(kicad_pcb
	(version 20260206)
	(generator "pcbnew")
	(generator_version "10.0")
	(general
		(thickness 1.6)
		(legacy_teardrops no)
	)
	(paper "A4")
	(layers
		(0 "F.Cu" signal "TOP")
		(4 "In1.Cu" signal "GND")
		(6 "In2.Cu" signal "IN1")
		(8 "In3.Cu" signal "GND1")
		(10 "In4.Cu" signal "IN2")
		(12 "In5.Cu" signal "GND2")
		(14 "In6.Cu" signal "IN3")
		(16 "In7.Cu" signal "GND3")
		(18 "In8.Cu" signal "VCC")
		(20 "In9.Cu" signal "VCC1")
		(22 "In10.Cu" signal "GND4")
		(24 "In11.Cu" signal "IN4")
		(26 "In12.Cu" signal "GND5")
		(28 "In13.Cu" signal "IN5")
		(30 "In14.Cu" signal "GND6")
		(32 "In15.Cu" signal "IN6")
		(34 "In16.Cu" signal "GND7")
		(2 "B.Cu" signal "BOTTOM")
		(9 "F.Adhes" user "F.Adhesive")
		(11 "B.Adhes" user "B.Adhesive")
		(13 "F.Paste" user "Package Geometry/Pastemask Top")
		(15 "B.Paste" user "Package Geometry/Pastemask Bottom")
		(5 "F.SilkS" user "Ref Des/Silkscreen Top")
		(7 "B.SilkS" user "Ref Des/Silkscreen Bottom")
		(1 "F.Mask" user "Board Geometry/Soldermask Top")
		(3 "B.Mask" user "Board Geometry/Soldermask Bottom")
		(17 "Dwgs.User" user "User.Drawings")
		(19 "Cmts.User" user "User.Comments")
		(21 "Eco1.User" user "User.Eco1")
		(23 "Eco2.User" user "User.Eco2")
		(25 "Edge.Cuts" user "Board Geometry/Outline")
		(27 "Margin" user)
		(31 "F.CrtYd" user "Package Geometry/Place Bound Top")
		(29 "B.CrtYd" user "Package Geometry/Place Bound Bottom")
		(35 "F.Fab" user "Ref Des/Assembly Top")
		(33 "B.Fab" user "Ref Des/Assembly Bottom")
	)
	(setup
		(pad_to_mask_clearance 0)
		(allow_soldermask_bridges_in_footprints no)
		(tenting
			(front yes)
			(back yes)
		)
		(covering
			(front no)
			(back no)
		)
		(plugging
			(front no)
			(back no)
		)
		(capping no)
		(filling no)
		(pcbplotparams
			(layerselection 0x00000000_00000000_55555555_5755f5ff)
			(plot_on_all_layers_selection 0x00000000_00000000_00000000_00000000)
			(disableapertmacros no)
			(usegerberextensions no)
			(usegerberattributes yes)
			(usegerberadvancedattributes yes)
			(creategerberjobfile yes)
			(dashed_line_dash_ratio 12)
			(dashed_line_gap_ratio 3)
			(svgprecision 4)
			(plotframeref no)
			(mode 1)
			(useauxorigin no)
			(pdf_front_fp_property_popups yes)
			(pdf_back_fp_property_popups yes)
			(pdf_metadata yes)
			(pdf_single_document no)
			(dxfpolygonmode yes)
			(dxfimperialunits yes)
			(dxfusepcbnewfont yes)
			(psnegative no)
			(psa4output no)
			(plot_black_and_white yes)
			(sketchpadsonfab no)
			(plotpadnumbers no)
			(hidednponfab no)
			(sketchdnponfab yes)
			(crossoutdnponfab yes)
			(subtractmaskfromsilk no)
			(outputformat 1)
			(mirror no)
			(drillshape 1)
			(scaleselection 1)
			(outputdirectory "")
		)
	)
	(arc
		(start 88.094058 -236.061758)
		(mid 87.811102 -236.137935)
		(end 87.528146 -236.061758)
		(width 0.0889)
		(layer "In13.Cu")
		(net "M_B_CPU1_SA_DQ<19>")
	)
	(arc
		(start 83.394042 -236.061758)
		(mid 83.111086 -236.137935)
		(end 82.82813 -236.061758)
		(width 0.0889)
		(layer "In13.Cu")
		(net "M_B_CPU1_SA_DQ<19>")
	)
	(arc
		(start 79.633572 -236.061758)
		(mid 79.496897 -236.118721)
		(end 79.350108 -236.138212)
		(width 0.0889)
		(layer "In13.Cu")
		(net "M_B_CPU1_SA_DQ<19>")
	)
	(arc
		(start 82.82813 -236.061758)
		(mid 82.645879 -236.011408)
		(end 82.46237 -236.056932)
		(width 0.0889)
		(layer "In13.Cu")
		(net "M_B_CPU1_SA_DQ<19>")
	)
	(arc
		(start 81.513934 -236.061758)
		(mid 81.230978 -236.137935)
		(end 80.948022 -236.061758)
		(width 0.0889)
		(layer "In13.Cu")
		(net "M_B_CPU1_SA_DQ<19>")
	)
	(arc
		(start 85.639656 -236.056932)
		(mid 85.456148 -236.011438)
		(end 85.273896 -236.061758)
		(width 0.0889)
		(layer "In13.Cu")
		(net "M_B_CPU1_SA_DQ<19>")
	)
	(arc
		(start 81.879694 -236.056932)
		(mid 81.696186 -236.011438)
		(end 81.513934 -236.061758)
		(width 0.0889)
		(layer "In13.Cu")
		(net "M_B_CPU1_SA_DQ<19>")
	)
	(arc
		(start 86.21395 -236.061758)
		(mid 85.930994 -236.137935)
		(end 85.648038 -236.061758)
		(width 0.0889)
		(layer "In13.Cu")
		(net "M_B_CPU1_SA_DQ<19>")
	)
	(arc
		(start 82.453988 -236.061758)
		(mid 82.171032 -236.137935)
		(end 81.888076 -236.061758)
		(width 0.0889)
		(layer "In13.Cu")
		(net "M_B_CPU1_SA_DQ<19>")
	)
	(arc
		(start 80.948022 -236.061758)
		(mid 80.761078 -236.011503)
		(end 80.574134 -236.061758)
		(width 0.0889)
		(layer "In13.Cu")
		(net "M_B_CPU1_SA_DQ<19>")
	)
	(arc
		(start 84.707984 -236.061758)
		(mid 84.52104 -236.011503)
		(end 84.334096 -236.061758)
		(width 0.0889)
		(layer "In13.Cu")
		(net "M_B_CPU1_SA_DQ<19>")
	)
	(arc
		(start 84.334096 -236.061758)
		(mid 84.05114 -236.137935)
		(end 83.768184 -236.061758)
		(width 0.0889)
		(layer "In13.Cu")
		(net "M_B_CPU1_SA_DQ<19>")
	)
	(arc
		(start 85.273896 -236.061758)
		(mid 84.99094 -236.137935)
		(end 84.707984 -236.061758)
		(width 0.0889)
		(layer "In13.Cu")
		(net "M_B_CPU1_SA_DQ<19>")
	)
	(arc
		(start 79.99984 -236.056932)
		(mid 79.816078 -236.011316)
		(end 79.633572 -236.061758)
		(width 0.0889)
		(layer "In13.Cu")
		(net "M_B_CPU1_SA_DQ<19>")
	)
	(arc
		(start 86.57971 -236.056932)
		(mid 86.396202 -236.011438)
		(end 86.21395 -236.061758)
		(width 0.0889)
		(layer "In13.Cu")
		(net "M_B_CPU1_SA_DQ<19>")
	)
	(arc
		(start 80.574134 -236.061758)
		(mid 80.291178 -236.137935)
		(end 80.008222 -236.061758)
		(width 0.0889)
		(layer "In13.Cu")
		(net "M_B_CPU1_SA_DQ<19>")
	)
	(arc
		(start 87.528146 -236.061758)
		(mid 87.345895 -236.011408)
		(end 87.162386 -236.056932)
		(width 0.0889)
		(layer "In13.Cu")
		(net "M_B_CPU1_SA_DQ<19>")
	)
	(segment
		(start 88.277954 -235.84027)
		(end 87.811102 -235.574332)
		(width 0.10668)
		(layer "F.Cu")
		(net "M_B_CPU1_SA_DQ<18>")
	)
	(segment
		(start 79.45501 -235.216192)
		(end 78.954376 -235.216192)
		(width 0.0889)
		(layer "In13.Cu")
		(net "M_B_CPU1_SA_DQ<18>")
	)
	(segment
		(start 80.478122 -235.251752)
		(end 80.46974 -235.246926)
		(width 0.0889)
		(layer "In13.Cu")
		(net "M_B_CPU1_SA_DQ<18>")
	)
	(segment
		(start 50.222404 -216.460324)
		(end 49.797462 -216.885266)
		(width 0.14478)
		(layer "In13.Cu")
		(net "M_B_CPU1_SA_DQ<18>")
	)
	(segment
		(start 68.73621 -227.272088)
		(end 68.73621 -225.605848)
		(width 0.14478)
		(layer "In13.Cu")
		(net "M_B_CPU1_SA_DQ<18>")
	)
	(segment
		(start 78.35265 -234.614466)
		(end 77.95895 -234.614466)
		(width 0.0889)
		(layer "In13.Cu")
		(net "M_B_CPU1_SA_DQ<18>")
	)
	(segment
		(start 61.874146 -218.743784)
		(end 58.41365 -217.310462)
		(width 0.14478)
		(layer "In13.Cu")
		(net "M_B_CPU1_SA_DQ<18>")
	)
	(segment
		(start 53.256434 -216.460324)
		(end 50.222404 -216.460324)
		(width 0.14478)
		(layer "In13.Cu")
		(net "M_B_CPU1_SA_DQ<18>")
	)
	(segment
		(start 75.92695 -233.247438)
		(end 74.71156 -233.247438)
		(width 0.14478)
		(layer "In13.Cu")
		(net "M_B_CPU1_SA_DQ<18>")
	)
	(segment
		(start 49.797462 -216.885266)
		(end 47.784004 -216.885266)
		(width 0.14478)
		(layer "In13.Cu")
		(net "M_B_CPU1_SA_DQ<18>")
	)
	(segment
		(start 84.238084 -235.251752)
		(end 84.229702 -235.246926)
		(width 0.0889)
		(layer "In13.Cu")
		(net "M_B_CPU1_SA_DQ<18>")
	)
	(segment
		(start 76.78293 -233.918506)
		(end 76.111862 -233.247438)
		(width 0.0889)
		(layer "In13.Cu")
		(net "M_B_CPU1_SA_DQ<18>")
	)
	(segment
		(start 77.95895 -234.614466)
		(end 77.26299 -233.918506)
		(width 0.0889)
		(layer "In13.Cu")
		(net "M_B_CPU1_SA_DQ<18>")
	)
	(segment
		(start 54.106572 -217.310462)
		(end 53.256434 -216.460324)
		(width 0.14478)
		(layer "In13.Cu")
		(net "M_B_CPU1_SA_DQ<18>")
	)
	(segment
		(start 79.561182 -235.264452)
		(end 79.539592 -235.252006)
		(width 0.0889)
		(layer "In13.Cu")
		(net "M_B_CPU1_SA_DQ<18>")
	)
	(segment
		(start 78.954376 -235.216192)
		(end 78.35265 -234.614466)
		(width 0.0889)
		(layer "In13.Cu")
		(net "M_B_CPU1_SA_DQ<18>")
	)
	(segment
		(start 76.111862 -233.247438)
		(end 75.92695 -233.247438)
		(width 0.0889)
		(layer "In13.Cu")
		(net "M_B_CPU1_SA_DQ<18>")
	)
	(segment
		(start 85.752432 -235.246926)
		(end 85.74405 -235.251752)
		(width 0.0889)
		(layer "In13.Cu")
		(net "M_B_CPU1_SA_DQ<18>")
	)
	(segment
		(start 58.41365 -217.310462)
		(end 54.106572 -217.310462)
		(width 0.14478)
		(layer "In13.Cu")
		(net "M_B_CPU1_SA_DQ<18>")
	)
	(segment
		(start 83.29803 -235.251752)
		(end 83.289648 -235.246926)
		(width 0.0889)
		(layer "In13.Cu")
		(net "M_B_CPU1_SA_DQ<18>")
	)
	(segment
		(start 84.812378 -235.246926)
		(end 84.803996 -235.251752)
		(width 0.0889)
		(layer "In13.Cu")
		(net "M_B_CPU1_SA_DQ<18>")
	)
	(segment
		(start 81.052416 -235.246926)
		(end 81.044034 -235.251752)
		(width 0.0889)
		(layer "In13.Cu")
		(net "M_B_CPU1_SA_DQ<18>")
	)
	(segment
		(start 74.71156 -233.247438)
		(end 68.73621 -227.272088)
		(width 0.14478)
		(layer "In13.Cu")
		(net "M_B_CPU1_SA_DQ<18>")
	)
	(segment
		(start 68.73621 -225.605848)
		(end 61.874146 -218.743784)
		(width 0.14478)
		(layer "In13.Cu")
		(net "M_B_CPU1_SA_DQ<18>")
	)
	(segment
		(start 87.656924 -235.308902)
		(end 87.560658 -235.283502)
		(width 0.0889)
		(layer "In13.Cu")
		(net "M_B_CPU1_SA_DQ<18>")
	)
	(segment
		(start 87.811102 -235.574332)
		(end 87.656924 -235.308902)
		(width 0.0889)
		(layer "In13.Cu")
		(net "M_B_CPU1_SA_DQ<18>")
	)
	(segment
		(start 77.26299 -233.918506)
		(end 76.78293 -233.918506)
		(width 0.0889)
		(layer "In13.Cu")
		(net "M_B_CPU1_SA_DQ<18>")
	)
	(arc
		(start 84.803996 -235.251752)
		(mid 84.52104 -235.327929)
		(end 84.238084 -235.251752)
		(width 0.0889)
		(layer "In13.Cu")
		(net "M_B_CPU1_SA_DQ<18>")
	)
	(arc
		(start 81.044034 -235.251752)
		(mid 80.761078 -235.327929)
		(end 80.478122 -235.251752)
		(width 0.0889)
		(layer "In13.Cu")
		(net "M_B_CPU1_SA_DQ<18>")
	)
	(arc
		(start 85.178138 -235.251752)
		(mid 84.995887 -235.201402)
		(end 84.812378 -235.246926)
		(width 0.0889)
		(layer "In13.Cu")
		(net "M_B_CPU1_SA_DQ<18>")
	)
	(arc
		(start 84.229702 -235.246926)
		(mid 84.046194 -235.201432)
		(end 83.863942 -235.251752)
		(width 0.0889)
		(layer "In13.Cu")
		(net "M_B_CPU1_SA_DQ<18>")
	)
	(arc
		(start 81.418176 -235.251752)
		(mid 81.235925 -235.201402)
		(end 81.052416 -235.246926)
		(width 0.0889)
		(layer "In13.Cu")
		(net "M_B_CPU1_SA_DQ<18>")
	)
	(arc
		(start 86.118192 -235.251752)
		(mid 85.935941 -235.201402)
		(end 85.752432 -235.246926)
		(width 0.0889)
		(layer "In13.Cu")
		(net "M_B_CPU1_SA_DQ<18>")
	)
	(arc
		(start 87.057992 -235.251752)
		(mid 86.871048 -235.201497)
		(end 86.684104 -235.251752)
		(width 0.0889)
		(layer "In13.Cu")
		(net "M_B_CPU1_SA_DQ<18>")
	)
	(arc
		(start 82.357976 -235.251752)
		(mid 82.171032 -235.201497)
		(end 81.984088 -235.251752)
		(width 0.0889)
		(layer "In13.Cu")
		(net "M_B_CPU1_SA_DQ<18>")
	)
	(arc
		(start 85.74405 -235.251752)
		(mid 85.461094 -235.327929)
		(end 85.178138 -235.251752)
		(width 0.0889)
		(layer "In13.Cu")
		(net "M_B_CPU1_SA_DQ<18>")
	)
	(arc
		(start 80.10398 -235.251752)
		(mid 79.834211 -235.327775)
		(end 79.561182 -235.264452)
		(width 0.0889)
		(layer "In13.Cu")
		(net "M_B_CPU1_SA_DQ<18>")
	)
	(arc
		(start 82.923888 -235.251752)
		(mid 82.640932 -235.327929)
		(end 82.357976 -235.251752)
		(width 0.0889)
		(layer "In13.Cu")
		(net "M_B_CPU1_SA_DQ<18>")
	)
	(arc
		(start 83.863942 -235.251752)
		(mid 83.580986 -235.327929)
		(end 83.29803 -235.251752)
		(width 0.0889)
		(layer "In13.Cu")
		(net "M_B_CPU1_SA_DQ<18>")
	)
	(arc
		(start 86.684104 -235.251752)
		(mid 86.401148 -235.327929)
		(end 86.118192 -235.251752)
		(width 0.0889)
		(layer "In13.Cu")
		(net "M_B_CPU1_SA_DQ<18>")
	)
	(arc
		(start 81.984088 -235.251752)
		(mid 81.701132 -235.327929)
		(end 81.418176 -235.251752)
		(width 0.0889)
		(layer "In13.Cu")
		(net "M_B_CPU1_SA_DQ<18>")
	)
	(arc
		(start 80.46974 -235.246926)
		(mid 80.286232 -235.201432)
		(end 80.10398 -235.251752)
		(width 0.0889)
		(layer "In13.Cu")
		(net "M_B_CPU1_SA_DQ<18>")
	)
	(arc
		(start 87.560658 -235.283502)
		(mid 87.305593 -235.326853)
		(end 87.057992 -235.251752)
		(width 0.0889)
		(layer "In13.Cu")
		(net "M_B_CPU1_SA_DQ<18>")
	)
	(arc
		(start 79.539592 -235.252006)
		(mid 79.498408 -235.231485)
		(end 79.45501 -235.216192)
		(width 0.0889)
		(layer "In13.Cu")
		(net "M_B_CPU1_SA_DQ<18>")
	)
	(arc
		(start 83.289648 -235.246926)
		(mid 83.10614 -235.201432)
		(end 82.923888 -235.251752)
		(width 0.0889)
		(layer "In13.Cu")
		(net "M_B_CPU1_SA_DQ<18>")
	)
	(segment
		(start 89.218008 -235.84027)
		(end 88.751156 -235.574332)
		(width 0.10668)
		(layer "F.Cu")
		(net "M_B_CPU1_SA_DQ<17>")
	)
	(segment
		(start 59.849766 -218.548712)
		(end 60.038742 -218.47048)
		(width 0.14478)
		(layer "In13.Cu")
		(net "M_B_CPU1_SA_DQ<17>")
	)
	(segment
		(start 56.563006 -218.323414)
		(end 56.726074 -218.160346)
		(width 0.14478)
		(layer "In13.Cu")
		(net "M_B_CPU1_SA_DQ<17>")
	)
	(segment
		(start 59.262264 -218.148662)
		(end 59.340496 -218.337638)
		(width 0.14478)
		(layer "In13.Cu")
		(net "M_B_CPU1_SA_DQ<17>")
	)
	(segment
		(start 54.084474 -218.160346)
		(end 54.730396 -218.160346)
		(width 0.14478)
		(layer "In13.Cu")
		(net "M_B_CPU1_SA_DQ<17>")
	)
	(segment
		(start 51.884072 -217.729816)
		(end 52.303426 -217.310462)
		(width 0.14478)
		(layer "In13.Cu")
		(net "M_B_CPU1_SA_DQ<17>")
	)
	(segment
		(start 55.449978 -218.390216)
		(end 55.449978 -218.323414)
		(width 0.14478)
		(layer "In13.Cu")
		(net "M_B_CPU1_SA_DQ<17>")
	)
	(segment
		(start 61.299344 -218.992958)
		(end 61.377576 -219.181934)
		(width 0.14478)
		(layer "In13.Cu")
		(net "M_B_CPU1_SA_DQ<17>")
	)
	(segment
		(start 85.74405 -235.896912)
		(end 85.752432 -235.901738)
		(width 0.0889)
		(layer "In13.Cu")
		(net "M_B_CPU1_SA_DQ<17>")
	)
	(segment
		(start 87.989664 -235.901738)
		(end 87.998046 -235.896912)
		(width 0.0889)
		(layer "In13.Cu")
		(net "M_B_CPU1_SA_DQ<17>")
	)
	(segment
		(start 53.23459 -217.310462)
		(end 54.084474 -218.160346)
		(width 0.14478)
		(layer "In13.Cu")
		(net "M_B_CPU1_SA_DQ<17>")
	)
	(segment
		(start 62.40272 -219.94114)
		(end 68.28155 -225.81997)
		(width 0.14478)
		(layer "In13.Cu")
		(net "M_B_CPU1_SA_DQ<17>")
	)
	(segment
		(start 78.25867 -235.947712)
		(end 79.349854 -235.947712)
		(width 0.0889)
		(layer "In13.Cu")
		(net "M_B_CPU1_SA_DQ<17>")
	)
	(segment
		(start 55.843424 -218.160346)
		(end 56.006492 -218.323414)
		(width 0.14478)
		(layer "In13.Cu")
		(net "M_B_CPU1_SA_DQ<17>")
	)
	(segment
		(start 61.377576 -219.181934)
		(end 61.31433 -219.334588)
		(width 0.14478)
		(layer "In13.Cu")
		(net "M_B_CPU1_SA_DQ<17>")
	)
	(segment
		(start 56.726074 -218.160346)
		(end 58.10377 -218.160346)
		(width 0.14478)
		(layer "In13.Cu")
		(net "M_B_CPU1_SA_DQ<17>")
	)
	(segment
		(start 84.803996 -235.896912)
		(end 84.812378 -235.901738)
		(width 0.0889)
		(layer "In13.Cu")
		(net "M_B_CPU1_SA_DQ<17>")
	)
	(segment
		(start 54.730396 -218.160346)
		(end 54.893464 -218.323414)
		(width 0.14478)
		(layer "In13.Cu")
		(net "M_B_CPU1_SA_DQ<17>")
	)
	(segment
		(start 56.16956 -218.553284)
		(end 56.399938 -218.553284)
		(width 0.14478)
		(layer "In13.Cu")
		(net "M_B_CPU1_SA_DQ<17>")
	)
	(segment
		(start 60.616084 -219.201746)
		(end 60.80506 -219.123514)
		(width 0.14478)
		(layer "In13.Cu")
		(net "M_B_CPU1_SA_DQ<17>")
	)
	(segment
		(start 60.038742 -218.47048)
		(end 60.280804 -218.57081)
		(width 0.14478)
		(layer "In13.Cu")
		(net "M_B_CPU1_SA_DQ<17>")
	)
	(segment
		(start 75.93965 -233.702098)
		(end 76.205842 -233.702098)
		(width 0.0889)
		(layer "In13.Cu")
		(net "M_B_CPU1_SA_DQ<17>")
	)
	(segment
		(start 55.449978 -218.323414)
		(end 55.613046 -218.160346)
		(width 0.14478)
		(layer "In13.Cu")
		(net "M_B_CPU1_SA_DQ<17>")
	)
	(segment
		(start 59.355482 -218.679268)
		(end 59.597544 -218.779598)
		(width 0.14478)
		(layer "In13.Cu")
		(net "M_B_CPU1_SA_DQ<17>")
	)
	(segment
		(start 80.46974 -235.901738)
		(end 80.478122 -235.896912)
		(width 0.0889)
		(layer "In13.Cu")
		(net "M_B_CPU1_SA_DQ<17>")
	)
	(segment
		(start 54.893464 -218.390216)
		(end 55.056532 -218.553284)
		(width 0.14478)
		(layer "In13.Cu")
		(net "M_B_CPU1_SA_DQ<17>")
	)
	(segment
		(start 55.613046 -218.160346)
		(end 55.843424 -218.160346)
		(width 0.14478)
		(layer "In13.Cu")
		(net "M_B_CPU1_SA_DQ<17>")
	)
	(segment
		(start 83.289648 -235.901738)
		(end 83.29803 -235.896912)
		(width 0.0889)
		(layer "In13.Cu")
		(net "M_B_CPU1_SA_DQ<17>")
	)
	(segment
		(start 58.579004 -218.35745)
		(end 58.76798 -218.279218)
		(width 0.14478)
		(layer "In13.Cu")
		(net "M_B_CPU1_SA_DQ<17>")
	)
	(segment
		(start 56.563006 -218.390216)
		(end 56.563006 -218.323414)
		(width 0.14478)
		(layer "In13.Cu")
		(net "M_B_CPU1_SA_DQ<17>")
	)
	(segment
		(start 76.205842 -233.702098)
		(end 76.67625 -234.172506)
		(width 0.0889)
		(layer "In13.Cu")
		(net "M_B_CPU1_SA_DQ<17>")
	)
	(segment
		(start 61.057282 -218.892628)
		(end 61.299344 -218.992958)
		(width 0.14478)
		(layer "In13.Cu")
		(net "M_B_CPU1_SA_DQ<17>")
	)
	(segment
		(start 61.392562 -219.52331)
		(end 62.40272 -219.94114)
		(width 0.14478)
		(layer "In13.Cu")
		(net "M_B_CPU1_SA_DQ<17>")
	)
	(segment
		(start 59.78652 -218.701366)
		(end 59.849766 -218.548712)
		(width 0.14478)
		(layer "In13.Cu")
		(net "M_B_CPU1_SA_DQ<17>")
	)
	(segment
		(start 59.020202 -218.048332)
		(end 59.262264 -218.148662)
		(width 0.14478)
		(layer "In13.Cu")
		(net "M_B_CPU1_SA_DQ<17>")
	)
	(segment
		(start 52.303426 -217.310462)
		(end 53.23459 -217.310462)
		(width 0.14478)
		(layer "In13.Cu")
		(net "M_B_CPU1_SA_DQ<17>")
	)
	(segment
		(start 55.056532 -218.553284)
		(end 55.28691 -218.553284)
		(width 0.14478)
		(layer "In13.Cu")
		(net "M_B_CPU1_SA_DQ<17>")
	)
	(segment
		(start 58.76798 -218.279218)
		(end 58.831226 -218.126564)
		(width 0.14478)
		(layer "In13.Cu")
		(net "M_B_CPU1_SA_DQ<17>")
	)
	(segment
		(start 59.597544 -218.779598)
		(end 59.78652 -218.701366)
		(width 0.14478)
		(layer "In13.Cu")
		(net "M_B_CPU1_SA_DQ<17>")
	)
	(segment
		(start 76.67625 -234.172506)
		(end 77.03693 -234.172506)
		(width 0.0889)
		(layer "In13.Cu")
		(net "M_B_CPU1_SA_DQ<17>")
	)
	(segment
		(start 60.374022 -219.101416)
		(end 60.616084 -219.201746)
		(width 0.14478)
		(layer "In13.Cu")
		(net "M_B_CPU1_SA_DQ<17>")
	)
	(segment
		(start 68.28155 -225.81997)
		(end 68.28155 -227.453444)
		(width 0.14478)
		(layer "In13.Cu")
		(net "M_B_CPU1_SA_DQ<17>")
	)
	(segment
		(start 74.530204 -233.702098)
		(end 75.93965 -233.702098)
		(width 0.14478)
		(layer "In13.Cu")
		(net "M_B_CPU1_SA_DQ<17>")
	)
	(segment
		(start 81.044034 -235.896912)
		(end 81.052416 -235.901738)
		(width 0.0889)
		(layer "In13.Cu")
		(net "M_B_CPU1_SA_DQ<17>")
	)
	(segment
		(start 61.31433 -219.334588)
		(end 61.392562 -219.52331)
		(width 0.14478)
		(layer "In13.Cu")
		(net "M_B_CPU1_SA_DQ<17>")
	)
	(segment
		(start 60.868306 -218.97086)
		(end 61.057282 -218.892628)
		(width 0.14478)
		(layer "In13.Cu")
		(net "M_B_CPU1_SA_DQ<17>")
	)
	(segment
		(start 56.006492 -218.323414)
		(end 56.006492 -218.390216)
		(width 0.14478)
		(layer "In13.Cu")
		(net "M_B_CPU1_SA_DQ<17>")
	)
	(segment
		(start 77.03693 -234.172506)
		(end 77.59573 -234.731306)
		(width 0.0889)
		(layer "In13.Cu")
		(net "M_B_CPU1_SA_DQ<17>")
	)
	(segment
		(start 56.006492 -218.390216)
		(end 56.16956 -218.553284)
		(width 0.14478)
		(layer "In13.Cu")
		(net "M_B_CPU1_SA_DQ<17>")
	)
	(segment
		(start 55.28691 -218.553284)
		(end 55.449978 -218.390216)
		(width 0.14478)
		(layer "In13.Cu")
		(net "M_B_CPU1_SA_DQ<17>")
	)
	(segment
		(start 84.229702 -235.901738)
		(end 84.238084 -235.896912)
		(width 0.0889)
		(layer "In13.Cu")
		(net "M_B_CPU1_SA_DQ<17>")
	)
	(segment
		(start 58.10377 -218.160346)
		(end 58.579004 -218.35745)
		(width 0.14478)
		(layer "In13.Cu")
		(net "M_B_CPU1_SA_DQ<17>")
	)
	(segment
		(start 59.340496 -218.337638)
		(end 59.27725 -218.490292)
		(width 0.14478)
		(layer "In13.Cu")
		(net "M_B_CPU1_SA_DQ<17>")
	)
	(segment
		(start 60.280804 -218.57081)
		(end 60.359036 -218.759786)
		(width 0.14478)
		(layer "In13.Cu")
		(net "M_B_CPU1_SA_DQ<17>")
	)
	(segment
		(start 60.29579 -218.91244)
		(end 60.374022 -219.101416)
		(width 0.14478)
		(layer "In13.Cu")
		(net "M_B_CPU1_SA_DQ<17>")
	)
	(segment
		(start 88.882728 -235.923074)
		(end 88.90508 -235.839762)
		(width 0.0889)
		(layer "In13.Cu")
		(net "M_B_CPU1_SA_DQ<17>")
	)
	(segment
		(start 77.59573 -235.284772)
		(end 78.25867 -235.947712)
		(width 0.0889)
		(layer "In13.Cu")
		(net "M_B_CPU1_SA_DQ<17>")
	)
	(segment
		(start 60.359036 -218.759786)
		(end 60.29579 -218.91244)
		(width 0.14478)
		(layer "In13.Cu")
		(net "M_B_CPU1_SA_DQ<17>")
	)
	(segment
		(start 56.399938 -218.553284)
		(end 56.563006 -218.390216)
		(width 0.14478)
		(layer "In13.Cu")
		(net "M_B_CPU1_SA_DQ<17>")
	)
	(segment
		(start 80.093566 -235.890816)
		(end 80.10398 -235.896912)
		(width 0.0889)
		(layer "In13.Cu")
		(net "M_B_CPU1_SA_DQ<17>")
	)
	(segment
		(start 88.90508 -235.839762)
		(end 88.751156 -235.574332)
		(width 0.0889)
		(layer "In13.Cu")
		(net "M_B_CPU1_SA_DQ<17>")
	)
	(segment
		(start 58.831226 -218.126564)
		(end 59.020202 -218.048332)
		(width 0.14478)
		(layer "In13.Cu")
		(net "M_B_CPU1_SA_DQ<17>")
	)
	(segment
		(start 77.59573 -234.731306)
		(end 77.59573 -235.284772)
		(width 0.0889)
		(layer "In13.Cu")
		(net "M_B_CPU1_SA_DQ<17>")
	)
	(segment
		(start 51.884072 -217.735404)
		(end 51.884072 -217.729816)
		(width 0.14478)
		(layer "In13.Cu")
		(net "M_B_CPU1_SA_DQ<17>")
	)
	(segment
		(start 54.893464 -218.323414)
		(end 54.893464 -218.390216)
		(width 0.14478)
		(layer "In13.Cu")
		(net "M_B_CPU1_SA_DQ<17>")
	)
	(segment
		(start 68.28155 -227.453444)
		(end 74.530204 -233.702098)
		(width 0.14478)
		(layer "In13.Cu")
		(net "M_B_CPU1_SA_DQ<17>")
	)
	(segment
		(start 60.80506 -219.123514)
		(end 60.868306 -218.97086)
		(width 0.14478)
		(layer "In13.Cu")
		(net "M_B_CPU1_SA_DQ<17>")
	)
	(segment
		(start 59.27725 -218.490292)
		(end 59.355482 -218.679268)
		(width 0.14478)
		(layer "In13.Cu")
		(net "M_B_CPU1_SA_DQ<17>")
	)
	(arc
		(start 85.752432 -235.901738)
		(mid 85.93594 -235.947232)
		(end 86.118192 -235.896912)
		(width 0.0889)
		(layer "In13.Cu")
		(net "M_B_CPU1_SA_DQ<17>")
	)
	(arc
		(start 86.684104 -235.896912)
		(mid 86.871048 -235.947167)
		(end 87.057992 -235.896912)
		(width 0.0889)
		(layer "In13.Cu")
		(net "M_B_CPU1_SA_DQ<17>")
	)
	(arc
		(start 79.537814 -235.896912)
		(mid 79.814881 -235.820641)
		(end 80.093566 -235.890816)
		(width 0.0889)
		(layer "In13.Cu")
		(net "M_B_CPU1_SA_DQ<17>")
	)
	(arc
		(start 79.349854 -235.947712)
		(mid 79.447215 -235.934804)
		(end 79.537814 -235.896912)
		(width 0.0889)
		(layer "In13.Cu")
		(net "M_B_CPU1_SA_DQ<17>")
	)
	(arc
		(start 87.998046 -235.896912)
		(mid 88.281002 -235.820735)
		(end 88.563958 -235.896912)
		(width 0.0889)
		(layer "In13.Cu")
		(net "M_B_CPU1_SA_DQ<17>")
	)
	(arc
		(start 82.357976 -235.896912)
		(mid 82.640932 -235.820735)
		(end 82.923888 -235.896912)
		(width 0.0889)
		(layer "In13.Cu")
		(net "M_B_CPU1_SA_DQ<17>")
	)
	(arc
		(start 87.623904 -235.896912)
		(mid 87.806155 -235.947262)
		(end 87.989664 -235.901738)
		(width 0.0889)
		(layer "In13.Cu")
		(net "M_B_CPU1_SA_DQ<17>")
	)
	(arc
		(start 86.118192 -235.896912)
		(mid 86.401148 -235.820735)
		(end 86.684104 -235.896912)
		(width 0.0889)
		(layer "In13.Cu")
		(net "M_B_CPU1_SA_DQ<17>")
	)
	(arc
		(start 81.052416 -235.901738)
		(mid 81.235924 -235.947232)
		(end 81.418176 -235.896912)
		(width 0.0889)
		(layer "In13.Cu")
		(net "M_B_CPU1_SA_DQ<17>")
	)
	(arc
		(start 81.984088 -235.896912)
		(mid 82.171032 -235.947167)
		(end 82.357976 -235.896912)
		(width 0.0889)
		(layer "In13.Cu")
		(net "M_B_CPU1_SA_DQ<17>")
	)
	(arc
		(start 80.10398 -235.896912)
		(mid 80.286231 -235.947262)
		(end 80.46974 -235.901738)
		(width 0.0889)
		(layer "In13.Cu")
		(net "M_B_CPU1_SA_DQ<17>")
	)
	(arc
		(start 80.478122 -235.896912)
		(mid 80.761078 -235.820735)
		(end 81.044034 -235.896912)
		(width 0.0889)
		(layer "In13.Cu")
		(net "M_B_CPU1_SA_DQ<17>")
	)
	(arc
		(start 82.923888 -235.896912)
		(mid 83.106139 -235.947262)
		(end 83.289648 -235.901738)
		(width 0.0889)
		(layer "In13.Cu")
		(net "M_B_CPU1_SA_DQ<17>")
	)
	(arc
		(start 84.238084 -235.896912)
		(mid 84.52104 -235.820735)
		(end 84.803996 -235.896912)
		(width 0.0889)
		(layer "In13.Cu")
		(net "M_B_CPU1_SA_DQ<17>")
	)
	(arc
		(start 85.178138 -235.896912)
		(mid 85.461094 -235.820735)
		(end 85.74405 -235.896912)
		(width 0.0889)
		(layer "In13.Cu")
		(net "M_B_CPU1_SA_DQ<17>")
	)
	(arc
		(start 84.812378 -235.901738)
		(mid 84.995886 -235.947232)
		(end 85.178138 -235.896912)
		(width 0.0889)
		(layer "In13.Cu")
		(net "M_B_CPU1_SA_DQ<17>")
	)
	(arc
		(start 83.29803 -235.896912)
		(mid 83.580986 -235.820735)
		(end 83.863942 -235.896912)
		(width 0.0889)
		(layer "In13.Cu")
		(net "M_B_CPU1_SA_DQ<17>")
	)
	(arc
		(start 87.057992 -235.896912)
		(mid 87.340948 -235.820735)
		(end 87.623904 -235.896912)
		(width 0.0889)
		(layer "In13.Cu")
		(net "M_B_CPU1_SA_DQ<17>")
	)
	(arc
		(start 88.563958 -235.896912)
		(mid 88.720396 -235.945883)
		(end 88.882728 -235.923074)
		(width 0.0889)
		(layer "In13.Cu")
		(net "M_B_CPU1_SA_DQ<17>")
	)
	(arc
		(start 83.863942 -235.896912)
		(mid 84.046193 -235.947262)
		(end 84.229702 -235.901738)
		(width 0.0889)
		(layer "In13.Cu")
		(net "M_B_CPU1_SA_DQ<17>")
	)
	(arc
		(start 81.418176 -235.896912)
		(mid 81.701132 -235.820735)
		(end 81.984088 -235.896912)
		(width 0.0889)
		(layer "In13.Cu")
		(net "M_B_CPU1_SA_DQ<17>")
	)
	(segment
		(start 87.8078 -235.030264)
		(end 87.340948 -234.764326)
		(width 0.10668)
		(layer "F.Cu")
		(net "M_B_CPU1_SA_DQ<16>")
	)
	(segment
		(start 78.225904 -234.423966)
		(end 78.601316 -234.423966)
		(width 0.0889)
		(layer "In13.Cu")
		(net "M_B_CPU1_SA_DQ<16>")
	)
	(segment
		(start 79.203042 -235.025692)
		(end 79.478886 -235.025692)
		(width 0.0889)
		(layer "In13.Cu")
		(net "M_B_CPU1_SA_DQ<16>")
	)
	(segment
		(start 56.384444 -216.698322)
		(end 56.384444 -216.33053)
		(width 0.14478)
		(layer "In13.Cu")
		(net "M_B_CPU1_SA_DQ<16>")
	)
	(segment
		(start 60.757562 -217.702892)
		(end 61.011054 -217.4494)
		(width 0.14478)
		(layer "In13.Cu")
		(net "M_B_CPU1_SA_DQ<16>")
	)
	(segment
		(start 60.621164 -216.854786)
		(end 60.621164 -217.05951)
		(width 0.14478)
		(layer "In13.Cu")
		(net "M_B_CPU1_SA_DQ<16>")
	)
	(segment
		(start 87.154004 -235.086906)
		(end 87.162386 -235.091732)
		(width 0.0889)
		(layer "In13.Cu")
		(net "M_B_CPU1_SA_DQ<16>")
	)
	(segment
		(start 79.634842 -235.086906)
		(end 79.634842 -235.086652)
		(width 0.0889)
		(layer "In13.Cu")
		(net "M_B_CPU1_SA_DQ<16>")
	)
	(segment
		(start 61.011054 -217.4494)
		(end 61.215778 -217.4494)
		(width 0.14478)
		(layer "In13.Cu")
		(net "M_B_CPU1_SA_DQ<16>")
	)
	(segment
		(start 57.648856 -216.168986)
		(end 57.877202 -216.168986)
		(width 0.14478)
		(layer "In13.Cu")
		(net "M_B_CPU1_SA_DQ<16>")
	)
	(segment
		(start 76.746862 -232.792778)
		(end 77.41539 -233.461306)
		(width 0.0889)
		(layer "In13.Cu")
		(net "M_B_CPU1_SA_DQ<16>")
	)
	(segment
		(start 53.23459 -215.61044)
		(end 54.084474 -216.460324)
		(width 0.14478)
		(layer "In13.Cu")
		(net "M_B_CPU1_SA_DQ<16>")
	)
	(segment
		(start 77.41539 -233.461306)
		(end 77.41539 -233.613452)
		(width 0.0889)
		(layer "In13.Cu")
		(net "M_B_CPU1_SA_DQ<16>")
	)
	(segment
		(start 57.325768 -216.859866)
		(end 57.487312 -216.698322)
		(width 0.14478)
		(layer "In13.Cu")
		(net "M_B_CPU1_SA_DQ<16>")
	)
	(segment
		(start 58.20029 -216.859866)
		(end 58.428636 -216.859866)
		(width 0.14478)
		(layer "In13.Cu")
		(net "M_B_CPU1_SA_DQ<16>")
	)
	(segment
		(start 55.994554 -216.859866)
		(end 56.2229 -216.859866)
		(width 0.14478)
		(layer "In13.Cu")
		(net "M_B_CPU1_SA_DQ<16>")
	)
	(segment
		(start 54.696868 -216.748106)
		(end 54.96052 -216.748106)
		(width 0.14478)
		(layer "In13.Cu")
		(net "M_B_CPU1_SA_DQ<16>")
	)
	(segment
		(start 60.367672 -217.313002)
		(end 60.367672 -217.517726)
		(width 0.14478)
		(layer "In13.Cu")
		(net "M_B_CPU1_SA_DQ<16>")
	)
	(segment
		(start 85.639656 -235.091732)
		(end 85.648038 -235.086906)
		(width 0.0889)
		(layer "In13.Cu")
		(net "M_B_CPU1_SA_DQ<16>")
	)
	(segment
		(start 78.601316 -234.423966)
		(end 79.203042 -235.025692)
		(width 0.0889)
		(layer "In13.Cu")
		(net "M_B_CPU1_SA_DQ<16>")
	)
	(segment
		(start 86.57971 -235.091732)
		(end 86.588092 -235.086906)
		(width 0.0889)
		(layer "In13.Cu")
		(net "M_B_CPU1_SA_DQ<16>")
	)
	(segment
		(start 81.879694 -235.091732)
		(end 81.888076 -235.086906)
		(width 0.0889)
		(layer "In13.Cu")
		(net "M_B_CPU1_SA_DQ<16>")
	)
	(segment
		(start 56.2229 -216.859866)
		(end 56.384444 -216.698322)
		(width 0.14478)
		(layer "In13.Cu")
		(net "M_B_CPU1_SA_DQ<16>")
	)
	(segment
		(start 58.59018 -216.698322)
		(end 58.59018 -216.621868)
		(width 0.14478)
		(layer "In13.Cu")
		(net "M_B_CPU1_SA_DQ<16>")
	)
	(segment
		(start 55.671466 -216.460324)
		(end 55.83301 -216.621868)
		(width 0.14478)
		(layer "In13.Cu")
		(net "M_B_CPU1_SA_DQ<16>")
	)
	(segment
		(start 69.19087 -227.090732)
		(end 74.892916 -232.792778)
		(width 0.14478)
		(layer "In13.Cu")
		(net "M_B_CPU1_SA_DQ<16>")
	)
	(segment
		(start 57.877202 -216.168986)
		(end 58.038746 -216.33053)
		(width 0.14478)
		(layer "In13.Cu")
		(net "M_B_CPU1_SA_DQ<16>")
	)
	(segment
		(start 75.94981 -232.792778)
		(end 76.746862 -232.792778)
		(width 0.0889)
		(layer "In13.Cu")
		(net "M_B_CPU1_SA_DQ<16>")
	)
	(segment
		(start 57.487312 -216.698322)
		(end 57.487312 -216.33053)
		(width 0.14478)
		(layer "In13.Cu")
		(net "M_B_CPU1_SA_DQ<16>")
	)
	(segment
		(start 69.19087 -225.424492)
		(end 69.19087 -227.090732)
		(width 0.14478)
		(layer "In13.Cu")
		(net "M_B_CPU1_SA_DQ<16>")
	)
	(segment
		(start 60.367672 -217.517726)
		(end 60.552838 -217.702892)
		(width 0.14478)
		(layer "In13.Cu")
		(net "M_B_CPU1_SA_DQ<16>")
	)
	(segment
		(start 58.038746 -216.33053)
		(end 58.038746 -216.698322)
		(width 0.14478)
		(layer "In13.Cu")
		(net "M_B_CPU1_SA_DQ<16>")
	)
	(segment
		(start 74.892916 -232.792778)
		(end 75.94981 -232.792778)
		(width 0.14478)
		(layer "In13.Cu")
		(net "M_B_CPU1_SA_DQ<16>")
	)
	(segment
		(start 56.384444 -216.33053)
		(end 56.545988 -216.168986)
		(width 0.14478)
		(layer "In13.Cu")
		(net "M_B_CPU1_SA_DQ<16>")
	)
	(segment
		(start 60.621164 -217.05951)
		(end 60.367672 -217.313002)
		(width 0.14478)
		(layer "In13.Cu")
		(net "M_B_CPU1_SA_DQ<16>")
	)
	(segment
		(start 58.751724 -216.460324)
		(end 60.226702 -216.460324)
		(width 0.14478)
		(layer "In13.Cu")
		(net "M_B_CPU1_SA_DQ<16>")
	)
	(segment
		(start 52.198016 -215.61044)
		(end 53.23459 -215.61044)
		(width 0.14478)
		(layer "In13.Cu")
		(net "M_B_CPU1_SA_DQ<16>")
	)
	(segment
		(start 55.248302 -216.460324)
		(end 55.671466 -216.460324)
		(width 0.14478)
		(layer "In13.Cu")
		(net "M_B_CPU1_SA_DQ<16>")
	)
	(segment
		(start 83.394042 -235.086906)
		(end 83.402424 -235.091732)
		(width 0.0889)
		(layer "In13.Cu")
		(net "M_B_CPU1_SA_DQ<16>")
	)
	(segment
		(start 51.884072 -215.924384)
		(end 52.198016 -215.61044)
		(width 0.14478)
		(layer "In13.Cu")
		(net "M_B_CPU1_SA_DQ<16>")
	)
	(segment
		(start 61.215778 -217.4494)
		(end 69.19087 -225.424492)
		(width 0.14478)
		(layer "In13.Cu")
		(net "M_B_CPU1_SA_DQ<16>")
	)
	(segment
		(start 57.097422 -216.859866)
		(end 57.325768 -216.859866)
		(width 0.14478)
		(layer "In13.Cu")
		(net "M_B_CPU1_SA_DQ<16>")
	)
	(segment
		(start 54.084474 -216.460324)
		(end 54.409086 -216.460324)
		(width 0.14478)
		(layer "In13.Cu")
		(net "M_B_CPU1_SA_DQ<16>")
	)
	(segment
		(start 56.545988 -216.168986)
		(end 56.774334 -216.168986)
		(width 0.14478)
		(layer "In13.Cu")
		(net "M_B_CPU1_SA_DQ<16>")
	)
	(segment
		(start 55.83301 -216.621868)
		(end 55.83301 -216.698322)
		(width 0.14478)
		(layer "In13.Cu")
		(net "M_B_CPU1_SA_DQ<16>")
	)
	(segment
		(start 54.409086 -216.460324)
		(end 54.696868 -216.748106)
		(width 0.14478)
		(layer "In13.Cu")
		(net "M_B_CPU1_SA_DQ<16>")
	)
	(segment
		(start 51.884072 -216.035382)
		(end 51.884072 -215.924384)
		(width 0.14478)
		(layer "In13.Cu")
		(net "M_B_CPU1_SA_DQ<16>")
	)
	(segment
		(start 56.935878 -216.33053)
		(end 56.935878 -216.698322)
		(width 0.14478)
		(layer "In13.Cu")
		(net "M_B_CPU1_SA_DQ<16>")
	)
	(segment
		(start 87.495126 -235.029756)
		(end 87.340948 -234.764326)
		(width 0.0889)
		(layer "In13.Cu")
		(net "M_B_CPU1_SA_DQ<16>")
	)
	(segment
		(start 56.935878 -216.698322)
		(end 57.097422 -216.859866)
		(width 0.14478)
		(layer "In13.Cu")
		(net "M_B_CPU1_SA_DQ<16>")
	)
	(segment
		(start 60.552838 -217.702892)
		(end 60.757562 -217.702892)
		(width 0.14478)
		(layer "In13.Cu")
		(net "M_B_CPU1_SA_DQ<16>")
	)
	(segment
		(start 58.038746 -216.698322)
		(end 58.20029 -216.859866)
		(width 0.14478)
		(layer "In13.Cu")
		(net "M_B_CPU1_SA_DQ<16>")
	)
	(segment
		(start 79.634842 -235.086652)
		(end 79.654908 -235.098082)
		(width 0.0889)
		(layer "In13.Cu")
		(net "M_B_CPU1_SA_DQ<16>")
	)
	(segment
		(start 77.41539 -233.613452)
		(end 78.225904 -234.423966)
		(width 0.0889)
		(layer "In13.Cu")
		(net "M_B_CPU1_SA_DQ<16>")
	)
	(segment
		(start 57.487312 -216.33053)
		(end 57.648856 -216.168986)
		(width 0.14478)
		(layer "In13.Cu")
		(net "M_B_CPU1_SA_DQ<16>")
	)
	(segment
		(start 58.59018 -216.621868)
		(end 58.751724 -216.460324)
		(width 0.14478)
		(layer "In13.Cu")
		(net "M_B_CPU1_SA_DQ<16>")
	)
	(segment
		(start 87.472774 -235.113068)
		(end 87.495126 -235.029756)
		(width 0.0889)
		(layer "In13.Cu")
		(net "M_B_CPU1_SA_DQ<16>")
	)
	(segment
		(start 58.428636 -216.859866)
		(end 58.59018 -216.698322)
		(width 0.14478)
		(layer "In13.Cu")
		(net "M_B_CPU1_SA_DQ<16>")
	)
	(segment
		(start 54.96052 -216.748106)
		(end 55.248302 -216.460324)
		(width 0.14478)
		(layer "In13.Cu")
		(net "M_B_CPU1_SA_DQ<16>")
	)
	(segment
		(start 60.226702 -216.460324)
		(end 60.621164 -216.854786)
		(width 0.14478)
		(layer "In13.Cu")
		(net "M_B_CPU1_SA_DQ<16>")
	)
	(segment
		(start 56.774334 -216.168986)
		(end 56.935878 -216.33053)
		(width 0.14478)
		(layer "In13.Cu")
		(net "M_B_CPU1_SA_DQ<16>")
	)
	(segment
		(start 82.453988 -235.086906)
		(end 82.46237 -235.091732)
		(width 0.0889)
		(layer "In13.Cu")
		(net "M_B_CPU1_SA_DQ<16>")
	)
	(segment
		(start 55.83301 -216.698322)
		(end 55.994554 -216.859866)
		(width 0.14478)
		(layer "In13.Cu")
		(net "M_B_CPU1_SA_DQ<16>")
	)
	(arc
		(start 79.478886 -235.025692)
		(mid 79.559152 -235.050469)
		(end 79.634842 -235.086906)
		(width 0.0889)
		(layer "In13.Cu")
		(net "M_B_CPU1_SA_DQ<16>")
	)
	(arc
		(start 86.21395 -235.086906)
		(mid 86.396201 -235.137256)
		(end 86.57971 -235.091732)
		(width 0.0889)
		(layer "In13.Cu")
		(net "M_B_CPU1_SA_DQ<16>")
	)
	(arc
		(start 81.513934 -235.086906)
		(mid 81.696185 -235.137256)
		(end 81.879694 -235.091732)
		(width 0.0889)
		(layer "In13.Cu")
		(net "M_B_CPU1_SA_DQ<16>")
	)
	(arc
		(start 87.162386 -235.091732)
		(mid 87.315256 -235.136373)
		(end 87.472774 -235.113068)
		(width 0.0889)
		(layer "In13.Cu")
		(net "M_B_CPU1_SA_DQ<16>")
	)
	(arc
		(start 84.334096 -235.086906)
		(mid 84.52104 -235.137161)
		(end 84.707984 -235.086906)
		(width 0.0889)
		(layer "In13.Cu")
		(net "M_B_CPU1_SA_DQ<16>")
	)
	(arc
		(start 83.768184 -235.086906)
		(mid 84.05114 -235.010729)
		(end 84.334096 -235.086906)
		(width 0.0889)
		(layer "In13.Cu")
		(net "M_B_CPU1_SA_DQ<16>")
	)
	(arc
		(start 82.82813 -235.086906)
		(mid 83.111086 -235.010729)
		(end 83.394042 -235.086906)
		(width 0.0889)
		(layer "In13.Cu")
		(net "M_B_CPU1_SA_DQ<16>")
	)
	(arc
		(start 86.588092 -235.086906)
		(mid 86.871048 -235.010729)
		(end 87.154004 -235.086906)
		(width 0.0889)
		(layer "In13.Cu")
		(net "M_B_CPU1_SA_DQ<16>")
	)
	(arc
		(start 83.402424 -235.091732)
		(mid 83.585932 -235.137226)
		(end 83.768184 -235.086906)
		(width 0.0889)
		(layer "In13.Cu")
		(net "M_B_CPU1_SA_DQ<16>")
	)
	(arc
		(start 85.648038 -235.086906)
		(mid 85.930994 -235.010729)
		(end 86.21395 -235.086906)
		(width 0.0889)
		(layer "In13.Cu")
		(net "M_B_CPU1_SA_DQ<16>")
	)
	(arc
		(start 80.948022 -235.086906)
		(mid 81.230978 -235.010729)
		(end 81.513934 -235.086906)
		(width 0.0889)
		(layer "In13.Cu")
		(net "M_B_CPU1_SA_DQ<16>")
	)
	(arc
		(start 82.46237 -235.091732)
		(mid 82.645878 -235.137226)
		(end 82.82813 -235.086906)
		(width 0.0889)
		(layer "In13.Cu")
		(net "M_B_CPU1_SA_DQ<16>")
	)
	(arc
		(start 80.574134 -235.086906)
		(mid 80.761078 -235.137161)
		(end 80.948022 -235.086906)
		(width 0.0889)
		(layer "In13.Cu")
		(net "M_B_CPU1_SA_DQ<16>")
	)
	(arc
		(start 85.273896 -235.086906)
		(mid 85.456147 -235.137256)
		(end 85.639656 -235.091732)
		(width 0.0889)
		(layer "In13.Cu")
		(net "M_B_CPU1_SA_DQ<16>")
	)
	(arc
		(start 80.008222 -235.086906)
		(mid 80.291178 -235.010729)
		(end 80.574134 -235.086906)
		(width 0.0889)
		(layer "In13.Cu")
		(net "M_B_CPU1_SA_DQ<16>")
	)
	(arc
		(start 81.888076 -235.086906)
		(mid 82.171032 -235.010729)
		(end 82.453988 -235.086906)
		(width 0.0889)
		(layer "In13.Cu")
		(net "M_B_CPU1_SA_DQ<16>")
	)
	(arc
		(start 84.707984 -235.086906)
		(mid 84.99094 -235.010729)
		(end 85.273896 -235.086906)
		(width 0.0889)
		(layer "In13.Cu")
		(net "M_B_CPU1_SA_DQ<16>")
	)
	(arc
		(start 79.654908 -235.098082)
		(mid 79.832986 -235.137066)
		(end 80.008222 -235.086906)
		(width 0.0889)
		(layer "In13.Cu")
		(net "M_B_CPU1_SA_DQ<16>")
	)
	(segment
		(start 89.687908 -235.030264)
		(end 89.221056 -234.764326)
		(width 0.10668)
		(layer "F.Cu")
		(net "M_B_CPU1_SA_DQ<15>")
	)
	(segment
		(start 69.74205 -226.862386)
		(end 75.116182 -232.236518)
		(width 0.14478)
		(layer "In13.Cu")
		(net "M_B_CPU1_SA_DQ<15>")
	)
	(segment
		(start 88.97112 -234.473496)
		(end 89.067132 -234.498896)
		(width 0.0889)
		(layer "In13.Cu")
		(net "M_B_CPU1_SA_DQ<15>")
	)
	(segment
		(start 81.879694 -234.43692)
		(end 81.888076 -234.441746)
		(width 0.0889)
		(layer "In13.Cu")
		(net "M_B_CPU1_SA_DQ<15>")
	)
	(segment
		(start 79.391764 -234.3912)
		(end 79.821024 -234.3912)
		(width 0.0889)
		(layer "In13.Cu")
		(net "M_B_CPU1_SA_DQ<15>")
	)
	(segment
		(start 87.154004 -234.441746)
		(end 87.162386 -234.43692)
		(width 0.0889)
		(layer "In13.Cu")
		(net "M_B_CPU1_SA_DQ<15>")
	)
	(segment
		(start 83.394042 -234.441746)
		(end 83.402424 -234.43692)
		(width 0.0889)
		(layer "In13.Cu")
		(net "M_B_CPU1_SA_DQ<15>")
	)
	(segment
		(start 82.453988 -234.441746)
		(end 82.46237 -234.43692)
		(width 0.0889)
		(layer "In13.Cu")
		(net "M_B_CPU1_SA_DQ<15>")
	)
	(segment
		(start 48.598836 -215.330024)
		(end 48.598836 -215.606884)
		(width 0.14478)
		(layer "In13.Cu")
		(net "M_B_CPU1_SA_DQ<15>")
	)
	(segment
		(start 69.74205 -225.196146)
		(end 69.74205 -226.862386)
		(width 0.14478)
		(layer "In13.Cu")
		(net "M_B_CPU1_SA_DQ<15>")
	)
	(segment
		(start 86.57971 -234.43692)
		(end 86.588092 -234.441746)
		(width 0.0889)
		(layer "In13.Cu")
		(net "M_B_CPU1_SA_DQ<15>")
	)
	(segment
		(start 85.639656 -234.43692)
		(end 85.648038 -234.441746)
		(width 0.0889)
		(layer "In13.Cu")
		(net "M_B_CPU1_SA_DQ<15>")
	)
	(segment
		(start 60.156344 -215.61044)
		(end 69.74205 -225.196146)
		(width 0.14478)
		(layer "In13.Cu")
		(net "M_B_CPU1_SA_DQ<15>")
	)
	(segment
		(start 76.84643 -232.541826)
		(end 77.90307 -233.598466)
		(width 0.0889)
		(layer "In13.Cu")
		(net "M_B_CPU1_SA_DQ<15>")
	)
	(segment
		(start 50.222404 -214.760302)
		(end 52.622704 -214.760302)
		(width 0.14478)
		(layer "In13.Cu")
		(net "M_B_CPU1_SA_DQ<15>")
	)
	(segment
		(start 52.622704 -214.760302)
		(end 53.70449 -215.208358)
		(width 0.14478)
		(layer "In13.Cu")
		(net "M_B_CPU1_SA_DQ<15>")
	)
	(segment
		(start 78.59903 -233.598466)
		(end 79.391764 -234.3912)
		(width 0.0889)
		(layer "In13.Cu")
		(net "M_B_CPU1_SA_DQ<15>")
	)
	(segment
		(start 76.46035 -232.541826)
		(end 76.84643 -232.541826)
		(width 0.0889)
		(layer "In13.Cu")
		(net "M_B_CPU1_SA_DQ<15>")
	)
	(segment
		(start 75.93457 -232.236518)
		(end 76.155042 -232.236518)
		(width 0.0889)
		(layer "In13.Cu")
		(net "M_B_CPU1_SA_DQ<15>")
	)
	(segment
		(start 89.067132 -234.498896)
		(end 89.221056 -234.764326)
		(width 0.0889)
		(layer "In13.Cu")
		(net "M_B_CPU1_SA_DQ<15>")
	)
	(segment
		(start 48.454056 -215.185244)
		(end 48.598836 -215.330024)
		(width 0.14478)
		(layer "In13.Cu")
		(net "M_B_CPU1_SA_DQ<15>")
	)
	(segment
		(start 75.116182 -232.236518)
		(end 75.93457 -232.236518)
		(width 0.14478)
		(layer "In13.Cu")
		(net "M_B_CPU1_SA_DQ<15>")
	)
	(segment
		(start 88.094058 -234.441746)
		(end 88.10244 -234.43692)
		(width 0.0889)
		(layer "In13.Cu")
		(net "M_B_CPU1_SA_DQ<15>")
	)
	(segment
		(start 48.598836 -215.606884)
		(end 48.743616 -215.751664)
		(width 0.14478)
		(layer "In13.Cu")
		(net "M_B_CPU1_SA_DQ<15>")
	)
	(segment
		(start 53.70449 -215.208358)
		(end 54.106572 -215.61044)
		(width 0.14478)
		(layer "In13.Cu")
		(net "M_B_CPU1_SA_DQ<15>")
	)
	(segment
		(start 49.797462 -215.185244)
		(end 50.222404 -214.760302)
		(width 0.14478)
		(layer "In13.Cu")
		(net "M_B_CPU1_SA_DQ<15>")
	)
	(segment
		(start 49.150016 -215.606884)
		(end 49.150016 -215.330024)
		(width 0.14478)
		(layer "In13.Cu")
		(net "M_B_CPU1_SA_DQ<15>")
	)
	(segment
		(start 54.106572 -215.61044)
		(end 60.156344 -215.61044)
		(width 0.14478)
		(layer "In13.Cu")
		(net "M_B_CPU1_SA_DQ<15>")
	)
	(segment
		(start 76.155042 -232.236518)
		(end 76.46035 -232.541826)
		(width 0.0889)
		(layer "In13.Cu")
		(net "M_B_CPU1_SA_DQ<15>")
	)
	(segment
		(start 77.90307 -233.598466)
		(end 78.59903 -233.598466)
		(width 0.0889)
		(layer "In13.Cu")
		(net "M_B_CPU1_SA_DQ<15>")
	)
	(segment
		(start 49.294796 -215.185244)
		(end 49.797462 -215.185244)
		(width 0.14478)
		(layer "In13.Cu")
		(net "M_B_CPU1_SA_DQ<15>")
	)
	(segment
		(start 47.784004 -215.185244)
		(end 48.454056 -215.185244)
		(width 0.14478)
		(layer "In13.Cu")
		(net "M_B_CPU1_SA_DQ<15>")
	)
	(segment
		(start 49.005236 -215.751664)
		(end 49.150016 -215.606884)
		(width 0.14478)
		(layer "In13.Cu")
		(net "M_B_CPU1_SA_DQ<15>")
	)
	(segment
		(start 48.743616 -215.751664)
		(end 49.005236 -215.751664)
		(width 0.14478)
		(layer "In13.Cu")
		(net "M_B_CPU1_SA_DQ<15>")
	)
	(segment
		(start 49.150016 -215.330024)
		(end 49.294796 -215.185244)
		(width 0.14478)
		(layer "In13.Cu")
		(net "M_B_CPU1_SA_DQ<15>")
	)
	(arc
		(start 83.402424 -234.43692)
		(mid 83.585932 -234.391426)
		(end 83.768184 -234.441746)
		(width 0.0889)
		(layer "In13.Cu")
		(net "M_B_CPU1_SA_DQ<15>")
	)
	(arc
		(start 79.821024 -234.3912)
		(mid 79.917971 -234.404083)
		(end 80.008222 -234.441746)
		(width 0.0889)
		(layer "In13.Cu")
		(net "M_B_CPU1_SA_DQ<15>")
	)
	(arc
		(start 85.648038 -234.441746)
		(mid 85.930994 -234.517923)
		(end 86.21395 -234.441746)
		(width 0.0889)
		(layer "In13.Cu")
		(net "M_B_CPU1_SA_DQ<15>")
	)
	(arc
		(start 82.46237 -234.43692)
		(mid 82.645878 -234.391426)
		(end 82.82813 -234.441746)
		(width 0.0889)
		(layer "In13.Cu")
		(net "M_B_CPU1_SA_DQ<15>")
	)
	(arc
		(start 80.008222 -234.441746)
		(mid 80.291178 -234.517923)
		(end 80.574134 -234.441746)
		(width 0.0889)
		(layer "In13.Cu")
		(net "M_B_CPU1_SA_DQ<15>")
	)
	(arc
		(start 83.768184 -234.441746)
		(mid 84.05114 -234.517923)
		(end 84.334096 -234.441746)
		(width 0.0889)
		(layer "In13.Cu")
		(net "M_B_CPU1_SA_DQ<15>")
	)
	(arc
		(start 88.10244 -234.43692)
		(mid 88.285948 -234.391426)
		(end 88.4682 -234.441746)
		(width 0.0889)
		(layer "In13.Cu")
		(net "M_B_CPU1_SA_DQ<15>")
	)
	(arc
		(start 80.574134 -234.441746)
		(mid 80.761078 -234.391491)
		(end 80.948022 -234.441746)
		(width 0.0889)
		(layer "In13.Cu")
		(net "M_B_CPU1_SA_DQ<15>")
	)
	(arc
		(start 86.588092 -234.441746)
		(mid 86.871048 -234.517923)
		(end 87.154004 -234.441746)
		(width 0.0889)
		(layer "In13.Cu")
		(net "M_B_CPU1_SA_DQ<15>")
	)
	(arc
		(start 86.21395 -234.441746)
		(mid 86.396201 -234.391396)
		(end 86.57971 -234.43692)
		(width 0.0889)
		(layer "In13.Cu")
		(net "M_B_CPU1_SA_DQ<15>")
	)
	(arc
		(start 84.334096 -234.441746)
		(mid 84.52104 -234.391491)
		(end 84.707984 -234.441746)
		(width 0.0889)
		(layer "In13.Cu")
		(net "M_B_CPU1_SA_DQ<15>")
	)
	(arc
		(start 87.162386 -234.43692)
		(mid 87.345894 -234.391426)
		(end 87.528146 -234.441746)
		(width 0.0889)
		(layer "In13.Cu")
		(net "M_B_CPU1_SA_DQ<15>")
	)
	(arc
		(start 87.528146 -234.441746)
		(mid 87.811102 -234.517923)
		(end 88.094058 -234.441746)
		(width 0.0889)
		(layer "In13.Cu")
		(net "M_B_CPU1_SA_DQ<15>")
	)
	(arc
		(start 82.82813 -234.441746)
		(mid 83.111086 -234.517923)
		(end 83.394042 -234.441746)
		(width 0.0889)
		(layer "In13.Cu")
		(net "M_B_CPU1_SA_DQ<15>")
	)
	(arc
		(start 81.513934 -234.441746)
		(mid 81.696185 -234.391396)
		(end 81.879694 -234.43692)
		(width 0.0889)
		(layer "In13.Cu")
		(net "M_B_CPU1_SA_DQ<15>")
	)
	(arc
		(start 85.273896 -234.441746)
		(mid 85.456147 -234.391396)
		(end 85.639656 -234.43692)
		(width 0.0889)
		(layer "In13.Cu")
		(net "M_B_CPU1_SA_DQ<15>")
	)
	(arc
		(start 81.888076 -234.441746)
		(mid 82.171032 -234.517923)
		(end 82.453988 -234.441746)
		(width 0.0889)
		(layer "In13.Cu")
		(net "M_B_CPU1_SA_DQ<15>")
	)
	(arc
		(start 88.4682 -234.441746)
		(mid 88.715913 -234.516966)
		(end 88.97112 -234.473496)
		(width 0.0889)
		(layer "In13.Cu")
		(net "M_B_CPU1_SA_DQ<15>")
	)
	(arc
		(start 80.948022 -234.441746)
		(mid 81.230978 -234.517923)
		(end 81.513934 -234.441746)
		(width 0.0889)
		(layer "In13.Cu")
		(net "M_B_CPU1_SA_DQ<15>")
	)
	(arc
		(start 84.707984 -234.441746)
		(mid 84.99094 -234.517923)
		(end 85.273896 -234.441746)
		(width 0.0889)
		(layer "In13.Cu")
		(net "M_B_CPU1_SA_DQ<15>")
	)
	(segment
		(start 88.277954 -234.220258)
		(end 87.811102 -233.95432)
		(width 0.10668)
		(layer "F.Cu")
		(net "M_B_CPU1_SA_DQ<14>")
	)
	(segment
		(start 77.21727 -231.642666)
		(end 77.21727 -231.957626)
		(width 0.0889)
		(layer "In13.Cu")
		(net "M_B_CPU1_SA_DQ<14>")
	)
	(segment
		(start 54.793642 -213.910418)
		(end 59.728608 -213.910418)
		(width 0.14478)
		(layer "In13.Cu")
		(net "M_B_CPU1_SA_DQ<14>")
	)
	(segment
		(start 83.289648 -233.626914)
		(end 83.29803 -233.63174)
		(width 0.0889)
		(layer "In13.Cu")
		(net "M_B_CPU1_SA_DQ<14>")
	)
	(segment
		(start 78.8035 -232.922826)
		(end 79.423006 -233.542332)
		(width 0.0889)
		(layer "In13.Cu")
		(net "M_B_CPU1_SA_DQ<14>")
	)
	(segment
		(start 49.797462 -213.485222)
		(end 50.222404 -213.06028)
		(width 0.14478)
		(layer "In13.Cu")
		(net "M_B_CPU1_SA_DQ<14>")
	)
	(segment
		(start 87.656924 -233.68889)
		(end 87.811102 -233.95432)
		(width 0.0889)
		(layer "In13.Cu")
		(net "M_B_CPU1_SA_DQ<14>")
	)
	(segment
		(start 76.895452 -231.320848)
		(end 77.21727 -231.642666)
		(width 0.0889)
		(layer "In13.Cu")
		(net "M_B_CPU1_SA_DQ<14>")
	)
	(segment
		(start 48.729392 -214.164164)
		(end 48.874172 -214.308944)
		(width 0.14478)
		(layer "In13.Cu")
		(net "M_B_CPU1_SA_DQ<14>")
	)
	(segment
		(start 75.91933 -231.320848)
		(end 76.895452 -231.320848)
		(width 0.0889)
		(layer "In13.Cu")
		(net "M_B_CPU1_SA_DQ<14>")
	)
	(segment
		(start 84.803996 -233.63174)
		(end 84.812378 -233.626914)
		(width 0.0889)
		(layer "In13.Cu")
		(net "M_B_CPU1_SA_DQ<14>")
	)
	(segment
		(start 80.46974 -233.626914)
		(end 80.478122 -233.63174)
		(width 0.0889)
		(layer "In13.Cu")
		(net "M_B_CPU1_SA_DQ<14>")
	)
	(segment
		(start 50.222404 -213.06028)
		(end 53.12029 -213.06028)
		(width 0.14478)
		(layer "In13.Cu")
		(net "M_B_CPU1_SA_DQ<14>")
	)
	(segment
		(start 87.560658 -233.66349)
		(end 87.656924 -233.68889)
		(width 0.0889)
		(layer "In13.Cu")
		(net "M_B_CPU1_SA_DQ<14>")
	)
	(segment
		(start 79.539592 -233.631994)
		(end 79.561182 -233.64444)
		(width 0.0889)
		(layer "In13.Cu")
		(net "M_B_CPU1_SA_DQ<14>")
	)
	(segment
		(start 49.135792 -214.308944)
		(end 49.280572 -214.164164)
		(width 0.14478)
		(layer "In13.Cu")
		(net "M_B_CPU1_SA_DQ<14>")
	)
	(segment
		(start 84.229702 -233.626914)
		(end 84.238084 -233.63174)
		(width 0.0889)
		(layer "In13.Cu")
		(net "M_B_CPU1_SA_DQ<14>")
	)
	(segment
		(start 48.584612 -213.485222)
		(end 48.729392 -213.630002)
		(width 0.14478)
		(layer "In13.Cu")
		(net "M_B_CPU1_SA_DQ<14>")
	)
	(segment
		(start 49.425352 -213.485222)
		(end 49.797462 -213.485222)
		(width 0.14478)
		(layer "In13.Cu")
		(net "M_B_CPU1_SA_DQ<14>")
	)
	(segment
		(start 47.784004 -213.485222)
		(end 48.584612 -213.485222)
		(width 0.14478)
		(layer "In13.Cu")
		(net "M_B_CPU1_SA_DQ<14>")
	)
	(segment
		(start 70.65772 -224.83953)
		(end 70.65772 -226.50577)
		(width 0.14478)
		(layer "In13.Cu")
		(net "M_B_CPU1_SA_DQ<14>")
	)
	(segment
		(start 48.874172 -214.308944)
		(end 49.135792 -214.308944)
		(width 0.14478)
		(layer "In13.Cu")
		(net "M_B_CPU1_SA_DQ<14>")
	)
	(segment
		(start 81.044034 -233.63174)
		(end 81.052416 -233.626914)
		(width 0.0889)
		(layer "In13.Cu")
		(net "M_B_CPU1_SA_DQ<14>")
	)
	(segment
		(start 77.21727 -231.957626)
		(end 78.18247 -232.922826)
		(width 0.0889)
		(layer "In13.Cu")
		(net "M_B_CPU1_SA_DQ<14>")
	)
	(segment
		(start 53.12029 -213.06028)
		(end 53.388514 -213.328504)
		(width 0.14478)
		(layer "In13.Cu")
		(net "M_B_CPU1_SA_DQ<14>")
	)
	(segment
		(start 59.728608 -213.910418)
		(end 70.65772 -224.83953)
		(width 0.14478)
		(layer "In13.Cu")
		(net "M_B_CPU1_SA_DQ<14>")
	)
	(segment
		(start 49.280572 -214.164164)
		(end 49.280572 -213.630002)
		(width 0.14478)
		(layer "In13.Cu")
		(net "M_B_CPU1_SA_DQ<14>")
	)
	(segment
		(start 85.74405 -233.63174)
		(end 85.752432 -233.626914)
		(width 0.0889)
		(layer "In13.Cu")
		(net "M_B_CPU1_SA_DQ<14>")
	)
	(segment
		(start 49.280572 -213.630002)
		(end 49.425352 -213.485222)
		(width 0.14478)
		(layer "In13.Cu")
		(net "M_B_CPU1_SA_DQ<14>")
	)
	(segment
		(start 70.65772 -226.50577)
		(end 75.472798 -231.320848)
		(width 0.14478)
		(layer "In13.Cu")
		(net "M_B_CPU1_SA_DQ<14>")
	)
	(segment
		(start 53.388514 -213.328504)
		(end 54.793642 -213.910418)
		(width 0.14478)
		(layer "In13.Cu")
		(net "M_B_CPU1_SA_DQ<14>")
	)
	(segment
		(start 78.18247 -232.922826)
		(end 78.8035 -232.922826)
		(width 0.0889)
		(layer "In13.Cu")
		(net "M_B_CPU1_SA_DQ<14>")
	)
	(segment
		(start 48.729392 -213.630002)
		(end 48.729392 -214.164164)
		(width 0.14478)
		(layer "In13.Cu")
		(net "M_B_CPU1_SA_DQ<14>")
	)
	(segment
		(start 75.472798 -231.320848)
		(end 75.91933 -231.320848)
		(width 0.14478)
		(layer "In13.Cu")
		(net "M_B_CPU1_SA_DQ<14>")
	)
	(arc
		(start 81.984088 -233.63174)
		(mid 82.171032 -233.581485)
		(end 82.357976 -233.63174)
		(width 0.0889)
		(layer "In13.Cu")
		(net "M_B_CPU1_SA_DQ<14>")
	)
	(arc
		(start 83.863942 -233.63174)
		(mid 84.046193 -233.58139)
		(end 84.229702 -233.626914)
		(width 0.0889)
		(layer "In13.Cu")
		(net "M_B_CPU1_SA_DQ<14>")
	)
	(arc
		(start 80.10398 -233.63174)
		(mid 80.286231 -233.58139)
		(end 80.46974 -233.626914)
		(width 0.0889)
		(layer "In13.Cu")
		(net "M_B_CPU1_SA_DQ<14>")
	)
	(arc
		(start 81.052416 -233.626914)
		(mid 81.235924 -233.58142)
		(end 81.418176 -233.63174)
		(width 0.0889)
		(layer "In13.Cu")
		(net "M_B_CPU1_SA_DQ<14>")
	)
	(arc
		(start 79.561182 -233.64444)
		(mid 79.834211 -233.707759)
		(end 80.10398 -233.63174)
		(width 0.0889)
		(layer "In13.Cu")
		(net "M_B_CPU1_SA_DQ<14>")
	)
	(arc
		(start 79.423006 -233.542332)
		(mid 79.478355 -233.590991)
		(end 79.539592 -233.631994)
		(width 0.0889)
		(layer "In13.Cu")
		(net "M_B_CPU1_SA_DQ<14>")
	)
	(arc
		(start 85.178138 -233.63174)
		(mid 85.461094 -233.707917)
		(end 85.74405 -233.63174)
		(width 0.0889)
		(layer "In13.Cu")
		(net "M_B_CPU1_SA_DQ<14>")
	)
	(arc
		(start 87.057992 -233.63174)
		(mid 87.305588 -233.706918)
		(end 87.560658 -233.66349)
		(width 0.0889)
		(layer "In13.Cu")
		(net "M_B_CPU1_SA_DQ<14>")
	)
	(arc
		(start 86.118192 -233.63174)
		(mid 86.401148 -233.707917)
		(end 86.684104 -233.63174)
		(width 0.0889)
		(layer "In13.Cu")
		(net "M_B_CPU1_SA_DQ<14>")
	)
	(arc
		(start 85.752432 -233.626914)
		(mid 85.93594 -233.58142)
		(end 86.118192 -233.63174)
		(width 0.0889)
		(layer "In13.Cu")
		(net "M_B_CPU1_SA_DQ<14>")
	)
	(arc
		(start 80.478122 -233.63174)
		(mid 80.761078 -233.707917)
		(end 81.044034 -233.63174)
		(width 0.0889)
		(layer "In13.Cu")
		(net "M_B_CPU1_SA_DQ<14>")
	)
	(arc
		(start 86.684104 -233.63174)
		(mid 86.871048 -233.581485)
		(end 87.057992 -233.63174)
		(width 0.0889)
		(layer "In13.Cu")
		(net "M_B_CPU1_SA_DQ<14>")
	)
	(arc
		(start 84.238084 -233.63174)
		(mid 84.52104 -233.707917)
		(end 84.803996 -233.63174)
		(width 0.0889)
		(layer "In13.Cu")
		(net "M_B_CPU1_SA_DQ<14>")
	)
	(arc
		(start 82.357976 -233.63174)
		(mid 82.640932 -233.707917)
		(end 82.923888 -233.63174)
		(width 0.0889)
		(layer "In13.Cu")
		(net "M_B_CPU1_SA_DQ<14>")
	)
	(arc
		(start 81.418176 -233.63174)
		(mid 81.701132 -233.707917)
		(end 81.984088 -233.63174)
		(width 0.0889)
		(layer "In13.Cu")
		(net "M_B_CPU1_SA_DQ<14>")
	)
	(arc
		(start 83.29803 -233.63174)
		(mid 83.580986 -233.707917)
		(end 83.863942 -233.63174)
		(width 0.0889)
		(layer "In13.Cu")
		(net "M_B_CPU1_SA_DQ<14>")
	)
	(arc
		(start 84.812378 -233.626914)
		(mid 84.995886 -233.58142)
		(end 85.178138 -233.63174)
		(width 0.0889)
		(layer "In13.Cu")
		(net "M_B_CPU1_SA_DQ<14>")
	)
	(arc
		(start 82.923888 -233.63174)
		(mid 83.106139 -233.58139)
		(end 83.289648 -233.626914)
		(width 0.0889)
		(layer "In13.Cu")
		(net "M_B_CPU1_SA_DQ<14>")
	)
	(segment
		(start 89.218008 -234.220258)
		(end 88.751156 -233.95432)
		(width 0.10668)
		(layer "F.Cu")
		(net "M_B_CPU1_SA_DQ<13>")
	)
	(segment
		(start 78.678024 -233.407966)
		(end 79.470758 -234.2007)
		(width 0.0889)
		(layer "In13.Cu")
		(net "M_B_CPU1_SA_DQ<13>")
	)
	(segment
		(start 84.229702 -234.281726)
		(end 84.238084 -234.2769)
		(width 0.0889)
		(layer "In13.Cu")
		(net "M_B_CPU1_SA_DQ<13>")
	)
	(segment
		(start 80.46974 -234.281726)
		(end 80.478122 -234.2769)
		(width 0.0889)
		(layer "In13.Cu")
		(net "M_B_CPU1_SA_DQ<13>")
	)
	(segment
		(start 57.624218 -214.971376)
		(end 57.768998 -215.116156)
		(width 0.14478)
		(layer "In13.Cu")
		(net "M_B_CPU1_SA_DQ<13>")
	)
	(segment
		(start 58.175398 -214.511128)
		(end 58.320178 -214.366348)
		(width 0.14478)
		(layer "In13.Cu")
		(net "M_B_CPU1_SA_DQ<13>")
	)
	(segment
		(start 85.74405 -234.2769)
		(end 85.752432 -234.281726)
		(width 0.0889)
		(layer "In13.Cu")
		(net "M_B_CPU1_SA_DQ<13>")
	)
	(segment
		(start 84.803996 -234.2769)
		(end 84.812378 -234.281726)
		(width 0.0889)
		(layer "In13.Cu")
		(net "M_B_CPU1_SA_DQ<13>")
	)
	(segment
		(start 54.537102 -214.310722)
		(end 54.681882 -214.455502)
		(width 0.14478)
		(layer "In13.Cu")
		(net "M_B_CPU1_SA_DQ<13>")
	)
	(segment
		(start 52.535836 -214.165942)
		(end 52.535836 -213.663276)
		(width 0.14478)
		(layer "In13.Cu")
		(net "M_B_CPU1_SA_DQ<13>")
	)
	(segment
		(start 54.84495 -215.149684)
		(end 55.075328 -215.149684)
		(width 0.14478)
		(layer "In13.Cu")
		(net "M_B_CPU1_SA_DQ<13>")
	)
	(segment
		(start 78.106016 -233.407966)
		(end 78.678024 -233.407966)
		(width 0.0889)
		(layer "In13.Cu")
		(net "M_B_CPU1_SA_DQ<13>")
	)
	(segment
		(start 88.882728 -234.303062)
		(end 88.90508 -234.21975)
		(width 0.0889)
		(layer "In13.Cu")
		(net "M_B_CPU1_SA_DQ<13>")
	)
	(segment
		(start 53.087016 -213.663276)
		(end 53.087016 -214.165942)
		(width 0.14478)
		(layer "In13.Cu")
		(net "M_B_CPU1_SA_DQ<13>")
	)
	(segment
		(start 87.989664 -234.281726)
		(end 87.998046 -234.2769)
		(width 0.0889)
		(layer "In13.Cu")
		(net "M_B_CPU1_SA_DQ<13>")
	)
	(segment
		(start 83.289648 -234.281726)
		(end 83.29803 -234.2769)
		(width 0.0889)
		(layer "In13.Cu")
		(net "M_B_CPU1_SA_DQ<13>")
	)
	(segment
		(start 51.90871 -214.310722)
		(end 52.391056 -214.310722)
		(width 0.14478)
		(layer "In13.Cu")
		(net "M_B_CPU1_SA_DQ<13>")
	)
	(segment
		(start 53.087016 -214.165942)
		(end 53.231796 -214.310722)
		(width 0.14478)
		(layer "In13.Cu")
		(net "M_B_CPU1_SA_DQ<13>")
	)
	(segment
		(start 58.175398 -214.971376)
		(end 58.175398 -214.511128)
		(width 0.14478)
		(layer "In13.Cu")
		(net "M_B_CPU1_SA_DQ<13>")
	)
	(segment
		(start 57.768998 -215.116156)
		(end 58.030618 -215.116156)
		(width 0.14478)
		(layer "In13.Cu")
		(net "M_B_CPU1_SA_DQ<13>")
	)
	(segment
		(start 54.681882 -214.986616)
		(end 54.84495 -215.149684)
		(width 0.14478)
		(layer "In13.Cu")
		(net "M_B_CPU1_SA_DQ<13>")
	)
	(segment
		(start 55.401464 -214.760302)
		(end 55.59171 -214.760302)
		(width 0.14478)
		(layer "In13.Cu")
		(net "M_B_CPU1_SA_DQ<13>")
	)
	(segment
		(start 59.548522 -214.366348)
		(end 70.20306 -225.020886)
		(width 0.14478)
		(layer "In13.Cu")
		(net "M_B_CPU1_SA_DQ<13>")
	)
	(segment
		(start 88.90508 -234.21975)
		(end 88.751156 -233.95432)
		(width 0.0889)
		(layer "In13.Cu")
		(net "M_B_CPU1_SA_DQ<13>")
	)
	(segment
		(start 52.391056 -214.310722)
		(end 52.535836 -214.165942)
		(width 0.14478)
		(layer "In13.Cu")
		(net "M_B_CPU1_SA_DQ<13>")
	)
	(segment
		(start 53.231796 -214.310722)
		(end 54.537102 -214.310722)
		(width 0.14478)
		(layer "In13.Cu")
		(net "M_B_CPU1_SA_DQ<13>")
	)
	(segment
		(start 58.320178 -214.366348)
		(end 59.548522 -214.366348)
		(width 0.14478)
		(layer "In13.Cu")
		(net "M_B_CPU1_SA_DQ<13>")
	)
	(segment
		(start 70.20306 -225.020886)
		(end 70.20306 -226.687126)
		(width 0.14478)
		(layer "In13.Cu")
		(net "M_B_CPU1_SA_DQ<13>")
	)
	(segment
		(start 58.030618 -215.116156)
		(end 58.175398 -214.971376)
		(width 0.14478)
		(layer "In13.Cu")
		(net "M_B_CPU1_SA_DQ<13>")
	)
	(segment
		(start 56.521858 -214.971376)
		(end 56.666638 -215.116156)
		(width 0.14478)
		(layer "In13.Cu")
		(net "M_B_CPU1_SA_DQ<13>")
	)
	(segment
		(start 76.937616 -232.239566)
		(end 78.106016 -233.407966)
		(width 0.0889)
		(layer "In13.Cu")
		(net "M_B_CPU1_SA_DQ<13>")
	)
	(segment
		(start 52.680616 -213.518496)
		(end 52.942236 -213.518496)
		(width 0.14478)
		(layer "In13.Cu")
		(net "M_B_CPU1_SA_DQ<13>")
	)
	(segment
		(start 76.62037 -232.239566)
		(end 76.937616 -232.239566)
		(width 0.0889)
		(layer "In13.Cu")
		(net "M_B_CPU1_SA_DQ<13>")
	)
	(segment
		(start 79.470758 -234.2007)
		(end 79.821278 -234.2007)
		(width 0.0889)
		(layer "In13.Cu")
		(net "M_B_CPU1_SA_DQ<13>")
	)
	(segment
		(start 56.928258 -215.116156)
		(end 57.073038 -214.971376)
		(width 0.14478)
		(layer "In13.Cu")
		(net "M_B_CPU1_SA_DQ<13>")
	)
	(segment
		(start 57.073038 -214.511128)
		(end 57.217818 -214.366348)
		(width 0.14478)
		(layer "In13.Cu")
		(net "M_B_CPU1_SA_DQ<13>")
	)
	(segment
		(start 75.97013 -231.775508)
		(end 76.156312 -231.775508)
		(width 0.0889)
		(layer "In13.Cu")
		(net "M_B_CPU1_SA_DQ<13>")
	)
	(segment
		(start 55.985664 -214.366348)
		(end 56.377078 -214.366348)
		(width 0.14478)
		(layer "In13.Cu")
		(net "M_B_CPU1_SA_DQ<13>")
	)
	(segment
		(start 81.044034 -234.2769)
		(end 81.052416 -234.281726)
		(width 0.0889)
		(layer "In13.Cu")
		(net "M_B_CPU1_SA_DQ<13>")
	)
	(segment
		(start 75.291442 -231.775508)
		(end 75.97013 -231.775508)
		(width 0.14478)
		(layer "In13.Cu")
		(net "M_B_CPU1_SA_DQ<13>")
	)
	(segment
		(start 54.681882 -214.455502)
		(end 54.681882 -214.986616)
		(width 0.14478)
		(layer "In13.Cu")
		(net "M_B_CPU1_SA_DQ<13>")
	)
	(segment
		(start 55.59171 -214.760302)
		(end 55.985664 -214.366348)
		(width 0.14478)
		(layer "In13.Cu")
		(net "M_B_CPU1_SA_DQ<13>")
	)
	(segment
		(start 57.479438 -214.366348)
		(end 57.624218 -214.511128)
		(width 0.14478)
		(layer "In13.Cu")
		(net "M_B_CPU1_SA_DQ<13>")
	)
	(segment
		(start 52.535836 -213.663276)
		(end 52.680616 -213.518496)
		(width 0.14478)
		(layer "In13.Cu")
		(net "M_B_CPU1_SA_DQ<13>")
	)
	(segment
		(start 70.20306 -226.687126)
		(end 75.291442 -231.775508)
		(width 0.14478)
		(layer "In13.Cu")
		(net "M_B_CPU1_SA_DQ<13>")
	)
	(segment
		(start 52.942236 -213.518496)
		(end 53.087016 -213.663276)
		(width 0.14478)
		(layer "In13.Cu")
		(net "M_B_CPU1_SA_DQ<13>")
	)
	(segment
		(start 57.073038 -214.971376)
		(end 57.073038 -214.511128)
		(width 0.14478)
		(layer "In13.Cu")
		(net "M_B_CPU1_SA_DQ<13>")
	)
	(segment
		(start 56.377078 -214.366348)
		(end 56.521858 -214.511128)
		(width 0.14478)
		(layer "In13.Cu")
		(net "M_B_CPU1_SA_DQ<13>")
	)
	(segment
		(start 51.884072 -214.33536)
		(end 51.90871 -214.310722)
		(width 0.14478)
		(layer "In13.Cu")
		(net "M_B_CPU1_SA_DQ<13>")
	)
	(segment
		(start 55.238396 -214.92337)
		(end 55.401464 -214.760302)
		(width 0.14478)
		(layer "In13.Cu")
		(net "M_B_CPU1_SA_DQ<13>")
	)
	(segment
		(start 56.521858 -214.511128)
		(end 56.521858 -214.971376)
		(width 0.14478)
		(layer "In13.Cu")
		(net "M_B_CPU1_SA_DQ<13>")
	)
	(segment
		(start 57.624218 -214.511128)
		(end 57.624218 -214.971376)
		(width 0.14478)
		(layer "In13.Cu")
		(net "M_B_CPU1_SA_DQ<13>")
	)
	(segment
		(start 55.075328 -215.149684)
		(end 55.238396 -214.986616)
		(width 0.14478)
		(layer "In13.Cu")
		(net "M_B_CPU1_SA_DQ<13>")
	)
	(segment
		(start 57.217818 -214.366348)
		(end 57.479438 -214.366348)
		(width 0.14478)
		(layer "In13.Cu")
		(net "M_B_CPU1_SA_DQ<13>")
	)
	(segment
		(start 55.238396 -214.986616)
		(end 55.238396 -214.92337)
		(width 0.14478)
		(layer "In13.Cu")
		(net "M_B_CPU1_SA_DQ<13>")
	)
	(segment
		(start 56.666638 -215.116156)
		(end 56.928258 -215.116156)
		(width 0.14478)
		(layer "In13.Cu")
		(net "M_B_CPU1_SA_DQ<13>")
	)
	(segment
		(start 76.156312 -231.775508)
		(end 76.62037 -232.239566)
		(width 0.0889)
		(layer "In13.Cu")
		(net "M_B_CPU1_SA_DQ<13>")
	)
	(arc
		(start 86.684104 -234.2769)
		(mid 86.871048 -234.327155)
		(end 87.057992 -234.2769)
		(width 0.0889)
		(layer "In13.Cu")
		(net "M_B_CPU1_SA_DQ<13>")
	)
	(arc
		(start 87.057992 -234.2769)
		(mid 87.340948 -234.200723)
		(end 87.623904 -234.2769)
		(width 0.0889)
		(layer "In13.Cu")
		(net "M_B_CPU1_SA_DQ<13>")
	)
	(arc
		(start 87.998046 -234.2769)
		(mid 88.281002 -234.200723)
		(end 88.563958 -234.2769)
		(width 0.0889)
		(layer "In13.Cu")
		(net "M_B_CPU1_SA_DQ<13>")
	)
	(arc
		(start 83.29803 -234.2769)
		(mid 83.580986 -234.200723)
		(end 83.863942 -234.2769)
		(width 0.0889)
		(layer "In13.Cu")
		(net "M_B_CPU1_SA_DQ<13>")
	)
	(arc
		(start 87.623904 -234.2769)
		(mid 87.806155 -234.32725)
		(end 87.989664 -234.281726)
		(width 0.0889)
		(layer "In13.Cu")
		(net "M_B_CPU1_SA_DQ<13>")
	)
	(arc
		(start 84.238084 -234.2769)
		(mid 84.52104 -234.200723)
		(end 84.803996 -234.2769)
		(width 0.0889)
		(layer "In13.Cu")
		(net "M_B_CPU1_SA_DQ<13>")
	)
	(arc
		(start 88.563958 -234.2769)
		(mid 88.720396 -234.325871)
		(end 88.882728 -234.303062)
		(width 0.0889)
		(layer "In13.Cu")
		(net "M_B_CPU1_SA_DQ<13>")
	)
	(arc
		(start 82.923888 -234.2769)
		(mid 83.106139 -234.32725)
		(end 83.289648 -234.281726)
		(width 0.0889)
		(layer "In13.Cu")
		(net "M_B_CPU1_SA_DQ<13>")
	)
	(arc
		(start 84.812378 -234.281726)
		(mid 84.995886 -234.32722)
		(end 85.178138 -234.2769)
		(width 0.0889)
		(layer "In13.Cu")
		(net "M_B_CPU1_SA_DQ<13>")
	)
	(arc
		(start 83.863942 -234.2769)
		(mid 84.046193 -234.32725)
		(end 84.229702 -234.281726)
		(width 0.0889)
		(layer "In13.Cu")
		(net "M_B_CPU1_SA_DQ<13>")
	)
	(arc
		(start 81.052416 -234.281726)
		(mid 81.235924 -234.32722)
		(end 81.418176 -234.2769)
		(width 0.0889)
		(layer "In13.Cu")
		(net "M_B_CPU1_SA_DQ<13>")
	)
	(arc
		(start 80.478122 -234.2769)
		(mid 80.761078 -234.200723)
		(end 81.044034 -234.2769)
		(width 0.0889)
		(layer "In13.Cu")
		(net "M_B_CPU1_SA_DQ<13>")
	)
	(arc
		(start 81.418176 -234.2769)
		(mid 81.701132 -234.200723)
		(end 81.984088 -234.2769)
		(width 0.0889)
		(layer "In13.Cu")
		(net "M_B_CPU1_SA_DQ<13>")
	)
	(arc
		(start 80.10398 -234.2769)
		(mid 80.286231 -234.32725)
		(end 80.46974 -234.281726)
		(width 0.0889)
		(layer "In13.Cu")
		(net "M_B_CPU1_SA_DQ<13>")
	)
	(arc
		(start 85.178138 -234.2769)
		(mid 85.461094 -234.200723)
		(end 85.74405 -234.2769)
		(width 0.0889)
		(layer "In13.Cu")
		(net "M_B_CPU1_SA_DQ<13>")
	)
	(arc
		(start 85.752432 -234.281726)
		(mid 85.93594 -234.32722)
		(end 86.118192 -234.2769)
		(width 0.0889)
		(layer "In13.Cu")
		(net "M_B_CPU1_SA_DQ<13>")
	)
	(arc
		(start 82.357976 -234.2769)
		(mid 82.640932 -234.200723)
		(end 82.923888 -234.2769)
		(width 0.0889)
		(layer "In13.Cu")
		(net "M_B_CPU1_SA_DQ<13>")
	)
	(arc
		(start 86.118192 -234.2769)
		(mid 86.401148 -234.200723)
		(end 86.684104 -234.2769)
		(width 0.0889)
		(layer "In13.Cu")
		(net "M_B_CPU1_SA_DQ<13>")
	)
	(arc
		(start 81.984088 -234.2769)
		(mid 82.171032 -234.327155)
		(end 82.357976 -234.2769)
		(width 0.0889)
		(layer "In13.Cu")
		(net "M_B_CPU1_SA_DQ<13>")
	)
	(arc
		(start 79.821278 -234.2007)
		(mid 79.967668 -234.220111)
		(end 80.10398 -234.2769)
		(width 0.0889)
		(layer "In13.Cu")
		(net "M_B_CPU1_SA_DQ<13>")
	)
	(segment
		(start 87.8078 -233.410252)
		(end 87.340948 -233.144314)
		(width 0.10668)
		(layer "F.Cu")
		(net "M_B_CPU1_SA_DQ<12>")
	)
	(segment
		(start 72.974454 -227.97262)
		(end 72.974454 -228.186488)
		(width 0.14478)
		(layer "In13.Cu")
		(net "M_B_CPU1_SA_DQ<12>")
	)
	(segment
		(start 78.882494 -232.732326)
		(end 79.55788 -233.407712)
		(width 0.0889)
		(layer "In13.Cu")
		(net "M_B_CPU1_SA_DQ<12>")
	)
	(segment
		(start 57.857898 -213.069932)
		(end 58.019442 -213.231476)
		(width 0.14478)
		(layer "In13.Cu")
		(net "M_B_CPU1_SA_DQ<12>")
	)
	(segment
		(start 75.91933 -230.871268)
		(end 76.232512 -230.871268)
		(width 0.0889)
		(layer "In13.Cu")
		(net "M_B_CPU1_SA_DQ<12>")
	)
	(segment
		(start 57.468008 -213.231476)
		(end 57.629552 -213.069932)
		(width 0.14478)
		(layer "In13.Cu")
		(net "M_B_CPU1_SA_DQ<12>")
	)
	(segment
		(start 73.471278 -228.469444)
		(end 73.754234 -228.7524)
		(width 0.14478)
		(layer "In13.Cu")
		(net "M_B_CPU1_SA_DQ<12>")
	)
	(segment
		(start 52.358544 -212.6107)
		(end 52.503324 -212.46592)
		(width 0.14478)
		(layer "In13.Cu")
		(net "M_B_CPU1_SA_DQ<12>")
	)
	(segment
		(start 58.409332 -213.456266)
		(end 58.570876 -213.294722)
		(width 0.14478)
		(layer "In13.Cu")
		(net "M_B_CPU1_SA_DQ<12>")
	)
	(segment
		(start 76.232512 -230.871268)
		(end 76.43241 -231.071166)
		(width 0.0889)
		(layer "In13.Cu")
		(net "M_B_CPU1_SA_DQ<12>")
	)
	(segment
		(start 52.503324 -212.46592)
		(end 52.503324 -212.371686)
		(width 0.14478)
		(layer "In13.Cu")
		(net "M_B_CPU1_SA_DQ<12>")
	)
	(segment
		(start 71.308468 -225.426016)
		(end 71.512684 -225.425762)
		(width 0.14478)
		(layer "In13.Cu")
		(net "M_B_CPU1_SA_DQ<12>")
	)
	(segment
		(start 78.261464 -232.732326)
		(end 78.882494 -232.732326)
		(width 0.0889)
		(layer "In13.Cu")
		(net "M_B_CPU1_SA_DQ<12>")
	)
	(segment
		(start 75.313794 -230.31196)
		(end 75.313794 -230.525828)
		(width 0.14478)
		(layer "In13.Cu")
		(net "M_B_CPU1_SA_DQ<12>")
	)
	(segment
		(start 71.635112 -225.303334)
		(end 71.839836 -225.303334)
		(width 0.14478)
		(layer "In13.Cu")
		(net "M_B_CPU1_SA_DQ<12>")
	)
	(segment
		(start 81.879694 -233.47172)
		(end 81.888076 -233.466894)
		(width 0.0889)
		(layer "In13.Cu")
		(net "M_B_CPU1_SA_DQ<12>")
	)
	(segment
		(start 54.071774 -213.069932)
		(end 54.566058 -213.069932)
		(width 0.14478)
		(layer "In13.Cu")
		(net "M_B_CPU1_SA_DQ<12>")
	)
	(segment
		(start 72.691498 -227.689664)
		(end 72.974454 -227.97262)
		(width 0.14478)
		(layer "In13.Cu")
		(net "M_B_CPU1_SA_DQ<12>")
	)
	(segment
		(start 74.534014 -229.53218)
		(end 74.534014 -229.746048)
		(width 0.14478)
		(layer "In13.Cu")
		(net "M_B_CPU1_SA_DQ<12>")
	)
	(segment
		(start 55.100728 -213.456266)
		(end 55.262272 -213.294722)
		(width 0.14478)
		(layer "In13.Cu")
		(net "M_B_CPU1_SA_DQ<12>")
	)
	(segment
		(start 58.73242 -213.069932)
		(end 59.606434 -213.069932)
		(width 0.14478)
		(layer "In13.Cu")
		(net "M_B_CPU1_SA_DQ<12>")
	)
	(segment
		(start 71.245222 -224.70872)
		(end 71.245476 -224.913444)
		(width 0.14478)
		(layer "In13.Cu")
		(net "M_B_CPU1_SA_DQ<12>")
	)
	(segment
		(start 71.839836 -225.303334)
		(end 72.07885 -225.542348)
		(width 0.14478)
		(layer "In13.Cu")
		(net "M_B_CPU1_SA_DQ<12>")
	)
	(segment
		(start 71.123048 -225.240596)
		(end 71.308468 -225.426016)
		(width 0.14478)
		(layer "In13.Cu")
		(net "M_B_CPU1_SA_DQ<12>")
	)
	(segment
		(start 73.754234 -228.7524)
		(end 73.754234 -228.966268)
		(width 0.14478)
		(layer "In13.Cu")
		(net "M_B_CPU1_SA_DQ<12>")
	)
	(segment
		(start 79.634842 -233.46664)
		(end 79.654908 -233.47807)
		(width 0.0889)
		(layer "In13.Cu")
		(net "M_B_CPU1_SA_DQ<12>")
	)
	(segment
		(start 59.606434 -213.069932)
		(end 71.245222 -224.70872)
		(width 0.14478)
		(layer "In13.Cu")
		(net "M_B_CPU1_SA_DQ<12>")
	)
	(segment
		(start 55.97525 -213.456266)
		(end 56.203596 -213.456266)
		(width 0.14478)
		(layer "In13.Cu")
		(net "M_B_CPU1_SA_DQ<12>")
	)
	(segment
		(start 71.512684 -225.425762)
		(end 71.635112 -225.303334)
		(width 0.14478)
		(layer "In13.Cu")
		(net "M_B_CPU1_SA_DQ<12>")
	)
	(segment
		(start 55.419752 -212.749638)
		(end 55.648098 -212.749638)
		(width 0.14478)
		(layer "In13.Cu")
		(net "M_B_CPU1_SA_DQ<12>")
	)
	(segment
		(start 56.526684 -213.069932)
		(end 56.75503 -213.069932)
		(width 0.14478)
		(layer "In13.Cu")
		(net "M_B_CPU1_SA_DQ<12>")
	)
	(segment
		(start 73.754234 -228.966268)
		(end 74.03719 -229.249224)
		(width 0.14478)
		(layer "In13.Cu")
		(net "M_B_CPU1_SA_DQ<12>")
	)
	(segment
		(start 54.710838 -213.214712)
		(end 54.710838 -213.294722)
		(width 0.14478)
		(layer "In13.Cu")
		(net "M_B_CPU1_SA_DQ<12>")
	)
	(segment
		(start 82.453988 -233.466894)
		(end 82.46237 -233.47172)
		(width 0.0889)
		(layer "In13.Cu")
		(net "M_B_CPU1_SA_DQ<12>")
	)
	(segment
		(start 52.909724 -212.226906)
		(end 53.054504 -212.371686)
		(width 0.14478)
		(layer "In13.Cu")
		(net "M_B_CPU1_SA_DQ<12>")
	)
	(segment
		(start 56.916574 -213.231476)
		(end 56.916574 -213.294722)
		(width 0.14478)
		(layer "In13.Cu")
		(net "M_B_CPU1_SA_DQ<12>")
	)
	(segment
		(start 55.262272 -212.907118)
		(end 55.419752 -212.749638)
		(width 0.14478)
		(layer "In13.Cu")
		(net "M_B_CPU1_SA_DQ<12>")
	)
	(segment
		(start 74.81697 -230.029004)
		(end 75.030838 -230.029004)
		(width 0.14478)
		(layer "In13.Cu")
		(net "M_B_CPU1_SA_DQ<12>")
	)
	(segment
		(start 51.884072 -212.635338)
		(end 51.90871 -212.6107)
		(width 0.14478)
		(layer "In13.Cu")
		(net "M_B_CPU1_SA_DQ<12>")
	)
	(segment
		(start 54.566058 -213.069932)
		(end 54.710838 -213.214712)
		(width 0.14478)
		(layer "In13.Cu")
		(net "M_B_CPU1_SA_DQ<12>")
	)
	(segment
		(start 54.872382 -213.456266)
		(end 55.100728 -213.456266)
		(width 0.14478)
		(layer "In13.Cu")
		(net "M_B_CPU1_SA_DQ<12>")
	)
	(segment
		(start 72.07885 -226.698556)
		(end 72.07885 -227.290884)
		(width 0.14478)
		(layer "In13.Cu")
		(net "M_B_CPU1_SA_DQ<12>")
	)
	(segment
		(start 58.019442 -213.294722)
		(end 58.180986 -213.456266)
		(width 0.14478)
		(layer "In13.Cu")
		(net "M_B_CPU1_SA_DQ<12>")
	)
	(segment
		(start 79.55788 -233.407712)
		(end 79.55788 -233.407458)
		(width 0.0889)
		(layer "In13.Cu")
		(net "M_B_CPU1_SA_DQ<12>")
	)
	(segment
		(start 57.306464 -213.456266)
		(end 57.468008 -213.294722)
		(width 0.14478)
		(layer "In13.Cu")
		(net "M_B_CPU1_SA_DQ<12>")
	)
	(segment
		(start 58.180986 -213.456266)
		(end 58.409332 -213.456266)
		(width 0.14478)
		(layer "In13.Cu")
		(net "M_B_CPU1_SA_DQ<12>")
	)
	(segment
		(start 74.534014 -229.746048)
		(end 74.81697 -230.029004)
		(width 0.14478)
		(layer "In13.Cu")
		(net "M_B_CPU1_SA_DQ<12>")
	)
	(segment
		(start 56.75503 -213.069932)
		(end 56.916574 -213.231476)
		(width 0.14478)
		(layer "In13.Cu")
		(net "M_B_CPU1_SA_DQ<12>")
	)
	(segment
		(start 71.93407 -226.553776)
		(end 72.07885 -226.698556)
		(width 0.14478)
		(layer "In13.Cu")
		(net "M_B_CPU1_SA_DQ<12>")
	)
	(segment
		(start 75.030838 -230.029004)
		(end 75.313794 -230.31196)
		(width 0.14478)
		(layer "In13.Cu")
		(net "M_B_CPU1_SA_DQ<12>")
	)
	(segment
		(start 72.47763 -227.689664)
		(end 72.691498 -227.689664)
		(width 0.14478)
		(layer "In13.Cu")
		(net "M_B_CPU1_SA_DQ<12>")
	)
	(segment
		(start 72.07885 -225.542348)
		(end 72.07885 -225.857816)
		(width 0.14478)
		(layer "In13.Cu")
		(net "M_B_CPU1_SA_DQ<12>")
	)
	(segment
		(start 87.472774 -233.493056)
		(end 87.495126 -233.409744)
		(width 0.0889)
		(layer "In13.Cu")
		(net "M_B_CPU1_SA_DQ<12>")
	)
	(segment
		(start 77.52969 -232.000552)
		(end 78.261464 -232.732326)
		(width 0.0889)
		(layer "In13.Cu")
		(net "M_B_CPU1_SA_DQ<12>")
	)
	(segment
		(start 85.639656 -233.47172)
		(end 85.648038 -233.466894)
		(width 0.0889)
		(layer "In13.Cu")
		(net "M_B_CPU1_SA_DQ<12>")
	)
	(segment
		(start 52.648104 -212.226906)
		(end 52.909724 -212.226906)
		(width 0.14478)
		(layer "In13.Cu")
		(net "M_B_CPU1_SA_DQ<12>")
	)
	(segment
		(start 83.394042 -233.466894)
		(end 83.402424 -233.47172)
		(width 0.0889)
		(layer "In13.Cu")
		(net "M_B_CPU1_SA_DQ<12>")
	)
	(segment
		(start 71.123048 -225.035872)
		(end 71.123048 -225.240596)
		(width 0.14478)
		(layer "In13.Cu")
		(net "M_B_CPU1_SA_DQ<12>")
	)
	(segment
		(start 76.43241 -231.071166)
		(end 77.03947 -231.071166)
		(width 0.0889)
		(layer "In13.Cu")
		(net "M_B_CPU1_SA_DQ<12>")
	)
	(segment
		(start 55.648098 -212.749638)
		(end 55.813706 -212.915246)
		(width 0.14478)
		(layer "In13.Cu")
		(net "M_B_CPU1_SA_DQ<12>")
	)
	(segment
		(start 57.629552 -213.069932)
		(end 57.857898 -213.069932)
		(width 0.14478)
		(layer "In13.Cu")
		(net "M_B_CPU1_SA_DQ<12>")
	)
	(segment
		(start 53.054504 -212.46592)
		(end 53.199284 -212.6107)
		(width 0.14478)
		(layer "In13.Cu")
		(net "M_B_CPU1_SA_DQ<12>")
	)
	(segment
		(start 71.194676 -226.147376)
		(end 71.194676 -226.40671)
		(width 0.14478)
		(layer "In13.Cu")
		(net "M_B_CPU1_SA_DQ<12>")
	)
	(segment
		(start 56.203596 -213.456266)
		(end 56.36514 -213.294722)
		(width 0.14478)
		(layer "In13.Cu")
		(net "M_B_CPU1_SA_DQ<12>")
	)
	(segment
		(start 71.194676 -226.40671)
		(end 71.341742 -226.553776)
		(width 0.14478)
		(layer "In13.Cu")
		(net "M_B_CPU1_SA_DQ<12>")
	)
	(segment
		(start 55.813706 -213.294722)
		(end 55.97525 -213.456266)
		(width 0.14478)
		(layer "In13.Cu")
		(net "M_B_CPU1_SA_DQ<12>")
	)
	(segment
		(start 55.813706 -212.915246)
		(end 55.813706 -213.294722)
		(width 0.14478)
		(layer "In13.Cu")
		(net "M_B_CPU1_SA_DQ<12>")
	)
	(segment
		(start 86.57971 -233.47172)
		(end 86.588092 -233.466894)
		(width 0.0889)
		(layer "In13.Cu")
		(net "M_B_CPU1_SA_DQ<12>")
	)
	(segment
		(start 58.019442 -213.231476)
		(end 58.019442 -213.294722)
		(width 0.14478)
		(layer "In13.Cu")
		(net "M_B_CPU1_SA_DQ<12>")
	)
	(segment
		(start 87.495126 -233.409744)
		(end 87.340948 -233.144314)
		(width 0.0889)
		(layer "In13.Cu")
		(net "M_B_CPU1_SA_DQ<12>")
	)
	(segment
		(start 54.710838 -213.294722)
		(end 54.872382 -213.456266)
		(width 0.14478)
		(layer "In13.Cu")
		(net "M_B_CPU1_SA_DQ<12>")
	)
	(segment
		(start 57.468008 -213.294722)
		(end 57.468008 -213.231476)
		(width 0.14478)
		(layer "In13.Cu")
		(net "M_B_CPU1_SA_DQ<12>")
	)
	(segment
		(start 72.974454 -228.186488)
		(end 73.25741 -228.469444)
		(width 0.14478)
		(layer "In13.Cu")
		(net "M_B_CPU1_SA_DQ<12>")
	)
	(segment
		(start 77.52969 -231.561386)
		(end 77.52969 -232.000552)
		(width 0.0889)
		(layer "In13.Cu")
		(net "M_B_CPU1_SA_DQ<12>")
	)
	(segment
		(start 74.03719 -229.249224)
		(end 74.251058 -229.249224)
		(width 0.14478)
		(layer "In13.Cu")
		(net "M_B_CPU1_SA_DQ<12>")
	)
	(segment
		(start 73.25741 -228.469444)
		(end 73.471278 -228.469444)
		(width 0.14478)
		(layer "In13.Cu")
		(net "M_B_CPU1_SA_DQ<12>")
	)
	(segment
		(start 71.245476 -224.913444)
		(end 71.123048 -225.035872)
		(width 0.14478)
		(layer "In13.Cu")
		(net "M_B_CPU1_SA_DQ<12>")
	)
	(segment
		(start 56.36514 -213.231476)
		(end 56.526684 -213.069932)
		(width 0.14478)
		(layer "In13.Cu")
		(net "M_B_CPU1_SA_DQ<12>")
	)
	(segment
		(start 75.313794 -230.525828)
		(end 75.659234 -230.871268)
		(width 0.14478)
		(layer "In13.Cu")
		(net "M_B_CPU1_SA_DQ<12>")
	)
	(segment
		(start 72.07885 -227.290884)
		(end 72.47763 -227.689664)
		(width 0.14478)
		(layer "In13.Cu")
		(net "M_B_CPU1_SA_DQ<12>")
	)
	(segment
		(start 87.154004 -233.466894)
		(end 87.162386 -233.47172)
		(width 0.0889)
		(layer "In13.Cu")
		(net "M_B_CPU1_SA_DQ<12>")
	)
	(segment
		(start 71.93407 -226.002596)
		(end 71.339456 -226.002596)
		(width 0.14478)
		(layer "In13.Cu")
		(net "M_B_CPU1_SA_DQ<12>")
	)
	(segment
		(start 56.916574 -213.294722)
		(end 57.078118 -213.456266)
		(width 0.14478)
		(layer "In13.Cu")
		(net "M_B_CPU1_SA_DQ<12>")
	)
	(segment
		(start 74.251058 -229.249224)
		(end 74.534014 -229.53218)
		(width 0.14478)
		(layer "In13.Cu")
		(net "M_B_CPU1_SA_DQ<12>")
	)
	(segment
		(start 52.503324 -212.371686)
		(end 52.648104 -212.226906)
		(width 0.14478)
		(layer "In13.Cu")
		(net "M_B_CPU1_SA_DQ<12>")
	)
	(segment
		(start 58.570876 -213.294722)
		(end 58.570876 -213.231476)
		(width 0.14478)
		(layer "In13.Cu")
		(net "M_B_CPU1_SA_DQ<12>")
	)
	(segment
		(start 75.659234 -230.871268)
		(end 75.91933 -230.871268)
		(width 0.14478)
		(layer "In13.Cu")
		(net "M_B_CPU1_SA_DQ<12>")
	)
	(segment
		(start 56.36514 -213.294722)
		(end 56.36514 -213.231476)
		(width 0.14478)
		(layer "In13.Cu")
		(net "M_B_CPU1_SA_DQ<12>")
	)
	(segment
		(start 72.07885 -225.857816)
		(end 71.93407 -226.002596)
		(width 0.14478)
		(layer "In13.Cu")
		(net "M_B_CPU1_SA_DQ<12>")
	)
	(segment
		(start 51.90871 -212.6107)
		(end 52.358544 -212.6107)
		(width 0.14478)
		(layer "In13.Cu")
		(net "M_B_CPU1_SA_DQ<12>")
	)
	(segment
		(start 58.570876 -213.231476)
		(end 58.73242 -213.069932)
		(width 0.14478)
		(layer "In13.Cu")
		(net "M_B_CPU1_SA_DQ<12>")
	)
	(segment
		(start 55.262272 -213.294722)
		(end 55.262272 -212.907118)
		(width 0.14478)
		(layer "In13.Cu")
		(net "M_B_CPU1_SA_DQ<12>")
	)
	(segment
		(start 57.078118 -213.456266)
		(end 57.306464 -213.456266)
		(width 0.14478)
		(layer "In13.Cu")
		(net "M_B_CPU1_SA_DQ<12>")
	)
	(segment
		(start 77.03947 -231.071166)
		(end 77.52969 -231.561386)
		(width 0.0889)
		(layer "In13.Cu")
		(net "M_B_CPU1_SA_DQ<12>")
	)
	(segment
		(start 53.612542 -212.6107)
		(end 54.071774 -213.069932)
		(width 0.14478)
		(layer "In13.Cu")
		(net "M_B_CPU1_SA_DQ<12>")
	)
	(segment
		(start 53.199284 -212.6107)
		(end 53.612542 -212.6107)
		(width 0.14478)
		(layer "In13.Cu")
		(net "M_B_CPU1_SA_DQ<12>")
	)
	(segment
		(start 71.339456 -226.002596)
		(end 71.194676 -226.147376)
		(width 0.14478)
		(layer "In13.Cu")
		(net "M_B_CPU1_SA_DQ<12>")
	)
	(segment
		(start 71.341742 -226.553776)
		(end 71.93407 -226.553776)
		(width 0.14478)
		(layer "In13.Cu")
		(net "M_B_CPU1_SA_DQ<12>")
	)
	(segment
		(start 53.054504 -212.371686)
		(end 53.054504 -212.46592)
		(width 0.14478)
		(layer "In13.Cu")
		(net "M_B_CPU1_SA_DQ<12>")
	)
	(arc
		(start 80.948022 -233.466894)
		(mid 81.230978 -233.390717)
		(end 81.513934 -233.466894)
		(width 0.0889)
		(layer "In13.Cu")
		(net "M_B_CPU1_SA_DQ<12>")
	)
	(arc
		(start 81.888076 -233.466894)
		(mid 82.171032 -233.390717)
		(end 82.453988 -233.466894)
		(width 0.0889)
		(layer "In13.Cu")
		(net "M_B_CPU1_SA_DQ<12>")
	)
	(arc
		(start 80.574134 -233.466894)
		(mid 80.761078 -233.517149)
		(end 80.948022 -233.466894)
		(width 0.0889)
		(layer "In13.Cu")
		(net "M_B_CPU1_SA_DQ<12>")
	)
	(arc
		(start 79.654908 -233.47807)
		(mid 79.832986 -233.517054)
		(end 80.008222 -233.466894)
		(width 0.0889)
		(layer "In13.Cu")
		(net "M_B_CPU1_SA_DQ<12>")
	)
	(arc
		(start 82.82813 -233.466894)
		(mid 83.111086 -233.390717)
		(end 83.394042 -233.466894)
		(width 0.0889)
		(layer "In13.Cu")
		(net "M_B_CPU1_SA_DQ<12>")
	)
	(arc
		(start 84.707984 -233.466894)
		(mid 84.99094 -233.390717)
		(end 85.273896 -233.466894)
		(width 0.0889)
		(layer "In13.Cu")
		(net "M_B_CPU1_SA_DQ<12>")
	)
	(arc
		(start 86.21395 -233.466894)
		(mid 86.396201 -233.517244)
		(end 86.57971 -233.47172)
		(width 0.0889)
		(layer "In13.Cu")
		(net "M_B_CPU1_SA_DQ<12>")
	)
	(arc
		(start 87.162386 -233.47172)
		(mid 87.315256 -233.516361)
		(end 87.472774 -233.493056)
		(width 0.0889)
		(layer "In13.Cu")
		(net "M_B_CPU1_SA_DQ<12>")
	)
	(arc
		(start 83.402424 -233.47172)
		(mid 83.585932 -233.517214)
		(end 83.768184 -233.466894)
		(width 0.0889)
		(layer "In13.Cu")
		(net "M_B_CPU1_SA_DQ<12>")
	)
	(arc
		(start 83.768184 -233.466894)
		(mid 84.05114 -233.390717)
		(end 84.334096 -233.466894)
		(width 0.0889)
		(layer "In13.Cu")
		(net "M_B_CPU1_SA_DQ<12>")
	)
	(arc
		(start 85.273896 -233.466894)
		(mid 85.456147 -233.517244)
		(end 85.639656 -233.47172)
		(width 0.0889)
		(layer "In13.Cu")
		(net "M_B_CPU1_SA_DQ<12>")
	)
	(arc
		(start 79.55788 -233.407458)
		(mid 79.594422 -233.43957)
		(end 79.634842 -233.46664)
		(width 0.0889)
		(layer "In13.Cu")
		(net "M_B_CPU1_SA_DQ<12>")
	)
	(arc
		(start 81.513934 -233.466894)
		(mid 81.696185 -233.517244)
		(end 81.879694 -233.47172)
		(width 0.0889)
		(layer "In13.Cu")
		(net "M_B_CPU1_SA_DQ<12>")
	)
	(arc
		(start 82.46237 -233.47172)
		(mid 82.645878 -233.517214)
		(end 82.82813 -233.466894)
		(width 0.0889)
		(layer "In13.Cu")
		(net "M_B_CPU1_SA_DQ<12>")
	)
	(arc
		(start 84.334096 -233.466894)
		(mid 84.52104 -233.517149)
		(end 84.707984 -233.466894)
		(width 0.0889)
		(layer "In13.Cu")
		(net "M_B_CPU1_SA_DQ<12>")
	)
	(arc
		(start 86.588092 -233.466894)
		(mid 86.871048 -233.390717)
		(end 87.154004 -233.466894)
		(width 0.0889)
		(layer "In13.Cu")
		(net "M_B_CPU1_SA_DQ<12>")
	)
	(arc
		(start 80.008222 -233.466894)
		(mid 80.291178 -233.390717)
		(end 80.574134 -233.466894)
		(width 0.0889)
		(layer "In13.Cu")
		(net "M_B_CPU1_SA_DQ<12>")
	)
	(arc
		(start 85.648038 -233.466894)
		(mid 85.930994 -233.390717)
		(end 86.21395 -233.466894)
		(width 0.0889)
		(layer "In13.Cu")
		(net "M_B_CPU1_SA_DQ<12>")
	)
	(segment
		(start 89.687908 -231.79024)
		(end 89.221056 -231.524302)
		(width 0.10668)
		(layer "F.Cu")
		(net "M_B_CPU1_SA_DQ<11>")
	)
	(segment
		(start 61.482224 -211.39785)
		(end 61.223906 -211.206334)
		(width 0.14478)
		(layer "In13.Cu")
		(net "M_B_CPU1_SA_DQ<11>")
	)
	(segment
		(start 76.052426 -227.674424)
		(end 74.36739 -225.989388)
		(width 0.14478)
		(layer "In13.Cu")
		(net "M_B_CPU1_SA_DQ<11>")
	)
	(segment
		(start 80.008222 -231.201976)
		(end 79.969106 -231.179116)
		(width 0.0889)
		(layer "In13.Cu")
		(net "M_B_CPU1_SA_DQ<11>")
	)
	(segment
		(start 86.588092 -231.201976)
		(end 86.57971 -231.19715)
		(width 0.0889)
		(layer "In13.Cu")
		(net "M_B_CPU1_SA_DQ<11>")
	)
	(segment
		(start 50.120296 -208.8007)
		(end 47.93488 -209.235294)
		(width 0.14478)
		(layer "In13.Cu")
		(net "M_B_CPU1_SA_DQ<11>")
	)
	(segment
		(start 83.402424 -231.19715)
		(end 83.394042 -231.201976)
		(width 0.0889)
		(layer "In13.Cu")
		(net "M_B_CPU1_SA_DQ<11>")
	)
	(segment
		(start 72.51319 -221.708218)
		(end 63.654178 -212.849206)
		(width 0.14478)
		(layer "In13.Cu")
		(net "M_B_CPU1_SA_DQ<11>")
	)
	(segment
		(start 56.779922 -209.66049)
		(end 54.170326 -209.66049)
		(width 0.14478)
		(layer "In13.Cu")
		(net "M_B_CPU1_SA_DQ<11>")
	)
	(segment
		(start 77.76083 -229.163626)
		(end 77.76083 -228.465126)
		(width 0.0889)
		(layer "In13.Cu")
		(net "M_B_CPU1_SA_DQ<11>")
	)
	(segment
		(start 74.36739 -224.396046)
		(end 72.51319 -222.541846)
		(width 0.14478)
		(layer "In13.Cu")
		(net "M_B_CPU1_SA_DQ<11>")
	)
	(segment
		(start 88.10244 -231.19715)
		(end 88.094058 -231.201976)
		(width 0.0889)
		(layer "In13.Cu")
		(net "M_B_CPU1_SA_DQ<11>")
	)
	(segment
		(start 72.51319 -222.541846)
		(end 72.51319 -221.708218)
		(width 0.14478)
		(layer "In13.Cu")
		(net "M_B_CPU1_SA_DQ<11>")
	)
	(segment
		(start 51.365912 -208.984088)
		(end 50.4444 -208.8007)
		(width 0.14478)
		(layer "In13.Cu")
		(net "M_B_CPU1_SA_DQ<11>")
	)
	(segment
		(start 89.067132 -231.258872)
		(end 88.971374 -231.233472)
		(width 0.0889)
		(layer "In13.Cu")
		(net "M_B_CPU1_SA_DQ<11>")
	)
	(segment
		(start 60.085224 -210.598004)
		(end 58.319924 -209.966814)
		(width 0.14478)
		(layer "In13.Cu")
		(net "M_B_CPU1_SA_DQ<11>")
	)
	(segment
		(start 51.9176 -209.212434)
		(end 51.365912 -208.984088)
		(width 0.14478)
		(layer "In13.Cu")
		(net "M_B_CPU1_SA_DQ<11>")
	)
	(segment
		(start 47.93488 -209.235294)
		(end 47.784004 -209.235294)
		(width 0.14478)
		(layer "In13.Cu")
		(net "M_B_CPU1_SA_DQ<11>")
	)
	(segment
		(start 61.223906 -211.206334)
		(end 60.085224 -210.598004)
		(width 0.14478)
		(layer "In13.Cu")
		(net "M_B_CPU1_SA_DQ<11>")
	)
	(segment
		(start 54.170326 -209.66049)
		(end 51.9176 -209.212434)
		(width 0.14478)
		(layer "In13.Cu")
		(net "M_B_CPU1_SA_DQ<11>")
	)
	(segment
		(start 63.654178 -212.849206)
		(end 61.482224 -211.39785)
		(width 0.14478)
		(layer "In13.Cu")
		(net "M_B_CPU1_SA_DQ<11>")
	)
	(segment
		(start 89.221056 -231.524302)
		(end 89.067132 -231.258872)
		(width 0.0889)
		(layer "In13.Cu")
		(net "M_B_CPU1_SA_DQ<11>")
	)
	(segment
		(start 82.46237 -231.19715)
		(end 82.453988 -231.201976)
		(width 0.0889)
		(layer "In13.Cu")
		(net "M_B_CPU1_SA_DQ<11>")
	)
	(segment
		(start 77.76083 -228.465126)
		(end 77.11821 -227.822506)
		(width 0.0889)
		(layer "In13.Cu")
		(net "M_B_CPU1_SA_DQ<11>")
	)
	(segment
		(start 58.319924 -209.966814)
		(end 56.779922 -209.66049)
		(width 0.14478)
		(layer "In13.Cu")
		(net "M_B_CPU1_SA_DQ<11>")
	)
	(segment
		(start 87.162386 -231.19715)
		(end 87.154004 -231.201976)
		(width 0.0889)
		(layer "In13.Cu")
		(net "M_B_CPU1_SA_DQ<11>")
	)
	(segment
		(start 50.4444 -208.8007)
		(end 50.120296 -208.8007)
		(width 0.14478)
		(layer "In13.Cu")
		(net "M_B_CPU1_SA_DQ<11>")
	)
	(segment
		(start 78.74635 -229.793546)
		(end 78.39075 -229.793546)
		(width 0.0889)
		(layer "In13.Cu")
		(net "M_B_CPU1_SA_DQ<11>")
	)
	(segment
		(start 85.648038 -231.201976)
		(end 85.639656 -231.19715)
		(width 0.0889)
		(layer "In13.Cu")
		(net "M_B_CPU1_SA_DQ<11>")
	)
	(segment
		(start 74.36739 -225.989388)
		(end 74.36739 -224.396046)
		(width 0.14478)
		(layer "In13.Cu")
		(net "M_B_CPU1_SA_DQ<11>")
	)
	(segment
		(start 76.200508 -227.822506)
		(end 76.052426 -227.674424)
		(width 0.0889)
		(layer "In13.Cu")
		(net "M_B_CPU1_SA_DQ<11>")
	)
	(segment
		(start 81.888076 -231.201976)
		(end 81.879694 -231.19715)
		(width 0.0889)
		(layer "In13.Cu")
		(net "M_B_CPU1_SA_DQ<11>")
	)
	(segment
		(start 78.39075 -229.793546)
		(end 77.76083 -229.163626)
		(width 0.0889)
		(layer "In13.Cu")
		(net "M_B_CPU1_SA_DQ<11>")
	)
	(segment
		(start 77.11821 -227.822506)
		(end 76.200508 -227.822506)
		(width 0.0889)
		(layer "In13.Cu")
		(net "M_B_CPU1_SA_DQ<11>")
	)
	(segment
		(start 79.205582 -230.252778)
		(end 78.74635 -229.793546)
		(width 0.0889)
		(layer "In13.Cu")
		(net "M_B_CPU1_SA_DQ<11>")
	)
	(arc
		(start 84.707984 -231.201976)
		(mid 84.52104 -231.151687)
		(end 84.334096 -231.201976)
		(width 0.0889)
		(layer "In13.Cu")
		(net "M_B_CPU1_SA_DQ<11>")
	)
	(arc
		(start 82.453988 -231.201976)
		(mid 82.171032 -231.278153)
		(end 81.888076 -231.201976)
		(width 0.0889)
		(layer "In13.Cu")
		(net "M_B_CPU1_SA_DQ<11>")
	)
	(arc
		(start 79.725774 -230.71455)
		(mid 79.676158 -230.529247)
		(end 79.540608 -230.393494)
		(width 0.0889)
		(layer "In13.Cu")
		(net "M_B_CPU1_SA_DQ<11>")
	)
	(arc
		(start 83.394042 -231.201976)
		(mid 83.111086 -231.278153)
		(end 82.82813 -231.201976)
		(width 0.0889)
		(layer "In13.Cu")
		(net "M_B_CPU1_SA_DQ<11>")
	)
	(arc
		(start 88.971374 -231.233472)
		(mid 88.716052 -231.277172)
		(end 88.4682 -231.201976)
		(width 0.0889)
		(layer "In13.Cu")
		(net "M_B_CPU1_SA_DQ<11>")
	)
	(arc
		(start 85.639656 -231.19715)
		(mid 85.456148 -231.151625)
		(end 85.273896 -231.201976)
		(width 0.0889)
		(layer "In13.Cu")
		(net "M_B_CPU1_SA_DQ<11>")
	)
	(arc
		(start 83.768184 -231.201976)
		(mid 83.585933 -231.151592)
		(end 83.402424 -231.19715)
		(width 0.0889)
		(layer "In13.Cu")
		(net "M_B_CPU1_SA_DQ<11>")
	)
	(arc
		(start 87.154004 -231.201976)
		(mid 86.871048 -231.278153)
		(end 86.588092 -231.201976)
		(width 0.0889)
		(layer "In13.Cu")
		(net "M_B_CPU1_SA_DQ<11>")
	)
	(arc
		(start 79.394812 -230.344472)
		(mid 79.292469 -230.314583)
		(end 79.205582 -230.252778)
		(width 0.0889)
		(layer "In13.Cu")
		(net "M_B_CPU1_SA_DQ<11>")
	)
	(arc
		(start 86.21395 -231.201976)
		(mid 85.930994 -231.278153)
		(end 85.648038 -231.201976)
		(width 0.0889)
		(layer "In13.Cu")
		(net "M_B_CPU1_SA_DQ<11>")
	)
	(arc
		(start 80.948022 -231.201976)
		(mid 80.761078 -231.151687)
		(end 80.574134 -231.201976)
		(width 0.0889)
		(layer "In13.Cu")
		(net "M_B_CPU1_SA_DQ<11>")
	)
	(arc
		(start 82.82813 -231.201976)
		(mid 82.645879 -231.151592)
		(end 82.46237 -231.19715)
		(width 0.0889)
		(layer "In13.Cu")
		(net "M_B_CPU1_SA_DQ<11>")
	)
	(arc
		(start 81.879694 -231.19715)
		(mid 81.696186 -231.151625)
		(end 81.513934 -231.201976)
		(width 0.0889)
		(layer "In13.Cu")
		(net "M_B_CPU1_SA_DQ<11>")
	)
	(arc
		(start 86.57971 -231.19715)
		(mid 86.396202 -231.151625)
		(end 86.21395 -231.201976)
		(width 0.0889)
		(layer "In13.Cu")
		(net "M_B_CPU1_SA_DQ<11>")
	)
	(arc
		(start 88.094058 -231.201976)
		(mid 87.811102 -231.278153)
		(end 87.528146 -231.201976)
		(width 0.0889)
		(layer "In13.Cu")
		(net "M_B_CPU1_SA_DQ<11>")
	)
	(arc
		(start 85.273896 -231.201976)
		(mid 84.99094 -231.278153)
		(end 84.707984 -231.201976)
		(width 0.0889)
		(layer "In13.Cu")
		(net "M_B_CPU1_SA_DQ<11>")
	)
	(arc
		(start 81.513934 -231.201976)
		(mid 81.230978 -231.278153)
		(end 80.948022 -231.201976)
		(width 0.0889)
		(layer "In13.Cu")
		(net "M_B_CPU1_SA_DQ<11>")
	)
	(arc
		(start 84.334096 -231.201976)
		(mid 84.05114 -231.278153)
		(end 83.768184 -231.201976)
		(width 0.0889)
		(layer "In13.Cu")
		(net "M_B_CPU1_SA_DQ<11>")
	)
	(arc
		(start 80.574134 -231.201976)
		(mid 80.291178 -231.278153)
		(end 80.008222 -231.201976)
		(width 0.0889)
		(layer "In13.Cu")
		(net "M_B_CPU1_SA_DQ<11>")
	)
	(arc
		(start 87.528146 -231.201976)
		(mid 87.345895 -231.151592)
		(end 87.162386 -231.19715)
		(width 0.0889)
		(layer "In13.Cu")
		(net "M_B_CPU1_SA_DQ<11>")
	)
	(arc
		(start 79.969106 -231.179116)
		(mid 79.790293 -230.976766)
		(end 79.725774 -230.71455)
		(width 0.0889)
		(layer "In13.Cu")
		(net "M_B_CPU1_SA_DQ<11>")
	)
	(arc
		(start 88.4682 -231.201976)
		(mid 88.285949 -231.151592)
		(end 88.10244 -231.19715)
		(width 0.0889)
		(layer "In13.Cu")
		(net "M_B_CPU1_SA_DQ<11>")
	)
	(arc
		(start 79.540608 -230.393494)
		(mid 79.470273 -230.361352)
		(end 79.394812 -230.344472)
		(width 0.0889)
		(layer "In13.Cu")
		(net "M_B_CPU1_SA_DQ<11>")
	)
	(segment
		(start 88.277954 -230.980234)
		(end 87.811102 -230.71455)
		(width 0.10668)
		(layer "F.Cu")
		(net "M_B_CPU1_SA_DQ<10>")
	)
	(segment
		(start 52.031392 -207.11033)
		(end 50.222404 -207.11033)
		(width 0.14478)
		(layer "In13.Cu")
		(net "M_B_CPU1_SA_DQ<10>")
	)
	(segment
		(start 54.083966 -207.960468)
		(end 52.031392 -207.11033)
		(width 0.14478)
		(layer "In13.Cu")
		(net "M_B_CPU1_SA_DQ<10>")
	)
	(segment
		(start 79.632302 -229.122478)
		(end 78.36789 -227.858066)
		(width 0.0889)
		(layer "In13.Cu")
		(net "M_B_CPU1_SA_DQ<10>")
	)
	(segment
		(start 76.378816 -226.344734)
		(end 75.371706 -225.337624)
		(width 0.14478)
		(layer "In13.Cu")
		(net "M_B_CPU1_SA_DQ<10>")
	)
	(segment
		(start 80.478122 -230.39197)
		(end 80.441546 -230.370634)
		(width 0.0889)
		(layer "In13.Cu")
		(net "M_B_CPU1_SA_DQ<10>")
	)
	(segment
		(start 83.29803 -230.39197)
		(end 83.289648 -230.387144)
		(width 0.0889)
		(layer "In13.Cu")
		(net "M_B_CPU1_SA_DQ<10>")
	)
	(segment
		(start 85.752432 -230.387144)
		(end 85.74405 -230.39197)
		(width 0.0889)
		(layer "In13.Cu")
		(net "M_B_CPU1_SA_DQ<10>")
	)
	(segment
		(start 78.36789 -227.858066)
		(end 78.21803 -227.858066)
		(width 0.0889)
		(layer "In13.Cu")
		(net "M_B_CPU1_SA_DQ<10>")
	)
	(segment
		(start 50.222404 -207.11033)
		(end 49.797462 -207.535272)
		(width 0.14478)
		(layer "In13.Cu")
		(net "M_B_CPU1_SA_DQ<10>")
	)
	(segment
		(start 78.21803 -227.858066)
		(end 77.39253 -227.032566)
		(width 0.0889)
		(layer "In13.Cu")
		(net "M_B_CPU1_SA_DQ<10>")
	)
	(segment
		(start 77.39253 -227.032566)
		(end 76.83881 -227.032566)
		(width 0.0889)
		(layer "In13.Cu")
		(net "M_B_CPU1_SA_DQ<10>")
	)
	(segment
		(start 87.656924 -230.44912)
		(end 87.560658 -230.42372)
		(width 0.0889)
		(layer "In13.Cu")
		(net "M_B_CPU1_SA_DQ<10>")
	)
	(segment
		(start 76.54925 -226.515168)
		(end 76.378816 -226.344734)
		(width 0.0889)
		(layer "In13.Cu")
		(net "M_B_CPU1_SA_DQ<10>")
	)
	(segment
		(start 76.83881 -227.032566)
		(end 76.54925 -226.743006)
		(width 0.0889)
		(layer "In13.Cu")
		(net "M_B_CPU1_SA_DQ<10>")
	)
	(segment
		(start 75.371706 -225.337624)
		(end 75.371706 -224.122742)
		(width 0.14478)
		(layer "In13.Cu")
		(net "M_B_CPU1_SA_DQ<10>")
	)
	(segment
		(start 84.238084 -230.39197)
		(end 84.229702 -230.387144)
		(width 0.0889)
		(layer "In13.Cu")
		(net "M_B_CPU1_SA_DQ<10>")
	)
	(segment
		(start 73.45045 -222.201486)
		(end 73.45045 -221.373446)
		(width 0.14478)
		(layer "In13.Cu")
		(net "M_B_CPU1_SA_DQ<10>")
	)
	(segment
		(start 60.85967 -208.782666)
		(end 58.87466 -207.960468)
		(width 0.14478)
		(layer "In13.Cu")
		(net "M_B_CPU1_SA_DQ<10>")
	)
	(segment
		(start 84.812378 -230.387144)
		(end 84.803996 -230.39197)
		(width 0.0889)
		(layer "In13.Cu")
		(net "M_B_CPU1_SA_DQ<10>")
	)
	(segment
		(start 49.797462 -207.535272)
		(end 47.784004 -207.535272)
		(width 0.14478)
		(layer "In13.Cu")
		(net "M_B_CPU1_SA_DQ<10>")
	)
	(segment
		(start 87.811102 -230.71455)
		(end 87.656924 -230.44912)
		(width 0.0889)
		(layer "In13.Cu")
		(net "M_B_CPU1_SA_DQ<10>")
	)
	(segment
		(start 58.87466 -207.960468)
		(end 54.083966 -207.960468)
		(width 0.14478)
		(layer "In13.Cu")
		(net "M_B_CPU1_SA_DQ<10>")
	)
	(segment
		(start 80.040734 -229.60076)
		(end 79.969106 -229.559104)
		(width 0.0889)
		(layer "In13.Cu")
		(net "M_B_CPU1_SA_DQ<10>")
	)
	(segment
		(start 75.371706 -224.122742)
		(end 73.45045 -222.201486)
		(width 0.14478)
		(layer "In13.Cu")
		(net "M_B_CPU1_SA_DQ<10>")
	)
	(segment
		(start 81.052416 -230.387144)
		(end 81.044034 -230.39197)
		(width 0.0889)
		(layer "In13.Cu")
		(net "M_B_CPU1_SA_DQ<10>")
	)
	(segment
		(start 73.45045 -221.373446)
		(end 60.85967 -208.782666)
		(width 0.14478)
		(layer "In13.Cu")
		(net "M_B_CPU1_SA_DQ<10>")
	)
	(segment
		(start 76.54925 -226.743006)
		(end 76.54925 -226.515168)
		(width 0.0889)
		(layer "In13.Cu")
		(net "M_B_CPU1_SA_DQ<10>")
	)
	(arc
		(start 83.863942 -230.39197)
		(mid 83.580986 -230.468113)
		(end 83.29803 -230.39197)
		(width 0.0889)
		(layer "In13.Cu")
		(net "M_B_CPU1_SA_DQ<10>")
	)
	(arc
		(start 79.969106 -229.559104)
		(mid 79.858069 -229.45789)
		(end 79.77759 -229.331012)
		(width 0.0889)
		(layer "In13.Cu")
		(net "M_B_CPU1_SA_DQ<10>")
	)
	(arc
		(start 86.684104 -230.39197)
		(mid 86.401148 -230.468113)
		(end 86.118192 -230.39197)
		(width 0.0889)
		(layer "In13.Cu")
		(net "M_B_CPU1_SA_DQ<10>")
	)
	(arc
		(start 85.178138 -230.39197)
		(mid 84.995887 -230.34162)
		(end 84.812378 -230.387144)
		(width 0.0889)
		(layer "In13.Cu")
		(net "M_B_CPU1_SA_DQ<10>")
	)
	(arc
		(start 84.803996 -230.39197)
		(mid 84.52104 -230.468113)
		(end 84.238084 -230.39197)
		(width 0.0889)
		(layer "In13.Cu")
		(net "M_B_CPU1_SA_DQ<10>")
	)
	(arc
		(start 79.77759 -229.331012)
		(mid 79.714185 -229.220309)
		(end 79.632302 -229.122478)
		(width 0.0889)
		(layer "In13.Cu")
		(net "M_B_CPU1_SA_DQ<10>")
	)
	(arc
		(start 87.560658 -230.42372)
		(mid 87.305593 -230.467051)
		(end 87.057992 -230.39197)
		(width 0.0889)
		(layer "In13.Cu")
		(net "M_B_CPU1_SA_DQ<10>")
	)
	(arc
		(start 86.118192 -230.39197)
		(mid 85.935941 -230.34162)
		(end 85.752432 -230.387144)
		(width 0.0889)
		(layer "In13.Cu")
		(net "M_B_CPU1_SA_DQ<10>")
	)
	(arc
		(start 80.441546 -230.370634)
		(mid 80.260894 -230.167889)
		(end 80.195674 -229.90429)
		(width 0.0889)
		(layer "In13.Cu")
		(net "M_B_CPU1_SA_DQ<10>")
	)
	(arc
		(start 81.418176 -230.39197)
		(mid 81.235925 -230.34162)
		(end 81.052416 -230.387144)
		(width 0.0889)
		(layer "In13.Cu")
		(net "M_B_CPU1_SA_DQ<10>")
	)
	(arc
		(start 87.057992 -230.39197)
		(mid 86.871048 -230.341715)
		(end 86.684104 -230.39197)
		(width 0.0889)
		(layer "In13.Cu")
		(net "M_B_CPU1_SA_DQ<10>")
	)
	(arc
		(start 84.229702 -230.387144)
		(mid 84.046194 -230.34165)
		(end 83.863942 -230.39197)
		(width 0.0889)
		(layer "In13.Cu")
		(net "M_B_CPU1_SA_DQ<10>")
	)
	(arc
		(start 81.984088 -230.39197)
		(mid 81.701132 -230.468113)
		(end 81.418176 -230.39197)
		(width 0.0889)
		(layer "In13.Cu")
		(net "M_B_CPU1_SA_DQ<10>")
	)
	(arc
		(start 81.044034 -230.39197)
		(mid 80.761078 -230.468113)
		(end 80.478122 -230.39197)
		(width 0.0889)
		(layer "In13.Cu")
		(net "M_B_CPU1_SA_DQ<10>")
	)
	(arc
		(start 85.74405 -230.39197)
		(mid 85.461094 -230.468113)
		(end 85.178138 -230.39197)
		(width 0.0889)
		(layer "In13.Cu")
		(net "M_B_CPU1_SA_DQ<10>")
	)
	(arc
		(start 83.289648 -230.387144)
		(mid 83.10614 -230.34165)
		(end 82.923888 -230.39197)
		(width 0.0889)
		(layer "In13.Cu")
		(net "M_B_CPU1_SA_DQ<10>")
	)
	(arc
		(start 82.923888 -230.39197)
		(mid 82.640932 -230.468113)
		(end 82.357976 -230.39197)
		(width 0.0889)
		(layer "In13.Cu")
		(net "M_B_CPU1_SA_DQ<10>")
	)
	(arc
		(start 80.195674 -229.90429)
		(mid 80.154708 -229.733884)
		(end 80.040734 -229.60076)
		(width 0.0889)
		(layer "In13.Cu")
		(net "M_B_CPU1_SA_DQ<10>")
	)
	(arc
		(start 82.357976 -230.39197)
		(mid 82.171032 -230.341715)
		(end 81.984088 -230.39197)
		(width 0.0889)
		(layer "In13.Cu")
		(net "M_B_CPU1_SA_DQ<10>")
	)
	(segment
		(start 87.8078 -225.310446)
		(end 87.340948 -225.044508)
		(width 0.10668)
		(layer "F.Cu")
		(net "M_B_CPU1_SA_DQ<0>")
	)
	(segment
		(start 87.154004 -225.367088)
		(end 87.162386 -225.371914)
		(width 0.0889)
		(layer "In13.Cu")
		(net "M_B_CPU1_SA_DQ<0>")
	)
	(segment
		(start 58.182002 -197.760336)
		(end 58.326782 -197.615556)
		(width 0.14478)
		(layer "In13.Cu")
		(net "M_B_CPU1_SA_DQ<0>")
	)
	(segment
		(start 85.639656 -225.371914)
		(end 85.648038 -225.367088)
		(width 0.0889)
		(layer "In13.Cu")
		(net "M_B_CPU1_SA_DQ<0>")
	)
	(segment
		(start 57.775602 -197.615556)
		(end 57.920382 -197.760336)
		(width 0.14478)
		(layer "In13.Cu")
		(net "M_B_CPU1_SA_DQ<0>")
	)
	(segment
		(start 54.08422 -197.760336)
		(end 55.977282 -197.760336)
		(width 0.14478)
		(layer "In13.Cu")
		(net "M_B_CPU1_SA_DQ<0>")
	)
	(segment
		(start 58.733182 -197.013068)
		(end 58.877962 -197.157848)
		(width 0.14478)
		(layer "In13.Cu")
		(net "M_B_CPU1_SA_DQ<0>")
	)
	(segment
		(start 82.923888 -224.557082)
		(end 82.963004 -224.579942)
		(width 0.0889)
		(layer "In13.Cu")
		(net "M_B_CPU1_SA_DQ<0>")
	)
	(segment
		(start 57.369202 -197.013068)
		(end 57.630822 -197.013068)
		(width 0.14478)
		(layer "In13.Cu")
		(net "M_B_CPU1_SA_DQ<0>")
	)
	(segment
		(start 57.630822 -197.013068)
		(end 57.775602 -197.157848)
		(width 0.14478)
		(layer "In13.Cu")
		(net "M_B_CPU1_SA_DQ<0>")
	)
	(segment
		(start 56.673242 -197.157848)
		(end 56.673242 -197.615556)
		(width 0.14478)
		(layer "In13.Cu")
		(net "M_B_CPU1_SA_DQ<0>")
	)
	(segment
		(start 59.022742 -197.760336)
		(end 59.758326 -197.760336)
		(width 0.14478)
		(layer "In13.Cu")
		(net "M_B_CPU1_SA_DQ<0>")
	)
	(segment
		(start 57.224422 -197.157848)
		(end 57.369202 -197.013068)
		(width 0.14478)
		(layer "In13.Cu")
		(net "M_B_CPU1_SA_DQ<0>")
	)
	(segment
		(start 56.122062 -197.157848)
		(end 56.266842 -197.013068)
		(width 0.14478)
		(layer "In13.Cu")
		(net "M_B_CPU1_SA_DQ<0>")
	)
	(segment
		(start 56.266842 -197.013068)
		(end 56.528462 -197.013068)
		(width 0.14478)
		(layer "In13.Cu")
		(net "M_B_CPU1_SA_DQ<0>")
	)
	(segment
		(start 58.326782 -197.615556)
		(end 58.326782 -197.157848)
		(width 0.14478)
		(layer "In13.Cu")
		(net "M_B_CPU1_SA_DQ<0>")
	)
	(segment
		(start 58.326782 -197.157848)
		(end 58.471562 -197.013068)
		(width 0.14478)
		(layer "In13.Cu")
		(net "M_B_CPU1_SA_DQ<0>")
	)
	(segment
		(start 51.884072 -197.335394)
		(end 52.309014 -196.910452)
		(width 0.14478)
		(layer "In13.Cu")
		(net "M_B_CPU1_SA_DQ<0>")
	)
	(segment
		(start 59.758326 -197.760336)
		(end 81.574386 -219.576396)
		(width 0.14478)
		(layer "In13.Cu")
		(net "M_B_CPU1_SA_DQ<0>")
	)
	(segment
		(start 81.574386 -219.576396)
		(end 81.574386 -221.253304)
		(width 0.14478)
		(layer "In13.Cu")
		(net "M_B_CPU1_SA_DQ<0>")
	)
	(segment
		(start 53.234336 -196.910452)
		(end 54.08422 -197.760336)
		(width 0.14478)
		(layer "In13.Cu")
		(net "M_B_CPU1_SA_DQ<0>")
	)
	(segment
		(start 57.224422 -197.615556)
		(end 57.224422 -197.157848)
		(width 0.14478)
		(layer "In13.Cu")
		(net "M_B_CPU1_SA_DQ<0>")
	)
	(segment
		(start 86.57971 -225.371914)
		(end 86.588092 -225.367088)
		(width 0.0889)
		(layer "In13.Cu")
		(net "M_B_CPU1_SA_DQ<0>")
	)
	(segment
		(start 57.775602 -197.157848)
		(end 57.775602 -197.615556)
		(width 0.14478)
		(layer "In13.Cu")
		(net "M_B_CPU1_SA_DQ<0>")
	)
	(segment
		(start 56.818022 -197.760336)
		(end 57.079642 -197.760336)
		(width 0.14478)
		(layer "In13.Cu")
		(net "M_B_CPU1_SA_DQ<0>")
	)
	(segment
		(start 58.877962 -197.615556)
		(end 59.022742 -197.760336)
		(width 0.14478)
		(layer "In13.Cu")
		(net "M_B_CPU1_SA_DQ<0>")
	)
	(segment
		(start 81.796382 -221.583758)
		(end 81.796382 -222.61449)
		(width 0.0889)
		(layer "In13.Cu")
		(net "M_B_CPU1_SA_DQ<0>")
	)
	(segment
		(start 58.471562 -197.013068)
		(end 58.733182 -197.013068)
		(width 0.14478)
		(layer "In13.Cu")
		(net "M_B_CPU1_SA_DQ<0>")
	)
	(segment
		(start 55.977282 -197.760336)
		(end 56.122062 -197.615556)
		(width 0.14478)
		(layer "In13.Cu")
		(net "M_B_CPU1_SA_DQ<0>")
	)
	(segment
		(start 87.472774 -225.39325)
		(end 87.495126 -225.309938)
		(width 0.0889)
		(layer "In13.Cu")
		(net "M_B_CPU1_SA_DQ<0>")
	)
	(segment
		(start 81.574386 -221.361762)
		(end 81.796382 -221.583758)
		(width 0.0889)
		(layer "In13.Cu")
		(net "M_B_CPU1_SA_DQ<0>")
	)
	(segment
		(start 82.453988 -223.747076)
		(end 82.493104 -223.769936)
		(width 0.0889)
		(layer "In13.Cu")
		(net "M_B_CPU1_SA_DQ<0>")
	)
	(segment
		(start 58.877962 -197.157848)
		(end 58.877962 -197.615556)
		(width 0.14478)
		(layer "In13.Cu")
		(net "M_B_CPU1_SA_DQ<0>")
	)
	(segment
		(start 57.920382 -197.760336)
		(end 58.182002 -197.760336)
		(width 0.14478)
		(layer "In13.Cu")
		(net "M_B_CPU1_SA_DQ<0>")
	)
	(segment
		(start 83.362292 -225.3488)
		(end 83.394042 -225.367088)
		(width 0.0889)
		(layer "In13.Cu")
		(net "M_B_CPU1_SA_DQ<0>")
	)
	(segment
		(start 57.079642 -197.760336)
		(end 57.224422 -197.615556)
		(width 0.14478)
		(layer "In13.Cu")
		(net "M_B_CPU1_SA_DQ<0>")
	)
	(segment
		(start 82.422238 -223.728788)
		(end 82.453988 -223.747076)
		(width 0.0889)
		(layer "In13.Cu")
		(net "M_B_CPU1_SA_DQ<0>")
	)
	(segment
		(start 87.495126 -225.309938)
		(end 87.340948 -225.044508)
		(width 0.0889)
		(layer "In13.Cu")
		(net "M_B_CPU1_SA_DQ<0>")
	)
	(segment
		(start 56.122062 -197.615556)
		(end 56.122062 -197.157848)
		(width 0.14478)
		(layer "In13.Cu")
		(net "M_B_CPU1_SA_DQ<0>")
	)
	(segment
		(start 81.574386 -221.253304)
		(end 81.574386 -221.361762)
		(width 0.0889)
		(layer "In13.Cu")
		(net "M_B_CPU1_SA_DQ<0>")
	)
	(segment
		(start 83.394042 -225.367088)
		(end 83.402424 -225.371914)
		(width 0.0889)
		(layer "In13.Cu")
		(net "M_B_CPU1_SA_DQ<0>")
	)
	(segment
		(start 81.952338 -222.918782)
		(end 82.02041 -222.958152)
		(width 0.0889)
		(layer "In13.Cu")
		(net "M_B_CPU1_SA_DQ<0>")
	)
	(segment
		(start 82.893408 -224.539302)
		(end 82.923888 -224.557082)
		(width 0.0889)
		(layer "In13.Cu")
		(net "M_B_CPU1_SA_DQ<0>")
	)
	(segment
		(start 56.673242 -197.615556)
		(end 56.818022 -197.760336)
		(width 0.14478)
		(layer "In13.Cu")
		(net "M_B_CPU1_SA_DQ<0>")
	)
	(segment
		(start 52.309014 -196.910452)
		(end 53.234336 -196.910452)
		(width 0.14478)
		(layer "In13.Cu")
		(net "M_B_CPU1_SA_DQ<0>")
	)
	(segment
		(start 56.528462 -197.013068)
		(end 56.673242 -197.157848)
		(width 0.14478)
		(layer "In13.Cu")
		(net "M_B_CPU1_SA_DQ<0>")
	)
	(arc
		(start 86.21395 -225.367088)
		(mid 86.396201 -225.417438)
		(end 86.57971 -225.371914)
		(width 0.0889)
		(layer "In13.Cu")
		(net "M_B_CPU1_SA_DQ<0>")
	)
	(arc
		(start 84.707984 -225.367088)
		(mid 84.99094 -225.290911)
		(end 85.273896 -225.367088)
		(width 0.0889)
		(layer "In13.Cu")
		(net "M_B_CPU1_SA_DQ<0>")
	)
	(arc
		(start 87.162386 -225.371914)
		(mid 87.315256 -225.416555)
		(end 87.472774 -225.39325)
		(width 0.0889)
		(layer "In13.Cu")
		(net "M_B_CPU1_SA_DQ<0>")
	)
	(arc
		(start 82.736436 -224.234502)
		(mid 82.777985 -224.405924)
		(end 82.893408 -224.539302)
		(width 0.0889)
		(layer "In13.Cu")
		(net "M_B_CPU1_SA_DQ<0>")
	)
	(arc
		(start 85.648038 -225.367088)
		(mid 85.930994 -225.290911)
		(end 86.21395 -225.367088)
		(width 0.0889)
		(layer "In13.Cu")
		(net "M_B_CPU1_SA_DQ<0>")
	)
	(arc
		(start 83.402424 -225.371914)
		(mid 83.585932 -225.417408)
		(end 83.768184 -225.367088)
		(width 0.0889)
		(layer "In13.Cu")
		(net "M_B_CPU1_SA_DQ<0>")
	)
	(arc
		(start 85.273896 -225.367088)
		(mid 85.456147 -225.417438)
		(end 85.639656 -225.371914)
		(width 0.0889)
		(layer "In13.Cu")
		(net "M_B_CPU1_SA_DQ<0>")
	)
	(arc
		(start 86.588092 -225.367088)
		(mid 86.871048 -225.290911)
		(end 87.154004 -225.367088)
		(width 0.0889)
		(layer "In13.Cu")
		(net "M_B_CPU1_SA_DQ<0>")
	)
	(arc
		(start 84.334096 -225.367088)
		(mid 84.52104 -225.417343)
		(end 84.707984 -225.367088)
		(width 0.0889)
		(layer "In13.Cu")
		(net "M_B_CPU1_SA_DQ<0>")
	)
	(arc
		(start 83.206336 -225.044508)
		(mid 83.247591 -225.215479)
		(end 83.362292 -225.3488)
		(width 0.0889)
		(layer "In13.Cu")
		(net "M_B_CPU1_SA_DQ<0>")
	)
	(arc
		(start 83.768184 -225.367088)
		(mid 84.05114 -225.290911)
		(end 84.334096 -225.367088)
		(width 0.0889)
		(layer "In13.Cu")
		(net "M_B_CPU1_SA_DQ<0>")
	)
	(arc
		(start 82.02041 -222.958152)
		(mid 82.201062 -223.160897)
		(end 82.266282 -223.424496)
		(width 0.0889)
		(layer "In13.Cu")
		(net "M_B_CPU1_SA_DQ<0>")
	)
	(arc
		(start 82.266282 -223.424496)
		(mid 82.307537 -223.595467)
		(end 82.422238 -223.728788)
		(width 0.0889)
		(layer "In13.Cu")
		(net "M_B_CPU1_SA_DQ<0>")
	)
	(arc
		(start 81.796382 -222.61449)
		(mid 81.837637 -222.785461)
		(end 81.952338 -222.918782)
		(width 0.0889)
		(layer "In13.Cu")
		(net "M_B_CPU1_SA_DQ<0>")
	)
	(arc
		(start 82.963004 -224.579942)
		(mid 83.141817 -224.782292)
		(end 83.206336 -225.044508)
		(width 0.0889)
		(layer "In13.Cu")
		(net "M_B_CPU1_SA_DQ<0>")
	)
	(arc
		(start 82.493104 -223.769936)
		(mid 82.671917 -223.972286)
		(end 82.736436 -224.234502)
		(width 0.0889)
		(layer "In13.Cu")
		(net "M_B_CPU1_SA_DQ<0>")
	)
	(segment
		(start 89.687908 -252.850396)
		(end 89.221056 -252.584458)
		(width 0.10668)
		(layer "F.Cu")
		(net "M_B_CPU1_SA_CS_N<1>")
	)
	(segment
		(start 54.993286 -248.760234)
		(end 59.856878 -248.760234)
		(width 0.14478)
		(layer "In13.Cu")
		(net "M_B_CPU1_SA_CS_N<1>")
	)
	(segment
		(start 85.639656 -252.257052)
		(end 85.648038 -252.261878)
		(width 0.0889)
		(layer "In13.Cu")
		(net "M_B_CPU1_SA_CS_N<1>")
	)
	(segment
		(start 49.123092 -246.63527)
		(end 49.548034 -247.060212)
		(width 0.14478)
		(layer "In13.Cu")
		(net "M_B_CPU1_SA_CS_N<1>")
	)
	(segment
		(start 77.540866 -252.21311)
		(end 77.975206 -252.21311)
		(width 0.0889)
		(layer "In13.Cu")
		(net "M_B_CPU1_SA_CS_N<1>")
	)
	(segment
		(start 83.394042 -252.261878)
		(end 83.402424 -252.257052)
		(width 0.0889)
		(layer "In13.Cu")
		(net "M_B_CPU1_SA_CS_N<1>")
	)
	(segment
		(start 79.99984 -252.257052)
		(end 80.008222 -252.261878)
		(width 0.0889)
		(layer "In13.Cu")
		(net "M_B_CPU1_SA_CS_N<1>")
	)
	(segment
		(start 88.97112 -252.293628)
		(end 89.067132 -252.319028)
		(width 0.0889)
		(layer "In13.Cu")
		(net "M_B_CPU1_SA_CS_N<1>")
	)
	(segment
		(start 59.856878 -248.760234)
		(end 62.615318 -251.518674)
		(width 0.14478)
		(layer "In13.Cu")
		(net "M_B_CPU1_SA_CS_N<1>")
	)
	(segment
		(start 73.865486 -252.137164)
		(end 76.067666 -252.137164)
		(width 0.14478)
		(layer "In13.Cu")
		(net "M_B_CPU1_SA_CS_N<1>")
	)
	(segment
		(start 87.154004 -252.261878)
		(end 87.162386 -252.257052)
		(width 0.0889)
		(layer "In13.Cu")
		(net "M_B_CPU1_SA_CS_N<1>")
	)
	(segment
		(start 62.615318 -251.518674)
		(end 73.246996 -251.518674)
		(width 0.14478)
		(layer "In13.Cu")
		(net "M_B_CPU1_SA_CS_N<1>")
	)
	(segment
		(start 78.693518 -252.262132)
		(end 78.709774 -252.252734)
		(width 0.0889)
		(layer "In13.Cu")
		(net "M_B_CPU1_SA_CS_N<1>")
	)
	(segment
		(start 81.879694 -252.257052)
		(end 81.888076 -252.261878)
		(width 0.0889)
		(layer "In13.Cu")
		(net "M_B_CPU1_SA_CS_N<1>")
	)
	(segment
		(start 79.067406 -252.261878)
		(end 79.07782 -252.267974)
		(width 0.0889)
		(layer "In13.Cu")
		(net "M_B_CPU1_SA_CS_N<1>")
	)
	(segment
		(start 77.46492 -252.137164)
		(end 77.540866 -252.21311)
		(width 0.0889)
		(layer "In13.Cu")
		(net "M_B_CPU1_SA_CS_N<1>")
	)
	(segment
		(start 53.293264 -247.060212)
		(end 54.993286 -248.760234)
		(width 0.14478)
		(layer "In13.Cu")
		(net "M_B_CPU1_SA_CS_N<1>")
	)
	(segment
		(start 76.067666 -252.137164)
		(end 77.46492 -252.137164)
		(width 0.0889)
		(layer "In13.Cu")
		(net "M_B_CPU1_SA_CS_N<1>")
	)
	(segment
		(start 89.067132 -252.319028)
		(end 89.221056 -252.584458)
		(width 0.0889)
		(layer "In13.Cu")
		(net "M_B_CPU1_SA_CS_N<1>")
	)
	(segment
		(start 86.587838 -252.261878)
		(end 86.588092 -252.261878)
		(width 0.0889)
		(layer "In13.Cu")
		(net "M_B_CPU1_SA_CS_N<1>")
	)
	(segment
		(start 78.67777 -252.271276)
		(end 78.693518 -252.262132)
		(width 0.0889)
		(layer "In13.Cu")
		(net "M_B_CPU1_SA_CS_N<1>")
	)
	(segment
		(start 49.548034 -247.060212)
		(end 53.293264 -247.060212)
		(width 0.14478)
		(layer "In13.Cu")
		(net "M_B_CPU1_SA_CS_N<1>")
	)
	(segment
		(start 73.246996 -251.518674)
		(end 73.865486 -252.137164)
		(width 0.14478)
		(layer "In13.Cu")
		(net "M_B_CPU1_SA_CS_N<1>")
	)
	(segment
		(start 88.094058 -252.261878)
		(end 88.10244 -252.257052)
		(width 0.0889)
		(layer "In13.Cu")
		(net "M_B_CPU1_SA_CS_N<1>")
	)
	(segment
		(start 47.784004 -246.63527)
		(end 49.123092 -246.63527)
		(width 0.14478)
		(layer "In13.Cu")
		(net "M_B_CPU1_SA_CS_N<1>")
	)
	(segment
		(start 82.453988 -252.261878)
		(end 82.46237 -252.257052)
		(width 0.0889)
		(layer "In13.Cu")
		(net "M_B_CPU1_SA_CS_N<1>")
	)
	(arc
		(start 88.4682 -252.261878)
		(mid 88.715913 -252.337098)
		(end 88.97112 -252.293628)
		(width 0.0889)
		(layer "In13.Cu")
		(net "M_B_CPU1_SA_CS_N<1>")
	)
	(arc
		(start 80.008222 -252.261878)
		(mid 80.291178 -252.338055)
		(end 80.574134 -252.261878)
		(width 0.0889)
		(layer "In13.Cu")
		(net "M_B_CPU1_SA_CS_N<1>")
	)
	(arc
		(start 79.633572 -252.261878)
		(mid 79.816077 -252.211401)
		(end 79.99984 -252.257052)
		(width 0.0889)
		(layer "In13.Cu")
		(net "M_B_CPU1_SA_CS_N<1>")
	)
	(arc
		(start 85.648038 -252.261878)
		(mid 85.930994 -252.338055)
		(end 86.21395 -252.261878)
		(width 0.0889)
		(layer "In13.Cu")
		(net "M_B_CPU1_SA_CS_N<1>")
	)
	(arc
		(start 78.127606 -252.261878)
		(mid 78.401461 -252.338228)
		(end 78.67777 -252.271276)
		(width 0.0889)
		(layer "In13.Cu")
		(net "M_B_CPU1_SA_CS_N<1>")
	)
	(arc
		(start 83.768184 -252.261878)
		(mid 84.05114 -252.338055)
		(end 84.334096 -252.261878)
		(width 0.0889)
		(layer "In13.Cu")
		(net "M_B_CPU1_SA_CS_N<1>")
	)
	(arc
		(start 81.513934 -252.261878)
		(mid 81.696185 -252.211528)
		(end 81.879694 -252.257052)
		(width 0.0889)
		(layer "In13.Cu")
		(net "M_B_CPU1_SA_CS_N<1>")
	)
	(arc
		(start 82.46237 -252.257052)
		(mid 82.645878 -252.211558)
		(end 82.82813 -252.261878)
		(width 0.0889)
		(layer "In13.Cu")
		(net "M_B_CPU1_SA_CS_N<1>")
	)
	(arc
		(start 84.707984 -252.261878)
		(mid 84.99094 -252.338055)
		(end 85.273896 -252.261878)
		(width 0.0889)
		(layer "In13.Cu")
		(net "M_B_CPU1_SA_CS_N<1>")
	)
	(arc
		(start 86.21395 -252.261878)
		(mid 86.400894 -252.211554)
		(end 86.587838 -252.261878)
		(width 0.0889)
		(layer "In13.Cu")
		(net "M_B_CPU1_SA_CS_N<1>")
	)
	(arc
		(start 85.273896 -252.261878)
		(mid 85.456147 -252.211528)
		(end 85.639656 -252.257052)
		(width 0.0889)
		(layer "In13.Cu")
		(net "M_B_CPU1_SA_CS_N<1>")
	)
	(arc
		(start 78.709774 -252.252734)
		(mid 78.889756 -252.211634)
		(end 79.067406 -252.261878)
		(width 0.0889)
		(layer "In13.Cu")
		(net "M_B_CPU1_SA_CS_N<1>")
	)
	(arc
		(start 77.975206 -252.21311)
		(mid 78.054055 -252.229219)
		(end 78.127606 -252.261878)
		(width 0.0889)
		(layer "In13.Cu")
		(net "M_B_CPU1_SA_CS_N<1>")
	)
	(arc
		(start 83.402424 -252.257052)
		(mid 83.585932 -252.211558)
		(end 83.768184 -252.261878)
		(width 0.0889)
		(layer "In13.Cu")
		(net "M_B_CPU1_SA_CS_N<1>")
	)
	(arc
		(start 88.10244 -252.257052)
		(mid 88.285948 -252.211558)
		(end 88.4682 -252.261878)
		(width 0.0889)
		(layer "In13.Cu")
		(net "M_B_CPU1_SA_CS_N<1>")
	)
	(arc
		(start 82.82813 -252.261878)
		(mid 83.111086 -252.338055)
		(end 83.394042 -252.261878)
		(width 0.0889)
		(layer "In13.Cu")
		(net "M_B_CPU1_SA_CS_N<1>")
	)
	(arc
		(start 79.07782 -252.267974)
		(mid 79.356506 -252.338194)
		(end 79.633572 -252.261878)
		(width 0.0889)
		(layer "In13.Cu")
		(net "M_B_CPU1_SA_CS_N<1>")
	)
	(arc
		(start 80.574134 -252.261878)
		(mid 80.761078 -252.211623)
		(end 80.948022 -252.261878)
		(width 0.0889)
		(layer "In13.Cu")
		(net "M_B_CPU1_SA_CS_N<1>")
	)
	(arc
		(start 84.334096 -252.261878)
		(mid 84.52104 -252.211623)
		(end 84.707984 -252.261878)
		(width 0.0889)
		(layer "In13.Cu")
		(net "M_B_CPU1_SA_CS_N<1>")
	)
	(arc
		(start 86.588092 -252.261878)
		(mid 86.871048 -252.338055)
		(end 87.154004 -252.261878)
		(width 0.0889)
		(layer "In13.Cu")
		(net "M_B_CPU1_SA_CS_N<1>")
	)
	(arc
		(start 81.888076 -252.261878)
		(mid 82.171032 -252.338055)
		(end 82.453988 -252.261878)
		(width 0.0889)
		(layer "In13.Cu")
		(net "M_B_CPU1_SA_CS_N<1>")
	)
	(arc
		(start 80.948022 -252.261878)
		(mid 81.230978 -252.338055)
		(end 81.513934 -252.261878)
		(width 0.0889)
		(layer "In13.Cu")
		(net "M_B_CPU1_SA_CS_N<1>")
	)
	(arc
		(start 87.162386 -252.257052)
		(mid 87.345894 -252.211558)
		(end 87.528146 -252.261878)
		(width 0.0889)
		(layer "In13.Cu")
		(net "M_B_CPU1_SA_CS_N<1>")
	)
	(arc
		(start 87.528146 -252.261878)
		(mid 87.811102 -252.338055)
		(end 88.094058 -252.261878)
		(width 0.0889)
		(layer "In13.Cu")
		(net "M_B_CPU1_SA_CS_N<1>")
	)
	(segment
		(start 88.277954 -252.04039)
		(end 87.811102 -251.774452)
		(width 0.10668)
		(layer "F.Cu")
		(net "M_B_CPU1_SA_CS_N<0>")
	)
	(segment
		(start 58.107072 -248.301764)
		(end 58.251852 -248.156984)
		(width 0.14478)
		(layer "In13.Cu")
		(net "M_B_CPU1_SA_CS_N<0>")
	)
	(segment
		(start 55.495952 -248.156984)
		(end 55.640732 -248.301764)
		(width 0.14478)
		(layer "In13.Cu")
		(net "M_B_CPU1_SA_CS_N<0>")
	)
	(segment
		(start 55.351172 -247.91035)
		(end 55.495952 -248.05513)
		(width 0.14478)
		(layer "In13.Cu")
		(net "M_B_CPU1_SA_CS_N<0>")
	)
	(segment
		(start 87.561166 -251.483622)
		(end 87.657178 -251.509022)
		(width 0.0889)
		(layer "In13.Cu")
		(net "M_B_CPU1_SA_CS_N<0>")
	)
	(segment
		(start 84.803996 -251.451872)
		(end 84.812378 -251.447046)
		(width 0.0889)
		(layer "In13.Cu")
		(net "M_B_CPU1_SA_CS_N<0>")
	)
	(segment
		(start 56.191912 -247.91035)
		(end 56.453532 -247.91035)
		(width 0.14478)
		(layer "In13.Cu")
		(net "M_B_CPU1_SA_CS_N<0>")
	)
	(segment
		(start 54.44998 -246.707914)
		(end 54.44998 -246.912638)
		(width 0.14478)
		(layer "In13.Cu")
		(net "M_B_CPU1_SA_CS_N<0>")
	)
	(segment
		(start 56.047132 -248.05513)
		(end 56.191912 -247.91035)
		(width 0.14478)
		(layer "In13.Cu")
		(net "M_B_CPU1_SA_CS_N<0>")
	)
	(segment
		(start 59.666378 -247.91035)
		(end 62.820042 -251.064014)
		(width 0.14478)
		(layer "In13.Cu")
		(net "M_B_CPU1_SA_CS_N<0>")
	)
	(segment
		(start 80.093566 -251.457968)
		(end 80.10398 -251.451872)
		(width 0.0889)
		(layer "In13.Cu")
		(net "M_B_CPU1_SA_CS_N<0>")
	)
	(segment
		(start 57.149492 -248.05513)
		(end 57.294272 -247.91035)
		(width 0.14478)
		(layer "In13.Cu")
		(net "M_B_CPU1_SA_CS_N<0>")
	)
	(segment
		(start 78.58633 -251.445014)
		(end 78.598014 -251.451872)
		(width 0.0889)
		(layer "In13.Cu")
		(net "M_B_CPU1_SA_CS_N<0>")
	)
	(segment
		(start 83.289648 -251.447046)
		(end 83.29803 -251.451872)
		(width 0.0889)
		(layer "In13.Cu")
		(net "M_B_CPU1_SA_CS_N<0>")
	)
	(segment
		(start 84.229702 -251.447046)
		(end 84.238084 -251.451872)
		(width 0.0889)
		(layer "In13.Cu")
		(net "M_B_CPU1_SA_CS_N<0>")
	)
	(segment
		(start 53.492146 -246.319548)
		(end 53.775356 -246.602758)
		(width 0.14478)
		(layer "In13.Cu")
		(net "M_B_CPU1_SA_CS_N<0>")
	)
	(segment
		(start 87.657178 -251.509022)
		(end 87.811102 -251.774452)
		(width 0.0889)
		(layer "In13.Cu")
		(net "M_B_CPU1_SA_CS_N<0>")
	)
	(segment
		(start 56.598312 -248.05513)
		(end 56.598312 -248.156984)
		(width 0.14478)
		(layer "In13.Cu")
		(net "M_B_CPU1_SA_CS_N<0>")
	)
	(segment
		(start 57.149492 -248.156984)
		(end 57.149492 -248.05513)
		(width 0.14478)
		(layer "In13.Cu")
		(net "M_B_CPU1_SA_CS_N<0>")
	)
	(segment
		(start 54.36997 -246.992648)
		(end 54.36997 -247.197372)
		(width 0.14478)
		(layer "In13.Cu")
		(net "M_B_CPU1_SA_CS_N<0>")
	)
	(segment
		(start 76.070206 -251.593604)
		(end 77.19695 -251.593604)
		(width 0.0889)
		(layer "In13.Cu")
		(net "M_B_CPU1_SA_CS_N<0>")
	)
	(segment
		(start 57.700672 -248.05513)
		(end 57.700672 -248.156984)
		(width 0.14478)
		(layer "In13.Cu")
		(net "M_B_CPU1_SA_CS_N<0>")
	)
	(segment
		(start 57.004712 -248.301764)
		(end 57.149492 -248.156984)
		(width 0.14478)
		(layer "In13.Cu")
		(net "M_B_CPU1_SA_CS_N<0>")
	)
	(segment
		(start 58.251852 -248.156984)
		(end 58.251852 -248.05513)
		(width 0.14478)
		(layer "In13.Cu")
		(net "M_B_CPU1_SA_CS_N<0>")
	)
	(segment
		(start 86.684104 -251.451872)
		(end 86.692486 -251.447046)
		(width 0.0889)
		(layer "In13.Cu")
		(net "M_B_CPU1_SA_CS_N<0>")
	)
	(segment
		(start 53.775356 -246.602758)
		(end 53.98008 -246.602758)
		(width 0.14478)
		(layer "In13.Cu")
		(net "M_B_CPU1_SA_CS_N<0>")
	)
	(segment
		(start 57.700672 -248.156984)
		(end 57.845452 -248.301764)
		(width 0.14478)
		(layer "In13.Cu")
		(net "M_B_CPU1_SA_CS_N<0>")
	)
	(segment
		(start 85.74405 -251.451872)
		(end 85.752432 -251.447046)
		(width 0.0889)
		(layer "In13.Cu")
		(net "M_B_CPU1_SA_CS_N<0>")
	)
	(segment
		(start 58.251852 -248.05513)
		(end 58.396632 -247.91035)
		(width 0.14478)
		(layer "In13.Cu")
		(net "M_B_CPU1_SA_CS_N<0>")
	)
	(segment
		(start 62.820042 -251.064014)
		(end 73.435464 -251.064014)
		(width 0.14478)
		(layer "In13.Cu")
		(net "M_B_CPU1_SA_CS_N<0>")
	)
	(segment
		(start 55.902352 -248.301764)
		(end 56.047132 -248.156984)
		(width 0.14478)
		(layer "In13.Cu")
		(net "M_B_CPU1_SA_CS_N<0>")
	)
	(segment
		(start 73.965054 -251.593604)
		(end 76.070206 -251.593604)
		(width 0.14478)
		(layer "In13.Cu")
		(net "M_B_CPU1_SA_CS_N<0>")
	)
	(segment
		(start 57.555892 -247.91035)
		(end 57.700672 -248.05513)
		(width 0.14478)
		(layer "In13.Cu")
		(net "M_B_CPU1_SA_CS_N<0>")
	)
	(segment
		(start 79.163672 -251.451872)
		(end 79.17815 -251.44349)
		(width 0.0889)
		(layer "In13.Cu")
		(net "M_B_CPU1_SA_CS_N<0>")
	)
	(segment
		(start 56.047132 -248.156984)
		(end 56.047132 -248.05513)
		(width 0.14478)
		(layer "In13.Cu")
		(net "M_B_CPU1_SA_CS_N<0>")
	)
	(segment
		(start 54.36997 -247.197372)
		(end 55.082948 -247.91035)
		(width 0.14478)
		(layer "In13.Cu")
		(net "M_B_CPU1_SA_CS_N<0>")
	)
	(segment
		(start 56.598312 -248.156984)
		(end 56.743092 -248.301764)
		(width 0.14478)
		(layer "In13.Cu")
		(net "M_B_CPU1_SA_CS_N<0>")
	)
	(segment
		(start 73.435464 -251.064014)
		(end 73.965054 -251.593604)
		(width 0.14478)
		(layer "In13.Cu")
		(net "M_B_CPU1_SA_CS_N<0>")
	)
	(segment
		(start 53.98008 -246.602758)
		(end 54.06009 -246.522748)
		(width 0.14478)
		(layer "In13.Cu")
		(net "M_B_CPU1_SA_CS_N<0>")
	)
	(segment
		(start 81.044034 -251.451872)
		(end 81.052416 -251.447046)
		(width 0.0889)
		(layer "In13.Cu")
		(net "M_B_CPU1_SA_CS_N<0>")
	)
	(segment
		(start 77.19695 -251.593604)
		(end 77.262228 -251.528326)
		(width 0.0889)
		(layer "In13.Cu")
		(net "M_B_CPU1_SA_CS_N<0>")
	)
	(segment
		(start 54.06009 -246.522748)
		(end 54.264814 -246.522748)
		(width 0.14478)
		(layer "In13.Cu")
		(net "M_B_CPU1_SA_CS_N<0>")
	)
	(segment
		(start 80.46974 -251.447046)
		(end 80.478122 -251.451872)
		(width 0.0889)
		(layer "In13.Cu")
		(net "M_B_CPU1_SA_CS_N<0>")
	)
	(segment
		(start 54.264814 -246.522748)
		(end 54.44998 -246.707914)
		(width 0.14478)
		(layer "In13.Cu")
		(net "M_B_CPU1_SA_CS_N<0>")
	)
	(segment
		(start 52.418234 -246.319548)
		(end 53.492146 -246.319548)
		(width 0.14478)
		(layer "In13.Cu")
		(net "M_B_CPU1_SA_CS_N<0>")
	)
	(segment
		(start 58.396632 -247.91035)
		(end 59.666378 -247.91035)
		(width 0.14478)
		(layer "In13.Cu")
		(net "M_B_CPU1_SA_CS_N<0>")
	)
	(segment
		(start 57.294272 -247.91035)
		(end 57.555892 -247.91035)
		(width 0.14478)
		(layer "In13.Cu")
		(net "M_B_CPU1_SA_CS_N<0>")
	)
	(segment
		(start 56.453532 -247.91035)
		(end 56.598312 -248.05513)
		(width 0.14478)
		(layer "In13.Cu")
		(net "M_B_CPU1_SA_CS_N<0>")
	)
	(segment
		(start 55.640732 -248.301764)
		(end 55.902352 -248.301764)
		(width 0.14478)
		(layer "In13.Cu")
		(net "M_B_CPU1_SA_CS_N<0>")
	)
	(segment
		(start 55.082948 -247.91035)
		(end 55.351172 -247.91035)
		(width 0.14478)
		(layer "In13.Cu")
		(net "M_B_CPU1_SA_CS_N<0>")
	)
	(segment
		(start 56.743092 -248.301764)
		(end 57.004712 -248.301764)
		(width 0.14478)
		(layer "In13.Cu")
		(net "M_B_CPU1_SA_CS_N<0>")
	)
	(segment
		(start 54.44998 -246.912638)
		(end 54.36997 -246.992648)
		(width 0.14478)
		(layer "In13.Cu")
		(net "M_B_CPU1_SA_CS_N<0>")
	)
	(segment
		(start 77.262228 -251.528326)
		(end 77.940154 -251.528326)
		(width 0.0889)
		(layer "In13.Cu")
		(net "M_B_CPU1_SA_CS_N<0>")
	)
	(segment
		(start 51.884072 -245.785386)
		(end 52.418234 -246.319548)
		(width 0.14478)
		(layer "In13.Cu")
		(net "M_B_CPU1_SA_CS_N<0>")
	)
	(segment
		(start 79.153258 -251.457968)
		(end 79.163672 -251.451872)
		(width 0.0889)
		(layer "In13.Cu")
		(net "M_B_CPU1_SA_CS_N<0>")
	)
	(segment
		(start 55.495952 -248.05513)
		(end 55.495952 -248.156984)
		(width 0.14478)
		(layer "In13.Cu")
		(net "M_B_CPU1_SA_CS_N<0>")
	)
	(segment
		(start 57.845452 -248.301764)
		(end 58.107072 -248.301764)
		(width 0.14478)
		(layer "In13.Cu")
		(net "M_B_CPU1_SA_CS_N<0>")
	)
	(arc
		(start 86.692486 -251.447046)
		(mid 86.875994 -251.401552)
		(end 87.058246 -251.451872)
		(width 0.0889)
		(layer "In13.Cu")
		(net "M_B_CPU1_SA_CS_N<0>")
	)
	(arc
		(start 82.923888 -251.451872)
		(mid 83.106139 -251.401522)
		(end 83.289648 -251.447046)
		(width 0.0889)
		(layer "In13.Cu")
		(net "M_B_CPU1_SA_CS_N<0>")
	)
	(arc
		(start 80.10398 -251.451872)
		(mid 80.286231 -251.401522)
		(end 80.46974 -251.447046)
		(width 0.0889)
		(layer "In13.Cu")
		(net "M_B_CPU1_SA_CS_N<0>")
	)
	(arc
		(start 79.537814 -251.451872)
		(mid 79.814881 -251.528143)
		(end 80.093566 -251.457968)
		(width 0.0889)
		(layer "In13.Cu")
		(net "M_B_CPU1_SA_CS_N<0>")
	)
	(arc
		(start 81.984088 -251.451872)
		(mid 82.171032 -251.401617)
		(end 82.357976 -251.451872)
		(width 0.0889)
		(layer "In13.Cu")
		(net "M_B_CPU1_SA_CS_N<0>")
	)
	(arc
		(start 81.418176 -251.451872)
		(mid 81.701132 -251.528049)
		(end 81.984088 -251.451872)
		(width 0.0889)
		(layer "In13.Cu")
		(net "M_B_CPU1_SA_CS_N<0>")
	)
	(arc
		(start 77.940154 -251.528326)
		(mid 78.086958 -251.50889)
		(end 78.223618 -251.451872)
		(width 0.0889)
		(layer "In13.Cu")
		(net "M_B_CPU1_SA_CS_N<0>")
	)
	(arc
		(start 86.118192 -251.451872)
		(mid 86.401148 -251.528049)
		(end 86.684104 -251.451872)
		(width 0.0889)
		(layer "In13.Cu")
		(net "M_B_CPU1_SA_CS_N<0>")
	)
	(arc
		(start 83.863942 -251.451872)
		(mid 84.046193 -251.401522)
		(end 84.229702 -251.447046)
		(width 0.0889)
		(layer "In13.Cu")
		(net "M_B_CPU1_SA_CS_N<0>")
	)
	(arc
		(start 84.238084 -251.451872)
		(mid 84.52104 -251.528049)
		(end 84.803996 -251.451872)
		(width 0.0889)
		(layer "In13.Cu")
		(net "M_B_CPU1_SA_CS_N<0>")
	)
	(arc
		(start 82.357976 -251.451872)
		(mid 82.640932 -251.528049)
		(end 82.923888 -251.451872)
		(width 0.0889)
		(layer "In13.Cu")
		(net "M_B_CPU1_SA_CS_N<0>")
	)
	(arc
		(start 85.752432 -251.447046)
		(mid 85.93594 -251.401552)
		(end 86.118192 -251.451872)
		(width 0.0889)
		(layer "In13.Cu")
		(net "M_B_CPU1_SA_CS_N<0>")
	)
	(arc
		(start 78.598014 -251.451872)
		(mid 78.874827 -251.528015)
		(end 79.153258 -251.457968)
		(width 0.0889)
		(layer "In13.Cu")
		(net "M_B_CPU1_SA_CS_N<0>")
	)
	(arc
		(start 80.478122 -251.451872)
		(mid 80.761078 -251.528049)
		(end 81.044034 -251.451872)
		(width 0.0889)
		(layer "In13.Cu")
		(net "M_B_CPU1_SA_CS_N<0>")
	)
	(arc
		(start 81.052416 -251.447046)
		(mid 81.235924 -251.401552)
		(end 81.418176 -251.451872)
		(width 0.0889)
		(layer "In13.Cu")
		(net "M_B_CPU1_SA_CS_N<0>")
	)
	(arc
		(start 83.29803 -251.451872)
		(mid 83.580986 -251.528049)
		(end 83.863942 -251.451872)
		(width 0.0889)
		(layer "In13.Cu")
		(net "M_B_CPU1_SA_CS_N<0>")
	)
	(arc
		(start 85.178138 -251.451872)
		(mid 85.461094 -251.528049)
		(end 85.74405 -251.451872)
		(width 0.0889)
		(layer "In13.Cu")
		(net "M_B_CPU1_SA_CS_N<0>")
	)
	(arc
		(start 79.17815 -251.44349)
		(mid 79.359058 -251.401468)
		(end 79.537814 -251.451872)
		(width 0.0889)
		(layer "In13.Cu")
		(net "M_B_CPU1_SA_CS_N<0>")
	)
	(arc
		(start 78.223618 -251.451872)
		(mid 78.404076 -251.401428)
		(end 78.58633 -251.445014)
		(width 0.0889)
		(layer "In13.Cu")
		(net "M_B_CPU1_SA_CS_N<0>")
	)
	(arc
		(start 84.812378 -251.447046)
		(mid 84.995886 -251.401552)
		(end 85.178138 -251.451872)
		(width 0.0889)
		(layer "In13.Cu")
		(net "M_B_CPU1_SA_CS_N<0>")
	)
	(arc
		(start 87.058246 -251.451872)
		(mid 87.305959 -251.527092)
		(end 87.561166 -251.483622)
		(width 0.0889)
		(layer "In13.Cu")
		(net "M_B_CPU1_SA_CS_N<0>")
	)
	(segment
		(start 89.687908 -249.610372)
		(end 89.221056 -249.344434)
		(width 0.10668)
		(layer "F.Cu")
		(net "M_B_CPU1_SA_CB<7>")
	)
	(segment
		(start 88.97112 -249.053604)
		(end 89.067132 -249.079004)
		(width 0.0889)
		(layer "In13.Cu")
		(net "M_B_CPU1_SA_CB<7>")
	)
	(segment
		(start 50.011584 -243.235226)
		(end 50.43678 -243.660422)
		(width 0.14478)
		(layer "In13.Cu")
		(net "M_B_CPU1_SA_CB<7>")
	)
	(segment
		(start 77.75321 -249.021854)
		(end 77.764894 -249.014996)
		(width 0.0889)
		(layer "In13.Cu")
		(net "M_B_CPU1_SA_CB<7>")
	)
	(segment
		(start 50.43678 -243.660422)
		(end 55.661306 -243.660422)
		(width 0.14478)
		(layer "In13.Cu")
		(net "M_B_CPU1_SA_CB<7>")
	)
	(segment
		(start 47.784004 -243.235226)
		(end 50.011584 -243.235226)
		(width 0.14478)
		(layer "In13.Cu")
		(net "M_B_CPU1_SA_CB<7>")
	)
	(segment
		(start 78.693518 -249.022108)
		(end 78.709774 -249.01271)
		(width 0.0889)
		(layer "In13.Cu")
		(net "M_B_CPU1_SA_CB<7>")
	)
	(segment
		(start 89.067132 -249.079004)
		(end 89.221056 -249.344434)
		(width 0.0889)
		(layer "In13.Cu")
		(net "M_B_CPU1_SA_CB<7>")
	)
	(segment
		(start 60.20816 -245.469918)
		(end 63.884556 -249.146314)
		(width 0.14478)
		(layer "In13.Cu")
		(net "M_B_CPU1_SA_CB<7>")
	)
	(segment
		(start 55.661306 -243.660422)
		(end 57.470802 -245.469918)
		(width 0.14478)
		(layer "In13.Cu")
		(net "M_B_CPU1_SA_CB<7>")
	)
	(segment
		(start 63.884556 -249.146314)
		(end 74.268076 -249.146314)
		(width 0.14478)
		(layer "In13.Cu")
		(net "M_B_CPU1_SA_CB<7>")
	)
	(segment
		(start 76.67879 -249.201686)
		(end 77.08519 -249.201686)
		(width 0.0889)
		(layer "In13.Cu")
		(net "M_B_CPU1_SA_CB<7>")
	)
	(segment
		(start 88.094058 -249.021854)
		(end 88.10244 -249.017028)
		(width 0.0889)
		(layer "In13.Cu")
		(net "M_B_CPU1_SA_CB<7>")
	)
	(segment
		(start 79.99984 -249.017028)
		(end 80.008222 -249.021854)
		(width 0.0889)
		(layer "In13.Cu")
		(net "M_B_CPU1_SA_CB<7>")
	)
	(segment
		(start 78.67777 -249.031252)
		(end 78.693518 -249.022108)
		(width 0.0889)
		(layer "In13.Cu")
		(net "M_B_CPU1_SA_CB<7>")
	)
	(segment
		(start 81.879694 -249.017028)
		(end 81.888076 -249.021854)
		(width 0.0889)
		(layer "In13.Cu")
		(net "M_B_CPU1_SA_CB<7>")
	)
	(segment
		(start 79.067406 -249.021854)
		(end 79.07782 -249.02795)
		(width 0.0889)
		(layer "In13.Cu")
		(net "M_B_CPU1_SA_CB<7>")
	)
	(segment
		(start 74.581766 -249.460004)
		(end 75.940666 -249.460004)
		(width 0.14478)
		(layer "In13.Cu")
		(net "M_B_CPU1_SA_CB<7>")
	)
	(segment
		(start 76.420472 -249.460004)
		(end 76.67879 -249.201686)
		(width 0.0889)
		(layer "In13.Cu")
		(net "M_B_CPU1_SA_CB<7>")
	)
	(segment
		(start 85.639656 -249.017028)
		(end 85.648038 -249.021854)
		(width 0.0889)
		(layer "In13.Cu")
		(net "M_B_CPU1_SA_CB<7>")
	)
	(segment
		(start 87.154004 -249.021854)
		(end 87.162386 -249.017028)
		(width 0.0889)
		(layer "In13.Cu")
		(net "M_B_CPU1_SA_CB<7>")
	)
	(segment
		(start 83.394042 -249.021854)
		(end 83.402424 -249.017028)
		(width 0.0889)
		(layer "In13.Cu")
		(net "M_B_CPU1_SA_CB<7>")
	)
	(segment
		(start 75.940666 -249.460004)
		(end 76.420472 -249.460004)
		(width 0.0889)
		(layer "In13.Cu")
		(net "M_B_CPU1_SA_CB<7>")
	)
	(segment
		(start 82.453988 -249.021854)
		(end 82.46237 -249.017028)
		(width 0.0889)
		(layer "In13.Cu")
		(net "M_B_CPU1_SA_CB<7>")
	)
	(segment
		(start 57.470802 -245.469918)
		(end 60.20816 -245.469918)
		(width 0.14478)
		(layer "In13.Cu")
		(net "M_B_CPU1_SA_CB<7>")
	)
	(segment
		(start 86.57971 -249.017028)
		(end 86.588092 -249.021854)
		(width 0.0889)
		(layer "In13.Cu")
		(net "M_B_CPU1_SA_CB<7>")
	)
	(segment
		(start 74.268076 -249.146314)
		(end 74.581766 -249.460004)
		(width 0.14478)
		(layer "In13.Cu")
		(net "M_B_CPU1_SA_CB<7>")
	)
	(arc
		(start 86.21395 -249.021854)
		(mid 86.396201 -248.971504)
		(end 86.57971 -249.017028)
		(width 0.0889)
		(layer "In13.Cu")
		(net "M_B_CPU1_SA_CB<7>")
	)
	(arc
		(start 77.08519 -249.201686)
		(mid 77.431083 -249.155927)
		(end 77.75321 -249.021854)
		(width 0.0889)
		(layer "In13.Cu")
		(net "M_B_CPU1_SA_CB<7>")
	)
	(arc
		(start 88.10244 -249.017028)
		(mid 88.285948 -248.971534)
		(end 88.4682 -249.021854)
		(width 0.0889)
		(layer "In13.Cu")
		(net "M_B_CPU1_SA_CB<7>")
	)
	(arc
		(start 84.707984 -249.021854)
		(mid 84.99094 -249.098031)
		(end 85.273896 -249.021854)
		(width 0.0889)
		(layer "In13.Cu")
		(net "M_B_CPU1_SA_CB<7>")
	)
	(arc
		(start 83.402424 -249.017028)
		(mid 83.585932 -248.971534)
		(end 83.768184 -249.021854)
		(width 0.0889)
		(layer "In13.Cu")
		(net "M_B_CPU1_SA_CB<7>")
	)
	(arc
		(start 88.4682 -249.021854)
		(mid 88.715913 -249.097074)
		(end 88.97112 -249.053604)
		(width 0.0889)
		(layer "In13.Cu")
		(net "M_B_CPU1_SA_CB<7>")
	)
	(arc
		(start 82.46237 -249.017028)
		(mid 82.645878 -248.971534)
		(end 82.82813 -249.021854)
		(width 0.0889)
		(layer "In13.Cu")
		(net "M_B_CPU1_SA_CB<7>")
	)
	(arc
		(start 80.574134 -249.021854)
		(mid 80.761078 -248.971599)
		(end 80.948022 -249.021854)
		(width 0.0889)
		(layer "In13.Cu")
		(net "M_B_CPU1_SA_CB<7>")
	)
	(arc
		(start 85.273896 -249.021854)
		(mid 85.456147 -248.971504)
		(end 85.639656 -249.017028)
		(width 0.0889)
		(layer "In13.Cu")
		(net "M_B_CPU1_SA_CB<7>")
	)
	(arc
		(start 85.648038 -249.021854)
		(mid 85.930994 -249.098031)
		(end 86.21395 -249.021854)
		(width 0.0889)
		(layer "In13.Cu")
		(net "M_B_CPU1_SA_CB<7>")
	)
	(arc
		(start 87.162386 -249.017028)
		(mid 87.345894 -248.971534)
		(end 87.528146 -249.021854)
		(width 0.0889)
		(layer "In13.Cu")
		(net "M_B_CPU1_SA_CB<7>")
	)
	(arc
		(start 82.82813 -249.021854)
		(mid 83.111086 -249.098031)
		(end 83.394042 -249.021854)
		(width 0.0889)
		(layer "In13.Cu")
		(net "M_B_CPU1_SA_CB<7>")
	)
	(arc
		(start 86.588092 -249.021854)
		(mid 86.871048 -249.098031)
		(end 87.154004 -249.021854)
		(width 0.0889)
		(layer "In13.Cu")
		(net "M_B_CPU1_SA_CB<7>")
	)
	(arc
		(start 87.528146 -249.021854)
		(mid 87.811102 -249.098031)
		(end 88.094058 -249.021854)
		(width 0.0889)
		(layer "In13.Cu")
		(net "M_B_CPU1_SA_CB<7>")
	)
	(arc
		(start 79.07782 -249.02795)
		(mid 79.356506 -249.09817)
		(end 79.633572 -249.021854)
		(width 0.0889)
		(layer "In13.Cu")
		(net "M_B_CPU1_SA_CB<7>")
	)
	(arc
		(start 81.888076 -249.021854)
		(mid 82.171032 -249.098031)
		(end 82.453988 -249.021854)
		(width 0.0889)
		(layer "In13.Cu")
		(net "M_B_CPU1_SA_CB<7>")
	)
	(arc
		(start 78.127606 -249.021854)
		(mid 78.401461 -249.098204)
		(end 78.67777 -249.031252)
		(width 0.0889)
		(layer "In13.Cu")
		(net "M_B_CPU1_SA_CB<7>")
	)
	(arc
		(start 79.633572 -249.021854)
		(mid 79.816077 -248.971377)
		(end 79.99984 -249.017028)
		(width 0.0889)
		(layer "In13.Cu")
		(net "M_B_CPU1_SA_CB<7>")
	)
	(arc
		(start 81.513934 -249.021854)
		(mid 81.696185 -248.971504)
		(end 81.879694 -249.017028)
		(width 0.0889)
		(layer "In13.Cu")
		(net "M_B_CPU1_SA_CB<7>")
	)
	(arc
		(start 80.948022 -249.021854)
		(mid 81.230978 -249.098031)
		(end 81.513934 -249.021854)
		(width 0.0889)
		(layer "In13.Cu")
		(net "M_B_CPU1_SA_CB<7>")
	)
	(arc
		(start 84.334096 -249.021854)
		(mid 84.52104 -248.971599)
		(end 84.707984 -249.021854)
		(width 0.0889)
		(layer "In13.Cu")
		(net "M_B_CPU1_SA_CB<7>")
	)
	(arc
		(start 77.764894 -249.014996)
		(mid 77.947149 -248.971343)
		(end 78.127606 -249.021854)
		(width 0.0889)
		(layer "In13.Cu")
		(net "M_B_CPU1_SA_CB<7>")
	)
	(arc
		(start 83.768184 -249.021854)
		(mid 84.05114 -249.098031)
		(end 84.334096 -249.021854)
		(width 0.0889)
		(layer "In13.Cu")
		(net "M_B_CPU1_SA_CB<7>")
	)
	(arc
		(start 78.709774 -249.01271)
		(mid 78.889756 -248.97161)
		(end 79.067406 -249.021854)
		(width 0.0889)
		(layer "In13.Cu")
		(net "M_B_CPU1_SA_CB<7>")
	)
	(arc
		(start 80.008222 -249.021854)
		(mid 80.291178 -249.098031)
		(end 80.574134 -249.021854)
		(width 0.0889)
		(layer "In13.Cu")
		(net "M_B_CPU1_SA_CB<7>")
	)
	(segment
		(start 88.277954 -248.800366)
		(end 87.811102 -248.534428)
		(width 0.10668)
		(layer "F.Cu")
		(net "M_B_CPU1_SA_CB<6>")
	)
	(segment
		(start 76.261468 -248.543064)
		(end 76.35367 -248.635266)
		(width 0.0889)
		(layer "In13.Cu")
		(net "M_B_CPU1_SA_CB<6>")
	)
	(segment
		(start 50.679858 -241.535204)
		(end 51.12766 -241.535204)
		(width 0.14478)
		(layer "In13.Cu")
		(net "M_B_CPU1_SA_CB<6>")
	)
	(segment
		(start 77.875384 -248.543826)
		(end 78.147926 -248.271284)
		(width 0.0889)
		(layer "In13.Cu")
		(net "M_B_CPU1_SA_CB<6>")
	)
	(segment
		(start 64.313816 -248.236994)
		(end 74.666856 -248.236994)
		(width 0.14478)
		(layer "In13.Cu")
		(net "M_B_CPU1_SA_CB<6>")
	)
	(segment
		(start 47.784004 -241.535204)
		(end 48.736758 -241.535204)
		(width 0.14478)
		(layer "In13.Cu")
		(net "M_B_CPU1_SA_CB<6>")
	)
	(segment
		(start 49.432718 -241.888264)
		(end 49.432718 -241.679984)
		(width 0.14478)
		(layer "In13.Cu")
		(net "M_B_CPU1_SA_CB<6>")
	)
	(segment
		(start 49.577498 -241.535204)
		(end 49.839118 -241.535204)
		(width 0.14478)
		(layer "In13.Cu")
		(net "M_B_CPU1_SA_CB<6>")
	)
	(segment
		(start 80.46974 -248.207022)
		(end 80.478122 -248.211848)
		(width 0.0889)
		(layer "In13.Cu")
		(net "M_B_CPU1_SA_CB<6>")
	)
	(segment
		(start 84.803996 -248.211848)
		(end 84.812378 -248.207022)
		(width 0.0889)
		(layer "In13.Cu")
		(net "M_B_CPU1_SA_CB<6>")
	)
	(segment
		(start 59.743848 -243.667026)
		(end 64.313816 -248.236994)
		(width 0.14478)
		(layer "In13.Cu")
		(net "M_B_CPU1_SA_CB<6>")
	)
	(segment
		(start 74.666856 -248.236994)
		(end 74.972926 -248.543064)
		(width 0.14478)
		(layer "In13.Cu")
		(net "M_B_CPU1_SA_CB<6>")
	)
	(segment
		(start 48.881538 -241.888264)
		(end 49.026318 -242.033044)
		(width 0.14478)
		(layer "In13.Cu")
		(net "M_B_CPU1_SA_CB<6>")
	)
	(segment
		(start 56.798972 -241.9604)
		(end 58.505598 -243.667026)
		(width 0.14478)
		(layer "In13.Cu")
		(net "M_B_CPU1_SA_CB<6>")
	)
	(segment
		(start 75.927966 -248.543064)
		(end 76.261468 -248.543064)
		(width 0.0889)
		(layer "In13.Cu")
		(net "M_B_CPU1_SA_CB<6>")
	)
	(segment
		(start 48.881538 -241.679984)
		(end 48.881538 -241.888264)
		(width 0.14478)
		(layer "In13.Cu")
		(net "M_B_CPU1_SA_CB<6>")
	)
	(segment
		(start 49.983898 -241.888264)
		(end 50.128678 -242.033044)
		(width 0.14478)
		(layer "In13.Cu")
		(net "M_B_CPU1_SA_CB<6>")
	)
	(segment
		(start 49.983898 -241.679984)
		(end 49.983898 -241.888264)
		(width 0.14478)
		(layer "In13.Cu")
		(net "M_B_CPU1_SA_CB<6>")
	)
	(segment
		(start 51.552856 -241.9604)
		(end 56.798972 -241.9604)
		(width 0.14478)
		(layer "In13.Cu")
		(net "M_B_CPU1_SA_CB<6>")
	)
	(segment
		(start 79.143098 -248.225564)
		(end 79.166466 -248.211848)
		(width 0.0889)
		(layer "In13.Cu")
		(net "M_B_CPU1_SA_CB<6>")
	)
	(segment
		(start 76.35367 -248.635266)
		(end 77.43317 -248.635266)
		(width 0.0889)
		(layer "In13.Cu")
		(net "M_B_CPU1_SA_CB<6>")
	)
	(segment
		(start 51.12766 -241.535204)
		(end 51.552856 -241.9604)
		(width 0.14478)
		(layer "In13.Cu")
		(net "M_B_CPU1_SA_CB<6>")
	)
	(segment
		(start 77.43317 -248.635266)
		(end 77.52461 -248.543826)
		(width 0.0889)
		(layer "In13.Cu")
		(net "M_B_CPU1_SA_CB<6>")
	)
	(segment
		(start 50.535078 -241.888264)
		(end 50.535078 -241.679984)
		(width 0.14478)
		(layer "In13.Cu")
		(net "M_B_CPU1_SA_CB<6>")
	)
	(segment
		(start 50.535078 -241.679984)
		(end 50.679858 -241.535204)
		(width 0.14478)
		(layer "In13.Cu")
		(net "M_B_CPU1_SA_CB<6>")
	)
	(segment
		(start 74.972926 -248.543064)
		(end 75.927966 -248.543064)
		(width 0.14478)
		(layer "In13.Cu")
		(net "M_B_CPU1_SA_CB<6>")
	)
	(segment
		(start 58.505598 -243.667026)
		(end 59.743848 -243.667026)
		(width 0.14478)
		(layer "In13.Cu")
		(net "M_B_CPU1_SA_CB<6>")
	)
	(segment
		(start 77.52461 -248.543826)
		(end 77.875384 -248.543826)
		(width 0.0889)
		(layer "In13.Cu")
		(net "M_B_CPU1_SA_CB<6>")
	)
	(segment
		(start 49.026318 -242.033044)
		(end 49.287938 -242.033044)
		(width 0.14478)
		(layer "In13.Cu")
		(net "M_B_CPU1_SA_CB<6>")
	)
	(segment
		(start 83.289648 -248.207022)
		(end 83.29803 -248.211848)
		(width 0.0889)
		(layer "In13.Cu")
		(net "M_B_CPU1_SA_CB<6>")
	)
	(segment
		(start 49.839118 -241.535204)
		(end 49.983898 -241.679984)
		(width 0.14478)
		(layer "In13.Cu")
		(net "M_B_CPU1_SA_CB<6>")
	)
	(segment
		(start 87.656924 -248.268998)
		(end 87.811102 -248.534428)
		(width 0.0889)
		(layer "In13.Cu")
		(net "M_B_CPU1_SA_CB<6>")
	)
	(segment
		(start 50.390298 -242.033044)
		(end 50.535078 -241.888264)
		(width 0.14478)
		(layer "In13.Cu")
		(net "M_B_CPU1_SA_CB<6>")
	)
	(segment
		(start 87.560658 -248.243598)
		(end 87.656924 -248.268998)
		(width 0.0889)
		(layer "In13.Cu")
		(net "M_B_CPU1_SA_CB<6>")
	)
	(segment
		(start 48.736758 -241.535204)
		(end 48.881538 -241.679984)
		(width 0.14478)
		(layer "In13.Cu")
		(net "M_B_CPU1_SA_CB<6>")
	)
	(segment
		(start 79.539592 -248.212102)
		(end 79.561182 -248.224548)
		(width 0.0889)
		(layer "In13.Cu")
		(net "M_B_CPU1_SA_CB<6>")
	)
	(segment
		(start 49.287938 -242.033044)
		(end 49.432718 -241.888264)
		(width 0.14478)
		(layer "In13.Cu")
		(net "M_B_CPU1_SA_CB<6>")
	)
	(segment
		(start 78.225142 -248.212102)
		(end 78.252574 -248.196354)
		(width 0.0889)
		(layer "In13.Cu")
		(net "M_B_CPU1_SA_CB<6>")
	)
	(segment
		(start 85.74405 -248.211848)
		(end 85.752432 -248.207022)
		(width 0.0889)
		(layer "In13.Cu")
		(net "M_B_CPU1_SA_CB<6>")
	)
	(segment
		(start 79.521304 -248.201688)
		(end 79.539592 -248.212102)
		(width 0.0889)
		(layer "In13.Cu")
		(net "M_B_CPU1_SA_CB<6>")
	)
	(segment
		(start 81.044034 -248.211848)
		(end 81.052416 -248.207022)
		(width 0.0889)
		(layer "In13.Cu")
		(net "M_B_CPU1_SA_CB<6>")
	)
	(segment
		(start 49.432718 -241.679984)
		(end 49.577498 -241.535204)
		(width 0.14478)
		(layer "In13.Cu")
		(net "M_B_CPU1_SA_CB<6>")
	)
	(segment
		(start 84.229702 -248.207022)
		(end 84.238084 -248.211848)
		(width 0.0889)
		(layer "In13.Cu")
		(net "M_B_CPU1_SA_CB<6>")
	)
	(segment
		(start 50.128678 -242.033044)
		(end 50.390298 -242.033044)
		(width 0.14478)
		(layer "In13.Cu")
		(net "M_B_CPU1_SA_CB<6>")
	)
	(arc
		(start 82.923888 -248.211848)
		(mid 83.106139 -248.161498)
		(end 83.289648 -248.207022)
		(width 0.0889)
		(layer "In13.Cu")
		(net "M_B_CPU1_SA_CB<6>")
	)
	(arc
		(start 87.057992 -248.211848)
		(mid 87.305588 -248.287026)
		(end 87.560658 -248.243598)
		(width 0.0889)
		(layer "In13.Cu")
		(net "M_B_CPU1_SA_CB<6>")
	)
	(arc
		(start 78.599284 -248.211848)
		(mid 78.869441 -248.28861)
		(end 79.143098 -248.225564)
		(width 0.0889)
		(layer "In13.Cu")
		(net "M_B_CPU1_SA_CB<6>")
	)
	(arc
		(start 83.863942 -248.211848)
		(mid 84.046193 -248.161498)
		(end 84.229702 -248.207022)
		(width 0.0889)
		(layer "In13.Cu")
		(net "M_B_CPU1_SA_CB<6>")
	)
	(arc
		(start 85.752432 -248.207022)
		(mid 85.93594 -248.161528)
		(end 86.118192 -248.211848)
		(width 0.0889)
		(layer "In13.Cu")
		(net "M_B_CPU1_SA_CB<6>")
	)
	(arc
		(start 81.052416 -248.207022)
		(mid 81.235924 -248.161528)
		(end 81.418176 -248.211848)
		(width 0.0889)
		(layer "In13.Cu")
		(net "M_B_CPU1_SA_CB<6>")
	)
	(arc
		(start 84.238084 -248.211848)
		(mid 84.52104 -248.288025)
		(end 84.803996 -248.211848)
		(width 0.0889)
		(layer "In13.Cu")
		(net "M_B_CPU1_SA_CB<6>")
	)
	(arc
		(start 82.357976 -248.211848)
		(mid 82.640932 -248.288025)
		(end 82.923888 -248.211848)
		(width 0.0889)
		(layer "In13.Cu")
		(net "M_B_CPU1_SA_CB<6>")
	)
	(arc
		(start 78.147926 -248.271284)
		(mid 78.184582 -248.239144)
		(end 78.225142 -248.212102)
		(width 0.0889)
		(layer "In13.Cu")
		(net "M_B_CPU1_SA_CB<6>")
	)
	(arc
		(start 79.166466 -248.211848)
		(mid 79.342586 -248.16187)
		(end 79.521304 -248.201688)
		(width 0.0889)
		(layer "In13.Cu")
		(net "M_B_CPU1_SA_CB<6>")
	)
	(arc
		(start 86.118192 -248.211848)
		(mid 86.401148 -248.288025)
		(end 86.684104 -248.211848)
		(width 0.0889)
		(layer "In13.Cu")
		(net "M_B_CPU1_SA_CB<6>")
	)
	(arc
		(start 80.478122 -248.211848)
		(mid 80.761078 -248.288025)
		(end 81.044034 -248.211848)
		(width 0.0889)
		(layer "In13.Cu")
		(net "M_B_CPU1_SA_CB<6>")
	)
	(arc
		(start 83.29803 -248.211848)
		(mid 83.580986 -248.288025)
		(end 83.863942 -248.211848)
		(width 0.0889)
		(layer "In13.Cu")
		(net "M_B_CPU1_SA_CB<6>")
	)
	(arc
		(start 80.10398 -248.211848)
		(mid 80.286231 -248.161498)
		(end 80.46974 -248.207022)
		(width 0.0889)
		(layer "In13.Cu")
		(net "M_B_CPU1_SA_CB<6>")
	)
	(arc
		(start 81.984088 -248.211848)
		(mid 82.171032 -248.161593)
		(end 82.357976 -248.211848)
		(width 0.0889)
		(layer "In13.Cu")
		(net "M_B_CPU1_SA_CB<6>")
	)
	(arc
		(start 84.812378 -248.207022)
		(mid 84.995886 -248.161528)
		(end 85.178138 -248.211848)
		(width 0.0889)
		(layer "In13.Cu")
		(net "M_B_CPU1_SA_CB<6>")
	)
	(arc
		(start 86.684104 -248.211848)
		(mid 86.871048 -248.161593)
		(end 87.057992 -248.211848)
		(width 0.0889)
		(layer "In13.Cu")
		(net "M_B_CPU1_SA_CB<6>")
	)
	(arc
		(start 79.561182 -248.224548)
		(mid 79.834211 -248.287867)
		(end 80.10398 -248.211848)
		(width 0.0889)
		(layer "In13.Cu")
		(net "M_B_CPU1_SA_CB<6>")
	)
	(arc
		(start 81.418176 -248.211848)
		(mid 81.701132 -248.288025)
		(end 81.984088 -248.211848)
		(width 0.0889)
		(layer "In13.Cu")
		(net "M_B_CPU1_SA_CB<6>")
	)
	(arc
		(start 78.252574 -248.196354)
		(mid 78.427825 -248.161421)
		(end 78.599284 -248.211848)
		(width 0.0889)
		(layer "In13.Cu")
		(net "M_B_CPU1_SA_CB<6>")
	)
	(arc
		(start 85.178138 -248.211848)
		(mid 85.461094 -248.288025)
		(end 85.74405 -248.211848)
		(width 0.0889)
		(layer "In13.Cu")
		(net "M_B_CPU1_SA_CB<6>")
	)
	(segment
		(start 89.218008 -248.800366)
		(end 88.751156 -248.534428)
		(width 0.10668)
		(layer "F.Cu")
		(net "M_B_CPU1_SA_CB<5>")
	)
	(segment
		(start 64.102996 -248.691654)
		(end 74.463656 -248.691654)
		(width 0.14478)
		(layer "In13.Cu")
		(net "M_B_CPU1_SA_CB<5>")
	)
	(segment
		(start 87.989664 -248.861834)
		(end 87.998046 -248.857008)
		(width 0.0889)
		(layer "In13.Cu")
		(net "M_B_CPU1_SA_CB<5>")
	)
	(segment
		(start 78.59776 -248.856754)
		(end 78.603348 -248.853452)
		(width 0.0889)
		(layer "In13.Cu")
		(net "M_B_CPU1_SA_CB<5>")
	)
	(segment
		(start 79.163164 -248.857008)
		(end 79.171546 -248.861834)
		(width 0.0889)
		(layer "In13.Cu")
		(net "M_B_CPU1_SA_CB<5>")
	)
	(segment
		(start 54.741572 -243.066062)
		(end 54.886352 -243.210842)
		(width 0.14478)
		(layer "In13.Cu")
		(net "M_B_CPU1_SA_CB<5>")
	)
	(segment
		(start 51.884072 -242.385342)
		(end 51.884072 -242.508024)
		(width 0.14478)
		(layer "In13.Cu")
		(net "M_B_CPU1_SA_CB<5>")
	)
	(segment
		(start 53.783992 -243.210842)
		(end 54.045612 -243.210842)
		(width 0.14478)
		(layer "In13.Cu")
		(net "M_B_CPU1_SA_CB<5>")
	)
	(segment
		(start 53.639212 -242.669822)
		(end 53.639212 -243.066062)
		(width 0.14478)
		(layer "In13.Cu")
		(net "M_B_CPU1_SA_CB<5>")
	)
	(segment
		(start 76.151232 -249.002804)
		(end 76.24953 -248.904506)
		(width 0.0889)
		(layer "In13.Cu")
		(net "M_B_CPU1_SA_CB<5>")
	)
	(segment
		(start 59.926728 -244.515386)
		(end 64.102996 -248.691654)
		(width 0.14478)
		(layer "In13.Cu")
		(net "M_B_CPU1_SA_CB<5>")
	)
	(segment
		(start 53.232812 -242.525042)
		(end 53.494432 -242.525042)
		(width 0.14478)
		(layer "In13.Cu")
		(net "M_B_CPU1_SA_CB<5>")
	)
	(segment
		(start 77.657198 -248.857008)
		(end 77.67193 -248.848372)
		(width 0.0889)
		(layer "In13.Cu")
		(net "M_B_CPU1_SA_CB<5>")
	)
	(segment
		(start 74.463656 -248.691654)
		(end 74.774806 -249.002804)
		(width 0.14478)
		(layer "In13.Cu")
		(net "M_B_CPU1_SA_CB<5>")
	)
	(segment
		(start 80.093566 -248.850912)
		(end 80.10398 -248.857008)
		(width 0.0889)
		(layer "In13.Cu")
		(net "M_B_CPU1_SA_CB<5>")
	)
	(segment
		(start 54.596792 -242.525042)
		(end 54.741572 -242.669822)
		(width 0.14478)
		(layer "In13.Cu")
		(net "M_B_CPU1_SA_CB<5>")
	)
	(segment
		(start 80.46974 -248.861834)
		(end 80.478122 -248.857008)
		(width 0.0889)
		(layer "In13.Cu")
		(net "M_B_CPU1_SA_CB<5>")
	)
	(segment
		(start 58.408062 -244.515386)
		(end 59.926728 -244.515386)
		(width 0.14478)
		(layer "In13.Cu")
		(net "M_B_CPU1_SA_CB<5>")
	)
	(segment
		(start 57.093104 -242.943634)
		(end 57.093104 -243.172234)
		(width 0.14478)
		(layer "In13.Cu")
		(net "M_B_CPU1_SA_CB<5>")
	)
	(segment
		(start 56.93156 -242.78209)
		(end 57.093104 -242.943634)
		(width 0.14478)
		(layer "In13.Cu")
		(net "M_B_CPU1_SA_CB<5>")
	)
	(segment
		(start 54.045612 -243.210842)
		(end 54.190392 -243.066062)
		(width 0.14478)
		(layer "In13.Cu")
		(net "M_B_CPU1_SA_CB<5>")
	)
	(segment
		(start 57.15254 -244.515386)
		(end 57.567322 -244.515386)
		(width 0.14478)
		(layer "In13.Cu")
		(net "M_B_CPU1_SA_CB<5>")
	)
	(segment
		(start 57.093104 -243.172234)
		(end 56.581548 -243.68379)
		(width 0.14478)
		(layer "In13.Cu")
		(net "M_B_CPU1_SA_CB<5>")
	)
	(segment
		(start 57.712102 -244.791992)
		(end 57.856882 -244.936772)
		(width 0.14478)
		(layer "In13.Cu")
		(net "M_B_CPU1_SA_CB<5>")
	)
	(segment
		(start 88.90508 -248.799858)
		(end 88.751156 -248.534428)
		(width 0.0889)
		(layer "In13.Cu")
		(net "M_B_CPU1_SA_CB<5>")
	)
	(segment
		(start 51.884072 -242.508024)
		(end 52.58689 -243.210842)
		(width 0.14478)
		(layer "In13.Cu")
		(net "M_B_CPU1_SA_CB<5>")
	)
	(segment
		(start 54.886352 -243.210842)
		(end 56.274208 -243.210842)
		(width 0.14478)
		(layer "In13.Cu")
		(net "M_B_CPU1_SA_CB<5>")
	)
	(segment
		(start 53.494432 -242.525042)
		(end 53.639212 -242.669822)
		(width 0.14478)
		(layer "In13.Cu")
		(net "M_B_CPU1_SA_CB<5>")
	)
	(segment
		(start 58.263282 -244.660166)
		(end 58.408062 -244.515386)
		(width 0.14478)
		(layer "In13.Cu")
		(net "M_B_CPU1_SA_CB<5>")
	)
	(segment
		(start 83.289648 -248.861834)
		(end 83.29803 -248.857008)
		(width 0.0889)
		(layer "In13.Cu")
		(net "M_B_CPU1_SA_CB<5>")
	)
	(segment
		(start 57.856882 -244.936772)
		(end 58.118502 -244.936772)
		(width 0.14478)
		(layer "In13.Cu")
		(net "M_B_CPU1_SA_CB<5>")
	)
	(segment
		(start 57.567322 -244.515386)
		(end 57.712102 -244.660166)
		(width 0.14478)
		(layer "In13.Cu")
		(net "M_B_CPU1_SA_CB<5>")
	)
	(segment
		(start 85.74405 -248.857008)
		(end 85.752432 -248.861834)
		(width 0.0889)
		(layer "In13.Cu")
		(net "M_B_CPU1_SA_CB<5>")
	)
	(segment
		(start 53.088032 -243.066062)
		(end 53.088032 -242.669822)
		(width 0.14478)
		(layer "In13.Cu")
		(net "M_B_CPU1_SA_CB<5>")
	)
	(segment
		(start 76.480162 -248.904506)
		(end 76.48321 -248.907554)
		(width 0.0889)
		(layer "In13.Cu")
		(net "M_B_CPU1_SA_CB<5>")
	)
	(segment
		(start 56.70296 -242.78209)
		(end 56.93156 -242.78209)
		(width 0.14478)
		(layer "In13.Cu")
		(net "M_B_CPU1_SA_CB<5>")
	)
	(segment
		(start 58.118502 -244.936772)
		(end 58.263282 -244.791992)
		(width 0.14478)
		(layer "In13.Cu")
		(net "M_B_CPU1_SA_CB<5>")
	)
	(segment
		(start 54.335172 -242.525042)
		(end 54.596792 -242.525042)
		(width 0.14478)
		(layer "In13.Cu")
		(net "M_B_CPU1_SA_CB<5>")
	)
	(segment
		(start 53.088032 -242.669822)
		(end 53.232812 -242.525042)
		(width 0.14478)
		(layer "In13.Cu")
		(net "M_B_CPU1_SA_CB<5>")
	)
	(segment
		(start 76.48321 -248.907554)
		(end 77.469746 -248.907554)
		(width 0.0889)
		(layer "In13.Cu")
		(net "M_B_CPU1_SA_CB<5>")
	)
	(segment
		(start 56.581548 -243.944394)
		(end 57.15254 -244.515386)
		(width 0.14478)
		(layer "In13.Cu")
		(net "M_B_CPU1_SA_CB<5>")
	)
	(segment
		(start 57.712102 -244.660166)
		(end 57.712102 -244.791992)
		(width 0.14478)
		(layer "In13.Cu")
		(net "M_B_CPU1_SA_CB<5>")
	)
	(segment
		(start 84.229702 -248.861834)
		(end 84.238084 -248.857008)
		(width 0.0889)
		(layer "In13.Cu")
		(net "M_B_CPU1_SA_CB<5>")
	)
	(segment
		(start 52.943252 -243.210842)
		(end 53.088032 -243.066062)
		(width 0.14478)
		(layer "In13.Cu")
		(net "M_B_CPU1_SA_CB<5>")
	)
	(segment
		(start 52.58689 -243.210842)
		(end 52.943252 -243.210842)
		(width 0.14478)
		(layer "In13.Cu")
		(net "M_B_CPU1_SA_CB<5>")
	)
	(segment
		(start 84.803996 -248.857008)
		(end 84.812378 -248.861834)
		(width 0.0889)
		(layer "In13.Cu")
		(net "M_B_CPU1_SA_CB<5>")
	)
	(segment
		(start 75.950826 -249.002804)
		(end 76.151232 -249.002804)
		(width 0.0889)
		(layer "In13.Cu")
		(net "M_B_CPU1_SA_CB<5>")
	)
	(segment
		(start 74.774806 -249.002804)
		(end 75.950826 -249.002804)
		(width 0.14478)
		(layer "In13.Cu")
		(net "M_B_CPU1_SA_CB<5>")
	)
	(segment
		(start 88.882728 -248.88317)
		(end 88.90508 -248.799858)
		(width 0.0889)
		(layer "In13.Cu")
		(net "M_B_CPU1_SA_CB<5>")
	)
	(segment
		(start 78.579472 -248.867168)
		(end 78.59776 -248.856754)
		(width 0.0889)
		(layer "In13.Cu")
		(net "M_B_CPU1_SA_CB<5>")
	)
	(segment
		(start 54.741572 -242.669822)
		(end 54.741572 -243.066062)
		(width 0.14478)
		(layer "In13.Cu")
		(net "M_B_CPU1_SA_CB<5>")
	)
	(segment
		(start 76.24953 -248.904506)
		(end 76.480162 -248.904506)
		(width 0.0889)
		(layer "In13.Cu")
		(net "M_B_CPU1_SA_CB<5>")
	)
	(segment
		(start 53.639212 -243.066062)
		(end 53.783992 -243.210842)
		(width 0.14478)
		(layer "In13.Cu")
		(net "M_B_CPU1_SA_CB<5>")
	)
	(segment
		(start 58.263282 -244.791992)
		(end 58.263282 -244.660166)
		(width 0.14478)
		(layer "In13.Cu")
		(net "M_B_CPU1_SA_CB<5>")
	)
	(segment
		(start 56.581548 -243.68379)
		(end 56.581548 -243.944394)
		(width 0.14478)
		(layer "In13.Cu")
		(net "M_B_CPU1_SA_CB<5>")
	)
	(segment
		(start 77.469746 -248.907554)
		(end 77.47 -248.9073)
		(width 0.0889)
		(layer "In13.Cu")
		(net "M_B_CPU1_SA_CB<5>")
	)
	(segment
		(start 81.044034 -248.857008)
		(end 81.052416 -248.861834)
		(width 0.0889)
		(layer "In13.Cu")
		(net "M_B_CPU1_SA_CB<5>")
	)
	(segment
		(start 56.274208 -243.210842)
		(end 56.70296 -242.78209)
		(width 0.14478)
		(layer "In13.Cu")
		(net "M_B_CPU1_SA_CB<5>")
	)
	(segment
		(start 54.190392 -243.066062)
		(end 54.190392 -242.669822)
		(width 0.14478)
		(layer "In13.Cu")
		(net "M_B_CPU1_SA_CB<5>")
	)
	(segment
		(start 54.190392 -242.669822)
		(end 54.335172 -242.525042)
		(width 0.14478)
		(layer "In13.Cu")
		(net "M_B_CPU1_SA_CB<5>")
	)
	(arc
		(start 81.418176 -248.857008)
		(mid 81.701132 -248.780831)
		(end 81.984088 -248.857008)
		(width 0.0889)
		(layer "In13.Cu")
		(net "M_B_CPU1_SA_CB<5>")
	)
	(arc
		(start 84.238084 -248.857008)
		(mid 84.52104 -248.780831)
		(end 84.803996 -248.857008)
		(width 0.0889)
		(layer "In13.Cu")
		(net "M_B_CPU1_SA_CB<5>")
	)
	(arc
		(start 86.118192 -248.857008)
		(mid 86.401148 -248.780831)
		(end 86.684104 -248.857008)
		(width 0.0889)
		(layer "In13.Cu")
		(net "M_B_CPU1_SA_CB<5>")
	)
	(arc
		(start 88.563958 -248.857008)
		(mid 88.720396 -248.905979)
		(end 88.882728 -248.88317)
		(width 0.0889)
		(layer "In13.Cu")
		(net "M_B_CPU1_SA_CB<5>")
	)
	(arc
		(start 79.537814 -248.857008)
		(mid 79.814881 -248.780737)
		(end 80.093566 -248.850912)
		(width 0.0889)
		(layer "In13.Cu")
		(net "M_B_CPU1_SA_CB<5>")
	)
	(arc
		(start 87.998046 -248.857008)
		(mid 88.281002 -248.780831)
		(end 88.563958 -248.857008)
		(width 0.0889)
		(layer "In13.Cu")
		(net "M_B_CPU1_SA_CB<5>")
	)
	(arc
		(start 81.052416 -248.861834)
		(mid 81.235924 -248.907328)
		(end 81.418176 -248.857008)
		(width 0.0889)
		(layer "In13.Cu")
		(net "M_B_CPU1_SA_CB<5>")
	)
	(arc
		(start 87.623904 -248.857008)
		(mid 87.806155 -248.907358)
		(end 87.989664 -248.861834)
		(width 0.0889)
		(layer "In13.Cu")
		(net "M_B_CPU1_SA_CB<5>")
	)
	(arc
		(start 78.223618 -248.857008)
		(mid 78.400246 -248.907241)
		(end 78.579472 -248.867168)
		(width 0.0889)
		(layer "In13.Cu")
		(net "M_B_CPU1_SA_CB<5>")
	)
	(arc
		(start 78.603348 -248.853452)
		(mid 78.883737 -248.780783)
		(end 79.163164 -248.857008)
		(width 0.0889)
		(layer "In13.Cu")
		(net "M_B_CPU1_SA_CB<5>")
	)
	(arc
		(start 81.984088 -248.857008)
		(mid 82.171032 -248.907263)
		(end 82.357976 -248.857008)
		(width 0.0889)
		(layer "In13.Cu")
		(net "M_B_CPU1_SA_CB<5>")
	)
	(arc
		(start 79.171546 -248.861834)
		(mid 79.355308 -248.90745)
		(end 79.537814 -248.857008)
		(width 0.0889)
		(layer "In13.Cu")
		(net "M_B_CPU1_SA_CB<5>")
	)
	(arc
		(start 83.29803 -248.857008)
		(mid 83.580986 -248.780831)
		(end 83.863942 -248.857008)
		(width 0.0889)
		(layer "In13.Cu")
		(net "M_B_CPU1_SA_CB<5>")
	)
	(arc
		(start 77.67193 -248.848372)
		(mid 77.948913 -248.780568)
		(end 78.223618 -248.857008)
		(width 0.0889)
		(layer "In13.Cu")
		(net "M_B_CPU1_SA_CB<5>")
	)
	(arc
		(start 85.752432 -248.861834)
		(mid 85.93594 -248.907328)
		(end 86.118192 -248.857008)
		(width 0.0889)
		(layer "In13.Cu")
		(net "M_B_CPU1_SA_CB<5>")
	)
	(arc
		(start 80.10398 -248.857008)
		(mid 80.286231 -248.907358)
		(end 80.46974 -248.861834)
		(width 0.0889)
		(layer "In13.Cu")
		(net "M_B_CPU1_SA_CB<5>")
	)
	(arc
		(start 83.863942 -248.857008)
		(mid 84.046193 -248.907358)
		(end 84.229702 -248.861834)
		(width 0.0889)
		(layer "In13.Cu")
		(net "M_B_CPU1_SA_CB<5>")
	)
	(arc
		(start 82.923888 -248.857008)
		(mid 83.106139 -248.907358)
		(end 83.289648 -248.861834)
		(width 0.0889)
		(layer "In13.Cu")
		(net "M_B_CPU1_SA_CB<5>")
	)
	(arc
		(start 77.47 -248.9073)
		(mid 77.566932 -248.894549)
		(end 77.657198 -248.857008)
		(width 0.0889)
		(layer "In13.Cu")
		(net "M_B_CPU1_SA_CB<5>")
	)
	(arc
		(start 87.057992 -248.857008)
		(mid 87.340948 -248.780831)
		(end 87.623904 -248.857008)
		(width 0.0889)
		(layer "In13.Cu")
		(net "M_B_CPU1_SA_CB<5>")
	)
	(arc
		(start 84.812378 -248.861834)
		(mid 84.995886 -248.907328)
		(end 85.178138 -248.857008)
		(width 0.0889)
		(layer "In13.Cu")
		(net "M_B_CPU1_SA_CB<5>")
	)
	(arc
		(start 86.684104 -248.857008)
		(mid 86.871048 -248.907263)
		(end 87.057992 -248.857008)
		(width 0.0889)
		(layer "In13.Cu")
		(net "M_B_CPU1_SA_CB<5>")
	)
	(arc
		(start 82.357976 -248.857008)
		(mid 82.640932 -248.780831)
		(end 82.923888 -248.857008)
		(width 0.0889)
		(layer "In13.Cu")
		(net "M_B_CPU1_SA_CB<5>")
	)
	(arc
		(start 85.178138 -248.857008)
		(mid 85.461094 -248.780831)
		(end 85.74405 -248.857008)
		(width 0.0889)
		(layer "In13.Cu")
		(net "M_B_CPU1_SA_CB<5>")
	)
	(arc
		(start 80.478122 -248.857008)
		(mid 80.761078 -248.780831)
		(end 81.044034 -248.857008)
		(width 0.0889)
		(layer "In13.Cu")
		(net "M_B_CPU1_SA_CB<5>")
	)
	(segment
		(start 87.8078 -247.99036)
		(end 87.340948 -247.724422)
		(width 0.10668)
		(layer "F.Cu")
		(net "M_B_CPU1_SA_CB<4>")
	)
	(segment
		(start 53.480716 -240.64976)
		(end 53.480716 -241.36604)
		(width 0.14478)
		(layer "In13.Cu")
		(net "M_B_CPU1_SA_CB<4>")
	)
	(segment
		(start 56.087772 -241.337592)
		(end 56.261 -241.51082)
		(width 0.14478)
		(layer "In13.Cu")
		(net "M_B_CPU1_SA_CB<4>")
	)
	(segment
		(start 54.182518 -241.36604)
		(end 54.182518 -240.87709)
		(width 0.14478)
		(layer "In13.Cu")
		(net "M_B_CPU1_SA_CB<4>")
	)
	(segment
		(start 53.625496 -241.51082)
		(end 54.037738 -241.51082)
		(width 0.14478)
		(layer "In13.Cu")
		(net "M_B_CPU1_SA_CB<4>")
	)
	(segment
		(start 54.733698 -240.87709)
		(end 54.733698 -241.36604)
		(width 0.14478)
		(layer "In13.Cu")
		(net "M_B_CPU1_SA_CB<4>")
	)
	(segment
		(start 79.634842 -248.046748)
		(end 79.654908 -248.058178)
		(width 0.0889)
		(layer "In13.Cu")
		(net "M_B_CPU1_SA_CB<4>")
	)
	(segment
		(start 78.129638 -248.046748)
		(end 78.161388 -248.02846)
		(width 0.0889)
		(layer "In13.Cu")
		(net "M_B_CPU1_SA_CB<4>")
	)
	(segment
		(start 55.363364 -241.51082)
		(end 55.536592 -241.337592)
		(width 0.14478)
		(layer "In13.Cu")
		(net "M_B_CPU1_SA_CB<4>")
	)
	(segment
		(start 85.639656 -248.051828)
		(end 85.648038 -248.047002)
		(width 0.0889)
		(layer "In13.Cu")
		(net "M_B_CPU1_SA_CB<4>")
	)
	(segment
		(start 83.394042 -248.047002)
		(end 83.402424 -248.051828)
		(width 0.0889)
		(layer "In13.Cu")
		(net "M_B_CPU1_SA_CB<4>")
	)
	(segment
		(start 57.341008 -241.51082)
		(end 58.650124 -242.819936)
		(width 0.14478)
		(layer "In13.Cu")
		(net "M_B_CPU1_SA_CB<4>")
	)
	(segment
		(start 52.784756 -241.51082)
		(end 52.929536 -241.36604)
		(width 0.14478)
		(layer "In13.Cu")
		(net "M_B_CPU1_SA_CB<4>")
	)
	(segment
		(start 64.576452 -247.782334)
		(end 74.867516 -247.782334)
		(width 0.14478)
		(layer "In13.Cu")
		(net "M_B_CPU1_SA_CB<4>")
	)
	(segment
		(start 75.955906 -248.083324)
		(end 76.345288 -248.083324)
		(width 0.0889)
		(layer "In13.Cu")
		(net "M_B_CPU1_SA_CB<4>")
	)
	(segment
		(start 87.472774 -248.073164)
		(end 87.495126 -247.989852)
		(width 0.0889)
		(layer "In13.Cu")
		(net "M_B_CPU1_SA_CB<4>")
	)
	(segment
		(start 54.037738 -241.51082)
		(end 54.182518 -241.36604)
		(width 0.14478)
		(layer "In13.Cu")
		(net "M_B_CPU1_SA_CB<4>")
	)
	(segment
		(start 55.536592 -240.416842)
		(end 55.681372 -240.272062)
		(width 0.14478)
		(layer "In13.Cu")
		(net "M_B_CPU1_SA_CB<4>")
	)
	(segment
		(start 58.650124 -242.819936)
		(end 59.614054 -242.819936)
		(width 0.14478)
		(layer "In13.Cu")
		(net "M_B_CPU1_SA_CB<4>")
	)
	(segment
		(start 79.051658 -248.057924)
		(end 79.070454 -248.047002)
		(width 0.0889)
		(layer "In13.Cu")
		(net "M_B_CPU1_SA_CB<4>")
	)
	(segment
		(start 55.681372 -240.272062)
		(end 55.942992 -240.272062)
		(width 0.14478)
		(layer "In13.Cu")
		(net "M_B_CPU1_SA_CB<4>")
	)
	(segment
		(start 53.07457 -240.504726)
		(end 53.335682 -240.504726)
		(width 0.14478)
		(layer "In13.Cu")
		(net "M_B_CPU1_SA_CB<4>")
	)
	(segment
		(start 82.453988 -248.047002)
		(end 82.46237 -248.051828)
		(width 0.0889)
		(layer "In13.Cu")
		(net "M_B_CPU1_SA_CB<4>")
	)
	(segment
		(start 74.867516 -247.782334)
		(end 75.168506 -248.083324)
		(width 0.14478)
		(layer "In13.Cu")
		(net "M_B_CPU1_SA_CB<4>")
	)
	(segment
		(start 87.154004 -248.047002)
		(end 87.162386 -248.051828)
		(width 0.0889)
		(layer "In13.Cu")
		(net "M_B_CPU1_SA_CB<4>")
	)
	(segment
		(start 56.261 -241.51082)
		(end 57.341008 -241.51082)
		(width 0.14478)
		(layer "In13.Cu")
		(net "M_B_CPU1_SA_CB<4>")
	)
	(segment
		(start 52.929536 -241.36604)
		(end 52.929536 -240.64976)
		(width 0.14478)
		(layer "In13.Cu")
		(net "M_B_CPU1_SA_CB<4>")
	)
	(segment
		(start 55.942992 -240.272062)
		(end 56.087772 -240.416842)
		(width 0.14478)
		(layer "In13.Cu")
		(net "M_B_CPU1_SA_CB<4>")
	)
	(segment
		(start 77.79639 -248.353326)
		(end 78.013052 -248.13641)
		(width 0.0889)
		(layer "In13.Cu")
		(net "M_B_CPU1_SA_CB<4>")
	)
	(segment
		(start 56.087772 -240.416842)
		(end 56.087772 -241.337592)
		(width 0.14478)
		(layer "In13.Cu")
		(net "M_B_CPU1_SA_CB<4>")
	)
	(segment
		(start 87.495126 -247.989852)
		(end 87.340948 -247.724422)
		(width 0.0889)
		(layer "In13.Cu")
		(net "M_B_CPU1_SA_CB<4>")
	)
	(segment
		(start 54.182518 -240.87709)
		(end 54.327298 -240.73231)
		(width 0.14478)
		(layer "In13.Cu")
		(net "M_B_CPU1_SA_CB<4>")
	)
	(segment
		(start 53.335682 -240.504726)
		(end 53.480716 -240.64976)
		(width 0.14478)
		(layer "In13.Cu")
		(net "M_B_CPU1_SA_CB<4>")
	)
	(segment
		(start 79.613252 -248.034302)
		(end 79.634842 -248.046748)
		(width 0.0889)
		(layer "In13.Cu")
		(net "M_B_CPU1_SA_CB<4>")
	)
	(segment
		(start 54.588918 -240.73231)
		(end 54.733698 -240.87709)
		(width 0.14478)
		(layer "In13.Cu")
		(net "M_B_CPU1_SA_CB<4>")
	)
	(segment
		(start 51.884072 -240.68532)
		(end 51.884072 -240.947448)
		(width 0.14478)
		(layer "In13.Cu")
		(net "M_B_CPU1_SA_CB<4>")
	)
	(segment
		(start 75.168506 -248.083324)
		(end 75.955906 -248.083324)
		(width 0.14478)
		(layer "In13.Cu")
		(net "M_B_CPU1_SA_CB<4>")
	)
	(segment
		(start 54.327298 -240.73231)
		(end 54.588918 -240.73231)
		(width 0.14478)
		(layer "In13.Cu")
		(net "M_B_CPU1_SA_CB<4>")
	)
	(segment
		(start 51.884072 -240.947448)
		(end 52.447444 -241.51082)
		(width 0.14478)
		(layer "In13.Cu")
		(net "M_B_CPU1_SA_CB<4>")
	)
	(segment
		(start 52.929536 -240.64976)
		(end 53.07457 -240.504726)
		(width 0.14478)
		(layer "In13.Cu")
		(net "M_B_CPU1_SA_CB<4>")
	)
	(segment
		(start 76.345288 -248.083324)
		(end 76.61529 -248.353326)
		(width 0.0889)
		(layer "In13.Cu")
		(net "M_B_CPU1_SA_CB<4>")
	)
	(segment
		(start 81.879694 -248.051828)
		(end 81.888076 -248.047002)
		(width 0.0889)
		(layer "In13.Cu")
		(net "M_B_CPU1_SA_CB<4>")
	)
	(segment
		(start 86.57971 -248.051828)
		(end 86.588092 -248.047002)
		(width 0.0889)
		(layer "In13.Cu")
		(net "M_B_CPU1_SA_CB<4>")
	)
	(segment
		(start 55.536592 -241.337592)
		(end 55.536592 -240.416842)
		(width 0.14478)
		(layer "In13.Cu")
		(net "M_B_CPU1_SA_CB<4>")
	)
	(segment
		(start 76.61529 -248.353326)
		(end 77.79639 -248.353326)
		(width 0.0889)
		(layer "In13.Cu")
		(net "M_B_CPU1_SA_CB<4>")
	)
	(segment
		(start 54.733698 -241.36604)
		(end 54.878478 -241.51082)
		(width 0.14478)
		(layer "In13.Cu")
		(net "M_B_CPU1_SA_CB<4>")
	)
	(segment
		(start 52.447444 -241.51082)
		(end 52.784756 -241.51082)
		(width 0.14478)
		(layer "In13.Cu")
		(net "M_B_CPU1_SA_CB<4>")
	)
	(segment
		(start 59.614054 -242.819936)
		(end 64.576452 -247.782334)
		(width 0.14478)
		(layer "In13.Cu")
		(net "M_B_CPU1_SA_CB<4>")
	)
	(segment
		(start 53.480716 -241.36604)
		(end 53.625496 -241.51082)
		(width 0.14478)
		(layer "In13.Cu")
		(net "M_B_CPU1_SA_CB<4>")
	)
	(segment
		(start 54.878478 -241.51082)
		(end 55.363364 -241.51082)
		(width 0.14478)
		(layer "In13.Cu")
		(net "M_B_CPU1_SA_CB<4>")
	)
	(arc
		(start 87.162386 -248.051828)
		(mid 87.315256 -248.096469)
		(end 87.472774 -248.073164)
		(width 0.0889)
		(layer "In13.Cu")
		(net "M_B_CPU1_SA_CB<4>")
	)
	(arc
		(start 79.654908 -248.058178)
		(mid 79.832986 -248.097162)
		(end 80.008222 -248.047002)
		(width 0.0889)
		(layer "In13.Cu")
		(net "M_B_CPU1_SA_CB<4>")
	)
	(arc
		(start 81.513934 -248.047002)
		(mid 81.696185 -248.097352)
		(end 81.879694 -248.051828)
		(width 0.0889)
		(layer "In13.Cu")
		(net "M_B_CPU1_SA_CB<4>")
	)
	(arc
		(start 80.948022 -248.047002)
		(mid 81.230978 -247.970825)
		(end 81.513934 -248.047002)
		(width 0.0889)
		(layer "In13.Cu")
		(net "M_B_CPU1_SA_CB<4>")
	)
	(arc
		(start 82.46237 -248.051828)
		(mid 82.645878 -248.097322)
		(end 82.82813 -248.047002)
		(width 0.0889)
		(layer "In13.Cu")
		(net "M_B_CPU1_SA_CB<4>")
	)
	(arc
		(start 80.008222 -248.047002)
		(mid 80.291178 -247.970825)
		(end 80.574134 -248.047002)
		(width 0.0889)
		(layer "In13.Cu")
		(net "M_B_CPU1_SA_CB<4>")
	)
	(arc
		(start 85.273896 -248.047002)
		(mid 85.456147 -248.097352)
		(end 85.639656 -248.051828)
		(width 0.0889)
		(layer "In13.Cu")
		(net "M_B_CPU1_SA_CB<4>")
	)
	(arc
		(start 81.888076 -248.047002)
		(mid 82.171032 -247.970825)
		(end 82.453988 -248.047002)
		(width 0.0889)
		(layer "In13.Cu")
		(net "M_B_CPU1_SA_CB<4>")
	)
	(arc
		(start 86.21395 -248.047002)
		(mid 86.396201 -248.097352)
		(end 86.57971 -248.051828)
		(width 0.0889)
		(layer "In13.Cu")
		(net "M_B_CPU1_SA_CB<4>")
	)
	(arc
		(start 80.574134 -248.047002)
		(mid 80.761078 -248.097257)
		(end 80.948022 -248.047002)
		(width 0.0889)
		(layer "In13.Cu")
		(net "M_B_CPU1_SA_CB<4>")
	)
	(arc
		(start 83.402424 -248.051828)
		(mid 83.585932 -248.097322)
		(end 83.768184 -248.047002)
		(width 0.0889)
		(layer "In13.Cu")
		(net "M_B_CPU1_SA_CB<4>")
	)
	(arc
		(start 86.588092 -248.047002)
		(mid 86.871048 -247.970825)
		(end 87.154004 -248.047002)
		(width 0.0889)
		(layer "In13.Cu")
		(net "M_B_CPU1_SA_CB<4>")
	)
	(arc
		(start 84.334096 -248.047002)
		(mid 84.52104 -248.097257)
		(end 84.707984 -248.047002)
		(width 0.0889)
		(layer "In13.Cu")
		(net "M_B_CPU1_SA_CB<4>")
	)
	(arc
		(start 78.695296 -248.047002)
		(mid 78.872087 -248.097721)
		(end 79.051658 -248.057924)
		(width 0.0889)
		(layer "In13.Cu")
		(net "M_B_CPU1_SA_CB<4>")
	)
	(arc
		(start 84.707984 -248.047002)
		(mid 84.99094 -247.970825)
		(end 85.273896 -248.047002)
		(width 0.0889)
		(layer "In13.Cu")
		(net "M_B_CPU1_SA_CB<4>")
	)
	(arc
		(start 79.070454 -248.047002)
		(mid 79.340223 -247.970979)
		(end 79.613252 -248.034302)
		(width 0.0889)
		(layer "In13.Cu")
		(net "M_B_CPU1_SA_CB<4>")
	)
	(arc
		(start 78.161388 -248.02846)
		(mid 78.430673 -247.970548)
		(end 78.695296 -248.047002)
		(width 0.0889)
		(layer "In13.Cu")
		(net "M_B_CPU1_SA_CB<4>")
	)
	(arc
		(start 78.013052 -248.13641)
		(mid 78.068401 -248.087751)
		(end 78.129638 -248.046748)
		(width 0.0889)
		(layer "In13.Cu")
		(net "M_B_CPU1_SA_CB<4>")
	)
	(arc
		(start 83.768184 -248.047002)
		(mid 84.05114 -247.970825)
		(end 84.334096 -248.047002)
		(width 0.0889)
		(layer "In13.Cu")
		(net "M_B_CPU1_SA_CB<4>")
	)
	(arc
		(start 82.82813 -248.047002)
		(mid 83.111086 -247.970825)
		(end 83.394042 -248.047002)
		(width 0.0889)
		(layer "In13.Cu")
		(net "M_B_CPU1_SA_CB<4>")
	)
	(arc
		(start 85.648038 -248.047002)
		(mid 85.930994 -247.970825)
		(end 86.21395 -248.047002)
		(width 0.0889)
		(layer "In13.Cu")
		(net "M_B_CPU1_SA_CB<4>")
	)
	(segment
		(start 89.687908 -246.370348)
		(end 89.221056 -246.10441)
		(width 0.10668)
		(layer "F.Cu")
		(net "M_B_CPU1_SA_CB<3>")
	)
	(segment
		(start 78.67777 -245.791228)
		(end 78.693518 -245.782084)
		(width 0.0889)
		(layer "In13.Cu")
		(net "M_B_CPU1_SA_CB<3>")
	)
	(segment
		(start 59.20867 -237.710472)
		(end 66.931032 -245.432834)
		(width 0.14478)
		(layer "In13.Cu")
		(net "M_B_CPU1_SA_CB<3>")
	)
	(segment
		(start 85.639656 -245.777004)
		(end 85.648038 -245.78183)
		(width 0.0889)
		(layer "In13.Cu")
		(net "M_B_CPU1_SA_CB<3>")
	)
	(segment
		(start 88.97112 -245.81358)
		(end 89.067132 -245.83898)
		(width 0.0889)
		(layer "In13.Cu")
		(net "M_B_CPU1_SA_CB<3>")
	)
	(segment
		(start 82.453988 -245.78183)
		(end 82.46237 -245.777004)
		(width 0.0889)
		(layer "In13.Cu")
		(net "M_B_CPU1_SA_CB<3>")
	)
	(segment
		(start 47.784004 -237.285276)
		(end 49.797462 -237.285276)
		(width 0.14478)
		(layer "In13.Cu")
		(net "M_B_CPU1_SA_CB<3>")
	)
	(segment
		(start 66.931032 -245.432834)
		(end 75.870816 -245.432834)
		(width 0.14478)
		(layer "In13.Cu")
		(net "M_B_CPU1_SA_CB<3>")
	)
	(segment
		(start 75.870816 -245.432834)
		(end 76.23683 -245.432834)
		(width 0.0889)
		(layer "In13.Cu")
		(net "M_B_CPU1_SA_CB<3>")
	)
	(segment
		(start 50.232056 -236.850682)
		(end 51.494182 -236.850682)
		(width 0.14478)
		(layer "In13.Cu")
		(net "M_B_CPU1_SA_CB<3>")
	)
	(segment
		(start 51.494182 -236.850682)
		(end 52.353972 -237.710472)
		(width 0.14478)
		(layer "In13.Cu")
		(net "M_B_CPU1_SA_CB<3>")
	)
	(segment
		(start 76.53528 -245.731284)
		(end 77.940408 -245.731284)
		(width 0.0889)
		(layer "In13.Cu")
		(net "M_B_CPU1_SA_CB<3>")
	)
	(segment
		(start 83.394042 -245.78183)
		(end 83.402424 -245.777004)
		(width 0.0889)
		(layer "In13.Cu")
		(net "M_B_CPU1_SA_CB<3>")
	)
	(segment
		(start 79.99984 -245.777004)
		(end 80.008222 -245.78183)
		(width 0.0889)
		(layer "In13.Cu")
		(net "M_B_CPU1_SA_CB<3>")
	)
	(segment
		(start 86.57971 -245.777004)
		(end 86.588092 -245.78183)
		(width 0.0889)
		(layer "In13.Cu")
		(net "M_B_CPU1_SA_CB<3>")
	)
	(segment
		(start 76.23683 -245.432834)
		(end 76.53528 -245.731284)
		(width 0.0889)
		(layer "In13.Cu")
		(net "M_B_CPU1_SA_CB<3>")
	)
	(segment
		(start 87.154004 -245.78183)
		(end 87.162386 -245.777004)
		(width 0.0889)
		(layer "In13.Cu")
		(net "M_B_CPU1_SA_CB<3>")
	)
	(segment
		(start 49.797462 -237.285276)
		(end 50.232056 -236.850682)
		(width 0.14478)
		(layer "In13.Cu")
		(net "M_B_CPU1_SA_CB<3>")
	)
	(segment
		(start 52.353972 -237.710472)
		(end 59.20867 -237.710472)
		(width 0.14478)
		(layer "In13.Cu")
		(net "M_B_CPU1_SA_CB<3>")
	)
	(segment
		(start 79.067406 -245.78183)
		(end 79.07782 -245.787926)
		(width 0.0889)
		(layer "In13.Cu")
		(net "M_B_CPU1_SA_CB<3>")
	)
	(segment
		(start 89.067132 -245.83898)
		(end 89.221056 -246.10441)
		(width 0.0889)
		(layer "In13.Cu")
		(net "M_B_CPU1_SA_CB<3>")
	)
	(segment
		(start 88.094058 -245.78183)
		(end 88.10244 -245.777004)
		(width 0.0889)
		(layer "In13.Cu")
		(net "M_B_CPU1_SA_CB<3>")
	)
	(segment
		(start 78.693518 -245.782084)
		(end 78.709774 -245.772686)
		(width 0.0889)
		(layer "In13.Cu")
		(net "M_B_CPU1_SA_CB<3>")
	)
	(segment
		(start 81.879694 -245.777004)
		(end 81.888076 -245.78183)
		(width 0.0889)
		(layer "In13.Cu")
		(net "M_B_CPU1_SA_CB<3>")
	)
	(arc
		(start 80.574134 -245.78183)
		(mid 80.761078 -245.731575)
		(end 80.948022 -245.78183)
		(width 0.0889)
		(layer "In13.Cu")
		(net "M_B_CPU1_SA_CB<3>")
	)
	(arc
		(start 77.940408 -245.731284)
		(mid 78.037359 -245.744159)
		(end 78.127606 -245.78183)
		(width 0.0889)
		(layer "In13.Cu")
		(net "M_B_CPU1_SA_CB<3>")
	)
	(arc
		(start 84.707984 -245.78183)
		(mid 84.99094 -245.858007)
		(end 85.273896 -245.78183)
		(width 0.0889)
		(layer "In13.Cu")
		(net "M_B_CPU1_SA_CB<3>")
	)
	(arc
		(start 82.82813 -245.78183)
		(mid 83.111086 -245.858007)
		(end 83.394042 -245.78183)
		(width 0.0889)
		(layer "In13.Cu")
		(net "M_B_CPU1_SA_CB<3>")
	)
	(arc
		(start 81.513934 -245.78183)
		(mid 81.696185 -245.73148)
		(end 81.879694 -245.777004)
		(width 0.0889)
		(layer "In13.Cu")
		(net "M_B_CPU1_SA_CB<3>")
	)
	(arc
		(start 82.46237 -245.777004)
		(mid 82.645878 -245.73151)
		(end 82.82813 -245.78183)
		(width 0.0889)
		(layer "In13.Cu")
		(net "M_B_CPU1_SA_CB<3>")
	)
	(arc
		(start 88.4682 -245.78183)
		(mid 88.715913 -245.85705)
		(end 88.97112 -245.81358)
		(width 0.0889)
		(layer "In13.Cu")
		(net "M_B_CPU1_SA_CB<3>")
	)
	(arc
		(start 86.21395 -245.78183)
		(mid 86.396201 -245.73148)
		(end 86.57971 -245.777004)
		(width 0.0889)
		(layer "In13.Cu")
		(net "M_B_CPU1_SA_CB<3>")
	)
	(arc
		(start 88.10244 -245.777004)
		(mid 88.285948 -245.73151)
		(end 88.4682 -245.78183)
		(width 0.0889)
		(layer "In13.Cu")
		(net "M_B_CPU1_SA_CB<3>")
	)
	(arc
		(start 78.127606 -245.78183)
		(mid 78.401461 -245.85818)
		(end 78.67777 -245.791228)
		(width 0.0889)
		(layer "In13.Cu")
		(net "M_B_CPU1_SA_CB<3>")
	)
	(arc
		(start 78.709774 -245.772686)
		(mid 78.889756 -245.731586)
		(end 79.067406 -245.78183)
		(width 0.0889)
		(layer "In13.Cu")
		(net "M_B_CPU1_SA_CB<3>")
	)
	(arc
		(start 84.334096 -245.78183)
		(mid 84.52104 -245.731575)
		(end 84.707984 -245.78183)
		(width 0.0889)
		(layer "In13.Cu")
		(net "M_B_CPU1_SA_CB<3>")
	)
	(arc
		(start 87.162386 -245.777004)
		(mid 87.345894 -245.73151)
		(end 87.528146 -245.78183)
		(width 0.0889)
		(layer "In13.Cu")
		(net "M_B_CPU1_SA_CB<3>")
	)
	(arc
		(start 85.648038 -245.78183)
		(mid 85.930994 -245.858007)
		(end 86.21395 -245.78183)
		(width 0.0889)
		(layer "In13.Cu")
		(net "M_B_CPU1_SA_CB<3>")
	)
	(arc
		(start 79.633572 -245.78183)
		(mid 79.816077 -245.731353)
		(end 79.99984 -245.777004)
		(width 0.0889)
		(layer "In13.Cu")
		(net "M_B_CPU1_SA_CB<3>")
	)
	(arc
		(start 83.768184 -245.78183)
		(mid 84.05114 -245.858007)
		(end 84.334096 -245.78183)
		(width 0.0889)
		(layer "In13.Cu")
		(net "M_B_CPU1_SA_CB<3>")
	)
	(arc
		(start 80.008222 -245.78183)
		(mid 80.291178 -245.858007)
		(end 80.574134 -245.78183)
		(width 0.0889)
		(layer "In13.Cu")
		(net "M_B_CPU1_SA_CB<3>")
	)
	(arc
		(start 81.888076 -245.78183)
		(mid 82.171032 -245.858007)
		(end 82.453988 -245.78183)
		(width 0.0889)
		(layer "In13.Cu")
		(net "M_B_CPU1_SA_CB<3>")
	)
	(arc
		(start 85.273896 -245.78183)
		(mid 85.456147 -245.73148)
		(end 85.639656 -245.777004)
		(width 0.0889)
		(layer "In13.Cu")
		(net "M_B_CPU1_SA_CB<3>")
	)
	(arc
		(start 79.07782 -245.787926)
		(mid 79.356506 -245.858146)
		(end 79.633572 -245.78183)
		(width 0.0889)
		(layer "In13.Cu")
		(net "M_B_CPU1_SA_CB<3>")
	)
	(arc
		(start 87.528146 -245.78183)
		(mid 87.811102 -245.858007)
		(end 88.094058 -245.78183)
		(width 0.0889)
		(layer "In13.Cu")
		(net "M_B_CPU1_SA_CB<3>")
	)
	(arc
		(start 86.588092 -245.78183)
		(mid 86.871048 -245.858007)
		(end 87.154004 -245.78183)
		(width 0.0889)
		(layer "In13.Cu")
		(net "M_B_CPU1_SA_CB<3>")
	)
	(arc
		(start 83.402424 -245.777004)
		(mid 83.585932 -245.73151)
		(end 83.768184 -245.78183)
		(width 0.0889)
		(layer "In13.Cu")
		(net "M_B_CPU1_SA_CB<3>")
	)
	(arc
		(start 80.948022 -245.78183)
		(mid 81.230978 -245.858007)
		(end 81.513934 -245.78183)
		(width 0.0889)
		(layer "In13.Cu")
		(net "M_B_CPU1_SA_CB<3>")
	)
	(segment
		(start 88.277954 -245.560342)
		(end 87.811102 -245.294404)
		(width 0.10668)
		(layer "F.Cu")
		(net "M_B_CPU1_SA_CB<2>")
	)
	(segment
		(start 84.812378 -244.966998)
		(end 84.803996 -244.971824)
		(width 0.0889)
		(layer "In13.Cu")
		(net "M_B_CPU1_SA_CB<2>")
	)
	(segment
		(start 79.561182 -244.984524)
		(end 79.539592 -244.972078)
		(width 0.0889)
		(layer "In13.Cu")
		(net "M_B_CPU1_SA_CB<2>")
	)
	(segment
		(start 77.02169 -244.378226)
		(end 76.353924 -244.378226)
		(width 0.0889)
		(layer "In13.Cu")
		(net "M_B_CPU1_SA_CB<2>")
	)
	(segment
		(start 50.222404 -235.160312)
		(end 49.797462 -235.585254)
		(width 0.14478)
		(layer "In13.Cu")
		(net "M_B_CPU1_SA_CB<2>")
	)
	(segment
		(start 84.238084 -244.971824)
		(end 84.229702 -244.966998)
		(width 0.0889)
		(layer "In13.Cu")
		(net "M_B_CPU1_SA_CB<2>")
	)
	(segment
		(start 87.656924 -245.028974)
		(end 87.560658 -245.003574)
		(width 0.0889)
		(layer "In13.Cu")
		(net "M_B_CPU1_SA_CB<2>")
	)
	(segment
		(start 59.276742 -236.422692)
		(end 58.8645 -236.01045)
		(width 0.14478)
		(layer "In13.Cu")
		(net "M_B_CPU1_SA_CB<2>")
	)
	(segment
		(start 76.353924 -244.378226)
		(end 76.198476 -244.533674)
		(width 0.0889)
		(layer "In13.Cu")
		(net "M_B_CPU1_SA_CB<2>")
	)
	(segment
		(start 59.878722 -236.277658)
		(end 59.650376 -236.277658)
		(width 0.14478)
		(layer "In13.Cu")
		(net "M_B_CPU1_SA_CB<2>")
	)
	(segment
		(start 80.478122 -244.971824)
		(end 80.46974 -244.966998)
		(width 0.0889)
		(layer "In13.Cu")
		(net "M_B_CPU1_SA_CB<2>")
	)
	(segment
		(start 67.387724 -244.533674)
		(end 59.895486 -237.041436)
		(width 0.14478)
		(layer "In13.Cu")
		(net "M_B_CPU1_SA_CB<2>")
	)
	(segment
		(start 83.29803 -244.971824)
		(end 83.289648 -244.966998)
		(width 0.0889)
		(layer "In13.Cu")
		(net "M_B_CPU1_SA_CB<2>")
	)
	(segment
		(start 81.052416 -244.966998)
		(end 81.044034 -244.971824)
		(width 0.0889)
		(layer "In13.Cu")
		(net "M_B_CPU1_SA_CB<2>")
	)
	(segment
		(start 59.505342 -236.422692)
		(end 59.276742 -236.422692)
		(width 0.14478)
		(layer "In13.Cu")
		(net "M_B_CPU1_SA_CB<2>")
	)
	(segment
		(start 79.166466 -244.971824)
		(end 79.143098 -244.98554)
		(width 0.0889)
		(layer "In13.Cu")
		(net "M_B_CPU1_SA_CB<2>")
	)
	(segment
		(start 49.797462 -235.585254)
		(end 47.784004 -235.585254)
		(width 0.14478)
		(layer "In13.Cu")
		(net "M_B_CPU1_SA_CB<2>")
	)
	(segment
		(start 59.895486 -236.812582)
		(end 60.04052 -236.667548)
		(width 0.14478)
		(layer "In13.Cu")
		(net "M_B_CPU1_SA_CB<2>")
	)
	(segment
		(start 60.04052 -236.667548)
		(end 60.04052 -236.439456)
		(width 0.14478)
		(layer "In13.Cu")
		(net "M_B_CPU1_SA_CB<2>")
	)
	(segment
		(start 60.04052 -236.439456)
		(end 59.878722 -236.277658)
		(width 0.14478)
		(layer "In13.Cu")
		(net "M_B_CPU1_SA_CB<2>")
	)
	(segment
		(start 59.650376 -236.277658)
		(end 59.505342 -236.422692)
		(width 0.14478)
		(layer "In13.Cu")
		(net "M_B_CPU1_SA_CB<2>")
	)
	(segment
		(start 52.944268 -236.01045)
		(end 52.09413 -235.160312)
		(width 0.14478)
		(layer "In13.Cu")
		(net "M_B_CPU1_SA_CB<2>")
	)
	(segment
		(start 87.811102 -245.294404)
		(end 87.656924 -245.028974)
		(width 0.0889)
		(layer "In13.Cu")
		(net "M_B_CPU1_SA_CB<2>")
	)
	(segment
		(start 59.895486 -237.041436)
		(end 59.895486 -236.812582)
		(width 0.14478)
		(layer "In13.Cu")
		(net "M_B_CPU1_SA_CB<2>")
	)
	(segment
		(start 79.539592 -244.972078)
		(end 79.521304 -244.961664)
		(width 0.0889)
		(layer "In13.Cu")
		(net "M_B_CPU1_SA_CB<2>")
	)
	(segment
		(start 77.564234 -244.92077)
		(end 77.02169 -244.378226)
		(width 0.0889)
		(layer "In13.Cu")
		(net "M_B_CPU1_SA_CB<2>")
	)
	(segment
		(start 78.41107 -244.92077)
		(end 77.564234 -244.92077)
		(width 0.0889)
		(layer "In13.Cu")
		(net "M_B_CPU1_SA_CB<2>")
	)
	(segment
		(start 52.09413 -235.160312)
		(end 50.222404 -235.160312)
		(width 0.14478)
		(layer "In13.Cu")
		(net "M_B_CPU1_SA_CB<2>")
	)
	(segment
		(start 76.198476 -244.533674)
		(end 67.387724 -244.533674)
		(width 0.14478)
		(layer "In13.Cu")
		(net "M_B_CPU1_SA_CB<2>")
	)
	(segment
		(start 85.752432 -244.966998)
		(end 85.74405 -244.971824)
		(width 0.0889)
		(layer "In13.Cu")
		(net "M_B_CPU1_SA_CB<2>")
	)
	(segment
		(start 58.8645 -236.01045)
		(end 52.944268 -236.01045)
		(width 0.14478)
		(layer "In13.Cu")
		(net "M_B_CPU1_SA_CB<2>")
	)
	(arc
		(start 79.521304 -244.961664)
		(mid 79.342583 -244.921741)
		(end 79.166466 -244.971824)
		(width 0.0889)
		(layer "In13.Cu")
		(net "M_B_CPU1_SA_CB<2>")
	)
	(arc
		(start 87.057992 -244.971824)
		(mid 86.871048 -244.921569)
		(end 86.684104 -244.971824)
		(width 0.0889)
		(layer "In13.Cu")
		(net "M_B_CPU1_SA_CB<2>")
	)
	(arc
		(start 81.044034 -244.971824)
		(mid 80.761078 -245.048001)
		(end 80.478122 -244.971824)
		(width 0.0889)
		(layer "In13.Cu")
		(net "M_B_CPU1_SA_CB<2>")
	)
	(arc
		(start 86.684104 -244.971824)
		(mid 86.401148 -245.048001)
		(end 86.118192 -244.971824)
		(width 0.0889)
		(layer "In13.Cu")
		(net "M_B_CPU1_SA_CB<2>")
	)
	(arc
		(start 83.289648 -244.966998)
		(mid 83.10614 -244.921504)
		(end 82.923888 -244.971824)
		(width 0.0889)
		(layer "In13.Cu")
		(net "M_B_CPU1_SA_CB<2>")
	)
	(arc
		(start 80.10398 -244.971824)
		(mid 79.834211 -245.047847)
		(end 79.561182 -244.984524)
		(width 0.0889)
		(layer "In13.Cu")
		(net "M_B_CPU1_SA_CB<2>")
	)
	(arc
		(start 79.143098 -244.98554)
		(mid 78.869444 -245.048483)
		(end 78.599284 -244.971824)
		(width 0.0889)
		(layer "In13.Cu")
		(net "M_B_CPU1_SA_CB<2>")
	)
	(arc
		(start 82.357976 -244.971824)
		(mid 82.171032 -244.921569)
		(end 81.984088 -244.971824)
		(width 0.0889)
		(layer "In13.Cu")
		(net "M_B_CPU1_SA_CB<2>")
	)
	(arc
		(start 87.560658 -245.003574)
		(mid 87.305593 -245.046925)
		(end 87.057992 -244.971824)
		(width 0.0889)
		(layer "In13.Cu")
		(net "M_B_CPU1_SA_CB<2>")
	)
	(arc
		(start 81.984088 -244.971824)
		(mid 81.701132 -245.048001)
		(end 81.418176 -244.971824)
		(width 0.0889)
		(layer "In13.Cu")
		(net "M_B_CPU1_SA_CB<2>")
	)
	(arc
		(start 83.863942 -244.971824)
		(mid 83.580986 -245.048001)
		(end 83.29803 -244.971824)
		(width 0.0889)
		(layer "In13.Cu")
		(net "M_B_CPU1_SA_CB<2>")
	)
	(arc
		(start 81.418176 -244.971824)
		(mid 81.235925 -244.921474)
		(end 81.052416 -244.966998)
		(width 0.0889)
		(layer "In13.Cu")
		(net "M_B_CPU1_SA_CB<2>")
	)
	(arc
		(start 85.178138 -244.971824)
		(mid 84.995887 -244.921474)
		(end 84.812378 -244.966998)
		(width 0.0889)
		(layer "In13.Cu")
		(net "M_B_CPU1_SA_CB<2>")
	)
	(arc
		(start 84.229702 -244.966998)
		(mid 84.046194 -244.921504)
		(end 83.863942 -244.971824)
		(width 0.0889)
		(layer "In13.Cu")
		(net "M_B_CPU1_SA_CB<2>")
	)
	(arc
		(start 85.74405 -244.971824)
		(mid 85.461094 -245.048001)
		(end 85.178138 -244.971824)
		(width 0.0889)
		(layer "In13.Cu")
		(net "M_B_CPU1_SA_CB<2>")
	)
	(arc
		(start 80.46974 -244.966998)
		(mid 80.286232 -244.921504)
		(end 80.10398 -244.971824)
		(width 0.0889)
		(layer "In13.Cu")
		(net "M_B_CPU1_SA_CB<2>")
	)
	(arc
		(start 84.803996 -244.971824)
		(mid 84.52104 -245.048001)
		(end 84.238084 -244.971824)
		(width 0.0889)
		(layer "In13.Cu")
		(net "M_B_CPU1_SA_CB<2>")
	)
	(arc
		(start 86.118192 -244.971824)
		(mid 85.935941 -244.921474)
		(end 85.752432 -244.966998)
		(width 0.0889)
		(layer "In13.Cu")
		(net "M_B_CPU1_SA_CB<2>")
	)
	(arc
		(start 78.599284 -244.971824)
		(mid 78.508565 -244.933817)
		(end 78.41107 -244.92077)
		(width 0.0889)
		(layer "In13.Cu")
		(net "M_B_CPU1_SA_CB<2>")
	)
	(arc
		(start 82.923888 -244.971824)
		(mid 82.640932 -245.048001)
		(end 82.357976 -244.971824)
		(width 0.0889)
		(layer "In13.Cu")
		(net "M_B_CPU1_SA_CB<2>")
	)
	(segment
		(start 89.218008 -245.560342)
		(end 88.751156 -245.294404)
		(width 0.10668)
		(layer "F.Cu")
		(net "M_B_CPU1_SA_CB<1>")
	)
	(segment
		(start 54.065678 -237.252764)
		(end 53.804058 -237.252764)
		(width 0.14478)
		(layer "In13.Cu")
		(net "M_B_CPU1_SA_CB<1>")
	)
	(segment
		(start 53.108098 -236.750352)
		(end 53.108098 -237.107984)
		(width 0.14478)
		(layer "In13.Cu")
		(net "M_B_CPU1_SA_CB<1>")
	)
	(segment
		(start 56.821578 -236.605572)
		(end 56.559958 -236.605572)
		(width 0.14478)
		(layer "In13.Cu")
		(net "M_B_CPU1_SA_CB<1>")
	)
	(segment
		(start 54.761638 -236.750352)
		(end 54.616858 -236.605572)
		(width 0.14478)
		(layer "In13.Cu")
		(net "M_B_CPU1_SA_CB<1>")
	)
	(segment
		(start 77.538326 -245.373906)
		(end 76.629768 -245.373906)
		(width 0.0889)
		(layer "In13.Cu")
		(net "M_B_CPU1_SA_CB<1>")
	)
	(segment
		(start 53.108098 -237.107984)
		(end 52.963318 -237.252764)
		(width 0.14478)
		(layer "In13.Cu")
		(net "M_B_CPU1_SA_CB<1>")
	)
	(segment
		(start 85.752432 -245.62181)
		(end 85.74405 -245.616984)
		(width 0.0889)
		(layer "In13.Cu")
		(net "M_B_CPU1_SA_CB<1>")
	)
	(segment
		(start 52.963318 -237.252764)
		(end 52.559712 -237.252764)
		(width 0.14478)
		(layer "In13.Cu")
		(net "M_B_CPU1_SA_CB<1>")
	)
	(segment
		(start 55.312818 -237.107984)
		(end 55.168038 -237.252764)
		(width 0.14478)
		(layer "In13.Cu")
		(net "M_B_CPU1_SA_CB<1>")
	)
	(segment
		(start 53.659278 -237.107984)
		(end 53.659278 -236.750352)
		(width 0.14478)
		(layer "In13.Cu")
		(net "M_B_CPU1_SA_CB<1>")
	)
	(segment
		(start 53.804058 -237.252764)
		(end 53.659278 -237.107984)
		(width 0.14478)
		(layer "In13.Cu")
		(net "M_B_CPU1_SA_CB<1>")
	)
	(segment
		(start 54.210458 -236.750352)
		(end 54.210458 -237.107984)
		(width 0.14478)
		(layer "In13.Cu")
		(net "M_B_CPU1_SA_CB<1>")
	)
	(segment
		(start 56.415178 -236.750352)
		(end 56.415178 -237.107984)
		(width 0.14478)
		(layer "In13.Cu")
		(net "M_B_CPU1_SA_CB<1>")
	)
	(segment
		(start 76.239116 -244.983254)
		(end 67.123564 -244.983254)
		(width 0.14478)
		(layer "In13.Cu")
		(net "M_B_CPU1_SA_CB<1>")
	)
	(segment
		(start 55.719218 -236.858302)
		(end 55.457598 -236.858302)
		(width 0.14478)
		(layer "In13.Cu")
		(net "M_B_CPU1_SA_CB<1>")
	)
	(segment
		(start 53.252878 -236.605572)
		(end 53.108098 -236.750352)
		(width 0.14478)
		(layer "In13.Cu")
		(net "M_B_CPU1_SA_CB<1>")
	)
	(segment
		(start 54.355238 -236.605572)
		(end 54.210458 -236.750352)
		(width 0.14478)
		(layer "In13.Cu")
		(net "M_B_CPU1_SA_CB<1>")
	)
	(segment
		(start 51.884072 -236.577124)
		(end 51.884072 -236.435392)
		(width 0.14478)
		(layer "In13.Cu")
		(net "M_B_CPU1_SA_CB<1>")
	)
	(segment
		(start 56.415178 -237.107984)
		(end 56.270398 -237.252764)
		(width 0.14478)
		(layer "In13.Cu")
		(net "M_B_CPU1_SA_CB<1>")
	)
	(segment
		(start 59.000644 -236.860334)
		(end 57.818274 -236.860334)
		(width 0.14478)
		(layer "In13.Cu")
		(net "M_B_CPU1_SA_CB<1>")
	)
	(segment
		(start 80.10398 -245.616984)
		(end 80.093566 -245.610888)
		(width 0.0889)
		(layer "In13.Cu")
		(net "M_B_CPU1_SA_CB<1>")
	)
	(segment
		(start 83.29803 -245.616984)
		(end 83.289648 -245.62181)
		(width 0.0889)
		(layer "In13.Cu")
		(net "M_B_CPU1_SA_CB<1>")
	)
	(segment
		(start 53.514498 -236.605572)
		(end 53.252878 -236.605572)
		(width 0.14478)
		(layer "In13.Cu")
		(net "M_B_CPU1_SA_CB<1>")
	)
	(segment
		(start 88.90508 -245.559834)
		(end 88.882728 -245.643146)
		(width 0.0889)
		(layer "In13.Cu")
		(net "M_B_CPU1_SA_CB<1>")
	)
	(segment
		(start 54.210458 -237.107984)
		(end 54.065678 -237.252764)
		(width 0.14478)
		(layer "In13.Cu")
		(net "M_B_CPU1_SA_CB<1>")
	)
	(segment
		(start 77.940408 -245.540784)
		(end 77.705204 -245.540784)
		(width 0.0889)
		(layer "In13.Cu")
		(net "M_B_CPU1_SA_CB<1>")
	)
	(segment
		(start 87.998046 -245.616984)
		(end 87.989664 -245.62181)
		(width 0.0889)
		(layer "In13.Cu")
		(net "M_B_CPU1_SA_CB<1>")
	)
	(segment
		(start 54.616858 -236.605572)
		(end 54.355238 -236.605572)
		(width 0.14478)
		(layer "In13.Cu")
		(net "M_B_CPU1_SA_CB<1>")
	)
	(segment
		(start 55.863998 -237.107984)
		(end 55.863998 -237.003082)
		(width 0.14478)
		(layer "In13.Cu")
		(net "M_B_CPU1_SA_CB<1>")
	)
	(segment
		(start 77.705204 -245.540784)
		(end 77.538326 -245.373906)
		(width 0.0889)
		(layer "In13.Cu")
		(net "M_B_CPU1_SA_CB<1>")
	)
	(segment
		(start 56.966358 -237.107984)
		(end 56.966358 -236.750352)
		(width 0.14478)
		(layer "In13.Cu")
		(net "M_B_CPU1_SA_CB<1>")
	)
	(segment
		(start 78.603348 -245.613428)
		(end 78.59776 -245.61673)
		(width 0.0889)
		(layer "In13.Cu")
		(net "M_B_CPU1_SA_CB<1>")
	)
	(segment
		(start 57.111138 -237.252764)
		(end 56.966358 -237.107984)
		(width 0.14478)
		(layer "In13.Cu")
		(net "M_B_CPU1_SA_CB<1>")
	)
	(segment
		(start 54.906418 -237.252764)
		(end 54.761638 -237.107984)
		(width 0.14478)
		(layer "In13.Cu")
		(net "M_B_CPU1_SA_CB<1>")
	)
	(segment
		(start 55.863998 -237.003082)
		(end 55.719218 -236.858302)
		(width 0.14478)
		(layer "In13.Cu")
		(net "M_B_CPU1_SA_CB<1>")
	)
	(segment
		(start 54.761638 -237.107984)
		(end 54.761638 -236.750352)
		(width 0.14478)
		(layer "In13.Cu")
		(net "M_B_CPU1_SA_CB<1>")
	)
	(segment
		(start 84.812378 -245.62181)
		(end 84.803996 -245.616984)
		(width 0.0889)
		(layer "In13.Cu")
		(net "M_B_CPU1_SA_CB<1>")
	)
	(segment
		(start 67.123564 -244.983254)
		(end 59.000644 -236.860334)
		(width 0.14478)
		(layer "In13.Cu")
		(net "M_B_CPU1_SA_CB<1>")
	)
	(segment
		(start 84.238084 -245.616984)
		(end 84.229702 -245.62181)
		(width 0.0889)
		(layer "In13.Cu")
		(net "M_B_CPU1_SA_CB<1>")
	)
	(segment
		(start 55.457598 -236.858302)
		(end 55.312818 -237.003082)
		(width 0.14478)
		(layer "In13.Cu")
		(net "M_B_CPU1_SA_CB<1>")
	)
	(segment
		(start 57.425844 -237.252764)
		(end 57.111138 -237.252764)
		(width 0.14478)
		(layer "In13.Cu")
		(net "M_B_CPU1_SA_CB<1>")
	)
	(segment
		(start 53.659278 -236.750352)
		(end 53.514498 -236.605572)
		(width 0.14478)
		(layer "In13.Cu")
		(net "M_B_CPU1_SA_CB<1>")
	)
	(segment
		(start 78.59776 -245.61673)
		(end 78.579472 -245.627144)
		(width 0.0889)
		(layer "In13.Cu")
		(net "M_B_CPU1_SA_CB<1>")
	)
	(segment
		(start 88.751156 -245.294404)
		(end 88.90508 -245.559834)
		(width 0.0889)
		(layer "In13.Cu")
		(net "M_B_CPU1_SA_CB<1>")
	)
	(segment
		(start 79.171546 -245.62181)
		(end 79.163164 -245.616984)
		(width 0.0889)
		(layer "In13.Cu")
		(net "M_B_CPU1_SA_CB<1>")
	)
	(segment
		(start 81.052416 -245.62181)
		(end 81.044034 -245.616984)
		(width 0.0889)
		(layer "In13.Cu")
		(net "M_B_CPU1_SA_CB<1>")
	)
	(segment
		(start 56.270398 -237.252764)
		(end 56.008778 -237.252764)
		(width 0.14478)
		(layer "In13.Cu")
		(net "M_B_CPU1_SA_CB<1>")
	)
	(segment
		(start 80.478122 -245.616984)
		(end 80.46974 -245.62181)
		(width 0.0889)
		(layer "In13.Cu")
		(net "M_B_CPU1_SA_CB<1>")
	)
	(segment
		(start 55.312818 -237.003082)
		(end 55.312818 -237.107984)
		(width 0.14478)
		(layer "In13.Cu")
		(net "M_B_CPU1_SA_CB<1>")
	)
	(segment
		(start 56.008778 -237.252764)
		(end 55.863998 -237.107984)
		(width 0.14478)
		(layer "In13.Cu")
		(net "M_B_CPU1_SA_CB<1>")
	)
	(segment
		(start 56.966358 -236.750352)
		(end 56.821578 -236.605572)
		(width 0.14478)
		(layer "In13.Cu")
		(net "M_B_CPU1_SA_CB<1>")
	)
	(segment
		(start 56.559958 -236.605572)
		(end 56.415178 -236.750352)
		(width 0.14478)
		(layer "In13.Cu")
		(net "M_B_CPU1_SA_CB<1>")
	)
	(segment
		(start 57.818274 -236.860334)
		(end 57.425844 -237.252764)
		(width 0.14478)
		(layer "In13.Cu")
		(net "M_B_CPU1_SA_CB<1>")
	)
	(segment
		(start 55.168038 -237.252764)
		(end 54.906418 -237.252764)
		(width 0.14478)
		(layer "In13.Cu")
		(net "M_B_CPU1_SA_CB<1>")
	)
	(segment
		(start 52.559712 -237.252764)
		(end 51.884072 -236.577124)
		(width 0.14478)
		(layer "In13.Cu")
		(net "M_B_CPU1_SA_CB<1>")
	)
	(segment
		(start 76.629768 -245.373906)
		(end 76.239116 -244.983254)
		(width 0.0889)
		(layer "In13.Cu")
		(net "M_B_CPU1_SA_CB<1>")
	)
	(arc
		(start 83.863942 -245.616984)
		(mid 83.580986 -245.540807)
		(end 83.29803 -245.616984)
		(width 0.0889)
		(layer "In13.Cu")
		(net "M_B_CPU1_SA_CB<1>")
	)
	(arc
		(start 80.093566 -245.610888)
		(mid 79.81488 -245.540668)
		(end 79.537814 -245.616984)
		(width 0.0889)
		(layer "In13.Cu")
		(net "M_B_CPU1_SA_CB<1>")
	)
	(arc
		(start 83.289648 -245.62181)
		(mid 83.10614 -245.667304)
		(end 82.923888 -245.616984)
		(width 0.0889)
		(layer "In13.Cu")
		(net "M_B_CPU1_SA_CB<1>")
	)
	(arc
		(start 78.223618 -245.616984)
		(mid 78.08705 -245.560177)
		(end 77.940408 -245.540784)
		(width 0.0889)
		(layer "In13.Cu")
		(net "M_B_CPU1_SA_CB<1>")
	)
	(arc
		(start 80.46974 -245.62181)
		(mid 80.286232 -245.667304)
		(end 80.10398 -245.616984)
		(width 0.0889)
		(layer "In13.Cu")
		(net "M_B_CPU1_SA_CB<1>")
	)
	(arc
		(start 87.057992 -245.616984)
		(mid 86.871048 -245.667239)
		(end 86.684104 -245.616984)
		(width 0.0889)
		(layer "In13.Cu")
		(net "M_B_CPU1_SA_CB<1>")
	)
	(arc
		(start 81.418176 -245.616984)
		(mid 81.235925 -245.667334)
		(end 81.052416 -245.62181)
		(width 0.0889)
		(layer "In13.Cu")
		(net "M_B_CPU1_SA_CB<1>")
	)
	(arc
		(start 84.803996 -245.616984)
		(mid 84.52104 -245.540807)
		(end 84.238084 -245.616984)
		(width 0.0889)
		(layer "In13.Cu")
		(net "M_B_CPU1_SA_CB<1>")
	)
	(arc
		(start 86.684104 -245.616984)
		(mid 86.401148 -245.540807)
		(end 86.118192 -245.616984)
		(width 0.0889)
		(layer "In13.Cu")
		(net "M_B_CPU1_SA_CB<1>")
	)
	(arc
		(start 81.044034 -245.616984)
		(mid 80.761078 -245.540807)
		(end 80.478122 -245.616984)
		(width 0.0889)
		(layer "In13.Cu")
		(net "M_B_CPU1_SA_CB<1>")
	)
	(arc
		(start 85.74405 -245.616984)
		(mid 85.461094 -245.540807)
		(end 85.178138 -245.616984)
		(width 0.0889)
		(layer "In13.Cu")
		(net "M_B_CPU1_SA_CB<1>")
	)
	(arc
		(start 87.989664 -245.62181)
		(mid 87.806156 -245.667304)
		(end 87.623904 -245.616984)
		(width 0.0889)
		(layer "In13.Cu")
		(net "M_B_CPU1_SA_CB<1>")
	)
	(arc
		(start 84.229702 -245.62181)
		(mid 84.046194 -245.667304)
		(end 83.863942 -245.616984)
		(width 0.0889)
		(layer "In13.Cu")
		(net "M_B_CPU1_SA_CB<1>")
	)
	(arc
		(start 82.357976 -245.616984)
		(mid 82.171032 -245.667239)
		(end 81.984088 -245.616984)
		(width 0.0889)
		(layer "In13.Cu")
		(net "M_B_CPU1_SA_CB<1>")
	)
	(arc
		(start 87.623904 -245.616984)
		(mid 87.340948 -245.540807)
		(end 87.057992 -245.616984)
		(width 0.0889)
		(layer "In13.Cu")
		(net "M_B_CPU1_SA_CB<1>")
	)
	(arc
		(start 88.563958 -245.616984)
		(mid 88.281002 -245.540807)
		(end 87.998046 -245.616984)
		(width 0.0889)
		(layer "In13.Cu")
		(net "M_B_CPU1_SA_CB<1>")
	)
	(arc
		(start 85.178138 -245.616984)
		(mid 84.995887 -245.667334)
		(end 84.812378 -245.62181)
		(width 0.0889)
		(layer "In13.Cu")
		(net "M_B_CPU1_SA_CB<1>")
	)
	(arc
		(start 78.579472 -245.627144)
		(mid 78.400243 -245.667297)
		(end 78.223618 -245.616984)
		(width 0.0889)
		(layer "In13.Cu")
		(net "M_B_CPU1_SA_CB<1>")
	)
	(arc
		(start 82.923888 -245.616984)
		(mid 82.640932 -245.540807)
		(end 82.357976 -245.616984)
		(width 0.0889)
		(layer "In13.Cu")
		(net "M_B_CPU1_SA_CB<1>")
	)
	(arc
		(start 79.163164 -245.616984)
		(mid 78.883736 -245.540818)
		(end 78.603348 -245.613428)
		(width 0.0889)
		(layer "In13.Cu")
		(net "M_B_CPU1_SA_CB<1>")
	)
	(arc
		(start 88.882728 -245.643146)
		(mid 88.720396 -245.665964)
		(end 88.563958 -245.616984)
		(width 0.0889)
		(layer "In13.Cu")
		(net "M_B_CPU1_SA_CB<1>")
	)
	(arc
		(start 86.118192 -245.616984)
		(mid 85.935941 -245.667334)
		(end 85.752432 -245.62181)
		(width 0.0889)
		(layer "In13.Cu")
		(net "M_B_CPU1_SA_CB<1>")
	)
	(arc
		(start 81.984088 -245.616984)
		(mid 81.701132 -245.540807)
		(end 81.418176 -245.616984)
		(width 0.0889)
		(layer "In13.Cu")
		(net "M_B_CPU1_SA_CB<1>")
	)
	(arc
		(start 79.537814 -245.616984)
		(mid 79.355309 -245.667461)
		(end 79.171546 -245.62181)
		(width 0.0889)
		(layer "In13.Cu")
		(net "M_B_CPU1_SA_CB<1>")
	)
	(segment
		(start 87.8078 -244.750336)
		(end 87.340948 -244.484398)
		(width 0.10668)
		(layer "F.Cu")
		(net "M_B_CPU1_SA_CB<0>")
	)
	(segment
		(start 55.110126 -235.405422)
		(end 55.110126 -235.305092)
		(width 0.14478)
		(layer "In13.Cu")
		(net "M_B_CPU1_SA_CB<0>")
	)
	(segment
		(start 57.459626 -235.160312)
		(end 57.721246 -235.160312)
		(width 0.14478)
		(layer "In13.Cu")
		(net "M_B_CPU1_SA_CB<0>")
	)
	(segment
		(start 61.837062 -238.11357)
		(end 61.999114 -238.275622)
		(width 0.14478)
		(layer "In13.Cu")
		(net "M_B_CPU1_SA_CB<0>")
	)
	(segment
		(start 56.763666 -235.405422)
		(end 56.908446 -235.550202)
		(width 0.14478)
		(layer "In13.Cu")
		(net "M_B_CPU1_SA_CB<0>")
	)
	(segment
		(start 86.57971 -244.811804)
		(end 86.588092 -244.806978)
		(width 0.0889)
		(layer "In13.Cu")
		(net "M_B_CPU1_SA_CB<0>")
	)
	(segment
		(start 51.884072 -234.73537)
		(end 52.309014 -234.310428)
		(width 0.14478)
		(layer "In13.Cu")
		(net "M_B_CPU1_SA_CB<0>")
	)
	(segment
		(start 61.81852 -237.35157)
		(end 61.980572 -237.513622)
		(width 0.14478)
		(layer "In13.Cu")
		(net "M_B_CPU1_SA_CB<0>")
	)
	(segment
		(start 54.558946 -235.305092)
		(end 54.558946 -235.405422)
		(width 0.14478)
		(layer "In13.Cu")
		(net "M_B_CPU1_SA_CB<0>")
	)
	(segment
		(start 58.272426 -235.550202)
		(end 58.417206 -235.405422)
		(width 0.14478)
		(layer "In13.Cu")
		(net "M_B_CPU1_SA_CB<0>")
	)
	(segment
		(start 67.79006 -244.066568)
		(end 75.92441 -244.066568)
		(width 0.14478)
		(layer "In13.Cu")
		(net "M_B_CPU1_SA_CB<0>")
	)
	(segment
		(start 61.590428 -237.35157)
		(end 61.81852 -237.35157)
		(width 0.14478)
		(layer "In13.Cu")
		(net "M_B_CPU1_SA_CB<0>")
	)
	(segment
		(start 53.233828 -235.102908)
		(end 53.418994 -235.288074)
		(width 0.14478)
		(layer "In13.Cu")
		(net "M_B_CPU1_SA_CB<0>")
	)
	(segment
		(start 62.76086 -238.29391)
		(end 62.76086 -238.522002)
		(width 0.14478)
		(layer "In13.Cu")
		(net "M_B_CPU1_SA_CB<0>")
	)
	(segment
		(start 55.110126 -235.305092)
		(end 55.254906 -235.160312)
		(width 0.14478)
		(layer "In13.Cu")
		(net "M_B_CPU1_SA_CB<0>")
	)
	(segment
		(start 62.61735 -238.665512)
		(end 62.61735 -238.893858)
		(width 0.14478)
		(layer "In13.Cu")
		(net "M_B_CPU1_SA_CB<0>")
	)
	(segment
		(start 53.425852 -234.70616)
		(end 53.233828 -234.898184)
		(width 0.14478)
		(layer "In13.Cu")
		(net "M_B_CPU1_SA_CB<0>")
	)
	(segment
		(start 53.418994 -235.288074)
		(end 53.623718 -235.288328)
		(width 0.14478)
		(layer "In13.Cu")
		(net "M_B_CPU1_SA_CB<0>")
	)
	(segment
		(start 54.703726 -235.550202)
		(end 54.965346 -235.550202)
		(width 0.14478)
		(layer "In13.Cu")
		(net "M_B_CPU1_SA_CB<0>")
	)
	(segment
		(start 81.879694 -244.811804)
		(end 81.888076 -244.806978)
		(width 0.0889)
		(layer "In13.Cu")
		(net "M_B_CPU1_SA_CB<0>")
	)
	(segment
		(start 61.446918 -237.495334)
		(end 61.590428 -237.35157)
		(width 0.14478)
		(layer "In13.Cu")
		(net "M_B_CPU1_SA_CB<0>")
	)
	(segment
		(start 53.233828 -234.898184)
		(end 53.233828 -235.102908)
		(width 0.14478)
		(layer "In13.Cu")
		(net "M_B_CPU1_SA_CB<0>")
	)
	(segment
		(start 57.314846 -235.405422)
		(end 57.314846 -235.305092)
		(width 0.14478)
		(layer "In13.Cu")
		(net "M_B_CPU1_SA_CB<0>")
	)
	(segment
		(start 85.639656 -244.811804)
		(end 85.648038 -244.806978)
		(width 0.0889)
		(layer "In13.Cu")
		(net "M_B_CPU1_SA_CB<0>")
	)
	(segment
		(start 56.908446 -235.550202)
		(end 57.170066 -235.550202)
		(width 0.14478)
		(layer "In13.Cu")
		(net "M_B_CPU1_SA_CB<0>")
	)
	(segment
		(start 56.357266 -235.160312)
		(end 56.618886 -235.160312)
		(width 0.14478)
		(layer "In13.Cu")
		(net "M_B_CPU1_SA_CB<0>")
	)
	(segment
		(start 58.010806 -235.550202)
		(end 58.272426 -235.550202)
		(width 0.14478)
		(layer "In13.Cu")
		(net "M_B_CPU1_SA_CB<0>")
	)
	(segment
		(start 58.417206 -235.305092)
		(end 58.561986 -235.160312)
		(width 0.14478)
		(layer "In13.Cu")
		(net "M_B_CPU1_SA_CB<0>")
	)
	(segment
		(start 52.309014 -234.310428)
		(end 53.23459 -234.310428)
		(width 0.14478)
		(layer "In13.Cu")
		(net "M_B_CPU1_SA_CB<0>")
	)
	(segment
		(start 56.763666 -235.305092)
		(end 56.763666 -235.405422)
		(width 0.14478)
		(layer "In13.Cu")
		(net "M_B_CPU1_SA_CB<0>")
	)
	(segment
		(start 62.76086 -238.522002)
		(end 62.61735 -238.665512)
		(width 0.14478)
		(layer "In13.Cu")
		(net "M_B_CPU1_SA_CB<0>")
	)
	(segment
		(start 55.661306 -235.305092)
		(end 55.661306 -235.405422)
		(width 0.14478)
		(layer "In13.Cu")
		(net "M_B_CPU1_SA_CB<0>")
	)
	(segment
		(start 61.837062 -237.885224)
		(end 61.837062 -238.11357)
		(width 0.14478)
		(layer "In13.Cu")
		(net "M_B_CPU1_SA_CB<0>")
	)
	(segment
		(start 76.979526 -244.066568)
		(end 77.643228 -244.73027)
		(width 0.0889)
		(layer "In13.Cu")
		(net "M_B_CPU1_SA_CB<0>")
	)
	(segment
		(start 62.370716 -238.131858)
		(end 62.598808 -238.131858)
		(width 0.14478)
		(layer "In13.Cu")
		(net "M_B_CPU1_SA_CB<0>")
	)
	(segment
		(start 56.212486 -235.405422)
		(end 56.212486 -235.305092)
		(width 0.14478)
		(layer "In13.Cu")
		(net "M_B_CPU1_SA_CB<0>")
	)
	(segment
		(start 53.426106 -234.501944)
		(end 53.425852 -234.70616)
		(width 0.14478)
		(layer "In13.Cu")
		(net "M_B_CPU1_SA_CB<0>")
	)
	(segment
		(start 53.751734 -235.160312)
		(end 54.414166 -235.160312)
		(width 0.14478)
		(layer "In13.Cu")
		(net "M_B_CPU1_SA_CB<0>")
	)
	(segment
		(start 87.154004 -244.806978)
		(end 87.162386 -244.811804)
		(width 0.0889)
		(layer "In13.Cu")
		(net "M_B_CPU1_SA_CB<0>")
	)
	(segment
		(start 57.314846 -235.305092)
		(end 57.459626 -235.160312)
		(width 0.14478)
		(layer "In13.Cu")
		(net "M_B_CPU1_SA_CB<0>")
	)
	(segment
		(start 61.056774 -237.333282)
		(end 61.218826 -237.495334)
		(width 0.14478)
		(layer "In13.Cu")
		(net "M_B_CPU1_SA_CB<0>")
	)
	(segment
		(start 53.23459 -234.310428)
		(end 53.426106 -234.501944)
		(width 0.14478)
		(layer "In13.Cu")
		(net "M_B_CPU1_SA_CB<0>")
	)
	(segment
		(start 53.623718 -235.288328)
		(end 53.751734 -235.160312)
		(width 0.14478)
		(layer "In13.Cu")
		(net "M_B_CPU1_SA_CB<0>")
	)
	(segment
		(start 57.866026 -235.405422)
		(end 58.010806 -235.550202)
		(width 0.14478)
		(layer "In13.Cu")
		(net "M_B_CPU1_SA_CB<0>")
	)
	(segment
		(start 55.516526 -235.160312)
		(end 55.661306 -235.305092)
		(width 0.14478)
		(layer "In13.Cu")
		(net "M_B_CPU1_SA_CB<0>")
	)
	(segment
		(start 54.414166 -235.160312)
		(end 54.558946 -235.305092)
		(width 0.14478)
		(layer "In13.Cu")
		(net "M_B_CPU1_SA_CB<0>")
	)
	(segment
		(start 54.965346 -235.550202)
		(end 55.110126 -235.405422)
		(width 0.14478)
		(layer "In13.Cu")
		(net "M_B_CPU1_SA_CB<0>")
	)
	(segment
		(start 87.495126 -244.749828)
		(end 87.340948 -244.484398)
		(width 0.0889)
		(layer "In13.Cu")
		(net "M_B_CPU1_SA_CB<0>")
	)
	(segment
		(start 79.051658 -244.8179)
		(end 79.070454 -244.806978)
		(width 0.0889)
		(layer "In13.Cu")
		(net "M_B_CPU1_SA_CB<0>")
	)
	(segment
		(start 55.661306 -235.405422)
		(end 55.806086 -235.550202)
		(width 0.14478)
		(layer "In13.Cu")
		(net "M_B_CPU1_SA_CB<0>")
	)
	(segment
		(start 56.212486 -235.305092)
		(end 56.357266 -235.160312)
		(width 0.14478)
		(layer "In13.Cu")
		(net "M_B_CPU1_SA_CB<0>")
	)
	(segment
		(start 79.634842 -244.806724)
		(end 79.654908 -244.818154)
		(width 0.0889)
		(layer "In13.Cu")
		(net "M_B_CPU1_SA_CB<0>")
	)
	(segment
		(start 57.170066 -235.550202)
		(end 57.314846 -235.405422)
		(width 0.14478)
		(layer "In13.Cu")
		(net "M_B_CPU1_SA_CB<0>")
	)
	(segment
		(start 58.417206 -235.405422)
		(end 58.417206 -235.305092)
		(width 0.14478)
		(layer "In13.Cu")
		(net "M_B_CPU1_SA_CB<0>")
	)
	(segment
		(start 61.999114 -238.275622)
		(end 62.227206 -238.275622)
		(width 0.14478)
		(layer "In13.Cu")
		(net "M_B_CPU1_SA_CB<0>")
	)
	(segment
		(start 61.980572 -237.513622)
		(end 61.980572 -237.741714)
		(width 0.14478)
		(layer "In13.Cu")
		(net "M_B_CPU1_SA_CB<0>")
	)
	(segment
		(start 55.806086 -235.550202)
		(end 56.067706 -235.550202)
		(width 0.14478)
		(layer "In13.Cu")
		(net "M_B_CPU1_SA_CB<0>")
	)
	(segment
		(start 61.218826 -237.495334)
		(end 61.446918 -237.495334)
		(width 0.14478)
		(layer "In13.Cu")
		(net "M_B_CPU1_SA_CB<0>")
	)
	(segment
		(start 57.721246 -235.160312)
		(end 57.866026 -235.305092)
		(width 0.14478)
		(layer "In13.Cu")
		(net "M_B_CPU1_SA_CB<0>")
	)
	(segment
		(start 61.056774 -237.10519)
		(end 61.056774 -237.333282)
		(width 0.14478)
		(layer "In13.Cu")
		(net "M_B_CPU1_SA_CB<0>")
	)
	(segment
		(start 79.613252 -244.794278)
		(end 79.634842 -244.806724)
		(width 0.0889)
		(layer "In13.Cu")
		(net "M_B_CPU1_SA_CB<0>")
	)
	(segment
		(start 56.618886 -235.160312)
		(end 56.763666 -235.305092)
		(width 0.14478)
		(layer "In13.Cu")
		(net "M_B_CPU1_SA_CB<0>")
	)
	(segment
		(start 61.980572 -237.741714)
		(end 61.837062 -237.885224)
		(width 0.14478)
		(layer "In13.Cu")
		(net "M_B_CPU1_SA_CB<0>")
	)
	(segment
		(start 82.453988 -244.806978)
		(end 82.46237 -244.811804)
		(width 0.0889)
		(layer "In13.Cu")
		(net "M_B_CPU1_SA_CB<0>")
	)
	(segment
		(start 62.598808 -238.131858)
		(end 62.76086 -238.29391)
		(width 0.14478)
		(layer "In13.Cu")
		(net "M_B_CPU1_SA_CB<0>")
	)
	(segment
		(start 62.227206 -238.275622)
		(end 62.370716 -238.131858)
		(width 0.14478)
		(layer "In13.Cu")
		(net "M_B_CPU1_SA_CB<0>")
	)
	(segment
		(start 61.200284 -236.96168)
		(end 61.056774 -237.10519)
		(width 0.14478)
		(layer "In13.Cu")
		(net "M_B_CPU1_SA_CB<0>")
	)
	(segment
		(start 87.472774 -244.83314)
		(end 87.495126 -244.749828)
		(width 0.0889)
		(layer "In13.Cu")
		(net "M_B_CPU1_SA_CB<0>")
	)
	(segment
		(start 54.558946 -235.405422)
		(end 54.703726 -235.550202)
		(width 0.14478)
		(layer "In13.Cu")
		(net "M_B_CPU1_SA_CB<0>")
	)
	(segment
		(start 83.394042 -244.806978)
		(end 83.402424 -244.811804)
		(width 0.0889)
		(layer "In13.Cu")
		(net "M_B_CPU1_SA_CB<0>")
	)
	(segment
		(start 55.254906 -235.160312)
		(end 55.516526 -235.160312)
		(width 0.14478)
		(layer "In13.Cu")
		(net "M_B_CPU1_SA_CB<0>")
	)
	(segment
		(start 59.627262 -235.160312)
		(end 61.200284 -236.733334)
		(width 0.14478)
		(layer "In13.Cu")
		(net "M_B_CPU1_SA_CB<0>")
	)
	(segment
		(start 77.643228 -244.73027)
		(end 78.41107 -244.73027)
		(width 0.0889)
		(layer "In13.Cu")
		(net "M_B_CPU1_SA_CB<0>")
	)
	(segment
		(start 61.200284 -236.733334)
		(end 61.200284 -236.96168)
		(width 0.14478)
		(layer "In13.Cu")
		(net "M_B_CPU1_SA_CB<0>")
	)
	(segment
		(start 75.92441 -244.066568)
		(end 76.979526 -244.066568)
		(width 0.0889)
		(layer "In13.Cu")
		(net "M_B_CPU1_SA_CB<0>")
	)
	(segment
		(start 57.866026 -235.305092)
		(end 57.866026 -235.405422)
		(width 0.14478)
		(layer "In13.Cu")
		(net "M_B_CPU1_SA_CB<0>")
	)
	(segment
		(start 62.61735 -238.893858)
		(end 67.79006 -244.066568)
		(width 0.14478)
		(layer "In13.Cu")
		(net "M_B_CPU1_SA_CB<0>")
	)
	(segment
		(start 56.067706 -235.550202)
		(end 56.212486 -235.405422)
		(width 0.14478)
		(layer "In13.Cu")
		(net "M_B_CPU1_SA_CB<0>")
	)
	(segment
		(start 58.561986 -235.160312)
		(end 59.627262 -235.160312)
		(width 0.14478)
		(layer "In13.Cu")
		(net "M_B_CPU1_SA_CB<0>")
	)
	(arc
		(start 86.21395 -244.806978)
		(mid 86.396201 -244.857328)
		(end 86.57971 -244.811804)
		(width 0.0889)
		(layer "In13.Cu")
		(net "M_B_CPU1_SA_CB<0>")
	)
	(arc
		(start 84.334096 -244.806978)
		(mid 84.52104 -244.857233)
		(end 84.707984 -244.806978)
		(width 0.0889)
		(layer "In13.Cu")
		(net "M_B_CPU1_SA_CB<0>")
	)
	(arc
		(start 87.162386 -244.811804)
		(mid 87.315256 -244.856445)
		(end 87.472774 -244.83314)
		(width 0.0889)
		(layer "In13.Cu")
		(net "M_B_CPU1_SA_CB<0>")
	)
	(arc
		(start 85.648038 -244.806978)
		(mid 85.930994 -244.730801)
		(end 86.21395 -244.806978)
		(width 0.0889)
		(layer "In13.Cu")
		(net "M_B_CPU1_SA_CB<0>")
	)
	(arc
		(start 86.588092 -244.806978)
		(mid 86.871048 -244.730801)
		(end 87.154004 -244.806978)
		(width 0.0889)
		(layer "In13.Cu")
		(net "M_B_CPU1_SA_CB<0>")
	)
	(arc
		(start 81.888076 -244.806978)
		(mid 82.171032 -244.730801)
		(end 82.453988 -244.806978)
		(width 0.0889)
		(layer "In13.Cu")
		(net "M_B_CPU1_SA_CB<0>")
	)
	(arc
		(start 83.402424 -244.811804)
		(mid 83.585932 -244.857298)
		(end 83.768184 -244.806978)
		(width 0.0889)
		(layer "In13.Cu")
		(net "M_B_CPU1_SA_CB<0>")
	)
	(arc
		(start 83.768184 -244.806978)
		(mid 84.05114 -244.730801)
		(end 84.334096 -244.806978)
		(width 0.0889)
		(layer "In13.Cu")
		(net "M_B_CPU1_SA_CB<0>")
	)
	(arc
		(start 78.695296 -244.806978)
		(mid 78.872087 -244.857697)
		(end 79.051658 -244.8179)
		(width 0.0889)
		(layer "In13.Cu")
		(net "M_B_CPU1_SA_CB<0>")
	)
	(arc
		(start 80.008222 -244.806978)
		(mid 80.291178 -244.730801)
		(end 80.574134 -244.806978)
		(width 0.0889)
		(layer "In13.Cu")
		(net "M_B_CPU1_SA_CB<0>")
	)
	(arc
		(start 82.82813 -244.806978)
		(mid 83.111086 -244.730801)
		(end 83.394042 -244.806978)
		(width 0.0889)
		(layer "In13.Cu")
		(net "M_B_CPU1_SA_CB<0>")
	)
	(arc
		(start 80.574134 -244.806978)
		(mid 80.761078 -244.857233)
		(end 80.948022 -244.806978)
		(width 0.0889)
		(layer "In13.Cu")
		(net "M_B_CPU1_SA_CB<0>")
	)
	(arc
		(start 80.948022 -244.806978)
		(mid 81.230978 -244.730801)
		(end 81.513934 -244.806978)
		(width 0.0889)
		(layer "In13.Cu")
		(net "M_B_CPU1_SA_CB<0>")
	)
	(arc
		(start 79.070454 -244.806978)
		(mid 79.340223 -244.730955)
		(end 79.613252 -244.794278)
		(width 0.0889)
		(layer "In13.Cu")
		(net "M_B_CPU1_SA_CB<0>")
	)
	(arc
		(start 82.46237 -244.811804)
		(mid 82.645878 -244.857298)
		(end 82.82813 -244.806978)
		(width 0.0889)
		(layer "In13.Cu")
		(net "M_B_CPU1_SA_CB<0>")
	)
	(arc
		(start 78.41107 -244.73027)
		(mid 78.558279 -244.749747)
		(end 78.695296 -244.806978)
		(width 0.0889)
		(layer "In13.Cu")
		(net "M_B_CPU1_SA_CB<0>")
	)
	(arc
		(start 84.707984 -244.806978)
		(mid 84.99094 -244.730801)
		(end 85.273896 -244.806978)
		(width 0.0889)
		(layer "In13.Cu")
		(net "M_B_CPU1_SA_CB<0>")
	)
	(arc
		(start 85.273896 -244.806978)
		(mid 85.456147 -244.857328)
		(end 85.639656 -244.811804)
		(width 0.0889)
		(layer "In13.Cu")
		(net "M_B_CPU1_SA_CB<0>")
	)
	(arc
		(start 81.513934 -244.806978)
		(mid 81.696185 -244.857328)
		(end 81.879694 -244.811804)
		(width 0.0889)
		(layer "In13.Cu")
		(net "M_B_CPU1_SA_CB<0>")
	)
	(arc
		(start 79.654908 -244.818154)
		(mid 79.832986 -244.857138)
		(end 80.008222 -244.806978)
		(width 0.0889)
		(layer "In13.Cu")
		(net "M_B_CPU1_SA_CB<0>")
	)
	(segment
		(start 89.218008 -255.280414)
		(end 88.751156 -255.014476)
		(width 0.10668)
		(layer "F.Cu")
		(net "M_B_CPU1_SA_CA<6>")
	)
	(segment
		(start 80.46974 -255.341882)
		(end 80.478122 -255.337056)
		(width 0.0889)
		(layer "In13.Cu")
		(net "M_B_CPU1_SA_CA<6>")
	)
	(segment
		(start 72.865742 -255.683004)
		(end 76.001626 -255.683004)
		(width 0.14478)
		(layer "In13.Cu")
		(net "M_B_CPU1_SA_CA<6>")
	)
	(segment
		(start 56.247538 -255.063752)
		(end 56.392318 -255.208532)
		(width 0.14478)
		(layer "In13.Cu")
		(net "M_B_CPU1_SA_CA<6>")
	)
	(segment
		(start 56.392318 -255.208532)
		(end 56.653938 -255.208532)
		(width 0.14478)
		(layer "In13.Cu")
		(net "M_B_CPU1_SA_CA<6>")
	)
	(segment
		(start 56.247538 -254.855218)
		(end 56.247538 -255.063752)
		(width 0.14478)
		(layer "In13.Cu")
		(net "M_B_CPU1_SA_CA<6>")
	)
	(segment
		(start 78.59776 -255.336802)
		(end 78.603348 -255.3335)
		(width 0.0889)
		(layer "In13.Cu")
		(net "M_B_CPU1_SA_CA<6>")
	)
	(segment
		(start 56.798718 -255.063752)
		(end 56.798718 -254.855218)
		(width 0.14478)
		(layer "In13.Cu")
		(net "M_B_CPU1_SA_CA<6>")
	)
	(segment
		(start 77.452474 -255.387602)
		(end 78.410816 -255.387602)
		(width 0.0889)
		(layer "In13.Cu")
		(net "M_B_CPU1_SA_CA<6>")
	)
	(segment
		(start 57.901078 -254.855218)
		(end 58.045858 -254.710438)
		(width 0.14478)
		(layer "In13.Cu")
		(net "M_B_CPU1_SA_CA<6>")
	)
	(segment
		(start 52.9082 -253.075948)
		(end 54.54269 -254.710438)
		(width 0.14478)
		(layer "In13.Cu")
		(net "M_B_CPU1_SA_CA<6>")
	)
	(segment
		(start 57.901078 -255.063752)
		(end 57.901078 -254.855218)
		(width 0.14478)
		(layer "In13.Cu")
		(net "M_B_CPU1_SA_CA<6>")
	)
	(segment
		(start 85.74405 -255.337056)
		(end 85.752432 -255.341882)
		(width 0.0889)
		(layer "In13.Cu")
		(net "M_B_CPU1_SA_CA<6>")
	)
	(segment
		(start 88.882728 -255.363218)
		(end 88.90508 -255.279906)
		(width 0.0889)
		(layer "In13.Cu")
		(net "M_B_CPU1_SA_CA<6>")
	)
	(segment
		(start 87.989664 -255.341882)
		(end 87.998046 -255.337056)
		(width 0.0889)
		(layer "In13.Cu")
		(net "M_B_CPU1_SA_CA<6>")
	)
	(segment
		(start 56.102758 -254.710438)
		(end 56.247538 -254.855218)
		(width 0.14478)
		(layer "In13.Cu")
		(net "M_B_CPU1_SA_CA<6>")
	)
	(segment
		(start 54.54269 -254.710438)
		(end 56.102758 -254.710438)
		(width 0.14478)
		(layer "In13.Cu")
		(net "M_B_CPU1_SA_CA<6>")
	)
	(segment
		(start 56.943498 -254.710438)
		(end 57.205118 -254.710438)
		(width 0.14478)
		(layer "In13.Cu")
		(net "M_B_CPU1_SA_CA<6>")
	)
	(segment
		(start 58.045858 -254.710438)
		(end 60.604146 -254.710438)
		(width 0.14478)
		(layer "In13.Cu")
		(net "M_B_CPU1_SA_CA<6>")
	)
	(segment
		(start 76.001626 -255.683004)
		(end 77.157072 -255.683004)
		(width 0.0889)
		(layer "In13.Cu")
		(net "M_B_CPU1_SA_CA<6>")
	)
	(segment
		(start 57.756298 -255.208532)
		(end 57.901078 -255.063752)
		(width 0.14478)
		(layer "In13.Cu")
		(net "M_B_CPU1_SA_CA<6>")
	)
	(segment
		(start 57.494678 -255.208532)
		(end 57.756298 -255.208532)
		(width 0.14478)
		(layer "In13.Cu")
		(net "M_B_CPU1_SA_CA<6>")
	)
	(segment
		(start 60.61329 -254.701294)
		(end 71.884032 -254.701294)
		(width 0.14478)
		(layer "In13.Cu")
		(net "M_B_CPU1_SA_CA<6>")
	)
	(segment
		(start 56.798718 -254.855218)
		(end 56.943498 -254.710438)
		(width 0.14478)
		(layer "In13.Cu")
		(net "M_B_CPU1_SA_CA<6>")
	)
	(segment
		(start 60.604146 -254.710438)
		(end 60.61329 -254.701294)
		(width 0.14478)
		(layer "In13.Cu")
		(net "M_B_CPU1_SA_CA<6>")
	)
	(segment
		(start 57.349898 -254.855218)
		(end 57.349898 -255.063752)
		(width 0.14478)
		(layer "In13.Cu")
		(net "M_B_CPU1_SA_CA<6>")
	)
	(segment
		(start 83.289648 -255.341882)
		(end 83.29803 -255.337056)
		(width 0.0889)
		(layer "In13.Cu")
		(net "M_B_CPU1_SA_CA<6>")
	)
	(segment
		(start 84.803996 -255.337056)
		(end 84.812378 -255.341882)
		(width 0.0889)
		(layer "In13.Cu")
		(net "M_B_CPU1_SA_CA<6>")
	)
	(segment
		(start 80.093566 -255.33096)
		(end 80.10398 -255.337056)
		(width 0.0889)
		(layer "In13.Cu")
		(net "M_B_CPU1_SA_CA<6>")
	)
	(segment
		(start 51.884072 -252.58522)
		(end 52.3748 -253.075948)
		(width 0.14478)
		(layer "In13.Cu")
		(net "M_B_CPU1_SA_CA<6>")
	)
	(segment
		(start 52.3748 -253.075948)
		(end 52.9082 -253.075948)
		(width 0.14478)
		(layer "In13.Cu")
		(net "M_B_CPU1_SA_CA<6>")
	)
	(segment
		(start 56.653938 -255.208532)
		(end 56.798718 -255.063752)
		(width 0.14478)
		(layer "In13.Cu")
		(net "M_B_CPU1_SA_CA<6>")
	)
	(segment
		(start 88.90508 -255.279906)
		(end 88.751156 -255.014476)
		(width 0.0889)
		(layer "In13.Cu")
		(net "M_B_CPU1_SA_CA<6>")
	)
	(segment
		(start 79.163164 -255.337056)
		(end 79.171546 -255.341882)
		(width 0.0889)
		(layer "In13.Cu")
		(net "M_B_CPU1_SA_CA<6>")
	)
	(segment
		(start 84.229702 -255.341882)
		(end 84.238084 -255.337056)
		(width 0.0889)
		(layer "In13.Cu")
		(net "M_B_CPU1_SA_CA<6>")
	)
	(segment
		(start 57.349898 -255.063752)
		(end 57.494678 -255.208532)
		(width 0.14478)
		(layer "In13.Cu")
		(net "M_B_CPU1_SA_CA<6>")
	)
	(segment
		(start 77.157072 -255.683004)
		(end 77.452474 -255.387602)
		(width 0.0889)
		(layer "In13.Cu")
		(net "M_B_CPU1_SA_CA<6>")
	)
	(segment
		(start 57.205118 -254.710438)
		(end 57.349898 -254.855218)
		(width 0.14478)
		(layer "In13.Cu")
		(net "M_B_CPU1_SA_CA<6>")
	)
	(segment
		(start 71.884032 -254.701294)
		(end 72.865742 -255.683004)
		(width 0.14478)
		(layer "In13.Cu")
		(net "M_B_CPU1_SA_CA<6>")
	)
	(segment
		(start 81.044034 -255.337056)
		(end 81.052416 -255.341882)
		(width 0.0889)
		(layer "In13.Cu")
		(net "M_B_CPU1_SA_CA<6>")
	)
	(arc
		(start 79.537814 -255.337056)
		(mid 79.814881 -255.260785)
		(end 80.093566 -255.33096)
		(width 0.0889)
		(layer "In13.Cu")
		(net "M_B_CPU1_SA_CA<6>")
	)
	(arc
		(start 81.052416 -255.341882)
		(mid 81.235924 -255.387376)
		(end 81.418176 -255.337056)
		(width 0.0889)
		(layer "In13.Cu")
		(net "M_B_CPU1_SA_CA<6>")
	)
	(arc
		(start 87.623904 -255.337056)
		(mid 87.806155 -255.387406)
		(end 87.989664 -255.341882)
		(width 0.0889)
		(layer "In13.Cu")
		(net "M_B_CPU1_SA_CA<6>")
	)
	(arc
		(start 84.812378 -255.341882)
		(mid 84.995886 -255.387376)
		(end 85.178138 -255.337056)
		(width 0.0889)
		(layer "In13.Cu")
		(net "M_B_CPU1_SA_CA<6>")
	)
	(arc
		(start 87.998046 -255.337056)
		(mid 88.281002 -255.260879)
		(end 88.563958 -255.337056)
		(width 0.0889)
		(layer "In13.Cu")
		(net "M_B_CPU1_SA_CA<6>")
	)
	(arc
		(start 78.603348 -255.3335)
		(mid 78.883737 -255.260831)
		(end 79.163164 -255.337056)
		(width 0.0889)
		(layer "In13.Cu")
		(net "M_B_CPU1_SA_CA<6>")
	)
	(arc
		(start 82.923888 -255.337056)
		(mid 83.106139 -255.387406)
		(end 83.289648 -255.341882)
		(width 0.0889)
		(layer "In13.Cu")
		(net "M_B_CPU1_SA_CA<6>")
	)
	(arc
		(start 81.984088 -255.337056)
		(mid 82.171032 -255.387311)
		(end 82.357976 -255.337056)
		(width 0.0889)
		(layer "In13.Cu")
		(net "M_B_CPU1_SA_CA<6>")
	)
	(arc
		(start 83.29803 -255.337056)
		(mid 83.580986 -255.260879)
		(end 83.863942 -255.337056)
		(width 0.0889)
		(layer "In13.Cu")
		(net "M_B_CPU1_SA_CA<6>")
	)
	(arc
		(start 88.563958 -255.337056)
		(mid 88.720396 -255.386027)
		(end 88.882728 -255.363218)
		(width 0.0889)
		(layer "In13.Cu")
		(net "M_B_CPU1_SA_CA<6>")
	)
	(arc
		(start 79.171546 -255.341882)
		(mid 79.355308 -255.387498)
		(end 79.537814 -255.337056)
		(width 0.0889)
		(layer "In13.Cu")
		(net "M_B_CPU1_SA_CA<6>")
	)
	(arc
		(start 81.418176 -255.337056)
		(mid 81.701132 -255.260879)
		(end 81.984088 -255.337056)
		(width 0.0889)
		(layer "In13.Cu")
		(net "M_B_CPU1_SA_CA<6>")
	)
	(arc
		(start 86.684104 -255.337056)
		(mid 86.871048 -255.387311)
		(end 87.057992 -255.337056)
		(width 0.0889)
		(layer "In13.Cu")
		(net "M_B_CPU1_SA_CA<6>")
	)
	(arc
		(start 84.238084 -255.337056)
		(mid 84.52104 -255.260879)
		(end 84.803996 -255.337056)
		(width 0.0889)
		(layer "In13.Cu")
		(net "M_B_CPU1_SA_CA<6>")
	)
	(arc
		(start 83.863942 -255.337056)
		(mid 84.046193 -255.387406)
		(end 84.229702 -255.341882)
		(width 0.0889)
		(layer "In13.Cu")
		(net "M_B_CPU1_SA_CA<6>")
	)
	(arc
		(start 80.478122 -255.337056)
		(mid 80.761078 -255.260879)
		(end 81.044034 -255.337056)
		(width 0.0889)
		(layer "In13.Cu")
		(net "M_B_CPU1_SA_CA<6>")
	)
	(arc
		(start 80.10398 -255.337056)
		(mid 80.286231 -255.387406)
		(end 80.46974 -255.341882)
		(width 0.0889)
		(layer "In13.Cu")
		(net "M_B_CPU1_SA_CA<6>")
	)
	(arc
		(start 85.752432 -255.341882)
		(mid 85.93594 -255.387376)
		(end 86.118192 -255.337056)
		(width 0.0889)
		(layer "In13.Cu")
		(net "M_B_CPU1_SA_CA<6>")
	)
	(arc
		(start 86.118192 -255.337056)
		(mid 86.401148 -255.260879)
		(end 86.684104 -255.337056)
		(width 0.0889)
		(layer "In13.Cu")
		(net "M_B_CPU1_SA_CA<6>")
	)
	(arc
		(start 78.410816 -255.387602)
		(mid 78.507634 -255.374531)
		(end 78.59776 -255.336802)
		(width 0.0889)
		(layer "In13.Cu")
		(net "M_B_CPU1_SA_CA<6>")
	)
	(arc
		(start 82.357976 -255.337056)
		(mid 82.640932 -255.260879)
		(end 82.923888 -255.337056)
		(width 0.0889)
		(layer "In13.Cu")
		(net "M_B_CPU1_SA_CA<6>")
	)
	(arc
		(start 85.178138 -255.337056)
		(mid 85.461094 -255.260879)
		(end 85.74405 -255.337056)
		(width 0.0889)
		(layer "In13.Cu")
		(net "M_B_CPU1_SA_CA<6>")
	)
	(arc
		(start 87.057992 -255.337056)
		(mid 87.340948 -255.260879)
		(end 87.623904 -255.337056)
		(width 0.0889)
		(layer "In13.Cu")
		(net "M_B_CPU1_SA_CA<6>")
	)
	(segment
		(start 88.277954 -255.280414)
		(end 87.811102 -255.014476)
		(width 0.10668)
		(layer "F.Cu")
		(net "M_B_CPU1_SA_CA<5>")
	)
	(segment
		(start 72.0725 -254.246634)
		(end 73.05167 -255.225804)
		(width 0.14478)
		(layer "In13.Cu")
		(net "M_B_CPU1_SA_CA<5>")
	)
	(segment
		(start 87.560658 -254.723646)
		(end 87.656924 -254.749046)
		(width 0.0889)
		(layer "In13.Cu")
		(net "M_B_CPU1_SA_CA<5>")
	)
	(segment
		(start 85.74405 -254.691896)
		(end 85.752432 -254.68707)
		(width 0.0889)
		(layer "In13.Cu")
		(net "M_B_CPU1_SA_CA<5>")
	)
	(segment
		(start 50.469292 -252.160278)
		(end 52.731924 -252.160278)
		(width 0.14478)
		(layer "In13.Cu")
		(net "M_B_CPU1_SA_CA<5>")
	)
	(segment
		(start 73.05167 -255.225804)
		(end 75.973686 -255.225804)
		(width 0.14478)
		(layer "In13.Cu")
		(net "M_B_CPU1_SA_CA<5>")
	)
	(segment
		(start 50.04435 -251.735336)
		(end 50.469292 -252.160278)
		(width 0.14478)
		(layer "In13.Cu")
		(net "M_B_CPU1_SA_CA<5>")
	)
	(segment
		(start 87.656924 -254.749046)
		(end 87.811102 -255.014476)
		(width 0.0889)
		(layer "In13.Cu")
		(net "M_B_CPU1_SA_CA<5>")
	)
	(segment
		(start 54.431946 -253.8603)
		(end 58.320178 -253.8603)
		(width 0.14478)
		(layer "In13.Cu")
		(net "M_B_CPU1_SA_CA<5>")
	)
	(segment
		(start 81.044034 -254.691896)
		(end 81.052416 -254.68707)
		(width 0.0889)
		(layer "In13.Cu")
		(net "M_B_CPU1_SA_CA<5>")
	)
	(segment
		(start 79.143098 -254.705612)
		(end 79.166466 -254.691896)
		(width 0.0889)
		(layer "In13.Cu")
		(net "M_B_CPU1_SA_CA<5>")
	)
	(segment
		(start 77.103732 -255.225804)
		(end 77.35697 -254.972566)
		(width 0.0889)
		(layer "In13.Cu")
		(net "M_B_CPU1_SA_CA<5>")
	)
	(segment
		(start 78.225142 -254.69215)
		(end 78.252574 -254.676402)
		(width 0.0889)
		(layer "In13.Cu")
		(net "M_B_CPU1_SA_CA<5>")
	)
	(segment
		(start 75.973686 -255.225804)
		(end 77.103732 -255.225804)
		(width 0.0889)
		(layer "In13.Cu")
		(net "M_B_CPU1_SA_CA<5>")
	)
	(segment
		(start 77.35697 -254.972566)
		(end 77.926692 -254.972566)
		(width 0.0889)
		(layer "In13.Cu")
		(net "M_B_CPU1_SA_CA<5>")
	)
	(segment
		(start 79.521304 -254.681736)
		(end 79.539592 -254.69215)
		(width 0.0889)
		(layer "In13.Cu")
		(net "M_B_CPU1_SA_CA<5>")
	)
	(segment
		(start 58.320178 -253.8603)
		(end 58.706512 -254.246634)
		(width 0.14478)
		(layer "In13.Cu")
		(net "M_B_CPU1_SA_CA<5>")
	)
	(segment
		(start 58.706512 -254.246634)
		(end 72.0725 -254.246634)
		(width 0.14478)
		(layer "In13.Cu")
		(net "M_B_CPU1_SA_CA<5>")
	)
	(segment
		(start 80.46974 -254.68707)
		(end 80.478122 -254.691896)
		(width 0.0889)
		(layer "In13.Cu")
		(net "M_B_CPU1_SA_CA<5>")
	)
	(segment
		(start 77.926692 -254.972566)
		(end 78.147926 -254.751332)
		(width 0.0889)
		(layer "In13.Cu")
		(net "M_B_CPU1_SA_CA<5>")
	)
	(segment
		(start 47.784004 -251.735336)
		(end 50.04435 -251.735336)
		(width 0.14478)
		(layer "In13.Cu")
		(net "M_B_CPU1_SA_CA<5>")
	)
	(segment
		(start 84.229702 -254.68707)
		(end 84.238084 -254.691896)
		(width 0.0889)
		(layer "In13.Cu")
		(net "M_B_CPU1_SA_CA<5>")
	)
	(segment
		(start 79.539592 -254.69215)
		(end 79.561182 -254.704596)
		(width 0.0889)
		(layer "In13.Cu")
		(net "M_B_CPU1_SA_CA<5>")
	)
	(segment
		(start 52.731924 -252.160278)
		(end 54.431946 -253.8603)
		(width 0.14478)
		(layer "In13.Cu")
		(net "M_B_CPU1_SA_CA<5>")
	)
	(segment
		(start 84.803996 -254.691896)
		(end 84.812378 -254.68707)
		(width 0.0889)
		(layer "In13.Cu")
		(net "M_B_CPU1_SA_CA<5>")
	)
	(segment
		(start 83.289648 -254.68707)
		(end 83.29803 -254.691896)
		(width 0.0889)
		(layer "In13.Cu")
		(net "M_B_CPU1_SA_CA<5>")
	)
	(arc
		(start 81.418176 -254.691896)
		(mid 81.701132 -254.768073)
		(end 81.984088 -254.691896)
		(width 0.0889)
		(layer "In13.Cu")
		(net "M_B_CPU1_SA_CA<5>")
	)
	(arc
		(start 79.166466 -254.691896)
		(mid 79.342586 -254.641918)
		(end 79.521304 -254.681736)
		(width 0.0889)
		(layer "In13.Cu")
		(net "M_B_CPU1_SA_CA<5>")
	)
	(arc
		(start 85.752432 -254.68707)
		(mid 85.93594 -254.641576)
		(end 86.118192 -254.691896)
		(width 0.0889)
		(layer "In13.Cu")
		(net "M_B_CPU1_SA_CA<5>")
	)
	(arc
		(start 80.10398 -254.691896)
		(mid 80.286231 -254.641546)
		(end 80.46974 -254.68707)
		(width 0.0889)
		(layer "In13.Cu")
		(net "M_B_CPU1_SA_CA<5>")
	)
	(arc
		(start 84.812378 -254.68707)
		(mid 84.995886 -254.641576)
		(end 85.178138 -254.691896)
		(width 0.0889)
		(layer "In13.Cu")
		(net "M_B_CPU1_SA_CA<5>")
	)
	(arc
		(start 78.599284 -254.691896)
		(mid 78.869441 -254.768658)
		(end 79.143098 -254.705612)
		(width 0.0889)
		(layer "In13.Cu")
		(net "M_B_CPU1_SA_CA<5>")
	)
	(arc
		(start 85.178138 -254.691896)
		(mid 85.461094 -254.768073)
		(end 85.74405 -254.691896)
		(width 0.0889)
		(layer "In13.Cu")
		(net "M_B_CPU1_SA_CA<5>")
	)
	(arc
		(start 87.057992 -254.691896)
		(mid 87.305588 -254.767074)
		(end 87.560658 -254.723646)
		(width 0.0889)
		(layer "In13.Cu")
		(net "M_B_CPU1_SA_CA<5>")
	)
	(arc
		(start 86.684104 -254.691896)
		(mid 86.871048 -254.641641)
		(end 87.057992 -254.691896)
		(width 0.0889)
		(layer "In13.Cu")
		(net "M_B_CPU1_SA_CA<5>")
	)
	(arc
		(start 83.29803 -254.691896)
		(mid 83.580986 -254.768073)
		(end 83.863942 -254.691896)
		(width 0.0889)
		(layer "In13.Cu")
		(net "M_B_CPU1_SA_CA<5>")
	)
	(arc
		(start 86.118192 -254.691896)
		(mid 86.401148 -254.768073)
		(end 86.684104 -254.691896)
		(width 0.0889)
		(layer "In13.Cu")
		(net "M_B_CPU1_SA_CA<5>")
	)
	(arc
		(start 81.984088 -254.691896)
		(mid 82.171032 -254.641641)
		(end 82.357976 -254.691896)
		(width 0.0889)
		(layer "In13.Cu")
		(net "M_B_CPU1_SA_CA<5>")
	)
	(arc
		(start 82.923888 -254.691896)
		(mid 83.106139 -254.641546)
		(end 83.289648 -254.68707)
		(width 0.0889)
		(layer "In13.Cu")
		(net "M_B_CPU1_SA_CA<5>")
	)
	(arc
		(start 83.863942 -254.691896)
		(mid 84.046193 -254.641546)
		(end 84.229702 -254.68707)
		(width 0.0889)
		(layer "In13.Cu")
		(net "M_B_CPU1_SA_CA<5>")
	)
	(arc
		(start 78.252574 -254.676402)
		(mid 78.427825 -254.641469)
		(end 78.599284 -254.691896)
		(width 0.0889)
		(layer "In13.Cu")
		(net "M_B_CPU1_SA_CA<5>")
	)
	(arc
		(start 78.147926 -254.751332)
		(mid 78.184582 -254.719192)
		(end 78.225142 -254.69215)
		(width 0.0889)
		(layer "In13.Cu")
		(net "M_B_CPU1_SA_CA<5>")
	)
	(arc
		(start 80.478122 -254.691896)
		(mid 80.761078 -254.768073)
		(end 81.044034 -254.691896)
		(width 0.0889)
		(layer "In13.Cu")
		(net "M_B_CPU1_SA_CA<5>")
	)
	(arc
		(start 81.052416 -254.68707)
		(mid 81.235924 -254.641576)
		(end 81.418176 -254.691896)
		(width 0.0889)
		(layer "In13.Cu")
		(net "M_B_CPU1_SA_CA<5>")
	)
	(arc
		(start 84.238084 -254.691896)
		(mid 84.52104 -254.768073)
		(end 84.803996 -254.691896)
		(width 0.0889)
		(layer "In13.Cu")
		(net "M_B_CPU1_SA_CA<5>")
	)
	(arc
		(start 82.357976 -254.691896)
		(mid 82.640932 -254.768073)
		(end 82.923888 -254.691896)
		(width 0.0889)
		(layer "In13.Cu")
		(net "M_B_CPU1_SA_CA<5>")
	)
	(arc
		(start 79.561182 -254.704596)
		(mid 79.834211 -254.767915)
		(end 80.10398 -254.691896)
		(width 0.0889)
		(layer "In13.Cu")
		(net "M_B_CPU1_SA_CA<5>")
	)
	(segment
		(start 87.8078 -254.470408)
		(end 87.340948 -254.20447)
		(width 0.10668)
		(layer "F.Cu")
		(net "M_B_CPU1_SA_CA<4>")
	)
	(segment
		(start 79.634842 -254.526796)
		(end 79.613252 -254.51435)
		(width 0.0889)
		(layer "In13.Cu")
		(net "M_B_CPU1_SA_CA<4>")
	)
	(segment
		(start 53.647848 -252.204728)
		(end 53.462682 -252.019562)
		(width 0.14478)
		(layer "In13.Cu")
		(net "M_B_CPU1_SA_CA<4>")
	)
	(segment
		(start 53.462682 -252.019562)
		(end 53.462682 -251.814838)
		(width 0.14478)
		(layer "In13.Cu")
		(net "M_B_CPU1_SA_CA<4>")
	)
	(segment
		(start 77.088238 -254.839724)
		(end 76.451968 -254.839724)
		(width 0.0889)
		(layer "In13.Cu")
		(net "M_B_CPU1_SA_CA<4>")
	)
	(segment
		(start 56.611012 -253.154942)
		(end 56.611012 -253.249684)
		(width 0.14478)
		(layer "In13.Cu")
		(net "M_B_CPU1_SA_CA<4>")
	)
	(segment
		(start 58.119772 -253.010162)
		(end 57.858152 -253.010162)
		(width 0.14478)
		(layer "In13.Cu")
		(net "M_B_CPU1_SA_CA<4>")
	)
	(segment
		(start 57.858152 -253.010162)
		(end 57.713372 -253.154942)
		(width 0.14478)
		(layer "In13.Cu")
		(net "M_B_CPU1_SA_CA<4>")
	)
	(segment
		(start 54.242462 -252.799342)
		(end 54.242462 -252.594618)
		(width 0.14478)
		(layer "In13.Cu")
		(net "M_B_CPU1_SA_CA<4>")
	)
	(segment
		(start 60.602622 -253.791974)
		(end 59.82081 -253.010162)
		(width 0.14478)
		(layer "In13.Cu")
		(net "M_B_CPU1_SA_CA<4>")
	)
	(segment
		(start 58.815732 -253.154942)
		(end 58.815732 -253.249684)
		(width 0.14478)
		(layer "In13.Cu")
		(net "M_B_CPU1_SA_CA<4>")
	)
	(segment
		(start 58.264552 -253.249684)
		(end 58.264552 -253.154942)
		(width 0.14478)
		(layer "In13.Cu")
		(net "M_B_CPU1_SA_CA<4>")
	)
	(segment
		(start 58.409332 -253.394464)
		(end 58.264552 -253.249684)
		(width 0.14478)
		(layer "In13.Cu")
		(net "M_B_CPU1_SA_CA<4>")
	)
	(segment
		(start 57.017412 -253.010162)
		(end 56.755792 -253.010162)
		(width 0.14478)
		(layer "In13.Cu")
		(net "M_B_CPU1_SA_CA<4>")
	)
	(segment
		(start 56.611012 -253.249684)
		(end 56.466232 -253.394464)
		(width 0.14478)
		(layer "In13.Cu")
		(net "M_B_CPU1_SA_CA<4>")
	)
	(segment
		(start 54.957472 -253.154942)
		(end 54.812692 -253.010162)
		(width 0.14478)
		(layer "In13.Cu")
		(net "M_B_CPU1_SA_CA<4>")
	)
	(segment
		(start 77.217016 -254.710946)
		(end 77.088238 -254.839724)
		(width 0.0889)
		(layer "In13.Cu")
		(net "M_B_CPU1_SA_CA<4>")
	)
	(segment
		(start 53.128926 -251.368814)
		(end 53.072792 -251.424948)
		(width 0.14478)
		(layer "In13.Cu")
		(net "M_B_CPU1_SA_CA<4>")
	)
	(segment
		(start 57.306972 -253.394464)
		(end 57.162192 -253.249684)
		(width 0.14478)
		(layer "In13.Cu")
		(net "M_B_CPU1_SA_CA<4>")
	)
	(segment
		(start 56.755792 -253.010162)
		(end 56.611012 -253.154942)
		(width 0.14478)
		(layer "In13.Cu")
		(net "M_B_CPU1_SA_CA<4>")
	)
	(segment
		(start 53.518816 -251.55398)
		(end 53.33365 -251.368814)
		(width 0.14478)
		(layer "In13.Cu")
		(net "M_B_CPU1_SA_CA<4>")
	)
	(segment
		(start 56.466232 -253.394464)
		(end 56.204612 -253.394464)
		(width 0.14478)
		(layer "In13.Cu")
		(net "M_B_CPU1_SA_CA<4>")
	)
	(segment
		(start 56.204612 -253.394464)
		(end 56.059832 -253.249684)
		(width 0.14478)
		(layer "In13.Cu")
		(net "M_B_CPU1_SA_CA<4>")
	)
	(segment
		(start 76.451968 -254.839724)
		(end 76.373228 -254.760984)
		(width 0.0889)
		(layer "In13.Cu")
		(net "M_B_CPU1_SA_CA<4>")
	)
	(segment
		(start 55.363872 -253.394464)
		(end 55.102252 -253.394464)
		(width 0.14478)
		(layer "In13.Cu")
		(net "M_B_CPU1_SA_CA<4>")
	)
	(segment
		(start 86.588092 -254.52705)
		(end 86.57971 -254.531876)
		(width 0.0889)
		(layer "In13.Cu")
		(net "M_B_CPU1_SA_CA<4>")
	)
	(segment
		(start 54.242462 -252.594618)
		(end 54.298596 -252.538484)
		(width 0.14478)
		(layer "In13.Cu")
		(net "M_B_CPU1_SA_CA<4>")
	)
	(segment
		(start 76.263246 -254.760984)
		(end 73.270618 -254.760984)
		(width 0.14478)
		(layer "In13.Cu")
		(net "M_B_CPU1_SA_CA<4>")
	)
	(segment
		(start 53.462682 -251.814838)
		(end 53.518816 -251.758704)
		(width 0.14478)
		(layer "In13.Cu")
		(net "M_B_CPU1_SA_CA<4>")
	)
	(segment
		(start 58.815732 -253.249684)
		(end 58.670952 -253.394464)
		(width 0.14478)
		(layer "In13.Cu")
		(net "M_B_CPU1_SA_CA<4>")
	)
	(segment
		(start 54.298596 -252.33376)
		(end 54.11343 -252.148594)
		(width 0.14478)
		(layer "In13.Cu")
		(net "M_B_CPU1_SA_CA<4>")
	)
	(segment
		(start 57.162192 -253.249684)
		(end 57.162192 -253.154942)
		(width 0.14478)
		(layer "In13.Cu")
		(net "M_B_CPU1_SA_CA<4>")
	)
	(segment
		(start 59.82081 -253.010162)
		(end 58.960512 -253.010162)
		(width 0.14478)
		(layer "In13.Cu")
		(net "M_B_CPU1_SA_CA<4>")
	)
	(segment
		(start 58.960512 -253.010162)
		(end 58.815732 -253.154942)
		(width 0.14478)
		(layer "In13.Cu")
		(net "M_B_CPU1_SA_CA<4>")
	)
	(segment
		(start 76.373228 -254.760984)
		(end 76.263246 -254.760984)
		(width 0.0889)
		(layer "In13.Cu")
		(net "M_B_CPU1_SA_CA<4>")
	)
	(segment
		(start 56.059832 -253.249684)
		(end 56.059832 -253.154942)
		(width 0.14478)
		(layer "In13.Cu")
		(net "M_B_CPU1_SA_CA<4>")
	)
	(segment
		(start 55.102252 -253.394464)
		(end 54.957472 -253.249684)
		(width 0.14478)
		(layer "In13.Cu")
		(net "M_B_CPU1_SA_CA<4>")
	)
	(segment
		(start 53.852572 -252.204728)
		(end 53.647848 -252.204728)
		(width 0.14478)
		(layer "In13.Cu")
		(net "M_B_CPU1_SA_CA<4>")
	)
	(segment
		(start 82.46237 -254.531876)
		(end 82.453988 -254.52705)
		(width 0.0889)
		(layer "In13.Cu")
		(net "M_B_CPU1_SA_CA<4>")
	)
	(segment
		(start 83.402424 -254.531876)
		(end 83.394042 -254.52705)
		(width 0.0889)
		(layer "In13.Cu")
		(net "M_B_CPU1_SA_CA<4>")
	)
	(segment
		(start 57.162192 -253.154942)
		(end 57.017412 -253.010162)
		(width 0.14478)
		(layer "In13.Cu")
		(net "M_B_CPU1_SA_CA<4>")
	)
	(segment
		(start 53.33365 -251.368814)
		(end 53.128926 -251.368814)
		(width 0.14478)
		(layer "In13.Cu")
		(net "M_B_CPU1_SA_CA<4>")
	)
	(segment
		(start 58.264552 -253.154942)
		(end 58.119772 -253.010162)
		(width 0.14478)
		(layer "In13.Cu")
		(net "M_B_CPU1_SA_CA<4>")
	)
	(segment
		(start 54.11343 -252.148594)
		(end 53.908706 -252.148594)
		(width 0.14478)
		(layer "In13.Cu")
		(net "M_B_CPU1_SA_CA<4>")
	)
	(segment
		(start 53.518816 -251.758704)
		(end 53.518816 -251.55398)
		(width 0.14478)
		(layer "In13.Cu")
		(net "M_B_CPU1_SA_CA<4>")
	)
	(segment
		(start 87.340948 -254.20447)
		(end 87.495126 -254.4699)
		(width 0.0889)
		(layer "In13.Cu")
		(net "M_B_CPU1_SA_CA<4>")
	)
	(segment
		(start 77.918564 -254.710946)
		(end 77.217016 -254.710946)
		(width 0.0889)
		(layer "In13.Cu")
		(net "M_B_CPU1_SA_CA<4>")
	)
	(segment
		(start 79.070454 -254.52705)
		(end 79.051658 -254.537972)
		(width 0.0889)
		(layer "In13.Cu")
		(net "M_B_CPU1_SA_CA<4>")
	)
	(segment
		(start 55.508652 -253.154942)
		(end 55.508652 -253.249684)
		(width 0.14478)
		(layer "In13.Cu")
		(net "M_B_CPU1_SA_CA<4>")
	)
	(segment
		(start 52.690268 -251.247148)
		(end 52.246022 -251.247148)
		(width 0.14478)
		(layer "In13.Cu")
		(net "M_B_CPU1_SA_CA<4>")
	)
	(segment
		(start 58.670952 -253.394464)
		(end 58.409332 -253.394464)
		(width 0.14478)
		(layer "In13.Cu")
		(net "M_B_CPU1_SA_CA<4>")
	)
	(segment
		(start 87.162386 -254.531876)
		(end 87.154004 -254.52705)
		(width 0.0889)
		(layer "In13.Cu")
		(net "M_B_CPU1_SA_CA<4>")
	)
	(segment
		(start 57.713372 -253.249684)
		(end 57.568592 -253.394464)
		(width 0.14478)
		(layer "In13.Cu")
		(net "M_B_CPU1_SA_CA<4>")
	)
	(segment
		(start 85.648038 -254.52705)
		(end 85.639656 -254.531876)
		(width 0.0889)
		(layer "In13.Cu")
		(net "M_B_CPU1_SA_CA<4>")
	)
	(segment
		(start 78.013052 -254.616458)
		(end 77.918564 -254.710946)
		(width 0.0889)
		(layer "In13.Cu")
		(net "M_B_CPU1_SA_CA<4>")
	)
	(segment
		(start 53.908706 -252.148594)
		(end 53.852572 -252.204728)
		(width 0.14478)
		(layer "In13.Cu")
		(net "M_B_CPU1_SA_CA<4>")
	)
	(segment
		(start 52.868068 -251.424948)
		(end 52.690268 -251.247148)
		(width 0.14478)
		(layer "In13.Cu")
		(net "M_B_CPU1_SA_CA<4>")
	)
	(segment
		(start 73.270618 -254.760984)
		(end 72.301608 -253.791974)
		(width 0.14478)
		(layer "In13.Cu")
		(net "M_B_CPU1_SA_CA<4>")
	)
	(segment
		(start 79.654908 -254.538226)
		(end 79.634842 -254.526796)
		(width 0.0889)
		(layer "In13.Cu")
		(net "M_B_CPU1_SA_CA<4>")
	)
	(segment
		(start 55.915052 -253.010162)
		(end 55.653432 -253.010162)
		(width 0.14478)
		(layer "In13.Cu")
		(net "M_B_CPU1_SA_CA<4>")
	)
	(segment
		(start 55.508652 -253.249684)
		(end 55.363872 -253.394464)
		(width 0.14478)
		(layer "In13.Cu")
		(net "M_B_CPU1_SA_CA<4>")
	)
	(segment
		(start 52.246022 -251.247148)
		(end 51.884072 -250.885198)
		(width 0.14478)
		(layer "In13.Cu")
		(net "M_B_CPU1_SA_CA<4>")
	)
	(segment
		(start 54.298596 -252.538484)
		(end 54.298596 -252.33376)
		(width 0.14478)
		(layer "In13.Cu")
		(net "M_B_CPU1_SA_CA<4>")
	)
	(segment
		(start 54.812692 -253.010162)
		(end 54.453282 -253.010162)
		(width 0.14478)
		(layer "In13.Cu")
		(net "M_B_CPU1_SA_CA<4>")
	)
	(segment
		(start 87.495126 -254.4699)
		(end 87.472774 -254.553212)
		(width 0.0889)
		(layer "In13.Cu")
		(net "M_B_CPU1_SA_CA<4>")
	)
	(segment
		(start 72.301608 -253.791974)
		(end 60.602622 -253.791974)
		(width 0.14478)
		(layer "In13.Cu")
		(net "M_B_CPU1_SA_CA<4>")
	)
	(segment
		(start 54.453282 -253.010162)
		(end 54.242462 -252.799342)
		(width 0.14478)
		(layer "In13.Cu")
		(net "M_B_CPU1_SA_CA<4>")
	)
	(segment
		(start 53.072792 -251.424948)
		(end 52.868068 -251.424948)
		(width 0.14478)
		(layer "In13.Cu")
		(net "M_B_CPU1_SA_CA<4>")
	)
	(segment
		(start 56.059832 -253.154942)
		(end 55.915052 -253.010162)
		(width 0.14478)
		(layer "In13.Cu")
		(net "M_B_CPU1_SA_CA<4>")
	)
	(segment
		(start 57.713372 -253.154942)
		(end 57.713372 -253.249684)
		(width 0.14478)
		(layer "In13.Cu")
		(net "M_B_CPU1_SA_CA<4>")
	)
	(segment
		(start 54.957472 -253.249684)
		(end 54.957472 -253.154942)
		(width 0.14478)
		(layer "In13.Cu")
		(net "M_B_CPU1_SA_CA<4>")
	)
	(segment
		(start 78.161388 -254.508508)
		(end 78.129638 -254.526796)
		(width 0.0889)
		(layer "In13.Cu")
		(net "M_B_CPU1_SA_CA<4>")
	)
	(segment
		(start 57.568592 -253.394464)
		(end 57.306972 -253.394464)
		(width 0.14478)
		(layer "In13.Cu")
		(net "M_B_CPU1_SA_CA<4>")
	)
	(segment
		(start 81.888076 -254.52705)
		(end 81.879694 -254.531876)
		(width 0.0889)
		(layer "In13.Cu")
		(net "M_B_CPU1_SA_CA<4>")
	)
	(segment
		(start 55.653432 -253.010162)
		(end 55.508652 -253.154942)
		(width 0.14478)
		(layer "In13.Cu")
		(net "M_B_CPU1_SA_CA<4>")
	)
	(arc
		(start 87.154004 -254.52705)
		(mid 86.871048 -254.450873)
		(end 86.588092 -254.52705)
		(width 0.0889)
		(layer "In13.Cu")
		(net "M_B_CPU1_SA_CA<4>")
	)
	(arc
		(start 81.879694 -254.531876)
		(mid 81.696186 -254.57737)
		(end 81.513934 -254.52705)
		(width 0.0889)
		(layer "In13.Cu")
		(net "M_B_CPU1_SA_CA<4>")
	)
	(arc
		(start 83.768184 -254.52705)
		(mid 83.585933 -254.5774)
		(end 83.402424 -254.531876)
		(width 0.0889)
		(layer "In13.Cu")
		(net "M_B_CPU1_SA_CA<4>")
	)
	(arc
		(start 82.82813 -254.52705)
		(mid 82.645879 -254.5774)
		(end 82.46237 -254.531876)
		(width 0.0889)
		(layer "In13.Cu")
		(net "M_B_CPU1_SA_CA<4>")
	)
	(arc
		(start 81.513934 -254.52705)
		(mid 81.230978 -254.450873)
		(end 80.948022 -254.52705)
		(width 0.0889)
		(layer "In13.Cu")
		(net "M_B_CPU1_SA_CA<4>")
	)
	(arc
		(start 84.334096 -254.52705)
		(mid 84.05114 -254.450873)
		(end 83.768184 -254.52705)
		(width 0.0889)
		(layer "In13.Cu")
		(net "M_B_CPU1_SA_CA<4>")
	)
	(arc
		(start 85.273896 -254.52705)
		(mid 84.99094 -254.450873)
		(end 84.707984 -254.52705)
		(width 0.0889)
		(layer "In13.Cu")
		(net "M_B_CPU1_SA_CA<4>")
	)
	(arc
		(start 86.21395 -254.52705)
		(mid 85.930994 -254.450873)
		(end 85.648038 -254.52705)
		(width 0.0889)
		(layer "In13.Cu")
		(net "M_B_CPU1_SA_CA<4>")
	)
	(arc
		(start 78.129638 -254.526796)
		(mid 78.068407 -254.567806)
		(end 78.013052 -254.616458)
		(width 0.0889)
		(layer "In13.Cu")
		(net "M_B_CPU1_SA_CA<4>")
	)
	(arc
		(start 78.695296 -254.52705)
		(mid 78.430673 -254.450575)
		(end 78.161388 -254.508508)
		(width 0.0889)
		(layer "In13.Cu")
		(net "M_B_CPU1_SA_CA<4>")
	)
	(arc
		(start 80.008222 -254.52705)
		(mid 79.832983 -254.577121)
		(end 79.654908 -254.538226)
		(width 0.0889)
		(layer "In13.Cu")
		(net "M_B_CPU1_SA_CA<4>")
	)
	(arc
		(start 83.394042 -254.52705)
		(mid 83.111086 -254.450873)
		(end 82.82813 -254.52705)
		(width 0.0889)
		(layer "In13.Cu")
		(net "M_B_CPU1_SA_CA<4>")
	)
	(arc
		(start 85.639656 -254.531876)
		(mid 85.456148 -254.57737)
		(end 85.273896 -254.52705)
		(width 0.0889)
		(layer "In13.Cu")
		(net "M_B_CPU1_SA_CA<4>")
	)
	(arc
		(start 86.57971 -254.531876)
		(mid 86.396202 -254.57737)
		(end 86.21395 -254.52705)
		(width 0.0889)
		(layer "In13.Cu")
		(net "M_B_CPU1_SA_CA<4>")
	)
	(arc
		(start 80.948022 -254.52705)
		(mid 80.761078 -254.577305)
		(end 80.574134 -254.52705)
		(width 0.0889)
		(layer "In13.Cu")
		(net "M_B_CPU1_SA_CA<4>")
	)
	(arc
		(start 79.051658 -254.537972)
		(mid 78.872087 -254.577789)
		(end 78.695296 -254.52705)
		(width 0.0889)
		(layer "In13.Cu")
		(net "M_B_CPU1_SA_CA<4>")
	)
	(arc
		(start 79.613252 -254.51435)
		(mid 79.340223 -254.451031)
		(end 79.070454 -254.52705)
		(width 0.0889)
		(layer "In13.Cu")
		(net "M_B_CPU1_SA_CA<4>")
	)
	(arc
		(start 80.574134 -254.52705)
		(mid 80.291178 -254.450873)
		(end 80.008222 -254.52705)
		(width 0.0889)
		(layer "In13.Cu")
		(net "M_B_CPU1_SA_CA<4>")
	)
	(arc
		(start 87.472774 -254.553212)
		(mid 87.315264 -254.57641)
		(end 87.162386 -254.531876)
		(width 0.0889)
		(layer "In13.Cu")
		(net "M_B_CPU1_SA_CA<4>")
	)
	(arc
		(start 84.707984 -254.52705)
		(mid 84.52104 -254.577305)
		(end 84.334096 -254.52705)
		(width 0.0889)
		(layer "In13.Cu")
		(net "M_B_CPU1_SA_CA<4>")
	)
	(arc
		(start 82.453988 -254.52705)
		(mid 82.171032 -254.450873)
		(end 81.888076 -254.52705)
		(width 0.0889)
		(layer "In13.Cu")
		(net "M_B_CPU1_SA_CA<4>")
	)
	(segment
		(start 89.687908 -254.470408)
		(end 89.221056 -254.20447)
		(width 0.10668)
		(layer "F.Cu")
		(net "M_B_CPU1_SA_CA<3>")
	)
	(segment
		(start 85.639656 -253.877064)
		(end 85.648038 -253.88189)
		(width 0.0889)
		(layer "In13.Cu")
		(net "M_B_CPU1_SA_CA<3>")
	)
	(segment
		(start 50.008028 -250.035314)
		(end 50.43297 -250.460256)
		(width 0.14478)
		(layer "In13.Cu")
		(net "M_B_CPU1_SA_CA<3>")
	)
	(segment
		(start 76.49591 -254.081026)
		(end 77.013562 -254.081026)
		(width 0.0889)
		(layer "In13.Cu")
		(net "M_B_CPU1_SA_CA<3>")
	)
	(segment
		(start 59.606942 -252.160278)
		(end 60.783978 -253.337314)
		(width 0.14478)
		(layer "In13.Cu")
		(net "M_B_CPU1_SA_CA<3>")
	)
	(segment
		(start 83.394042 -253.88189)
		(end 83.402424 -253.877064)
		(width 0.0889)
		(layer "In13.Cu")
		(net "M_B_CPU1_SA_CA<3>")
	)
	(segment
		(start 54.907434 -252.160278)
		(end 59.606942 -252.160278)
		(width 0.14478)
		(layer "In13.Cu")
		(net "M_B_CPU1_SA_CA<3>")
	)
	(segment
		(start 73.454006 -254.301244)
		(end 75.955906 -254.301244)
		(width 0.14478)
		(layer "In13.Cu")
		(net "M_B_CPU1_SA_CA<3>")
	)
	(segment
		(start 76.275692 -254.301244)
		(end 76.49591 -254.081026)
		(width 0.0889)
		(layer "In13.Cu")
		(net "M_B_CPU1_SA_CA<3>")
	)
	(segment
		(start 78.693518 -253.882144)
		(end 78.709774 -253.872746)
		(width 0.0889)
		(layer "In13.Cu")
		(net "M_B_CPU1_SA_CA<3>")
	)
	(segment
		(start 82.453988 -253.88189)
		(end 82.46237 -253.877064)
		(width 0.0889)
		(layer "In13.Cu")
		(net "M_B_CPU1_SA_CA<3>")
	)
	(segment
		(start 81.879694 -253.877064)
		(end 81.888076 -253.88189)
		(width 0.0889)
		(layer "In13.Cu")
		(net "M_B_CPU1_SA_CA<3>")
	)
	(segment
		(start 89.067132 -253.93904)
		(end 89.221056 -254.20447)
		(width 0.0889)
		(layer "In13.Cu")
		(net "M_B_CPU1_SA_CA<3>")
	)
	(segment
		(start 79.99984 -253.877064)
		(end 80.008222 -253.88189)
		(width 0.0889)
		(layer "In13.Cu")
		(net "M_B_CPU1_SA_CA<3>")
	)
	(segment
		(start 77.75321 -253.88189)
		(end 77.764894 -253.875032)
		(width 0.0889)
		(layer "In13.Cu")
		(net "M_B_CPU1_SA_CA<3>")
	)
	(segment
		(start 53.207412 -250.460256)
		(end 54.907434 -252.160278)
		(width 0.14478)
		(layer "In13.Cu")
		(net "M_B_CPU1_SA_CA<3>")
	)
	(segment
		(start 50.43297 -250.460256)
		(end 53.207412 -250.460256)
		(width 0.14478)
		(layer "In13.Cu")
		(net "M_B_CPU1_SA_CA<3>")
	)
	(segment
		(start 47.784004 -250.035314)
		(end 50.008028 -250.035314)
		(width 0.14478)
		(layer "In13.Cu")
		(net "M_B_CPU1_SA_CA<3>")
	)
	(segment
		(start 75.955906 -254.301244)
		(end 76.275692 -254.301244)
		(width 0.0889)
		(layer "In13.Cu")
		(net "M_B_CPU1_SA_CA<3>")
	)
	(segment
		(start 87.154004 -253.88189)
		(end 87.162386 -253.877064)
		(width 0.0889)
		(layer "In13.Cu")
		(net "M_B_CPU1_SA_CA<3>")
	)
	(segment
		(start 79.067406 -253.88189)
		(end 79.07782 -253.887986)
		(width 0.0889)
		(layer "In13.Cu")
		(net "M_B_CPU1_SA_CA<3>")
	)
	(segment
		(start 88.094058 -253.88189)
		(end 88.10244 -253.877064)
		(width 0.0889)
		(layer "In13.Cu")
		(net "M_B_CPU1_SA_CA<3>")
	)
	(segment
		(start 72.490076 -253.337314)
		(end 73.454006 -254.301244)
		(width 0.14478)
		(layer "In13.Cu")
		(net "M_B_CPU1_SA_CA<3>")
	)
	(segment
		(start 88.97112 -253.91364)
		(end 89.067132 -253.93904)
		(width 0.0889)
		(layer "In13.Cu")
		(net "M_B_CPU1_SA_CA<3>")
	)
	(segment
		(start 78.67777 -253.891288)
		(end 78.693518 -253.882144)
		(width 0.0889)
		(layer "In13.Cu")
		(net "M_B_CPU1_SA_CA<3>")
	)
	(segment
		(start 60.783978 -253.337314)
		(end 72.490076 -253.337314)
		(width 0.14478)
		(layer "In13.Cu")
		(net "M_B_CPU1_SA_CA<3>")
	)
	(segment
		(start 86.57971 -253.877064)
		(end 86.588092 -253.88189)
		(width 0.0889)
		(layer "In13.Cu")
		(net "M_B_CPU1_SA_CA<3>")
	)
	(arc
		(start 78.709774 -253.872746)
		(mid 78.889756 -253.831646)
		(end 79.067406 -253.88189)
		(width 0.0889)
		(layer "In13.Cu")
		(net "M_B_CPU1_SA_CA<3>")
	)
	(arc
		(start 86.21395 -253.88189)
		(mid 86.396201 -253.83154)
		(end 86.57971 -253.877064)
		(width 0.0889)
		(layer "In13.Cu")
		(net "M_B_CPU1_SA_CA<3>")
	)
	(arc
		(start 81.513934 -253.88189)
		(mid 81.696185 -253.83154)
		(end 81.879694 -253.877064)
		(width 0.0889)
		(layer "In13.Cu")
		(net "M_B_CPU1_SA_CA<3>")
	)
	(arc
		(start 79.07782 -253.887986)
		(mid 79.356506 -253.958206)
		(end 79.633572 -253.88189)
		(width 0.0889)
		(layer "In13.Cu")
		(net "M_B_CPU1_SA_CA<3>")
	)
	(arc
		(start 81.888076 -253.88189)
		(mid 82.171032 -253.958067)
		(end 82.453988 -253.88189)
		(width 0.0889)
		(layer "In13.Cu")
		(net "M_B_CPU1_SA_CA<3>")
	)
	(arc
		(start 77.013562 -254.081026)
		(mid 77.396555 -254.030371)
		(end 77.75321 -253.88189)
		(width 0.0889)
		(layer "In13.Cu")
		(net "M_B_CPU1_SA_CA<3>")
	)
	(arc
		(start 82.82813 -253.88189)
		(mid 83.111086 -253.958067)
		(end 83.394042 -253.88189)
		(width 0.0889)
		(layer "In13.Cu")
		(net "M_B_CPU1_SA_CA<3>")
	)
	(arc
		(start 80.574134 -253.88189)
		(mid 80.761078 -253.831635)
		(end 80.948022 -253.88189)
		(width 0.0889)
		(layer "In13.Cu")
		(net "M_B_CPU1_SA_CA<3>")
	)
	(arc
		(start 88.10244 -253.877064)
		(mid 88.285948 -253.83157)
		(end 88.4682 -253.88189)
		(width 0.0889)
		(layer "In13.Cu")
		(net "M_B_CPU1_SA_CA<3>")
	)
	(arc
		(start 87.528146 -253.88189)
		(mid 87.811102 -253.958067)
		(end 88.094058 -253.88189)
		(width 0.0889)
		(layer "In13.Cu")
		(net "M_B_CPU1_SA_CA<3>")
	)
	(arc
		(start 84.707984 -253.88189)
		(mid 84.99094 -253.958067)
		(end 85.273896 -253.88189)
		(width 0.0889)
		(layer "In13.Cu")
		(net "M_B_CPU1_SA_CA<3>")
	)
	(arc
		(start 88.4682 -253.88189)
		(mid 88.715913 -253.95711)
		(end 88.97112 -253.91364)
		(width 0.0889)
		(layer "In13.Cu")
		(net "M_B_CPU1_SA_CA<3>")
	)
	(arc
		(start 82.46237 -253.877064)
		(mid 82.645878 -253.83157)
		(end 82.82813 -253.88189)
		(width 0.0889)
		(layer "In13.Cu")
		(net "M_B_CPU1_SA_CA<3>")
	)
	(arc
		(start 78.127606 -253.88189)
		(mid 78.401461 -253.95824)
		(end 78.67777 -253.891288)
		(width 0.0889)
		(layer "In13.Cu")
		(net "M_B_CPU1_SA_CA<3>")
	)
	(arc
		(start 83.768184 -253.88189)
		(mid 84.05114 -253.958067)
		(end 84.334096 -253.88189)
		(width 0.0889)
		(layer "In13.Cu")
		(net "M_B_CPU1_SA_CA<3>")
	)
	(arc
		(start 87.162386 -253.877064)
		(mid 87.345894 -253.83157)
		(end 87.528146 -253.88189)
		(width 0.0889)
		(layer "In13.Cu")
		(net "M_B_CPU1_SA_CA<3>")
	)
	(arc
		(start 83.402424 -253.877064)
		(mid 83.585932 -253.83157)
		(end 83.768184 -253.88189)
		(width 0.0889)
		(layer "In13.Cu")
		(net "M_B_CPU1_SA_CA<3>")
	)
	(arc
		(start 80.948022 -253.88189)
		(mid 81.230978 -253.958067)
		(end 81.513934 -253.88189)
		(width 0.0889)
		(layer "In13.Cu")
		(net "M_B_CPU1_SA_CA<3>")
	)
	(arc
		(start 84.334096 -253.88189)
		(mid 84.52104 -253.831635)
		(end 84.707984 -253.88189)
		(width 0.0889)
		(layer "In13.Cu")
		(net "M_B_CPU1_SA_CA<3>")
	)
	(arc
		(start 86.588092 -253.88189)
		(mid 86.871048 -253.958067)
		(end 87.154004 -253.88189)
		(width 0.0889)
		(layer "In13.Cu")
		(net "M_B_CPU1_SA_CA<3>")
	)
	(arc
		(start 85.273896 -253.88189)
		(mid 85.456147 -253.83154)
		(end 85.639656 -253.877064)
		(width 0.0889)
		(layer "In13.Cu")
		(net "M_B_CPU1_SA_CA<3>")
	)
	(arc
		(start 80.008222 -253.88189)
		(mid 80.291178 -253.958067)
		(end 80.574134 -253.88189)
		(width 0.0889)
		(layer "In13.Cu")
		(net "M_B_CPU1_SA_CA<3>")
	)
	(arc
		(start 77.764894 -253.875032)
		(mid 77.947149 -253.831379)
		(end 78.127606 -253.88189)
		(width 0.0889)
		(layer "In13.Cu")
		(net "M_B_CPU1_SA_CA<3>")
	)
	(arc
		(start 79.633572 -253.88189)
		(mid 79.816077 -253.831413)
		(end 79.99984 -253.877064)
		(width 0.0889)
		(layer "In13.Cu")
		(net "M_B_CPU1_SA_CA<3>")
	)
	(arc
		(start 85.648038 -253.88189)
		(mid 85.930994 -253.958067)
		(end 86.21395 -253.88189)
		(width 0.0889)
		(layer "In13.Cu")
		(net "M_B_CPU1_SA_CA<3>")
	)
	(segment
		(start 89.218008 -253.660402)
		(end 88.751156 -253.394464)
		(width 0.10668)
		(layer "F.Cu")
		(net "M_B_CPU1_SA_CA<2>")
	)
	(segment
		(start 88.90508 -253.659894)
		(end 88.751156 -253.394464)
		(width 0.0889)
		(layer "In13.Cu")
		(net "M_B_CPU1_SA_CA<2>")
	)
	(segment
		(start 76.321666 -253.76759)
		(end 77.469746 -253.76759)
		(width 0.0889)
		(layer "In13.Cu")
		(net "M_B_CPU1_SA_CA<2>")
	)
	(segment
		(start 56.761126 -251.45492)
		(end 56.761126 -251.52223)
		(width 0.14478)
		(layer "In13.Cu")
		(net "M_B_CPU1_SA_CA<2>")
	)
	(segment
		(start 85.74405 -253.717044)
		(end 85.752432 -253.72187)
		(width 0.0889)
		(layer "In13.Cu")
		(net "M_B_CPU1_SA_CA<2>")
	)
	(segment
		(start 55.658766 -251.52223)
		(end 55.803546 -251.66701)
		(width 0.14478)
		(layer "In13.Cu")
		(net "M_B_CPU1_SA_CA<2>")
	)
	(segment
		(start 58.414666 -251.52223)
		(end 58.414666 -251.45492)
		(width 0.14478)
		(layer "In13.Cu")
		(net "M_B_CPU1_SA_CA<2>")
	)
	(segment
		(start 56.209946 -251.52223)
		(end 56.209946 -251.45492)
		(width 0.14478)
		(layer "In13.Cu")
		(net "M_B_CPU1_SA_CA<2>")
	)
	(segment
		(start 55.803546 -251.66701)
		(end 56.065166 -251.66701)
		(width 0.14478)
		(layer "In13.Cu")
		(net "M_B_CPU1_SA_CA<2>")
	)
	(segment
		(start 80.093566 -253.710948)
		(end 80.10398 -253.717044)
		(width 0.0889)
		(layer "In13.Cu")
		(net "M_B_CPU1_SA_CA<2>")
	)
	(segment
		(start 77.469746 -253.76759)
		(end 77.47 -253.767336)
		(width 0.0889)
		(layer "In13.Cu")
		(net "M_B_CPU1_SA_CA<2>")
	)
	(segment
		(start 58.269886 -251.66701)
		(end 58.414666 -251.52223)
		(width 0.14478)
		(layer "In13.Cu")
		(net "M_B_CPU1_SA_CA<2>")
	)
	(segment
		(start 78.59776 -253.71679)
		(end 78.603348 -253.713488)
		(width 0.0889)
		(layer "In13.Cu")
		(net "M_B_CPU1_SA_CA<2>")
	)
	(segment
		(start 83.289648 -253.72187)
		(end 83.29803 -253.717044)
		(width 0.0889)
		(layer "In13.Cu")
		(net "M_B_CPU1_SA_CA<2>")
	)
	(segment
		(start 80.46974 -253.72187)
		(end 80.478122 -253.717044)
		(width 0.0889)
		(layer "In13.Cu")
		(net "M_B_CPU1_SA_CA<2>")
	)
	(segment
		(start 55.658766 -251.45492)
		(end 55.658766 -251.52223)
		(width 0.14478)
		(layer "In13.Cu")
		(net "M_B_CPU1_SA_CA<2>")
	)
	(segment
		(start 57.718706 -251.31014)
		(end 57.863486 -251.45492)
		(width 0.14478)
		(layer "In13.Cu")
		(net "M_B_CPU1_SA_CA<2>")
	)
	(segment
		(start 56.905906 -251.66701)
		(end 57.167526 -251.66701)
		(width 0.14478)
		(layer "In13.Cu")
		(net "M_B_CPU1_SA_CA<2>")
	)
	(segment
		(start 56.354726 -251.31014)
		(end 56.616346 -251.31014)
		(width 0.14478)
		(layer "In13.Cu")
		(net "M_B_CPU1_SA_CA<2>")
	)
	(segment
		(start 84.803996 -253.717044)
		(end 84.812378 -253.72187)
		(width 0.0889)
		(layer "In13.Cu")
		(net "M_B_CPU1_SA_CA<2>")
	)
	(segment
		(start 78.579472 -253.727204)
		(end 78.59776 -253.71679)
		(width 0.0889)
		(layer "In13.Cu")
		(net "M_B_CPU1_SA_CA<2>")
	)
	(segment
		(start 56.209946 -251.45492)
		(end 56.354726 -251.31014)
		(width 0.14478)
		(layer "In13.Cu")
		(net "M_B_CPU1_SA_CA<2>")
	)
	(segment
		(start 56.616346 -251.31014)
		(end 56.761126 -251.45492)
		(width 0.14478)
		(layer "In13.Cu")
		(net "M_B_CPU1_SA_CA<2>")
	)
	(segment
		(start 57.312306 -251.52223)
		(end 57.312306 -251.45492)
		(width 0.14478)
		(layer "In13.Cu")
		(net "M_B_CPU1_SA_CA<2>")
	)
	(segment
		(start 72.678544 -252.882654)
		(end 73.639934 -253.844044)
		(width 0.14478)
		(layer "In13.Cu")
		(net "M_B_CPU1_SA_CA<2>")
	)
	(segment
		(start 56.065166 -251.66701)
		(end 56.209946 -251.52223)
		(width 0.14478)
		(layer "In13.Cu")
		(net "M_B_CPU1_SA_CA<2>")
	)
	(segment
		(start 58.414666 -251.45492)
		(end 58.559446 -251.31014)
		(width 0.14478)
		(layer "In13.Cu")
		(net "M_B_CPU1_SA_CA<2>")
	)
	(segment
		(start 59.61253 -251.31014)
		(end 61.185044 -252.882654)
		(width 0.14478)
		(layer "In13.Cu")
		(net "M_B_CPU1_SA_CA<2>")
	)
	(segment
		(start 57.457086 -251.31014)
		(end 57.718706 -251.31014)
		(width 0.14478)
		(layer "In13.Cu")
		(net "M_B_CPU1_SA_CA<2>")
	)
	(segment
		(start 57.863486 -251.52223)
		(end 58.008266 -251.66701)
		(width 0.14478)
		(layer "In13.Cu")
		(net "M_B_CPU1_SA_CA<2>")
	)
	(segment
		(start 54.973982 -251.31014)
		(end 55.513986 -251.31014)
		(width 0.14478)
		(layer "In13.Cu")
		(net "M_B_CPU1_SA_CA<2>")
	)
	(segment
		(start 52.21859 -249.519948)
		(end 53.18379 -249.519948)
		(width 0.14478)
		(layer "In13.Cu")
		(net "M_B_CPU1_SA_CA<2>")
	)
	(segment
		(start 53.18379 -249.519948)
		(end 54.973982 -251.31014)
		(width 0.14478)
		(layer "In13.Cu")
		(net "M_B_CPU1_SA_CA<2>")
	)
	(segment
		(start 57.863486 -251.45492)
		(end 57.863486 -251.52223)
		(width 0.14478)
		(layer "In13.Cu")
		(net "M_B_CPU1_SA_CA<2>")
	)
	(segment
		(start 57.312306 -251.45492)
		(end 57.457086 -251.31014)
		(width 0.14478)
		(layer "In13.Cu")
		(net "M_B_CPU1_SA_CA<2>")
	)
	(segment
		(start 58.008266 -251.66701)
		(end 58.269886 -251.66701)
		(width 0.14478)
		(layer "In13.Cu")
		(net "M_B_CPU1_SA_CA<2>")
	)
	(segment
		(start 58.559446 -251.31014)
		(end 59.61253 -251.31014)
		(width 0.14478)
		(layer "In13.Cu")
		(net "M_B_CPU1_SA_CA<2>")
	)
	(segment
		(start 55.513986 -251.31014)
		(end 55.658766 -251.45492)
		(width 0.14478)
		(layer "In13.Cu")
		(net "M_B_CPU1_SA_CA<2>")
	)
	(segment
		(start 77.657198 -253.717044)
		(end 77.67193 -253.708408)
		(width 0.0889)
		(layer "In13.Cu")
		(net "M_B_CPU1_SA_CA<2>")
	)
	(segment
		(start 84.229702 -253.72187)
		(end 84.238084 -253.717044)
		(width 0.0889)
		(layer "In13.Cu")
		(net "M_B_CPU1_SA_CA<2>")
	)
	(segment
		(start 56.761126 -251.52223)
		(end 56.905906 -251.66701)
		(width 0.14478)
		(layer "In13.Cu")
		(net "M_B_CPU1_SA_CA<2>")
	)
	(segment
		(start 79.163164 -253.717044)
		(end 79.171546 -253.72187)
		(width 0.0889)
		(layer "In13.Cu")
		(net "M_B_CPU1_SA_CA<2>")
	)
	(segment
		(start 75.960986 -253.844044)
		(end 76.245212 -253.844044)
		(width 0.0889)
		(layer "In13.Cu")
		(net "M_B_CPU1_SA_CA<2>")
	)
	(segment
		(start 61.185044 -252.882654)
		(end 72.678544 -252.882654)
		(width 0.14478)
		(layer "In13.Cu")
		(net "M_B_CPU1_SA_CA<2>")
	)
	(segment
		(start 76.245212 -253.844044)
		(end 76.321666 -253.76759)
		(width 0.0889)
		(layer "In13.Cu")
		(net "M_B_CPU1_SA_CA<2>")
	)
	(segment
		(start 57.167526 -251.66701)
		(end 57.312306 -251.52223)
		(width 0.14478)
		(layer "In13.Cu")
		(net "M_B_CPU1_SA_CA<2>")
	)
	(segment
		(start 51.884072 -249.18543)
		(end 52.21859 -249.519948)
		(width 0.14478)
		(layer "In13.Cu")
		(net "M_B_CPU1_SA_CA<2>")
	)
	(segment
		(start 73.639934 -253.844044)
		(end 75.960986 -253.844044)
		(width 0.14478)
		(layer "In13.Cu")
		(net "M_B_CPU1_SA_CA<2>")
	)
	(segment
		(start 88.882728 -253.743206)
		(end 88.90508 -253.659894)
		(width 0.0889)
		(layer "In13.Cu")
		(net "M_B_CPU1_SA_CA<2>")
	)
	(segment
		(start 81.044034 -253.717044)
		(end 81.052416 -253.72187)
		(width 0.0889)
		(layer "In13.Cu")
		(net "M_B_CPU1_SA_CA<2>")
	)
	(segment
		(start 87.989664 -253.72187)
		(end 87.998046 -253.717044)
		(width 0.0889)
		(layer "In13.Cu")
		(net "M_B_CPU1_SA_CA<2>")
	)
	(arc
		(start 82.923888 -253.717044)
		(mid 83.106139 -253.767394)
		(end 83.289648 -253.72187)
		(width 0.0889)
		(layer "In13.Cu")
		(net "M_B_CPU1_SA_CA<2>")
	)
	(arc
		(start 80.10398 -253.717044)
		(mid 80.286231 -253.767394)
		(end 80.46974 -253.72187)
		(width 0.0889)
		(layer "In13.Cu")
		(net "M_B_CPU1_SA_CA<2>")
	)
	(arc
		(start 87.998046 -253.717044)
		(mid 88.281002 -253.640867)
		(end 88.563958 -253.717044)
		(width 0.0889)
		(layer "In13.Cu")
		(net "M_B_CPU1_SA_CA<2>")
	)
	(arc
		(start 79.171546 -253.72187)
		(mid 79.355308 -253.767486)
		(end 79.537814 -253.717044)
		(width 0.0889)
		(layer "In13.Cu")
		(net "M_B_CPU1_SA_CA<2>")
	)
	(arc
		(start 79.537814 -253.717044)
		(mid 79.814881 -253.640773)
		(end 80.093566 -253.710948)
		(width 0.0889)
		(layer "In13.Cu")
		(net "M_B_CPU1_SA_CA<2>")
	)
	(arc
		(start 86.118192 -253.717044)
		(mid 86.401148 -253.640867)
		(end 86.684104 -253.717044)
		(width 0.0889)
		(layer "In13.Cu")
		(net "M_B_CPU1_SA_CA<2>")
	)
	(arc
		(start 83.29803 -253.717044)
		(mid 83.580986 -253.640867)
		(end 83.863942 -253.717044)
		(width 0.0889)
		(layer "In13.Cu")
		(net "M_B_CPU1_SA_CA<2>")
	)
	(arc
		(start 78.223618 -253.717044)
		(mid 78.400246 -253.767277)
		(end 78.579472 -253.727204)
		(width 0.0889)
		(layer "In13.Cu")
		(net "M_B_CPU1_SA_CA<2>")
	)
	(arc
		(start 78.603348 -253.713488)
		(mid 78.883737 -253.640819)
		(end 79.163164 -253.717044)
		(width 0.0889)
		(layer "In13.Cu")
		(net "M_B_CPU1_SA_CA<2>")
	)
	(arc
		(start 84.238084 -253.717044)
		(mid 84.52104 -253.640867)
		(end 84.803996 -253.717044)
		(width 0.0889)
		(layer "In13.Cu")
		(net "M_B_CPU1_SA_CA<2>")
	)
	(arc
		(start 81.418176 -253.717044)
		(mid 81.701132 -253.640867)
		(end 81.984088 -253.717044)
		(width 0.0889)
		(layer "In13.Cu")
		(net "M_B_CPU1_SA_CA<2>")
	)
	(arc
		(start 87.057992 -253.717044)
		(mid 87.340948 -253.640867)
		(end 87.623904 -253.717044)
		(width 0.0889)
		(layer "In13.Cu")
		(net "M_B_CPU1_SA_CA<2>")
	)
	(arc
		(start 81.052416 -253.72187)
		(mid 81.235924 -253.767364)
		(end 81.418176 -253.717044)
		(width 0.0889)
		(layer "In13.Cu")
		(net "M_B_CPU1_SA_CA<2>")
	)
	(arc
		(start 77.47 -253.767336)
		(mid 77.566932 -253.754585)
		(end 77.657198 -253.717044)
		(width 0.0889)
		(layer "In13.Cu")
		(net "M_B_CPU1_SA_CA<2>")
	)
	(arc
		(start 77.67193 -253.708408)
		(mid 77.948913 -253.640604)
		(end 78.223618 -253.717044)
		(width 0.0889)
		(layer "In13.Cu")
		(net "M_B_CPU1_SA_CA<2>")
	)
	(arc
		(start 83.863942 -253.717044)
		(mid 84.046193 -253.767394)
		(end 84.229702 -253.72187)
		(width 0.0889)
		(layer "In13.Cu")
		(net "M_B_CPU1_SA_CA<2>")
	)
	(arc
		(start 81.984088 -253.717044)
		(mid 82.171032 -253.767299)
		(end 82.357976 -253.717044)
		(width 0.0889)
		(layer "In13.Cu")
		(net "M_B_CPU1_SA_CA<2>")
	)
	(arc
		(start 84.812378 -253.72187)
		(mid 84.995886 -253.767364)
		(end 85.178138 -253.717044)
		(width 0.0889)
		(layer "In13.Cu")
		(net "M_B_CPU1_SA_CA<2>")
	)
	(arc
		(start 86.684104 -253.717044)
		(mid 86.871048 -253.767299)
		(end 87.057992 -253.717044)
		(width 0.0889)
		(layer "In13.Cu")
		(net "M_B_CPU1_SA_CA<2>")
	)
	(arc
		(start 80.478122 -253.717044)
		(mid 80.761078 -253.640867)
		(end 81.044034 -253.717044)
		(width 0.0889)
		(layer "In13.Cu")
		(net "M_B_CPU1_SA_CA<2>")
	)
	(arc
		(start 87.623904 -253.717044)
		(mid 87.806155 -253.767394)
		(end 87.989664 -253.72187)
		(width 0.0889)
		(layer "In13.Cu")
		(net "M_B_CPU1_SA_CA<2>")
	)
	(arc
		(start 88.563958 -253.717044)
		(mid 88.720396 -253.766015)
		(end 88.882728 -253.743206)
		(width 0.0889)
		(layer "In13.Cu")
		(net "M_B_CPU1_SA_CA<2>")
	)
	(arc
		(start 85.178138 -253.717044)
		(mid 85.461094 -253.640867)
		(end 85.74405 -253.717044)
		(width 0.0889)
		(layer "In13.Cu")
		(net "M_B_CPU1_SA_CA<2>")
	)
	(arc
		(start 82.357976 -253.717044)
		(mid 82.640932 -253.640867)
		(end 82.923888 -253.717044)
		(width 0.0889)
		(layer "In13.Cu")
		(net "M_B_CPU1_SA_CA<2>")
	)
	(arc
		(start 85.752432 -253.72187)
		(mid 85.93594 -253.767364)
		(end 86.118192 -253.717044)
		(width 0.0889)
		(layer "In13.Cu")
		(net "M_B_CPU1_SA_CA<2>")
	)
	(segment
		(start 88.277954 -253.660402)
		(end 87.811102 -253.394464)
		(width 0.10668)
		(layer "F.Cu")
		(net "M_B_CPU1_SA_CA<1>")
	)
	(segment
		(start 75.968606 -253.381764)
		(end 77.060552 -253.381764)
		(width 0.0889)
		(layer "In13.Cu")
		(net "M_B_CPU1_SA_CA<1>")
	)
	(segment
		(start 77.060552 -253.381764)
		(end 77.29474 -253.147576)
		(width 0.0889)
		(layer "In13.Cu")
		(net "M_B_CPU1_SA_CA<1>")
	)
	(segment
		(start 81.044034 -253.071884)
		(end 81.052416 -253.067058)
		(width 0.0889)
		(layer "In13.Cu")
		(net "M_B_CPU1_SA_CA<1>")
	)
	(segment
		(start 78.225142 -253.072138)
		(end 78.252574 -253.05639)
		(width 0.0889)
		(layer "In13.Cu")
		(net "M_B_CPU1_SA_CA<1>")
	)
	(segment
		(start 84.229702 -253.067058)
		(end 84.238084 -253.071884)
		(width 0.0889)
		(layer "In13.Cu")
		(net "M_B_CPU1_SA_CA<1>")
	)
	(segment
		(start 79.539592 -253.072138)
		(end 79.561182 -253.084584)
		(width 0.0889)
		(layer "In13.Cu")
		(net "M_B_CPU1_SA_CA<1>")
	)
	(segment
		(start 84.803996 -253.071884)
		(end 84.812378 -253.067058)
		(width 0.0889)
		(layer "In13.Cu")
		(net "M_B_CPU1_SA_CA<1>")
	)
	(segment
		(start 47.784004 -248.335292)
		(end 49.995074 -248.335292)
		(width 0.14478)
		(layer "In13.Cu")
		(net "M_B_CPU1_SA_CA<1>")
	)
	(segment
		(start 87.560658 -253.103634)
		(end 87.656924 -253.129034)
		(width 0.0889)
		(layer "In13.Cu")
		(net "M_B_CPU1_SA_CA<1>")
	)
	(segment
		(start 54.913022 -250.460256)
		(end 59.398662 -250.460256)
		(width 0.14478)
		(layer "In13.Cu")
		(net "M_B_CPU1_SA_CA<1>")
	)
	(segment
		(start 72.87006 -252.427994)
		(end 73.82383 -253.381764)
		(width 0.14478)
		(layer "In13.Cu")
		(net "M_B_CPU1_SA_CA<1>")
	)
	(segment
		(start 53.213 -248.760234)
		(end 54.913022 -250.460256)
		(width 0.14478)
		(layer "In13.Cu")
		(net "M_B_CPU1_SA_CA<1>")
	)
	(segment
		(start 73.82383 -253.381764)
		(end 75.968606 -253.381764)
		(width 0.14478)
		(layer "In13.Cu")
		(net "M_B_CPU1_SA_CA<1>")
	)
	(segment
		(start 83.289648 -253.067058)
		(end 83.29803 -253.071884)
		(width 0.0889)
		(layer "In13.Cu")
		(net "M_B_CPU1_SA_CA<1>")
	)
	(segment
		(start 77.29474 -253.147576)
		(end 77.943456 -253.147576)
		(width 0.0889)
		(layer "In13.Cu")
		(net "M_B_CPU1_SA_CA<1>")
	)
	(segment
		(start 61.3664 -252.427994)
		(end 72.87006 -252.427994)
		(width 0.14478)
		(layer "In13.Cu")
		(net "M_B_CPU1_SA_CA<1>")
	)
	(segment
		(start 80.46974 -253.067058)
		(end 80.478122 -253.071884)
		(width 0.0889)
		(layer "In13.Cu")
		(net "M_B_CPU1_SA_CA<1>")
	)
	(segment
		(start 79.521304 -253.061724)
		(end 79.539592 -253.072138)
		(width 0.0889)
		(layer "In13.Cu")
		(net "M_B_CPU1_SA_CA<1>")
	)
	(segment
		(start 49.995074 -248.335292)
		(end 50.420016 -248.760234)
		(width 0.14478)
		(layer "In13.Cu")
		(net "M_B_CPU1_SA_CA<1>")
	)
	(segment
		(start 87.656924 -253.129034)
		(end 87.811102 -253.394464)
		(width 0.0889)
		(layer "In13.Cu")
		(net "M_B_CPU1_SA_CA<1>")
	)
	(segment
		(start 50.420016 -248.760234)
		(end 53.213 -248.760234)
		(width 0.14478)
		(layer "In13.Cu")
		(net "M_B_CPU1_SA_CA<1>")
	)
	(segment
		(start 85.74405 -253.071884)
		(end 85.752432 -253.067058)
		(width 0.0889)
		(layer "In13.Cu")
		(net "M_B_CPU1_SA_CA<1>")
	)
	(segment
		(start 59.398662 -250.460256)
		(end 61.3664 -252.427994)
		(width 0.14478)
		(layer "In13.Cu")
		(net "M_B_CPU1_SA_CA<1>")
	)
	(segment
		(start 79.143098 -253.0856)
		(end 79.166466 -253.071884)
		(width 0.0889)
		(layer "In13.Cu")
		(net "M_B_CPU1_SA_CA<1>")
	)
	(arc
		(start 83.863942 -253.071884)
		(mid 84.046193 -253.021534)
		(end 84.229702 -253.067058)
		(width 0.0889)
		(layer "In13.Cu")
		(net "M_B_CPU1_SA_CA<1>")
	)
	(arc
		(start 82.923888 -253.071884)
		(mid 83.106139 -253.021534)
		(end 83.289648 -253.067058)
		(width 0.0889)
		(layer "In13.Cu")
		(net "M_B_CPU1_SA_CA<1>")
	)
	(arc
		(start 86.684104 -253.071884)
		(mid 86.871048 -253.021629)
		(end 87.057992 -253.071884)
		(width 0.0889)
		(layer "In13.Cu")
		(net "M_B_CPU1_SA_CA<1>")
	)
	(arc
		(start 79.166466 -253.071884)
		(mid 79.342586 -253.021906)
		(end 79.521304 -253.061724)
		(width 0.0889)
		(layer "In13.Cu")
		(net "M_B_CPU1_SA_CA<1>")
	)
	(arc
		(start 85.178138 -253.071884)
		(mid 85.461094 -253.148061)
		(end 85.74405 -253.071884)
		(width 0.0889)
		(layer "In13.Cu")
		(net "M_B_CPU1_SA_CA<1>")
	)
	(arc
		(start 77.943456 -253.147576)
		(mid 78.089279 -253.128436)
		(end 78.225142 -253.072138)
		(width 0.0889)
		(layer "In13.Cu")
		(net "M_B_CPU1_SA_CA<1>")
	)
	(arc
		(start 79.561182 -253.084584)
		(mid 79.834211 -253.147903)
		(end 80.10398 -253.071884)
		(width 0.0889)
		(layer "In13.Cu")
		(net "M_B_CPU1_SA_CA<1>")
	)
	(arc
		(start 87.057992 -253.071884)
		(mid 87.305588 -253.147062)
		(end 87.560658 -253.103634)
		(width 0.0889)
		(layer "In13.Cu")
		(net "M_B_CPU1_SA_CA<1>")
	)
	(arc
		(start 80.478122 -253.071884)
		(mid 80.761078 -253.148061)
		(end 81.044034 -253.071884)
		(width 0.0889)
		(layer "In13.Cu")
		(net "M_B_CPU1_SA_CA<1>")
	)
	(arc
		(start 78.599284 -253.071884)
		(mid 78.869441 -253.148646)
		(end 79.143098 -253.0856)
		(width 0.0889)
		(layer "In13.Cu")
		(net "M_B_CPU1_SA_CA<1>")
	)
	(arc
		(start 84.812378 -253.067058)
		(mid 84.995886 -253.021564)
		(end 85.178138 -253.071884)
		(width 0.0889)
		(layer "In13.Cu")
		(net "M_B_CPU1_SA_CA<1>")
	)
	(arc
		(start 82.357976 -253.071884)
		(mid 82.640932 -253.148061)
		(end 82.923888 -253.071884)
		(width 0.0889)
		(layer "In13.Cu")
		(net "M_B_CPU1_SA_CA<1>")
	)
	(arc
		(start 85.752432 -253.067058)
		(mid 85.93594 -253.021564)
		(end 86.118192 -253.071884)
		(width 0.0889)
		(layer "In13.Cu")
		(net "M_B_CPU1_SA_CA<1>")
	)
	(arc
		(start 81.984088 -253.071884)
		(mid 82.171032 -253.021629)
		(end 82.357976 -253.071884)
		(width 0.0889)
		(layer "In13.Cu")
		(net "M_B_CPU1_SA_CA<1>")
	)
	(arc
		(start 81.418176 -253.071884)
		(mid 81.701132 -253.148061)
		(end 81.984088 -253.071884)
		(width 0.0889)
		(layer "In13.Cu")
		(net "M_B_CPU1_SA_CA<1>")
	)
	(arc
		(start 81.052416 -253.067058)
		(mid 81.235924 -253.021564)
		(end 81.418176 -253.071884)
		(width 0.0889)
		(layer "In13.Cu")
		(net "M_B_CPU1_SA_CA<1>")
	)
	(arc
		(start 80.10398 -253.071884)
		(mid 80.286231 -253.021534)
		(end 80.46974 -253.067058)
		(width 0.0889)
		(layer "In13.Cu")
		(net "M_B_CPU1_SA_CA<1>")
	)
	(arc
		(start 83.29803 -253.071884)
		(mid 83.580986 -253.148061)
		(end 83.863942 -253.071884)
		(width 0.0889)
		(layer "In13.Cu")
		(net "M_B_CPU1_SA_CA<1>")
	)
	(arc
		(start 86.118192 -253.071884)
		(mid 86.401148 -253.148061)
		(end 86.684104 -253.071884)
		(width 0.0889)
		(layer "In13.Cu")
		(net "M_B_CPU1_SA_CA<1>")
	)
	(arc
		(start 84.238084 -253.071884)
		(mid 84.52104 -253.148061)
		(end 84.803996 -253.071884)
		(width 0.0889)
		(layer "In13.Cu")
		(net "M_B_CPU1_SA_CA<1>")
	)
	(arc
		(start 78.252574 -253.05639)
		(mid 78.427825 -253.021457)
		(end 78.599284 -253.071884)
		(width 0.0889)
		(layer "In13.Cu")
		(net "M_B_CPU1_SA_CA<1>")
	)
	(segment
		(start 87.8078 -252.850396)
		(end 87.340948 -252.584458)
		(width 0.10668)
		(layer "F.Cu")
		(net "M_B_CPU1_SA_CA<0>")
	)
	(segment
		(start 62.402212 -251.973334)
		(end 73.058528 -251.973334)
		(width 0.14478)
		(layer "In13.Cu")
		(net "M_B_CPU1_SA_CA<0>")
	)
	(segment
		(start 56.562498 -249.755152)
		(end 56.707278 -249.610372)
		(width 0.14478)
		(layer "In13.Cu")
		(net "M_B_CPU1_SA_CA<0>")
	)
	(segment
		(start 87.154004 -252.907038)
		(end 87.162386 -252.911864)
		(width 0.0889)
		(layer "In13.Cu")
		(net "M_B_CPU1_SA_CA<0>")
	)
	(segment
		(start 87.495126 -252.849888)
		(end 87.340948 -252.584458)
		(width 0.0889)
		(layer "In13.Cu")
		(net "M_B_CPU1_SA_CA<0>")
	)
	(segment
		(start 51.884072 -247.485408)
		(end 51.884072 -247.621044)
		(width 0.14478)
		(layer "In13.Cu")
		(net "M_B_CPU1_SA_CA<0>")
	)
	(segment
		(start 57.113678 -249.860054)
		(end 57.258458 -250.004834)
		(width 0.14478)
		(layer "In13.Cu")
		(net "M_B_CPU1_SA_CA<0>")
	)
	(segment
		(start 78.129892 -252.907038)
		(end 78.129892 -252.906784)
		(width 0.0889)
		(layer "In13.Cu")
		(net "M_B_CPU1_SA_CA<0>")
	)
	(segment
		(start 60.03925 -249.610372)
		(end 60.377832 -249.948954)
		(width 0.14478)
		(layer "In13.Cu")
		(net "M_B_CPU1_SA_CA<0>")
	)
	(segment
		(start 56.562498 -249.860054)
		(end 56.562498 -249.755152)
		(width 0.14478)
		(layer "In13.Cu")
		(net "M_B_CPU1_SA_CA<0>")
	)
	(segment
		(start 55.866538 -249.610372)
		(end 56.011318 -249.755152)
		(width 0.14478)
		(layer "In13.Cu")
		(net "M_B_CPU1_SA_CA<0>")
	)
	(segment
		(start 76.293472 -252.723904)
		(end 76.54925 -252.468126)
		(width 0.0889)
		(layer "In13.Cu")
		(net "M_B_CPU1_SA_CA<0>")
	)
	(segment
		(start 58.071258 -249.610372)
		(end 58.216038 -249.755152)
		(width 0.14478)
		(layer "In13.Cu")
		(net "M_B_CPU1_SA_CA<0>")
	)
	(segment
		(start 58.767218 -249.860054)
		(end 58.767218 -249.755152)
		(width 0.14478)
		(layer "In13.Cu")
		(net "M_B_CPU1_SA_CA<0>")
	)
	(segment
		(start 58.216038 -249.860054)
		(end 58.360818 -250.004834)
		(width 0.14478)
		(layer "In13.Cu")
		(net "M_B_CPU1_SA_CA<0>")
	)
	(segment
		(start 57.258458 -250.004834)
		(end 57.520078 -250.004834)
		(width 0.14478)
		(layer "In13.Cu")
		(net "M_B_CPU1_SA_CA<0>")
	)
	(segment
		(start 56.417718 -250.004834)
		(end 56.562498 -249.860054)
		(width 0.14478)
		(layer "In13.Cu")
		(net "M_B_CPU1_SA_CA<0>")
	)
	(segment
		(start 58.911998 -249.610372)
		(end 60.03925 -249.610372)
		(width 0.14478)
		(layer "In13.Cu")
		(net "M_B_CPU1_SA_CA<0>")
	)
	(segment
		(start 56.156098 -250.004834)
		(end 56.417718 -250.004834)
		(width 0.14478)
		(layer "In13.Cu")
		(net "M_B_CPU1_SA_CA<0>")
	)
	(segment
		(start 76.123546 -252.723904)
		(end 76.293472 -252.723904)
		(width 0.0889)
		(layer "In13.Cu")
		(net "M_B_CPU1_SA_CA<0>")
	)
	(segment
		(start 60.29833 -250.437904)
		(end 60.483496 -250.62307)
		(width 0.14478)
		(layer "In13.Cu")
		(net "M_B_CPU1_SA_CA<0>")
	)
	(segment
		(start 56.011318 -249.755152)
		(end 56.011318 -249.860054)
		(width 0.14478)
		(layer "In13.Cu")
		(net "M_B_CPU1_SA_CA<0>")
	)
	(segment
		(start 79.634842 -252.906784)
		(end 79.654908 -252.918214)
		(width 0.0889)
		(layer "In13.Cu")
		(net "M_B_CPU1_SA_CA<0>")
	)
	(segment
		(start 81.879694 -252.911864)
		(end 81.888076 -252.907038)
		(width 0.0889)
		(layer "In13.Cu")
		(net "M_B_CPU1_SA_CA<0>")
	)
	(segment
		(start 57.113678 -249.755152)
		(end 57.113678 -249.860054)
		(width 0.14478)
		(layer "In13.Cu")
		(net "M_B_CPU1_SA_CA<0>")
	)
	(segment
		(start 77.03312 -252.468126)
		(end 77.52207 -252.957076)
		(width 0.0889)
		(layer "In13.Cu")
		(net "M_B_CPU1_SA_CA<0>")
	)
	(segment
		(start 51.884072 -247.621044)
		(end 52.208176 -247.945148)
		(width 0.14478)
		(layer "In13.Cu")
		(net "M_B_CPU1_SA_CA<0>")
	)
	(segment
		(start 57.664858 -249.860054)
		(end 57.664858 -249.755152)
		(width 0.14478)
		(layer "In13.Cu")
		(net "M_B_CPU1_SA_CA<0>")
	)
	(segment
		(start 58.622438 -250.004834)
		(end 58.767218 -249.860054)
		(width 0.14478)
		(layer "In13.Cu")
		(net "M_B_CPU1_SA_CA<0>")
	)
	(segment
		(start 56.707278 -249.610372)
		(end 56.968898 -249.610372)
		(width 0.14478)
		(layer "In13.Cu")
		(net "M_B_CPU1_SA_CA<0>")
	)
	(segment
		(start 77.52207 -252.957076)
		(end 77.94371 -252.957076)
		(width 0.0889)
		(layer "In13.Cu")
		(net "M_B_CPU1_SA_CA<0>")
	)
	(segment
		(start 78.129638 -252.906784)
		(end 78.161388 -252.888496)
		(width 0.0889)
		(layer "In13.Cu")
		(net "M_B_CPU1_SA_CA<0>")
	)
	(segment
		(start 60.972446 -250.543568)
		(end 62.402212 -251.973334)
		(width 0.14478)
		(layer "In13.Cu")
		(net "M_B_CPU1_SA_CA<0>")
	)
	(segment
		(start 60.68822 -250.62307)
		(end 60.767722 -250.543568)
		(width 0.14478)
		(layer "In13.Cu")
		(net "M_B_CPU1_SA_CA<0>")
	)
	(segment
		(start 56.968898 -249.610372)
		(end 57.113678 -249.755152)
		(width 0.14478)
		(layer "In13.Cu")
		(net "M_B_CPU1_SA_CA<0>")
	)
	(segment
		(start 79.051658 -252.91796)
		(end 79.070454 -252.907038)
		(width 0.0889)
		(layer "In13.Cu")
		(net "M_B_CPU1_SA_CA<0>")
	)
	(segment
		(start 79.613252 -252.894338)
		(end 79.634842 -252.906784)
		(width 0.0889)
		(layer "In13.Cu")
		(net "M_B_CPU1_SA_CA<0>")
	)
	(segment
		(start 82.453988 -252.907038)
		(end 82.46237 -252.911864)
		(width 0.0889)
		(layer "In13.Cu")
		(net "M_B_CPU1_SA_CA<0>")
	)
	(segment
		(start 58.767218 -249.755152)
		(end 58.911998 -249.610372)
		(width 0.14478)
		(layer "In13.Cu")
		(net "M_B_CPU1_SA_CA<0>")
	)
	(segment
		(start 56.011318 -249.860054)
		(end 56.156098 -250.004834)
		(width 0.14478)
		(layer "In13.Cu")
		(net "M_B_CPU1_SA_CA<0>")
	)
	(segment
		(start 86.57971 -252.911864)
		(end 86.588092 -252.907038)
		(width 0.0889)
		(layer "In13.Cu")
		(net "M_B_CPU1_SA_CA<0>")
	)
	(segment
		(start 53.325014 -247.945148)
		(end 54.990238 -249.610372)
		(width 0.14478)
		(layer "In13.Cu")
		(net "M_B_CPU1_SA_CA<0>")
	)
	(segment
		(start 76.54925 -252.468126)
		(end 77.03312 -252.468126)
		(width 0.0889)
		(layer "In13.Cu")
		(net "M_B_CPU1_SA_CA<0>")
	)
	(segment
		(start 78.129892 -252.906784)
		(end 78.129638 -252.906784)
		(width 0.0889)
		(layer "In13.Cu")
		(net "M_B_CPU1_SA_CA<0>")
	)
	(segment
		(start 85.639656 -252.911864)
		(end 85.648038 -252.907038)
		(width 0.0889)
		(layer "In13.Cu")
		(net "M_B_CPU1_SA_CA<0>")
	)
	(segment
		(start 83.394042 -252.907038)
		(end 83.402424 -252.911864)
		(width 0.0889)
		(layer "In13.Cu")
		(net "M_B_CPU1_SA_CA<0>")
	)
	(segment
		(start 57.520078 -250.004834)
		(end 57.664858 -249.860054)
		(width 0.14478)
		(layer "In13.Cu")
		(net "M_B_CPU1_SA_CA<0>")
	)
	(segment
		(start 60.377832 -249.948954)
		(end 60.377832 -250.153678)
		(width 0.14478)
		(layer "In13.Cu")
		(net "M_B_CPU1_SA_CA<0>")
	)
	(segment
		(start 57.809638 -249.610372)
		(end 58.071258 -249.610372)
		(width 0.14478)
		(layer "In13.Cu")
		(net "M_B_CPU1_SA_CA<0>")
	)
	(segment
		(start 60.29833 -250.23318)
		(end 60.29833 -250.437904)
		(width 0.14478)
		(layer "In13.Cu")
		(net "M_B_CPU1_SA_CA<0>")
	)
	(segment
		(start 52.208176 -247.945148)
		(end 53.325014 -247.945148)
		(width 0.14478)
		(layer "In13.Cu")
		(net "M_B_CPU1_SA_CA<0>")
	)
	(segment
		(start 60.767722 -250.543568)
		(end 60.972446 -250.543568)
		(width 0.14478)
		(layer "In13.Cu")
		(net "M_B_CPU1_SA_CA<0>")
	)
	(segment
		(start 73.809098 -252.723904)
		(end 76.123546 -252.723904)
		(width 0.14478)
		(layer "In13.Cu")
		(net "M_B_CPU1_SA_CA<0>")
	)
	(segment
		(start 54.990238 -249.610372)
		(end 55.866538 -249.610372)
		(width 0.14478)
		(layer "In13.Cu")
		(net "M_B_CPU1_SA_CA<0>")
	)
	(segment
		(start 58.216038 -249.755152)
		(end 58.216038 -249.860054)
		(width 0.14478)
		(layer "In13.Cu")
		(net "M_B_CPU1_SA_CA<0>")
	)
	(segment
		(start 73.058528 -251.973334)
		(end 73.809098 -252.723904)
		(width 0.14478)
		(layer "In13.Cu")
		(net "M_B_CPU1_SA_CA<0>")
	)
	(segment
		(start 60.483496 -250.62307)
		(end 60.68822 -250.62307)
		(width 0.14478)
		(layer "In13.Cu")
		(net "M_B_CPU1_SA_CA<0>")
	)
	(segment
		(start 57.664858 -249.755152)
		(end 57.809638 -249.610372)
		(width 0.14478)
		(layer "In13.Cu")
		(net "M_B_CPU1_SA_CA<0>")
	)
	(segment
		(start 58.360818 -250.004834)
		(end 58.622438 -250.004834)
		(width 0.14478)
		(layer "In13.Cu")
		(net "M_B_CPU1_SA_CA<0>")
	)
	(segment
		(start 87.472774 -252.9332)
		(end 87.495126 -252.849888)
		(width 0.0889)
		(layer "In13.Cu")
		(net "M_B_CPU1_SA_CA<0>")
	)
	(segment
		(start 60.377832 -250.153678)
		(end 60.29833 -250.23318)
		(width 0.14478)
		(layer "In13.Cu")
		(net "M_B_CPU1_SA_CA<0>")
	)
	(arc
		(start 81.513934 -252.907038)
		(mid 81.696185 -252.957388)
		(end 81.879694 -252.911864)
		(width 0.0889)
		(layer "In13.Cu")
		(net "M_B_CPU1_SA_CA<0>")
	)
	(arc
		(start 82.46237 -252.911864)
		(mid 82.645878 -252.957358)
		(end 82.82813 -252.907038)
		(width 0.0889)
		(layer "In13.Cu")
		(net "M_B_CPU1_SA_CA<0>")
	)
	(arc
		(start 80.574134 -252.907038)
		(mid 80.761078 -252.957293)
		(end 80.948022 -252.907038)
		(width 0.0889)
		(layer "In13.Cu")
		(net "M_B_CPU1_SA_CA<0>")
	)
	(arc
		(start 78.695296 -252.907038)
		(mid 78.872087 -252.957757)
		(end 79.051658 -252.91796)
		(width 0.0889)
		(layer "In13.Cu")
		(net "M_B_CPU1_SA_CA<0>")
	)
	(arc
		(start 78.161388 -252.888496)
		(mid 78.430673 -252.830584)
		(end 78.695296 -252.907038)
		(width 0.0889)
		(layer "In13.Cu")
		(net "M_B_CPU1_SA_CA<0>")
	)
	(arc
		(start 82.82813 -252.907038)
		(mid 83.111086 -252.830861)
		(end 83.394042 -252.907038)
		(width 0.0889)
		(layer "In13.Cu")
		(net "M_B_CPU1_SA_CA<0>")
	)
	(arc
		(start 80.948022 -252.907038)
		(mid 81.230978 -252.830861)
		(end 81.513934 -252.907038)
		(width 0.0889)
		(layer "In13.Cu")
		(net "M_B_CPU1_SA_CA<0>")
	)
	(arc
		(start 84.707984 -252.907038)
		(mid 84.99094 -252.830861)
		(end 85.273896 -252.907038)
		(width 0.0889)
		(layer "In13.Cu")
		(net "M_B_CPU1_SA_CA<0>")
	)
	(arc
		(start 81.888076 -252.907038)
		(mid 82.171032 -252.830861)
		(end 82.453988 -252.907038)
		(width 0.0889)
		(layer "In13.Cu")
		(net "M_B_CPU1_SA_CA<0>")
	)
	(arc
		(start 85.648038 -252.907038)
		(mid 85.930994 -252.830861)
		(end 86.21395 -252.907038)
		(width 0.0889)
		(layer "In13.Cu")
		(net "M_B_CPU1_SA_CA<0>")
	)
	(arc
		(start 86.588092 -252.907038)
		(mid 86.871048 -252.830861)
		(end 87.154004 -252.907038)
		(width 0.0889)
		(layer "In13.Cu")
		(net "M_B_CPU1_SA_CA<0>")
	)
	(arc
		(start 85.273896 -252.907038)
		(mid 85.456147 -252.957388)
		(end 85.639656 -252.911864)
		(width 0.0889)
		(layer "In13.Cu")
		(net "M_B_CPU1_SA_CA<0>")
	)
	(arc
		(start 87.162386 -252.911864)
		(mid 87.315256 -252.956505)
		(end 87.472774 -252.9332)
		(width 0.0889)
		(layer "In13.Cu")
		(net "M_B_CPU1_SA_CA<0>")
	)
	(arc
		(start 79.654908 -252.918214)
		(mid 79.832986 -252.957198)
		(end 80.008222 -252.907038)
		(width 0.0889)
		(layer "In13.Cu")
		(net "M_B_CPU1_SA_CA<0>")
	)
	(arc
		(start 80.008222 -252.907038)
		(mid 80.291178 -252.830861)
		(end 80.574134 -252.907038)
		(width 0.0889)
		(layer "In13.Cu")
		(net "M_B_CPU1_SA_CA<0>")
	)
	(arc
		(start 86.21395 -252.907038)
		(mid 86.396201 -252.957388)
		(end 86.57971 -252.911864)
		(width 0.0889)
		(layer "In13.Cu")
		(net "M_B_CPU1_SA_CA<0>")
	)
	(arc
		(start 83.402424 -252.911864)
		(mid 83.585932 -252.957358)
		(end 83.768184 -252.907038)
		(width 0.0889)
		(layer "In13.Cu")
		(net "M_B_CPU1_SA_CA<0>")
	)
	(arc
		(start 77.94371 -252.957076)
		(mid 78.040101 -252.944325)
		(end 78.129892 -252.907038)
		(width 0.0889)
		(layer "In13.Cu")
		(net "M_B_CPU1_SA_CA<0>")
	)
	(arc
		(start 84.334096 -252.907038)
		(mid 84.52104 -252.957293)
		(end 84.707984 -252.907038)
		(width 0.0889)
		(layer "In13.Cu")
		(net "M_B_CPU1_SA_CA<0>")
	)
	(arc
		(start 83.768184 -252.907038)
		(mid 84.05114 -252.830861)
		(end 84.334096 -252.907038)
		(width 0.0889)
		(layer "In13.Cu")
		(net "M_B_CPU1_SA_CA<0>")
	)
	(arc
		(start 79.070454 -252.907038)
		(mid 79.340223 -252.831015)
		(end 79.613252 -252.894338)
		(width 0.0889)
		(layer "In13.Cu")
		(net "M_B_CPU1_SA_CA<0>")
	)
	(segment
		(start 89.687908 -251.230384)
		(end 89.221056 -250.964446)
		(width 0.10668)
		(layer "F.Cu")
		(net "M_B_CPU1_RESET_N")
	)
	(segment
		(start 73.744582 -250.318524)
		(end 74.260202 -250.834144)
		(width 0.11684)
		(layer "In13.Cu")
		(net "M_B_CPU1_RESET_N")
	)
	(segment
		(start 54.19852 -245.360444)
		(end 55.048404 -246.210328)
		(width 0.11684)
		(layer "In13.Cu")
		(net "M_B_CPU1_RESET_N")
	)
	(segment
		(start 50.776886 -245.360444)
		(end 54.19852 -245.360444)
		(width 0.11684)
		(layer "In13.Cu")
		(net "M_B_CPU1_RESET_N")
	)
	(segment
		(start 83.394042 -250.641866)
		(end 83.402424 -250.63704)
		(width 0.0889)
		(layer "In13.Cu")
		(net "M_B_CPU1_RESET_N")
	)
	(segment
		(start 81.879694 -250.63704)
		(end 81.888076 -250.641866)
		(width 0.0889)
		(layer "In13.Cu")
		(net "M_B_CPU1_RESET_N")
	)
	(segment
		(start 76.313792 -250.834144)
		(end 76.37653 -250.771406)
		(width 0.0889)
		(layer "In13.Cu")
		(net "M_B_CPU1_RESET_N")
	)
	(segment
		(start 79.63408 -250.641866)
		(end 79.642462 -250.63704)
		(width 0.0889)
		(layer "In13.Cu")
		(net "M_B_CPU1_RESET_N")
	)
	(segment
		(start 50.35169 -244.935248)
		(end 50.776886 -245.360444)
		(width 0.11684)
		(layer "In13.Cu")
		(net "M_B_CPU1_RESET_N")
	)
	(segment
		(start 76.014326 -250.834144)
		(end 76.313792 -250.834144)
		(width 0.0889)
		(layer "In13.Cu")
		(net "M_B_CPU1_RESET_N")
	)
	(segment
		(start 56.520842 -247.060212)
		(end 60.098686 -247.060212)
		(width 0.11684)
		(layer "In13.Cu")
		(net "M_B_CPU1_RESET_N")
	)
	(segment
		(start 76.37653 -250.771406)
		(end 78.5114 -250.771406)
		(width 0.0889)
		(layer "In13.Cu")
		(net "M_B_CPU1_RESET_N")
	)
	(segment
		(start 88.094058 -250.641866)
		(end 88.10244 -250.63704)
		(width 0.0889)
		(layer "In13.Cu")
		(net "M_B_CPU1_RESET_N")
	)
	(segment
		(start 89.067132 -250.699016)
		(end 89.221056 -250.964446)
		(width 0.0889)
		(layer "In13.Cu")
		(net "M_B_CPU1_RESET_N")
	)
	(segment
		(start 74.260202 -250.834144)
		(end 76.014326 -250.834144)
		(width 0.11684)
		(layer "In13.Cu")
		(net "M_B_CPU1_RESET_N")
	)
	(segment
		(start 87.154004 -250.641866)
		(end 87.162386 -250.63704)
		(width 0.0889)
		(layer "In13.Cu")
		(net "M_B_CPU1_RESET_N")
	)
	(segment
		(start 88.97112 -250.673616)
		(end 89.067132 -250.699016)
		(width 0.0889)
		(layer "In13.Cu")
		(net "M_B_CPU1_RESET_N")
	)
	(segment
		(start 60.098686 -247.060212)
		(end 63.356998 -250.318524)
		(width 0.11684)
		(layer "In13.Cu")
		(net "M_B_CPU1_RESET_N")
	)
	(segment
		(start 55.048404 -246.210328)
		(end 55.670958 -246.210328)
		(width 0.11684)
		(layer "In13.Cu")
		(net "M_B_CPU1_RESET_N")
	)
	(segment
		(start 55.670958 -246.210328)
		(end 56.520842 -247.060212)
		(width 0.11684)
		(layer "In13.Cu")
		(net "M_B_CPU1_RESET_N")
	)
	(segment
		(start 86.57971 -250.63704)
		(end 86.588092 -250.641866)
		(width 0.0889)
		(layer "In13.Cu")
		(net "M_B_CPU1_RESET_N")
	)
	(segment
		(start 63.356998 -250.318524)
		(end 73.744582 -250.318524)
		(width 0.11684)
		(layer "In13.Cu")
		(net "M_B_CPU1_RESET_N")
	)
	(segment
		(start 47.784004 -244.935248)
		(end 50.35169 -244.935248)
		(width 0.11684)
		(layer "In13.Cu")
		(net "M_B_CPU1_RESET_N")
	)
	(segment
		(start 78.591664 -250.738132)
		(end 78.655164 -250.674632)
		(width 0.0889)
		(layer "In13.Cu")
		(net "M_B_CPU1_RESET_N")
	)
	(segment
		(start 82.453988 -250.641866)
		(end 82.46237 -250.63704)
		(width 0.0889)
		(layer "In13.Cu")
		(net "M_B_CPU1_RESET_N")
	)
	(segment
		(start 85.639656 -250.63704)
		(end 85.648038 -250.641866)
		(width 0.0889)
		(layer "In13.Cu")
		(net "M_B_CPU1_RESET_N")
	)
	(arc
		(start 88.10244 -250.63704)
		(mid 88.285948 -250.591546)
		(end 88.4682 -250.641866)
		(width 0.0889)
		(layer "In13.Cu")
		(net "M_B_CPU1_RESET_N")
	)
	(arc
		(start 84.707984 -250.641866)
		(mid 84.99094 -250.718043)
		(end 85.273896 -250.641866)
		(width 0.0889)
		(layer "In13.Cu")
		(net "M_B_CPU1_RESET_N")
	)
	(arc
		(start 84.334096 -250.641866)
		(mid 84.52104 -250.591611)
		(end 84.707984 -250.641866)
		(width 0.0889)
		(layer "In13.Cu")
		(net "M_B_CPU1_RESET_N")
	)
	(arc
		(start 82.46237 -250.63704)
		(mid 82.645878 -250.591546)
		(end 82.82813 -250.641866)
		(width 0.0889)
		(layer "In13.Cu")
		(net "M_B_CPU1_RESET_N")
	)
	(arc
		(start 87.528146 -250.641866)
		(mid 87.811102 -250.718043)
		(end 88.094058 -250.641866)
		(width 0.0889)
		(layer "In13.Cu")
		(net "M_B_CPU1_RESET_N")
	)
	(arc
		(start 82.82813 -250.641866)
		(mid 83.111086 -250.718043)
		(end 83.394042 -250.641866)
		(width 0.0889)
		(layer "In13.Cu")
		(net "M_B_CPU1_RESET_N")
	)
	(arc
		(start 83.768184 -250.641866)
		(mid 84.05114 -250.718043)
		(end 84.334096 -250.641866)
		(width 0.0889)
		(layer "In13.Cu")
		(net "M_B_CPU1_RESET_N")
	)
	(arc
		(start 88.4682 -250.641866)
		(mid 88.715913 -250.717086)
		(end 88.97112 -250.673616)
		(width 0.0889)
		(layer "In13.Cu")
		(net "M_B_CPU1_RESET_N")
	)
	(arc
		(start 81.513934 -250.641866)
		(mid 81.696185 -250.591516)
		(end 81.879694 -250.63704)
		(width 0.0889)
		(layer "In13.Cu")
		(net "M_B_CPU1_RESET_N")
	)
	(arc
		(start 80.948022 -250.641866)
		(mid 81.230978 -250.718043)
		(end 81.513934 -250.641866)
		(width 0.0889)
		(layer "In13.Cu")
		(net "M_B_CPU1_RESET_N")
	)
	(arc
		(start 78.728316 -250.624086)
		(mid 78.900397 -250.591927)
		(end 79.068168 -250.641866)
		(width 0.0889)
		(layer "In13.Cu")
		(net "M_B_CPU1_RESET_N")
	)
	(arc
		(start 79.068168 -250.641866)
		(mid 79.351124 -250.718043)
		(end 79.63408 -250.641866)
		(width 0.0889)
		(layer "In13.Cu")
		(net "M_B_CPU1_RESET_N")
	)
	(arc
		(start 83.402424 -250.63704)
		(mid 83.585932 -250.591546)
		(end 83.768184 -250.641866)
		(width 0.0889)
		(layer "In13.Cu")
		(net "M_B_CPU1_RESET_N")
	)
	(arc
		(start 85.273896 -250.641866)
		(mid 85.456147 -250.591516)
		(end 85.639656 -250.63704)
		(width 0.0889)
		(layer "In13.Cu")
		(net "M_B_CPU1_RESET_N")
	)
	(arc
		(start 79.642462 -250.63704)
		(mid 79.82597 -250.591546)
		(end 80.008222 -250.641866)
		(width 0.0889)
		(layer "In13.Cu")
		(net "M_B_CPU1_RESET_N")
	)
	(arc
		(start 80.008222 -250.641866)
		(mid 80.291178 -250.718043)
		(end 80.574134 -250.641866)
		(width 0.0889)
		(layer "In13.Cu")
		(net "M_B_CPU1_RESET_N")
	)
	(arc
		(start 86.588092 -250.641866)
		(mid 86.871048 -250.718043)
		(end 87.154004 -250.641866)
		(width 0.0889)
		(layer "In13.Cu")
		(net "M_B_CPU1_RESET_N")
	)
	(arc
		(start 80.574134 -250.641866)
		(mid 80.761078 -250.591611)
		(end 80.948022 -250.641866)
		(width 0.0889)
		(layer "In13.Cu")
		(net "M_B_CPU1_RESET_N")
	)
	(arc
		(start 87.162386 -250.63704)
		(mid 87.345894 -250.591546)
		(end 87.528146 -250.641866)
		(width 0.0889)
		(layer "In13.Cu")
		(net "M_B_CPU1_RESET_N")
	)
	(arc
		(start 81.888076 -250.641866)
		(mid 82.171032 -250.718043)
		(end 82.453988 -250.641866)
		(width 0.0889)
		(layer "In13.Cu")
		(net "M_B_CPU1_RESET_N")
	)
	(arc
		(start 85.648038 -250.641866)
		(mid 85.930994 -250.718043)
		(end 86.21395 -250.641866)
		(width 0.0889)
		(layer "In13.Cu")
		(net "M_B_CPU1_RESET_N")
	)
	(arc
		(start 78.5114 -250.771406)
		(mid 78.554835 -250.762748)
		(end 78.591664 -250.738132)
		(width 0.0889)
		(layer "In13.Cu")
		(net "M_B_CPU1_RESET_N")
	)
	(arc
		(start 86.21395 -250.641866)
		(mid 86.396201 -250.591516)
		(end 86.57971 -250.63704)
		(width 0.0889)
		(layer "In13.Cu")
		(net "M_B_CPU1_RESET_N")
	)
	(arc
		(start 78.655164 -250.674632)
		(mid 78.689428 -250.646012)
		(end 78.728316 -250.624086)
		(width 0.0889)
		(layer "In13.Cu")
		(net "M_B_CPU1_RESET_N")
	)
	(segment
		(start 87.8078 -256.09042)
		(end 87.340948 -255.824482)
		(width 0.14732)
		(layer "F.Cu")
		(net "M_B_CPU1_CLK_DP<0>")
	)
	(segment
		(start 65.397126 -256.432304)
		(end 52.018438 -256.432304)
		(width 0.16002)
		(layer "In13.Cu")
		(net "M_B_CPU1_CLK_DP<0>")
	)
	(segment
		(start 83.4009 -256.154428)
		(end 83.392518 -256.149602)
		(width 0.09525)
		(layer "In13.Cu")
		(net "M_B_CPU1_CLK_DP<0>")
	)
	(segment
		(start 82.460846 -256.154428)
		(end 82.452464 -256.149602)
		(width 0.09525)
		(layer "In13.Cu")
		(net "M_B_CPU1_CLK_DP<0>")
	)
	(segment
		(start 76.28509 -257.350006)
		(end 76.225908 -257.290824)
		(width 0.09525)
		(layer "In13.Cu")
		(net "M_B_CPU1_CLK_DP<0>")
	)
	(segment
		(start 87.160862 -256.154428)
		(end 87.15248 -256.149602)
		(width 0.09525)
		(layer "In13.Cu")
		(net "M_B_CPU1_CLK_DP<0>")
	)
	(segment
		(start 85.649562 -256.149602)
		(end 85.64118 -256.154428)
		(width 0.09525)
		(layer "In13.Cu")
		(net "M_B_CPU1_CLK_DP<0>")
	)
	(segment
		(start 65.999106 -255.830324)
		(end 65.397126 -256.432304)
		(width 0.16002)
		(layer "In13.Cu")
		(net "M_B_CPU1_CLK_DP<0>")
	)
	(segment
		(start 78.015338 -256.238248)
		(end 76.90358 -257.350006)
		(width 0.09525)
		(layer "In13.Cu")
		(net "M_B_CPU1_CLK_DP<0>")
	)
	(segment
		(start 71.177658 -255.830324)
		(end 65.999106 -255.830324)
		(width 0.16002)
		(layer "In13.Cu")
		(net "M_B_CPU1_CLK_DP<0>")
	)
	(segment
		(start 48.084994 -253.736348)
		(end 47.784004 -253.435358)
		(width 0.16002)
		(layer "In13.Cu")
		(net "M_B_CPU1_CLK_DP<0>")
	)
	(segment
		(start 87.340948 -255.824482)
		(end 87.494872 -256.089912)
		(width 0.09525)
		(layer "In13.Cu")
		(net "M_B_CPU1_CLK_DP<0>")
	)
	(segment
		(start 76.90358 -257.350006)
		(end 76.28509 -257.350006)
		(width 0.09525)
		(layer "In13.Cu")
		(net "M_B_CPU1_CLK_DP<0>")
	)
	(segment
		(start 78.165706 -256.129536)
		(end 78.131162 -256.149602)
		(width 0.09525)
		(layer "In13.Cu")
		(net "M_B_CPU1_CLK_DP<0>")
	)
	(segment
		(start 72.638158 -257.290824)
		(end 71.177658 -255.830324)
		(width 0.16002)
		(layer "In13.Cu")
		(net "M_B_CPU1_CLK_DP<0>")
	)
	(segment
		(start 87.494872 -256.089912)
		(end 87.471504 -256.17678)
		(width 0.09525)
		(layer "In13.Cu")
		(net "M_B_CPU1_CLK_DP<0>")
	)
	(segment
		(start 86.589616 -256.149602)
		(end 86.581234 -256.154428)
		(width 0.09525)
		(layer "In13.Cu")
		(net "M_B_CPU1_CLK_DP<0>")
	)
	(segment
		(start 76.225908 -257.290824)
		(end 76.202286 -257.290824)
		(width 0.09525)
		(layer "In13.Cu")
		(net "M_B_CPU1_CLK_DP<0>")
	)
	(segment
		(start 79.071216 -256.149602)
		(end 79.04734 -256.163318)
		(width 0.09525)
		(layer "In13.Cu")
		(net "M_B_CPU1_CLK_DP<0>")
	)
	(segment
		(start 76.202286 -257.290824)
		(end 72.638158 -257.290824)
		(width 0.16002)
		(layer "In13.Cu")
		(net "M_B_CPU1_CLK_DP<0>")
	)
	(segment
		(start 49.322482 -253.736348)
		(end 48.084994 -253.736348)
		(width 0.16002)
		(layer "In13.Cu")
		(net "M_B_CPU1_CLK_DP<0>")
	)
	(segment
		(start 79.096616 -256.13487)
		(end 79.071216 -256.149602)
		(width 0.09525)
		(layer "In13.Cu")
		(net "M_B_CPU1_CLK_DP<0>")
	)
	(segment
		(start 79.640938 -256.154428)
		(end 79.632556 -256.149602)
		(width 0.09525)
		(layer "In13.Cu")
		(net "M_B_CPU1_CLK_DP<0>")
	)
	(segment
		(start 81.8896 -256.149602)
		(end 81.881218 -256.154428)
		(width 0.09525)
		(layer "In13.Cu")
		(net "M_B_CPU1_CLK_DP<0>")
	)
	(segment
		(start 52.018438 -256.432304)
		(end 49.322482 -253.736348)
		(width 0.16002)
		(layer "In13.Cu")
		(net "M_B_CPU1_CLK_DP<0>")
	)
	(arc
		(start 84.332572 -256.149602)
		(mid 84.05114 -256.073847)
		(end 83.769708 -256.149602)
		(width 0.09525)
		(layer "In13.Cu")
		(net "M_B_CPU1_CLK_DP<0>")
	)
	(arc
		(start 80.009746 -256.149602)
		(mid 79.825971 -256.200374)
		(end 79.640938 -256.154428)
		(width 0.09525)
		(layer "In13.Cu")
		(net "M_B_CPU1_CLK_DP<0>")
	)
	(arc
		(start 82.829654 -256.149602)
		(mid 82.645879 -256.200374)
		(end 82.460846 -256.154428)
		(width 0.09525)
		(layer "In13.Cu")
		(net "M_B_CPU1_CLK_DP<0>")
	)
	(arc
		(start 87.15248 -256.149602)
		(mid 86.871048 -256.073847)
		(end 86.589616 -256.149602)
		(width 0.09525)
		(layer "In13.Cu")
		(net "M_B_CPU1_CLK_DP<0>")
	)
	(arc
		(start 78.131162 -256.149602)
		(mid 78.084744 -256.179518)
		(end 78.0415 -256.213864)
		(width 0.09525)
		(layer "In13.Cu")
		(net "M_B_CPU1_CLK_DP<0>")
	)
	(arc
		(start 78.693772 -256.149602)
		(mid 78.432236 -256.073489)
		(end 78.165706 -256.129536)
		(width 0.09525)
		(layer "In13.Cu")
		(net "M_B_CPU1_CLK_DP<0>")
	)
	(arc
		(start 85.64118 -256.154428)
		(mid 85.456148 -256.200342)
		(end 85.272372 -256.149602)
		(width 0.09525)
		(layer "In13.Cu")
		(net "M_B_CPU1_CLK_DP<0>")
	)
	(arc
		(start 86.212426 -256.149602)
		(mid 85.930994 -256.073847)
		(end 85.649562 -256.149602)
		(width 0.09525)
		(layer "In13.Cu")
		(net "M_B_CPU1_CLK_DP<0>")
	)
	(arc
		(start 86.581234 -256.154428)
		(mid 86.396202 -256.200342)
		(end 86.212426 -256.149602)
		(width 0.09525)
		(layer "In13.Cu")
		(net "M_B_CPU1_CLK_DP<0>")
	)
	(arc
		(start 80.57261 -256.149602)
		(mid 80.291178 -256.073847)
		(end 80.009746 -256.149602)
		(width 0.09525)
		(layer "In13.Cu")
		(net "M_B_CPU1_CLK_DP<0>")
	)
	(arc
		(start 83.392518 -256.149602)
		(mid 83.111086 -256.073847)
		(end 82.829654 -256.149602)
		(width 0.09525)
		(layer "In13.Cu")
		(net "M_B_CPU1_CLK_DP<0>")
	)
	(arc
		(start 81.51241 -256.149602)
		(mid 81.230978 -256.073847)
		(end 80.949546 -256.149602)
		(width 0.09525)
		(layer "In13.Cu")
		(net "M_B_CPU1_CLK_DP<0>")
	)
	(arc
		(start 85.272372 -256.149602)
		(mid 84.99094 -256.073847)
		(end 84.709508 -256.149602)
		(width 0.09525)
		(layer "In13.Cu")
		(net "M_B_CPU1_CLK_DP<0>")
	)
	(arc
		(start 87.471504 -256.17678)
		(mid 87.313754 -256.199299)
		(end 87.160862 -256.154428)
		(width 0.09525)
		(layer "In13.Cu")
		(net "M_B_CPU1_CLK_DP<0>")
	)
	(arc
		(start 82.452464 -256.149602)
		(mid 82.171032 -256.073847)
		(end 81.8896 -256.149602)
		(width 0.09525)
		(layer "In13.Cu")
		(net "M_B_CPU1_CLK_DP<0>")
	)
	(arc
		(start 79.632556 -256.149602)
		(mid 79.366469 -256.074057)
		(end 79.096616 -256.13487)
		(width 0.09525)
		(layer "In13.Cu")
		(net "M_B_CPU1_CLK_DP<0>")
	)
	(arc
		(start 83.769708 -256.149602)
		(mid 83.585933 -256.200374)
		(end 83.4009 -256.154428)
		(width 0.09525)
		(layer "In13.Cu")
		(net "M_B_CPU1_CLK_DP<0>")
	)
	(arc
		(start 79.04734 -256.163318)
		(mid 78.868854 -256.200561)
		(end 78.693772 -256.149602)
		(width 0.09525)
		(layer "In13.Cu")
		(net "M_B_CPU1_CLK_DP<0>")
	)
	(arc
		(start 80.949546 -256.149602)
		(mid 80.761078 -256.200279)
		(end 80.57261 -256.149602)
		(width 0.09525)
		(layer "In13.Cu")
		(net "M_B_CPU1_CLK_DP<0>")
	)
	(arc
		(start 84.709508 -256.149602)
		(mid 84.52104 -256.200279)
		(end 84.332572 -256.149602)
		(width 0.09525)
		(layer "In13.Cu")
		(net "M_B_CPU1_CLK_DP<0>")
	)
	(arc
		(start 78.0415 -256.213864)
		(mid 78.028224 -256.225847)
		(end 78.015338 -256.238248)
		(width 0.09525)
		(layer "In13.Cu")
		(net "M_B_CPU1_CLK_DP<0>")
	)
	(arc
		(start 81.881218 -256.154428)
		(mid 81.696186 -256.200342)
		(end 81.51241 -256.149602)
		(width 0.09525)
		(layer "In13.Cu")
		(net "M_B_CPU1_CLK_DP<0>")
	)
	(segment
		(start 88.277954 -256.900426)
		(end 87.811102 -256.634488)
		(width 0.14732)
		(layer "F.Cu")
		(net "M_B_CPU1_CLK_DN<0>")
	)
	(segment
		(start 85.750908 -256.304542)
		(end 85.742526 -256.309368)
		(width 0.09525)
		(layer "In13.Cu")
		(net "M_B_CPU1_CLK_DN<0>")
	)
	(segment
		(start 78.145386 -256.368804)
		(end 76.980034 -257.534156)
		(width 0.09525)
		(layer "In13.Cu")
		(net "M_B_CPU1_CLK_DN<0>")
	)
	(segment
		(start 76.284836 -257.534156)
		(end 76.225908 -257.593084)
		(width 0.09525)
		(layer "In13.Cu")
		(net "M_B_CPU1_CLK_DN<0>")
	)
	(segment
		(start 79.177896 -256.300986)
		(end 79.163418 -256.309368)
		(width 0.09525)
		(layer "In13.Cu")
		(net "M_B_CPU1_CLK_DN<0>")
	)
	(segment
		(start 72.512936 -257.593084)
		(end 71.052436 -256.132584)
		(width 0.16002)
		(layer "In13.Cu")
		(net "M_B_CPU1_CLK_DN<0>")
	)
	(segment
		(start 66.124328 -256.132584)
		(end 65.522348 -256.734564)
		(width 0.16002)
		(layer "In13.Cu")
		(net "M_B_CPU1_CLK_DN<0>")
	)
	(segment
		(start 49.19726 -254.038608)
		(end 48.030638 -254.038608)
		(width 0.16002)
		(layer "In13.Cu")
		(net "M_B_CPU1_CLK_DN<0>")
	)
	(segment
		(start 79.163418 -256.309368)
		(end 79.128874 -256.329434)
		(width 0.09525)
		(layer "In13.Cu")
		(net "M_B_CPU1_CLK_DN<0>")
	)
	(segment
		(start 87.811102 -256.634488)
		(end 87.657178 -256.369058)
		(width 0.09525)
		(layer "In13.Cu")
		(net "M_B_CPU1_CLK_DN<0>")
	)
	(segment
		(start 81.050892 -256.304542)
		(end 81.04251 -256.309368)
		(width 0.09525)
		(layer "In13.Cu")
		(net "M_B_CPU1_CLK_DN<0>")
	)
	(segment
		(start 84.239608 -256.309368)
		(end 84.231226 -256.304542)
		(width 0.09525)
		(layer "In13.Cu")
		(net "M_B_CPU1_CLK_DN<0>")
	)
	(segment
		(start 80.479646 -256.309368)
		(end 80.471264 -256.304542)
		(width 0.09525)
		(layer "In13.Cu")
		(net "M_B_CPU1_CLK_DN<0>")
	)
	(segment
		(start 71.052436 -256.132584)
		(end 66.124328 -256.132584)
		(width 0.16002)
		(layer "In13.Cu")
		(net "M_B_CPU1_CLK_DN<0>")
	)
	(segment
		(start 78.249018 -256.29489)
		(end 78.223618 -256.309368)
		(width 0.09525)
		(layer "In13.Cu")
		(net "M_B_CPU1_CLK_DN<0>")
	)
	(segment
		(start 76.225908 -257.593084)
		(end 76.202286 -257.593084)
		(width 0.09525)
		(layer "In13.Cu")
		(net "M_B_CPU1_CLK_DN<0>")
	)
	(segment
		(start 84.810854 -256.304542)
		(end 84.802472 -256.309368)
		(width 0.09525)
		(layer "In13.Cu")
		(net "M_B_CPU1_CLK_DN<0>")
	)
	(segment
		(start 65.522348 -256.734564)
		(end 51.893216 -256.734564)
		(width 0.16002)
		(layer "In13.Cu")
		(net "M_B_CPU1_CLK_DN<0>")
	)
	(segment
		(start 87.657178 -256.369058)
		(end 87.55634 -256.342388)
		(width 0.09525)
		(layer "In13.Cu")
		(net "M_B_CPU1_CLK_DN<0>")
	)
	(segment
		(start 83.299554 -256.309368)
		(end 83.291172 -256.304542)
		(width 0.09525)
		(layer "In13.Cu")
		(net "M_B_CPU1_CLK_DN<0>")
	)
	(segment
		(start 76.980034 -257.534156)
		(end 76.284836 -257.534156)
		(width 0.09525)
		(layer "In13.Cu")
		(net "M_B_CPU1_CLK_DN<0>")
	)
	(segment
		(start 51.893216 -256.734564)
		(end 49.19726 -254.038608)
		(width 0.16002)
		(layer "In13.Cu")
		(net "M_B_CPU1_CLK_DN<0>")
	)
	(segment
		(start 76.202286 -257.593084)
		(end 72.512936 -257.593084)
		(width 0.16002)
		(layer "In13.Cu")
		(net "M_B_CPU1_CLK_DN<0>")
	)
	(segment
		(start 48.030638 -254.038608)
		(end 47.784004 -254.285242)
		(width 0.16002)
		(layer "In13.Cu")
		(net "M_B_CPU1_CLK_DN<0>")
	)
	(arc
		(start 85.742526 -256.309368)
		(mid 85.461094 -256.385123)
		(end 85.179662 -256.309368)
		(width 0.09525)
		(layer "In13.Cu")
		(net "M_B_CPU1_CLK_DN<0>")
	)
	(arc
		(start 82.3595 -256.309368)
		(mid 82.171032 -256.258691)
		(end 81.982564 -256.309368)
		(width 0.09525)
		(layer "In13.Cu")
		(net "M_B_CPU1_CLK_DN<0>")
	)
	(arc
		(start 83.862418 -256.309368)
		(mid 83.580986 -256.385123)
		(end 83.299554 -256.309368)
		(width 0.09525)
		(layer "In13.Cu")
		(net "M_B_CPU1_CLK_DN<0>")
	)
	(arc
		(start 79.539592 -256.309368)
		(mid 79.35982 -256.258792)
		(end 79.177896 -256.300986)
		(width 0.09525)
		(layer "In13.Cu")
		(net "M_B_CPU1_CLK_DN<0>")
	)
	(arc
		(start 79.128874 -256.329434)
		(mid 78.862348 -256.385371)
		(end 78.600808 -256.309368)
		(width 0.09525)
		(layer "In13.Cu")
		(net "M_B_CPU1_CLK_DN<0>")
	)
	(arc
		(start 85.179662 -256.309368)
		(mid 84.995887 -256.258596)
		(end 84.810854 -256.304542)
		(width 0.09525)
		(layer "In13.Cu")
		(net "M_B_CPU1_CLK_DN<0>")
	)
	(arc
		(start 78.600808 -256.309368)
		(mid 78.426719 -256.258496)
		(end 78.249018 -256.29489)
		(width 0.09525)
		(layer "In13.Cu")
		(net "M_B_CPU1_CLK_DN<0>")
	)
	(arc
		(start 81.04251 -256.309368)
		(mid 80.761078 -256.385123)
		(end 80.479646 -256.309368)
		(width 0.09525)
		(layer "In13.Cu")
		(net "M_B_CPU1_CLK_DN<0>")
	)
	(arc
		(start 83.291172 -256.304542)
		(mid 83.10614 -256.258628)
		(end 82.922364 -256.309368)
		(width 0.09525)
		(layer "In13.Cu")
		(net "M_B_CPU1_CLK_DN<0>")
	)
	(arc
		(start 87.55634 -256.342388)
		(mid 87.304056 -256.384082)
		(end 87.059516 -256.309368)
		(width 0.09525)
		(layer "In13.Cu")
		(net "M_B_CPU1_CLK_DN<0>")
	)
	(arc
		(start 84.802472 -256.309368)
		(mid 84.52104 -256.385123)
		(end 84.239608 -256.309368)
		(width 0.09525)
		(layer "In13.Cu")
		(net "M_B_CPU1_CLK_DN<0>")
	)
	(arc
		(start 80.471264 -256.304542)
		(mid 80.286232 -256.258628)
		(end 80.102456 -256.309368)
		(width 0.09525)
		(layer "In13.Cu")
		(net "M_B_CPU1_CLK_DN<0>")
	)
	(arc
		(start 82.922364 -256.309368)
		(mid 82.640932 -256.385123)
		(end 82.3595 -256.309368)
		(width 0.09525)
		(layer "In13.Cu")
		(net "M_B_CPU1_CLK_DN<0>")
	)
	(arc
		(start 81.4197 -256.309368)
		(mid 81.235925 -256.258596)
		(end 81.050892 -256.304542)
		(width 0.09525)
		(layer "In13.Cu")
		(net "M_B_CPU1_CLK_DN<0>")
	)
	(arc
		(start 86.68258 -256.309368)
		(mid 86.401148 -256.385123)
		(end 86.119716 -256.309368)
		(width 0.09525)
		(layer "In13.Cu")
		(net "M_B_CPU1_CLK_DN<0>")
	)
	(arc
		(start 87.059516 -256.309368)
		(mid 86.871048 -256.258691)
		(end 86.68258 -256.309368)
		(width 0.09525)
		(layer "In13.Cu")
		(net "M_B_CPU1_CLK_DN<0>")
	)
	(arc
		(start 86.119716 -256.309368)
		(mid 85.935941 -256.258596)
		(end 85.750908 -256.304542)
		(width 0.09525)
		(layer "In13.Cu")
		(net "M_B_CPU1_CLK_DN<0>")
	)
	(arc
		(start 81.982564 -256.309368)
		(mid 81.701132 -256.385123)
		(end 81.4197 -256.309368)
		(width 0.09525)
		(layer "In13.Cu")
		(net "M_B_CPU1_CLK_DN<0>")
	)
	(arc
		(start 78.162658 -256.352802)
		(mid 78.153897 -256.360668)
		(end 78.145386 -256.368804)
		(width 0.09525)
		(layer "In13.Cu")
		(net "M_B_CPU1_CLK_DN<0>")
	)
	(arc
		(start 80.102456 -256.309368)
		(mid 79.821024 -256.385123)
		(end 79.539592 -256.309368)
		(width 0.09525)
		(layer "In13.Cu")
		(net "M_B_CPU1_CLK_DN<0>")
	)
	(arc
		(start 78.223618 -256.309368)
		(mid 78.192063 -256.329575)
		(end 78.162658 -256.352802)
		(width 0.09525)
		(layer "In13.Cu")
		(net "M_B_CPU1_CLK_DN<0>")
	)
	(arc
		(start 84.231226 -256.304542)
		(mid 84.046194 -256.258628)
		(end 83.862418 -256.309368)
		(width 0.09525)
		(layer "In13.Cu")
		(net "M_B_CPU1_CLK_DN<0>")
	)
	(segment
		(start 89.218008 -250.420378)
		(end 88.751156 -250.15444)
		(width 0.10668)
		(layer "F.Cu")
		(net "M_B_CPU1_ALERT_R_N")
	)
	(segment
		(start 63.553086 -249.891804)
		(end 73.921366 -249.891804)
		(width 0.11684)
		(layer "In13.Cu")
		(net "M_B_CPU1_ALERT_R_N")
	)
	(segment
		(start 77.02169 -250.400566)
		(end 77.940154 -250.400566)
		(width 0.0889)
		(layer "In13.Cu")
		(net "M_B_CPU1_ALERT_R_N")
	)
	(segment
		(start 88.882728 -250.503182)
		(end 88.90508 -250.41987)
		(width 0.0889)
		(layer "In13.Cu")
		(net "M_B_CPU1_ALERT_R_N")
	)
	(segment
		(start 80.46974 -250.481846)
		(end 80.478122 -250.47702)
		(width 0.0889)
		(layer "In13.Cu")
		(net "M_B_CPU1_ALERT_R_N")
	)
	(segment
		(start 74.36866 -250.339098)
		(end 76.306934 -250.339098)
		(width 0.11684)
		(layer "In13.Cu")
		(net "M_B_CPU1_ALERT_R_N")
	)
	(segment
		(start 84.229702 -250.481846)
		(end 84.238084 -250.47702)
		(width 0.0889)
		(layer "In13.Cu")
		(net "M_B_CPU1_ALERT_R_N")
	)
	(segment
		(start 56.85155 -246.210328)
		(end 59.87161 -246.210328)
		(width 0.11684)
		(layer "In13.Cu")
		(net "M_B_CPU1_ALERT_R_N")
	)
	(segment
		(start 73.921366 -249.891804)
		(end 74.36866 -250.339098)
		(width 0.11684)
		(layer "In13.Cu")
		(net "M_B_CPU1_ALERT_R_N")
	)
	(segment
		(start 79.529686 -250.481846)
		(end 79.538068 -250.47702)
		(width 0.0889)
		(layer "In13.Cu")
		(net "M_B_CPU1_ALERT_R_N")
	)
	(segment
		(start 78.58633 -250.483878)
		(end 78.598014 -250.47702)
		(width 0.0889)
		(layer "In13.Cu")
		(net "M_B_CPU1_ALERT_R_N")
	)
	(segment
		(start 87.989664 -250.481846)
		(end 87.998046 -250.47702)
		(width 0.0889)
		(layer "In13.Cu")
		(net "M_B_CPU1_ALERT_R_N")
	)
	(segment
		(start 83.289648 -250.481846)
		(end 83.29803 -250.47702)
		(width 0.0889)
		(layer "In13.Cu")
		(net "M_B_CPU1_ALERT_R_N")
	)
	(segment
		(start 59.87161 -246.210328)
		(end 63.553086 -249.891804)
		(width 0.11684)
		(layer "In13.Cu")
		(net "M_B_CPU1_ALERT_R_N")
	)
	(segment
		(start 56.001666 -245.360444)
		(end 56.85155 -246.210328)
		(width 0.11684)
		(layer "In13.Cu")
		(net "M_B_CPU1_ALERT_R_N")
	)
	(segment
		(start 85.74405 -250.47702)
		(end 85.752432 -250.481846)
		(width 0.0889)
		(layer "In13.Cu")
		(net "M_B_CPU1_ALERT_R_N")
	)
	(segment
		(start 54.527958 -244.537484)
		(end 55.350918 -245.360444)
		(width 0.11684)
		(layer "In13.Cu")
		(net "M_B_CPU1_ALERT_R_N")
	)
	(segment
		(start 53.281072 -244.085364)
		(end 53.733192 -244.537484)
		(width 0.11684)
		(layer "In13.Cu")
		(net "M_B_CPU1_ALERT_R_N")
	)
	(segment
		(start 53.733192 -244.537484)
		(end 54.527958 -244.537484)
		(width 0.11684)
		(layer "In13.Cu")
		(net "M_B_CPU1_ALERT_R_N")
	)
	(segment
		(start 84.803996 -250.47702)
		(end 84.812378 -250.481846)
		(width 0.0889)
		(layer "In13.Cu")
		(net "M_B_CPU1_ALERT_R_N")
	)
	(segment
		(start 88.90508 -250.41987)
		(end 88.751156 -250.15444)
		(width 0.0889)
		(layer "In13.Cu")
		(net "M_B_CPU1_ALERT_R_N")
	)
	(segment
		(start 76.960222 -250.339098)
		(end 77.02169 -250.400566)
		(width 0.0889)
		(layer "In13.Cu")
		(net "M_B_CPU1_ALERT_R_N")
	)
	(segment
		(start 76.306934 -250.339098)
		(end 76.960222 -250.339098)
		(width 0.0889)
		(layer "In13.Cu")
		(net "M_B_CPU1_ALERT_R_N")
	)
	(segment
		(start 55.350918 -245.360444)
		(end 56.001666 -245.360444)
		(width 0.11684)
		(layer "In13.Cu")
		(net "M_B_CPU1_ALERT_R_N")
	)
	(segment
		(start 81.044034 -250.47702)
		(end 81.052416 -250.481846)
		(width 0.0889)
		(layer "In13.Cu")
		(net "M_B_CPU1_ALERT_R_N")
	)
	(arc
		(start 81.052416 -250.481846)
		(mid 81.235924 -250.52734)
		(end 81.418176 -250.47702)
		(width 0.0889)
		(layer "In13.Cu")
		(net "M_B_CPU1_ALERT_R_N")
	)
	(arc
		(start 84.812378 -250.481846)
		(mid 84.995886 -250.52734)
		(end 85.178138 -250.47702)
		(width 0.0889)
		(layer "In13.Cu")
		(net "M_B_CPU1_ALERT_R_N")
	)
	(arc
		(start 86.684104 -250.47702)
		(mid 86.871048 -250.527275)
		(end 87.057992 -250.47702)
		(width 0.0889)
		(layer "In13.Cu")
		(net "M_B_CPU1_ALERT_R_N")
	)
	(arc
		(start 85.178138 -250.47702)
		(mid 85.461094 -250.400843)
		(end 85.74405 -250.47702)
		(width 0.0889)
		(layer "In13.Cu")
		(net "M_B_CPU1_ALERT_R_N")
	)
	(arc
		(start 85.752432 -250.481846)
		(mid 85.93594 -250.52734)
		(end 86.118192 -250.47702)
		(width 0.0889)
		(layer "In13.Cu")
		(net "M_B_CPU1_ALERT_R_N")
	)
	(arc
		(start 82.923888 -250.47702)
		(mid 83.106139 -250.52737)
		(end 83.289648 -250.481846)
		(width 0.0889)
		(layer "In13.Cu")
		(net "M_B_CPU1_ALERT_R_N")
	)
	(arc
		(start 82.357976 -250.47702)
		(mid 82.640932 -250.400843)
		(end 82.923888 -250.47702)
		(width 0.0889)
		(layer "In13.Cu")
		(net "M_B_CPU1_ALERT_R_N")
	)
	(arc
		(start 80.478122 -250.47702)
		(mid 80.761078 -250.400843)
		(end 81.044034 -250.47702)
		(width 0.0889)
		(layer "In13.Cu")
		(net "M_B_CPU1_ALERT_R_N")
	)
	(arc
		(start 79.163926 -250.47702)
		(mid 79.346177 -250.52737)
		(end 79.529686 -250.481846)
		(width 0.0889)
		(layer "In13.Cu")
		(net "M_B_CPU1_ALERT_R_N")
	)
	(arc
		(start 78.598014 -250.47702)
		(mid 78.88097 -250.400843)
		(end 79.163926 -250.47702)
		(width 0.0889)
		(layer "In13.Cu")
		(net "M_B_CPU1_ALERT_R_N")
	)
	(arc
		(start 83.863942 -250.47702)
		(mid 84.046193 -250.52737)
		(end 84.229702 -250.481846)
		(width 0.0889)
		(layer "In13.Cu")
		(net "M_B_CPU1_ALERT_R_N")
	)
	(arc
		(start 88.563958 -250.47702)
		(mid 88.720396 -250.525991)
		(end 88.882728 -250.503182)
		(width 0.0889)
		(layer "In13.Cu")
		(net "M_B_CPU1_ALERT_R_N")
	)
	(arc
		(start 87.998046 -250.47702)
		(mid 88.281002 -250.400843)
		(end 88.563958 -250.47702)
		(width 0.0889)
		(layer "In13.Cu")
		(net "M_B_CPU1_ALERT_R_N")
	)
	(arc
		(start 84.238084 -250.47702)
		(mid 84.52104 -250.400843)
		(end 84.803996 -250.47702)
		(width 0.0889)
		(layer "In13.Cu")
		(net "M_B_CPU1_ALERT_R_N")
	)
	(arc
		(start 78.07198 -250.41606)
		(mid 78.150021 -250.441013)
		(end 78.223618 -250.47702)
		(width 0.0889)
		(layer "In13.Cu")
		(net "M_B_CPU1_ALERT_R_N")
	)
	(arc
		(start 86.118192 -250.47702)
		(mid 86.401148 -250.400843)
		(end 86.684104 -250.47702)
		(width 0.0889)
		(layer "In13.Cu")
		(net "M_B_CPU1_ALERT_R_N")
	)
	(arc
		(start 78.223618 -250.47702)
		(mid 78.404076 -250.527464)
		(end 78.58633 -250.483878)
		(width 0.0889)
		(layer "In13.Cu")
		(net "M_B_CPU1_ALERT_R_N")
	)
	(arc
		(start 87.623904 -250.47702)
		(mid 87.806155 -250.52737)
		(end 87.989664 -250.481846)
		(width 0.0889)
		(layer "In13.Cu")
		(net "M_B_CPU1_ALERT_R_N")
	)
	(arc
		(start 81.984088 -250.47702)
		(mid 82.171032 -250.527275)
		(end 82.357976 -250.47702)
		(width 0.0889)
		(layer "In13.Cu")
		(net "M_B_CPU1_ALERT_R_N")
	)
	(arc
		(start 79.538068 -250.47702)
		(mid 79.821024 -250.400843)
		(end 80.10398 -250.47702)
		(width 0.0889)
		(layer "In13.Cu")
		(net "M_B_CPU1_ALERT_R_N")
	)
	(arc
		(start 77.940154 -250.400566)
		(mid 78.006526 -250.404408)
		(end 78.07198 -250.41606)
		(width 0.0889)
		(layer "In13.Cu")
		(net "M_B_CPU1_ALERT_R_N")
	)
	(arc
		(start 80.10398 -250.47702)
		(mid 80.286231 -250.52737)
		(end 80.46974 -250.481846)
		(width 0.0889)
		(layer "In13.Cu")
		(net "M_B_CPU1_ALERT_R_N")
	)
	(arc
		(start 87.057992 -250.47702)
		(mid 87.340948 -250.400843)
		(end 87.623904 -250.47702)
		(width 0.0889)
		(layer "In13.Cu")
		(net "M_B_CPU1_ALERT_R_N")
	)
	(arc
		(start 83.29803 -250.47702)
		(mid 83.580986 -250.400843)
		(end 83.863942 -250.47702)
		(width 0.0889)
		(layer "In13.Cu")
		(net "M_B_CPU1_ALERT_R_N")
	)
	(arc
		(start 81.418176 -250.47702)
		(mid 81.701132 -250.400843)
		(end 81.984088 -250.47702)
		(width 0.0889)
		(layer "In13.Cu")
		(net "M_B_CPU1_ALERT_R_N")
	)
	(via
		(at 51.884072 -244.085364)
		(size 0.4826)
		(drill 0.254)
		(layers "F.Cu" "B.Cu")
		(net "M_B_CPU1_ALERT_N")
	)
	(segment
		(start 52.480972 -244.085364)
		(end 51.884072 -244.085364)
		(width 0.10668)
		(layer "B.Cu")
		(net "M_B_CPU1_ALERT_N")
	)
	(segment
		(start 336.517996 -267.34008)
		(end 336.051144 -267.606018)
		(width 0.10668)
		(layer "F.Cu")
		(net "M_B_CPU0_SB_RSP<0>")
	)
	(segment
		(start 303.043336 -270.010128)
		(end 303.595786 -270.010128)
		(width 0.11684)
		(layer "In13.Cu")
		(net "M_B_CPU0_SB_RSP<0>")
	)
	(segment
		(start 304.420524 -270.010128)
		(end 304.652426 -270.010128)
		(width 0.11684)
		(layer "In13.Cu")
		(net "M_B_CPU0_SB_RSP<0>")
	)
	(segment
		(start 327.776078 -267.92301)
		(end 327.799446 -267.909294)
		(width 0.0889)
		(layer "In13.Cu")
		(net "M_B_CPU0_SB_RSP<0>")
	)
	(segment
		(start 302.746918 -269.71371)
		(end 303.043336 -270.010128)
		(width 0.11684)
		(layer "In13.Cu")
		(net "M_B_CPU0_SB_RSP<0>")
	)
	(segment
		(start 306.533804 -270.010128)
		(end 306.765706 -270.010128)
		(width 0.11684)
		(layer "In13.Cu")
		(net "M_B_CPU0_SB_RSP<0>")
	)
	(segment
		(start 308.479444 -268.591538)
		(end 310.219852 -266.85113)
		(width 0.11684)
		(layer "In13.Cu")
		(net "M_B_CPU0_SB_RSP<0>")
	)
	(segment
		(start 306.765706 -270.010128)
		(end 307.062124 -269.71371)
		(width 0.11684)
		(layer "In13.Cu")
		(net "M_B_CPU0_SB_RSP<0>")
	)
	(segment
		(start 307.294026 -269.71371)
		(end 307.590444 -270.010128)
		(width 0.11684)
		(layer "In13.Cu")
		(net "M_B_CPU0_SB_RSP<0>")
	)
	(segment
		(start 300.249082 -270.010128)
		(end 302.218598 -270.010128)
		(width 0.11684)
		(layer "In13.Cu")
		(net "M_B_CPU0_SB_RSP<0>")
	)
	(segment
		(start 331.535024 -267.92301)
		(end 331.545692 -267.916914)
		(width 0.0889)
		(layer "In13.Cu")
		(net "M_B_CPU0_SB_RSP<0>")
	)
	(segment
		(start 307.822346 -270.010128)
		(end 308.479444 -269.35303)
		(width 0.11684)
		(layer "In13.Cu")
		(net "M_B_CPU0_SB_RSP<0>")
	)
	(segment
		(start 330.59497 -267.92301)
		(end 330.605638 -267.916914)
		(width 0.0889)
		(layer "In13.Cu")
		(net "M_B_CPU0_SB_RSP<0>")
	)
	(segment
		(start 304.652426 -270.010128)
		(end 304.948844 -269.71371)
		(width 0.11684)
		(layer "In13.Cu")
		(net "M_B_CPU0_SB_RSP<0>")
	)
	(segment
		(start 336.199988 -267.862304)
		(end 336.051144 -267.606018)
		(width 0.0889)
		(layer "In13.Cu")
		(net "M_B_CPU0_SB_RSP<0>")
	)
	(segment
		(start 326.835008 -267.92301)
		(end 326.858376 -267.909294)
		(width 0.0889)
		(layer "In13.Cu")
		(net "M_B_CPU0_SB_RSP<0>")
	)
	(segment
		(start 324.392036 -266.85113)
		(end 324.771258 -267.230352)
		(width 0.0889)
		(layer "In13.Cu")
		(net "M_B_CPU0_SB_RSP<0>")
	)
	(segment
		(start 302.515016 -269.71371)
		(end 302.746918 -269.71371)
		(width 0.11684)
		(layer "In13.Cu")
		(net "M_B_CPU0_SB_RSP<0>")
	)
	(segment
		(start 304.124106 -269.71371)
		(end 304.420524 -270.010128)
		(width 0.11684)
		(layer "In13.Cu")
		(net "M_B_CPU0_SB_RSP<0>")
	)
	(segment
		(start 324.771258 -267.230352)
		(end 325.757794 -267.230352)
		(width 0.0889)
		(layer "In13.Cu")
		(net "M_B_CPU0_SB_RSP<0>")
	)
	(segment
		(start 334.916526 -267.916914)
		(end 334.927194 -267.92301)
		(width 0.0889)
		(layer "In13.Cu")
		(net "M_B_CPU0_SB_RSP<0>")
	)
	(segment
		(start 325.757794 -267.230352)
		(end 326.392286 -267.864844)
		(width 0.0889)
		(layer "In13.Cu")
		(net "M_B_CPU0_SB_RSP<0>")
	)
	(segment
		(start 307.590444 -270.010128)
		(end 307.822346 -270.010128)
		(width 0.11684)
		(layer "In13.Cu")
		(net "M_B_CPU0_SB_RSP<0>")
	)
	(segment
		(start 304.948844 -269.71371)
		(end 305.180746 -269.71371)
		(width 0.11684)
		(layer "In13.Cu")
		(net "M_B_CPU0_SB_RSP<0>")
	)
	(segment
		(start 306.005484 -269.71371)
		(end 306.237386 -269.71371)
		(width 0.11684)
		(layer "In13.Cu")
		(net "M_B_CPU0_SB_RSP<0>")
	)
	(segment
		(start 305.709066 -270.010128)
		(end 306.005484 -269.71371)
		(width 0.11684)
		(layer "In13.Cu")
		(net "M_B_CPU0_SB_RSP<0>")
	)
	(segment
		(start 327.752456 -267.936472)
		(end 327.776078 -267.92301)
		(width 0.0889)
		(layer "In13.Cu")
		(net "M_B_CPU0_SB_RSP<0>")
	)
	(segment
		(start 310.219852 -266.85113)
		(end 323.908674 -266.85113)
		(width 0.11684)
		(layer "In13.Cu")
		(net "M_B_CPU0_SB_RSP<0>")
	)
	(segment
		(start 326.468232 -267.92301)
		(end 326.484742 -267.932408)
		(width 0.0889)
		(layer "In13.Cu")
		(net "M_B_CPU0_SB_RSP<0>")
	)
	(segment
		(start 330.21651 -267.916914)
		(end 330.227178 -267.92301)
		(width 0.0889)
		(layer "In13.Cu")
		(net "M_B_CPU0_SB_RSP<0>")
	)
	(segment
		(start 336.17662 -267.950188)
		(end 336.199988 -267.862304)
		(width 0.0889)
		(layer "In13.Cu")
		(net "M_B_CPU0_SB_RSP<0>")
	)
	(segment
		(start 306.237386 -269.71371)
		(end 306.533804 -270.010128)
		(width 0.11684)
		(layer "In13.Cu")
		(net "M_B_CPU0_SB_RSP<0>")
	)
	(segment
		(start 305.180746 -269.71371)
		(end 305.477164 -270.010128)
		(width 0.11684)
		(layer "In13.Cu")
		(net "M_B_CPU0_SB_RSP<0>")
	)
	(segment
		(start 303.595786 -270.010128)
		(end 303.892204 -269.71371)
		(width 0.11684)
		(layer "In13.Cu")
		(net "M_B_CPU0_SB_RSP<0>")
	)
	(segment
		(start 305.477164 -270.010128)
		(end 305.709066 -270.010128)
		(width 0.11684)
		(layer "In13.Cu")
		(net "M_B_CPU0_SB_RSP<0>")
	)
	(segment
		(start 335.85658 -267.916914)
		(end 335.867248 -267.92301)
		(width 0.0889)
		(layer "In13.Cu")
		(net "M_B_CPU0_SB_RSP<0>")
	)
	(segment
		(start 307.062124 -269.71371)
		(end 307.294026 -269.71371)
		(width 0.11684)
		(layer "In13.Cu")
		(net "M_B_CPU0_SB_RSP<0>")
	)
	(segment
		(start 303.892204 -269.71371)
		(end 304.124106 -269.71371)
		(width 0.11684)
		(layer "In13.Cu")
		(net "M_B_CPU0_SB_RSP<0>")
	)
	(segment
		(start 323.908674 -266.85113)
		(end 324.392036 -266.85113)
		(width 0.0889)
		(layer "In13.Cu")
		(net "M_B_CPU0_SB_RSP<0>")
	)
	(segment
		(start 308.479444 -269.35303)
		(end 308.479444 -268.591538)
		(width 0.11684)
		(layer "In13.Cu")
		(net "M_B_CPU0_SB_RSP<0>")
	)
	(segment
		(start 299.82414 -270.43507)
		(end 300.249082 -270.010128)
		(width 0.11684)
		(layer "In13.Cu")
		(net "M_B_CPU0_SB_RSP<0>")
	)
	(segment
		(start 302.218598 -270.010128)
		(end 302.515016 -269.71371)
		(width 0.11684)
		(layer "In13.Cu")
		(net "M_B_CPU0_SB_RSP<0>")
	)
	(segment
		(start 333.976472 -267.916914)
		(end 333.98714 -267.92301)
		(width 0.0889)
		(layer "In13.Cu")
		(net "M_B_CPU0_SB_RSP<0>")
	)
	(arc
		(start 334.354932 -267.92301)
		(mid 334.634936 -267.845965)
		(end 334.916526 -267.916914)
		(width 0.0889)
		(layer "In13.Cu")
		(net "M_B_CPU0_SB_RSP<0>")
	)
	(arc
		(start 329.287124 -267.92301)
		(mid 329.47102 -267.97249)
		(end 329.654916 -267.92301)
		(width 0.0889)
		(layer "In13.Cu")
		(net "M_B_CPU0_SB_RSP<0>")
	)
	(arc
		(start 327.408286 -267.92301)
		(mid 327.578684 -267.972596)
		(end 327.752456 -267.936472)
		(width 0.0889)
		(layer "In13.Cu")
		(net "M_B_CPU0_SB_RSP<0>")
	)
	(arc
		(start 330.227178 -267.92301)
		(mid 330.411074 -267.97249)
		(end 330.59497 -267.92301)
		(width 0.0889)
		(layer "In13.Cu")
		(net "M_B_CPU0_SB_RSP<0>")
	)
	(arc
		(start 332.475078 -267.92301)
		(mid 332.761082 -267.846058)
		(end 333.047086 -267.92301)
		(width 0.0889)
		(layer "In13.Cu")
		(net "M_B_CPU0_SB_RSP<0>")
	)
	(arc
		(start 331.545692 -267.916914)
		(mid 331.827281 -267.84604)
		(end 332.107286 -267.92301)
		(width 0.0889)
		(layer "In13.Cu")
		(net "M_B_CPU0_SB_RSP<0>")
	)
	(arc
		(start 332.107286 -267.92301)
		(mid 332.291182 -267.97249)
		(end 332.475078 -267.92301)
		(width 0.0889)
		(layer "In13.Cu")
		(net "M_B_CPU0_SB_RSP<0>")
	)
	(arc
		(start 331.167232 -267.92301)
		(mid 331.351128 -267.97249)
		(end 331.535024 -267.92301)
		(width 0.0889)
		(layer "In13.Cu")
		(net "M_B_CPU0_SB_RSP<0>")
	)
	(arc
		(start 326.392286 -267.864844)
		(mid 326.428357 -267.89641)
		(end 326.468232 -267.92301)
		(width 0.0889)
		(layer "In13.Cu")
		(net "M_B_CPU0_SB_RSP<0>")
	)
	(arc
		(start 327.799446 -267.909294)
		(mid 328.075133 -267.846039)
		(end 328.347324 -267.92301)
		(width 0.0889)
		(layer "In13.Cu")
		(net "M_B_CPU0_SB_RSP<0>")
	)
	(arc
		(start 329.654916 -267.92301)
		(mid 329.93492 -267.845965)
		(end 330.21651 -267.916914)
		(width 0.0889)
		(layer "In13.Cu")
		(net "M_B_CPU0_SB_RSP<0>")
	)
	(arc
		(start 334.927194 -267.92301)
		(mid 335.11109 -267.97249)
		(end 335.294986 -267.92301)
		(width 0.0889)
		(layer "In13.Cu")
		(net "M_B_CPU0_SB_RSP<0>")
	)
	(arc
		(start 326.484742 -267.932408)
		(mid 326.661088 -267.97235)
		(end 326.835008 -267.92301)
		(width 0.0889)
		(layer "In13.Cu")
		(net "M_B_CPU0_SB_RSP<0>")
	)
	(arc
		(start 333.047086 -267.92301)
		(mid 333.230982 -267.97249)
		(end 333.414878 -267.92301)
		(width 0.0889)
		(layer "In13.Cu")
		(net "M_B_CPU0_SB_RSP<0>")
	)
	(arc
		(start 326.858376 -267.909294)
		(mid 327.135078 -267.845573)
		(end 327.408286 -267.92301)
		(width 0.0889)
		(layer "In13.Cu")
		(net "M_B_CPU0_SB_RSP<0>")
	)
	(arc
		(start 335.867248 -267.92301)
		(mid 336.018907 -267.970964)
		(end 336.17662 -267.950188)
		(width 0.0889)
		(layer "In13.Cu")
		(net "M_B_CPU0_SB_RSP<0>")
	)
	(arc
		(start 328.347324 -267.92301)
		(mid 328.53122 -267.97249)
		(end 328.715116 -267.92301)
		(width 0.0889)
		(layer "In13.Cu")
		(net "M_B_CPU0_SB_RSP<0>")
	)
	(arc
		(start 328.715116 -267.92301)
		(mid 329.00112 -267.846058)
		(end 329.287124 -267.92301)
		(width 0.0889)
		(layer "In13.Cu")
		(net "M_B_CPU0_SB_RSP<0>")
	)
	(arc
		(start 335.294986 -267.92301)
		(mid 335.57499 -267.845965)
		(end 335.85658 -267.916914)
		(width 0.0889)
		(layer "In13.Cu")
		(net "M_B_CPU0_SB_RSP<0>")
	)
	(arc
		(start 330.605638 -267.916914)
		(mid 330.887227 -267.84604)
		(end 331.167232 -267.92301)
		(width 0.0889)
		(layer "In13.Cu")
		(net "M_B_CPU0_SB_RSP<0>")
	)
	(arc
		(start 333.98714 -267.92301)
		(mid 334.171036 -267.97249)
		(end 334.354932 -267.92301)
		(width 0.0889)
		(layer "In13.Cu")
		(net "M_B_CPU0_SB_RSP<0>")
	)
	(arc
		(start 333.414878 -267.92301)
		(mid 333.694882 -267.845965)
		(end 333.976472 -267.916914)
		(width 0.0889)
		(layer "In13.Cu")
		(net "M_B_CPU0_SB_RSP<0>")
	)
	(segment
		(start 336.047842 -264.910062)
		(end 335.58099 -265.176)
		(width 0.10668)
		(layer "F.Cu")
		(net "M_B_CPU0_SB_PAR")
	)
	(segment
		(start 295.724072 -266.98448)
		(end 296.098468 -266.610084)
		(width 0.14478)
		(layer "In13.Cu")
		(net "M_B_CPU0_SB_PAR")
	)
	(segment
		(start 335.712816 -264.827258)
		(end 335.735168 -264.91057)
		(width 0.0889)
		(layer "In13.Cu")
		(net "M_B_CPU0_SB_PAR")
	)
	(segment
		(start 324.24497 -265.0744)
		(end 324.791578 -264.527792)
		(width 0.0889)
		(layer "In13.Cu")
		(net "M_B_CPU0_SB_PAR")
	)
	(segment
		(start 334.819752 -264.848594)
		(end 334.828134 -264.85342)
		(width 0.0889)
		(layer "In13.Cu")
		(net "M_B_CPU0_SB_PAR")
	)
	(segment
		(start 330.119736 -264.848594)
		(end 330.128118 -264.85342)
		(width 0.0889)
		(layer "In13.Cu")
		(net "M_B_CPU0_SB_PAR")
	)
	(segment
		(start 328.239882 -264.848594)
		(end 328.248264 -264.85342)
		(width 0.0889)
		(layer "In13.Cu")
		(net "M_B_CPU0_SB_PAR")
	)
	(segment
		(start 307.740304 -266.610084)
		(end 309.275988 -265.0744)
		(width 0.14478)
		(layer "In13.Cu")
		(net "M_B_CPU0_SB_PAR")
	)
	(segment
		(start 324.791578 -264.527792)
		(end 326.01535 -264.527792)
		(width 0.0889)
		(layer "In13.Cu")
		(net "M_B_CPU0_SB_PAR")
	)
	(segment
		(start 326.917812 -264.862818)
		(end 326.93356 -264.853674)
		(width 0.0889)
		(layer "In13.Cu")
		(net "M_B_CPU0_SB_PAR")
	)
	(segment
		(start 326.93356 -264.853674)
		(end 326.949816 -264.844276)
		(width 0.0889)
		(layer "In13.Cu")
		(net "M_B_CPU0_SB_PAR")
	)
	(segment
		(start 335.394046 -264.85342)
		(end 335.402428 -264.848594)
		(width 0.0889)
		(layer "In13.Cu")
		(net "M_B_CPU0_SB_PAR")
	)
	(segment
		(start 326.01535 -264.527792)
		(end 326.252332 -264.764774)
		(width 0.0889)
		(layer "In13.Cu")
		(net "M_B_CPU0_SB_PAR")
	)
	(segment
		(start 323.906134 -265.0744)
		(end 324.24497 -265.0744)
		(width 0.0889)
		(layer "In13.Cu")
		(net "M_B_CPU0_SB_PAR")
	)
	(segment
		(start 331.05979 -264.848594)
		(end 331.068172 -264.85342)
		(width 0.0889)
		(layer "In13.Cu")
		(net "M_B_CPU0_SB_PAR")
	)
	(segment
		(start 327.307448 -264.85342)
		(end 327.317862 -264.859516)
		(width 0.0889)
		(layer "In13.Cu")
		(net "M_B_CPU0_SB_PAR")
	)
	(segment
		(start 333.879698 -264.848594)
		(end 333.88808 -264.85342)
		(width 0.0889)
		(layer "In13.Cu")
		(net "M_B_CPU0_SB_PAR")
	)
	(segment
		(start 295.724072 -267.035026)
		(end 295.724072 -266.98448)
		(width 0.14478)
		(layer "In13.Cu")
		(net "M_B_CPU0_SB_PAR")
	)
	(segment
		(start 309.275988 -265.0744)
		(end 323.906134 -265.0744)
		(width 0.14478)
		(layer "In13.Cu")
		(net "M_B_CPU0_SB_PAR")
	)
	(segment
		(start 331.634084 -264.85342)
		(end 331.642466 -264.848594)
		(width 0.0889)
		(layer "In13.Cu")
		(net "M_B_CPU0_SB_PAR")
	)
	(segment
		(start 296.098468 -266.610084)
		(end 307.740304 -266.610084)
		(width 0.14478)
		(layer "In13.Cu")
		(net "M_B_CPU0_SB_PAR")
	)
	(segment
		(start 335.735168 -264.91057)
		(end 335.58099 -265.176)
		(width 0.0889)
		(layer "In13.Cu")
		(net "M_B_CPU0_SB_PAR")
	)
	(arc
		(start 326.949816 -264.844276)
		(mid 327.129798 -264.803176)
		(end 327.307448 -264.85342)
		(width 0.0889)
		(layer "In13.Cu")
		(net "M_B_CPU0_SB_PAR")
	)
	(arc
		(start 330.128118 -264.85342)
		(mid 330.411074 -264.929597)
		(end 330.69403 -264.85342)
		(width 0.0889)
		(layer "In13.Cu")
		(net "M_B_CPU0_SB_PAR")
	)
	(arc
		(start 333.88808 -264.85342)
		(mid 334.171036 -264.929597)
		(end 334.453992 -264.85342)
		(width 0.0889)
		(layer "In13.Cu")
		(net "M_B_CPU0_SB_PAR")
	)
	(arc
		(start 327.317862 -264.859516)
		(mid 327.596548 -264.929736)
		(end 327.873614 -264.85342)
		(width 0.0889)
		(layer "In13.Cu")
		(net "M_B_CPU0_SB_PAR")
	)
	(arc
		(start 331.642466 -264.848594)
		(mid 331.825974 -264.8031)
		(end 332.008226 -264.85342)
		(width 0.0889)
		(layer "In13.Cu")
		(net "M_B_CPU0_SB_PAR")
	)
	(arc
		(start 328.248264 -264.85342)
		(mid 328.53122 -264.929597)
		(end 328.814176 -264.85342)
		(width 0.0889)
		(layer "In13.Cu")
		(net "M_B_CPU0_SB_PAR")
	)
	(arc
		(start 332.948026 -264.85342)
		(mid 333.230982 -264.929597)
		(end 333.513938 -264.85342)
		(width 0.0889)
		(layer "In13.Cu")
		(net "M_B_CPU0_SB_PAR")
	)
	(arc
		(start 327.873614 -264.85342)
		(mid 328.056119 -264.802943)
		(end 328.239882 -264.848594)
		(width 0.0889)
		(layer "In13.Cu")
		(net "M_B_CPU0_SB_PAR")
	)
	(arc
		(start 329.753976 -264.85342)
		(mid 329.936227 -264.80307)
		(end 330.119736 -264.848594)
		(width 0.0889)
		(layer "In13.Cu")
		(net "M_B_CPU0_SB_PAR")
	)
	(arc
		(start 332.574138 -264.85342)
		(mid 332.761082 -264.803165)
		(end 332.948026 -264.85342)
		(width 0.0889)
		(layer "In13.Cu")
		(net "M_B_CPU0_SB_PAR")
	)
	(arc
		(start 326.252332 -264.764774)
		(mid 326.307117 -264.812834)
		(end 326.367648 -264.85342)
		(width 0.0889)
		(layer "In13.Cu")
		(net "M_B_CPU0_SB_PAR")
	)
	(arc
		(start 328.814176 -264.85342)
		(mid 329.00112 -264.803165)
		(end 329.188064 -264.85342)
		(width 0.0889)
		(layer "In13.Cu")
		(net "M_B_CPU0_SB_PAR")
	)
	(arc
		(start 334.453992 -264.85342)
		(mid 334.636243 -264.80307)
		(end 334.819752 -264.848594)
		(width 0.0889)
		(layer "In13.Cu")
		(net "M_B_CPU0_SB_PAR")
	)
	(arc
		(start 331.068172 -264.85342)
		(mid 331.351128 -264.929597)
		(end 331.634084 -264.85342)
		(width 0.0889)
		(layer "In13.Cu")
		(net "M_B_CPU0_SB_PAR")
	)
	(arc
		(start 330.69403 -264.85342)
		(mid 330.876281 -264.80307)
		(end 331.05979 -264.848594)
		(width 0.0889)
		(layer "In13.Cu")
		(net "M_B_CPU0_SB_PAR")
	)
	(arc
		(start 335.402428 -264.848594)
		(mid 335.555298 -264.803953)
		(end 335.712816 -264.827258)
		(width 0.0889)
		(layer "In13.Cu")
		(net "M_B_CPU0_SB_PAR")
	)
	(arc
		(start 329.188064 -264.85342)
		(mid 329.47102 -264.929597)
		(end 329.753976 -264.85342)
		(width 0.0889)
		(layer "In13.Cu")
		(net "M_B_CPU0_SB_PAR")
	)
	(arc
		(start 326.367648 -264.85342)
		(mid 326.641503 -264.92977)
		(end 326.917812 -264.862818)
		(width 0.0889)
		(layer "In13.Cu")
		(net "M_B_CPU0_SB_PAR")
	)
	(arc
		(start 333.513938 -264.85342)
		(mid 333.696189 -264.80307)
		(end 333.879698 -264.848594)
		(width 0.0889)
		(layer "In13.Cu")
		(net "M_B_CPU0_SB_PAR")
	)
	(arc
		(start 332.008226 -264.85342)
		(mid 332.291182 -264.929597)
		(end 332.574138 -264.85342)
		(width 0.0889)
		(layer "In13.Cu")
		(net "M_B_CPU0_SB_PAR")
	)
	(arc
		(start 334.828134 -264.85342)
		(mid 335.11109 -264.929597)
		(end 335.394046 -264.85342)
		(width 0.0889)
		(layer "In13.Cu")
		(net "M_B_CPU0_SB_PAR")
	)
	(segment
		(start 336.517996 -270.580104)
		(end 336.051144 -270.846042)
		(width 0.12954)
		(layer "F.Cu")
		(net "M_B_CPU0_SB_DQS_DP<9>")
	)
	(segment
		(start 301.979584 -275.98751)
		(end 301.775368 -275.783294)
		(width 0.16002)
		(layer "In13.Cu")
		(net "M_B_CPU0_SB_DQS_DP<9>")
	)
	(segment
		(start 328.342498 -271.171162)
		(end 328.332084 -271.165066)
		(width 0.09525)
		(layer "In13.Cu")
		(net "M_B_CPU0_SB_DQS_DP<9>")
	)
	(segment
		(start 307.466746 -275.372576)
		(end 306.810156 -275.372576)
		(width 0.16002)
		(layer "In13.Cu")
		(net "M_B_CPU0_SB_DQS_DP<9>")
	)
	(segment
		(start 324.222364 -269.592552)
		(end 323.995796 -269.592552)
		(width 0.09525)
		(layer "In13.Cu")
		(net "M_B_CPU0_SB_DQS_DP<9>")
	)
	(segment
		(start 311.80278 -270.194278)
		(end 311.80278 -270.670782)
		(width 0.16002)
		(layer "In13.Cu")
		(net "M_B_CPU0_SB_DQS_DP<9>")
	)
	(segment
		(start 310.25338 -272.585942)
		(end 310.02732 -272.585942)
		(width 0.16002)
		(layer "In13.Cu")
		(net "M_B_CPU0_SB_DQS_DP<9>")
	)
	(segment
		(start 326.48017 -271.222724)
		(end 325.401178 -270.143732)
		(width 0.09525)
		(layer "In13.Cu")
		(net "M_B_CPU0_SB_DQS_DP<9>")
	)
	(segment
		(start 312.226706 -269.770352)
		(end 311.80278 -270.194278)
		(width 0.16002)
		(layer "In13.Cu")
		(net "M_B_CPU0_SB_DQS_DP<9>")
	)
	(segment
		(start 307.75402 -275.085302)
		(end 307.466746 -275.372576)
		(width 0.16002)
		(layer "In13.Cu")
		(net "M_B_CPU0_SB_DQS_DP<9>")
	)
	(segment
		(start 323.912992 -269.53337)
		(end 313.305952 -269.53337)
		(width 0.16002)
		(layer "In13.Cu")
		(net "M_B_CPU0_SB_DQS_DP<9>")
	)
	(segment
		(start 310.02732 -272.585942)
		(end 309.95747 -272.516092)
		(width 0.16002)
		(layer "In13.Cu")
		(net "M_B_CPU0_SB_DQS_DP<9>")
	)
	(segment
		(start 309.05704 -272.940018)
		(end 309.05704 -273.416522)
		(width 0.16002)
		(layer "In13.Cu")
		(net "M_B_CPU0_SB_DQS_DP<9>")
	)
	(segment
		(start 310.49976 -272.113502)
		(end 310.49976 -272.339562)
		(width 0.16002)
		(layer "In13.Cu")
		(net "M_B_CPU0_SB_DQS_DP<9>")
	)
	(segment
		(start 309.95747 -272.516092)
		(end 309.480966 -272.516092)
		(width 0.16002)
		(layer "In13.Cu")
		(net "M_B_CPU0_SB_DQS_DP<9>")
	)
	(segment
		(start 302.897794 -274.400772)
		(end 302.524922 -274.773644)
		(width 0.16002)
		(layer "In13.Cu")
		(net "M_B_CPU0_SB_DQS_DP<9>")
	)
	(segment
		(start 335.89722 -271.111472)
		(end 335.796382 -271.138142)
		(width 0.09525)
		(layer "In13.Cu")
		(net "M_B_CPU0_SB_DQS_DP<9>")
	)
	(segment
		(start 310.42991 -272.043652)
		(end 310.49976 -272.113502)
		(width 0.16002)
		(layer "In13.Cu")
		(net "M_B_CPU0_SB_DQS_DP<9>")
	)
	(segment
		(start 327.590404 -271.222724)
		(end 326.48017 -271.222724)
		(width 0.09525)
		(layer "In13.Cu")
		(net "M_B_CPU0_SB_DQS_DP<9>")
	)
	(segment
		(start 304.876454 -275.98751)
		(end 303.99355 -275.98751)
		(width 0.16002)
		(layer "In13.Cu")
		(net "M_B_CPU0_SB_DQS_DP<9>")
	)
	(segment
		(start 311.33034 -271.143222)
		(end 310.853836 -271.143222)
		(width 0.16002)
		(layer "In13.Cu")
		(net "M_B_CPU0_SB_DQS_DP<9>")
	)
	(segment
		(start 332.47965 -271.171162)
		(end 332.471268 -271.175988)
		(width 0.09525)
		(layer "In13.Cu")
		(net "M_B_CPU0_SB_DQS_DP<9>")
	)
	(segment
		(start 310.42991 -271.567148)
		(end 310.42991 -272.043652)
		(width 0.16002)
		(layer "In13.Cu")
		(net "M_B_CPU0_SB_DQS_DP<9>")
	)
	(segment
		(start 323.936614 -269.53337)
		(end 323.912992 -269.53337)
		(width 0.09525)
		(layer "In13.Cu")
		(net "M_B_CPU0_SB_DQS_DP<9>")
	)
	(segment
		(start 313.06897 -269.770352)
		(end 312.226706 -269.770352)
		(width 0.16002)
		(layer "In13.Cu")
		(net "M_B_CPU0_SB_DQS_DP<9>")
	)
	(segment
		(start 331.539596 -271.171162)
		(end 331.531214 -271.175988)
		(width 0.09525)
		(layer "In13.Cu")
		(net "M_B_CPU0_SB_DQS_DP<9>")
	)
	(segment
		(start 333.99095 -271.175988)
		(end 333.982568 -271.171162)
		(width 0.09525)
		(layer "In13.Cu")
		(net "M_B_CPU0_SB_DQS_DP<9>")
	)
	(segment
		(start 301.775368 -275.783294)
		(end 300.072298 -275.783294)
		(width 0.16002)
		(layer "In13.Cu")
		(net "M_B_CPU0_SB_DQS_DP<9>")
	)
	(segment
		(start 303.424844 -274.400772)
		(end 302.897794 -274.400772)
		(width 0.16002)
		(layer "In13.Cu")
		(net "M_B_CPU0_SB_DQS_DP<9>")
	)
	(segment
		(start 313.305952 -269.53337)
		(end 313.06897 -269.770352)
		(width 0.16002)
		(layer "In13.Cu")
		(net "M_B_CPU0_SB_DQS_DP<9>")
	)
	(segment
		(start 307.68417 -274.789392)
		(end 307.75402 -274.859242)
		(width 0.16002)
		(layer "In13.Cu")
		(net "M_B_CPU0_SB_DQS_DP<9>")
	)
	(segment
		(start 309.05704 -273.416522)
		(end 309.12689 -273.486372)
		(width 0.16002)
		(layer "In13.Cu")
		(net "M_B_CPU0_SB_DQS_DP<9>")
	)
	(segment
		(start 310.853836 -271.143222)
		(end 310.42991 -271.567148)
		(width 0.16002)
		(layer "In13.Cu")
		(net "M_B_CPU0_SB_DQS_DP<9>")
	)
	(segment
		(start 300.072298 -275.783294)
		(end 299.82414 -275.535136)
		(width 0.16002)
		(layer "In13.Cu")
		(net "M_B_CPU0_SB_DQS_DP<9>")
	)
	(segment
		(start 329.290934 -271.175988)
		(end 329.282552 -271.171162)
		(width 0.09525)
		(layer "In13.Cu")
		(net "M_B_CPU0_SB_DQS_DP<9>")
	)
	(segment
		(start 303.797716 -274.773644)
		(end 303.424844 -274.400772)
		(width 0.16002)
		(layer "In13.Cu")
		(net "M_B_CPU0_SB_DQS_DP<9>")
	)
	(segment
		(start 328.719688 -271.171162)
		(end 328.711306 -271.175988)
		(width 0.09525)
		(layer "In13.Cu")
		(net "M_B_CPU0_SB_DQS_DP<9>")
	)
	(segment
		(start 306.58689 -275.14931)
		(end 305.714654 -275.14931)
		(width 0.16002)
		(layer "In13.Cu")
		(net "M_B_CPU0_SB_DQS_DP<9>")
	)
	(segment
		(start 311.87263 -270.966692)
		(end 311.62625 -271.213072)
		(width 0.16002)
		(layer "In13.Cu")
		(net "M_B_CPU0_SB_DQS_DP<9>")
	)
	(segment
		(start 311.80278 -270.670782)
		(end 311.87263 -270.740632)
		(width 0.16002)
		(layer "In13.Cu")
		(net "M_B_CPU0_SB_DQS_DP<9>")
	)
	(segment
		(start 324.773544 -270.143732)
		(end 324.222364 -269.592552)
		(width 0.09525)
		(layer "In13.Cu")
		(net "M_B_CPU0_SB_DQS_DP<9>")
	)
	(segment
		(start 303.797716 -275.791676)
		(end 303.797716 -274.773644)
		(width 0.16002)
		(layer "In13.Cu")
		(net "M_B_CPU0_SB_DQS_DP<9>")
	)
	(segment
		(start 308.65445 -273.958812)
		(end 308.5846 -273.888962)
		(width 0.16002)
		(layer "In13.Cu")
		(net "M_B_CPU0_SB_DQS_DP<9>")
	)
	(segment
		(start 336.051144 -270.846042)
		(end 335.89722 -271.111472)
		(width 0.09525)
		(layer "In13.Cu")
		(net "M_B_CPU0_SB_DQS_DP<9>")
	)
	(segment
		(start 307.68417 -274.312888)
		(end 307.68417 -274.789392)
		(width 0.16002)
		(layer "In13.Cu")
		(net "M_B_CPU0_SB_DQS_DP<9>")
	)
	(segment
		(start 302.524922 -274.773644)
		(end 302.524922 -275.791676)
		(width 0.16002)
		(layer "In13.Cu")
		(net "M_B_CPU0_SB_DQS_DP<9>")
	)
	(segment
		(start 308.5846 -273.888962)
		(end 308.108096 -273.888962)
		(width 0.16002)
		(layer "In13.Cu")
		(net "M_B_CPU0_SB_DQS_DP<9>")
	)
	(segment
		(start 309.12689 -273.486372)
		(end 309.12689 -273.712432)
		(width 0.16002)
		(layer "In13.Cu")
		(net "M_B_CPU0_SB_DQS_DP<9>")
	)
	(segment
		(start 303.99355 -275.98751)
		(end 303.797716 -275.791676)
		(width 0.16002)
		(layer "In13.Cu")
		(net "M_B_CPU0_SB_DQS_DP<9>")
	)
	(segment
		(start 305.714654 -275.14931)
		(end 304.876454 -275.98751)
		(width 0.16002)
		(layer "In13.Cu")
		(net "M_B_CPU0_SB_DQS_DP<9>")
	)
	(segment
		(start 310.49976 -272.339562)
		(end 310.25338 -272.585942)
		(width 0.16002)
		(layer "In13.Cu")
		(net "M_B_CPU0_SB_DQS_DP<9>")
	)
	(segment
		(start 308.108096 -273.888962)
		(end 307.68417 -274.312888)
		(width 0.16002)
		(layer "In13.Cu")
		(net "M_B_CPU0_SB_DQS_DP<9>")
	)
	(segment
		(start 311.40019 -271.213072)
		(end 311.33034 -271.143222)
		(width 0.16002)
		(layer "In13.Cu")
		(net "M_B_CPU0_SB_DQS_DP<9>")
	)
	(segment
		(start 309.12689 -273.712432)
		(end 308.88051 -273.958812)
		(width 0.16002)
		(layer "In13.Cu")
		(net "M_B_CPU0_SB_DQS_DP<9>")
	)
	(segment
		(start 333.050896 -271.175988)
		(end 333.042514 -271.171162)
		(width 0.09525)
		(layer "In13.Cu")
		(net "M_B_CPU0_SB_DQS_DP<9>")
	)
	(segment
		(start 323.995796 -269.592552)
		(end 323.936614 -269.53337)
		(width 0.09525)
		(layer "In13.Cu")
		(net "M_B_CPU0_SB_DQS_DP<9>")
	)
	(segment
		(start 308.88051 -273.958812)
		(end 308.65445 -273.958812)
		(width 0.16002)
		(layer "In13.Cu")
		(net "M_B_CPU0_SB_DQS_DP<9>")
	)
	(segment
		(start 306.810156 -275.372576)
		(end 306.58689 -275.14931)
		(width 0.16002)
		(layer "In13.Cu")
		(net "M_B_CPU0_SB_DQS_DP<9>")
	)
	(segment
		(start 311.62625 -271.213072)
		(end 311.40019 -271.213072)
		(width 0.16002)
		(layer "In13.Cu")
		(net "M_B_CPU0_SB_DQS_DP<9>")
	)
	(segment
		(start 311.87263 -270.740632)
		(end 311.87263 -270.966692)
		(width 0.16002)
		(layer "In13.Cu")
		(net "M_B_CPU0_SB_DQS_DP<9>")
	)
	(segment
		(start 302.329088 -275.98751)
		(end 301.979584 -275.98751)
		(width 0.16002)
		(layer "In13.Cu")
		(net "M_B_CPU0_SB_DQS_DP<9>")
	)
	(segment
		(start 325.401178 -270.143732)
		(end 324.773544 -270.143732)
		(width 0.09525)
		(layer "In13.Cu")
		(net "M_B_CPU0_SB_DQS_DP<9>")
	)
	(segment
		(start 309.480966 -272.516092)
		(end 309.05704 -272.940018)
		(width 0.16002)
		(layer "In13.Cu")
		(net "M_B_CPU0_SB_DQS_DP<9>")
	)
	(segment
		(start 307.75402 -274.859242)
		(end 307.75402 -275.085302)
		(width 0.16002)
		(layer "In13.Cu")
		(net "M_B_CPU0_SB_DQS_DP<9>")
	)
	(segment
		(start 302.524922 -275.791676)
		(end 302.329088 -275.98751)
		(width 0.16002)
		(layer "In13.Cu")
		(net "M_B_CPU0_SB_DQS_DP<9>")
	)
	(arc
		(start 331.162406 -271.171162)
		(mid 330.880974 -271.095407)
		(end 330.599542 -271.171162)
		(width 0.09525)
		(layer "In13.Cu")
		(net "M_B_CPU0_SB_DQS_DP<9>")
	)
	(arc
		(start 328.711306 -271.175988)
		(mid 328.526274 -271.221902)
		(end 328.342498 -271.171162)
		(width 0.09525)
		(layer "In13.Cu")
		(net "M_B_CPU0_SB_DQS_DP<9>")
	)
	(arc
		(start 332.10246 -271.171162)
		(mid 331.821028 -271.095407)
		(end 331.539596 -271.171162)
		(width 0.09525)
		(layer "In13.Cu")
		(net "M_B_CPU0_SB_DQS_DP<9>")
	)
	(arc
		(start 331.531214 -271.175988)
		(mid 331.346182 -271.221902)
		(end 331.162406 -271.171162)
		(width 0.09525)
		(layer "In13.Cu")
		(net "M_B_CPU0_SB_DQS_DP<9>")
	)
	(arc
		(start 333.419704 -271.171162)
		(mid 333.235929 -271.221934)
		(end 333.050896 -271.175988)
		(width 0.09525)
		(layer "In13.Cu")
		(net "M_B_CPU0_SB_DQS_DP<9>")
	)
	(arc
		(start 334.359758 -271.171162)
		(mid 334.175983 -271.221934)
		(end 333.99095 -271.175988)
		(width 0.09525)
		(layer "In13.Cu")
		(net "M_B_CPU0_SB_DQS_DP<9>")
	)
	(arc
		(start 333.042514 -271.171162)
		(mid 332.761082 -271.095407)
		(end 332.47965 -271.171162)
		(width 0.09525)
		(layer "In13.Cu")
		(net "M_B_CPU0_SB_DQS_DP<9>")
	)
	(arc
		(start 329.282552 -271.171162)
		(mid 329.00112 -271.095407)
		(end 328.719688 -271.171162)
		(width 0.09525)
		(layer "In13.Cu")
		(net "M_B_CPU0_SB_DQS_DP<9>")
	)
	(arc
		(start 330.599542 -271.171162)
		(mid 330.411074 -271.221839)
		(end 330.222606 -271.171162)
		(width 0.09525)
		(layer "In13.Cu")
		(net "M_B_CPU0_SB_DQS_DP<9>")
	)
	(arc
		(start 333.982568 -271.171162)
		(mid 333.701136 -271.095407)
		(end 333.419704 -271.171162)
		(width 0.09525)
		(layer "In13.Cu")
		(net "M_B_CPU0_SB_DQS_DP<9>")
	)
	(arc
		(start 329.659742 -271.171162)
		(mid 329.475967 -271.221934)
		(end 329.290934 -271.175988)
		(width 0.09525)
		(layer "In13.Cu")
		(net "M_B_CPU0_SB_DQS_DP<9>")
	)
	(arc
		(start 332.471268 -271.175988)
		(mid 332.286236 -271.221902)
		(end 332.10246 -271.171162)
		(width 0.09525)
		(layer "In13.Cu")
		(net "M_B_CPU0_SB_DQS_DP<9>")
	)
	(arc
		(start 334.922622 -271.171162)
		(mid 334.64119 -271.095407)
		(end 334.359758 -271.171162)
		(width 0.09525)
		(layer "In13.Cu")
		(net "M_B_CPU0_SB_DQS_DP<9>")
	)
	(arc
		(start 328.332084 -271.165066)
		(mid 328.054922 -271.095266)
		(end 327.77938 -271.171162)
		(width 0.09525)
		(layer "In13.Cu")
		(net "M_B_CPU0_SB_DQS_DP<9>")
	)
	(arc
		(start 335.299558 -271.171162)
		(mid 335.11109 -271.221839)
		(end 334.922622 -271.171162)
		(width 0.09525)
		(layer "In13.Cu")
		(net "M_B_CPU0_SB_DQS_DP<9>")
	)
	(arc
		(start 335.796382 -271.138142)
		(mid 335.544098 -271.096448)
		(end 335.299558 -271.171162)
		(width 0.09525)
		(layer "In13.Cu")
		(net "M_B_CPU0_SB_DQS_DP<9>")
	)
	(arc
		(start 330.222606 -271.171162)
		(mid 329.941174 -271.095407)
		(end 329.659742 -271.171162)
		(width 0.09525)
		(layer "In13.Cu")
		(net "M_B_CPU0_SB_DQS_DP<9>")
	)
	(arc
		(start 327.77938 -271.171162)
		(mid 327.688303 -271.209446)
		(end 327.590404 -271.222724)
		(width 0.09525)
		(layer "In13.Cu")
		(net "M_B_CPU0_SB_DQS_DP<9>")
	)
	(segment
		(start 337.45805 -291.640006)
		(end 336.991198 -291.905944)
		(width 0.12954)
		(layer "F.Cu")
		(net "M_B_CPU0_SB_DQS_DP<8>")
	)
	(segment
		(start 329.290934 -291.575998)
		(end 329.282552 -291.580824)
		(width 0.09525)
		(layer "In13.Cu")
		(net "M_B_CPU0_SB_DQS_DP<8>")
	)
	(segment
		(start 319.286128 -303.958752)
		(end 310.34228 -312.9026)
		(width 0.16002)
		(layer "In13.Cu")
		(net "M_B_CPU0_SB_DQS_DP<8>")
	)
	(segment
		(start 325.314564 -295.444672)
		(end 325.315072 -295.444926)
		(width 0.09525)
		(layer "In13.Cu")
		(net "M_B_CPU0_SB_DQS_DP<8>")
	)
	(segment
		(start 333.050896 -291.575998)
		(end 333.042514 -291.580824)
		(width 0.09525)
		(layer "In13.Cu")
		(net "M_B_CPU0_SB_DQS_DP<8>")
	)
	(segment
		(start 296.483786 -314.182252)
		(end 296.314368 -314.35167)
		(width 0.16002)
		(layer "In13.Cu")
		(net "M_B_CPU0_SB_DQS_DP<8>")
	)
	(segment
		(start 325.666608 -294.44442)
		(end 325.666608 -295.093898)
		(width 0.09525)
		(layer "In13.Cu")
		(net "M_B_CPU0_SB_DQS_DP<8>")
	)
	(segment
		(start 327.697338 -291.656516)
		(end 326.927718 -292.42639)
		(width 0.09525)
		(layer "In13.Cu")
		(net "M_B_CPU0_SB_DQS_DP<8>")
	)
	(segment
		(start 325.666608 -295.093898)
		(end 325.314564 -295.444672)
		(width 0.09525)
		(layer "In13.Cu")
		(net "M_B_CPU0_SB_DQS_DP<8>")
	)
	(segment
		(start 325.809864 -294.099234)
		(end 325.666608 -294.44442)
		(width 0.09525)
		(layer "In13.Cu")
		(net "M_B_CPU0_SB_DQS_DP<8>")
	)
	(segment
		(start 296.314368 -314.35167)
		(end 296.007536 -314.35167)
		(width 0.16002)
		(layer "In13.Cu")
		(net "M_B_CPU0_SB_DQS_DP<8>")
	)
	(segment
		(start 304.991008 -314.98921)
		(end 299.419772 -314.98921)
		(width 0.16002)
		(layer "In13.Cu")
		(net "M_B_CPU0_SB_DQS_DP<8>")
	)
	(segment
		(start 331.539596 -291.580824)
		(end 331.531214 -291.575998)
		(width 0.09525)
		(layer "In13.Cu")
		(net "M_B_CPU0_SB_DQS_DP<8>")
	)
	(segment
		(start 328.061066 -291.656516)
		(end 327.697338 -291.656516)
		(width 0.09525)
		(layer "In13.Cu")
		(net "M_B_CPU0_SB_DQS_DP<8>")
	)
	(segment
		(start 336.991198 -291.905944)
		(end 337.145122 -291.640514)
		(width 0.09525)
		(layer "In13.Cu")
		(net "M_B_CPU0_SB_DQS_DP<8>")
	)
	(segment
		(start 305.782726 -314.197492)
		(end 304.991008 -314.98921)
		(width 0.16002)
		(layer "In13.Cu")
		(net "M_B_CPU0_SB_DQS_DP<8>")
	)
	(segment
		(start 322.594478 -299.447966)
		(end 319.286128 -302.756316)
		(width 0.16002)
		(layer "In13.Cu")
		(net "M_B_CPU0_SB_DQS_DP<8>")
	)
	(segment
		(start 296.007536 -314.35167)
		(end 295.724072 -314.635134)
		(width 0.16002)
		(layer "In13.Cu")
		(net "M_B_CPU0_SB_DQS_DP<8>")
	)
	(segment
		(start 332.47965 -291.580824)
		(end 332.471268 -291.575998)
		(width 0.09525)
		(layer "In13.Cu")
		(net "M_B_CPU0_SB_DQS_DP<8>")
	)
	(segment
		(start 325.31431 -295.528238)
		(end 325.297546 -295.545002)
		(width 0.09525)
		(layer "In13.Cu")
		(net "M_B_CPU0_SB_DQS_DP<8>")
	)
	(segment
		(start 328.719688 -291.580824)
		(end 328.711306 -291.575998)
		(width 0.09525)
		(layer "In13.Cu")
		(net "M_B_CPU0_SB_DQS_DP<8>")
	)
	(segment
		(start 298.6278 -314.182252)
		(end 296.483786 -314.182252)
		(width 0.16002)
		(layer "In13.Cu")
		(net "M_B_CPU0_SB_DQS_DP<8>")
	)
	(segment
		(start 307.216302 -314.197492)
		(end 305.782726 -314.197492)
		(width 0.16002)
		(layer "In13.Cu")
		(net "M_B_CPU0_SB_DQS_DP<8>")
	)
	(segment
		(start 326.927718 -292.42639)
		(end 325.809864 -294.099234)
		(width 0.09525)
		(layer "In13.Cu")
		(net "M_B_CPU0_SB_DQS_DP<8>")
	)
	(segment
		(start 336.239612 -291.580824)
		(end 336.23123 -291.575998)
		(width 0.09525)
		(layer "In13.Cu")
		(net "M_B_CPU0_SB_DQS_DP<8>")
	)
	(segment
		(start 337.145122 -291.640514)
		(end 337.121754 -291.553646)
		(width 0.09525)
		(layer "In13.Cu")
		(net "M_B_CPU0_SB_DQS_DP<8>")
	)
	(segment
		(start 319.286128 -302.756316)
		(end 319.286128 -303.958752)
		(width 0.16002)
		(layer "In13.Cu")
		(net "M_B_CPU0_SB_DQS_DP<8>")
	)
	(segment
		(start 325.31431 -295.445434)
		(end 325.31431 -295.528238)
		(width 0.09525)
		(layer "In13.Cu")
		(net "M_B_CPU0_SB_DQS_DP<8>")
	)
	(segment
		(start 333.99095 -291.575998)
		(end 333.982568 -291.580824)
		(width 0.09525)
		(layer "In13.Cu")
		(net "M_B_CPU0_SB_DQS_DP<8>")
	)
	(segment
		(start 325.297546 -295.545002)
		(end 322.594478 -298.24807)
		(width 0.16002)
		(layer "In13.Cu")
		(net "M_B_CPU0_SB_DQS_DP<8>")
	)
	(segment
		(start 310.34228 -312.9026)
		(end 307.216302 -314.197492)
		(width 0.16002)
		(layer "In13.Cu")
		(net "M_B_CPU0_SB_DQS_DP<8>")
	)
	(segment
		(start 299.419772 -314.98921)
		(end 298.6278 -314.182252)
		(width 0.16002)
		(layer "In13.Cu")
		(net "M_B_CPU0_SB_DQS_DP<8>")
	)
	(segment
		(start 322.594478 -298.24807)
		(end 322.594478 -299.447966)
		(width 0.16002)
		(layer "In13.Cu")
		(net "M_B_CPU0_SB_DQS_DP<8>")
	)
	(segment
		(start 325.315072 -295.444926)
		(end 325.31431 -295.445434)
		(width 0.09525)
		(layer "In13.Cu")
		(net "M_B_CPU0_SB_DQS_DP<8>")
	)
	(arc
		(start 330.222606 -291.580824)
		(mid 329.941174 -291.656579)
		(end 329.659742 -291.580824)
		(width 0.09525)
		(layer "In13.Cu")
		(net "M_B_CPU0_SB_DQS_DP<8>")
	)
	(arc
		(start 336.802476 -291.580824)
		(mid 336.521044 -291.656579)
		(end 336.239612 -291.580824)
		(width 0.09525)
		(layer "In13.Cu")
		(net "M_B_CPU0_SB_DQS_DP<8>")
	)
	(arc
		(start 333.982568 -291.580824)
		(mid 333.701136 -291.656579)
		(end 333.419704 -291.580824)
		(width 0.09525)
		(layer "In13.Cu")
		(net "M_B_CPU0_SB_DQS_DP<8>")
	)
	(arc
		(start 333.419704 -291.580824)
		(mid 333.235929 -291.530052)
		(end 333.050896 -291.575998)
		(width 0.09525)
		(layer "In13.Cu")
		(net "M_B_CPU0_SB_DQS_DP<8>")
	)
	(arc
		(start 332.471268 -291.575998)
		(mid 332.286236 -291.530084)
		(end 332.10246 -291.580824)
		(width 0.09525)
		(layer "In13.Cu")
		(net "M_B_CPU0_SB_DQS_DP<8>")
	)
	(arc
		(start 334.922622 -291.580824)
		(mid 334.64119 -291.656579)
		(end 334.359758 -291.580824)
		(width 0.09525)
		(layer "In13.Cu")
		(net "M_B_CPU0_SB_DQS_DP<8>")
	)
	(arc
		(start 328.711306 -291.575998)
		(mid 328.526274 -291.530084)
		(end 328.342498 -291.580824)
		(width 0.09525)
		(layer "In13.Cu")
		(net "M_B_CPU0_SB_DQS_DP<8>")
	)
	(arc
		(start 330.599542 -291.580824)
		(mid 330.411074 -291.530147)
		(end 330.222606 -291.580824)
		(width 0.09525)
		(layer "In13.Cu")
		(net "M_B_CPU0_SB_DQS_DP<8>")
	)
	(arc
		(start 336.23123 -291.575998)
		(mid 336.046198 -291.530084)
		(end 335.862422 -291.580824)
		(width 0.09525)
		(layer "In13.Cu")
		(net "M_B_CPU0_SB_DQS_DP<8>")
	)
	(arc
		(start 328.342498 -291.580824)
		(mid 328.206791 -291.637309)
		(end 328.061066 -291.656516)
		(width 0.09525)
		(layer "In13.Cu")
		(net "M_B_CPU0_SB_DQS_DP<8>")
	)
	(arc
		(start 329.282552 -291.580824)
		(mid 329.00112 -291.656579)
		(end 328.719688 -291.580824)
		(width 0.09525)
		(layer "In13.Cu")
		(net "M_B_CPU0_SB_DQS_DP<8>")
	)
	(arc
		(start 337.121754 -291.553646)
		(mid 336.959072 -291.531514)
		(end 336.802476 -291.580824)
		(width 0.09525)
		(layer "In13.Cu")
		(net "M_B_CPU0_SB_DQS_DP<8>")
	)
	(arc
		(start 335.299558 -291.580824)
		(mid 335.11109 -291.530147)
		(end 334.922622 -291.580824)
		(width 0.09525)
		(layer "In13.Cu")
		(net "M_B_CPU0_SB_DQS_DP<8>")
	)
	(arc
		(start 334.359758 -291.580824)
		(mid 334.175983 -291.530052)
		(end 333.99095 -291.575998)
		(width 0.09525)
		(layer "In13.Cu")
		(net "M_B_CPU0_SB_DQS_DP<8>")
	)
	(arc
		(start 331.162406 -291.580824)
		(mid 330.880974 -291.656579)
		(end 330.599542 -291.580824)
		(width 0.09525)
		(layer "In13.Cu")
		(net "M_B_CPU0_SB_DQS_DP<8>")
	)
	(arc
		(start 329.659742 -291.580824)
		(mid 329.475967 -291.530052)
		(end 329.290934 -291.575998)
		(width 0.09525)
		(layer "In13.Cu")
		(net "M_B_CPU0_SB_DQS_DP<8>")
	)
	(arc
		(start 333.042514 -291.580824)
		(mid 332.761082 -291.656579)
		(end 332.47965 -291.580824)
		(width 0.09525)
		(layer "In13.Cu")
		(net "M_B_CPU0_SB_DQS_DP<8>")
	)
	(arc
		(start 335.862422 -291.580824)
		(mid 335.58099 -291.656579)
		(end 335.299558 -291.580824)
		(width 0.09525)
		(layer "In13.Cu")
		(net "M_B_CPU0_SB_DQS_DP<8>")
	)
	(arc
		(start 332.10246 -291.580824)
		(mid 331.821028 -291.656579)
		(end 331.539596 -291.580824)
		(width 0.09525)
		(layer "In13.Cu")
		(net "M_B_CPU0_SB_DQS_DP<8>")
	)
	(arc
		(start 331.531214 -291.575998)
		(mid 331.346182 -291.530084)
		(end 331.162406 -291.580824)
		(width 0.09525)
		(layer "In13.Cu")
		(net "M_B_CPU0_SB_DQS_DP<8>")
	)
	(segment
		(start 337.45805 -286.780224)
		(end 336.991198 -287.045908)
		(width 0.12954)
		(layer "F.Cu")
		(net "M_B_CPU0_SB_DQS_DP<7>")
	)
	(segment
		(start 326.168512 -286.812482)
		(end 325.954644 -286.812482)
		(width 0.09525)
		(layer "In13.Cu")
		(net "M_B_CPU0_SB_DQS_DP<7>")
	)
	(segment
		(start 329.290934 -286.715962)
		(end 329.282552 -286.720788)
		(width 0.09525)
		(layer "In13.Cu")
		(net "M_B_CPU0_SB_DQS_DP<7>")
	)
	(segment
		(start 336.991198 -287.045908)
		(end 337.145122 -286.780478)
		(width 0.09525)
		(layer "In13.Cu")
		(net "M_B_CPU0_SB_DQS_DP<7>")
	)
	(segment
		(start 327.780904 -286.721042)
		(end 327.763886 -286.71139)
		(width 0.09525)
		(layer "In13.Cu")
		(net "M_B_CPU0_SB_DQS_DP<7>")
	)
	(segment
		(start 327.7997 -286.731964)
		(end 327.780904 -286.721042)
		(width 0.09525)
		(layer "In13.Cu")
		(net "M_B_CPU0_SB_DQS_DP<7>")
	)
	(segment
		(start 308.4449 -304.3555)
		(end 308.439312 -304.349912)
		(width 0.16002)
		(layer "In13.Cu")
		(net "M_B_CPU0_SB_DQS_DP<7>")
	)
	(segment
		(start 297.671744 -304.832258)
		(end 297.239182 -305.011328)
		(width 0.16002)
		(layer "In13.Cu")
		(net "M_B_CPU0_SB_DQS_DP<7>")
	)
	(segment
		(start 332.47965 -286.720788)
		(end 332.471268 -286.715962)
		(width 0.09525)
		(layer "In13.Cu")
		(net "M_B_CPU0_SB_DQS_DP<7>")
	)
	(segment
		(start 333.99095 -286.715962)
		(end 333.982568 -286.720788)
		(width 0.09525)
		(layer "In13.Cu")
		(net "M_B_CPU0_SB_DQS_DP<7>")
	)
	(segment
		(start 295.997884 -305.011328)
		(end 295.724072 -305.28514)
		(width 0.16002)
		(layer "In13.Cu")
		(net "M_B_CPU0_SB_DQS_DP<7>")
	)
	(segment
		(start 316.304676 -295.831514)
		(end 316.304676 -297.050968)
		(width 0.16002)
		(layer "In13.Cu")
		(net "M_B_CPU0_SB_DQS_DP<7>")
	)
	(segment
		(start 324.109842 -288.026856)
		(end 316.304676 -295.831514)
		(width 0.16002)
		(layer "In13.Cu")
		(net "M_B_CPU0_SB_DQS_DP<7>")
	)
	(segment
		(start 324.126606 -287.927288)
		(end 324.126606 -288.010092)
		(width 0.09525)
		(layer "In13.Cu")
		(net "M_B_CPU0_SB_DQS_DP<7>")
	)
	(segment
		(start 326.866504 -286.744918)
		(end 326.835262 -286.726884)
		(width 0.09525)
		(layer "In13.Cu")
		(net "M_B_CPU0_SB_DQS_DP<7>")
	)
	(segment
		(start 304.931064 -305.67757)
		(end 302.036226 -305.67757)
		(width 0.16002)
		(layer "In13.Cu")
		(net "M_B_CPU0_SB_DQS_DP<7>")
	)
	(segment
		(start 298.634404 -304.832258)
		(end 297.671744 -304.832258)
		(width 0.16002)
		(layer "In13.Cu")
		(net "M_B_CPU0_SB_DQS_DP<7>")
	)
	(segment
		(start 337.145122 -286.780478)
		(end 337.121754 -286.69361)
		(width 0.09525)
		(layer "In13.Cu")
		(net "M_B_CPU0_SB_DQS_DP<7>")
	)
	(segment
		(start 328.719688 -286.720788)
		(end 328.711306 -286.715962)
		(width 0.09525)
		(layer "In13.Cu")
		(net "M_B_CPU0_SB_DQS_DP<7>")
	)
	(segment
		(start 309.000144 -304.3555)
		(end 308.4449 -304.3555)
		(width 0.16002)
		(layer "In13.Cu")
		(net "M_B_CPU0_SB_DQS_DP<7>")
	)
	(segment
		(start 325.681594 -287.085532)
		(end 324.968108 -287.085532)
		(width 0.09525)
		(layer "In13.Cu")
		(net "M_B_CPU0_SB_DQS_DP<7>")
	)
	(segment
		(start 336.239612 -286.720788)
		(end 336.23123 -286.715962)
		(width 0.09525)
		(layer "In13.Cu")
		(net "M_B_CPU0_SB_DQS_DP<7>")
	)
	(segment
		(start 302.036226 -305.67757)
		(end 300.7868 -305.160172)
		(width 0.16002)
		(layer "In13.Cu")
		(net "M_B_CPU0_SB_DQS_DP<7>")
	)
	(segment
		(start 308.439312 -304.349912)
		(end 305.717448 -304.891186)
		(width 0.16002)
		(layer "In13.Cu")
		(net "M_B_CPU0_SB_DQS_DP<7>")
	)
	(segment
		(start 305.717448 -304.891186)
		(end 304.931064 -305.67757)
		(width 0.16002)
		(layer "In13.Cu")
		(net "M_B_CPU0_SB_DQS_DP<7>")
	)
	(segment
		(start 297.239182 -305.011328)
		(end 295.997884 -305.011328)
		(width 0.16002)
		(layer "In13.Cu")
		(net "M_B_CPU0_SB_DQS_DP<7>")
	)
	(segment
		(start 299.426122 -305.160172)
		(end 298.634404 -304.832258)
		(width 0.16002)
		(layer "In13.Cu")
		(net "M_B_CPU0_SB_DQS_DP<7>")
	)
	(segment
		(start 333.050896 -286.715962)
		(end 333.042514 -286.720788)
		(width 0.09525)
		(layer "In13.Cu")
		(net "M_B_CPU0_SB_DQS_DP<7>")
	)
	(segment
		(start 300.7868 -305.160172)
		(end 299.426122 -305.160172)
		(width 0.16002)
		(layer "In13.Cu")
		(net "M_B_CPU0_SB_DQS_DP<7>")
	)
	(segment
		(start 316.304676 -297.050968)
		(end 309.000144 -304.3555)
		(width 0.16002)
		(layer "In13.Cu")
		(net "M_B_CPU0_SB_DQS_DP<7>")
	)
	(segment
		(start 327.763886 -286.71139)
		(end 327.762616 -286.710628)
		(width 0.09525)
		(layer "In13.Cu")
		(net "M_B_CPU0_SB_DQS_DP<7>")
	)
	(segment
		(start 324.968108 -287.085532)
		(end 324.126606 -287.927288)
		(width 0.09525)
		(layer "In13.Cu")
		(net "M_B_CPU0_SB_DQS_DP<7>")
	)
	(segment
		(start 325.954644 -286.812482)
		(end 325.681594 -287.085532)
		(width 0.09525)
		(layer "In13.Cu")
		(net "M_B_CPU0_SB_DQS_DP<7>")
	)
	(segment
		(start 324.126606 -288.010092)
		(end 324.109842 -288.026856)
		(width 0.09525)
		(layer "In13.Cu")
		(net "M_B_CPU0_SB_DQS_DP<7>")
	)
	(segment
		(start 331.539596 -286.720788)
		(end 331.531214 -286.715962)
		(width 0.09525)
		(layer "In13.Cu")
		(net "M_B_CPU0_SB_DQS_DP<7>")
	)
	(segment
		(start 326.835262 -286.726884)
		(end 326.811132 -286.713168)
		(width 0.09525)
		(layer "In13.Cu")
		(net "M_B_CPU0_SB_DQS_DP<7>")
	)
	(arc
		(start 333.419704 -286.720788)
		(mid 333.235929 -286.670016)
		(end 333.050896 -286.715962)
		(width 0.09525)
		(layer "In13.Cu")
		(net "M_B_CPU0_SB_DQS_DP<7>")
	)
	(arc
		(start 332.10246 -286.720788)
		(mid 331.821028 -286.796577)
		(end 331.539596 -286.720788)
		(width 0.09525)
		(layer "In13.Cu")
		(net "M_B_CPU0_SB_DQS_DP<7>")
	)
	(arc
		(start 327.338182 -286.74695)
		(mid 327.102172 -286.787326)
		(end 326.866504 -286.744918)
		(width 0.09525)
		(layer "In13.Cu")
		(net "M_B_CPU0_SB_DQS_DP<7>")
	)
	(arc
		(start 327.762616 -286.710628)
		(mid 327.59425 -286.670143)
		(end 327.425558 -286.709358)
		(width 0.09525)
		(layer "In13.Cu")
		(net "M_B_CPU0_SB_DQS_DP<7>")
	)
	(arc
		(start 336.23123 -286.715962)
		(mid 336.046198 -286.670048)
		(end 335.862422 -286.720788)
		(width 0.09525)
		(layer "In13.Cu")
		(net "M_B_CPU0_SB_DQS_DP<7>")
	)
	(arc
		(start 329.282552 -286.720788)
		(mid 329.00112 -286.796577)
		(end 328.719688 -286.720788)
		(width 0.09525)
		(layer "In13.Cu")
		(net "M_B_CPU0_SB_DQS_DP<7>")
	)
	(arc
		(start 326.458072 -286.730948)
		(mid 326.318928 -286.791723)
		(end 326.168512 -286.812482)
		(width 0.09525)
		(layer "In13.Cu")
		(net "M_B_CPU0_SB_DQS_DP<7>")
	)
	(arc
		(start 335.299558 -286.720788)
		(mid 335.11109 -286.670111)
		(end 334.922622 -286.720788)
		(width 0.09525)
		(layer "In13.Cu")
		(net "M_B_CPU0_SB_DQS_DP<7>")
	)
	(arc
		(start 336.802476 -286.720788)
		(mid 336.521044 -286.796577)
		(end 336.239612 -286.720788)
		(width 0.09525)
		(layer "In13.Cu")
		(net "M_B_CPU0_SB_DQS_DP<7>")
	)
	(arc
		(start 328.711306 -286.715962)
		(mid 328.526274 -286.670048)
		(end 328.342498 -286.720788)
		(width 0.09525)
		(layer "In13.Cu")
		(net "M_B_CPU0_SB_DQS_DP<7>")
	)
	(arc
		(start 335.862422 -286.720788)
		(mid 335.58099 -286.796577)
		(end 335.299558 -286.720788)
		(width 0.09525)
		(layer "In13.Cu")
		(net "M_B_CPU0_SB_DQS_DP<7>")
	)
	(arc
		(start 331.162406 -286.720788)
		(mid 330.880974 -286.796577)
		(end 330.599542 -286.720788)
		(width 0.09525)
		(layer "In13.Cu")
		(net "M_B_CPU0_SB_DQS_DP<7>")
	)
	(arc
		(start 331.531214 -286.715962)
		(mid 331.346182 -286.670048)
		(end 331.162406 -286.720788)
		(width 0.09525)
		(layer "In13.Cu")
		(net "M_B_CPU0_SB_DQS_DP<7>")
	)
	(arc
		(start 330.222606 -286.720788)
		(mid 329.941174 -286.796577)
		(end 329.659742 -286.720788)
		(width 0.09525)
		(layer "In13.Cu")
		(net "M_B_CPU0_SB_DQS_DP<7>")
	)
	(arc
		(start 332.471268 -286.715962)
		(mid 332.286236 -286.670048)
		(end 332.10246 -286.720788)
		(width 0.09525)
		(layer "In13.Cu")
		(net "M_B_CPU0_SB_DQS_DP<7>")
	)
	(arc
		(start 334.922622 -286.720788)
		(mid 334.64119 -286.796577)
		(end 334.359758 -286.720788)
		(width 0.09525)
		(layer "In13.Cu")
		(net "M_B_CPU0_SB_DQS_DP<7>")
	)
	(arc
		(start 333.982568 -286.720788)
		(mid 333.701136 -286.796577)
		(end 333.419704 -286.720788)
		(width 0.09525)
		(layer "In13.Cu")
		(net "M_B_CPU0_SB_DQS_DP<7>")
	)
	(arc
		(start 326.811132 -286.713168)
		(mid 326.632329 -286.677044)
		(end 326.458072 -286.730948)
		(width 0.09525)
		(layer "In13.Cu")
		(net "M_B_CPU0_SB_DQS_DP<7>")
	)
	(arc
		(start 337.121754 -286.69361)
		(mid 336.959072 -286.671478)
		(end 336.802476 -286.720788)
		(width 0.09525)
		(layer "In13.Cu")
		(net "M_B_CPU0_SB_DQS_DP<7>")
	)
	(arc
		(start 330.599542 -286.720788)
		(mid 330.411074 -286.670111)
		(end 330.222606 -286.720788)
		(width 0.09525)
		(layer "In13.Cu")
		(net "M_B_CPU0_SB_DQS_DP<7>")
	)
	(arc
		(start 327.425558 -286.709358)
		(mid 327.38242 -286.729433)
		(end 327.338182 -286.74695)
		(width 0.09525)
		(layer "In13.Cu")
		(net "M_B_CPU0_SB_DQS_DP<7>")
	)
	(arc
		(start 333.042514 -286.720788)
		(mid 332.761082 -286.796577)
		(end 332.47965 -286.720788)
		(width 0.09525)
		(layer "In13.Cu")
		(net "M_B_CPU0_SB_DQS_DP<7>")
	)
	(arc
		(start 329.659742 -286.720788)
		(mid 329.475967 -286.670016)
		(end 329.290934 -286.715962)
		(width 0.09525)
		(layer "In13.Cu")
		(net "M_B_CPU0_SB_DQS_DP<7>")
	)
	(arc
		(start 334.359758 -286.720788)
		(mid 334.175983 -286.670016)
		(end 333.99095 -286.715962)
		(width 0.09525)
		(layer "In13.Cu")
		(net "M_B_CPU0_SB_DQS_DP<7>")
	)
	(arc
		(start 328.342498 -286.720788)
		(mid 328.07255 -286.79646)
		(end 327.7997 -286.731964)
		(width 0.09525)
		(layer "In13.Cu")
		(net "M_B_CPU0_SB_DQS_DP<7>")
	)
	(segment
		(start 337.45805 -281.920188)
		(end 336.991198 -282.186126)
		(width 0.12954)
		(layer "F.Cu")
		(net "M_B_CPU0_SB_DQS_DP<6>")
	)
	(segment
		(start 333.99095 -281.85618)
		(end 333.982568 -281.861006)
		(width 0.09525)
		(layer "In13.Cu")
		(net "M_B_CPU0_SB_DQS_DP<6>")
	)
	(segment
		(start 304.97907 -296.27957)
		(end 301.685198 -296.27957)
		(width 0.16002)
		(layer "In13.Cu")
		(net "M_B_CPU0_SB_DQS_DP<6>")
	)
	(segment
		(start 299.489368 -295.810178)
		(end 298.76496 -295.482264)
		(width 0.16002)
		(layer "In13.Cu")
		(net "M_B_CPU0_SB_DQS_DP<6>")
	)
	(segment
		(start 323.895974 -281.97429)
		(end 322.055744 -281.97429)
		(width 0.16002)
		(layer "In13.Cu")
		(net "M_B_CPU0_SB_DQS_DP<6>")
	)
	(segment
		(start 331.539596 -281.861006)
		(end 331.531214 -281.85618)
		(width 0.09525)
		(layer "In13.Cu")
		(net "M_B_CPU0_SB_DQS_DP<6>")
	)
	(segment
		(start 305.776376 -295.482264)
		(end 304.97907 -296.27957)
		(width 0.16002)
		(layer "In13.Cu")
		(net "M_B_CPU0_SB_DQS_DP<6>")
	)
	(segment
		(start 323.919596 -281.97429)
		(end 323.895974 -281.97429)
		(width 0.09525)
		(layer "In13.Cu")
		(net "M_B_CPU0_SB_DQS_DP<6>")
	)
	(segment
		(start 337.145122 -281.920696)
		(end 337.121754 -281.833828)
		(width 0.09525)
		(layer "In13.Cu")
		(net "M_B_CPU0_SB_DQS_DP<6>")
	)
	(segment
		(start 298.76496 -295.482264)
		(end 296.506138 -295.482264)
		(width 0.16002)
		(layer "In13.Cu")
		(net "M_B_CPU0_SB_DQS_DP<6>")
	)
	(segment
		(start 308.54777 -295.482264)
		(end 305.776376 -295.482264)
		(width 0.16002)
		(layer "In13.Cu")
		(net "M_B_CPU0_SB_DQS_DP<6>")
	)
	(segment
		(start 324.641972 -281.727402)
		(end 324.454012 -281.915362)
		(width 0.09525)
		(layer "In13.Cu")
		(net "M_B_CPU0_SB_DQS_DP<6>")
	)
	(segment
		(start 332.47965 -281.861006)
		(end 332.471268 -281.85618)
		(width 0.09525)
		(layer "In13.Cu")
		(net "M_B_CPU0_SB_DQS_DP<6>")
	)
	(segment
		(start 327.102978 -281.727402)
		(end 324.641972 -281.727402)
		(width 0.09525)
		(layer "In13.Cu")
		(net "M_B_CPU0_SB_DQS_DP<6>")
	)
	(segment
		(start 301.685198 -296.27957)
		(end 301.215806 -295.810178)
		(width 0.16002)
		(layer "In13.Cu")
		(net "M_B_CPU0_SB_DQS_DP<6>")
	)
	(segment
		(start 336.991198 -282.186126)
		(end 337.145122 -281.920696)
		(width 0.09525)
		(layer "In13.Cu")
		(net "M_B_CPU0_SB_DQS_DP<6>")
	)
	(segment
		(start 323.978524 -281.915362)
		(end 323.919596 -281.97429)
		(width 0.09525)
		(layer "In13.Cu")
		(net "M_B_CPU0_SB_DQS_DP<6>")
	)
	(segment
		(start 336.239612 -281.861006)
		(end 336.23123 -281.85618)
		(width 0.09525)
		(layer "In13.Cu")
		(net "M_B_CPU0_SB_DQS_DP<6>")
	)
	(segment
		(start 295.997884 -295.661334)
		(end 295.724072 -295.935146)
		(width 0.16002)
		(layer "In13.Cu")
		(net "M_B_CPU0_SB_DQS_DP<6>")
	)
	(segment
		(start 322.055744 -281.97429)
		(end 308.54777 -295.482264)
		(width 0.16002)
		(layer "In13.Cu")
		(net "M_B_CPU0_SB_DQS_DP<6>")
	)
	(segment
		(start 333.050896 -281.85618)
		(end 333.042514 -281.861006)
		(width 0.09525)
		(layer "In13.Cu")
		(net "M_B_CPU0_SB_DQS_DP<6>")
	)
	(segment
		(start 301.215806 -295.810178)
		(end 299.489368 -295.810178)
		(width 0.16002)
		(layer "In13.Cu")
		(net "M_B_CPU0_SB_DQS_DP<6>")
	)
	(segment
		(start 324.454012 -281.915362)
		(end 323.978524 -281.915362)
		(width 0.09525)
		(layer "In13.Cu")
		(net "M_B_CPU0_SB_DQS_DP<6>")
	)
	(segment
		(start 296.506138 -295.482264)
		(end 296.327068 -295.661334)
		(width 0.16002)
		(layer "In13.Cu")
		(net "M_B_CPU0_SB_DQS_DP<6>")
	)
	(segment
		(start 296.327068 -295.661334)
		(end 295.997884 -295.661334)
		(width 0.16002)
		(layer "In13.Cu")
		(net "M_B_CPU0_SB_DQS_DP<6>")
	)
	(arc
		(start 333.982568 -281.861006)
		(mid 333.701136 -281.936761)
		(end 333.419704 -281.861006)
		(width 0.09525)
		(layer "In13.Cu")
		(net "M_B_CPU0_SB_DQS_DP<6>")
	)
	(arc
		(start 329.659742 -281.861006)
		(mid 329.486782 -281.810649)
		(end 329.310238 -281.846528)
		(width 0.09525)
		(layer "In13.Cu")
		(net "M_B_CPU0_SB_DQS_DP<6>")
	)
	(arc
		(start 333.042514 -281.861006)
		(mid 332.761082 -281.936761)
		(end 332.47965 -281.861006)
		(width 0.09525)
		(layer "In13.Cu")
		(net "M_B_CPU0_SB_DQS_DP<6>")
	)
	(arc
		(start 329.309984 -281.845766)
		(mid 329.021685 -281.916711)
		(end 328.728578 -281.869388)
		(width 0.09525)
		(layer "In13.Cu")
		(net "M_B_CPU0_SB_DQS_DP<6>")
	)
	(arc
		(start 331.162406 -281.861006)
		(mid 330.880974 -281.936761)
		(end 330.599542 -281.861006)
		(width 0.09525)
		(layer "In13.Cu")
		(net "M_B_CPU0_SB_DQS_DP<6>")
	)
	(arc
		(start 327.828148 -281.88539)
		(mid 327.474078 -281.767301)
		(end 327.102978 -281.727402)
		(width 0.09525)
		(layer "In13.Cu")
		(net "M_B_CPU0_SB_DQS_DP<6>")
	)
	(arc
		(start 328.728578 -281.869388)
		(mid 328.510733 -281.833615)
		(end 328.296016 -281.884882)
		(width 0.09525)
		(layer "In13.Cu")
		(net "M_B_CPU0_SB_DQS_DP<6>")
	)
	(arc
		(start 337.121754 -281.833828)
		(mid 336.959072 -281.811696)
		(end 336.802476 -281.861006)
		(width 0.09525)
		(layer "In13.Cu")
		(net "M_B_CPU0_SB_DQS_DP<6>")
	)
	(arc
		(start 330.599542 -281.861006)
		(mid 330.411074 -281.810329)
		(end 330.222606 -281.861006)
		(width 0.09525)
		(layer "In13.Cu")
		(net "M_B_CPU0_SB_DQS_DP<6>")
	)
	(arc
		(start 336.23123 -281.85618)
		(mid 336.046198 -281.810266)
		(end 335.862422 -281.861006)
		(width 0.09525)
		(layer "In13.Cu")
		(net "M_B_CPU0_SB_DQS_DP<6>")
	)
	(arc
		(start 328.296016 -281.884882)
		(mid 328.062142 -281.936323)
		(end 327.828148 -281.88539)
		(width 0.09525)
		(layer "In13.Cu")
		(net "M_B_CPU0_SB_DQS_DP<6>")
	)
	(arc
		(start 330.222606 -281.861006)
		(mid 329.941174 -281.936761)
		(end 329.659742 -281.861006)
		(width 0.09525)
		(layer "In13.Cu")
		(net "M_B_CPU0_SB_DQS_DP<6>")
	)
	(arc
		(start 332.10246 -281.861006)
		(mid 331.821028 -281.936761)
		(end 331.539596 -281.861006)
		(width 0.09525)
		(layer "In13.Cu")
		(net "M_B_CPU0_SB_DQS_DP<6>")
	)
	(arc
		(start 329.310238 -281.846528)
		(mid 329.310112 -281.846147)
		(end 329.309984 -281.845766)
		(width 0.09525)
		(layer "In13.Cu")
		(net "M_B_CPU0_SB_DQS_DP<6>")
	)
	(arc
		(start 331.531214 -281.85618)
		(mid 331.346182 -281.810266)
		(end 331.162406 -281.861006)
		(width 0.09525)
		(layer "In13.Cu")
		(net "M_B_CPU0_SB_DQS_DP<6>")
	)
	(arc
		(start 336.802476 -281.861006)
		(mid 336.521044 -281.936761)
		(end 336.239612 -281.861006)
		(width 0.09525)
		(layer "In13.Cu")
		(net "M_B_CPU0_SB_DQS_DP<6>")
	)
	(arc
		(start 334.359758 -281.861006)
		(mid 334.175983 -281.810234)
		(end 333.99095 -281.85618)
		(width 0.09525)
		(layer "In13.Cu")
		(net "M_B_CPU0_SB_DQS_DP<6>")
	)
	(arc
		(start 335.862422 -281.861006)
		(mid 335.58099 -281.936761)
		(end 335.299558 -281.861006)
		(width 0.09525)
		(layer "In13.Cu")
		(net "M_B_CPU0_SB_DQS_DP<6>")
	)
	(arc
		(start 334.922622 -281.861006)
		(mid 334.64119 -281.936761)
		(end 334.359758 -281.861006)
		(width 0.09525)
		(layer "In13.Cu")
		(net "M_B_CPU0_SB_DQS_DP<6>")
	)
	(arc
		(start 332.471268 -281.85618)
		(mid 332.286236 -281.810266)
		(end 332.10246 -281.861006)
		(width 0.09525)
		(layer "In13.Cu")
		(net "M_B_CPU0_SB_DQS_DP<6>")
	)
	(arc
		(start 333.419704 -281.861006)
		(mid 333.235929 -281.810234)
		(end 333.050896 -281.85618)
		(width 0.09525)
		(layer "In13.Cu")
		(net "M_B_CPU0_SB_DQS_DP<6>")
	)
	(arc
		(start 335.299558 -281.861006)
		(mid 335.11109 -281.810329)
		(end 334.922622 -281.861006)
		(width 0.09525)
		(layer "In13.Cu")
		(net "M_B_CPU0_SB_DQS_DP<6>")
	)
	(segment
		(start 337.45805 -277.060152)
		(end 336.991198 -277.32609)
		(width 0.12954)
		(layer "F.Cu")
		(net "M_B_CPU0_SB_DQS_DP<5>")
	)
	(segment
		(start 324.74281 -276.794214)
		(end 324.275958 -276.327362)
		(width 0.09525)
		(layer "In13.Cu")
		(net "M_B_CPU0_SB_DQS_DP<5>")
	)
	(segment
		(start 323.895974 -276.35073)
		(end 318.040512 -276.35073)
		(width 0.16002)
		(layer "In13.Cu")
		(net "M_B_CPU0_SB_DQS_DP<5>")
	)
	(segment
		(start 337.145122 -277.06066)
		(end 337.121754 -276.973792)
		(width 0.09525)
		(layer "In13.Cu")
		(net "M_B_CPU0_SB_DQS_DP<5>")
	)
	(segment
		(start 333.050896 -276.996144)
		(end 333.042514 -277.00097)
		(width 0.09525)
		(layer "In13.Cu")
		(net "M_B_CPU0_SB_DQS_DP<5>")
	)
	(segment
		(start 336.239612 -277.00097)
		(end 336.23123 -276.996144)
		(width 0.09525)
		(layer "In13.Cu")
		(net "M_B_CPU0_SB_DQS_DP<5>")
	)
	(segment
		(start 306.486814 -286.13227)
		(end 305.776376 -286.13227)
		(width 0.16002)
		(layer "In13.Cu")
		(net "M_B_CPU0_SB_DQS_DP<5>")
	)
	(segment
		(start 323.978524 -276.291802)
		(end 323.919596 -276.35073)
		(width 0.09525)
		(layer "In13.Cu")
		(net "M_B_CPU0_SB_DQS_DP<5>")
	)
	(segment
		(start 327.177654 -276.883622)
		(end 324.959218 -276.883622)
		(width 0.09525)
		(layer "In13.Cu")
		(net "M_B_CPU0_SB_DQS_DP<5>")
	)
	(segment
		(start 305.776376 -286.13227)
		(end 304.976276 -286.93237)
		(width 0.16002)
		(layer "In13.Cu")
		(net "M_B_CPU0_SB_DQS_DP<5>")
	)
	(segment
		(start 309.512208 -284.879034)
		(end 306.486814 -286.13227)
		(width 0.16002)
		(layer "In13.Cu")
		(net "M_B_CPU0_SB_DQS_DP<5>")
	)
	(segment
		(start 323.919596 -276.35073)
		(end 323.895974 -276.35073)
		(width 0.09525)
		(layer "In13.Cu")
		(net "M_B_CPU0_SB_DQS_DP<5>")
	)
	(segment
		(start 296.028364 -286.28086)
		(end 295.724072 -286.585152)
		(width 0.16002)
		(layer "In13.Cu")
		(net "M_B_CPU0_SB_DQS_DP<5>")
	)
	(segment
		(start 298.977812 -286.273494)
		(end 298.977812 -286.27324)
		(width 0.16002)
		(layer "In13.Cu")
		(net "M_B_CPU0_SB_DQS_DP<5>")
	)
	(segment
		(start 336.991198 -277.32609)
		(end 337.145122 -277.06066)
		(width 0.09525)
		(layer "In13.Cu")
		(net "M_B_CPU0_SB_DQS_DP<5>")
	)
	(segment
		(start 301.89678 -286.93237)
		(end 301.424594 -286.460184)
		(width 0.16002)
		(layer "In13.Cu")
		(net "M_B_CPU0_SB_DQS_DP<5>")
	)
	(segment
		(start 331.539596 -277.00097)
		(end 331.531214 -276.996144)
		(width 0.09525)
		(layer "In13.Cu")
		(net "M_B_CPU0_SB_DQS_DP<5>")
	)
	(segment
		(start 298.977812 -286.27324)
		(end 298.637452 -286.13227)
		(width 0.16002)
		(layer "In13.Cu")
		(net "M_B_CPU0_SB_DQS_DP<5>")
	)
	(segment
		(start 298.637452 -286.13227)
		(end 297.798744 -286.13227)
		(width 0.16002)
		(layer "In13.Cu")
		(net "M_B_CPU0_SB_DQS_DP<5>")
	)
	(segment
		(start 333.99095 -276.996144)
		(end 333.982568 -277.00097)
		(width 0.09525)
		(layer "In13.Cu")
		(net "M_B_CPU0_SB_DQS_DP<5>")
	)
	(segment
		(start 301.424594 -286.460184)
		(end 299.42917 -286.460184)
		(width 0.16002)
		(layer "In13.Cu")
		(net "M_B_CPU0_SB_DQS_DP<5>")
	)
	(segment
		(start 318.040512 -276.35073)
		(end 309.512208 -284.879034)
		(width 0.16002)
		(layer "In13.Cu")
		(net "M_B_CPU0_SB_DQS_DP<5>")
	)
	(segment
		(start 324.190106 -276.291802)
		(end 323.978524 -276.291802)
		(width 0.09525)
		(layer "In13.Cu")
		(net "M_B_CPU0_SB_DQS_DP<5>")
	)
	(segment
		(start 332.47965 -277.00097)
		(end 332.471268 -276.996144)
		(width 0.09525)
		(layer "In13.Cu")
		(net "M_B_CPU0_SB_DQS_DP<5>")
	)
	(segment
		(start 304.976276 -286.93237)
		(end 301.89678 -286.93237)
		(width 0.16002)
		(layer "In13.Cu")
		(net "M_B_CPU0_SB_DQS_DP<5>")
	)
	(segment
		(start 297.798744 -286.13227)
		(end 297.439842 -286.28086)
		(width 0.16002)
		(layer "In13.Cu")
		(net "M_B_CPU0_SB_DQS_DP<5>")
	)
	(segment
		(start 299.42917 -286.460184)
		(end 298.977812 -286.273494)
		(width 0.16002)
		(layer "In13.Cu")
		(net "M_B_CPU0_SB_DQS_DP<5>")
	)
	(segment
		(start 297.439842 -286.28086)
		(end 296.028364 -286.28086)
		(width 0.16002)
		(layer "In13.Cu")
		(net "M_B_CPU0_SB_DQS_DP<5>")
	)
	(arc
		(start 332.10246 -277.00097)
		(mid 331.821028 -277.076725)
		(end 331.539596 -277.00097)
		(width 0.09525)
		(layer "In13.Cu")
		(net "M_B_CPU0_SB_DQS_DP<5>")
	)
	(arc
		(start 333.042514 -277.00097)
		(mid 332.761082 -277.076725)
		(end 332.47965 -277.00097)
		(width 0.09525)
		(layer "In13.Cu")
		(net "M_B_CPU0_SB_DQS_DP<5>")
	)
	(arc
		(start 324.275958 -276.327362)
		(mid 324.236583 -276.300989)
		(end 324.190106 -276.291802)
		(width 0.09525)
		(layer "In13.Cu")
		(net "M_B_CPU0_SB_DQS_DP<5>")
	)
	(arc
		(start 330.599542 -277.00097)
		(mid 330.411074 -276.950293)
		(end 330.222606 -277.00097)
		(width 0.09525)
		(layer "In13.Cu")
		(net "M_B_CPU0_SB_DQS_DP<5>")
	)
	(arc
		(start 334.359758 -277.00097)
		(mid 334.175983 -276.950198)
		(end 333.99095 -276.996144)
		(width 0.09525)
		(layer "In13.Cu")
		(net "M_B_CPU0_SB_DQS_DP<5>")
	)
	(arc
		(start 328.296016 -277.024846)
		(mid 328.062142 -277.076287)
		(end 327.828148 -277.025354)
		(width 0.09525)
		(layer "In13.Cu")
		(net "M_B_CPU0_SB_DQS_DP<5>")
	)
	(arc
		(start 336.802476 -277.00097)
		(mid 336.521044 -277.076725)
		(end 336.239612 -277.00097)
		(width 0.09525)
		(layer "In13.Cu")
		(net "M_B_CPU0_SB_DQS_DP<5>")
	)
	(arc
		(start 333.419704 -277.00097)
		(mid 333.235929 -276.950198)
		(end 333.050896 -276.996144)
		(width 0.09525)
		(layer "In13.Cu")
		(net "M_B_CPU0_SB_DQS_DP<5>")
	)
	(arc
		(start 334.922622 -277.00097)
		(mid 334.64119 -277.076725)
		(end 334.359758 -277.00097)
		(width 0.09525)
		(layer "In13.Cu")
		(net "M_B_CPU0_SB_DQS_DP<5>")
	)
	(arc
		(start 329.309984 -276.98573)
		(mid 329.021685 -277.056675)
		(end 328.728578 -277.009352)
		(width 0.09525)
		(layer "In13.Cu")
		(net "M_B_CPU0_SB_DQS_DP<5>")
	)
	(arc
		(start 335.862422 -277.00097)
		(mid 335.58099 -277.076725)
		(end 335.299558 -277.00097)
		(width 0.09525)
		(layer "In13.Cu")
		(net "M_B_CPU0_SB_DQS_DP<5>")
	)
	(arc
		(start 329.310238 -276.986492)
		(mid 329.310112 -276.986111)
		(end 329.309984 -276.98573)
		(width 0.09525)
		(layer "In13.Cu")
		(net "M_B_CPU0_SB_DQS_DP<5>")
	)
	(arc
		(start 330.222606 -277.00097)
		(mid 329.941174 -277.076725)
		(end 329.659742 -277.00097)
		(width 0.09525)
		(layer "In13.Cu")
		(net "M_B_CPU0_SB_DQS_DP<5>")
	)
	(arc
		(start 328.728578 -277.009352)
		(mid 328.510733 -276.973579)
		(end 328.296016 -277.024846)
		(width 0.09525)
		(layer "In13.Cu")
		(net "M_B_CPU0_SB_DQS_DP<5>")
	)
	(arc
		(start 329.659742 -277.00097)
		(mid 329.486782 -276.950613)
		(end 329.310238 -276.986492)
		(width 0.09525)
		(layer "In13.Cu")
		(net "M_B_CPU0_SB_DQS_DP<5>")
	)
	(arc
		(start 335.299558 -277.00097)
		(mid 335.11109 -276.950293)
		(end 334.922622 -277.00097)
		(width 0.09525)
		(layer "In13.Cu")
		(net "M_B_CPU0_SB_DQS_DP<5>")
	)
	(arc
		(start 332.471268 -276.996144)
		(mid 332.286236 -276.95023)
		(end 332.10246 -277.00097)
		(width 0.09525)
		(layer "In13.Cu")
		(net "M_B_CPU0_SB_DQS_DP<5>")
	)
	(arc
		(start 331.531214 -276.996144)
		(mid 331.346182 -276.95023)
		(end 331.162406 -277.00097)
		(width 0.09525)
		(layer "In13.Cu")
		(net "M_B_CPU0_SB_DQS_DP<5>")
	)
	(arc
		(start 331.162406 -277.00097)
		(mid 330.880974 -277.076725)
		(end 330.599542 -277.00097)
		(width 0.09525)
		(layer "In13.Cu")
		(net "M_B_CPU0_SB_DQS_DP<5>")
	)
	(arc
		(start 336.23123 -276.996144)
		(mid 336.046198 -276.95023)
		(end 335.862422 -277.00097)
		(width 0.09525)
		(layer "In13.Cu")
		(net "M_B_CPU0_SB_DQS_DP<5>")
	)
	(arc
		(start 324.959218 -276.883622)
		(mid 324.842094 -276.860494)
		(end 324.74281 -276.794214)
		(width 0.09525)
		(layer "In13.Cu")
		(net "M_B_CPU0_SB_DQS_DP<5>")
	)
	(arc
		(start 327.828148 -277.025354)
		(mid 327.510539 -276.919432)
		(end 327.177654 -276.883622)
		(width 0.09525)
		(layer "In13.Cu")
		(net "M_B_CPU0_SB_DQS_DP<5>")
	)
	(arc
		(start 333.982568 -277.00097)
		(mid 333.701136 -277.076725)
		(end 333.419704 -277.00097)
		(width 0.09525)
		(layer "In13.Cu")
		(net "M_B_CPU0_SB_DQS_DP<5>")
	)
	(arc
		(start 337.121754 -276.973792)
		(mid 336.959072 -276.95166)
		(end 336.802476 -277.00097)
		(width 0.09525)
		(layer "In13.Cu")
		(net "M_B_CPU0_SB_DQS_DP<5>")
	)
	(segment
		(start 337.45805 -272.200116)
		(end 336.991198 -272.466054)
		(width 0.12954)
		(layer "F.Cu")
		(net "M_B_CPU0_SB_DQS_DP<4>")
	)
	(segment
		(start 323.978524 -270.668242)
		(end 323.919596 -270.72717)
		(width 0.09525)
		(layer "In13.Cu")
		(net "M_B_CPU0_SB_DQS_DP<4>")
	)
	(segment
		(start 296.029126 -276.930104)
		(end 295.724072 -277.235158)
		(width 0.16002)
		(layer "In13.Cu")
		(net "M_B_CPU0_SB_DQS_DP<4>")
	)
	(segment
		(start 302.942752 -277.58517)
		(end 301.754032 -277.58517)
		(width 0.16002)
		(layer "In13.Cu")
		(net "M_B_CPU0_SB_DQS_DP<4>")
	)
	(segment
		(start 298.553632 -276.72157)
		(end 297.55465 -276.72157)
		(width 0.16002)
		(layer "In13.Cu")
		(net "M_B_CPU0_SB_DQS_DP<4>")
	)
	(segment
		(start 336.239612 -272.140934)
		(end 336.23123 -272.136108)
		(width 0.09525)
		(layer "In13.Cu")
		(net "M_B_CPU0_SB_DQS_DP<4>")
	)
	(segment
		(start 301.279052 -277.11019)
		(end 298.942252 -277.11019)
		(width 0.16002)
		(layer "In13.Cu")
		(net "M_B_CPU0_SB_DQS_DP<4>")
	)
	(segment
		(start 305.797204 -276.77237)
		(end 305.578256 -276.991318)
		(width 0.16002)
		(layer "In13.Cu")
		(net "M_B_CPU0_SB_DQS_DP<4>")
	)
	(segment
		(start 337.145122 -272.200624)
		(end 337.121754 -272.113756)
		(width 0.09525)
		(layer "In13.Cu")
		(net "M_B_CPU0_SB_DQS_DP<4>")
	)
	(segment
		(start 324.367144 -270.879062)
		(end 324.156324 -270.668242)
		(width 0.09525)
		(layer "In13.Cu")
		(net "M_B_CPU0_SB_DQS_DP<4>")
	)
	(segment
		(start 307.212746 -276.77237)
		(end 305.797204 -276.77237)
		(width 0.16002)
		(layer "In13.Cu")
		(net "M_B_CPU0_SB_DQS_DP<4>")
	)
	(segment
		(start 308.08422 -276.411436)
		(end 307.212746 -276.77237)
		(width 0.16002)
		(layer "In13.Cu")
		(net "M_B_CPU0_SB_DQS_DP<4>")
	)
	(segment
		(start 333.99095 -272.136108)
		(end 333.982568 -272.140934)
		(width 0.09525)
		(layer "In13.Cu")
		(net "M_B_CPU0_SB_DQS_DP<4>")
	)
	(segment
		(start 324.156324 -270.668242)
		(end 323.978524 -270.668242)
		(width 0.09525)
		(layer "In13.Cu")
		(net "M_B_CPU0_SB_DQS_DP<4>")
	)
	(segment
		(start 323.895974 -270.72717)
		(end 313.768486 -270.72717)
		(width 0.16002)
		(layer "In13.Cu")
		(net "M_B_CPU0_SB_DQS_DP<4>")
	)
	(segment
		(start 331.539596 -272.140934)
		(end 331.531214 -272.136108)
		(width 0.09525)
		(layer "In13.Cu")
		(net "M_B_CPU0_SB_DQS_DP<4>")
	)
	(segment
		(start 305.578256 -276.991318)
		(end 305.25466 -277.125684)
		(width 0.16002)
		(layer "In13.Cu")
		(net "M_B_CPU0_SB_DQS_DP<4>")
	)
	(segment
		(start 301.754032 -277.58517)
		(end 301.279052 -277.11019)
		(width 0.16002)
		(layer "In13.Cu")
		(net "M_B_CPU0_SB_DQS_DP<4>")
	)
	(segment
		(start 297.050968 -276.930104)
		(end 296.029126 -276.930104)
		(width 0.16002)
		(layer "In13.Cu")
		(net "M_B_CPU0_SB_DQS_DP<4>")
	)
	(segment
		(start 329.290934 -272.136108)
		(end 329.282552 -272.140934)
		(width 0.09525)
		(layer "In13.Cu")
		(net "M_B_CPU0_SB_DQS_DP<4>")
	)
	(segment
		(start 326.446896 -272.090134)
		(end 325.235824 -270.879062)
		(width 0.09525)
		(layer "In13.Cu")
		(net "M_B_CPU0_SB_DQS_DP<4>")
	)
	(segment
		(start 327.592944 -272.090134)
		(end 326.446896 -272.090134)
		(width 0.09525)
		(layer "In13.Cu")
		(net "M_B_CPU0_SB_DQS_DP<4>")
	)
	(segment
		(start 313.768486 -270.72717)
		(end 308.08422 -276.411436)
		(width 0.16002)
		(layer "In13.Cu")
		(net "M_B_CPU0_SB_DQS_DP<4>")
	)
	(segment
		(start 297.55465 -276.72157)
		(end 297.050968 -276.930104)
		(width 0.16002)
		(layer "In13.Cu")
		(net "M_B_CPU0_SB_DQS_DP<4>")
	)
	(segment
		(start 332.47965 -272.140934)
		(end 332.471268 -272.136108)
		(width 0.09525)
		(layer "In13.Cu")
		(net "M_B_CPU0_SB_DQS_DP<4>")
	)
	(segment
		(start 323.919596 -270.72717)
		(end 323.895974 -270.72717)
		(width 0.09525)
		(layer "In13.Cu")
		(net "M_B_CPU0_SB_DQS_DP<4>")
	)
	(segment
		(start 328.719688 -272.140934)
		(end 328.711306 -272.136108)
		(width 0.09525)
		(layer "In13.Cu")
		(net "M_B_CPU0_SB_DQS_DP<4>")
	)
	(segment
		(start 336.991198 -272.466054)
		(end 337.145122 -272.200624)
		(width 0.09525)
		(layer "In13.Cu")
		(net "M_B_CPU0_SB_DQS_DP<4>")
	)
	(segment
		(start 298.942252 -277.11019)
		(end 298.553632 -276.72157)
		(width 0.16002)
		(layer "In13.Cu")
		(net "M_B_CPU0_SB_DQS_DP<4>")
	)
	(segment
		(start 305.25466 -277.125684)
		(end 302.942752 -277.58517)
		(width 0.16002)
		(layer "In13.Cu")
		(net "M_B_CPU0_SB_DQS_DP<4>")
	)
	(segment
		(start 325.235824 -270.879062)
		(end 324.367144 -270.879062)
		(width 0.09525)
		(layer "In13.Cu")
		(net "M_B_CPU0_SB_DQS_DP<4>")
	)
	(segment
		(start 333.050896 -272.136108)
		(end 333.042514 -272.140934)
		(width 0.09525)
		(layer "In13.Cu")
		(net "M_B_CPU0_SB_DQS_DP<4>")
	)
	(segment
		(start 327.804272 -272.154396)
		(end 327.780904 -272.140934)
		(width 0.09525)
		(layer "In13.Cu")
		(net "M_B_CPU0_SB_DQS_DP<4>")
	)
	(arc
		(start 333.042514 -272.140934)
		(mid 332.761082 -272.216689)
		(end 332.47965 -272.140934)
		(width 0.09525)
		(layer "In13.Cu")
		(net "M_B_CPU0_SB_DQS_DP<4>")
	)
	(arc
		(start 330.599542 -272.140934)
		(mid 330.411074 -272.090257)
		(end 330.222606 -272.140934)
		(width 0.09525)
		(layer "In13.Cu")
		(net "M_B_CPU0_SB_DQS_DP<4>")
	)
	(arc
		(start 328.711306 -272.136108)
		(mid 328.526274 -272.090194)
		(end 328.342498 -272.140934)
		(width 0.09525)
		(layer "In13.Cu")
		(net "M_B_CPU0_SB_DQS_DP<4>")
	)
	(arc
		(start 329.282552 -272.140934)
		(mid 329.00112 -272.216689)
		(end 328.719688 -272.140934)
		(width 0.09525)
		(layer "In13.Cu")
		(net "M_B_CPU0_SB_DQS_DP<4>")
	)
	(arc
		(start 329.659742 -272.140934)
		(mid 329.475967 -272.090162)
		(end 329.290934 -272.136108)
		(width 0.09525)
		(layer "In13.Cu")
		(net "M_B_CPU0_SB_DQS_DP<4>")
	)
	(arc
		(start 327.780904 -272.140934)
		(mid 327.690275 -272.103127)
		(end 327.592944 -272.090134)
		(width 0.09525)
		(layer "In13.Cu")
		(net "M_B_CPU0_SB_DQS_DP<4>")
	)
	(arc
		(start 330.222606 -272.140934)
		(mid 329.941174 -272.216689)
		(end 329.659742 -272.140934)
		(width 0.09525)
		(layer "In13.Cu")
		(net "M_B_CPU0_SB_DQS_DP<4>")
	)
	(arc
		(start 333.982568 -272.140934)
		(mid 333.701136 -272.216689)
		(end 333.419704 -272.140934)
		(width 0.09525)
		(layer "In13.Cu")
		(net "M_B_CPU0_SB_DQS_DP<4>")
	)
	(arc
		(start 333.419704 -272.140934)
		(mid 333.235929 -272.090162)
		(end 333.050896 -272.136108)
		(width 0.09525)
		(layer "In13.Cu")
		(net "M_B_CPU0_SB_DQS_DP<4>")
	)
	(arc
		(start 328.342498 -272.140934)
		(mid 328.075104 -272.216513)
		(end 327.804272 -272.154396)
		(width 0.09525)
		(layer "In13.Cu")
		(net "M_B_CPU0_SB_DQS_DP<4>")
	)
	(arc
		(start 331.531214 -272.136108)
		(mid 331.346182 -272.090194)
		(end 331.162406 -272.140934)
		(width 0.09525)
		(layer "In13.Cu")
		(net "M_B_CPU0_SB_DQS_DP<4>")
	)
	(arc
		(start 336.23123 -272.136108)
		(mid 336.046198 -272.090194)
		(end 335.862422 -272.140934)
		(width 0.09525)
		(layer "In13.Cu")
		(net "M_B_CPU0_SB_DQS_DP<4>")
	)
	(arc
		(start 332.471268 -272.136108)
		(mid 332.286236 -272.090194)
		(end 332.10246 -272.140934)
		(width 0.09525)
		(layer "In13.Cu")
		(net "M_B_CPU0_SB_DQS_DP<4>")
	)
	(arc
		(start 334.922622 -272.140934)
		(mid 334.64119 -272.216689)
		(end 334.359758 -272.140934)
		(width 0.09525)
		(layer "In13.Cu")
		(net "M_B_CPU0_SB_DQS_DP<4>")
	)
	(arc
		(start 332.10246 -272.140934)
		(mid 331.821028 -272.216689)
		(end 331.539596 -272.140934)
		(width 0.09525)
		(layer "In13.Cu")
		(net "M_B_CPU0_SB_DQS_DP<4>")
	)
	(arc
		(start 331.162406 -272.140934)
		(mid 330.880974 -272.216689)
		(end 330.599542 -272.140934)
		(width 0.09525)
		(layer "In13.Cu")
		(net "M_B_CPU0_SB_DQS_DP<4>")
	)
	(arc
		(start 337.121754 -272.113756)
		(mid 336.959072 -272.091624)
		(end 336.802476 -272.140934)
		(width 0.09525)
		(layer "In13.Cu")
		(net "M_B_CPU0_SB_DQS_DP<4>")
	)
	(arc
		(start 336.802476 -272.140934)
		(mid 336.521044 -272.216689)
		(end 336.239612 -272.140934)
		(width 0.09525)
		(layer "In13.Cu")
		(net "M_B_CPU0_SB_DQS_DP<4>")
	)
	(arc
		(start 334.359758 -272.140934)
		(mid 334.175983 -272.090162)
		(end 333.99095 -272.136108)
		(width 0.09525)
		(layer "In13.Cu")
		(net "M_B_CPU0_SB_DQS_DP<4>")
	)
	(arc
		(start 335.862422 -272.140934)
		(mid 335.58099 -272.216689)
		(end 335.299558 -272.140934)
		(width 0.09525)
		(layer "In13.Cu")
		(net "M_B_CPU0_SB_DQS_DP<4>")
	)
	(arc
		(start 335.299558 -272.140934)
		(mid 335.11109 -272.090257)
		(end 334.922622 -272.140934)
		(width 0.09525)
		(layer "In13.Cu")
		(net "M_B_CPU0_SB_DQS_DP<4>")
	)
	(segment
		(start 336.517996 -290.019994)
		(end 336.051144 -290.285932)
		(width 0.12954)
		(layer "F.Cu")
		(net "M_B_CPU0_SB_DQS_DP<3>")
	)
	(segment
		(start 300.097952 -313.208924)
		(end 302.483774 -313.208924)
		(width 0.16002)
		(layer "In13.Cu")
		(net "M_B_CPU0_SB_DQS_DP<3>")
	)
	(segment
		(start 309.582058 -311.503822)
		(end 309.475632 -311.397396)
		(width 0.16002)
		(layer "In13.Cu")
		(net "M_B_CPU0_SB_DQS_DP<3>")
	)
	(segment
		(start 316.716664 -303.628806)
		(end 317.243714 -303.628806)
		(width 0.16002)
		(layer "In13.Cu")
		(net "M_B_CPU0_SB_DQS_DP<3>")
	)
	(segment
		(start 315.976762 -305.109118)
		(end 316.253622 -305.109118)
		(width 0.16002)
		(layer "In13.Cu")
		(net "M_B_CPU0_SB_DQS_DP<3>")
	)
	(segment
		(start 328.711306 -290.615878)
		(end 328.719688 -290.611052)
		(width 0.09525)
		(layer "In13.Cu")
		(net "M_B_CPU0_SB_DQS_DP<3>")
	)
	(segment
		(start 313.596528 -307.2765)
		(end 313.596528 -306.748942)
		(width 0.16002)
		(layer "In13.Cu")
		(net "M_B_CPU0_SB_DQS_DP<3>")
	)
	(segment
		(start 317.82385 -303.26203)
		(end 317.717424 -303.155604)
		(width 0.16002)
		(layer "In13.Cu")
		(net "M_B_CPU0_SB_DQS_DP<3>")
	)
	(segment
		(start 307.086508 -312.404252)
		(end 307.203348 -312.521092)
		(width 0.16002)
		(layer "In13.Cu")
		(net "M_B_CPU0_SB_DQS_DP<3>")
	)
	(segment
		(start 312.222896 -308.122574)
		(end 312.595768 -307.749702)
		(width 0.16002)
		(layer "In13.Cu")
		(net "M_B_CPU0_SB_DQS_DP<3>")
	)
	(segment
		(start 313.122818 -307.749702)
		(end 313.229498 -307.856382)
		(width 0.16002)
		(layer "In13.Cu")
		(net "M_B_CPU0_SB_DQS_DP<3>")
	)
	(segment
		(start 332.471268 -290.615878)
		(end 332.47965 -290.611052)
		(width 0.09525)
		(layer "In13.Cu")
		(net "M_B_CPU0_SB_DQS_DP<3>")
	)
	(segment
		(start 310.849264 -309.496206)
		(end 311.222136 -309.123334)
		(width 0.16002)
		(layer "In13.Cu")
		(net "M_B_CPU0_SB_DQS_DP<3>")
	)
	(segment
		(start 305.689254 -312.521092)
		(end 306.489608 -312.521092)
		(width 0.16002)
		(layer "In13.Cu")
		(net "M_B_CPU0_SB_DQS_DP<3>")
	)
	(segment
		(start 309.385462 -311.977278)
		(end 309.582058 -311.780682)
		(width 0.16002)
		(layer "In13.Cu")
		(net "M_B_CPU0_SB_DQS_DP<3>")
	)
	(segment
		(start 317.717424 -303.155604)
		(end 317.717424 -302.628046)
		(width 0.16002)
		(layer "In13.Cu")
		(net "M_B_CPU0_SB_DQS_DP<3>")
	)
	(segment
		(start 324.173088 -295.064688)
		(end 324.377558 -294.860218)
		(width 0.09525)
		(layer "In13.Cu")
		(net "M_B_CPU0_SB_DQS_DP<3>")
	)
	(segment
		(start 335.796382 -290.578032)
		(end 335.89722 -290.551362)
		(width 0.09525)
		(layer "In13.Cu")
		(net "M_B_CPU0_SB_DQS_DP<3>")
	)
	(segment
		(start 310.849264 -310.023764)
		(end 310.849264 -309.496206)
		(width 0.16002)
		(layer "In13.Cu")
		(net "M_B_CPU0_SB_DQS_DP<3>")
	)
	(segment
		(start 317.717424 -302.628046)
		(end 321.377818 -298.967652)
		(width 0.16002)
		(layer "In13.Cu")
		(net "M_B_CPU0_SB_DQS_DP<3>")
	)
	(segment
		(start 310.482234 -310.603646)
		(end 310.759094 -310.603646)
		(width 0.16002)
		(layer "In13.Cu")
		(net "M_B_CPU0_SB_DQS_DP<3>")
	)
	(segment
		(start 333.042514 -290.611052)
		(end 333.050896 -290.615878)
		(width 0.09525)
		(layer "In13.Cu")
		(net "M_B_CPU0_SB_DQS_DP<3>")
	)
	(segment
		(start 317.82385 -303.53889)
		(end 317.82385 -303.26203)
		(width 0.16002)
		(layer "In13.Cu")
		(net "M_B_CPU0_SB_DQS_DP<3>")
	)
	(segment
		(start 312.329322 -309.033418)
		(end 312.329322 -308.756558)
		(width 0.16002)
		(layer "In13.Cu")
		(net "M_B_CPU0_SB_DQS_DP<3>")
	)
	(segment
		(start 327.684892 -290.53536)
		(end 328.06132 -290.53536)
		(width 0.09525)
		(layer "In13.Cu")
		(net "M_B_CPU0_SB_DQS_DP<3>")
	)
	(segment
		(start 335.89722 -290.551362)
		(end 336.051144 -290.285932)
		(width 0.09525)
		(layer "In13.Cu")
		(net "M_B_CPU0_SB_DQS_DP<3>")
	)
	(segment
		(start 309.475632 -310.869838)
		(end 309.848504 -310.496966)
		(width 0.16002)
		(layer "In13.Cu")
		(net "M_B_CPU0_SB_DQS_DP<3>")
	)
	(segment
		(start 315.343032 -305.002438)
		(end 315.870082 -305.002438)
		(width 0.16002)
		(layer "In13.Cu")
		(net "M_B_CPU0_SB_DQS_DP<3>")
	)
	(segment
		(start 311.222136 -309.123334)
		(end 311.749186 -309.123334)
		(width 0.16002)
		(layer "In13.Cu")
		(net "M_B_CPU0_SB_DQS_DP<3>")
	)
	(segment
		(start 325.07174 -293.251636)
		(end 326.243188 -291.498782)
		(width 0.09525)
		(layer "In13.Cu")
		(net "M_B_CPU0_SB_DQS_DP<3>")
	)
	(segment
		(start 315.870082 -305.002438)
		(end 315.976762 -305.109118)
		(width 0.16002)
		(layer "In13.Cu")
		(net "M_B_CPU0_SB_DQS_DP<3>")
	)
	(segment
		(start 310.375554 -310.496966)
		(end 310.482234 -310.603646)
		(width 0.16002)
		(layer "In13.Cu")
		(net "M_B_CPU0_SB_DQS_DP<3>")
	)
	(segment
		(start 311.749186 -309.123334)
		(end 311.855866 -309.230014)
		(width 0.16002)
		(layer "In13.Cu")
		(net "M_B_CPU0_SB_DQS_DP<3>")
	)
	(segment
		(start 314.97016 -305.37531)
		(end 315.343032 -305.002438)
		(width 0.16002)
		(layer "In13.Cu")
		(net "M_B_CPU0_SB_DQS_DP<3>")
	)
	(segment
		(start 310.95569 -310.40705)
		(end 310.95569 -310.13019)
		(width 0.16002)
		(layer "In13.Cu")
		(net "M_B_CPU0_SB_DQS_DP<3>")
	)
	(segment
		(start 324.377558 -294.860218)
		(end 324.377558 -294.268398)
		(width 0.09525)
		(layer "In13.Cu")
		(net "M_B_CPU0_SB_DQS_DP<3>")
	)
	(segment
		(start 326.243188 -291.498782)
		(end 327.684892 -290.53536)
		(width 0.09525)
		(layer "In13.Cu")
		(net "M_B_CPU0_SB_DQS_DP<3>")
	)
	(segment
		(start 317.350394 -303.735486)
		(end 317.627254 -303.735486)
		(width 0.16002)
		(layer "In13.Cu")
		(net "M_B_CPU0_SB_DQS_DP<3>")
	)
	(segment
		(start 314.97016 -305.902868)
		(end 314.97016 -305.37531)
		(width 0.16002)
		(layer "In13.Cu")
		(net "M_B_CPU0_SB_DQS_DP<3>")
	)
	(segment
		(start 324.089268 -295.064688)
		(end 324.173088 -295.064688)
		(width 0.09525)
		(layer "In13.Cu")
		(net "M_B_CPU0_SB_DQS_DP<3>")
	)
	(segment
		(start 324.072504 -295.081452)
		(end 324.089268 -295.064688)
		(width 0.09525)
		(layer "In13.Cu")
		(net "M_B_CPU0_SB_DQS_DP<3>")
	)
	(segment
		(start 316.343792 -304.001678)
		(end 316.716664 -303.628806)
		(width 0.16002)
		(layer "In13.Cu")
		(net "M_B_CPU0_SB_DQS_DP<3>")
	)
	(segment
		(start 331.531214 -290.615878)
		(end 331.539596 -290.611052)
		(width 0.09525)
		(layer "In13.Cu")
		(net "M_B_CPU0_SB_DQS_DP<3>")
	)
	(segment
		(start 315.076586 -306.286154)
		(end 315.076586 -306.009294)
		(width 0.16002)
		(layer "In13.Cu")
		(net "M_B_CPU0_SB_DQS_DP<3>")
	)
	(segment
		(start 316.450218 -304.912522)
		(end 316.450218 -304.635662)
		(width 0.16002)
		(layer "In13.Cu")
		(net "M_B_CPU0_SB_DQS_DP<3>")
	)
	(segment
		(start 316.343792 -304.529236)
		(end 316.343792 -304.001678)
		(width 0.16002)
		(layer "In13.Cu")
		(net "M_B_CPU0_SB_DQS_DP<3>")
	)
	(segment
		(start 307.203348 -312.521092)
		(end 307.824378 -312.521092)
		(width 0.16002)
		(layer "In13.Cu")
		(net "M_B_CPU0_SB_DQS_DP<3>")
	)
	(segment
		(start 317.627254 -303.735486)
		(end 317.82385 -303.53889)
		(width 0.16002)
		(layer "In13.Cu")
		(net "M_B_CPU0_SB_DQS_DP<3>")
	)
	(segment
		(start 329.282552 -290.611052)
		(end 329.290934 -290.615878)
		(width 0.09525)
		(layer "In13.Cu")
		(net "M_B_CPU0_SB_DQS_DP<3>")
	)
	(segment
		(start 309.475632 -311.397396)
		(end 309.475632 -310.869838)
		(width 0.16002)
		(layer "In13.Cu")
		(net "M_B_CPU0_SB_DQS_DP<3>")
	)
	(segment
		(start 314.87999 -306.48275)
		(end 315.076586 -306.286154)
		(width 0.16002)
		(layer "In13.Cu")
		(net "M_B_CPU0_SB_DQS_DP<3>")
	)
	(segment
		(start 324.605396 -293.718234)
		(end 325.07174 -293.251636)
		(width 0.09525)
		(layer "In13.Cu")
		(net "M_B_CPU0_SB_DQS_DP<3>")
	)
	(segment
		(start 313.702954 -307.382926)
		(end 313.596528 -307.2765)
		(width 0.16002)
		(layer "In13.Cu")
		(net "M_B_CPU0_SB_DQS_DP<3>")
	)
	(segment
		(start 306.606448 -312.404252)
		(end 307.086508 -312.404252)
		(width 0.16002)
		(layer "In13.Cu")
		(net "M_B_CPU0_SB_DQS_DP<3>")
	)
	(segment
		(start 311.855866 -309.230014)
		(end 312.132726 -309.230014)
		(width 0.16002)
		(layer "In13.Cu")
		(net "M_B_CPU0_SB_DQS_DP<3>")
	)
	(segment
		(start 313.229498 -307.856382)
		(end 313.506358 -307.856382)
		(width 0.16002)
		(layer "In13.Cu")
		(net "M_B_CPU0_SB_DQS_DP<3>")
	)
	(segment
		(start 312.222896 -308.650132)
		(end 312.222896 -308.122574)
		(width 0.16002)
		(layer "In13.Cu")
		(net "M_B_CPU0_SB_DQS_DP<3>")
	)
	(segment
		(start 315.076586 -306.009294)
		(end 314.97016 -305.902868)
		(width 0.16002)
		(layer "In13.Cu")
		(net "M_B_CPU0_SB_DQS_DP<3>")
	)
	(segment
		(start 324.377558 -294.268398)
		(end 324.605396 -293.718234)
		(width 0.09525)
		(layer "In13.Cu")
		(net "M_B_CPU0_SB_DQS_DP<3>")
	)
	(segment
		(start 309.582058 -311.780682)
		(end 309.582058 -311.503822)
		(width 0.16002)
		(layer "In13.Cu")
		(net "M_B_CPU0_SB_DQS_DP<3>")
	)
	(segment
		(start 310.759094 -310.603646)
		(end 310.95569 -310.40705)
		(width 0.16002)
		(layer "In13.Cu")
		(net "M_B_CPU0_SB_DQS_DP<3>")
	)
	(segment
		(start 303.002188 -312.69051)
		(end 303.516284 -312.69051)
		(width 0.16002)
		(layer "In13.Cu")
		(net "M_B_CPU0_SB_DQS_DP<3>")
	)
	(segment
		(start 308.368192 -311.977278)
		(end 309.385462 -311.977278)
		(width 0.16002)
		(layer "In13.Cu")
		(net "M_B_CPU0_SB_DQS_DP<3>")
	)
	(segment
		(start 333.982568 -290.611052)
		(end 333.99095 -290.615878)
		(width 0.09525)
		(layer "In13.Cu")
		(net "M_B_CPU0_SB_DQS_DP<3>")
	)
	(segment
		(start 313.702954 -307.659786)
		(end 313.702954 -307.382926)
		(width 0.16002)
		(layer "In13.Cu")
		(net "M_B_CPU0_SB_DQS_DP<3>")
	)
	(segment
		(start 316.450218 -304.635662)
		(end 316.343792 -304.529236)
		(width 0.16002)
		(layer "In13.Cu")
		(net "M_B_CPU0_SB_DQS_DP<3>")
	)
	(segment
		(start 304.210466 -313.384692)
		(end 304.825654 -313.384692)
		(width 0.16002)
		(layer "In13.Cu")
		(net "M_B_CPU0_SB_DQS_DP<3>")
	)
	(segment
		(start 314.49645 -306.37607)
		(end 314.60313 -306.48275)
		(width 0.16002)
		(layer "In13.Cu")
		(net "M_B_CPU0_SB_DQS_DP<3>")
	)
	(segment
		(start 310.95569 -310.13019)
		(end 310.849264 -310.023764)
		(width 0.16002)
		(layer "In13.Cu")
		(net "M_B_CPU0_SB_DQS_DP<3>")
	)
	(segment
		(start 313.596528 -306.748942)
		(end 313.9694 -306.37607)
		(width 0.16002)
		(layer "In13.Cu")
		(net "M_B_CPU0_SB_DQS_DP<3>")
	)
	(segment
		(start 299.82414 -312.935112)
		(end 300.097952 -313.208924)
		(width 0.16002)
		(layer "In13.Cu")
		(net "M_B_CPU0_SB_DQS_DP<3>")
	)
	(segment
		(start 309.848504 -310.496966)
		(end 310.375554 -310.496966)
		(width 0.16002)
		(layer "In13.Cu")
		(net "M_B_CPU0_SB_DQS_DP<3>")
	)
	(segment
		(start 321.377818 -297.77563)
		(end 324.072504 -295.081452)
		(width 0.16002)
		(layer "In13.Cu")
		(net "M_B_CPU0_SB_DQS_DP<3>")
	)
	(segment
		(start 312.595768 -307.749702)
		(end 313.122818 -307.749702)
		(width 0.16002)
		(layer "In13.Cu")
		(net "M_B_CPU0_SB_DQS_DP<3>")
	)
	(segment
		(start 312.329322 -308.756558)
		(end 312.222896 -308.650132)
		(width 0.16002)
		(layer "In13.Cu")
		(net "M_B_CPU0_SB_DQS_DP<3>")
	)
	(segment
		(start 302.483774 -313.208924)
		(end 303.002188 -312.69051)
		(width 0.16002)
		(layer "In13.Cu")
		(net "M_B_CPU0_SB_DQS_DP<3>")
	)
	(segment
		(start 321.377818 -298.967652)
		(end 321.377818 -297.77563)
		(width 0.16002)
		(layer "In13.Cu")
		(net "M_B_CPU0_SB_DQS_DP<3>")
	)
	(segment
		(start 316.253622 -305.109118)
		(end 316.450218 -304.912522)
		(width 0.16002)
		(layer "In13.Cu")
		(net "M_B_CPU0_SB_DQS_DP<3>")
	)
	(segment
		(start 304.825654 -313.384692)
		(end 305.689254 -312.521092)
		(width 0.16002)
		(layer "In13.Cu")
		(net "M_B_CPU0_SB_DQS_DP<3>")
	)
	(segment
		(start 303.516284 -312.69051)
		(end 304.210466 -313.384692)
		(width 0.16002)
		(layer "In13.Cu")
		(net "M_B_CPU0_SB_DQS_DP<3>")
	)
	(segment
		(start 312.132726 -309.230014)
		(end 312.329322 -309.033418)
		(width 0.16002)
		(layer "In13.Cu")
		(net "M_B_CPU0_SB_DQS_DP<3>")
	)
	(segment
		(start 314.60313 -306.48275)
		(end 314.87999 -306.48275)
		(width 0.16002)
		(layer "In13.Cu")
		(net "M_B_CPU0_SB_DQS_DP<3>")
	)
	(segment
		(start 313.506358 -307.856382)
		(end 313.702954 -307.659786)
		(width 0.16002)
		(layer "In13.Cu")
		(net "M_B_CPU0_SB_DQS_DP<3>")
	)
	(segment
		(start 307.824378 -312.521092)
		(end 308.368192 -311.977278)
		(width 0.16002)
		(layer "In13.Cu")
		(net "M_B_CPU0_SB_DQS_DP<3>")
	)
	(segment
		(start 313.9694 -306.37607)
		(end 314.49645 -306.37607)
		(width 0.16002)
		(layer "In13.Cu")
		(net "M_B_CPU0_SB_DQS_DP<3>")
	)
	(segment
		(start 317.243714 -303.628806)
		(end 317.350394 -303.735486)
		(width 0.16002)
		(layer "In13.Cu")
		(net "M_B_CPU0_SB_DQS_DP<3>")
	)
	(segment
		(start 306.489608 -312.521092)
		(end 306.606448 -312.404252)
		(width 0.16002)
		(layer "In13.Cu")
		(net "M_B_CPU0_SB_DQS_DP<3>")
	)
	(arc
		(start 331.162406 -290.611052)
		(mid 331.346181 -290.661824)
		(end 331.531214 -290.615878)
		(width 0.09525)
		(layer "In13.Cu")
		(net "M_B_CPU0_SB_DQS_DP<3>")
	)
	(arc
		(start 328.719688 -290.611052)
		(mid 329.00112 -290.535297)
		(end 329.282552 -290.611052)
		(width 0.09525)
		(layer "In13.Cu")
		(net "M_B_CPU0_SB_DQS_DP<3>")
	)
	(arc
		(start 329.290934 -290.615878)
		(mid 329.475966 -290.661792)
		(end 329.659742 -290.611052)
		(width 0.09525)
		(layer "In13.Cu")
		(net "M_B_CPU0_SB_DQS_DP<3>")
	)
	(arc
		(start 332.47965 -290.611052)
		(mid 332.761082 -290.535297)
		(end 333.042514 -290.611052)
		(width 0.09525)
		(layer "In13.Cu")
		(net "M_B_CPU0_SB_DQS_DP<3>")
	)
	(arc
		(start 334.922622 -290.611052)
		(mid 335.11109 -290.661729)
		(end 335.299558 -290.611052)
		(width 0.09525)
		(layer "In13.Cu")
		(net "M_B_CPU0_SB_DQS_DP<3>")
	)
	(arc
		(start 330.599542 -290.611052)
		(mid 330.880974 -290.535297)
		(end 331.162406 -290.611052)
		(width 0.09525)
		(layer "In13.Cu")
		(net "M_B_CPU0_SB_DQS_DP<3>")
	)
	(arc
		(start 328.342498 -290.611052)
		(mid 328.526273 -290.661824)
		(end 328.711306 -290.615878)
		(width 0.09525)
		(layer "In13.Cu")
		(net "M_B_CPU0_SB_DQS_DP<3>")
	)
	(arc
		(start 333.050896 -290.615878)
		(mid 333.235928 -290.661792)
		(end 333.419704 -290.611052)
		(width 0.09525)
		(layer "In13.Cu")
		(net "M_B_CPU0_SB_DQS_DP<3>")
	)
	(arc
		(start 335.299558 -290.611052)
		(mid 335.533072 -290.537209)
		(end 335.775808 -290.569904)
		(width 0.09525)
		(layer "In13.Cu")
		(net "M_B_CPU0_SB_DQS_DP<3>")
	)
	(arc
		(start 329.659742 -290.611052)
		(mid 329.941174 -290.535297)
		(end 330.222606 -290.611052)
		(width 0.09525)
		(layer "In13.Cu")
		(net "M_B_CPU0_SB_DQS_DP<3>")
	)
	(arc
		(start 328.06132 -290.53536)
		(mid 328.206897 -290.554661)
		(end 328.342498 -290.611052)
		(width 0.09525)
		(layer "In13.Cu")
		(net "M_B_CPU0_SB_DQS_DP<3>")
	)
	(arc
		(start 330.222606 -290.611052)
		(mid 330.411074 -290.661729)
		(end 330.599542 -290.611052)
		(width 0.09525)
		(layer "In13.Cu")
		(net "M_B_CPU0_SB_DQS_DP<3>")
	)
	(arc
		(start 334.359758 -290.611052)
		(mid 334.64119 -290.535297)
		(end 334.922622 -290.611052)
		(width 0.09525)
		(layer "In13.Cu")
		(net "M_B_CPU0_SB_DQS_DP<3>")
	)
	(arc
		(start 331.539596 -290.611052)
		(mid 331.821028 -290.535297)
		(end 332.10246 -290.611052)
		(width 0.09525)
		(layer "In13.Cu")
		(net "M_B_CPU0_SB_DQS_DP<3>")
	)
	(arc
		(start 333.419704 -290.611052)
		(mid 333.701136 -290.535297)
		(end 333.982568 -290.611052)
		(width 0.09525)
		(layer "In13.Cu")
		(net "M_B_CPU0_SB_DQS_DP<3>")
	)
	(arc
		(start 333.99095 -290.615878)
		(mid 334.175982 -290.661792)
		(end 334.359758 -290.611052)
		(width 0.09525)
		(layer "In13.Cu")
		(net "M_B_CPU0_SB_DQS_DP<3>")
	)
	(arc
		(start 335.775808 -290.569904)
		(mid 335.786136 -290.573864)
		(end 335.796382 -290.578032)
		(width 0.09525)
		(layer "In13.Cu")
		(net "M_B_CPU0_SB_DQS_DP<3>")
	)
	(arc
		(start 332.10246 -290.611052)
		(mid 332.286235 -290.661824)
		(end 332.471268 -290.615878)
		(width 0.09525)
		(layer "In13.Cu")
		(net "M_B_CPU0_SB_DQS_DP<3>")
	)
	(segment
		(start 336.517996 -285.160212)
		(end 336.051144 -285.42615)
		(width 0.12954)
		(layer "F.Cu")
		(net "M_B_CPU0_SB_DQS_DP<2>")
	)
	(segment
		(start 311.913016 -299.485558)
		(end 311.701688 -299.27423)
		(width 0.16002)
		(layer "In13.Cu")
		(net "M_B_CPU0_SB_DQS_DP<2>")
	)
	(segment
		(start 311.012586 -300.66234)
		(end 310.815736 -300.85919)
		(width 0.16002)
		(layer "In13.Cu")
		(net "M_B_CPU0_SB_DQS_DP<2>")
	)
	(segment
		(start 325.383144 -286.365442)
		(end 324.166992 -286.365442)
		(width 0.09525)
		(layer "In13.Cu")
		(net "M_B_CPU0_SB_DQS_DP<2>")
	)
	(segment
		(start 307.571648 -303.171098)
		(end 307.454808 -303.054258)
		(width 0.16002)
		(layer "In13.Cu")
		(net "M_B_CPU0_SB_DQS_DP<2>")
	)
	(segment
		(start 301.302928 -303.85893)
		(end 300.097952 -303.85893)
		(width 0.16002)
		(layer "In13.Cu")
		(net "M_B_CPU0_SB_DQS_DP<2>")
	)
	(segment
		(start 333.050896 -285.756096)
		(end 333.042514 -285.75127)
		(width 0.09525)
		(layer "In13.Cu")
		(net "M_B_CPU0_SB_DQS_DP<2>")
	)
	(segment
		(start 302.330866 -304.09261)
		(end 301.536608 -304.09261)
		(width 0.16002)
		(layer "In13.Cu")
		(net "M_B_CPU0_SB_DQS_DP<2>")
	)
	(segment
		(start 329.290934 -285.756096)
		(end 329.282552 -285.75127)
		(width 0.09525)
		(layer "In13.Cu")
		(net "M_B_CPU0_SB_DQS_DP<2>")
	)
	(segment
		(start 304.007012 -303.727104)
		(end 303.623218 -303.34331)
		(width 0.16002)
		(layer "In13.Cu")
		(net "M_B_CPU0_SB_DQS_DP<2>")
	)
	(segment
		(start 312.189368 -299.485558)
		(end 311.913016 -299.485558)
		(width 0.16002)
		(layer "In13.Cu")
		(net "M_B_CPU0_SB_DQS_DP<2>")
	)
	(segment
		(start 315.133482 -296.541444)
		(end 314.936632 -296.738294)
		(width 0.16002)
		(layer "In13.Cu")
		(net "M_B_CPU0_SB_DQS_DP<2>")
	)
	(segment
		(start 313.286648 -298.111926)
		(end 313.07532 -297.900598)
		(width 0.16002)
		(layer "In13.Cu")
		(net "M_B_CPU0_SB_DQS_DP<2>")
	)
	(segment
		(start 327.77938 -285.75127)
		(end 327.715118 -285.788608)
		(width 0.09525)
		(layer "In13.Cu")
		(net "M_B_CPU0_SB_DQS_DP<2>")
	)
	(segment
		(start 326.898762 -285.721552)
		(end 326.710802 -285.809944)
		(width 0.09525)
		(layer "In13.Cu")
		(net "M_B_CPU0_SB_DQS_DP<2>")
	)
	(segment
		(start 304.204878 -304.47361)
		(end 304.007012 -304.275744)
		(width 0.16002)
		(layer "In13.Cu")
		(net "M_B_CPU0_SB_DQS_DP<2>")
	)
	(segment
		(start 303.623218 -303.34331)
		(end 303.080166 -303.34331)
		(width 0.16002)
		(layer "In13.Cu")
		(net "M_B_CPU0_SB_DQS_DP<2>")
	)
	(segment
		(start 300.097952 -303.85893)
		(end 299.82414 -303.585118)
		(width 0.16002)
		(layer "In13.Cu")
		(net "M_B_CPU0_SB_DQS_DP<2>")
	)
	(segment
		(start 325.938642 -285.809944)
		(end 325.383144 -286.365442)
		(width 0.09525)
		(layer "In13.Cu")
		(net "M_B_CPU0_SB_DQS_DP<2>")
	)
	(segment
		(start 324.166992 -286.365442)
		(end 323.996558 -286.535876)
		(width 0.09525)
		(layer "In13.Cu")
		(net "M_B_CPU0_SB_DQS_DP<2>")
	)
	(segment
		(start 311.701688 -299.27423)
		(end 311.174384 -299.27423)
		(width 0.16002)
		(layer "In13.Cu")
		(net "M_B_CPU0_SB_DQS_DP<2>")
	)
	(segment
		(start 309.358538 -301.982632)
		(end 308.170072 -303.171098)
		(width 0.16002)
		(layer "In13.Cu")
		(net "M_B_CPU0_SB_DQS_DP<2>")
	)
	(segment
		(start 326.710802 -285.809944)
		(end 325.938642 -285.809944)
		(width 0.09525)
		(layer "In13.Cu")
		(net "M_B_CPU0_SB_DQS_DP<2>")
	)
	(segment
		(start 328.342498 -285.75127)
		(end 328.332084 -285.745174)
		(width 0.09525)
		(layer "In13.Cu")
		(net "M_B_CPU0_SB_DQS_DP<2>")
	)
	(segment
		(start 306.857908 -303.171098)
		(end 305.742594 -303.171098)
		(width 0.16002)
		(layer "In13.Cu")
		(net "M_B_CPU0_SB_DQS_DP<2>")
	)
	(segment
		(start 309.358538 -301.090076)
		(end 309.358538 -301.982632)
		(width 0.16002)
		(layer "In13.Cu")
		(net "M_B_CPU0_SB_DQS_DP<2>")
	)
	(segment
		(start 331.539596 -285.75127)
		(end 331.531214 -285.756096)
		(width 0.09525)
		(layer "In13.Cu")
		(net "M_B_CPU0_SB_DQS_DP<2>")
	)
	(segment
		(start 312.175144 -298.27347)
		(end 312.175144 -298.801028)
		(width 0.16002)
		(layer "In13.Cu")
		(net "M_B_CPU0_SB_DQS_DP<2>")
	)
	(segment
		(start 306.974748 -303.054258)
		(end 306.857908 -303.171098)
		(width 0.16002)
		(layer "In13.Cu")
		(net "M_B_CPU0_SB_DQS_DP<2>")
	)
	(segment
		(start 304.007012 -304.275744)
		(end 304.007012 -303.727104)
		(width 0.16002)
		(layer "In13.Cu")
		(net "M_B_CPU0_SB_DQS_DP<2>")
	)
	(segment
		(start 314.448952 -296.526966)
		(end 313.921648 -296.526966)
		(width 0.16002)
		(layer "In13.Cu")
		(net "M_B_CPU0_SB_DQS_DP<2>")
	)
	(segment
		(start 310.801512 -299.647102)
		(end 310.801512 -300.17466)
		(width 0.16002)
		(layer "In13.Cu")
		(net "M_B_CPU0_SB_DQS_DP<2>")
	)
	(segment
		(start 311.174384 -299.27423)
		(end 310.801512 -299.647102)
		(width 0.16002)
		(layer "In13.Cu")
		(net "M_B_CPU0_SB_DQS_DP<2>")
	)
	(segment
		(start 312.386218 -299.288708)
		(end 312.189368 -299.485558)
		(width 0.16002)
		(layer "In13.Cu")
		(net "M_B_CPU0_SB_DQS_DP<2>")
	)
	(segment
		(start 323.912738 -286.535876)
		(end 323.895974 -286.55264)
		(width 0.09525)
		(layer "In13.Cu")
		(net "M_B_CPU0_SB_DQS_DP<2>")
	)
	(segment
		(start 313.563 -298.111926)
		(end 313.286648 -298.111926)
		(width 0.16002)
		(layer "In13.Cu")
		(net "M_B_CPU0_SB_DQS_DP<2>")
	)
	(segment
		(start 335.89722 -285.69158)
		(end 335.796382 -285.71825)
		(width 0.09525)
		(layer "In13.Cu")
		(net "M_B_CPU0_SB_DQS_DP<2>")
	)
	(segment
		(start 333.99095 -285.756096)
		(end 333.982568 -285.75127)
		(width 0.09525)
		(layer "In13.Cu")
		(net "M_B_CPU0_SB_DQS_DP<2>")
	)
	(segment
		(start 312.548016 -297.900598)
		(end 312.175144 -298.27347)
		(width 0.16002)
		(layer "In13.Cu")
		(net "M_B_CPU0_SB_DQS_DP<2>")
	)
	(segment
		(start 314.936632 -296.738294)
		(end 314.66028 -296.738294)
		(width 0.16002)
		(layer "In13.Cu")
		(net "M_B_CPU0_SB_DQS_DP<2>")
	)
	(segment
		(start 310.539384 -300.85919)
		(end 310.328056 -300.647862)
		(width 0.16002)
		(layer "In13.Cu")
		(net "M_B_CPU0_SB_DQS_DP<2>")
	)
	(segment
		(start 313.548776 -296.899838)
		(end 313.548776 -297.427396)
		(width 0.16002)
		(layer "In13.Cu")
		(net "M_B_CPU0_SB_DQS_DP<2>")
	)
	(segment
		(start 313.75985 -297.915076)
		(end 313.563 -298.111926)
		(width 0.16002)
		(layer "In13.Cu")
		(net "M_B_CPU0_SB_DQS_DP<2>")
	)
	(segment
		(start 323.895974 -286.55264)
		(end 314.922408 -295.526206)
		(width 0.16002)
		(layer "In13.Cu")
		(net "M_B_CPU0_SB_DQS_DP<2>")
	)
	(segment
		(start 314.66028 -296.738294)
		(end 314.448952 -296.526966)
		(width 0.16002)
		(layer "In13.Cu")
		(net "M_B_CPU0_SB_DQS_DP<2>")
	)
	(segment
		(start 313.07532 -297.900598)
		(end 312.548016 -297.900598)
		(width 0.16002)
		(layer "In13.Cu")
		(net "M_B_CPU0_SB_DQS_DP<2>")
	)
	(segment
		(start 308.170072 -303.171098)
		(end 307.571648 -303.171098)
		(width 0.16002)
		(layer "In13.Cu")
		(net "M_B_CPU0_SB_DQS_DP<2>")
	)
	(segment
		(start 313.548776 -297.427396)
		(end 313.75985 -297.63847)
		(width 0.16002)
		(layer "In13.Cu")
		(net "M_B_CPU0_SB_DQS_DP<2>")
	)
	(segment
		(start 307.454808 -303.054258)
		(end 306.974748 -303.054258)
		(width 0.16002)
		(layer "In13.Cu")
		(net "M_B_CPU0_SB_DQS_DP<2>")
	)
	(segment
		(start 310.801512 -300.17466)
		(end 311.012586 -300.385734)
		(width 0.16002)
		(layer "In13.Cu")
		(net "M_B_CPU0_SB_DQS_DP<2>")
	)
	(segment
		(start 332.47965 -285.75127)
		(end 332.471268 -285.756096)
		(width 0.09525)
		(layer "In13.Cu")
		(net "M_B_CPU0_SB_DQS_DP<2>")
	)
	(segment
		(start 309.800752 -300.647862)
		(end 309.358538 -301.090076)
		(width 0.16002)
		(layer "In13.Cu")
		(net "M_B_CPU0_SB_DQS_DP<2>")
	)
	(segment
		(start 313.75985 -297.63847)
		(end 313.75985 -297.915076)
		(width 0.16002)
		(layer "In13.Cu")
		(net "M_B_CPU0_SB_DQS_DP<2>")
	)
	(segment
		(start 304.440082 -304.47361)
		(end 304.204878 -304.47361)
		(width 0.16002)
		(layer "In13.Cu")
		(net "M_B_CPU0_SB_DQS_DP<2>")
	)
	(segment
		(start 314.922408 -296.053764)
		(end 315.133482 -296.264838)
		(width 0.16002)
		(layer "In13.Cu")
		(net "M_B_CPU0_SB_DQS_DP<2>")
	)
	(segment
		(start 310.328056 -300.647862)
		(end 309.800752 -300.647862)
		(width 0.16002)
		(layer "In13.Cu")
		(net "M_B_CPU0_SB_DQS_DP<2>")
	)
	(segment
		(start 336.051144 -285.42615)
		(end 335.89722 -285.69158)
		(width 0.09525)
		(layer "In13.Cu")
		(net "M_B_CPU0_SB_DQS_DP<2>")
	)
	(segment
		(start 323.996558 -286.535876)
		(end 323.912738 -286.535876)
		(width 0.09525)
		(layer "In13.Cu")
		(net "M_B_CPU0_SB_DQS_DP<2>")
	)
	(segment
		(start 315.133482 -296.264838)
		(end 315.133482 -296.541444)
		(width 0.16002)
		(layer "In13.Cu")
		(net "M_B_CPU0_SB_DQS_DP<2>")
	)
	(segment
		(start 303.080166 -303.34331)
		(end 302.330866 -304.09261)
		(width 0.16002)
		(layer "In13.Cu")
		(net "M_B_CPU0_SB_DQS_DP<2>")
	)
	(segment
		(start 312.175144 -298.801028)
		(end 312.386218 -299.012102)
		(width 0.16002)
		(layer "In13.Cu")
		(net "M_B_CPU0_SB_DQS_DP<2>")
	)
	(segment
		(start 312.386218 -299.012102)
		(end 312.386218 -299.288708)
		(width 0.16002)
		(layer "In13.Cu")
		(net "M_B_CPU0_SB_DQS_DP<2>")
	)
	(segment
		(start 301.536608 -304.09261)
		(end 301.302928 -303.85893)
		(width 0.16002)
		(layer "In13.Cu")
		(net "M_B_CPU0_SB_DQS_DP<2>")
	)
	(segment
		(start 313.921648 -296.526966)
		(end 313.548776 -296.899838)
		(width 0.16002)
		(layer "In13.Cu")
		(net "M_B_CPU0_SB_DQS_DP<2>")
	)
	(segment
		(start 314.922408 -295.526206)
		(end 314.922408 -296.053764)
		(width 0.16002)
		(layer "In13.Cu")
		(net "M_B_CPU0_SB_DQS_DP<2>")
	)
	(segment
		(start 311.012586 -300.385734)
		(end 311.012586 -300.66234)
		(width 0.16002)
		(layer "In13.Cu")
		(net "M_B_CPU0_SB_DQS_DP<2>")
	)
	(segment
		(start 328.719688 -285.75127)
		(end 328.711306 -285.756096)
		(width 0.09525)
		(layer "In13.Cu")
		(net "M_B_CPU0_SB_DQS_DP<2>")
	)
	(segment
		(start 305.742594 -303.171098)
		(end 304.440082 -304.47361)
		(width 0.16002)
		(layer "In13.Cu")
		(net "M_B_CPU0_SB_DQS_DP<2>")
	)
	(segment
		(start 310.815736 -300.85919)
		(end 310.539384 -300.85919)
		(width 0.16002)
		(layer "In13.Cu")
		(net "M_B_CPU0_SB_DQS_DP<2>")
	)
	(arc
		(start 327.715118 -285.788608)
		(mid 327.553093 -285.807536)
		(end 327.397872 -285.757366)
		(width 0.09525)
		(layer "In13.Cu")
		(net "M_B_CPU0_SB_DQS_DP<2>")
	)
	(arc
		(start 331.531214 -285.756096)
		(mid 331.346182 -285.80201)
		(end 331.162406 -285.75127)
		(width 0.09525)
		(layer "In13.Cu")
		(net "M_B_CPU0_SB_DQS_DP<2>")
	)
	(arc
		(start 335.299558 -285.75127)
		(mid 335.11109 -285.801947)
		(end 334.922622 -285.75127)
		(width 0.09525)
		(layer "In13.Cu")
		(net "M_B_CPU0_SB_DQS_DP<2>")
	)
	(arc
		(start 332.471268 -285.756096)
		(mid 332.286236 -285.80201)
		(end 332.10246 -285.75127)
		(width 0.09525)
		(layer "In13.Cu")
		(net "M_B_CPU0_SB_DQS_DP<2>")
	)
	(arc
		(start 328.332084 -285.745174)
		(mid 328.054922 -285.675374)
		(end 327.77938 -285.75127)
		(width 0.09525)
		(layer "In13.Cu")
		(net "M_B_CPU0_SB_DQS_DP<2>")
	)
	(arc
		(start 328.711306 -285.756096)
		(mid 328.526274 -285.80201)
		(end 328.342498 -285.75127)
		(width 0.09525)
		(layer "In13.Cu")
		(net "M_B_CPU0_SB_DQS_DP<2>")
	)
	(arc
		(start 334.922622 -285.75127)
		(mid 334.64119 -285.675515)
		(end 334.359758 -285.75127)
		(width 0.09525)
		(layer "In13.Cu")
		(net "M_B_CPU0_SB_DQS_DP<2>")
	)
	(arc
		(start 329.659742 -285.75127)
		(mid 329.475967 -285.802042)
		(end 329.290934 -285.756096)
		(width 0.09525)
		(layer "In13.Cu")
		(net "M_B_CPU0_SB_DQS_DP<2>")
	)
	(arc
		(start 333.419704 -285.75127)
		(mid 333.235929 -285.802042)
		(end 333.050896 -285.756096)
		(width 0.09525)
		(layer "In13.Cu")
		(net "M_B_CPU0_SB_DQS_DP<2>")
	)
	(arc
		(start 333.982568 -285.75127)
		(mid 333.701136 -285.675515)
		(end 333.419704 -285.75127)
		(width 0.09525)
		(layer "In13.Cu")
		(net "M_B_CPU0_SB_DQS_DP<2>")
	)
	(arc
		(start 327.397872 -285.757366)
		(mid 327.152477 -285.681558)
		(end 326.898762 -285.721552)
		(width 0.09525)
		(layer "In13.Cu")
		(net "M_B_CPU0_SB_DQS_DP<2>")
	)
	(arc
		(start 331.162406 -285.75127)
		(mid 330.880974 -285.675515)
		(end 330.599542 -285.75127)
		(width 0.09525)
		(layer "In13.Cu")
		(net "M_B_CPU0_SB_DQS_DP<2>")
	)
	(arc
		(start 333.042514 -285.75127)
		(mid 332.761082 -285.675515)
		(end 332.47965 -285.75127)
		(width 0.09525)
		(layer "In13.Cu")
		(net "M_B_CPU0_SB_DQS_DP<2>")
	)
	(arc
		(start 334.359758 -285.75127)
		(mid 334.175983 -285.802042)
		(end 333.99095 -285.756096)
		(width 0.09525)
		(layer "In13.Cu")
		(net "M_B_CPU0_SB_DQS_DP<2>")
	)
	(arc
		(start 335.775808 -285.710122)
		(mid 335.533066 -285.677352)
		(end 335.299558 -285.75127)
		(width 0.09525)
		(layer "In13.Cu")
		(net "M_B_CPU0_SB_DQS_DP<2>")
	)
	(arc
		(start 329.282552 -285.75127)
		(mid 329.00112 -285.675515)
		(end 328.719688 -285.75127)
		(width 0.09525)
		(layer "In13.Cu")
		(net "M_B_CPU0_SB_DQS_DP<2>")
	)
	(arc
		(start 330.222606 -285.75127)
		(mid 329.941174 -285.675515)
		(end 329.659742 -285.75127)
		(width 0.09525)
		(layer "In13.Cu")
		(net "M_B_CPU0_SB_DQS_DP<2>")
	)
	(arc
		(start 332.10246 -285.75127)
		(mid 331.821028 -285.675515)
		(end 331.539596 -285.75127)
		(width 0.09525)
		(layer "In13.Cu")
		(net "M_B_CPU0_SB_DQS_DP<2>")
	)
	(arc
		(start 335.796382 -285.71825)
		(mid 335.786134 -285.714087)
		(end 335.775808 -285.710122)
		(width 0.09525)
		(layer "In13.Cu")
		(net "M_B_CPU0_SB_DQS_DP<2>")
	)
	(arc
		(start 330.599542 -285.75127)
		(mid 330.411074 -285.801947)
		(end 330.222606 -285.75127)
		(width 0.09525)
		(layer "In13.Cu")
		(net "M_B_CPU0_SB_DQS_DP<2>")
	)
	(segment
		(start 336.517996 -280.300176)
		(end 336.051144 -280.566114)
		(width 0.12954)
		(layer "F.Cu")
		(net "M_B_CPU0_SB_DQS_DP<1>")
	)
	(segment
		(start 321.593972 -280.779982)
		(end 320.76009 -281.613864)
		(width 0.16002)
		(layer "In13.Cu")
		(net "M_B_CPU0_SB_DQS_DP<1>")
	)
	(segment
		(start 324.071742 -280.779982)
		(end 321.593972 -280.779982)
		(width 0.16002)
		(layer "In13.Cu")
		(net "M_B_CPU0_SB_DQS_DP<1>")
	)
	(segment
		(start 326.84974 -280.885138)
		(end 326.839326 -280.891234)
		(width 0.09525)
		(layer "In13.Cu")
		(net "M_B_CPU0_SB_DQS_DP<1>")
	)
	(segment
		(start 324.095364 -280.779982)
		(end 324.071742 -280.779982)
		(width 0.09525)
		(layer "In13.Cu")
		(net "M_B_CPU0_SB_DQS_DP<1>")
	)
	(segment
		(start 313.908694 -287.302956)
		(end 313.908694 -287.83026)
		(width 0.16002)
		(layer "In13.Cu")
		(net "M_B_CPU0_SB_DQS_DP<1>")
	)
	(segment
		(start 316.655958 -285.082996)
		(end 316.835028 -285.262066)
		(width 0.16002)
		(layer "In13.Cu")
		(net "M_B_CPU0_SB_DQS_DP<1>")
	)
	(segment
		(start 316.835028 -285.538926)
		(end 316.639194 -285.73476)
		(width 0.16002)
		(layer "In13.Cu")
		(net "M_B_CPU0_SB_DQS_DP<1>")
	)
	(segment
		(start 336.051144 -280.566114)
		(end 335.89722 -280.831544)
		(width 0.09525)
		(layer "In13.Cu")
		(net "M_B_CPU0_SB_DQS_DP<1>")
	)
	(segment
		(start 320.48323 -281.613864)
		(end 320.30416 -281.434794)
		(width 0.16002)
		(layer "In13.Cu")
		(net "M_B_CPU0_SB_DQS_DP<1>")
	)
	(segment
		(start 315.65596 -285.55569)
		(end 315.282326 -285.929324)
		(width 0.16002)
		(layer "In13.Cu")
		(net "M_B_CPU0_SB_DQS_DP<1>")
	)
	(segment
		(start 302.038004 -294.502078)
		(end 300.091094 -294.502078)
		(width 0.16002)
		(layer "In13.Cu")
		(net "M_B_CPU0_SB_DQS_DP<1>")
	)
	(segment
		(start 325.055992 -280.535634)
		(end 324.722236 -280.535634)
		(width 0.09525)
		(layer "In13.Cu")
		(net "M_B_CPU0_SB_DQS_DP<1>")
	)
	(segment
		(start 315.461396 -286.912558)
		(end 315.265562 -287.108392)
		(width 0.16002)
		(layer "In13.Cu")
		(net "M_B_CPU0_SB_DQS_DP<1>")
	)
	(segment
		(start 319.386458 -282.987496)
		(end 319.109598 -282.987496)
		(width 0.16002)
		(layer "In13.Cu")
		(net "M_B_CPU0_SB_DQS_DP<1>")
	)
	(segment
		(start 326.839326 -280.891234)
		(end 326.826372 -280.8986)
		(width 0.09525)
		(layer "In13.Cu")
		(net "M_B_CPU0_SB_DQS_DP<1>")
	)
	(segment
		(start 316.362334 -285.73476)
		(end 316.183264 -285.55569)
		(width 0.16002)
		(layer "In13.Cu")
		(net "M_B_CPU0_SB_DQS_DP<1>")
	)
	(segment
		(start 331.539596 -280.891234)
		(end 331.531214 -280.89606)
		(width 0.09525)
		(layer "In13.Cu")
		(net "M_B_CPU0_SB_DQS_DP<1>")
	)
	(segment
		(start 315.282326 -285.929324)
		(end 315.282326 -286.456628)
		(width 0.16002)
		(layer "In13.Cu")
		(net "M_B_CPU0_SB_DQS_DP<1>")
	)
	(segment
		(start 314.988702 -287.108392)
		(end 314.809632 -286.929322)
		(width 0.16002)
		(layer "In13.Cu")
		(net "M_B_CPU0_SB_DQS_DP<1>")
	)
	(segment
		(start 314.809632 -286.929322)
		(end 314.282328 -286.929322)
		(width 0.16002)
		(layer "In13.Cu")
		(net "M_B_CPU0_SB_DQS_DP<1>")
	)
	(segment
		(start 326.384412 -280.870406)
		(end 325.19747 -280.554176)
		(width 0.09525)
		(layer "In13.Cu")
		(net "M_B_CPU0_SB_DQS_DP<1>")
	)
	(segment
		(start 317.556896 -284.182058)
		(end 317.029592 -284.182058)
		(width 0.16002)
		(layer "In13.Cu")
		(net "M_B_CPU0_SB_DQS_DP<1>")
	)
	(segment
		(start 328.342498 -280.891234)
		(end 328.332084 -280.885138)
		(width 0.09525)
		(layer "In13.Cu")
		(net "M_B_CPU0_SB_DQS_DP<1>")
	)
	(segment
		(start 329.290934 -280.89606)
		(end 329.282552 -280.891234)
		(width 0.09525)
		(layer "In13.Cu")
		(net "M_B_CPU0_SB_DQS_DP<1>")
	)
	(segment
		(start 320.76009 -281.613864)
		(end 320.48323 -281.613864)
		(width 0.16002)
		(layer "In13.Cu")
		(net "M_B_CPU0_SB_DQS_DP<1>")
	)
	(segment
		(start 316.655958 -284.555692)
		(end 316.655958 -285.082996)
		(width 0.16002)
		(layer "In13.Cu")
		(net "M_B_CPU0_SB_DQS_DP<1>")
	)
	(segment
		(start 318.403224 -282.808426)
		(end 318.02959 -283.18206)
		(width 0.16002)
		(layer "In13.Cu")
		(net "M_B_CPU0_SB_DQS_DP<1>")
	)
	(segment
		(start 318.930528 -282.808426)
		(end 318.403224 -282.808426)
		(width 0.16002)
		(layer "In13.Cu")
		(net "M_B_CPU0_SB_DQS_DP<1>")
	)
	(segment
		(start 324.722236 -280.535634)
		(end 324.418706 -280.839164)
		(width 0.09525)
		(layer "In13.Cu")
		(net "M_B_CPU0_SB_DQS_DP<1>")
	)
	(segment
		(start 300.091094 -294.502078)
		(end 299.82414 -294.235124)
		(width 0.16002)
		(layer "In13.Cu")
		(net "M_B_CPU0_SB_DQS_DP<1>")
	)
	(segment
		(start 313.908694 -287.83026)
		(end 314.087764 -288.00933)
		(width 0.16002)
		(layer "In13.Cu")
		(net "M_B_CPU0_SB_DQS_DP<1>")
	)
	(segment
		(start 314.087764 -288.00933)
		(end 314.087764 -288.28619)
		(width 0.16002)
		(layer "In13.Cu")
		(net "M_B_CPU0_SB_DQS_DP<1>")
	)
	(segment
		(start 320.30416 -281.434794)
		(end 319.776856 -281.434794)
		(width 0.16002)
		(layer "In13.Cu")
		(net "M_B_CPU0_SB_DQS_DP<1>")
	)
	(segment
		(start 318.20866 -284.165294)
		(end 318.012826 -284.361128)
		(width 0.16002)
		(layer "In13.Cu")
		(net "M_B_CPU0_SB_DQS_DP<1>")
	)
	(segment
		(start 319.776856 -281.434794)
		(end 319.403222 -281.808428)
		(width 0.16002)
		(layer "In13.Cu")
		(net "M_B_CPU0_SB_DQS_DP<1>")
	)
	(segment
		(start 328.719688 -280.891234)
		(end 328.711306 -280.89606)
		(width 0.09525)
		(layer "In13.Cu")
		(net "M_B_CPU0_SB_DQS_DP<1>")
	)
	(segment
		(start 317.029592 -284.182058)
		(end 316.655958 -284.555692)
		(width 0.16002)
		(layer "In13.Cu")
		(net "M_B_CPU0_SB_DQS_DP<1>")
	)
	(segment
		(start 305.689254 -293.821104)
		(end 304.825654 -294.684704)
		(width 0.16002)
		(layer "In13.Cu")
		(net "M_B_CPU0_SB_DQS_DP<1>")
	)
	(segment
		(start 318.012826 -284.361128)
		(end 317.735966 -284.361128)
		(width 0.16002)
		(layer "In13.Cu")
		(net "M_B_CPU0_SB_DQS_DP<1>")
	)
	(segment
		(start 326.826372 -280.8986)
		(end 326.824848 -280.899616)
		(width 0.09525)
		(layer "In13.Cu")
		(net "M_B_CPU0_SB_DQS_DP<1>")
	)
	(segment
		(start 316.183264 -285.55569)
		(end 315.65596 -285.55569)
		(width 0.16002)
		(layer "In13.Cu")
		(net "M_B_CPU0_SB_DQS_DP<1>")
	)
	(segment
		(start 319.582292 -282.791662)
		(end 319.386458 -282.987496)
		(width 0.16002)
		(layer "In13.Cu")
		(net "M_B_CPU0_SB_DQS_DP<1>")
	)
	(segment
		(start 314.087764 -288.28619)
		(end 308.55285 -293.821104)
		(width 0.16002)
		(layer "In13.Cu")
		(net "M_B_CPU0_SB_DQS_DP<1>")
	)
	(segment
		(start 314.282328 -286.929322)
		(end 313.908694 -287.302956)
		(width 0.16002)
		(layer "In13.Cu")
		(net "M_B_CPU0_SB_DQS_DP<1>")
	)
	(segment
		(start 333.99095 -280.89606)
		(end 333.982568 -280.891234)
		(width 0.09525)
		(layer "In13.Cu")
		(net "M_B_CPU0_SB_DQS_DP<1>")
	)
	(segment
		(start 304.825654 -294.684704)
		(end 302.22063 -294.684704)
		(width 0.16002)
		(layer "In13.Cu")
		(net "M_B_CPU0_SB_DQS_DP<1>")
	)
	(segment
		(start 324.418706 -280.839164)
		(end 324.154546 -280.839164)
		(width 0.09525)
		(layer "In13.Cu")
		(net "M_B_CPU0_SB_DQS_DP<1>")
	)
	(segment
		(start 302.22063 -294.684704)
		(end 302.038004 -294.502078)
		(width 0.16002)
		(layer "In13.Cu")
		(net "M_B_CPU0_SB_DQS_DP<1>")
	)
	(segment
		(start 319.403222 -282.335732)
		(end 319.582292 -282.514802)
		(width 0.16002)
		(layer "In13.Cu")
		(net "M_B_CPU0_SB_DQS_DP<1>")
	)
	(segment
		(start 319.109598 -282.987496)
		(end 318.930528 -282.808426)
		(width 0.16002)
		(layer "In13.Cu")
		(net "M_B_CPU0_SB_DQS_DP<1>")
	)
	(segment
		(start 318.02959 -283.709364)
		(end 318.20866 -283.888434)
		(width 0.16002)
		(layer "In13.Cu")
		(net "M_B_CPU0_SB_DQS_DP<1>")
	)
	(segment
		(start 335.89722 -280.831544)
		(end 335.796382 -280.858214)
		(width 0.09525)
		(layer "In13.Cu")
		(net "M_B_CPU0_SB_DQS_DP<1>")
	)
	(segment
		(start 318.20866 -283.888434)
		(end 318.20866 -284.165294)
		(width 0.16002)
		(layer "In13.Cu")
		(net "M_B_CPU0_SB_DQS_DP<1>")
	)
	(segment
		(start 315.461396 -286.635698)
		(end 315.461396 -286.912558)
		(width 0.16002)
		(layer "In13.Cu")
		(net "M_B_CPU0_SB_DQS_DP<1>")
	)
	(segment
		(start 324.154546 -280.839164)
		(end 324.095364 -280.779982)
		(width 0.09525)
		(layer "In13.Cu")
		(net "M_B_CPU0_SB_DQS_DP<1>")
	)
	(segment
		(start 316.639194 -285.73476)
		(end 316.362334 -285.73476)
		(width 0.16002)
		(layer "In13.Cu")
		(net "M_B_CPU0_SB_DQS_DP<1>")
	)
	(segment
		(start 326.824848 -280.899616)
		(end 326.825102 -280.900124)
		(width 0.09525)
		(layer "In13.Cu")
		(net "M_B_CPU0_SB_DQS_DP<1>")
	)
	(segment
		(start 315.265562 -287.108392)
		(end 314.988702 -287.108392)
		(width 0.16002)
		(layer "In13.Cu")
		(net "M_B_CPU0_SB_DQS_DP<1>")
	)
	(segment
		(start 332.47965 -280.891234)
		(end 332.471268 -280.89606)
		(width 0.09525)
		(layer "In13.Cu")
		(net "M_B_CPU0_SB_DQS_DP<1>")
	)
	(segment
		(start 319.582292 -282.514802)
		(end 319.582292 -282.791662)
		(width 0.16002)
		(layer "In13.Cu")
		(net "M_B_CPU0_SB_DQS_DP<1>")
	)
	(segment
		(start 333.050896 -280.89606)
		(end 333.042514 -280.891234)
		(width 0.09525)
		(layer "In13.Cu")
		(net "M_B_CPU0_SB_DQS_DP<1>")
	)
	(segment
		(start 316.835028 -285.262066)
		(end 316.835028 -285.538926)
		(width 0.16002)
		(layer "In13.Cu")
		(net "M_B_CPU0_SB_DQS_DP<1>")
	)
	(segment
		(start 315.282326 -286.456628)
		(end 315.461396 -286.635698)
		(width 0.16002)
		(layer "In13.Cu")
		(net "M_B_CPU0_SB_DQS_DP<1>")
	)
	(segment
		(start 308.55285 -293.821104)
		(end 305.689254 -293.821104)
		(width 0.16002)
		(layer "In13.Cu")
		(net "M_B_CPU0_SB_DQS_DP<1>")
	)
	(segment
		(start 319.403222 -281.808428)
		(end 319.403222 -282.335732)
		(width 0.16002)
		(layer "In13.Cu")
		(net "M_B_CPU0_SB_DQS_DP<1>")
	)
	(segment
		(start 317.735966 -284.361128)
		(end 317.556896 -284.182058)
		(width 0.16002)
		(layer "In13.Cu")
		(net "M_B_CPU0_SB_DQS_DP<1>")
	)
	(segment
		(start 318.02959 -283.18206)
		(end 318.02959 -283.709364)
		(width 0.16002)
		(layer "In13.Cu")
		(net "M_B_CPU0_SB_DQS_DP<1>")
	)
	(arc
		(start 326.500236 -280.9113)
		(mid 326.443094 -280.888672)
		(end 326.384412 -280.870406)
		(width 0.09525)
		(layer "In13.Cu")
		(net "M_B_CPU0_SB_DQS_DP<1>")
	)
	(arc
		(start 328.332084 -280.885138)
		(mid 328.054922 -280.815338)
		(end 327.77938 -280.891234)
		(width 0.09525)
		(layer "In13.Cu")
		(net "M_B_CPU0_SB_DQS_DP<1>")
	)
	(arc
		(start 327.401936 -280.891234)
		(mid 327.126647 -280.815513)
		(end 326.84974 -280.885138)
		(width 0.09525)
		(layer "In13.Cu")
		(net "M_B_CPU0_SB_DQS_DP<1>")
	)
	(arc
		(start 333.042514 -280.891234)
		(mid 332.761082 -280.815479)
		(end 332.47965 -280.891234)
		(width 0.09525)
		(layer "In13.Cu")
		(net "M_B_CPU0_SB_DQS_DP<1>")
	)
	(arc
		(start 325.19747 -280.554176)
		(mid 325.127335 -280.540305)
		(end 325.055992 -280.535634)
		(width 0.09525)
		(layer "In13.Cu")
		(net "M_B_CPU0_SB_DQS_DP<1>")
	)
	(arc
		(start 332.10246 -280.891234)
		(mid 331.821028 -280.815479)
		(end 331.539596 -280.891234)
		(width 0.09525)
		(layer "In13.Cu")
		(net "M_B_CPU0_SB_DQS_DP<1>")
	)
	(arc
		(start 328.711306 -280.89606)
		(mid 328.526274 -280.941974)
		(end 328.342498 -280.891234)
		(width 0.09525)
		(layer "In13.Cu")
		(net "M_B_CPU0_SB_DQS_DP<1>")
	)
	(arc
		(start 331.162406 -280.891234)
		(mid 330.880974 -280.815479)
		(end 330.599542 -280.891234)
		(width 0.09525)
		(layer "In13.Cu")
		(net "M_B_CPU0_SB_DQS_DP<1>")
	)
	(arc
		(start 333.419704 -280.891234)
		(mid 333.235929 -280.942006)
		(end 333.050896 -280.89606)
		(width 0.09525)
		(layer "In13.Cu")
		(net "M_B_CPU0_SB_DQS_DP<1>")
	)
	(arc
		(start 332.471268 -280.89606)
		(mid 332.286236 -280.941974)
		(end 332.10246 -280.891234)
		(width 0.09525)
		(layer "In13.Cu")
		(net "M_B_CPU0_SB_DQS_DP<1>")
	)
	(arc
		(start 327.77938 -280.891234)
		(mid 327.590658 -280.942038)
		(end 327.401936 -280.891234)
		(width 0.09525)
		(layer "In13.Cu")
		(net "M_B_CPU0_SB_DQS_DP<1>")
	)
	(arc
		(start 334.922622 -280.891234)
		(mid 334.64119 -280.815479)
		(end 334.359758 -280.891234)
		(width 0.09525)
		(layer "In13.Cu")
		(net "M_B_CPU0_SB_DQS_DP<1>")
	)
	(arc
		(start 335.796382 -280.858214)
		(mid 335.786134 -280.854051)
		(end 335.775808 -280.850086)
		(width 0.09525)
		(layer "In13.Cu")
		(net "M_B_CPU0_SB_DQS_DP<1>")
	)
	(arc
		(start 329.659742 -280.891234)
		(mid 329.475967 -280.942006)
		(end 329.290934 -280.89606)
		(width 0.09525)
		(layer "In13.Cu")
		(net "M_B_CPU0_SB_DQS_DP<1>")
	)
	(arc
		(start 333.982568 -280.891234)
		(mid 333.701136 -280.815479)
		(end 333.419704 -280.891234)
		(width 0.09525)
		(layer "In13.Cu")
		(net "M_B_CPU0_SB_DQS_DP<1>")
	)
	(arc
		(start 331.531214 -280.89606)
		(mid 331.346182 -280.941974)
		(end 331.162406 -280.891234)
		(width 0.09525)
		(layer "In13.Cu")
		(net "M_B_CPU0_SB_DQS_DP<1>")
	)
	(arc
		(start 330.599542 -280.891234)
		(mid 330.411074 -280.941911)
		(end 330.222606 -280.891234)
		(width 0.09525)
		(layer "In13.Cu")
		(net "M_B_CPU0_SB_DQS_DP<1>")
	)
	(arc
		(start 335.775808 -280.850086)
		(mid 335.533066 -280.817316)
		(end 335.299558 -280.891234)
		(width 0.09525)
		(layer "In13.Cu")
		(net "M_B_CPU0_SB_DQS_DP<1>")
	)
	(arc
		(start 334.359758 -280.891234)
		(mid 334.175983 -280.942006)
		(end 333.99095 -280.89606)
		(width 0.09525)
		(layer "In13.Cu")
		(net "M_B_CPU0_SB_DQS_DP<1>")
	)
	(arc
		(start 326.825102 -280.900124)
		(mid 326.663947 -280.942505)
		(end 326.500236 -280.9113)
		(width 0.09525)
		(layer "In13.Cu")
		(net "M_B_CPU0_SB_DQS_DP<1>")
	)
	(arc
		(start 330.222606 -280.891234)
		(mid 329.941174 -280.815479)
		(end 329.659742 -280.891234)
		(width 0.09525)
		(layer "In13.Cu")
		(net "M_B_CPU0_SB_DQS_DP<1>")
	)
	(arc
		(start 335.299558 -280.891234)
		(mid 335.11109 -280.941911)
		(end 334.922622 -280.891234)
		(width 0.09525)
		(layer "In13.Cu")
		(net "M_B_CPU0_SB_DQS_DP<1>")
	)
	(arc
		(start 329.282552 -280.891234)
		(mid 329.00112 -280.815479)
		(end 328.719688 -280.891234)
		(width 0.09525)
		(layer "In13.Cu")
		(net "M_B_CPU0_SB_DQS_DP<1>")
	)
	(segment
		(start 336.517996 -275.44014)
		(end 336.051144 -275.706078)
		(width 0.12954)
		(layer "F.Cu")
		(net "M_B_CPU0_SB_DQS_DP<0>")
	)
	(segment
		(start 311.900824 -280.293064)
		(end 312.038238 -280.430478)
		(width 0.16002)
		(layer "In13.Cu")
		(net "M_B_CPU0_SB_DQS_DP<0>")
	)
	(segment
		(start 313.411108 -279.057608)
		(end 313.411108 -279.283668)
		(width 0.16002)
		(layer "In13.Cu")
		(net "M_B_CPU0_SB_DQS_DP<0>")
	)
	(segment
		(start 312.800746 -279.393142)
		(end 312.324242 -279.393142)
		(width 0.16002)
		(layer "In13.Cu")
		(net "M_B_CPU0_SB_DQS_DP<0>")
	)
	(segment
		(start 310.665368 -281.803348)
		(end 310.665368 -282.029408)
		(width 0.16002)
		(layer "In13.Cu")
		(net "M_B_CPU0_SB_DQS_DP<0>")
	)
	(segment
		(start 315.90996 -276.784816)
		(end 315.6839 -276.784816)
		(width 0.16002)
		(layer "In13.Cu")
		(net "M_B_CPU0_SB_DQS_DP<0>")
	)
	(segment
		(start 311.427876 -280.766012)
		(end 310.951372 -280.766012)
		(width 0.16002)
		(layer "In13.Cu")
		(net "M_B_CPU0_SB_DQS_DP<0>")
	)
	(segment
		(start 311.900824 -279.81656)
		(end 311.900824 -280.293064)
		(width 0.16002)
		(layer "In13.Cu")
		(net "M_B_CPU0_SB_DQS_DP<0>")
	)
	(segment
		(start 311.79135 -280.903426)
		(end 311.56529 -280.903426)
		(width 0.16002)
		(layer "In13.Cu")
		(net "M_B_CPU0_SB_DQS_DP<0>")
	)
	(segment
		(start 309.578502 -282.138882)
		(end 309.155084 -282.5623)
		(width 0.16002)
		(layer "In13.Cu")
		(net "M_B_CPU0_SB_DQS_DP<0>")
	)
	(segment
		(start 312.324242 -279.393142)
		(end 311.900824 -279.81656)
		(width 0.16002)
		(layer "In13.Cu")
		(net "M_B_CPU0_SB_DQS_DP<0>")
	)
	(segment
		(start 300.067726 -285.128716)
		(end 299.82414 -284.88513)
		(width 0.16002)
		(layer "In13.Cu")
		(net "M_B_CPU0_SB_DQS_DP<0>")
	)
	(segment
		(start 323.919596 -275.15693)
		(end 323.895974 -275.15693)
		(width 0.09525)
		(layer "In13.Cu")
		(net "M_B_CPU0_SB_DQS_DP<0>")
	)
	(segment
		(start 313.697112 -278.020272)
		(end 313.273694 -278.44369)
		(width 0.16002)
		(layer "In13.Cu")
		(net "M_B_CPU0_SB_DQS_DP<0>")
	)
	(segment
		(start 314.31103 -278.157686)
		(end 314.173616 -278.020272)
		(width 0.16002)
		(layer "In13.Cu")
		(net "M_B_CPU0_SB_DQS_DP<0>")
	)
	(segment
		(start 310.055006 -282.138882)
		(end 309.578502 -282.138882)
		(width 0.16002)
		(layer "In13.Cu")
		(net "M_B_CPU0_SB_DQS_DP<0>")
	)
	(segment
		(start 313.411108 -279.283668)
		(end 313.16422 -279.530556)
		(width 0.16002)
		(layer "In13.Cu")
		(net "M_B_CPU0_SB_DQS_DP<0>")
	)
	(segment
		(start 336.051144 -275.706078)
		(end 335.89722 -275.971508)
		(width 0.09525)
		(layer "In13.Cu")
		(net "M_B_CPU0_SB_DQS_DP<0>")
	)
	(segment
		(start 316.560454 -275.15693)
		(end 316.019434 -275.69795)
		(width 0.16002)
		(layer "In13.Cu")
		(net "M_B_CPU0_SB_DQS_DP<0>")
	)
	(segment
		(start 312.038238 -280.430478)
		(end 312.038238 -280.656538)
		(width 0.16002)
		(layer "In13.Cu")
		(net "M_B_CPU0_SB_DQS_DP<0>")
	)
	(segment
		(start 314.646564 -277.547324)
		(end 314.783978 -277.684738)
		(width 0.16002)
		(layer "In13.Cu")
		(net "M_B_CPU0_SB_DQS_DP<0>")
	)
	(segment
		(start 310.41848 -282.276296)
		(end 310.19242 -282.276296)
		(width 0.16002)
		(layer "In13.Cu")
		(net "M_B_CPU0_SB_DQS_DP<0>")
	)
	(segment
		(start 312.038238 -280.656538)
		(end 311.79135 -280.903426)
		(width 0.16002)
		(layer "In13.Cu")
		(net "M_B_CPU0_SB_DQS_DP<0>")
	)
	(segment
		(start 315.6839 -276.784816)
		(end 315.546486 -276.647402)
		(width 0.16002)
		(layer "In13.Cu")
		(net "M_B_CPU0_SB_DQS_DP<0>")
	)
	(segment
		(start 323.895974 -275.15693)
		(end 316.560454 -275.15693)
		(width 0.16002)
		(layer "In13.Cu")
		(net "M_B_CPU0_SB_DQS_DP<0>")
	)
	(segment
		(start 332.47965 -276.031198)
		(end 332.471268 -276.036024)
		(width 0.09525)
		(layer "In13.Cu")
		(net "M_B_CPU0_SB_DQS_DP<0>")
	)
	(segment
		(start 303.245266 -285.128716)
		(end 300.067726 -285.128716)
		(width 0.16002)
		(layer "In13.Cu")
		(net "M_B_CPU0_SB_DQS_DP<0>")
	)
	(segment
		(start 333.99095 -276.036024)
		(end 333.982568 -276.031198)
		(width 0.09525)
		(layer "In13.Cu")
		(net "M_B_CPU0_SB_DQS_DP<0>")
	)
	(segment
		(start 308.81955 -283.649166)
		(end 308.682136 -283.511752)
		(width 0.16002)
		(layer "In13.Cu")
		(net "M_B_CPU0_SB_DQS_DP<0>")
	)
	(segment
		(start 323.978778 -275.216112)
		(end 323.919596 -275.15693)
		(width 0.09525)
		(layer "In13.Cu")
		(net "M_B_CPU0_SB_DQS_DP<0>")
	)
	(segment
		(start 312.93816 -279.530556)
		(end 312.800746 -279.393142)
		(width 0.16002)
		(layer "In13.Cu")
		(net "M_B_CPU0_SB_DQS_DP<0>")
	)
	(segment
		(start 313.273694 -278.920194)
		(end 313.411108 -279.057608)
		(width 0.16002)
		(layer "In13.Cu")
		(net "M_B_CPU0_SB_DQS_DP<0>")
	)
	(segment
		(start 308.205632 -283.511752)
		(end 307.157374 -284.56001)
		(width 0.16002)
		(layer "In13.Cu")
		(net "M_B_CPU0_SB_DQS_DP<0>")
	)
	(segment
		(start 328.72553 -276.024594)
		(end 328.724006 -276.025102)
		(width 0.09525)
		(layer "In13.Cu")
		(net "M_B_CPU0_SB_DQS_DP<0>")
	)
	(segment
		(start 315.069982 -276.647402)
		(end 314.646564 -277.07082)
		(width 0.16002)
		(layer "In13.Cu")
		(net "M_B_CPU0_SB_DQS_DP<0>")
	)
	(segment
		(start 309.292498 -283.176218)
		(end 309.292498 -283.402278)
		(width 0.16002)
		(layer "In13.Cu")
		(net "M_B_CPU0_SB_DQS_DP<0>")
	)
	(segment
		(start 313.16422 -279.530556)
		(end 312.93816 -279.530556)
		(width 0.16002)
		(layer "In13.Cu")
		(net "M_B_CPU0_SB_DQS_DP<0>")
	)
	(segment
		(start 329.312524 -276.047454)
		(end 329.310746 -276.046438)
		(width 0.09525)
		(layer "In13.Cu")
		(net "M_B_CPU0_SB_DQS_DP<0>")
	)
	(segment
		(start 305.600354 -284.56001)
		(end 304.431954 -285.72841)
		(width 0.16002)
		(layer "In13.Cu")
		(net "M_B_CPU0_SB_DQS_DP<0>")
	)
	(segment
		(start 316.019434 -275.69795)
		(end 316.019434 -276.174454)
		(width 0.16002)
		(layer "In13.Cu")
		(net "M_B_CPU0_SB_DQS_DP<0>")
	)
	(segment
		(start 309.155084 -282.5623)
		(end 309.155084 -283.038804)
		(width 0.16002)
		(layer "In13.Cu")
		(net "M_B_CPU0_SB_DQS_DP<0>")
	)
	(segment
		(start 333.050896 -276.036024)
		(end 333.042514 -276.031198)
		(width 0.09525)
		(layer "In13.Cu")
		(net "M_B_CPU0_SB_DQS_DP<0>")
	)
	(segment
		(start 309.04561 -283.649166)
		(end 308.81955 -283.649166)
		(width 0.16002)
		(layer "In13.Cu")
		(net "M_B_CPU0_SB_DQS_DP<0>")
	)
	(segment
		(start 304.431954 -285.72841)
		(end 303.84496 -285.72841)
		(width 0.16002)
		(layer "In13.Cu")
		(net "M_B_CPU0_SB_DQS_DP<0>")
	)
	(segment
		(start 310.951372 -280.766012)
		(end 310.527954 -281.18943)
		(width 0.16002)
		(layer "In13.Cu")
		(net "M_B_CPU0_SB_DQS_DP<0>")
	)
	(segment
		(start 316.156848 -276.311868)
		(end 316.156848 -276.537928)
		(width 0.16002)
		(layer "In13.Cu")
		(net "M_B_CPU0_SB_DQS_DP<0>")
	)
	(segment
		(start 316.019434 -276.174454)
		(end 316.156848 -276.311868)
		(width 0.16002)
		(layer "In13.Cu")
		(net "M_B_CPU0_SB_DQS_DP<0>")
	)
	(segment
		(start 316.156848 -276.537928)
		(end 315.90996 -276.784816)
		(width 0.16002)
		(layer "In13.Cu")
		(net "M_B_CPU0_SB_DQS_DP<0>")
	)
	(segment
		(start 315.546486 -276.647402)
		(end 315.069982 -276.647402)
		(width 0.16002)
		(layer "In13.Cu")
		(net "M_B_CPU0_SB_DQS_DP<0>")
	)
	(segment
		(start 314.53709 -278.157686)
		(end 314.31103 -278.157686)
		(width 0.16002)
		(layer "In13.Cu")
		(net "M_B_CPU0_SB_DQS_DP<0>")
	)
	(segment
		(start 310.19242 -282.276296)
		(end 310.055006 -282.138882)
		(width 0.16002)
		(layer "In13.Cu")
		(net "M_B_CPU0_SB_DQS_DP<0>")
	)
	(segment
		(start 327.504552 -276.08276)
		(end 326.076056 -276.08276)
		(width 0.09525)
		(layer "In13.Cu")
		(net "M_B_CPU0_SB_DQS_DP<0>")
	)
	(segment
		(start 329.313794 -276.047962)
		(end 329.312524 -276.047454)
		(width 0.09525)
		(layer "In13.Cu")
		(net "M_B_CPU0_SB_DQS_DP<0>")
	)
	(segment
		(start 314.173616 -278.020272)
		(end 313.697112 -278.020272)
		(width 0.16002)
		(layer "In13.Cu")
		(net "M_B_CPU0_SB_DQS_DP<0>")
	)
	(segment
		(start 310.665368 -282.029408)
		(end 310.41848 -282.276296)
		(width 0.16002)
		(layer "In13.Cu")
		(net "M_B_CPU0_SB_DQS_DP<0>")
	)
	(segment
		(start 314.783978 -277.684738)
		(end 314.783978 -277.910798)
		(width 0.16002)
		(layer "In13.Cu")
		(net "M_B_CPU0_SB_DQS_DP<0>")
	)
	(segment
		(start 309.155084 -283.038804)
		(end 309.292498 -283.176218)
		(width 0.16002)
		(layer "In13.Cu")
		(net "M_B_CPU0_SB_DQS_DP<0>")
	)
	(segment
		(start 311.56529 -280.903426)
		(end 311.427876 -280.766012)
		(width 0.16002)
		(layer "In13.Cu")
		(net "M_B_CPU0_SB_DQS_DP<0>")
	)
	(segment
		(start 308.682136 -283.511752)
		(end 308.205632 -283.511752)
		(width 0.16002)
		(layer "In13.Cu")
		(net "M_B_CPU0_SB_DQS_DP<0>")
	)
	(segment
		(start 313.273694 -278.44369)
		(end 313.273694 -278.920194)
		(width 0.16002)
		(layer "In13.Cu")
		(net "M_B_CPU0_SB_DQS_DP<0>")
	)
	(segment
		(start 314.783978 -277.910798)
		(end 314.53709 -278.157686)
		(width 0.16002)
		(layer "In13.Cu")
		(net "M_B_CPU0_SB_DQS_DP<0>")
	)
	(segment
		(start 310.527954 -281.18943)
		(end 310.527954 -281.665934)
		(width 0.16002)
		(layer "In13.Cu")
		(net "M_B_CPU0_SB_DQS_DP<0>")
	)
	(segment
		(start 307.157374 -284.56001)
		(end 305.600354 -284.56001)
		(width 0.16002)
		(layer "In13.Cu")
		(net "M_B_CPU0_SB_DQS_DP<0>")
	)
	(segment
		(start 326.076056 -276.08276)
		(end 325.209408 -275.216112)
		(width 0.09525)
		(layer "In13.Cu")
		(net "M_B_CPU0_SB_DQS_DP<0>")
	)
	(segment
		(start 335.89722 -275.971508)
		(end 335.796382 -275.998178)
		(width 0.09525)
		(layer "In13.Cu")
		(net "M_B_CPU0_SB_DQS_DP<0>")
	)
	(segment
		(start 310.527954 -281.665934)
		(end 310.665368 -281.803348)
		(width 0.16002)
		(layer "In13.Cu")
		(net "M_B_CPU0_SB_DQS_DP<0>")
	)
	(segment
		(start 309.292498 -283.402278)
		(end 309.04561 -283.649166)
		(width 0.16002)
		(layer "In13.Cu")
		(net "M_B_CPU0_SB_DQS_DP<0>")
	)
	(segment
		(start 303.84496 -285.72841)
		(end 303.245266 -285.128716)
		(width 0.16002)
		(layer "In13.Cu")
		(net "M_B_CPU0_SB_DQS_DP<0>")
	)
	(segment
		(start 325.209408 -275.216112)
		(end 323.978778 -275.216112)
		(width 0.09525)
		(layer "In13.Cu")
		(net "M_B_CPU0_SB_DQS_DP<0>")
	)
	(segment
		(start 331.539596 -276.031198)
		(end 331.531214 -276.036024)
		(width 0.09525)
		(layer "In13.Cu")
		(net "M_B_CPU0_SB_DQS_DP<0>")
	)
	(segment
		(start 314.646564 -277.07082)
		(end 314.646564 -277.547324)
		(width 0.16002)
		(layer "In13.Cu")
		(net "M_B_CPU0_SB_DQS_DP<0>")
	)
	(arc
		(start 331.531214 -276.036024)
		(mid 331.346182 -276.081938)
		(end 331.162406 -276.031198)
		(width 0.09525)
		(layer "In13.Cu")
		(net "M_B_CPU0_SB_DQS_DP<0>")
	)
	(arc
		(start 332.10246 -276.031198)
		(mid 331.821028 -275.955443)
		(end 331.539596 -276.031198)
		(width 0.09525)
		(layer "In13.Cu")
		(net "M_B_CPU0_SB_DQS_DP<0>")
	)
	(arc
		(start 330.209398 -276.02434)
		(mid 329.933752 -275.955869)
		(end 329.659996 -276.031452)
		(width 0.09525)
		(layer "In13.Cu")
		(net "M_B_CPU0_SB_DQS_DP<0>")
	)
	(arc
		(start 334.359758 -276.031198)
		(mid 334.175983 -276.08197)
		(end 333.99095 -276.036024)
		(width 0.09525)
		(layer "In13.Cu")
		(net "M_B_CPU0_SB_DQS_DP<0>")
	)
	(arc
		(start 328.724006 -276.025102)
		(mid 328.522907 -276.062839)
		(end 328.32167 -276.025864)
		(width 0.09525)
		(layer "In13.Cu")
		(net "M_B_CPU0_SB_DQS_DP<0>")
	)
	(arc
		(start 330.599542 -276.031198)
		(mid 330.411074 -276.081875)
		(end 330.222606 -276.031198)
		(width 0.09525)
		(layer "In13.Cu")
		(net "M_B_CPU0_SB_DQS_DP<0>")
	)
	(arc
		(start 330.222606 -276.031198)
		(mid 330.216025 -276.027725)
		(end 330.209398 -276.02434)
		(width 0.09525)
		(layer "In13.Cu")
		(net "M_B_CPU0_SB_DQS_DP<0>")
	)
	(arc
		(start 333.419704 -276.031198)
		(mid 333.235929 -276.08197)
		(end 333.050896 -276.036024)
		(width 0.09525)
		(layer "In13.Cu")
		(net "M_B_CPU0_SB_DQS_DP<0>")
	)
	(arc
		(start 331.162406 -276.031198)
		(mid 330.880974 -275.955443)
		(end 330.599542 -276.031198)
		(width 0.09525)
		(layer "In13.Cu")
		(net "M_B_CPU0_SB_DQS_DP<0>")
	)
	(arc
		(start 328.32167 -276.025864)
		(mid 328.050544 -275.976786)
		(end 327.780142 -276.029674)
		(width 0.09525)
		(layer "In13.Cu")
		(net "M_B_CPU0_SB_DQS_DP<0>")
	)
	(arc
		(start 329.659996 -276.031452)
		(mid 329.488912 -276.081924)
		(end 329.313794 -276.047962)
		(width 0.09525)
		(layer "In13.Cu")
		(net "M_B_CPU0_SB_DQS_DP<0>")
	)
	(arc
		(start 335.796382 -275.998178)
		(mid 335.786134 -275.994015)
		(end 335.775808 -275.99005)
		(width 0.09525)
		(layer "In13.Cu")
		(net "M_B_CPU0_SB_DQS_DP<0>")
	)
	(arc
		(start 334.922622 -276.031198)
		(mid 334.64119 -275.955443)
		(end 334.359758 -276.031198)
		(width 0.09525)
		(layer "In13.Cu")
		(net "M_B_CPU0_SB_DQS_DP<0>")
	)
	(arc
		(start 335.775808 -275.99005)
		(mid 335.533066 -275.95728)
		(end 335.299558 -276.031198)
		(width 0.09525)
		(layer "In13.Cu")
		(net "M_B_CPU0_SB_DQS_DP<0>")
	)
	(arc
		(start 333.982568 -276.031198)
		(mid 333.701136 -275.955443)
		(end 333.419704 -276.031198)
		(width 0.09525)
		(layer "In13.Cu")
		(net "M_B_CPU0_SB_DQS_DP<0>")
	)
	(arc
		(start 333.042514 -276.031198)
		(mid 332.761082 -275.955443)
		(end 332.47965 -276.031198)
		(width 0.09525)
		(layer "In13.Cu")
		(net "M_B_CPU0_SB_DQS_DP<0>")
	)
	(arc
		(start 327.780142 -276.029674)
		(mid 327.644871 -276.069323)
		(end 327.504552 -276.08276)
		(width 0.09525)
		(layer "In13.Cu")
		(net "M_B_CPU0_SB_DQS_DP<0>")
	)
	(arc
		(start 332.471268 -276.036024)
		(mid 332.286236 -276.081938)
		(end 332.10246 -276.031198)
		(width 0.09525)
		(layer "In13.Cu")
		(net "M_B_CPU0_SB_DQS_DP<0>")
	)
	(arc
		(start 335.299558 -276.031198)
		(mid 335.11109 -276.081875)
		(end 334.922622 -276.031198)
		(width 0.09525)
		(layer "In13.Cu")
		(net "M_B_CPU0_SB_DQS_DP<0>")
	)
	(arc
		(start 329.310746 -276.046438)
		(mid 329.020387 -275.975246)
		(end 328.72553 -276.024594)
		(width 0.09525)
		(layer "In13.Cu")
		(net "M_B_CPU0_SB_DQS_DP<0>")
	)
	(segment
		(start 336.047842 -271.39011)
		(end 335.58099 -271.656048)
		(width 0.12954)
		(layer "F.Cu")
		(net "M_B_CPU0_SB_DQS_DN<9>")
	)
	(segment
		(start 308.05628 -275.210524)
		(end 307.591968 -275.674836)
		(width 0.16002)
		(layer "In13.Cu")
		(net "M_B_CPU0_SB_DQS_DN<9>")
	)
	(segment
		(start 335.734914 -271.390618)
		(end 335.711546 -271.30375)
		(width 0.09525)
		(layer "In13.Cu")
		(net "M_B_CPU0_SB_DQS_DN<9>")
	)
	(segment
		(start 311.274968 -271.515332)
		(end 311.205118 -271.445482)
		(width 0.16002)
		(layer "In13.Cu")
		(net "M_B_CPU0_SB_DQS_DN<9>")
	)
	(segment
		(start 302.45431 -276.28977)
		(end 301.854362 -276.28977)
		(width 0.16002)
		(layer "In13.Cu")
		(net "M_B_CPU0_SB_DQS_DN<9>")
	)
	(segment
		(start 308.529228 -274.261072)
		(end 308.459378 -274.191222)
		(width 0.16002)
		(layer "In13.Cu")
		(net "M_B_CPU0_SB_DQS_DN<9>")
	)
	(segment
		(start 310.979058 -271.445482)
		(end 310.73217 -271.69237)
		(width 0.16002)
		(layer "In13.Cu")
		(net "M_B_CPU0_SB_DQS_DN<9>")
	)
	(segment
		(start 335.58099 -271.656048)
		(end 335.734914 -271.390618)
		(width 0.09525)
		(layer "In13.Cu")
		(net "M_B_CPU0_SB_DQS_DN<9>")
	)
	(segment
		(start 323.995542 -269.776702)
		(end 323.936614 -269.83563)
		(width 0.09525)
		(layer "In13.Cu")
		(net "M_B_CPU0_SB_DQS_DN<9>")
	)
	(segment
		(start 335.400904 -271.326102)
		(end 335.392522 -271.330928)
		(width 0.09525)
		(layer "In13.Cu")
		(net "M_B_CPU0_SB_DQS_DN<9>")
	)
	(segment
		(start 312.351928 -270.072612)
		(end 312.10504 -270.3195)
		(width 0.16002)
		(layer "In13.Cu")
		(net "M_B_CPU0_SB_DQS_DN<9>")
	)
	(segment
		(start 309.42915 -273.837654)
		(end 309.005732 -274.261072)
		(width 0.16002)
		(layer "In13.Cu")
		(net "M_B_CPU0_SB_DQS_DN<9>")
	)
	(segment
		(start 307.591968 -275.674836)
		(end 306.684934 -275.674836)
		(width 0.16002)
		(layer "In13.Cu")
		(net "M_B_CPU0_SB_DQS_DN<9>")
	)
	(segment
		(start 303.495456 -274.898866)
		(end 303.299622 -274.703032)
		(width 0.16002)
		(layer "In13.Cu")
		(net "M_B_CPU0_SB_DQS_DN<9>")
	)
	(segment
		(start 309.3593 -273.06524)
		(end 309.3593 -273.2913)
		(width 0.16002)
		(layer "In13.Cu")
		(net "M_B_CPU0_SB_DQS_DN<9>")
	)
	(segment
		(start 309.832248 -272.818352)
		(end 309.606188 -272.818352)
		(width 0.16002)
		(layer "In13.Cu")
		(net "M_B_CPU0_SB_DQS_DN<9>")
	)
	(segment
		(start 333.889604 -271.330928)
		(end 333.881222 -271.326102)
		(width 0.09525)
		(layer "In13.Cu")
		(net "M_B_CPU0_SB_DQS_DN<9>")
	)
	(segment
		(start 303.868328 -276.28977)
		(end 303.495456 -275.916898)
		(width 0.16002)
		(layer "In13.Cu")
		(net "M_B_CPU0_SB_DQS_DN<9>")
	)
	(segment
		(start 303.495456 -275.916898)
		(end 303.495456 -274.898866)
		(width 0.16002)
		(layer "In13.Cu")
		(net "M_B_CPU0_SB_DQS_DN<9>")
	)
	(segment
		(start 303.023016 -274.703032)
		(end 302.827182 -274.898866)
		(width 0.16002)
		(layer "In13.Cu")
		(net "M_B_CPU0_SB_DQS_DN<9>")
	)
	(segment
		(start 310.80202 -272.464784)
		(end 310.378602 -272.888202)
		(width 0.16002)
		(layer "In13.Cu")
		(net "M_B_CPU0_SB_DQS_DN<9>")
	)
	(segment
		(start 310.73217 -271.69237)
		(end 310.73217 -271.91843)
		(width 0.16002)
		(layer "In13.Cu")
		(net "M_B_CPU0_SB_DQS_DN<9>")
	)
	(segment
		(start 313.431174 -269.83563)
		(end 313.194192 -270.072612)
		(width 0.16002)
		(layer "In13.Cu")
		(net "M_B_CPU0_SB_DQS_DN<9>")
	)
	(segment
		(start 323.936614 -269.83563)
		(end 323.912992 -269.83563)
		(width 0.09525)
		(layer "In13.Cu")
		(net "M_B_CPU0_SB_DQS_DN<9>")
	)
	(segment
		(start 310.73217 -271.91843)
		(end 310.80202 -271.98828)
		(width 0.16002)
		(layer "In13.Cu")
		(net "M_B_CPU0_SB_DQS_DN<9>")
	)
	(segment
		(start 324.69709 -270.327882)
		(end 324.14591 -269.776702)
		(width 0.09525)
		(layer "In13.Cu")
		(net "M_B_CPU0_SB_DQS_DN<9>")
	)
	(segment
		(start 312.10504 -270.54556)
		(end 312.17489 -270.61541)
		(width 0.16002)
		(layer "In13.Cu")
		(net "M_B_CPU0_SB_DQS_DN<9>")
	)
	(segment
		(start 301.854362 -276.28977)
		(end 301.650146 -276.085554)
		(width 0.16002)
		(layer "In13.Cu")
		(net "M_B_CPU0_SB_DQS_DN<9>")
	)
	(segment
		(start 309.3593 -273.2913)
		(end 309.42915 -273.36115)
		(width 0.16002)
		(layer "In13.Cu")
		(net "M_B_CPU0_SB_DQS_DN<9>")
	)
	(segment
		(start 312.17489 -271.091914)
		(end 311.751472 -271.515332)
		(width 0.16002)
		(layer "In13.Cu")
		(net "M_B_CPU0_SB_DQS_DN<9>")
	)
	(segment
		(start 307.98643 -274.43811)
		(end 307.98643 -274.66417)
		(width 0.16002)
		(layer "In13.Cu")
		(net "M_B_CPU0_SB_DQS_DN<9>")
	)
	(segment
		(start 311.751472 -271.515332)
		(end 311.274968 -271.515332)
		(width 0.16002)
		(layer "In13.Cu")
		(net "M_B_CPU0_SB_DQS_DN<9>")
	)
	(segment
		(start 302.827182 -274.898866)
		(end 302.827182 -275.916898)
		(width 0.16002)
		(layer "In13.Cu")
		(net "M_B_CPU0_SB_DQS_DN<9>")
	)
	(segment
		(start 326.403716 -271.406874)
		(end 325.324724 -270.327882)
		(width 0.09525)
		(layer "In13.Cu")
		(net "M_B_CPU0_SB_DQS_DN<9>")
	)
	(segment
		(start 312.17489 -270.61541)
		(end 312.17489 -271.091914)
		(width 0.16002)
		(layer "In13.Cu")
		(net "M_B_CPU0_SB_DQS_DN<9>")
	)
	(segment
		(start 306.461668 -275.45157)
		(end 305.839876 -275.45157)
		(width 0.16002)
		(layer "In13.Cu")
		(net "M_B_CPU0_SB_DQS_DN<9>")
	)
	(segment
		(start 309.42915 -273.36115)
		(end 309.42915 -273.837654)
		(width 0.16002)
		(layer "In13.Cu")
		(net "M_B_CPU0_SB_DQS_DN<9>")
	)
	(segment
		(start 308.05628 -274.73402)
		(end 308.05628 -275.210524)
		(width 0.16002)
		(layer "In13.Cu")
		(net "M_B_CPU0_SB_DQS_DN<9>")
	)
	(segment
		(start 303.299622 -274.703032)
		(end 303.023016 -274.703032)
		(width 0.16002)
		(layer "In13.Cu")
		(net "M_B_CPU0_SB_DQS_DN<9>")
	)
	(segment
		(start 313.194192 -270.072612)
		(end 312.351928 -270.072612)
		(width 0.16002)
		(layer "In13.Cu")
		(net "M_B_CPU0_SB_DQS_DN<9>")
	)
	(segment
		(start 309.606188 -272.818352)
		(end 309.3593 -273.06524)
		(width 0.16002)
		(layer "In13.Cu")
		(net "M_B_CPU0_SB_DQS_DN<9>")
	)
	(segment
		(start 305.839876 -275.45157)
		(end 305.001676 -276.28977)
		(width 0.16002)
		(layer "In13.Cu")
		(net "M_B_CPU0_SB_DQS_DN<9>")
	)
	(segment
		(start 302.827182 -275.916898)
		(end 302.45431 -276.28977)
		(width 0.16002)
		(layer "In13.Cu")
		(net "M_B_CPU0_SB_DQS_DN<9>")
	)
	(segment
		(start 311.205118 -271.445482)
		(end 310.979058 -271.445482)
		(width 0.16002)
		(layer "In13.Cu")
		(net "M_B_CPU0_SB_DQS_DN<9>")
	)
	(segment
		(start 310.378602 -272.888202)
		(end 309.902098 -272.888202)
		(width 0.16002)
		(layer "In13.Cu")
		(net "M_B_CPU0_SB_DQS_DN<9>")
	)
	(segment
		(start 301.650146 -276.085554)
		(end 300.123606 -276.085554)
		(width 0.16002)
		(layer "In13.Cu")
		(net "M_B_CPU0_SB_DQS_DN<9>")
	)
	(segment
		(start 306.684934 -275.674836)
		(end 306.461668 -275.45157)
		(width 0.16002)
		(layer "In13.Cu")
		(net "M_B_CPU0_SB_DQS_DN<9>")
	)
	(segment
		(start 327.60793 -271.40662)
		(end 327.607676 -271.406874)
		(width 0.09525)
		(layer "In13.Cu")
		(net "M_B_CPU0_SB_DQS_DN<9>")
	)
	(segment
		(start 307.98643 -274.66417)
		(end 308.05628 -274.73402)
		(width 0.16002)
		(layer "In13.Cu")
		(net "M_B_CPU0_SB_DQS_DN<9>")
	)
	(segment
		(start 300.123606 -276.085554)
		(end 299.82414 -276.38502)
		(width 0.16002)
		(layer "In13.Cu")
		(net "M_B_CPU0_SB_DQS_DN<9>")
	)
	(segment
		(start 323.912992 -269.83563)
		(end 313.431174 -269.83563)
		(width 0.16002)
		(layer "In13.Cu")
		(net "M_B_CPU0_SB_DQS_DN<9>")
	)
	(segment
		(start 308.459378 -274.191222)
		(end 308.233318 -274.191222)
		(width 0.16002)
		(layer "In13.Cu")
		(net "M_B_CPU0_SB_DQS_DN<9>")
	)
	(segment
		(start 334.829658 -271.330928)
		(end 334.821276 -271.326102)
		(width 0.09525)
		(layer "In13.Cu")
		(net "M_B_CPU0_SB_DQS_DN<9>")
	)
	(segment
		(start 325.324724 -270.327882)
		(end 324.69709 -270.327882)
		(width 0.09525)
		(layer "In13.Cu")
		(net "M_B_CPU0_SB_DQS_DN<9>")
	)
	(segment
		(start 330.700888 -271.326102)
		(end 330.692506 -271.330928)
		(width 0.09525)
		(layer "In13.Cu")
		(net "M_B_CPU0_SB_DQS_DN<9>")
	)
	(segment
		(start 310.80202 -271.98828)
		(end 310.80202 -272.464784)
		(width 0.16002)
		(layer "In13.Cu")
		(net "M_B_CPU0_SB_DQS_DN<9>")
	)
	(segment
		(start 312.10504 -270.3195)
		(end 312.10504 -270.54556)
		(width 0.16002)
		(layer "In13.Cu")
		(net "M_B_CPU0_SB_DQS_DN<9>")
	)
	(segment
		(start 327.607676 -271.406874)
		(end 326.403716 -271.406874)
		(width 0.09525)
		(layer "In13.Cu")
		(net "M_B_CPU0_SB_DQS_DN<9>")
	)
	(segment
		(start 305.001676 -276.28977)
		(end 303.868328 -276.28977)
		(width 0.16002)
		(layer "In13.Cu")
		(net "M_B_CPU0_SB_DQS_DN<9>")
	)
	(segment
		(start 324.14591 -269.776702)
		(end 323.995542 -269.776702)
		(width 0.09525)
		(layer "In13.Cu")
		(net "M_B_CPU0_SB_DQS_DN<9>")
	)
	(segment
		(start 309.902098 -272.888202)
		(end 309.832248 -272.818352)
		(width 0.16002)
		(layer "In13.Cu")
		(net "M_B_CPU0_SB_DQS_DN<9>")
	)
	(segment
		(start 309.005732 -274.261072)
		(end 308.529228 -274.261072)
		(width 0.16002)
		(layer "In13.Cu")
		(net "M_B_CPU0_SB_DQS_DN<9>")
	)
	(segment
		(start 331.640942 -271.326102)
		(end 331.63256 -271.330928)
		(width 0.09525)
		(layer "In13.Cu")
		(net "M_B_CPU0_SB_DQS_DN<9>")
	)
	(segment
		(start 308.233318 -274.191222)
		(end 307.98643 -274.43811)
		(width 0.16002)
		(layer "In13.Cu")
		(net "M_B_CPU0_SB_DQS_DN<9>")
	)
	(segment
		(start 330.129642 -271.330928)
		(end 330.12126 -271.326102)
		(width 0.09525)
		(layer "In13.Cu")
		(net "M_B_CPU0_SB_DQS_DN<9>")
	)
	(arc
		(start 329.189588 -271.330928)
		(mid 329.00112 -271.280251)
		(end 328.812652 -271.330928)
		(width 0.09525)
		(layer "In13.Cu")
		(net "M_B_CPU0_SB_DQS_DN<9>")
	)
	(arc
		(start 332.572614 -271.330928)
		(mid 332.291182 -271.406683)
		(end 332.00975 -271.330928)
		(width 0.09525)
		(layer "In13.Cu")
		(net "M_B_CPU0_SB_DQS_DN<9>")
	)
	(arc
		(start 328.812652 -271.330928)
		(mid 328.53122 -271.406683)
		(end 328.249788 -271.330928)
		(width 0.09525)
		(layer "In13.Cu")
		(net "M_B_CPU0_SB_DQS_DN<9>")
	)
	(arc
		(start 333.512414 -271.330928)
		(mid 333.230982 -271.406683)
		(end 332.94955 -271.330928)
		(width 0.09525)
		(layer "In13.Cu")
		(net "M_B_CPU0_SB_DQS_DN<9>")
	)
	(arc
		(start 329.752452 -271.330928)
		(mid 329.47102 -271.406683)
		(end 329.189588 -271.330928)
		(width 0.09525)
		(layer "In13.Cu")
		(net "M_B_CPU0_SB_DQS_DN<9>")
	)
	(arc
		(start 331.63256 -271.330928)
		(mid 331.351128 -271.406683)
		(end 331.069696 -271.330928)
		(width 0.09525)
		(layer "In13.Cu")
		(net "M_B_CPU0_SB_DQS_DN<9>")
	)
	(arc
		(start 332.00975 -271.330928)
		(mid 331.825975 -271.280156)
		(end 331.640942 -271.326102)
		(width 0.09525)
		(layer "In13.Cu")
		(net "M_B_CPU0_SB_DQS_DN<9>")
	)
	(arc
		(start 330.692506 -271.330928)
		(mid 330.411074 -271.406683)
		(end 330.129642 -271.330928)
		(width 0.09525)
		(layer "In13.Cu")
		(net "M_B_CPU0_SB_DQS_DN<9>")
	)
	(arc
		(start 330.12126 -271.326102)
		(mid 329.936228 -271.280188)
		(end 329.752452 -271.330928)
		(width 0.09525)
		(layer "In13.Cu")
		(net "M_B_CPU0_SB_DQS_DN<9>")
	)
	(arc
		(start 327.872344 -271.330928)
		(mid 327.744852 -271.385255)
		(end 327.60793 -271.40662)
		(width 0.09525)
		(layer "In13.Cu")
		(net "M_B_CPU0_SB_DQS_DN<9>")
	)
	(arc
		(start 334.821276 -271.326102)
		(mid 334.636244 -271.280188)
		(end 334.452468 -271.330928)
		(width 0.09525)
		(layer "In13.Cu")
		(net "M_B_CPU0_SB_DQS_DN<9>")
	)
	(arc
		(start 331.069696 -271.330928)
		(mid 330.885921 -271.280156)
		(end 330.700888 -271.326102)
		(width 0.09525)
		(layer "In13.Cu")
		(net "M_B_CPU0_SB_DQS_DN<9>")
	)
	(arc
		(start 335.711546 -271.30375)
		(mid 335.553796 -271.281231)
		(end 335.400904 -271.326102)
		(width 0.09525)
		(layer "In13.Cu")
		(net "M_B_CPU0_SB_DQS_DN<9>")
	)
	(arc
		(start 332.94955 -271.330928)
		(mid 332.761082 -271.280251)
		(end 332.572614 -271.330928)
		(width 0.09525)
		(layer "In13.Cu")
		(net "M_B_CPU0_SB_DQS_DN<9>")
	)
	(arc
		(start 333.881222 -271.326102)
		(mid 333.69619 -271.280188)
		(end 333.512414 -271.330928)
		(width 0.09525)
		(layer "In13.Cu")
		(net "M_B_CPU0_SB_DQS_DN<9>")
	)
	(arc
		(start 335.392522 -271.330928)
		(mid 335.11109 -271.406683)
		(end 334.829658 -271.330928)
		(width 0.09525)
		(layer "In13.Cu")
		(net "M_B_CPU0_SB_DQS_DN<9>")
	)
	(arc
		(start 334.452468 -271.330928)
		(mid 334.171036 -271.406683)
		(end 333.889604 -271.330928)
		(width 0.09525)
		(layer "In13.Cu")
		(net "M_B_CPU0_SB_DQS_DN<9>")
	)
	(arc
		(start 328.249788 -271.330928)
		(mid 328.061066 -271.280124)
		(end 327.872344 -271.330928)
		(width 0.09525)
		(layer "In13.Cu")
		(net "M_B_CPU0_SB_DQS_DN<9>")
	)
	(segment
		(start 337.92795 -290.83)
		(end 337.461098 -291.095938)
		(width 0.12954)
		(layer "F.Cu")
		(net "M_B_CPU0_SB_DQS_DN<8>")
	)
	(segment
		(start 330.700888 -291.425884)
		(end 330.692506 -291.421058)
		(width 0.09525)
		(layer "In13.Cu")
		(net "M_B_CPU0_SB_DQS_DN<8>")
	)
	(segment
		(start 325.08444 -295.330626)
		(end 322.292218 -298.122848)
		(width 0.16002)
		(layer "In13.Cu")
		(net "M_B_CPU0_SB_DQS_DN<8>")
	)
	(segment
		(start 303.924208 -314.57011)
		(end 303.444148 -314.57011)
		(width 0.16002)
		(layer "In13.Cu")
		(net "M_B_CPU0_SB_DQS_DN<8>")
	)
	(segment
		(start 307.156104 -313.895232)
		(end 305.657504 -313.895232)
		(width 0.16002)
		(layer "In13.Cu")
		(net "M_B_CPU0_SB_DQS_DN<8>")
	)
	(segment
		(start 303.327308 -314.68695)
		(end 299.546772 -314.68695)
		(width 0.16002)
		(layer "In13.Cu")
		(net "M_B_CPU0_SB_DQS_DN<8>")
	)
	(segment
		(start 296.189146 -314.04941)
		(end 295.988486 -314.04941)
		(width 0.16002)
		(layer "In13.Cu")
		(net "M_B_CPU0_SB_DQS_DN<8>")
	)
	(segment
		(start 295.988486 -314.04941)
		(end 295.724072 -313.784996)
		(width 0.16002)
		(layer "In13.Cu")
		(net "M_B_CPU0_SB_DQS_DN<8>")
	)
	(segment
		(start 336.340958 -291.425884)
		(end 336.332576 -291.421058)
		(width 0.09525)
		(layer "In13.Cu")
		(net "M_B_CPU0_SB_DQS_DN<8>")
	)
	(segment
		(start 325.482458 -295.01719)
		(end 325.184516 -295.314116)
		(width 0.09525)
		(layer "In13.Cu")
		(net "M_B_CPU0_SB_DQS_DN<8>")
	)
	(segment
		(start 303.444148 -314.57011)
		(end 303.327308 -314.68695)
		(width 0.16002)
		(layer "In13.Cu")
		(net "M_B_CPU0_SB_DQS_DN<8>")
	)
	(segment
		(start 296.358564 -313.879992)
		(end 296.189146 -314.04941)
		(width 0.16002)
		(layer "In13.Cu")
		(net "M_B_CPU0_SB_DQS_DN<8>")
	)
	(segment
		(start 325.646542 -294.011858)
		(end 325.482458 -294.40759)
		(width 0.09525)
		(layer "In13.Cu")
		(net "M_B_CPU0_SB_DQS_DN<8>")
	)
	(segment
		(start 337.307174 -291.361368)
		(end 337.206336 -291.388038)
		(width 0.09525)
		(layer "In13.Cu")
		(net "M_B_CPU0_SB_DQS_DN<8>")
	)
	(segment
		(start 326.784462 -292.308788)
		(end 325.646542 -294.011858)
		(width 0.09525)
		(layer "In13.Cu")
		(net "M_B_CPU0_SB_DQS_DN<8>")
	)
	(segment
		(start 305.657504 -313.895232)
		(end 304.865786 -314.68695)
		(width 0.16002)
		(layer "In13.Cu")
		(net "M_B_CPU0_SB_DQS_DN<8>")
	)
	(segment
		(start 327.620884 -291.472366)
		(end 326.784462 -292.308788)
		(width 0.09525)
		(layer "In13.Cu")
		(net "M_B_CPU0_SB_DQS_DN<8>")
	)
	(segment
		(start 331.640942 -291.425884)
		(end 331.63256 -291.421058)
		(width 0.09525)
		(layer "In13.Cu")
		(net "M_B_CPU0_SB_DQS_DN<8>")
	)
	(segment
		(start 322.292218 -299.322744)
		(end 318.983868 -302.631094)
		(width 0.16002)
		(layer "In13.Cu")
		(net "M_B_CPU0_SB_DQS_DN<8>")
	)
	(segment
		(start 337.461098 -291.095938)
		(end 337.307174 -291.361368)
		(width 0.09525)
		(layer "In13.Cu")
		(net "M_B_CPU0_SB_DQS_DN<8>")
	)
	(segment
		(start 333.889604 -291.421058)
		(end 333.881222 -291.425884)
		(width 0.09525)
		(layer "In13.Cu")
		(net "M_B_CPU0_SB_DQS_DN<8>")
	)
	(segment
		(start 322.292218 -298.122848)
		(end 322.292218 -299.322744)
		(width 0.16002)
		(layer "In13.Cu")
		(net "M_B_CPU0_SB_DQS_DN<8>")
	)
	(segment
		(start 335.400904 -291.425884)
		(end 335.392522 -291.421058)
		(width 0.09525)
		(layer "In13.Cu")
		(net "M_B_CPU0_SB_DQS_DN<8>")
	)
	(segment
		(start 318.983868 -303.83353)
		(end 310.171084 -312.646314)
		(width 0.16002)
		(layer "In13.Cu")
		(net "M_B_CPU0_SB_DQS_DN<8>")
	)
	(segment
		(start 310.171084 -312.646314)
		(end 307.156104 -313.895232)
		(width 0.16002)
		(layer "In13.Cu")
		(net "M_B_CPU0_SB_DQS_DN<8>")
	)
	(segment
		(start 298.755054 -313.879992)
		(end 296.358564 -313.879992)
		(width 0.16002)
		(layer "In13.Cu")
		(net "M_B_CPU0_SB_DQS_DN<8>")
	)
	(segment
		(start 330.129642 -291.421058)
		(end 330.12126 -291.425884)
		(width 0.09525)
		(layer "In13.Cu")
		(net "M_B_CPU0_SB_DQS_DN<8>")
	)
	(segment
		(start 304.865786 -314.68695)
		(end 304.041048 -314.68695)
		(width 0.16002)
		(layer "In13.Cu")
		(net "M_B_CPU0_SB_DQS_DN<8>")
	)
	(segment
		(start 328.061066 -291.472366)
		(end 327.620884 -291.472366)
		(width 0.09525)
		(layer "In13.Cu")
		(net "M_B_CPU0_SB_DQS_DN<8>")
	)
	(segment
		(start 334.829658 -291.421058)
		(end 334.821276 -291.425884)
		(width 0.09525)
		(layer "In13.Cu")
		(net "M_B_CPU0_SB_DQS_DN<8>")
	)
	(segment
		(start 318.983868 -302.631094)
		(end 318.983868 -303.83353)
		(width 0.16002)
		(layer "In13.Cu")
		(net "M_B_CPU0_SB_DQS_DN<8>")
	)
	(segment
		(start 325.184516 -295.314116)
		(end 325.101204 -295.313862)
		(width 0.09525)
		(layer "In13.Cu")
		(net "M_B_CPU0_SB_DQS_DN<8>")
	)
	(segment
		(start 325.482458 -294.40759)
		(end 325.482458 -295.01719)
		(width 0.09525)
		(layer "In13.Cu")
		(net "M_B_CPU0_SB_DQS_DN<8>")
	)
	(segment
		(start 299.546772 -314.68695)
		(end 298.755054 -313.879992)
		(width 0.16002)
		(layer "In13.Cu")
		(net "M_B_CPU0_SB_DQS_DN<8>")
	)
	(segment
		(start 304.041048 -314.68695)
		(end 303.924208 -314.57011)
		(width 0.16002)
		(layer "In13.Cu")
		(net "M_B_CPU0_SB_DQS_DN<8>")
	)
	(segment
		(start 325.101204 -295.313862)
		(end 325.08444 -295.330626)
		(width 0.09525)
		(layer "In13.Cu")
		(net "M_B_CPU0_SB_DQS_DN<8>")
	)
	(arc
		(start 333.881222 -291.425884)
		(mid 333.69619 -291.471798)
		(end 333.512414 -291.421058)
		(width 0.09525)
		(layer "In13.Cu")
		(net "M_B_CPU0_SB_DQS_DN<8>")
	)
	(arc
		(start 331.069696 -291.421058)
		(mid 330.885921 -291.47183)
		(end 330.700888 -291.425884)
		(width 0.09525)
		(layer "In13.Cu")
		(net "M_B_CPU0_SB_DQS_DN<8>")
	)
	(arc
		(start 331.63256 -291.421058)
		(mid 331.351128 -291.345303)
		(end 331.069696 -291.421058)
		(width 0.09525)
		(layer "In13.Cu")
		(net "M_B_CPU0_SB_DQS_DN<8>")
	)
	(arc
		(start 332.00975 -291.421058)
		(mid 331.825975 -291.47183)
		(end 331.640942 -291.425884)
		(width 0.09525)
		(layer "In13.Cu")
		(net "M_B_CPU0_SB_DQS_DN<8>")
	)
	(arc
		(start 337.186016 -291.380164)
		(mid 336.943304 -291.347281)
		(end 336.709766 -291.421058)
		(width 0.09525)
		(layer "In13.Cu")
		(net "M_B_CPU0_SB_DQS_DN<8>")
	)
	(arc
		(start 329.752452 -291.421058)
		(mid 329.47102 -291.345303)
		(end 329.189588 -291.421058)
		(width 0.09525)
		(layer "In13.Cu")
		(net "M_B_CPU0_SB_DQS_DN<8>")
	)
	(arc
		(start 328.812652 -291.421058)
		(mid 328.53122 -291.345303)
		(end 328.249788 -291.421058)
		(width 0.09525)
		(layer "In13.Cu")
		(net "M_B_CPU0_SB_DQS_DN<8>")
	)
	(arc
		(start 336.332576 -291.421058)
		(mid 336.051144 -291.345303)
		(end 335.769712 -291.421058)
		(width 0.09525)
		(layer "In13.Cu")
		(net "M_B_CPU0_SB_DQS_DN<8>")
	)
	(arc
		(start 333.512414 -291.421058)
		(mid 333.230982 -291.345303)
		(end 332.94955 -291.421058)
		(width 0.09525)
		(layer "In13.Cu")
		(net "M_B_CPU0_SB_DQS_DN<8>")
	)
	(arc
		(start 334.821276 -291.425884)
		(mid 334.636244 -291.471798)
		(end 334.452468 -291.421058)
		(width 0.09525)
		(layer "In13.Cu")
		(net "M_B_CPU0_SB_DQS_DN<8>")
	)
	(arc
		(start 329.189588 -291.421058)
		(mid 329.00112 -291.471735)
		(end 328.812652 -291.421058)
		(width 0.09525)
		(layer "In13.Cu")
		(net "M_B_CPU0_SB_DQS_DN<8>")
	)
	(arc
		(start 335.392522 -291.421058)
		(mid 335.11109 -291.345303)
		(end 334.829658 -291.421058)
		(width 0.09525)
		(layer "In13.Cu")
		(net "M_B_CPU0_SB_DQS_DN<8>")
	)
	(arc
		(start 332.572614 -291.421058)
		(mid 332.291182 -291.345303)
		(end 332.00975 -291.421058)
		(width 0.09525)
		(layer "In13.Cu")
		(net "M_B_CPU0_SB_DQS_DN<8>")
	)
	(arc
		(start 336.709766 -291.421058)
		(mid 336.525991 -291.47183)
		(end 336.340958 -291.425884)
		(width 0.09525)
		(layer "In13.Cu")
		(net "M_B_CPU0_SB_DQS_DN<8>")
	)
	(arc
		(start 328.249788 -291.421058)
		(mid 328.158822 -291.459211)
		(end 328.061066 -291.472366)
		(width 0.09525)
		(layer "In13.Cu")
		(net "M_B_CPU0_SB_DQS_DN<8>")
	)
	(arc
		(start 337.206336 -291.388038)
		(mid 337.196214 -291.384003)
		(end 337.186016 -291.380164)
		(width 0.09525)
		(layer "In13.Cu")
		(net "M_B_CPU0_SB_DQS_DN<8>")
	)
	(arc
		(start 334.452468 -291.421058)
		(mid 334.171036 -291.345303)
		(end 333.889604 -291.421058)
		(width 0.09525)
		(layer "In13.Cu")
		(net "M_B_CPU0_SB_DQS_DN<8>")
	)
	(arc
		(start 335.769712 -291.421058)
		(mid 335.585937 -291.47183)
		(end 335.400904 -291.425884)
		(width 0.09525)
		(layer "In13.Cu")
		(net "M_B_CPU0_SB_DQS_DN<8>")
	)
	(arc
		(start 332.94955 -291.421058)
		(mid 332.761082 -291.471735)
		(end 332.572614 -291.421058)
		(width 0.09525)
		(layer "In13.Cu")
		(net "M_B_CPU0_SB_DQS_DN<8>")
	)
	(arc
		(start 330.692506 -291.421058)
		(mid 330.411074 -291.345303)
		(end 330.129642 -291.421058)
		(width 0.09525)
		(layer "In13.Cu")
		(net "M_B_CPU0_SB_DQS_DN<8>")
	)
	(arc
		(start 330.12126 -291.425884)
		(mid 329.936228 -291.471798)
		(end 329.752452 -291.421058)
		(width 0.09525)
		(layer "In13.Cu")
		(net "M_B_CPU0_SB_DQS_DN<8>")
	)
	(segment
		(start 337.92795 -285.970218)
		(end 337.461098 -286.236156)
		(width 0.12954)
		(layer "F.Cu")
		(net "M_B_CPU0_SB_DQS_DN<7>")
	)
	(segment
		(start 299.48632 -304.857912)
		(end 298.694602 -304.529998)
		(width 0.16002)
		(layer "In13.Cu")
		(net "M_B_CPU0_SB_DQS_DN<7>")
	)
	(segment
		(start 326.946006 -286.577278)
		(end 326.896476 -286.549084)
		(width 0.09525)
		(layer "In13.Cu")
		(net "M_B_CPU0_SB_DQS_DN<7>")
	)
	(segment
		(start 327.87336 -286.561022)
		(end 327.85558 -286.550608)
		(width 0.09525)
		(layer "In13.Cu")
		(net "M_B_CPU0_SB_DQS_DN<7>")
	)
	(segment
		(start 308.380384 -304.05324)
		(end 305.568604 -304.612548)
		(width 0.16002)
		(layer "In13.Cu")
		(net "M_B_CPU0_SB_DQS_DN<7>")
	)
	(segment
		(start 325.87819 -286.628332)
		(end 325.60514 -286.901382)
		(width 0.09525)
		(layer "In13.Cu")
		(net "M_B_CPU0_SB_DQS_DN<7>")
	)
	(segment
		(start 303.357788 -305.37531)
		(end 303.240948 -305.25847)
		(width 0.16002)
		(layer "In13.Cu")
		(net "M_B_CPU0_SB_DQS_DN<7>")
	)
	(segment
		(start 298.694602 -304.529998)
		(end 297.611546 -304.529998)
		(width 0.16002)
		(layer "In13.Cu")
		(net "M_B_CPU0_SB_DQS_DN<7>")
	)
	(segment
		(start 323.912738 -287.796478)
		(end 323.895974 -287.813242)
		(width 0.09525)
		(layer "In13.Cu")
		(net "M_B_CPU0_SB_DQS_DN<7>")
	)
	(segment
		(start 330.129642 -286.561276)
		(end 330.12126 -286.566102)
		(width 0.09525)
		(layer "In13.Cu")
		(net "M_B_CPU0_SB_DQS_DN<7>")
	)
	(segment
		(start 337.307174 -286.501586)
		(end 337.206336 -286.528256)
		(width 0.09525)
		(layer "In13.Cu")
		(net "M_B_CPU0_SB_DQS_DN<7>")
	)
	(segment
		(start 295.998138 -304.709068)
		(end 295.724072 -304.435002)
		(width 0.16002)
		(layer "In13.Cu")
		(net "M_B_CPU0_SB_DQS_DN<7>")
	)
	(segment
		(start 308.874922 -304.05324)
		(end 308.380384 -304.05324)
		(width 0.16002)
		(layer "In13.Cu")
		(net "M_B_CPU0_SB_DQS_DN<7>")
	)
	(segment
		(start 337.461098 -286.236156)
		(end 337.307174 -286.501586)
		(width 0.09525)
		(layer "In13.Cu")
		(net "M_B_CPU0_SB_DQS_DN<7>")
	)
	(segment
		(start 327.85558 -286.550608)
		(end 327.854564 -286.5501)
		(width 0.09525)
		(layer "In13.Cu")
		(net "M_B_CPU0_SB_DQS_DN<7>")
	)
	(segment
		(start 336.340958 -286.566102)
		(end 336.332576 -286.561276)
		(width 0.09525)
		(layer "In13.Cu")
		(net "M_B_CPU0_SB_DQS_DN<7>")
	)
	(segment
		(start 316.002416 -295.706292)
		(end 316.002416 -296.925746)
		(width 0.16002)
		(layer "In13.Cu")
		(net "M_B_CPU0_SB_DQS_DN<7>")
	)
	(segment
		(start 304.805842 -305.37531)
		(end 303.357788 -305.37531)
		(width 0.16002)
		(layer "In13.Cu")
		(net "M_B_CPU0_SB_DQS_DN<7>")
	)
	(segment
		(start 324.891654 -286.901382)
		(end 323.996558 -287.796478)
		(width 0.09525)
		(layer "In13.Cu")
		(net "M_B_CPU0_SB_DQS_DN<7>")
	)
	(segment
		(start 326.168512 -286.628332)
		(end 325.87819 -286.628332)
		(width 0.09525)
		(layer "In13.Cu")
		(net "M_B_CPU0_SB_DQS_DN<7>")
	)
	(segment
		(start 327.893426 -286.572706)
		(end 327.87336 -286.561022)
		(width 0.09525)
		(layer "In13.Cu")
		(net "M_B_CPU0_SB_DQS_DN<7>")
	)
	(segment
		(start 333.889604 -286.561276)
		(end 333.881222 -286.566102)
		(width 0.09525)
		(layer "In13.Cu")
		(net "M_B_CPU0_SB_DQS_DN<7>")
	)
	(segment
		(start 325.60514 -286.901382)
		(end 324.891654 -286.901382)
		(width 0.09525)
		(layer "In13.Cu")
		(net "M_B_CPU0_SB_DQS_DN<7>")
	)
	(segment
		(start 300.846998 -304.857912)
		(end 299.48632 -304.857912)
		(width 0.16002)
		(layer "In13.Cu")
		(net "M_B_CPU0_SB_DQS_DN<7>")
	)
	(segment
		(start 302.760888 -305.25847)
		(end 302.644048 -305.37531)
		(width 0.16002)
		(layer "In13.Cu")
		(net "M_B_CPU0_SB_DQS_DN<7>")
	)
	(segment
		(start 297.178984 -304.709068)
		(end 295.998138 -304.709068)
		(width 0.16002)
		(layer "In13.Cu")
		(net "M_B_CPU0_SB_DQS_DN<7>")
	)
	(segment
		(start 335.400904 -286.566102)
		(end 335.392522 -286.561276)
		(width 0.09525)
		(layer "In13.Cu")
		(net "M_B_CPU0_SB_DQS_DN<7>")
	)
	(segment
		(start 303.240948 -305.25847)
		(end 302.760888 -305.25847)
		(width 0.16002)
		(layer "In13.Cu")
		(net "M_B_CPU0_SB_DQS_DN<7>")
	)
	(segment
		(start 316.002416 -296.925746)
		(end 308.874922 -304.05324)
		(width 0.16002)
		(layer "In13.Cu")
		(net "M_B_CPU0_SB_DQS_DN<7>")
	)
	(segment
		(start 302.096424 -305.37531)
		(end 300.846998 -304.857912)
		(width 0.16002)
		(layer "In13.Cu")
		(net "M_B_CPU0_SB_DQS_DN<7>")
	)
	(segment
		(start 302.644048 -305.37531)
		(end 302.096424 -305.37531)
		(width 0.16002)
		(layer "In13.Cu")
		(net "M_B_CPU0_SB_DQS_DN<7>")
	)
	(segment
		(start 323.996558 -287.796478)
		(end 323.912738 -287.796478)
		(width 0.09525)
		(layer "In13.Cu")
		(net "M_B_CPU0_SB_DQS_DN<7>")
	)
	(segment
		(start 330.700888 -286.566102)
		(end 330.692506 -286.561276)
		(width 0.09525)
		(layer "In13.Cu")
		(net "M_B_CPU0_SB_DQS_DN<7>")
	)
	(segment
		(start 334.829658 -286.561276)
		(end 334.821276 -286.566102)
		(width 0.09525)
		(layer "In13.Cu")
		(net "M_B_CPU0_SB_DQS_DN<7>")
	)
	(segment
		(start 323.895974 -287.813242)
		(end 316.002416 -295.706292)
		(width 0.16002)
		(layer "In13.Cu")
		(net "M_B_CPU0_SB_DQS_DN<7>")
	)
	(segment
		(start 305.568604 -304.612548)
		(end 304.805842 -305.37531)
		(width 0.16002)
		(layer "In13.Cu")
		(net "M_B_CPU0_SB_DQS_DN<7>")
	)
	(segment
		(start 297.611546 -304.529998)
		(end 297.178984 -304.709068)
		(width 0.16002)
		(layer "In13.Cu")
		(net "M_B_CPU0_SB_DQS_DN<7>")
	)
	(segment
		(start 331.640942 -286.566102)
		(end 331.63256 -286.561276)
		(width 0.09525)
		(layer "In13.Cu")
		(net "M_B_CPU0_SB_DQS_DN<7>")
	)
	(arc
		(start 327.343262 -286.544512)
		(mid 327.309906 -286.559984)
		(end 327.275698 -286.573468)
		(width 0.09525)
		(layer "In13.Cu")
		(net "M_B_CPU0_SB_DQS_DN<7>")
	)
	(arc
		(start 326.896476 -286.549084)
		(mid 326.625874 -286.492373)
		(end 326.361552 -286.573468)
		(width 0.09525)
		(layer "In13.Cu")
		(net "M_B_CPU0_SB_DQS_DN<7>")
	)
	(arc
		(start 327.854564 -286.5501)
		(mid 327.850254 -286.548177)
		(end 327.845928 -286.54629)
		(width 0.09525)
		(layer "In13.Cu")
		(net "M_B_CPU0_SB_DQS_DN<7>")
	)
	(arc
		(start 332.00975 -286.561276)
		(mid 331.825975 -286.612048)
		(end 331.640942 -286.566102)
		(width 0.09525)
		(layer "In13.Cu")
		(net "M_B_CPU0_SB_DQS_DN<7>")
	)
	(arc
		(start 335.392522 -286.561276)
		(mid 335.11109 -286.485487)
		(end 334.829658 -286.561276)
		(width 0.09525)
		(layer "In13.Cu")
		(net "M_B_CPU0_SB_DQS_DN<7>")
	)
	(arc
		(start 331.63256 -286.561276)
		(mid 331.351128 -286.485487)
		(end 331.069696 -286.561276)
		(width 0.09525)
		(layer "In13.Cu")
		(net "M_B_CPU0_SB_DQS_DN<7>")
	)
	(arc
		(start 327.275698 -286.573468)
		(mid 327.111168 -286.602908)
		(end 326.946006 -286.577278)
		(width 0.09525)
		(layer "In13.Cu")
		(net "M_B_CPU0_SB_DQS_DN<7>")
	)
	(arc
		(start 328.812652 -286.561276)
		(mid 328.53122 -286.485487)
		(end 328.249788 -286.561276)
		(width 0.09525)
		(layer "In13.Cu")
		(net "M_B_CPU0_SB_DQS_DN<7>")
	)
	(arc
		(start 333.512414 -286.561276)
		(mid 333.230982 -286.485487)
		(end 332.94955 -286.561276)
		(width 0.09525)
		(layer "In13.Cu")
		(net "M_B_CPU0_SB_DQS_DN<7>")
	)
	(arc
		(start 330.692506 -286.561276)
		(mid 330.411074 -286.485487)
		(end 330.129642 -286.561276)
		(width 0.09525)
		(layer "In13.Cu")
		(net "M_B_CPU0_SB_DQS_DN<7>")
	)
	(arc
		(start 332.572614 -286.561276)
		(mid 332.291182 -286.485487)
		(end 332.00975 -286.561276)
		(width 0.09525)
		(layer "In13.Cu")
		(net "M_B_CPU0_SB_DQS_DN<7>")
	)
	(arc
		(start 328.249788 -286.561276)
		(mid 328.073055 -286.611889)
		(end 327.893426 -286.572706)
		(width 0.09525)
		(layer "In13.Cu")
		(net "M_B_CPU0_SB_DQS_DN<7>")
	)
	(arc
		(start 329.752452 -286.561276)
		(mid 329.47102 -286.485487)
		(end 329.189588 -286.561276)
		(width 0.09525)
		(layer "In13.Cu")
		(net "M_B_CPU0_SB_DQS_DN<7>")
	)
	(arc
		(start 337.206336 -286.528256)
		(mid 337.196215 -286.524094)
		(end 337.186016 -286.520128)
		(width 0.09525)
		(layer "In13.Cu")
		(net "M_B_CPU0_SB_DQS_DN<7>")
	)
	(arc
		(start 336.709766 -286.561276)
		(mid 336.525991 -286.612048)
		(end 336.340958 -286.566102)
		(width 0.09525)
		(layer "In13.Cu")
		(net "M_B_CPU0_SB_DQS_DN<7>")
	)
	(arc
		(start 335.769712 -286.561276)
		(mid 335.585937 -286.612048)
		(end 335.400904 -286.566102)
		(width 0.09525)
		(layer "In13.Cu")
		(net "M_B_CPU0_SB_DQS_DN<7>")
	)
	(arc
		(start 332.94955 -286.561276)
		(mid 332.761082 -286.611953)
		(end 332.572614 -286.561276)
		(width 0.09525)
		(layer "In13.Cu")
		(net "M_B_CPU0_SB_DQS_DN<7>")
	)
	(arc
		(start 330.12126 -286.566102)
		(mid 329.936228 -286.612016)
		(end 329.752452 -286.561276)
		(width 0.09525)
		(layer "In13.Cu")
		(net "M_B_CPU0_SB_DQS_DN<7>")
	)
	(arc
		(start 326.361552 -286.573468)
		(mid 326.268824 -286.614237)
		(end 326.168512 -286.628332)
		(width 0.09525)
		(layer "In13.Cu")
		(net "M_B_CPU0_SB_DQS_DN<7>")
	)
	(arc
		(start 327.845928 -286.54629)
		(mid 327.594818 -286.485894)
		(end 327.343262 -286.544512)
		(width 0.09525)
		(layer "In13.Cu")
		(net "M_B_CPU0_SB_DQS_DN<7>")
	)
	(arc
		(start 336.332576 -286.561276)
		(mid 336.051144 -286.485487)
		(end 335.769712 -286.561276)
		(width 0.09525)
		(layer "In13.Cu")
		(net "M_B_CPU0_SB_DQS_DN<7>")
	)
	(arc
		(start 337.186016 -286.520128)
		(mid 336.943274 -286.487343)
		(end 336.709766 -286.561276)
		(width 0.09525)
		(layer "In13.Cu")
		(net "M_B_CPU0_SB_DQS_DN<7>")
	)
	(arc
		(start 334.452468 -286.561276)
		(mid 334.171036 -286.485487)
		(end 333.889604 -286.561276)
		(width 0.09525)
		(layer "In13.Cu")
		(net "M_B_CPU0_SB_DQS_DN<7>")
	)
	(arc
		(start 329.189588 -286.561276)
		(mid 329.00112 -286.611953)
		(end 328.812652 -286.561276)
		(width 0.09525)
		(layer "In13.Cu")
		(net "M_B_CPU0_SB_DQS_DN<7>")
	)
	(arc
		(start 331.069696 -286.561276)
		(mid 330.885921 -286.612048)
		(end 330.700888 -286.566102)
		(width 0.09525)
		(layer "In13.Cu")
		(net "M_B_CPU0_SB_DQS_DN<7>")
	)
	(arc
		(start 334.821276 -286.566102)
		(mid 334.636244 -286.612016)
		(end 334.452468 -286.561276)
		(width 0.09525)
		(layer "In13.Cu")
		(net "M_B_CPU0_SB_DQS_DN<7>")
	)
	(arc
		(start 333.881222 -286.566102)
		(mid 333.69619 -286.612016)
		(end 333.512414 -286.561276)
		(width 0.09525)
		(layer "In13.Cu")
		(net "M_B_CPU0_SB_DQS_DN<7>")
	)
	(segment
		(start 337.92795 -281.110182)
		(end 337.461098 -281.37612)
		(width 0.12954)
		(layer "F.Cu")
		(net "M_B_CPU0_SB_DQS_DN<6>")
	)
	(segment
		(start 327.102978 -281.543252)
		(end 324.61581 -281.543252)
		(width 0.09525)
		(layer "In13.Cu")
		(net "M_B_CPU0_SB_DQS_DN<6>")
	)
	(segment
		(start 323.978778 -281.731212)
		(end 323.919596 -281.67203)
		(width 0.09525)
		(layer "In13.Cu")
		(net "M_B_CPU0_SB_DQS_DN<6>")
	)
	(segment
		(start 330.700888 -281.706066)
		(end 330.692506 -281.70124)
		(width 0.09525)
		(layer "In13.Cu")
		(net "M_B_CPU0_SB_DQS_DN<6>")
	)
	(segment
		(start 299.554646 -295.507918)
		(end 298.830238 -295.180004)
		(width 0.16002)
		(layer "In13.Cu")
		(net "M_B_CPU0_SB_DQS_DN<6>")
	)
	(segment
		(start 331.640942 -281.706066)
		(end 331.63256 -281.70124)
		(width 0.09525)
		(layer "In13.Cu")
		(net "M_B_CPU0_SB_DQS_DN<6>")
	)
	(segment
		(start 304.853848 -295.97731)
		(end 301.81042 -295.97731)
		(width 0.16002)
		(layer "In13.Cu")
		(net "M_B_CPU0_SB_DQS_DN<6>")
	)
	(segment
		(start 305.651154 -295.180004)
		(end 304.853848 -295.97731)
		(width 0.16002)
		(layer "In13.Cu")
		(net "M_B_CPU0_SB_DQS_DN<6>")
	)
	(segment
		(start 296.201846 -295.359074)
		(end 295.998138 -295.359074)
		(width 0.16002)
		(layer "In13.Cu")
		(net "M_B_CPU0_SB_DQS_DN<6>")
	)
	(segment
		(start 301.81042 -295.97731)
		(end 301.341028 -295.507918)
		(width 0.16002)
		(layer "In13.Cu")
		(net "M_B_CPU0_SB_DQS_DN<6>")
	)
	(segment
		(start 335.400904 -281.706066)
		(end 335.392522 -281.70124)
		(width 0.09525)
		(layer "In13.Cu")
		(net "M_B_CPU0_SB_DQS_DN<6>")
	)
	(segment
		(start 324.377558 -281.731212)
		(end 323.978778 -281.731212)
		(width 0.09525)
		(layer "In13.Cu")
		(net "M_B_CPU0_SB_DQS_DN<6>")
	)
	(segment
		(start 296.380916 -295.180004)
		(end 296.201846 -295.359074)
		(width 0.16002)
		(layer "In13.Cu")
		(net "M_B_CPU0_SB_DQS_DN<6>")
	)
	(segment
		(start 337.461098 -281.37612)
		(end 337.307174 -281.64155)
		(width 0.09525)
		(layer "In13.Cu")
		(net "M_B_CPU0_SB_DQS_DN<6>")
	)
	(segment
		(start 324.529958 -281.578812)
		(end 324.377558 -281.731212)
		(width 0.09525)
		(layer "In13.Cu")
		(net "M_B_CPU0_SB_DQS_DN<6>")
	)
	(segment
		(start 298.830238 -295.180004)
		(end 296.380916 -295.180004)
		(width 0.16002)
		(layer "In13.Cu")
		(net "M_B_CPU0_SB_DQS_DN<6>")
	)
	(segment
		(start 308.422548 -295.180004)
		(end 305.651154 -295.180004)
		(width 0.16002)
		(layer "In13.Cu")
		(net "M_B_CPU0_SB_DQS_DN<6>")
	)
	(segment
		(start 301.341028 -295.507918)
		(end 299.554646 -295.507918)
		(width 0.16002)
		(layer "In13.Cu")
		(net "M_B_CPU0_SB_DQS_DN<6>")
	)
	(segment
		(start 336.340958 -281.706066)
		(end 336.332576 -281.70124)
		(width 0.09525)
		(layer "In13.Cu")
		(net "M_B_CPU0_SB_DQS_DN<6>")
	)
	(segment
		(start 333.889604 -281.70124)
		(end 333.881222 -281.706066)
		(width 0.09525)
		(layer "In13.Cu")
		(net "M_B_CPU0_SB_DQS_DN<6>")
	)
	(segment
		(start 330.129642 -281.70124)
		(end 330.12126 -281.706066)
		(width 0.09525)
		(layer "In13.Cu")
		(net "M_B_CPU0_SB_DQS_DN<6>")
	)
	(segment
		(start 321.930522 -281.67203)
		(end 308.422548 -295.180004)
		(width 0.16002)
		(layer "In13.Cu")
		(net "M_B_CPU0_SB_DQS_DN<6>")
	)
	(segment
		(start 337.307174 -281.64155)
		(end 337.206336 -281.66822)
		(width 0.09525)
		(layer "In13.Cu")
		(net "M_B_CPU0_SB_DQS_DN<6>")
	)
	(segment
		(start 334.829658 -281.70124)
		(end 334.821276 -281.706066)
		(width 0.09525)
		(layer "In13.Cu")
		(net "M_B_CPU0_SB_DQS_DN<6>")
	)
	(segment
		(start 295.998138 -295.359074)
		(end 295.724072 -295.085008)
		(width 0.16002)
		(layer "In13.Cu")
		(net "M_B_CPU0_SB_DQS_DN<6>")
	)
	(segment
		(start 323.895974 -281.67203)
		(end 321.930522 -281.67203)
		(width 0.16002)
		(layer "In13.Cu")
		(net "M_B_CPU0_SB_DQS_DN<6>")
	)
	(segment
		(start 323.919596 -281.67203)
		(end 323.895974 -281.67203)
		(width 0.09525)
		(layer "In13.Cu")
		(net "M_B_CPU0_SB_DQS_DN<6>")
	)
	(arc
		(start 328.793602 -281.696922)
		(mid 328.504129 -281.649417)
		(end 328.2188 -281.717496)
		(width 0.09525)
		(layer "In13.Cu")
		(net "M_B_CPU0_SB_DQS_DN<6>")
	)
	(arc
		(start 329.752452 -281.70124)
		(mid 329.494569 -281.625863)
		(end 329.231244 -281.679142)
		(width 0.09525)
		(layer "In13.Cu")
		(net "M_B_CPU0_SB_DQS_DN<6>")
	)
	(arc
		(start 332.00975 -281.70124)
		(mid 331.825975 -281.752012)
		(end 331.640942 -281.706066)
		(width 0.09525)
		(layer "In13.Cu")
		(net "M_B_CPU0_SB_DQS_DN<6>")
	)
	(arc
		(start 331.069696 -281.70124)
		(mid 330.885921 -281.752012)
		(end 330.700888 -281.706066)
		(width 0.09525)
		(layer "In13.Cu")
		(net "M_B_CPU0_SB_DQS_DN<6>")
	)
	(arc
		(start 328.2188 -281.717496)
		(mid 328.061858 -281.751962)
		(end 327.904856 -281.71775)
		(width 0.09525)
		(layer "In13.Cu")
		(net "M_B_CPU0_SB_DQS_DN<6>")
	)
	(arc
		(start 331.63256 -281.70124)
		(mid 331.351128 -281.625485)
		(end 331.069696 -281.70124)
		(width 0.09525)
		(layer "In13.Cu")
		(net "M_B_CPU0_SB_DQS_DN<6>")
	)
	(arc
		(start 337.206336 -281.66822)
		(mid 337.196214 -281.664185)
		(end 337.186016 -281.660346)
		(width 0.09525)
		(layer "In13.Cu")
		(net "M_B_CPU0_SB_DQS_DN<6>")
	)
	(arc
		(start 335.392522 -281.70124)
		(mid 335.11109 -281.625485)
		(end 334.829658 -281.70124)
		(width 0.09525)
		(layer "In13.Cu")
		(net "M_B_CPU0_SB_DQS_DN<6>")
	)
	(arc
		(start 337.186016 -281.660346)
		(mid 336.943304 -281.627463)
		(end 336.709766 -281.70124)
		(width 0.09525)
		(layer "In13.Cu")
		(net "M_B_CPU0_SB_DQS_DN<6>")
	)
	(arc
		(start 333.881222 -281.706066)
		(mid 333.69619 -281.75198)
		(end 333.512414 -281.70124)
		(width 0.09525)
		(layer "In13.Cu")
		(net "M_B_CPU0_SB_DQS_DN<6>")
	)
	(arc
		(start 336.709766 -281.70124)
		(mid 336.525991 -281.752012)
		(end 336.340958 -281.706066)
		(width 0.09525)
		(layer "In13.Cu")
		(net "M_B_CPU0_SB_DQS_DN<6>")
	)
	(arc
		(start 329.231244 -281.679142)
		(mid 329.014231 -281.732546)
		(end 328.793602 -281.696922)
		(width 0.09525)
		(layer "In13.Cu")
		(net "M_B_CPU0_SB_DQS_DN<6>")
	)
	(arc
		(start 336.332576 -281.70124)
		(mid 336.051144 -281.625485)
		(end 335.769712 -281.70124)
		(width 0.09525)
		(layer "In13.Cu")
		(net "M_B_CPU0_SB_DQS_DN<6>")
	)
	(arc
		(start 332.94955 -281.70124)
		(mid 332.761082 -281.751917)
		(end 332.572614 -281.70124)
		(width 0.09525)
		(layer "In13.Cu")
		(net "M_B_CPU0_SB_DQS_DN<6>")
	)
	(arc
		(start 327.904856 -281.71775)
		(mid 327.513321 -281.587276)
		(end 327.102978 -281.543252)
		(width 0.09525)
		(layer "In13.Cu")
		(net "M_B_CPU0_SB_DQS_DN<6>")
	)
	(arc
		(start 334.452468 -281.70124)
		(mid 334.171036 -281.625485)
		(end 333.889604 -281.70124)
		(width 0.09525)
		(layer "In13.Cu")
		(net "M_B_CPU0_SB_DQS_DN<6>")
	)
	(arc
		(start 335.769712 -281.70124)
		(mid 335.585937 -281.752012)
		(end 335.400904 -281.706066)
		(width 0.09525)
		(layer "In13.Cu")
		(net "M_B_CPU0_SB_DQS_DN<6>")
	)
	(arc
		(start 332.572614 -281.70124)
		(mid 332.291182 -281.625485)
		(end 332.00975 -281.70124)
		(width 0.09525)
		(layer "In13.Cu")
		(net "M_B_CPU0_SB_DQS_DN<6>")
	)
	(arc
		(start 330.12126 -281.706066)
		(mid 329.936228 -281.75198)
		(end 329.752452 -281.70124)
		(width 0.09525)
		(layer "In13.Cu")
		(net "M_B_CPU0_SB_DQS_DN<6>")
	)
	(arc
		(start 334.821276 -281.706066)
		(mid 334.636244 -281.75198)
		(end 334.452468 -281.70124)
		(width 0.09525)
		(layer "In13.Cu")
		(net "M_B_CPU0_SB_DQS_DN<6>")
	)
	(arc
		(start 333.512414 -281.70124)
		(mid 333.230982 -281.625485)
		(end 332.94955 -281.70124)
		(width 0.09525)
		(layer "In13.Cu")
		(net "M_B_CPU0_SB_DQS_DN<6>")
	)
	(arc
		(start 330.692506 -281.70124)
		(mid 330.411074 -281.625485)
		(end 330.129642 -281.70124)
		(width 0.09525)
		(layer "In13.Cu")
		(net "M_B_CPU0_SB_DQS_DN<6>")
	)
	(arc
		(start 324.61581 -281.543252)
		(mid 324.569362 -281.552509)
		(end 324.529958 -281.578812)
		(width 0.09525)
		(layer "In13.Cu")
		(net "M_B_CPU0_SB_DQS_DN<6>")
	)
	(segment
		(start 337.92795 -276.250146)
		(end 337.461098 -276.516084)
		(width 0.12954)
		(layer "F.Cu")
		(net "M_B_CPU0_SB_DQS_DN<5>")
	)
	(segment
		(start 323.978778 -276.107652)
		(end 323.919596 -276.04847)
		(width 0.09525)
		(layer "In13.Cu")
		(net "M_B_CPU0_SB_DQS_DN<5>")
	)
	(segment
		(start 297.738546 -285.83001)
		(end 297.379644 -285.9786)
		(width 0.16002)
		(layer "In13.Cu")
		(net "M_B_CPU0_SB_DQS_DN<5>")
	)
	(segment
		(start 298.69765 -285.83001)
		(end 297.738546 -285.83001)
		(width 0.16002)
		(layer "In13.Cu")
		(net "M_B_CPU0_SB_DQS_DN<5>")
	)
	(segment
		(start 297.379644 -285.9786)
		(end 295.967658 -285.9786)
		(width 0.16002)
		(layer "In13.Cu")
		(net "M_B_CPU0_SB_DQS_DN<5>")
	)
	(segment
		(start 336.340958 -276.84603)
		(end 336.332576 -276.841204)
		(width 0.09525)
		(layer "In13.Cu")
		(net "M_B_CPU0_SB_DQS_DN<5>")
	)
	(segment
		(start 337.461098 -276.516084)
		(end 337.307174 -276.781514)
		(width 0.09525)
		(layer "In13.Cu")
		(net "M_B_CPU0_SB_DQS_DN<5>")
	)
	(segment
		(start 306.426616 -285.83001)
		(end 305.651154 -285.83001)
		(width 0.16002)
		(layer "In13.Cu")
		(net "M_B_CPU0_SB_DQS_DN<5>")
	)
	(segment
		(start 327.177654 -276.699472)
		(end 324.958964 -276.699472)
		(width 0.09525)
		(layer "In13.Cu")
		(net "M_B_CPU0_SB_DQS_DN<5>")
	)
	(segment
		(start 323.919596 -276.04847)
		(end 323.895974 -276.04847)
		(width 0.09525)
		(layer "In13.Cu")
		(net "M_B_CPU0_SB_DQS_DN<5>")
	)
	(segment
		(start 295.967658 -285.9786)
		(end 295.724072 -285.735014)
		(width 0.16002)
		(layer "In13.Cu")
		(net "M_B_CPU0_SB_DQS_DN<5>")
	)
	(segment
		(start 330.700888 -276.84603)
		(end 330.692506 -276.841204)
		(width 0.09525)
		(layer "In13.Cu")
		(net "M_B_CPU0_SB_DQS_DN<5>")
	)
	(segment
		(start 304.851054 -286.63011)
		(end 302.022002 -286.63011)
		(width 0.16002)
		(layer "In13.Cu")
		(net "M_B_CPU0_SB_DQS_DN<5>")
	)
	(segment
		(start 317.91529 -276.04847)
		(end 309.341012 -284.622748)
		(width 0.16002)
		(layer "In13.Cu")
		(net "M_B_CPU0_SB_DQS_DN<5>")
	)
	(segment
		(start 330.129642 -276.841204)
		(end 330.12126 -276.84603)
		(width 0.09525)
		(layer "In13.Cu")
		(net "M_B_CPU0_SB_DQS_DN<5>")
	)
	(segment
		(start 301.549816 -286.157924)
		(end 299.489368 -286.157924)
		(width 0.16002)
		(layer "In13.Cu")
		(net "M_B_CPU0_SB_DQS_DN<5>")
	)
	(segment
		(start 337.307174 -276.781514)
		(end 337.206336 -276.808184)
		(width 0.09525)
		(layer "In13.Cu")
		(net "M_B_CPU0_SB_DQS_DN<5>")
	)
	(segment
		(start 323.895974 -276.04847)
		(end 317.91529 -276.04847)
		(width 0.16002)
		(layer "In13.Cu")
		(net "M_B_CPU0_SB_DQS_DN<5>")
	)
	(segment
		(start 334.829658 -276.841204)
		(end 334.821276 -276.84603)
		(width 0.09525)
		(layer "In13.Cu")
		(net "M_B_CPU0_SB_DQS_DN<5>")
	)
	(segment
		(start 309.341012 -284.622748)
		(end 306.426616 -285.83001)
		(width 0.16002)
		(layer "In13.Cu")
		(net "M_B_CPU0_SB_DQS_DN<5>")
	)
	(segment
		(start 324.873112 -276.663912)
		(end 324.316852 -276.107652)
		(width 0.09525)
		(layer "In13.Cu")
		(net "M_B_CPU0_SB_DQS_DN<5>")
	)
	(segment
		(start 324.316852 -276.107652)
		(end 323.978778 -276.107652)
		(width 0.09525)
		(layer "In13.Cu")
		(net "M_B_CPU0_SB_DQS_DN<5>")
	)
	(segment
		(start 333.889604 -276.841204)
		(end 333.881222 -276.84603)
		(width 0.09525)
		(layer "In13.Cu")
		(net "M_B_CPU0_SB_DQS_DN<5>")
	)
	(segment
		(start 305.651154 -285.83001)
		(end 304.851054 -286.63011)
		(width 0.16002)
		(layer "In13.Cu")
		(net "M_B_CPU0_SB_DQS_DN<5>")
	)
	(segment
		(start 302.022002 -286.63011)
		(end 301.549816 -286.157924)
		(width 0.16002)
		(layer "In13.Cu")
		(net "M_B_CPU0_SB_DQS_DN<5>")
	)
	(segment
		(start 331.640942 -276.84603)
		(end 331.63256 -276.841204)
		(width 0.09525)
		(layer "In13.Cu")
		(net "M_B_CPU0_SB_DQS_DN<5>")
	)
	(segment
		(start 299.489368 -286.157924)
		(end 298.69765 -285.83001)
		(width 0.16002)
		(layer "In13.Cu")
		(net "M_B_CPU0_SB_DQS_DN<5>")
	)
	(segment
		(start 335.400904 -276.84603)
		(end 335.392522 -276.841204)
		(width 0.09525)
		(layer "In13.Cu")
		(net "M_B_CPU0_SB_DQS_DN<5>")
	)
	(arc
		(start 333.512414 -276.841204)
		(mid 333.230982 -276.765449)
		(end 332.94955 -276.841204)
		(width 0.09525)
		(layer "In13.Cu")
		(net "M_B_CPU0_SB_DQS_DN<5>")
	)
	(arc
		(start 335.392522 -276.841204)
		(mid 335.11109 -276.765449)
		(end 334.829658 -276.841204)
		(width 0.09525)
		(layer "In13.Cu")
		(net "M_B_CPU0_SB_DQS_DN<5>")
	)
	(arc
		(start 336.332576 -276.841204)
		(mid 336.051144 -276.765449)
		(end 335.769712 -276.841204)
		(width 0.09525)
		(layer "In13.Cu")
		(net "M_B_CPU0_SB_DQS_DN<5>")
	)
	(arc
		(start 334.452468 -276.841204)
		(mid 334.171036 -276.765449)
		(end 333.889604 -276.841204)
		(width 0.09525)
		(layer "In13.Cu")
		(net "M_B_CPU0_SB_DQS_DN<5>")
	)
	(arc
		(start 331.63256 -276.841204)
		(mid 331.351128 -276.765449)
		(end 331.069696 -276.841204)
		(width 0.09525)
		(layer "In13.Cu")
		(net "M_B_CPU0_SB_DQS_DN<5>")
	)
	(arc
		(start 330.12126 -276.84603)
		(mid 329.936228 -276.891944)
		(end 329.752452 -276.841204)
		(width 0.09525)
		(layer "In13.Cu")
		(net "M_B_CPU0_SB_DQS_DN<5>")
	)
	(arc
		(start 330.692506 -276.841204)
		(mid 330.411074 -276.765449)
		(end 330.129642 -276.841204)
		(width 0.09525)
		(layer "In13.Cu")
		(net "M_B_CPU0_SB_DQS_DN<5>")
	)
	(arc
		(start 335.769712 -276.841204)
		(mid 335.585937 -276.891976)
		(end 335.400904 -276.84603)
		(width 0.09525)
		(layer "In13.Cu")
		(net "M_B_CPU0_SB_DQS_DN<5>")
	)
	(arc
		(start 336.709766 -276.841204)
		(mid 336.525991 -276.891976)
		(end 336.340958 -276.84603)
		(width 0.09525)
		(layer "In13.Cu")
		(net "M_B_CPU0_SB_DQS_DN<5>")
	)
	(arc
		(start 337.206336 -276.808184)
		(mid 337.196214 -276.804149)
		(end 337.186016 -276.80031)
		(width 0.09525)
		(layer "In13.Cu")
		(net "M_B_CPU0_SB_DQS_DN<5>")
	)
	(arc
		(start 332.94955 -276.841204)
		(mid 332.761082 -276.891881)
		(end 332.572614 -276.841204)
		(width 0.09525)
		(layer "In13.Cu")
		(net "M_B_CPU0_SB_DQS_DN<5>")
	)
	(arc
		(start 327.904856 -276.857714)
		(mid 327.549782 -276.739407)
		(end 327.177654 -276.699472)
		(width 0.09525)
		(layer "In13.Cu")
		(net "M_B_CPU0_SB_DQS_DN<5>")
	)
	(arc
		(start 334.821276 -276.84603)
		(mid 334.636244 -276.891944)
		(end 334.452468 -276.841204)
		(width 0.09525)
		(layer "In13.Cu")
		(net "M_B_CPU0_SB_DQS_DN<5>")
	)
	(arc
		(start 324.958964 -276.699472)
		(mid 324.912516 -276.690215)
		(end 324.873112 -276.663912)
		(width 0.09525)
		(layer "In13.Cu")
		(net "M_B_CPU0_SB_DQS_DN<5>")
	)
	(arc
		(start 332.572614 -276.841204)
		(mid 332.291182 -276.765449)
		(end 332.00975 -276.841204)
		(width 0.09525)
		(layer "In13.Cu")
		(net "M_B_CPU0_SB_DQS_DN<5>")
	)
	(arc
		(start 328.2188 -276.85746)
		(mid 328.061858 -276.891926)
		(end 327.904856 -276.857714)
		(width 0.09525)
		(layer "In13.Cu")
		(net "M_B_CPU0_SB_DQS_DN<5>")
	)
	(arc
		(start 332.00975 -276.841204)
		(mid 331.825975 -276.891976)
		(end 331.640942 -276.84603)
		(width 0.09525)
		(layer "In13.Cu")
		(net "M_B_CPU0_SB_DQS_DN<5>")
	)
	(arc
		(start 331.069696 -276.841204)
		(mid 330.885921 -276.891976)
		(end 330.700888 -276.84603)
		(width 0.09525)
		(layer "In13.Cu")
		(net "M_B_CPU0_SB_DQS_DN<5>")
	)
	(arc
		(start 328.793602 -276.836886)
		(mid 328.504129 -276.789381)
		(end 328.2188 -276.85746)
		(width 0.09525)
		(layer "In13.Cu")
		(net "M_B_CPU0_SB_DQS_DN<5>")
	)
	(arc
		(start 329.752452 -276.841204)
		(mid 329.494569 -276.765827)
		(end 329.231244 -276.819106)
		(width 0.09525)
		(layer "In13.Cu")
		(net "M_B_CPU0_SB_DQS_DN<5>")
	)
	(arc
		(start 329.231244 -276.819106)
		(mid 329.014231 -276.87251)
		(end 328.793602 -276.836886)
		(width 0.09525)
		(layer "In13.Cu")
		(net "M_B_CPU0_SB_DQS_DN<5>")
	)
	(arc
		(start 333.881222 -276.84603)
		(mid 333.69619 -276.891944)
		(end 333.512414 -276.841204)
		(width 0.09525)
		(layer "In13.Cu")
		(net "M_B_CPU0_SB_DQS_DN<5>")
	)
	(arc
		(start 337.186016 -276.80031)
		(mid 336.943304 -276.767427)
		(end 336.709766 -276.841204)
		(width 0.09525)
		(layer "In13.Cu")
		(net "M_B_CPU0_SB_DQS_DN<5>")
	)
	(segment
		(start 337.92795 -271.39011)
		(end 337.461098 -271.656048)
		(width 0.12954)
		(layer "F.Cu")
		(net "M_B_CPU0_SB_DQS_DN<4>")
	)
	(segment
		(start 337.461098 -271.656048)
		(end 337.307174 -271.921478)
		(width 0.09525)
		(layer "In13.Cu")
		(net "M_B_CPU0_SB_DQS_DN<4>")
	)
	(segment
		(start 337.307174 -271.921478)
		(end 337.206336 -271.948148)
		(width 0.09525)
		(layer "In13.Cu")
		(net "M_B_CPU0_SB_DQS_DN<4>")
	)
	(segment
		(start 334.829658 -271.981168)
		(end 334.821276 -271.985994)
		(width 0.09525)
		(layer "In13.Cu")
		(net "M_B_CPU0_SB_DQS_DN<4>")
	)
	(segment
		(start 307.913024 -276.15515)
		(end 307.152548 -276.47011)
		(width 0.16002)
		(layer "In13.Cu")
		(net "M_B_CPU0_SB_DQS_DN<4>")
	)
	(segment
		(start 324.232778 -270.484092)
		(end 323.978778 -270.484092)
		(width 0.09525)
		(layer "In13.Cu")
		(net "M_B_CPU0_SB_DQS_DN<4>")
	)
	(segment
		(start 323.978778 -270.484092)
		(end 323.919596 -270.42491)
		(width 0.09525)
		(layer "In13.Cu")
		(net "M_B_CPU0_SB_DQS_DN<4>")
	)
	(segment
		(start 336.340958 -271.985994)
		(end 336.332576 -271.981168)
		(width 0.09525)
		(layer "In13.Cu")
		(net "M_B_CPU0_SB_DQS_DN<4>")
	)
	(segment
		(start 324.443598 -270.694912)
		(end 324.232778 -270.484092)
		(width 0.09525)
		(layer "In13.Cu")
		(net "M_B_CPU0_SB_DQS_DN<4>")
	)
	(segment
		(start 313.643264 -270.42491)
		(end 307.913024 -276.15515)
		(width 0.16002)
		(layer "In13.Cu")
		(net "M_B_CPU0_SB_DQS_DN<4>")
	)
	(segment
		(start 323.919596 -270.42491)
		(end 323.895974 -270.42491)
		(width 0.09525)
		(layer "In13.Cu")
		(net "M_B_CPU0_SB_DQS_DN<4>")
	)
	(segment
		(start 305.166268 -276.834854)
		(end 302.91278 -277.28291)
		(width 0.16002)
		(layer "In13.Cu")
		(net "M_B_CPU0_SB_DQS_DN<4>")
	)
	(segment
		(start 305.671982 -276.47011)
		(end 305.40706 -276.735032)
		(width 0.16002)
		(layer "In13.Cu")
		(net "M_B_CPU0_SB_DQS_DN<4>")
	)
	(segment
		(start 330.129642 -271.981168)
		(end 330.12126 -271.985994)
		(width 0.09525)
		(layer "In13.Cu")
		(net "M_B_CPU0_SB_DQS_DN<4>")
	)
	(segment
		(start 335.400904 -271.985994)
		(end 335.392522 -271.981168)
		(width 0.09525)
		(layer "In13.Cu")
		(net "M_B_CPU0_SB_DQS_DN<4>")
	)
	(segment
		(start 305.40706 -276.735032)
		(end 305.166268 -276.834854)
		(width 0.16002)
		(layer "In13.Cu")
		(net "M_B_CPU0_SB_DQS_DN<4>")
	)
	(segment
		(start 327.890124 -271.99082)
		(end 327.87336 -271.981168)
		(width 0.09525)
		(layer "In13.Cu")
		(net "M_B_CPU0_SB_DQS_DN<4>")
	)
	(segment
		(start 297.494452 -276.41931)
		(end 296.99077 -276.627844)
		(width 0.16002)
		(layer "In13.Cu")
		(net "M_B_CPU0_SB_DQS_DN<4>")
	)
	(segment
		(start 326.52335 -271.905984)
		(end 325.312278 -270.694912)
		(width 0.09525)
		(layer "In13.Cu")
		(net "M_B_CPU0_SB_DQS_DN<4>")
	)
	(segment
		(start 296.99077 -276.627844)
		(end 295.966896 -276.627844)
		(width 0.16002)
		(layer "In13.Cu")
		(net "M_B_CPU0_SB_DQS_DN<4>")
	)
	(segment
		(start 323.895974 -270.42491)
		(end 313.643264 -270.42491)
		(width 0.16002)
		(layer "In13.Cu")
		(net "M_B_CPU0_SB_DQS_DN<4>")
	)
	(segment
		(start 299.067474 -276.80793)
		(end 298.678854 -276.41931)
		(width 0.16002)
		(layer "In13.Cu")
		(net "M_B_CPU0_SB_DQS_DN<4>")
	)
	(segment
		(start 301.879254 -277.28291)
		(end 301.404274 -276.80793)
		(width 0.16002)
		(layer "In13.Cu")
		(net "M_B_CPU0_SB_DQS_DN<4>")
	)
	(segment
		(start 298.678854 -276.41931)
		(end 297.494452 -276.41931)
		(width 0.16002)
		(layer "In13.Cu")
		(net "M_B_CPU0_SB_DQS_DN<4>")
	)
	(segment
		(start 331.640942 -271.985994)
		(end 331.63256 -271.981168)
		(width 0.09525)
		(layer "In13.Cu")
		(net "M_B_CPU0_SB_DQS_DN<4>")
	)
	(segment
		(start 325.312278 -270.694912)
		(end 324.443598 -270.694912)
		(width 0.09525)
		(layer "In13.Cu")
		(net "M_B_CPU0_SB_DQS_DN<4>")
	)
	(segment
		(start 295.966896 -276.627844)
		(end 295.724072 -276.38502)
		(width 0.16002)
		(layer "In13.Cu")
		(net "M_B_CPU0_SB_DQS_DN<4>")
	)
	(segment
		(start 307.152548 -276.47011)
		(end 305.671982 -276.47011)
		(width 0.16002)
		(layer "In13.Cu")
		(net "M_B_CPU0_SB_DQS_DN<4>")
	)
	(segment
		(start 330.700888 -271.985994)
		(end 330.692506 -271.981168)
		(width 0.09525)
		(layer "In13.Cu")
		(net "M_B_CPU0_SB_DQS_DN<4>")
	)
	(segment
		(start 333.889604 -271.981168)
		(end 333.881222 -271.985994)
		(width 0.09525)
		(layer "In13.Cu")
		(net "M_B_CPU0_SB_DQS_DN<4>")
	)
	(segment
		(start 327.592944 -271.905984)
		(end 326.52335 -271.905984)
		(width 0.09525)
		(layer "In13.Cu")
		(net "M_B_CPU0_SB_DQS_DN<4>")
	)
	(segment
		(start 301.404274 -276.80793)
		(end 299.067474 -276.80793)
		(width 0.16002)
		(layer "In13.Cu")
		(net "M_B_CPU0_SB_DQS_DN<4>")
	)
	(segment
		(start 302.91278 -277.28291)
		(end 301.879254 -277.28291)
		(width 0.16002)
		(layer "In13.Cu")
		(net "M_B_CPU0_SB_DQS_DN<4>")
	)
	(arc
		(start 328.812652 -271.981168)
		(mid 328.53122 -271.905413)
		(end 328.249788 -271.981168)
		(width 0.09525)
		(layer "In13.Cu")
		(net "M_B_CPU0_SB_DQS_DN<4>")
	)
	(arc
		(start 336.709766 -271.981168)
		(mid 336.525991 -272.03194)
		(end 336.340958 -271.985994)
		(width 0.09525)
		(layer "In13.Cu")
		(net "M_B_CPU0_SB_DQS_DN<4>")
	)
	(arc
		(start 336.332576 -271.981168)
		(mid 336.051144 -271.905413)
		(end 335.769712 -271.981168)
		(width 0.09525)
		(layer "In13.Cu")
		(net "M_B_CPU0_SB_DQS_DN<4>")
	)
	(arc
		(start 331.069696 -271.981168)
		(mid 330.885921 -272.03194)
		(end 330.700888 -271.985994)
		(width 0.09525)
		(layer "In13.Cu")
		(net "M_B_CPU0_SB_DQS_DN<4>")
	)
	(arc
		(start 327.87336 -271.981168)
		(mid 327.738112 -271.925061)
		(end 327.592944 -271.905984)
		(width 0.09525)
		(layer "In13.Cu")
		(net "M_B_CPU0_SB_DQS_DN<4>")
	)
	(arc
		(start 330.692506 -271.981168)
		(mid 330.411074 -271.905413)
		(end 330.129642 -271.981168)
		(width 0.09525)
		(layer "In13.Cu")
		(net "M_B_CPU0_SB_DQS_DN<4>")
	)
	(arc
		(start 330.12126 -271.985994)
		(mid 329.936228 -272.031908)
		(end 329.752452 -271.981168)
		(width 0.09525)
		(layer "In13.Cu")
		(net "M_B_CPU0_SB_DQS_DN<4>")
	)
	(arc
		(start 337.186016 -271.940274)
		(mid 336.943304 -271.907391)
		(end 336.709766 -271.981168)
		(width 0.09525)
		(layer "In13.Cu")
		(net "M_B_CPU0_SB_DQS_DN<4>")
	)
	(arc
		(start 334.821276 -271.985994)
		(mid 334.636244 -272.031908)
		(end 334.452468 -271.981168)
		(width 0.09525)
		(layer "In13.Cu")
		(net "M_B_CPU0_SB_DQS_DN<4>")
	)
	(arc
		(start 329.752452 -271.981168)
		(mid 329.47102 -271.905413)
		(end 329.189588 -271.981168)
		(width 0.09525)
		(layer "In13.Cu")
		(net "M_B_CPU0_SB_DQS_DN<4>")
	)
	(arc
		(start 332.572614 -271.981168)
		(mid 332.291182 -271.905413)
		(end 332.00975 -271.981168)
		(width 0.09525)
		(layer "In13.Cu")
		(net "M_B_CPU0_SB_DQS_DN<4>")
	)
	(arc
		(start 337.206336 -271.948148)
		(mid 337.196214 -271.944113)
		(end 337.186016 -271.940274)
		(width 0.09525)
		(layer "In13.Cu")
		(net "M_B_CPU0_SB_DQS_DN<4>")
	)
	(arc
		(start 332.00975 -271.981168)
		(mid 331.825975 -272.03194)
		(end 331.640942 -271.985994)
		(width 0.09525)
		(layer "In13.Cu")
		(net "M_B_CPU0_SB_DQS_DN<4>")
	)
	(arc
		(start 328.249788 -271.981168)
		(mid 328.071182 -272.031836)
		(end 327.890124 -271.99082)
		(width 0.09525)
		(layer "In13.Cu")
		(net "M_B_CPU0_SB_DQS_DN<4>")
	)
	(arc
		(start 335.392522 -271.981168)
		(mid 335.11109 -271.905413)
		(end 334.829658 -271.981168)
		(width 0.09525)
		(layer "In13.Cu")
		(net "M_B_CPU0_SB_DQS_DN<4>")
	)
	(arc
		(start 335.769712 -271.981168)
		(mid 335.585937 -272.03194)
		(end 335.400904 -271.985994)
		(width 0.09525)
		(layer "In13.Cu")
		(net "M_B_CPU0_SB_DQS_DN<4>")
	)
	(arc
		(start 333.512414 -271.981168)
		(mid 333.230982 -271.905413)
		(end 332.94955 -271.981168)
		(width 0.09525)
		(layer "In13.Cu")
		(net "M_B_CPU0_SB_DQS_DN<4>")
	)
	(arc
		(start 332.94955 -271.981168)
		(mid 332.761082 -272.031845)
		(end 332.572614 -271.981168)
		(width 0.09525)
		(layer "In13.Cu")
		(net "M_B_CPU0_SB_DQS_DN<4>")
	)
	(arc
		(start 333.881222 -271.985994)
		(mid 333.69619 -272.031908)
		(end 333.512414 -271.981168)
		(width 0.09525)
		(layer "In13.Cu")
		(net "M_B_CPU0_SB_DQS_DN<4>")
	)
	(arc
		(start 331.63256 -271.981168)
		(mid 331.351128 -271.905413)
		(end 331.069696 -271.981168)
		(width 0.09525)
		(layer "In13.Cu")
		(net "M_B_CPU0_SB_DQS_DN<4>")
	)
	(arc
		(start 334.452468 -271.981168)
		(mid 334.171036 -271.905413)
		(end 333.889604 -271.981168)
		(width 0.09525)
		(layer "In13.Cu")
		(net "M_B_CPU0_SB_DQS_DN<4>")
	)
	(arc
		(start 329.189588 -271.981168)
		(mid 329.00112 -272.031845)
		(end 328.812652 -271.981168)
		(width 0.09525)
		(layer "In13.Cu")
		(net "M_B_CPU0_SB_DQS_DN<4>")
	)
	(segment
		(start 336.047842 -290.83)
		(end 335.58099 -291.095938)
		(width 0.12954)
		(layer "F.Cu")
		(net "M_B_CPU0_SB_DQS_DN<3>")
	)
	(segment
		(start 312.997596 -308.051962)
		(end 313.104276 -308.158642)
		(width 0.16002)
		(layer "In13.Cu")
		(net "M_B_CPU0_SB_DQS_DN<3>")
	)
	(segment
		(start 324.561708 -294.936672)
		(end 324.561708 -294.305228)
		(width 0.09525)
		(layer "In13.Cu")
		(net "M_B_CPU0_SB_DQS_DN<3>")
	)
	(segment
		(start 316.841886 -303.931066)
		(end 317.118492 -303.931066)
		(width 0.16002)
		(layer "In13.Cu")
		(net "M_B_CPU0_SB_DQS_DN<3>")
	)
	(segment
		(start 327.740772 -290.71951)
		(end 328.061066 -290.71951)
		(width 0.09525)
		(layer "In13.Cu")
		(net "M_B_CPU0_SB_DQS_DN<3>")
	)
	(segment
		(start 311.623964 -309.425594)
		(end 311.730644 -309.532274)
		(width 0.16002)
		(layer "In13.Cu")
		(net "M_B_CPU0_SB_DQS_DN<3>")
	)
	(segment
		(start 310.250332 -310.799226)
		(end 310.357012 -310.905906)
		(width 0.16002)
		(layer "In13.Cu")
		(net "M_B_CPU0_SB_DQS_DN<3>")
	)
	(segment
		(start 334.821276 -290.765992)
		(end 334.829658 -290.770818)
		(width 0.09525)
		(layer "In13.Cu")
		(net "M_B_CPU0_SB_DQS_DN<3>")
	)
	(segment
		(start 330.12126 -290.765992)
		(end 330.129642 -290.770818)
		(width 0.09525)
		(layer "In13.Cu")
		(net "M_B_CPU0_SB_DQS_DN<3>")
	)
	(segment
		(start 309.777892 -311.27192)
		(end 309.777892 -310.99506)
		(width 0.16002)
		(layer "In13.Cu")
		(net "M_B_CPU0_SB_DQS_DN<3>")
	)
	(segment
		(start 302.608996 -313.511184)
		(end 303.12741 -312.99277)
		(width 0.16002)
		(layer "In13.Cu")
		(net "M_B_CPU0_SB_DQS_DN<3>")
	)
	(segment
		(start 315.378846 -306.193952)
		(end 315.3791 -305.884072)
		(width 0.16002)
		(layer "In13.Cu")
		(net "M_B_CPU0_SB_DQS_DN<3>")
	)
	(segment
		(start 314.094622 -306.67833)
		(end 314.371228 -306.67833)
		(width 0.16002)
		(layer "In13.Cu")
		(net "M_B_CPU0_SB_DQS_DN<3>")
	)
	(segment
		(start 315.378846 -306.411376)
		(end 315.378846 -306.193952)
		(width 0.16002)
		(layer "In13.Cu")
		(net "M_B_CPU0_SB_DQS_DN<3>")
	)
	(segment
		(start 316.646052 -304.40376)
		(end 316.646052 -304.1269)
		(width 0.16002)
		(layer "In13.Cu")
		(net "M_B_CPU0_SB_DQS_DN<3>")
	)
	(segment
		(start 313.898788 -306.874164)
		(end 314.094622 -306.67833)
		(width 0.16002)
		(layer "In13.Cu")
		(net "M_B_CPU0_SB_DQS_DN<3>")
	)
	(segment
		(start 304.950876 -313.686952)
		(end 305.814476 -312.823352)
		(width 0.16002)
		(layer "In13.Cu")
		(net "M_B_CPU0_SB_DQS_DN<3>")
	)
	(segment
		(start 324.303136 -295.278302)
		(end 324.303136 -295.195498)
		(width 0.09525)
		(layer "In13.Cu")
		(net "M_B_CPU0_SB_DQS_DN<3>")
	)
	(segment
		(start 309.777892 -310.99506)
		(end 309.973726 -310.799226)
		(width 0.16002)
		(layer "In13.Cu")
		(net "M_B_CPU0_SB_DQS_DN<3>")
	)
	(segment
		(start 317.225172 -304.037746)
		(end 317.752476 -304.037746)
		(width 0.16002)
		(layer "In13.Cu")
		(net "M_B_CPU0_SB_DQS_DN<3>")
	)
	(segment
		(start 318.019684 -302.753268)
		(end 321.680078 -299.092874)
		(width 0.16002)
		(layer "In13.Cu")
		(net "M_B_CPU0_SB_DQS_DN<3>")
	)
	(segment
		(start 324.303136 -295.195498)
		(end 324.561708 -294.936672)
		(width 0.09525)
		(layer "In13.Cu")
		(net "M_B_CPU0_SB_DQS_DN<3>")
	)
	(segment
		(start 331.63256 -290.770818)
		(end 331.640942 -290.765992)
		(width 0.09525)
		(layer "In13.Cu")
		(net "M_B_CPU0_SB_DQS_DN<3>")
	)
	(segment
		(start 315.27242 -305.777392)
		(end 315.27242 -305.500532)
		(width 0.16002)
		(layer "In13.Cu")
		(net "M_B_CPU0_SB_DQS_DN<3>")
	)
	(segment
		(start 318.12611 -303.664112)
		(end 318.126364 -303.136808)
		(width 0.16002)
		(layer "In13.Cu")
		(net "M_B_CPU0_SB_DQS_DN<3>")
	)
	(segment
		(start 308.493414 -312.279538)
		(end 309.510684 -312.279538)
		(width 0.16002)
		(layer "In13.Cu")
		(net "M_B_CPU0_SB_DQS_DN<3>")
	)
	(segment
		(start 335.734914 -290.830508)
		(end 335.58099 -291.095938)
		(width 0.09525)
		(layer "In13.Cu")
		(net "M_B_CPU0_SB_DQS_DN<3>")
	)
	(segment
		(start 312.525156 -308.524656)
		(end 312.525156 -308.247796)
		(width 0.16002)
		(layer "In13.Cu")
		(net "M_B_CPU0_SB_DQS_DN<3>")
	)
	(segment
		(start 317.752476 -304.037746)
		(end 318.12611 -303.664112)
		(width 0.16002)
		(layer "In13.Cu")
		(net "M_B_CPU0_SB_DQS_DN<3>")
	)
	(segment
		(start 324.286372 -295.295066)
		(end 324.303136 -295.278302)
		(width 0.09525)
		(layer "In13.Cu")
		(net "M_B_CPU0_SB_DQS_DN<3>")
	)
	(segment
		(start 325.214996 -293.369238)
		(end 326.37603 -291.631624)
		(width 0.09525)
		(layer "In13.Cu")
		(net "M_B_CPU0_SB_DQS_DN<3>")
	)
	(segment
		(start 324.761606 -293.822628)
		(end 325.214996 -293.369238)
		(width 0.09525)
		(layer "In13.Cu")
		(net "M_B_CPU0_SB_DQS_DN<3>")
	)
	(segment
		(start 314.371228 -306.67833)
		(end 314.477908 -306.78501)
		(width 0.16002)
		(layer "In13.Cu")
		(net "M_B_CPU0_SB_DQS_DN<3>")
	)
	(segment
		(start 312.525156 -308.247796)
		(end 312.72099 -308.051962)
		(width 0.16002)
		(layer "In13.Cu")
		(net "M_B_CPU0_SB_DQS_DN<3>")
	)
	(segment
		(start 333.881222 -290.765992)
		(end 333.889604 -290.770818)
		(width 0.09525)
		(layer "In13.Cu")
		(net "M_B_CPU0_SB_DQS_DN<3>")
	)
	(segment
		(start 303.391062 -312.99277)
		(end 304.085244 -313.686952)
		(width 0.16002)
		(layer "In13.Cu")
		(net "M_B_CPU0_SB_DQS_DN<3>")
	)
	(segment
		(start 318.126364 -303.136808)
		(end 318.019684 -303.030128)
		(width 0.16002)
		(layer "In13.Cu")
		(net "M_B_CPU0_SB_DQS_DN<3>")
	)
	(segment
		(start 315.005212 -306.78501)
		(end 315.378846 -306.411376)
		(width 0.16002)
		(layer "In13.Cu")
		(net "M_B_CPU0_SB_DQS_DN<3>")
	)
	(segment
		(start 313.898788 -307.151024)
		(end 313.898788 -306.874164)
		(width 0.16002)
		(layer "In13.Cu")
		(net "M_B_CPU0_SB_DQS_DN<3>")
	)
	(segment
		(start 312.631836 -308.631336)
		(end 312.525156 -308.524656)
		(width 0.16002)
		(layer "In13.Cu")
		(net "M_B_CPU0_SB_DQS_DN<3>")
	)
	(segment
		(start 310.357012 -310.905906)
		(end 310.884316 -310.905906)
		(width 0.16002)
		(layer "In13.Cu")
		(net "M_B_CPU0_SB_DQS_DN<3>")
	)
	(segment
		(start 326.37603 -291.631624)
		(end 327.740772 -290.71951)
		(width 0.09525)
		(layer "In13.Cu")
		(net "M_B_CPU0_SB_DQS_DN<3>")
	)
	(segment
		(start 315.74486 -305.304698)
		(end 315.85154 -305.411378)
		(width 0.16002)
		(layer "In13.Cu")
		(net "M_B_CPU0_SB_DQS_DN<3>")
	)
	(segment
		(start 311.730644 -309.532274)
		(end 312.257948 -309.532274)
		(width 0.16002)
		(layer "In13.Cu")
		(net "M_B_CPU0_SB_DQS_DN<3>")
	)
	(segment
		(start 300.097952 -313.511184)
		(end 302.608996 -313.511184)
		(width 0.16002)
		(layer "In13.Cu")
		(net "M_B_CPU0_SB_DQS_DN<3>")
	)
	(segment
		(start 335.392522 -290.770818)
		(end 335.400904 -290.765992)
		(width 0.09525)
		(layer "In13.Cu")
		(net "M_B_CPU0_SB_DQS_DN<3>")
	)
	(segment
		(start 316.378844 -305.411378)
		(end 316.752478 -305.037744)
		(width 0.16002)
		(layer "In13.Cu")
		(net "M_B_CPU0_SB_DQS_DN<3>")
	)
	(segment
		(start 335.711546 -290.74364)
		(end 335.734914 -290.830508)
		(width 0.09525)
		(layer "In13.Cu")
		(net "M_B_CPU0_SB_DQS_DN<3>")
	)
	(segment
		(start 314.005214 -307.785008)
		(end 314.005468 -307.257704)
		(width 0.16002)
		(layer "In13.Cu")
		(net "M_B_CPU0_SB_DQS_DN<3>")
	)
	(segment
		(start 313.63158 -308.158642)
		(end 314.005214 -307.785008)
		(width 0.16002)
		(layer "In13.Cu")
		(net "M_B_CPU0_SB_DQS_DN<3>")
	)
	(segment
		(start 311.151524 -309.898288)
		(end 311.151524 -309.621428)
		(width 0.16002)
		(layer "In13.Cu")
		(net "M_B_CPU0_SB_DQS_DN<3>")
	)
	(segment
		(start 316.752732 -304.51044)
		(end 316.646052 -304.40376)
		(width 0.16002)
		(layer "In13.Cu")
		(net "M_B_CPU0_SB_DQS_DN<3>")
	)
	(segment
		(start 299.82414 -313.784996)
		(end 300.097952 -313.511184)
		(width 0.16002)
		(layer "In13.Cu")
		(net "M_B_CPU0_SB_DQS_DN<3>")
	)
	(segment
		(start 303.12741 -312.99277)
		(end 303.391062 -312.99277)
		(width 0.16002)
		(layer "In13.Cu")
		(net "M_B_CPU0_SB_DQS_DN<3>")
	)
	(segment
		(start 315.3791 -305.884072)
		(end 315.27242 -305.777392)
		(width 0.16002)
		(layer "In13.Cu")
		(net "M_B_CPU0_SB_DQS_DN<3>")
	)
	(segment
		(start 315.85154 -305.411378)
		(end 316.378844 -305.411378)
		(width 0.16002)
		(layer "In13.Cu")
		(net "M_B_CPU0_SB_DQS_DN<3>")
	)
	(segment
		(start 315.27242 -305.500532)
		(end 315.468254 -305.304698)
		(width 0.16002)
		(layer "In13.Cu")
		(net "M_B_CPU0_SB_DQS_DN<3>")
	)
	(segment
		(start 314.477908 -306.78501)
		(end 315.005212 -306.78501)
		(width 0.16002)
		(layer "In13.Cu")
		(net "M_B_CPU0_SB_DQS_DN<3>")
	)
	(segment
		(start 312.72099 -308.051962)
		(end 312.997596 -308.051962)
		(width 0.16002)
		(layer "In13.Cu")
		(net "M_B_CPU0_SB_DQS_DN<3>")
	)
	(segment
		(start 311.347358 -309.425594)
		(end 311.623964 -309.425594)
		(width 0.16002)
		(layer "In13.Cu")
		(net "M_B_CPU0_SB_DQS_DN<3>")
	)
	(segment
		(start 321.680078 -299.092874)
		(end 321.680078 -297.900852)
		(width 0.16002)
		(layer "In13.Cu")
		(net "M_B_CPU0_SB_DQS_DN<3>")
	)
	(segment
		(start 316.646052 -304.1269)
		(end 316.841886 -303.931066)
		(width 0.16002)
		(layer "In13.Cu")
		(net "M_B_CPU0_SB_DQS_DN<3>")
	)
	(segment
		(start 304.085244 -313.686952)
		(end 304.950876 -313.686952)
		(width 0.16002)
		(layer "In13.Cu")
		(net "M_B_CPU0_SB_DQS_DN<3>")
	)
	(segment
		(start 311.151524 -309.621428)
		(end 311.347358 -309.425594)
		(width 0.16002)
		(layer "In13.Cu")
		(net "M_B_CPU0_SB_DQS_DN<3>")
	)
	(segment
		(start 314.005468 -307.257704)
		(end 313.898788 -307.151024)
		(width 0.16002)
		(layer "In13.Cu")
		(net "M_B_CPU0_SB_DQS_DN<3>")
	)
	(segment
		(start 309.884318 -311.905904)
		(end 309.884572 -311.3786)
		(width 0.16002)
		(layer "In13.Cu")
		(net "M_B_CPU0_SB_DQS_DN<3>")
	)
	(segment
		(start 324.561708 -294.305228)
		(end 324.761606 -293.822628)
		(width 0.09525)
		(layer "In13.Cu")
		(net "M_B_CPU0_SB_DQS_DN<3>")
	)
	(segment
		(start 312.631582 -309.15864)
		(end 312.631836 -308.631336)
		(width 0.16002)
		(layer "In13.Cu")
		(net "M_B_CPU0_SB_DQS_DN<3>")
	)
	(segment
		(start 317.118492 -303.931066)
		(end 317.225172 -304.037746)
		(width 0.16002)
		(layer "In13.Cu")
		(net "M_B_CPU0_SB_DQS_DN<3>")
	)
	(segment
		(start 311.25795 -310.532272)
		(end 311.258204 -310.004968)
		(width 0.16002)
		(layer "In13.Cu")
		(net "M_B_CPU0_SB_DQS_DN<3>")
	)
	(segment
		(start 315.468254 -305.304698)
		(end 315.74486 -305.304698)
		(width 0.16002)
		(layer "In13.Cu")
		(net "M_B_CPU0_SB_DQS_DN<3>")
	)
	(segment
		(start 309.510684 -312.279538)
		(end 309.884318 -311.905904)
		(width 0.16002)
		(layer "In13.Cu")
		(net "M_B_CPU0_SB_DQS_DN<3>")
	)
	(segment
		(start 312.257948 -309.532274)
		(end 312.631582 -309.15864)
		(width 0.16002)
		(layer "In13.Cu")
		(net "M_B_CPU0_SB_DQS_DN<3>")
	)
	(segment
		(start 310.884316 -310.905906)
		(end 311.25795 -310.532272)
		(width 0.16002)
		(layer "In13.Cu")
		(net "M_B_CPU0_SB_DQS_DN<3>")
	)
	(segment
		(start 330.692506 -290.770818)
		(end 330.700888 -290.765992)
		(width 0.09525)
		(layer "In13.Cu")
		(net "M_B_CPU0_SB_DQS_DN<3>")
	)
	(segment
		(start 305.814476 -312.823352)
		(end 307.9496 -312.823352)
		(width 0.16002)
		(layer "In13.Cu")
		(net "M_B_CPU0_SB_DQS_DN<3>")
	)
	(segment
		(start 307.9496 -312.823352)
		(end 308.493414 -312.279538)
		(width 0.16002)
		(layer "In13.Cu")
		(net "M_B_CPU0_SB_DQS_DN<3>")
	)
	(segment
		(start 309.884572 -311.3786)
		(end 309.777892 -311.27192)
		(width 0.16002)
		(layer "In13.Cu")
		(net "M_B_CPU0_SB_DQS_DN<3>")
	)
	(segment
		(start 316.752478 -305.037744)
		(end 316.752732 -304.51044)
		(width 0.16002)
		(layer "In13.Cu")
		(net "M_B_CPU0_SB_DQS_DN<3>")
	)
	(segment
		(start 309.973726 -310.799226)
		(end 310.250332 -310.799226)
		(width 0.16002)
		(layer "In13.Cu")
		(net "M_B_CPU0_SB_DQS_DN<3>")
	)
	(segment
		(start 311.258204 -310.004968)
		(end 311.151524 -309.898288)
		(width 0.16002)
		(layer "In13.Cu")
		(net "M_B_CPU0_SB_DQS_DN<3>")
	)
	(segment
		(start 321.680078 -297.900852)
		(end 324.286372 -295.295066)
		(width 0.16002)
		(layer "In13.Cu")
		(net "M_B_CPU0_SB_DQS_DN<3>")
	)
	(segment
		(start 313.104276 -308.158642)
		(end 313.63158 -308.158642)
		(width 0.16002)
		(layer "In13.Cu")
		(net "M_B_CPU0_SB_DQS_DN<3>")
	)
	(segment
		(start 318.019684 -303.030128)
		(end 318.019684 -302.753268)
		(width 0.16002)
		(layer "In13.Cu")
		(net "M_B_CPU0_SB_DQS_DN<3>")
	)
	(arc
		(start 328.812652 -290.770818)
		(mid 329.00112 -290.720141)
		(end 329.189588 -290.770818)
		(width 0.09525)
		(layer "In13.Cu")
		(net "M_B_CPU0_SB_DQS_DN<3>")
	)
	(arc
		(start 329.752452 -290.770818)
		(mid 329.936227 -290.720046)
		(end 330.12126 -290.765992)
		(width 0.09525)
		(layer "In13.Cu")
		(net "M_B_CPU0_SB_DQS_DN<3>")
	)
	(arc
		(start 334.829658 -290.770818)
		(mid 335.11109 -290.846573)
		(end 335.392522 -290.770818)
		(width 0.09525)
		(layer "In13.Cu")
		(net "M_B_CPU0_SB_DQS_DN<3>")
	)
	(arc
		(start 328.249788 -290.770818)
		(mid 328.53122 -290.846573)
		(end 328.812652 -290.770818)
		(width 0.09525)
		(layer "In13.Cu")
		(net "M_B_CPU0_SB_DQS_DN<3>")
	)
	(arc
		(start 329.189588 -290.770818)
		(mid 329.47102 -290.846573)
		(end 329.752452 -290.770818)
		(width 0.09525)
		(layer "In13.Cu")
		(net "M_B_CPU0_SB_DQS_DN<3>")
	)
	(arc
		(start 332.94955 -290.770818)
		(mid 333.230982 -290.846573)
		(end 333.512414 -290.770818)
		(width 0.09525)
		(layer "In13.Cu")
		(net "M_B_CPU0_SB_DQS_DN<3>")
	)
	(arc
		(start 332.572614 -290.770818)
		(mid 332.761082 -290.720141)
		(end 332.94955 -290.770818)
		(width 0.09525)
		(layer "In13.Cu")
		(net "M_B_CPU0_SB_DQS_DN<3>")
	)
	(arc
		(start 328.061066 -290.71951)
		(mid 328.158812 -290.732705)
		(end 328.249788 -290.770818)
		(width 0.09525)
		(layer "In13.Cu")
		(net "M_B_CPU0_SB_DQS_DN<3>")
	)
	(arc
		(start 333.512414 -290.770818)
		(mid 333.696189 -290.720046)
		(end 333.881222 -290.765992)
		(width 0.09525)
		(layer "In13.Cu")
		(net "M_B_CPU0_SB_DQS_DN<3>")
	)
	(arc
		(start 335.400904 -290.765992)
		(mid 335.553799 -290.721164)
		(end 335.711546 -290.74364)
		(width 0.09525)
		(layer "In13.Cu")
		(net "M_B_CPU0_SB_DQS_DN<3>")
	)
	(arc
		(start 332.00975 -290.770818)
		(mid 332.291182 -290.846573)
		(end 332.572614 -290.770818)
		(width 0.09525)
		(layer "In13.Cu")
		(net "M_B_CPU0_SB_DQS_DN<3>")
	)
	(arc
		(start 333.889604 -290.770818)
		(mid 334.171036 -290.846573)
		(end 334.452468 -290.770818)
		(width 0.09525)
		(layer "In13.Cu")
		(net "M_B_CPU0_SB_DQS_DN<3>")
	)
	(arc
		(start 334.452468 -290.770818)
		(mid 334.636243 -290.720046)
		(end 334.821276 -290.765992)
		(width 0.09525)
		(layer "In13.Cu")
		(net "M_B_CPU0_SB_DQS_DN<3>")
	)
	(arc
		(start 331.069696 -290.770818)
		(mid 331.351128 -290.846573)
		(end 331.63256 -290.770818)
		(width 0.09525)
		(layer "In13.Cu")
		(net "M_B_CPU0_SB_DQS_DN<3>")
	)
	(arc
		(start 331.640942 -290.765992)
		(mid 331.825974 -290.720078)
		(end 332.00975 -290.770818)
		(width 0.09525)
		(layer "In13.Cu")
		(net "M_B_CPU0_SB_DQS_DN<3>")
	)
	(arc
		(start 330.700888 -290.765992)
		(mid 330.88592 -290.720078)
		(end 331.069696 -290.770818)
		(width 0.09525)
		(layer "In13.Cu")
		(net "M_B_CPU0_SB_DQS_DN<3>")
	)
	(arc
		(start 330.129642 -290.770818)
		(mid 330.411074 -290.846573)
		(end 330.692506 -290.770818)
		(width 0.09525)
		(layer "In13.Cu")
		(net "M_B_CPU0_SB_DQS_DN<3>")
	)
	(segment
		(start 336.047842 -285.970218)
		(end 335.58099 -286.236156)
		(width 0.12954)
		(layer "F.Cu")
		(net "M_B_CPU0_SB_DQS_DN<2>")
	)
	(segment
		(start 309.925974 -300.950122)
		(end 309.660798 -301.215298)
		(width 0.16002)
		(layer "In13.Cu")
		(net "M_B_CPU0_SB_DQS_DN<2>")
	)
	(segment
		(start 312.673238 -298.202858)
		(end 312.477404 -298.398692)
		(width 0.16002)
		(layer "In13.Cu")
		(net "M_B_CPU0_SB_DQS_DN<2>")
	)
	(segment
		(start 309.660798 -301.215298)
		(end 309.660798 -302.107854)
		(width 0.16002)
		(layer "In13.Cu")
		(net "M_B_CPU0_SB_DQS_DN<2>")
	)
	(segment
		(start 312.688732 -298.88688)
		(end 312.688478 -299.414184)
		(width 0.16002)
		(layer "In13.Cu")
		(net "M_B_CPU0_SB_DQS_DN<2>")
	)
	(segment
		(start 333.889604 -285.911036)
		(end 333.881222 -285.90621)
		(width 0.09525)
		(layer "In13.Cu")
		(net "M_B_CPU0_SB_DQS_DN<2>")
	)
	(segment
		(start 335.58099 -286.236156)
		(end 335.734914 -285.970726)
		(width 0.09525)
		(layer "In13.Cu")
		(net "M_B_CPU0_SB_DQS_DN<2>")
	)
	(segment
		(start 312.31459 -299.788072)
		(end 311.787794 -299.787818)
		(width 0.16002)
		(layer "In13.Cu")
		(net "M_B_CPU0_SB_DQS_DN<2>")
	)
	(segment
		(start 311.103772 -300.049184)
		(end 311.3151 -300.260512)
		(width 0.16002)
		(layer "In13.Cu")
		(net "M_B_CPU0_SB_DQS_DN<2>")
	)
	(segment
		(start 311.576466 -299.57649)
		(end 311.299606 -299.57649)
		(width 0.16002)
		(layer "In13.Cu")
		(net "M_B_CPU0_SB_DQS_DN<2>")
	)
	(segment
		(start 315.224668 -295.928288)
		(end 315.435996 -296.139616)
		(width 0.16002)
		(layer "In13.Cu")
		(net "M_B_CPU0_SB_DQS_DN<2>")
	)
	(segment
		(start 315.435742 -296.66692)
		(end 315.061854 -297.040808)
		(width 0.16002)
		(layer "In13.Cu")
		(net "M_B_CPU0_SB_DQS_DN<2>")
	)
	(segment
		(start 314.04687 -296.829226)
		(end 313.851036 -297.02506)
		(width 0.16002)
		(layer "In13.Cu")
		(net "M_B_CPU0_SB_DQS_DN<2>")
	)
	(segment
		(start 311.299606 -299.57649)
		(end 311.103772 -299.772324)
		(width 0.16002)
		(layer "In13.Cu")
		(net "M_B_CPU0_SB_DQS_DN<2>")
	)
	(segment
		(start 313.161426 -298.414186)
		(end 312.950098 -298.202858)
		(width 0.16002)
		(layer "In13.Cu")
		(net "M_B_CPU0_SB_DQS_DN<2>")
	)
	(segment
		(start 330.700888 -285.90621)
		(end 330.692506 -285.911036)
		(width 0.09525)
		(layer "In13.Cu")
		(net "M_B_CPU0_SB_DQS_DN<2>")
	)
	(segment
		(start 311.103772 -299.772324)
		(end 311.103772 -300.049184)
		(width 0.16002)
		(layer "In13.Cu")
		(net "M_B_CPU0_SB_DQS_DN<2>")
	)
	(segment
		(start 335.734914 -285.970726)
		(end 335.711546 -285.883858)
		(width 0.09525)
		(layer "In13.Cu")
		(net "M_B_CPU0_SB_DQS_DN<2>")
	)
	(segment
		(start 313.851036 -297.02506)
		(end 313.851036 -297.30192)
		(width 0.16002)
		(layer "In13.Cu")
		(net "M_B_CPU0_SB_DQS_DN<2>")
	)
	(segment
		(start 312.688478 -299.414184)
		(end 312.31459 -299.788072)
		(width 0.16002)
		(layer "In13.Cu")
		(net "M_B_CPU0_SB_DQS_DN<2>")
	)
	(segment
		(start 304.565304 -304.77587)
		(end 304.079656 -304.77587)
		(width 0.16002)
		(layer "In13.Cu")
		(net "M_B_CPU0_SB_DQS_DN<2>")
	)
	(segment
		(start 335.400904 -285.90621)
		(end 335.392522 -285.911036)
		(width 0.09525)
		(layer "In13.Cu")
		(net "M_B_CPU0_SB_DQS_DN<2>")
	)
	(segment
		(start 301.177706 -304.16119)
		(end 300.097952 -304.16119)
		(width 0.16002)
		(layer "In13.Cu")
		(net "M_B_CPU0_SB_DQS_DN<2>")
	)
	(segment
		(start 303.704752 -303.852326)
		(end 303.497996 -303.64557)
		(width 0.16002)
		(layer "In13.Cu")
		(net "M_B_CPU0_SB_DQS_DN<2>")
	)
	(segment
		(start 334.829658 -285.911036)
		(end 334.821276 -285.90621)
		(width 0.09525)
		(layer "In13.Cu")
		(net "M_B_CPU0_SB_DQS_DN<2>")
	)
	(segment
		(start 313.851036 -297.30192)
		(end 314.062364 -297.513248)
		(width 0.16002)
		(layer "In13.Cu")
		(net "M_B_CPU0_SB_DQS_DN<2>")
	)
	(segment
		(start 324.109588 -286.766508)
		(end 315.224668 -295.651428)
		(width 0.16002)
		(layer "In13.Cu")
		(net "M_B_CPU0_SB_DQS_DN<2>")
	)
	(segment
		(start 314.535058 -297.040554)
		(end 314.32373 -296.829226)
		(width 0.16002)
		(layer "In13.Cu")
		(net "M_B_CPU0_SB_DQS_DN<2>")
	)
	(segment
		(start 312.950098 -298.202858)
		(end 312.673238 -298.202858)
		(width 0.16002)
		(layer "In13.Cu")
		(net "M_B_CPU0_SB_DQS_DN<2>")
	)
	(segment
		(start 324.243446 -286.549592)
		(end 324.126098 -286.66694)
		(width 0.09525)
		(layer "In13.Cu")
		(net "M_B_CPU0_SB_DQS_DN<2>")
	)
	(segment
		(start 311.314846 -300.787816)
		(end 310.940958 -301.161704)
		(width 0.16002)
		(layer "In13.Cu")
		(net "M_B_CPU0_SB_DQS_DN<2>")
	)
	(segment
		(start 302.456088 -304.39487)
		(end 301.411386 -304.39487)
		(width 0.16002)
		(layer "In13.Cu")
		(net "M_B_CPU0_SB_DQS_DN<2>")
	)
	(segment
		(start 315.435996 -296.139616)
		(end 315.435742 -296.66692)
		(width 0.16002)
		(layer "In13.Cu")
		(net "M_B_CPU0_SB_DQS_DN<2>")
	)
	(segment
		(start 330.129642 -285.911036)
		(end 330.12126 -285.90621)
		(width 0.09525)
		(layer "In13.Cu")
		(net "M_B_CPU0_SB_DQS_DN<2>")
	)
	(segment
		(start 326.76084 -285.994094)
		(end 326.015096 -285.994094)
		(width 0.09525)
		(layer "In13.Cu")
		(net "M_B_CPU0_SB_DQS_DN<2>")
	)
	(segment
		(start 311.787794 -299.787818)
		(end 311.576466 -299.57649)
		(width 0.16002)
		(layer "In13.Cu")
		(net "M_B_CPU0_SB_DQS_DN<2>")
	)
	(segment
		(start 311.3151 -300.260512)
		(end 311.314846 -300.787816)
		(width 0.16002)
		(layer "In13.Cu")
		(net "M_B_CPU0_SB_DQS_DN<2>")
	)
	(segment
		(start 301.411386 -304.39487)
		(end 301.177706 -304.16119)
		(width 0.16002)
		(layer "In13.Cu")
		(net "M_B_CPU0_SB_DQS_DN<2>")
	)
	(segment
		(start 326.015096 -285.994094)
		(end 325.459598 -286.549592)
		(width 0.09525)
		(layer "In13.Cu")
		(net "M_B_CPU0_SB_DQS_DN<2>")
	)
	(segment
		(start 310.202834 -300.950122)
		(end 309.925974 -300.950122)
		(width 0.16002)
		(layer "In13.Cu")
		(net "M_B_CPU0_SB_DQS_DN<2>")
	)
	(segment
		(start 326.977248 -285.889446)
		(end 326.76846 -285.986474)
		(width 0.09525)
		(layer "In13.Cu")
		(net "M_B_CPU0_SB_DQS_DN<2>")
	)
	(segment
		(start 326.76846 -285.986474)
		(end 326.76084 -285.994094)
		(width 0.09525)
		(layer "In13.Cu")
		(net "M_B_CPU0_SB_DQS_DN<2>")
	)
	(segment
		(start 314.062364 -297.513248)
		(end 314.06211 -298.040552)
		(width 0.16002)
		(layer "In13.Cu")
		(net "M_B_CPU0_SB_DQS_DN<2>")
	)
	(segment
		(start 303.205388 -303.64557)
		(end 302.456088 -304.39487)
		(width 0.16002)
		(layer "In13.Cu")
		(net "M_B_CPU0_SB_DQS_DN<2>")
	)
	(segment
		(start 315.224668 -295.651428)
		(end 315.224668 -295.928288)
		(width 0.16002)
		(layer "In13.Cu")
		(net "M_B_CPU0_SB_DQS_DN<2>")
	)
	(segment
		(start 312.477404 -298.675552)
		(end 312.688732 -298.88688)
		(width 0.16002)
		(layer "In13.Cu")
		(net "M_B_CPU0_SB_DQS_DN<2>")
	)
	(segment
		(start 327.872344 -285.911036)
		(end 327.794112 -285.956502)
		(width 0.09525)
		(layer "In13.Cu")
		(net "M_B_CPU0_SB_DQS_DN<2>")
	)
	(segment
		(start 304.079656 -304.77587)
		(end 303.704752 -304.400966)
		(width 0.16002)
		(layer "In13.Cu")
		(net "M_B_CPU0_SB_DQS_DN<2>")
	)
	(segment
		(start 310.940958 -301.161704)
		(end 310.414162 -301.16145)
		(width 0.16002)
		(layer "In13.Cu")
		(net "M_B_CPU0_SB_DQS_DN<2>")
	)
	(segment
		(start 325.459598 -286.549592)
		(end 324.243446 -286.549592)
		(width 0.09525)
		(layer "In13.Cu")
		(net "M_B_CPU0_SB_DQS_DN<2>")
	)
	(segment
		(start 310.414162 -301.16145)
		(end 310.202834 -300.950122)
		(width 0.16002)
		(layer "In13.Cu")
		(net "M_B_CPU0_SB_DQS_DN<2>")
	)
	(segment
		(start 303.497996 -303.64557)
		(end 303.205388 -303.64557)
		(width 0.16002)
		(layer "In13.Cu")
		(net "M_B_CPU0_SB_DQS_DN<2>")
	)
	(segment
		(start 308.295294 -303.473358)
		(end 305.867816 -303.473358)
		(width 0.16002)
		(layer "In13.Cu")
		(net "M_B_CPU0_SB_DQS_DN<2>")
	)
	(segment
		(start 314.32373 -296.829226)
		(end 314.04687 -296.829226)
		(width 0.16002)
		(layer "In13.Cu")
		(net "M_B_CPU0_SB_DQS_DN<2>")
	)
	(segment
		(start 324.126352 -286.749744)
		(end 324.109588 -286.766508)
		(width 0.09525)
		(layer "In13.Cu")
		(net "M_B_CPU0_SB_DQS_DN<2>")
	)
	(segment
		(start 312.477404 -298.398692)
		(end 312.477404 -298.675552)
		(width 0.16002)
		(layer "In13.Cu")
		(net "M_B_CPU0_SB_DQS_DN<2>")
	)
	(segment
		(start 331.640942 -285.90621)
		(end 331.63256 -285.911036)
		(width 0.09525)
		(layer "In13.Cu")
		(net "M_B_CPU0_SB_DQS_DN<2>")
	)
	(segment
		(start 300.097952 -304.16119)
		(end 299.82414 -304.435002)
		(width 0.16002)
		(layer "In13.Cu")
		(net "M_B_CPU0_SB_DQS_DN<2>")
	)
	(segment
		(start 324.126098 -286.66694)
		(end 324.126352 -286.749744)
		(width 0.09525)
		(layer "In13.Cu")
		(net "M_B_CPU0_SB_DQS_DN<2>")
	)
	(segment
		(start 305.867816 -303.473358)
		(end 304.565304 -304.77587)
		(width 0.16002)
		(layer "In13.Cu")
		(net "M_B_CPU0_SB_DQS_DN<2>")
	)
	(segment
		(start 315.061854 -297.040808)
		(end 314.535058 -297.040554)
		(width 0.16002)
		(layer "In13.Cu")
		(net "M_B_CPU0_SB_DQS_DN<2>")
	)
	(segment
		(start 309.660798 -302.107854)
		(end 308.295294 -303.473358)
		(width 0.16002)
		(layer "In13.Cu")
		(net "M_B_CPU0_SB_DQS_DN<2>")
	)
	(segment
		(start 313.688222 -298.41444)
		(end 313.161426 -298.414186)
		(width 0.16002)
		(layer "In13.Cu")
		(net "M_B_CPU0_SB_DQS_DN<2>")
	)
	(segment
		(start 303.704752 -304.400966)
		(end 303.704752 -303.852326)
		(width 0.16002)
		(layer "In13.Cu")
		(net "M_B_CPU0_SB_DQS_DN<2>")
	)
	(segment
		(start 314.06211 -298.040552)
		(end 313.688222 -298.41444)
		(width 0.16002)
		(layer "In13.Cu")
		(net "M_B_CPU0_SB_DQS_DN<2>")
	)
	(arc
		(start 329.752452 -285.911036)
		(mid 329.47102 -285.986791)
		(end 329.189588 -285.911036)
		(width 0.09525)
		(layer "In13.Cu")
		(net "M_B_CPU0_SB_DQS_DN<2>")
	)
	(arc
		(start 327.304654 -285.916878)
		(mid 327.144045 -285.866317)
		(end 326.977248 -285.889446)
		(width 0.09525)
		(layer "In13.Cu")
		(net "M_B_CPU0_SB_DQS_DN<2>")
	)
	(arc
		(start 335.711546 -285.883858)
		(mid 335.553796 -285.861339)
		(end 335.400904 -285.90621)
		(width 0.09525)
		(layer "In13.Cu")
		(net "M_B_CPU0_SB_DQS_DN<2>")
	)
	(arc
		(start 328.249788 -285.911036)
		(mid 328.061066 -285.860232)
		(end 327.872344 -285.911036)
		(width 0.09525)
		(layer "In13.Cu")
		(net "M_B_CPU0_SB_DQS_DN<2>")
	)
	(arc
		(start 327.794112 -285.956502)
		(mid 327.544872 -285.992339)
		(end 327.304654 -285.916878)
		(width 0.09525)
		(layer "In13.Cu")
		(net "M_B_CPU0_SB_DQS_DN<2>")
	)
	(arc
		(start 332.94955 -285.911036)
		(mid 332.761082 -285.860359)
		(end 332.572614 -285.911036)
		(width 0.09525)
		(layer "In13.Cu")
		(net "M_B_CPU0_SB_DQS_DN<2>")
	)
	(arc
		(start 330.692506 -285.911036)
		(mid 330.411074 -285.986791)
		(end 330.129642 -285.911036)
		(width 0.09525)
		(layer "In13.Cu")
		(net "M_B_CPU0_SB_DQS_DN<2>")
	)
	(arc
		(start 333.881222 -285.90621)
		(mid 333.69619 -285.860296)
		(end 333.512414 -285.911036)
		(width 0.09525)
		(layer "In13.Cu")
		(net "M_B_CPU0_SB_DQS_DN<2>")
	)
	(arc
		(start 331.069696 -285.911036)
		(mid 330.885921 -285.860264)
		(end 330.700888 -285.90621)
		(width 0.09525)
		(layer "In13.Cu")
		(net "M_B_CPU0_SB_DQS_DN<2>")
	)
	(arc
		(start 334.452468 -285.911036)
		(mid 334.171036 -285.986791)
		(end 333.889604 -285.911036)
		(width 0.09525)
		(layer "In13.Cu")
		(net "M_B_CPU0_SB_DQS_DN<2>")
	)
	(arc
		(start 333.512414 -285.911036)
		(mid 333.230982 -285.986791)
		(end 332.94955 -285.911036)
		(width 0.09525)
		(layer "In13.Cu")
		(net "M_B_CPU0_SB_DQS_DN<2>")
	)
	(arc
		(start 332.00975 -285.911036)
		(mid 331.825975 -285.860264)
		(end 331.640942 -285.90621)
		(width 0.09525)
		(layer "In13.Cu")
		(net "M_B_CPU0_SB_DQS_DN<2>")
	)
	(arc
		(start 330.12126 -285.90621)
		(mid 329.936228 -285.860296)
		(end 329.752452 -285.911036)
		(width 0.09525)
		(layer "In13.Cu")
		(net "M_B_CPU0_SB_DQS_DN<2>")
	)
	(arc
		(start 331.63256 -285.911036)
		(mid 331.351128 -285.986791)
		(end 331.069696 -285.911036)
		(width 0.09525)
		(layer "In13.Cu")
		(net "M_B_CPU0_SB_DQS_DN<2>")
	)
	(arc
		(start 329.189588 -285.911036)
		(mid 329.00112 -285.860359)
		(end 328.812652 -285.911036)
		(width 0.09525)
		(layer "In13.Cu")
		(net "M_B_CPU0_SB_DQS_DN<2>")
	)
	(arc
		(start 334.821276 -285.90621)
		(mid 334.636244 -285.860296)
		(end 334.452468 -285.911036)
		(width 0.09525)
		(layer "In13.Cu")
		(net "M_B_CPU0_SB_DQS_DN<2>")
	)
	(arc
		(start 335.392522 -285.911036)
		(mid 335.11109 -285.986791)
		(end 334.829658 -285.911036)
		(width 0.09525)
		(layer "In13.Cu")
		(net "M_B_CPU0_SB_DQS_DN<2>")
	)
	(arc
		(start 328.812652 -285.911036)
		(mid 328.53122 -285.986791)
		(end 328.249788 -285.911036)
		(width 0.09525)
		(layer "In13.Cu")
		(net "M_B_CPU0_SB_DQS_DN<2>")
	)
	(arc
		(start 332.572614 -285.911036)
		(mid 332.291182 -285.986791)
		(end 332.00975 -285.911036)
		(width 0.09525)
		(layer "In13.Cu")
		(net "M_B_CPU0_SB_DQS_DN<2>")
	)
	(segment
		(start 336.047842 -281.110182)
		(end 335.58099 -281.37612)
		(width 0.12954)
		(layer "F.Cu")
		(net "M_B_CPU0_SB_DQS_DN<1>")
	)
	(segment
		(start 314.86348 -287.410652)
		(end 314.68441 -287.231582)
		(width 0.16002)
		(layer "In13.Cu")
		(net "M_B_CPU0_SB_DQS_DN<1>")
	)
	(segment
		(start 318.33185 -283.584142)
		(end 318.51092 -283.763212)
		(width 0.16002)
		(layer "In13.Cu")
		(net "M_B_CPU0_SB_DQS_DN<1>")
	)
	(segment
		(start 324.79869 -280.719784)
		(end 324.49516 -281.023314)
		(width 0.09525)
		(layer "In13.Cu")
		(net "M_B_CPU0_SB_DQS_DN<1>")
	)
	(segment
		(start 320.885312 -281.916124)
		(end 320.358008 -281.916124)
		(width 0.16002)
		(layer "In13.Cu")
		(net "M_B_CPU0_SB_DQS_DN<1>")
	)
	(segment
		(start 318.984376 -283.289756)
		(end 318.805306 -283.110686)
		(width 0.16002)
		(layer "In13.Cu")
		(net "M_B_CPU0_SB_DQS_DN<1>")
	)
	(segment
		(start 316.958218 -284.957774)
		(end 317.137288 -285.136844)
		(width 0.16002)
		(layer "In13.Cu")
		(net "M_B_CPU0_SB_DQS_DN<1>")
	)
	(segment
		(start 335.400904 -281.046174)
		(end 335.392522 -281.051)
		(width 0.09525)
		(layer "In13.Cu")
		(net "M_B_CPU0_SB_DQS_DN<1>")
	)
	(segment
		(start 334.829658 -281.051)
		(end 334.821276 -281.046174)
		(width 0.09525)
		(layer "In13.Cu")
		(net "M_B_CPU0_SB_DQS_DN<1>")
	)
	(segment
		(start 318.33185 -283.307282)
		(end 318.33185 -283.584142)
		(width 0.16002)
		(layer "In13.Cu")
		(net "M_B_CPU0_SB_DQS_DN<1>")
	)
	(segment
		(start 301.912782 -294.804338)
		(end 300.10481 -294.804338)
		(width 0.16002)
		(layer "In13.Cu")
		(net "M_B_CPU0_SB_DQS_DN<1>")
	)
	(segment
		(start 330.700888 -281.046174)
		(end 330.692506 -281.051)
		(width 0.09525)
		(layer "In13.Cu")
		(net "M_B_CPU0_SB_DQS_DN<1>")
	)
	(segment
		(start 319.902078 -281.737054)
		(end 319.705482 -281.93365)
		(width 0.16002)
		(layer "In13.Cu")
		(net "M_B_CPU0_SB_DQS_DN<1>")
	)
	(segment
		(start 315.584586 -286.054546)
		(end 315.584586 -286.331406)
		(width 0.16002)
		(layer "In13.Cu")
		(net "M_B_CPU0_SB_DQS_DN<1>")
	)
	(segment
		(start 314.68441 -287.231582)
		(end 314.40755 -287.231582)
		(width 0.16002)
		(layer "In13.Cu")
		(net "M_B_CPU0_SB_DQS_DN<1>")
	)
	(segment
		(start 326.33666 -281.04846)
		(end 325.149972 -280.73223)
		(width 0.09525)
		(layer "In13.Cu")
		(net "M_B_CPU0_SB_DQS_DN<1>")
	)
	(segment
		(start 321.719194 -281.082242)
		(end 320.885312 -281.916124)
		(width 0.16002)
		(layer "In13.Cu")
		(net "M_B_CPU0_SB_DQS_DN<1>")
	)
	(segment
		(start 324.095364 -281.082242)
		(end 324.071742 -281.082242)
		(width 0.09525)
		(layer "In13.Cu")
		(net "M_B_CPU0_SB_DQS_DN<1>")
	)
	(segment
		(start 319.884552 -282.38958)
		(end 319.884552 -282.916884)
		(width 0.16002)
		(layer "In13.Cu")
		(net "M_B_CPU0_SB_DQS_DN<1>")
	)
	(segment
		(start 302.095408 -294.986964)
		(end 301.912782 -294.804338)
		(width 0.16002)
		(layer "In13.Cu")
		(net "M_B_CPU0_SB_DQS_DN<1>")
	)
	(segment
		(start 315.781182 -285.85795)
		(end 315.584586 -286.054546)
		(width 0.16002)
		(layer "In13.Cu")
		(net "M_B_CPU0_SB_DQS_DN<1>")
	)
	(segment
		(start 317.137288 -285.664148)
		(end 316.764416 -286.03702)
		(width 0.16002)
		(layer "In13.Cu")
		(net "M_B_CPU0_SB_DQS_DN<1>")
	)
	(segment
		(start 319.705482 -281.93365)
		(end 319.705482 -282.21051)
		(width 0.16002)
		(layer "In13.Cu")
		(net "M_B_CPU0_SB_DQS_DN<1>")
	)
	(segment
		(start 315.584586 -286.331406)
		(end 315.763656 -286.510476)
		(width 0.16002)
		(layer "In13.Cu")
		(net "M_B_CPU0_SB_DQS_DN<1>")
	)
	(segment
		(start 316.237112 -286.03702)
		(end 316.058042 -285.85795)
		(width 0.16002)
		(layer "In13.Cu")
		(net "M_B_CPU0_SB_DQS_DN<1>")
	)
	(segment
		(start 319.884552 -282.916884)
		(end 319.51168 -283.289756)
		(width 0.16002)
		(layer "In13.Cu")
		(net "M_B_CPU0_SB_DQS_DN<1>")
	)
	(segment
		(start 315.763656 -287.03778)
		(end 315.390784 -287.410652)
		(width 0.16002)
		(layer "In13.Cu")
		(net "M_B_CPU0_SB_DQS_DN<1>")
	)
	(segment
		(start 316.958218 -284.680914)
		(end 316.958218 -284.957774)
		(width 0.16002)
		(layer "In13.Cu")
		(net "M_B_CPU0_SB_DQS_DN<1>")
	)
	(segment
		(start 314.210954 -287.428178)
		(end 314.210954 -287.705038)
		(width 0.16002)
		(layer "In13.Cu")
		(net "M_B_CPU0_SB_DQS_DN<1>")
	)
	(segment
		(start 325.055738 -280.719784)
		(end 324.79869 -280.719784)
		(width 0.09525)
		(layer "In13.Cu")
		(net "M_B_CPU0_SB_DQS_DN<1>")
	)
	(segment
		(start 320.178938 -281.737054)
		(end 319.902078 -281.737054)
		(width 0.16002)
		(layer "In13.Cu")
		(net "M_B_CPU0_SB_DQS_DN<1>")
	)
	(segment
		(start 319.705482 -282.21051)
		(end 319.884552 -282.38958)
		(width 0.16002)
		(layer "In13.Cu")
		(net "M_B_CPU0_SB_DQS_DN<1>")
	)
	(segment
		(start 324.071742 -281.082242)
		(end 321.719194 -281.082242)
		(width 0.16002)
		(layer "In13.Cu")
		(net "M_B_CPU0_SB_DQS_DN<1>")
	)
	(segment
		(start 319.51168 -283.289756)
		(end 318.984376 -283.289756)
		(width 0.16002)
		(layer "In13.Cu")
		(net "M_B_CPU0_SB_DQS_DN<1>")
	)
	(segment
		(start 304.950876 -294.986964)
		(end 302.095408 -294.986964)
		(width 0.16002)
		(layer "In13.Cu")
		(net "M_B_CPU0_SB_DQS_DN<1>")
	)
	(segment
		(start 320.358008 -281.916124)
		(end 320.178938 -281.737054)
		(width 0.16002)
		(layer "In13.Cu")
		(net "M_B_CPU0_SB_DQS_DN<1>")
	)
	(segment
		(start 316.058042 -285.85795)
		(end 315.781182 -285.85795)
		(width 0.16002)
		(layer "In13.Cu")
		(net "M_B_CPU0_SB_DQS_DN<1>")
	)
	(segment
		(start 331.640942 -281.046174)
		(end 331.63256 -281.051)
		(width 0.09525)
		(layer "In13.Cu")
		(net "M_B_CPU0_SB_DQS_DN<1>")
	)
	(segment
		(start 314.390024 -287.884108)
		(end 314.390024 -288.411412)
		(width 0.16002)
		(layer "In13.Cu")
		(net "M_B_CPU0_SB_DQS_DN<1>")
	)
	(segment
		(start 333.889604 -281.051)
		(end 333.881222 -281.046174)
		(width 0.09525)
		(layer "In13.Cu")
		(net "M_B_CPU0_SB_DQS_DN<1>")
	)
	(segment
		(start 327.31964 -281.057096)
		(end 327.309226 -281.051)
		(width 0.09525)
		(layer "In13.Cu")
		(net "M_B_CPU0_SB_DQS_DN<1>")
	)
	(segment
		(start 300.10481 -294.804338)
		(end 299.82414 -295.085008)
		(width 0.16002)
		(layer "In13.Cu")
		(net "M_B_CPU0_SB_DQS_DN<1>")
	)
	(segment
		(start 314.390024 -288.411412)
		(end 308.678072 -294.123364)
		(width 0.16002)
		(layer "In13.Cu")
		(net "M_B_CPU0_SB_DQS_DN<1>")
	)
	(segment
		(start 318.138048 -284.663388)
		(end 317.610744 -284.663388)
		(width 0.16002)
		(layer "In13.Cu")
		(net "M_B_CPU0_SB_DQS_DN<1>")
	)
	(segment
		(start 324.154292 -281.023314)
		(end 324.095364 -281.082242)
		(width 0.09525)
		(layer "In13.Cu")
		(net "M_B_CPU0_SB_DQS_DN<1>")
	)
	(segment
		(start 335.734914 -281.11069)
		(end 335.711546 -281.023822)
		(width 0.09525)
		(layer "In13.Cu")
		(net "M_B_CPU0_SB_DQS_DN<1>")
	)
	(segment
		(start 326.93229 -281.051)
		(end 326.91832 -281.059128)
		(width 0.09525)
		(layer "In13.Cu")
		(net "M_B_CPU0_SB_DQS_DN<1>")
	)
	(segment
		(start 318.805306 -283.110686)
		(end 318.528446 -283.110686)
		(width 0.16002)
		(layer "In13.Cu")
		(net "M_B_CPU0_SB_DQS_DN<1>")
	)
	(segment
		(start 335.58099 -281.37612)
		(end 335.734914 -281.11069)
		(width 0.09525)
		(layer "In13.Cu")
		(net "M_B_CPU0_SB_DQS_DN<1>")
	)
	(segment
		(start 308.678072 -294.123364)
		(end 305.814476 -294.123364)
		(width 0.16002)
		(layer "In13.Cu")
		(net "M_B_CPU0_SB_DQS_DN<1>")
	)
	(segment
		(start 318.528446 -283.110686)
		(end 318.33185 -283.307282)
		(width 0.16002)
		(layer "In13.Cu")
		(net "M_B_CPU0_SB_DQS_DN<1>")
	)
	(segment
		(start 326.91832 -281.059128)
		(end 326.917558 -281.059636)
		(width 0.09525)
		(layer "In13.Cu")
		(net "M_B_CPU0_SB_DQS_DN<1>")
	)
	(segment
		(start 330.129642 -281.051)
		(end 330.12126 -281.046174)
		(width 0.09525)
		(layer "In13.Cu")
		(net "M_B_CPU0_SB_DQS_DN<1>")
	)
	(segment
		(start 324.49516 -281.023314)
		(end 324.154292 -281.023314)
		(width 0.09525)
		(layer "In13.Cu")
		(net "M_B_CPU0_SB_DQS_DN<1>")
	)
	(segment
		(start 314.40755 -287.231582)
		(end 314.210954 -287.428178)
		(width 0.16002)
		(layer "In13.Cu")
		(net "M_B_CPU0_SB_DQS_DN<1>")
	)
	(segment
		(start 315.390784 -287.410652)
		(end 314.86348 -287.410652)
		(width 0.16002)
		(layer "In13.Cu")
		(net "M_B_CPU0_SB_DQS_DN<1>")
	)
	(segment
		(start 318.51092 -284.290516)
		(end 318.138048 -284.663388)
		(width 0.16002)
		(layer "In13.Cu")
		(net "M_B_CPU0_SB_DQS_DN<1>")
	)
	(segment
		(start 318.51092 -283.763212)
		(end 318.51092 -284.290516)
		(width 0.16002)
		(layer "In13.Cu")
		(net "M_B_CPU0_SB_DQS_DN<1>")
	)
	(segment
		(start 317.154814 -284.484318)
		(end 316.958218 -284.680914)
		(width 0.16002)
		(layer "In13.Cu")
		(net "M_B_CPU0_SB_DQS_DN<1>")
	)
	(segment
		(start 317.610744 -284.663388)
		(end 317.431674 -284.484318)
		(width 0.16002)
		(layer "In13.Cu")
		(net "M_B_CPU0_SB_DQS_DN<1>")
	)
	(segment
		(start 326.944228 -281.044142)
		(end 326.93229 -281.051)
		(width 0.09525)
		(layer "In13.Cu")
		(net "M_B_CPU0_SB_DQS_DN<1>")
	)
	(segment
		(start 305.814476 -294.123364)
		(end 304.950876 -294.986964)
		(width 0.16002)
		(layer "In13.Cu")
		(net "M_B_CPU0_SB_DQS_DN<1>")
	)
	(segment
		(start 314.210954 -287.705038)
		(end 314.390024 -287.884108)
		(width 0.16002)
		(layer "In13.Cu")
		(net "M_B_CPU0_SB_DQS_DN<1>")
	)
	(segment
		(start 317.137288 -285.136844)
		(end 317.137288 -285.664148)
		(width 0.16002)
		(layer "In13.Cu")
		(net "M_B_CPU0_SB_DQS_DN<1>")
	)
	(segment
		(start 315.763656 -286.510476)
		(end 315.763656 -287.03778)
		(width 0.16002)
		(layer "In13.Cu")
		(net "M_B_CPU0_SB_DQS_DN<1>")
	)
	(segment
		(start 316.764416 -286.03702)
		(end 316.237112 -286.03702)
		(width 0.16002)
		(layer "In13.Cu")
		(net "M_B_CPU0_SB_DQS_DN<1>")
	)
	(segment
		(start 317.431674 -284.484318)
		(end 317.154814 -284.484318)
		(width 0.16002)
		(layer "In13.Cu")
		(net "M_B_CPU0_SB_DQS_DN<1>")
	)
	(arc
		(start 333.881222 -281.046174)
		(mid 333.69619 -281.00026)
		(end 333.512414 -281.051)
		(width 0.09525)
		(layer "In13.Cu")
		(net "M_B_CPU0_SB_DQS_DN<1>")
	)
	(arc
		(start 330.692506 -281.051)
		(mid 330.411074 -281.126755)
		(end 330.129642 -281.051)
		(width 0.09525)
		(layer "In13.Cu")
		(net "M_B_CPU0_SB_DQS_DN<1>")
	)
	(arc
		(start 327.872344 -281.051)
		(mid 327.596801 -281.126849)
		(end 327.31964 -281.057096)
		(width 0.09525)
		(layer "In13.Cu")
		(net "M_B_CPU0_SB_DQS_DN<1>")
	)
	(arc
		(start 335.392522 -281.051)
		(mid 335.11109 -281.126755)
		(end 334.829658 -281.051)
		(width 0.09525)
		(layer "In13.Cu")
		(net "M_B_CPU0_SB_DQS_DN<1>")
	)
	(arc
		(start 335.711546 -281.023822)
		(mid 335.553796 -281.001303)
		(end 335.400904 -281.046174)
		(width 0.09525)
		(layer "In13.Cu")
		(net "M_B_CPU0_SB_DQS_DN<1>")
	)
	(arc
		(start 328.812652 -281.051)
		(mid 328.53122 -281.126755)
		(end 328.249788 -281.051)
		(width 0.09525)
		(layer "In13.Cu")
		(net "M_B_CPU0_SB_DQS_DN<1>")
	)
	(arc
		(start 333.512414 -281.051)
		(mid 333.230982 -281.126755)
		(end 332.94955 -281.051)
		(width 0.09525)
		(layer "In13.Cu")
		(net "M_B_CPU0_SB_DQS_DN<1>")
	)
	(arc
		(start 332.94955 -281.051)
		(mid 332.761082 -281.000323)
		(end 332.572614 -281.051)
		(width 0.09525)
		(layer "In13.Cu")
		(net "M_B_CPU0_SB_DQS_DN<1>")
	)
	(arc
		(start 327.309226 -281.051)
		(mid 327.12761 -281.000263)
		(end 326.944228 -281.044142)
		(width 0.09525)
		(layer "In13.Cu")
		(net "M_B_CPU0_SB_DQS_DN<1>")
	)
	(arc
		(start 332.572614 -281.051)
		(mid 332.291182 -281.126755)
		(end 332.00975 -281.051)
		(width 0.09525)
		(layer "In13.Cu")
		(net "M_B_CPU0_SB_DQS_DN<1>")
	)
	(arc
		(start 334.452468 -281.051)
		(mid 334.171036 -281.126755)
		(end 333.889604 -281.051)
		(width 0.09525)
		(layer "In13.Cu")
		(net "M_B_CPU0_SB_DQS_DN<1>")
	)
	(arc
		(start 331.63256 -281.051)
		(mid 331.351128 -281.126755)
		(end 331.069696 -281.051)
		(width 0.09525)
		(layer "In13.Cu")
		(net "M_B_CPU0_SB_DQS_DN<1>")
	)
	(arc
		(start 334.821276 -281.046174)
		(mid 334.636244 -281.00026)
		(end 334.452468 -281.051)
		(width 0.09525)
		(layer "In13.Cu")
		(net "M_B_CPU0_SB_DQS_DN<1>")
	)
	(arc
		(start 326.426576 -281.08021)
		(mid 326.382218 -281.062636)
		(end 326.33666 -281.04846)
		(width 0.09525)
		(layer "In13.Cu")
		(net "M_B_CPU0_SB_DQS_DN<1>")
	)
	(arc
		(start 328.249788 -281.051)
		(mid 328.061066 -281.000196)
		(end 327.872344 -281.051)
		(width 0.09525)
		(layer "In13.Cu")
		(net "M_B_CPU0_SB_DQS_DN<1>")
	)
	(arc
		(start 330.12126 -281.046174)
		(mid 329.936228 -281.00026)
		(end 329.752452 -281.051)
		(width 0.09525)
		(layer "In13.Cu")
		(net "M_B_CPU0_SB_DQS_DN<1>")
	)
	(arc
		(start 332.00975 -281.051)
		(mid 331.825975 -281.000228)
		(end 331.640942 -281.046174)
		(width 0.09525)
		(layer "In13.Cu")
		(net "M_B_CPU0_SB_DQS_DN<1>")
	)
	(arc
		(start 329.752452 -281.051)
		(mid 329.47102 -281.126755)
		(end 329.189588 -281.051)
		(width 0.09525)
		(layer "In13.Cu")
		(net "M_B_CPU0_SB_DQS_DN<1>")
	)
	(arc
		(start 325.149972 -280.73223)
		(mid 325.103261 -280.722941)
		(end 325.055738 -280.719784)
		(width 0.09525)
		(layer "In13.Cu")
		(net "M_B_CPU0_SB_DQS_DN<1>")
	)
	(arc
		(start 329.189588 -281.051)
		(mid 329.00112 -281.000323)
		(end 328.812652 -281.051)
		(width 0.09525)
		(layer "In13.Cu")
		(net "M_B_CPU0_SB_DQS_DN<1>")
	)
	(arc
		(start 326.917558 -281.059636)
		(mid 326.674432 -281.126593)
		(end 326.426576 -281.08021)
		(width 0.09525)
		(layer "In13.Cu")
		(net "M_B_CPU0_SB_DQS_DN<1>")
	)
	(arc
		(start 331.069696 -281.051)
		(mid 330.885921 -281.000228)
		(end 330.700888 -281.046174)
		(width 0.09525)
		(layer "In13.Cu")
		(net "M_B_CPU0_SB_DQS_DN<1>")
	)
	(segment
		(start 336.047842 -276.250146)
		(end 335.58099 -276.516084)
		(width 0.12954)
		(layer "F.Cu")
		(net "M_B_CPU0_SB_DQS_DN<0>")
	)
	(segment
		(start 323.978524 -275.400262)
		(end 323.919596 -275.45919)
		(width 0.09525)
		(layer "In13.Cu")
		(net "M_B_CPU0_SB_DQS_DN<0>")
	)
	(segment
		(start 310.967628 -281.678126)
		(end 310.967628 -282.15463)
		(width 0.16002)
		(layer "In13.Cu")
		(net "M_B_CPU0_SB_DQS_DN<0>")
	)
	(segment
		(start 314.662312 -278.459946)
		(end 314.185808 -278.459946)
		(width 0.16002)
		(layer "In13.Cu")
		(net "M_B_CPU0_SB_DQS_DN<0>")
	)
	(segment
		(start 309.594758 -283.5275)
		(end 309.170832 -283.951426)
		(width 0.16002)
		(layer "In13.Cu")
		(net "M_B_CPU0_SB_DQS_DN<0>")
	)
	(segment
		(start 315.086238 -278.03602)
		(end 314.662312 -278.459946)
		(width 0.16002)
		(layer "In13.Cu")
		(net "M_B_CPU0_SB_DQS_DN<0>")
	)
	(segment
		(start 335.400904 -276.186138)
		(end 335.392522 -276.190964)
		(width 0.09525)
		(layer "In13.Cu")
		(net "M_B_CPU0_SB_DQS_DN<0>")
	)
	(segment
		(start 315.558678 -277.087076)
		(end 315.421264 -276.949662)
		(width 0.16002)
		(layer "In13.Cu")
		(net "M_B_CPU0_SB_DQS_DN<0>")
	)
	(segment
		(start 310.830214 -281.314652)
		(end 310.830214 -281.540712)
		(width 0.16002)
		(layer "In13.Cu")
		(net "M_B_CPU0_SB_DQS_DN<0>")
	)
	(segment
		(start 315.086238 -277.559516)
		(end 315.086238 -278.03602)
		(width 0.16002)
		(layer "In13.Cu")
		(net "M_B_CPU0_SB_DQS_DN<0>")
	)
	(segment
		(start 316.459108 -276.66315)
		(end 316.035182 -277.087076)
		(width 0.16002)
		(layer "In13.Cu")
		(net "M_B_CPU0_SB_DQS_DN<0>")
	)
	(segment
		(start 310.067198 -282.578556)
		(end 309.929784 -282.441142)
		(width 0.16002)
		(layer "In13.Cu")
		(net "M_B_CPU0_SB_DQS_DN<0>")
	)
	(segment
		(start 309.703724 -282.441142)
		(end 309.457344 -282.687522)
		(width 0.16002)
		(layer "In13.Cu")
		(net "M_B_CPU0_SB_DQS_DN<0>")
	)
	(segment
		(start 310.543702 -282.578556)
		(end 310.067198 -282.578556)
		(width 0.16002)
		(layer "In13.Cu")
		(net "M_B_CPU0_SB_DQS_DN<0>")
	)
	(segment
		(start 312.203084 -279.941782)
		(end 312.203084 -280.167842)
		(width 0.16002)
		(layer "In13.Cu")
		(net "M_B_CPU0_SB_DQS_DN<0>")
	)
	(segment
		(start 333.889604 -276.190964)
		(end 333.881222 -276.186138)
		(width 0.09525)
		(layer "In13.Cu")
		(net "M_B_CPU0_SB_DQS_DN<0>")
	)
	(segment
		(start 315.195204 -276.949662)
		(end 314.948824 -277.196042)
		(width 0.16002)
		(layer "In13.Cu")
		(net "M_B_CPU0_SB_DQS_DN<0>")
	)
	(segment
		(start 315.421264 -276.949662)
		(end 315.195204 -276.949662)
		(width 0.16002)
		(layer "In13.Cu")
		(net "M_B_CPU0_SB_DQS_DN<0>")
	)
	(segment
		(start 325.9455 -276.212808)
		(end 325.132954 -275.400262)
		(width 0.09525)
		(layer "In13.Cu")
		(net "M_B_CPU0_SB_DQS_DN<0>")
	)
	(segment
		(start 330.700888 -276.186138)
		(end 330.692506 -276.190964)
		(width 0.09525)
		(layer "In13.Cu")
		(net "M_B_CPU0_SB_DQS_DN<0>")
	)
	(segment
		(start 313.713368 -278.932386)
		(end 313.713368 -279.40889)
		(width 0.16002)
		(layer "In13.Cu")
		(net "M_B_CPU0_SB_DQS_DN<0>")
	)
	(segment
		(start 304.557176 -286.03067)
		(end 303.719738 -286.03067)
		(width 0.16002)
		(layer "In13.Cu")
		(net "M_B_CPU0_SB_DQS_DN<0>")
	)
	(segment
		(start 309.170832 -283.951426)
		(end 308.694328 -283.951426)
		(width 0.16002)
		(layer "In13.Cu")
		(net "M_B_CPU0_SB_DQS_DN<0>")
	)
	(segment
		(start 309.457344 -282.687522)
		(end 309.457344 -282.913582)
		(width 0.16002)
		(layer "In13.Cu")
		(net "M_B_CPU0_SB_DQS_DN<0>")
	)
	(segment
		(start 309.594758 -283.050996)
		(end 309.594758 -283.5275)
		(width 0.16002)
		(layer "In13.Cu")
		(net "M_B_CPU0_SB_DQS_DN<0>")
	)
	(segment
		(start 308.556914 -283.814012)
		(end 308.330854 -283.814012)
		(width 0.16002)
		(layer "In13.Cu")
		(net "M_B_CPU0_SB_DQS_DN<0>")
	)
	(segment
		(start 314.185808 -278.459946)
		(end 314.048394 -278.322532)
		(width 0.16002)
		(layer "In13.Cu")
		(net "M_B_CPU0_SB_DQS_DN<0>")
	)
	(segment
		(start 313.822334 -278.322532)
		(end 313.575954 -278.568912)
		(width 0.16002)
		(layer "In13.Cu")
		(net "M_B_CPU0_SB_DQS_DN<0>")
	)
	(segment
		(start 309.457344 -282.913582)
		(end 309.594758 -283.050996)
		(width 0.16002)
		(layer "In13.Cu")
		(net "M_B_CPU0_SB_DQS_DN<0>")
	)
	(segment
		(start 335.58099 -276.516084)
		(end 335.734914 -276.250654)
		(width 0.09525)
		(layer "In13.Cu")
		(net "M_B_CPU0_SB_DQS_DN<0>")
	)
	(segment
		(start 309.929784 -282.441142)
		(end 309.703724 -282.441142)
		(width 0.16002)
		(layer "In13.Cu")
		(net "M_B_CPU0_SB_DQS_DN<0>")
	)
	(segment
		(start 311.076594 -281.068272)
		(end 310.830214 -281.314652)
		(width 0.16002)
		(layer "In13.Cu")
		(net "M_B_CPU0_SB_DQS_DN<0>")
	)
	(segment
		(start 312.203084 -280.167842)
		(end 312.340498 -280.305256)
		(width 0.16002)
		(layer "In13.Cu")
		(net "M_B_CPU0_SB_DQS_DN<0>")
	)
	(segment
		(start 316.035182 -277.087076)
		(end 315.558678 -277.087076)
		(width 0.16002)
		(layer "In13.Cu")
		(net "M_B_CPU0_SB_DQS_DN<0>")
	)
	(segment
		(start 312.449464 -279.695402)
		(end 312.203084 -279.941782)
		(width 0.16002)
		(layer "In13.Cu")
		(net "M_B_CPU0_SB_DQS_DN<0>")
	)
	(segment
		(start 323.895974 -275.45919)
		(end 316.685676 -275.45919)
		(width 0.16002)
		(layer "In13.Cu")
		(net "M_B_CPU0_SB_DQS_DN<0>")
	)
	(segment
		(start 334.829658 -276.190964)
		(end 334.821276 -276.186138)
		(width 0.09525)
		(layer "In13.Cu")
		(net "M_B_CPU0_SB_DQS_DN<0>")
	)
	(segment
		(start 329.231498 -276.213062)
		(end 329.229974 -276.2123)
		(width 0.09525)
		(layer "In13.Cu")
		(net "M_B_CPU0_SB_DQS_DN<0>")
	)
	(segment
		(start 325.132954 -275.400262)
		(end 323.978524 -275.400262)
		(width 0.09525)
		(layer "In13.Cu")
		(net "M_B_CPU0_SB_DQS_DN<0>")
	)
	(segment
		(start 313.289442 -279.832816)
		(end 312.812938 -279.832816)
		(width 0.16002)
		(layer "In13.Cu")
		(net "M_B_CPU0_SB_DQS_DN<0>")
	)
	(segment
		(start 312.340498 -280.78176)
		(end 311.916572 -281.205686)
		(width 0.16002)
		(layer "In13.Cu")
		(net "M_B_CPU0_SB_DQS_DN<0>")
	)
	(segment
		(start 330.129642 -276.190964)
		(end 330.12126 -276.186138)
		(width 0.09525)
		(layer "In13.Cu")
		(net "M_B_CPU0_SB_DQS_DN<0>")
	)
	(segment
		(start 311.440068 -281.205686)
		(end 311.302654 -281.068272)
		(width 0.16002)
		(layer "In13.Cu")
		(net "M_B_CPU0_SB_DQS_DN<0>")
	)
	(segment
		(start 331.640942 -276.186138)
		(end 331.63256 -276.190964)
		(width 0.09525)
		(layer "In13.Cu")
		(net "M_B_CPU0_SB_DQS_DN<0>")
	)
	(segment
		(start 310.967628 -282.15463)
		(end 310.543702 -282.578556)
		(width 0.16002)
		(layer "In13.Cu")
		(net "M_B_CPU0_SB_DQS_DN<0>")
	)
	(segment
		(start 335.734914 -276.250654)
		(end 335.711546 -276.163786)
		(width 0.09525)
		(layer "In13.Cu")
		(net "M_B_CPU0_SB_DQS_DN<0>")
	)
	(segment
		(start 313.575954 -278.794972)
		(end 313.713368 -278.932386)
		(width 0.16002)
		(layer "In13.Cu")
		(net "M_B_CPU0_SB_DQS_DN<0>")
	)
	(segment
		(start 310.830214 -281.540712)
		(end 310.967628 -281.678126)
		(width 0.16002)
		(layer "In13.Cu")
		(net "M_B_CPU0_SB_DQS_DN<0>")
	)
	(segment
		(start 328.791824 -276.196552)
		(end 328.7903 -276.19706)
		(width 0.09525)
		(layer "In13.Cu")
		(net "M_B_CPU0_SB_DQS_DN<0>")
	)
	(segment
		(start 313.713368 -279.40889)
		(end 313.289442 -279.832816)
		(width 0.16002)
		(layer "In13.Cu")
		(net "M_B_CPU0_SB_DQS_DN<0>")
	)
	(segment
		(start 312.340498 -280.305256)
		(end 312.340498 -280.78176)
		(width 0.16002)
		(layer "In13.Cu")
		(net "M_B_CPU0_SB_DQS_DN<0>")
	)
	(segment
		(start 303.120044 -285.430976)
		(end 300.128178 -285.430976)
		(width 0.16002)
		(layer "In13.Cu")
		(net "M_B_CPU0_SB_DQS_DN<0>")
	)
	(segment
		(start 327.504806 -276.26691)
		(end 326.076056 -276.26691)
		(width 0.09525)
		(layer "In13.Cu")
		(net "M_B_CPU0_SB_DQS_DN<0>")
	)
	(segment
		(start 311.916572 -281.205686)
		(end 311.440068 -281.205686)
		(width 0.16002)
		(layer "In13.Cu")
		(net "M_B_CPU0_SB_DQS_DN<0>")
	)
	(segment
		(start 314.948824 -277.196042)
		(end 314.948824 -277.422102)
		(width 0.16002)
		(layer "In13.Cu")
		(net "M_B_CPU0_SB_DQS_DN<0>")
	)
	(segment
		(start 308.330854 -283.814012)
		(end 307.282596 -284.86227)
		(width 0.16002)
		(layer "In13.Cu")
		(net "M_B_CPU0_SB_DQS_DN<0>")
	)
	(segment
		(start 314.048394 -278.322532)
		(end 313.822334 -278.322532)
		(width 0.16002)
		(layer "In13.Cu")
		(net "M_B_CPU0_SB_DQS_DN<0>")
	)
	(segment
		(start 303.719738 -286.03067)
		(end 303.120044 -285.430976)
		(width 0.16002)
		(layer "In13.Cu")
		(net "M_B_CPU0_SB_DQS_DN<0>")
	)
	(segment
		(start 307.282596 -284.86227)
		(end 305.725576 -284.86227)
		(width 0.16002)
		(layer "In13.Cu")
		(net "M_B_CPU0_SB_DQS_DN<0>")
	)
	(segment
		(start 312.812938 -279.832816)
		(end 312.675524 -279.695402)
		(width 0.16002)
		(layer "In13.Cu")
		(net "M_B_CPU0_SB_DQS_DN<0>")
	)
	(segment
		(start 312.675524 -279.695402)
		(end 312.449464 -279.695402)
		(width 0.16002)
		(layer "In13.Cu")
		(net "M_B_CPU0_SB_DQS_DN<0>")
	)
	(segment
		(start 316.321694 -275.823172)
		(end 316.321694 -276.049232)
		(width 0.16002)
		(layer "In13.Cu")
		(net "M_B_CPU0_SB_DQS_DN<0>")
	)
	(segment
		(start 323.919596 -275.45919)
		(end 323.895974 -275.45919)
		(width 0.09525)
		(layer "In13.Cu")
		(net "M_B_CPU0_SB_DQS_DN<0>")
	)
	(segment
		(start 308.694328 -283.951426)
		(end 308.556914 -283.814012)
		(width 0.16002)
		(layer "In13.Cu")
		(net "M_B_CPU0_SB_DQS_DN<0>")
	)
	(segment
		(start 316.459108 -276.186646)
		(end 316.459108 -276.66315)
		(width 0.16002)
		(layer "In13.Cu")
		(net "M_B_CPU0_SB_DQS_DN<0>")
	)
	(segment
		(start 311.302654 -281.068272)
		(end 311.076594 -281.068272)
		(width 0.16002)
		(layer "In13.Cu")
		(net "M_B_CPU0_SB_DQS_DN<0>")
	)
	(segment
		(start 314.948824 -277.422102)
		(end 315.086238 -277.559516)
		(width 0.16002)
		(layer "In13.Cu")
		(net "M_B_CPU0_SB_DQS_DN<0>")
	)
	(segment
		(start 313.575954 -278.568912)
		(end 313.575954 -278.794972)
		(width 0.16002)
		(layer "In13.Cu")
		(net "M_B_CPU0_SB_DQS_DN<0>")
	)
	(segment
		(start 305.725576 -284.86227)
		(end 304.557176 -286.03067)
		(width 0.16002)
		(layer "In13.Cu")
		(net "M_B_CPU0_SB_DQS_DN<0>")
	)
	(segment
		(start 316.321694 -276.049232)
		(end 316.459108 -276.186646)
		(width 0.16002)
		(layer "In13.Cu")
		(net "M_B_CPU0_SB_DQS_DN<0>")
	)
	(segment
		(start 300.128178 -285.430976)
		(end 299.82414 -285.735014)
		(width 0.16002)
		(layer "In13.Cu")
		(net "M_B_CPU0_SB_DQS_DN<0>")
	)
	(segment
		(start 316.685676 -275.45919)
		(end 316.321694 -275.823172)
		(width 0.16002)
		(layer "In13.Cu")
		(net "M_B_CPU0_SB_DQS_DN<0>")
	)
	(arc
		(start 330.12126 -276.186138)
		(mid 329.936228 -276.140224)
		(end 329.752452 -276.190964)
		(width 0.09525)
		(layer "In13.Cu")
		(net "M_B_CPU0_SB_DQS_DN<0>")
	)
	(arc
		(start 335.392522 -276.190964)
		(mid 335.11109 -276.266719)
		(end 334.829658 -276.190964)
		(width 0.09525)
		(layer "In13.Cu")
		(net "M_B_CPU0_SB_DQS_DN<0>")
	)
	(arc
		(start 333.881222 -276.186138)
		(mid 333.69619 -276.140224)
		(end 333.512414 -276.190964)
		(width 0.09525)
		(layer "In13.Cu")
		(net "M_B_CPU0_SB_DQS_DN<0>")
	)
	(arc
		(start 328.7903 -276.19706)
		(mid 328.52319 -276.247134)
		(end 328.255884 -276.198076)
		(width 0.09525)
		(layer "In13.Cu")
		(net "M_B_CPU0_SB_DQS_DN<0>")
	)
	(arc
		(start 331.63256 -276.190964)
		(mid 331.351128 -276.266719)
		(end 331.069696 -276.190964)
		(width 0.09525)
		(layer "In13.Cu")
		(net "M_B_CPU0_SB_DQS_DN<0>")
	)
	(arc
		(start 332.572614 -276.190964)
		(mid 332.291182 -276.266719)
		(end 332.00975 -276.190964)
		(width 0.09525)
		(layer "In13.Cu")
		(net "M_B_CPU0_SB_DQS_DN<0>")
	)
	(arc
		(start 326.076056 -276.26691)
		(mid 326.00539 -276.252854)
		(end 325.9455 -276.212808)
		(width 0.09525)
		(layer "In13.Cu")
		(net "M_B_CPU0_SB_DQS_DN<0>")
	)
	(arc
		(start 332.00975 -276.190964)
		(mid 331.825975 -276.140192)
		(end 331.640942 -276.186138)
		(width 0.09525)
		(layer "In13.Cu")
		(net "M_B_CPU0_SB_DQS_DN<0>")
	)
	(arc
		(start 329.229974 -276.2123)
		(mid 329.012512 -276.159455)
		(end 328.791824 -276.196552)
		(width 0.09525)
		(layer "In13.Cu")
		(net "M_B_CPU0_SB_DQS_DN<0>")
	)
	(arc
		(start 334.821276 -276.186138)
		(mid 334.636244 -276.140224)
		(end 334.452468 -276.190964)
		(width 0.09525)
		(layer "In13.Cu")
		(net "M_B_CPU0_SB_DQS_DN<0>")
	)
	(arc
		(start 335.711546 -276.163786)
		(mid 335.553796 -276.141267)
		(end 335.400904 -276.186138)
		(width 0.09525)
		(layer "In13.Cu")
		(net "M_B_CPU0_SB_DQS_DN<0>")
	)
	(arc
		(start 333.512414 -276.190964)
		(mid 333.230982 -276.266719)
		(end 332.94955 -276.190964)
		(width 0.09525)
		(layer "In13.Cu")
		(net "M_B_CPU0_SB_DQS_DN<0>")
	)
	(arc
		(start 330.692506 -276.190964)
		(mid 330.411074 -276.266719)
		(end 330.129642 -276.190964)
		(width 0.09525)
		(layer "In13.Cu")
		(net "M_B_CPU0_SB_DQS_DN<0>")
	)
	(arc
		(start 332.94955 -276.190964)
		(mid 332.761082 -276.140287)
		(end 332.572614 -276.190964)
		(width 0.09525)
		(layer "In13.Cu")
		(net "M_B_CPU0_SB_DQS_DN<0>")
	)
	(arc
		(start 334.452468 -276.190964)
		(mid 334.171036 -276.266719)
		(end 333.889604 -276.190964)
		(width 0.09525)
		(layer "In13.Cu")
		(net "M_B_CPU0_SB_DQS_DN<0>")
	)
	(arc
		(start 331.069696 -276.190964)
		(mid 330.885921 -276.140192)
		(end 330.700888 -276.186138)
		(width 0.09525)
		(layer "In13.Cu")
		(net "M_B_CPU0_SB_DQS_DN<0>")
	)
	(arc
		(start 328.255884 -276.198076)
		(mid 328.051911 -276.161131)
		(end 327.848468 -276.20087)
		(width 0.09525)
		(layer "In13.Cu")
		(net "M_B_CPU0_SB_DQS_DN<0>")
	)
	(arc
		(start 329.752452 -276.190964)
		(mid 329.494708 -276.266218)
		(end 329.231498 -276.213062)
		(width 0.09525)
		(layer "In13.Cu")
		(net "M_B_CPU0_SB_DQS_DN<0>")
	)
	(arc
		(start 327.848468 -276.20087)
		(mid 327.679774 -276.250208)
		(end 327.504806 -276.26691)
		(width 0.09525)
		(layer "In13.Cu")
		(net "M_B_CPU0_SB_DQS_DN<0>")
	)
	(segment
		(start 337.92795 -279.49017)
		(end 337.461098 -279.756108)
		(width 0.10668)
		(layer "F.Cu")
		(net "M_B_CPU0_SB_DQ<9>")
	)
	(segment
		(start 306.232306 -292.37051)
		(end 305.971702 -292.109906)
		(width 0.14478)
		(layer "In13.Cu")
		(net "M_B_CPU0_SB_DQ<9>")
	)
	(segment
		(start 337.461098 -279.756108)
		(end 337.307174 -280.021538)
		(width 0.0889)
		(layer "In13.Cu")
		(net "M_B_CPU0_SB_DQ<9>")
	)
	(segment
		(start 334.828134 -280.078688)
		(end 334.819752 -280.083514)
		(width 0.0889)
		(layer "In13.Cu")
		(net "M_B_CPU0_SB_DQ<9>")
	)
	(segment
		(start 306.788566 -292.109906)
		(end 306.527962 -292.37051)
		(width 0.14478)
		(layer "In13.Cu")
		(net "M_B_CPU0_SB_DQ<9>")
	)
	(segment
		(start 337.307174 -280.021538)
		(end 337.211162 -280.046938)
		(width 0.0889)
		(layer "In13.Cu")
		(net "M_B_CPU0_SB_DQ<9>")
	)
	(segment
		(start 311.729374 -288.40176)
		(end 312.021474 -288.69386)
		(width 0.14478)
		(layer "In13.Cu")
		(net "M_B_CPU0_SB_DQ<9>")
	)
	(segment
		(start 336.342482 -280.083514)
		(end 336.3341 -280.078688)
		(width 0.0889)
		(layer "In13.Cu")
		(net "M_B_CPU0_SB_DQ<9>")
	)
	(segment
		(start 312.411364 -288.30397)
		(end 312.119264 -288.01187)
		(width 0.14478)
		(layer "In13.Cu")
		(net "M_B_CPU0_SB_DQ<9>")
	)
	(segment
		(start 327.586848 -280.078688)
		(end 327.428352 -279.920192)
		(width 0.0889)
		(layer "In13.Cu")
		(net "M_B_CPU0_SB_DQ<9>")
	)
	(segment
		(start 327.428352 -279.920192)
		(end 324.588378 -279.920192)
		(width 0.0889)
		(layer "In13.Cu")
		(net "M_B_CPU0_SB_DQ<9>")
	)
	(segment
		(start 311.339484 -288.79165)
		(end 311.13476 -288.79165)
		(width 0.14478)
		(layer "In13.Cu")
		(net "M_B_CPU0_SB_DQ<9>")
	)
	(segment
		(start 306.527962 -292.37051)
		(end 306.232306 -292.37051)
		(width 0.14478)
		(layer "In13.Cu")
		(net "M_B_CPU0_SB_DQ<9>")
	)
	(segment
		(start 330.702412 -280.083514)
		(end 330.69403 -280.078688)
		(width 0.0889)
		(layer "In13.Cu")
		(net "M_B_CPU0_SB_DQ<9>")
	)
	(segment
		(start 310.949594 -288.976816)
		(end 310.949594 -289.18154)
		(width 0.14478)
		(layer "In13.Cu")
		(net "M_B_CPU0_SB_DQ<9>")
	)
	(segment
		(start 299.82414 -292.341046)
		(end 299.82414 -292.535102)
		(width 0.14478)
		(layer "In13.Cu")
		(net "M_B_CPU0_SB_DQ<9>")
	)
	(segment
		(start 311.91454 -288.01187)
		(end 311.729374 -288.197036)
		(width 0.14478)
		(layer "In13.Cu")
		(net "M_B_CPU0_SB_DQ<9>")
	)
	(segment
		(start 312.900314 -286.7406)
		(end 312.900314 -288.019744)
		(width 0.14478)
		(layer "In13.Cu")
		(net "M_B_CPU0_SB_DQ<9>")
	)
	(segment
		(start 311.836308 -289.08375)
		(end 311.631584 -289.08375)
		(width 0.14478)
		(layer "In13.Cu")
		(net "M_B_CPU0_SB_DQ<9>")
	)
	(segment
		(start 305.971702 -292.109906)
		(end 305.5366 -292.109906)
		(width 0.14478)
		(layer "In13.Cu")
		(net "M_B_CPU0_SB_DQ<9>")
	)
	(segment
		(start 311.729374 -288.197036)
		(end 311.729374 -288.40176)
		(width 0.14478)
		(layer "In13.Cu")
		(net "M_B_CPU0_SB_DQ<9>")
	)
	(segment
		(start 333.88808 -280.078688)
		(end 333.879698 -280.083514)
		(width 0.0889)
		(layer "In13.Cu")
		(net "M_B_CPU0_SB_DQ<9>")
	)
	(segment
		(start 305.5366 -292.109906)
		(end 304.685954 -292.960298)
		(width 0.14478)
		(layer "In13.Cu")
		(net "M_B_CPU0_SB_DQ<9>")
	)
	(segment
		(start 312.616088 -288.30397)
		(end 312.411364 -288.30397)
		(width 0.14478)
		(layer "In13.Cu")
		(net "M_B_CPU0_SB_DQ<9>")
	)
	(segment
		(start 319.887854 -279.75306)
		(end 312.900314 -286.7406)
		(width 0.14478)
		(layer "In13.Cu")
		(net "M_B_CPU0_SB_DQ<9>")
	)
	(segment
		(start 330.128118 -280.078688)
		(end 330.119736 -280.083514)
		(width 0.0889)
		(layer "In13.Cu")
		(net "M_B_CPU0_SB_DQ<9>")
	)
	(segment
		(start 331.642466 -280.083514)
		(end 331.634084 -280.078688)
		(width 0.0889)
		(layer "In13.Cu")
		(net "M_B_CPU0_SB_DQ<9>")
	)
	(segment
		(start 302.342042 -292.960298)
		(end 301.1678 -291.78631)
		(width 0.14478)
		(layer "In13.Cu")
		(net "M_B_CPU0_SB_DQ<9>")
	)
	(segment
		(start 312.900314 -288.019744)
		(end 312.616088 -288.30397)
		(width 0.14478)
		(layer "In13.Cu")
		(net "M_B_CPU0_SB_DQ<9>")
	)
	(segment
		(start 311.13476 -288.79165)
		(end 310.949594 -288.976816)
		(width 0.14478)
		(layer "In13.Cu")
		(net "M_B_CPU0_SB_DQ<9>")
	)
	(segment
		(start 301.1678 -291.78631)
		(end 300.378876 -291.78631)
		(width 0.14478)
		(layer "In13.Cu")
		(net "M_B_CPU0_SB_DQ<9>")
	)
	(segment
		(start 304.6857 -292.960044)
		(end 302.342296 -292.960044)
		(width 0.14478)
		(layer "In13.Cu")
		(net "M_B_CPU0_SB_DQ<9>")
	)
	(segment
		(start 312.119264 -288.01187)
		(end 311.91454 -288.01187)
		(width 0.14478)
		(layer "In13.Cu")
		(net "M_B_CPU0_SB_DQ<9>")
	)
	(segment
		(start 324.421246 -279.75306)
		(end 324.26783 -279.75306)
		(width 0.0889)
		(layer "In13.Cu")
		(net "M_B_CPU0_SB_DQ<9>")
	)
	(segment
		(start 324.26783 -279.75306)
		(end 319.887854 -279.75306)
		(width 0.14478)
		(layer "In13.Cu")
		(net "M_B_CPU0_SB_DQ<9>")
	)
	(segment
		(start 327.873868 -280.078688)
		(end 327.586848 -280.078688)
		(width 0.0889)
		(layer "In13.Cu")
		(net "M_B_CPU0_SB_DQ<9>")
	)
	(segment
		(start 311.241694 -289.678364)
		(end 308.810152 -292.109906)
		(width 0.14478)
		(layer "In13.Cu")
		(net "M_B_CPU0_SB_DQ<9>")
	)
	(segment
		(start 310.949594 -289.18154)
		(end 311.241694 -289.47364)
		(width 0.14478)
		(layer "In13.Cu")
		(net "M_B_CPU0_SB_DQ<9>")
	)
	(segment
		(start 312.021474 -288.69386)
		(end 312.021474 -288.898584)
		(width 0.14478)
		(layer "In13.Cu")
		(net "M_B_CPU0_SB_DQ<9>")
	)
	(segment
		(start 324.588378 -279.920192)
		(end 324.421246 -279.75306)
		(width 0.0889)
		(layer "In13.Cu")
		(net "M_B_CPU0_SB_DQ<9>")
	)
	(segment
		(start 311.631584 -289.08375)
		(end 311.339484 -288.79165)
		(width 0.14478)
		(layer "In13.Cu")
		(net "M_B_CPU0_SB_DQ<9>")
	)
	(segment
		(start 302.342296 -292.960044)
		(end 302.342042 -292.960298)
		(width 0.14478)
		(layer "In13.Cu")
		(net "M_B_CPU0_SB_DQ<9>")
	)
	(segment
		(start 335.402428 -280.083514)
		(end 335.394046 -280.078688)
		(width 0.0889)
		(layer "In13.Cu")
		(net "M_B_CPU0_SB_DQ<9>")
	)
	(segment
		(start 311.241694 -289.47364)
		(end 311.241694 -289.678364)
		(width 0.14478)
		(layer "In13.Cu")
		(net "M_B_CPU0_SB_DQ<9>")
	)
	(segment
		(start 300.378876 -291.78631)
		(end 299.82414 -292.341046)
		(width 0.14478)
		(layer "In13.Cu")
		(net "M_B_CPU0_SB_DQ<9>")
	)
	(segment
		(start 312.021474 -288.898584)
		(end 311.836308 -289.08375)
		(width 0.14478)
		(layer "In13.Cu")
		(net "M_B_CPU0_SB_DQ<9>")
	)
	(segment
		(start 304.685954 -292.960298)
		(end 304.6857 -292.960044)
		(width 0.14478)
		(layer "In13.Cu")
		(net "M_B_CPU0_SB_DQ<9>")
	)
	(segment
		(start 308.810152 -292.109906)
		(end 306.788566 -292.109906)
		(width 0.14478)
		(layer "In13.Cu")
		(net "M_B_CPU0_SB_DQ<9>")
	)
	(arc
		(start 330.69403 -280.078688)
		(mid 330.411074 -280.002511)
		(end 330.128118 -280.078688)
		(width 0.0889)
		(layer "In13.Cu")
		(net "M_B_CPU0_SB_DQ<9>")
	)
	(arc
		(start 334.819752 -280.083514)
		(mid 334.636244 -280.129008)
		(end 334.453992 -280.078688)
		(width 0.0889)
		(layer "In13.Cu")
		(net "M_B_CPU0_SB_DQ<9>")
	)
	(arc
		(start 330.119736 -280.083514)
		(mid 329.936228 -280.129008)
		(end 329.753976 -280.078688)
		(width 0.0889)
		(layer "In13.Cu")
		(net "M_B_CPU0_SB_DQ<9>")
	)
	(arc
		(start 329.753976 -280.078688)
		(mid 329.47102 -280.002511)
		(end 329.188064 -280.078688)
		(width 0.0889)
		(layer "In13.Cu")
		(net "M_B_CPU0_SB_DQ<9>")
	)
	(arc
		(start 334.453992 -280.078688)
		(mid 334.171036 -280.002511)
		(end 333.88808 -280.078688)
		(width 0.0889)
		(layer "In13.Cu")
		(net "M_B_CPU0_SB_DQ<9>")
	)
	(arc
		(start 328.814176 -280.078688)
		(mid 328.53122 -280.002511)
		(end 328.248264 -280.078688)
		(width 0.0889)
		(layer "In13.Cu")
		(net "M_B_CPU0_SB_DQ<9>")
	)
	(arc
		(start 335.394046 -280.078688)
		(mid 335.11109 -280.002511)
		(end 334.828134 -280.078688)
		(width 0.0889)
		(layer "In13.Cu")
		(net "M_B_CPU0_SB_DQ<9>")
	)
	(arc
		(start 329.188064 -280.078688)
		(mid 329.00112 -280.128943)
		(end 328.814176 -280.078688)
		(width 0.0889)
		(layer "In13.Cu")
		(net "M_B_CPU0_SB_DQ<9>")
	)
	(arc
		(start 332.948026 -280.078688)
		(mid 332.761082 -280.128943)
		(end 332.574138 -280.078688)
		(width 0.0889)
		(layer "In13.Cu")
		(net "M_B_CPU0_SB_DQ<9>")
	)
	(arc
		(start 332.008226 -280.078688)
		(mid 331.825975 -280.129038)
		(end 331.642466 -280.083514)
		(width 0.0889)
		(layer "In13.Cu")
		(net "M_B_CPU0_SB_DQ<9>")
	)
	(arc
		(start 331.068172 -280.078688)
		(mid 330.885921 -280.129038)
		(end 330.702412 -280.083514)
		(width 0.0889)
		(layer "In13.Cu")
		(net "M_B_CPU0_SB_DQ<9>")
	)
	(arc
		(start 335.768188 -280.078688)
		(mid 335.585937 -280.129038)
		(end 335.402428 -280.083514)
		(width 0.0889)
		(layer "In13.Cu")
		(net "M_B_CPU0_SB_DQ<9>")
	)
	(arc
		(start 333.879698 -280.083514)
		(mid 333.69619 -280.129008)
		(end 333.513938 -280.078688)
		(width 0.0889)
		(layer "In13.Cu")
		(net "M_B_CPU0_SB_DQ<9>")
	)
	(arc
		(start 336.708242 -280.078688)
		(mid 336.525991 -280.129038)
		(end 336.342482 -280.083514)
		(width 0.0889)
		(layer "In13.Cu")
		(net "M_B_CPU0_SB_DQ<9>")
	)
	(arc
		(start 337.211162 -280.046938)
		(mid 336.955954 -280.003461)
		(end 336.708242 -280.078688)
		(width 0.0889)
		(layer "In13.Cu")
		(net "M_B_CPU0_SB_DQ<9>")
	)
	(arc
		(start 332.574138 -280.078688)
		(mid 332.291182 -280.002511)
		(end 332.008226 -280.078688)
		(width 0.0889)
		(layer "In13.Cu")
		(net "M_B_CPU0_SB_DQ<9>")
	)
	(arc
		(start 336.3341 -280.078688)
		(mid 336.051144 -280.002511)
		(end 335.768188 -280.078688)
		(width 0.0889)
		(layer "In13.Cu")
		(net "M_B_CPU0_SB_DQ<9>")
	)
	(arc
		(start 331.634084 -280.078688)
		(mid 331.351128 -280.002511)
		(end 331.068172 -280.078688)
		(width 0.0889)
		(layer "In13.Cu")
		(net "M_B_CPU0_SB_DQ<9>")
	)
	(arc
		(start 328.248264 -280.078688)
		(mid 328.061066 -280.12907)
		(end 327.873868 -280.078688)
		(width 0.0889)
		(layer "In13.Cu")
		(net "M_B_CPU0_SB_DQ<9>")
	)
	(arc
		(start 333.513938 -280.078688)
		(mid 333.230982 -280.002511)
		(end 332.948026 -280.078688)
		(width 0.0889)
		(layer "In13.Cu")
		(net "M_B_CPU0_SB_DQ<9>")
	)
	(segment
		(start 336.517996 -278.680164)
		(end 336.051144 -278.946102)
		(width 0.10668)
		(layer "F.Cu")
		(net "M_B_CPU0_SB_DQ<8>")
	)
	(segment
		(start 305.316128 -290.623244)
		(end 305.395884 -290.703)
		(width 0.14478)
		(layer "In13.Cu")
		(net "M_B_CPU0_SB_DQ<8>")
	)
	(segment
		(start 306.806346 -290.929568)
		(end 306.806346 -290.554918)
		(width 0.14478)
		(layer "In13.Cu")
		(net "M_B_CPU0_SB_DQ<8>")
	)
	(segment
		(start 307.906674 -290.410138)
		(end 308.072028 -290.244784)
		(width 0.14478)
		(layer "In13.Cu")
		(net "M_B_CPU0_SB_DQ<8>")
	)
	(segment
		(start 308.997858 -290.18611)
		(end 308.666642 -289.854894)
		(width 0.14478)
		(layer "In13.Cu")
		(net "M_B_CPU0_SB_DQ<8>")
	)
	(segment
		(start 301.084488 -290.69411)
		(end 301.575724 -290.69411)
		(width 0.14478)
		(layer "In13.Cu")
		(net "M_B_CPU0_SB_DQ<8>")
	)
	(segment
		(start 326.020684 -278.84374)
		(end 326.386952 -279.210008)
		(width 0.0889)
		(layer "In13.Cu")
		(net "M_B_CPU0_SB_DQ<8>")
	)
	(segment
		(start 303.564544 -291.260276)
		(end 303.858422 -290.966398)
		(width 0.14478)
		(layer "In13.Cu")
		(net "M_B_CPU0_SB_DQ<8>")
	)
	(segment
		(start 306.110386 -290.410138)
		(end 306.255166 -290.554918)
		(width 0.14478)
		(layer "In13.Cu")
		(net "M_B_CPU0_SB_DQ<8>")
	)
	(segment
		(start 300.388528 -290.375848)
		(end 300.533308 -290.231068)
		(width 0.14478)
		(layer "In13.Cu")
		(net "M_B_CPU0_SB_DQ<8>")
	)
	(segment
		(start 306.255166 -290.929568)
		(end 306.399946 -291.074348)
		(width 0.14478)
		(layer "In13.Cu")
		(net "M_B_CPU0_SB_DQ<8>")
	)
	(segment
		(start 323.982334 -278.84374)
		(end 326.020684 -278.84374)
		(width 0.0889)
		(layer "In13.Cu")
		(net "M_B_CPU0_SB_DQ<8>")
	)
	(segment
		(start 304.092102 -290.966398)
		(end 304.253392 -291.127688)
		(width 0.14478)
		(layer "In13.Cu")
		(net "M_B_CPU0_SB_DQ<8>")
	)
	(segment
		(start 308.607968 -290.576)
		(end 308.812692 -290.576)
		(width 0.14478)
		(layer "In13.Cu")
		(net "M_B_CPU0_SB_DQ<8>")
	)
	(segment
		(start 309.777638 -289.40633)
		(end 309.446422 -289.075114)
		(width 0.14478)
		(layer "In13.Cu")
		(net "M_B_CPU0_SB_DQ<8>")
	)
	(segment
		(start 326.463406 -279.268682)
		(end 326.46366 -279.268682)
		(width 0.0889)
		(layer "In13.Cu")
		(net "M_B_CPU0_SB_DQ<8>")
	)
	(segment
		(start 319.473072 -278.84374)
		(end 323.982334 -278.84374)
		(width 0.14478)
		(layer "In13.Cu")
		(net "M_B_CPU0_SB_DQ<8>")
	)
	(segment
		(start 300.939708 -290.54933)
		(end 301.084488 -290.69411)
		(width 0.14478)
		(layer "In13.Cu")
		(net "M_B_CPU0_SB_DQ<8>")
	)
	(segment
		(start 306.255166 -290.554918)
		(end 306.255166 -290.929568)
		(width 0.14478)
		(layer "In13.Cu")
		(net "M_B_CPU0_SB_DQ<8>")
	)
	(segment
		(start 335.8007 -279.236932)
		(end 335.896966 -279.211532)
		(width 0.0889)
		(layer "In13.Cu")
		(net "M_B_CPU0_SB_DQ<8>")
	)
	(segment
		(start 308.812692 -290.576)
		(end 308.997858 -290.390834)
		(width 0.14478)
		(layer "In13.Cu")
		(net "M_B_CPU0_SB_DQ<8>")
	)
	(segment
		(start 306.399946 -291.074348)
		(end 306.661566 -291.074348)
		(width 0.14478)
		(layer "In13.Cu")
		(net "M_B_CPU0_SB_DQ<8>")
	)
	(segment
		(start 300.794928 -290.231068)
		(end 300.939708 -290.375848)
		(width 0.14478)
		(layer "In13.Cu")
		(net "M_B_CPU0_SB_DQ<8>")
	)
	(segment
		(start 303.858422 -290.966398)
		(end 304.092102 -290.966398)
		(width 0.14478)
		(layer "In13.Cu")
		(net "M_B_CPU0_SB_DQ<8>")
	)
	(segment
		(start 300.388528 -290.54933)
		(end 300.388528 -290.375848)
		(width 0.14478)
		(layer "In13.Cu")
		(net "M_B_CPU0_SB_DQ<8>")
	)
	(segment
		(start 302.900842 -291.53231)
		(end 303.172876 -291.260276)
		(width 0.14478)
		(layer "In13.Cu")
		(net "M_B_CPU0_SB_DQ<8>")
	)
	(segment
		(start 309.056532 -289.465004)
		(end 309.387748 -289.79622)
		(width 0.14478)
		(layer "In13.Cu")
		(net "M_B_CPU0_SB_DQ<8>")
	)
	(segment
		(start 305.600608 -290.703)
		(end 305.89347 -290.410138)
		(width 0.14478)
		(layer "In13.Cu")
		(net "M_B_CPU0_SB_DQ<8>")
	)
	(segment
		(start 326.819514 -279.278842)
		(end 326.837802 -279.268428)
		(width 0.0889)
		(layer "In13.Cu")
		(net "M_B_CPU0_SB_DQ<8>")
	)
	(segment
		(start 333.984092 -279.268682)
		(end 333.992474 -279.273508)
		(width 0.0889)
		(layer "In13.Cu")
		(net "M_B_CPU0_SB_DQ<8>")
	)
	(segment
		(start 306.806346 -290.554918)
		(end 306.951126 -290.410138)
		(width 0.14478)
		(layer "In13.Cu")
		(net "M_B_CPU0_SB_DQ<8>")
	)
	(segment
		(start 308.666642 -289.65017)
		(end 308.851808 -289.465004)
		(width 0.14478)
		(layer "In13.Cu")
		(net "M_B_CPU0_SB_DQ<8>")
	)
	(segment
		(start 304.414682 -291.6555)
		(end 304.648108 -291.6555)
		(width 0.14478)
		(layer "In13.Cu")
		(net "M_B_CPU0_SB_DQ<8>")
	)
	(segment
		(start 305.111912 -290.62299)
		(end 305.316128 -290.623244)
		(width 0.14478)
		(layer "In13.Cu")
		(net "M_B_CPU0_SB_DQ<8>")
	)
	(segment
		(start 308.851808 -289.465004)
		(end 309.056532 -289.465004)
		(width 0.14478)
		(layer "In13.Cu")
		(net "M_B_CPU0_SB_DQ<8>")
	)
	(segment
		(start 305.005994 -291.297614)
		(end 305.006248 -291.09289)
		(width 0.14478)
		(layer "In13.Cu")
		(net "M_B_CPU0_SB_DQ<8>")
	)
	(segment
		(start 304.253392 -291.127688)
		(end 304.253392 -291.49421)
		(width 0.14478)
		(layer "In13.Cu")
		(net "M_B_CPU0_SB_DQ<8>")
	)
	(segment
		(start 304.926492 -291.013134)
		(end 304.926492 -290.80841)
		(width 0.14478)
		(layer "In13.Cu")
		(net "M_B_CPU0_SB_DQ<8>")
	)
	(segment
		(start 299.96511 -290.69411)
		(end 300.243748 -290.69411)
		(width 0.14478)
		(layer "In13.Cu")
		(net "M_B_CPU0_SB_DQ<8>")
	)
	(segment
		(start 303.172876 -291.260276)
		(end 303.564544 -291.260276)
		(width 0.14478)
		(layer "In13.Cu")
		(net "M_B_CPU0_SB_DQ<8>")
	)
	(segment
		(start 300.243748 -290.69411)
		(end 300.388528 -290.54933)
		(width 0.14478)
		(layer "In13.Cu")
		(net "M_B_CPU0_SB_DQ<8>")
	)
	(segment
		(start 328.709782 -279.273508)
		(end 328.718164 -279.268682)
		(width 0.0889)
		(layer "In13.Cu")
		(net "M_B_CPU0_SB_DQ<8>")
	)
	(segment
		(start 306.661566 -291.074348)
		(end 306.806346 -290.929568)
		(width 0.14478)
		(layer "In13.Cu")
		(net "M_B_CPU0_SB_DQ<8>")
	)
	(segment
		(start 332.469744 -279.273508)
		(end 332.478126 -279.268682)
		(width 0.0889)
		(layer "In13.Cu")
		(net "M_B_CPU0_SB_DQ<8>")
	)
	(segment
		(start 301.575724 -290.69411)
		(end 302.413924 -291.53231)
		(width 0.14478)
		(layer "In13.Cu")
		(net "M_B_CPU0_SB_DQ<8>")
	)
	(segment
		(start 326.837802 -279.268428)
		(end 326.84339 -279.265126)
		(width 0.0889)
		(layer "In13.Cu")
		(net "M_B_CPU0_SB_DQ<8>")
	)
	(segment
		(start 304.253392 -291.49421)
		(end 304.414682 -291.6555)
		(width 0.14478)
		(layer "In13.Cu")
		(net "M_B_CPU0_SB_DQ<8>")
	)
	(segment
		(start 327.403206 -279.268682)
		(end 327.411588 -279.273508)
		(width 0.0889)
		(layer "In13.Cu")
		(net "M_B_CPU0_SB_DQ<8>")
	)
	(segment
		(start 308.666642 -289.854894)
		(end 308.666642 -289.65017)
		(width 0.14478)
		(layer "In13.Cu")
		(net "M_B_CPU0_SB_DQ<8>")
	)
	(segment
		(start 300.939708 -290.375848)
		(end 300.939708 -290.54933)
		(width 0.14478)
		(layer "In13.Cu")
		(net "M_B_CPU0_SB_DQ<8>")
	)
	(segment
		(start 309.592472 -289.79622)
		(end 309.777638 -289.611054)
		(width 0.14478)
		(layer "In13.Cu")
		(net "M_B_CPU0_SB_DQ<8>")
	)
	(segment
		(start 305.395884 -290.703)
		(end 305.600608 -290.703)
		(width 0.14478)
		(layer "In13.Cu")
		(net "M_B_CPU0_SB_DQ<8>")
	)
	(segment
		(start 306.951126 -290.410138)
		(end 307.906674 -290.410138)
		(width 0.14478)
		(layer "In13.Cu")
		(net "M_B_CPU0_SB_DQ<8>")
	)
	(segment
		(start 309.777638 -289.611054)
		(end 309.777638 -289.40633)
		(width 0.14478)
		(layer "In13.Cu")
		(net "M_B_CPU0_SB_DQ<8>")
	)
	(segment
		(start 309.446422 -289.075114)
		(end 309.446422 -288.87039)
		(width 0.14478)
		(layer "In13.Cu")
		(net "M_B_CPU0_SB_DQ<8>")
	)
	(segment
		(start 309.387748 -289.79622)
		(end 309.592472 -289.79622)
		(width 0.14478)
		(layer "In13.Cu")
		(net "M_B_CPU0_SB_DQ<8>")
	)
	(segment
		(start 302.413924 -291.53231)
		(end 302.900842 -291.53231)
		(width 0.14478)
		(layer "In13.Cu")
		(net "M_B_CPU0_SB_DQ<8>")
	)
	(segment
		(start 331.52969 -279.273508)
		(end 331.538072 -279.268682)
		(width 0.0889)
		(layer "In13.Cu")
		(net "M_B_CPU0_SB_DQ<8>")
	)
	(segment
		(start 304.648108 -291.6555)
		(end 305.005994 -291.297614)
		(width 0.14478)
		(layer "In13.Cu")
		(net "M_B_CPU0_SB_DQ<8>")
	)
	(segment
		(start 305.006248 -291.09289)
		(end 304.926492 -291.013134)
		(width 0.14478)
		(layer "In13.Cu")
		(net "M_B_CPU0_SB_DQ<8>")
	)
	(segment
		(start 329.284076 -279.268682)
		(end 329.292458 -279.273508)
		(width 0.0889)
		(layer "In13.Cu")
		(net "M_B_CPU0_SB_DQ<8>")
	)
	(segment
		(start 304.926492 -290.80841)
		(end 305.111912 -290.62299)
		(width 0.14478)
		(layer "In13.Cu")
		(net "M_B_CPU0_SB_DQ<8>")
	)
	(segment
		(start 335.896966 -279.211532)
		(end 336.051144 -278.946102)
		(width 0.0889)
		(layer "In13.Cu")
		(net "M_B_CPU0_SB_DQ<8>")
	)
	(segment
		(start 300.533308 -290.231068)
		(end 300.794928 -290.231068)
		(width 0.14478)
		(layer "In13.Cu")
		(net "M_B_CPU0_SB_DQ<8>")
	)
	(segment
		(start 328.333608 -279.262586)
		(end 328.344022 -279.268682)
		(width 0.0889)
		(layer "In13.Cu")
		(net "M_B_CPU0_SB_DQ<8>")
	)
	(segment
		(start 305.89347 -290.410138)
		(end 306.110386 -290.410138)
		(width 0.14478)
		(layer "In13.Cu")
		(net "M_B_CPU0_SB_DQ<8>")
	)
	(segment
		(start 308.997858 -290.390834)
		(end 308.997858 -290.18611)
		(width 0.14478)
		(layer "In13.Cu")
		(net "M_B_CPU0_SB_DQ<8>")
	)
	(segment
		(start 309.446422 -288.87039)
		(end 319.473072 -278.84374)
		(width 0.14478)
		(layer "In13.Cu")
		(net "M_B_CPU0_SB_DQ<8>")
	)
	(segment
		(start 308.276752 -290.244784)
		(end 308.607968 -290.576)
		(width 0.14478)
		(layer "In13.Cu")
		(net "M_B_CPU0_SB_DQ<8>")
	)
	(segment
		(start 299.82414 -290.83508)
		(end 299.96511 -290.69411)
		(width 0.14478)
		(layer "In13.Cu")
		(net "M_B_CPU0_SB_DQ<8>")
	)
	(segment
		(start 308.072028 -290.244784)
		(end 308.276752 -290.244784)
		(width 0.14478)
		(layer "In13.Cu")
		(net "M_B_CPU0_SB_DQ<8>")
	)
	(segment
		(start 333.044038 -279.268682)
		(end 333.05242 -279.273508)
		(width 0.0889)
		(layer "In13.Cu")
		(net "M_B_CPU0_SB_DQ<8>")
	)
	(arc
		(start 334.924146 -279.268682)
		(mid 335.11109 -279.318937)
		(end 335.298034 -279.268682)
		(width 0.0889)
		(layer "In13.Cu")
		(net "M_B_CPU0_SB_DQ<8>")
	)
	(arc
		(start 330.22413 -279.268682)
		(mid 330.411074 -279.318937)
		(end 330.598018 -279.268682)
		(width 0.0889)
		(layer "In13.Cu")
		(net "M_B_CPU0_SB_DQ<8>")
	)
	(arc
		(start 331.538072 -279.268682)
		(mid 331.821028 -279.192505)
		(end 332.103984 -279.268682)
		(width 0.0889)
		(layer "In13.Cu")
		(net "M_B_CPU0_SB_DQ<8>")
	)
	(arc
		(start 333.992474 -279.273508)
		(mid 334.175982 -279.319002)
		(end 334.358234 -279.268682)
		(width 0.0889)
		(layer "In13.Cu")
		(net "M_B_CPU0_SB_DQ<8>")
	)
	(arc
		(start 329.658218 -279.268682)
		(mid 329.941174 -279.192505)
		(end 330.22413 -279.268682)
		(width 0.0889)
		(layer "In13.Cu")
		(net "M_B_CPU0_SB_DQ<8>")
	)
	(arc
		(start 328.718164 -279.268682)
		(mid 329.00112 -279.192505)
		(end 329.284076 -279.268682)
		(width 0.0889)
		(layer "In13.Cu")
		(net "M_B_CPU0_SB_DQ<8>")
	)
	(arc
		(start 333.05242 -279.273508)
		(mid 333.235928 -279.319002)
		(end 333.41818 -279.268682)
		(width 0.0889)
		(layer "In13.Cu")
		(net "M_B_CPU0_SB_DQ<8>")
	)
	(arc
		(start 331.16393 -279.268682)
		(mid 331.346181 -279.319032)
		(end 331.52969 -279.273508)
		(width 0.0889)
		(layer "In13.Cu")
		(net "M_B_CPU0_SB_DQ<8>")
	)
	(arc
		(start 326.84339 -279.265126)
		(mid 327.123779 -279.192457)
		(end 327.403206 -279.268682)
		(width 0.0889)
		(layer "In13.Cu")
		(net "M_B_CPU0_SB_DQ<8>")
	)
	(arc
		(start 328.344022 -279.268682)
		(mid 328.526273 -279.319032)
		(end 328.709782 -279.273508)
		(width 0.0889)
		(layer "In13.Cu")
		(net "M_B_CPU0_SB_DQ<8>")
	)
	(arc
		(start 327.777856 -279.268682)
		(mid 328.054923 -279.192411)
		(end 328.333608 -279.262586)
		(width 0.0889)
		(layer "In13.Cu")
		(net "M_B_CPU0_SB_DQ<8>")
	)
	(arc
		(start 330.598018 -279.268682)
		(mid 330.880974 -279.192505)
		(end 331.16393 -279.268682)
		(width 0.0889)
		(layer "In13.Cu")
		(net "M_B_CPU0_SB_DQ<8>")
	)
	(arc
		(start 334.358234 -279.268682)
		(mid 334.64119 -279.192505)
		(end 334.924146 -279.268682)
		(width 0.0889)
		(layer "In13.Cu")
		(net "M_B_CPU0_SB_DQ<8>")
	)
	(arc
		(start 329.292458 -279.273508)
		(mid 329.475966 -279.319002)
		(end 329.658218 -279.268682)
		(width 0.0889)
		(layer "In13.Cu")
		(net "M_B_CPU0_SB_DQ<8>")
	)
	(arc
		(start 326.46366 -279.268682)
		(mid 326.640288 -279.318915)
		(end 326.819514 -279.278842)
		(width 0.0889)
		(layer "In13.Cu")
		(net "M_B_CPU0_SB_DQ<8>")
	)
	(arc
		(start 332.478126 -279.268682)
		(mid 332.761082 -279.192505)
		(end 333.044038 -279.268682)
		(width 0.0889)
		(layer "In13.Cu")
		(net "M_B_CPU0_SB_DQ<8>")
	)
	(arc
		(start 327.411588 -279.273508)
		(mid 327.59535 -279.319124)
		(end 327.777856 -279.268682)
		(width 0.0889)
		(layer "In13.Cu")
		(net "M_B_CPU0_SB_DQ<8>")
	)
	(arc
		(start 326.386952 -279.210008)
		(mid 326.423279 -279.241821)
		(end 326.463406 -279.268682)
		(width 0.0889)
		(layer "In13.Cu")
		(net "M_B_CPU0_SB_DQ<8>")
	)
	(arc
		(start 333.41818 -279.268682)
		(mid 333.701136 -279.192505)
		(end 333.984092 -279.268682)
		(width 0.0889)
		(layer "In13.Cu")
		(net "M_B_CPU0_SB_DQ<8>")
	)
	(arc
		(start 332.103984 -279.268682)
		(mid 332.286235 -279.319032)
		(end 332.469744 -279.273508)
		(width 0.0889)
		(layer "In13.Cu")
		(net "M_B_CPU0_SB_DQ<8>")
	)
	(arc
		(start 335.298034 -279.268682)
		(mid 335.54563 -279.193504)
		(end 335.8007 -279.236932)
		(width 0.0889)
		(layer "In13.Cu")
		(net "M_B_CPU0_SB_DQ<8>")
	)
	(segment
		(start 337.45805 -278.680164)
		(end 336.991198 -278.946102)
		(width 0.10668)
		(layer "F.Cu")
		(net "M_B_CPU0_SB_DQ<7>")
	)
	(segment
		(start 305.272948 -290.03371)
		(end 301.75962 -290.03371)
		(width 0.14478)
		(layer "In13.Cu")
		(net "M_B_CPU0_SB_DQ<7>")
	)
	(segment
		(start 300.615858 -289.56)
		(end 299.689774 -289.56)
		(width 0.14478)
		(layer "In13.Cu")
		(net "M_B_CPU0_SB_DQ<7>")
	)
	(segment
		(start 333.05242 -278.618696)
		(end 333.044038 -278.623522)
		(width 0.0889)
		(layer "In13.Cu")
		(net "M_B_CPU0_SB_DQ<7>")
	)
	(segment
		(start 336.238088 -278.623522)
		(end 336.229706 -278.618696)
		(width 0.0889)
		(layer "In13.Cu")
		(net "M_B_CPU0_SB_DQ<7>")
	)
	(segment
		(start 337.145122 -278.680672)
		(end 337.12277 -278.59736)
		(width 0.0889)
		(layer "In13.Cu")
		(net "M_B_CPU0_SB_DQ<7>")
	)
	(segment
		(start 328.344022 -278.623522)
		(end 328.333608 -278.629618)
		(width 0.0889)
		(layer "In13.Cu")
		(net "M_B_CPU0_SB_DQ<7>")
	)
	(segment
		(start 305.561492 -289.914076)
		(end 305.272948 -290.03371)
		(width 0.14478)
		(layer "In13.Cu")
		(net "M_B_CPU0_SB_DQ<7>")
	)
	(segment
		(start 307.342286 -289.56)
		(end 305.561492 -289.914076)
		(width 0.14478)
		(layer "In13.Cu")
		(net "M_B_CPU0_SB_DQ<7>")
	)
	(segment
		(start 323.97446 -278.28748)
		(end 319.249806 -278.28748)
		(width 0.14478)
		(layer "In13.Cu")
		(net "M_B_CPU0_SB_DQ<7>")
	)
	(segment
		(start 328.718164 -278.623522)
		(end 328.709782 -278.618696)
		(width 0.0889)
		(layer "In13.Cu")
		(net "M_B_CPU0_SB_DQ<7>")
	)
	(segment
		(start 327.274936 -278.487632)
		(end 324.767448 -278.487632)
		(width 0.0889)
		(layer "In13.Cu")
		(net "M_B_CPU0_SB_DQ<7>")
	)
	(segment
		(start 319.249806 -278.28748)
		(end 308.209442 -289.327844)
		(width 0.14478)
		(layer "In13.Cu")
		(net "M_B_CPU0_SB_DQ<7>")
	)
	(segment
		(start 307.648864 -289.56)
		(end 307.342286 -289.56)
		(width 0.14478)
		(layer "In13.Cu")
		(net "M_B_CPU0_SB_DQ<7>")
	)
	(segment
		(start 331.538072 -278.623522)
		(end 331.52969 -278.618696)
		(width 0.0889)
		(layer "In13.Cu")
		(net "M_B_CPU0_SB_DQ<7>")
	)
	(segment
		(start 324.520306 -278.28748)
		(end 323.97446 -278.28748)
		(width 0.0889)
		(layer "In13.Cu")
		(net "M_B_CPU0_SB_DQ<7>")
	)
	(segment
		(start 336.991198 -278.946102)
		(end 337.145122 -278.680672)
		(width 0.0889)
		(layer "In13.Cu")
		(net "M_B_CPU0_SB_DQ<7>")
	)
	(segment
		(start 329.292458 -278.618696)
		(end 329.284076 -278.623522)
		(width 0.0889)
		(layer "In13.Cu")
		(net "M_B_CPU0_SB_DQ<7>")
	)
	(segment
		(start 332.478126 -278.623522)
		(end 332.469744 -278.618696)
		(width 0.0889)
		(layer "In13.Cu")
		(net "M_B_CPU0_SB_DQ<7>")
	)
	(segment
		(start 301.75962 -290.03371)
		(end 300.615858 -289.56)
		(width 0.14478)
		(layer "In13.Cu")
		(net "M_B_CPU0_SB_DQ<7>")
	)
	(segment
		(start 333.992474 -278.618696)
		(end 333.984092 -278.623522)
		(width 0.0889)
		(layer "In13.Cu")
		(net "M_B_CPU0_SB_DQ<7>")
	)
	(segment
		(start 308.209442 -289.327844)
		(end 307.648864 -289.56)
		(width 0.14478)
		(layer "In13.Cu")
		(net "M_B_CPU0_SB_DQ<7>")
	)
	(segment
		(start 324.687184 -278.454358)
		(end 324.520306 -278.28748)
		(width 0.0889)
		(layer "In13.Cu")
		(net "M_B_CPU0_SB_DQ<7>")
	)
	(segment
		(start 299.689774 -289.56)
		(end 295.724072 -289.985196)
		(width 0.14478)
		(layer "In13.Cu")
		(net "M_B_CPU0_SB_DQ<7>")
	)
	(arc
		(start 333.044038 -278.623522)
		(mid 332.761082 -278.699699)
		(end 332.478126 -278.623522)
		(width 0.0889)
		(layer "In13.Cu")
		(net "M_B_CPU0_SB_DQ<7>")
	)
	(arc
		(start 336.804 -278.623522)
		(mid 336.521044 -278.699699)
		(end 336.238088 -278.623522)
		(width 0.0889)
		(layer "In13.Cu")
		(net "M_B_CPU0_SB_DQ<7>")
	)
	(arc
		(start 327.777856 -278.623522)
		(mid 327.535416 -278.522192)
		(end 327.274936 -278.487632)
		(width 0.0889)
		(layer "In13.Cu")
		(net "M_B_CPU0_SB_DQ<7>")
	)
	(arc
		(start 336.229706 -278.618696)
		(mid 336.046198 -278.573202)
		(end 335.863946 -278.623522)
		(width 0.0889)
		(layer "In13.Cu")
		(net "M_B_CPU0_SB_DQ<7>")
	)
	(arc
		(start 332.103984 -278.623522)
		(mid 331.821028 -278.699699)
		(end 331.538072 -278.623522)
		(width 0.0889)
		(layer "In13.Cu")
		(net "M_B_CPU0_SB_DQ<7>")
	)
	(arc
		(start 328.709782 -278.618696)
		(mid 328.526274 -278.573202)
		(end 328.344022 -278.623522)
		(width 0.0889)
		(layer "In13.Cu")
		(net "M_B_CPU0_SB_DQ<7>")
	)
	(arc
		(start 331.52969 -278.618696)
		(mid 331.346182 -278.573202)
		(end 331.16393 -278.623522)
		(width 0.0889)
		(layer "In13.Cu")
		(net "M_B_CPU0_SB_DQ<7>")
	)
	(arc
		(start 329.658218 -278.623522)
		(mid 329.475967 -278.573172)
		(end 329.292458 -278.618696)
		(width 0.0889)
		(layer "In13.Cu")
		(net "M_B_CPU0_SB_DQ<7>")
	)
	(arc
		(start 329.284076 -278.623522)
		(mid 329.00112 -278.699699)
		(end 328.718164 -278.623522)
		(width 0.0889)
		(layer "In13.Cu")
		(net "M_B_CPU0_SB_DQ<7>")
	)
	(arc
		(start 332.469744 -278.618696)
		(mid 332.286236 -278.573202)
		(end 332.103984 -278.623522)
		(width 0.0889)
		(layer "In13.Cu")
		(net "M_B_CPU0_SB_DQ<7>")
	)
	(arc
		(start 324.767448 -278.487632)
		(mid 324.724013 -278.478974)
		(end 324.687184 -278.454358)
		(width 0.0889)
		(layer "In13.Cu")
		(net "M_B_CPU0_SB_DQ<7>")
	)
	(arc
		(start 335.863946 -278.623522)
		(mid 335.58099 -278.699699)
		(end 335.298034 -278.623522)
		(width 0.0889)
		(layer "In13.Cu")
		(net "M_B_CPU0_SB_DQ<7>")
	)
	(arc
		(start 331.16393 -278.623522)
		(mid 330.880974 -278.699699)
		(end 330.598018 -278.623522)
		(width 0.0889)
		(layer "In13.Cu")
		(net "M_B_CPU0_SB_DQ<7>")
	)
	(arc
		(start 328.333608 -278.629618)
		(mid 328.054922 -278.699838)
		(end 327.777856 -278.623522)
		(width 0.0889)
		(layer "In13.Cu")
		(net "M_B_CPU0_SB_DQ<7>")
	)
	(arc
		(start 333.41818 -278.623522)
		(mid 333.235929 -278.573172)
		(end 333.05242 -278.618696)
		(width 0.0889)
		(layer "In13.Cu")
		(net "M_B_CPU0_SB_DQ<7>")
	)
	(arc
		(start 334.924146 -278.623522)
		(mid 334.64119 -278.699699)
		(end 334.358234 -278.623522)
		(width 0.0889)
		(layer "In13.Cu")
		(net "M_B_CPU0_SB_DQ<7>")
	)
	(arc
		(start 337.12277 -278.59736)
		(mid 336.960438 -278.574542)
		(end 336.804 -278.623522)
		(width 0.0889)
		(layer "In13.Cu")
		(net "M_B_CPU0_SB_DQ<7>")
	)
	(arc
		(start 330.598018 -278.623522)
		(mid 330.411074 -278.573267)
		(end 330.22413 -278.623522)
		(width 0.0889)
		(layer "In13.Cu")
		(net "M_B_CPU0_SB_DQ<7>")
	)
	(arc
		(start 334.358234 -278.623522)
		(mid 334.175983 -278.573172)
		(end 333.992474 -278.618696)
		(width 0.0889)
		(layer "In13.Cu")
		(net "M_B_CPU0_SB_DQ<7>")
	)
	(arc
		(start 335.298034 -278.623522)
		(mid 335.11109 -278.573267)
		(end 334.924146 -278.623522)
		(width 0.0889)
		(layer "In13.Cu")
		(net "M_B_CPU0_SB_DQ<7>")
	)
	(arc
		(start 330.22413 -278.623522)
		(mid 329.941174 -278.699699)
		(end 329.658218 -278.623522)
		(width 0.0889)
		(layer "In13.Cu")
		(net "M_B_CPU0_SB_DQ<7>")
	)
	(arc
		(start 333.984092 -278.623522)
		(mid 333.701136 -278.699699)
		(end 333.41818 -278.623522)
		(width 0.0889)
		(layer "In13.Cu")
		(net "M_B_CPU0_SB_DQ<7>")
	)
	(segment
		(start 336.047842 -277.870158)
		(end 335.58099 -278.136096)
		(width 0.10668)
		(layer "F.Cu")
		(net "M_B_CPU0_SB_DQ<6>")
	)
	(segment
		(start 328.239882 -277.80869)
		(end 328.248264 -277.813516)
		(width 0.0889)
		(layer "In13.Cu")
		(net "M_B_CPU0_SB_DQ<6>")
	)
	(segment
		(start 298.908216 -287.859978)
		(end 301.170848 -287.859978)
		(width 0.14478)
		(layer "In13.Cu")
		(net "M_B_CPU0_SB_DQ<6>")
	)
	(segment
		(start 331.634084 -277.813516)
		(end 331.642466 -277.80869)
		(width 0.0889)
		(layer "In13.Cu")
		(net "M_B_CPU0_SB_DQ<6>")
	)
	(segment
		(start 333.88808 -277.813516)
		(end 333.888334 -277.813516)
		(width 0.0889)
		(layer "In13.Cu")
		(net "M_B_CPU0_SB_DQ<6>")
	)
	(segment
		(start 330.69403 -277.813516)
		(end 330.702412 -277.80869)
		(width 0.0889)
		(layer "In13.Cu")
		(net "M_B_CPU0_SB_DQ<6>")
	)
	(segment
		(start 323.894704 -277.37816)
		(end 325.909686 -277.37816)
		(width 0.0889)
		(layer "In13.Cu")
		(net "M_B_CPU0_SB_DQ<6>")
	)
	(segment
		(start 308.405022 -287.859978)
		(end 318.88684 -277.37816)
		(width 0.14478)
		(layer "In13.Cu")
		(net "M_B_CPU0_SB_DQ<6>")
	)
	(segment
		(start 325.909686 -277.37816)
		(end 326.421242 -277.889716)
		(width 0.0889)
		(layer "In13.Cu")
		(net "M_B_CPU0_SB_DQ<6>")
	)
	(segment
		(start 306.23764 -287.859978)
		(end 308.405022 -287.859978)
		(width 0.14478)
		(layer "In13.Cu")
		(net "M_B_CPU0_SB_DQ<6>")
	)
	(segment
		(start 335.712816 -277.787354)
		(end 335.735168 -277.870666)
		(width 0.0889)
		(layer "In13.Cu")
		(net "M_B_CPU0_SB_DQ<6>")
	)
	(segment
		(start 302.020986 -288.710116)
		(end 305.387502 -288.710116)
		(width 0.14478)
		(layer "In13.Cu")
		(net "M_B_CPU0_SB_DQ<6>")
	)
	(segment
		(start 301.170848 -287.859978)
		(end 302.020986 -288.710116)
		(width 0.14478)
		(layer "In13.Cu")
		(net "M_B_CPU0_SB_DQ<6>")
	)
	(segment
		(start 327.307448 -277.813516)
		(end 327.317862 -277.819612)
		(width 0.0889)
		(layer "In13.Cu")
		(net "M_B_CPU0_SB_DQ<6>")
	)
	(segment
		(start 298.48302 -288.285174)
		(end 298.908216 -287.859978)
		(width 0.14478)
		(layer "In13.Cu")
		(net "M_B_CPU0_SB_DQ<6>")
	)
	(segment
		(start 318.88684 -277.37816)
		(end 323.894704 -277.37816)
		(width 0.14478)
		(layer "In13.Cu")
		(net "M_B_CPU0_SB_DQ<6>")
	)
	(segment
		(start 326.421242 -277.889716)
		(end 326.651112 -277.889716)
		(width 0.0889)
		(layer "In13.Cu")
		(net "M_B_CPU0_SB_DQ<6>")
	)
	(segment
		(start 335.394046 -277.813516)
		(end 335.402428 -277.80869)
		(width 0.0889)
		(layer "In13.Cu")
		(net "M_B_CPU0_SB_DQ<6>")
	)
	(segment
		(start 295.724072 -288.285174)
		(end 298.48302 -288.285174)
		(width 0.14478)
		(layer "In13.Cu")
		(net "M_B_CPU0_SB_DQ<6>")
	)
	(segment
		(start 326.93356 -277.81377)
		(end 326.949816 -277.804372)
		(width 0.0889)
		(layer "In13.Cu")
		(net "M_B_CPU0_SB_DQ<6>")
	)
	(segment
		(start 334.819752 -277.80869)
		(end 334.828134 -277.813516)
		(width 0.0889)
		(layer "In13.Cu")
		(net "M_B_CPU0_SB_DQ<6>")
	)
	(segment
		(start 305.387502 -288.710116)
		(end 306.23764 -287.859978)
		(width 0.14478)
		(layer "In13.Cu")
		(net "M_B_CPU0_SB_DQ<6>")
	)
	(segment
		(start 330.119736 -277.80869)
		(end 330.128118 -277.813516)
		(width 0.0889)
		(layer "In13.Cu")
		(net "M_B_CPU0_SB_DQ<6>")
	)
	(segment
		(start 335.735168 -277.870666)
		(end 335.58099 -278.136096)
		(width 0.0889)
		(layer "In13.Cu")
		(net "M_B_CPU0_SB_DQ<6>")
	)
	(segment
		(start 333.879698 -277.80869)
		(end 333.88808 -277.813516)
		(width 0.0889)
		(layer "In13.Cu")
		(net "M_B_CPU0_SB_DQ<6>")
	)
	(arc
		(start 328.814176 -277.813516)
		(mid 329.00112 -277.763261)
		(end 329.188064 -277.813516)
		(width 0.0889)
		(layer "In13.Cu")
		(net "M_B_CPU0_SB_DQ<6>")
	)
	(arc
		(start 329.188064 -277.813516)
		(mid 329.47102 -277.889693)
		(end 329.753976 -277.813516)
		(width 0.0889)
		(layer "In13.Cu")
		(net "M_B_CPU0_SB_DQ<6>")
	)
	(arc
		(start 328.248264 -277.813516)
		(mid 328.53122 -277.889693)
		(end 328.814176 -277.813516)
		(width 0.0889)
		(layer "In13.Cu")
		(net "M_B_CPU0_SB_DQ<6>")
	)
	(arc
		(start 327.873614 -277.813516)
		(mid 328.056119 -277.763039)
		(end 328.239882 -277.80869)
		(width 0.0889)
		(layer "In13.Cu")
		(net "M_B_CPU0_SB_DQ<6>")
	)
	(arc
		(start 327.317862 -277.819612)
		(mid 327.596548 -277.889832)
		(end 327.873614 -277.813516)
		(width 0.0889)
		(layer "In13.Cu")
		(net "M_B_CPU0_SB_DQ<6>")
	)
	(arc
		(start 331.068172 -277.813516)
		(mid 331.351128 -277.889693)
		(end 331.634084 -277.813516)
		(width 0.0889)
		(layer "In13.Cu")
		(net "M_B_CPU0_SB_DQ<6>")
	)
	(arc
		(start 333.888334 -277.813516)
		(mid 334.17118 -277.889693)
		(end 334.453992 -277.813516)
		(width 0.0889)
		(layer "In13.Cu")
		(net "M_B_CPU0_SB_DQ<6>")
	)
	(arc
		(start 330.702412 -277.80869)
		(mid 330.88592 -277.763196)
		(end 331.068172 -277.813516)
		(width 0.0889)
		(layer "In13.Cu")
		(net "M_B_CPU0_SB_DQ<6>")
	)
	(arc
		(start 330.128118 -277.813516)
		(mid 330.411074 -277.889693)
		(end 330.69403 -277.813516)
		(width 0.0889)
		(layer "In13.Cu")
		(net "M_B_CPU0_SB_DQ<6>")
	)
	(arc
		(start 332.574138 -277.813516)
		(mid 332.761082 -277.763261)
		(end 332.948026 -277.813516)
		(width 0.0889)
		(layer "In13.Cu")
		(net "M_B_CPU0_SB_DQ<6>")
	)
	(arc
		(start 326.651112 -277.889716)
		(mid 326.79736 -277.870411)
		(end 326.93356 -277.81377)
		(width 0.0889)
		(layer "In13.Cu")
		(net "M_B_CPU0_SB_DQ<6>")
	)
	(arc
		(start 334.453992 -277.813516)
		(mid 334.636243 -277.763166)
		(end 334.819752 -277.80869)
		(width 0.0889)
		(layer "In13.Cu")
		(net "M_B_CPU0_SB_DQ<6>")
	)
	(arc
		(start 326.949816 -277.804372)
		(mid 327.129798 -277.763272)
		(end 327.307448 -277.813516)
		(width 0.0889)
		(layer "In13.Cu")
		(net "M_B_CPU0_SB_DQ<6>")
	)
	(arc
		(start 332.008226 -277.813516)
		(mid 332.291182 -277.889693)
		(end 332.574138 -277.813516)
		(width 0.0889)
		(layer "In13.Cu")
		(net "M_B_CPU0_SB_DQ<6>")
	)
	(arc
		(start 335.402428 -277.80869)
		(mid 335.555298 -277.764049)
		(end 335.712816 -277.787354)
		(width 0.0889)
		(layer "In13.Cu")
		(net "M_B_CPU0_SB_DQ<6>")
	)
	(arc
		(start 332.948026 -277.813516)
		(mid 333.230982 -277.889693)
		(end 333.513938 -277.813516)
		(width 0.0889)
		(layer "In13.Cu")
		(net "M_B_CPU0_SB_DQ<6>")
	)
	(arc
		(start 329.753976 -277.813516)
		(mid 329.936227 -277.763166)
		(end 330.119736 -277.80869)
		(width 0.0889)
		(layer "In13.Cu")
		(net "M_B_CPU0_SB_DQ<6>")
	)
	(arc
		(start 333.513938 -277.813516)
		(mid 333.696189 -277.763166)
		(end 333.879698 -277.80869)
		(width 0.0889)
		(layer "In13.Cu")
		(net "M_B_CPU0_SB_DQ<6>")
	)
	(arc
		(start 334.828134 -277.813516)
		(mid 335.11109 -277.889693)
		(end 335.394046 -277.813516)
		(width 0.0889)
		(layer "In13.Cu")
		(net "M_B_CPU0_SB_DQ<6>")
	)
	(arc
		(start 331.642466 -277.80869)
		(mid 331.825974 -277.763196)
		(end 332.008226 -277.813516)
		(width 0.0889)
		(layer "In13.Cu")
		(net "M_B_CPU0_SB_DQ<6>")
	)
	(segment
		(start 337.92795 -277.870158)
		(end 337.461098 -278.136096)
		(width 0.10668)
		(layer "F.Cu")
		(net "M_B_CPU0_SB_DQ<5>")
	)
	(segment
		(start 302.791368 -289.31235)
		(end 302.791368 -289.415474)
		(width 0.14478)
		(layer "In13.Cu")
		(net "M_B_CPU0_SB_DQ<5>")
	)
	(segment
		(start 300.409102 -288.465006)
		(end 300.553882 -288.320226)
		(width 0.14478)
		(layer "In13.Cu")
		(net "M_B_CPU0_SB_DQ<5>")
	)
	(segment
		(start 337.307174 -278.401526)
		(end 337.461098 -278.136096)
		(width 0.0889)
		(layer "In13.Cu")
		(net "M_B_CPU0_SB_DQ<5>")
	)
	(segment
		(start 333.88808 -278.458676)
		(end 333.888334 -278.458676)
		(width 0.0889)
		(layer "In13.Cu")
		(net "M_B_CPU0_SB_DQ<5>")
	)
	(segment
		(start 300.409102 -288.96564)
		(end 300.409102 -288.465006)
		(width 0.14478)
		(layer "In13.Cu")
		(net "M_B_CPU0_SB_DQ<5>")
	)
	(segment
		(start 335.394046 -278.458676)
		(end 335.402428 -278.463502)
		(width 0.0889)
		(layer "In13.Cu")
		(net "M_B_CPU0_SB_DQ<5>")
	)
	(segment
		(start 302.646588 -289.16757)
		(end 302.791368 -289.31235)
		(width 0.14478)
		(layer "In13.Cu")
		(net "M_B_CPU0_SB_DQ<5>")
	)
	(segment
		(start 301.105062 -289.11042)
		(end 301.342044 -289.11042)
		(width 0.14478)
		(layer "In13.Cu")
		(net "M_B_CPU0_SB_DQ<5>")
	)
	(segment
		(start 304.034698 -289.560254)
		(end 304.179478 -289.415474)
		(width 0.14478)
		(layer "In13.Cu")
		(net "M_B_CPU0_SB_DQ<5>")
	)
	(segment
		(start 304.179478 -289.32886)
		(end 304.324258 -289.18408)
		(width 0.14478)
		(layer "In13.Cu")
		(net "M_B_CPU0_SB_DQ<5>")
	)
	(segment
		(start 308.191154 -288.710116)
		(end 319.06845 -277.83282)
		(width 0.14478)
		(layer "In13.Cu")
		(net "M_B_CPU0_SB_DQ<5>")
	)
	(segment
		(start 336.3341 -278.458676)
		(end 336.342482 -278.463502)
		(width 0.0889)
		(layer "In13.Cu")
		(net "M_B_CPU0_SB_DQ<5>")
	)
	(segment
		(start 305.22291 -289.560254)
		(end 306.16144 -288.621724)
		(width 0.14478)
		(layer "In13.Cu")
		(net "M_B_CPU0_SB_DQ<5>")
	)
	(segment
		(start 299.848778 -289.11042)
		(end 300.264322 -289.11042)
		(width 0.14478)
		(layer "In13.Cu")
		(net "M_B_CPU0_SB_DQ<5>")
	)
	(segment
		(start 306.56657 -288.621724)
		(end 306.71135 -288.766504)
		(width 0.14478)
		(layer "In13.Cu")
		(net "M_B_CPU0_SB_DQ<5>")
	)
	(segment
		(start 304.179478 -289.415474)
		(end 304.179478 -289.32886)
		(width 0.14478)
		(layer "In13.Cu")
		(net "M_B_CPU0_SB_DQ<5>")
	)
	(segment
		(start 330.69403 -278.458676)
		(end 330.702412 -278.463502)
		(width 0.0889)
		(layer "In13.Cu")
		(net "M_B_CPU0_SB_DQ<5>")
	)
	(segment
		(start 307.11775 -289.139122)
		(end 307.26253 -288.994342)
		(width 0.14478)
		(layer "In13.Cu")
		(net "M_B_CPU0_SB_DQ<5>")
	)
	(segment
		(start 307.40731 -288.710116)
		(end 308.191154 -288.710116)
		(width 0.14478)
		(layer "In13.Cu")
		(net "M_B_CPU0_SB_DQ<5>")
	)
	(segment
		(start 304.730658 -289.415474)
		(end 304.875438 -289.560254)
		(width 0.14478)
		(layer "In13.Cu")
		(net "M_B_CPU0_SB_DQ<5>")
	)
	(segment
		(start 300.815502 -288.320226)
		(end 300.960282 -288.465006)
		(width 0.14478)
		(layer "In13.Cu")
		(net "M_B_CPU0_SB_DQ<5>")
	)
	(segment
		(start 324.947788 -278.264112)
		(end 327.152508 -278.264112)
		(width 0.0889)
		(layer "In13.Cu")
		(net "M_B_CPU0_SB_DQ<5>")
	)
	(segment
		(start 324.469506 -277.83282)
		(end 324.867524 -278.230838)
		(width 0.0889)
		(layer "In13.Cu")
		(net "M_B_CPU0_SB_DQ<5>")
	)
	(segment
		(start 306.71135 -288.766504)
		(end 306.71135 -288.994342)
		(width 0.14478)
		(layer "In13.Cu")
		(net "M_B_CPU0_SB_DQ<5>")
	)
	(segment
		(start 337.211162 -278.426926)
		(end 337.307174 -278.401526)
		(width 0.0889)
		(layer "In13.Cu")
		(net "M_B_CPU0_SB_DQ<5>")
	)
	(segment
		(start 302.791368 -289.415474)
		(end 302.936148 -289.560254)
		(width 0.14478)
		(layer "In13.Cu")
		(net "M_B_CPU0_SB_DQ<5>")
	)
	(segment
		(start 306.16144 -288.621724)
		(end 306.56657 -288.621724)
		(width 0.14478)
		(layer "In13.Cu")
		(net "M_B_CPU0_SB_DQ<5>")
	)
	(segment
		(start 300.960282 -288.96564)
		(end 301.105062 -289.11042)
		(width 0.14478)
		(layer "In13.Cu")
		(net "M_B_CPU0_SB_DQ<5>")
	)
	(segment
		(start 300.264322 -289.11042)
		(end 300.409102 -288.96564)
		(width 0.14478)
		(layer "In13.Cu")
		(net "M_B_CPU0_SB_DQ<5>")
	)
	(segment
		(start 307.26253 -288.994342)
		(end 307.26253 -288.854896)
		(width 0.14478)
		(layer "In13.Cu")
		(net "M_B_CPU0_SB_DQ<5>")
	)
	(segment
		(start 304.585878 -289.18408)
		(end 304.730658 -289.32886)
		(width 0.14478)
		(layer "In13.Cu")
		(net "M_B_CPU0_SB_DQ<5>")
	)
	(segment
		(start 319.06845 -277.83282)
		(end 323.97446 -277.83282)
		(width 0.14478)
		(layer "In13.Cu")
		(net "M_B_CPU0_SB_DQ<5>")
	)
	(segment
		(start 301.791878 -289.560254)
		(end 302.095408 -289.560254)
		(width 0.14478)
		(layer "In13.Cu")
		(net "M_B_CPU0_SB_DQ<5>")
	)
	(segment
		(start 304.730658 -289.32886)
		(end 304.730658 -289.415474)
		(width 0.14478)
		(layer "In13.Cu")
		(net "M_B_CPU0_SB_DQ<5>")
	)
	(segment
		(start 307.26253 -288.854896)
		(end 307.40731 -288.710116)
		(width 0.14478)
		(layer "In13.Cu")
		(net "M_B_CPU0_SB_DQ<5>")
	)
	(segment
		(start 301.342044 -289.11042)
		(end 301.791878 -289.560254)
		(width 0.14478)
		(layer "In13.Cu")
		(net "M_B_CPU0_SB_DQ<5>")
	)
	(segment
		(start 302.240188 -289.415474)
		(end 302.240188 -289.31235)
		(width 0.14478)
		(layer "In13.Cu")
		(net "M_B_CPU0_SB_DQ<5>")
	)
	(segment
		(start 300.960282 -288.465006)
		(end 300.960282 -288.96564)
		(width 0.14478)
		(layer "In13.Cu")
		(net "M_B_CPU0_SB_DQ<5>")
	)
	(segment
		(start 299.82414 -289.135058)
		(end 299.848778 -289.11042)
		(width 0.14478)
		(layer "In13.Cu")
		(net "M_B_CPU0_SB_DQ<5>")
	)
	(segment
		(start 300.553882 -288.320226)
		(end 300.815502 -288.320226)
		(width 0.14478)
		(layer "In13.Cu")
		(net "M_B_CPU0_SB_DQ<5>")
	)
	(segment
		(start 330.119736 -278.463502)
		(end 330.128118 -278.458676)
		(width 0.0889)
		(layer "In13.Cu")
		(net "M_B_CPU0_SB_DQ<5>")
	)
	(segment
		(start 304.324258 -289.18408)
		(end 304.585878 -289.18408)
		(width 0.14478)
		(layer "In13.Cu")
		(net "M_B_CPU0_SB_DQ<5>")
	)
	(segment
		(start 331.634084 -278.458676)
		(end 331.642466 -278.463502)
		(width 0.0889)
		(layer "In13.Cu")
		(net "M_B_CPU0_SB_DQ<5>")
	)
	(segment
		(start 306.71135 -288.994342)
		(end 306.85613 -289.139122)
		(width 0.14478)
		(layer "In13.Cu")
		(net "M_B_CPU0_SB_DQ<5>")
	)
	(segment
		(start 302.384968 -289.16757)
		(end 302.646588 -289.16757)
		(width 0.14478)
		(layer "In13.Cu")
		(net "M_B_CPU0_SB_DQ<5>")
	)
	(segment
		(start 302.095408 -289.560254)
		(end 302.240188 -289.415474)
		(width 0.14478)
		(layer "In13.Cu")
		(net "M_B_CPU0_SB_DQ<5>")
	)
	(segment
		(start 302.936148 -289.560254)
		(end 304.034698 -289.560254)
		(width 0.14478)
		(layer "In13.Cu")
		(net "M_B_CPU0_SB_DQ<5>")
	)
	(segment
		(start 334.819752 -278.463502)
		(end 334.828134 -278.458676)
		(width 0.0889)
		(layer "In13.Cu")
		(net "M_B_CPU0_SB_DQ<5>")
	)
	(segment
		(start 333.879698 -278.463502)
		(end 333.88808 -278.458676)
		(width 0.0889)
		(layer "In13.Cu")
		(net "M_B_CPU0_SB_DQ<5>")
	)
	(segment
		(start 302.240188 -289.31235)
		(end 302.384968 -289.16757)
		(width 0.14478)
		(layer "In13.Cu")
		(net "M_B_CPU0_SB_DQ<5>")
	)
	(segment
		(start 323.97446 -277.83282)
		(end 324.469506 -277.83282)
		(width 0.0889)
		(layer "In13.Cu")
		(net "M_B_CPU0_SB_DQ<5>")
	)
	(segment
		(start 306.85613 -289.139122)
		(end 307.11775 -289.139122)
		(width 0.14478)
		(layer "In13.Cu")
		(net "M_B_CPU0_SB_DQ<5>")
	)
	(segment
		(start 304.875438 -289.560254)
		(end 305.22291 -289.560254)
		(width 0.14478)
		(layer "In13.Cu")
		(net "M_B_CPU0_SB_DQ<5>")
	)
	(arc
		(start 333.513938 -278.458676)
		(mid 333.696189 -278.509026)
		(end 333.879698 -278.463502)
		(width 0.0889)
		(layer "In13.Cu")
		(net "M_B_CPU0_SB_DQ<5>")
	)
	(arc
		(start 331.642466 -278.463502)
		(mid 331.825974 -278.508996)
		(end 332.008226 -278.458676)
		(width 0.0889)
		(layer "In13.Cu")
		(net "M_B_CPU0_SB_DQ<5>")
	)
	(arc
		(start 334.453992 -278.458676)
		(mid 334.636243 -278.509026)
		(end 334.819752 -278.463502)
		(width 0.0889)
		(layer "In13.Cu")
		(net "M_B_CPU0_SB_DQ<5>")
	)
	(arc
		(start 328.248264 -278.458676)
		(mid 328.53122 -278.382499)
		(end 328.814176 -278.458676)
		(width 0.0889)
		(layer "In13.Cu")
		(net "M_B_CPU0_SB_DQ<5>")
	)
	(arc
		(start 336.708242 -278.458676)
		(mid 336.955955 -278.383456)
		(end 337.211162 -278.426926)
		(width 0.0889)
		(layer "In13.Cu")
		(net "M_B_CPU0_SB_DQ<5>")
	)
	(arc
		(start 333.888334 -278.458676)
		(mid 334.17118 -278.382499)
		(end 334.453992 -278.458676)
		(width 0.0889)
		(layer "In13.Cu")
		(net "M_B_CPU0_SB_DQ<5>")
	)
	(arc
		(start 332.008226 -278.458676)
		(mid 332.291182 -278.382499)
		(end 332.574138 -278.458676)
		(width 0.0889)
		(layer "In13.Cu")
		(net "M_B_CPU0_SB_DQ<5>")
	)
	(arc
		(start 334.828134 -278.458676)
		(mid 335.11109 -278.382499)
		(end 335.394046 -278.458676)
		(width 0.0889)
		(layer "In13.Cu")
		(net "M_B_CPU0_SB_DQ<5>")
	)
	(arc
		(start 335.402428 -278.463502)
		(mid 335.585936 -278.508996)
		(end 335.768188 -278.458676)
		(width 0.0889)
		(layer "In13.Cu")
		(net "M_B_CPU0_SB_DQ<5>")
	)
	(arc
		(start 324.867524 -278.230838)
		(mid 324.904335 -278.255498)
		(end 324.947788 -278.264112)
		(width 0.0889)
		(layer "In13.Cu")
		(net "M_B_CPU0_SB_DQ<5>")
	)
	(arc
		(start 329.188064 -278.458676)
		(mid 329.47102 -278.382499)
		(end 329.753976 -278.458676)
		(width 0.0889)
		(layer "In13.Cu")
		(net "M_B_CPU0_SB_DQ<5>")
	)
	(arc
		(start 332.574138 -278.458676)
		(mid 332.761082 -278.508931)
		(end 332.948026 -278.458676)
		(width 0.0889)
		(layer "In13.Cu")
		(net "M_B_CPU0_SB_DQ<5>")
	)
	(arc
		(start 327.152508 -278.264112)
		(mid 327.526083 -278.313597)
		(end 327.873868 -278.458676)
		(width 0.0889)
		(layer "In13.Cu")
		(net "M_B_CPU0_SB_DQ<5>")
	)
	(arc
		(start 335.768188 -278.458676)
		(mid 336.051144 -278.382499)
		(end 336.3341 -278.458676)
		(width 0.0889)
		(layer "In13.Cu")
		(net "M_B_CPU0_SB_DQ<5>")
	)
	(arc
		(start 332.948026 -278.458676)
		(mid 333.230982 -278.382499)
		(end 333.513938 -278.458676)
		(width 0.0889)
		(layer "In13.Cu")
		(net "M_B_CPU0_SB_DQ<5>")
	)
	(arc
		(start 327.873868 -278.458676)
		(mid 328.061066 -278.509058)
		(end 328.248264 -278.458676)
		(width 0.0889)
		(layer "In13.Cu")
		(net "M_B_CPU0_SB_DQ<5>")
	)
	(arc
		(start 328.814176 -278.458676)
		(mid 329.00112 -278.508931)
		(end 329.188064 -278.458676)
		(width 0.0889)
		(layer "In13.Cu")
		(net "M_B_CPU0_SB_DQ<5>")
	)
	(arc
		(start 331.068172 -278.458676)
		(mid 331.351128 -278.382499)
		(end 331.634084 -278.458676)
		(width 0.0889)
		(layer "In13.Cu")
		(net "M_B_CPU0_SB_DQ<5>")
	)
	(arc
		(start 330.702412 -278.463502)
		(mid 330.88592 -278.508996)
		(end 331.068172 -278.458676)
		(width 0.0889)
		(layer "In13.Cu")
		(net "M_B_CPU0_SB_DQ<5>")
	)
	(arc
		(start 329.753976 -278.458676)
		(mid 329.936227 -278.509026)
		(end 330.119736 -278.463502)
		(width 0.0889)
		(layer "In13.Cu")
		(net "M_B_CPU0_SB_DQ<5>")
	)
	(arc
		(start 336.342482 -278.463502)
		(mid 336.52599 -278.508996)
		(end 336.708242 -278.458676)
		(width 0.0889)
		(layer "In13.Cu")
		(net "M_B_CPU0_SB_DQ<5>")
	)
	(arc
		(start 330.128118 -278.458676)
		(mid 330.411074 -278.382499)
		(end 330.69403 -278.458676)
		(width 0.0889)
		(layer "In13.Cu")
		(net "M_B_CPU0_SB_DQ<5>")
	)
	(segment
		(start 336.517996 -277.060152)
		(end 336.051144 -277.32609)
		(width 0.10668)
		(layer "F.Cu")
		(net "M_B_CPU0_SB_DQ<4>")
	)
	(segment
		(start 331.52969 -277.653496)
		(end 331.538072 -277.64867)
		(width 0.0889)
		(layer "In13.Cu")
		(net "M_B_CPU0_SB_DQ<4>")
	)
	(segment
		(start 309.09006 -286.09163)
		(end 309.5371 -286.09163)
		(width 0.14478)
		(layer "In13.Cu")
		(net "M_B_CPU0_SB_DQ<4>")
	)
	(segment
		(start 306.80025 -286.707072)
		(end 307.028596 -286.707072)
		(width 0.14478)
		(layer "In13.Cu")
		(net "M_B_CPU0_SB_DQ<4>")
	)
	(segment
		(start 326.500236 -277.699216)
		(end 326.650858 -277.699216)
		(width 0.0889)
		(layer "In13.Cu")
		(net "M_B_CPU0_SB_DQ<4>")
	)
	(segment
		(start 309.5371 -286.09163)
		(end 309.703724 -285.925006)
		(width 0.14478)
		(layer "In13.Cu")
		(net "M_B_CPU0_SB_DQ<4>")
	)
	(segment
		(start 315.946028 -279.682702)
		(end 315.946028 -279.235662)
		(width 0.14478)
		(layer "In13.Cu")
		(net "M_B_CPU0_SB_DQ<4>")
	)
	(segment
		(start 332.469744 -277.653496)
		(end 332.478126 -277.64867)
		(width 0.0889)
		(layer "In13.Cu")
		(net "M_B_CPU0_SB_DQ<4>")
	)
	(segment
		(start 333.984092 -277.64867)
		(end 333.992474 -277.653496)
		(width 0.0889)
		(layer "In13.Cu")
		(net "M_B_CPU0_SB_DQ<4>")
	)
	(segment
		(start 318.25819 -276.9235)
		(end 323.897244 -276.9235)
		(width 0.14478)
		(layer "In13.Cu")
		(net "M_B_CPU0_SB_DQ<4>")
	)
	(segment
		(start 314.218828 -281.409902)
		(end 314.385452 -281.243278)
		(width 0.14478)
		(layer "In13.Cu")
		(net "M_B_CPU0_SB_DQ<4>")
	)
	(segment
		(start 306.477162 -287.39211)
		(end 306.638706 -287.230566)
		(width 0.14478)
		(layer "In13.Cu")
		(net "M_B_CPU0_SB_DQ<4>")
	)
	(segment
		(start 313.605164 -281.576526)
		(end 313.771788 -281.409902)
		(width 0.14478)
		(layer "In13.Cu")
		(net "M_B_CPU0_SB_DQ<4>")
	)
	(segment
		(start 299.969174 -287.019746)
		(end 301.193708 -287.019746)
		(width 0.14478)
		(layer "In13.Cu")
		(net "M_B_CPU0_SB_DQ<4>")
	)
	(segment
		(start 314.999116 -280.629614)
		(end 315.16574 -280.46299)
		(width 0.14478)
		(layer "In13.Cu")
		(net "M_B_CPU0_SB_DQ<4>")
	)
	(segment
		(start 299.82414 -287.435036)
		(end 299.82414 -287.16478)
		(width 0.14478)
		(layer "In13.Cu")
		(net "M_B_CPU0_SB_DQ<4>")
	)
	(segment
		(start 307.19014 -287.230566)
		(end 307.351684 -287.39211)
		(width 0.14478)
		(layer "In13.Cu")
		(net "M_B_CPU0_SB_DQ<4>")
	)
	(segment
		(start 307.028596 -286.707072)
		(end 307.19014 -286.868616)
		(width 0.14478)
		(layer "In13.Cu")
		(net "M_B_CPU0_SB_DQ<4>")
	)
	(segment
		(start 306.638706 -286.868616)
		(end 306.80025 -286.707072)
		(width 0.14478)
		(layer "In13.Cu")
		(net "M_B_CPU0_SB_DQ<4>")
	)
	(segment
		(start 311.2643 -283.91739)
		(end 311.430924 -283.750766)
		(width 0.14478)
		(layer "In13.Cu")
		(net "M_B_CPU0_SB_DQ<4>")
	)
	(segment
		(start 316.726316 -278.455374)
		(end 316.89294 -278.28875)
		(width 0.14478)
		(layer "In13.Cu")
		(net "M_B_CPU0_SB_DQ<4>")
	)
	(segment
		(start 327.403206 -277.64867)
		(end 327.411588 -277.653496)
		(width 0.0889)
		(layer "In13.Cu")
		(net "M_B_CPU0_SB_DQ<4>")
	)
	(segment
		(start 325.919592 -277.118572)
		(end 326.500236 -277.699216)
		(width 0.0889)
		(layer "In13.Cu")
		(net "M_B_CPU0_SB_DQ<4>")
	)
	(segment
		(start 308.309772 -286.871918)
		(end 308.738524 -286.871918)
		(width 0.14478)
		(layer "In13.Cu")
		(net "M_B_CPU0_SB_DQ<4>")
	)
	(segment
		(start 313.605164 -282.023566)
		(end 313.605164 -281.576526)
		(width 0.14478)
		(layer "In13.Cu")
		(net "M_B_CPU0_SB_DQ<4>")
	)
	(segment
		(start 310.317388 -285.311342)
		(end 310.484012 -285.144718)
		(width 0.14478)
		(layer "In13.Cu")
		(net "M_B_CPU0_SB_DQ<4>")
	)
	(segment
		(start 309.703724 -285.925006)
		(end 309.703724 -285.477966)
		(width 0.14478)
		(layer "In13.Cu")
		(net "M_B_CPU0_SB_DQ<4>")
	)
	(segment
		(start 328.709782 -277.653496)
		(end 328.718164 -277.64867)
		(width 0.0889)
		(layer "In13.Cu")
		(net "M_B_CPU0_SB_DQ<4>")
	)
	(segment
		(start 312.824876 -282.356814)
		(end 312.9915 -282.19019)
		(width 0.14478)
		(layer "In13.Cu")
		(net "M_B_CPU0_SB_DQ<4>")
	)
	(segment
		(start 305.576478 -287.860232)
		(end 306.0446 -287.39211)
		(width 0.14478)
		(layer "In13.Cu")
		(net "M_B_CPU0_SB_DQ<4>")
	)
	(segment
		(start 315.332364 -279.849326)
		(end 315.779404 -279.849326)
		(width 0.14478)
		(layer "In13.Cu")
		(net "M_B_CPU0_SB_DQ<4>")
	)
	(segment
		(start 315.16574 -280.46299)
		(end 315.16574 -280.01595)
		(width 0.14478)
		(layer "In13.Cu")
		(net "M_B_CPU0_SB_DQ<4>")
	)
	(segment
		(start 306.0446 -287.39211)
		(end 306.477162 -287.39211)
		(width 0.14478)
		(layer "In13.Cu")
		(net "M_B_CPU0_SB_DQ<4>")
	)
	(segment
		(start 312.824876 -282.803854)
		(end 312.824876 -282.356814)
		(width 0.14478)
		(layer "In13.Cu")
		(net "M_B_CPU0_SB_DQ<4>")
	)
	(segment
		(start 302.034194 -287.860232)
		(end 305.576478 -287.860232)
		(width 0.14478)
		(layer "In13.Cu")
		(net "M_B_CPU0_SB_DQ<4>")
	)
	(segment
		(start 316.112652 -279.069038)
		(end 316.559692 -279.069038)
		(width 0.14478)
		(layer "In13.Cu")
		(net "M_B_CPU0_SB_DQ<4>")
	)
	(segment
		(start 333.044038 -277.64867)
		(end 333.05242 -277.653496)
		(width 0.0889)
		(layer "In13.Cu")
		(net "M_B_CPU0_SB_DQ<4>")
	)
	(segment
		(start 308.923436 -286.258254)
		(end 309.09006 -286.09163)
		(width 0.14478)
		(layer "In13.Cu")
		(net "M_B_CPU0_SB_DQ<4>")
	)
	(segment
		(start 326.837802 -277.648416)
		(end 326.84339 -277.645114)
		(width 0.0889)
		(layer "In13.Cu")
		(net "M_B_CPU0_SB_DQ<4>")
	)
	(segment
		(start 311.430924 -283.750766)
		(end 311.877964 -283.750766)
		(width 0.14478)
		(layer "In13.Cu")
		(net "M_B_CPU0_SB_DQ<4>")
	)
	(segment
		(start 324.509638 -277.118572)
		(end 325.919592 -277.118572)
		(width 0.0889)
		(layer "In13.Cu")
		(net "M_B_CPU0_SB_DQ<4>")
	)
	(segment
		(start 317.506604 -278.122126)
		(end 317.506604 -277.675086)
		(width 0.14478)
		(layer "In13.Cu")
		(net "M_B_CPU0_SB_DQ<4>")
	)
	(segment
		(start 310.650636 -284.531054)
		(end 311.097676 -284.531054)
		(width 0.14478)
		(layer "In13.Cu")
		(net "M_B_CPU0_SB_DQ<4>")
	)
	(segment
		(start 310.484012 -285.144718)
		(end 310.484012 -284.697678)
		(width 0.14478)
		(layer "In13.Cu")
		(net "M_B_CPU0_SB_DQ<4>")
	)
	(segment
		(start 311.097676 -284.531054)
		(end 311.2643 -284.36443)
		(width 0.14478)
		(layer "In13.Cu")
		(net "M_B_CPU0_SB_DQ<4>")
	)
	(segment
		(start 313.771788 -281.409902)
		(end 314.218828 -281.409902)
		(width 0.14478)
		(layer "In13.Cu")
		(net "M_B_CPU0_SB_DQ<4>")
	)
	(segment
		(start 315.779404 -279.849326)
		(end 315.946028 -279.682702)
		(width 0.14478)
		(layer "In13.Cu")
		(net "M_B_CPU0_SB_DQ<4>")
	)
	(segment
		(start 309.703724 -285.477966)
		(end 309.870348 -285.311342)
		(width 0.14478)
		(layer "In13.Cu")
		(net "M_B_CPU0_SB_DQ<4>")
	)
	(segment
		(start 312.211212 -282.970478)
		(end 312.658252 -282.970478)
		(width 0.14478)
		(layer "In13.Cu")
		(net "M_B_CPU0_SB_DQ<4>")
	)
	(segment
		(start 317.506604 -277.675086)
		(end 318.25819 -276.9235)
		(width 0.14478)
		(layer "In13.Cu")
		(net "M_B_CPU0_SB_DQ<4>")
	)
	(segment
		(start 311.2643 -284.36443)
		(end 311.2643 -283.91739)
		(width 0.14478)
		(layer "In13.Cu")
		(net "M_B_CPU0_SB_DQ<4>")
	)
	(segment
		(start 313.43854 -282.19019)
		(end 313.605164 -282.023566)
		(width 0.14478)
		(layer "In13.Cu")
		(net "M_B_CPU0_SB_DQ<4>")
	)
	(segment
		(start 335.896966 -277.59152)
		(end 336.051144 -277.32609)
		(width 0.0889)
		(layer "In13.Cu")
		(net "M_B_CPU0_SB_DQ<4>")
	)
	(segment
		(start 308.923436 -286.687006)
		(end 308.923436 -286.258254)
		(width 0.14478)
		(layer "In13.Cu")
		(net "M_B_CPU0_SB_DQ<4>")
	)
	(segment
		(start 301.193708 -287.019746)
		(end 302.034194 -287.860232)
		(width 0.14478)
		(layer "In13.Cu")
		(net "M_B_CPU0_SB_DQ<4>")
	)
	(segment
		(start 323.897244 -276.9235)
		(end 324.314566 -276.9235)
		(width 0.0889)
		(layer "In13.Cu")
		(net "M_B_CPU0_SB_DQ<4>")
	)
	(segment
		(start 307.19014 -286.868616)
		(end 307.19014 -287.230566)
		(width 0.14478)
		(layer "In13.Cu")
		(net "M_B_CPU0_SB_DQ<4>")
	)
	(segment
		(start 314.552076 -280.629614)
		(end 314.999116 -280.629614)
		(width 0.14478)
		(layer "In13.Cu")
		(net "M_B_CPU0_SB_DQ<4>")
	)
	(segment
		(start 307.351684 -287.39211)
		(end 307.78958 -287.39211)
		(width 0.14478)
		(layer "In13.Cu")
		(net "M_B_CPU0_SB_DQ<4>")
	)
	(segment
		(start 306.638706 -287.230566)
		(end 306.638706 -286.868616)
		(width 0.14478)
		(layer "In13.Cu")
		(net "M_B_CPU0_SB_DQ<4>")
	)
	(segment
		(start 310.484012 -284.697678)
		(end 310.650636 -284.531054)
		(width 0.14478)
		(layer "In13.Cu")
		(net "M_B_CPU0_SB_DQ<4>")
	)
	(segment
		(start 328.333608 -277.642574)
		(end 328.344022 -277.64867)
		(width 0.0889)
		(layer "In13.Cu")
		(net "M_B_CPU0_SB_DQ<4>")
	)
	(segment
		(start 309.870348 -285.311342)
		(end 310.317388 -285.311342)
		(width 0.14478)
		(layer "In13.Cu")
		(net "M_B_CPU0_SB_DQ<4>")
	)
	(segment
		(start 315.946028 -279.235662)
		(end 316.112652 -279.069038)
		(width 0.14478)
		(layer "In13.Cu")
		(net "M_B_CPU0_SB_DQ<4>")
	)
	(segment
		(start 311.877964 -283.750766)
		(end 312.044588 -283.584142)
		(width 0.14478)
		(layer "In13.Cu")
		(net "M_B_CPU0_SB_DQ<4>")
	)
	(segment
		(start 329.284076 -277.64867)
		(end 329.292458 -277.653496)
		(width 0.0889)
		(layer "In13.Cu")
		(net "M_B_CPU0_SB_DQ<4>")
	)
	(segment
		(start 312.044588 -283.584142)
		(end 312.044588 -283.137102)
		(width 0.14478)
		(layer "In13.Cu")
		(net "M_B_CPU0_SB_DQ<4>")
	)
	(segment
		(start 315.16574 -280.01595)
		(end 315.332364 -279.849326)
		(width 0.14478)
		(layer "In13.Cu")
		(net "M_B_CPU0_SB_DQ<4>")
	)
	(segment
		(start 299.82414 -287.16478)
		(end 299.969174 -287.019746)
		(width 0.14478)
		(layer "In13.Cu")
		(net "M_B_CPU0_SB_DQ<4>")
	)
	(segment
		(start 307.78958 -287.39211)
		(end 308.309772 -286.871918)
		(width 0.14478)
		(layer "In13.Cu")
		(net "M_B_CPU0_SB_DQ<4>")
	)
	(segment
		(start 308.738524 -286.871918)
		(end 308.923436 -286.687006)
		(width 0.14478)
		(layer "In13.Cu")
		(net "M_B_CPU0_SB_DQ<4>")
	)
	(segment
		(start 312.044588 -283.137102)
		(end 312.211212 -282.970478)
		(width 0.14478)
		(layer "In13.Cu")
		(net "M_B_CPU0_SB_DQ<4>")
	)
	(segment
		(start 316.726316 -278.902414)
		(end 316.726316 -278.455374)
		(width 0.14478)
		(layer "In13.Cu")
		(net "M_B_CPU0_SB_DQ<4>")
	)
	(segment
		(start 324.314566 -276.9235)
		(end 324.509638 -277.118572)
		(width 0.0889)
		(layer "In13.Cu")
		(net "M_B_CPU0_SB_DQ<4>")
	)
	(segment
		(start 312.9915 -282.19019)
		(end 313.43854 -282.19019)
		(width 0.14478)
		(layer "In13.Cu")
		(net "M_B_CPU0_SB_DQ<4>")
	)
	(segment
		(start 316.89294 -278.28875)
		(end 317.33998 -278.28875)
		(width 0.14478)
		(layer "In13.Cu")
		(net "M_B_CPU0_SB_DQ<4>")
	)
	(segment
		(start 312.658252 -282.970478)
		(end 312.824876 -282.803854)
		(width 0.14478)
		(layer "In13.Cu")
		(net "M_B_CPU0_SB_DQ<4>")
	)
	(segment
		(start 314.385452 -280.796238)
		(end 314.552076 -280.629614)
		(width 0.14478)
		(layer "In13.Cu")
		(net "M_B_CPU0_SB_DQ<4>")
	)
	(segment
		(start 316.559692 -279.069038)
		(end 316.726316 -278.902414)
		(width 0.14478)
		(layer "In13.Cu")
		(net "M_B_CPU0_SB_DQ<4>")
	)
	(segment
		(start 335.8007 -277.61692)
		(end 335.896966 -277.59152)
		(width 0.0889)
		(layer "In13.Cu")
		(net "M_B_CPU0_SB_DQ<4>")
	)
	(segment
		(start 314.385452 -281.243278)
		(end 314.385452 -280.796238)
		(width 0.14478)
		(layer "In13.Cu")
		(net "M_B_CPU0_SB_DQ<4>")
	)
	(segment
		(start 317.33998 -278.28875)
		(end 317.506604 -278.122126)
		(width 0.14478)
		(layer "In13.Cu")
		(net "M_B_CPU0_SB_DQ<4>")
	)
	(arc
		(start 326.650858 -277.699216)
		(mid 326.747676 -277.686145)
		(end 326.837802 -277.648416)
		(width 0.0889)
		(layer "In13.Cu")
		(net "M_B_CPU0_SB_DQ<4>")
	)
	(arc
		(start 334.924146 -277.64867)
		(mid 335.11109 -277.698925)
		(end 335.298034 -277.64867)
		(width 0.0889)
		(layer "In13.Cu")
		(net "M_B_CPU0_SB_DQ<4>")
	)
	(arc
		(start 333.05242 -277.653496)
		(mid 333.235928 -277.69899)
		(end 333.41818 -277.64867)
		(width 0.0889)
		(layer "In13.Cu")
		(net "M_B_CPU0_SB_DQ<4>")
	)
	(arc
		(start 335.298034 -277.64867)
		(mid 335.54563 -277.573492)
		(end 335.8007 -277.61692)
		(width 0.0889)
		(layer "In13.Cu")
		(net "M_B_CPU0_SB_DQ<4>")
	)
	(arc
		(start 334.358234 -277.64867)
		(mid 334.64119 -277.572493)
		(end 334.924146 -277.64867)
		(width 0.0889)
		(layer "In13.Cu")
		(net "M_B_CPU0_SB_DQ<4>")
	)
	(arc
		(start 331.538072 -277.64867)
		(mid 331.821028 -277.572493)
		(end 332.103984 -277.64867)
		(width 0.0889)
		(layer "In13.Cu")
		(net "M_B_CPU0_SB_DQ<4>")
	)
	(arc
		(start 328.718164 -277.64867)
		(mid 329.00112 -277.572493)
		(end 329.284076 -277.64867)
		(width 0.0889)
		(layer "In13.Cu")
		(net "M_B_CPU0_SB_DQ<4>")
	)
	(arc
		(start 330.598018 -277.64867)
		(mid 330.880974 -277.572493)
		(end 331.16393 -277.64867)
		(width 0.0889)
		(layer "In13.Cu")
		(net "M_B_CPU0_SB_DQ<4>")
	)
	(arc
		(start 330.22413 -277.64867)
		(mid 330.411074 -277.698925)
		(end 330.598018 -277.64867)
		(width 0.0889)
		(layer "In13.Cu")
		(net "M_B_CPU0_SB_DQ<4>")
	)
	(arc
		(start 332.103984 -277.64867)
		(mid 332.286235 -277.69902)
		(end 332.469744 -277.653496)
		(width 0.0889)
		(layer "In13.Cu")
		(net "M_B_CPU0_SB_DQ<4>")
	)
	(arc
		(start 329.658218 -277.64867)
		(mid 329.941174 -277.572493)
		(end 330.22413 -277.64867)
		(width 0.0889)
		(layer "In13.Cu")
		(net "M_B_CPU0_SB_DQ<4>")
	)
	(arc
		(start 326.84339 -277.645114)
		(mid 327.123779 -277.572445)
		(end 327.403206 -277.64867)
		(width 0.0889)
		(layer "In13.Cu")
		(net "M_B_CPU0_SB_DQ<4>")
	)
	(arc
		(start 331.16393 -277.64867)
		(mid 331.346181 -277.69902)
		(end 331.52969 -277.653496)
		(width 0.0889)
		(layer "In13.Cu")
		(net "M_B_CPU0_SB_DQ<4>")
	)
	(arc
		(start 329.292458 -277.653496)
		(mid 329.475966 -277.69899)
		(end 329.658218 -277.64867)
		(width 0.0889)
		(layer "In13.Cu")
		(net "M_B_CPU0_SB_DQ<4>")
	)
	(arc
		(start 327.777856 -277.64867)
		(mid 328.054923 -277.572399)
		(end 328.333608 -277.642574)
		(width 0.0889)
		(layer "In13.Cu")
		(net "M_B_CPU0_SB_DQ<4>")
	)
	(arc
		(start 333.992474 -277.653496)
		(mid 334.175982 -277.69899)
		(end 334.358234 -277.64867)
		(width 0.0889)
		(layer "In13.Cu")
		(net "M_B_CPU0_SB_DQ<4>")
	)
	(arc
		(start 328.344022 -277.64867)
		(mid 328.526273 -277.69902)
		(end 328.709782 -277.653496)
		(width 0.0889)
		(layer "In13.Cu")
		(net "M_B_CPU0_SB_DQ<4>")
	)
	(arc
		(start 333.41818 -277.64867)
		(mid 333.701136 -277.572493)
		(end 333.984092 -277.64867)
		(width 0.0889)
		(layer "In13.Cu")
		(net "M_B_CPU0_SB_DQ<4>")
	)
	(arc
		(start 332.478126 -277.64867)
		(mid 332.761082 -277.572493)
		(end 333.044038 -277.64867)
		(width 0.0889)
		(layer "In13.Cu")
		(net "M_B_CPU0_SB_DQ<4>")
	)
	(arc
		(start 327.411588 -277.653496)
		(mid 327.59535 -277.699112)
		(end 327.777856 -277.64867)
		(width 0.0889)
		(layer "In13.Cu")
		(net "M_B_CPU0_SB_DQ<4>")
	)
	(segment
		(start 337.45805 -275.44014)
		(end 336.991198 -275.706078)
		(width 0.10668)
		(layer "F.Cu")
		(net "M_B_CPU0_SB_DQ<3>")
	)
	(segment
		(start 295.724072 -284.034992)
		(end 297.769026 -284.034992)
		(width 0.14478)
		(layer "In13.Cu")
		(net "M_B_CPU0_SB_DQ<3>")
	)
	(segment
		(start 326.340724 -275.332698)
		(end 327.589896 -275.332698)
		(width 0.0889)
		(layer "In13.Cu")
		(net "M_B_CPU0_SB_DQ<3>")
	)
	(segment
		(start 333.044038 -275.383498)
		(end 333.05242 -275.378672)
		(width 0.0889)
		(layer "In13.Cu")
		(net "M_B_CPU0_SB_DQ<3>")
	)
	(segment
		(start 300.996604 -283.600398)
		(end 301.460916 -284.06471)
		(width 0.14478)
		(layer "In13.Cu")
		(net "M_B_CPU0_SB_DQ<3>")
	)
	(segment
		(start 305.737768 -283.61005)
		(end 307.316886 -283.61005)
		(width 0.14478)
		(layer "In13.Cu")
		(net "M_B_CPU0_SB_DQ<3>")
	)
	(segment
		(start 336.229706 -275.378672)
		(end 336.238088 -275.383498)
		(width 0.0889)
		(layer "In13.Cu")
		(net "M_B_CPU0_SB_DQ<3>")
	)
	(segment
		(start 324.768718 -274.240752)
		(end 325.248778 -274.240752)
		(width 0.0889)
		(layer "In13.Cu")
		(net "M_B_CPU0_SB_DQ<3>")
	)
	(segment
		(start 301.460916 -284.06471)
		(end 305.283108 -284.06471)
		(width 0.14478)
		(layer "In13.Cu")
		(net "M_B_CPU0_SB_DQ<3>")
	)
	(segment
		(start 324.311518 -274.58416)
		(end 324.42531 -274.58416)
		(width 0.0889)
		(layer "In13.Cu")
		(net "M_B_CPU0_SB_DQ<3>")
	)
	(segment
		(start 328.709782 -275.378672)
		(end 328.718164 -275.383498)
		(width 0.0889)
		(layer "In13.Cu")
		(net "M_B_CPU0_SB_DQ<3>")
	)
	(segment
		(start 332.469744 -275.378672)
		(end 332.478126 -275.383498)
		(width 0.0889)
		(layer "In13.Cu")
		(net "M_B_CPU0_SB_DQ<3>")
	)
	(segment
		(start 297.769026 -284.034992)
		(end 298.20362 -283.600398)
		(width 0.14478)
		(layer "In13.Cu")
		(net "M_B_CPU0_SB_DQ<3>")
	)
	(segment
		(start 328.32929 -275.392134)
		(end 328.344022 -275.383498)
		(width 0.0889)
		(layer "In13.Cu")
		(net "M_B_CPU0_SB_DQ<3>")
	)
	(segment
		(start 305.283108 -284.06471)
		(end 305.737768 -283.61005)
		(width 0.14478)
		(layer "In13.Cu")
		(net "M_B_CPU0_SB_DQ<3>")
	)
	(segment
		(start 325.248778 -274.240752)
		(end 326.340724 -275.332698)
		(width 0.0889)
		(layer "In13.Cu")
		(net "M_B_CPU0_SB_DQ<3>")
	)
	(segment
		(start 298.20362 -283.600398)
		(end 300.996604 -283.600398)
		(width 0.14478)
		(layer "In13.Cu")
		(net "M_B_CPU0_SB_DQ<3>")
	)
	(segment
		(start 316.342776 -274.58416)
		(end 324.311518 -274.58416)
		(width 0.14478)
		(layer "In13.Cu")
		(net "M_B_CPU0_SB_DQ<3>")
	)
	(segment
		(start 324.42531 -274.58416)
		(end 324.768718 -274.240752)
		(width 0.0889)
		(layer "In13.Cu")
		(net "M_B_CPU0_SB_DQ<3>")
	)
	(segment
		(start 337.12277 -275.357336)
		(end 337.145122 -275.440648)
		(width 0.0889)
		(layer "In13.Cu")
		(net "M_B_CPU0_SB_DQ<3>")
	)
	(segment
		(start 337.145122 -275.440648)
		(end 336.991198 -275.706078)
		(width 0.0889)
		(layer "In13.Cu")
		(net "M_B_CPU0_SB_DQ<3>")
	)
	(segment
		(start 333.984092 -275.383498)
		(end 333.992474 -275.378672)
		(width 0.0889)
		(layer "In13.Cu")
		(net "M_B_CPU0_SB_DQ<3>")
	)
	(segment
		(start 331.52969 -275.378672)
		(end 331.538072 -275.383498)
		(width 0.0889)
		(layer "In13.Cu")
		(net "M_B_CPU0_SB_DQ<3>")
	)
	(segment
		(start 329.284076 -275.383498)
		(end 329.292458 -275.378672)
		(width 0.0889)
		(layer "In13.Cu")
		(net "M_B_CPU0_SB_DQ<3>")
	)
	(segment
		(start 307.316886 -283.61005)
		(end 316.342776 -274.58416)
		(width 0.14478)
		(layer "In13.Cu")
		(net "M_B_CPU0_SB_DQ<3>")
	)
	(arc
		(start 335.298034 -275.383498)
		(mid 335.58099 -275.459675)
		(end 335.863946 -275.383498)
		(width 0.0889)
		(layer "In13.Cu")
		(net "M_B_CPU0_SB_DQ<3>")
	)
	(arc
		(start 330.22413 -275.383498)
		(mid 330.411074 -275.333243)
		(end 330.598018 -275.383498)
		(width 0.0889)
		(layer "In13.Cu")
		(net "M_B_CPU0_SB_DQ<3>")
	)
	(arc
		(start 328.718164 -275.383498)
		(mid 329.00112 -275.459675)
		(end 329.284076 -275.383498)
		(width 0.0889)
		(layer "In13.Cu")
		(net "M_B_CPU0_SB_DQ<3>")
	)
	(arc
		(start 334.358234 -275.383498)
		(mid 334.64119 -275.459675)
		(end 334.924146 -275.383498)
		(width 0.0889)
		(layer "In13.Cu")
		(net "M_B_CPU0_SB_DQ<3>")
	)
	(arc
		(start 329.292458 -275.378672)
		(mid 329.475966 -275.333178)
		(end 329.658218 -275.383498)
		(width 0.0889)
		(layer "In13.Cu")
		(net "M_B_CPU0_SB_DQ<3>")
	)
	(arc
		(start 332.478126 -275.383498)
		(mid 332.761082 -275.459675)
		(end 333.044038 -275.383498)
		(width 0.0889)
		(layer "In13.Cu")
		(net "M_B_CPU0_SB_DQ<3>")
	)
	(arc
		(start 331.16393 -275.383498)
		(mid 331.346181 -275.333148)
		(end 331.52969 -275.378672)
		(width 0.0889)
		(layer "In13.Cu")
		(net "M_B_CPU0_SB_DQ<3>")
	)
	(arc
		(start 330.598018 -275.383498)
		(mid 330.880974 -275.459675)
		(end 331.16393 -275.383498)
		(width 0.0889)
		(layer "In13.Cu")
		(net "M_B_CPU0_SB_DQ<3>")
	)
	(arc
		(start 334.924146 -275.383498)
		(mid 335.11109 -275.333243)
		(end 335.298034 -275.383498)
		(width 0.0889)
		(layer "In13.Cu")
		(net "M_B_CPU0_SB_DQ<3>")
	)
	(arc
		(start 328.344022 -275.383498)
		(mid 328.526273 -275.333148)
		(end 328.709782 -275.378672)
		(width 0.0889)
		(layer "In13.Cu")
		(net "M_B_CPU0_SB_DQ<3>")
	)
	(arc
		(start 333.05242 -275.378672)
		(mid 333.235928 -275.333178)
		(end 333.41818 -275.383498)
		(width 0.0889)
		(layer "In13.Cu")
		(net "M_B_CPU0_SB_DQ<3>")
	)
	(arc
		(start 332.103984 -275.383498)
		(mid 332.286235 -275.333148)
		(end 332.469744 -275.378672)
		(width 0.0889)
		(layer "In13.Cu")
		(net "M_B_CPU0_SB_DQ<3>")
	)
	(arc
		(start 327.777602 -275.383498)
		(mid 328.052308 -275.459862)
		(end 328.32929 -275.392134)
		(width 0.0889)
		(layer "In13.Cu")
		(net "M_B_CPU0_SB_DQ<3>")
	)
	(arc
		(start 336.238088 -275.383498)
		(mid 336.521044 -275.459675)
		(end 336.804 -275.383498)
		(width 0.0889)
		(layer "In13.Cu")
		(net "M_B_CPU0_SB_DQ<3>")
	)
	(arc
		(start 331.538072 -275.383498)
		(mid 331.821028 -275.459675)
		(end 332.103984 -275.383498)
		(width 0.0889)
		(layer "In13.Cu")
		(net "M_B_CPU0_SB_DQ<3>")
	)
	(arc
		(start 336.804 -275.383498)
		(mid 336.960438 -275.334527)
		(end 337.12277 -275.357336)
		(width 0.0889)
		(layer "In13.Cu")
		(net "M_B_CPU0_SB_DQ<3>")
	)
	(arc
		(start 329.658218 -275.383498)
		(mid 329.941174 -275.459675)
		(end 330.22413 -275.383498)
		(width 0.0889)
		(layer "In13.Cu")
		(net "M_B_CPU0_SB_DQ<3>")
	)
	(arc
		(start 327.589896 -275.332698)
		(mid 327.687121 -275.345647)
		(end 327.777602 -275.383498)
		(width 0.0889)
		(layer "In13.Cu")
		(net "M_B_CPU0_SB_DQ<3>")
	)
	(arc
		(start 333.992474 -275.378672)
		(mid 334.175982 -275.333178)
		(end 334.358234 -275.383498)
		(width 0.0889)
		(layer "In13.Cu")
		(net "M_B_CPU0_SB_DQ<3>")
	)
	(arc
		(start 333.41818 -275.383498)
		(mid 333.701136 -275.459675)
		(end 333.984092 -275.383498)
		(width 0.0889)
		(layer "In13.Cu")
		(net "M_B_CPU0_SB_DQ<3>")
	)
	(arc
		(start 335.863946 -275.383498)
		(mid 336.046197 -275.333148)
		(end 336.229706 -275.378672)
		(width 0.0889)
		(layer "In13.Cu")
		(net "M_B_CPU0_SB_DQ<3>")
	)
	(segment
		(start 337.45805 -293.260018)
		(end 336.991198 -293.525956)
		(width 0.10668)
		(layer "F.Cu")
		(net "M_B_CPU0_SB_DQ<31>")
	)
	(segment
		(start 327.852532 -296.458132)
		(end 328.289412 -296.458132)
		(width 0.0889)
		(layer "In13.Cu")
		(net "M_B_CPU0_SB_DQ<31>")
	)
	(segment
		(start 331.52969 -293.19855)
		(end 331.538072 -293.203376)
		(width 0.0889)
		(layer "In13.Cu")
		(net "M_B_CPU0_SB_DQ<31>")
	)
	(segment
		(start 329.252326 -294.841676)
		(end 329.284076 -294.823388)
		(width 0.0889)
		(layer "In13.Cu")
		(net "M_B_CPU0_SB_DQ<31>")
	)
	(segment
		(start 330.221336 -293.205154)
		(end 330.22413 -293.203376)
		(width 0.0889)
		(layer "In13.Cu")
		(net "M_B_CPU0_SB_DQ<31>")
	)
	(segment
		(start 310.235854 -316.37478)
		(end 325.062088 -301.548546)
		(width 0.14478)
		(layer "In13.Cu")
		(net "M_B_CPU0_SB_DQ<31>")
	)
	(segment
		(start 296.174668 -318.12484)
		(end 297.860466 -318.46012)
		(width 0.14478)
		(layer "In13.Cu")
		(net "M_B_CPU0_SB_DQ<31>")
	)
	(segment
		(start 328.813922 -295.633394)
		(end 328.853038 -295.610534)
		(width 0.0889)
		(layer "In13.Cu")
		(net "M_B_CPU0_SB_DQ<31>")
	)
	(segment
		(start 296.085006 -318.035178)
		(end 296.174668 -318.12484)
		(width 0.14478)
		(layer "In13.Cu")
		(net "M_B_CPU0_SB_DQ<31>")
	)
	(segment
		(start 297.860466 -318.46012)
		(end 305.201574 -318.46012)
		(width 0.14478)
		(layer "In13.Cu")
		(net "M_B_CPU0_SB_DQ<31>")
	)
	(segment
		(start 336.229706 -293.19855)
		(end 336.238088 -293.203376)
		(width 0.0889)
		(layer "In13.Cu")
		(net "M_B_CPU0_SB_DQ<31>")
	)
	(segment
		(start 305.201574 -318.46012)
		(end 310.235854 -316.37478)
		(width 0.14478)
		(layer "In13.Cu")
		(net "M_B_CPU0_SB_DQ<31>")
	)
	(segment
		(start 325.062088 -301.548546)
		(end 325.062088 -299.232828)
		(width 0.14478)
		(layer "In13.Cu")
		(net "M_B_CPU0_SB_DQ<31>")
	)
	(segment
		(start 332.469744 -293.19855)
		(end 332.478126 -293.203376)
		(width 0.0889)
		(layer "In13.Cu")
		(net "M_B_CPU0_SB_DQ<31>")
	)
	(segment
		(start 329.284076 -294.823388)
		(end 329.323192 -294.800528)
		(width 0.0889)
		(layer "In13.Cu")
		(net "M_B_CPU0_SB_DQ<31>")
	)
	(segment
		(start 325.062088 -299.232828)
		(end 327.739248 -296.555668)
		(width 0.14478)
		(layer "In13.Cu")
		(net "M_B_CPU0_SB_DQ<31>")
	)
	(segment
		(start 337.145122 -293.260526)
		(end 336.991198 -293.525956)
		(width 0.0889)
		(layer "In13.Cu")
		(net "M_B_CPU0_SB_DQ<31>")
	)
	(segment
		(start 328.343768 -296.4434)
		(end 328.384154 -296.419778)
		(width 0.0889)
		(layer "In13.Cu")
		(net "M_B_CPU0_SB_DQ<31>")
	)
	(segment
		(start 328.783442 -295.651174)
		(end 328.813922 -295.633394)
		(width 0.0889)
		(layer "In13.Cu")
		(net "M_B_CPU0_SB_DQ<31>")
	)
	(segment
		(start 333.984092 -293.203376)
		(end 333.992474 -293.19855)
		(width 0.0889)
		(layer "In13.Cu")
		(net "M_B_CPU0_SB_DQ<31>")
	)
	(segment
		(start 337.12277 -293.177214)
		(end 337.145122 -293.260526)
		(width 0.0889)
		(layer "In13.Cu")
		(net "M_B_CPU0_SB_DQ<31>")
	)
	(segment
		(start 329.723496 -294.031162)
		(end 329.753976 -294.013382)
		(width 0.0889)
		(layer "In13.Cu")
		(net "M_B_CPU0_SB_DQ<31>")
	)
	(segment
		(start 329.753976 -294.013382)
		(end 329.756516 -294.011604)
		(width 0.0889)
		(layer "In13.Cu")
		(net "M_B_CPU0_SB_DQ<31>")
	)
	(segment
		(start 327.739248 -296.555668)
		(end 327.825608 -296.469308)
		(width 0.0889)
		(layer "In13.Cu")
		(net "M_B_CPU0_SB_DQ<31>")
	)
	(segment
		(start 295.724072 -318.035178)
		(end 296.085006 -318.035178)
		(width 0.14478)
		(layer "In13.Cu")
		(net "M_B_CPU0_SB_DQ<31>")
	)
	(segment
		(start 333.044038 -293.203376)
		(end 333.05242 -293.19855)
		(width 0.0889)
		(layer "In13.Cu")
		(net "M_B_CPU0_SB_DQ<31>")
	)
	(arc
		(start 330.22413 -293.203376)
		(mid 330.411074 -293.153121)
		(end 330.598018 -293.203376)
		(width 0.0889)
		(layer "In13.Cu")
		(net "M_B_CPU0_SB_DQ<31>")
	)
	(arc
		(start 328.853038 -295.610534)
		(mid 329.031851 -295.408184)
		(end 329.09637 -295.145968)
		(width 0.0889)
		(layer "In13.Cu")
		(net "M_B_CPU0_SB_DQ<31>")
	)
	(arc
		(start 328.62647 -295.955974)
		(mid 328.668019 -295.784552)
		(end 328.783442 -295.651174)
		(width 0.0889)
		(layer "In13.Cu")
		(net "M_B_CPU0_SB_DQ<31>")
	)
	(arc
		(start 328.384154 -296.419778)
		(mid 328.562219 -296.217601)
		(end 328.62647 -295.955974)
		(width 0.0889)
		(layer "In13.Cu")
		(net "M_B_CPU0_SB_DQ<31>")
	)
	(arc
		(start 329.756516 -294.011604)
		(mid 329.961416 -293.806204)
		(end 330.036424 -293.525956)
		(width 0.0889)
		(layer "In13.Cu")
		(net "M_B_CPU0_SB_DQ<31>")
	)
	(arc
		(start 329.566524 -294.335962)
		(mid 329.608073 -294.16454)
		(end 329.723496 -294.031162)
		(width 0.0889)
		(layer "In13.Cu")
		(net "M_B_CPU0_SB_DQ<31>")
	)
	(arc
		(start 336.804 -293.203376)
		(mid 336.960438 -293.154405)
		(end 337.12277 -293.177214)
		(width 0.0889)
		(layer "In13.Cu")
		(net "M_B_CPU0_SB_DQ<31>")
	)
	(arc
		(start 330.036424 -293.525956)
		(mid 330.085953 -293.340803)
		(end 330.221336 -293.205154)
		(width 0.0889)
		(layer "In13.Cu")
		(net "M_B_CPU0_SB_DQ<31>")
	)
	(arc
		(start 333.41818 -293.203376)
		(mid 333.701136 -293.279553)
		(end 333.984092 -293.203376)
		(width 0.0889)
		(layer "In13.Cu")
		(net "M_B_CPU0_SB_DQ<31>")
	)
	(arc
		(start 330.598018 -293.203376)
		(mid 330.880974 -293.279553)
		(end 331.16393 -293.203376)
		(width 0.0889)
		(layer "In13.Cu")
		(net "M_B_CPU0_SB_DQ<31>")
	)
	(arc
		(start 333.992474 -293.19855)
		(mid 334.175982 -293.153056)
		(end 334.358234 -293.203376)
		(width 0.0889)
		(layer "In13.Cu")
		(net "M_B_CPU0_SB_DQ<31>")
	)
	(arc
		(start 331.16393 -293.203376)
		(mid 331.346181 -293.153026)
		(end 331.52969 -293.19855)
		(width 0.0889)
		(layer "In13.Cu")
		(net "M_B_CPU0_SB_DQ<31>")
	)
	(arc
		(start 329.09637 -295.145968)
		(mid 329.137625 -294.974997)
		(end 329.252326 -294.841676)
		(width 0.0889)
		(layer "In13.Cu")
		(net "M_B_CPU0_SB_DQ<31>")
	)
	(arc
		(start 334.924146 -293.203376)
		(mid 335.11109 -293.153121)
		(end 335.298034 -293.203376)
		(width 0.0889)
		(layer "In13.Cu")
		(net "M_B_CPU0_SB_DQ<31>")
	)
	(arc
		(start 329.323192 -294.800528)
		(mid 329.502005 -294.598178)
		(end 329.566524 -294.335962)
		(width 0.0889)
		(layer "In13.Cu")
		(net "M_B_CPU0_SB_DQ<31>")
	)
	(arc
		(start 335.298034 -293.203376)
		(mid 335.58099 -293.279553)
		(end 335.863946 -293.203376)
		(width 0.0889)
		(layer "In13.Cu")
		(net "M_B_CPU0_SB_DQ<31>")
	)
	(arc
		(start 334.358234 -293.203376)
		(mid 334.64119 -293.279553)
		(end 334.924146 -293.203376)
		(width 0.0889)
		(layer "In13.Cu")
		(net "M_B_CPU0_SB_DQ<31>")
	)
	(arc
		(start 332.103984 -293.203376)
		(mid 332.286235 -293.153026)
		(end 332.469744 -293.19855)
		(width 0.0889)
		(layer "In13.Cu")
		(net "M_B_CPU0_SB_DQ<31>")
	)
	(arc
		(start 336.238088 -293.203376)
		(mid 336.521044 -293.279553)
		(end 336.804 -293.203376)
		(width 0.0889)
		(layer "In13.Cu")
		(net "M_B_CPU0_SB_DQ<31>")
	)
	(arc
		(start 327.825608 -296.469308)
		(mid 327.837961 -296.461054)
		(end 327.852532 -296.458132)
		(width 0.0889)
		(layer "In13.Cu")
		(net "M_B_CPU0_SB_DQ<31>")
	)
	(arc
		(start 333.05242 -293.19855)
		(mid 333.235928 -293.153056)
		(end 333.41818 -293.203376)
		(width 0.0889)
		(layer "In13.Cu")
		(net "M_B_CPU0_SB_DQ<31>")
	)
	(arc
		(start 335.863946 -293.203376)
		(mid 336.046197 -293.153026)
		(end 336.229706 -293.19855)
		(width 0.0889)
		(layer "In13.Cu")
		(net "M_B_CPU0_SB_DQ<31>")
	)
	(arc
		(start 332.478126 -293.203376)
		(mid 332.761082 -293.279553)
		(end 333.044038 -293.203376)
		(width 0.0889)
		(layer "In13.Cu")
		(net "M_B_CPU0_SB_DQ<31>")
	)
	(arc
		(start 328.289412 -296.458132)
		(mid 328.317571 -296.454385)
		(end 328.343768 -296.4434)
		(width 0.0889)
		(layer "In13.Cu")
		(net "M_B_CPU0_SB_DQ<31>")
	)
	(arc
		(start 331.538072 -293.203376)
		(mid 331.821028 -293.279553)
		(end 332.103984 -293.203376)
		(width 0.0889)
		(layer "In13.Cu")
		(net "M_B_CPU0_SB_DQ<31>")
	)
	(segment
		(start 336.047842 -292.450012)
		(end 335.58099 -292.71595)
		(width 0.10668)
		(layer "F.Cu")
		(net "M_B_CPU0_SB_DQ<30>")
	)
	(segment
		(start 297.444414 -317.116714)
		(end 297.589194 -317.261494)
		(width 0.14478)
		(layer "In13.Cu")
		(net "M_B_CPU0_SB_DQ<30>")
	)
	(segment
		(start 333.887826 -292.39337)
		(end 333.888334 -292.39337)
		(width 0.0889)
		(layer "In13.Cu")
		(net "M_B_CPU0_SB_DQ<30>")
	)
	(segment
		(start 296.079926 -316.335156)
		(end 296.504868 -316.760098)
		(width 0.14478)
		(layer "In13.Cu")
		(net "M_B_CPU0_SB_DQ<30>")
	)
	(segment
		(start 297.299634 -316.760098)
		(end 297.444414 -316.904878)
		(width 0.14478)
		(layer "In13.Cu")
		(net "M_B_CPU0_SB_DQ<30>")
	)
	(segment
		(start 332.948026 -292.39337)
		(end 332.94828 -292.39337)
		(width 0.0889)
		(layer "In13.Cu")
		(net "M_B_CPU0_SB_DQ<30>")
	)
	(segment
		(start 310.33212 -314.578746)
		(end 323.699378 -301.211488)
		(width 0.14478)
		(layer "In13.Cu")
		(net "M_B_CPU0_SB_DQ<30>")
	)
	(segment
		(start 330.69403 -292.39337)
		(end 330.702412 -292.388544)
		(width 0.0889)
		(layer "In13.Cu")
		(net "M_B_CPU0_SB_DQ<30>")
	)
	(segment
		(start 323.699378 -298.668186)
		(end 326.250554 -296.11701)
		(width 0.14478)
		(layer "In13.Cu")
		(net "M_B_CPU0_SB_DQ<30>")
	)
	(segment
		(start 297.444414 -316.904878)
		(end 297.444414 -317.116714)
		(width 0.14478)
		(layer "In13.Cu")
		(net "M_B_CPU0_SB_DQ<30>")
	)
	(segment
		(start 327.874122 -294.013382)
		(end 327.913238 -293.990522)
		(width 0.0889)
		(layer "In13.Cu")
		(net "M_B_CPU0_SB_DQ<30>")
	)
	(segment
		(start 328.782426 -292.411658)
		(end 328.814176 -292.39337)
		(width 0.0889)
		(layer "In13.Cu")
		(net "M_B_CPU0_SB_DQ<30>")
	)
	(segment
		(start 327.372726 -294.841676)
		(end 327.404476 -294.823388)
		(width 0.0889)
		(layer "In13.Cu")
		(net "M_B_CPU0_SB_DQ<30>")
	)
	(segment
		(start 328.313542 -293.221156)
		(end 328.344022 -293.203376)
		(width 0.0889)
		(layer "In13.Cu")
		(net "M_B_CPU0_SB_DQ<30>")
	)
	(segment
		(start 335.735168 -292.45052)
		(end 335.58099 -292.71595)
		(width 0.0889)
		(layer "In13.Cu")
		(net "M_B_CPU0_SB_DQ<30>")
	)
	(segment
		(start 297.995594 -316.904878)
		(end 298.140374 -316.760098)
		(width 0.14478)
		(layer "In13.Cu")
		(net "M_B_CPU0_SB_DQ<30>")
	)
	(segment
		(start 326.88784 -295.669716)
		(end 326.972168 -295.61155)
		(width 0.0889)
		(layer "In13.Cu")
		(net "M_B_CPU0_SB_DQ<30>")
	)
	(segment
		(start 326.250554 -296.11701)
		(end 326.502522 -295.865042)
		(width 0.0889)
		(layer "In13.Cu")
		(net "M_B_CPU0_SB_DQ<30>")
	)
	(segment
		(start 296.504868 -316.760098)
		(end 297.299634 -316.760098)
		(width 0.14478)
		(layer "In13.Cu")
		(net "M_B_CPU0_SB_DQ<30>")
	)
	(segment
		(start 323.699378 -301.211488)
		(end 323.699378 -298.668186)
		(width 0.14478)
		(layer "In13.Cu")
		(net "M_B_CPU0_SB_DQ<30>")
	)
	(segment
		(start 297.995594 -317.116714)
		(end 297.995594 -316.904878)
		(width 0.14478)
		(layer "In13.Cu")
		(net "M_B_CPU0_SB_DQ<30>")
	)
	(segment
		(start 326.502522 -295.865042)
		(end 326.58177 -295.786048)
		(width 0.0889)
		(layer "In13.Cu")
		(net "M_B_CPU0_SB_DQ<30>")
	)
	(segment
		(start 295.724072 -316.335156)
		(end 296.079926 -316.335156)
		(width 0.14478)
		(layer "In13.Cu")
		(net "M_B_CPU0_SB_DQ<30>")
	)
	(segment
		(start 328.344022 -293.203376)
		(end 328.383138 -293.180516)
		(width 0.0889)
		(layer "In13.Cu")
		(net "M_B_CPU0_SB_DQ<30>")
	)
	(segment
		(start 297.850814 -317.261494)
		(end 297.995594 -317.116714)
		(width 0.14478)
		(layer "In13.Cu")
		(net "M_B_CPU0_SB_DQ<30>")
	)
	(segment
		(start 327.844658 -294.0304)
		(end 327.874122 -294.013382)
		(width 0.0889)
		(layer "In13.Cu")
		(net "M_B_CPU0_SB_DQ<30>")
	)
	(segment
		(start 298.140374 -316.760098)
		(end 305.065938 -316.760098)
		(width 0.14478)
		(layer "In13.Cu")
		(net "M_B_CPU0_SB_DQ<30>")
	)
	(segment
		(start 305.065938 -316.760098)
		(end 310.33212 -314.578746)
		(width 0.14478)
		(layer "In13.Cu")
		(net "M_B_CPU0_SB_DQ<30>")
	)
	(segment
		(start 335.712816 -292.367208)
		(end 335.735168 -292.45052)
		(width 0.0889)
		(layer "In13.Cu")
		(net "M_B_CPU0_SB_DQ<30>")
	)
	(segment
		(start 330.119736 -292.388544)
		(end 330.128118 -292.39337)
		(width 0.0889)
		(layer "In13.Cu")
		(net "M_B_CPU0_SB_DQ<30>")
	)
	(segment
		(start 297.589194 -317.261494)
		(end 297.850814 -317.261494)
		(width 0.14478)
		(layer "In13.Cu")
		(net "M_B_CPU0_SB_DQ<30>")
	)
	(segment
		(start 335.394046 -292.39337)
		(end 335.402428 -292.388544)
		(width 0.0889)
		(layer "In13.Cu")
		(net "M_B_CPU0_SB_DQ<30>")
	)
	(segment
		(start 331.634084 -292.39337)
		(end 331.642466 -292.388544)
		(width 0.0889)
		(layer "In13.Cu")
		(net "M_B_CPU0_SB_DQ<30>")
	)
	(segment
		(start 334.82788 -292.39337)
		(end 334.828134 -292.39337)
		(width 0.0889)
		(layer "In13.Cu")
		(net "M_B_CPU0_SB_DQ<30>")
	)
	(segment
		(start 327.404476 -294.823388)
		(end 327.440798 -294.802306)
		(width 0.0889)
		(layer "In13.Cu")
		(net "M_B_CPU0_SB_DQ<30>")
	)
	(arc
		(start 326.972168 -295.61155)
		(mid 327.151897 -295.40893)
		(end 327.21677 -295.145968)
		(width 0.0889)
		(layer "In13.Cu")
		(net "M_B_CPU0_SB_DQ<30>")
	)
	(arc
		(start 331.068172 -292.39337)
		(mid 331.351128 -292.469547)
		(end 331.634084 -292.39337)
		(width 0.0889)
		(layer "In13.Cu")
		(net "M_B_CPU0_SB_DQ<30>")
	)
	(arc
		(start 327.21677 -295.145968)
		(mid 327.258025 -294.974997)
		(end 327.372726 -294.841676)
		(width 0.0889)
		(layer "In13.Cu")
		(net "M_B_CPU0_SB_DQ<30>")
	)
	(arc
		(start 328.15657 -293.525956)
		(mid 328.198119 -293.354534)
		(end 328.313542 -293.221156)
		(width 0.0889)
		(layer "In13.Cu")
		(net "M_B_CPU0_SB_DQ<30>")
	)
	(arc
		(start 331.642466 -292.388544)
		(mid 331.825974 -292.34305)
		(end 332.008226 -292.39337)
		(width 0.0889)
		(layer "In13.Cu")
		(net "M_B_CPU0_SB_DQ<30>")
	)
	(arc
		(start 334.828134 -292.39337)
		(mid 335.11109 -292.469547)
		(end 335.394046 -292.39337)
		(width 0.0889)
		(layer "In13.Cu")
		(net "M_B_CPU0_SB_DQ<30>")
	)
	(arc
		(start 332.574138 -292.39337)
		(mid 332.761082 -292.343115)
		(end 332.948026 -292.39337)
		(width 0.0889)
		(layer "In13.Cu")
		(net "M_B_CPU0_SB_DQ<30>")
	)
	(arc
		(start 328.62647 -292.71595)
		(mid 328.667725 -292.544979)
		(end 328.782426 -292.411658)
		(width 0.0889)
		(layer "In13.Cu")
		(net "M_B_CPU0_SB_DQ<30>")
	)
	(arc
		(start 332.008226 -292.39337)
		(mid 332.291182 -292.469547)
		(end 332.574138 -292.39337)
		(width 0.0889)
		(layer "In13.Cu")
		(net "M_B_CPU0_SB_DQ<30>")
	)
	(arc
		(start 326.78497 -295.70172)
		(mid 326.838831 -295.693525)
		(end 326.88784 -295.669716)
		(width 0.0889)
		(layer "In13.Cu")
		(net "M_B_CPU0_SB_DQ<30>")
	)
	(arc
		(start 333.513938 -292.39337)
		(mid 333.700882 -292.343046)
		(end 333.887826 -292.39337)
		(width 0.0889)
		(layer "In13.Cu")
		(net "M_B_CPU0_SB_DQ<30>")
	)
	(arc
		(start 330.128118 -292.39337)
		(mid 330.411074 -292.469547)
		(end 330.69403 -292.39337)
		(width 0.0889)
		(layer "In13.Cu")
		(net "M_B_CPU0_SB_DQ<30>")
	)
	(arc
		(start 327.440798 -294.802306)
		(mid 327.62145 -294.599561)
		(end 327.68667 -294.335962)
		(width 0.0889)
		(layer "In13.Cu")
		(net "M_B_CPU0_SB_DQ<30>")
	)
	(arc
		(start 335.402428 -292.388544)
		(mid 335.555298 -292.343903)
		(end 335.712816 -292.367208)
		(width 0.0889)
		(layer "In13.Cu")
		(net "M_B_CPU0_SB_DQ<30>")
	)
	(arc
		(start 333.888334 -292.39337)
		(mid 334.17118 -292.469547)
		(end 334.453992 -292.39337)
		(width 0.0889)
		(layer "In13.Cu")
		(net "M_B_CPU0_SB_DQ<30>")
	)
	(arc
		(start 328.383138 -293.180516)
		(mid 328.561951 -292.978166)
		(end 328.62647 -292.71595)
		(width 0.0889)
		(layer "In13.Cu")
		(net "M_B_CPU0_SB_DQ<30>")
	)
	(arc
		(start 329.753976 -292.39337)
		(mid 329.936227 -292.34302)
		(end 330.119736 -292.388544)
		(width 0.0889)
		(layer "In13.Cu")
		(net "M_B_CPU0_SB_DQ<30>")
	)
	(arc
		(start 326.58177 -295.786048)
		(mid 326.674984 -295.723671)
		(end 326.78497 -295.70172)
		(width 0.0889)
		(layer "In13.Cu")
		(net "M_B_CPU0_SB_DQ<30>")
	)
	(arc
		(start 334.453992 -292.39337)
		(mid 334.640936 -292.343046)
		(end 334.82788 -292.39337)
		(width 0.0889)
		(layer "In13.Cu")
		(net "M_B_CPU0_SB_DQ<30>")
	)
	(arc
		(start 327.913238 -293.990522)
		(mid 328.092051 -293.788172)
		(end 328.15657 -293.525956)
		(width 0.0889)
		(layer "In13.Cu")
		(net "M_B_CPU0_SB_DQ<30>")
	)
	(arc
		(start 328.814176 -292.39337)
		(mid 329.00112 -292.343115)
		(end 329.188064 -292.39337)
		(width 0.0889)
		(layer "In13.Cu")
		(net "M_B_CPU0_SB_DQ<30>")
	)
	(arc
		(start 330.702412 -292.388544)
		(mid 330.88592 -292.34305)
		(end 331.068172 -292.39337)
		(width 0.0889)
		(layer "In13.Cu")
		(net "M_B_CPU0_SB_DQ<30>")
	)
	(arc
		(start 329.188064 -292.39337)
		(mid 329.47102 -292.469547)
		(end 329.753976 -292.39337)
		(width 0.0889)
		(layer "In13.Cu")
		(net "M_B_CPU0_SB_DQ<30>")
	)
	(arc
		(start 327.68667 -294.335962)
		(mid 327.72851 -294.163976)
		(end 327.844658 -294.0304)
		(width 0.0889)
		(layer "In13.Cu")
		(net "M_B_CPU0_SB_DQ<30>")
	)
	(arc
		(start 332.94828 -292.39337)
		(mid 333.231126 -292.469547)
		(end 333.513938 -292.39337)
		(width 0.0889)
		(layer "In13.Cu")
		(net "M_B_CPU0_SB_DQ<30>")
	)
	(segment
		(start 336.047842 -274.630134)
		(end 335.58099 -274.896072)
		(width 0.10668)
		(layer "F.Cu")
		(net "M_B_CPU0_SB_DQ<2>")
	)
	(segment
		(start 335.735168 -274.630642)
		(end 335.712816 -274.54733)
		(width 0.0889)
		(layer "In13.Cu")
		(net "M_B_CPU0_SB_DQ<2>")
	)
	(segment
		(start 305.331622 -282.364942)
		(end 301.373286 -282.364942)
		(width 0.14478)
		(layer "In13.Cu")
		(net "M_B_CPU0_SB_DQ<2>")
	)
	(segment
		(start 333.88808 -274.573492)
		(end 333.879698 -274.568666)
		(width 0.0889)
		(layer "In13.Cu")
		(net "M_B_CPU0_SB_DQ<2>")
	)
	(segment
		(start 331.642466 -274.568666)
		(end 331.634084 -274.573492)
		(width 0.0889)
		(layer "In13.Cu")
		(net "M_B_CPU0_SB_DQ<2>")
	)
	(segment
		(start 296.448734 -282.33497)
		(end 295.724072 -282.33497)
		(width 0.14478)
		(layer "In13.Cu")
		(net "M_B_CPU0_SB_DQ<2>")
	)
	(segment
		(start 315.97981 -273.67484)
		(end 307.744622 -281.910028)
		(width 0.14478)
		(layer "In13.Cu")
		(net "M_B_CPU0_SB_DQ<2>")
	)
	(segment
		(start 326.93356 -274.573746)
		(end 326.917812 -274.58289)
		(width 0.0889)
		(layer "In13.Cu")
		(net "M_B_CPU0_SB_DQ<2>")
	)
	(segment
		(start 298.76369 -282.33497)
		(end 297.289474 -282.33497)
		(width 0.14478)
		(layer "In13.Cu")
		(net "M_B_CPU0_SB_DQ<2>")
	)
	(segment
		(start 297.144694 -282.47975)
		(end 297.144694 -282.818078)
		(width 0.14478)
		(layer "In13.Cu")
		(net "M_B_CPU0_SB_DQ<2>")
	)
	(segment
		(start 297.144694 -282.818078)
		(end 296.999914 -282.962858)
		(width 0.14478)
		(layer "In13.Cu")
		(net "M_B_CPU0_SB_DQ<2>")
	)
	(segment
		(start 301.373286 -282.364942)
		(end 300.918372 -281.910028)
		(width 0.14478)
		(layer "In13.Cu")
		(net "M_B_CPU0_SB_DQ<2>")
	)
	(segment
		(start 335.58099 -274.896072)
		(end 335.735168 -274.630642)
		(width 0.0889)
		(layer "In13.Cu")
		(net "M_B_CPU0_SB_DQ<2>")
	)
	(segment
		(start 326.949816 -274.564348)
		(end 326.93356 -274.573746)
		(width 0.0889)
		(layer "In13.Cu")
		(net "M_B_CPU0_SB_DQ<2>")
	)
	(segment
		(start 328.248264 -274.573492)
		(end 328.239882 -274.568666)
		(width 0.0889)
		(layer "In13.Cu")
		(net "M_B_CPU0_SB_DQ<2>")
	)
	(segment
		(start 326.252332 -274.484846)
		(end 325.505318 -273.737832)
		(width 0.0889)
		(layer "In13.Cu")
		(net "M_B_CPU0_SB_DQ<2>")
	)
	(segment
		(start 330.128118 -274.573492)
		(end 330.119736 -274.568666)
		(width 0.0889)
		(layer "In13.Cu")
		(net "M_B_CPU0_SB_DQ<2>")
	)
	(segment
		(start 334.828134 -274.573492)
		(end 334.819752 -274.568666)
		(width 0.0889)
		(layer "In13.Cu")
		(net "M_B_CPU0_SB_DQ<2>")
	)
	(segment
		(start 296.593514 -282.47975)
		(end 296.448734 -282.33497)
		(width 0.14478)
		(layer "In13.Cu")
		(net "M_B_CPU0_SB_DQ<2>")
	)
	(segment
		(start 307.744622 -281.910028)
		(end 305.786536 -281.910028)
		(width 0.14478)
		(layer "In13.Cu")
		(net "M_B_CPU0_SB_DQ<2>")
	)
	(segment
		(start 297.289474 -282.33497)
		(end 297.144694 -282.47975)
		(width 0.14478)
		(layer "In13.Cu")
		(net "M_B_CPU0_SB_DQ<2>")
	)
	(segment
		(start 299.188632 -281.910028)
		(end 298.76369 -282.33497)
		(width 0.14478)
		(layer "In13.Cu")
		(net "M_B_CPU0_SB_DQ<2>")
	)
	(segment
		(start 335.402428 -274.568666)
		(end 335.394046 -274.573492)
		(width 0.0889)
		(layer "In13.Cu")
		(net "M_B_CPU0_SB_DQ<2>")
	)
	(segment
		(start 324.185026 -273.67484)
		(end 323.925184 -273.67484)
		(width 0.0889)
		(layer "In13.Cu")
		(net "M_B_CPU0_SB_DQ<2>")
	)
	(segment
		(start 325.505318 -273.737832)
		(end 324.248018 -273.737832)
		(width 0.0889)
		(layer "In13.Cu")
		(net "M_B_CPU0_SB_DQ<2>")
	)
	(segment
		(start 324.248018 -273.737832)
		(end 324.185026 -273.67484)
		(width 0.0889)
		(layer "In13.Cu")
		(net "M_B_CPU0_SB_DQ<2>")
	)
	(segment
		(start 305.786536 -281.910028)
		(end 305.331622 -282.364942)
		(width 0.14478)
		(layer "In13.Cu")
		(net "M_B_CPU0_SB_DQ<2>")
	)
	(segment
		(start 300.918372 -281.910028)
		(end 299.188632 -281.910028)
		(width 0.14478)
		(layer "In13.Cu")
		(net "M_B_CPU0_SB_DQ<2>")
	)
	(segment
		(start 330.702412 -274.568666)
		(end 330.69403 -274.573492)
		(width 0.0889)
		(layer "In13.Cu")
		(net "M_B_CPU0_SB_DQ<2>")
	)
	(segment
		(start 296.593514 -282.818078)
		(end 296.593514 -282.47975)
		(width 0.14478)
		(layer "In13.Cu")
		(net "M_B_CPU0_SB_DQ<2>")
	)
	(segment
		(start 296.738294 -282.962858)
		(end 296.593514 -282.818078)
		(width 0.14478)
		(layer "In13.Cu")
		(net "M_B_CPU0_SB_DQ<2>")
	)
	(segment
		(start 327.317862 -274.579588)
		(end 327.307448 -274.573492)
		(width 0.0889)
		(layer "In13.Cu")
		(net "M_B_CPU0_SB_DQ<2>")
	)
	(segment
		(start 323.925184 -273.67484)
		(end 315.97981 -273.67484)
		(width 0.14478)
		(layer "In13.Cu")
		(net "M_B_CPU0_SB_DQ<2>")
	)
	(segment
		(start 296.999914 -282.962858)
		(end 296.738294 -282.962858)
		(width 0.14478)
		(layer "In13.Cu")
		(net "M_B_CPU0_SB_DQ<2>")
	)
	(arc
		(start 330.119736 -274.568666)
		(mid 329.936228 -274.523172)
		(end 329.753976 -274.573492)
		(width 0.0889)
		(layer "In13.Cu")
		(net "M_B_CPU0_SB_DQ<2>")
	)
	(arc
		(start 328.239882 -274.568666)
		(mid 328.05612 -274.52305)
		(end 327.873614 -274.573492)
		(width 0.0889)
		(layer "In13.Cu")
		(net "M_B_CPU0_SB_DQ<2>")
	)
	(arc
		(start 326.917812 -274.58289)
		(mid 326.641503 -274.649866)
		(end 326.367648 -274.573492)
		(width 0.0889)
		(layer "In13.Cu")
		(net "M_B_CPU0_SB_DQ<2>")
	)
	(arc
		(start 331.068172 -274.573492)
		(mid 330.885921 -274.523142)
		(end 330.702412 -274.568666)
		(width 0.0889)
		(layer "In13.Cu")
		(net "M_B_CPU0_SB_DQ<2>")
	)
	(arc
		(start 327.307448 -274.573492)
		(mid 327.129798 -274.523232)
		(end 326.949816 -274.564348)
		(width 0.0889)
		(layer "In13.Cu")
		(net "M_B_CPU0_SB_DQ<2>")
	)
	(arc
		(start 328.814176 -274.573492)
		(mid 328.53122 -274.649669)
		(end 328.248264 -274.573492)
		(width 0.0889)
		(layer "In13.Cu")
		(net "M_B_CPU0_SB_DQ<2>")
	)
	(arc
		(start 334.819752 -274.568666)
		(mid 334.636244 -274.523172)
		(end 334.453992 -274.573492)
		(width 0.0889)
		(layer "In13.Cu")
		(net "M_B_CPU0_SB_DQ<2>")
	)
	(arc
		(start 332.574138 -274.573492)
		(mid 332.291182 -274.649669)
		(end 332.008226 -274.573492)
		(width 0.0889)
		(layer "In13.Cu")
		(net "M_B_CPU0_SB_DQ<2>")
	)
	(arc
		(start 329.753976 -274.573492)
		(mid 329.47102 -274.649669)
		(end 329.188064 -274.573492)
		(width 0.0889)
		(layer "In13.Cu")
		(net "M_B_CPU0_SB_DQ<2>")
	)
	(arc
		(start 326.367648 -274.573492)
		(mid 326.307124 -274.532898)
		(end 326.252332 -274.484846)
		(width 0.0889)
		(layer "In13.Cu")
		(net "M_B_CPU0_SB_DQ<2>")
	)
	(arc
		(start 330.69403 -274.573492)
		(mid 330.411074 -274.649669)
		(end 330.128118 -274.573492)
		(width 0.0889)
		(layer "In13.Cu")
		(net "M_B_CPU0_SB_DQ<2>")
	)
	(arc
		(start 329.188064 -274.573492)
		(mid 329.00112 -274.523237)
		(end 328.814176 -274.573492)
		(width 0.0889)
		(layer "In13.Cu")
		(net "M_B_CPU0_SB_DQ<2>")
	)
	(arc
		(start 335.712816 -274.54733)
		(mid 335.555306 -274.524132)
		(end 335.402428 -274.568666)
		(width 0.0889)
		(layer "In13.Cu")
		(net "M_B_CPU0_SB_DQ<2>")
	)
	(arc
		(start 334.453992 -274.573492)
		(mid 334.171036 -274.649669)
		(end 333.88808 -274.573492)
		(width 0.0889)
		(layer "In13.Cu")
		(net "M_B_CPU0_SB_DQ<2>")
	)
	(arc
		(start 333.879698 -274.568666)
		(mid 333.69619 -274.523172)
		(end 333.513938 -274.573492)
		(width 0.0889)
		(layer "In13.Cu")
		(net "M_B_CPU0_SB_DQ<2>")
	)
	(arc
		(start 332.008226 -274.573492)
		(mid 331.825975 -274.523142)
		(end 331.642466 -274.568666)
		(width 0.0889)
		(layer "In13.Cu")
		(net "M_B_CPU0_SB_DQ<2>")
	)
	(arc
		(start 331.634084 -274.573492)
		(mid 331.351128 -274.649669)
		(end 331.068172 -274.573492)
		(width 0.0889)
		(layer "In13.Cu")
		(net "M_B_CPU0_SB_DQ<2>")
	)
	(arc
		(start 332.948026 -274.573492)
		(mid 332.761082 -274.523237)
		(end 332.574138 -274.573492)
		(width 0.0889)
		(layer "In13.Cu")
		(net "M_B_CPU0_SB_DQ<2>")
	)
	(arc
		(start 335.394046 -274.573492)
		(mid 335.11109 -274.649669)
		(end 334.828134 -274.573492)
		(width 0.0889)
		(layer "In13.Cu")
		(net "M_B_CPU0_SB_DQ<2>")
	)
	(arc
		(start 327.873614 -274.573492)
		(mid 327.596547 -274.649763)
		(end 327.317862 -274.579588)
		(width 0.0889)
		(layer "In13.Cu")
		(net "M_B_CPU0_SB_DQ<2>")
	)
	(arc
		(start 333.513938 -274.573492)
		(mid 333.230982 -274.649669)
		(end 332.948026 -274.573492)
		(width 0.0889)
		(layer "In13.Cu")
		(net "M_B_CPU0_SB_DQ<2>")
	)
	(segment
		(start 337.92795 -292.450012)
		(end 337.461098 -292.71595)
		(width 0.10668)
		(layer "F.Cu")
		(net "M_B_CPU0_SB_DQ<29>")
	)
	(segment
		(start 302.708818 -317.827914)
		(end 302.708818 -317.754762)
		(width 0.14478)
		(layer "In13.Cu")
		(net "M_B_CPU0_SB_DQ<29>")
	)
	(segment
		(start 301.751238 -317.609982)
		(end 302.012858 -317.609982)
		(width 0.14478)
		(layer "In13.Cu")
		(net "M_B_CPU0_SB_DQ<29>")
	)
	(segment
		(start 304.362358 -317.827914)
		(end 304.507138 -317.972694)
		(width 0.14478)
		(layer "In13.Cu")
		(net "M_B_CPU0_SB_DQ<29>")
	)
	(segment
		(start 308.734206 -315.915294)
		(end 308.824122 -316.13221)
		(width 0.14478)
		(layer "In13.Cu")
		(net "M_B_CPU0_SB_DQ<29>")
	)
	(segment
		(start 324.184264 -298.8691)
		(end 326.566022 -296.487342)
		(width 0.14478)
		(layer "In13.Cu")
		(net "M_B_CPU0_SB_DQ<29>")
	)
	(segment
		(start 302.012858 -317.609982)
		(end 302.157638 -317.754762)
		(width 0.14478)
		(layer "In13.Cu")
		(net "M_B_CPU0_SB_DQ<29>")
	)
	(segment
		(start 301.200058 -317.972694)
		(end 301.461678 -317.972694)
		(width 0.14478)
		(layer "In13.Cu")
		(net "M_B_CPU0_SB_DQ<29>")
	)
	(segment
		(start 330.119736 -293.043356)
		(end 330.128118 -293.03853)
		(width 0.0889)
		(layer "In13.Cu")
		(net "M_B_CPU0_SB_DQ<29>")
	)
	(segment
		(start 330.69403 -293.03853)
		(end 330.702412 -293.043356)
		(width 0.0889)
		(layer "In13.Cu")
		(net "M_B_CPU0_SB_DQ<29>")
	)
	(segment
		(start 308.303422 -315.937392)
		(end 308.545484 -315.837062)
		(width 0.14478)
		(layer "In13.Cu")
		(net "M_B_CPU0_SB_DQ<29>")
	)
	(segment
		(start 306.150264 -316.822074)
		(end 306.392326 -316.721744)
		(width 0.14478)
		(layer "In13.Cu")
		(net "M_B_CPU0_SB_DQ<29>")
	)
	(segment
		(start 331.634084 -293.03853)
		(end 331.642466 -293.043356)
		(width 0.0889)
		(layer "In13.Cu")
		(net "M_B_CPU0_SB_DQ<29>")
	)
	(segment
		(start 299.82414 -317.18504)
		(end 300.249082 -317.609982)
		(width 0.14478)
		(layer "In13.Cu")
		(net "M_B_CPU0_SB_DQ<29>")
	)
	(segment
		(start 300.249082 -317.609982)
		(end 300.910498 -317.609982)
		(width 0.14478)
		(layer "In13.Cu")
		(net "M_B_CPU0_SB_DQ<29>")
	)
	(segment
		(start 333.879698 -293.043356)
		(end 333.88808 -293.03853)
		(width 0.0889)
		(layer "In13.Cu")
		(net "M_B_CPU0_SB_DQ<29>")
	)
	(segment
		(start 306.673758 -317.023242)
		(end 306.862734 -317.101474)
		(width 0.14478)
		(layer "In13.Cu")
		(net "M_B_CPU0_SB_DQ<29>")
	)
	(segment
		(start 309.564024 -315.982858)
		(end 324.184264 -301.362618)
		(width 0.14478)
		(layer "In13.Cu")
		(net "M_B_CPU0_SB_DQ<29>")
	)
	(segment
		(start 304.768758 -317.972694)
		(end 304.913538 -317.827914)
		(width 0.14478)
		(layer "In13.Cu")
		(net "M_B_CPU0_SB_DQ<29>")
	)
	(segment
		(start 303.666398 -317.972694)
		(end 303.811178 -317.827914)
		(width 0.14478)
		(layer "In13.Cu")
		(net "M_B_CPU0_SB_DQ<29>")
	)
	(segment
		(start 301.055278 -317.827914)
		(end 301.200058 -317.972694)
		(width 0.14478)
		(layer "In13.Cu")
		(net "M_B_CPU0_SB_DQ<29>")
	)
	(segment
		(start 301.606458 -317.754762)
		(end 301.751238 -317.609982)
		(width 0.14478)
		(layer "In13.Cu")
		(net "M_B_CPU0_SB_DQ<29>")
	)
	(segment
		(start 304.507138 -317.972694)
		(end 304.768758 -317.972694)
		(width 0.14478)
		(layer "In13.Cu")
		(net "M_B_CPU0_SB_DQ<29>")
	)
	(segment
		(start 327.178416 -296.353992)
		(end 327.340976 -296.259504)
		(width 0.0889)
		(layer "In13.Cu")
		(net "M_B_CPU0_SB_DQ<29>")
	)
	(segment
		(start 301.461678 -317.972694)
		(end 301.606458 -317.827914)
		(width 0.14478)
		(layer "In13.Cu")
		(net "M_B_CPU0_SB_DQ<29>")
	)
	(segment
		(start 335.394046 -293.03853)
		(end 335.402428 -293.043356)
		(width 0.0889)
		(layer "In13.Cu")
		(net "M_B_CPU0_SB_DQ<29>")
	)
	(segment
		(start 308.545484 -315.837062)
		(end 308.734206 -315.915294)
		(width 0.14478)
		(layer "In13.Cu")
		(net "M_B_CPU0_SB_DQ<29>")
	)
	(segment
		(start 308.23662 -316.53226)
		(end 308.314852 -316.343284)
		(width 0.14478)
		(layer "In13.Cu")
		(net "M_B_CPU0_SB_DQ<29>")
	)
	(segment
		(start 302.157638 -317.827914)
		(end 302.302418 -317.972694)
		(width 0.14478)
		(layer "In13.Cu")
		(net "M_B_CPU0_SB_DQ<29>")
	)
	(segment
		(start 302.157638 -317.754762)
		(end 302.157638 -317.827914)
		(width 0.14478)
		(layer "In13.Cu")
		(net "M_B_CPU0_SB_DQ<29>")
	)
	(segment
		(start 304.913538 -317.754762)
		(end 305.058318 -317.609982)
		(width 0.14478)
		(layer "In13.Cu")
		(net "M_B_CPU0_SB_DQ<29>")
	)
	(segment
		(start 305.635914 -317.609982)
		(end 306.086256 -317.423292)
		(width 0.14478)
		(layer "In13.Cu")
		(net "M_B_CPU0_SB_DQ<29>")
	)
	(segment
		(start 337.307174 -292.98138)
		(end 337.461098 -292.71595)
		(width 0.0889)
		(layer "In13.Cu")
		(net "M_B_CPU0_SB_DQ<29>")
	)
	(segment
		(start 327.739248 -295.491408)
		(end 327.778364 -295.468548)
		(width 0.0889)
		(layer "In13.Cu")
		(net "M_B_CPU0_SB_DQ<29>")
	)
	(segment
		(start 304.362358 -317.754762)
		(end 304.362358 -317.827914)
		(width 0.14478)
		(layer "In13.Cu")
		(net "M_B_CPU0_SB_DQ<29>")
	)
	(segment
		(start 303.404778 -317.972694)
		(end 303.666398 -317.972694)
		(width 0.14478)
		(layer "In13.Cu")
		(net "M_B_CPU0_SB_DQ<29>")
	)
	(segment
		(start 328.211942 -294.679624)
		(end 328.248264 -294.658542)
		(width 0.0889)
		(layer "In13.Cu")
		(net "M_B_CPU0_SB_DQ<29>")
	)
	(segment
		(start 301.606458 -317.827914)
		(end 301.606458 -317.754762)
		(width 0.14478)
		(layer "In13.Cu")
		(net "M_B_CPU0_SB_DQ<29>")
	)
	(segment
		(start 305.058318 -317.609982)
		(end 305.635914 -317.609982)
		(width 0.14478)
		(layer "In13.Cu")
		(net "M_B_CPU0_SB_DQ<29>")
	)
	(segment
		(start 306.862734 -317.101474)
		(end 308.23662 -316.53226)
		(width 0.14478)
		(layer "In13.Cu")
		(net "M_B_CPU0_SB_DQ<29>")
	)
	(segment
		(start 309.013352 -316.210696)
		(end 309.564024 -315.982858)
		(width 0.14478)
		(layer "In13.Cu")
		(net "M_B_CPU0_SB_DQ<29>")
	)
	(segment
		(start 328.248264 -294.658542)
		(end 328.278744 -294.640762)
		(width 0.0889)
		(layer "In13.Cu")
		(net "M_B_CPU0_SB_DQ<29>")
	)
	(segment
		(start 306.581302 -316.799976)
		(end 306.673758 -317.023242)
		(width 0.14478)
		(layer "In13.Cu")
		(net "M_B_CPU0_SB_DQ<29>")
	)
	(segment
		(start 326.759062 -296.407332)
		(end 326.98055 -296.407332)
		(width 0.0889)
		(layer "In13.Cu")
		(net "M_B_CPU0_SB_DQ<29>")
	)
	(segment
		(start 302.564038 -317.972694)
		(end 302.708818 -317.827914)
		(width 0.14478)
		(layer "In13.Cu")
		(net "M_B_CPU0_SB_DQ<29>")
	)
	(segment
		(start 300.910498 -317.609982)
		(end 301.055278 -317.754762)
		(width 0.14478)
		(layer "In13.Cu")
		(net "M_B_CPU0_SB_DQ<29>")
	)
	(segment
		(start 306.164488 -317.234316)
		(end 306.072032 -317.01105)
		(width 0.14478)
		(layer "In13.Cu")
		(net "M_B_CPU0_SB_DQ<29>")
	)
	(segment
		(start 303.115218 -317.609982)
		(end 303.259998 -317.754762)
		(width 0.14478)
		(layer "In13.Cu")
		(net "M_B_CPU0_SB_DQ<29>")
	)
	(segment
		(start 327.778364 -295.468548)
		(end 327.810114 -295.45026)
		(width 0.0889)
		(layer "In13.Cu")
		(net "M_B_CPU0_SB_DQ<29>")
	)
	(segment
		(start 304.913538 -317.827914)
		(end 304.913538 -317.754762)
		(width 0.14478)
		(layer "In13.Cu")
		(net "M_B_CPU0_SB_DQ<29>")
	)
	(segment
		(start 306.086256 -317.423292)
		(end 306.164488 -317.234316)
		(width 0.14478)
		(layer "In13.Cu")
		(net "M_B_CPU0_SB_DQ<29>")
	)
	(segment
		(start 303.811178 -317.754762)
		(end 303.955958 -317.609982)
		(width 0.14478)
		(layer "In13.Cu")
		(net "M_B_CPU0_SB_DQ<29>")
	)
	(segment
		(start 303.811178 -317.827914)
		(end 303.811178 -317.754762)
		(width 0.14478)
		(layer "In13.Cu")
		(net "M_B_CPU0_SB_DQ<29>")
	)
	(segment
		(start 303.259998 -317.754762)
		(end 303.259998 -317.827914)
		(width 0.14478)
		(layer "In13.Cu")
		(net "M_B_CPU0_SB_DQ<29>")
	)
	(segment
		(start 337.211162 -293.00678)
		(end 337.307174 -292.98138)
		(width 0.0889)
		(layer "In13.Cu")
		(net "M_B_CPU0_SB_DQ<29>")
	)
	(segment
		(start 303.259998 -317.827914)
		(end 303.404778 -317.972694)
		(width 0.14478)
		(layer "In13.Cu")
		(net "M_B_CPU0_SB_DQ<29>")
	)
	(segment
		(start 324.184264 -301.362618)
		(end 324.184264 -298.8691)
		(width 0.14478)
		(layer "In13.Cu")
		(net "M_B_CPU0_SB_DQ<29>")
	)
	(segment
		(start 306.072032 -317.01105)
		(end 306.150264 -316.822074)
		(width 0.14478)
		(layer "In13.Cu")
		(net "M_B_CPU0_SB_DQ<29>")
	)
	(segment
		(start 336.3341 -293.03853)
		(end 336.342482 -293.043356)
		(width 0.0889)
		(layer "In13.Cu")
		(net "M_B_CPU0_SB_DQ<29>")
	)
	(segment
		(start 302.708818 -317.754762)
		(end 302.853598 -317.609982)
		(width 0.14478)
		(layer "In13.Cu")
		(net "M_B_CPU0_SB_DQ<29>")
	)
	(segment
		(start 302.302418 -317.972694)
		(end 302.564038 -317.972694)
		(width 0.14478)
		(layer "In13.Cu")
		(net "M_B_CPU0_SB_DQ<29>")
	)
	(segment
		(start 328.718164 -293.848536)
		(end 328.749914 -293.830248)
		(width 0.0889)
		(layer "In13.Cu")
		(net "M_B_CPU0_SB_DQ<29>")
	)
	(segment
		(start 308.224936 -316.126368)
		(end 308.303422 -315.937392)
		(width 0.14478)
		(layer "In13.Cu")
		(net "M_B_CPU0_SB_DQ<29>")
	)
	(segment
		(start 308.314852 -316.343284)
		(end 308.224936 -316.126368)
		(width 0.14478)
		(layer "In13.Cu")
		(net "M_B_CPU0_SB_DQ<29>")
	)
	(segment
		(start 328.679048 -293.871396)
		(end 328.718164 -293.848536)
		(width 0.0889)
		(layer "In13.Cu")
		(net "M_B_CPU0_SB_DQ<29>")
	)
	(segment
		(start 333.88808 -293.03853)
		(end 333.888334 -293.03853)
		(width 0.0889)
		(layer "In13.Cu")
		(net "M_B_CPU0_SB_DQ<29>")
	)
	(segment
		(start 308.824122 -316.13221)
		(end 309.013352 -316.210696)
		(width 0.14478)
		(layer "In13.Cu")
		(net "M_B_CPU0_SB_DQ<29>")
	)
	(segment
		(start 304.217578 -317.609982)
		(end 304.362358 -317.754762)
		(width 0.14478)
		(layer "In13.Cu")
		(net "M_B_CPU0_SB_DQ<29>")
	)
	(segment
		(start 302.853598 -317.609982)
		(end 303.115218 -317.609982)
		(width 0.14478)
		(layer "In13.Cu")
		(net "M_B_CPU0_SB_DQ<29>")
	)
	(segment
		(start 306.392326 -316.721744)
		(end 306.581302 -316.799976)
		(width 0.14478)
		(layer "In13.Cu")
		(net "M_B_CPU0_SB_DQ<29>")
	)
	(segment
		(start 329.151742 -293.059612)
		(end 329.188064 -293.03853)
		(width 0.0889)
		(layer "In13.Cu")
		(net "M_B_CPU0_SB_DQ<29>")
	)
	(segment
		(start 303.955958 -317.609982)
		(end 304.217578 -317.609982)
		(width 0.14478)
		(layer "In13.Cu")
		(net "M_B_CPU0_SB_DQ<29>")
	)
	(segment
		(start 334.819752 -293.043356)
		(end 334.828134 -293.03853)
		(width 0.0889)
		(layer "In13.Cu")
		(net "M_B_CPU0_SB_DQ<29>")
	)
	(segment
		(start 301.055278 -317.754762)
		(end 301.055278 -317.827914)
		(width 0.14478)
		(layer "In13.Cu")
		(net "M_B_CPU0_SB_DQ<29>")
	)
	(arc
		(start 333.888334 -293.03853)
		(mid 334.17118 -292.962353)
		(end 334.453992 -293.03853)
		(width 0.0889)
		(layer "In13.Cu")
		(net "M_B_CPU0_SB_DQ<29>")
	)
	(arc
		(start 332.574138 -293.03853)
		(mid 332.761082 -293.088785)
		(end 332.948026 -293.03853)
		(width 0.0889)
		(layer "In13.Cu")
		(net "M_B_CPU0_SB_DQ<29>")
	)
	(arc
		(start 326.98055 -296.407332)
		(mid 327.083015 -296.393764)
		(end 327.178416 -296.353992)
		(width 0.0889)
		(layer "In13.Cu")
		(net "M_B_CPU0_SB_DQ<29>")
	)
	(arc
		(start 327.495916 -295.955974)
		(mid 327.560431 -295.693755)
		(end 327.739248 -295.491408)
		(width 0.0889)
		(layer "In13.Cu")
		(net "M_B_CPU0_SB_DQ<29>")
	)
	(arc
		(start 327.810114 -295.45026)
		(mid 327.92479 -295.316926)
		(end 327.96607 -295.145968)
		(width 0.0889)
		(layer "In13.Cu")
		(net "M_B_CPU0_SB_DQ<29>")
	)
	(arc
		(start 328.435716 -294.335962)
		(mid 328.500231 -294.073743)
		(end 328.679048 -293.871396)
		(width 0.0889)
		(layer "In13.Cu")
		(net "M_B_CPU0_SB_DQ<29>")
	)
	(arc
		(start 332.008226 -293.03853)
		(mid 332.291182 -292.962353)
		(end 332.574138 -293.03853)
		(width 0.0889)
		(layer "In13.Cu")
		(net "M_B_CPU0_SB_DQ<29>")
	)
	(arc
		(start 334.828134 -293.03853)
		(mid 335.11109 -292.962353)
		(end 335.394046 -293.03853)
		(width 0.0889)
		(layer "In13.Cu")
		(net "M_B_CPU0_SB_DQ<29>")
	)
	(arc
		(start 332.948026 -293.03853)
		(mid 333.230982 -292.962353)
		(end 333.513938 -293.03853)
		(width 0.0889)
		(layer "In13.Cu")
		(net "M_B_CPU0_SB_DQ<29>")
	)
	(arc
		(start 328.749914 -293.830248)
		(mid 328.86459 -293.696914)
		(end 328.90587 -293.525956)
		(width 0.0889)
		(layer "In13.Cu")
		(net "M_B_CPU0_SB_DQ<29>")
	)
	(arc
		(start 328.90587 -293.525956)
		(mid 328.971106 -293.262365)
		(end 329.151742 -293.059612)
		(width 0.0889)
		(layer "In13.Cu")
		(net "M_B_CPU0_SB_DQ<29>")
	)
	(arc
		(start 335.768188 -293.03853)
		(mid 336.051144 -292.962353)
		(end 336.3341 -293.03853)
		(width 0.0889)
		(layer "In13.Cu")
		(net "M_B_CPU0_SB_DQ<29>")
	)
	(arc
		(start 329.188064 -293.03853)
		(mid 329.47102 -292.962353)
		(end 329.753976 -293.03853)
		(width 0.0889)
		(layer "In13.Cu")
		(net "M_B_CPU0_SB_DQ<29>")
	)
	(arc
		(start 333.513938 -293.03853)
		(mid 333.696189 -293.08888)
		(end 333.879698 -293.043356)
		(width 0.0889)
		(layer "In13.Cu")
		(net "M_B_CPU0_SB_DQ<29>")
	)
	(arc
		(start 330.702412 -293.043356)
		(mid 330.88592 -293.08885)
		(end 331.068172 -293.03853)
		(width 0.0889)
		(layer "In13.Cu")
		(net "M_B_CPU0_SB_DQ<29>")
	)
	(arc
		(start 331.642466 -293.043356)
		(mid 331.825974 -293.08885)
		(end 332.008226 -293.03853)
		(width 0.0889)
		(layer "In13.Cu")
		(net "M_B_CPU0_SB_DQ<29>")
	)
	(arc
		(start 330.128118 -293.03853)
		(mid 330.411074 -292.962353)
		(end 330.69403 -293.03853)
		(width 0.0889)
		(layer "In13.Cu")
		(net "M_B_CPU0_SB_DQ<29>")
	)
	(arc
		(start 326.566022 -296.487342)
		(mid 326.65459 -296.428163)
		(end 326.759062 -296.407332)
		(width 0.0889)
		(layer "In13.Cu")
		(net "M_B_CPU0_SB_DQ<29>")
	)
	(arc
		(start 336.708242 -293.03853)
		(mid 336.955955 -292.96331)
		(end 337.211162 -293.00678)
		(width 0.0889)
		(layer "In13.Cu")
		(net "M_B_CPU0_SB_DQ<29>")
	)
	(arc
		(start 331.068172 -293.03853)
		(mid 331.351128 -292.962353)
		(end 331.634084 -293.03853)
		(width 0.0889)
		(layer "In13.Cu")
		(net "M_B_CPU0_SB_DQ<29>")
	)
	(arc
		(start 327.96607 -295.145968)
		(mid 328.031306 -294.882377)
		(end 328.211942 -294.679624)
		(width 0.0889)
		(layer "In13.Cu")
		(net "M_B_CPU0_SB_DQ<29>")
	)
	(arc
		(start 328.278744 -294.640762)
		(mid 328.394171 -294.507386)
		(end 328.435716 -294.335962)
		(width 0.0889)
		(layer "In13.Cu")
		(net "M_B_CPU0_SB_DQ<29>")
	)
	(arc
		(start 334.453992 -293.03853)
		(mid 334.636243 -293.08888)
		(end 334.819752 -293.043356)
		(width 0.0889)
		(layer "In13.Cu")
		(net "M_B_CPU0_SB_DQ<29>")
	)
	(arc
		(start 329.753976 -293.03853)
		(mid 329.936227 -293.08888)
		(end 330.119736 -293.043356)
		(width 0.0889)
		(layer "In13.Cu")
		(net "M_B_CPU0_SB_DQ<29>")
	)
	(arc
		(start 336.342482 -293.043356)
		(mid 336.52599 -293.08885)
		(end 336.708242 -293.03853)
		(width 0.0889)
		(layer "In13.Cu")
		(net "M_B_CPU0_SB_DQ<29>")
	)
	(arc
		(start 335.402428 -293.043356)
		(mid 335.585936 -293.08885)
		(end 335.768188 -293.03853)
		(width 0.0889)
		(layer "In13.Cu")
		(net "M_B_CPU0_SB_DQ<29>")
	)
	(arc
		(start 327.340976 -296.259504)
		(mid 327.454905 -296.126357)
		(end 327.495916 -295.955974)
		(width 0.0889)
		(layer "In13.Cu")
		(net "M_B_CPU0_SB_DQ<29>")
	)
	(segment
		(start 336.517996 -291.640006)
		(end 336.051144 -291.905944)
		(width 0.10668)
		(layer "F.Cu")
		(net "M_B_CPU0_SB_DQ<28>")
	)
	(segment
		(start 302.901604 -316.100714)
		(end 302.901604 -316.060074)
		(width 0.14478)
		(layer "In13.Cu")
		(net "M_B_CPU0_SB_DQ<28>")
	)
	(segment
		(start 329.292458 -292.23335)
		(end 329.284076 -292.228524)
		(width 0.0889)
		(layer "In13.Cu")
		(net "M_B_CPU0_SB_DQ<28>")
	)
	(segment
		(start 321.939666 -301.09922)
		(end 321.734942 -301.09922)
		(width 0.14478)
		(layer "In13.Cu")
		(net "M_B_CPU0_SB_DQ<28>")
	)
	(segment
		(start 302.350424 -316.060074)
		(end 302.350424 -316.100714)
		(width 0.14478)
		(layer "In13.Cu")
		(net "M_B_CPU0_SB_DQ<28>")
	)
	(segment
		(start 321.555872 -302.274986)
		(end 321.159886 -301.879)
		(width 0.14478)
		(layer "In13.Cu")
		(net "M_B_CPU0_SB_DQ<28>")
	)
	(segment
		(start 327.33869 -293.02075)
		(end 327.30821 -293.03853)
		(width 0.0889)
		(layer "In13.Cu")
		(net "M_B_CPU0_SB_DQ<28>")
	)
	(segment
		(start 320.769996 -302.26889)
		(end 321.165982 -302.664876)
		(width 0.14478)
		(layer "In13.Cu")
		(net "M_B_CPU0_SB_DQ<28>")
	)
	(segment
		(start 328.718164 -292.228524)
		(end 328.71791 -292.228524)
		(width 0.0889)
		(layer "In13.Cu")
		(net "M_B_CPU0_SB_DQ<28>")
	)
	(segment
		(start 320.955162 -301.879)
		(end 320.769996 -302.064166)
		(width 0.14478)
		(layer "In13.Cu")
		(net "M_B_CPU0_SB_DQ<28>")
	)
	(segment
		(start 301.799244 -316.060074)
		(end 301.654464 -315.915294)
		(width 0.14478)
		(layer "In13.Cu")
		(net "M_B_CPU0_SB_DQ<28>")
	)
	(segment
		(start 320.386202 -303.64938)
		(end 309.965344 -314.070238)
		(width 0.14478)
		(layer "In13.Cu")
		(net "M_B_CPU0_SB_DQ<28>")
	)
	(segment
		(start 301.944024 -316.245494)
		(end 301.799244 -316.100714)
		(width 0.14478)
		(layer "In13.Cu")
		(net "M_B_CPU0_SB_DQ<28>")
	)
	(segment
		(start 326.398636 -294.640762)
		(end 326.357234 -294.664638)
		(width 0.0889)
		(layer "In13.Cu")
		(net "M_B_CPU0_SB_DQ<28>")
	)
	(segment
		(start 302.495204 -315.915294)
		(end 302.350424 -316.060074)
		(width 0.14478)
		(layer "In13.Cu")
		(net "M_B_CPU0_SB_DQ<28>")
	)
	(segment
		(start 302.205644 -316.245494)
		(end 301.944024 -316.245494)
		(width 0.14478)
		(layer "In13.Cu")
		(net "M_B_CPU0_SB_DQ<28>")
	)
	(segment
		(start 321.159886 -301.879)
		(end 320.955162 -301.879)
		(width 0.14478)
		(layer "In13.Cu")
		(net "M_B_CPU0_SB_DQ<28>")
	)
	(segment
		(start 323.214492 -300.82109)
		(end 322.540376 -301.495206)
		(width 0.14478)
		(layer "In13.Cu")
		(net "M_B_CPU0_SB_DQ<28>")
	)
	(segment
		(start 320.380106 -302.65878)
		(end 320.175382 -302.65878)
		(width 0.14478)
		(layer "In13.Cu")
		(net "M_B_CPU0_SB_DQ<28>")
	)
	(segment
		(start 305.510946 -315.915294)
		(end 303.597564 -315.915294)
		(width 0.14478)
		(layer "In13.Cu")
		(net "M_B_CPU0_SB_DQ<28>")
	)
	(segment
		(start 322.335652 -301.495206)
		(end 321.939666 -301.09922)
		(width 0.14478)
		(layer "In13.Cu")
		(net "M_B_CPU0_SB_DQ<28>")
	)
	(segment
		(start 325.640954 -296.04081)
		(end 323.214492 -298.467272)
		(width 0.14478)
		(layer "In13.Cu")
		(net "M_B_CPU0_SB_DQ<28>")
	)
	(segment
		(start 320.175382 -302.65878)
		(end 319.990216 -302.843946)
		(width 0.14478)
		(layer "In13.Cu")
		(net "M_B_CPU0_SB_DQ<28>")
	)
	(segment
		(start 319.990216 -302.843946)
		(end 319.990216 -303.04867)
		(width 0.14478)
		(layer "In13.Cu")
		(net "M_B_CPU0_SB_DQ<28>")
	)
	(segment
		(start 323.214492 -298.467272)
		(end 323.214492 -300.82109)
		(width 0.14478)
		(layer "In13.Cu")
		(net "M_B_CPU0_SB_DQ<28>")
	)
	(segment
		(start 321.945762 -302.08982)
		(end 321.760596 -302.274986)
		(width 0.14478)
		(layer "In13.Cu")
		(net "M_B_CPU0_SB_DQ<28>")
	)
	(segment
		(start 321.945762 -301.885096)
		(end 321.945762 -302.08982)
		(width 0.14478)
		(layer "In13.Cu")
		(net "M_B_CPU0_SB_DQ<28>")
	)
	(segment
		(start 301.654464 -315.915294)
		(end 300.254416 -315.915294)
		(width 0.14478)
		(layer "In13.Cu")
		(net "M_B_CPU0_SB_DQ<28>")
	)
	(segment
		(start 303.452784 -316.060074)
		(end 303.452784 -316.100714)
		(width 0.14478)
		(layer "In13.Cu")
		(net "M_B_CPU0_SB_DQ<28>")
	)
	(segment
		(start 303.452784 -316.100714)
		(end 303.308004 -316.245494)
		(width 0.14478)
		(layer "In13.Cu")
		(net "M_B_CPU0_SB_DQ<28>")
	)
	(segment
		(start 320.776092 -303.054766)
		(end 320.380106 -302.65878)
		(width 0.14478)
		(layer "In13.Cu")
		(net "M_B_CPU0_SB_DQ<28>")
	)
	(segment
		(start 332.478126 -292.228524)
		(end 332.469744 -292.23335)
		(width 0.0889)
		(layer "In13.Cu")
		(net "M_B_CPU0_SB_DQ<28>")
	)
	(segment
		(start 321.165982 -302.664876)
		(end 321.165982 -302.8696)
		(width 0.14478)
		(layer "In13.Cu")
		(net "M_B_CPU0_SB_DQ<28>")
	)
	(segment
		(start 327.30821 -293.03853)
		(end 327.269094 -293.06139)
		(width 0.0889)
		(layer "In13.Cu")
		(net "M_B_CPU0_SB_DQ<28>")
	)
	(segment
		(start 333.992474 -292.23335)
		(end 333.984092 -292.228524)
		(width 0.0889)
		(layer "In13.Cu")
		(net "M_B_CPU0_SB_DQ<28>")
	)
	(segment
		(start 303.597564 -315.915294)
		(end 303.452784 -316.060074)
		(width 0.14478)
		(layer "In13.Cu")
		(net "M_B_CPU0_SB_DQ<28>")
	)
	(segment
		(start 321.549776 -301.48911)
		(end 321.945762 -301.885096)
		(width 0.14478)
		(layer "In13.Cu")
		(net "M_B_CPU0_SB_DQ<28>")
	)
	(segment
		(start 326.079612 -295.145968)
		(end 326.079612 -295.181528)
		(width 0.0889)
		(layer "In13.Cu")
		(net "M_B_CPU0_SB_DQ<28>")
	)
	(segment
		(start 326.838056 -293.848536)
		(end 326.80021 -293.87038)
		(width 0.0889)
		(layer "In13.Cu")
		(net "M_B_CPU0_SB_DQ<28>")
	)
	(segment
		(start 321.165982 -302.8696)
		(end 320.980816 -303.054766)
		(width 0.14478)
		(layer "In13.Cu")
		(net "M_B_CPU0_SB_DQ<28>")
	)
	(segment
		(start 325.782178 -295.899586)
		(end 325.640954 -296.04081)
		(width 0.0889)
		(layer "In13.Cu")
		(net "M_B_CPU0_SB_DQ<28>")
	)
	(segment
		(start 309.965344 -314.070238)
		(end 305.510946 -315.915294)
		(width 0.14478)
		(layer "In13.Cu")
		(net "M_B_CPU0_SB_DQ<28>")
	)
	(segment
		(start 333.05242 -292.23335)
		(end 333.044038 -292.228524)
		(width 0.0889)
		(layer "In13.Cu")
		(net "M_B_CPU0_SB_DQ<28>")
	)
	(segment
		(start 303.046384 -316.245494)
		(end 302.901604 -316.100714)
		(width 0.14478)
		(layer "In13.Cu")
		(net "M_B_CPU0_SB_DQ<28>")
	)
	(segment
		(start 300.254416 -315.915294)
		(end 299.82414 -315.485018)
		(width 0.14478)
		(layer "In13.Cu")
		(net "M_B_CPU0_SB_DQ<28>")
	)
	(segment
		(start 302.901604 -316.060074)
		(end 302.756824 -315.915294)
		(width 0.14478)
		(layer "In13.Cu")
		(net "M_B_CPU0_SB_DQ<28>")
	)
	(segment
		(start 331.538072 -292.228524)
		(end 331.52969 -292.23335)
		(width 0.0889)
		(layer "In13.Cu")
		(net "M_B_CPU0_SB_DQ<28>")
	)
	(segment
		(start 327.77811 -292.228524)
		(end 327.738994 -292.251384)
		(width 0.0889)
		(layer "In13.Cu")
		(net "M_B_CPU0_SB_DQ<28>")
	)
	(segment
		(start 321.549776 -301.284386)
		(end 321.549776 -301.48911)
		(width 0.14478)
		(layer "In13.Cu")
		(net "M_B_CPU0_SB_DQ<28>")
	)
	(segment
		(start 303.308004 -316.245494)
		(end 303.046384 -316.245494)
		(width 0.14478)
		(layer "In13.Cu")
		(net "M_B_CPU0_SB_DQ<28>")
	)
	(segment
		(start 301.799244 -316.100714)
		(end 301.799244 -316.060074)
		(width 0.14478)
		(layer "In13.Cu")
		(net "M_B_CPU0_SB_DQ<28>")
	)
	(segment
		(start 320.769996 -302.064166)
		(end 320.769996 -302.26889)
		(width 0.14478)
		(layer "In13.Cu")
		(net "M_B_CPU0_SB_DQ<28>")
	)
	(segment
		(start 335.896966 -292.171374)
		(end 335.8007 -292.196774)
		(width 0.0889)
		(layer "In13.Cu")
		(net "M_B_CPU0_SB_DQ<28>")
	)
	(segment
		(start 319.990216 -303.04867)
		(end 320.386202 -303.444656)
		(width 0.14478)
		(layer "In13.Cu")
		(net "M_B_CPU0_SB_DQ<28>")
	)
	(segment
		(start 321.734942 -301.09922)
		(end 321.549776 -301.284386)
		(width 0.14478)
		(layer "In13.Cu")
		(net "M_B_CPU0_SB_DQ<28>")
	)
	(segment
		(start 322.540376 -301.495206)
		(end 322.335652 -301.495206)
		(width 0.14478)
		(layer "In13.Cu")
		(net "M_B_CPU0_SB_DQ<28>")
	)
	(segment
		(start 320.386202 -303.444656)
		(end 320.386202 -303.64938)
		(width 0.14478)
		(layer "In13.Cu")
		(net "M_B_CPU0_SB_DQ<28>")
	)
	(segment
		(start 321.760596 -302.274986)
		(end 321.555872 -302.274986)
		(width 0.14478)
		(layer "In13.Cu")
		(net "M_B_CPU0_SB_DQ<28>")
	)
	(segment
		(start 302.350424 -316.100714)
		(end 302.205644 -316.245494)
		(width 0.14478)
		(layer "In13.Cu")
		(net "M_B_CPU0_SB_DQ<28>")
	)
	(segment
		(start 320.980816 -303.054766)
		(end 320.776092 -303.054766)
		(width 0.14478)
		(layer "In13.Cu")
		(net "M_B_CPU0_SB_DQ<28>")
	)
	(segment
		(start 302.756824 -315.915294)
		(end 302.495204 -315.915294)
		(width 0.14478)
		(layer "In13.Cu")
		(net "M_B_CPU0_SB_DQ<28>")
	)
	(segment
		(start 336.051144 -291.905944)
		(end 335.896966 -292.171374)
		(width 0.0889)
		(layer "In13.Cu")
		(net "M_B_CPU0_SB_DQ<28>")
	)
	(segment
		(start 326.869806 -293.830248)
		(end 326.838056 -293.848536)
		(width 0.0889)
		(layer "In13.Cu")
		(net "M_B_CPU0_SB_DQ<28>")
	)
	(arc
		(start 335.298034 -292.228524)
		(mid 335.11109 -292.278779)
		(end 334.924146 -292.228524)
		(width 0.0889)
		(layer "In13.Cu")
		(net "M_B_CPU0_SB_DQ<28>")
	)
	(arc
		(start 329.284076 -292.228524)
		(mid 329.00112 -292.152347)
		(end 328.718164 -292.228524)
		(width 0.0889)
		(layer "In13.Cu")
		(net "M_B_CPU0_SB_DQ<28>")
	)
	(arc
		(start 328.71791 -292.228524)
		(mid 328.530966 -292.278848)
		(end 328.344022 -292.228524)
		(width 0.0889)
		(layer "In13.Cu")
		(net "M_B_CPU0_SB_DQ<28>")
	)
	(arc
		(start 327.269094 -293.06139)
		(mid 327.090281 -293.26374)
		(end 327.025762 -293.525956)
		(width 0.0889)
		(layer "In13.Cu")
		(net "M_B_CPU0_SB_DQ<28>")
	)
	(arc
		(start 334.358234 -292.228524)
		(mid 334.175983 -292.278874)
		(end 333.992474 -292.23335)
		(width 0.0889)
		(layer "In13.Cu")
		(net "M_B_CPU0_SB_DQ<28>")
	)
	(arc
		(start 327.738994 -292.251384)
		(mid 327.560181 -292.453734)
		(end 327.495662 -292.71595)
		(width 0.0889)
		(layer "In13.Cu")
		(net "M_B_CPU0_SB_DQ<28>")
	)
	(arc
		(start 330.598018 -292.228524)
		(mid 330.411074 -292.278779)
		(end 330.22413 -292.228524)
		(width 0.0889)
		(layer "In13.Cu")
		(net "M_B_CPU0_SB_DQ<28>")
	)
	(arc
		(start 326.079612 -295.181528)
		(mid 326.002312 -295.57014)
		(end 325.782178 -295.899586)
		(width 0.0889)
		(layer "In13.Cu")
		(net "M_B_CPU0_SB_DQ<28>")
	)
	(arc
		(start 331.16393 -292.228524)
		(mid 330.880974 -292.152347)
		(end 330.598018 -292.228524)
		(width 0.0889)
		(layer "In13.Cu")
		(net "M_B_CPU0_SB_DQ<28>")
	)
	(arc
		(start 326.555608 -294.335962)
		(mid 326.514059 -294.507384)
		(end 326.398636 -294.640762)
		(width 0.0889)
		(layer "In13.Cu")
		(net "M_B_CPU0_SB_DQ<28>")
	)
	(arc
		(start 327.495662 -292.71595)
		(mid 327.454113 -292.887372)
		(end 327.33869 -293.02075)
		(width 0.0889)
		(layer "In13.Cu")
		(net "M_B_CPU0_SB_DQ<28>")
	)
	(arc
		(start 333.41818 -292.228524)
		(mid 333.235929 -292.278874)
		(end 333.05242 -292.23335)
		(width 0.0889)
		(layer "In13.Cu")
		(net "M_B_CPU0_SB_DQ<28>")
	)
	(arc
		(start 333.044038 -292.228524)
		(mid 332.761082 -292.152347)
		(end 332.478126 -292.228524)
		(width 0.0889)
		(layer "In13.Cu")
		(net "M_B_CPU0_SB_DQ<28>")
	)
	(arc
		(start 333.984092 -292.228524)
		(mid 333.701136 -292.152347)
		(end 333.41818 -292.228524)
		(width 0.0889)
		(layer "In13.Cu")
		(net "M_B_CPU0_SB_DQ<28>")
	)
	(arc
		(start 335.8007 -292.196774)
		(mid 335.545635 -292.153423)
		(end 335.298034 -292.228524)
		(width 0.0889)
		(layer "In13.Cu")
		(net "M_B_CPU0_SB_DQ<28>")
	)
	(arc
		(start 332.469744 -292.23335)
		(mid 332.286236 -292.278844)
		(end 332.103984 -292.228524)
		(width 0.0889)
		(layer "In13.Cu")
		(net "M_B_CPU0_SB_DQ<28>")
	)
	(arc
		(start 334.924146 -292.228524)
		(mid 334.64119 -292.152347)
		(end 334.358234 -292.228524)
		(width 0.0889)
		(layer "In13.Cu")
		(net "M_B_CPU0_SB_DQ<28>")
	)
	(arc
		(start 332.103984 -292.228524)
		(mid 331.821028 -292.152347)
		(end 331.538072 -292.228524)
		(width 0.0889)
		(layer "In13.Cu")
		(net "M_B_CPU0_SB_DQ<28>")
	)
	(arc
		(start 331.52969 -292.23335)
		(mid 331.346182 -292.278844)
		(end 331.16393 -292.228524)
		(width 0.0889)
		(layer "In13.Cu")
		(net "M_B_CPU0_SB_DQ<28>")
	)
	(arc
		(start 328.344022 -292.228524)
		(mid 328.061066 -292.152347)
		(end 327.77811 -292.228524)
		(width 0.0889)
		(layer "In13.Cu")
		(net "M_B_CPU0_SB_DQ<28>")
	)
	(arc
		(start 330.22413 -292.228524)
		(mid 329.941174 -292.152347)
		(end 329.658218 -292.228524)
		(width 0.0889)
		(layer "In13.Cu")
		(net "M_B_CPU0_SB_DQ<28>")
	)
	(arc
		(start 326.357234 -294.664638)
		(mid 326.153971 -294.868133)
		(end 326.079612 -295.145968)
		(width 0.0889)
		(layer "In13.Cu")
		(net "M_B_CPU0_SB_DQ<28>")
	)
	(arc
		(start 329.658218 -292.228524)
		(mid 329.475967 -292.278874)
		(end 329.292458 -292.23335)
		(width 0.0889)
		(layer "In13.Cu")
		(net "M_B_CPU0_SB_DQ<28>")
	)
	(arc
		(start 327.025762 -293.525956)
		(mid 326.984507 -293.696927)
		(end 326.869806 -293.830248)
		(width 0.0889)
		(layer "In13.Cu")
		(net "M_B_CPU0_SB_DQ<28>")
	)
	(arc
		(start 326.80021 -293.87038)
		(mid 326.620481 -294.073)
		(end 326.555608 -294.335962)
		(width 0.0889)
		(layer "In13.Cu")
		(net "M_B_CPU0_SB_DQ<28>")
	)
	(segment
		(start 337.45805 -290.019994)
		(end 336.991198 -290.285932)
		(width 0.10668)
		(layer "F.Cu")
		(net "M_B_CPU0_SB_DQ<27>")
	)
	(segment
		(start 304.875184 -312.114692)
		(end 305.329844 -311.660032)
		(width 0.14478)
		(layer "In13.Cu")
		(net "M_B_CPU0_SB_DQ<27>")
	)
	(segment
		(start 307.89499 -311.660032)
		(end 320.801746 -298.753276)
		(width 0.14478)
		(layer "In13.Cu")
		(net "M_B_CPU0_SB_DQ<27>")
	)
	(segment
		(start 329.284076 -289.963352)
		(end 329.292458 -289.958526)
		(width 0.0889)
		(layer "In13.Cu")
		(net "M_B_CPU0_SB_DQ<27>")
	)
	(segment
		(start 337.145122 -290.020502)
		(end 336.991198 -290.285932)
		(width 0.0889)
		(layer "In13.Cu")
		(net "M_B_CPU0_SB_DQ<27>")
	)
	(segment
		(start 326.244458 -291.004498)
		(end 326.244458 -290.182554)
		(width 0.0889)
		(layer "In13.Cu")
		(net "M_B_CPU0_SB_DQ<27>")
	)
	(segment
		(start 305.329844 -311.660032)
		(end 307.89499 -311.660032)
		(width 0.14478)
		(layer "In13.Cu")
		(net "M_B_CPU0_SB_DQ<27>")
	)
	(segment
		(start 326.819514 -289.953192)
		(end 326.837802 -289.963606)
		(width 0.0889)
		(layer "In13.Cu")
		(net "M_B_CPU0_SB_DQ<27>")
	)
	(segment
		(start 320.801746 -298.753276)
		(end 320.801746 -297.542458)
		(width 0.14478)
		(layer "In13.Cu")
		(net "M_B_CPU0_SB_DQ<27>")
	)
	(segment
		(start 325.223124 -292.025832)
		(end 326.244458 -291.004498)
		(width 0.0889)
		(layer "In13.Cu")
		(net "M_B_CPU0_SB_DQ<27>")
	)
	(segment
		(start 326.837802 -289.963606)
		(end 326.84339 -289.966908)
		(width 0.0889)
		(layer "In13.Cu")
		(net "M_B_CPU0_SB_DQ<27>")
	)
	(segment
		(start 326.244458 -290.182554)
		(end 326.46366 -289.963352)
		(width 0.0889)
		(layer "In13.Cu")
		(net "M_B_CPU0_SB_DQ<27>")
	)
	(segment
		(start 320.801746 -297.542458)
		(end 323.901054 -294.44315)
		(width 0.14478)
		(layer "In13.Cu")
		(net "M_B_CPU0_SB_DQ<27>")
	)
	(segment
		(start 297.386502 -312.084974)
		(end 297.821096 -311.65038)
		(width 0.14478)
		(layer "In13.Cu")
		(net "M_B_CPU0_SB_DQ<27>")
	)
	(segment
		(start 299.257212 -312.114692)
		(end 304.875184 -312.114692)
		(width 0.14478)
		(layer "In13.Cu")
		(net "M_B_CPU0_SB_DQ<27>")
	)
	(segment
		(start 324.667118 -292.266878)
		(end 324.908164 -292.025832)
		(width 0.0889)
		(layer "In13.Cu")
		(net "M_B_CPU0_SB_DQ<27>")
	)
	(segment
		(start 297.821096 -311.65038)
		(end 298.7929 -311.65038)
		(width 0.14478)
		(layer "In13.Cu")
		(net "M_B_CPU0_SB_DQ<27>")
	)
	(segment
		(start 324.667118 -293.100252)
		(end 324.667118 -292.266878)
		(width 0.0889)
		(layer "In13.Cu")
		(net "M_B_CPU0_SB_DQ<27>")
	)
	(segment
		(start 331.52969 -289.958526)
		(end 331.538072 -289.963352)
		(width 0.0889)
		(layer "In13.Cu")
		(net "M_B_CPU0_SB_DQ<27>")
	)
	(segment
		(start 328.32929 -289.971988)
		(end 328.344022 -289.963352)
		(width 0.0889)
		(layer "In13.Cu")
		(net "M_B_CPU0_SB_DQ<27>")
	)
	(segment
		(start 327.403206 -289.963352)
		(end 327.41489 -289.956494)
		(width 0.0889)
		(layer "In13.Cu")
		(net "M_B_CPU0_SB_DQ<27>")
	)
	(segment
		(start 298.7929 -311.65038)
		(end 299.257212 -312.114692)
		(width 0.14478)
		(layer "In13.Cu")
		(net "M_B_CPU0_SB_DQ<27>")
	)
	(segment
		(start 324.108318 -294.235886)
		(end 324.108318 -293.659052)
		(width 0.0889)
		(layer "In13.Cu")
		(net "M_B_CPU0_SB_DQ<27>")
	)
	(segment
		(start 295.724072 -312.084974)
		(end 297.386502 -312.084974)
		(width 0.14478)
		(layer "In13.Cu")
		(net "M_B_CPU0_SB_DQ<27>")
	)
	(segment
		(start 337.12277 -289.93719)
		(end 337.145122 -290.020502)
		(width 0.0889)
		(layer "In13.Cu")
		(net "M_B_CPU0_SB_DQ<27>")
	)
	(segment
		(start 333.984092 -289.963352)
		(end 333.992474 -289.958526)
		(width 0.0889)
		(layer "In13.Cu")
		(net "M_B_CPU0_SB_DQ<27>")
	)
	(segment
		(start 324.108318 -293.659052)
		(end 324.667118 -293.100252)
		(width 0.0889)
		(layer "In13.Cu")
		(net "M_B_CPU0_SB_DQ<27>")
	)
	(segment
		(start 323.901054 -294.44315)
		(end 324.108318 -294.235886)
		(width 0.0889)
		(layer "In13.Cu")
		(net "M_B_CPU0_SB_DQ<27>")
	)
	(segment
		(start 333.044038 -289.963352)
		(end 333.05242 -289.958526)
		(width 0.0889)
		(layer "In13.Cu")
		(net "M_B_CPU0_SB_DQ<27>")
	)
	(segment
		(start 332.469744 -289.958526)
		(end 332.478126 -289.963352)
		(width 0.0889)
		(layer "In13.Cu")
		(net "M_B_CPU0_SB_DQ<27>")
	)
	(segment
		(start 336.229706 -289.958526)
		(end 336.238088 -289.963352)
		(width 0.0889)
		(layer "In13.Cu")
		(net "M_B_CPU0_SB_DQ<27>")
	)
	(segment
		(start 324.908164 -292.025832)
		(end 325.223124 -292.025832)
		(width 0.0889)
		(layer "In13.Cu")
		(net "M_B_CPU0_SB_DQ<27>")
	)
	(segment
		(start 328.709782 -289.958526)
		(end 328.718164 -289.963352)
		(width 0.0889)
		(layer "In13.Cu")
		(net "M_B_CPU0_SB_DQ<27>")
	)
	(arc
		(start 336.804 -289.963352)
		(mid 336.960438 -289.914381)
		(end 337.12277 -289.93719)
		(width 0.0889)
		(layer "In13.Cu")
		(net "M_B_CPU0_SB_DQ<27>")
	)
	(arc
		(start 328.344022 -289.963352)
		(mid 328.526273 -289.913002)
		(end 328.709782 -289.958526)
		(width 0.0889)
		(layer "In13.Cu")
		(net "M_B_CPU0_SB_DQ<27>")
	)
	(arc
		(start 335.863946 -289.963352)
		(mid 336.046197 -289.913002)
		(end 336.229706 -289.958526)
		(width 0.0889)
		(layer "In13.Cu")
		(net "M_B_CPU0_SB_DQ<27>")
	)
	(arc
		(start 333.05242 -289.958526)
		(mid 333.235928 -289.913032)
		(end 333.41818 -289.963352)
		(width 0.0889)
		(layer "In13.Cu")
		(net "M_B_CPU0_SB_DQ<27>")
	)
	(arc
		(start 334.358234 -289.963352)
		(mid 334.64119 -290.039529)
		(end 334.924146 -289.963352)
		(width 0.0889)
		(layer "In13.Cu")
		(net "M_B_CPU0_SB_DQ<27>")
	)
	(arc
		(start 330.598018 -289.963352)
		(mid 330.880974 -290.039529)
		(end 331.16393 -289.963352)
		(width 0.0889)
		(layer "In13.Cu")
		(net "M_B_CPU0_SB_DQ<27>")
	)
	(arc
		(start 334.924146 -289.963352)
		(mid 335.11109 -289.913097)
		(end 335.298034 -289.963352)
		(width 0.0889)
		(layer "In13.Cu")
		(net "M_B_CPU0_SB_DQ<27>")
	)
	(arc
		(start 335.298034 -289.963352)
		(mid 335.58099 -290.039529)
		(end 335.863946 -289.963352)
		(width 0.0889)
		(layer "In13.Cu")
		(net "M_B_CPU0_SB_DQ<27>")
	)
	(arc
		(start 326.84339 -289.966908)
		(mid 327.123779 -290.039577)
		(end 327.403206 -289.963352)
		(width 0.0889)
		(layer "In13.Cu")
		(net "M_B_CPU0_SB_DQ<27>")
	)
	(arc
		(start 329.292458 -289.958526)
		(mid 329.475966 -289.913032)
		(end 329.658218 -289.963352)
		(width 0.0889)
		(layer "In13.Cu")
		(net "M_B_CPU0_SB_DQ<27>")
	)
	(arc
		(start 333.992474 -289.958526)
		(mid 334.175982 -289.913032)
		(end 334.358234 -289.963352)
		(width 0.0889)
		(layer "In13.Cu")
		(net "M_B_CPU0_SB_DQ<27>")
	)
	(arc
		(start 329.658218 -289.963352)
		(mid 329.941174 -290.039529)
		(end 330.22413 -289.963352)
		(width 0.0889)
		(layer "In13.Cu")
		(net "M_B_CPU0_SB_DQ<27>")
	)
	(arc
		(start 332.103984 -289.963352)
		(mid 332.286235 -289.913002)
		(end 332.469744 -289.958526)
		(width 0.0889)
		(layer "In13.Cu")
		(net "M_B_CPU0_SB_DQ<27>")
	)
	(arc
		(start 336.238088 -289.963352)
		(mid 336.521044 -290.039529)
		(end 336.804 -289.963352)
		(width 0.0889)
		(layer "In13.Cu")
		(net "M_B_CPU0_SB_DQ<27>")
	)
	(arc
		(start 326.46366 -289.963352)
		(mid 326.640288 -289.913119)
		(end 326.819514 -289.953192)
		(width 0.0889)
		(layer "In13.Cu")
		(net "M_B_CPU0_SB_DQ<27>")
	)
	(arc
		(start 330.22413 -289.963352)
		(mid 330.411074 -289.913097)
		(end 330.598018 -289.963352)
		(width 0.0889)
		(layer "In13.Cu")
		(net "M_B_CPU0_SB_DQ<27>")
	)
	(arc
		(start 332.478126 -289.963352)
		(mid 332.761082 -290.039529)
		(end 333.044038 -289.963352)
		(width 0.0889)
		(layer "In13.Cu")
		(net "M_B_CPU0_SB_DQ<27>")
	)
	(arc
		(start 328.718164 -289.963352)
		(mid 329.00112 -290.039529)
		(end 329.284076 -289.963352)
		(width 0.0889)
		(layer "In13.Cu")
		(net "M_B_CPU0_SB_DQ<27>")
	)
	(arc
		(start 331.538072 -289.963352)
		(mid 331.821028 -290.039529)
		(end 332.103984 -289.963352)
		(width 0.0889)
		(layer "In13.Cu")
		(net "M_B_CPU0_SB_DQ<27>")
	)
	(arc
		(start 333.41818 -289.963352)
		(mid 333.701136 -290.039529)
		(end 333.984092 -289.963352)
		(width 0.0889)
		(layer "In13.Cu")
		(net "M_B_CPU0_SB_DQ<27>")
	)
	(arc
		(start 331.16393 -289.963352)
		(mid 331.346181 -289.913002)
		(end 331.52969 -289.958526)
		(width 0.0889)
		(layer "In13.Cu")
		(net "M_B_CPU0_SB_DQ<27>")
	)
	(arc
		(start 327.777602 -289.963352)
		(mid 328.052308 -290.039716)
		(end 328.32929 -289.971988)
		(width 0.0889)
		(layer "In13.Cu")
		(net "M_B_CPU0_SB_DQ<27>")
	)
	(arc
		(start 327.41489 -289.956494)
		(mid 327.597145 -289.912841)
		(end 327.777602 -289.963352)
		(width 0.0889)
		(layer "In13.Cu")
		(net "M_B_CPU0_SB_DQ<27>")
	)
	(segment
		(start 336.047842 -289.209988)
		(end 335.58099 -289.475926)
		(width 0.10668)
		(layer "F.Cu")
		(net "M_B_CPU0_SB_DQ<26>")
	)
	(segment
		(start 335.394046 -289.153346)
		(end 335.402428 -289.14852)
		(width 0.0889)
		(layer "In13.Cu")
		(net "M_B_CPU0_SB_DQ<26>")
	)
	(segment
		(start 295.724072 -310.384952)
		(end 297.800014 -310.384952)
		(width 0.14478)
		(layer "In13.Cu")
		(net "M_B_CPU0_SB_DQ<26>")
	)
	(segment
		(start 319.902586 -296.74185)
		(end 323.871336 -292.7731)
		(width 0.14478)
		(layer "In13.Cu")
		(net "M_B_CPU0_SB_DQ<26>")
	)
	(segment
		(start 333.879698 -289.14852)
		(end 333.88808 -289.153346)
		(width 0.0889)
		(layer "In13.Cu")
		(net "M_B_CPU0_SB_DQ<26>")
	)
	(segment
		(start 335.735168 -289.210496)
		(end 335.58099 -289.475926)
		(width 0.0889)
		(layer "In13.Cu")
		(net "M_B_CPU0_SB_DQ<26>")
	)
	(segment
		(start 304.893218 -310.810148)
		(end 305.743356 -309.96001)
		(width 0.14478)
		(layer "In13.Cu")
		(net "M_B_CPU0_SB_DQ<26>")
	)
	(segment
		(start 310.37403 -307.661056)
		(end 310.39562 -307.682646)
		(width 0.14478)
		(layer "In13.Cu")
		(net "M_B_CPU0_SB_DQ<26>")
	)
	(segment
		(start 311.5437 -306.286662)
		(end 311.728866 -306.101496)
		(width 0.14478)
		(layer "In13.Cu")
		(net "M_B_CPU0_SB_DQ<26>")
	)
	(segment
		(start 310.00573 -308.27726)
		(end 310.00573 -308.072536)
		(width 0.14478)
		(layer "In13.Cu")
		(net "M_B_CPU0_SB_DQ<26>")
	)
	(segment
		(start 330.69403 -289.153346)
		(end 330.702412 -289.14852)
		(width 0.0889)
		(layer "In13.Cu")
		(net "M_B_CPU0_SB_DQ<26>")
	)
	(segment
		(start 309.61584 -308.462426)
		(end 309.820564 -308.462426)
		(width 0.14478)
		(layer "In13.Cu")
		(net "M_B_CPU0_SB_DQ<26>")
	)
	(segment
		(start 330.119736 -289.14852)
		(end 330.128118 -289.153346)
		(width 0.0889)
		(layer "In13.Cu")
		(net "M_B_CPU0_SB_DQ<26>")
	)
	(segment
		(start 327.85939 -289.161982)
		(end 327.874122 -289.153346)
		(width 0.0889)
		(layer "In13.Cu")
		(net "M_B_CPU0_SB_DQ<26>")
	)
	(segment
		(start 311.380124 -306.902866)
		(end 311.56529 -306.7177)
		(width 0.14478)
		(layer "In13.Cu")
		(net "M_B_CPU0_SB_DQ<26>")
	)
	(segment
		(start 311.56529 -306.7177)
		(end 311.56529 -306.512976)
		(width 0.14478)
		(layer "In13.Cu")
		(net "M_B_CPU0_SB_DQ<26>")
	)
	(segment
		(start 333.88808 -289.153346)
		(end 333.888334 -289.153346)
		(width 0.0889)
		(layer "In13.Cu")
		(net "M_B_CPU0_SB_DQ<26>")
	)
	(segment
		(start 311.1754 -306.902866)
		(end 311.380124 -306.902866)
		(width 0.14478)
		(layer "In13.Cu")
		(net "M_B_CPU0_SB_DQ<26>")
	)
	(segment
		(start 312.159904 -306.123086)
		(end 319.902586 -298.380404)
		(width 0.14478)
		(layer "In13.Cu")
		(net "M_B_CPU0_SB_DQ<26>")
	)
	(segment
		(start 311.5437 -306.491386)
		(end 311.5437 -306.286662)
		(width 0.14478)
		(layer "In13.Cu")
		(net "M_B_CPU0_SB_DQ<26>")
	)
	(segment
		(start 325.121778 -291.367972)
		(end 325.558658 -290.931092)
		(width 0.0889)
		(layer "In13.Cu")
		(net "M_B_CPU0_SB_DQ<26>")
	)
	(segment
		(start 309.22595 -308.852316)
		(end 309.20436 -308.830726)
		(width 0.14478)
		(layer "In13.Cu")
		(net "M_B_CPU0_SB_DQ<26>")
	)
	(segment
		(start 310.00573 -308.072536)
		(end 309.98414 -308.050946)
		(width 0.14478)
		(layer "In13.Cu")
		(net "M_B_CPU0_SB_DQ<26>")
	)
	(segment
		(start 311.728866 -306.101496)
		(end 311.93359 -306.101496)
		(width 0.14478)
		(layer "In13.Cu")
		(net "M_B_CPU0_SB_DQ<26>")
	)
	(segment
		(start 309.98414 -307.846222)
		(end 310.169306 -307.661056)
		(width 0.14478)
		(layer "In13.Cu")
		(net "M_B_CPU0_SB_DQ<26>")
	)
	(segment
		(start 310.76392 -307.066442)
		(end 310.949086 -306.881276)
		(width 0.14478)
		(layer "In13.Cu")
		(net "M_B_CPU0_SB_DQ<26>")
	)
	(segment
		(start 311.15381 -306.881276)
		(end 311.1754 -306.902866)
		(width 0.14478)
		(layer "In13.Cu")
		(net "M_B_CPU0_SB_DQ<26>")
	)
	(segment
		(start 311.93359 -306.101496)
		(end 311.95518 -306.123086)
		(width 0.14478)
		(layer "In13.Cu")
		(net "M_B_CPU0_SB_DQ<26>")
	)
	(segment
		(start 310.949086 -306.881276)
		(end 311.15381 -306.881276)
		(width 0.14478)
		(layer "In13.Cu")
		(net "M_B_CPU0_SB_DQ<26>")
	)
	(segment
		(start 327.874122 -289.153346)
		(end 327.882504 -289.14852)
		(width 0.0889)
		(layer "In13.Cu")
		(net "M_B_CPU0_SB_DQ<26>")
	)
	(segment
		(start 326.193912 -289.229546)
		(end 326.651112 -289.229546)
		(width 0.0889)
		(layer "In13.Cu")
		(net "M_B_CPU0_SB_DQ<26>")
	)
	(segment
		(start 310.39562 -307.682646)
		(end 310.600344 -307.682646)
		(width 0.14478)
		(layer "In13.Cu")
		(net "M_B_CPU0_SB_DQ<26>")
	)
	(segment
		(start 301.35576 -309.96001)
		(end 302.205898 -310.810148)
		(width 0.14478)
		(layer "In13.Cu")
		(net "M_B_CPU0_SB_DQ<26>")
	)
	(segment
		(start 324.171818 -292.472618)
		(end 324.171818 -291.904166)
		(width 0.0889)
		(layer "In13.Cu")
		(net "M_B_CPU0_SB_DQ<26>")
	)
	(segment
		(start 309.20436 -308.626002)
		(end 309.389526 -308.440836)
		(width 0.14478)
		(layer "In13.Cu")
		(net "M_B_CPU0_SB_DQ<26>")
	)
	(segment
		(start 309.98414 -308.050946)
		(end 309.98414 -307.846222)
		(width 0.14478)
		(layer "In13.Cu")
		(net "M_B_CPU0_SB_DQ<26>")
	)
	(segment
		(start 310.78551 -307.49748)
		(end 310.78551 -307.292756)
		(width 0.14478)
		(layer "In13.Cu")
		(net "M_B_CPU0_SB_DQ<26>")
	)
	(segment
		(start 311.56529 -306.512976)
		(end 311.5437 -306.491386)
		(width 0.14478)
		(layer "In13.Cu")
		(net "M_B_CPU0_SB_DQ<26>")
	)
	(segment
		(start 305.743356 -309.96001)
		(end 308.32298 -309.96001)
		(width 0.14478)
		(layer "In13.Cu")
		(net "M_B_CPU0_SB_DQ<26>")
	)
	(segment
		(start 335.712816 -289.127184)
		(end 335.735168 -289.210496)
		(width 0.0889)
		(layer "In13.Cu")
		(net "M_B_CPU0_SB_DQ<26>")
	)
	(segment
		(start 309.22595 -309.05704)
		(end 309.22595 -308.852316)
		(width 0.14478)
		(layer "In13.Cu")
		(net "M_B_CPU0_SB_DQ<26>")
	)
	(segment
		(start 310.78551 -307.292756)
		(end 310.76392 -307.271166)
		(width 0.14478)
		(layer "In13.Cu")
		(net "M_B_CPU0_SB_DQ<26>")
	)
	(segment
		(start 309.59425 -308.440836)
		(end 309.61584 -308.462426)
		(width 0.14478)
		(layer "In13.Cu")
		(net "M_B_CPU0_SB_DQ<26>")
	)
	(segment
		(start 326.93356 -289.1536)
		(end 326.951848 -289.143186)
		(width 0.0889)
		(layer "In13.Cu")
		(net "M_B_CPU0_SB_DQ<26>")
	)
	(segment
		(start 309.389526 -308.440836)
		(end 309.59425 -308.440836)
		(width 0.14478)
		(layer "In13.Cu")
		(net "M_B_CPU0_SB_DQ<26>")
	)
	(segment
		(start 334.819752 -289.14852)
		(end 334.828134 -289.153346)
		(width 0.0889)
		(layer "In13.Cu")
		(net "M_B_CPU0_SB_DQ<26>")
	)
	(segment
		(start 302.205898 -310.810148)
		(end 304.893218 -310.810148)
		(width 0.14478)
		(layer "In13.Cu")
		(net "M_B_CPU0_SB_DQ<26>")
	)
	(segment
		(start 310.169306 -307.661056)
		(end 310.37403 -307.661056)
		(width 0.14478)
		(layer "In13.Cu")
		(net "M_B_CPU0_SB_DQ<26>")
	)
	(segment
		(start 324.171818 -291.904166)
		(end 324.708012 -291.367972)
		(width 0.0889)
		(layer "In13.Cu")
		(net "M_B_CPU0_SB_DQ<26>")
	)
	(segment
		(start 319.902586 -298.380404)
		(end 319.902586 -296.74185)
		(width 0.14478)
		(layer "In13.Cu")
		(net "M_B_CPU0_SB_DQ<26>")
	)
	(segment
		(start 297.800014 -310.384952)
		(end 298.224956 -309.96001)
		(width 0.14478)
		(layer "In13.Cu")
		(net "M_B_CPU0_SB_DQ<26>")
	)
	(segment
		(start 298.224956 -309.96001)
		(end 301.35576 -309.96001)
		(width 0.14478)
		(layer "In13.Cu")
		(net "M_B_CPU0_SB_DQ<26>")
	)
	(segment
		(start 310.76392 -307.271166)
		(end 310.76392 -307.066442)
		(width 0.14478)
		(layer "In13.Cu")
		(net "M_B_CPU0_SB_DQ<26>")
	)
	(segment
		(start 325.558658 -290.931092)
		(end 325.558658 -289.8648)
		(width 0.0889)
		(layer "In13.Cu")
		(net "M_B_CPU0_SB_DQ<26>")
	)
	(segment
		(start 309.820564 -308.462426)
		(end 310.00573 -308.27726)
		(width 0.14478)
		(layer "In13.Cu")
		(net "M_B_CPU0_SB_DQ<26>")
	)
	(segment
		(start 325.558658 -289.8648)
		(end 326.193912 -289.229546)
		(width 0.0889)
		(layer "In13.Cu")
		(net "M_B_CPU0_SB_DQ<26>")
	)
	(segment
		(start 309.20436 -308.830726)
		(end 309.20436 -308.626002)
		(width 0.14478)
		(layer "In13.Cu")
		(net "M_B_CPU0_SB_DQ<26>")
	)
	(segment
		(start 324.708012 -291.367972)
		(end 325.121778 -291.367972)
		(width 0.0889)
		(layer "In13.Cu")
		(net "M_B_CPU0_SB_DQ<26>")
	)
	(segment
		(start 308.32298 -309.96001)
		(end 309.22595 -309.05704)
		(width 0.14478)
		(layer "In13.Cu")
		(net "M_B_CPU0_SB_DQ<26>")
	)
	(segment
		(start 310.600344 -307.682646)
		(end 310.78551 -307.49748)
		(width 0.14478)
		(layer "In13.Cu")
		(net "M_B_CPU0_SB_DQ<26>")
	)
	(segment
		(start 311.95518 -306.123086)
		(end 312.159904 -306.123086)
		(width 0.14478)
		(layer "In13.Cu")
		(net "M_B_CPU0_SB_DQ<26>")
	)
	(segment
		(start 323.871336 -292.7731)
		(end 324.171818 -292.472618)
		(width 0.0889)
		(layer "In13.Cu")
		(net "M_B_CPU0_SB_DQ<26>")
	)
	(segment
		(start 331.634084 -289.153346)
		(end 331.642466 -289.14852)
		(width 0.0889)
		(layer "In13.Cu")
		(net "M_B_CPU0_SB_DQ<26>")
	)
	(arc
		(start 334.828134 -289.153346)
		(mid 335.11109 -289.229523)
		(end 335.394046 -289.153346)
		(width 0.0889)
		(layer "In13.Cu")
		(net "M_B_CPU0_SB_DQ<26>")
	)
	(arc
		(start 332.574138 -289.153346)
		(mid 332.761082 -289.103091)
		(end 332.948026 -289.153346)
		(width 0.0889)
		(layer "In13.Cu")
		(net "M_B_CPU0_SB_DQ<26>")
	)
	(arc
		(start 333.888334 -289.153346)
		(mid 334.17118 -289.229523)
		(end 334.453992 -289.153346)
		(width 0.0889)
		(layer "In13.Cu")
		(net "M_B_CPU0_SB_DQ<26>")
	)
	(arc
		(start 327.307702 -289.153346)
		(mid 327.582408 -289.22971)
		(end 327.85939 -289.161982)
		(width 0.0889)
		(layer "In13.Cu")
		(net "M_B_CPU0_SB_DQ<26>")
	)
	(arc
		(start 328.814176 -289.153346)
		(mid 329.00112 -289.103091)
		(end 329.188064 -289.153346)
		(width 0.0889)
		(layer "In13.Cu")
		(net "M_B_CPU0_SB_DQ<26>")
	)
	(arc
		(start 331.642466 -289.14852)
		(mid 331.825974 -289.103026)
		(end 332.008226 -289.153346)
		(width 0.0889)
		(layer "In13.Cu")
		(net "M_B_CPU0_SB_DQ<26>")
	)
	(arc
		(start 332.948026 -289.153346)
		(mid 333.230982 -289.229523)
		(end 333.513938 -289.153346)
		(width 0.0889)
		(layer "In13.Cu")
		(net "M_B_CPU0_SB_DQ<26>")
	)
	(arc
		(start 332.008226 -289.153346)
		(mid 332.291182 -289.229523)
		(end 332.574138 -289.153346)
		(width 0.0889)
		(layer "In13.Cu")
		(net "M_B_CPU0_SB_DQ<26>")
	)
	(arc
		(start 330.128118 -289.153346)
		(mid 330.411074 -289.229523)
		(end 330.69403 -289.153346)
		(width 0.0889)
		(layer "In13.Cu")
		(net "M_B_CPU0_SB_DQ<26>")
	)
	(arc
		(start 328.248264 -289.153346)
		(mid 328.53122 -289.229523)
		(end 328.814176 -289.153346)
		(width 0.0889)
		(layer "In13.Cu")
		(net "M_B_CPU0_SB_DQ<26>")
	)
	(arc
		(start 331.068172 -289.153346)
		(mid 331.351128 -289.229523)
		(end 331.634084 -289.153346)
		(width 0.0889)
		(layer "In13.Cu")
		(net "M_B_CPU0_SB_DQ<26>")
	)
	(arc
		(start 334.453992 -289.153346)
		(mid 334.636243 -289.102996)
		(end 334.819752 -289.14852)
		(width 0.0889)
		(layer "In13.Cu")
		(net "M_B_CPU0_SB_DQ<26>")
	)
	(arc
		(start 333.513938 -289.153346)
		(mid 333.696189 -289.102996)
		(end 333.879698 -289.14852)
		(width 0.0889)
		(layer "In13.Cu")
		(net "M_B_CPU0_SB_DQ<26>")
	)
	(arc
		(start 327.882504 -289.14852)
		(mid 328.066012 -289.103026)
		(end 328.248264 -289.153346)
		(width 0.0889)
		(layer "In13.Cu")
		(net "M_B_CPU0_SB_DQ<26>")
	)
	(arc
		(start 326.951848 -289.143186)
		(mid 327.131077 -289.103033)
		(end 327.307702 -289.153346)
		(width 0.0889)
		(layer "In13.Cu")
		(net "M_B_CPU0_SB_DQ<26>")
	)
	(arc
		(start 335.402428 -289.14852)
		(mid 335.555298 -289.103879)
		(end 335.712816 -289.127184)
		(width 0.0889)
		(layer "In13.Cu")
		(net "M_B_CPU0_SB_DQ<26>")
	)
	(arc
		(start 330.702412 -289.14852)
		(mid 330.88592 -289.103026)
		(end 331.068172 -289.153346)
		(width 0.0889)
		(layer "In13.Cu")
		(net "M_B_CPU0_SB_DQ<26>")
	)
	(arc
		(start 326.651112 -289.229546)
		(mid 326.79736 -289.210241)
		(end 326.93356 -289.1536)
		(width 0.0889)
		(layer "In13.Cu")
		(net "M_B_CPU0_SB_DQ<26>")
	)
	(arc
		(start 329.188064 -289.153346)
		(mid 329.47102 -289.229523)
		(end 329.753976 -289.153346)
		(width 0.0889)
		(layer "In13.Cu")
		(net "M_B_CPU0_SB_DQ<26>")
	)
	(arc
		(start 329.753976 -289.153346)
		(mid 329.936227 -289.102996)
		(end 330.119736 -289.14852)
		(width 0.0889)
		(layer "In13.Cu")
		(net "M_B_CPU0_SB_DQ<26>")
	)
	(segment
		(start 337.92795 -289.209988)
		(end 337.461098 -289.475926)
		(width 0.10668)
		(layer "F.Cu")
		(net "M_B_CPU0_SB_DQ<25>")
	)
	(segment
		(start 320.352166 -298.56684)
		(end 320.352166 -296.935906)
		(width 0.14478)
		(layer "In13.Cu")
		(net "M_B_CPU0_SB_DQ<25>")
	)
	(segment
		(start 323.684138 -293.814246)
		(end 323.681344 -293.811452)
		(width 0.14478)
		(layer "In13.Cu")
		(net "M_B_CPU0_SB_DQ<25>")
	)
	(segment
		(start 323.08673 -294.201342)
		(end 323.291454 -294.201088)
		(width 0.14478)
		(layer "In13.Cu")
		(net "M_B_CPU0_SB_DQ<25>")
	)
	(segment
		(start 327.307194 -289.798506)
		(end 327.321926 -289.78987)
		(width 0.0889)
		(layer "In13.Cu")
		(net "M_B_CPU0_SB_DQ<25>")
	)
	(segment
		(start 322.901564 -294.386508)
		(end 323.08673 -294.201342)
		(width 0.14478)
		(layer "In13.Cu")
		(net "M_B_CPU0_SB_DQ<25>")
	)
	(segment
		(start 320.952114 -296.540428)
		(end 320.954908 -296.543222)
		(width 0.14478)
		(layer "In13.Cu")
		(net "M_B_CPU0_SB_DQ<25>")
	)
	(segment
		(start 306.067206 -310.809894)
		(end 306.211986 -310.954674)
		(width 0.14478)
		(layer "In13.Cu")
		(net "M_B_CPU0_SB_DQ<25>")
	)
	(segment
		(start 306.356766 -311.165494)
		(end 306.618386 -311.165494)
		(width 0.14478)
		(layer "In13.Cu")
		(net "M_B_CPU0_SB_DQ<25>")
	)
	(segment
		(start 331.634084 -289.798506)
		(end 331.642466 -289.803332)
		(width 0.0889)
		(layer "In13.Cu")
		(net "M_B_CPU0_SB_DQ<25>")
	)
	(segment
		(start 321.345052 -296.357802)
		(end 321.344798 -296.153586)
		(width 0.14478)
		(layer "In13.Cu")
		(net "M_B_CPU0_SB_DQ<25>")
	)
	(segment
		(start 308.109112 -310.809894)
		(end 320.352166 -298.56684)
		(width 0.14478)
		(layer "In13.Cu")
		(net "M_B_CPU0_SB_DQ<25>")
	)
	(segment
		(start 333.88808 -289.798506)
		(end 333.888334 -289.798506)
		(width 0.0889)
		(layer "In13.Cu")
		(net "M_B_CPU0_SB_DQ<25>")
	)
	(segment
		(start 306.763166 -310.954674)
		(end 306.907946 -310.809894)
		(width 0.14478)
		(layer "In13.Cu")
		(net "M_B_CPU0_SB_DQ<25>")
	)
	(segment
		(start 322.719192 -294.983662)
		(end 322.904612 -294.798242)
		(width 0.14478)
		(layer "In13.Cu")
		(net "M_B_CPU0_SB_DQ<25>")
	)
	(segment
		(start 306.211986 -310.954674)
		(end 306.211986 -311.020714)
		(width 0.14478)
		(layer "In13.Cu")
		(net "M_B_CPU0_SB_DQ<25>")
	)
	(segment
		(start 324.362318 -292.135052)
		(end 324.806818 -291.690552)
		(width 0.0889)
		(layer "In13.Cu")
		(net "M_B_CPU0_SB_DQ<25>")
	)
	(segment
		(start 302.468026 -311.439052)
		(end 302.689006 -311.660032)
		(width 0.14478)
		(layer "In13.Cu")
		(net "M_B_CPU0_SB_DQ<25>")
	)
	(segment
		(start 323.681344 -293.811452)
		(end 323.681344 -293.606728)
		(width 0.14478)
		(layer "In13.Cu")
		(net "M_B_CPU0_SB_DQ<25>")
	)
	(segment
		(start 321.159632 -296.543222)
		(end 321.345052 -296.357802)
		(width 0.14478)
		(layer "In13.Cu")
		(net "M_B_CPU0_SB_DQ<25>")
	)
	(segment
		(start 325.159878 -291.690552)
		(end 325.911718 -290.938712)
		(width 0.0889)
		(layer "In13.Cu")
		(net "M_B_CPU0_SB_DQ<25>")
	)
	(segment
		(start 300.63313 -311.495694)
		(end 300.778164 -311.35066)
		(width 0.14478)
		(layer "In13.Cu")
		(net "M_B_CPU0_SB_DQ<25>")
	)
	(segment
		(start 301.79645 -311.629552)
		(end 301.98695 -311.439052)
		(width 0.14478)
		(layer "In13.Cu")
		(net "M_B_CPU0_SB_DQ<25>")
	)
	(segment
		(start 336.3341 -289.798506)
		(end 336.342482 -289.803332)
		(width 0.0889)
		(layer "In13.Cu")
		(net "M_B_CPU0_SB_DQ<25>")
	)
	(segment
		(start 330.119736 -289.803332)
		(end 330.128118 -289.798506)
		(width 0.0889)
		(layer "In13.Cu")
		(net "M_B_CPU0_SB_DQ<25>")
	)
	(segment
		(start 301.59706 -310.844438)
		(end 301.59706 -311.049162)
		(width 0.14478)
		(layer "In13.Cu")
		(net "M_B_CPU0_SB_DQ<25>")
	)
	(segment
		(start 304.686462 -311.660032)
		(end 305.5366 -310.809894)
		(width 0.14478)
		(layer "In13.Cu")
		(net "M_B_CPU0_SB_DQ<25>")
	)
	(segment
		(start 323.291454 -294.201088)
		(end 323.294248 -294.203882)
		(width 0.14478)
		(layer "In13.Cu")
		(net "M_B_CPU0_SB_DQ<25>")
	)
	(segment
		(start 322.121784 -295.166288)
		(end 322.30695 -294.981122)
		(width 0.14478)
		(layer "In13.Cu")
		(net "M_B_CPU0_SB_DQ<25>")
	)
	(segment
		(start 322.514468 -294.983662)
		(end 322.719192 -294.983662)
		(width 0.14478)
		(layer "In13.Cu")
		(net "M_B_CPU0_SB_DQ<25>")
	)
	(segment
		(start 308.010306 -310.809894)
		(end 308.109112 -310.809894)
		(width 0.14478)
		(layer "In13.Cu")
		(net "M_B_CPU0_SB_DQ<25>")
	)
	(segment
		(start 324.362318 -292.925754)
		(end 324.362318 -292.135052)
		(width 0.0889)
		(layer "In13.Cu")
		(net "M_B_CPU0_SB_DQ<25>")
	)
	(segment
		(start 322.124832 -295.578022)
		(end 322.124578 -295.373806)
		(width 0.14478)
		(layer "In13.Cu")
		(net "M_B_CPU0_SB_DQ<25>")
	)
	(segment
		(start 301.59706 -311.049162)
		(end 301.40656 -311.239662)
		(width 0.14478)
		(layer "In13.Cu")
		(net "M_B_CPU0_SB_DQ<25>")
	)
	(segment
		(start 323.498972 -294.203882)
		(end 323.684392 -294.018462)
		(width 0.14478)
		(layer "In13.Cu")
		(net "M_B_CPU0_SB_DQ<25>")
	)
	(segment
		(start 321.734688 -295.763442)
		(end 321.939412 -295.763442)
		(width 0.14478)
		(layer "In13.Cu")
		(net "M_B_CPU0_SB_DQ<25>")
	)
	(segment
		(start 337.307174 -289.741356)
		(end 337.461098 -289.475926)
		(width 0.0889)
		(layer "In13.Cu")
		(net "M_B_CPU0_SB_DQ<25>")
	)
	(segment
		(start 300.778164 -311.35066)
		(end 300.778164 -310.590692)
		(width 0.14478)
		(layer "In13.Cu")
		(net "M_B_CPU0_SB_DQ<25>")
	)
	(segment
		(start 307.314346 -310.954674)
		(end 307.314346 -311.020714)
		(width 0.14478)
		(layer "In13.Cu")
		(net "M_B_CPU0_SB_DQ<25>")
	)
	(segment
		(start 322.30695 -294.981122)
		(end 322.511674 -294.980868)
		(width 0.14478)
		(layer "In13.Cu")
		(net "M_B_CPU0_SB_DQ<25>")
	)
	(segment
		(start 325.911718 -290.938712)
		(end 325.911718 -290.147502)
		(width 0.0889)
		(layer "In13.Cu")
		(net "M_B_CPU0_SB_DQ<25>")
	)
	(segment
		(start 299.984668 -311.495694)
		(end 300.63313 -311.495694)
		(width 0.14478)
		(layer "In13.Cu")
		(net "M_B_CPU0_SB_DQ<25>")
	)
	(segment
		(start 323.875908 -293.412164)
		(end 324.362318 -292.925754)
		(width 0.0889)
		(layer "In13.Cu")
		(net "M_B_CPU0_SB_DQ<25>")
	)
	(segment
		(start 325.911718 -290.147502)
		(end 326.112124 -289.947096)
		(width 0.0889)
		(layer "In13.Cu")
		(net "M_B_CPU0_SB_DQ<25>")
	)
	(segment
		(start 301.98695 -311.439052)
		(end 302.468026 -311.439052)
		(width 0.14478)
		(layer "In13.Cu")
		(net "M_B_CPU0_SB_DQ<25>")
	)
	(segment
		(start 326.112124 -289.947096)
		(end 326.367648 -289.798506)
		(width 0.0889)
		(layer "In13.Cu")
		(net "M_B_CPU0_SB_DQ<25>")
	)
	(segment
		(start 299.82414 -311.23509)
		(end 299.82414 -311.335166)
		(width 0.14478)
		(layer "In13.Cu")
		(net "M_B_CPU0_SB_DQ<25>")
	)
	(segment
		(start 333.879698 -289.803332)
		(end 333.88808 -289.798506)
		(width 0.0889)
		(layer "In13.Cu")
		(net "M_B_CPU0_SB_DQ<25>")
	)
	(segment
		(start 301.591726 -311.629552)
		(end 301.79645 -311.629552)
		(width 0.14478)
		(layer "In13.Cu")
		(net "M_B_CPU0_SB_DQ<25>")
	)
	(segment
		(start 302.689006 -311.660032)
		(end 304.686462 -311.660032)
		(width 0.14478)
		(layer "In13.Cu")
		(net "M_B_CPU0_SB_DQ<25>")
	)
	(segment
		(start 320.74739 -296.540682)
		(end 320.952114 -296.540428)
		(width 0.14478)
		(layer "In13.Cu")
		(net "M_B_CPU0_SB_DQ<25>")
	)
	(segment
		(start 320.352166 -296.935906)
		(end 320.74739 -296.540682)
		(width 0.14478)
		(layer "In13.Cu")
		(net "M_B_CPU0_SB_DQ<25>")
	)
	(segment
		(start 330.69403 -289.798506)
		(end 330.702412 -289.803332)
		(width 0.0889)
		(layer "In13.Cu")
		(net "M_B_CPU0_SB_DQ<25>")
	)
	(segment
		(start 321.731894 -295.760648)
		(end 321.734688 -295.763442)
		(width 0.14478)
		(layer "In13.Cu")
		(net "M_B_CPU0_SB_DQ<25>")
	)
	(segment
		(start 322.124578 -295.373806)
		(end 322.121784 -295.371012)
		(width 0.14478)
		(layer "In13.Cu")
		(net "M_B_CPU0_SB_DQ<25>")
	)
	(segment
		(start 307.459126 -311.165494)
		(end 307.720746 -311.165494)
		(width 0.14478)
		(layer "In13.Cu")
		(net "M_B_CPU0_SB_DQ<25>")
	)
	(segment
		(start 328.239882 -289.803332)
		(end 328.248264 -289.798506)
		(width 0.0889)
		(layer "In13.Cu")
		(net "M_B_CPU0_SB_DQ<25>")
	)
	(segment
		(start 320.954908 -296.543222)
		(end 321.159632 -296.543222)
		(width 0.14478)
		(layer "In13.Cu")
		(net "M_B_CPU0_SB_DQ<25>")
	)
	(segment
		(start 307.865526 -311.020714)
		(end 307.865526 -310.954674)
		(width 0.14478)
		(layer "In13.Cu")
		(net "M_B_CPU0_SB_DQ<25>")
	)
	(segment
		(start 307.169566 -310.809894)
		(end 307.314346 -310.954674)
		(width 0.14478)
		(layer "In13.Cu")
		(net "M_B_CPU0_SB_DQ<25>")
	)
	(segment
		(start 321.52717 -295.760902)
		(end 321.731894 -295.760648)
		(width 0.14478)
		(layer "In13.Cu")
		(net "M_B_CPU0_SB_DQ<25>")
	)
	(segment
		(start 322.901564 -294.591232)
		(end 322.901564 -294.386508)
		(width 0.14478)
		(layer "In13.Cu")
		(net "M_B_CPU0_SB_DQ<25>")
	)
	(segment
		(start 306.618386 -311.165494)
		(end 306.763166 -311.020714)
		(width 0.14478)
		(layer "In13.Cu")
		(net "M_B_CPU0_SB_DQ<25>")
	)
	(segment
		(start 324.806818 -291.690552)
		(end 325.159878 -291.690552)
		(width 0.0889)
		(layer "In13.Cu")
		(net "M_B_CPU0_SB_DQ<25>")
	)
	(segment
		(start 321.342004 -295.946068)
		(end 321.52717 -295.760902)
		(width 0.14478)
		(layer "In13.Cu")
		(net "M_B_CPU0_SB_DQ<25>")
	)
	(segment
		(start 299.82414 -311.335166)
		(end 299.984668 -311.495694)
		(width 0.14478)
		(layer "In13.Cu")
		(net "M_B_CPU0_SB_DQ<25>")
	)
	(segment
		(start 321.342004 -296.150792)
		(end 321.342004 -295.946068)
		(width 0.14478)
		(layer "In13.Cu")
		(net "M_B_CPU0_SB_DQ<25>")
	)
	(segment
		(start 337.211162 -289.766756)
		(end 337.307174 -289.741356)
		(width 0.0889)
		(layer "In13.Cu")
		(net "M_B_CPU0_SB_DQ<25>")
	)
	(segment
		(start 322.904358 -294.594026)
		(end 322.901564 -294.591232)
		(width 0.14478)
		(layer "In13.Cu")
		(net "M_B_CPU0_SB_DQ<25>")
	)
	(segment
		(start 322.121784 -295.371012)
		(end 322.121784 -295.166288)
		(width 0.14478)
		(layer "In13.Cu")
		(net "M_B_CPU0_SB_DQ<25>")
	)
	(segment
		(start 301.1805 -310.427878)
		(end 301.59706 -310.844438)
		(width 0.14478)
		(layer "In13.Cu")
		(net "M_B_CPU0_SB_DQ<25>")
	)
	(segment
		(start 301.40656 -311.444386)
		(end 301.591726 -311.629552)
		(width 0.14478)
		(layer "In13.Cu")
		(net "M_B_CPU0_SB_DQ<25>")
	)
	(segment
		(start 307.314346 -311.020714)
		(end 307.459126 -311.165494)
		(width 0.14478)
		(layer "In13.Cu")
		(net "M_B_CPU0_SB_DQ<25>")
	)
	(segment
		(start 322.511674 -294.980868)
		(end 322.514468 -294.983662)
		(width 0.14478)
		(layer "In13.Cu")
		(net "M_B_CPU0_SB_DQ<25>")
	)
	(segment
		(start 334.819752 -289.803332)
		(end 334.828134 -289.798506)
		(width 0.0889)
		(layer "In13.Cu")
		(net "M_B_CPU0_SB_DQ<25>")
	)
	(segment
		(start 335.394046 -289.798506)
		(end 335.402428 -289.803332)
		(width 0.0889)
		(layer "In13.Cu")
		(net "M_B_CPU0_SB_DQ<25>")
	)
	(segment
		(start 306.763166 -311.020714)
		(end 306.763166 -310.954674)
		(width 0.14478)
		(layer "In13.Cu")
		(net "M_B_CPU0_SB_DQ<25>")
	)
	(segment
		(start 301.40656 -311.239662)
		(end 301.40656 -311.444386)
		(width 0.14478)
		(layer "In13.Cu")
		(net "M_B_CPU0_SB_DQ<25>")
	)
	(segment
		(start 323.681344 -293.606728)
		(end 323.875908 -293.412164)
		(width 0.14478)
		(layer "In13.Cu")
		(net "M_B_CPU0_SB_DQ<25>")
	)
	(segment
		(start 307.720746 -311.165494)
		(end 307.865526 -311.020714)
		(width 0.14478)
		(layer "In13.Cu")
		(net "M_B_CPU0_SB_DQ<25>")
	)
	(segment
		(start 322.904612 -294.798242)
		(end 322.904358 -294.594026)
		(width 0.14478)
		(layer "In13.Cu")
		(net "M_B_CPU0_SB_DQ<25>")
	)
	(segment
		(start 307.865526 -310.954674)
		(end 308.010306 -310.809894)
		(width 0.14478)
		(layer "In13.Cu")
		(net "M_B_CPU0_SB_DQ<25>")
	)
	(segment
		(start 305.5366 -310.809894)
		(end 306.067206 -310.809894)
		(width 0.14478)
		(layer "In13.Cu")
		(net "M_B_CPU0_SB_DQ<25>")
	)
	(segment
		(start 300.940978 -310.427878)
		(end 301.1805 -310.427878)
		(width 0.14478)
		(layer "In13.Cu")
		(net "M_B_CPU0_SB_DQ<25>")
	)
	(segment
		(start 300.778164 -310.590692)
		(end 300.940978 -310.427878)
		(width 0.14478)
		(layer "In13.Cu")
		(net "M_B_CPU0_SB_DQ<25>")
	)
	(segment
		(start 306.211986 -311.020714)
		(end 306.356766 -311.165494)
		(width 0.14478)
		(layer "In13.Cu")
		(net "M_B_CPU0_SB_DQ<25>")
	)
	(segment
		(start 326.917812 -289.789108)
		(end 326.93356 -289.798252)
		(width 0.0889)
		(layer "In13.Cu")
		(net "M_B_CPU0_SB_DQ<25>")
	)
	(segment
		(start 323.294248 -294.203882)
		(end 323.498972 -294.203882)
		(width 0.14478)
		(layer "In13.Cu")
		(net "M_B_CPU0_SB_DQ<25>")
	)
	(segment
		(start 321.344798 -296.153586)
		(end 321.342004 -296.150792)
		(width 0.14478)
		(layer "In13.Cu")
		(net "M_B_CPU0_SB_DQ<25>")
	)
	(segment
		(start 323.684392 -294.018462)
		(end 323.684138 -293.814246)
		(width 0.14478)
		(layer "In13.Cu")
		(net "M_B_CPU0_SB_DQ<25>")
	)
	(segment
		(start 306.907946 -310.809894)
		(end 307.169566 -310.809894)
		(width 0.14478)
		(layer "In13.Cu")
		(net "M_B_CPU0_SB_DQ<25>")
	)
	(segment
		(start 321.939412 -295.763442)
		(end 322.124832 -295.578022)
		(width 0.14478)
		(layer "In13.Cu")
		(net "M_B_CPU0_SB_DQ<25>")
	)
	(segment
		(start 326.93356 -289.798252)
		(end 326.947276 -289.806126)
		(width 0.0889)
		(layer "In13.Cu")
		(net "M_B_CPU0_SB_DQ<25>")
	)
	(arc
		(start 333.513938 -289.798506)
		(mid 333.696189 -289.848856)
		(end 333.879698 -289.803332)
		(width 0.0889)
		(layer "In13.Cu")
		(net "M_B_CPU0_SB_DQ<25>")
	)
	(arc
		(start 331.642466 -289.803332)
		(mid 331.825974 -289.848826)
		(end 332.008226 -289.798506)
		(width 0.0889)
		(layer "In13.Cu")
		(net "M_B_CPU0_SB_DQ<25>")
	)
	(arc
		(start 336.708242 -289.798506)
		(mid 336.955955 -289.723286)
		(end 337.211162 -289.766756)
		(width 0.0889)
		(layer "In13.Cu")
		(net "M_B_CPU0_SB_DQ<25>")
	)
	(arc
		(start 326.947276 -289.806126)
		(mid 327.128206 -289.848604)
		(end 327.307194 -289.798506)
		(width 0.0889)
		(layer "In13.Cu")
		(net "M_B_CPU0_SB_DQ<25>")
	)
	(arc
		(start 332.008226 -289.798506)
		(mid 332.291182 -289.722329)
		(end 332.574138 -289.798506)
		(width 0.0889)
		(layer "In13.Cu")
		(net "M_B_CPU0_SB_DQ<25>")
	)
	(arc
		(start 327.321926 -289.78987)
		(mid 327.598909 -289.722066)
		(end 327.873614 -289.798506)
		(width 0.0889)
		(layer "In13.Cu")
		(net "M_B_CPU0_SB_DQ<25>")
	)
	(arc
		(start 334.828134 -289.798506)
		(mid 335.11109 -289.722329)
		(end 335.394046 -289.798506)
		(width 0.0889)
		(layer "In13.Cu")
		(net "M_B_CPU0_SB_DQ<25>")
	)
	(arc
		(start 327.873614 -289.798506)
		(mid 328.056119 -289.848983)
		(end 328.239882 -289.803332)
		(width 0.0889)
		(layer "In13.Cu")
		(net "M_B_CPU0_SB_DQ<25>")
	)
	(arc
		(start 331.068172 -289.798506)
		(mid 331.351128 -289.722329)
		(end 331.634084 -289.798506)
		(width 0.0889)
		(layer "In13.Cu")
		(net "M_B_CPU0_SB_DQ<25>")
	)
	(arc
		(start 328.814176 -289.798506)
		(mid 329.00112 -289.848761)
		(end 329.188064 -289.798506)
		(width 0.0889)
		(layer "In13.Cu")
		(net "M_B_CPU0_SB_DQ<25>")
	)
	(arc
		(start 329.753976 -289.798506)
		(mid 329.936227 -289.848856)
		(end 330.119736 -289.803332)
		(width 0.0889)
		(layer "In13.Cu")
		(net "M_B_CPU0_SB_DQ<25>")
	)
	(arc
		(start 332.948026 -289.798506)
		(mid 333.230982 -289.722329)
		(end 333.513938 -289.798506)
		(width 0.0889)
		(layer "In13.Cu")
		(net "M_B_CPU0_SB_DQ<25>")
	)
	(arc
		(start 326.367648 -289.798506)
		(mid 326.641503 -289.722156)
		(end 326.917812 -289.789108)
		(width 0.0889)
		(layer "In13.Cu")
		(net "M_B_CPU0_SB_DQ<25>")
	)
	(arc
		(start 336.342482 -289.803332)
		(mid 336.52599 -289.848826)
		(end 336.708242 -289.798506)
		(width 0.0889)
		(layer "In13.Cu")
		(net "M_B_CPU0_SB_DQ<25>")
	)
	(arc
		(start 330.128118 -289.798506)
		(mid 330.411074 -289.722329)
		(end 330.69403 -289.798506)
		(width 0.0889)
		(layer "In13.Cu")
		(net "M_B_CPU0_SB_DQ<25>")
	)
	(arc
		(start 329.188064 -289.798506)
		(mid 329.47102 -289.722329)
		(end 329.753976 -289.798506)
		(width 0.0889)
		(layer "In13.Cu")
		(net "M_B_CPU0_SB_DQ<25>")
	)
	(arc
		(start 330.702412 -289.803332)
		(mid 330.88592 -289.848826)
		(end 331.068172 -289.798506)
		(width 0.0889)
		(layer "In13.Cu")
		(net "M_B_CPU0_SB_DQ<25>")
	)
	(arc
		(start 335.402428 -289.803332)
		(mid 335.585936 -289.848826)
		(end 335.768188 -289.798506)
		(width 0.0889)
		(layer "In13.Cu")
		(net "M_B_CPU0_SB_DQ<25>")
	)
	(arc
		(start 333.888334 -289.798506)
		(mid 334.17118 -289.722329)
		(end 334.453992 -289.798506)
		(width 0.0889)
		(layer "In13.Cu")
		(net "M_B_CPU0_SB_DQ<25>")
	)
	(arc
		(start 332.574138 -289.798506)
		(mid 332.761082 -289.848761)
		(end 332.948026 -289.798506)
		(width 0.0889)
		(layer "In13.Cu")
		(net "M_B_CPU0_SB_DQ<25>")
	)
	(arc
		(start 328.248264 -289.798506)
		(mid 328.53122 -289.722329)
		(end 328.814176 -289.798506)
		(width 0.0889)
		(layer "In13.Cu")
		(net "M_B_CPU0_SB_DQ<25>")
	)
	(arc
		(start 334.453992 -289.798506)
		(mid 334.636243 -289.848856)
		(end 334.819752 -289.803332)
		(width 0.0889)
		(layer "In13.Cu")
		(net "M_B_CPU0_SB_DQ<25>")
	)
	(arc
		(start 335.768188 -289.798506)
		(mid 336.051144 -289.722329)
		(end 336.3341 -289.798506)
		(width 0.0889)
		(layer "In13.Cu")
		(net "M_B_CPU0_SB_DQ<25>")
	)
	(segment
		(start 336.517996 -288.399982)
		(end 336.051144 -288.66592)
		(width 0.10668)
		(layer "F.Cu")
		(net "M_B_CPU0_SB_DQ<24>")
	)
	(segment
		(start 314.441586 -302.691038)
		(end 314.25642 -302.876204)
		(width 0.14478)
		(layer "In13.Cu")
		(net "M_B_CPU0_SB_DQ<24>")
	)
	(segment
		(start 331.538072 -288.9885)
		(end 331.52969 -288.993326)
		(width 0.0889)
		(layer "In13.Cu")
		(net "M_B_CPU0_SB_DQ<24>")
	)
	(segment
		(start 302.309022 -309.285132)
		(end 302.078898 -309.285132)
		(width 0.14478)
		(layer "In13.Cu")
		(net "M_B_CPU0_SB_DQ<24>")
	)
	(segment
		(start 304.359564 -310.144414)
		(end 304.359564 -309.73395)
		(width 0.14478)
		(layer "In13.Cu")
		(net "M_B_CPU0_SB_DQ<24>")
	)
	(segment
		(start 306.75072 -308.85511)
		(end 306.449476 -308.85511)
		(width 0.14478)
		(layer "In13.Cu")
		(net "M_B_CPU0_SB_DQ<24>")
	)
	(segment
		(start 317.76543 -299.571918)
		(end 317.560706 -299.571918)
		(width 0.14478)
		(layer "In13.Cu")
		(net "M_B_CPU0_SB_DQ<24>")
	)
	(segment
		(start 312.69686 -304.435764)
		(end 312.696606 -304.640488)
		(width 0.14478)
		(layer "In13.Cu")
		(net "M_B_CPU0_SB_DQ<24>")
	)
	(segment
		(start 315.815726 -301.521368)
		(end 315.858144 -301.563786)
		(width 0.14478)
		(layer "In13.Cu")
		(net "M_B_CPU0_SB_DQ<24>")
	)
	(segment
		(start 326.85355 -288.979102)
		(end 326.837802 -288.988246)
		(width 0.0889)
		(layer "In13.Cu")
		(net "M_B_CPU0_SB_DQ<24>")
	)
	(segment
		(start 312.349388 -305.072796)
		(end 312.30697 -305.030378)
		(width 0.14478)
		(layer "In13.Cu")
		(net "M_B_CPU0_SB_DQ<24>")
	)
	(segment
		(start 318.791844 -298.83481)
		(end 318.587628 -298.834556)
		(width 0.14478)
		(layer "In13.Cu")
		(net "M_B_CPU0_SB_DQ<24>")
	)
	(segment
		(start 312.30697 -305.030378)
		(end 312.102246 -305.030378)
		(width 0.14478)
		(layer "In13.Cu")
		(net "M_B_CPU0_SB_DQ<24>")
	)
	(segment
		(start 317.807848 -299.614336)
		(end 317.76543 -299.571918)
		(width 0.14478)
		(layer "In13.Cu")
		(net "M_B_CPU0_SB_DQ<24>")
	)
	(segment
		(start 318.15532 -298.977304)
		(end 318.155066 -299.182028)
		(width 0.14478)
		(layer "In13.Cu")
		(net "M_B_CPU0_SB_DQ<24>")
	)
	(segment
		(start 327.77811 -288.9885)
		(end 327.766426 -288.995358)
		(width 0.0889)
		(layer "In13.Cu")
		(net "M_B_CPU0_SB_DQ<24>")
	)
	(segment
		(start 302.472344 -309.678578)
		(end 302.472344 -309.448454)
		(width 0.14478)
		(layer "In13.Cu")
		(net "M_B_CPU0_SB_DQ<24>")
	)
	(segment
		(start 318.012064 -299.61459)
		(end 317.807848 -299.614336)
		(width 0.14478)
		(layer "In13.Cu")
		(net "M_B_CPU0_SB_DQ<24>")
	)
	(segment
		(start 304.522378 -310.307228)
		(end 304.359564 -310.144414)
		(width 0.14478)
		(layer "In13.Cu")
		(net "M_B_CPU0_SB_DQ<24>")
	)
	(segment
		(start 318.977264 -298.444666)
		(end 318.977264 -298.64939)
		(width 0.14478)
		(layer "In13.Cu")
		(net "M_B_CPU0_SB_DQ<24>")
	)
	(segment
		(start 304.910998 -309.456074)
		(end 304.910998 -309.685944)
		(width 0.14478)
		(layer "In13.Cu")
		(net "M_B_CPU0_SB_DQ<24>")
	)
	(segment
		(start 318.934846 -298.402248)
		(end 318.977264 -298.444666)
		(width 0.14478)
		(layer "In13.Cu")
		(net "M_B_CPU0_SB_DQ<24>")
	)
	(segment
		(start 318.197484 -299.42917)
		(end 318.012064 -299.61459)
		(width 0.14478)
		(layer "In13.Cu")
		(net "M_B_CPU0_SB_DQ<24>")
	)
	(segment
		(start 316.248288 -301.173896)
		(end 316.20587 -301.131478)
		(width 0.14478)
		(layer "In13.Cu")
		(net "M_B_CPU0_SB_DQ<24>")
	)
	(segment
		(start 333.992474 -288.993326)
		(end 333.984092 -288.9885)
		(width 0.0889)
		(layer "In13.Cu")
		(net "M_B_CPU0_SB_DQ<24>")
	)
	(segment
		(start 315.672724 -301.95393)
		(end 315.468508 -301.953676)
		(width 0.14478)
		(layer "In13.Cu")
		(net "M_B_CPU0_SB_DQ<24>")
	)
	(segment
		(start 315.468508 -301.953676)
		(end 315.42609 -301.911258)
		(width 0.14478)
		(layer "In13.Cu")
		(net "M_B_CPU0_SB_DQ<24>")
	)
	(segment
		(start 303.803304 -310.144414)
		(end 303.64049 -310.307228)
		(width 0.14478)
		(layer "In13.Cu")
		(net "M_B_CPU0_SB_DQ<24>")
	)
	(segment
		(start 317.375286 -299.961808)
		(end 317.417704 -300.004226)
		(width 0.14478)
		(layer "In13.Cu")
		(net "M_B_CPU0_SB_DQ<24>")
	)
	(segment
		(start 303.803304 -309.73395)
		(end 303.803304 -310.144414)
		(width 0.14478)
		(layer "In13.Cu")
		(net "M_B_CPU0_SB_DQ<24>")
	)
	(segment
		(start 317.417704 -300.004226)
		(end 317.417704 -300.20895)
		(width 0.14478)
		(layer "In13.Cu")
		(net "M_B_CPU0_SB_DQ<24>")
	)
	(segment
		(start 318.340486 -298.792138)
		(end 318.15532 -298.977304)
		(width 0.14478)
		(layer "In13.Cu")
		(net "M_B_CPU0_SB_DQ<24>")
	)
	(segment
		(start 335.896966 -288.93135)
		(end 335.8007 -288.95675)
		(width 0.0889)
		(layer "In13.Cu")
		(net "M_B_CPU0_SB_DQ<24>")
	)
	(segment
		(start 302.078898 -309.285132)
		(end 301.88789 -309.47614)
		(width 0.14478)
		(layer "In13.Cu")
		(net "M_B_CPU0_SB_DQ<24>")
	)
	(segment
		(start 313.08675 -304.250598)
		(end 312.882026 -304.250598)
		(width 0.14478)
		(layer "In13.Cu")
		(net "M_B_CPU0_SB_DQ<24>")
	)
	(segment
		(start 315.81598 -301.316644)
		(end 315.815726 -301.521368)
		(width 0.14478)
		(layer "In13.Cu")
		(net "M_B_CPU0_SB_DQ<24>")
	)
	(segment
		(start 313.661806 -303.470818)
		(end 313.47664 -303.655984)
		(width 0.14478)
		(layer "In13.Cu")
		(net "M_B_CPU0_SB_DQ<24>")
	)
	(segment
		(start 312.739024 -304.682906)
		(end 312.739024 -304.88763)
		(width 0.14478)
		(layer "In13.Cu")
		(net "M_B_CPU0_SB_DQ<24>")
	)
	(segment
		(start 317.417704 -300.20895)
		(end 317.232284 -300.39437)
		(width 0.14478)
		(layer "In13.Cu")
		(net "M_B_CPU0_SB_DQ<24>")
	)
	(segment
		(start 316.637924 -300.784006)
		(end 316.637924 -300.98873)
		(width 0.14478)
		(layer "In13.Cu")
		(net "M_B_CPU0_SB_DQ<24>")
	)
	(segment
		(start 314.25642 -302.876204)
		(end 314.256166 -303.080928)
		(width 0.14478)
		(layer "In13.Cu")
		(net "M_B_CPU0_SB_DQ<24>")
	)
	(segment
		(start 316.780926 -300.351698)
		(end 316.59576 -300.536864)
		(width 0.14478)
		(layer "In13.Cu")
		(net "M_B_CPU0_SB_DQ<24>")
	)
	(segment
		(start 304.359564 -309.73395)
		(end 304.19675 -309.571136)
		(width 0.14478)
		(layer "In13.Cu")
		(net "M_B_CPU0_SB_DQ<24>")
	)
	(segment
		(start 324.649338 -291.157152)
		(end 323.723254 -292.083236)
		(width 0.0889)
		(layer "In13.Cu")
		(net "M_B_CPU0_SB_DQ<24>")
	)
	(segment
		(start 317.232284 -300.39437)
		(end 317.028068 -300.394116)
		(width 0.14478)
		(layer "In13.Cu")
		(net "M_B_CPU0_SB_DQ<24>")
	)
	(segment
		(start 336.051144 -288.66592)
		(end 335.896966 -288.93135)
		(width 0.0889)
		(layer "In13.Cu")
		(net "M_B_CPU0_SB_DQ<24>")
	)
	(segment
		(start 301.88789 -309.47614)
		(end 301.657766 -309.47614)
		(width 0.14478)
		(layer "In13.Cu")
		(net "M_B_CPU0_SB_DQ<24>")
	)
	(segment
		(start 314.298584 -303.123346)
		(end 314.298584 -303.32807)
		(width 0.14478)
		(layer "In13.Cu")
		(net "M_B_CPU0_SB_DQ<24>")
	)
	(segment
		(start 332.478126 -288.9885)
		(end 332.469744 -288.993326)
		(width 0.0889)
		(layer "In13.Cu")
		(net "M_B_CPU0_SB_DQ<24>")
	)
	(segment
		(start 316.20587 -301.131478)
		(end 316.001146 -301.131478)
		(width 0.14478)
		(layer "In13.Cu")
		(net "M_B_CPU0_SB_DQ<24>")
	)
	(segment
		(start 318.977264 -298.64939)
		(end 318.791844 -298.83481)
		(width 0.14478)
		(layer "In13.Cu")
		(net "M_B_CPU0_SB_DQ<24>")
	)
	(segment
		(start 304.19675 -309.571136)
		(end 303.966118 -309.571136)
		(width 0.14478)
		(layer "In13.Cu")
		(net "M_B_CPU0_SB_DQ<24>")
	)
	(segment
		(start 312.553604 -305.07305)
		(end 312.349388 -305.072796)
		(width 0.14478)
		(layer "In13.Cu")
		(net "M_B_CPU0_SB_DQ<24>")
	)
	(segment
		(start 313.518804 -303.903126)
		(end 313.518804 -304.10785)
		(width 0.14478)
		(layer "In13.Cu")
		(net "M_B_CPU0_SB_DQ<24>")
	)
	(segment
		(start 312.696606 -304.640488)
		(end 312.739024 -304.682906)
		(width 0.14478)
		(layer "In13.Cu")
		(net "M_B_CPU0_SB_DQ<24>")
	)
	(segment
		(start 317.028068 -300.394116)
		(end 316.98565 -300.351698)
		(width 0.14478)
		(layer "In13.Cu")
		(net "M_B_CPU0_SB_DQ<24>")
	)
	(segment
		(start 305.027584 -309.80253)
		(end 305.027584 -310.032654)
		(width 0.14478)
		(layer "In13.Cu")
		(net "M_B_CPU0_SB_DQ<24>")
	)
	(segment
		(start 315.858144 -301.76851)
		(end 315.672724 -301.95393)
		(width 0.14478)
		(layer "In13.Cu")
		(net "M_B_CPU0_SB_DQ<24>")
	)
	(segment
		(start 318.155066 -299.182028)
		(end 318.197484 -299.224446)
		(width 0.14478)
		(layer "In13.Cu")
		(net "M_B_CPU0_SB_DQ<24>")
	)
	(segment
		(start 306.011834 -309.292752)
		(end 305.07432 -309.292752)
		(width 0.14478)
		(layer "In13.Cu")
		(net "M_B_CPU0_SB_DQ<24>")
	)
	(segment
		(start 315.0362 -302.096424)
		(end 315.035946 -302.301148)
		(width 0.14478)
		(layer "In13.Cu")
		(net "M_B_CPU0_SB_DQ<24>")
	)
	(segment
		(start 314.298584 -303.32807)
		(end 314.113164 -303.51349)
		(width 0.14478)
		(layer "In13.Cu")
		(net "M_B_CPU0_SB_DQ<24>")
	)
	(segment
		(start 302.281336 -309.869586)
		(end 302.472344 -309.678578)
		(width 0.14478)
		(layer "In13.Cu")
		(net "M_B_CPU0_SB_DQ<24>")
	)
	(segment
		(start 324.649338 -290.504626)
		(end 324.649338 -291.157152)
		(width 0.0889)
		(layer "In13.Cu")
		(net "M_B_CPU0_SB_DQ<24>")
	)
	(segment
		(start 305.07432 -309.292752)
		(end 304.910998 -309.456074)
		(width 0.14478)
		(layer "In13.Cu")
		(net "M_B_CPU0_SB_DQ<24>")
	)
	(segment
		(start 326.650858 -289.039046)
		(end 326.114918 -289.039046)
		(width 0.0889)
		(layer "In13.Cu")
		(net "M_B_CPU0_SB_DQ<24>")
	)
	(segment
		(start 316.001146 -301.131478)
		(end 315.81598 -301.316644)
		(width 0.14478)
		(layer "In13.Cu")
		(net "M_B_CPU0_SB_DQ<24>")
	)
	(segment
		(start 301.291752 -309.110126)
		(end 300.249082 -309.110126)
		(width 0.14478)
		(layer "In13.Cu")
		(net "M_B_CPU0_SB_DQ<24>")
	)
	(segment
		(start 301.657766 -309.47614)
		(end 301.291752 -309.110126)
		(width 0.14478)
		(layer "In13.Cu")
		(net "M_B_CPU0_SB_DQ<24>")
	)
	(segment
		(start 319.453006 -296.353484)
		(end 319.453006 -297.679618)
		(width 0.14478)
		(layer "In13.Cu")
		(net "M_B_CPU0_SB_DQ<24>")
	)
	(segment
		(start 313.908948 -303.513236)
		(end 313.86653 -303.470818)
		(width 0.14478)
		(layer "In13.Cu")
		(net "M_B_CPU0_SB_DQ<24>")
	)
	(segment
		(start 313.476386 -303.860708)
		(end 313.518804 -303.903126)
		(width 0.14478)
		(layer "In13.Cu")
		(net "M_B_CPU0_SB_DQ<24>")
	)
	(segment
		(start 316.59576 -300.536864)
		(end 316.595506 -300.741588)
		(width 0.14478)
		(layer "In13.Cu")
		(net "M_B_CPU0_SB_DQ<24>")
	)
	(segment
		(start 314.256166 -303.080928)
		(end 314.298584 -303.123346)
		(width 0.14478)
		(layer "In13.Cu")
		(net "M_B_CPU0_SB_DQ<24>")
	)
	(segment
		(start 328.718164 -288.9885)
		(end 328.709782 -288.993326)
		(width 0.0889)
		(layer "In13.Cu")
		(net "M_B_CPU0_SB_DQ<24>")
	)
	(segment
		(start 316.637924 -300.98873)
		(end 316.452504 -301.17415)
		(width 0.14478)
		(layer "In13.Cu")
		(net "M_B_CPU0_SB_DQ<24>")
	)
	(segment
		(start 315.221366 -301.911258)
		(end 315.0362 -302.096424)
		(width 0.14478)
		(layer "In13.Cu")
		(net "M_B_CPU0_SB_DQ<24>")
	)
	(segment
		(start 303.64049 -310.307228)
		(end 302.488854 -310.307228)
		(width 0.14478)
		(layer "In13.Cu")
		(net "M_B_CPU0_SB_DQ<24>")
	)
	(segment
		(start 300.249082 -309.110126)
		(end 299.82414 -309.535068)
		(width 0.14478)
		(layer "In13.Cu")
		(net "M_B_CPU0_SB_DQ<24>")
	)
	(segment
		(start 318.587628 -298.834556)
		(end 318.54521 -298.792138)
		(width 0.14478)
		(layer "In13.Cu")
		(net "M_B_CPU0_SB_DQ<24>")
	)
	(segment
		(start 312.882026 -304.250598)
		(end 312.69686 -304.435764)
		(width 0.14478)
		(layer "In13.Cu")
		(net "M_B_CPU0_SB_DQ<24>")
	)
	(segment
		(start 315.078364 -302.343566)
		(end 315.078364 -302.54829)
		(width 0.14478)
		(layer "In13.Cu")
		(net "M_B_CPU0_SB_DQ<24>")
	)
	(segment
		(start 304.75301 -310.307228)
		(end 304.522378 -310.307228)
		(width 0.14478)
		(layer "In13.Cu")
		(net "M_B_CPU0_SB_DQ<24>")
	)
	(segment
		(start 313.518804 -304.10785)
		(end 313.333384 -304.29327)
		(width 0.14478)
		(layer "In13.Cu")
		(net "M_B_CPU0_SB_DQ<24>")
	)
	(segment
		(start 315.858144 -301.563786)
		(end 315.858144 -301.76851)
		(width 0.14478)
		(layer "In13.Cu")
		(net "M_B_CPU0_SB_DQ<24>")
	)
	(segment
		(start 302.472344 -309.448454)
		(end 302.309022 -309.285132)
		(width 0.14478)
		(layer "In13.Cu")
		(net "M_B_CPU0_SB_DQ<24>")
	)
	(segment
		(start 329.292458 -288.993326)
		(end 329.284076 -288.9885)
		(width 0.0889)
		(layer "In13.Cu")
		(net "M_B_CPU0_SB_DQ<24>")
	)
	(segment
		(start 313.333384 -304.29327)
		(end 313.129168 -304.293016)
		(width 0.14478)
		(layer "In13.Cu")
		(net "M_B_CPU0_SB_DQ<24>")
	)
	(segment
		(start 317.37554 -299.757084)
		(end 317.375286 -299.961808)
		(width 0.14478)
		(layer "In13.Cu")
		(net "M_B_CPU0_SB_DQ<24>")
	)
	(segment
		(start 312.739024 -304.88763)
		(end 312.553604 -305.07305)
		(width 0.14478)
		(layer "In13.Cu")
		(net "M_B_CPU0_SB_DQ<24>")
	)
	(segment
		(start 314.892944 -302.73371)
		(end 314.688728 -302.733456)
		(width 0.14478)
		(layer "In13.Cu")
		(net "M_B_CPU0_SB_DQ<24>")
	)
	(segment
		(start 333.05242 -288.993326)
		(end 333.044038 -288.9885)
		(width 0.0889)
		(layer "In13.Cu")
		(net "M_B_CPU0_SB_DQ<24>")
	)
	(segment
		(start 316.595506 -300.741588)
		(end 316.637924 -300.784006)
		(width 0.14478)
		(layer "In13.Cu")
		(net "M_B_CPU0_SB_DQ<24>")
	)
	(segment
		(start 307.005736 -309.110126)
		(end 306.75072 -308.85511)
		(width 0.14478)
		(layer "In13.Cu")
		(net "M_B_CPU0_SB_DQ<24>")
	)
	(segment
		(start 304.910998 -309.685944)
		(end 305.027584 -309.80253)
		(width 0.14478)
		(layer "In13.Cu")
		(net "M_B_CPU0_SB_DQ<24>")
	)
	(segment
		(start 315.035946 -302.301148)
		(end 315.078364 -302.343566)
		(width 0.14478)
		(layer "In13.Cu")
		(net "M_B_CPU0_SB_DQ<24>")
	)
	(segment
		(start 313.86653 -303.470818)
		(end 313.661806 -303.470818)
		(width 0.14478)
		(layer "In13.Cu")
		(net "M_B_CPU0_SB_DQ<24>")
	)
	(segment
		(start 314.64631 -302.691038)
		(end 314.441586 -302.691038)
		(width 0.14478)
		(layer "In13.Cu")
		(net "M_B_CPU0_SB_DQ<24>")
	)
	(segment
		(start 314.113164 -303.51349)
		(end 313.908948 -303.513236)
		(width 0.14478)
		(layer "In13.Cu")
		(net "M_B_CPU0_SB_DQ<24>")
	)
	(segment
		(start 305.027584 -310.032654)
		(end 304.75301 -310.307228)
		(width 0.14478)
		(layer "In13.Cu")
		(net "M_B_CPU0_SB_DQ<24>")
	)
	(segment
		(start 318.54521 -298.792138)
		(end 318.340486 -298.792138)
		(width 0.14478)
		(layer "In13.Cu")
		(net "M_B_CPU0_SB_DQ<24>")
	)
	(segment
		(start 303.966118 -309.571136)
		(end 303.803304 -309.73395)
		(width 0.14478)
		(layer "In13.Cu")
		(net "M_B_CPU0_SB_DQ<24>")
	)
	(segment
		(start 313.129168 -304.293016)
		(end 313.08675 -304.250598)
		(width 0.14478)
		(layer "In13.Cu")
		(net "M_B_CPU0_SB_DQ<24>")
	)
	(segment
		(start 318.197484 -299.224446)
		(end 318.197484 -299.42917)
		(width 0.14478)
		(layer "In13.Cu")
		(net "M_B_CPU0_SB_DQ<24>")
	)
	(segment
		(start 315.42609 -301.911258)
		(end 315.221366 -301.911258)
		(width 0.14478)
		(layer "In13.Cu")
		(net "M_B_CPU0_SB_DQ<24>")
	)
	(segment
		(start 316.98565 -300.351698)
		(end 316.780926 -300.351698)
		(width 0.14478)
		(layer "In13.Cu")
		(net "M_B_CPU0_SB_DQ<24>")
	)
	(segment
		(start 318.9351 -298.197524)
		(end 318.934846 -298.402248)
		(width 0.14478)
		(layer "In13.Cu")
		(net "M_B_CPU0_SB_DQ<24>")
	)
	(segment
		(start 302.281336 -310.09971)
		(end 302.281336 -309.869586)
		(width 0.14478)
		(layer "In13.Cu")
		(net "M_B_CPU0_SB_DQ<24>")
	)
	(segment
		(start 312.102246 -305.030378)
		(end 308.022498 -309.110126)
		(width 0.14478)
		(layer "In13.Cu")
		(net "M_B_CPU0_SB_DQ<24>")
	)
	(segment
		(start 326.114918 -289.039046)
		(end 324.649338 -290.504626)
		(width 0.0889)
		(layer "In13.Cu")
		(net "M_B_CPU0_SB_DQ<24>")
	)
	(segment
		(start 319.453006 -297.679618)
		(end 318.9351 -298.197524)
		(width 0.14478)
		(layer "In13.Cu")
		(net "M_B_CPU0_SB_DQ<24>")
	)
	(segment
		(start 313.47664 -303.655984)
		(end 313.476386 -303.860708)
		(width 0.14478)
		(layer "In13.Cu")
		(net "M_B_CPU0_SB_DQ<24>")
	)
	(segment
		(start 315.078364 -302.54829)
		(end 314.892944 -302.73371)
		(width 0.14478)
		(layer "In13.Cu")
		(net "M_B_CPU0_SB_DQ<24>")
	)
	(segment
		(start 308.022498 -309.110126)
		(end 307.005736 -309.110126)
		(width 0.14478)
		(layer "In13.Cu")
		(net "M_B_CPU0_SB_DQ<24>")
	)
	(segment
		(start 302.488854 -310.307228)
		(end 302.281336 -310.09971)
		(width 0.14478)
		(layer "In13.Cu")
		(net "M_B_CPU0_SB_DQ<24>")
	)
	(segment
		(start 323.723254 -292.083236)
		(end 319.453006 -296.353484)
		(width 0.14478)
		(layer "In13.Cu")
		(net "M_B_CPU0_SB_DQ<24>")
	)
	(segment
		(start 314.688728 -302.733456)
		(end 314.64631 -302.691038)
		(width 0.14478)
		(layer "In13.Cu")
		(net "M_B_CPU0_SB_DQ<24>")
	)
	(segment
		(start 306.449476 -308.85511)
		(end 306.011834 -309.292752)
		(width 0.14478)
		(layer "In13.Cu")
		(net "M_B_CPU0_SB_DQ<24>")
	)
	(segment
		(start 316.452504 -301.17415)
		(end 316.248288 -301.173896)
		(width 0.14478)
		(layer "In13.Cu")
		(net "M_B_CPU0_SB_DQ<24>")
	)
	(segment
		(start 317.560706 -299.571918)
		(end 317.37554 -299.757084)
		(width 0.14478)
		(layer "In13.Cu")
		(net "M_B_CPU0_SB_DQ<24>")
	)
	(arc
		(start 335.298034 -288.9885)
		(mid 335.11109 -289.038755)
		(end 334.924146 -288.9885)
		(width 0.0889)
		(layer "In13.Cu")
		(net "M_B_CPU0_SB_DQ<24>")
	)
	(arc
		(start 334.924146 -288.9885)
		(mid 334.64119 -288.912323)
		(end 334.358234 -288.9885)
		(width 0.0889)
		(layer "In13.Cu")
		(net "M_B_CPU0_SB_DQ<24>")
	)
	(arc
		(start 327.403714 -288.9885)
		(mid 327.129859 -288.91215)
		(end 326.85355 -288.979102)
		(width 0.0889)
		(layer "In13.Cu")
		(net "M_B_CPU0_SB_DQ<24>")
	)
	(arc
		(start 328.709782 -288.993326)
		(mid 328.526274 -289.03882)
		(end 328.344022 -288.9885)
		(width 0.0889)
		(layer "In13.Cu")
		(net "M_B_CPU0_SB_DQ<24>")
	)
	(arc
		(start 332.469744 -288.993326)
		(mid 332.286236 -289.03882)
		(end 332.103984 -288.9885)
		(width 0.0889)
		(layer "In13.Cu")
		(net "M_B_CPU0_SB_DQ<24>")
	)
	(arc
		(start 328.344022 -288.9885)
		(mid 328.061066 -288.912323)
		(end 327.77811 -288.9885)
		(width 0.0889)
		(layer "In13.Cu")
		(net "M_B_CPU0_SB_DQ<24>")
	)
	(arc
		(start 333.41818 -288.9885)
		(mid 333.235929 -289.03885)
		(end 333.05242 -288.993326)
		(width 0.0889)
		(layer "In13.Cu")
		(net "M_B_CPU0_SB_DQ<24>")
	)
	(arc
		(start 331.16393 -288.9885)
		(mid 330.880974 -288.912323)
		(end 330.598018 -288.9885)
		(width 0.0889)
		(layer "In13.Cu")
		(net "M_B_CPU0_SB_DQ<24>")
	)
	(arc
		(start 329.658218 -288.9885)
		(mid 329.475967 -289.03885)
		(end 329.292458 -288.993326)
		(width 0.0889)
		(layer "In13.Cu")
		(net "M_B_CPU0_SB_DQ<24>")
	)
	(arc
		(start 333.044038 -288.9885)
		(mid 332.761082 -288.912323)
		(end 332.478126 -288.9885)
		(width 0.0889)
		(layer "In13.Cu")
		(net "M_B_CPU0_SB_DQ<24>")
	)
	(arc
		(start 330.22413 -288.9885)
		(mid 329.941174 -288.912323)
		(end 329.658218 -288.9885)
		(width 0.0889)
		(layer "In13.Cu")
		(net "M_B_CPU0_SB_DQ<24>")
	)
	(arc
		(start 334.358234 -288.9885)
		(mid 334.175983 -289.03885)
		(end 333.992474 -288.993326)
		(width 0.0889)
		(layer "In13.Cu")
		(net "M_B_CPU0_SB_DQ<24>")
	)
	(arc
		(start 327.766426 -288.995358)
		(mid 327.584171 -289.039011)
		(end 327.403714 -288.9885)
		(width 0.0889)
		(layer "In13.Cu")
		(net "M_B_CPU0_SB_DQ<24>")
	)
	(arc
		(start 331.52969 -288.993326)
		(mid 331.346182 -289.03882)
		(end 331.16393 -288.9885)
		(width 0.0889)
		(layer "In13.Cu")
		(net "M_B_CPU0_SB_DQ<24>")
	)
	(arc
		(start 326.837802 -288.988246)
		(mid 326.747693 -289.02604)
		(end 326.650858 -289.039046)
		(width 0.0889)
		(layer "In13.Cu")
		(net "M_B_CPU0_SB_DQ<24>")
	)
	(arc
		(start 330.598018 -288.9885)
		(mid 330.411074 -289.038755)
		(end 330.22413 -288.9885)
		(width 0.0889)
		(layer "In13.Cu")
		(net "M_B_CPU0_SB_DQ<24>")
	)
	(arc
		(start 332.103984 -288.9885)
		(mid 331.821028 -288.912323)
		(end 331.538072 -288.9885)
		(width 0.0889)
		(layer "In13.Cu")
		(net "M_B_CPU0_SB_DQ<24>")
	)
	(arc
		(start 329.284076 -288.9885)
		(mid 329.00112 -288.912323)
		(end 328.718164 -288.9885)
		(width 0.0889)
		(layer "In13.Cu")
		(net "M_B_CPU0_SB_DQ<24>")
	)
	(arc
		(start 333.984092 -288.9885)
		(mid 333.701136 -288.912323)
		(end 333.41818 -288.9885)
		(width 0.0889)
		(layer "In13.Cu")
		(net "M_B_CPU0_SB_DQ<24>")
	)
	(arc
		(start 335.8007 -288.95675)
		(mid 335.545635 -288.913399)
		(end 335.298034 -288.9885)
		(width 0.0889)
		(layer "In13.Cu")
		(net "M_B_CPU0_SB_DQ<24>")
	)
	(segment
		(start 337.45805 -288.399982)
		(end 336.991198 -288.66592)
		(width 0.10668)
		(layer "F.Cu")
		(net "M_B_CPU0_SB_DQ<23>")
	)
	(segment
		(start 306.146708 -308.389274)
		(end 306.50053 -308.21757)
		(width 0.14478)
		(layer "In13.Cu")
		(net "M_B_CPU0_SB_DQ<23>")
	)
	(segment
		(start 323.805804 -291.167566)
		(end 324.351904 -290.621466)
		(width 0.0889)
		(layer "In13.Cu")
		(net "M_B_CPU0_SB_DQ<23>")
	)
	(segment
		(start 331.52969 -288.338768)
		(end 331.538072 -288.343594)
		(width 0.0889)
		(layer "In13.Cu")
		(net "M_B_CPU0_SB_DQ<23>")
	)
	(segment
		(start 299.64253 -308.259988)
		(end 300.68012 -308.259988)
		(width 0.14478)
		(layer "In13.Cu")
		(net "M_B_CPU0_SB_DQ<23>")
	)
	(segment
		(start 306.50053 -308.21757)
		(end 307.976778 -307.91277)
		(width 0.14478)
		(layer "In13.Cu")
		(net "M_B_CPU0_SB_DQ<23>")
	)
	(segment
		(start 329.284076 -288.343594)
		(end 329.292458 -288.338768)
		(width 0.0889)
		(layer "In13.Cu")
		(net "M_B_CPU0_SB_DQ<23>")
	)
	(segment
		(start 324.351904 -290.532566)
		(end 325.568818 -289.315652)
		(width 0.0889)
		(layer "In13.Cu")
		(net "M_B_CPU0_SB_DQ<23>")
	)
	(segment
		(start 336.229706 -288.338768)
		(end 336.238088 -288.343594)
		(width 0.0889)
		(layer "In13.Cu")
		(net "M_B_CPU0_SB_DQ<23>")
	)
	(segment
		(start 308.77637 -307.576728)
		(end 318.901826 -297.451272)
		(width 0.14478)
		(layer "In13.Cu")
		(net "M_B_CPU0_SB_DQ<23>")
	)
	(segment
		(start 305.759358 -308.714902)
		(end 306.146708 -308.389274)
		(width 0.14478)
		(layer "In13.Cu")
		(net "M_B_CPU0_SB_DQ<23>")
	)
	(segment
		(start 337.145122 -288.40049)
		(end 336.991198 -288.66592)
		(width 0.0889)
		(layer "In13.Cu")
		(net "M_B_CPU0_SB_DQ<23>")
	)
	(segment
		(start 337.12277 -288.317432)
		(end 337.145122 -288.40049)
		(width 0.0889)
		(layer "In13.Cu")
		(net "M_B_CPU0_SB_DQ<23>")
	)
	(segment
		(start 328.709782 -288.338768)
		(end 328.718164 -288.343594)
		(width 0.0889)
		(layer "In13.Cu")
		(net "M_B_CPU0_SB_DQ<23>")
	)
	(segment
		(start 332.469744 -288.338768)
		(end 332.478126 -288.343594)
		(width 0.0889)
		(layer "In13.Cu")
		(net "M_B_CPU0_SB_DQ<23>")
	)
	(segment
		(start 324.351904 -290.621466)
		(end 324.351904 -290.532566)
		(width 0.0889)
		(layer "In13.Cu")
		(net "M_B_CPU0_SB_DQ<23>")
	)
	(segment
		(start 295.724072 -308.685184)
		(end 299.64253 -308.259988)
		(width 0.14478)
		(layer "In13.Cu")
		(net "M_B_CPU0_SB_DQ<23>")
	)
	(segment
		(start 325.568818 -289.315652)
		(end 325.568818 -289.031172)
		(width 0.0889)
		(layer "In13.Cu")
		(net "M_B_CPU0_SB_DQ<23>")
	)
	(segment
		(start 325.568818 -289.031172)
		(end 326.179942 -288.420048)
		(width 0.0889)
		(layer "In13.Cu")
		(net "M_B_CPU0_SB_DQ<23>")
	)
	(segment
		(start 301.616618 -308.647846)
		(end 301.683674 -308.714902)
		(width 0.14478)
		(layer "In13.Cu")
		(net "M_B_CPU0_SB_DQ<23>")
	)
	(segment
		(start 333.984092 -288.343594)
		(end 333.992474 -288.338768)
		(width 0.0889)
		(layer "In13.Cu")
		(net "M_B_CPU0_SB_DQ<23>")
	)
	(segment
		(start 318.901826 -296.071544)
		(end 323.805804 -291.167566)
		(width 0.14478)
		(layer "In13.Cu")
		(net "M_B_CPU0_SB_DQ<23>")
	)
	(segment
		(start 307.976778 -307.91277)
		(end 308.77637 -307.576728)
		(width 0.14478)
		(layer "In13.Cu")
		(net "M_B_CPU0_SB_DQ<23>")
	)
	(segment
		(start 300.68012 -308.259988)
		(end 301.616618 -308.647846)
		(width 0.14478)
		(layer "In13.Cu")
		(net "M_B_CPU0_SB_DQ<23>")
	)
	(segment
		(start 333.044038 -288.343594)
		(end 333.05242 -288.338768)
		(width 0.0889)
		(layer "In13.Cu")
		(net "M_B_CPU0_SB_DQ<23>")
	)
	(segment
		(start 318.901826 -297.451272)
		(end 318.901826 -296.071544)
		(width 0.14478)
		(layer "In13.Cu")
		(net "M_B_CPU0_SB_DQ<23>")
	)
	(segment
		(start 326.826372 -288.336736)
		(end 326.838056 -288.343594)
		(width 0.0889)
		(layer "In13.Cu")
		(net "M_B_CPU0_SB_DQ<23>")
	)
	(segment
		(start 301.683674 -308.714902)
		(end 305.759358 -308.714902)
		(width 0.14478)
		(layer "In13.Cu")
		(net "M_B_CPU0_SB_DQ<23>")
	)
	(segment
		(start 327.769728 -288.338768)
		(end 327.77811 -288.343594)
		(width 0.0889)
		(layer "In13.Cu")
		(net "M_B_CPU0_SB_DQ<23>")
	)
	(arc
		(start 326.179942 -288.420048)
		(mid 326.326873 -288.400637)
		(end 326.46366 -288.343594)
		(width 0.0889)
		(layer "In13.Cu")
		(net "M_B_CPU0_SB_DQ<23>")
	)
	(arc
		(start 330.598018 -288.343594)
		(mid 330.880974 -288.419771)
		(end 331.16393 -288.343594)
		(width 0.0889)
		(layer "In13.Cu")
		(net "M_B_CPU0_SB_DQ<23>")
	)
	(arc
		(start 333.41818 -288.343594)
		(mid 333.701136 -288.419771)
		(end 333.984092 -288.343594)
		(width 0.0889)
		(layer "In13.Cu")
		(net "M_B_CPU0_SB_DQ<23>")
	)
	(arc
		(start 326.46366 -288.343594)
		(mid 326.644118 -288.293115)
		(end 326.826372 -288.336736)
		(width 0.0889)
		(layer "In13.Cu")
		(net "M_B_CPU0_SB_DQ<23>")
	)
	(arc
		(start 332.103984 -288.343594)
		(mid 332.286235 -288.29321)
		(end 332.469744 -288.338768)
		(width 0.0889)
		(layer "In13.Cu")
		(net "M_B_CPU0_SB_DQ<23>")
	)
	(arc
		(start 327.403968 -288.343594)
		(mid 327.586219 -288.29321)
		(end 327.769728 -288.338768)
		(width 0.0889)
		(layer "In13.Cu")
		(net "M_B_CPU0_SB_DQ<23>")
	)
	(arc
		(start 330.22413 -288.343594)
		(mid 330.411074 -288.293305)
		(end 330.598018 -288.343594)
		(width 0.0889)
		(layer "In13.Cu")
		(net "M_B_CPU0_SB_DQ<23>")
	)
	(arc
		(start 336.804 -288.343594)
		(mid 336.960438 -288.294589)
		(end 337.12277 -288.317432)
		(width 0.0889)
		(layer "In13.Cu")
		(net "M_B_CPU0_SB_DQ<23>")
	)
	(arc
		(start 334.358234 -288.343594)
		(mid 334.64119 -288.419771)
		(end 334.924146 -288.343594)
		(width 0.0889)
		(layer "In13.Cu")
		(net "M_B_CPU0_SB_DQ<23>")
	)
	(arc
		(start 331.538072 -288.343594)
		(mid 331.821028 -288.419771)
		(end 332.103984 -288.343594)
		(width 0.0889)
		(layer "In13.Cu")
		(net "M_B_CPU0_SB_DQ<23>")
	)
	(arc
		(start 335.298034 -288.343594)
		(mid 335.58099 -288.419771)
		(end 335.863946 -288.343594)
		(width 0.0889)
		(layer "In13.Cu")
		(net "M_B_CPU0_SB_DQ<23>")
	)
	(arc
		(start 333.992474 -288.338768)
		(mid 334.175982 -288.293243)
		(end 334.358234 -288.343594)
		(width 0.0889)
		(layer "In13.Cu")
		(net "M_B_CPU0_SB_DQ<23>")
	)
	(arc
		(start 328.344022 -288.343594)
		(mid 328.526273 -288.29321)
		(end 328.709782 -288.338768)
		(width 0.0889)
		(layer "In13.Cu")
		(net "M_B_CPU0_SB_DQ<23>")
	)
	(arc
		(start 327.77811 -288.343594)
		(mid 328.061066 -288.419771)
		(end 328.344022 -288.343594)
		(width 0.0889)
		(layer "In13.Cu")
		(net "M_B_CPU0_SB_DQ<23>")
	)
	(arc
		(start 326.838056 -288.343594)
		(mid 327.121012 -288.419771)
		(end 327.403968 -288.343594)
		(width 0.0889)
		(layer "In13.Cu")
		(net "M_B_CPU0_SB_DQ<23>")
	)
	(arc
		(start 329.658218 -288.343594)
		(mid 329.941174 -288.419771)
		(end 330.22413 -288.343594)
		(width 0.0889)
		(layer "In13.Cu")
		(net "M_B_CPU0_SB_DQ<23>")
	)
	(arc
		(start 328.718164 -288.343594)
		(mid 329.00112 -288.419771)
		(end 329.284076 -288.343594)
		(width 0.0889)
		(layer "In13.Cu")
		(net "M_B_CPU0_SB_DQ<23>")
	)
	(arc
		(start 332.478126 -288.343594)
		(mid 332.761082 -288.419771)
		(end 333.044038 -288.343594)
		(width 0.0889)
		(layer "In13.Cu")
		(net "M_B_CPU0_SB_DQ<23>")
	)
	(arc
		(start 333.05242 -288.338768)
		(mid 333.235928 -288.293243)
		(end 333.41818 -288.343594)
		(width 0.0889)
		(layer "In13.Cu")
		(net "M_B_CPU0_SB_DQ<23>")
	)
	(arc
		(start 329.292458 -288.338768)
		(mid 329.475966 -288.293243)
		(end 329.658218 -288.343594)
		(width 0.0889)
		(layer "In13.Cu")
		(net "M_B_CPU0_SB_DQ<23>")
	)
	(arc
		(start 336.238088 -288.343594)
		(mid 336.521044 -288.419771)
		(end 336.804 -288.343594)
		(width 0.0889)
		(layer "In13.Cu")
		(net "M_B_CPU0_SB_DQ<23>")
	)
	(arc
		(start 334.924146 -288.343594)
		(mid 335.11109 -288.293305)
		(end 335.298034 -288.343594)
		(width 0.0889)
		(layer "In13.Cu")
		(net "M_B_CPU0_SB_DQ<23>")
	)
	(arc
		(start 331.16393 -288.343594)
		(mid 331.346181 -288.29321)
		(end 331.52969 -288.338768)
		(width 0.0889)
		(layer "In13.Cu")
		(net "M_B_CPU0_SB_DQ<23>")
	)
	(arc
		(start 335.863946 -288.343594)
		(mid 336.046197 -288.29321)
		(end 336.229706 -288.338768)
		(width 0.0889)
		(layer "In13.Cu")
		(net "M_B_CPU0_SB_DQ<23>")
	)
	(segment
		(start 336.047842 -287.59023)
		(end 335.58099 -287.856168)
		(width 0.10668)
		(layer "F.Cu")
		(net "M_B_CPU0_SB_DQ<22>")
	)
	(segment
		(start 295.724072 -306.985162)
		(end 296.699432 -306.985162)
		(width 0.14478)
		(layer "In13.Cu")
		(net "M_B_CPU0_SB_DQ<22>")
	)
	(segment
		(start 308.22265 -306.559966)
		(end 318.002666 -296.77995)
		(width 0.14478)
		(layer "In13.Cu")
		(net "M_B_CPU0_SB_DQ<22>")
	)
	(segment
		(start 298.908216 -306.559966)
		(end 299.970952 -306.559966)
		(width 0.14478)
		(layer "In13.Cu")
		(net "M_B_CPU0_SB_DQ<22>")
	)
	(segment
		(start 318.002666 -295.58742)
		(end 323.890386 -289.6997)
		(width 0.14478)
		(layer "In13.Cu")
		(net "M_B_CPU0_SB_DQ<22>")
	)
	(segment
		(start 333.88808 -287.533588)
		(end 333.888334 -287.533588)
		(width 0.0889)
		(layer "In13.Cu")
		(net "M_B_CPU0_SB_DQ<22>")
	)
	(segment
		(start 306.21986 -306.559966)
		(end 308.22265 -306.559966)
		(width 0.14478)
		(layer "In13.Cu")
		(net "M_B_CPU0_SB_DQ<22>")
	)
	(segment
		(start 331.634084 -287.533588)
		(end 331.642466 -287.528762)
		(width 0.0889)
		(layer "In13.Cu")
		(net "M_B_CPU0_SB_DQ<22>")
	)
	(segment
		(start 296.988992 -307.390546)
		(end 297.250612 -307.390546)
		(width 0.14478)
		(layer "In13.Cu")
		(net "M_B_CPU0_SB_DQ<22>")
	)
	(segment
		(start 335.735168 -287.590738)
		(end 335.58099 -287.856168)
		(width 0.0889)
		(layer "In13.Cu")
		(net "M_B_CPU0_SB_DQ<22>")
	)
	(segment
		(start 325.809356 -287.609788)
		(end 326.651112 -287.609788)
		(width 0.0889)
		(layer "In13.Cu")
		(net "M_B_CPU0_SB_DQ<22>")
	)
	(segment
		(start 323.890386 -289.6997)
		(end 324.369938 -289.220148)
		(width 0.0889)
		(layer "In13.Cu")
		(net "M_B_CPU0_SB_DQ<22>")
	)
	(segment
		(start 297.395392 -307.245766)
		(end 297.395392 -307.129942)
		(width 0.14478)
		(layer "In13.Cu")
		(net "M_B_CPU0_SB_DQ<22>")
	)
	(segment
		(start 324.369938 -288.962338)
		(end 325.182484 -288.149792)
		(width 0.0889)
		(layer "In13.Cu")
		(net "M_B_CPU0_SB_DQ<22>")
	)
	(segment
		(start 305.369722 -307.410104)
		(end 306.21986 -306.559966)
		(width 0.14478)
		(layer "In13.Cu")
		(net "M_B_CPU0_SB_DQ<22>")
	)
	(segment
		(start 328.239882 -287.528762)
		(end 328.248264 -287.533588)
		(width 0.0889)
		(layer "In13.Cu")
		(net "M_B_CPU0_SB_DQ<22>")
	)
	(segment
		(start 335.712816 -287.507426)
		(end 335.735168 -287.590738)
		(width 0.0889)
		(layer "In13.Cu")
		(net "M_B_CPU0_SB_DQ<22>")
	)
	(segment
		(start 318.002666 -296.77995)
		(end 318.002666 -295.58742)
		(width 0.14478)
		(layer "In13.Cu")
		(net "M_B_CPU0_SB_DQ<22>")
	)
	(segment
		(start 297.540172 -306.985162)
		(end 298.48302 -306.985162)
		(width 0.14478)
		(layer "In13.Cu")
		(net "M_B_CPU0_SB_DQ<22>")
	)
	(segment
		(start 325.182484 -288.149792)
		(end 325.269352 -288.149792)
		(width 0.0889)
		(layer "In13.Cu")
		(net "M_B_CPU0_SB_DQ<22>")
	)
	(segment
		(start 296.699432 -306.985162)
		(end 296.844212 -307.129942)
		(width 0.14478)
		(layer "In13.Cu")
		(net "M_B_CPU0_SB_DQ<22>")
	)
	(segment
		(start 297.395392 -307.129942)
		(end 297.540172 -306.985162)
		(width 0.14478)
		(layer "In13.Cu")
		(net "M_B_CPU0_SB_DQ<22>")
	)
	(segment
		(start 324.369938 -289.220148)
		(end 324.369938 -288.962338)
		(width 0.0889)
		(layer "In13.Cu")
		(net "M_B_CPU0_SB_DQ<22>")
	)
	(segment
		(start 330.119736 -287.528762)
		(end 330.128118 -287.533588)
		(width 0.0889)
		(layer "In13.Cu")
		(net "M_B_CPU0_SB_DQ<22>")
	)
	(segment
		(start 327.307956 -287.533588)
		(end 327.32599 -287.544002)
		(width 0.0889)
		(layer "In13.Cu")
		(net "M_B_CPU0_SB_DQ<22>")
	)
	(segment
		(start 335.394046 -287.533588)
		(end 335.402428 -287.528762)
		(width 0.0889)
		(layer "In13.Cu")
		(net "M_B_CPU0_SB_DQ<22>")
	)
	(segment
		(start 296.844212 -307.129942)
		(end 296.844212 -307.245766)
		(width 0.14478)
		(layer "In13.Cu")
		(net "M_B_CPU0_SB_DQ<22>")
	)
	(segment
		(start 297.250612 -307.390546)
		(end 297.395392 -307.245766)
		(width 0.14478)
		(layer "In13.Cu")
		(net "M_B_CPU0_SB_DQ<22>")
	)
	(segment
		(start 330.69403 -287.533588)
		(end 330.702412 -287.528762)
		(width 0.0889)
		(layer "In13.Cu")
		(net "M_B_CPU0_SB_DQ<22>")
	)
	(segment
		(start 333.879698 -287.528762)
		(end 333.88808 -287.533588)
		(width 0.0889)
		(layer "In13.Cu")
		(net "M_B_CPU0_SB_DQ<22>")
	)
	(segment
		(start 299.970952 -306.559966)
		(end 302.023526 -307.410104)
		(width 0.14478)
		(layer "In13.Cu")
		(net "M_B_CPU0_SB_DQ<22>")
	)
	(segment
		(start 334.819752 -287.528762)
		(end 334.828134 -287.533588)
		(width 0.0889)
		(layer "In13.Cu")
		(net "M_B_CPU0_SB_DQ<22>")
	)
	(segment
		(start 325.269352 -288.149792)
		(end 325.809356 -287.609788)
		(width 0.0889)
		(layer "In13.Cu")
		(net "M_B_CPU0_SB_DQ<22>")
	)
	(segment
		(start 296.844212 -307.245766)
		(end 296.988992 -307.390546)
		(width 0.14478)
		(layer "In13.Cu")
		(net "M_B_CPU0_SB_DQ<22>")
	)
	(segment
		(start 298.48302 -306.985162)
		(end 298.908216 -306.559966)
		(width 0.14478)
		(layer "In13.Cu")
		(net "M_B_CPU0_SB_DQ<22>")
	)
	(segment
		(start 302.023526 -307.410104)
		(end 305.369722 -307.410104)
		(width 0.14478)
		(layer "In13.Cu")
		(net "M_B_CPU0_SB_DQ<22>")
	)
	(arc
		(start 330.128118 -287.533588)
		(mid 330.411074 -287.609731)
		(end 330.69403 -287.533588)
		(width 0.0889)
		(layer "In13.Cu")
		(net "M_B_CPU0_SB_DQ<22>")
	)
	(arc
		(start 333.513938 -287.533588)
		(mid 333.696189 -287.483238)
		(end 333.879698 -287.528762)
		(width 0.0889)
		(layer "In13.Cu")
		(net "M_B_CPU0_SB_DQ<22>")
	)
	(arc
		(start 328.248264 -287.533588)
		(mid 328.53122 -287.609731)
		(end 328.814176 -287.533588)
		(width 0.0889)
		(layer "In13.Cu")
		(net "M_B_CPU0_SB_DQ<22>")
	)
	(arc
		(start 335.402428 -287.528762)
		(mid 335.555298 -287.484121)
		(end 335.712816 -287.507426)
		(width 0.0889)
		(layer "In13.Cu")
		(net "M_B_CPU0_SB_DQ<22>")
	)
	(arc
		(start 329.753976 -287.533588)
		(mid 329.936227 -287.483238)
		(end 330.119736 -287.528762)
		(width 0.0889)
		(layer "In13.Cu")
		(net "M_B_CPU0_SB_DQ<22>")
	)
	(arc
		(start 327.873614 -287.533588)
		(mid 328.056119 -287.483111)
		(end 328.239882 -287.528762)
		(width 0.0889)
		(layer "In13.Cu")
		(net "M_B_CPU0_SB_DQ<22>")
	)
	(arc
		(start 332.008226 -287.533588)
		(mid 332.291182 -287.609731)
		(end 332.574138 -287.533588)
		(width 0.0889)
		(layer "In13.Cu")
		(net "M_B_CPU0_SB_DQ<22>")
	)
	(arc
		(start 334.453992 -287.533588)
		(mid 334.636243 -287.483238)
		(end 334.819752 -287.528762)
		(width 0.0889)
		(layer "In13.Cu")
		(net "M_B_CPU0_SB_DQ<22>")
	)
	(arc
		(start 329.188064 -287.533588)
		(mid 329.47102 -287.609731)
		(end 329.753976 -287.533588)
		(width 0.0889)
		(layer "In13.Cu")
		(net "M_B_CPU0_SB_DQ<22>")
	)
	(arc
		(start 330.702412 -287.528762)
		(mid 330.88592 -287.483268)
		(end 331.068172 -287.533588)
		(width 0.0889)
		(layer "In13.Cu")
		(net "M_B_CPU0_SB_DQ<22>")
	)
	(arc
		(start 326.651112 -287.609788)
		(mid 326.797638 -287.590418)
		(end 326.934068 -287.533588)
		(width 0.0889)
		(layer "In13.Cu")
		(net "M_B_CPU0_SB_DQ<22>")
	)
	(arc
		(start 326.934068 -287.533588)
		(mid 327.121012 -287.483333)
		(end 327.307956 -287.533588)
		(width 0.0889)
		(layer "In13.Cu")
		(net "M_B_CPU0_SB_DQ<22>")
	)
	(arc
		(start 334.828134 -287.533588)
		(mid 335.11109 -287.609731)
		(end 335.394046 -287.533588)
		(width 0.0889)
		(layer "In13.Cu")
		(net "M_B_CPU0_SB_DQ<22>")
	)
	(arc
		(start 328.814176 -287.533588)
		(mid 329.00112 -287.483333)
		(end 329.188064 -287.533588)
		(width 0.0889)
		(layer "In13.Cu")
		(net "M_B_CPU0_SB_DQ<22>")
	)
	(arc
		(start 332.574138 -287.533588)
		(mid 332.761082 -287.483333)
		(end 332.948026 -287.533588)
		(width 0.0889)
		(layer "In13.Cu")
		(net "M_B_CPU0_SB_DQ<22>")
	)
	(arc
		(start 333.888334 -287.533588)
		(mid 334.17118 -287.609731)
		(end 334.453992 -287.533588)
		(width 0.0889)
		(layer "In13.Cu")
		(net "M_B_CPU0_SB_DQ<22>")
	)
	(arc
		(start 331.642466 -287.528762)
		(mid 331.825974 -287.483268)
		(end 332.008226 -287.533588)
		(width 0.0889)
		(layer "In13.Cu")
		(net "M_B_CPU0_SB_DQ<22>")
	)
	(arc
		(start 331.068172 -287.533588)
		(mid 331.351128 -287.609731)
		(end 331.634084 -287.533588)
		(width 0.0889)
		(layer "In13.Cu")
		(net "M_B_CPU0_SB_DQ<22>")
	)
	(arc
		(start 332.948026 -287.533588)
		(mid 333.230982 -287.609731)
		(end 333.513938 -287.533588)
		(width 0.0889)
		(layer "In13.Cu")
		(net "M_B_CPU0_SB_DQ<22>")
	)
	(arc
		(start 327.32599 -287.544002)
		(mid 327.601148 -287.609732)
		(end 327.873614 -287.533588)
		(width 0.0889)
		(layer "In13.Cu")
		(net "M_B_CPU0_SB_DQ<22>")
	)
	(segment
		(start 337.92795 -287.59023)
		(end 337.461098 -287.856168)
		(width 0.10668)
		(layer "F.Cu")
		(net "M_B_CPU0_SB_DQ<21>")
	)
	(segment
		(start 337.211416 -288.146998)
		(end 337.307174 -288.121598)
		(width 0.0889)
		(layer "In13.Cu")
		(net "M_B_CPU0_SB_DQ<21>")
	)
	(segment
		(start 310.339486 -305.079654)
		(end 310.637174 -305.079654)
		(width 0.14478)
		(layer "In13.Cu")
		(net "M_B_CPU0_SB_DQ<21>")
	)
	(segment
		(start 303.82464 -308.260242)
		(end 303.96942 -308.115462)
		(width 0.14478)
		(layer "In13.Cu")
		(net "M_B_CPU0_SB_DQ<21>")
	)
	(segment
		(start 334.819752 -288.18332)
		(end 334.828134 -288.178494)
		(width 0.0889)
		(layer "In13.Cu")
		(net "M_B_CPU0_SB_DQ<21>")
	)
	(segment
		(start 316.577726 -298.841414)
		(end 316.875414 -298.841414)
		(width 0.14478)
		(layer "In13.Cu")
		(net "M_B_CPU0_SB_DQ<21>")
	)
	(segment
		(start 300.505622 -307.382164)
		(end 301.252636 -307.691536)
		(width 0.14478)
		(layer "In13.Cu")
		(net "M_B_CPU0_SB_DQ<21>")
	)
	(segment
		(start 315.315854 -300.400974)
		(end 315.5569 -300.159928)
		(width 0.14478)
		(layer "In13.Cu")
		(net "M_B_CPU0_SB_DQ<21>")
	)
	(segment
		(start 325.340218 -288.340292)
		(end 325.611998 -288.340292)
		(width 0.0889)
		(layer "In13.Cu")
		(net "M_B_CPU0_SB_DQ<21>")
	)
	(segment
		(start 299.82414 -307.608478)
		(end 300.050454 -307.382164)
		(width 0.14478)
		(layer "In13.Cu")
		(net "M_B_CPU0_SB_DQ<21>")
	)
	(segment
		(start 315.797946 -299.621194)
		(end 316.095634 -299.621194)
		(width 0.14478)
		(layer "In13.Cu")
		(net "M_B_CPU0_SB_DQ<21>")
	)
	(segment
		(start 315.5569 -300.159928)
		(end 315.5569 -299.86224)
		(width 0.14478)
		(layer "In13.Cu")
		(net "M_B_CPU0_SB_DQ<21>")
	)
	(segment
		(start 317.11646 -298.30268)
		(end 317.357506 -298.061634)
		(width 0.14478)
		(layer "In13.Cu")
		(net "M_B_CPU0_SB_DQ<21>")
	)
	(segment
		(start 311.899046 -303.520094)
		(end 312.196734 -303.520094)
		(width 0.14478)
		(layer "In13.Cu")
		(net "M_B_CPU0_SB_DQ<21>")
	)
	(segment
		(start 303.96942 -308.004464)
		(end 304.1142 -307.859684)
		(width 0.14478)
		(layer "In13.Cu")
		(net "M_B_CPU0_SB_DQ<21>")
	)
	(segment
		(start 335.394046 -288.178494)
		(end 335.402428 -288.18332)
		(width 0.0889)
		(layer "In13.Cu")
		(net "M_B_CPU0_SB_DQ<21>")
	)
	(segment
		(start 313.21756 -302.499268)
		(end 313.21756 -302.20158)
		(width 0.14478)
		(layer "In13.Cu")
		(net "M_B_CPU0_SB_DQ<21>")
	)
	(segment
		(start 318.452246 -297.264582)
		(end 318.452246 -295.780968)
		(width 0.14478)
		(layer "In13.Cu")
		(net "M_B_CPU0_SB_DQ<21>")
	)
	(segment
		(start 310.09844 -305.3207)
		(end 310.339486 -305.079654)
		(width 0.14478)
		(layer "In13.Cu")
		(net "M_B_CPU0_SB_DQ<21>")
	)
	(segment
		(start 313.21756 -302.20158)
		(end 313.458606 -301.960534)
		(width 0.14478)
		(layer "In13.Cu")
		(net "M_B_CPU0_SB_DQ<21>")
	)
	(segment
		(start 309.31866 -306.10048)
		(end 309.559706 -305.859434)
		(width 0.14478)
		(layer "In13.Cu")
		(net "M_B_CPU0_SB_DQ<21>")
	)
	(segment
		(start 311.658 -303.76114)
		(end 311.899046 -303.520094)
		(width 0.14478)
		(layer "In13.Cu")
		(net "M_B_CPU0_SB_DQ<21>")
	)
	(segment
		(start 310.87822 -304.54092)
		(end 311.119266 -304.299874)
		(width 0.14478)
		(layer "In13.Cu")
		(net "M_B_CPU0_SB_DQ<21>")
	)
	(segment
		(start 310.637174 -305.079654)
		(end 310.87822 -304.838608)
		(width 0.14478)
		(layer "In13.Cu")
		(net "M_B_CPU0_SB_DQ<21>")
	)
	(segment
		(start 314.77712 -300.64202)
		(end 315.018166 -300.400974)
		(width 0.14478)
		(layer "In13.Cu")
		(net "M_B_CPU0_SB_DQ<21>")
	)
	(segment
		(start 312.43778 -302.98136)
		(end 312.678826 -302.740314)
		(width 0.14478)
		(layer "In13.Cu")
		(net "M_B_CPU0_SB_DQ<21>")
	)
	(segment
		(start 323.891148 -290.342066)
		(end 324.654418 -289.578796)
		(width 0.0889)
		(layer "In13.Cu")
		(net "M_B_CPU0_SB_DQ<21>")
	)
	(segment
		(start 300.050454 -307.382164)
		(end 300.505622 -307.382164)
		(width 0.14478)
		(layer "In13.Cu")
		(net "M_B_CPU0_SB_DQ<21>")
	)
	(segment
		(start 309.559706 -305.859434)
		(end 309.857394 -305.859434)
		(width 0.14478)
		(layer "In13.Cu")
		(net "M_B_CPU0_SB_DQ<21>")
	)
	(segment
		(start 304.5206 -308.115462)
		(end 304.66538 -308.260242)
		(width 0.14478)
		(layer "In13.Cu")
		(net "M_B_CPU0_SB_DQ<21>")
	)
	(segment
		(start 309.857394 -305.859434)
		(end 310.09844 -305.618388)
		(width 0.14478)
		(layer "In13.Cu")
		(net "M_B_CPU0_SB_DQ<21>")
	)
	(segment
		(start 302.10379 -308.260242)
		(end 303.82464 -308.260242)
		(width 0.14478)
		(layer "In13.Cu")
		(net "M_B_CPU0_SB_DQ<21>")
	)
	(segment
		(start 304.66538 -308.260242)
		(end 305.369722 -308.260242)
		(width 0.14478)
		(layer "In13.Cu")
		(net "M_B_CPU0_SB_DQ<21>")
	)
	(segment
		(start 310.09844 -305.618388)
		(end 310.09844 -305.3207)
		(width 0.14478)
		(layer "In13.Cu")
		(net "M_B_CPU0_SB_DQ<21>")
	)
	(segment
		(start 316.33668 -299.380148)
		(end 316.33668 -299.08246)
		(width 0.14478)
		(layer "In13.Cu")
		(net "M_B_CPU0_SB_DQ<21>")
	)
	(segment
		(start 313.458606 -301.960534)
		(end 313.756294 -301.960534)
		(width 0.14478)
		(layer "In13.Cu")
		(net "M_B_CPU0_SB_DQ<21>")
	)
	(segment
		(start 314.238386 -301.180754)
		(end 314.536074 -301.180754)
		(width 0.14478)
		(layer "In13.Cu")
		(net "M_B_CPU0_SB_DQ<21>")
	)
	(segment
		(start 326.934068 -288.178494)
		(end 326.94245 -288.18332)
		(width 0.0889)
		(layer "In13.Cu")
		(net "M_B_CPU0_SB_DQ<21>")
	)
	(segment
		(start 314.536074 -301.180754)
		(end 314.77712 -300.939708)
		(width 0.14478)
		(layer "In13.Cu")
		(net "M_B_CPU0_SB_DQ<21>")
	)
	(segment
		(start 330.119736 -288.18332)
		(end 330.128118 -288.178494)
		(width 0.0889)
		(layer "In13.Cu")
		(net "M_B_CPU0_SB_DQ<21>")
	)
	(segment
		(start 307.42763 -307.410104)
		(end 308.928262 -306.788566)
		(width 0.14478)
		(layer "In13.Cu")
		(net "M_B_CPU0_SB_DQ<21>")
	)
	(segment
		(start 324.654418 -289.578796)
		(end 324.654418 -289.026092)
		(width 0.0889)
		(layer "In13.Cu")
		(net "M_B_CPU0_SB_DQ<21>")
	)
	(segment
		(start 312.43778 -303.279048)
		(end 312.43778 -302.98136)
		(width 0.14478)
		(layer "In13.Cu")
		(net "M_B_CPU0_SB_DQ<21>")
	)
	(segment
		(start 310.87822 -304.838608)
		(end 310.87822 -304.54092)
		(width 0.14478)
		(layer "In13.Cu")
		(net "M_B_CPU0_SB_DQ<21>")
	)
	(segment
		(start 313.99734 -301.719488)
		(end 313.99734 -301.4218)
		(width 0.14478)
		(layer "In13.Cu")
		(net "M_B_CPU0_SB_DQ<21>")
	)
	(segment
		(start 333.879698 -288.18332)
		(end 333.88808 -288.178494)
		(width 0.0889)
		(layer "In13.Cu")
		(net "M_B_CPU0_SB_DQ<21>")
	)
	(segment
		(start 304.5206 -308.004464)
		(end 304.5206 -308.115462)
		(width 0.14478)
		(layer "In13.Cu")
		(net "M_B_CPU0_SB_DQ<21>")
	)
	(segment
		(start 315.018166 -300.400974)
		(end 315.315854 -300.400974)
		(width 0.14478)
		(layer "In13.Cu")
		(net "M_B_CPU0_SB_DQ<21>")
	)
	(segment
		(start 318.452246 -295.780968)
		(end 323.891148 -290.342066)
		(width 0.14478)
		(layer "In13.Cu")
		(net "M_B_CPU0_SB_DQ<21>")
	)
	(segment
		(start 304.37582 -307.859684)
		(end 304.5206 -308.004464)
		(width 0.14478)
		(layer "In13.Cu")
		(net "M_B_CPU0_SB_DQ<21>")
	)
	(segment
		(start 312.196734 -303.520094)
		(end 312.43778 -303.279048)
		(width 0.14478)
		(layer "In13.Cu")
		(net "M_B_CPU0_SB_DQ<21>")
	)
	(segment
		(start 330.69403 -288.178494)
		(end 330.702412 -288.18332)
		(width 0.0889)
		(layer "In13.Cu")
		(net "M_B_CPU0_SB_DQ<21>")
	)
	(segment
		(start 316.095634 -299.621194)
		(end 316.33668 -299.380148)
		(width 0.14478)
		(layer "In13.Cu")
		(net "M_B_CPU0_SB_DQ<21>")
	)
	(segment
		(start 325.611998 -288.340292)
		(end 325.722742 -288.229548)
		(width 0.0889)
		(layer "In13.Cu")
		(net "M_B_CPU0_SB_DQ<21>")
	)
	(segment
		(start 303.96942 -308.115462)
		(end 303.96942 -308.004464)
		(width 0.14478)
		(layer "In13.Cu")
		(net "M_B_CPU0_SB_DQ<21>")
	)
	(segment
		(start 312.976514 -302.740314)
		(end 313.21756 -302.499268)
		(width 0.14478)
		(layer "In13.Cu")
		(net "M_B_CPU0_SB_DQ<21>")
	)
	(segment
		(start 316.33668 -299.08246)
		(end 316.577726 -298.841414)
		(width 0.14478)
		(layer "In13.Cu")
		(net "M_B_CPU0_SB_DQ<21>")
	)
	(segment
		(start 312.678826 -302.740314)
		(end 312.976514 -302.740314)
		(width 0.14478)
		(layer "In13.Cu")
		(net "M_B_CPU0_SB_DQ<21>")
	)
	(segment
		(start 309.31866 -306.398168)
		(end 309.31866 -306.10048)
		(width 0.14478)
		(layer "In13.Cu")
		(net "M_B_CPU0_SB_DQ<21>")
	)
	(segment
		(start 317.655194 -298.061634)
		(end 318.452246 -297.264582)
		(width 0.14478)
		(layer "In13.Cu")
		(net "M_B_CPU0_SB_DQ<21>")
	)
	(segment
		(start 337.307174 -288.121598)
		(end 337.461098 -287.856168)
		(width 0.0889)
		(layer "In13.Cu")
		(net "M_B_CPU0_SB_DQ<21>")
	)
	(segment
		(start 313.756294 -301.960534)
		(end 313.99734 -301.719488)
		(width 0.14478)
		(layer "In13.Cu")
		(net "M_B_CPU0_SB_DQ<21>")
	)
	(segment
		(start 331.634084 -288.178494)
		(end 331.642466 -288.18332)
		(width 0.0889)
		(layer "In13.Cu")
		(net "M_B_CPU0_SB_DQ<21>")
	)
	(segment
		(start 326.919336 -288.169858)
		(end 326.934068 -288.178494)
		(width 0.0889)
		(layer "In13.Cu")
		(net "M_B_CPU0_SB_DQ<21>")
	)
	(segment
		(start 306.21986 -307.410104)
		(end 307.42763 -307.410104)
		(width 0.14478)
		(layer "In13.Cu")
		(net "M_B_CPU0_SB_DQ<21>")
	)
	(segment
		(start 313.99734 -301.4218)
		(end 314.238386 -301.180754)
		(width 0.14478)
		(layer "In13.Cu")
		(net "M_B_CPU0_SB_DQ<21>")
	)
	(segment
		(start 336.3341 -288.178494)
		(end 336.342482 -288.18332)
		(width 0.0889)
		(layer "In13.Cu")
		(net "M_B_CPU0_SB_DQ<21>")
	)
	(segment
		(start 317.11646 -298.600368)
		(end 317.11646 -298.30268)
		(width 0.14478)
		(layer "In13.Cu")
		(net "M_B_CPU0_SB_DQ<21>")
	)
	(segment
		(start 316.875414 -298.841414)
		(end 317.11646 -298.600368)
		(width 0.14478)
		(layer "In13.Cu")
		(net "M_B_CPU0_SB_DQ<21>")
	)
	(segment
		(start 299.82414 -307.835046)
		(end 299.82414 -307.608478)
		(width 0.14478)
		(layer "In13.Cu")
		(net "M_B_CPU0_SB_DQ<21>")
	)
	(segment
		(start 301.252636 -307.691536)
		(end 302.10379 -308.260242)
		(width 0.14478)
		(layer "In13.Cu")
		(net "M_B_CPU0_SB_DQ<21>")
	)
	(segment
		(start 327.874122 -288.178494)
		(end 327.882504 -288.18332)
		(width 0.0889)
		(layer "In13.Cu")
		(net "M_B_CPU0_SB_DQ<21>")
	)
	(segment
		(start 315.5569 -299.86224)
		(end 315.797946 -299.621194)
		(width 0.14478)
		(layer "In13.Cu")
		(net "M_B_CPU0_SB_DQ<21>")
	)
	(segment
		(start 325.722742 -288.229548)
		(end 326.179942 -288.229548)
		(width 0.0889)
		(layer "In13.Cu")
		(net "M_B_CPU0_SB_DQ<21>")
	)
	(segment
		(start 317.357506 -298.061634)
		(end 317.655194 -298.061634)
		(width 0.14478)
		(layer "In13.Cu")
		(net "M_B_CPU0_SB_DQ<21>")
	)
	(segment
		(start 304.1142 -307.859684)
		(end 304.37582 -307.859684)
		(width 0.14478)
		(layer "In13.Cu")
		(net "M_B_CPU0_SB_DQ<21>")
	)
	(segment
		(start 314.77712 -300.939708)
		(end 314.77712 -300.64202)
		(width 0.14478)
		(layer "In13.Cu")
		(net "M_B_CPU0_SB_DQ<21>")
	)
	(segment
		(start 308.928262 -306.788566)
		(end 309.31866 -306.398168)
		(width 0.14478)
		(layer "In13.Cu")
		(net "M_B_CPU0_SB_DQ<21>")
	)
	(segment
		(start 311.658 -304.058828)
		(end 311.658 -303.76114)
		(width 0.14478)
		(layer "In13.Cu")
		(net "M_B_CPU0_SB_DQ<21>")
	)
	(segment
		(start 305.369722 -308.260242)
		(end 306.21986 -307.410104)
		(width 0.14478)
		(layer "In13.Cu")
		(net "M_B_CPU0_SB_DQ<21>")
	)
	(segment
		(start 311.416954 -304.299874)
		(end 311.658 -304.058828)
		(width 0.14478)
		(layer "In13.Cu")
		(net "M_B_CPU0_SB_DQ<21>")
	)
	(segment
		(start 311.119266 -304.299874)
		(end 311.416954 -304.299874)
		(width 0.14478)
		(layer "In13.Cu")
		(net "M_B_CPU0_SB_DQ<21>")
	)
	(segment
		(start 333.88808 -288.178494)
		(end 333.888334 -288.178494)
		(width 0.0889)
		(layer "In13.Cu")
		(net "M_B_CPU0_SB_DQ<21>")
	)
	(segment
		(start 324.654418 -289.026092)
		(end 325.340218 -288.340292)
		(width 0.0889)
		(layer "In13.Cu")
		(net "M_B_CPU0_SB_DQ<21>")
	)
	(arc
		(start 329.753976 -288.178494)
		(mid 329.936227 -288.228878)
		(end 330.119736 -288.18332)
		(width 0.0889)
		(layer "In13.Cu")
		(net "M_B_CPU0_SB_DQ<21>")
	)
	(arc
		(start 328.814176 -288.178494)
		(mid 329.00112 -288.228783)
		(end 329.188064 -288.178494)
		(width 0.0889)
		(layer "In13.Cu")
		(net "M_B_CPU0_SB_DQ<21>")
	)
	(arc
		(start 326.179942 -288.229548)
		(mid 326.277173 -288.216451)
		(end 326.367648 -288.178494)
		(width 0.0889)
		(layer "In13.Cu")
		(net "M_B_CPU0_SB_DQ<21>")
	)
	(arc
		(start 329.188064 -288.178494)
		(mid 329.47102 -288.102317)
		(end 329.753976 -288.178494)
		(width 0.0889)
		(layer "In13.Cu")
		(net "M_B_CPU0_SB_DQ<21>")
	)
	(arc
		(start 327.30821 -288.178494)
		(mid 327.591166 -288.102317)
		(end 327.874122 -288.178494)
		(width 0.0889)
		(layer "In13.Cu")
		(net "M_B_CPU0_SB_DQ<21>")
	)
	(arc
		(start 335.402428 -288.18332)
		(mid 335.585936 -288.228845)
		(end 335.768188 -288.178494)
		(width 0.0889)
		(layer "In13.Cu")
		(net "M_B_CPU0_SB_DQ<21>")
	)
	(arc
		(start 336.342482 -288.18332)
		(mid 336.52599 -288.228845)
		(end 336.708242 -288.178494)
		(width 0.0889)
		(layer "In13.Cu")
		(net "M_B_CPU0_SB_DQ<21>")
	)
	(arc
		(start 333.513938 -288.178494)
		(mid 333.696189 -288.228878)
		(end 333.879698 -288.18332)
		(width 0.0889)
		(layer "In13.Cu")
		(net "M_B_CPU0_SB_DQ<21>")
	)
	(arc
		(start 327.882504 -288.18332)
		(mid 328.066012 -288.228845)
		(end 328.248264 -288.178494)
		(width 0.0889)
		(layer "In13.Cu")
		(net "M_B_CPU0_SB_DQ<21>")
	)
	(arc
		(start 328.248264 -288.178494)
		(mid 328.53122 -288.102317)
		(end 328.814176 -288.178494)
		(width 0.0889)
		(layer "In13.Cu")
		(net "M_B_CPU0_SB_DQ<21>")
	)
	(arc
		(start 332.948026 -288.178494)
		(mid 333.230982 -288.102317)
		(end 333.513938 -288.178494)
		(width 0.0889)
		(layer "In13.Cu")
		(net "M_B_CPU0_SB_DQ<21>")
	)
	(arc
		(start 333.888334 -288.178494)
		(mid 334.17118 -288.102283)
		(end 334.453992 -288.178494)
		(width 0.0889)
		(layer "In13.Cu")
		(net "M_B_CPU0_SB_DQ<21>")
	)
	(arc
		(start 326.94245 -288.18332)
		(mid 327.125958 -288.228845)
		(end 327.30821 -288.178494)
		(width 0.0889)
		(layer "In13.Cu")
		(net "M_B_CPU0_SB_DQ<21>")
	)
	(arc
		(start 332.008226 -288.178494)
		(mid 332.291182 -288.102317)
		(end 332.574138 -288.178494)
		(width 0.0889)
		(layer "In13.Cu")
		(net "M_B_CPU0_SB_DQ<21>")
	)
	(arc
		(start 332.574138 -288.178494)
		(mid 332.761082 -288.228783)
		(end 332.948026 -288.178494)
		(width 0.0889)
		(layer "In13.Cu")
		(net "M_B_CPU0_SB_DQ<21>")
	)
	(arc
		(start 334.828134 -288.178494)
		(mid 335.11109 -288.102317)
		(end 335.394046 -288.178494)
		(width 0.0889)
		(layer "In13.Cu")
		(net "M_B_CPU0_SB_DQ<21>")
	)
	(arc
		(start 335.768188 -288.178494)
		(mid 336.051144 -288.102317)
		(end 336.3341 -288.178494)
		(width 0.0889)
		(layer "In13.Cu")
		(net "M_B_CPU0_SB_DQ<21>")
	)
	(arc
		(start 326.367648 -288.178494)
		(mid 326.642354 -288.10213)
		(end 326.919336 -288.169858)
		(width 0.0889)
		(layer "In13.Cu")
		(net "M_B_CPU0_SB_DQ<21>")
	)
	(arc
		(start 330.702412 -288.18332)
		(mid 330.88592 -288.228845)
		(end 331.068172 -288.178494)
		(width 0.0889)
		(layer "In13.Cu")
		(net "M_B_CPU0_SB_DQ<21>")
	)
	(arc
		(start 331.068172 -288.178494)
		(mid 331.351128 -288.102317)
		(end 331.634084 -288.178494)
		(width 0.0889)
		(layer "In13.Cu")
		(net "M_B_CPU0_SB_DQ<21>")
	)
	(arc
		(start 336.708242 -288.178494)
		(mid 336.956102 -288.103411)
		(end 337.211416 -288.146998)
		(width 0.0889)
		(layer "In13.Cu")
		(net "M_B_CPU0_SB_DQ<21>")
	)
	(arc
		(start 331.642466 -288.18332)
		(mid 331.825974 -288.228845)
		(end 332.008226 -288.178494)
		(width 0.0889)
		(layer "In13.Cu")
		(net "M_B_CPU0_SB_DQ<21>")
	)
	(arc
		(start 330.128118 -288.178494)
		(mid 330.411074 -288.102317)
		(end 330.69403 -288.178494)
		(width 0.0889)
		(layer "In13.Cu")
		(net "M_B_CPU0_SB_DQ<21>")
	)
	(arc
		(start 334.453992 -288.178494)
		(mid 334.636243 -288.228878)
		(end 334.819752 -288.18332)
		(width 0.0889)
		(layer "In13.Cu")
		(net "M_B_CPU0_SB_DQ<21>")
	)
	(segment
		(start 336.517996 -286.780224)
		(end 336.051144 -287.045908)
		(width 0.10668)
		(layer "F.Cu")
		(net "M_B_CPU0_SB_DQ<20>")
	)
	(segment
		(start 303.156112 -306.410868)
		(end 303.156112 -306.789836)
		(width 0.14478)
		(layer "In13.Cu")
		(net "M_B_CPU0_SB_DQ<20>")
	)
	(segment
		(start 329.284076 -287.368488)
		(end 329.292458 -287.373314)
		(width 0.0889)
		(layer "In13.Cu")
		(net "M_B_CPU0_SB_DQ<20>")
	)
	(segment
		(start 305.444906 -306.487068)
		(end 305.28895 -306.331112)
		(width 0.14478)
		(layer "In13.Cu")
		(net "M_B_CPU0_SB_DQ<20>")
	)
	(segment
		(start 328.709782 -287.373314)
		(end 328.718164 -287.368488)
		(width 0.0889)
		(layer "In13.Cu")
		(net "M_B_CPU0_SB_DQ<20>")
	)
	(segment
		(start 303.300892 -306.934616)
		(end 303.562512 -306.934616)
		(width 0.14478)
		(layer "In13.Cu")
		(net "M_B_CPU0_SB_DQ<20>")
	)
	(segment
		(start 323.926454 -289.020504)
		(end 324.987666 -287.959292)
		(width 0.0889)
		(layer "In13.Cu")
		(net "M_B_CPU0_SB_DQ<20>")
	)
	(segment
		(start 303.156112 -306.789836)
		(end 303.300892 -306.934616)
		(width 0.14478)
		(layer "In13.Cu")
		(net "M_B_CPU0_SB_DQ<20>")
	)
	(segment
		(start 305.444906 -306.691792)
		(end 305.444906 -306.487068)
		(width 0.14478)
		(layer "In13.Cu")
		(net "M_B_CPU0_SB_DQ<20>")
	)
	(segment
		(start 317.553086 -296.593514)
		(end 317.553086 -295.393872)
		(width 0.14478)
		(layer "In13.Cu")
		(net "M_B_CPU0_SB_DQ<20>")
	)
	(segment
		(start 303.852072 -306.266088)
		(end 304.113692 -306.266088)
		(width 0.14478)
		(layer "In13.Cu")
		(net "M_B_CPU0_SB_DQ<20>")
	)
	(segment
		(start 307.448966 -305.367944)
		(end 307.448966 -305.925728)
		(width 0.14478)
		(layer "In13.Cu")
		(net "M_B_CPU0_SB_DQ<20>")
	)
	(segment
		(start 306.859178 -305.61026)
		(end 306.79517 -305.546252)
		(width 0.14478)
		(layer "In13.Cu")
		(net "M_B_CPU0_SB_DQ<20>")
	)
	(segment
		(start 325.730362 -287.419288)
		(end 326.650858 -287.419288)
		(width 0.0889)
		(layer "In13.Cu")
		(net "M_B_CPU0_SB_DQ<20>")
	)
	(segment
		(start 306.79517 -305.341528)
		(end 306.913534 -305.223164)
		(width 0.14478)
		(layer "In13.Cu")
		(net "M_B_CPU0_SB_DQ<20>")
	)
	(segment
		(start 332.469744 -287.373314)
		(end 332.478126 -287.368488)
		(width 0.0889)
		(layer "In13.Cu")
		(net "M_B_CPU0_SB_DQ<20>")
	)
	(segment
		(start 305.834796 -306.097178)
		(end 306.03952 -306.097178)
		(width 0.14478)
		(layer "In13.Cu")
		(net "M_B_CPU0_SB_DQ<20>")
	)
	(segment
		(start 306.674012 -306.00015)
		(end 306.859178 -305.814984)
		(width 0.14478)
		(layer "In13.Cu")
		(net "M_B_CPU0_SB_DQ<20>")
	)
	(segment
		(start 308.000146 -305.367944)
		(end 308.144926 -305.223164)
		(width 0.14478)
		(layer "In13.Cu")
		(net "M_B_CPU0_SB_DQ<20>")
	)
	(segment
		(start 307.593746 -306.070508)
		(end 307.855366 -306.070508)
		(width 0.14478)
		(layer "In13.Cu")
		(net "M_B_CPU0_SB_DQ<20>")
	)
	(segment
		(start 308.000146 -305.925728)
		(end 308.000146 -305.367944)
		(width 0.14478)
		(layer "In13.Cu")
		(net "M_B_CPU0_SB_DQ<20>")
	)
	(segment
		(start 304.258472 -306.789836)
		(end 304.403252 -306.934616)
		(width 0.14478)
		(layer "In13.Cu")
		(net "M_B_CPU0_SB_DQ<20>")
	)
	(segment
		(start 302.749712 -306.266088)
		(end 303.011332 -306.266088)
		(width 0.14478)
		(layer "In13.Cu")
		(net "M_B_CPU0_SB_DQ<20>")
	)
	(segment
		(start 325.190358 -287.959292)
		(end 325.730362 -287.419288)
		(width 0.0889)
		(layer "In13.Cu")
		(net "M_B_CPU0_SB_DQ<20>")
	)
	(segment
		(start 306.03952 -306.097178)
		(end 306.200556 -305.936142)
		(width 0.14478)
		(layer "In13.Cu")
		(net "M_B_CPU0_SB_DQ<20>")
	)
	(segment
		(start 305.67884 -305.941222)
		(end 305.834796 -306.097178)
		(width 0.14478)
		(layer "In13.Cu")
		(net "M_B_CPU0_SB_DQ<20>")
	)
	(segment
		(start 306.913534 -305.223164)
		(end 307.304186 -305.223164)
		(width 0.14478)
		(layer "In13.Cu")
		(net "M_B_CPU0_SB_DQ<20>")
	)
	(segment
		(start 302.604932 -306.410868)
		(end 302.749712 -306.266088)
		(width 0.14478)
		(layer "In13.Cu")
		(net "M_B_CPU0_SB_DQ<20>")
	)
	(segment
		(start 307.448966 -305.925728)
		(end 307.593746 -306.070508)
		(width 0.14478)
		(layer "In13.Cu")
		(net "M_B_CPU0_SB_DQ<20>")
	)
	(segment
		(start 302.460152 -306.934616)
		(end 302.604932 -306.789836)
		(width 0.14478)
		(layer "In13.Cu")
		(net "M_B_CPU0_SB_DQ<20>")
	)
	(segment
		(start 304.258472 -306.410868)
		(end 304.258472 -306.789836)
		(width 0.14478)
		(layer "In13.Cu")
		(net "M_B_CPU0_SB_DQ<20>")
	)
	(segment
		(start 303.707292 -306.789836)
		(end 303.707292 -306.410868)
		(width 0.14478)
		(layer "In13.Cu")
		(net "M_B_CPU0_SB_DQ<20>")
	)
	(segment
		(start 333.984092 -287.368488)
		(end 333.992474 -287.373314)
		(width 0.0889)
		(layer "In13.Cu")
		(net "M_B_CPU0_SB_DQ<20>")
	)
	(segment
		(start 306.469288 -306.00015)
		(end 306.674012 -306.00015)
		(width 0.14478)
		(layer "In13.Cu")
		(net "M_B_CPU0_SB_DQ<20>")
	)
	(segment
		(start 303.707292 -306.410868)
		(end 303.852072 -306.266088)
		(width 0.14478)
		(layer "In13.Cu")
		(net "M_B_CPU0_SB_DQ<20>")
	)
	(segment
		(start 328.333608 -287.362392)
		(end 328.344022 -287.368488)
		(width 0.0889)
		(layer "In13.Cu")
		(net "M_B_CPU0_SB_DQ<20>")
	)
	(segment
		(start 299.82414 -306.135024)
		(end 300.12767 -305.831494)
		(width 0.14478)
		(layer "In13.Cu")
		(net "M_B_CPU0_SB_DQ<20>")
	)
	(segment
		(start 303.562512 -306.934616)
		(end 303.707292 -306.789836)
		(width 0.14478)
		(layer "In13.Cu")
		(net "M_B_CPU0_SB_DQ<20>")
	)
	(segment
		(start 335.896966 -287.311338)
		(end 336.051144 -287.045908)
		(width 0.0889)
		(layer "In13.Cu")
		(net "M_B_CPU0_SB_DQ<20>")
	)
	(segment
		(start 306.859178 -305.814984)
		(end 306.859178 -305.61026)
		(width 0.14478)
		(layer "In13.Cu")
		(net "M_B_CPU0_SB_DQ<20>")
	)
	(segment
		(start 308.923436 -305.223164)
		(end 317.553086 -296.593514)
		(width 0.14478)
		(layer "In13.Cu")
		(net "M_B_CPU0_SB_DQ<20>")
	)
	(segment
		(start 306.40528 -305.936142)
		(end 306.469288 -306.00015)
		(width 0.14478)
		(layer "In13.Cu")
		(net "M_B_CPU0_SB_DQ<20>")
	)
	(segment
		(start 307.304186 -305.223164)
		(end 307.448966 -305.367944)
		(width 0.14478)
		(layer "In13.Cu")
		(net "M_B_CPU0_SB_DQ<20>")
	)
	(segment
		(start 327.40346 -287.368488)
		(end 327.415144 -287.375346)
		(width 0.0889)
		(layer "In13.Cu")
		(net "M_B_CPU0_SB_DQ<20>")
	)
	(segment
		(start 302.05045 -306.934616)
		(end 302.460152 -306.934616)
		(width 0.14478)
		(layer "In13.Cu")
		(net "M_B_CPU0_SB_DQ<20>")
	)
	(segment
		(start 305.28895 -306.126388)
		(end 305.474116 -305.941222)
		(width 0.14478)
		(layer "In13.Cu")
		(net "M_B_CPU0_SB_DQ<20>")
	)
	(segment
		(start 300.947328 -305.831494)
		(end 302.05045 -306.934616)
		(width 0.14478)
		(layer "In13.Cu")
		(net "M_B_CPU0_SB_DQ<20>")
	)
	(segment
		(start 308.144926 -305.223164)
		(end 308.923436 -305.223164)
		(width 0.14478)
		(layer "In13.Cu")
		(net "M_B_CPU0_SB_DQ<20>")
	)
	(segment
		(start 302.604932 -306.789836)
		(end 302.604932 -306.410868)
		(width 0.14478)
		(layer "In13.Cu")
		(net "M_B_CPU0_SB_DQ<20>")
	)
	(segment
		(start 305.202082 -306.934616)
		(end 305.444906 -306.691792)
		(width 0.14478)
		(layer "In13.Cu")
		(net "M_B_CPU0_SB_DQ<20>")
	)
	(segment
		(start 305.474116 -305.941222)
		(end 305.67884 -305.941222)
		(width 0.14478)
		(layer "In13.Cu")
		(net "M_B_CPU0_SB_DQ<20>")
	)
	(segment
		(start 327.388728 -287.359852)
		(end 327.40346 -287.368488)
		(width 0.0889)
		(layer "In13.Cu")
		(net "M_B_CPU0_SB_DQ<20>")
	)
	(segment
		(start 306.200556 -305.936142)
		(end 306.40528 -305.936142)
		(width 0.14478)
		(layer "In13.Cu")
		(net "M_B_CPU0_SB_DQ<20>")
	)
	(segment
		(start 305.28895 -306.331112)
		(end 305.28895 -306.126388)
		(width 0.14478)
		(layer "In13.Cu")
		(net "M_B_CPU0_SB_DQ<20>")
	)
	(segment
		(start 333.044038 -287.368488)
		(end 333.05242 -287.373314)
		(width 0.0889)
		(layer "In13.Cu")
		(net "M_B_CPU0_SB_DQ<20>")
	)
	(segment
		(start 304.113692 -306.266088)
		(end 304.258472 -306.410868)
		(width 0.14478)
		(layer "In13.Cu")
		(net "M_B_CPU0_SB_DQ<20>")
	)
	(segment
		(start 335.8007 -287.336738)
		(end 335.896966 -287.311338)
		(width 0.0889)
		(layer "In13.Cu")
		(net "M_B_CPU0_SB_DQ<20>")
	)
	(segment
		(start 307.855366 -306.070508)
		(end 308.000146 -305.925728)
		(width 0.14478)
		(layer "In13.Cu")
		(net "M_B_CPU0_SB_DQ<20>")
	)
	(segment
		(start 306.79517 -305.546252)
		(end 306.79517 -305.341528)
		(width 0.14478)
		(layer "In13.Cu")
		(net "M_B_CPU0_SB_DQ<20>")
	)
	(segment
		(start 303.011332 -306.266088)
		(end 303.156112 -306.410868)
		(width 0.14478)
		(layer "In13.Cu")
		(net "M_B_CPU0_SB_DQ<20>")
	)
	(segment
		(start 324.987666 -287.959292)
		(end 325.190358 -287.959292)
		(width 0.0889)
		(layer "In13.Cu")
		(net "M_B_CPU0_SB_DQ<20>")
	)
	(segment
		(start 317.553086 -295.393872)
		(end 323.926454 -289.020504)
		(width 0.14478)
		(layer "In13.Cu")
		(net "M_B_CPU0_SB_DQ<20>")
	)
	(segment
		(start 300.12767 -305.831494)
		(end 300.947328 -305.831494)
		(width 0.14478)
		(layer "In13.Cu")
		(net "M_B_CPU0_SB_DQ<20>")
	)
	(segment
		(start 304.403252 -306.934616)
		(end 305.202082 -306.934616)
		(width 0.14478)
		(layer "In13.Cu")
		(net "M_B_CPU0_SB_DQ<20>")
	)
	(segment
		(start 331.52969 -287.373314)
		(end 331.538072 -287.368488)
		(width 0.0889)
		(layer "In13.Cu")
		(net "M_B_CPU0_SB_DQ<20>")
	)
	(arc
		(start 331.16393 -287.368488)
		(mid 331.346181 -287.418838)
		(end 331.52969 -287.373314)
		(width 0.0889)
		(layer "In13.Cu")
		(net "M_B_CPU0_SB_DQ<20>")
	)
	(arc
		(start 334.924146 -287.368488)
		(mid 335.11109 -287.418743)
		(end 335.298034 -287.368488)
		(width 0.0889)
		(layer "In13.Cu")
		(net "M_B_CPU0_SB_DQ<20>")
	)
	(arc
		(start 330.22413 -287.368488)
		(mid 330.411074 -287.418743)
		(end 330.598018 -287.368488)
		(width 0.0889)
		(layer "In13.Cu")
		(net "M_B_CPU0_SB_DQ<20>")
	)
	(arc
		(start 333.992474 -287.373314)
		(mid 334.175982 -287.418808)
		(end 334.358234 -287.368488)
		(width 0.0889)
		(layer "In13.Cu")
		(net "M_B_CPU0_SB_DQ<20>")
	)
	(arc
		(start 335.298034 -287.368488)
		(mid 335.545631 -287.293344)
		(end 335.8007 -287.336738)
		(width 0.0889)
		(layer "In13.Cu")
		(net "M_B_CPU0_SB_DQ<20>")
	)
	(arc
		(start 328.718164 -287.368488)
		(mid 329.00112 -287.292345)
		(end 329.284076 -287.368488)
		(width 0.0889)
		(layer "In13.Cu")
		(net "M_B_CPU0_SB_DQ<20>")
	)
	(arc
		(start 329.292458 -287.373314)
		(mid 329.475966 -287.418808)
		(end 329.658218 -287.368488)
		(width 0.0889)
		(layer "In13.Cu")
		(net "M_B_CPU0_SB_DQ<20>")
	)
	(arc
		(start 333.41818 -287.368488)
		(mid 333.701136 -287.292345)
		(end 333.984092 -287.368488)
		(width 0.0889)
		(layer "In13.Cu")
		(net "M_B_CPU0_SB_DQ<20>")
	)
	(arc
		(start 329.658218 -287.368488)
		(mid 329.941174 -287.292345)
		(end 330.22413 -287.368488)
		(width 0.0889)
		(layer "In13.Cu")
		(net "M_B_CPU0_SB_DQ<20>")
	)
	(arc
		(start 332.478126 -287.368488)
		(mid 332.761082 -287.292345)
		(end 333.044038 -287.368488)
		(width 0.0889)
		(layer "In13.Cu")
		(net "M_B_CPU0_SB_DQ<20>")
	)
	(arc
		(start 327.415144 -287.375346)
		(mid 327.597399 -287.418999)
		(end 327.777856 -287.368488)
		(width 0.0889)
		(layer "In13.Cu")
		(net "M_B_CPU0_SB_DQ<20>")
	)
	(arc
		(start 332.103984 -287.368488)
		(mid 332.286235 -287.418838)
		(end 332.469744 -287.373314)
		(width 0.0889)
		(layer "In13.Cu")
		(net "M_B_CPU0_SB_DQ<20>")
	)
	(arc
		(start 334.358234 -287.368488)
		(mid 334.64119 -287.292345)
		(end 334.924146 -287.368488)
		(width 0.0889)
		(layer "In13.Cu")
		(net "M_B_CPU0_SB_DQ<20>")
	)
	(arc
		(start 330.598018 -287.368488)
		(mid 330.880974 -287.292345)
		(end 331.16393 -287.368488)
		(width 0.0889)
		(layer "In13.Cu")
		(net "M_B_CPU0_SB_DQ<20>")
	)
	(arc
		(start 327.777856 -287.368488)
		(mid 328.054923 -287.292251)
		(end 328.333608 -287.362392)
		(width 0.0889)
		(layer "In13.Cu")
		(net "M_B_CPU0_SB_DQ<20>")
	)
	(arc
		(start 328.344022 -287.368488)
		(mid 328.526273 -287.418838)
		(end 328.709782 -287.373314)
		(width 0.0889)
		(layer "In13.Cu")
		(net "M_B_CPU0_SB_DQ<20>")
	)
	(arc
		(start 331.538072 -287.368488)
		(mid 331.821028 -287.292345)
		(end 332.103984 -287.368488)
		(width 0.0889)
		(layer "In13.Cu")
		(net "M_B_CPU0_SB_DQ<20>")
	)
	(arc
		(start 326.650858 -287.419288)
		(mid 326.747816 -287.406265)
		(end 326.838056 -287.368488)
		(width 0.0889)
		(layer "In13.Cu")
		(net "M_B_CPU0_SB_DQ<20>")
	)
	(arc
		(start 326.838056 -287.368488)
		(mid 327.112254 -287.292413)
		(end 327.388728 -287.359852)
		(width 0.0889)
		(layer "In13.Cu")
		(net "M_B_CPU0_SB_DQ<20>")
	)
	(arc
		(start 333.05242 -287.373314)
		(mid 333.235928 -287.418808)
		(end 333.41818 -287.368488)
		(width 0.0889)
		(layer "In13.Cu")
		(net "M_B_CPU0_SB_DQ<20>")
	)
	(segment
		(start 337.92795 -274.630134)
		(end 337.461098 -274.896072)
		(width 0.10668)
		(layer "F.Cu")
		(net "M_B_CPU0_SB_DQ<1>")
	)
	(segment
		(start 304.43551 -282.823412)
		(end 304.597054 -282.984956)
		(width 0.14478)
		(layer "In13.Cu")
		(net "M_B_CPU0_SB_DQ<1>")
	)
	(segment
		(start 304.04562 -283.448506)
		(end 304.04562 -282.984956)
		(width 0.14478)
		(layer "In13.Cu")
		(net "M_B_CPU0_SB_DQ<1>")
	)
	(segment
		(start 335.394046 -275.218652)
		(end 335.402428 -275.223478)
		(width 0.0889)
		(layer "In13.Cu")
		(net "M_B_CPU0_SB_DQ<1>")
	)
	(segment
		(start 302.735996 -283.448506)
		(end 302.89754 -283.61005)
		(width 0.14478)
		(layer "In13.Cu")
		(net "M_B_CPU0_SB_DQ<1>")
	)
	(segment
		(start 330.119736 -275.223478)
		(end 330.128118 -275.218652)
		(width 0.0889)
		(layer "In13.Cu")
		(net "M_B_CPU0_SB_DQ<1>")
	)
	(segment
		(start 324.413118 -274.047712)
		(end 325.325232 -274.047712)
		(width 0.0889)
		(layer "In13.Cu")
		(net "M_B_CPU0_SB_DQ<1>")
	)
	(segment
		(start 302.184562 -283.152596)
		(end 302.346106 -282.991052)
		(width 0.14478)
		(layer "In13.Cu")
		(net "M_B_CPU0_SB_DQ<1>")
	)
	(segment
		(start 337.307174 -275.161502)
		(end 337.461098 -274.896072)
		(width 0.0889)
		(layer "In13.Cu")
		(net "M_B_CPU0_SB_DQ<1>")
	)
	(segment
		(start 302.89754 -283.61005)
		(end 303.884076 -283.61005)
		(width 0.14478)
		(layer "In13.Cu")
		(net "M_B_CPU0_SB_DQ<1>")
	)
	(segment
		(start 304.758598 -283.61005)
		(end 304.924714 -283.61005)
		(width 0.14478)
		(layer "In13.Cu")
		(net "M_B_CPU0_SB_DQ<1>")
	)
	(segment
		(start 306.578 -282.741116)
		(end 306.578 -283.01569)
		(width 0.14478)
		(layer "In13.Cu")
		(net "M_B_CPU0_SB_DQ<1>")
	)
	(segment
		(start 304.207164 -282.823412)
		(end 304.43551 -282.823412)
		(width 0.14478)
		(layer "In13.Cu")
		(net "M_B_CPU0_SB_DQ<1>")
	)
	(segment
		(start 301.006256 -282.759912)
		(end 301.856394 -283.61005)
		(width 0.14478)
		(layer "In13.Cu")
		(net "M_B_CPU0_SB_DQ<1>")
	)
	(segment
		(start 324.33133 -274.1295)
		(end 324.413118 -274.047712)
		(width 0.0889)
		(layer "In13.Cu")
		(net "M_B_CPU0_SB_DQ<1>")
	)
	(segment
		(start 337.211162 -275.186902)
		(end 337.307174 -275.161502)
		(width 0.0889)
		(layer "In13.Cu")
		(net "M_B_CPU0_SB_DQ<1>")
	)
	(segment
		(start 325.325232 -274.047712)
		(end 326.419718 -275.142198)
		(width 0.0889)
		(layer "In13.Cu")
		(net "M_B_CPU0_SB_DQ<1>")
	)
	(segment
		(start 331.634084 -275.218652)
		(end 331.642466 -275.223478)
		(width 0.0889)
		(layer "In13.Cu")
		(net "M_B_CPU0_SB_DQ<1>")
	)
	(segment
		(start 302.574452 -282.991052)
		(end 302.735996 -283.152596)
		(width 0.14478)
		(layer "In13.Cu")
		(net "M_B_CPU0_SB_DQ<1>")
	)
	(segment
		(start 302.346106 -282.991052)
		(end 302.574452 -282.991052)
		(width 0.14478)
		(layer "In13.Cu")
		(net "M_B_CPU0_SB_DQ<1>")
	)
	(segment
		(start 302.023018 -283.61005)
		(end 302.184562 -283.448506)
		(width 0.14478)
		(layer "In13.Cu")
		(net "M_B_CPU0_SB_DQ<1>")
	)
	(segment
		(start 304.597054 -283.448506)
		(end 304.758598 -283.61005)
		(width 0.14478)
		(layer "In13.Cu")
		(net "M_B_CPU0_SB_DQ<1>")
	)
	(segment
		(start 316.16142 -274.1295)
		(end 324.141084 -274.1295)
		(width 0.14478)
		(layer "In13.Cu")
		(net "M_B_CPU0_SB_DQ<1>")
	)
	(segment
		(start 299.82414 -283.166312)
		(end 300.23054 -282.759912)
		(width 0.14478)
		(layer "In13.Cu")
		(net "M_B_CPU0_SB_DQ<1>")
	)
	(segment
		(start 303.884076 -283.61005)
		(end 304.04562 -283.448506)
		(width 0.14478)
		(layer "In13.Cu")
		(net "M_B_CPU0_SB_DQ<1>")
	)
	(segment
		(start 301.856394 -283.61005)
		(end 302.023018 -283.61005)
		(width 0.14478)
		(layer "In13.Cu")
		(net "M_B_CPU0_SB_DQ<1>")
	)
	(segment
		(start 306.02682 -283.01569)
		(end 306.02682 -282.741116)
		(width 0.14478)
		(layer "In13.Cu")
		(net "M_B_CPU0_SB_DQ<1>")
	)
	(segment
		(start 304.597054 -282.984956)
		(end 304.597054 -283.448506)
		(width 0.14478)
		(layer "In13.Cu")
		(net "M_B_CPU0_SB_DQ<1>")
	)
	(segment
		(start 336.3341 -275.218652)
		(end 336.342482 -275.223478)
		(width 0.0889)
		(layer "In13.Cu")
		(net "M_B_CPU0_SB_DQ<1>")
	)
	(segment
		(start 333.879698 -275.223478)
		(end 333.88808 -275.218652)
		(width 0.0889)
		(layer "In13.Cu")
		(net "M_B_CPU0_SB_DQ<1>")
	)
	(segment
		(start 302.735996 -283.152596)
		(end 302.735996 -283.448506)
		(width 0.14478)
		(layer "In13.Cu")
		(net "M_B_CPU0_SB_DQ<1>")
	)
	(segment
		(start 306.72278 -283.16047)
		(end 307.13045 -283.16047)
		(width 0.14478)
		(layer "In13.Cu")
		(net "M_B_CPU0_SB_DQ<1>")
	)
	(segment
		(start 307.13045 -283.16047)
		(end 316.16142 -274.1295)
		(width 0.14478)
		(layer "In13.Cu")
		(net "M_B_CPU0_SB_DQ<1>")
	)
	(segment
		(start 330.69403 -275.218652)
		(end 330.702412 -275.223478)
		(width 0.0889)
		(layer "In13.Cu")
		(net "M_B_CPU0_SB_DQ<1>")
	)
	(segment
		(start 306.02682 -282.741116)
		(end 306.1716 -282.596336)
		(width 0.14478)
		(layer "In13.Cu")
		(net "M_B_CPU0_SB_DQ<1>")
	)
	(segment
		(start 324.141084 -274.1295)
		(end 324.33133 -274.1295)
		(width 0.0889)
		(layer "In13.Cu")
		(net "M_B_CPU0_SB_DQ<1>")
	)
	(segment
		(start 306.1716 -282.596336)
		(end 306.43322 -282.596336)
		(width 0.14478)
		(layer "In13.Cu")
		(net "M_B_CPU0_SB_DQ<1>")
	)
	(segment
		(start 304.04562 -282.984956)
		(end 304.207164 -282.823412)
		(width 0.14478)
		(layer "In13.Cu")
		(net "M_B_CPU0_SB_DQ<1>")
	)
	(segment
		(start 333.88808 -275.218652)
		(end 333.888334 -275.218652)
		(width 0.0889)
		(layer "In13.Cu")
		(net "M_B_CPU0_SB_DQ<1>")
	)
	(segment
		(start 306.43322 -282.596336)
		(end 306.578 -282.741116)
		(width 0.14478)
		(layer "In13.Cu")
		(net "M_B_CPU0_SB_DQ<1>")
	)
	(segment
		(start 305.88204 -283.16047)
		(end 306.02682 -283.01569)
		(width 0.14478)
		(layer "In13.Cu")
		(net "M_B_CPU0_SB_DQ<1>")
	)
	(segment
		(start 334.819752 -275.223478)
		(end 334.828134 -275.218652)
		(width 0.0889)
		(layer "In13.Cu")
		(net "M_B_CPU0_SB_DQ<1>")
	)
	(segment
		(start 326.419718 -275.142198)
		(end 327.59015 -275.142198)
		(width 0.0889)
		(layer "In13.Cu")
		(net "M_B_CPU0_SB_DQ<1>")
	)
	(segment
		(start 300.23054 -282.759912)
		(end 301.006256 -282.759912)
		(width 0.14478)
		(layer "In13.Cu")
		(net "M_B_CPU0_SB_DQ<1>")
	)
	(segment
		(start 328.239882 -275.223478)
		(end 328.248264 -275.218652)
		(width 0.0889)
		(layer "In13.Cu")
		(net "M_B_CPU0_SB_DQ<1>")
	)
	(segment
		(start 306.578 -283.01569)
		(end 306.72278 -283.16047)
		(width 0.14478)
		(layer "In13.Cu")
		(net "M_B_CPU0_SB_DQ<1>")
	)
	(segment
		(start 302.184562 -283.448506)
		(end 302.184562 -283.152596)
		(width 0.14478)
		(layer "In13.Cu")
		(net "M_B_CPU0_SB_DQ<1>")
	)
	(segment
		(start 304.924714 -283.61005)
		(end 305.374294 -283.16047)
		(width 0.14478)
		(layer "In13.Cu")
		(net "M_B_CPU0_SB_DQ<1>")
	)
	(segment
		(start 305.374294 -283.16047)
		(end 305.88204 -283.16047)
		(width 0.14478)
		(layer "In13.Cu")
		(net "M_B_CPU0_SB_DQ<1>")
	)
	(segment
		(start 299.82414 -283.185108)
		(end 299.82414 -283.166312)
		(width 0.14478)
		(layer "In13.Cu")
		(net "M_B_CPU0_SB_DQ<1>")
	)
	(arc
		(start 331.068172 -275.218652)
		(mid 331.351128 -275.142475)
		(end 331.634084 -275.218652)
		(width 0.0889)
		(layer "In13.Cu")
		(net "M_B_CPU0_SB_DQ<1>")
	)
	(arc
		(start 329.753976 -275.218652)
		(mid 329.936227 -275.269002)
		(end 330.119736 -275.223478)
		(width 0.0889)
		(layer "In13.Cu")
		(net "M_B_CPU0_SB_DQ<1>")
	)
	(arc
		(start 336.342482 -275.223478)
		(mid 336.52599 -275.268972)
		(end 336.708242 -275.218652)
		(width 0.0889)
		(layer "In13.Cu")
		(net "M_B_CPU0_SB_DQ<1>")
	)
	(arc
		(start 334.828134 -275.218652)
		(mid 335.11109 -275.142475)
		(end 335.394046 -275.218652)
		(width 0.0889)
		(layer "In13.Cu")
		(net "M_B_CPU0_SB_DQ<1>")
	)
	(arc
		(start 332.008226 -275.218652)
		(mid 332.291182 -275.142475)
		(end 332.574138 -275.218652)
		(width 0.0889)
		(layer "In13.Cu")
		(net "M_B_CPU0_SB_DQ<1>")
	)
	(arc
		(start 327.873614 -275.218652)
		(mid 328.056119 -275.269129)
		(end 328.239882 -275.223478)
		(width 0.0889)
		(layer "In13.Cu")
		(net "M_B_CPU0_SB_DQ<1>")
	)
	(arc
		(start 331.642466 -275.223478)
		(mid 331.825974 -275.268972)
		(end 332.008226 -275.218652)
		(width 0.0889)
		(layer "In13.Cu")
		(net "M_B_CPU0_SB_DQ<1>")
	)
	(arc
		(start 330.702412 -275.223478)
		(mid 330.88592 -275.268972)
		(end 331.068172 -275.218652)
		(width 0.0889)
		(layer "In13.Cu")
		(net "M_B_CPU0_SB_DQ<1>")
	)
	(arc
		(start 334.453992 -275.218652)
		(mid 334.636243 -275.269002)
		(end 334.819752 -275.223478)
		(width 0.0889)
		(layer "In13.Cu")
		(net "M_B_CPU0_SB_DQ<1>")
	)
	(arc
		(start 336.708242 -275.218652)
		(mid 336.955955 -275.143432)
		(end 337.211162 -275.186902)
		(width 0.0889)
		(layer "In13.Cu")
		(net "M_B_CPU0_SB_DQ<1>")
	)
	(arc
		(start 335.402428 -275.223478)
		(mid 335.585936 -275.268972)
		(end 335.768188 -275.218652)
		(width 0.0889)
		(layer "In13.Cu")
		(net "M_B_CPU0_SB_DQ<1>")
	)
	(arc
		(start 328.814176 -275.218652)
		(mid 329.00112 -275.268907)
		(end 329.188064 -275.218652)
		(width 0.0889)
		(layer "In13.Cu")
		(net "M_B_CPU0_SB_DQ<1>")
	)
	(arc
		(start 328.248264 -275.218652)
		(mid 328.53122 -275.142475)
		(end 328.814176 -275.218652)
		(width 0.0889)
		(layer "In13.Cu")
		(net "M_B_CPU0_SB_DQ<1>")
	)
	(arc
		(start 327.59015 -275.142198)
		(mid 327.73695 -275.161642)
		(end 327.873614 -275.218652)
		(width 0.0889)
		(layer "In13.Cu")
		(net "M_B_CPU0_SB_DQ<1>")
	)
	(arc
		(start 330.128118 -275.218652)
		(mid 330.411074 -275.142475)
		(end 330.69403 -275.218652)
		(width 0.0889)
		(layer "In13.Cu")
		(net "M_B_CPU0_SB_DQ<1>")
	)
	(arc
		(start 332.948026 -275.218652)
		(mid 333.230982 -275.142475)
		(end 333.513938 -275.218652)
		(width 0.0889)
		(layer "In13.Cu")
		(net "M_B_CPU0_SB_DQ<1>")
	)
	(arc
		(start 332.574138 -275.218652)
		(mid 332.761082 -275.268907)
		(end 332.948026 -275.218652)
		(width 0.0889)
		(layer "In13.Cu")
		(net "M_B_CPU0_SB_DQ<1>")
	)
	(arc
		(start 335.768188 -275.218652)
		(mid 336.051144 -275.142475)
		(end 336.3341 -275.218652)
		(width 0.0889)
		(layer "In13.Cu")
		(net "M_B_CPU0_SB_DQ<1>")
	)
	(arc
		(start 333.513938 -275.218652)
		(mid 333.696189 -275.269002)
		(end 333.879698 -275.223478)
		(width 0.0889)
		(layer "In13.Cu")
		(net "M_B_CPU0_SB_DQ<1>")
	)
	(arc
		(start 333.888334 -275.218652)
		(mid 334.17118 -275.142475)
		(end 334.453992 -275.218652)
		(width 0.0889)
		(layer "In13.Cu")
		(net "M_B_CPU0_SB_DQ<1>")
	)
	(arc
		(start 329.188064 -275.218652)
		(mid 329.47102 -275.142475)
		(end 329.753976 -275.218652)
		(width 0.0889)
		(layer "In13.Cu")
		(net "M_B_CPU0_SB_DQ<1>")
	)
	(segment
		(start 337.45805 -285.160212)
		(end 336.991198 -285.42615)
		(width 0.10668)
		(layer "F.Cu")
		(net "M_B_CPU0_SB_DQ<19>")
	)
	(segment
		(start 308.708044 -300.929548)
		(end 323.806312 -285.83128)
		(width 0.14478)
		(layer "In13.Cu")
		(net "M_B_CPU0_SB_DQ<19>")
	)
	(segment
		(start 305.414172 -302.22571)
		(end 306.192936 -302.22571)
		(width 0.14478)
		(layer "In13.Cu")
		(net "M_B_CPU0_SB_DQ<19>")
	)
	(segment
		(start 323.861684 -285.83128)
		(end 324.22211 -285.83128)
		(width 0.0889)
		(layer "In13.Cu")
		(net "M_B_CPU0_SB_DQ<19>")
	)
	(segment
		(start 297.386502 -302.73498)
		(end 297.96994 -302.151542)
		(width 0.14478)
		(layer "In13.Cu")
		(net "M_B_CPU0_SB_DQ<19>")
	)
	(segment
		(start 332.469744 -285.098744)
		(end 332.478126 -285.10357)
		(width 0.0889)
		(layer "In13.Cu")
		(net "M_B_CPU0_SB_DQ<19>")
	)
	(segment
		(start 297.96994 -302.151542)
		(end 298.46778 -302.151542)
		(width 0.14478)
		(layer "In13.Cu")
		(net "M_B_CPU0_SB_DQ<19>")
	)
	(segment
		(start 324.752208 -285.348172)
		(end 325.554848 -285.348172)
		(width 0.0889)
		(layer "In13.Cu")
		(net "M_B_CPU0_SB_DQ<19>")
	)
	(segment
		(start 306.192936 -302.22571)
		(end 306.403756 -302.43653)
		(width 0.14478)
		(layer "In13.Cu")
		(net "M_B_CPU0_SB_DQ<19>")
	)
	(segment
		(start 331.52969 -285.098744)
		(end 331.538072 -285.10357)
		(width 0.0889)
		(layer "In13.Cu")
		(net "M_B_CPU0_SB_DQ<19>")
	)
	(segment
		(start 295.724072 -302.73498)
		(end 297.386502 -302.73498)
		(width 0.14478)
		(layer "In13.Cu")
		(net "M_B_CPU0_SB_DQ<19>")
	)
	(segment
		(start 308.021482 -302.43653)
		(end 308.708044 -301.749968)
		(width 0.14478)
		(layer "In13.Cu")
		(net "M_B_CPU0_SB_DQ<19>")
	)
	(segment
		(start 326.837802 -285.103824)
		(end 326.84339 -285.107126)
		(width 0.0889)
		(layer "In13.Cu")
		(net "M_B_CPU0_SB_DQ<19>")
	)
	(segment
		(start 304.875184 -302.764698)
		(end 305.414172 -302.22571)
		(width 0.14478)
		(layer "In13.Cu")
		(net "M_B_CPU0_SB_DQ<19>")
	)
	(segment
		(start 337.145122 -285.16072)
		(end 336.991198 -285.42615)
		(width 0.0889)
		(layer "In13.Cu")
		(net "M_B_CPU0_SB_DQ<19>")
	)
	(segment
		(start 333.044038 -285.10357)
		(end 333.05242 -285.098744)
		(width 0.0889)
		(layer "In13.Cu")
		(net "M_B_CPU0_SB_DQ<19>")
	)
	(segment
		(start 298.46778 -302.151542)
		(end 299.080936 -302.764698)
		(width 0.14478)
		(layer "In13.Cu")
		(net "M_B_CPU0_SB_DQ<19>")
	)
	(segment
		(start 323.806312 -285.83128)
		(end 323.861684 -285.83128)
		(width 0.14478)
		(layer "In13.Cu")
		(net "M_B_CPU0_SB_DQ<19>")
	)
	(segment
		(start 329.284076 -285.10357)
		(end 329.292458 -285.098744)
		(width 0.0889)
		(layer "In13.Cu")
		(net "M_B_CPU0_SB_DQ<19>")
	)
	(segment
		(start 337.12277 -285.077408)
		(end 337.145122 -285.16072)
		(width 0.0889)
		(layer "In13.Cu")
		(net "M_B_CPU0_SB_DQ<19>")
	)
	(segment
		(start 308.708044 -301.749968)
		(end 308.708044 -300.929548)
		(width 0.14478)
		(layer "In13.Cu")
		(net "M_B_CPU0_SB_DQ<19>")
	)
	(segment
		(start 327.403206 -285.10357)
		(end 327.41489 -285.096712)
		(width 0.0889)
		(layer "In13.Cu")
		(net "M_B_CPU0_SB_DQ<19>")
	)
	(segment
		(start 328.709782 -285.098744)
		(end 328.718164 -285.10357)
		(width 0.0889)
		(layer "In13.Cu")
		(net "M_B_CPU0_SB_DQ<19>")
	)
	(segment
		(start 333.984092 -285.10357)
		(end 333.992474 -285.098744)
		(width 0.0889)
		(layer "In13.Cu")
		(net "M_B_CPU0_SB_DQ<19>")
	)
	(segment
		(start 299.080936 -302.764698)
		(end 304.875184 -302.764698)
		(width 0.14478)
		(layer "In13.Cu")
		(net "M_B_CPU0_SB_DQ<19>")
	)
	(segment
		(start 324.22211 -285.83128)
		(end 324.671944 -285.381446)
		(width 0.0889)
		(layer "In13.Cu")
		(net "M_B_CPU0_SB_DQ<19>")
	)
	(segment
		(start 328.32929 -285.112206)
		(end 328.344022 -285.10357)
		(width 0.0889)
		(layer "In13.Cu")
		(net "M_B_CPU0_SB_DQ<19>")
	)
	(segment
		(start 336.229706 -285.098744)
		(end 336.238088 -285.10357)
		(width 0.0889)
		(layer "In13.Cu")
		(net "M_B_CPU0_SB_DQ<19>")
	)
	(segment
		(start 326.819514 -285.09341)
		(end 326.837802 -285.103824)
		(width 0.0889)
		(layer "In13.Cu")
		(net "M_B_CPU0_SB_DQ<19>")
	)
	(segment
		(start 306.403756 -302.43653)
		(end 308.021482 -302.43653)
		(width 0.14478)
		(layer "In13.Cu")
		(net "M_B_CPU0_SB_DQ<19>")
	)
	(arc
		(start 333.41818 -285.10357)
		(mid 333.701136 -285.179747)
		(end 333.984092 -285.10357)
		(width 0.0889)
		(layer "In13.Cu")
		(net "M_B_CPU0_SB_DQ<19>")
	)
	(arc
		(start 326.84339 -285.107126)
		(mid 327.123779 -285.179795)
		(end 327.403206 -285.10357)
		(width 0.0889)
		(layer "In13.Cu")
		(net "M_B_CPU0_SB_DQ<19>")
	)
	(arc
		(start 331.538072 -285.10357)
		(mid 331.821028 -285.179747)
		(end 332.103984 -285.10357)
		(width 0.0889)
		(layer "In13.Cu")
		(net "M_B_CPU0_SB_DQ<19>")
	)
	(arc
		(start 327.41489 -285.096712)
		(mid 327.597145 -285.053059)
		(end 327.777602 -285.10357)
		(width 0.0889)
		(layer "In13.Cu")
		(net "M_B_CPU0_SB_DQ<19>")
	)
	(arc
		(start 328.344022 -285.10357)
		(mid 328.526273 -285.05322)
		(end 328.709782 -285.098744)
		(width 0.0889)
		(layer "In13.Cu")
		(net "M_B_CPU0_SB_DQ<19>")
	)
	(arc
		(start 334.358234 -285.10357)
		(mid 334.64119 -285.179747)
		(end 334.924146 -285.10357)
		(width 0.0889)
		(layer "In13.Cu")
		(net "M_B_CPU0_SB_DQ<19>")
	)
	(arc
		(start 330.598018 -285.10357)
		(mid 330.880974 -285.179747)
		(end 331.16393 -285.10357)
		(width 0.0889)
		(layer "In13.Cu")
		(net "M_B_CPU0_SB_DQ<19>")
	)
	(arc
		(start 325.554848 -285.348172)
		(mid 326.025418 -285.285941)
		(end 326.46366 -285.10357)
		(width 0.0889)
		(layer "In13.Cu")
		(net "M_B_CPU0_SB_DQ<19>")
	)
	(arc
		(start 331.16393 -285.10357)
		(mid 331.346181 -285.05322)
		(end 331.52969 -285.098744)
		(width 0.0889)
		(layer "In13.Cu")
		(net "M_B_CPU0_SB_DQ<19>")
	)
	(arc
		(start 329.292458 -285.098744)
		(mid 329.475966 -285.05325)
		(end 329.658218 -285.10357)
		(width 0.0889)
		(layer "In13.Cu")
		(net "M_B_CPU0_SB_DQ<19>")
	)
	(arc
		(start 326.46366 -285.10357)
		(mid 326.640288 -285.053337)
		(end 326.819514 -285.09341)
		(width 0.0889)
		(layer "In13.Cu")
		(net "M_B_CPU0_SB_DQ<19>")
	)
	(arc
		(start 335.298034 -285.10357)
		(mid 335.58099 -285.179747)
		(end 335.863946 -285.10357)
		(width 0.0889)
		(layer "In13.Cu")
		(net "M_B_CPU0_SB_DQ<19>")
	)
	(arc
		(start 336.238088 -285.10357)
		(mid 336.521044 -285.179747)
		(end 336.804 -285.10357)
		(width 0.0889)
		(layer "In13.Cu")
		(net "M_B_CPU0_SB_DQ<19>")
	)
	(arc
		(start 328.718164 -285.10357)
		(mid 329.00112 -285.179747)
		(end 329.284076 -285.10357)
		(width 0.0889)
		(layer "In13.Cu")
		(net "M_B_CPU0_SB_DQ<19>")
	)
	(arc
		(start 334.924146 -285.10357)
		(mid 335.11109 -285.053315)
		(end 335.298034 -285.10357)
		(width 0.0889)
		(layer "In13.Cu")
		(net "M_B_CPU0_SB_DQ<19>")
	)
	(arc
		(start 336.804 -285.10357)
		(mid 336.960438 -285.054599)
		(end 337.12277 -285.077408)
		(width 0.0889)
		(layer "In13.Cu")
		(net "M_B_CPU0_SB_DQ<19>")
	)
	(arc
		(start 332.478126 -285.10357)
		(mid 332.761082 -285.179747)
		(end 333.044038 -285.10357)
		(width 0.0889)
		(layer "In13.Cu")
		(net "M_B_CPU0_SB_DQ<19>")
	)
	(arc
		(start 332.103984 -285.10357)
		(mid 332.286235 -285.05322)
		(end 332.469744 -285.098744)
		(width 0.0889)
		(layer "In13.Cu")
		(net "M_B_CPU0_SB_DQ<19>")
	)
	(arc
		(start 333.05242 -285.098744)
		(mid 333.235928 -285.05325)
		(end 333.41818 -285.10357)
		(width 0.0889)
		(layer "In13.Cu")
		(net "M_B_CPU0_SB_DQ<19>")
	)
	(arc
		(start 324.671944 -285.381446)
		(mid 324.708755 -285.356786)
		(end 324.752208 -285.348172)
		(width 0.0889)
		(layer "In13.Cu")
		(net "M_B_CPU0_SB_DQ<19>")
	)
	(arc
		(start 335.863946 -285.10357)
		(mid 336.046197 -285.05322)
		(end 336.229706 -285.098744)
		(width 0.0889)
		(layer "In13.Cu")
		(net "M_B_CPU0_SB_DQ<19>")
	)
	(arc
		(start 329.658218 -285.10357)
		(mid 329.941174 -285.179747)
		(end 330.22413 -285.10357)
		(width 0.0889)
		(layer "In13.Cu")
		(net "M_B_CPU0_SB_DQ<19>")
	)
	(arc
		(start 333.992474 -285.098744)
		(mid 334.175982 -285.05325)
		(end 334.358234 -285.10357)
		(width 0.0889)
		(layer "In13.Cu")
		(net "M_B_CPU0_SB_DQ<19>")
	)
	(arc
		(start 327.777602 -285.10357)
		(mid 328.052308 -285.179934)
		(end 328.32929 -285.112206)
		(width 0.0889)
		(layer "In13.Cu")
		(net "M_B_CPU0_SB_DQ<19>")
	)
	(arc
		(start 330.22413 -285.10357)
		(mid 330.411074 -285.053315)
		(end 330.598018 -285.10357)
		(width 0.0889)
		(layer "In13.Cu")
		(net "M_B_CPU0_SB_DQ<19>")
	)
	(segment
		(start 336.047842 -284.350206)
		(end 335.58099 -284.616144)
		(width 0.10668)
		(layer "F.Cu")
		(net "M_B_CPU0_SB_DQ<18>")
	)
	(segment
		(start 297.094148 -301.68088)
		(end 297.094148 -301.179738)
		(width 0.14478)
		(layer "In13.Cu")
		(net "M_B_CPU0_SB_DQ<18>")
	)
	(segment
		(start 327.307448 -284.293564)
		(end 327.317862 -284.29966)
		(width 0.0889)
		(layer "In13.Cu")
		(net "M_B_CPU0_SB_DQ<18>")
	)
	(segment
		(start 298.602654 -301.344838)
		(end 298.864274 -301.344838)
		(width 0.14478)
		(layer "In13.Cu")
		(net "M_B_CPU0_SB_DQ<18>")
	)
	(segment
		(start 335.735168 -284.350714)
		(end 335.58099 -284.616144)
		(width 0.0889)
		(layer "In13.Cu")
		(net "M_B_CPU0_SB_DQ<18>")
	)
	(segment
		(start 298.864274 -301.344838)
		(end 299.009054 -301.200058)
		(width 0.14478)
		(layer "In13.Cu")
		(net "M_B_CPU0_SB_DQ<18>")
	)
	(segment
		(start 325.818246 -284.369764)
		(end 326.651112 -284.369764)
		(width 0.0889)
		(layer "In13.Cu")
		(net "M_B_CPU0_SB_DQ<18>")
	)
	(segment
		(start 299.009054 -300.754796)
		(end 299.153834 -300.610016)
		(width 0.14478)
		(layer "In13.Cu")
		(net "M_B_CPU0_SB_DQ<18>")
	)
	(segment
		(start 326.93356 -284.293818)
		(end 326.949816 -284.28442)
		(width 0.0889)
		(layer "In13.Cu")
		(net "M_B_CPU0_SB_DQ<18>")
	)
	(segment
		(start 302.030892 -300.610016)
		(end 302.88103 -301.460154)
		(width 0.14478)
		(layer "In13.Cu")
		(net "M_B_CPU0_SB_DQ<18>")
	)
	(segment
		(start 297.50639 -301.034958)
		(end 297.931332 -300.610016)
		(width 0.14478)
		(layer "In13.Cu")
		(net "M_B_CPU0_SB_DQ<18>")
	)
	(segment
		(start 328.239882 -284.288738)
		(end 328.248264 -284.293564)
		(width 0.0889)
		(layer "In13.Cu")
		(net "M_B_CPU0_SB_DQ<18>")
	)
	(segment
		(start 334.819752 -284.288738)
		(end 334.828134 -284.293564)
		(width 0.0889)
		(layer "In13.Cu")
		(net "M_B_CPU0_SB_DQ<18>")
	)
	(segment
		(start 324.21703 -284.92196)
		(end 324.423278 -284.715712)
		(width 0.0889)
		(layer "In13.Cu")
		(net "M_B_CPU0_SB_DQ<18>")
	)
	(segment
		(start 295.724072 -301.034958)
		(end 296.398188 -301.034958)
		(width 0.14478)
		(layer "In13.Cu")
		(net "M_B_CPU0_SB_DQ<18>")
	)
	(segment
		(start 298.313094 -300.610016)
		(end 298.457874 -300.754796)
		(width 0.14478)
		(layer "In13.Cu")
		(net "M_B_CPU0_SB_DQ<18>")
	)
	(segment
		(start 302.88103 -301.460154)
		(end 304.893218 -301.460154)
		(width 0.14478)
		(layer "In13.Cu")
		(net "M_B_CPU0_SB_DQ<18>")
	)
	(segment
		(start 323.436488 -284.92196)
		(end 323.913754 -284.92196)
		(width 0.14478)
		(layer "In13.Cu")
		(net "M_B_CPU0_SB_DQ<18>")
	)
	(segment
		(start 305.743356 -300.610016)
		(end 307.748432 -300.610016)
		(width 0.14478)
		(layer "In13.Cu")
		(net "M_B_CPU0_SB_DQ<18>")
	)
	(segment
		(start 299.009054 -301.200058)
		(end 299.009054 -300.754796)
		(width 0.14478)
		(layer "In13.Cu")
		(net "M_B_CPU0_SB_DQ<18>")
	)
	(segment
		(start 333.879698 -284.288738)
		(end 333.88808 -284.293564)
		(width 0.0889)
		(layer "In13.Cu")
		(net "M_B_CPU0_SB_DQ<18>")
	)
	(segment
		(start 297.931332 -300.610016)
		(end 298.313094 -300.610016)
		(width 0.14478)
		(layer "In13.Cu")
		(net "M_B_CPU0_SB_DQ<18>")
	)
	(segment
		(start 330.119736 -284.288738)
		(end 330.128118 -284.293564)
		(width 0.0889)
		(layer "In13.Cu")
		(net "M_B_CPU0_SB_DQ<18>")
	)
	(segment
		(start 307.748432 -300.610016)
		(end 323.436488 -284.92196)
		(width 0.14478)
		(layer "In13.Cu")
		(net "M_B_CPU0_SB_DQ<18>")
	)
	(segment
		(start 324.423278 -284.715712)
		(end 325.472298 -284.715712)
		(width 0.0889)
		(layer "In13.Cu")
		(net "M_B_CPU0_SB_DQ<18>")
	)
	(segment
		(start 296.398188 -301.034958)
		(end 296.542968 -301.179738)
		(width 0.14478)
		(layer "In13.Cu")
		(net "M_B_CPU0_SB_DQ<18>")
	)
	(segment
		(start 333.88808 -284.293564)
		(end 333.888334 -284.293564)
		(width 0.0889)
		(layer "In13.Cu")
		(net "M_B_CPU0_SB_DQ<18>")
	)
	(segment
		(start 297.094148 -301.179738)
		(end 297.238928 -301.034958)
		(width 0.14478)
		(layer "In13.Cu")
		(net "M_B_CPU0_SB_DQ<18>")
	)
	(segment
		(start 304.893218 -301.460154)
		(end 305.743356 -300.610016)
		(width 0.14478)
		(layer "In13.Cu")
		(net "M_B_CPU0_SB_DQ<18>")
	)
	(segment
		(start 335.394046 -284.293564)
		(end 335.402428 -284.288738)
		(width 0.0889)
		(layer "In13.Cu")
		(net "M_B_CPU0_SB_DQ<18>")
	)
	(segment
		(start 298.457874 -300.754796)
		(end 298.457874 -301.200058)
		(width 0.14478)
		(layer "In13.Cu")
		(net "M_B_CPU0_SB_DQ<18>")
	)
	(segment
		(start 325.472298 -284.715712)
		(end 325.818246 -284.369764)
		(width 0.0889)
		(layer "In13.Cu")
		(net "M_B_CPU0_SB_DQ<18>")
	)
	(segment
		(start 298.457874 -301.200058)
		(end 298.602654 -301.344838)
		(width 0.14478)
		(layer "In13.Cu")
		(net "M_B_CPU0_SB_DQ<18>")
	)
	(segment
		(start 296.687748 -301.82566)
		(end 296.949368 -301.82566)
		(width 0.14478)
		(layer "In13.Cu")
		(net "M_B_CPU0_SB_DQ<18>")
	)
	(segment
		(start 323.913754 -284.92196)
		(end 324.21703 -284.92196)
		(width 0.0889)
		(layer "In13.Cu")
		(net "M_B_CPU0_SB_DQ<18>")
	)
	(segment
		(start 330.69403 -284.293564)
		(end 330.702412 -284.288738)
		(width 0.0889)
		(layer "In13.Cu")
		(net "M_B_CPU0_SB_DQ<18>")
	)
	(segment
		(start 335.712816 -284.267402)
		(end 335.735168 -284.350714)
		(width 0.0889)
		(layer "In13.Cu")
		(net "M_B_CPU0_SB_DQ<18>")
	)
	(segment
		(start 331.634084 -284.293564)
		(end 331.642466 -284.288738)
		(width 0.0889)
		(layer "In13.Cu")
		(net "M_B_CPU0_SB_DQ<18>")
	)
	(segment
		(start 296.542968 -301.179738)
		(end 296.542968 -301.68088)
		(width 0.14478)
		(layer "In13.Cu")
		(net "M_B_CPU0_SB_DQ<18>")
	)
	(segment
		(start 296.542968 -301.68088)
		(end 296.687748 -301.82566)
		(width 0.14478)
		(layer "In13.Cu")
		(net "M_B_CPU0_SB_DQ<18>")
	)
	(segment
		(start 296.949368 -301.82566)
		(end 297.094148 -301.68088)
		(width 0.14478)
		(layer "In13.Cu")
		(net "M_B_CPU0_SB_DQ<18>")
	)
	(segment
		(start 299.153834 -300.610016)
		(end 302.030892 -300.610016)
		(width 0.14478)
		(layer "In13.Cu")
		(net "M_B_CPU0_SB_DQ<18>")
	)
	(segment
		(start 297.238928 -301.034958)
		(end 297.50639 -301.034958)
		(width 0.14478)
		(layer "In13.Cu")
		(net "M_B_CPU0_SB_DQ<18>")
	)
	(arc
		(start 329.188064 -284.293564)
		(mid 329.47102 -284.369741)
		(end 329.753976 -284.293564)
		(width 0.0889)
		(layer "In13.Cu")
		(net "M_B_CPU0_SB_DQ<18>")
	)
	(arc
		(start 331.642466 -284.288738)
		(mid 331.825974 -284.243244)
		(end 332.008226 -284.293564)
		(width 0.0889)
		(layer "In13.Cu")
		(net "M_B_CPU0_SB_DQ<18>")
	)
	(arc
		(start 333.513938 -284.293564)
		(mid 333.696189 -284.243214)
		(end 333.879698 -284.288738)
		(width 0.0889)
		(layer "In13.Cu")
		(net "M_B_CPU0_SB_DQ<18>")
	)
	(arc
		(start 326.949816 -284.28442)
		(mid 327.129798 -284.24332)
		(end 327.307448 -284.293564)
		(width 0.0889)
		(layer "In13.Cu")
		(net "M_B_CPU0_SB_DQ<18>")
	)
	(arc
		(start 326.651112 -284.369764)
		(mid 326.79736 -284.350459)
		(end 326.93356 -284.293818)
		(width 0.0889)
		(layer "In13.Cu")
		(net "M_B_CPU0_SB_DQ<18>")
	)
	(arc
		(start 331.068172 -284.293564)
		(mid 331.351128 -284.369741)
		(end 331.634084 -284.293564)
		(width 0.0889)
		(layer "In13.Cu")
		(net "M_B_CPU0_SB_DQ<18>")
	)
	(arc
		(start 328.814176 -284.293564)
		(mid 329.00112 -284.243309)
		(end 329.188064 -284.293564)
		(width 0.0889)
		(layer "In13.Cu")
		(net "M_B_CPU0_SB_DQ<18>")
	)
	(arc
		(start 332.948026 -284.293564)
		(mid 333.230982 -284.369741)
		(end 333.513938 -284.293564)
		(width 0.0889)
		(layer "In13.Cu")
		(net "M_B_CPU0_SB_DQ<18>")
	)
	(arc
		(start 327.873614 -284.293564)
		(mid 328.056119 -284.243087)
		(end 328.239882 -284.288738)
		(width 0.0889)
		(layer "In13.Cu")
		(net "M_B_CPU0_SB_DQ<18>")
	)
	(arc
		(start 327.317862 -284.29966)
		(mid 327.596548 -284.36988)
		(end 327.873614 -284.293564)
		(width 0.0889)
		(layer "In13.Cu")
		(net "M_B_CPU0_SB_DQ<18>")
	)
	(arc
		(start 330.128118 -284.293564)
		(mid 330.411074 -284.369741)
		(end 330.69403 -284.293564)
		(width 0.0889)
		(layer "In13.Cu")
		(net "M_B_CPU0_SB_DQ<18>")
	)
	(arc
		(start 330.702412 -284.288738)
		(mid 330.88592 -284.243244)
		(end 331.068172 -284.293564)
		(width 0.0889)
		(layer "In13.Cu")
		(net "M_B_CPU0_SB_DQ<18>")
	)
	(arc
		(start 334.828134 -284.293564)
		(mid 335.11109 -284.369741)
		(end 335.394046 -284.293564)
		(width 0.0889)
		(layer "In13.Cu")
		(net "M_B_CPU0_SB_DQ<18>")
	)
	(arc
		(start 332.008226 -284.293564)
		(mid 332.291182 -284.369741)
		(end 332.574138 -284.293564)
		(width 0.0889)
		(layer "In13.Cu")
		(net "M_B_CPU0_SB_DQ<18>")
	)
	(arc
		(start 335.402428 -284.288738)
		(mid 335.555298 -284.244097)
		(end 335.712816 -284.267402)
		(width 0.0889)
		(layer "In13.Cu")
		(net "M_B_CPU0_SB_DQ<18>")
	)
	(arc
		(start 329.753976 -284.293564)
		(mid 329.936227 -284.243214)
		(end 330.119736 -284.288738)
		(width 0.0889)
		(layer "In13.Cu")
		(net "M_B_CPU0_SB_DQ<18>")
	)
	(arc
		(start 334.453992 -284.293564)
		(mid 334.636243 -284.243214)
		(end 334.819752 -284.288738)
		(width 0.0889)
		(layer "In13.Cu")
		(net "M_B_CPU0_SB_DQ<18>")
	)
	(arc
		(start 333.888334 -284.293564)
		(mid 334.17118 -284.369741)
		(end 334.453992 -284.293564)
		(width 0.0889)
		(layer "In13.Cu")
		(net "M_B_CPU0_SB_DQ<18>")
	)
	(arc
		(start 328.248264 -284.293564)
		(mid 328.53122 -284.369741)
		(end 328.814176 -284.293564)
		(width 0.0889)
		(layer "In13.Cu")
		(net "M_B_CPU0_SB_DQ<18>")
	)
	(arc
		(start 332.574138 -284.293564)
		(mid 332.761082 -284.243309)
		(end 332.948026 -284.293564)
		(width 0.0889)
		(layer "In13.Cu")
		(net "M_B_CPU0_SB_DQ<18>")
	)
	(segment
		(start 337.92795 -284.350206)
		(end 337.461098 -284.616144)
		(width 0.10668)
		(layer "F.Cu")
		(net "M_B_CPU0_SB_DQ<17>")
	)
	(segment
		(start 306.333398 -301.551086)
		(end 306.500022 -301.71771)
		(width 0.14478)
		(layer "In13.Cu")
		(net "M_B_CPU0_SB_DQ<17>")
	)
	(segment
		(start 326.367902 -284.938724)
		(end 326.367648 -284.938724)
		(width 0.0889)
		(layer "In13.Cu")
		(net "M_B_CPU0_SB_DQ<17>")
	)
	(segment
		(start 307.856382 -301.717456)
		(end 308.104286 -301.717456)
		(width 0.14478)
		(layer "In13.Cu")
		(net "M_B_CPU0_SB_DQ<17>")
	)
	(segment
		(start 324.615048 -285.056072)
		(end 325.932292 -285.056072)
		(width 0.0889)
		(layer "In13.Cu")
		(net "M_B_CPU0_SB_DQ<17>")
	)
	(segment
		(start 302.041814 -301.45863)
		(end 302.186594 -301.60341)
		(width 0.14478)
		(layer "In13.Cu")
		(net "M_B_CPU0_SB_DQ<17>")
	)
	(segment
		(start 304.686462 -302.310038)
		(end 305.84521 -301.15129)
		(width 0.14478)
		(layer "In13.Cu")
		(net "M_B_CPU0_SB_DQ<17>")
	)
	(segment
		(start 323.898514 -285.37662)
		(end 324.24751 -285.37662)
		(width 0.0889)
		(layer "In13.Cu")
		(net "M_B_CPU0_SB_DQ<17>")
	)
	(segment
		(start 301.780194 -301.45863)
		(end 302.041814 -301.45863)
		(width 0.14478)
		(layer "In13.Cu")
		(net "M_B_CPU0_SB_DQ<17>")
	)
	(segment
		(start 300.478444 -301.24527)
		(end 300.623224 -301.10049)
		(width 0.14478)
		(layer "In13.Cu")
		(net "M_B_CPU0_SB_DQ<17>")
	)
	(segment
		(start 302.186594 -302.165258)
		(end 302.331374 -302.310038)
		(width 0.14478)
		(layer "In13.Cu")
		(net "M_B_CPU0_SB_DQ<17>")
	)
	(segment
		(start 306.333398 -301.305468)
		(end 306.333398 -301.551086)
		(width 0.14478)
		(layer "In13.Cu")
		(net "M_B_CPU0_SB_DQ<17>")
	)
	(segment
		(start 301.635414 -301.60341)
		(end 301.780194 -301.45863)
		(width 0.14478)
		(layer "In13.Cu")
		(net "M_B_CPU0_SB_DQ<17>")
	)
	(segment
		(start 307.005736 -301.4599)
		(end 307.598826 -301.4599)
		(width 0.14478)
		(layer "In13.Cu")
		(net "M_B_CPU0_SB_DQ<17>")
	)
	(segment
		(start 306.747926 -301.71771)
		(end 307.005736 -301.4599)
		(width 0.14478)
		(layer "In13.Cu")
		(net "M_B_CPU0_SB_DQ<17>")
	)
	(segment
		(start 302.186594 -301.60341)
		(end 302.186594 -302.165258)
		(width 0.14478)
		(layer "In13.Cu")
		(net "M_B_CPU0_SB_DQ<17>")
	)
	(segment
		(start 300.333664 -302.310038)
		(end 300.478444 -302.165258)
		(width 0.14478)
		(layer "In13.Cu")
		(net "M_B_CPU0_SB_DQ<17>")
	)
	(segment
		(start 333.88808 -284.938724)
		(end 333.888334 -284.938724)
		(width 0.0889)
		(layer "In13.Cu")
		(net "M_B_CPU0_SB_DQ<17>")
	)
	(segment
		(start 307.598826 -301.4599)
		(end 307.856382 -301.717456)
		(width 0.14478)
		(layer "In13.Cu")
		(net "M_B_CPU0_SB_DQ<17>")
	)
	(segment
		(start 301.174404 -302.310038)
		(end 301.490634 -302.310038)
		(width 0.14478)
		(layer "In13.Cu")
		(net "M_B_CPU0_SB_DQ<17>")
	)
	(segment
		(start 300.623224 -301.10049)
		(end 300.884844 -301.10049)
		(width 0.14478)
		(layer "In13.Cu")
		(net "M_B_CPU0_SB_DQ<17>")
	)
	(segment
		(start 299.82414 -301.885096)
		(end 299.82414 -302.147224)
		(width 0.14478)
		(layer "In13.Cu")
		(net "M_B_CPU0_SB_DQ<17>")
	)
	(segment
		(start 331.634084 -284.938724)
		(end 331.642466 -284.94355)
		(width 0.0889)
		(layer "In13.Cu")
		(net "M_B_CPU0_SB_DQ<17>")
	)
	(segment
		(start 335.394046 -284.938724)
		(end 335.402428 -284.94355)
		(width 0.0889)
		(layer "In13.Cu")
		(net "M_B_CPU0_SB_DQ<17>")
	)
	(segment
		(start 306.17922 -301.15129)
		(end 306.333398 -301.305468)
		(width 0.14478)
		(layer "In13.Cu")
		(net "M_B_CPU0_SB_DQ<17>")
	)
	(segment
		(start 305.84521 -301.15129)
		(end 306.17922 -301.15129)
		(width 0.14478)
		(layer "In13.Cu")
		(net "M_B_CPU0_SB_DQ<17>")
	)
	(segment
		(start 299.82414 -302.147224)
		(end 299.986954 -302.310038)
		(width 0.14478)
		(layer "In13.Cu")
		(net "M_B_CPU0_SB_DQ<17>")
	)
	(segment
		(start 308.258464 -301.563278)
		(end 308.258464 -300.736)
		(width 0.14478)
		(layer "In13.Cu")
		(net "M_B_CPU0_SB_DQ<17>")
	)
	(segment
		(start 327.307194 -284.938724)
		(end 327.321926 -284.930088)
		(width 0.0889)
		(layer "In13.Cu")
		(net "M_B_CPU0_SB_DQ<17>")
	)
	(segment
		(start 301.635414 -302.165258)
		(end 301.635414 -301.60341)
		(width 0.14478)
		(layer "In13.Cu")
		(net "M_B_CPU0_SB_DQ<17>")
	)
	(segment
		(start 337.307174 -284.881574)
		(end 337.461098 -284.616144)
		(width 0.0889)
		(layer "In13.Cu")
		(net "M_B_CPU0_SB_DQ<17>")
	)
	(segment
		(start 299.986954 -302.310038)
		(end 300.333664 -302.310038)
		(width 0.14478)
		(layer "In13.Cu")
		(net "M_B_CPU0_SB_DQ<17>")
	)
	(segment
		(start 308.258464 -300.736)
		(end 323.617844 -285.37662)
		(width 0.14478)
		(layer "In13.Cu")
		(net "M_B_CPU0_SB_DQ<17>")
	)
	(segment
		(start 306.500022 -301.71771)
		(end 306.747926 -301.71771)
		(width 0.14478)
		(layer "In13.Cu")
		(net "M_B_CPU0_SB_DQ<17>")
	)
	(segment
		(start 334.819752 -284.94355)
		(end 334.828134 -284.938724)
		(width 0.0889)
		(layer "In13.Cu")
		(net "M_B_CPU0_SB_DQ<17>")
	)
	(segment
		(start 300.478444 -302.165258)
		(end 300.478444 -301.24527)
		(width 0.14478)
		(layer "In13.Cu")
		(net "M_B_CPU0_SB_DQ<17>")
	)
	(segment
		(start 326.93356 -284.93847)
		(end 326.947276 -284.946344)
		(width 0.0889)
		(layer "In13.Cu")
		(net "M_B_CPU0_SB_DQ<17>")
	)
	(segment
		(start 301.490634 -302.310038)
		(end 301.635414 -302.165258)
		(width 0.14478)
		(layer "In13.Cu")
		(net "M_B_CPU0_SB_DQ<17>")
	)
	(segment
		(start 300.884844 -301.10049)
		(end 301.029624 -301.24527)
		(width 0.14478)
		(layer "In13.Cu")
		(net "M_B_CPU0_SB_DQ<17>")
	)
	(segment
		(start 328.239882 -284.94355)
		(end 328.248264 -284.938724)
		(width 0.0889)
		(layer "In13.Cu")
		(net "M_B_CPU0_SB_DQ<17>")
	)
	(segment
		(start 301.029624 -302.165258)
		(end 301.174404 -302.310038)
		(width 0.14478)
		(layer "In13.Cu")
		(net "M_B_CPU0_SB_DQ<17>")
	)
	(segment
		(start 324.24751 -285.37662)
		(end 324.534784 -285.089346)
		(width 0.0889)
		(layer "In13.Cu")
		(net "M_B_CPU0_SB_DQ<17>")
	)
	(segment
		(start 337.211162 -284.906974)
		(end 337.307174 -284.881574)
		(width 0.0889)
		(layer "In13.Cu")
		(net "M_B_CPU0_SB_DQ<17>")
	)
	(segment
		(start 302.331374 -302.310038)
		(end 304.686462 -302.310038)
		(width 0.14478)
		(layer "In13.Cu")
		(net "M_B_CPU0_SB_DQ<17>")
	)
	(segment
		(start 323.617844 -285.37662)
		(end 323.898514 -285.37662)
		(width 0.14478)
		(layer "In13.Cu")
		(net "M_B_CPU0_SB_DQ<17>")
	)
	(segment
		(start 308.104286 -301.717456)
		(end 308.258464 -301.563278)
		(width 0.14478)
		(layer "In13.Cu")
		(net "M_B_CPU0_SB_DQ<17>")
	)
	(segment
		(start 336.3341 -284.938724)
		(end 336.342482 -284.94355)
		(width 0.0889)
		(layer "In13.Cu")
		(net "M_B_CPU0_SB_DQ<17>")
	)
	(segment
		(start 333.879698 -284.94355)
		(end 333.88808 -284.938724)
		(width 0.0889)
		(layer "In13.Cu")
		(net "M_B_CPU0_SB_DQ<17>")
	)
	(segment
		(start 330.69403 -284.938724)
		(end 330.702412 -284.94355)
		(width 0.0889)
		(layer "In13.Cu")
		(net "M_B_CPU0_SB_DQ<17>")
	)
	(segment
		(start 330.119736 -284.94355)
		(end 330.128118 -284.938724)
		(width 0.0889)
		(layer "In13.Cu")
		(net "M_B_CPU0_SB_DQ<17>")
	)
	(segment
		(start 326.917812 -284.929326)
		(end 326.93356 -284.93847)
		(width 0.0889)
		(layer "In13.Cu")
		(net "M_B_CPU0_SB_DQ<17>")
	)
	(segment
		(start 301.029624 -301.24527)
		(end 301.029624 -302.165258)
		(width 0.14478)
		(layer "In13.Cu")
		(net "M_B_CPU0_SB_DQ<17>")
	)
	(arc
		(start 324.534784 -285.089346)
		(mid 324.571595 -285.064686)
		(end 324.615048 -285.056072)
		(width 0.0889)
		(layer "In13.Cu")
		(net "M_B_CPU0_SB_DQ<17>")
	)
	(arc
		(start 335.768188 -284.938724)
		(mid 336.051144 -284.862547)
		(end 336.3341 -284.938724)
		(width 0.0889)
		(layer "In13.Cu")
		(net "M_B_CPU0_SB_DQ<17>")
	)
	(arc
		(start 328.814176 -284.938724)
		(mid 329.00112 -284.988979)
		(end 329.188064 -284.938724)
		(width 0.0889)
		(layer "In13.Cu")
		(net "M_B_CPU0_SB_DQ<17>")
	)
	(arc
		(start 335.402428 -284.94355)
		(mid 335.585936 -284.989044)
		(end 335.768188 -284.938724)
		(width 0.0889)
		(layer "In13.Cu")
		(net "M_B_CPU0_SB_DQ<17>")
	)
	(arc
		(start 332.948026 -284.938724)
		(mid 333.230982 -284.862547)
		(end 333.513938 -284.938724)
		(width 0.0889)
		(layer "In13.Cu")
		(net "M_B_CPU0_SB_DQ<17>")
	)
	(arc
		(start 336.342482 -284.94355)
		(mid 336.52599 -284.989044)
		(end 336.708242 -284.938724)
		(width 0.0889)
		(layer "In13.Cu")
		(net "M_B_CPU0_SB_DQ<17>")
	)
	(arc
		(start 329.753976 -284.938724)
		(mid 329.936227 -284.989074)
		(end 330.119736 -284.94355)
		(width 0.0889)
		(layer "In13.Cu")
		(net "M_B_CPU0_SB_DQ<17>")
	)
	(arc
		(start 332.574138 -284.938724)
		(mid 332.761082 -284.988979)
		(end 332.948026 -284.938724)
		(width 0.0889)
		(layer "In13.Cu")
		(net "M_B_CPU0_SB_DQ<17>")
	)
	(arc
		(start 328.248264 -284.938724)
		(mid 328.53122 -284.862547)
		(end 328.814176 -284.938724)
		(width 0.0889)
		(layer "In13.Cu")
		(net "M_B_CPU0_SB_DQ<17>")
	)
	(arc
		(start 326.947276 -284.946344)
		(mid 327.128206 -284.988822)
		(end 327.307194 -284.938724)
		(width 0.0889)
		(layer "In13.Cu")
		(net "M_B_CPU0_SB_DQ<17>")
	)
	(arc
		(start 331.642466 -284.94355)
		(mid 331.825974 -284.989044)
		(end 332.008226 -284.938724)
		(width 0.0889)
		(layer "In13.Cu")
		(net "M_B_CPU0_SB_DQ<17>")
	)
	(arc
		(start 329.188064 -284.938724)
		(mid 329.47102 -284.862547)
		(end 329.753976 -284.938724)
		(width 0.0889)
		(layer "In13.Cu")
		(net "M_B_CPU0_SB_DQ<17>")
	)
	(arc
		(start 327.873614 -284.938724)
		(mid 328.056119 -284.989201)
		(end 328.239882 -284.94355)
		(width 0.0889)
		(layer "In13.Cu")
		(net "M_B_CPU0_SB_DQ<17>")
	)
	(arc
		(start 333.888334 -284.938724)
		(mid 334.17118 -284.862547)
		(end 334.453992 -284.938724)
		(width 0.0889)
		(layer "In13.Cu")
		(net "M_B_CPU0_SB_DQ<17>")
	)
	(arc
		(start 332.008226 -284.938724)
		(mid 332.291182 -284.862547)
		(end 332.574138 -284.938724)
		(width 0.0889)
		(layer "In13.Cu")
		(net "M_B_CPU0_SB_DQ<17>")
	)
	(arc
		(start 333.513938 -284.938724)
		(mid 333.696189 -284.989074)
		(end 333.879698 -284.94355)
		(width 0.0889)
		(layer "In13.Cu")
		(net "M_B_CPU0_SB_DQ<17>")
	)
	(arc
		(start 326.367648 -284.938724)
		(mid 326.641503 -284.862374)
		(end 326.917812 -284.929326)
		(width 0.0889)
		(layer "In13.Cu")
		(net "M_B_CPU0_SB_DQ<17>")
	)
	(arc
		(start 330.128118 -284.938724)
		(mid 330.411074 -284.862547)
		(end 330.69403 -284.938724)
		(width 0.0889)
		(layer "In13.Cu")
		(net "M_B_CPU0_SB_DQ<17>")
	)
	(arc
		(start 334.453992 -284.938724)
		(mid 334.636243 -284.989074)
		(end 334.819752 -284.94355)
		(width 0.0889)
		(layer "In13.Cu")
		(net "M_B_CPU0_SB_DQ<17>")
	)
	(arc
		(start 336.708242 -284.938724)
		(mid 336.955955 -284.863504)
		(end 337.211162 -284.906974)
		(width 0.0889)
		(layer "In13.Cu")
		(net "M_B_CPU0_SB_DQ<17>")
	)
	(arc
		(start 331.068172 -284.938724)
		(mid 331.351128 -284.862547)
		(end 331.634084 -284.938724)
		(width 0.0889)
		(layer "In13.Cu")
		(net "M_B_CPU0_SB_DQ<17>")
	)
	(arc
		(start 325.932292 -285.056072)
		(mid 326.157857 -285.026212)
		(end 326.367902 -284.938724)
		(width 0.0889)
		(layer "In13.Cu")
		(net "M_B_CPU0_SB_DQ<17>")
	)
	(arc
		(start 327.321926 -284.930088)
		(mid 327.598909 -284.862284)
		(end 327.873614 -284.938724)
		(width 0.0889)
		(layer "In13.Cu")
		(net "M_B_CPU0_SB_DQ<17>")
	)
	(arc
		(start 330.702412 -284.94355)
		(mid 330.88592 -284.989044)
		(end 331.068172 -284.938724)
		(width 0.0889)
		(layer "In13.Cu")
		(net "M_B_CPU0_SB_DQ<17>")
	)
	(arc
		(start 334.828134 -284.938724)
		(mid 335.11109 -284.862547)
		(end 335.394046 -284.938724)
		(width 0.0889)
		(layer "In13.Cu")
		(net "M_B_CPU0_SB_DQ<17>")
	)
	(segment
		(start 336.517996 -283.5402)
		(end 336.051144 -283.806138)
		(width 0.10668)
		(layer "F.Cu")
		(net "M_B_CPU0_SB_DQ<16>")
	)
	(segment
		(start 315.465206 -292.051994)
		(end 315.75248 -291.76472)
		(width 0.14478)
		(layer "In13.Cu")
		(net "M_B_CPU0_SB_DQ<16>")
	)
	(segment
		(start 303.040796 -300.98365)
		(end 303.658016 -300.98365)
		(width 0.14478)
		(layer "In13.Cu")
		(net "M_B_CPU0_SB_DQ<16>")
	)
	(segment
		(start 326.837802 -284.128464)
		(end 326.84339 -284.125162)
		(width 0.0889)
		(layer "In13.Cu")
		(net "M_B_CPU0_SB_DQ<16>")
	)
	(segment
		(start 316.244986 -291.477446)
		(end 316.244986 -291.272214)
		(width 0.14478)
		(layer "In13.Cu")
		(net "M_B_CPU0_SB_DQ<16>")
	)
	(segment
		(start 311.0738 -296.4434)
		(end 311.279032 -296.4434)
		(width 0.14478)
		(layer "In13.Cu")
		(net "M_B_CPU0_SB_DQ<16>")
	)
	(segment
		(start 329.284076 -284.128718)
		(end 329.292458 -284.133544)
		(width 0.0889)
		(layer "In13.Cu")
		(net "M_B_CPU0_SB_DQ<16>")
	)
	(segment
		(start 332.469744 -284.133544)
		(end 332.478126 -284.128718)
		(width 0.0889)
		(layer "In13.Cu")
		(net "M_B_CPU0_SB_DQ<16>")
	)
	(segment
		(start 314.398152 -293.32428)
		(end 314.685426 -293.037006)
		(width 0.14478)
		(layer "In13.Cu")
		(net "M_B_CPU0_SB_DQ<16>")
	)
	(segment
		(start 319.364106 -288.358326)
		(end 319.364106 -288.153094)
		(width 0.14478)
		(layer "In13.Cu")
		(net "M_B_CPU0_SB_DQ<16>")
	)
	(segment
		(start 322.7705 -284.7467)
		(end 322.975732 -284.7467)
		(width 0.14478)
		(layer "In13.Cu")
		(net "M_B_CPU0_SB_DQ<16>")
	)
	(segment
		(start 305.47691 -300.02861)
		(end 305.681634 -300.02861)
		(width 0.14478)
		(layer "In13.Cu")
		(net "M_B_CPU0_SB_DQ<16>")
	)
	(segment
		(start 314.9727 -292.5445)
		(end 315.177932 -292.5445)
		(width 0.14478)
		(layer "In13.Cu")
		(net "M_B_CPU0_SB_DQ<16>")
	)
	(segment
		(start 317.024766 -290.492434)
		(end 317.31204 -290.20516)
		(width 0.14478)
		(layer "In13.Cu")
		(net "M_B_CPU0_SB_DQ<16>")
	)
	(segment
		(start 302.762158 -300.060868)
		(end 302.762158 -300.705012)
		(width 0.14478)
		(layer "In13.Cu")
		(net "M_B_CPU0_SB_DQ<16>")
	)
	(segment
		(start 319.076832 -288.6456)
		(end 319.364106 -288.358326)
		(width 0.14478)
		(layer "In13.Cu")
		(net "M_B_CPU0_SB_DQ<16>")
	)
	(segment
		(start 320.923666 -286.798766)
		(end 320.923666 -286.593534)
		(width 0.14478)
		(layer "In13.Cu")
		(net "M_B_CPU0_SB_DQ<16>")
	)
	(segment
		(start 318.8716 -288.6456)
		(end 319.076832 -288.6456)
		(width 0.14478)
		(layer "In13.Cu")
		(net "M_B_CPU0_SB_DQ<16>")
	)
	(segment
		(start 310.786526 -296.730674)
		(end 311.0738 -296.4434)
		(width 0.14478)
		(layer "In13.Cu")
		(net "M_B_CPU0_SB_DQ<16>")
	)
	(segment
		(start 311.566306 -295.950894)
		(end 311.85358 -295.66362)
		(width 0.14478)
		(layer "In13.Cu")
		(net "M_B_CPU0_SB_DQ<16>")
	)
	(segment
		(start 320.143886 -287.578546)
		(end 320.143886 -287.373314)
		(width 0.14478)
		(layer "In13.Cu")
		(net "M_B_CPU0_SB_DQ<16>")
	)
	(segment
		(start 300.574202 -299.49521)
		(end 300.835822 -299.49521)
		(width 0.14478)
		(layer "In13.Cu")
		(net "M_B_CPU0_SB_DQ<16>")
	)
	(segment
		(start 323.903594 -284.4673)
		(end 324.20433 -284.4673)
		(width 0.0889)
		(layer "In13.Cu")
		(net "M_B_CPU0_SB_DQ<16>")
	)
	(segment
		(start 305.171856 -299.92828)
		(end 305.37658 -299.92828)
		(width 0.14478)
		(layer "In13.Cu")
		(net "M_B_CPU0_SB_DQ<16>")
	)
	(segment
		(start 310.006746 -297.510454)
		(end 310.29402 -297.22318)
		(width 0.14478)
		(layer "In13.Cu")
		(net "M_B_CPU0_SB_DQ<16>")
	)
	(segment
		(start 324.725538 -283.946092)
		(end 325.907146 -283.946092)
		(width 0.0889)
		(layer "In13.Cu")
		(net "M_B_CPU0_SB_DQ<16>")
	)
	(segment
		(start 335.8007 -284.096968)
		(end 335.896966 -284.071568)
		(width 0.0889)
		(layer "In13.Cu")
		(net "M_B_CPU0_SB_DQ<16>")
	)
	(segment
		(start 315.465206 -292.257226)
		(end 315.465206 -292.051994)
		(width 0.14478)
		(layer "In13.Cu")
		(net "M_B_CPU0_SB_DQ<16>")
	)
	(segment
		(start 320.636392 -287.08604)
		(end 320.923666 -286.798766)
		(width 0.14478)
		(layer "In13.Cu")
		(net "M_B_CPU0_SB_DQ<16>")
	)
	(segment
		(start 314.19292 -293.32428)
		(end 314.398152 -293.32428)
		(width 0.14478)
		(layer "In13.Cu")
		(net "M_B_CPU0_SB_DQ<16>")
	)
	(segment
		(start 304.370994 -300.099476)
		(end 304.370994 -300.822106)
		(width 0.14478)
		(layer "In13.Cu")
		(net "M_B_CPU0_SB_DQ<16>")
	)
	(segment
		(start 318.297052 -289.42538)
		(end 318.584326 -289.138106)
		(width 0.14478)
		(layer "In13.Cu")
		(net "M_B_CPU0_SB_DQ<16>")
	)
	(segment
		(start 317.517272 -290.20516)
		(end 317.804546 -289.917886)
		(width 0.14478)
		(layer "In13.Cu")
		(net "M_B_CPU0_SB_DQ<16>")
	)
	(segment
		(start 302.271938 -299.916088)
		(end 302.617378 -299.916088)
		(width 0.14478)
		(layer "In13.Cu")
		(net "M_B_CPU0_SB_DQ<16>")
	)
	(segment
		(start 317.024766 -290.697666)
		(end 317.024766 -290.492434)
		(width 0.14478)
		(layer "In13.Cu")
		(net "M_B_CPU0_SB_DQ<16>")
	)
	(segment
		(start 315.957712 -291.76472)
		(end 316.244986 -291.477446)
		(width 0.14478)
		(layer "In13.Cu")
		(net "M_B_CPU0_SB_DQ<16>")
	)
	(segment
		(start 310.006746 -297.715686)
		(end 310.006746 -297.510454)
		(width 0.14478)
		(layer "In13.Cu")
		(net "M_B_CPU0_SB_DQ<16>")
	)
	(segment
		(start 313.905646 -293.611554)
		(end 314.19292 -293.32428)
		(width 0.14478)
		(layer "In13.Cu")
		(net "M_B_CPU0_SB_DQ<16>")
	)
	(segment
		(start 317.804546 -289.712654)
		(end 318.09182 -289.42538)
		(width 0.14478)
		(layer "In13.Cu")
		(net "M_B_CPU0_SB_DQ<16>")
	)
	(segment
		(start 306.327302 -299.760132)
		(end 306.71008 -300.14291)
		(width 0.14478)
		(layer "In13.Cu")
		(net "M_B_CPU0_SB_DQ<16>")
	)
	(segment
		(start 299.82414 -300.185074)
		(end 299.868082 -300.141132)
		(width 0.14478)
		(layer "In13.Cu")
		(net "M_B_CPU0_SB_DQ<16>")
	)
	(segment
		(start 302.046894 -300.141132)
		(end 302.271938 -299.916088)
		(width 0.14478)
		(layer "In13.Cu")
		(net "M_B_CPU0_SB_DQ<16>")
	)
	(segment
		(start 313.125866 -294.391334)
		(end 313.41314 -294.10406)
		(width 0.14478)
		(layer "In13.Cu")
		(net "M_B_CPU0_SB_DQ<16>")
	)
	(segment
		(start 310.29402 -297.22318)
		(end 310.499252 -297.22318)
		(width 0.14478)
		(layer "In13.Cu")
		(net "M_B_CPU0_SB_DQ<16>")
	)
	(segment
		(start 318.09182 -289.42538)
		(end 318.297052 -289.42538)
		(width 0.14478)
		(layer "In13.Cu")
		(net "M_B_CPU0_SB_DQ<16>")
	)
	(segment
		(start 304.726594 -300.98365)
		(end 305.08702 -300.623224)
		(width 0.14478)
		(layer "In13.Cu")
		(net "M_B_CPU0_SB_DQ<16>")
	)
	(segment
		(start 309.226966 -298.495466)
		(end 309.226966 -298.290234)
		(width 0.14478)
		(layer "In13.Cu")
		(net "M_B_CPU0_SB_DQ<16>")
	)
	(segment
		(start 316.244986 -291.272214)
		(end 316.53226 -290.98494)
		(width 0.14478)
		(layer "In13.Cu")
		(net "M_B_CPU0_SB_DQ<16>")
	)
	(segment
		(start 302.617378 -299.916088)
		(end 302.762158 -300.060868)
		(width 0.14478)
		(layer "In13.Cu")
		(net "M_B_CPU0_SB_DQ<16>")
	)
	(segment
		(start 322.195952 -285.52648)
		(end 322.483226 -285.239206)
		(width 0.14478)
		(layer "In13.Cu")
		(net "M_B_CPU0_SB_DQ<16>")
	)
	(segment
		(start 300.284642 -300.141132)
		(end 300.429422 -299.996352)
		(width 0.14478)
		(layer "In13.Cu")
		(net "M_B_CPU0_SB_DQ<16>")
	)
	(segment
		(start 309.719472 -298.00296)
		(end 310.006746 -297.715686)
		(width 0.14478)
		(layer "In13.Cu")
		(net "M_B_CPU0_SB_DQ<16>")
	)
	(segment
		(start 311.279032 -296.4434)
		(end 311.566306 -296.156126)
		(width 0.14478)
		(layer "In13.Cu")
		(net "M_B_CPU0_SB_DQ<16>")
	)
	(segment
		(start 300.980602 -299.996352)
		(end 301.125382 -300.141132)
		(width 0.14478)
		(layer "In13.Cu")
		(net "M_B_CPU0_SB_DQ<16>")
	)
	(segment
		(start 324.20433 -284.4673)
		(end 324.725538 -283.946092)
		(width 0.0889)
		(layer "In13.Cu")
		(net "M_B_CPU0_SB_DQ<16>")
	)
	(segment
		(start 319.856612 -287.86582)
		(end 320.143886 -287.578546)
		(width 0.14478)
		(layer "In13.Cu")
		(net "M_B_CPU0_SB_DQ<16>")
	)
	(segment
		(start 305.681634 -300.02861)
		(end 305.950112 -299.760132)
		(width 0.14478)
		(layer "In13.Cu")
		(net "M_B_CPU0_SB_DQ<16>")
	)
	(segment
		(start 322.975732 -284.7467)
		(end 323.255132 -284.4673)
		(width 0.14478)
		(layer "In13.Cu")
		(net "M_B_CPU0_SB_DQ<16>")
	)
	(segment
		(start 321.703446 -285.813754)
		(end 321.99072 -285.52648)
		(width 0.14478)
		(layer "In13.Cu")
		(net "M_B_CPU0_SB_DQ<16>")
	)
	(segment
		(start 310.786526 -296.935906)
		(end 310.786526 -296.730674)
		(width 0.14478)
		(layer "In13.Cu")
		(net "M_B_CPU0_SB_DQ<16>")
	)
	(segment
		(start 321.99072 -285.52648)
		(end 322.195952 -285.52648)
		(width 0.14478)
		(layer "In13.Cu")
		(net "M_B_CPU0_SB_DQ<16>")
	)
	(segment
		(start 304.98669 -300.31817)
		(end 304.98669 -300.113446)
		(width 0.14478)
		(layer "In13.Cu")
		(net "M_B_CPU0_SB_DQ<16>")
	)
	(segment
		(start 309.226966 -298.290234)
		(end 309.51424 -298.00296)
		(width 0.14478)
		(layer "In13.Cu")
		(net "M_B_CPU0_SB_DQ<16>")
	)
	(segment
		(start 331.52969 -284.133544)
		(end 331.538072 -284.128718)
		(width 0.0889)
		(layer "In13.Cu")
		(net "M_B_CPU0_SB_DQ<16>")
	)
	(segment
		(start 311.566306 -296.156126)
		(end 311.566306 -295.950894)
		(width 0.14478)
		(layer "In13.Cu")
		(net "M_B_CPU0_SB_DQ<16>")
	)
	(segment
		(start 303.81956 -300.822106)
		(end 303.81956 -300.099476)
		(width 0.14478)
		(layer "In13.Cu")
		(net "M_B_CPU0_SB_DQ<16>")
	)
	(segment
		(start 315.177932 -292.5445)
		(end 315.465206 -292.257226)
		(width 0.14478)
		(layer "In13.Cu")
		(net "M_B_CPU0_SB_DQ<16>")
	)
	(segment
		(start 319.364106 -288.153094)
		(end 319.65138 -287.86582)
		(width 0.14478)
		(layer "In13.Cu")
		(net "M_B_CPU0_SB_DQ<16>")
	)
	(segment
		(start 312.346086 -295.376346)
		(end 312.346086 -295.171114)
		(width 0.14478)
		(layer "In13.Cu")
		(net "M_B_CPU0_SB_DQ<16>")
	)
	(segment
		(start 304.20945 -299.937932)
		(end 304.370994 -300.099476)
		(width 0.14478)
		(layer "In13.Cu")
		(net "M_B_CPU0_SB_DQ<16>")
	)
	(segment
		(start 301.125382 -300.141132)
		(end 302.046894 -300.141132)
		(width 0.14478)
		(layer "In13.Cu")
		(net "M_B_CPU0_SB_DQ<16>")
	)
	(segment
		(start 318.584326 -288.932874)
		(end 318.8716 -288.6456)
		(width 0.14478)
		(layer "In13.Cu")
		(net "M_B_CPU0_SB_DQ<16>")
	)
	(segment
		(start 303.658016 -300.98365)
		(end 303.81956 -300.822106)
		(width 0.14478)
		(layer "In13.Cu")
		(net "M_B_CPU0_SB_DQ<16>")
	)
	(segment
		(start 328.333608 -284.122622)
		(end 328.344022 -284.128718)
		(width 0.0889)
		(layer "In13.Cu")
		(net "M_B_CPU0_SB_DQ<16>")
	)
	(segment
		(start 333.984092 -284.128718)
		(end 333.992474 -284.133544)
		(width 0.0889)
		(layer "In13.Cu")
		(net "M_B_CPU0_SB_DQ<16>")
	)
	(segment
		(start 321.21094 -286.30626)
		(end 321.416172 -286.30626)
		(width 0.14478)
		(layer "In13.Cu")
		(net "M_B_CPU0_SB_DQ<16>")
	)
	(segment
		(start 312.838592 -294.88384)
		(end 313.125866 -294.596566)
		(width 0.14478)
		(layer "In13.Cu")
		(net "M_B_CPU0_SB_DQ<16>")
	)
	(segment
		(start 320.143886 -287.373314)
		(end 320.43116 -287.08604)
		(width 0.14478)
		(layer "In13.Cu")
		(net "M_B_CPU0_SB_DQ<16>")
	)
	(segment
		(start 325.907146 -283.946092)
		(end 326.140318 -284.179264)
		(width 0.0889)
		(layer "In13.Cu")
		(net "M_B_CPU0_SB_DQ<16>")
	)
	(segment
		(start 327.403206 -284.128718)
		(end 327.411588 -284.133544)
		(width 0.0889)
		(layer "In13.Cu")
		(net "M_B_CPU0_SB_DQ<16>")
	)
	(segment
		(start 306.940712 -300.14291)
		(end 307.32349 -299.760132)
		(width 0.14478)
		(layer "In13.Cu")
		(net "M_B_CPU0_SB_DQ<16>")
	)
	(segment
		(start 300.980602 -299.63999)
		(end 300.980602 -299.996352)
		(width 0.14478)
		(layer "In13.Cu")
		(net "M_B_CPU0_SB_DQ<16>")
	)
	(segment
		(start 314.685426 -293.037006)
		(end 314.685426 -292.831774)
		(width 0.14478)
		(layer "In13.Cu")
		(net "M_B_CPU0_SB_DQ<16>")
	)
	(segment
		(start 316.53226 -290.98494)
		(end 316.737492 -290.98494)
		(width 0.14478)
		(layer "In13.Cu")
		(net "M_B_CPU0_SB_DQ<16>")
	)
	(segment
		(start 317.31204 -290.20516)
		(end 317.517272 -290.20516)
		(width 0.14478)
		(layer "In13.Cu")
		(net "M_B_CPU0_SB_DQ<16>")
	)
	(segment
		(start 299.868082 -300.141132)
		(end 300.284642 -300.141132)
		(width 0.14478)
		(layer "In13.Cu")
		(net "M_B_CPU0_SB_DQ<16>")
	)
	(segment
		(start 333.044038 -284.128718)
		(end 333.05242 -284.133544)
		(width 0.0889)
		(layer "In13.Cu")
		(net "M_B_CPU0_SB_DQ<16>")
	)
	(segment
		(start 314.685426 -292.831774)
		(end 314.9727 -292.5445)
		(width 0.14478)
		(layer "In13.Cu")
		(net "M_B_CPU0_SB_DQ<16>")
	)
	(segment
		(start 303.981104 -299.937932)
		(end 304.20945 -299.937932)
		(width 0.14478)
		(layer "In13.Cu")
		(net "M_B_CPU0_SB_DQ<16>")
	)
	(segment
		(start 315.75248 -291.76472)
		(end 315.957712 -291.76472)
		(width 0.14478)
		(layer "In13.Cu")
		(net "M_B_CPU0_SB_DQ<16>")
	)
	(segment
		(start 313.905646 -293.816786)
		(end 313.905646 -293.611554)
		(width 0.14478)
		(layer "In13.Cu")
		(net "M_B_CPU0_SB_DQ<16>")
	)
	(segment
		(start 313.41314 -294.10406)
		(end 313.618372 -294.10406)
		(width 0.14478)
		(layer "In13.Cu")
		(net "M_B_CPU0_SB_DQ<16>")
	)
	(segment
		(start 306.71008 -300.14291)
		(end 306.940712 -300.14291)
		(width 0.14478)
		(layer "In13.Cu")
		(net "M_B_CPU0_SB_DQ<16>")
	)
	(segment
		(start 304.532538 -300.98365)
		(end 304.726594 -300.98365)
		(width 0.14478)
		(layer "In13.Cu")
		(net "M_B_CPU0_SB_DQ<16>")
	)
	(segment
		(start 300.429422 -299.996352)
		(end 300.429422 -299.63999)
		(width 0.14478)
		(layer "In13.Cu")
		(net "M_B_CPU0_SB_DQ<16>")
	)
	(segment
		(start 300.835822 -299.49521)
		(end 300.980602 -299.63999)
		(width 0.14478)
		(layer "In13.Cu")
		(net "M_B_CPU0_SB_DQ<16>")
	)
	(segment
		(start 305.08702 -300.4185)
		(end 304.98669 -300.31817)
		(width 0.14478)
		(layer "In13.Cu")
		(net "M_B_CPU0_SB_DQ<16>")
	)
	(segment
		(start 312.63336 -294.88384)
		(end 312.838592 -294.88384)
		(width 0.14478)
		(layer "In13.Cu")
		(net "M_B_CPU0_SB_DQ<16>")
	)
	(segment
		(start 317.804546 -289.917886)
		(end 317.804546 -289.712654)
		(width 0.14478)
		(layer "In13.Cu")
		(net "M_B_CPU0_SB_DQ<16>")
	)
	(segment
		(start 303.81956 -300.099476)
		(end 303.981104 -299.937932)
		(width 0.14478)
		(layer "In13.Cu")
		(net "M_B_CPU0_SB_DQ<16>")
	)
	(segment
		(start 316.737492 -290.98494)
		(end 317.024766 -290.697666)
		(width 0.14478)
		(layer "In13.Cu")
		(net "M_B_CPU0_SB_DQ<16>")
	)
	(segment
		(start 318.584326 -289.138106)
		(end 318.584326 -288.932874)
		(width 0.14478)
		(layer "In13.Cu")
		(net "M_B_CPU0_SB_DQ<16>")
	)
	(segment
		(start 326.140318 -284.179264)
		(end 326.650858 -284.179264)
		(width 0.0889)
		(layer "In13.Cu")
		(net "M_B_CPU0_SB_DQ<16>")
	)
	(segment
		(start 320.923666 -286.593534)
		(end 321.21094 -286.30626)
		(width 0.14478)
		(layer "In13.Cu")
		(net "M_B_CPU0_SB_DQ<16>")
	)
	(segment
		(start 302.762158 -300.705012)
		(end 303.040796 -300.98365)
		(width 0.14478)
		(layer "In13.Cu")
		(net "M_B_CPU0_SB_DQ<16>")
	)
	(segment
		(start 322.483226 -285.239206)
		(end 322.483226 -285.033974)
		(width 0.14478)
		(layer "In13.Cu")
		(net "M_B_CPU0_SB_DQ<16>")
	)
	(segment
		(start 319.65138 -287.86582)
		(end 319.856612 -287.86582)
		(width 0.14478)
		(layer "In13.Cu")
		(net "M_B_CPU0_SB_DQ<16>")
	)
	(segment
		(start 304.98669 -300.113446)
		(end 305.171856 -299.92828)
		(width 0.14478)
		(layer "In13.Cu")
		(net "M_B_CPU0_SB_DQ<16>")
	)
	(segment
		(start 312.058812 -295.66362)
		(end 312.346086 -295.376346)
		(width 0.14478)
		(layer "In13.Cu")
		(net "M_B_CPU0_SB_DQ<16>")
	)
	(segment
		(start 312.346086 -295.171114)
		(end 312.63336 -294.88384)
		(width 0.14478)
		(layer "In13.Cu")
		(net "M_B_CPU0_SB_DQ<16>")
	)
	(segment
		(start 313.125866 -294.596566)
		(end 313.125866 -294.391334)
		(width 0.14478)
		(layer "In13.Cu")
		(net "M_B_CPU0_SB_DQ<16>")
	)
	(segment
		(start 335.896966 -284.071568)
		(end 336.051144 -283.806138)
		(width 0.0889)
		(layer "In13.Cu")
		(net "M_B_CPU0_SB_DQ<16>")
	)
	(segment
		(start 305.37658 -299.92828)
		(end 305.47691 -300.02861)
		(width 0.14478)
		(layer "In13.Cu")
		(net "M_B_CPU0_SB_DQ<16>")
	)
	(segment
		(start 307.32349 -299.760132)
		(end 307.9623 -299.760132)
		(width 0.14478)
		(layer "In13.Cu")
		(net "M_B_CPU0_SB_DQ<16>")
	)
	(segment
		(start 309.51424 -298.00296)
		(end 309.719472 -298.00296)
		(width 0.14478)
		(layer "In13.Cu")
		(net "M_B_CPU0_SB_DQ<16>")
	)
	(segment
		(start 322.483226 -285.033974)
		(end 322.7705 -284.7467)
		(width 0.14478)
		(layer "In13.Cu")
		(net "M_B_CPU0_SB_DQ<16>")
	)
	(segment
		(start 305.08702 -300.623224)
		(end 305.08702 -300.4185)
		(width 0.14478)
		(layer "In13.Cu")
		(net "M_B_CPU0_SB_DQ<16>")
	)
	(segment
		(start 313.618372 -294.10406)
		(end 313.905646 -293.816786)
		(width 0.14478)
		(layer "In13.Cu")
		(net "M_B_CPU0_SB_DQ<16>")
	)
	(segment
		(start 307.9623 -299.760132)
		(end 309.226966 -298.495466)
		(width 0.14478)
		(layer "In13.Cu")
		(net "M_B_CPU0_SB_DQ<16>")
	)
	(segment
		(start 304.370994 -300.822106)
		(end 304.532538 -300.98365)
		(width 0.14478)
		(layer "In13.Cu")
		(net "M_B_CPU0_SB_DQ<16>")
	)
	(segment
		(start 300.429422 -299.63999)
		(end 300.574202 -299.49521)
		(width 0.14478)
		(layer "In13.Cu")
		(net "M_B_CPU0_SB_DQ<16>")
	)
	(segment
		(start 323.255132 -284.4673)
		(end 323.903594 -284.4673)
		(width 0.14478)
		(layer "In13.Cu")
		(net "M_B_CPU0_SB_DQ<16>")
	)
	(segment
		(start 321.703446 -286.018986)
		(end 321.703446 -285.813754)
		(width 0.14478)
		(layer "In13.Cu")
		(net "M_B_CPU0_SB_DQ<16>")
	)
	(segment
		(start 310.499252 -297.22318)
		(end 310.786526 -296.935906)
		(width 0.14478)
		(layer "In13.Cu")
		(net "M_B_CPU0_SB_DQ<16>")
	)
	(segment
		(start 305.950112 -299.760132)
		(end 306.327302 -299.760132)
		(width 0.14478)
		(layer "In13.Cu")
		(net "M_B_CPU0_SB_DQ<16>")
	)
	(segment
		(start 320.43116 -287.08604)
		(end 320.636392 -287.08604)
		(width 0.14478)
		(layer "In13.Cu")
		(net "M_B_CPU0_SB_DQ<16>")
	)
	(segment
		(start 311.85358 -295.66362)
		(end 312.058812 -295.66362)
		(width 0.14478)
		(layer "In13.Cu")
		(net "M_B_CPU0_SB_DQ<16>")
	)
	(segment
		(start 321.416172 -286.30626)
		(end 321.703446 -286.018986)
		(width 0.14478)
		(layer "In13.Cu")
		(net "M_B_CPU0_SB_DQ<16>")
	)
	(segment
		(start 328.709782 -284.133544)
		(end 328.718164 -284.128718)
		(width 0.0889)
		(layer "In13.Cu")
		(net "M_B_CPU0_SB_DQ<16>")
	)
	(arc
		(start 334.924146 -284.128718)
		(mid 335.11109 -284.178973)
		(end 335.298034 -284.128718)
		(width 0.0889)
		(layer "In13.Cu")
		(net "M_B_CPU0_SB_DQ<16>")
	)
	(arc
		(start 329.658218 -284.128718)
		(mid 329.941174 -284.052541)
		(end 330.22413 -284.128718)
		(width 0.0889)
		(layer "In13.Cu")
		(net "M_B_CPU0_SB_DQ<16>")
	)
	(arc
		(start 328.718164 -284.128718)
		(mid 329.00112 -284.052541)
		(end 329.284076 -284.128718)
		(width 0.0889)
		(layer "In13.Cu")
		(net "M_B_CPU0_SB_DQ<16>")
	)
	(arc
		(start 328.344022 -284.128718)
		(mid 328.526273 -284.179068)
		(end 328.709782 -284.133544)
		(width 0.0889)
		(layer "In13.Cu")
		(net "M_B_CPU0_SB_DQ<16>")
	)
	(arc
		(start 327.411588 -284.133544)
		(mid 327.59535 -284.17916)
		(end 327.777856 -284.128718)
		(width 0.0889)
		(layer "In13.Cu")
		(net "M_B_CPU0_SB_DQ<16>")
	)
	(arc
		(start 329.292458 -284.133544)
		(mid 329.475966 -284.179038)
		(end 329.658218 -284.128718)
		(width 0.0889)
		(layer "In13.Cu")
		(net "M_B_CPU0_SB_DQ<16>")
	)
	(arc
		(start 333.41818 -284.128718)
		(mid 333.701136 -284.052541)
		(end 333.984092 -284.128718)
		(width 0.0889)
		(layer "In13.Cu")
		(net "M_B_CPU0_SB_DQ<16>")
	)
	(arc
		(start 333.05242 -284.133544)
		(mid 333.235928 -284.179038)
		(end 333.41818 -284.128718)
		(width 0.0889)
		(layer "In13.Cu")
		(net "M_B_CPU0_SB_DQ<16>")
	)
	(arc
		(start 330.22413 -284.128718)
		(mid 330.411074 -284.178973)
		(end 330.598018 -284.128718)
		(width 0.0889)
		(layer "In13.Cu")
		(net "M_B_CPU0_SB_DQ<16>")
	)
	(arc
		(start 333.992474 -284.133544)
		(mid 334.175982 -284.179038)
		(end 334.358234 -284.128718)
		(width 0.0889)
		(layer "In13.Cu")
		(net "M_B_CPU0_SB_DQ<16>")
	)
	(arc
		(start 330.598018 -284.128718)
		(mid 330.880974 -284.052541)
		(end 331.16393 -284.128718)
		(width 0.0889)
		(layer "In13.Cu")
		(net "M_B_CPU0_SB_DQ<16>")
	)
	(arc
		(start 332.478126 -284.128718)
		(mid 332.761082 -284.052541)
		(end 333.044038 -284.128718)
		(width 0.0889)
		(layer "In13.Cu")
		(net "M_B_CPU0_SB_DQ<16>")
	)
	(arc
		(start 326.650858 -284.179264)
		(mid 326.747676 -284.166193)
		(end 326.837802 -284.128464)
		(width 0.0889)
		(layer "In13.Cu")
		(net "M_B_CPU0_SB_DQ<16>")
	)
	(arc
		(start 332.103984 -284.128718)
		(mid 332.286235 -284.179068)
		(end 332.469744 -284.133544)
		(width 0.0889)
		(layer "In13.Cu")
		(net "M_B_CPU0_SB_DQ<16>")
	)
	(arc
		(start 334.358234 -284.128718)
		(mid 334.64119 -284.052541)
		(end 334.924146 -284.128718)
		(width 0.0889)
		(layer "In13.Cu")
		(net "M_B_CPU0_SB_DQ<16>")
	)
	(arc
		(start 326.84339 -284.125162)
		(mid 327.123779 -284.052493)
		(end 327.403206 -284.128718)
		(width 0.0889)
		(layer "In13.Cu")
		(net "M_B_CPU0_SB_DQ<16>")
	)
	(arc
		(start 331.538072 -284.128718)
		(mid 331.821028 -284.052541)
		(end 332.103984 -284.128718)
		(width 0.0889)
		(layer "In13.Cu")
		(net "M_B_CPU0_SB_DQ<16>")
	)
	(arc
		(start 335.298034 -284.128718)
		(mid 335.54563 -284.05354)
		(end 335.8007 -284.096968)
		(width 0.0889)
		(layer "In13.Cu")
		(net "M_B_CPU0_SB_DQ<16>")
	)
	(arc
		(start 327.777856 -284.128718)
		(mid 328.054923 -284.052447)
		(end 328.333608 -284.122622)
		(width 0.0889)
		(layer "In13.Cu")
		(net "M_B_CPU0_SB_DQ<16>")
	)
	(arc
		(start 331.16393 -284.128718)
		(mid 331.346181 -284.179068)
		(end 331.52969 -284.133544)
		(width 0.0889)
		(layer "In13.Cu")
		(net "M_B_CPU0_SB_DQ<16>")
	)
	(segment
		(start 337.45805 -283.5402)
		(end 336.991198 -283.806138)
		(width 0.10668)
		(layer "F.Cu")
		(net "M_B_CPU0_SB_DQ<15>")
	)
	(segment
		(start 301.147988 -299.02785)
		(end 301.485046 -299.364908)
		(width 0.14478)
		(layer "In13.Cu")
		(net "M_B_CPU0_SB_DQ<15>")
	)
	(segment
		(start 300.863508 -298.909994)
		(end 301.147988 -299.02785)
		(width 0.14478)
		(layer "In13.Cu")
		(net "M_B_CPU0_SB_DQ<15>")
	)
	(segment
		(start 329.284076 -283.483558)
		(end 329.292458 -283.478732)
		(width 0.0889)
		(layer "In13.Cu")
		(net "M_B_CPU0_SB_DQ<15>")
	)
	(segment
		(start 336.229706 -283.478732)
		(end 336.238088 -283.483558)
		(width 0.0889)
		(layer "In13.Cu")
		(net "M_B_CPU0_SB_DQ<15>")
	)
	(segment
		(start 331.52969 -283.478732)
		(end 331.538072 -283.483558)
		(width 0.0889)
		(layer "In13.Cu")
		(net "M_B_CPU0_SB_DQ<15>")
	)
	(segment
		(start 333.044038 -283.483558)
		(end 333.05242 -283.478732)
		(width 0.0889)
		(layer "In13.Cu")
		(net "M_B_CPU0_SB_DQ<15>")
	)
	(segment
		(start 301.485046 -299.364908)
		(end 305.463702 -299.364908)
		(width 0.14478)
		(layer "In13.Cu")
		(net "M_B_CPU0_SB_DQ<15>")
	)
	(segment
		(start 332.469744 -283.478732)
		(end 332.478126 -283.483558)
		(width 0.0889)
		(layer "In13.Cu")
		(net "M_B_CPU0_SB_DQ<15>")
	)
	(segment
		(start 308.287674 -298.44111)
		(end 322.817744 -283.91104)
		(width 0.14478)
		(layer "In13.Cu")
		(net "M_B_CPU0_SB_DQ<15>")
	)
	(segment
		(start 337.145122 -283.540708)
		(end 336.991198 -283.806138)
		(width 0.0889)
		(layer "In13.Cu")
		(net "M_B_CPU0_SB_DQ<15>")
	)
	(segment
		(start 337.12277 -283.457396)
		(end 337.145122 -283.540708)
		(width 0.0889)
		(layer "In13.Cu")
		(net "M_B_CPU0_SB_DQ<15>")
	)
	(segment
		(start 305.463702 -299.364908)
		(end 305.789076 -299.230034)
		(width 0.14478)
		(layer "In13.Cu")
		(net "M_B_CPU0_SB_DQ<15>")
	)
	(segment
		(start 322.817744 -283.91104)
		(end 323.902324 -283.91104)
		(width 0.14478)
		(layer "In13.Cu")
		(net "M_B_CPU0_SB_DQ<15>")
	)
	(segment
		(start 324.26529 -283.91104)
		(end 324.74408 -283.43225)
		(width 0.0889)
		(layer "In13.Cu")
		(net "M_B_CPU0_SB_DQ<15>")
	)
	(segment
		(start 295.724072 -299.33519)
		(end 299.559218 -298.909994)
		(width 0.14478)
		(layer "In13.Cu")
		(net "M_B_CPU0_SB_DQ<15>")
	)
	(segment
		(start 323.902324 -283.91104)
		(end 324.26529 -283.91104)
		(width 0.0889)
		(layer "In13.Cu")
		(net "M_B_CPU0_SB_DQ<15>")
	)
	(segment
		(start 333.984092 -283.483558)
		(end 333.992474 -283.478732)
		(width 0.0889)
		(layer "In13.Cu")
		(net "M_B_CPU0_SB_DQ<15>")
	)
	(segment
		(start 328.709782 -283.478732)
		(end 328.718164 -283.483558)
		(width 0.0889)
		(layer "In13.Cu")
		(net "M_B_CPU0_SB_DQ<15>")
	)
	(segment
		(start 305.789076 -299.230034)
		(end 306.931568 -299.002704)
		(width 0.14478)
		(layer "In13.Cu")
		(net "M_B_CPU0_SB_DQ<15>")
	)
	(segment
		(start 327.779888 -283.483812)
		(end 327.803764 -283.497782)
		(width 0.0889)
		(layer "In13.Cu")
		(net "M_B_CPU0_SB_DQ<15>")
	)
	(segment
		(start 306.931568 -299.002704)
		(end 308.287674 -298.44111)
		(width 0.14478)
		(layer "In13.Cu")
		(net "M_B_CPU0_SB_DQ<15>")
	)
	(segment
		(start 327.37933 -283.49956)
		(end 327.407016 -283.483558)
		(width 0.0889)
		(layer "In13.Cu")
		(net "M_B_CPU0_SB_DQ<15>")
	)
	(segment
		(start 327.759822 -283.472382)
		(end 327.779888 -283.483812)
		(width 0.0889)
		(layer "In13.Cu")
		(net "M_B_CPU0_SB_DQ<15>")
	)
	(segment
		(start 324.74408 -283.43225)
		(end 326.651112 -283.43225)
		(width 0.0889)
		(layer "In13.Cu")
		(net "M_B_CPU0_SB_DQ<15>")
	)
	(segment
		(start 299.559218 -298.909994)
		(end 300.863508 -298.909994)
		(width 0.14478)
		(layer "In13.Cu")
		(net "M_B_CPU0_SB_DQ<15>")
	)
	(arc
		(start 333.41818 -283.483558)
		(mid 333.701136 -283.559735)
		(end 333.984092 -283.483558)
		(width 0.0889)
		(layer "In13.Cu")
		(net "M_B_CPU0_SB_DQ<15>")
	)
	(arc
		(start 329.658218 -283.483558)
		(mid 329.941174 -283.559735)
		(end 330.22413 -283.483558)
		(width 0.0889)
		(layer "In13.Cu")
		(net "M_B_CPU0_SB_DQ<15>")
	)
	(arc
		(start 332.478126 -283.483558)
		(mid 332.761082 -283.559735)
		(end 333.044038 -283.483558)
		(width 0.0889)
		(layer "In13.Cu")
		(net "M_B_CPU0_SB_DQ<15>")
	)
	(arc
		(start 334.358234 -283.483558)
		(mid 334.64119 -283.559735)
		(end 334.924146 -283.483558)
		(width 0.0889)
		(layer "In13.Cu")
		(net "M_B_CPU0_SB_DQ<15>")
	)
	(arc
		(start 329.292458 -283.478732)
		(mid 329.475966 -283.433238)
		(end 329.658218 -283.483558)
		(width 0.0889)
		(layer "In13.Cu")
		(net "M_B_CPU0_SB_DQ<15>")
	)
	(arc
		(start 333.05242 -283.478732)
		(mid 333.235928 -283.433238)
		(end 333.41818 -283.483558)
		(width 0.0889)
		(layer "In13.Cu")
		(net "M_B_CPU0_SB_DQ<15>")
	)
	(arc
		(start 332.103984 -283.483558)
		(mid 332.286235 -283.433208)
		(end 332.469744 -283.478732)
		(width 0.0889)
		(layer "In13.Cu")
		(net "M_B_CPU0_SB_DQ<15>")
	)
	(arc
		(start 330.598018 -283.483558)
		(mid 330.880974 -283.559735)
		(end 331.16393 -283.483558)
		(width 0.0889)
		(layer "In13.Cu")
		(net "M_B_CPU0_SB_DQ<15>")
	)
	(arc
		(start 335.863946 -283.483558)
		(mid 336.046197 -283.433208)
		(end 336.229706 -283.478732)
		(width 0.0889)
		(layer "In13.Cu")
		(net "M_B_CPU0_SB_DQ<15>")
	)
	(arc
		(start 328.718164 -283.483558)
		(mid 329.00112 -283.559735)
		(end 329.284076 -283.483558)
		(width 0.0889)
		(layer "In13.Cu")
		(net "M_B_CPU0_SB_DQ<15>")
	)
	(arc
		(start 330.22413 -283.483558)
		(mid 330.411074 -283.433303)
		(end 330.598018 -283.483558)
		(width 0.0889)
		(layer "In13.Cu")
		(net "M_B_CPU0_SB_DQ<15>")
	)
	(arc
		(start 333.992474 -283.478732)
		(mid 334.175982 -283.433238)
		(end 334.358234 -283.483558)
		(width 0.0889)
		(layer "In13.Cu")
		(net "M_B_CPU0_SB_DQ<15>")
	)
	(arc
		(start 336.238088 -283.483558)
		(mid 336.521044 -283.559735)
		(end 336.804 -283.483558)
		(width 0.0889)
		(layer "In13.Cu")
		(net "M_B_CPU0_SB_DQ<15>")
	)
	(arc
		(start 327.407016 -283.483558)
		(mid 327.582001 -283.433614)
		(end 327.759822 -283.472382)
		(width 0.0889)
		(layer "In13.Cu")
		(net "M_B_CPU0_SB_DQ<15>")
	)
	(arc
		(start 336.804 -283.483558)
		(mid 336.960438 -283.434587)
		(end 337.12277 -283.457396)
		(width 0.0889)
		(layer "In13.Cu")
		(net "M_B_CPU0_SB_DQ<15>")
	)
	(arc
		(start 331.16393 -283.483558)
		(mid 331.346181 -283.433208)
		(end 331.52969 -283.478732)
		(width 0.0889)
		(layer "In13.Cu")
		(net "M_B_CPU0_SB_DQ<15>")
	)
	(arc
		(start 328.344022 -283.483558)
		(mid 328.526273 -283.433208)
		(end 328.709782 -283.478732)
		(width 0.0889)
		(layer "In13.Cu")
		(net "M_B_CPU0_SB_DQ<15>")
	)
	(arc
		(start 326.839326 -283.483558)
		(mid 327.107295 -283.560381)
		(end 327.37933 -283.49956)
		(width 0.0889)
		(layer "In13.Cu")
		(net "M_B_CPU0_SB_DQ<15>")
	)
	(arc
		(start 327.803764 -283.497782)
		(mid 328.075701 -283.559608)
		(end 328.344022 -283.483558)
		(width 0.0889)
		(layer "In13.Cu")
		(net "M_B_CPU0_SB_DQ<15>")
	)
	(arc
		(start 335.298034 -283.483558)
		(mid 335.58099 -283.559735)
		(end 335.863946 -283.483558)
		(width 0.0889)
		(layer "In13.Cu")
		(net "M_B_CPU0_SB_DQ<15>")
	)
	(arc
		(start 331.538072 -283.483558)
		(mid 331.821028 -283.559735)
		(end 332.103984 -283.483558)
		(width 0.0889)
		(layer "In13.Cu")
		(net "M_B_CPU0_SB_DQ<15>")
	)
	(arc
		(start 326.651112 -283.43225)
		(mid 326.748626 -283.445405)
		(end 326.839326 -283.483558)
		(width 0.0889)
		(layer "In13.Cu")
		(net "M_B_CPU0_SB_DQ<15>")
	)
	(arc
		(start 334.924146 -283.483558)
		(mid 335.11109 -283.433303)
		(end 335.298034 -283.483558)
		(width 0.0889)
		(layer "In13.Cu")
		(net "M_B_CPU0_SB_DQ<15>")
	)
	(segment
		(start 336.047842 -282.730194)
		(end 335.58099 -282.996132)
		(width 0.10668)
		(layer "F.Cu")
		(net "M_B_CPU0_SB_DQ<14>")
	)
	(segment
		(start 325.462138 -282.358592)
		(end 324.786498 -282.358592)
		(width 0.0889)
		(layer "In13.Cu")
		(net "M_B_CPU0_SB_DQ<14>")
	)
	(segment
		(start 335.58099 -282.996132)
		(end 335.735168 -282.730702)
		(width 0.0889)
		(layer "In13.Cu")
		(net "M_B_CPU0_SB_DQ<14>")
	)
	(segment
		(start 326.651112 -282.749752)
		(end 325.853298 -282.749752)
		(width 0.0889)
		(layer "In13.Cu")
		(net "M_B_CPU0_SB_DQ<14>")
	)
	(segment
		(start 324.14337 -283.00172)
		(end 323.908674 -283.00172)
		(width 0.0889)
		(layer "In13.Cu")
		(net "M_B_CPU0_SB_DQ<14>")
	)
	(segment
		(start 335.402428 -282.668726)
		(end 335.394046 -282.673552)
		(width 0.0889)
		(layer "In13.Cu")
		(net "M_B_CPU0_SB_DQ<14>")
	)
	(segment
		(start 334.828134 -282.673552)
		(end 334.819752 -282.668726)
		(width 0.0889)
		(layer "In13.Cu")
		(net "M_B_CPU0_SB_DQ<14>")
	)
	(segment
		(start 333.888334 -282.673552)
		(end 333.88808 -282.673552)
		(width 0.0889)
		(layer "In13.Cu")
		(net "M_B_CPU0_SB_DQ<14>")
	)
	(segment
		(start 324.786498 -282.358592)
		(end 324.14337 -283.00172)
		(width 0.0889)
		(layer "In13.Cu")
		(net "M_B_CPU0_SB_DQ<14>")
	)
	(segment
		(start 330.702412 -282.668726)
		(end 330.69403 -282.673552)
		(width 0.0889)
		(layer "In13.Cu")
		(net "M_B_CPU0_SB_DQ<14>")
	)
	(segment
		(start 325.853298 -282.749752)
		(end 325.462138 -282.358592)
		(width 0.0889)
		(layer "In13.Cu")
		(net "M_B_CPU0_SB_DQ<14>")
	)
	(segment
		(start 296.098468 -298.06011)
		(end 295.724072 -297.685714)
		(width 0.14478)
		(layer "In13.Cu")
		(net "M_B_CPU0_SB_DQ<14>")
	)
	(segment
		(start 326.949816 -282.664408)
		(end 326.93356 -282.673806)
		(width 0.0889)
		(layer "In13.Cu")
		(net "M_B_CPU0_SB_DQ<14>")
	)
	(segment
		(start 308.239414 -297.217338)
		(end 306.212494 -297.217338)
		(width 0.14478)
		(layer "In13.Cu")
		(net "M_B_CPU0_SB_DQ<14>")
	)
	(segment
		(start 298.058078 -298.06011)
		(end 296.098468 -298.06011)
		(width 0.14478)
		(layer "In13.Cu")
		(net "M_B_CPU0_SB_DQ<14>")
	)
	(segment
		(start 333.88808 -282.673552)
		(end 333.879698 -282.668726)
		(width 0.0889)
		(layer "In13.Cu")
		(net "M_B_CPU0_SB_DQ<14>")
	)
	(segment
		(start 327.317862 -282.679648)
		(end 327.307448 -282.673552)
		(width 0.0889)
		(layer "In13.Cu")
		(net "M_B_CPU0_SB_DQ<14>")
	)
	(segment
		(start 328.248264 -282.673552)
		(end 328.239882 -282.668726)
		(width 0.0889)
		(layer "In13.Cu")
		(net "M_B_CPU0_SB_DQ<14>")
	)
	(segment
		(start 305.369722 -298.06011)
		(end 301.780702 -298.06011)
		(width 0.14478)
		(layer "In13.Cu")
		(net "M_B_CPU0_SB_DQ<14>")
	)
	(segment
		(start 300.930564 -297.209972)
		(end 298.908216 -297.209972)
		(width 0.14478)
		(layer "In13.Cu")
		(net "M_B_CPU0_SB_DQ<14>")
	)
	(segment
		(start 295.724072 -297.685714)
		(end 295.724072 -297.635168)
		(width 0.14478)
		(layer "In13.Cu")
		(net "M_B_CPU0_SB_DQ<14>")
	)
	(segment
		(start 298.908216 -297.209972)
		(end 298.058078 -298.06011)
		(width 0.14478)
		(layer "In13.Cu")
		(net "M_B_CPU0_SB_DQ<14>")
	)
	(segment
		(start 335.735168 -282.730702)
		(end 335.712816 -282.64739)
		(width 0.0889)
		(layer "In13.Cu")
		(net "M_B_CPU0_SB_DQ<14>")
	)
	(segment
		(start 306.212494 -297.217338)
		(end 305.369722 -298.06011)
		(width 0.14478)
		(layer "In13.Cu")
		(net "M_B_CPU0_SB_DQ<14>")
	)
	(segment
		(start 301.780702 -298.06011)
		(end 300.930564 -297.209972)
		(width 0.14478)
		(layer "In13.Cu")
		(net "M_B_CPU0_SB_DQ<14>")
	)
	(segment
		(start 322.455032 -283.00172)
		(end 308.239414 -297.217338)
		(width 0.14478)
		(layer "In13.Cu")
		(net "M_B_CPU0_SB_DQ<14>")
	)
	(segment
		(start 323.908674 -283.00172)
		(end 322.455032 -283.00172)
		(width 0.14478)
		(layer "In13.Cu")
		(net "M_B_CPU0_SB_DQ<14>")
	)
	(segment
		(start 330.128118 -282.673552)
		(end 330.119736 -282.668726)
		(width 0.0889)
		(layer "In13.Cu")
		(net "M_B_CPU0_SB_DQ<14>")
	)
	(segment
		(start 331.642466 -282.668726)
		(end 331.634084 -282.673552)
		(width 0.0889)
		(layer "In13.Cu")
		(net "M_B_CPU0_SB_DQ<14>")
	)
	(arc
		(start 327.307448 -282.673552)
		(mid 327.129798 -282.623292)
		(end 326.949816 -282.664408)
		(width 0.0889)
		(layer "In13.Cu")
		(net "M_B_CPU0_SB_DQ<14>")
	)
	(arc
		(start 331.068172 -282.673552)
		(mid 330.885921 -282.623202)
		(end 330.702412 -282.668726)
		(width 0.0889)
		(layer "In13.Cu")
		(net "M_B_CPU0_SB_DQ<14>")
	)
	(arc
		(start 335.394046 -282.673552)
		(mid 335.11109 -282.749729)
		(end 334.828134 -282.673552)
		(width 0.0889)
		(layer "In13.Cu")
		(net "M_B_CPU0_SB_DQ<14>")
	)
	(arc
		(start 334.453992 -282.673552)
		(mid 334.17118 -282.749601)
		(end 333.888334 -282.673552)
		(width 0.0889)
		(layer "In13.Cu")
		(net "M_B_CPU0_SB_DQ<14>")
	)
	(arc
		(start 335.712816 -282.64739)
		(mid 335.555306 -282.624192)
		(end 335.402428 -282.668726)
		(width 0.0889)
		(layer "In13.Cu")
		(net "M_B_CPU0_SB_DQ<14>")
	)
	(arc
		(start 330.69403 -282.673552)
		(mid 330.411074 -282.749729)
		(end 330.128118 -282.673552)
		(width 0.0889)
		(layer "In13.Cu")
		(net "M_B_CPU0_SB_DQ<14>")
	)
	(arc
		(start 329.188064 -282.673552)
		(mid 329.00112 -282.623297)
		(end 328.814176 -282.673552)
		(width 0.0889)
		(layer "In13.Cu")
		(net "M_B_CPU0_SB_DQ<14>")
	)
	(arc
		(start 332.008226 -282.673552)
		(mid 331.825975 -282.623202)
		(end 331.642466 -282.668726)
		(width 0.0889)
		(layer "In13.Cu")
		(net "M_B_CPU0_SB_DQ<14>")
	)
	(arc
		(start 328.814176 -282.673552)
		(mid 328.53122 -282.749729)
		(end 328.248264 -282.673552)
		(width 0.0889)
		(layer "In13.Cu")
		(net "M_B_CPU0_SB_DQ<14>")
	)
	(arc
		(start 332.574138 -282.673552)
		(mid 332.291182 -282.749729)
		(end 332.008226 -282.673552)
		(width 0.0889)
		(layer "In13.Cu")
		(net "M_B_CPU0_SB_DQ<14>")
	)
	(arc
		(start 333.879698 -282.668726)
		(mid 333.69619 -282.623232)
		(end 333.513938 -282.673552)
		(width 0.0889)
		(layer "In13.Cu")
		(net "M_B_CPU0_SB_DQ<14>")
	)
	(arc
		(start 333.513938 -282.673552)
		(mid 333.230982 -282.749729)
		(end 332.948026 -282.673552)
		(width 0.0889)
		(layer "In13.Cu")
		(net "M_B_CPU0_SB_DQ<14>")
	)
	(arc
		(start 326.93356 -282.673806)
		(mid 326.797345 -282.730391)
		(end 326.651112 -282.749752)
		(width 0.0889)
		(layer "In13.Cu")
		(net "M_B_CPU0_SB_DQ<14>")
	)
	(arc
		(start 329.753976 -282.673552)
		(mid 329.47102 -282.749729)
		(end 329.188064 -282.673552)
		(width 0.0889)
		(layer "In13.Cu")
		(net "M_B_CPU0_SB_DQ<14>")
	)
	(arc
		(start 327.873614 -282.673552)
		(mid 327.596547 -282.749823)
		(end 327.317862 -282.679648)
		(width 0.0889)
		(layer "In13.Cu")
		(net "M_B_CPU0_SB_DQ<14>")
	)
	(arc
		(start 328.239882 -282.668726)
		(mid 328.05612 -282.62311)
		(end 327.873614 -282.673552)
		(width 0.0889)
		(layer "In13.Cu")
		(net "M_B_CPU0_SB_DQ<14>")
	)
	(arc
		(start 332.948026 -282.673552)
		(mid 332.761082 -282.623297)
		(end 332.574138 -282.673552)
		(width 0.0889)
		(layer "In13.Cu")
		(net "M_B_CPU0_SB_DQ<14>")
	)
	(arc
		(start 330.119736 -282.668726)
		(mid 329.936228 -282.623232)
		(end 329.753976 -282.673552)
		(width 0.0889)
		(layer "In13.Cu")
		(net "M_B_CPU0_SB_DQ<14>")
	)
	(arc
		(start 331.634084 -282.673552)
		(mid 331.351128 -282.749729)
		(end 331.068172 -282.673552)
		(width 0.0889)
		(layer "In13.Cu")
		(net "M_B_CPU0_SB_DQ<14>")
	)
	(arc
		(start 334.819752 -282.668726)
		(mid 334.636244 -282.623232)
		(end 334.453992 -282.673552)
		(width 0.0889)
		(layer "In13.Cu")
		(net "M_B_CPU0_SB_DQ<14>")
	)
	(segment
		(start 337.92795 -282.730194)
		(end 337.461098 -282.996132)
		(width 0.10668)
		(layer "F.Cu")
		(net "M_B_CPU0_SB_DQ<13>")
	)
	(segment
		(start 300.441614 -298.193206)
		(end 300.441614 -297.908472)
		(width 0.14478)
		(layer "In13.Cu")
		(net "M_B_CPU0_SB_DQ<13>")
	)
	(segment
		(start 337.211162 -283.286962)
		(end 337.307174 -283.261562)
		(width 0.0889)
		(layer "In13.Cu")
		(net "M_B_CPU0_SB_DQ<13>")
	)
	(segment
		(start 327.292208 -283.329634)
		(end 327.311004 -283.318712)
		(width 0.0889)
		(layer "In13.Cu")
		(net "M_B_CPU0_SB_DQ<13>")
	)
	(segment
		(start 306.88788 -297.851576)
		(end 306.88788 -298.197524)
		(width 0.14478)
		(layer "In13.Cu")
		(net "M_B_CPU0_SB_DQ<13>")
	)
	(segment
		(start 322.636388 -283.45638)
		(end 323.903594 -283.45638)
		(width 0.14478)
		(layer "In13.Cu")
		(net "M_B_CPU0_SB_DQ<13>")
	)
	(segment
		(start 302.946308 -298.910248)
		(end 303.878742 -298.910248)
		(width 0.14478)
		(layer "In13.Cu")
		(net "M_B_CPU0_SB_DQ<13>")
	)
	(segment
		(start 304.040286 -298.682156)
		(end 304.20183 -298.520612)
		(width 0.14478)
		(layer "In13.Cu")
		(net "M_B_CPU0_SB_DQ<13>")
	)
	(segment
		(start 305.369722 -298.910248)
		(end 305.688238 -298.591732)
		(width 0.14478)
		(layer "In13.Cu")
		(net "M_B_CPU0_SB_DQ<13>")
	)
	(segment
		(start 302.801528 -298.694602)
		(end 302.801528 -298.765468)
		(width 0.14478)
		(layer "In13.Cu")
		(net "M_B_CPU0_SB_DQ<13>")
	)
	(segment
		(start 306.19192 -298.591732)
		(end 306.3367 -298.446952)
		(width 0.14478)
		(layer "In13.Cu")
		(net "M_B_CPU0_SB_DQ<13>")
	)
	(segment
		(start 304.430176 -298.520612)
		(end 304.59172 -298.682156)
		(width 0.14478)
		(layer "In13.Cu")
		(net "M_B_CPU0_SB_DQ<13>")
	)
	(segment
		(start 304.59172 -298.748704)
		(end 304.753264 -298.910248)
		(width 0.14478)
		(layer "In13.Cu")
		(net "M_B_CPU0_SB_DQ<13>")
	)
	(segment
		(start 303.878742 -298.910248)
		(end 304.040286 -298.748704)
		(width 0.14478)
		(layer "In13.Cu")
		(net "M_B_CPU0_SB_DQ<13>")
	)
	(segment
		(start 330.119736 -283.323538)
		(end 330.128118 -283.318712)
		(width 0.0889)
		(layer "In13.Cu")
		(net "M_B_CPU0_SB_DQ<13>")
	)
	(segment
		(start 334.819752 -283.323538)
		(end 334.828134 -283.318712)
		(width 0.0889)
		(layer "In13.Cu")
		(net "M_B_CPU0_SB_DQ<13>")
	)
	(segment
		(start 300.848014 -297.763692)
		(end 300.992794 -297.908472)
		(width 0.14478)
		(layer "In13.Cu")
		(net "M_B_CPU0_SB_DQ<13>")
	)
	(segment
		(start 327.875138 -283.318458)
		(end 327.896982 -283.330904)
		(width 0.0889)
		(layer "In13.Cu")
		(net "M_B_CPU0_SB_DQ<13>")
	)
	(segment
		(start 300.441614 -297.908472)
		(end 300.586394 -297.763692)
		(width 0.14478)
		(layer "In13.Cu")
		(net "M_B_CPU0_SB_DQ<13>")
	)
	(segment
		(start 300.992794 -297.908472)
		(end 300.992794 -298.340272)
		(width 0.14478)
		(layer "In13.Cu")
		(net "M_B_CPU0_SB_DQ<13>")
	)
	(segment
		(start 308.082442 -298.010326)
		(end 322.636388 -283.45638)
		(width 0.14478)
		(layer "In13.Cu")
		(net "M_B_CPU0_SB_DQ<13>")
	)
	(segment
		(start 302.801528 -298.765468)
		(end 302.946308 -298.910248)
		(width 0.14478)
		(layer "In13.Cu")
		(net "M_B_CPU0_SB_DQ<13>")
	)
	(segment
		(start 307.280818 -298.342304)
		(end 308.082442 -298.010326)
		(width 0.14478)
		(layer "In13.Cu")
		(net "M_B_CPU0_SB_DQ<13>")
	)
	(segment
		(start 301.422054 -298.485052)
		(end 301.84725 -298.910248)
		(width 0.14478)
		(layer "In13.Cu")
		(net "M_B_CPU0_SB_DQ<13>")
	)
	(segment
		(start 305.688238 -298.591732)
		(end 306.19192 -298.591732)
		(width 0.14478)
		(layer "In13.Cu")
		(net "M_B_CPU0_SB_DQ<13>")
	)
	(segment
		(start 301.84725 -298.910248)
		(end 302.105568 -298.910248)
		(width 0.14478)
		(layer "In13.Cu")
		(net "M_B_CPU0_SB_DQ<13>")
	)
	(segment
		(start 306.88788 -298.197524)
		(end 307.03266 -298.342304)
		(width 0.14478)
		(layer "In13.Cu")
		(net "M_B_CPU0_SB_DQ<13>")
	)
	(segment
		(start 304.20183 -298.520612)
		(end 304.430176 -298.520612)
		(width 0.14478)
		(layer "In13.Cu")
		(net "M_B_CPU0_SB_DQ<13>")
	)
	(segment
		(start 302.250348 -298.765468)
		(end 302.250348 -298.694602)
		(width 0.14478)
		(layer "In13.Cu")
		(net "M_B_CPU0_SB_DQ<13>")
	)
	(segment
		(start 301.137574 -298.485052)
		(end 301.422054 -298.485052)
		(width 0.14478)
		(layer "In13.Cu")
		(net "M_B_CPU0_SB_DQ<13>")
	)
	(segment
		(start 302.250348 -298.694602)
		(end 302.395128 -298.549822)
		(width 0.14478)
		(layer "In13.Cu")
		(net "M_B_CPU0_SB_DQ<13>")
	)
	(segment
		(start 335.394046 -283.318712)
		(end 335.402428 -283.323538)
		(width 0.0889)
		(layer "In13.Cu")
		(net "M_B_CPU0_SB_DQ<13>")
	)
	(segment
		(start 330.69403 -283.318712)
		(end 330.702412 -283.323538)
		(width 0.0889)
		(layer "In13.Cu")
		(net "M_B_CPU0_SB_DQ<13>")
	)
	(segment
		(start 324.23481 -283.45638)
		(end 324.44944 -283.24175)
		(width 0.0889)
		(layer "In13.Cu")
		(net "M_B_CPU0_SB_DQ<13>")
	)
	(segment
		(start 306.3367 -297.851576)
		(end 306.48148 -297.706796)
		(width 0.14478)
		(layer "In13.Cu")
		(net "M_B_CPU0_SB_DQ<13>")
	)
	(segment
		(start 331.634084 -283.318712)
		(end 331.642466 -283.323538)
		(width 0.0889)
		(layer "In13.Cu")
		(net "M_B_CPU0_SB_DQ<13>")
	)
	(segment
		(start 337.307174 -283.261562)
		(end 337.461098 -282.996132)
		(width 0.0889)
		(layer "In13.Cu")
		(net "M_B_CPU0_SB_DQ<13>")
	)
	(segment
		(start 307.03266 -298.342304)
		(end 307.280818 -298.342304)
		(width 0.14478)
		(layer "In13.Cu")
		(net "M_B_CPU0_SB_DQ<13>")
	)
	(segment
		(start 336.3341 -283.318712)
		(end 336.342482 -283.323538)
		(width 0.0889)
		(layer "In13.Cu")
		(net "M_B_CPU0_SB_DQ<13>")
	)
	(segment
		(start 304.59172 -298.682156)
		(end 304.59172 -298.748704)
		(width 0.14478)
		(layer "In13.Cu")
		(net "M_B_CPU0_SB_DQ<13>")
	)
	(segment
		(start 333.879698 -283.323538)
		(end 333.88808 -283.318712)
		(width 0.0889)
		(layer "In13.Cu")
		(net "M_B_CPU0_SB_DQ<13>")
	)
	(segment
		(start 304.753264 -298.910248)
		(end 305.369722 -298.910248)
		(width 0.14478)
		(layer "In13.Cu")
		(net "M_B_CPU0_SB_DQ<13>")
	)
	(segment
		(start 300.992794 -298.340272)
		(end 301.137574 -298.485052)
		(width 0.14478)
		(layer "In13.Cu")
		(net "M_B_CPU0_SB_DQ<13>")
	)
	(segment
		(start 304.040286 -298.748704)
		(end 304.040286 -298.682156)
		(width 0.14478)
		(layer "In13.Cu")
		(net "M_B_CPU0_SB_DQ<13>")
	)
	(segment
		(start 300.586394 -297.763692)
		(end 300.848014 -297.763692)
		(width 0.14478)
		(layer "In13.Cu")
		(net "M_B_CPU0_SB_DQ<13>")
	)
	(segment
		(start 306.7431 -297.706796)
		(end 306.88788 -297.851576)
		(width 0.14478)
		(layer "In13.Cu")
		(net "M_B_CPU0_SB_DQ<13>")
	)
	(segment
		(start 323.903594 -283.45638)
		(end 324.23481 -283.45638)
		(width 0.0889)
		(layer "In13.Cu")
		(net "M_B_CPU0_SB_DQ<13>")
	)
	(segment
		(start 306.3367 -298.446952)
		(end 306.3367 -297.851576)
		(width 0.14478)
		(layer "In13.Cu")
		(net "M_B_CPU0_SB_DQ<13>")
	)
	(segment
		(start 299.971206 -298.337986)
		(end 300.296834 -298.337986)
		(width 0.14478)
		(layer "In13.Cu")
		(net "M_B_CPU0_SB_DQ<13>")
	)
	(segment
		(start 306.48148 -297.706796)
		(end 306.7431 -297.706796)
		(width 0.14478)
		(layer "In13.Cu")
		(net "M_B_CPU0_SB_DQ<13>")
	)
	(segment
		(start 324.44944 -283.24175)
		(end 326.651112 -283.24175)
		(width 0.0889)
		(layer "In13.Cu")
		(net "M_B_CPU0_SB_DQ<13>")
	)
	(segment
		(start 302.105568 -298.910248)
		(end 302.250348 -298.765468)
		(width 0.14478)
		(layer "In13.Cu")
		(net "M_B_CPU0_SB_DQ<13>")
	)
	(segment
		(start 300.296834 -298.337986)
		(end 300.441614 -298.193206)
		(width 0.14478)
		(layer "In13.Cu")
		(net "M_B_CPU0_SB_DQ<13>")
	)
	(segment
		(start 302.656748 -298.549822)
		(end 302.801528 -298.694602)
		(width 0.14478)
		(layer "In13.Cu")
		(net "M_B_CPU0_SB_DQ<13>")
	)
	(segment
		(start 302.395128 -298.549822)
		(end 302.656748 -298.549822)
		(width 0.14478)
		(layer "In13.Cu")
		(net "M_B_CPU0_SB_DQ<13>")
	)
	(segment
		(start 333.88808 -283.318712)
		(end 333.888334 -283.318712)
		(width 0.0889)
		(layer "In13.Cu")
		(net "M_B_CPU0_SB_DQ<13>")
	)
	(segment
		(start 327.851262 -283.304488)
		(end 327.875138 -283.318458)
		(width 0.0889)
		(layer "In13.Cu")
		(net "M_B_CPU0_SB_DQ<13>")
	)
	(segment
		(start 299.82414 -298.485052)
		(end 299.971206 -298.337986)
		(width 0.14478)
		(layer "In13.Cu")
		(net "M_B_CPU0_SB_DQ<13>")
	)
	(arc
		(start 336.708242 -283.318712)
		(mid 336.955955 -283.243492)
		(end 337.211162 -283.286962)
		(width 0.0889)
		(layer "In13.Cu")
		(net "M_B_CPU0_SB_DQ<13>")
	)
	(arc
		(start 328.814176 -283.318712)
		(mid 329.00112 -283.368967)
		(end 329.188064 -283.318712)
		(width 0.0889)
		(layer "In13.Cu")
		(net "M_B_CPU0_SB_DQ<13>")
	)
	(arc
		(start 335.768188 -283.318712)
		(mid 336.051144 -283.242535)
		(end 336.3341 -283.318712)
		(width 0.0889)
		(layer "In13.Cu")
		(net "M_B_CPU0_SB_DQ<13>")
	)
	(arc
		(start 329.188064 -283.318712)
		(mid 329.47102 -283.242535)
		(end 329.753976 -283.318712)
		(width 0.0889)
		(layer "In13.Cu")
		(net "M_B_CPU0_SB_DQ<13>")
	)
	(arc
		(start 326.935846 -283.318712)
		(mid 327.112637 -283.369431)
		(end 327.292208 -283.329634)
		(width 0.0889)
		(layer "In13.Cu")
		(net "M_B_CPU0_SB_DQ<13>")
	)
	(arc
		(start 327.896982 -283.330904)
		(mid 328.074164 -283.368844)
		(end 328.248264 -283.318712)
		(width 0.0889)
		(layer "In13.Cu")
		(net "M_B_CPU0_SB_DQ<13>")
	)
	(arc
		(start 333.888334 -283.318712)
		(mid 334.17118 -283.242535)
		(end 334.453992 -283.318712)
		(width 0.0889)
		(layer "In13.Cu")
		(net "M_B_CPU0_SB_DQ<13>")
	)
	(arc
		(start 326.651112 -283.24175)
		(mid 326.798599 -283.261293)
		(end 326.935846 -283.318712)
		(width 0.0889)
		(layer "In13.Cu")
		(net "M_B_CPU0_SB_DQ<13>")
	)
	(arc
		(start 334.453992 -283.318712)
		(mid 334.636243 -283.369062)
		(end 334.819752 -283.323538)
		(width 0.0889)
		(layer "In13.Cu")
		(net "M_B_CPU0_SB_DQ<13>")
	)
	(arc
		(start 327.311004 -283.318712)
		(mid 327.579324 -283.242604)
		(end 327.851262 -283.304488)
		(width 0.0889)
		(layer "In13.Cu")
		(net "M_B_CPU0_SB_DQ<13>")
	)
	(arc
		(start 336.342482 -283.323538)
		(mid 336.52599 -283.369032)
		(end 336.708242 -283.318712)
		(width 0.0889)
		(layer "In13.Cu")
		(net "M_B_CPU0_SB_DQ<13>")
	)
	(arc
		(start 330.702412 -283.323538)
		(mid 330.88592 -283.369032)
		(end 331.068172 -283.318712)
		(width 0.0889)
		(layer "In13.Cu")
		(net "M_B_CPU0_SB_DQ<13>")
	)
	(arc
		(start 333.513938 -283.318712)
		(mid 333.696189 -283.369062)
		(end 333.879698 -283.323538)
		(width 0.0889)
		(layer "In13.Cu")
		(net "M_B_CPU0_SB_DQ<13>")
	)
	(arc
		(start 331.642466 -283.323538)
		(mid 331.825974 -283.369032)
		(end 332.008226 -283.318712)
		(width 0.0889)
		(layer "In13.Cu")
		(net "M_B_CPU0_SB_DQ<13>")
	)
	(arc
		(start 335.402428 -283.323538)
		(mid 335.585936 -283.369032)
		(end 335.768188 -283.318712)
		(width 0.0889)
		(layer "In13.Cu")
		(net "M_B_CPU0_SB_DQ<13>")
	)
	(arc
		(start 329.753976 -283.318712)
		(mid 329.936227 -283.369062)
		(end 330.119736 -283.323538)
		(width 0.0889)
		(layer "In13.Cu")
		(net "M_B_CPU0_SB_DQ<13>")
	)
	(arc
		(start 330.128118 -283.318712)
		(mid 330.411074 -283.242535)
		(end 330.69403 -283.318712)
		(width 0.0889)
		(layer "In13.Cu")
		(net "M_B_CPU0_SB_DQ<13>")
	)
	(arc
		(start 332.008226 -283.318712)
		(mid 332.291182 -283.242535)
		(end 332.574138 -283.318712)
		(width 0.0889)
		(layer "In13.Cu")
		(net "M_B_CPU0_SB_DQ<13>")
	)
	(arc
		(start 334.828134 -283.318712)
		(mid 335.11109 -283.242535)
		(end 335.394046 -283.318712)
		(width 0.0889)
		(layer "In13.Cu")
		(net "M_B_CPU0_SB_DQ<13>")
	)
	(arc
		(start 328.248264 -283.318712)
		(mid 328.53122 -283.242535)
		(end 328.814176 -283.318712)
		(width 0.0889)
		(layer "In13.Cu")
		(net "M_B_CPU0_SB_DQ<13>")
	)
	(arc
		(start 331.068172 -283.318712)
		(mid 331.351128 -283.242535)
		(end 331.634084 -283.318712)
		(width 0.0889)
		(layer "In13.Cu")
		(net "M_B_CPU0_SB_DQ<13>")
	)
	(arc
		(start 332.948026 -283.318712)
		(mid 333.230982 -283.242535)
		(end 333.513938 -283.318712)
		(width 0.0889)
		(layer "In13.Cu")
		(net "M_B_CPU0_SB_DQ<13>")
	)
	(arc
		(start 332.574138 -283.318712)
		(mid 332.761082 -283.368967)
		(end 332.948026 -283.318712)
		(width 0.0889)
		(layer "In13.Cu")
		(net "M_B_CPU0_SB_DQ<13>")
	)
	(segment
		(start 336.517996 -281.920188)
		(end 336.051144 -282.186126)
		(width 0.10668)
		(layer "F.Cu")
		(net "M_B_CPU0_SB_DQ<12>")
	)
	(segment
		(start 305.501802 -297.284902)
		(end 305.501802 -297.080178)
		(width 0.14478)
		(layer "In13.Cu")
		(net "M_B_CPU0_SB_DQ<12>")
	)
	(segment
		(start 307.163724 -296.041064)
		(end 307.308504 -296.185844)
		(width 0.14478)
		(layer "In13.Cu")
		(net "M_B_CPU0_SB_DQ<12>")
	)
	(segment
		(start 302.482758 -297.368976)
		(end 302.482758 -297.018202)
		(width 0.14478)
		(layer "In13.Cu")
		(net "M_B_CPU0_SB_DQ<12>")
	)
	(segment
		(start 323.898514 -282.54706)
		(end 324.19671 -282.54706)
		(width 0.0889)
		(layer "In13.Cu")
		(net "M_B_CPU0_SB_DQ<12>")
	)
	(segment
		(start 322.273676 -282.54706)
		(end 323.898514 -282.54706)
		(width 0.14478)
		(layer "In13.Cu")
		(net "M_B_CPU0_SB_DQ<12>")
	)
	(segment
		(start 303.595278 -297.452288)
		(end 303.595278 -297.017186)
		(width 0.14478)
		(layer "In13.Cu")
		(net "M_B_CPU0_SB_DQ<12>")
	)
	(segment
		(start 303.437036 -297.61053)
		(end 303.595278 -297.452288)
		(width 0.14478)
		(layer "In13.Cu")
		(net "M_B_CPU0_SB_DQ<12>")
	)
	(segment
		(start 332.469744 -282.513532)
		(end 332.478126 -282.508706)
		(width 0.0889)
		(layer "In13.Cu")
		(net "M_B_CPU0_SB_DQ<12>")
	)
	(segment
		(start 335.896966 -282.451556)
		(end 336.051144 -282.186126)
		(width 0.0889)
		(layer "In13.Cu")
		(net "M_B_CPU0_SB_DQ<12>")
	)
	(segment
		(start 324.575678 -282.168092)
		(end 325.541132 -282.168092)
		(width 0.0889)
		(layer "In13.Cu")
		(net "M_B_CPU0_SB_DQ<12>")
	)
	(segment
		(start 303.595278 -297.017186)
		(end 303.752504 -296.85996)
		(width 0.14478)
		(layer "In13.Cu")
		(net "M_B_CPU0_SB_DQ<12>")
	)
	(segment
		(start 302.337978 -297.513756)
		(end 302.482758 -297.368976)
		(width 0.14478)
		(layer "In13.Cu")
		(net "M_B_CPU0_SB_DQ<12>")
	)
	(segment
		(start 306.74564 -296.041064)
		(end 307.163724 -296.041064)
		(width 0.14478)
		(layer "In13.Cu")
		(net "M_B_CPU0_SB_DQ<12>")
	)
	(segment
		(start 305.501802 -297.080178)
		(end 305.364134 -296.94251)
		(width 0.14478)
		(layer "In13.Cu")
		(net "M_B_CPU0_SB_DQ<12>")
	)
	(segment
		(start 304.784252 -297.60291)
		(end 305.183794 -297.60291)
		(width 0.14478)
		(layer "In13.Cu")
		(net "M_B_CPU0_SB_DQ<12>")
	)
	(segment
		(start 302.641 -296.85996)
		(end 302.880776 -296.85996)
		(width 0.14478)
		(layer "In13.Cu")
		(net "M_B_CPU0_SB_DQ<12>")
	)
	(segment
		(start 307.308504 -296.185844)
		(end 307.308504 -296.60215)
		(width 0.14478)
		(layer "In13.Cu")
		(net "M_B_CPU0_SB_DQ<12>")
	)
	(segment
		(start 301.870364 -297.513756)
		(end 302.337978 -297.513756)
		(width 0.14478)
		(layer "In13.Cu")
		(net "M_B_CPU0_SB_DQ<12>")
	)
	(segment
		(start 305.364134 -296.94251)
		(end 305.364134 -296.737786)
		(width 0.14478)
		(layer "In13.Cu")
		(net "M_B_CPU0_SB_DQ<12>")
	)
	(segment
		(start 324.19671 -282.54706)
		(end 324.575678 -282.168092)
		(width 0.0889)
		(layer "In13.Cu")
		(net "M_B_CPU0_SB_DQ<12>")
	)
	(segment
		(start 304.041302 -296.85996)
		(end 304.784252 -297.60291)
		(width 0.14478)
		(layer "In13.Cu")
		(net "M_B_CPU0_SB_DQ<12>")
	)
	(segment
		(start 305.754024 -296.55262)
		(end 305.891692 -296.690288)
		(width 0.14478)
		(layer "In13.Cu")
		(net "M_B_CPU0_SB_DQ<12>")
	)
	(segment
		(start 307.859684 -296.60215)
		(end 307.859684 -296.185844)
		(width 0.14478)
		(layer "In13.Cu")
		(net "M_B_CPU0_SB_DQ<12>")
	)
	(segment
		(start 302.482758 -297.018202)
		(end 302.641 -296.85996)
		(width 0.14478)
		(layer "In13.Cu")
		(net "M_B_CPU0_SB_DQ<12>")
	)
	(segment
		(start 331.52969 -282.513532)
		(end 331.538072 -282.508706)
		(width 0.0889)
		(layer "In13.Cu")
		(net "M_B_CPU0_SB_DQ<12>")
	)
	(segment
		(start 328.333608 -282.50261)
		(end 328.344022 -282.508706)
		(width 0.0889)
		(layer "In13.Cu")
		(net "M_B_CPU0_SB_DQ<12>")
	)
	(segment
		(start 306.096416 -296.690288)
		(end 306.74564 -296.041064)
		(width 0.14478)
		(layer "In13.Cu")
		(net "M_B_CPU0_SB_DQ<12>")
	)
	(segment
		(start 325.932292 -282.559252)
		(end 326.650858 -282.559252)
		(width 0.0889)
		(layer "In13.Cu")
		(net "M_B_CPU0_SB_DQ<12>")
	)
	(segment
		(start 300.725586 -296.368978)
		(end 301.870364 -297.513756)
		(width 0.14478)
		(layer "In13.Cu")
		(net "M_B_CPU0_SB_DQ<12>")
	)
	(segment
		(start 305.183794 -297.60291)
		(end 305.501802 -297.284902)
		(width 0.14478)
		(layer "In13.Cu")
		(net "M_B_CPU0_SB_DQ<12>")
	)
	(segment
		(start 327.403206 -282.508706)
		(end 327.411588 -282.513532)
		(width 0.0889)
		(layer "In13.Cu")
		(net "M_B_CPU0_SB_DQ<12>")
	)
	(segment
		(start 307.859684 -296.185844)
		(end 308.004464 -296.041064)
		(width 0.14478)
		(layer "In13.Cu")
		(net "M_B_CPU0_SB_DQ<12>")
	)
	(segment
		(start 328.709782 -282.513532)
		(end 328.718164 -282.508706)
		(width 0.0889)
		(layer "In13.Cu")
		(net "M_B_CPU0_SB_DQ<12>")
	)
	(segment
		(start 299.82414 -296.582846)
		(end 300.038008 -296.368978)
		(width 0.14478)
		(layer "In13.Cu")
		(net "M_B_CPU0_SB_DQ<12>")
	)
	(segment
		(start 303.752504 -296.85996)
		(end 304.041302 -296.85996)
		(width 0.14478)
		(layer "In13.Cu")
		(net "M_B_CPU0_SB_DQ<12>")
	)
	(segment
		(start 303.19726 -297.61053)
		(end 303.437036 -297.61053)
		(width 0.14478)
		(layer "In13.Cu")
		(net "M_B_CPU0_SB_DQ<12>")
	)
	(segment
		(start 303.039018 -297.452288)
		(end 303.19726 -297.61053)
		(width 0.14478)
		(layer "In13.Cu")
		(net "M_B_CPU0_SB_DQ<12>")
	)
	(segment
		(start 299.82414 -296.78503)
		(end 299.82414 -296.582846)
		(width 0.14478)
		(layer "In13.Cu")
		(net "M_B_CPU0_SB_DQ<12>")
	)
	(segment
		(start 305.891692 -296.690288)
		(end 306.096416 -296.690288)
		(width 0.14478)
		(layer "In13.Cu")
		(net "M_B_CPU0_SB_DQ<12>")
	)
	(segment
		(start 305.5493 -296.55262)
		(end 305.754024 -296.55262)
		(width 0.14478)
		(layer "In13.Cu")
		(net "M_B_CPU0_SB_DQ<12>")
	)
	(segment
		(start 308.779672 -296.041064)
		(end 322.273676 -282.54706)
		(width 0.14478)
		(layer "In13.Cu")
		(net "M_B_CPU0_SB_DQ<12>")
	)
	(segment
		(start 302.880776 -296.85996)
		(end 303.039018 -297.018202)
		(width 0.14478)
		(layer "In13.Cu")
		(net "M_B_CPU0_SB_DQ<12>")
	)
	(segment
		(start 303.039018 -297.018202)
		(end 303.039018 -297.452288)
		(width 0.14478)
		(layer "In13.Cu")
		(net "M_B_CPU0_SB_DQ<12>")
	)
	(segment
		(start 307.308504 -296.60215)
		(end 307.453284 -296.74693)
		(width 0.14478)
		(layer "In13.Cu")
		(net "M_B_CPU0_SB_DQ<12>")
	)
	(segment
		(start 335.8007 -282.476956)
		(end 335.896966 -282.451556)
		(width 0.0889)
		(layer "In13.Cu")
		(net "M_B_CPU0_SB_DQ<12>")
	)
	(segment
		(start 329.284076 -282.508706)
		(end 329.292458 -282.513532)
		(width 0.0889)
		(layer "In13.Cu")
		(net "M_B_CPU0_SB_DQ<12>")
	)
	(segment
		(start 325.541132 -282.168092)
		(end 325.932292 -282.559252)
		(width 0.0889)
		(layer "In13.Cu")
		(net "M_B_CPU0_SB_DQ<12>")
	)
	(segment
		(start 307.453284 -296.74693)
		(end 307.714904 -296.74693)
		(width 0.14478)
		(layer "In13.Cu")
		(net "M_B_CPU0_SB_DQ<12>")
	)
	(segment
		(start 333.044038 -282.508706)
		(end 333.05242 -282.513532)
		(width 0.0889)
		(layer "In13.Cu")
		(net "M_B_CPU0_SB_DQ<12>")
	)
	(segment
		(start 308.004464 -296.041064)
		(end 308.779672 -296.041064)
		(width 0.14478)
		(layer "In13.Cu")
		(net "M_B_CPU0_SB_DQ<12>")
	)
	(segment
		(start 307.714904 -296.74693)
		(end 307.859684 -296.60215)
		(width 0.14478)
		(layer "In13.Cu")
		(net "M_B_CPU0_SB_DQ<12>")
	)
	(segment
		(start 305.364134 -296.737786)
		(end 305.5493 -296.55262)
		(width 0.14478)
		(layer "In13.Cu")
		(net "M_B_CPU0_SB_DQ<12>")
	)
	(segment
		(start 300.038008 -296.368978)
		(end 300.725586 -296.368978)
		(width 0.14478)
		(layer "In13.Cu")
		(net "M_B_CPU0_SB_DQ<12>")
	)
	(segment
		(start 333.984092 -282.508706)
		(end 333.992474 -282.513532)
		(width 0.0889)
		(layer "In13.Cu")
		(net "M_B_CPU0_SB_DQ<12>")
	)
	(segment
		(start 326.837802 -282.508452)
		(end 326.84339 -282.50515)
		(width 0.0889)
		(layer "In13.Cu")
		(net "M_B_CPU0_SB_DQ<12>")
	)
	(arc
		(start 334.358234 -282.508706)
		(mid 334.64119 -282.432529)
		(end 334.924146 -282.508706)
		(width 0.0889)
		(layer "In13.Cu")
		(net "M_B_CPU0_SB_DQ<12>")
	)
	(arc
		(start 329.292458 -282.513532)
		(mid 329.475966 -282.559026)
		(end 329.658218 -282.508706)
		(width 0.0889)
		(layer "In13.Cu")
		(net "M_B_CPU0_SB_DQ<12>")
	)
	(arc
		(start 335.298034 -282.508706)
		(mid 335.54563 -282.433528)
		(end 335.8007 -282.476956)
		(width 0.0889)
		(layer "In13.Cu")
		(net "M_B_CPU0_SB_DQ<12>")
	)
	(arc
		(start 329.658218 -282.508706)
		(mid 329.941174 -282.432529)
		(end 330.22413 -282.508706)
		(width 0.0889)
		(layer "In13.Cu")
		(net "M_B_CPU0_SB_DQ<12>")
	)
	(arc
		(start 328.718164 -282.508706)
		(mid 329.00112 -282.432529)
		(end 329.284076 -282.508706)
		(width 0.0889)
		(layer "In13.Cu")
		(net "M_B_CPU0_SB_DQ<12>")
	)
	(arc
		(start 326.650858 -282.559252)
		(mid 326.747676 -282.546181)
		(end 326.837802 -282.508452)
		(width 0.0889)
		(layer "In13.Cu")
		(net "M_B_CPU0_SB_DQ<12>")
	)
	(arc
		(start 334.924146 -282.508706)
		(mid 335.11109 -282.558961)
		(end 335.298034 -282.508706)
		(width 0.0889)
		(layer "In13.Cu")
		(net "M_B_CPU0_SB_DQ<12>")
	)
	(arc
		(start 330.22413 -282.508706)
		(mid 330.411074 -282.558961)
		(end 330.598018 -282.508706)
		(width 0.0889)
		(layer "In13.Cu")
		(net "M_B_CPU0_SB_DQ<12>")
	)
	(arc
		(start 332.478126 -282.508706)
		(mid 332.761082 -282.432529)
		(end 333.044038 -282.508706)
		(width 0.0889)
		(layer "In13.Cu")
		(net "M_B_CPU0_SB_DQ<12>")
	)
	(arc
		(start 333.41818 -282.508706)
		(mid 333.701136 -282.432529)
		(end 333.984092 -282.508706)
		(width 0.0889)
		(layer "In13.Cu")
		(net "M_B_CPU0_SB_DQ<12>")
	)
	(arc
		(start 331.16393 -282.508706)
		(mid 331.346181 -282.559056)
		(end 331.52969 -282.513532)
		(width 0.0889)
		(layer "In13.Cu")
		(net "M_B_CPU0_SB_DQ<12>")
	)
	(arc
		(start 327.777856 -282.508706)
		(mid 328.054923 -282.432435)
		(end 328.333608 -282.50261)
		(width 0.0889)
		(layer "In13.Cu")
		(net "M_B_CPU0_SB_DQ<12>")
	)
	(arc
		(start 328.344022 -282.508706)
		(mid 328.526273 -282.559056)
		(end 328.709782 -282.513532)
		(width 0.0889)
		(layer "In13.Cu")
		(net "M_B_CPU0_SB_DQ<12>")
	)
	(arc
		(start 330.598018 -282.508706)
		(mid 330.880974 -282.432529)
		(end 331.16393 -282.508706)
		(width 0.0889)
		(layer "In13.Cu")
		(net "M_B_CPU0_SB_DQ<12>")
	)
	(arc
		(start 326.84339 -282.50515)
		(mid 327.123779 -282.432481)
		(end 327.403206 -282.508706)
		(width 0.0889)
		(layer "In13.Cu")
		(net "M_B_CPU0_SB_DQ<12>")
	)
	(arc
		(start 333.05242 -282.513532)
		(mid 333.235928 -282.559026)
		(end 333.41818 -282.508706)
		(width 0.0889)
		(layer "In13.Cu")
		(net "M_B_CPU0_SB_DQ<12>")
	)
	(arc
		(start 333.992474 -282.513532)
		(mid 334.175982 -282.559026)
		(end 334.358234 -282.508706)
		(width 0.0889)
		(layer "In13.Cu")
		(net "M_B_CPU0_SB_DQ<12>")
	)
	(arc
		(start 331.538072 -282.508706)
		(mid 331.821028 -282.432529)
		(end 332.103984 -282.508706)
		(width 0.0889)
		(layer "In13.Cu")
		(net "M_B_CPU0_SB_DQ<12>")
	)
	(arc
		(start 332.103984 -282.508706)
		(mid 332.286235 -282.559056)
		(end 332.469744 -282.513532)
		(width 0.0889)
		(layer "In13.Cu")
		(net "M_B_CPU0_SB_DQ<12>")
	)
	(arc
		(start 327.411588 -282.513532)
		(mid 327.59535 -282.559148)
		(end 327.777856 -282.508706)
		(width 0.0889)
		(layer "In13.Cu")
		(net "M_B_CPU0_SB_DQ<12>")
	)
	(segment
		(start 337.45805 -280.300176)
		(end 336.991198 -280.566114)
		(width 0.10668)
		(layer "F.Cu")
		(net "M_B_CPU0_SB_DQ<11>")
	)
	(segment
		(start 331.538072 -280.243534)
		(end 331.52969 -280.238708)
		(width 0.0889)
		(layer "In13.Cu")
		(net "M_B_CPU0_SB_DQ<11>")
	)
	(segment
		(start 297.386502 -293.384986)
		(end 295.724072 -293.384986)
		(width 0.14478)
		(layer "In13.Cu")
		(net "M_B_CPU0_SB_DQ<11>")
	)
	(segment
		(start 329.292458 -280.238708)
		(end 329.284076 -280.243534)
		(width 0.0889)
		(layer "In13.Cu")
		(net "M_B_CPU0_SB_DQ<11>")
	)
	(segment
		(start 327.523856 -280.325068)
		(end 327.36028 -280.161492)
		(width 0.0889)
		(layer "In13.Cu")
		(net "M_B_CPU0_SB_DQ<11>")
	)
	(segment
		(start 337.145122 -280.300684)
		(end 337.12277 -280.217372)
		(width 0.0889)
		(layer "In13.Cu")
		(net "M_B_CPU0_SB_DQ<11>")
	)
	(segment
		(start 328.344022 -280.243534)
		(end 328.333608 -280.24963)
		(width 0.0889)
		(layer "In13.Cu")
		(net "M_B_CPU0_SB_DQ<11>")
	)
	(segment
		(start 305.329844 -292.960044)
		(end 304.87493 -293.414958)
		(width 0.14478)
		(layer "In13.Cu")
		(net "M_B_CPU0_SB_DQ<11>")
	)
	(segment
		(start 332.478126 -280.243534)
		(end 332.469744 -280.238708)
		(width 0.0889)
		(layer "In13.Cu")
		(net "M_B_CPU0_SB_DQ<11>")
	)
	(segment
		(start 324.544436 -280.20772)
		(end 324.256146 -280.20772)
		(width 0.0889)
		(layer "In13.Cu")
		(net "M_B_CPU0_SB_DQ<11>")
	)
	(segment
		(start 313.349894 -288.20618)
		(end 308.59603 -292.960044)
		(width 0.14478)
		(layer "In13.Cu")
		(net "M_B_CPU0_SB_DQ<11>")
	)
	(segment
		(start 336.238088 -280.243534)
		(end 336.229706 -280.238708)
		(width 0.0889)
		(layer "In13.Cu")
		(net "M_B_CPU0_SB_DQ<11>")
	)
	(segment
		(start 328.718164 -280.243534)
		(end 328.709782 -280.238708)
		(width 0.0889)
		(layer "In13.Cu")
		(net "M_B_CPU0_SB_DQ<11>")
	)
	(segment
		(start 333.05242 -280.238708)
		(end 333.044038 -280.243534)
		(width 0.0889)
		(layer "In13.Cu")
		(net "M_B_CPU0_SB_DQ<11>")
	)
	(segment
		(start 320.213482 -280.20772)
		(end 313.349894 -287.071308)
		(width 0.14478)
		(layer "In13.Cu")
		(net "M_B_CPU0_SB_DQ<11>")
	)
	(segment
		(start 333.992474 -280.238708)
		(end 333.984092 -280.243534)
		(width 0.0889)
		(layer "In13.Cu")
		(net "M_B_CPU0_SB_DQ<11>")
	)
	(segment
		(start 304.87493 -293.414958)
		(end 301.933102 -293.414958)
		(width 0.14478)
		(layer "In13.Cu")
		(net "M_B_CPU0_SB_DQ<11>")
	)
	(segment
		(start 324.590664 -280.161492)
		(end 324.544436 -280.20772)
		(width 0.0889)
		(layer "In13.Cu")
		(net "M_B_CPU0_SB_DQ<11>")
	)
	(segment
		(start 313.349894 -287.071308)
		(end 313.349894 -288.20618)
		(width 0.14478)
		(layer "In13.Cu")
		(net "M_B_CPU0_SB_DQ<11>")
	)
	(segment
		(start 327.36028 -280.161492)
		(end 324.590664 -280.161492)
		(width 0.0889)
		(layer "In13.Cu")
		(net "M_B_CPU0_SB_DQ<11>")
	)
	(segment
		(start 308.59603 -292.960044)
		(end 305.329844 -292.960044)
		(width 0.14478)
		(layer "In13.Cu")
		(net "M_B_CPU0_SB_DQ<11>")
	)
	(segment
		(start 324.256146 -280.20772)
		(end 320.213482 -280.20772)
		(width 0.14478)
		(layer "In13.Cu")
		(net "M_B_CPU0_SB_DQ<11>")
	)
	(segment
		(start 328.041 -280.325068)
		(end 327.523856 -280.325068)
		(width 0.0889)
		(layer "In13.Cu")
		(net "M_B_CPU0_SB_DQ<11>")
	)
	(segment
		(start 336.991198 -280.566114)
		(end 337.145122 -280.300684)
		(width 0.0889)
		(layer "In13.Cu")
		(net "M_B_CPU0_SB_DQ<11>")
	)
	(segment
		(start 301.933102 -293.414958)
		(end 301.468536 -292.950392)
		(width 0.14478)
		(layer "In13.Cu")
		(net "M_B_CPU0_SB_DQ<11>")
	)
	(segment
		(start 301.468536 -292.950392)
		(end 297.821096 -292.950392)
		(width 0.14478)
		(layer "In13.Cu")
		(net "M_B_CPU0_SB_DQ<11>")
	)
	(segment
		(start 297.821096 -292.950392)
		(end 297.386502 -293.384986)
		(width 0.14478)
		(layer "In13.Cu")
		(net "M_B_CPU0_SB_DQ<11>")
	)
	(arc
		(start 333.044038 -280.243534)
		(mid 332.761082 -280.319711)
		(end 332.478126 -280.243534)
		(width 0.0889)
		(layer "In13.Cu")
		(net "M_B_CPU0_SB_DQ<11>")
	)
	(arc
		(start 335.298034 -280.243534)
		(mid 335.11109 -280.193279)
		(end 334.924146 -280.243534)
		(width 0.0889)
		(layer "In13.Cu")
		(net "M_B_CPU0_SB_DQ<11>")
	)
	(arc
		(start 334.924146 -280.243534)
		(mid 334.64119 -280.319711)
		(end 334.358234 -280.243534)
		(width 0.0889)
		(layer "In13.Cu")
		(net "M_B_CPU0_SB_DQ<11>")
	)
	(arc
		(start 332.103984 -280.243534)
		(mid 331.821028 -280.319711)
		(end 331.538072 -280.243534)
		(width 0.0889)
		(layer "In13.Cu")
		(net "M_B_CPU0_SB_DQ<11>")
	)
	(arc
		(start 333.41818 -280.243534)
		(mid 333.235929 -280.193184)
		(end 333.05242 -280.238708)
		(width 0.0889)
		(layer "In13.Cu")
		(net "M_B_CPU0_SB_DQ<11>")
	)
	(arc
		(start 329.284076 -280.243534)
		(mid 329.00112 -280.319711)
		(end 328.718164 -280.243534)
		(width 0.0889)
		(layer "In13.Cu")
		(net "M_B_CPU0_SB_DQ<11>")
	)
	(arc
		(start 334.358234 -280.243534)
		(mid 334.175983 -280.193184)
		(end 333.992474 -280.238708)
		(width 0.0889)
		(layer "In13.Cu")
		(net "M_B_CPU0_SB_DQ<11>")
	)
	(arc
		(start 332.469744 -280.238708)
		(mid 332.286236 -280.193214)
		(end 332.103984 -280.243534)
		(width 0.0889)
		(layer "In13.Cu")
		(net "M_B_CPU0_SB_DQ<11>")
	)
	(arc
		(start 335.863946 -280.243534)
		(mid 335.58099 -280.319711)
		(end 335.298034 -280.243534)
		(width 0.0889)
		(layer "In13.Cu")
		(net "M_B_CPU0_SB_DQ<11>")
	)
	(arc
		(start 330.22413 -280.243534)
		(mid 329.941174 -280.319711)
		(end 329.658218 -280.243534)
		(width 0.0889)
		(layer "In13.Cu")
		(net "M_B_CPU0_SB_DQ<11>")
	)
	(arc
		(start 336.229706 -280.238708)
		(mid 336.046198 -280.193214)
		(end 335.863946 -280.243534)
		(width 0.0889)
		(layer "In13.Cu")
		(net "M_B_CPU0_SB_DQ<11>")
	)
	(arc
		(start 329.658218 -280.243534)
		(mid 329.475967 -280.193184)
		(end 329.292458 -280.238708)
		(width 0.0889)
		(layer "In13.Cu")
		(net "M_B_CPU0_SB_DQ<11>")
	)
	(arc
		(start 328.709782 -280.238708)
		(mid 328.526274 -280.193214)
		(end 328.344022 -280.243534)
		(width 0.0889)
		(layer "In13.Cu")
		(net "M_B_CPU0_SB_DQ<11>")
	)
	(arc
		(start 331.16393 -280.243534)
		(mid 330.880974 -280.319711)
		(end 330.598018 -280.243534)
		(width 0.0889)
		(layer "In13.Cu")
		(net "M_B_CPU0_SB_DQ<11>")
	)
	(arc
		(start 331.52969 -280.238708)
		(mid 331.346182 -280.193214)
		(end 331.16393 -280.243534)
		(width 0.0889)
		(layer "In13.Cu")
		(net "M_B_CPU0_SB_DQ<11>")
	)
	(arc
		(start 333.984092 -280.243534)
		(mid 333.701136 -280.319711)
		(end 333.41818 -280.243534)
		(width 0.0889)
		(layer "In13.Cu")
		(net "M_B_CPU0_SB_DQ<11>")
	)
	(arc
		(start 328.333608 -280.24963)
		(mid 328.192083 -280.305874)
		(end 328.041 -280.325068)
		(width 0.0889)
		(layer "In13.Cu")
		(net "M_B_CPU0_SB_DQ<11>")
	)
	(arc
		(start 330.598018 -280.243534)
		(mid 330.411074 -280.193279)
		(end 330.22413 -280.243534)
		(width 0.0889)
		(layer "In13.Cu")
		(net "M_B_CPU0_SB_DQ<11>")
	)
	(arc
		(start 336.804 -280.243534)
		(mid 336.521044 -280.319711)
		(end 336.238088 -280.243534)
		(width 0.0889)
		(layer "In13.Cu")
		(net "M_B_CPU0_SB_DQ<11>")
	)
	(arc
		(start 337.12277 -280.217372)
		(mid 336.960438 -280.194554)
		(end 336.804 -280.243534)
		(width 0.0889)
		(layer "In13.Cu")
		(net "M_B_CPU0_SB_DQ<11>")
	)
	(segment
		(start 336.047842 -279.49017)
		(end 335.58099 -279.756108)
		(width 0.10668)
		(layer "F.Cu")
		(net "M_B_CPU0_SB_DQ<10>")
	)
	(segment
		(start 310.250586 -288.702242)
		(end 311.56783 -287.384998)
		(width 0.14478)
		(layer "In13.Cu")
		(net "M_B_CPU0_SB_DQ<10>")
	)
	(segment
		(start 330.119736 -279.428702)
		(end 330.128118 -279.433528)
		(width 0.0889)
		(layer "In13.Cu")
		(net "M_B_CPU0_SB_DQ<10>")
	)
	(segment
		(start 324.285864 -279.2984)
		(end 324.44563 -279.2984)
		(width 0.0889)
		(layer "In13.Cu")
		(net "M_B_CPU0_SB_DQ<10>")
	)
	(segment
		(start 312.11266 -287.52038)
		(end 312.297826 -287.335214)
		(width 0.14478)
		(layer "In13.Cu")
		(net "M_B_CPU0_SB_DQ<10>")
	)
	(segment
		(start 326.93356 -279.433782)
		(end 326.949816 -279.424384)
		(width 0.0889)
		(layer "In13.Cu")
		(net "M_B_CPU0_SB_DQ<10>")
	)
	(segment
		(start 319.654428 -279.2984)
		(end 324.285864 -279.2984)
		(width 0.14478)
		(layer "In13.Cu")
		(net "M_B_CPU0_SB_DQ<10>")
	)
	(segment
		(start 310.250586 -290.033456)
		(end 310.250586 -288.702242)
		(width 0.14478)
		(layer "In13.Cu")
		(net "M_B_CPU0_SB_DQ<10>")
	)
	(segment
		(start 335.394046 -279.433528)
		(end 335.402428 -279.428702)
		(width 0.0889)
		(layer "In13.Cu")
		(net "M_B_CPU0_SB_DQ<10>")
	)
	(segment
		(start 327.87336 -279.433782)
		(end 327.873868 -279.433528)
		(width 0.0889)
		(layer "In13.Cu")
		(net "M_B_CPU0_SB_DQ<10>")
	)
	(segment
		(start 324.659498 -279.084532)
		(end 325.991982 -279.084532)
		(width 0.0889)
		(layer "In13.Cu")
		(net "M_B_CPU0_SB_DQ<10>")
	)
	(segment
		(start 335.735168 -279.490678)
		(end 335.58099 -279.756108)
		(width 0.0889)
		(layer "In13.Cu")
		(net "M_B_CPU0_SB_DQ<10>")
	)
	(segment
		(start 325.991982 -279.084532)
		(end 326.252332 -279.344882)
		(width 0.0889)
		(layer "In13.Cu")
		(net "M_B_CPU0_SB_DQ<10>")
	)
	(segment
		(start 306.869592 -291.535612)
		(end 307.145182 -291.260022)
		(width 0.14478)
		(layer "In13.Cu")
		(net "M_B_CPU0_SB_DQ<10>")
	)
	(segment
		(start 312.162444 -286.995108)
		(end 312.162444 -286.790384)
		(width 0.14478)
		(layer "In13.Cu")
		(net "M_B_CPU0_SB_DQ<10>")
	)
	(segment
		(start 331.634084 -279.433528)
		(end 331.642466 -279.428702)
		(width 0.0889)
		(layer "In13.Cu")
		(net "M_B_CPU0_SB_DQ<10>")
	)
	(segment
		(start 312.162444 -286.790384)
		(end 319.654428 -279.2984)
		(width 0.14478)
		(layer "In13.Cu")
		(net "M_B_CPU0_SB_DQ<10>")
	)
	(segment
		(start 311.772554 -287.384998)
		(end 311.907936 -287.52038)
		(width 0.14478)
		(layer "In13.Cu")
		(net "M_B_CPU0_SB_DQ<10>")
	)
	(segment
		(start 335.712816 -279.407366)
		(end 335.735168 -279.490678)
		(width 0.0889)
		(layer "In13.Cu")
		(net "M_B_CPU0_SB_DQ<10>")
	)
	(segment
		(start 334.819752 -279.428702)
		(end 334.828134 -279.433528)
		(width 0.0889)
		(layer "In13.Cu")
		(net "M_B_CPU0_SB_DQ<10>")
	)
	(segment
		(start 333.879698 -279.428702)
		(end 333.88808 -279.433528)
		(width 0.0889)
		(layer "In13.Cu")
		(net "M_B_CPU0_SB_DQ<10>")
	)
	(segment
		(start 312.297826 -287.13049)
		(end 312.162444 -286.995108)
		(width 0.14478)
		(layer "In13.Cu")
		(net "M_B_CPU0_SB_DQ<10>")
	)
	(segment
		(start 298.224956 -291.260022)
		(end 301.498508 -291.260022)
		(width 0.14478)
		(layer "In13.Cu")
		(net "M_B_CPU0_SB_DQ<10>")
	)
	(segment
		(start 302.348646 -292.11016)
		(end 304.893218 -292.11016)
		(width 0.14478)
		(layer "In13.Cu")
		(net "M_B_CPU0_SB_DQ<10>")
	)
	(segment
		(start 324.44563 -279.2984)
		(end 324.659498 -279.084532)
		(width 0.0889)
		(layer "In13.Cu")
		(net "M_B_CPU0_SB_DQ<10>")
	)
	(segment
		(start 304.893218 -292.11016)
		(end 305.467766 -291.535612)
		(width 0.14478)
		(layer "In13.Cu")
		(net "M_B_CPU0_SB_DQ<10>")
	)
	(segment
		(start 305.467766 -291.535612)
		(end 306.869592 -291.535612)
		(width 0.14478)
		(layer "In13.Cu")
		(net "M_B_CPU0_SB_DQ<10>")
	)
	(segment
		(start 309.02402 -291.260022)
		(end 310.250586 -290.033456)
		(width 0.14478)
		(layer "In13.Cu")
		(net "M_B_CPU0_SB_DQ<10>")
	)
	(segment
		(start 297.800014 -291.684964)
		(end 298.224956 -291.260022)
		(width 0.14478)
		(layer "In13.Cu")
		(net "M_B_CPU0_SB_DQ<10>")
	)
	(segment
		(start 311.907936 -287.52038)
		(end 312.11266 -287.52038)
		(width 0.14478)
		(layer "In13.Cu")
		(net "M_B_CPU0_SB_DQ<10>")
	)
	(segment
		(start 326.917812 -279.442926)
		(end 326.93356 -279.433782)
		(width 0.0889)
		(layer "In13.Cu")
		(net "M_B_CPU0_SB_DQ<10>")
	)
	(segment
		(start 301.498508 -291.260022)
		(end 302.348646 -292.11016)
		(width 0.14478)
		(layer "In13.Cu")
		(net "M_B_CPU0_SB_DQ<10>")
	)
	(segment
		(start 312.297826 -287.335214)
		(end 312.297826 -287.13049)
		(width 0.14478)
		(layer "In13.Cu")
		(net "M_B_CPU0_SB_DQ<10>")
	)
	(segment
		(start 330.69403 -279.433528)
		(end 330.702412 -279.428702)
		(width 0.0889)
		(layer "In13.Cu")
		(net "M_B_CPU0_SB_DQ<10>")
	)
	(segment
		(start 327.307448 -279.433528)
		(end 327.317862 -279.439624)
		(width 0.0889)
		(layer "In13.Cu")
		(net "M_B_CPU0_SB_DQ<10>")
	)
	(segment
		(start 295.724072 -291.684964)
		(end 297.800014 -291.684964)
		(width 0.14478)
		(layer "In13.Cu")
		(net "M_B_CPU0_SB_DQ<10>")
	)
	(segment
		(start 311.56783 -287.384998)
		(end 311.772554 -287.384998)
		(width 0.14478)
		(layer "In13.Cu")
		(net "M_B_CPU0_SB_DQ<10>")
	)
	(segment
		(start 307.145182 -291.260022)
		(end 309.02402 -291.260022)
		(width 0.14478)
		(layer "In13.Cu")
		(net "M_B_CPU0_SB_DQ<10>")
	)
	(segment
		(start 327.873614 -279.433528)
		(end 327.87336 -279.433782)
		(width 0.0889)
		(layer "In13.Cu")
		(net "M_B_CPU0_SB_DQ<10>")
	)
	(arc
		(start 334.828134 -279.433528)
		(mid 335.11109 -279.509705)
		(end 335.394046 -279.433528)
		(width 0.0889)
		(layer "In13.Cu")
		(net "M_B_CPU0_SB_DQ<10>")
	)
	(arc
		(start 332.948026 -279.433528)
		(mid 333.230982 -279.509705)
		(end 333.513938 -279.433528)
		(width 0.0889)
		(layer "In13.Cu")
		(net "M_B_CPU0_SB_DQ<10>")
	)
	(arc
		(start 335.402428 -279.428702)
		(mid 335.555298 -279.384061)
		(end 335.712816 -279.407366)
		(width 0.0889)
		(layer "In13.Cu")
		(net "M_B_CPU0_SB_DQ<10>")
	)
	(arc
		(start 326.367648 -279.433528)
		(mid 326.641503 -279.509878)
		(end 326.917812 -279.442926)
		(width 0.0889)
		(layer "In13.Cu")
		(net "M_B_CPU0_SB_DQ<10>")
	)
	(arc
		(start 327.317862 -279.439624)
		(mid 327.596548 -279.509844)
		(end 327.873614 -279.433528)
		(width 0.0889)
		(layer "In13.Cu")
		(net "M_B_CPU0_SB_DQ<10>")
	)
	(arc
		(start 329.188064 -279.433528)
		(mid 329.47102 -279.509705)
		(end 329.753976 -279.433528)
		(width 0.0889)
		(layer "In13.Cu")
		(net "M_B_CPU0_SB_DQ<10>")
	)
	(arc
		(start 334.453992 -279.433528)
		(mid 334.636243 -279.383178)
		(end 334.819752 -279.428702)
		(width 0.0889)
		(layer "In13.Cu")
		(net "M_B_CPU0_SB_DQ<10>")
	)
	(arc
		(start 331.068172 -279.433528)
		(mid 331.351128 -279.509705)
		(end 331.634084 -279.433528)
		(width 0.0889)
		(layer "In13.Cu")
		(net "M_B_CPU0_SB_DQ<10>")
	)
	(arc
		(start 331.642466 -279.428702)
		(mid 331.825974 -279.383208)
		(end 332.008226 -279.433528)
		(width 0.0889)
		(layer "In13.Cu")
		(net "M_B_CPU0_SB_DQ<10>")
	)
	(arc
		(start 332.008226 -279.433528)
		(mid 332.291182 -279.509705)
		(end 332.574138 -279.433528)
		(width 0.0889)
		(layer "In13.Cu")
		(net "M_B_CPU0_SB_DQ<10>")
	)
	(arc
		(start 333.513938 -279.433528)
		(mid 333.696189 -279.383178)
		(end 333.879698 -279.428702)
		(width 0.0889)
		(layer "In13.Cu")
		(net "M_B_CPU0_SB_DQ<10>")
	)
	(arc
		(start 326.949816 -279.424384)
		(mid 327.129798 -279.383284)
		(end 327.307448 -279.433528)
		(width 0.0889)
		(layer "In13.Cu")
		(net "M_B_CPU0_SB_DQ<10>")
	)
	(arc
		(start 330.128118 -279.433528)
		(mid 330.411074 -279.509705)
		(end 330.69403 -279.433528)
		(width 0.0889)
		(layer "In13.Cu")
		(net "M_B_CPU0_SB_DQ<10>")
	)
	(arc
		(start 332.574138 -279.433528)
		(mid 332.761082 -279.383273)
		(end 332.948026 -279.433528)
		(width 0.0889)
		(layer "In13.Cu")
		(net "M_B_CPU0_SB_DQ<10>")
	)
	(arc
		(start 333.88808 -279.433528)
		(mid 334.171036 -279.509705)
		(end 334.453992 -279.433528)
		(width 0.0889)
		(layer "In13.Cu")
		(net "M_B_CPU0_SB_DQ<10>")
	)
	(arc
		(start 327.873868 -279.433528)
		(mid 328.061066 -279.383146)
		(end 328.248264 -279.433528)
		(width 0.0889)
		(layer "In13.Cu")
		(net "M_B_CPU0_SB_DQ<10>")
	)
	(arc
		(start 326.252332 -279.344882)
		(mid 326.307117 -279.392942)
		(end 326.367648 -279.433528)
		(width 0.0889)
		(layer "In13.Cu")
		(net "M_B_CPU0_SB_DQ<10>")
	)
	(arc
		(start 329.753976 -279.433528)
		(mid 329.936227 -279.383178)
		(end 330.119736 -279.428702)
		(width 0.0889)
		(layer "In13.Cu")
		(net "M_B_CPU0_SB_DQ<10>")
	)
	(arc
		(start 328.248264 -279.433528)
		(mid 328.53122 -279.509705)
		(end 328.814176 -279.433528)
		(width 0.0889)
		(layer "In13.Cu")
		(net "M_B_CPU0_SB_DQ<10>")
	)
	(arc
		(start 328.814176 -279.433528)
		(mid 329.00112 -279.383273)
		(end 329.188064 -279.433528)
		(width 0.0889)
		(layer "In13.Cu")
		(net "M_B_CPU0_SB_DQ<10>")
	)
	(arc
		(start 330.702412 -279.428702)
		(mid 330.88592 -279.383208)
		(end 331.068172 -279.433528)
		(width 0.0889)
		(layer "In13.Cu")
		(net "M_B_CPU0_SB_DQ<10>")
	)
	(segment
		(start 336.517996 -273.820128)
		(end 336.051144 -274.086066)
		(width 0.10668)
		(layer "F.Cu")
		(net "M_B_CPU0_SB_DQ<0>")
	)
	(segment
		(start 333.05242 -274.413472)
		(end 333.044038 -274.408646)
		(width 0.0889)
		(layer "In13.Cu")
		(net "M_B_CPU0_SB_DQ<0>")
	)
	(segment
		(start 303.769268 -281.910028)
		(end 302.807116 -281.910028)
		(width 0.14478)
		(layer "In13.Cu")
		(net "M_B_CPU0_SB_DQ<0>")
	)
	(segment
		(start 311.005474 -277.998428)
		(end 310.674004 -277.998428)
		(width 0.14478)
		(layer "In13.Cu")
		(net "M_B_CPU0_SB_DQ<0>")
	)
	(segment
		(start 313.014868 -275.657564)
		(end 312.790332 -275.8821)
		(width 0.14478)
		(layer "In13.Cu")
		(net "M_B_CPU0_SB_DQ<0>")
	)
	(segment
		(start 308.33314 -280.339292)
		(end 307.211984 -281.460448)
		(width 0.14478)
		(layer "In13.Cu")
		(net "M_B_CPU0_SB_DQ<0>")
	)
	(segment
		(start 314.350908 -274.549616)
		(end 314.351162 -274.65274)
		(width 0.14478)
		(layer "In13.Cu")
		(net "M_B_CPU0_SB_DQ<0>")
	)
	(segment
		(start 326.386952 -274.349972)
		(end 325.475092 -273.438112)
		(width 0.0889)
		(layer "In13.Cu")
		(net "M_B_CPU0_SB_DQ<0>")
	)
	(segment
		(start 299.82414 -281.266138)
		(end 299.82414 -281.485086)
		(width 0.14478)
		(layer "In13.Cu")
		(net "M_B_CPU0_SB_DQ<0>")
	)
	(segment
		(start 306.277772 -280.864818)
		(end 306.132992 -281.009598)
		(width 0.14478)
		(layer "In13.Cu")
		(net "M_B_CPU0_SB_DQ<0>")
	)
	(segment
		(start 302.807116 -281.910028)
		(end 302.645572 -281.748484)
		(width 0.14478)
		(layer "In13.Cu")
		(net "M_B_CPU0_SB_DQ<0>")
	)
	(segment
		(start 311.229756 -277.442676)
		(end 311.229756 -277.670768)
		(width 0.14478)
		(layer "In13.Cu")
		(net "M_B_CPU0_SB_DQ<0>")
	)
	(segment
		(start 313.795156 -274.877276)
		(end 313.57062 -275.101812)
		(width 0.14478)
		(layer "In13.Cu")
		(net "M_B_CPU0_SB_DQ<0>")
	)
	(segment
		(start 310.449468 -278.222964)
		(end 310.449468 -278.451056)
		(width 0.14478)
		(layer "In13.Cu")
		(net "M_B_CPU0_SB_DQ<0>")
	)
	(segment
		(start 332.478126 -274.408646)
		(end 332.469744 -274.413472)
		(width 0.0889)
		(layer "In13.Cu")
		(net "M_B_CPU0_SB_DQ<0>")
	)
	(segment
		(start 307.211984 -281.460448)
		(end 306.828952 -281.460448)
		(width 0.14478)
		(layer "In13.Cu")
		(net "M_B_CPU0_SB_DQ<0>")
	)
	(segment
		(start 333.992474 -274.413472)
		(end 333.984092 -274.408646)
		(width 0.0889)
		(layer "In13.Cu")
		(net "M_B_CPU0_SB_DQ<0>")
	)
	(segment
		(start 301.932594 -281.910028)
		(end 301.654718 -281.910028)
		(width 0.14478)
		(layer "In13.Cu")
		(net "M_B_CPU0_SB_DQ<0>")
	)
	(segment
		(start 324.539864 -273.22018)
		(end 315.452252 -273.22018)
		(width 0.14478)
		(layer "In13.Cu")
		(net "M_B_CPU0_SB_DQ<0>")
	)
	(segment
		(start 314.351162 -274.65274)
		(end 314.126626 -274.877276)
		(width 0.14478)
		(layer "In13.Cu")
		(net "M_B_CPU0_SB_DQ<0>")
	)
	(segment
		(start 303.930812 -281.402536)
		(end 303.930812 -281.748484)
		(width 0.14478)
		(layer "In13.Cu")
		(net "M_B_CPU0_SB_DQ<0>")
	)
	(segment
		(start 326.46366 -274.408646)
		(end 326.463406 -274.408646)
		(width 0.0889)
		(layer "In13.Cu")
		(net "M_B_CPU0_SB_DQ<0>")
	)
	(segment
		(start 331.538072 -274.408646)
		(end 331.52969 -274.413472)
		(width 0.0889)
		(layer "In13.Cu")
		(net "M_B_CPU0_SB_DQ<0>")
	)
	(segment
		(start 309.66918 -279.003252)
		(end 309.66918 -279.231344)
		(width 0.14478)
		(layer "In13.Cu")
		(net "M_B_CPU0_SB_DQ<0>")
	)
	(segment
		(start 306.539392 -280.864818)
		(end 306.277772 -280.864818)
		(width 0.14478)
		(layer "In13.Cu")
		(net "M_B_CPU0_SB_DQ<0>")
	)
	(segment
		(start 304.482246 -281.402536)
		(end 304.320702 -281.240992)
		(width 0.14478)
		(layer "In13.Cu")
		(net "M_B_CPU0_SB_DQ<0>")
	)
	(segment
		(start 304.482246 -281.748484)
		(end 304.482246 -281.402536)
		(width 0.14478)
		(layer "In13.Cu")
		(net "M_B_CPU0_SB_DQ<0>")
	)
	(segment
		(start 302.094138 -281.748484)
		(end 301.932594 -281.910028)
		(width 0.14478)
		(layer "In13.Cu")
		(net "M_B_CPU0_SB_DQ<0>")
	)
	(segment
		(start 302.094138 -281.382216)
		(end 302.094138 -281.748484)
		(width 0.14478)
		(layer "In13.Cu")
		(net "M_B_CPU0_SB_DQ<0>")
	)
	(segment
		(start 310.449722 -278.55418)
		(end 310.225186 -278.778716)
		(width 0.14478)
		(layer "In13.Cu")
		(net "M_B_CPU0_SB_DQ<0>")
	)
	(segment
		(start 335.896966 -274.351496)
		(end 335.8007 -274.376896)
		(width 0.0889)
		(layer "In13.Cu")
		(net "M_B_CPU0_SB_DQ<0>")
	)
	(segment
		(start 306.684172 -281.009598)
		(end 306.539392 -280.864818)
		(width 0.14478)
		(layer "In13.Cu")
		(net "M_B_CPU0_SB_DQ<0>")
	)
	(segment
		(start 305.988212 -281.460448)
		(end 305.599846 -281.460448)
		(width 0.14478)
		(layer "In13.Cu")
		(net "M_B_CPU0_SB_DQ<0>")
	)
	(segment
		(start 311.229756 -277.670768)
		(end 311.23001 -277.773892)
		(width 0.14478)
		(layer "In13.Cu")
		(net "M_B_CPU0_SB_DQ<0>")
	)
	(segment
		(start 312.56605 -276.437852)
		(end 312.23458 -276.437852)
		(width 0.14478)
		(layer "In13.Cu")
		(net "M_B_CPU0_SB_DQ<0>")
	)
	(segment
		(start 306.132992 -281.009598)
		(end 306.132992 -281.315668)
		(width 0.14478)
		(layer "In13.Cu")
		(net "M_B_CPU0_SB_DQ<0>")
	)
	(segment
		(start 310.225186 -278.778716)
		(end 309.893716 -278.778716)
		(width 0.14478)
		(layer "In13.Cu")
		(net "M_B_CPU0_SB_DQ<0>")
	)
	(segment
		(start 306.132992 -281.315668)
		(end 305.988212 -281.460448)
		(width 0.14478)
		(layer "In13.Cu")
		(net "M_B_CPU0_SB_DQ<0>")
	)
	(segment
		(start 309.444898 -279.559004)
		(end 309.113428 -279.559004)
		(width 0.14478)
		(layer "In13.Cu")
		(net "M_B_CPU0_SB_DQ<0>")
	)
	(segment
		(start 312.010044 -276.89048)
		(end 312.010298 -276.993604)
		(width 0.14478)
		(layer "In13.Cu")
		(net "M_B_CPU0_SB_DQ<0>")
	)
	(segment
		(start 300.030388 -281.05989)
		(end 299.82414 -281.266138)
		(width 0.14478)
		(layer "In13.Cu")
		(net "M_B_CPU0_SB_DQ<0>")
	)
	(segment
		(start 311.785762 -277.21814)
		(end 311.454292 -277.21814)
		(width 0.14478)
		(layer "In13.Cu")
		(net "M_B_CPU0_SB_DQ<0>")
	)
	(segment
		(start 304.092356 -281.240992)
		(end 303.930812 -281.402536)
		(width 0.14478)
		(layer "In13.Cu")
		(net "M_B_CPU0_SB_DQ<0>")
	)
	(segment
		(start 312.23458 -276.437852)
		(end 312.010044 -276.662388)
		(width 0.14478)
		(layer "In13.Cu")
		(net "M_B_CPU0_SB_DQ<0>")
	)
	(segment
		(start 302.645572 -281.382216)
		(end 302.484028 -281.220672)
		(width 0.14478)
		(layer "In13.Cu")
		(net "M_B_CPU0_SB_DQ<0>")
	)
	(segment
		(start 309.669434 -279.334468)
		(end 309.444898 -279.559004)
		(width 0.14478)
		(layer "In13.Cu")
		(net "M_B_CPU0_SB_DQ<0>")
	)
	(segment
		(start 315.452252 -273.22018)
		(end 315.131196 -273.541236)
		(width 0.14478)
		(layer "In13.Cu")
		(net "M_B_CPU0_SB_DQ<0>")
	)
	(segment
		(start 314.575444 -274.096988)
		(end 314.350908 -274.321524)
		(width 0.14478)
		(layer "In13.Cu")
		(net "M_B_CPU0_SB_DQ<0>")
	)
	(segment
		(start 308.888892 -280.11501)
		(end 308.66461 -280.339292)
		(width 0.14478)
		(layer "In13.Cu")
		(net "M_B_CPU0_SB_DQ<0>")
	)
	(segment
		(start 312.790332 -276.110192)
		(end 312.790586 -276.213316)
		(width 0.14478)
		(layer "In13.Cu")
		(net "M_B_CPU0_SB_DQ<0>")
	)
	(segment
		(start 305.599846 -281.460448)
		(end 305.150266 -281.910028)
		(width 0.14478)
		(layer "In13.Cu")
		(net "M_B_CPU0_SB_DQ<0>")
	)
	(segment
		(start 301.654718 -281.910028)
		(end 300.80458 -281.05989)
		(width 0.14478)
		(layer "In13.Cu")
		(net "M_B_CPU0_SB_DQ<0>")
	)
	(segment
		(start 313.346338 -275.657564)
		(end 313.014868 -275.657564)
		(width 0.14478)
		(layer "In13.Cu")
		(net "M_B_CPU0_SB_DQ<0>")
	)
	(segment
		(start 325.475092 -273.438112)
		(end 324.757796 -273.438112)
		(width 0.0889)
		(layer "In13.Cu")
		(net "M_B_CPU0_SB_DQ<0>")
	)
	(segment
		(start 305.150266 -281.910028)
		(end 304.64379 -281.910028)
		(width 0.14478)
		(layer "In13.Cu")
		(net "M_B_CPU0_SB_DQ<0>")
	)
	(segment
		(start 308.888892 -279.78354)
		(end 308.888892 -280.11501)
		(width 0.14478)
		(layer "In13.Cu")
		(net "M_B_CPU0_SB_DQ<0>")
	)
	(segment
		(start 315.131196 -273.769328)
		(end 315.13145 -273.872452)
		(width 0.14478)
		(layer "In13.Cu")
		(net "M_B_CPU0_SB_DQ<0>")
	)
	(segment
		(start 310.449468 -278.451056)
		(end 310.449722 -278.55418)
		(width 0.14478)
		(layer "In13.Cu")
		(net "M_B_CPU0_SB_DQ<0>")
	)
	(segment
		(start 310.674004 -277.998428)
		(end 310.449468 -278.222964)
		(width 0.14478)
		(layer "In13.Cu")
		(net "M_B_CPU0_SB_DQ<0>")
	)
	(segment
		(start 315.13145 -273.872452)
		(end 314.906914 -274.096988)
		(width 0.14478)
		(layer "In13.Cu")
		(net "M_B_CPU0_SB_DQ<0>")
	)
	(segment
		(start 303.930812 -281.748484)
		(end 303.769268 -281.910028)
		(width 0.14478)
		(layer "In13.Cu")
		(net "M_B_CPU0_SB_DQ<0>")
	)
	(segment
		(start 326.84339 -274.40509)
		(end 326.837802 -274.408392)
		(width 0.0889)
		(layer "In13.Cu")
		(net "M_B_CPU0_SB_DQ<0>")
	)
	(segment
		(start 313.570874 -275.433028)
		(end 313.346338 -275.657564)
		(width 0.14478)
		(layer "In13.Cu")
		(net "M_B_CPU0_SB_DQ<0>")
	)
	(segment
		(start 327.411588 -274.413472)
		(end 327.403206 -274.408646)
		(width 0.0889)
		(layer "In13.Cu")
		(net "M_B_CPU0_SB_DQ<0>")
	)
	(segment
		(start 309.113428 -279.559004)
		(end 308.888892 -279.78354)
		(width 0.14478)
		(layer "In13.Cu")
		(net "M_B_CPU0_SB_DQ<0>")
	)
	(segment
		(start 312.790332 -275.8821)
		(end 312.790332 -276.110192)
		(width 0.14478)
		(layer "In13.Cu")
		(net "M_B_CPU0_SB_DQ<0>")
	)
	(segment
		(start 311.23001 -277.773892)
		(end 311.005474 -277.998428)
		(width 0.14478)
		(layer "In13.Cu")
		(net "M_B_CPU0_SB_DQ<0>")
	)
	(segment
		(start 328.718164 -274.408646)
		(end 328.709782 -274.413472)
		(width 0.0889)
		(layer "In13.Cu")
		(net "M_B_CPU0_SB_DQ<0>")
	)
	(segment
		(start 312.790586 -276.213316)
		(end 312.56605 -276.437852)
		(width 0.14478)
		(layer "In13.Cu")
		(net "M_B_CPU0_SB_DQ<0>")
	)
	(segment
		(start 326.837802 -274.408392)
		(end 326.819514 -274.418806)
		(width 0.0889)
		(layer "In13.Cu")
		(net "M_B_CPU0_SB_DQ<0>")
	)
	(segment
		(start 304.64379 -281.910028)
		(end 304.482246 -281.748484)
		(width 0.14478)
		(layer "In13.Cu")
		(net "M_B_CPU0_SB_DQ<0>")
	)
	(segment
		(start 324.757796 -273.438112)
		(end 324.539864 -273.22018)
		(width 0.0889)
		(layer "In13.Cu")
		(net "M_B_CPU0_SB_DQ<0>")
	)
	(segment
		(start 312.010298 -276.993604)
		(end 311.785762 -277.21814)
		(width 0.14478)
		(layer "In13.Cu")
		(net "M_B_CPU0_SB_DQ<0>")
	)
	(segment
		(start 314.906914 -274.096988)
		(end 314.575444 -274.096988)
		(width 0.14478)
		(layer "In13.Cu")
		(net "M_B_CPU0_SB_DQ<0>")
	)
	(segment
		(start 314.350908 -274.321524)
		(end 314.350908 -274.549616)
		(width 0.14478)
		(layer "In13.Cu")
		(net "M_B_CPU0_SB_DQ<0>")
	)
	(segment
		(start 329.292458 -274.413472)
		(end 329.284076 -274.408646)
		(width 0.0889)
		(layer "In13.Cu")
		(net "M_B_CPU0_SB_DQ<0>")
	)
	(segment
		(start 304.320702 -281.240992)
		(end 304.092356 -281.240992)
		(width 0.14478)
		(layer "In13.Cu")
		(net "M_B_CPU0_SB_DQ<0>")
	)
	(segment
		(start 309.893716 -278.778716)
		(end 309.66918 -279.003252)
		(width 0.14478)
		(layer "In13.Cu")
		(net "M_B_CPU0_SB_DQ<0>")
	)
	(segment
		(start 336.051144 -274.086066)
		(end 335.896966 -274.351496)
		(width 0.0889)
		(layer "In13.Cu")
		(net "M_B_CPU0_SB_DQ<0>")
	)
	(segment
		(start 308.66461 -280.339292)
		(end 308.33314 -280.339292)
		(width 0.14478)
		(layer "In13.Cu")
		(net "M_B_CPU0_SB_DQ<0>")
	)
	(segment
		(start 311.454292 -277.21814)
		(end 311.229756 -277.442676)
		(width 0.14478)
		(layer "In13.Cu")
		(net "M_B_CPU0_SB_DQ<0>")
	)
	(segment
		(start 313.57062 -275.329904)
		(end 313.570874 -275.433028)
		(width 0.14478)
		(layer "In13.Cu")
		(net "M_B_CPU0_SB_DQ<0>")
	)
	(segment
		(start 302.645572 -281.748484)
		(end 302.645572 -281.382216)
		(width 0.14478)
		(layer "In13.Cu")
		(net "M_B_CPU0_SB_DQ<0>")
	)
	(segment
		(start 302.255682 -281.220672)
		(end 302.094138 -281.382216)
		(width 0.14478)
		(layer "In13.Cu")
		(net "M_B_CPU0_SB_DQ<0>")
	)
	(segment
		(start 313.57062 -275.101812)
		(end 313.57062 -275.329904)
		(width 0.14478)
		(layer "In13.Cu")
		(net "M_B_CPU0_SB_DQ<0>")
	)
	(segment
		(start 300.80458 -281.05989)
		(end 300.030388 -281.05989)
		(width 0.14478)
		(layer "In13.Cu")
		(net "M_B_CPU0_SB_DQ<0>")
	)
	(segment
		(start 328.344022 -274.408646)
		(end 328.333608 -274.40255)
		(width 0.0889)
		(layer "In13.Cu")
		(net "M_B_CPU0_SB_DQ<0>")
	)
	(segment
		(start 314.126626 -274.877276)
		(end 313.795156 -274.877276)
		(width 0.14478)
		(layer "In13.Cu")
		(net "M_B_CPU0_SB_DQ<0>")
	)
	(segment
		(start 306.828952 -281.460448)
		(end 306.684172 -281.315668)
		(width 0.14478)
		(layer "In13.Cu")
		(net "M_B_CPU0_SB_DQ<0>")
	)
	(segment
		(start 306.684172 -281.315668)
		(end 306.684172 -281.009598)
		(width 0.14478)
		(layer "In13.Cu")
		(net "M_B_CPU0_SB_DQ<0>")
	)
	(segment
		(start 302.484028 -281.220672)
		(end 302.255682 -281.220672)
		(width 0.14478)
		(layer "In13.Cu")
		(net "M_B_CPU0_SB_DQ<0>")
	)
	(segment
		(start 309.66918 -279.231344)
		(end 309.669434 -279.334468)
		(width 0.14478)
		(layer "In13.Cu")
		(net "M_B_CPU0_SB_DQ<0>")
	)
	(segment
		(start 315.131196 -273.541236)
		(end 315.131196 -273.769328)
		(width 0.14478)
		(layer "In13.Cu")
		(net "M_B_CPU0_SB_DQ<0>")
	)
	(segment
		(start 312.010044 -276.662388)
		(end 312.010044 -276.89048)
		(width 0.14478)
		(layer "In13.Cu")
		(net "M_B_CPU0_SB_DQ<0>")
	)
	(arc
		(start 330.22413 -274.408646)
		(mid 329.941174 -274.332469)
		(end 329.658218 -274.408646)
		(width 0.0889)
		(layer "In13.Cu")
		(net "M_B_CPU0_SB_DQ<0>")
	)
	(arc
		(start 334.924146 -274.408646)
		(mid 334.64119 -274.332469)
		(end 334.358234 -274.408646)
		(width 0.0889)
		(layer "In13.Cu")
		(net "M_B_CPU0_SB_DQ<0>")
	)
	(arc
		(start 327.777856 -274.408646)
		(mid 327.595351 -274.459123)
		(end 327.411588 -274.413472)
		(width 0.0889)
		(layer "In13.Cu")
		(net "M_B_CPU0_SB_DQ<0>")
	)
	(arc
		(start 326.819514 -274.418806)
		(mid 326.640285 -274.458959)
		(end 326.46366 -274.408646)
		(width 0.0889)
		(layer "In13.Cu")
		(net "M_B_CPU0_SB_DQ<0>")
	)
	(arc
		(start 328.333608 -274.40255)
		(mid 328.054922 -274.33233)
		(end 327.777856 -274.408646)
		(width 0.0889)
		(layer "In13.Cu")
		(net "M_B_CPU0_SB_DQ<0>")
	)
	(arc
		(start 330.598018 -274.408646)
		(mid 330.411074 -274.458901)
		(end 330.22413 -274.408646)
		(width 0.0889)
		(layer "In13.Cu")
		(net "M_B_CPU0_SB_DQ<0>")
	)
	(arc
		(start 329.658218 -274.408646)
		(mid 329.475967 -274.458996)
		(end 329.292458 -274.413472)
		(width 0.0889)
		(layer "In13.Cu")
		(net "M_B_CPU0_SB_DQ<0>")
	)
	(arc
		(start 334.358234 -274.408646)
		(mid 334.175983 -274.458996)
		(end 333.992474 -274.413472)
		(width 0.0889)
		(layer "In13.Cu")
		(net "M_B_CPU0_SB_DQ<0>")
	)
	(arc
		(start 333.41818 -274.408646)
		(mid 333.235929 -274.458996)
		(end 333.05242 -274.413472)
		(width 0.0889)
		(layer "In13.Cu")
		(net "M_B_CPU0_SB_DQ<0>")
	)
	(arc
		(start 333.044038 -274.408646)
		(mid 332.761082 -274.332469)
		(end 332.478126 -274.408646)
		(width 0.0889)
		(layer "In13.Cu")
		(net "M_B_CPU0_SB_DQ<0>")
	)
	(arc
		(start 328.709782 -274.413472)
		(mid 328.526274 -274.458966)
		(end 328.344022 -274.408646)
		(width 0.0889)
		(layer "In13.Cu")
		(net "M_B_CPU0_SB_DQ<0>")
	)
	(arc
		(start 327.403206 -274.408646)
		(mid 327.123778 -274.33248)
		(end 326.84339 -274.40509)
		(width 0.0889)
		(layer "In13.Cu")
		(net "M_B_CPU0_SB_DQ<0>")
	)
	(arc
		(start 335.298034 -274.408646)
		(mid 335.11109 -274.458901)
		(end 334.924146 -274.408646)
		(width 0.0889)
		(layer "In13.Cu")
		(net "M_B_CPU0_SB_DQ<0>")
	)
	(arc
		(start 329.284076 -274.408646)
		(mid 329.00112 -274.332469)
		(end 328.718164 -274.408646)
		(width 0.0889)
		(layer "In13.Cu")
		(net "M_B_CPU0_SB_DQ<0>")
	)
	(arc
		(start 331.16393 -274.408646)
		(mid 330.880974 -274.332469)
		(end 330.598018 -274.408646)
		(width 0.0889)
		(layer "In13.Cu")
		(net "M_B_CPU0_SB_DQ<0>")
	)
	(arc
		(start 332.469744 -274.413472)
		(mid 332.286236 -274.458966)
		(end 332.103984 -274.408646)
		(width 0.0889)
		(layer "In13.Cu")
		(net "M_B_CPU0_SB_DQ<0>")
	)
	(arc
		(start 331.52969 -274.413472)
		(mid 331.346182 -274.458966)
		(end 331.16393 -274.408646)
		(width 0.0889)
		(layer "In13.Cu")
		(net "M_B_CPU0_SB_DQ<0>")
	)
	(arc
		(start 333.984092 -274.408646)
		(mid 333.701136 -274.332469)
		(end 333.41818 -274.408646)
		(width 0.0889)
		(layer "In13.Cu")
		(net "M_B_CPU0_SB_DQ<0>")
	)
	(arc
		(start 326.463406 -274.408646)
		(mid 326.423277 -274.381787)
		(end 326.386952 -274.349972)
		(width 0.0889)
		(layer "In13.Cu")
		(net "M_B_CPU0_SB_DQ<0>")
	)
	(arc
		(start 332.103984 -274.408646)
		(mid 331.821028 -274.332469)
		(end 331.538072 -274.408646)
		(width 0.0889)
		(layer "In13.Cu")
		(net "M_B_CPU0_SB_DQ<0>")
	)
	(arc
		(start 335.8007 -274.376896)
		(mid 335.545635 -274.333545)
		(end 335.298034 -274.408646)
		(width 0.0889)
		(layer "In13.Cu")
		(net "M_B_CPU0_SB_DQ<0>")
	)
	(segment
		(start 336.047842 -266.530074)
		(end 335.58099 -266.796012)
		(width 0.10668)
		(layer "F.Cu")
		(net "M_B_CPU0_SB_CS_N<1>")
	)
	(segment
		(start 335.58099 -266.796012)
		(end 335.426812 -266.530582)
		(width 0.0889)
		(layer "In13.Cu")
		(net "M_B_CPU0_SB_CS_N<1>")
	)
	(segment
		(start 325.823326 -265.98372)
		(end 323.897244 -265.98372)
		(width 0.0889)
		(layer "In13.Cu")
		(net "M_B_CPU0_SB_CS_N<1>")
	)
	(segment
		(start 307.316886 -268.310106)
		(end 298.466764 -268.310106)
		(width 0.14478)
		(layer "In13.Cu")
		(net "M_B_CPU0_SB_CS_N<1>")
	)
	(segment
		(start 309.643272 -265.98372)
		(end 307.316886 -268.310106)
		(width 0.14478)
		(layer "In13.Cu")
		(net "M_B_CPU0_SB_CS_N<1>")
	)
	(segment
		(start 333.88808 -266.473432)
		(end 333.879698 -266.468606)
		(width 0.0889)
		(layer "In13.Cu")
		(net "M_B_CPU0_SB_CS_N<1>")
	)
	(segment
		(start 326.262492 -266.422886)
		(end 325.823326 -265.98372)
		(width 0.0889)
		(layer "In13.Cu")
		(net "M_B_CPU0_SB_CS_N<1>")
	)
	(segment
		(start 328.061066 -266.422886)
		(end 326.262492 -266.422886)
		(width 0.0889)
		(layer "In13.Cu")
		(net "M_B_CPU0_SB_CS_N<1>")
	)
	(segment
		(start 335.426812 -266.530582)
		(end 335.330546 -266.505182)
		(width 0.0889)
		(layer "In13.Cu")
		(net "M_B_CPU0_SB_CS_N<1>")
	)
	(segment
		(start 330.128118 -266.473432)
		(end 330.119736 -266.468606)
		(width 0.0889)
		(layer "In13.Cu")
		(net "M_B_CPU0_SB_CS_N<1>")
	)
	(segment
		(start 298.041822 -268.735048)
		(end 295.724072 -268.735048)
		(width 0.14478)
		(layer "In13.Cu")
		(net "M_B_CPU0_SB_CS_N<1>")
	)
	(segment
		(start 323.897244 -265.98372)
		(end 309.643272 -265.98372)
		(width 0.14478)
		(layer "In13.Cu")
		(net "M_B_CPU0_SB_CS_N<1>")
	)
	(segment
		(start 298.466764 -268.310106)
		(end 298.041822 -268.735048)
		(width 0.14478)
		(layer "In13.Cu")
		(net "M_B_CPU0_SB_CS_N<1>")
	)
	(segment
		(start 330.702412 -266.468606)
		(end 330.69403 -266.473432)
		(width 0.0889)
		(layer "In13.Cu")
		(net "M_B_CPU0_SB_CS_N<1>")
	)
	(segment
		(start 331.642466 -266.468606)
		(end 331.634084 -266.473432)
		(width 0.0889)
		(layer "In13.Cu")
		(net "M_B_CPU0_SB_CS_N<1>")
	)
	(arc
		(start 329.753976 -266.473432)
		(mid 329.47102 -266.549609)
		(end 329.188064 -266.473432)
		(width 0.0889)
		(layer "In13.Cu")
		(net "M_B_CPU0_SB_CS_N<1>")
	)
	(arc
		(start 328.814176 -266.473432)
		(mid 328.53122 -266.549609)
		(end 328.248264 -266.473432)
		(width 0.0889)
		(layer "In13.Cu")
		(net "M_B_CPU0_SB_CS_N<1>")
	)
	(arc
		(start 330.119736 -266.468606)
		(mid 329.936228 -266.423112)
		(end 329.753976 -266.473432)
		(width 0.0889)
		(layer "In13.Cu")
		(net "M_B_CPU0_SB_CS_N<1>")
	)
	(arc
		(start 332.948026 -266.473432)
		(mid 332.761082 -266.423177)
		(end 332.574138 -266.473432)
		(width 0.0889)
		(layer "In13.Cu")
		(net "M_B_CPU0_SB_CS_N<1>")
	)
	(arc
		(start 334.453992 -266.473432)
		(mid 334.171036 -266.549609)
		(end 333.88808 -266.473432)
		(width 0.0889)
		(layer "In13.Cu")
		(net "M_B_CPU0_SB_CS_N<1>")
	)
	(arc
		(start 333.879698 -266.468606)
		(mid 333.69619 -266.423112)
		(end 333.513938 -266.473432)
		(width 0.0889)
		(layer "In13.Cu")
		(net "M_B_CPU0_SB_CS_N<1>")
	)
	(arc
		(start 328.248264 -266.473432)
		(mid 328.158004 -266.435804)
		(end 328.061066 -266.422886)
		(width 0.0889)
		(layer "In13.Cu")
		(net "M_B_CPU0_SB_CS_N<1>")
	)
	(arc
		(start 332.008226 -266.473432)
		(mid 331.825975 -266.423082)
		(end 331.642466 -266.468606)
		(width 0.0889)
		(layer "In13.Cu")
		(net "M_B_CPU0_SB_CS_N<1>")
	)
	(arc
		(start 331.068172 -266.473432)
		(mid 330.885921 -266.423082)
		(end 330.702412 -266.468606)
		(width 0.0889)
		(layer "In13.Cu")
		(net "M_B_CPU0_SB_CS_N<1>")
	)
	(arc
		(start 334.82788 -266.473432)
		(mid 334.640936 -266.423177)
		(end 334.453992 -266.473432)
		(width 0.0889)
		(layer "In13.Cu")
		(net "M_B_CPU0_SB_CS_N<1>")
	)
	(arc
		(start 332.574138 -266.473432)
		(mid 332.291182 -266.549609)
		(end 332.008226 -266.473432)
		(width 0.0889)
		(layer "In13.Cu")
		(net "M_B_CPU0_SB_CS_N<1>")
	)
	(arc
		(start 329.188064 -266.473432)
		(mid 329.00112 -266.423177)
		(end 328.814176 -266.473432)
		(width 0.0889)
		(layer "In13.Cu")
		(net "M_B_CPU0_SB_CS_N<1>")
	)
	(arc
		(start 331.634084 -266.473432)
		(mid 331.351128 -266.549609)
		(end 331.068172 -266.473432)
		(width 0.0889)
		(layer "In13.Cu")
		(net "M_B_CPU0_SB_CS_N<1>")
	)
	(arc
		(start 330.69403 -266.473432)
		(mid 330.411074 -266.549609)
		(end 330.128118 -266.473432)
		(width 0.0889)
		(layer "In13.Cu")
		(net "M_B_CPU0_SB_CS_N<1>")
	)
	(arc
		(start 335.330546 -266.505182)
		(mid 335.075481 -266.548533)
		(end 334.82788 -266.473432)
		(width 0.0889)
		(layer "In13.Cu")
		(net "M_B_CPU0_SB_CS_N<1>")
	)
	(arc
		(start 333.513938 -266.473432)
		(mid 333.230982 -266.549609)
		(end 332.948026 -266.473432)
		(width 0.0889)
		(layer "In13.Cu")
		(net "M_B_CPU0_SB_CS_N<1>")
	)
	(segment
		(start 337.45805 -265.720068)
		(end 336.991198 -265.986006)
		(width 0.10668)
		(layer "F.Cu")
		(net "M_B_CPU0_SB_CS_N<0>")
	)
	(segment
		(start 300.413674 -267.14831)
		(end 300.819058 -267.14831)
		(width 0.14478)
		(layer "In13.Cu")
		(net "M_B_CPU0_SB_CS_N<0>")
	)
	(segment
		(start 305.825398 -267.460222)
		(end 306.13731 -267.14831)
		(width 0.14478)
		(layer "In13.Cu")
		(net "M_B_CPU0_SB_CS_N<0>")
	)
	(segment
		(start 302.79975 -267.14831)
		(end 303.044098 -267.14831)
		(width 0.14478)
		(layer "In13.Cu")
		(net "M_B_CPU0_SB_CS_N<0>")
	)
	(segment
		(start 306.861972 -267.628624)
		(end 307.362098 -267.628624)
		(width 0.14478)
		(layer "In13.Cu")
		(net "M_B_CPU0_SB_CS_N<0>")
	)
	(segment
		(start 303.600358 -267.460222)
		(end 303.91227 -267.14831)
		(width 0.14478)
		(layer "In13.Cu")
		(net "M_B_CPU0_SB_CS_N<0>")
	)
	(segment
		(start 304.712878 -267.460222)
		(end 305.02479 -267.14831)
		(width 0.14478)
		(layer "In13.Cu")
		(net "M_B_CPU0_SB_CS_N<0>")
	)
	(segment
		(start 306.13731 -267.14831)
		(end 306.381658 -267.14831)
		(width 0.14478)
		(layer "In13.Cu")
		(net "M_B_CPU0_SB_CS_N<0>")
	)
	(segment
		(start 333.984092 -265.663426)
		(end 333.992474 -265.6586)
		(width 0.0889)
		(layer "In13.Cu")
		(net "M_B_CPU0_SB_CS_N<0>")
	)
	(segment
		(start 303.35601 -267.460222)
		(end 303.600358 -267.460222)
		(width 0.14478)
		(layer "In13.Cu")
		(net "M_B_CPU0_SB_CS_N<0>")
	)
	(segment
		(start 309.461662 -265.52906)
		(end 324.059804 -265.52906)
		(width 0.14478)
		(layer "In13.Cu")
		(net "M_B_CPU0_SB_CS_N<0>")
	)
	(segment
		(start 303.91227 -267.14831)
		(end 304.156618 -267.14831)
		(width 0.14478)
		(layer "In13.Cu")
		(net "M_B_CPU0_SB_CS_N<0>")
	)
	(segment
		(start 336.740754 -265.695176)
		(end 336.83702 -265.720576)
		(width 0.0889)
		(layer "In13.Cu")
		(net "M_B_CPU0_SB_CS_N<0>")
	)
	(segment
		(start 336.83702 -265.720576)
		(end 336.991198 -265.986006)
		(width 0.0889)
		(layer "In13.Cu")
		(net "M_B_CPU0_SB_CS_N<0>")
	)
	(segment
		(start 305.02479 -267.14831)
		(end 305.269138 -267.14831)
		(width 0.14478)
		(layer "In13.Cu")
		(net "M_B_CPU0_SB_CS_N<0>")
	)
	(segment
		(start 307.362098 -267.628624)
		(end 309.461662 -265.52906)
		(width 0.14478)
		(layer "In13.Cu")
		(net "M_B_CPU0_SB_CS_N<0>")
	)
	(segment
		(start 304.156618 -267.14831)
		(end 304.46853 -267.460222)
		(width 0.14478)
		(layer "In13.Cu")
		(net "M_B_CPU0_SB_CS_N<0>")
	)
	(segment
		(start 300.819058 -267.14831)
		(end 301.13097 -267.460222)
		(width 0.14478)
		(layer "In13.Cu")
		(net "M_B_CPU0_SB_CS_N<0>")
	)
	(segment
		(start 301.375318 -267.460222)
		(end 301.68723 -267.14831)
		(width 0.14478)
		(layer "In13.Cu")
		(net "M_B_CPU0_SB_CS_N<0>")
	)
	(segment
		(start 303.044098 -267.14831)
		(end 303.35601 -267.460222)
		(width 0.14478)
		(layer "In13.Cu")
		(net "M_B_CPU0_SB_CS_N<0>")
	)
	(segment
		(start 329.284076 -265.663426)
		(end 329.292458 -265.6586)
		(width 0.0889)
		(layer "In13.Cu")
		(net "M_B_CPU0_SB_CS_N<0>")
	)
	(segment
		(start 304.46853 -267.460222)
		(end 304.712878 -267.460222)
		(width 0.14478)
		(layer "In13.Cu")
		(net "M_B_CPU0_SB_CS_N<0>")
	)
	(segment
		(start 328.709782 -265.6586)
		(end 328.718164 -265.663426)
		(width 0.0889)
		(layer "In13.Cu")
		(net "M_B_CPU0_SB_CS_N<0>")
	)
	(segment
		(start 332.469744 -265.6586)
		(end 332.478126 -265.663426)
		(width 0.0889)
		(layer "In13.Cu")
		(net "M_B_CPU0_SB_CS_N<0>")
	)
	(segment
		(start 301.931578 -267.14831)
		(end 302.24349 -267.460222)
		(width 0.14478)
		(layer "In13.Cu")
		(net "M_B_CPU0_SB_CS_N<0>")
	)
	(segment
		(start 305.269138 -267.14831)
		(end 305.58105 -267.460222)
		(width 0.14478)
		(layer "In13.Cu")
		(net "M_B_CPU0_SB_CS_N<0>")
	)
	(segment
		(start 299.82414 -267.737844)
		(end 300.413674 -267.14831)
		(width 0.14478)
		(layer "In13.Cu")
		(net "M_B_CPU0_SB_CS_N<0>")
	)
	(segment
		(start 330.22413 -265.663426)
		(end 330.232512 -265.6586)
		(width 0.0889)
		(layer "In13.Cu")
		(net "M_B_CPU0_SB_CS_N<0>")
	)
	(segment
		(start 301.68723 -267.14831)
		(end 301.931578 -267.14831)
		(width 0.14478)
		(layer "In13.Cu")
		(net "M_B_CPU0_SB_CS_N<0>")
	)
	(segment
		(start 302.487838 -267.460222)
		(end 302.79975 -267.14831)
		(width 0.14478)
		(layer "In13.Cu")
		(net "M_B_CPU0_SB_CS_N<0>")
	)
	(segment
		(start 299.82414 -267.885164)
		(end 299.82414 -267.737844)
		(width 0.14478)
		(layer "In13.Cu")
		(net "M_B_CPU0_SB_CS_N<0>")
	)
	(segment
		(start 305.58105 -267.460222)
		(end 305.825398 -267.460222)
		(width 0.14478)
		(layer "In13.Cu")
		(net "M_B_CPU0_SB_CS_N<0>")
	)
	(segment
		(start 306.381658 -267.14831)
		(end 306.861972 -267.628624)
		(width 0.14478)
		(layer "In13.Cu")
		(net "M_B_CPU0_SB_CS_N<0>")
	)
	(segment
		(start 333.044038 -265.663426)
		(end 333.05242 -265.6586)
		(width 0.0889)
		(layer "In13.Cu")
		(net "M_B_CPU0_SB_CS_N<0>")
	)
	(segment
		(start 328.32929 -265.672062)
		(end 328.344022 -265.663426)
		(width 0.0889)
		(layer "In13.Cu")
		(net "M_B_CPU0_SB_CS_N<0>")
	)
	(segment
		(start 324.059804 -265.52906)
		(end 327.28027 -265.52906)
		(width 0.0889)
		(layer "In13.Cu")
		(net "M_B_CPU0_SB_CS_N<0>")
	)
	(segment
		(start 302.24349 -267.460222)
		(end 302.487838 -267.460222)
		(width 0.14478)
		(layer "In13.Cu")
		(net "M_B_CPU0_SB_CS_N<0>")
	)
	(segment
		(start 301.13097 -267.460222)
		(end 301.375318 -267.460222)
		(width 0.14478)
		(layer "In13.Cu")
		(net "M_B_CPU0_SB_CS_N<0>")
	)
	(segment
		(start 334.924146 -265.663426)
		(end 334.932528 -265.6586)
		(width 0.0889)
		(layer "In13.Cu")
		(net "M_B_CPU0_SB_CS_N<0>")
	)
	(arc
		(start 328.718164 -265.663426)
		(mid 329.00112 -265.739603)
		(end 329.284076 -265.663426)
		(width 0.0889)
		(layer "In13.Cu")
		(net "M_B_CPU0_SB_CS_N<0>")
	)
	(arc
		(start 329.658218 -265.663426)
		(mid 329.941174 -265.739603)
		(end 330.22413 -265.663426)
		(width 0.0889)
		(layer "In13.Cu")
		(net "M_B_CPU0_SB_CS_N<0>")
	)
	(arc
		(start 328.344022 -265.663426)
		(mid 328.526273 -265.613076)
		(end 328.709782 -265.6586)
		(width 0.0889)
		(layer "In13.Cu")
		(net "M_B_CPU0_SB_CS_N<0>")
	)
	(arc
		(start 330.232512 -265.6586)
		(mid 330.41602 -265.613106)
		(end 330.598272 -265.663426)
		(width 0.0889)
		(layer "In13.Cu")
		(net "M_B_CPU0_SB_CS_N<0>")
	)
	(arc
		(start 336.238088 -265.663426)
		(mid 336.485684 -265.738604)
		(end 336.740754 -265.695176)
		(width 0.0889)
		(layer "In13.Cu")
		(net "M_B_CPU0_SB_CS_N<0>")
	)
	(arc
		(start 332.103984 -265.663426)
		(mid 332.286235 -265.613076)
		(end 332.469744 -265.6586)
		(width 0.0889)
		(layer "In13.Cu")
		(net "M_B_CPU0_SB_CS_N<0>")
	)
	(arc
		(start 333.41818 -265.663426)
		(mid 333.701136 -265.739603)
		(end 333.984092 -265.663426)
		(width 0.0889)
		(layer "In13.Cu")
		(net "M_B_CPU0_SB_CS_N<0>")
	)
	(arc
		(start 333.05242 -265.6586)
		(mid 333.235928 -265.613106)
		(end 333.41818 -265.663426)
		(width 0.0889)
		(layer "In13.Cu")
		(net "M_B_CPU0_SB_CS_N<0>")
	)
	(arc
		(start 332.478126 -265.663426)
		(mid 332.761082 -265.739603)
		(end 333.044038 -265.663426)
		(width 0.0889)
		(layer "In13.Cu")
		(net "M_B_CPU0_SB_CS_N<0>")
	)
	(arc
		(start 335.8642 -265.663426)
		(mid 336.051144 -265.613171)
		(end 336.238088 -265.663426)
		(width 0.0889)
		(layer "In13.Cu")
		(net "M_B_CPU0_SB_CS_N<0>")
	)
	(arc
		(start 330.598272 -265.663426)
		(mid 330.881228 -265.739603)
		(end 331.164184 -265.663426)
		(width 0.0889)
		(layer "In13.Cu")
		(net "M_B_CPU0_SB_CS_N<0>")
	)
	(arc
		(start 331.538072 -265.663426)
		(mid 331.821028 -265.739603)
		(end 332.103984 -265.663426)
		(width 0.0889)
		(layer "In13.Cu")
		(net "M_B_CPU0_SB_CS_N<0>")
	)
	(arc
		(start 331.164184 -265.663426)
		(mid 331.351128 -265.613171)
		(end 331.538072 -265.663426)
		(width 0.0889)
		(layer "In13.Cu")
		(net "M_B_CPU0_SB_CS_N<0>")
	)
	(arc
		(start 334.358234 -265.663426)
		(mid 334.64119 -265.739603)
		(end 334.924146 -265.663426)
		(width 0.0889)
		(layer "In13.Cu")
		(net "M_B_CPU0_SB_CS_N<0>")
	)
	(arc
		(start 334.932528 -265.6586)
		(mid 335.116036 -265.613106)
		(end 335.298288 -265.663426)
		(width 0.0889)
		(layer "In13.Cu")
		(net "M_B_CPU0_SB_CS_N<0>")
	)
	(arc
		(start 329.292458 -265.6586)
		(mid 329.475966 -265.613106)
		(end 329.658218 -265.663426)
		(width 0.0889)
		(layer "In13.Cu")
		(net "M_B_CPU0_SB_CS_N<0>")
	)
	(arc
		(start 333.992474 -265.6586)
		(mid 334.175982 -265.613106)
		(end 334.358234 -265.663426)
		(width 0.0889)
		(layer "In13.Cu")
		(net "M_B_CPU0_SB_CS_N<0>")
	)
	(arc
		(start 327.28027 -265.52906)
		(mid 327.537847 -265.563252)
		(end 327.777602 -265.663426)
		(width 0.0889)
		(layer "In13.Cu")
		(net "M_B_CPU0_SB_CS_N<0>")
	)
	(arc
		(start 327.777602 -265.663426)
		(mid 328.052308 -265.73979)
		(end 328.32929 -265.672062)
		(width 0.0889)
		(layer "In13.Cu")
		(net "M_B_CPU0_SB_CS_N<0>")
	)
	(arc
		(start 335.298288 -265.663426)
		(mid 335.581244 -265.739603)
		(end 335.8642 -265.663426)
		(width 0.0889)
		(layer "In13.Cu")
		(net "M_B_CPU0_SB_CS_N<0>")
	)
	(segment
		(start 337.45805 -270.580104)
		(end 336.991198 -270.846042)
		(width 0.10668)
		(layer "F.Cu")
		(net "M_B_CPU0_SB_CB<7>")
	)
	(segment
		(start 299.51299 -274.527772)
		(end 301.719488 -274.527772)
		(width 0.14478)
		(layer "In13.Cu")
		(net "M_B_CPU0_SB_CB<7>")
	)
	(segment
		(start 329.284076 -270.523462)
		(end 329.292458 -270.518636)
		(width 0.0889)
		(layer "In13.Cu")
		(net "M_B_CPU0_SB_CB<7>")
	)
	(segment
		(start 302.837088 -273.410172)
		(end 303.556924 -273.410172)
		(width 0.14478)
		(layer "In13.Cu")
		(net "M_B_CPU0_SB_CB<7>")
	)
	(segment
		(start 295.724072 -274.684998)
		(end 296.147998 -274.261072)
		(width 0.14478)
		(layer "In13.Cu")
		(net "M_B_CPU0_SB_CB<7>")
	)
	(segment
		(start 333.984092 -270.523462)
		(end 333.992474 -270.518636)
		(width 0.0889)
		(layer "In13.Cu")
		(net "M_B_CPU0_SB_CB<7>")
	)
	(segment
		(start 303.556924 -273.410172)
		(end 304.220118 -274.073366)
		(width 0.14478)
		(layer "In13.Cu")
		(net "M_B_CPU0_SB_CB<7>")
	)
	(segment
		(start 301.719488 -274.527772)
		(end 302.837088 -273.410172)
		(width 0.14478)
		(layer "In13.Cu")
		(net "M_B_CPU0_SB_CB<7>")
	)
	(segment
		(start 331.52969 -270.518636)
		(end 331.538072 -270.523462)
		(width 0.0889)
		(layer "In13.Cu")
		(net "M_B_CPU0_SB_CB<7>")
	)
	(segment
		(start 323.874892 -268.9606)
		(end 324.223126 -268.9606)
		(width 0.0889)
		(layer "In13.Cu")
		(net "M_B_CPU0_SB_CB<7>")
	)
	(segment
		(start 337.12277 -270.4973)
		(end 337.145122 -270.580612)
		(width 0.0889)
		(layer "In13.Cu")
		(net "M_B_CPU0_SB_CB<7>")
	)
	(segment
		(start 299.24629 -274.261072)
		(end 299.51299 -274.527772)
		(width 0.14478)
		(layer "In13.Cu")
		(net "M_B_CPU0_SB_CB<7>")
	)
	(segment
		(start 324.223126 -268.9606)
		(end 324.390258 -269.127732)
		(width 0.0889)
		(layer "In13.Cu")
		(net "M_B_CPU0_SB_CB<7>")
	)
	(segment
		(start 332.469744 -270.518636)
		(end 332.478126 -270.523462)
		(width 0.0889)
		(layer "In13.Cu")
		(net "M_B_CPU0_SB_CB<7>")
	)
	(segment
		(start 296.147998 -274.261072)
		(end 299.24629 -274.261072)
		(width 0.14478)
		(layer "In13.Cu")
		(net "M_B_CPU0_SB_CB<7>")
	)
	(segment
		(start 312.239152 -268.9606)
		(end 323.874892 -268.9606)
		(width 0.14478)
		(layer "In13.Cu")
		(net "M_B_CPU0_SB_CB<7>")
	)
	(segment
		(start 333.044038 -270.523462)
		(end 333.05242 -270.518636)
		(width 0.0889)
		(layer "In13.Cu")
		(net "M_B_CPU0_SB_CB<7>")
	)
	(segment
		(start 337.145122 -270.580612)
		(end 336.991198 -270.846042)
		(width 0.0889)
		(layer "In13.Cu")
		(net "M_B_CPU0_SB_CB<7>")
	)
	(segment
		(start 324.390258 -269.127732)
		(end 324.943978 -269.127732)
		(width 0.0889)
		(layer "In13.Cu")
		(net "M_B_CPU0_SB_CB<7>")
	)
	(segment
		(start 324.943978 -269.127732)
		(end 325.928736 -270.11249)
		(width 0.0889)
		(layer "In13.Cu")
		(net "M_B_CPU0_SB_CB<7>")
	)
	(segment
		(start 336.229706 -270.518636)
		(end 336.238088 -270.523462)
		(width 0.0889)
		(layer "In13.Cu")
		(net "M_B_CPU0_SB_CB<7>")
	)
	(segment
		(start 326.629776 -270.402812)
		(end 327.33107 -270.402812)
		(width 0.0889)
		(layer "In13.Cu")
		(net "M_B_CPU0_SB_CB<7>")
	)
	(segment
		(start 328.32929 -270.532098)
		(end 328.344022 -270.523462)
		(width 0.0889)
		(layer "In13.Cu")
		(net "M_B_CPU0_SB_CB<7>")
	)
	(segment
		(start 307.126386 -274.073366)
		(end 312.239152 -268.9606)
		(width 0.14478)
		(layer "In13.Cu")
		(net "M_B_CPU0_SB_CB<7>")
	)
	(segment
		(start 328.709782 -270.518636)
		(end 328.718164 -270.523462)
		(width 0.0889)
		(layer "In13.Cu")
		(net "M_B_CPU0_SB_CB<7>")
	)
	(segment
		(start 304.220118 -274.073366)
		(end 307.126386 -274.073366)
		(width 0.14478)
		(layer "In13.Cu")
		(net "M_B_CPU0_SB_CB<7>")
	)
	(arc
		(start 333.05242 -270.518636)
		(mid 333.235928 -270.473142)
		(end 333.41818 -270.523462)
		(width 0.0889)
		(layer "In13.Cu")
		(net "M_B_CPU0_SB_CB<7>")
	)
	(arc
		(start 328.718164 -270.523462)
		(mid 329.00112 -270.599639)
		(end 329.284076 -270.523462)
		(width 0.0889)
		(layer "In13.Cu")
		(net "M_B_CPU0_SB_CB<7>")
	)
	(arc
		(start 327.33107 -270.402812)
		(mid 327.562339 -270.433512)
		(end 327.777602 -270.523462)
		(width 0.0889)
		(layer "In13.Cu")
		(net "M_B_CPU0_SB_CB<7>")
	)
	(arc
		(start 325.928736 -270.11249)
		(mid 326.25039 -270.327349)
		(end 326.629776 -270.402812)
		(width 0.0889)
		(layer "In13.Cu")
		(net "M_B_CPU0_SB_CB<7>")
	)
	(arc
		(start 330.598018 -270.523462)
		(mid 330.880974 -270.599639)
		(end 331.16393 -270.523462)
		(width 0.0889)
		(layer "In13.Cu")
		(net "M_B_CPU0_SB_CB<7>")
	)
	(arc
		(start 329.658218 -270.523462)
		(mid 329.941174 -270.599639)
		(end 330.22413 -270.523462)
		(width 0.0889)
		(layer "In13.Cu")
		(net "M_B_CPU0_SB_CB<7>")
	)
	(arc
		(start 327.777602 -270.523462)
		(mid 328.052308 -270.599826)
		(end 328.32929 -270.532098)
		(width 0.0889)
		(layer "In13.Cu")
		(net "M_B_CPU0_SB_CB<7>")
	)
	(arc
		(start 334.924146 -270.523462)
		(mid 335.11109 -270.473207)
		(end 335.298034 -270.523462)
		(width 0.0889)
		(layer "In13.Cu")
		(net "M_B_CPU0_SB_CB<7>")
	)
	(arc
		(start 333.41818 -270.523462)
		(mid 333.701136 -270.599639)
		(end 333.984092 -270.523462)
		(width 0.0889)
		(layer "In13.Cu")
		(net "M_B_CPU0_SB_CB<7>")
	)
	(arc
		(start 334.358234 -270.523462)
		(mid 334.64119 -270.599639)
		(end 334.924146 -270.523462)
		(width 0.0889)
		(layer "In13.Cu")
		(net "M_B_CPU0_SB_CB<7>")
	)
	(arc
		(start 336.804 -270.523462)
		(mid 336.960438 -270.474491)
		(end 337.12277 -270.4973)
		(width 0.0889)
		(layer "In13.Cu")
		(net "M_B_CPU0_SB_CB<7>")
	)
	(arc
		(start 335.863946 -270.523462)
		(mid 336.046197 -270.473112)
		(end 336.229706 -270.518636)
		(width 0.0889)
		(layer "In13.Cu")
		(net "M_B_CPU0_SB_CB<7>")
	)
	(arc
		(start 332.103984 -270.523462)
		(mid 332.286235 -270.473112)
		(end 332.469744 -270.518636)
		(width 0.0889)
		(layer "In13.Cu")
		(net "M_B_CPU0_SB_CB<7>")
	)
	(arc
		(start 336.238088 -270.523462)
		(mid 336.521044 -270.599639)
		(end 336.804 -270.523462)
		(width 0.0889)
		(layer "In13.Cu")
		(net "M_B_CPU0_SB_CB<7>")
	)
	(arc
		(start 330.22413 -270.523462)
		(mid 330.411074 -270.473207)
		(end 330.598018 -270.523462)
		(width 0.0889)
		(layer "In13.Cu")
		(net "M_B_CPU0_SB_CB<7>")
	)
	(arc
		(start 335.298034 -270.523462)
		(mid 335.58099 -270.599639)
		(end 335.863946 -270.523462)
		(width 0.0889)
		(layer "In13.Cu")
		(net "M_B_CPU0_SB_CB<7>")
	)
	(arc
		(start 331.538072 -270.523462)
		(mid 331.821028 -270.599639)
		(end 332.103984 -270.523462)
		(width 0.0889)
		(layer "In13.Cu")
		(net "M_B_CPU0_SB_CB<7>")
	)
	(arc
		(start 333.992474 -270.518636)
		(mid 334.175982 -270.473142)
		(end 334.358234 -270.523462)
		(width 0.0889)
		(layer "In13.Cu")
		(net "M_B_CPU0_SB_CB<7>")
	)
	(arc
		(start 329.292458 -270.518636)
		(mid 329.475966 -270.473142)
		(end 329.658218 -270.523462)
		(width 0.0889)
		(layer "In13.Cu")
		(net "M_B_CPU0_SB_CB<7>")
	)
	(arc
		(start 331.16393 -270.523462)
		(mid 331.346181 -270.473112)
		(end 331.52969 -270.518636)
		(width 0.0889)
		(layer "In13.Cu")
		(net "M_B_CPU0_SB_CB<7>")
	)
	(arc
		(start 328.344022 -270.523462)
		(mid 328.526273 -270.473112)
		(end 328.709782 -270.518636)
		(width 0.0889)
		(layer "In13.Cu")
		(net "M_B_CPU0_SB_CB<7>")
	)
	(arc
		(start 332.478126 -270.523462)
		(mid 332.761082 -270.599639)
		(end 333.044038 -270.523462)
		(width 0.0889)
		(layer "In13.Cu")
		(net "M_B_CPU0_SB_CB<7>")
	)
	(segment
		(start 336.047842 -269.770098)
		(end 335.58099 -270.036036)
		(width 0.10668)
		(layer "F.Cu")
		(net "M_B_CPU0_SB_CB<6>")
	)
	(segment
		(start 326.917812 -269.722854)
		(end 326.93356 -269.71371)
		(width 0.0889)
		(layer "In13.Cu")
		(net "M_B_CPU0_SB_CB<6>")
	)
	(segment
		(start 335.712816 -269.687294)
		(end 335.735168 -269.770606)
		(width 0.0889)
		(layer "In13.Cu")
		(net "M_B_CPU0_SB_CB<6>")
	)
	(segment
		(start 323.915024 -268.05128)
		(end 324.390766 -268.05128)
		(width 0.0889)
		(layer "In13.Cu")
		(net "M_B_CPU0_SB_CB<6>")
	)
	(segment
		(start 326.93356 -269.71371)
		(end 326.951848 -269.703296)
		(width 0.0889)
		(layer "In13.Cu")
		(net "M_B_CPU0_SB_CB<6>")
	)
	(segment
		(start 302.16348 -271.71015)
		(end 308.21757 -271.71015)
		(width 0.14478)
		(layer "In13.Cu")
		(net "M_B_CPU0_SB_CB<6>")
	)
	(segment
		(start 334.819752 -269.70863)
		(end 334.828134 -269.713456)
		(width 0.0889)
		(layer "In13.Cu")
		(net "M_B_CPU0_SB_CB<6>")
	)
	(segment
		(start 301.313596 -272.560034)
		(end 302.16348 -271.71015)
		(width 0.14478)
		(layer "In13.Cu")
		(net "M_B_CPU0_SB_CB<6>")
	)
	(segment
		(start 296.91965 -272.840196)
		(end 296.91965 -272.227802)
		(width 0.14478)
		(layer "In13.Cu")
		(net "M_B_CPU0_SB_CB<6>")
	)
	(segment
		(start 327.874122 -269.713456)
		(end 327.882504 -269.70863)
		(width 0.0889)
		(layer "In13.Cu")
		(net "M_B_CPU0_SB_CB<6>")
	)
	(segment
		(start 296.91965 -272.227802)
		(end 297.06443 -272.083022)
		(width 0.14478)
		(layer "In13.Cu")
		(net "M_B_CPU0_SB_CB<6>")
	)
	(segment
		(start 331.634084 -269.713456)
		(end 331.642466 -269.70863)
		(width 0.0889)
		(layer "In13.Cu")
		(net "M_B_CPU0_SB_CB<6>")
	)
	(segment
		(start 299.331126 -272.560034)
		(end 301.313596 -272.560034)
		(width 0.14478)
		(layer "In13.Cu")
		(net "M_B_CPU0_SB_CB<6>")
	)
	(segment
		(start 297.47083 -272.227802)
		(end 297.47083 -272.840196)
		(width 0.14478)
		(layer "In13.Cu")
		(net "M_B_CPU0_SB_CB<6>")
	)
	(segment
		(start 297.47083 -272.840196)
		(end 297.61561 -272.984976)
		(width 0.14478)
		(layer "In13.Cu")
		(net "M_B_CPU0_SB_CB<6>")
	)
	(segment
		(start 297.61561 -272.984976)
		(end 298.906184 -272.984976)
		(width 0.14478)
		(layer "In13.Cu")
		(net "M_B_CPU0_SB_CB<6>")
	)
	(segment
		(start 333.88808 -269.713456)
		(end 333.888334 -269.713456)
		(width 0.0889)
		(layer "In13.Cu")
		(net "M_B_CPU0_SB_CB<6>")
	)
	(segment
		(start 335.394046 -269.713456)
		(end 335.402428 -269.70863)
		(width 0.0889)
		(layer "In13.Cu")
		(net "M_B_CPU0_SB_CB<6>")
	)
	(segment
		(start 325.178674 -268.551152)
		(end 326.252332 -269.62481)
		(width 0.0889)
		(layer "In13.Cu")
		(net "M_B_CPU0_SB_CB<6>")
	)
	(segment
		(start 311.87644 -268.05128)
		(end 323.915024 -268.05128)
		(width 0.14478)
		(layer "In13.Cu")
		(net "M_B_CPU0_SB_CB<6>")
	)
	(segment
		(start 335.735168 -269.770606)
		(end 335.58099 -270.036036)
		(width 0.0889)
		(layer "In13.Cu")
		(net "M_B_CPU0_SB_CB<6>")
	)
	(segment
		(start 324.390766 -268.05128)
		(end 324.890638 -268.551152)
		(width 0.0889)
		(layer "In13.Cu")
		(net "M_B_CPU0_SB_CB<6>")
	)
	(segment
		(start 327.85939 -269.722092)
		(end 327.874122 -269.713456)
		(width 0.0889)
		(layer "In13.Cu")
		(net "M_B_CPU0_SB_CB<6>")
	)
	(segment
		(start 297.32605 -272.083022)
		(end 297.47083 -272.227802)
		(width 0.14478)
		(layer "In13.Cu")
		(net "M_B_CPU0_SB_CB<6>")
	)
	(segment
		(start 330.119736 -269.70863)
		(end 330.128118 -269.713456)
		(width 0.0889)
		(layer "In13.Cu")
		(net "M_B_CPU0_SB_CB<6>")
	)
	(segment
		(start 333.879698 -269.70863)
		(end 333.88808 -269.713456)
		(width 0.0889)
		(layer "In13.Cu")
		(net "M_B_CPU0_SB_CB<6>")
	)
	(segment
		(start 330.69403 -269.713456)
		(end 330.702412 -269.70863)
		(width 0.0889)
		(layer "In13.Cu")
		(net "M_B_CPU0_SB_CB<6>")
	)
	(segment
		(start 308.21757 -271.71015)
		(end 311.87644 -268.05128)
		(width 0.14478)
		(layer "In13.Cu")
		(net "M_B_CPU0_SB_CB<6>")
	)
	(segment
		(start 324.890638 -268.551152)
		(end 325.178674 -268.551152)
		(width 0.0889)
		(layer "In13.Cu")
		(net "M_B_CPU0_SB_CB<6>")
	)
	(segment
		(start 298.906184 -272.984976)
		(end 299.331126 -272.560034)
		(width 0.14478)
		(layer "In13.Cu")
		(net "M_B_CPU0_SB_CB<6>")
	)
	(segment
		(start 295.724072 -272.984976)
		(end 296.77487 -272.984976)
		(width 0.14478)
		(layer "In13.Cu")
		(net "M_B_CPU0_SB_CB<6>")
	)
	(segment
		(start 296.77487 -272.984976)
		(end 296.91965 -272.840196)
		(width 0.14478)
		(layer "In13.Cu")
		(net "M_B_CPU0_SB_CB<6>")
	)
	(segment
		(start 297.06443 -272.083022)
		(end 297.32605 -272.083022)
		(width 0.14478)
		(layer "In13.Cu")
		(net "M_B_CPU0_SB_CB<6>")
	)
	(arc
		(start 326.367648 -269.713456)
		(mid 326.641503 -269.789806)
		(end 326.917812 -269.722854)
		(width 0.0889)
		(layer "In13.Cu")
		(net "M_B_CPU0_SB_CB<6>")
	)
	(arc
		(start 330.128118 -269.713456)
		(mid 330.411074 -269.789633)
		(end 330.69403 -269.713456)
		(width 0.0889)
		(layer "In13.Cu")
		(net "M_B_CPU0_SB_CB<6>")
	)
	(arc
		(start 326.951848 -269.703296)
		(mid 327.131077 -269.663143)
		(end 327.307702 -269.713456)
		(width 0.0889)
		(layer "In13.Cu")
		(net "M_B_CPU0_SB_CB<6>")
	)
	(arc
		(start 332.948026 -269.713456)
		(mid 333.230982 -269.789633)
		(end 333.513938 -269.713456)
		(width 0.0889)
		(layer "In13.Cu")
		(net "M_B_CPU0_SB_CB<6>")
	)
	(arc
		(start 330.702412 -269.70863)
		(mid 330.88592 -269.663136)
		(end 331.068172 -269.713456)
		(width 0.0889)
		(layer "In13.Cu")
		(net "M_B_CPU0_SB_CB<6>")
	)
	(arc
		(start 331.068172 -269.713456)
		(mid 331.351128 -269.789633)
		(end 331.634084 -269.713456)
		(width 0.0889)
		(layer "In13.Cu")
		(net "M_B_CPU0_SB_CB<6>")
	)
	(arc
		(start 334.453992 -269.713456)
		(mid 334.636243 -269.663106)
		(end 334.819752 -269.70863)
		(width 0.0889)
		(layer "In13.Cu")
		(net "M_B_CPU0_SB_CB<6>")
	)
	(arc
		(start 327.882504 -269.70863)
		(mid 328.066012 -269.663136)
		(end 328.248264 -269.713456)
		(width 0.0889)
		(layer "In13.Cu")
		(net "M_B_CPU0_SB_CB<6>")
	)
	(arc
		(start 335.402428 -269.70863)
		(mid 335.555298 -269.663989)
		(end 335.712816 -269.687294)
		(width 0.0889)
		(layer "In13.Cu")
		(net "M_B_CPU0_SB_CB<6>")
	)
	(arc
		(start 332.008226 -269.713456)
		(mid 332.291182 -269.789633)
		(end 332.574138 -269.713456)
		(width 0.0889)
		(layer "In13.Cu")
		(net "M_B_CPU0_SB_CB<6>")
	)
	(arc
		(start 326.252332 -269.62481)
		(mid 326.307117 -269.67287)
		(end 326.367648 -269.713456)
		(width 0.0889)
		(layer "In13.Cu")
		(net "M_B_CPU0_SB_CB<6>")
	)
	(arc
		(start 329.753976 -269.713456)
		(mid 329.936227 -269.663106)
		(end 330.119736 -269.70863)
		(width 0.0889)
		(layer "In13.Cu")
		(net "M_B_CPU0_SB_CB<6>")
	)
	(arc
		(start 329.188064 -269.713456)
		(mid 329.47102 -269.789633)
		(end 329.753976 -269.713456)
		(width 0.0889)
		(layer "In13.Cu")
		(net "M_B_CPU0_SB_CB<6>")
	)
	(arc
		(start 328.814176 -269.713456)
		(mid 329.00112 -269.663201)
		(end 329.188064 -269.713456)
		(width 0.0889)
		(layer "In13.Cu")
		(net "M_B_CPU0_SB_CB<6>")
	)
	(arc
		(start 333.888334 -269.713456)
		(mid 334.17118 -269.789633)
		(end 334.453992 -269.713456)
		(width 0.0889)
		(layer "In13.Cu")
		(net "M_B_CPU0_SB_CB<6>")
	)
	(arc
		(start 328.248264 -269.713456)
		(mid 328.53122 -269.789633)
		(end 328.814176 -269.713456)
		(width 0.0889)
		(layer "In13.Cu")
		(net "M_B_CPU0_SB_CB<6>")
	)
	(arc
		(start 334.828134 -269.713456)
		(mid 335.11109 -269.789633)
		(end 335.394046 -269.713456)
		(width 0.0889)
		(layer "In13.Cu")
		(net "M_B_CPU0_SB_CB<6>")
	)
	(arc
		(start 332.574138 -269.713456)
		(mid 332.761082 -269.663201)
		(end 332.948026 -269.713456)
		(width 0.0889)
		(layer "In13.Cu")
		(net "M_B_CPU0_SB_CB<6>")
	)
	(arc
		(start 331.642466 -269.70863)
		(mid 331.825974 -269.663136)
		(end 332.008226 -269.713456)
		(width 0.0889)
		(layer "In13.Cu")
		(net "M_B_CPU0_SB_CB<6>")
	)
	(arc
		(start 333.513938 -269.713456)
		(mid 333.696189 -269.663106)
		(end 333.879698 -269.70863)
		(width 0.0889)
		(layer "In13.Cu")
		(net "M_B_CPU0_SB_CB<6>")
	)
	(arc
		(start 327.307702 -269.713456)
		(mid 327.582408 -269.78982)
		(end 327.85939 -269.722092)
		(width 0.0889)
		(layer "In13.Cu")
		(net "M_B_CPU0_SB_CB<6>")
	)
	(segment
		(start 337.92795 -269.770098)
		(end 337.461098 -270.036036)
		(width 0.10668)
		(layer "F.Cu")
		(net "M_B_CPU0_SB_CB<5>")
	)
	(segment
		(start 304.820066 -273.405346)
		(end 304.964846 -273.260566)
		(width 0.14478)
		(layer "In13.Cu")
		(net "M_B_CPU0_SB_CB<5>")
	)
	(segment
		(start 324.240906 -268.50594)
		(end 324.542658 -268.807692)
		(width 0.0889)
		(layer "In13.Cu")
		(net "M_B_CPU0_SB_CB<5>")
	)
	(segment
		(start 305.516026 -272.360644)
		(end 305.516026 -273.260566)
		(width 0.14478)
		(layer "In13.Cu")
		(net "M_B_CPU0_SB_CB<5>")
	)
	(segment
		(start 333.88808 -270.358616)
		(end 333.888334 -270.358616)
		(width 0.0889)
		(layer "In13.Cu")
		(net "M_B_CPU0_SB_CB<5>")
	)
	(segment
		(start 312.057796 -268.50594)
		(end 323.887084 -268.50594)
		(width 0.14478)
		(layer "In13.Cu")
		(net "M_B_CPU0_SB_CB<5>")
	)
	(segment
		(start 337.307174 -270.301466)
		(end 337.461098 -270.036036)
		(width 0.0889)
		(layer "In13.Cu")
		(net "M_B_CPU0_SB_CB<5>")
	)
	(segment
		(start 328.239882 -270.363442)
		(end 328.248264 -270.358616)
		(width 0.0889)
		(layer "In13.Cu")
		(net "M_B_CPU0_SB_CB<5>")
	)
	(segment
		(start 304.413666 -273.260566)
		(end 304.558446 -273.405346)
		(width 0.14478)
		(layer "In13.Cu")
		(net "M_B_CPU0_SB_CB<5>")
	)
	(segment
		(start 330.119736 -270.363442)
		(end 330.128118 -270.358616)
		(width 0.0889)
		(layer "In13.Cu")
		(net "M_B_CPU0_SB_CB<5>")
	)
	(segment
		(start 304.964846 -273.260566)
		(end 304.964846 -272.360644)
		(width 0.14478)
		(layer "In13.Cu")
		(net "M_B_CPU0_SB_CB<5>")
	)
	(segment
		(start 335.394046 -270.358616)
		(end 335.402428 -270.363442)
		(width 0.0889)
		(layer "In13.Cu")
		(net "M_B_CPU0_SB_CB<5>")
	)
	(segment
		(start 336.3341 -270.358616)
		(end 336.342482 -270.363442)
		(width 0.0889)
		(layer "In13.Cu")
		(net "M_B_CPU0_SB_CB<5>")
	)
	(segment
		(start 308.347872 -272.215864)
		(end 312.057796 -268.50594)
		(width 0.14478)
		(layer "In13.Cu")
		(net "M_B_CPU0_SB_CB<5>")
	)
	(segment
		(start 303.53381 -272.560034)
		(end 303.87798 -272.215864)
		(width 0.14478)
		(layer "In13.Cu")
		(net "M_B_CPU0_SB_CB<5>")
	)
	(segment
		(start 324.964298 -268.807692)
		(end 326.054974 -269.898368)
		(width 0.0889)
		(layer "In13.Cu")
		(net "M_B_CPU0_SB_CB<5>")
	)
	(segment
		(start 304.558446 -273.405346)
		(end 304.820066 -273.405346)
		(width 0.14478)
		(layer "In13.Cu")
		(net "M_B_CPU0_SB_CB<5>")
	)
	(segment
		(start 306.211986 -272.215864)
		(end 308.347872 -272.215864)
		(width 0.14478)
		(layer "In13.Cu")
		(net "M_B_CPU0_SB_CB<5>")
	)
	(segment
		(start 302.439578 -272.560034)
		(end 303.53381 -272.560034)
		(width 0.14478)
		(layer "In13.Cu")
		(net "M_B_CPU0_SB_CB<5>")
	)
	(segment
		(start 304.964846 -272.360644)
		(end 305.109626 -272.215864)
		(width 0.14478)
		(layer "In13.Cu")
		(net "M_B_CPU0_SB_CB<5>")
	)
	(segment
		(start 303.87798 -272.215864)
		(end 304.268886 -272.215864)
		(width 0.14478)
		(layer "In13.Cu")
		(net "M_B_CPU0_SB_CB<5>")
	)
	(segment
		(start 305.371246 -272.215864)
		(end 305.516026 -272.360644)
		(width 0.14478)
		(layer "In13.Cu")
		(net "M_B_CPU0_SB_CB<5>")
	)
	(segment
		(start 324.542658 -268.807692)
		(end 324.964298 -268.807692)
		(width 0.0889)
		(layer "In13.Cu")
		(net "M_B_CPU0_SB_CB<5>")
	)
	(segment
		(start 305.516026 -273.260566)
		(end 305.660806 -273.405346)
		(width 0.14478)
		(layer "In13.Cu")
		(net "M_B_CPU0_SB_CB<5>")
	)
	(segment
		(start 305.109626 -272.215864)
		(end 305.371246 -272.215864)
		(width 0.14478)
		(layer "In13.Cu")
		(net "M_B_CPU0_SB_CB<5>")
	)
	(segment
		(start 333.879698 -270.363442)
		(end 333.88808 -270.358616)
		(width 0.0889)
		(layer "In13.Cu")
		(net "M_B_CPU0_SB_CB<5>")
	)
	(segment
		(start 326.677782 -270.156432)
		(end 327.123806 -270.156432)
		(width 0.0889)
		(layer "In13.Cu")
		(net "M_B_CPU0_SB_CB<5>")
	)
	(segment
		(start 305.922426 -273.405346)
		(end 306.067206 -273.260566)
		(width 0.14478)
		(layer "In13.Cu")
		(net "M_B_CPU0_SB_CB<5>")
	)
	(segment
		(start 323.887084 -268.50594)
		(end 324.240906 -268.50594)
		(width 0.0889)
		(layer "In13.Cu")
		(net "M_B_CPU0_SB_CB<5>")
	)
	(segment
		(start 330.69403 -270.358616)
		(end 330.702412 -270.363442)
		(width 0.0889)
		(layer "In13.Cu")
		(net "M_B_CPU0_SB_CB<5>")
	)
	(segment
		(start 306.067206 -273.260566)
		(end 306.067206 -272.360644)
		(width 0.14478)
		(layer "In13.Cu")
		(net "M_B_CPU0_SB_CB<5>")
	)
	(segment
		(start 305.660806 -273.405346)
		(end 305.922426 -273.405346)
		(width 0.14478)
		(layer "In13.Cu")
		(net "M_B_CPU0_SB_CB<5>")
	)
	(segment
		(start 301.164498 -273.835114)
		(end 302.439578 -272.560034)
		(width 0.14478)
		(layer "In13.Cu")
		(net "M_B_CPU0_SB_CB<5>")
	)
	(segment
		(start 334.819752 -270.363442)
		(end 334.828134 -270.358616)
		(width 0.0889)
		(layer "In13.Cu")
		(net "M_B_CPU0_SB_CB<5>")
	)
	(segment
		(start 299.82414 -273.835114)
		(end 301.164498 -273.835114)
		(width 0.14478)
		(layer "In13.Cu")
		(net "M_B_CPU0_SB_CB<5>")
	)
	(segment
		(start 306.067206 -272.360644)
		(end 306.211986 -272.215864)
		(width 0.14478)
		(layer "In13.Cu")
		(net "M_B_CPU0_SB_CB<5>")
	)
	(segment
		(start 331.634084 -270.358616)
		(end 331.642466 -270.363442)
		(width 0.0889)
		(layer "In13.Cu")
		(net "M_B_CPU0_SB_CB<5>")
	)
	(segment
		(start 337.211162 -270.326866)
		(end 337.307174 -270.301466)
		(width 0.0889)
		(layer "In13.Cu")
		(net "M_B_CPU0_SB_CB<5>")
	)
	(segment
		(start 304.268886 -272.215864)
		(end 304.413666 -272.360644)
		(width 0.14478)
		(layer "In13.Cu")
		(net "M_B_CPU0_SB_CB<5>")
	)
	(segment
		(start 304.413666 -272.360644)
		(end 304.413666 -273.260566)
		(width 0.14478)
		(layer "In13.Cu")
		(net "M_B_CPU0_SB_CB<5>")
	)
	(arc
		(start 330.128118 -270.358616)
		(mid 330.411074 -270.282439)
		(end 330.69403 -270.358616)
		(width 0.0889)
		(layer "In13.Cu")
		(net "M_B_CPU0_SB_CB<5>")
	)
	(arc
		(start 332.008226 -270.358616)
		(mid 332.291182 -270.282439)
		(end 332.574138 -270.358616)
		(width 0.0889)
		(layer "In13.Cu")
		(net "M_B_CPU0_SB_CB<5>")
	)
	(arc
		(start 333.888334 -270.358616)
		(mid 334.17118 -270.282439)
		(end 334.453992 -270.358616)
		(width 0.0889)
		(layer "In13.Cu")
		(net "M_B_CPU0_SB_CB<5>")
	)
	(arc
		(start 331.068172 -270.358616)
		(mid 331.351128 -270.282439)
		(end 331.634084 -270.358616)
		(width 0.0889)
		(layer "In13.Cu")
		(net "M_B_CPU0_SB_CB<5>")
	)
	(arc
		(start 336.342482 -270.363442)
		(mid 336.52599 -270.408936)
		(end 336.708242 -270.358616)
		(width 0.0889)
		(layer "In13.Cu")
		(net "M_B_CPU0_SB_CB<5>")
	)
	(arc
		(start 329.188064 -270.358616)
		(mid 329.47102 -270.282439)
		(end 329.753976 -270.358616)
		(width 0.0889)
		(layer "In13.Cu")
		(net "M_B_CPU0_SB_CB<5>")
	)
	(arc
		(start 335.402428 -270.363442)
		(mid 335.585936 -270.408936)
		(end 335.768188 -270.358616)
		(width 0.0889)
		(layer "In13.Cu")
		(net "M_B_CPU0_SB_CB<5>")
	)
	(arc
		(start 334.453992 -270.358616)
		(mid 334.636243 -270.408966)
		(end 334.819752 -270.363442)
		(width 0.0889)
		(layer "In13.Cu")
		(net "M_B_CPU0_SB_CB<5>")
	)
	(arc
		(start 334.828134 -270.358616)
		(mid 335.11109 -270.282439)
		(end 335.394046 -270.358616)
		(width 0.0889)
		(layer "In13.Cu")
		(net "M_B_CPU0_SB_CB<5>")
	)
	(arc
		(start 328.814176 -270.358616)
		(mid 329.00112 -270.408871)
		(end 329.188064 -270.358616)
		(width 0.0889)
		(layer "In13.Cu")
		(net "M_B_CPU0_SB_CB<5>")
	)
	(arc
		(start 330.702412 -270.363442)
		(mid 330.88592 -270.408936)
		(end 331.068172 -270.358616)
		(width 0.0889)
		(layer "In13.Cu")
		(net "M_B_CPU0_SB_CB<5>")
	)
	(arc
		(start 331.642466 -270.363442)
		(mid 331.825974 -270.408936)
		(end 332.008226 -270.358616)
		(width 0.0889)
		(layer "In13.Cu")
		(net "M_B_CPU0_SB_CB<5>")
	)
	(arc
		(start 328.248264 -270.358616)
		(mid 328.53122 -270.282439)
		(end 328.814176 -270.358616)
		(width 0.0889)
		(layer "In13.Cu")
		(net "M_B_CPU0_SB_CB<5>")
	)
	(arc
		(start 336.708242 -270.358616)
		(mid 336.955955 -270.283396)
		(end 337.211162 -270.326866)
		(width 0.0889)
		(layer "In13.Cu")
		(net "M_B_CPU0_SB_CB<5>")
	)
	(arc
		(start 335.768188 -270.358616)
		(mid 336.051144 -270.282439)
		(end 336.3341 -270.358616)
		(width 0.0889)
		(layer "In13.Cu")
		(net "M_B_CPU0_SB_CB<5>")
	)
	(arc
		(start 333.513938 -270.358616)
		(mid 333.696189 -270.408966)
		(end 333.879698 -270.363442)
		(width 0.0889)
		(layer "In13.Cu")
		(net "M_B_CPU0_SB_CB<5>")
	)
	(arc
		(start 327.123806 -270.156432)
		(mid 327.512097 -270.207871)
		(end 327.873614 -270.358616)
		(width 0.0889)
		(layer "In13.Cu")
		(net "M_B_CPU0_SB_CB<5>")
	)
	(arc
		(start 327.873614 -270.358616)
		(mid 328.056119 -270.409093)
		(end 328.239882 -270.363442)
		(width 0.0889)
		(layer "In13.Cu")
		(net "M_B_CPU0_SB_CB<5>")
	)
	(arc
		(start 332.574138 -270.358616)
		(mid 332.761082 -270.408871)
		(end 332.948026 -270.358616)
		(width 0.0889)
		(layer "In13.Cu")
		(net "M_B_CPU0_SB_CB<5>")
	)
	(arc
		(start 332.948026 -270.358616)
		(mid 333.230982 -270.282439)
		(end 333.513938 -270.358616)
		(width 0.0889)
		(layer "In13.Cu")
		(net "M_B_CPU0_SB_CB<5>")
	)
	(arc
		(start 329.753976 -270.358616)
		(mid 329.936227 -270.408966)
		(end 330.119736 -270.363442)
		(width 0.0889)
		(layer "In13.Cu")
		(net "M_B_CPU0_SB_CB<5>")
	)
	(arc
		(start 326.054974 -269.898368)
		(mid 326.340706 -270.089352)
		(end 326.677782 -270.156432)
		(width 0.0889)
		(layer "In13.Cu")
		(net "M_B_CPU0_SB_CB<5>")
	)
	(segment
		(start 336.517996 -268.960092)
		(end 336.051144 -269.22603)
		(width 0.10668)
		(layer "F.Cu")
		(net "M_B_CPU0_SB_CB<4>")
	)
	(segment
		(start 306.48275 -271.237964)
		(end 306.74437 -271.237964)
		(width 0.14478)
		(layer "In13.Cu")
		(net "M_B_CPU0_SB_CB<4>")
	)
	(segment
		(start 299.82414 -272.135092)
		(end 300.246288 -271.712944)
		(width 0.14478)
		(layer "In13.Cu")
		(net "M_B_CPU0_SB_CB<4>")
	)
	(segment
		(start 300.451012 -271.712944)
		(end 300.830488 -272.09242)
		(width 0.14478)
		(layer "In13.Cu")
		(net "M_B_CPU0_SB_CB<4>")
	)
	(segment
		(start 303.58207 -270.895318)
		(end 303.72685 -270.750538)
		(width 0.14478)
		(layer "In13.Cu")
		(net "M_B_CPU0_SB_CB<4>")
	)
	(segment
		(start 301.220378 -271.70253)
		(end 300.840902 -271.323054)
		(width 0.14478)
		(layer "In13.Cu")
		(net "M_B_CPU0_SB_CB<4>")
	)
	(segment
		(start 302.07331 -271.237964)
		(end 302.33493 -271.237964)
		(width 0.14478)
		(layer "In13.Cu")
		(net "M_B_CPU0_SB_CB<4>")
	)
	(segment
		(start 304.53965 -271.237964)
		(end 304.68443 -271.093184)
		(width 0.14478)
		(layer "In13.Cu")
		(net "M_B_CPU0_SB_CB<4>")
	)
	(segment
		(start 305.78679 -271.093184)
		(end 305.78679 -270.895318)
		(width 0.14478)
		(layer "In13.Cu")
		(net "M_B_CPU0_SB_CB<4>")
	)
	(segment
		(start 305.09083 -270.750538)
		(end 305.23561 -270.895318)
		(width 0.14478)
		(layer "In13.Cu")
		(net "M_B_CPU0_SB_CB<4>")
	)
	(segment
		(start 302.62449 -270.750538)
		(end 302.88611 -270.750538)
		(width 0.14478)
		(layer "In13.Cu")
		(net "M_B_CPU0_SB_CB<4>")
	)
	(segment
		(start 306.74437 -271.237964)
		(end 306.88915 -271.093184)
		(width 0.14478)
		(layer "In13.Cu")
		(net "M_B_CPU0_SB_CB<4>")
	)
	(segment
		(start 309.255414 -269.624556)
		(end 309.255414 -268.899894)
		(width 0.14478)
		(layer "In13.Cu")
		(net "M_B_CPU0_SB_CB<4>")
	)
	(segment
		(start 305.64201 -271.237964)
		(end 305.78679 -271.093184)
		(width 0.14478)
		(layer "In13.Cu")
		(net "M_B_CPU0_SB_CB<4>")
	)
	(segment
		(start 306.19319 -270.750538)
		(end 306.33797 -270.895318)
		(width 0.14478)
		(layer "In13.Cu")
		(net "M_B_CPU0_SB_CB<4>")
	)
	(segment
		(start 302.88611 -270.750538)
		(end 303.03089 -270.895318)
		(width 0.14478)
		(layer "In13.Cu")
		(net "M_B_CPU0_SB_CB<4>")
	)
	(segment
		(start 303.43729 -271.237964)
		(end 303.58207 -271.093184)
		(width 0.14478)
		(layer "In13.Cu")
		(net "M_B_CPU0_SB_CB<4>")
	)
	(segment
		(start 305.23561 -270.895318)
		(end 305.23561 -271.093184)
		(width 0.14478)
		(layer "In13.Cu")
		(net "M_B_CPU0_SB_CB<4>")
	)
	(segment
		(start 305.78679 -270.895318)
		(end 305.93157 -270.750538)
		(width 0.14478)
		(layer "In13.Cu")
		(net "M_B_CPU0_SB_CB<4>")
	)
	(segment
		(start 301.208694 -270.750538)
		(end 301.78375 -270.750538)
		(width 0.14478)
		(layer "In13.Cu")
		(net "M_B_CPU0_SB_CB<4>")
	)
	(segment
		(start 300.246288 -271.712944)
		(end 300.451012 -271.712944)
		(width 0.14478)
		(layer "In13.Cu")
		(net "M_B_CPU0_SB_CB<4>")
	)
	(segment
		(start 329.284076 -269.54861)
		(end 329.292458 -269.553436)
		(width 0.0889)
		(layer "In13.Cu")
		(net "M_B_CPU0_SB_CB<4>")
	)
	(segment
		(start 335.8007 -269.51686)
		(end 335.896966 -269.49146)
		(width 0.0889)
		(layer "In13.Cu")
		(net "M_B_CPU0_SB_CB<4>")
	)
	(segment
		(start 304.82921 -270.750538)
		(end 305.09083 -270.750538)
		(width 0.14478)
		(layer "In13.Cu")
		(net "M_B_CPU0_SB_CB<4>")
	)
	(segment
		(start 304.68443 -270.895318)
		(end 304.82921 -270.750538)
		(width 0.14478)
		(layer "In13.Cu")
		(net "M_B_CPU0_SB_CB<4>")
	)
	(segment
		(start 325.995538 -269.098522)
		(end 326.386952 -269.489936)
		(width 0.0889)
		(layer "In13.Cu")
		(net "M_B_CPU0_SB_CB<4>")
	)
	(segment
		(start 327.766426 -269.555468)
		(end 327.77811 -269.54861)
		(width 0.0889)
		(layer "In13.Cu")
		(net "M_B_CPU0_SB_CB<4>")
	)
	(segment
		(start 306.88915 -271.093184)
		(end 306.88915 -270.895318)
		(width 0.14478)
		(layer "In13.Cu")
		(net "M_B_CPU0_SB_CB<4>")
	)
	(segment
		(start 304.13325 -271.093184)
		(end 304.27803 -271.237964)
		(width 0.14478)
		(layer "In13.Cu")
		(net "M_B_CPU0_SB_CB<4>")
	)
	(segment
		(start 325.995538 -268.162532)
		(end 325.995538 -269.098522)
		(width 0.0889)
		(layer "In13.Cu")
		(net "M_B_CPU0_SB_CB<4>")
	)
	(segment
		(start 305.93157 -270.750538)
		(end 306.19319 -270.750538)
		(width 0.14478)
		(layer "In13.Cu")
		(net "M_B_CPU0_SB_CB<4>")
	)
	(segment
		(start 308.129432 -270.750538)
		(end 309.255414 -269.624556)
		(width 0.14478)
		(layer "In13.Cu")
		(net "M_B_CPU0_SB_CB<4>")
	)
	(segment
		(start 303.03089 -271.093184)
		(end 303.17567 -271.237964)
		(width 0.14478)
		(layer "In13.Cu")
		(net "M_B_CPU0_SB_CB<4>")
	)
	(segment
		(start 304.13325 -270.895318)
		(end 304.13325 -271.093184)
		(width 0.14478)
		(layer "In13.Cu")
		(net "M_B_CPU0_SB_CB<4>")
	)
	(segment
		(start 303.72685 -270.750538)
		(end 303.98847 -270.750538)
		(width 0.14478)
		(layer "In13.Cu")
		(net "M_B_CPU0_SB_CB<4>")
	)
	(segment
		(start 326.819514 -269.55877)
		(end 326.837802 -269.548356)
		(width 0.0889)
		(layer "In13.Cu")
		(net "M_B_CPU0_SB_CB<4>")
	)
	(segment
		(start 323.909944 -267.59662)
		(end 325.429626 -267.59662)
		(width 0.0889)
		(layer "In13.Cu")
		(net "M_B_CPU0_SB_CB<4>")
	)
	(segment
		(start 310.563768 -267.59154)
		(end 323.904864 -267.59154)
		(width 0.14478)
		(layer "In13.Cu")
		(net "M_B_CPU0_SB_CB<4>")
	)
	(segment
		(start 304.68443 -271.093184)
		(end 304.68443 -270.895318)
		(width 0.14478)
		(layer "In13.Cu")
		(net "M_B_CPU0_SB_CB<4>")
	)
	(segment
		(start 301.78375 -270.750538)
		(end 301.92853 -270.895318)
		(width 0.14478)
		(layer "In13.Cu")
		(net "M_B_CPU0_SB_CB<4>")
	)
	(segment
		(start 306.88915 -270.895318)
		(end 307.03393 -270.750538)
		(width 0.14478)
		(layer "In13.Cu")
		(net "M_B_CPU0_SB_CB<4>")
	)
	(segment
		(start 302.33493 -271.237964)
		(end 302.47971 -271.093184)
		(width 0.14478)
		(layer "In13.Cu")
		(net "M_B_CPU0_SB_CB<4>")
	)
	(segment
		(start 326.837802 -269.548356)
		(end 326.85355 -269.539212)
		(width 0.0889)
		(layer "In13.Cu")
		(net "M_B_CPU0_SB_CB<4>")
	)
	(segment
		(start 305.38039 -271.237964)
		(end 305.64201 -271.237964)
		(width 0.14478)
		(layer "In13.Cu")
		(net "M_B_CPU0_SB_CB<4>")
	)
	(segment
		(start 306.33797 -271.093184)
		(end 306.48275 -271.237964)
		(width 0.14478)
		(layer "In13.Cu")
		(net "M_B_CPU0_SB_CB<4>")
	)
	(segment
		(start 335.896966 -269.49146)
		(end 336.051144 -269.22603)
		(width 0.0889)
		(layer "In13.Cu")
		(net "M_B_CPU0_SB_CB<4>")
	)
	(segment
		(start 301.92853 -271.093184)
		(end 302.07331 -271.237964)
		(width 0.14478)
		(layer "In13.Cu")
		(net "M_B_CPU0_SB_CB<4>")
	)
	(segment
		(start 306.33797 -270.895318)
		(end 306.33797 -271.093184)
		(width 0.14478)
		(layer "In13.Cu")
		(net "M_B_CPU0_SB_CB<4>")
	)
	(segment
		(start 305.23561 -271.093184)
		(end 305.38039 -271.237964)
		(width 0.14478)
		(layer "In13.Cu")
		(net "M_B_CPU0_SB_CB<4>")
	)
	(segment
		(start 331.52969 -269.553436)
		(end 331.538072 -269.54861)
		(width 0.0889)
		(layer "In13.Cu")
		(net "M_B_CPU0_SB_CB<4>")
	)
	(segment
		(start 304.27803 -271.237964)
		(end 304.53965 -271.237964)
		(width 0.14478)
		(layer "In13.Cu")
		(net "M_B_CPU0_SB_CB<4>")
	)
	(segment
		(start 301.92853 -270.895318)
		(end 301.92853 -271.093184)
		(width 0.14478)
		(layer "In13.Cu")
		(net "M_B_CPU0_SB_CB<4>")
	)
	(segment
		(start 328.709782 -269.553436)
		(end 328.718164 -269.54861)
		(width 0.0889)
		(layer "In13.Cu")
		(net "M_B_CPU0_SB_CB<4>")
	)
	(segment
		(start 326.463406 -269.54861)
		(end 326.46366 -269.54861)
		(width 0.0889)
		(layer "In13.Cu")
		(net "M_B_CPU0_SB_CB<4>")
	)
	(segment
		(start 302.47971 -270.895318)
		(end 302.62449 -270.750538)
		(width 0.14478)
		(layer "In13.Cu")
		(net "M_B_CPU0_SB_CB<4>")
	)
	(segment
		(start 323.904864 -267.59154)
		(end 323.909944 -267.59662)
		(width 0.14478)
		(layer "In13.Cu")
		(net "M_B_CPU0_SB_CB<4>")
	)
	(segment
		(start 303.17567 -271.237964)
		(end 303.43729 -271.237964)
		(width 0.14478)
		(layer "In13.Cu")
		(net "M_B_CPU0_SB_CB<4>")
	)
	(segment
		(start 302.47971 -271.093184)
		(end 302.47971 -270.895318)
		(width 0.14478)
		(layer "In13.Cu")
		(net "M_B_CPU0_SB_CB<4>")
	)
	(segment
		(start 303.98847 -270.750538)
		(end 304.13325 -270.895318)
		(width 0.14478)
		(layer "In13.Cu")
		(net "M_B_CPU0_SB_CB<4>")
	)
	(segment
		(start 332.469744 -269.553436)
		(end 332.478126 -269.54861)
		(width 0.0889)
		(layer "In13.Cu")
		(net "M_B_CPU0_SB_CB<4>")
	)
	(segment
		(start 309.255414 -268.899894)
		(end 310.563768 -267.59154)
		(width 0.14478)
		(layer "In13.Cu")
		(net "M_B_CPU0_SB_CB<4>")
	)
	(segment
		(start 325.429626 -267.59662)
		(end 325.995538 -268.162532)
		(width 0.0889)
		(layer "In13.Cu")
		(net "M_B_CPU0_SB_CB<4>")
	)
	(segment
		(start 300.830488 -272.09242)
		(end 301.035212 -272.09242)
		(width 0.14478)
		(layer "In13.Cu")
		(net "M_B_CPU0_SB_CB<4>")
	)
	(segment
		(start 333.984092 -269.54861)
		(end 333.992474 -269.553436)
		(width 0.0889)
		(layer "In13.Cu")
		(net "M_B_CPU0_SB_CB<4>")
	)
	(segment
		(start 307.03393 -270.750538)
		(end 308.129432 -270.750538)
		(width 0.14478)
		(layer "In13.Cu")
		(net "M_B_CPU0_SB_CB<4>")
	)
	(segment
		(start 303.03089 -270.895318)
		(end 303.03089 -271.093184)
		(width 0.14478)
		(layer "In13.Cu")
		(net "M_B_CPU0_SB_CB<4>")
	)
	(segment
		(start 301.220378 -271.907254)
		(end 301.220378 -271.70253)
		(width 0.14478)
		(layer "In13.Cu")
		(net "M_B_CPU0_SB_CB<4>")
	)
	(segment
		(start 301.035212 -272.09242)
		(end 301.220378 -271.907254)
		(width 0.14478)
		(layer "In13.Cu")
		(net "M_B_CPU0_SB_CB<4>")
	)
	(segment
		(start 333.044038 -269.54861)
		(end 333.05242 -269.553436)
		(width 0.0889)
		(layer "In13.Cu")
		(net "M_B_CPU0_SB_CB<4>")
	)
	(segment
		(start 300.840902 -271.11833)
		(end 301.208694 -270.750538)
		(width 0.14478)
		(layer "In13.Cu")
		(net "M_B_CPU0_SB_CB<4>")
	)
	(segment
		(start 300.840902 -271.323054)
		(end 300.840902 -271.11833)
		(width 0.14478)
		(layer "In13.Cu")
		(net "M_B_CPU0_SB_CB<4>")
	)
	(segment
		(start 303.58207 -271.093184)
		(end 303.58207 -270.895318)
		(width 0.14478)
		(layer "In13.Cu")
		(net "M_B_CPU0_SB_CB<4>")
	)
	(arc
		(start 332.478126 -269.54861)
		(mid 332.761082 -269.472433)
		(end 333.044038 -269.54861)
		(width 0.0889)
		(layer "In13.Cu")
		(net "M_B_CPU0_SB_CB<4>")
	)
	(arc
		(start 332.103984 -269.54861)
		(mid 332.286235 -269.59896)
		(end 332.469744 -269.553436)
		(width 0.0889)
		(layer "In13.Cu")
		(net "M_B_CPU0_SB_CB<4>")
	)
	(arc
		(start 326.386952 -269.489936)
		(mid 326.423279 -269.521749)
		(end 326.463406 -269.54861)
		(width 0.0889)
		(layer "In13.Cu")
		(net "M_B_CPU0_SB_CB<4>")
	)
	(arc
		(start 331.16393 -269.54861)
		(mid 331.346181 -269.59896)
		(end 331.52969 -269.553436)
		(width 0.0889)
		(layer "In13.Cu")
		(net "M_B_CPU0_SB_CB<4>")
	)
	(arc
		(start 333.41818 -269.54861)
		(mid 333.701136 -269.472433)
		(end 333.984092 -269.54861)
		(width 0.0889)
		(layer "In13.Cu")
		(net "M_B_CPU0_SB_CB<4>")
	)
	(arc
		(start 326.46366 -269.54861)
		(mid 326.640288 -269.598843)
		(end 326.819514 -269.55877)
		(width 0.0889)
		(layer "In13.Cu")
		(net "M_B_CPU0_SB_CB<4>")
	)
	(arc
		(start 329.658218 -269.54861)
		(mid 329.941174 -269.472433)
		(end 330.22413 -269.54861)
		(width 0.0889)
		(layer "In13.Cu")
		(net "M_B_CPU0_SB_CB<4>")
	)
	(arc
		(start 331.538072 -269.54861)
		(mid 331.821028 -269.472433)
		(end 332.103984 -269.54861)
		(width 0.0889)
		(layer "In13.Cu")
		(net "M_B_CPU0_SB_CB<4>")
	)
	(arc
		(start 330.598018 -269.54861)
		(mid 330.880974 -269.472433)
		(end 331.16393 -269.54861)
		(width 0.0889)
		(layer "In13.Cu")
		(net "M_B_CPU0_SB_CB<4>")
	)
	(arc
		(start 328.344022 -269.54861)
		(mid 328.526273 -269.59896)
		(end 328.709782 -269.553436)
		(width 0.0889)
		(layer "In13.Cu")
		(net "M_B_CPU0_SB_CB<4>")
	)
	(arc
		(start 334.358234 -269.54861)
		(mid 334.64119 -269.472433)
		(end 334.924146 -269.54861)
		(width 0.0889)
		(layer "In13.Cu")
		(net "M_B_CPU0_SB_CB<4>")
	)
	(arc
		(start 326.85355 -269.539212)
		(mid 327.129859 -269.472236)
		(end 327.403714 -269.54861)
		(width 0.0889)
		(layer "In13.Cu")
		(net "M_B_CPU0_SB_CB<4>")
	)
	(arc
		(start 329.292458 -269.553436)
		(mid 329.475966 -269.59893)
		(end 329.658218 -269.54861)
		(width 0.0889)
		(layer "In13.Cu")
		(net "M_B_CPU0_SB_CB<4>")
	)
	(arc
		(start 328.718164 -269.54861)
		(mid 329.00112 -269.472433)
		(end 329.284076 -269.54861)
		(width 0.0889)
		(layer "In13.Cu")
		(net "M_B_CPU0_SB_CB<4>")
	)
	(arc
		(start 330.22413 -269.54861)
		(mid 330.411074 -269.598865)
		(end 330.598018 -269.54861)
		(width 0.0889)
		(layer "In13.Cu")
		(net "M_B_CPU0_SB_CB<4>")
	)
	(arc
		(start 335.298034 -269.54861)
		(mid 335.54563 -269.473432)
		(end 335.8007 -269.51686)
		(width 0.0889)
		(layer "In13.Cu")
		(net "M_B_CPU0_SB_CB<4>")
	)
	(arc
		(start 327.77811 -269.54861)
		(mid 328.061066 -269.472433)
		(end 328.344022 -269.54861)
		(width 0.0889)
		(layer "In13.Cu")
		(net "M_B_CPU0_SB_CB<4>")
	)
	(arc
		(start 333.992474 -269.553436)
		(mid 334.175982 -269.59893)
		(end 334.358234 -269.54861)
		(width 0.0889)
		(layer "In13.Cu")
		(net "M_B_CPU0_SB_CB<4>")
	)
	(arc
		(start 327.403714 -269.54861)
		(mid 327.584172 -269.599054)
		(end 327.766426 -269.555468)
		(width 0.0889)
		(layer "In13.Cu")
		(net "M_B_CPU0_SB_CB<4>")
	)
	(arc
		(start 333.05242 -269.553436)
		(mid 333.235928 -269.59893)
		(end 333.41818 -269.54861)
		(width 0.0889)
		(layer "In13.Cu")
		(net "M_B_CPU0_SB_CB<4>")
	)
	(arc
		(start 334.924146 -269.54861)
		(mid 335.11109 -269.598865)
		(end 335.298034 -269.54861)
		(width 0.0889)
		(layer "In13.Cu")
		(net "M_B_CPU0_SB_CB<4>")
	)
	(segment
		(start 337.45805 -273.820128)
		(end 336.991198 -274.086066)
		(width 0.10668)
		(layer "F.Cu")
		(net "M_B_CPU0_SB_CB<3>")
	)
	(segment
		(start 299.636942 -280.210006)
		(end 300.192948 -280.210006)
		(width 0.14478)
		(layer "In13.Cu")
		(net "M_B_CPU0_SB_CB<3>")
	)
	(segment
		(start 306.744116 -280.209498)
		(end 307.160422 -280.126694)
		(width 0.14478)
		(layer "In13.Cu")
		(net "M_B_CPU0_SB_CB<3>")
	)
	(segment
		(start 326.837802 -273.76374)
		(end 326.84339 -273.767042)
		(width 0.0889)
		(layer "In13.Cu")
		(net "M_B_CPU0_SB_CB<3>")
	)
	(segment
		(start 300.192948 -280.210006)
		(end 301.29099 -280.664666)
		(width 0.14478)
		(layer "In13.Cu")
		(net "M_B_CPU0_SB_CB<3>")
	)
	(segment
		(start 336.229706 -273.75866)
		(end 336.238088 -273.763486)
		(width 0.0889)
		(layer "In13.Cu")
		(net "M_B_CPU0_SB_CB<3>")
	)
	(segment
		(start 324.331584 -272.66392)
		(end 324.53961 -272.66392)
		(width 0.0889)
		(layer "In13.Cu")
		(net "M_B_CPU0_SB_CB<3>")
	)
	(segment
		(start 315.035946 -272.66392)
		(end 324.331584 -272.66392)
		(width 0.14478)
		(layer "In13.Cu")
		(net "M_B_CPU0_SB_CB<3>")
	)
	(segment
		(start 307.160422 -280.126694)
		(end 307.865272 -279.834594)
		(width 0.14478)
		(layer "In13.Cu")
		(net "M_B_CPU0_SB_CB<3>")
	)
	(segment
		(start 333.984092 -273.763486)
		(end 333.992474 -273.75866)
		(width 0.0889)
		(layer "In13.Cu")
		(net "M_B_CPU0_SB_CB<3>")
	)
	(segment
		(start 327.403206 -273.763486)
		(end 327.41489 -273.756628)
		(width 0.0889)
		(layer "In13.Cu")
		(net "M_B_CPU0_SB_CB<3>")
	)
	(segment
		(start 337.12277 -273.737324)
		(end 337.145122 -273.820636)
		(width 0.0889)
		(layer "In13.Cu")
		(net "M_B_CPU0_SB_CB<3>")
	)
	(segment
		(start 324.672198 -272.531332)
		(end 325.147178 -272.531332)
		(width 0.0889)
		(layer "In13.Cu")
		(net "M_B_CPU0_SB_CB<3>")
	)
	(segment
		(start 331.52969 -273.75866)
		(end 331.538072 -273.763486)
		(width 0.0889)
		(layer "In13.Cu")
		(net "M_B_CPU0_SB_CB<3>")
	)
	(segment
		(start 332.469744 -273.75866)
		(end 332.478126 -273.763486)
		(width 0.0889)
		(layer "In13.Cu")
		(net "M_B_CPU0_SB_CB<3>")
	)
	(segment
		(start 333.044038 -273.763486)
		(end 333.05242 -273.75866)
		(width 0.0889)
		(layer "In13.Cu")
		(net "M_B_CPU0_SB_CB<3>")
	)
	(segment
		(start 324.53961 -272.66392)
		(end 324.672198 -272.531332)
		(width 0.0889)
		(layer "In13.Cu")
		(net "M_B_CPU0_SB_CB<3>")
	)
	(segment
		(start 326.328786 -273.71294)
		(end 326.651112 -273.71294)
		(width 0.0889)
		(layer "In13.Cu")
		(net "M_B_CPU0_SB_CB<3>")
	)
	(segment
		(start 328.32929 -273.772122)
		(end 328.344022 -273.763486)
		(width 0.0889)
		(layer "In13.Cu")
		(net "M_B_CPU0_SB_CB<3>")
	)
	(segment
		(start 301.29099 -280.664666)
		(end 305.093116 -280.664666)
		(width 0.14478)
		(layer "In13.Cu")
		(net "M_B_CPU0_SB_CB<3>")
	)
	(segment
		(start 307.865272 -279.834594)
		(end 315.035946 -272.66392)
		(width 0.14478)
		(layer "In13.Cu")
		(net "M_B_CPU0_SB_CB<3>")
	)
	(segment
		(start 305.529742 -280.577798)
		(end 306.116228 -280.334974)
		(width 0.14478)
		(layer "In13.Cu")
		(net "M_B_CPU0_SB_CB<3>")
	)
	(segment
		(start 306.116228 -280.334974)
		(end 306.743862 -280.210006)
		(width 0.14478)
		(layer "In13.Cu")
		(net "M_B_CPU0_SB_CB<3>")
	)
	(segment
		(start 295.724072 -280.634948)
		(end 299.636942 -280.210006)
		(width 0.14478)
		(layer "In13.Cu")
		(net "M_B_CPU0_SB_CB<3>")
	)
	(segment
		(start 305.093116 -280.664666)
		(end 305.529742 -280.577798)
		(width 0.14478)
		(layer "In13.Cu")
		(net "M_B_CPU0_SB_CB<3>")
	)
	(segment
		(start 306.743862 -280.210006)
		(end 306.744116 -280.209498)
		(width 0.14478)
		(layer "In13.Cu")
		(net "M_B_CPU0_SB_CB<3>")
	)
	(segment
		(start 337.145122 -273.820636)
		(end 336.991198 -274.086066)
		(width 0.0889)
		(layer "In13.Cu")
		(net "M_B_CPU0_SB_CB<3>")
	)
	(segment
		(start 328.709782 -273.75866)
		(end 328.718164 -273.763486)
		(width 0.0889)
		(layer "In13.Cu")
		(net "M_B_CPU0_SB_CB<3>")
	)
	(segment
		(start 329.284076 -273.763486)
		(end 329.292458 -273.75866)
		(width 0.0889)
		(layer "In13.Cu")
		(net "M_B_CPU0_SB_CB<3>")
	)
	(segment
		(start 325.147178 -272.531332)
		(end 326.328786 -273.71294)
		(width 0.0889)
		(layer "In13.Cu")
		(net "M_B_CPU0_SB_CB<3>")
	)
	(arc
		(start 326.651112 -273.71294)
		(mid 326.747803 -273.726036)
		(end 326.837802 -273.76374)
		(width 0.0889)
		(layer "In13.Cu")
		(net "M_B_CPU0_SB_CB<3>")
	)
	(arc
		(start 335.863946 -273.763486)
		(mid 336.046197 -273.713136)
		(end 336.229706 -273.75866)
		(width 0.0889)
		(layer "In13.Cu")
		(net "M_B_CPU0_SB_CB<3>")
	)
	(arc
		(start 334.924146 -273.763486)
		(mid 335.11109 -273.713231)
		(end 335.298034 -273.763486)
		(width 0.0889)
		(layer "In13.Cu")
		(net "M_B_CPU0_SB_CB<3>")
	)
	(arc
		(start 329.658218 -273.763486)
		(mid 329.941174 -273.839663)
		(end 330.22413 -273.763486)
		(width 0.0889)
		(layer "In13.Cu")
		(net "M_B_CPU0_SB_CB<3>")
	)
	(arc
		(start 329.292458 -273.75866)
		(mid 329.475966 -273.713166)
		(end 329.658218 -273.763486)
		(width 0.0889)
		(layer "In13.Cu")
		(net "M_B_CPU0_SB_CB<3>")
	)
	(arc
		(start 332.478126 -273.763486)
		(mid 332.761082 -273.839663)
		(end 333.044038 -273.763486)
		(width 0.0889)
		(layer "In13.Cu")
		(net "M_B_CPU0_SB_CB<3>")
	)
	(arc
		(start 326.84339 -273.767042)
		(mid 327.123779 -273.839711)
		(end 327.403206 -273.763486)
		(width 0.0889)
		(layer "In13.Cu")
		(net "M_B_CPU0_SB_CB<3>")
	)
	(arc
		(start 328.344022 -273.763486)
		(mid 328.526273 -273.713136)
		(end 328.709782 -273.75866)
		(width 0.0889)
		(layer "In13.Cu")
		(net "M_B_CPU0_SB_CB<3>")
	)
	(arc
		(start 327.777602 -273.763486)
		(mid 328.052308 -273.83985)
		(end 328.32929 -273.772122)
		(width 0.0889)
		(layer "In13.Cu")
		(net "M_B_CPU0_SB_CB<3>")
	)
	(arc
		(start 334.358234 -273.763486)
		(mid 334.64119 -273.839663)
		(end 334.924146 -273.763486)
		(width 0.0889)
		(layer "In13.Cu")
		(net "M_B_CPU0_SB_CB<3>")
	)
	(arc
		(start 336.804 -273.763486)
		(mid 336.960438 -273.714515)
		(end 337.12277 -273.737324)
		(width 0.0889)
		(layer "In13.Cu")
		(net "M_B_CPU0_SB_CB<3>")
	)
	(arc
		(start 336.238088 -273.763486)
		(mid 336.521044 -273.839663)
		(end 336.804 -273.763486)
		(width 0.0889)
		(layer "In13.Cu")
		(net "M_B_CPU0_SB_CB<3>")
	)
	(arc
		(start 333.41818 -273.763486)
		(mid 333.701136 -273.839663)
		(end 333.984092 -273.763486)
		(width 0.0889)
		(layer "In13.Cu")
		(net "M_B_CPU0_SB_CB<3>")
	)
	(arc
		(start 328.718164 -273.763486)
		(mid 329.00112 -273.839663)
		(end 329.284076 -273.763486)
		(width 0.0889)
		(layer "In13.Cu")
		(net "M_B_CPU0_SB_CB<3>")
	)
	(arc
		(start 327.41489 -273.756628)
		(mid 327.597145 -273.712975)
		(end 327.777602 -273.763486)
		(width 0.0889)
		(layer "In13.Cu")
		(net "M_B_CPU0_SB_CB<3>")
	)
	(arc
		(start 331.16393 -273.763486)
		(mid 331.346181 -273.713136)
		(end 331.52969 -273.75866)
		(width 0.0889)
		(layer "In13.Cu")
		(net "M_B_CPU0_SB_CB<3>")
	)
	(arc
		(start 330.22413 -273.763486)
		(mid 330.411074 -273.713231)
		(end 330.598018 -273.763486)
		(width 0.0889)
		(layer "In13.Cu")
		(net "M_B_CPU0_SB_CB<3>")
	)
	(arc
		(start 331.538072 -273.763486)
		(mid 331.821028 -273.839663)
		(end 332.103984 -273.763486)
		(width 0.0889)
		(layer "In13.Cu")
		(net "M_B_CPU0_SB_CB<3>")
	)
	(arc
		(start 333.05242 -273.75866)
		(mid 333.235928 -273.713166)
		(end 333.41818 -273.763486)
		(width 0.0889)
		(layer "In13.Cu")
		(net "M_B_CPU0_SB_CB<3>")
	)
	(arc
		(start 332.103984 -273.763486)
		(mid 332.286235 -273.713136)
		(end 332.469744 -273.75866)
		(width 0.0889)
		(layer "In13.Cu")
		(net "M_B_CPU0_SB_CB<3>")
	)
	(arc
		(start 330.598018 -273.763486)
		(mid 330.880974 -273.839663)
		(end 331.16393 -273.763486)
		(width 0.0889)
		(layer "In13.Cu")
		(net "M_B_CPU0_SB_CB<3>")
	)
	(arc
		(start 335.298034 -273.763486)
		(mid 335.58099 -273.839663)
		(end 335.863946 -273.763486)
		(width 0.0889)
		(layer "In13.Cu")
		(net "M_B_CPU0_SB_CB<3>")
	)
	(arc
		(start 333.992474 -273.75866)
		(mid 334.175982 -273.713166)
		(end 334.358234 -273.763486)
		(width 0.0889)
		(layer "In13.Cu")
		(net "M_B_CPU0_SB_CB<3>")
	)
	(segment
		(start 336.047842 -273.010122)
		(end 335.58099 -273.27606)
		(width 0.10668)
		(layer "F.Cu")
		(net "M_B_CPU0_SB_CB<2>")
	)
	(segment
		(start 330.702412 -272.948654)
		(end 330.69403 -272.95348)
		(width 0.0889)
		(layer "In13.Cu")
		(net "M_B_CPU0_SB_CB<2>")
	)
	(segment
		(start 305.350926 -279.28951)
		(end 301.162466 -279.28951)
		(width 0.14478)
		(layer "In13.Cu")
		(net "M_B_CPU0_SB_CB<2>")
	)
	(segment
		(start 298.74718 -278.509984)
		(end 298.321984 -278.93518)
		(width 0.14478)
		(layer "In13.Cu")
		(net "M_B_CPU0_SB_CB<2>")
	)
	(segment
		(start 326.252332 -272.864834)
		(end 325.40829 -272.020792)
		(width 0.0889)
		(layer "In13.Cu")
		(net "M_B_CPU0_SB_CB<2>")
	)
	(segment
		(start 326.93356 -272.953734)
		(end 326.917812 -272.962878)
		(width 0.0889)
		(layer "In13.Cu")
		(net "M_B_CPU0_SB_CB<2>")
	)
	(segment
		(start 307.617114 -278.509984)
		(end 306.130452 -278.509984)
		(width 0.14478)
		(layer "In13.Cu")
		(net "M_B_CPU0_SB_CB<2>")
	)
	(segment
		(start 314.372498 -271.7546)
		(end 307.617114 -278.509984)
		(width 0.14478)
		(layer "In13.Cu")
		(net "M_B_CPU0_SB_CB<2>")
	)
	(segment
		(start 331.642466 -272.948654)
		(end 331.634084 -272.95348)
		(width 0.0889)
		(layer "In13.Cu")
		(net "M_B_CPU0_SB_CB<2>")
	)
	(segment
		(start 306.130452 -278.509984)
		(end 305.350926 -279.28951)
		(width 0.14478)
		(layer "In13.Cu")
		(net "M_B_CPU0_SB_CB<2>")
	)
	(segment
		(start 326.949816 -272.944336)
		(end 326.93356 -272.953734)
		(width 0.0889)
		(layer "In13.Cu")
		(net "M_B_CPU0_SB_CB<2>")
	)
	(segment
		(start 335.402428 -272.948654)
		(end 335.394046 -272.95348)
		(width 0.0889)
		(layer "In13.Cu")
		(net "M_B_CPU0_SB_CB<2>")
	)
	(segment
		(start 300.38294 -278.509984)
		(end 298.74718 -278.509984)
		(width 0.14478)
		(layer "In13.Cu")
		(net "M_B_CPU0_SB_CB<2>")
	)
	(segment
		(start 323.901054 -271.7546)
		(end 314.372498 -271.7546)
		(width 0.14478)
		(layer "In13.Cu")
		(net "M_B_CPU0_SB_CB<2>")
	)
	(segment
		(start 333.88808 -272.95348)
		(end 333.879698 -272.948654)
		(width 0.0889)
		(layer "In13.Cu")
		(net "M_B_CPU0_SB_CB<2>")
	)
	(segment
		(start 333.888334 -272.95348)
		(end 333.88808 -272.95348)
		(width 0.0889)
		(layer "In13.Cu")
		(net "M_B_CPU0_SB_CB<2>")
	)
	(segment
		(start 335.735168 -273.01063)
		(end 335.712816 -272.927318)
		(width 0.0889)
		(layer "In13.Cu")
		(net "M_B_CPU0_SB_CB<2>")
	)
	(segment
		(start 335.58099 -273.27606)
		(end 335.735168 -273.01063)
		(width 0.0889)
		(layer "In13.Cu")
		(net "M_B_CPU0_SB_CB<2>")
	)
	(segment
		(start 298.321984 -278.93518)
		(end 295.724072 -278.93518)
		(width 0.14478)
		(layer "In13.Cu")
		(net "M_B_CPU0_SB_CB<2>")
	)
	(segment
		(start 301.162466 -279.28951)
		(end 300.38294 -278.509984)
		(width 0.14478)
		(layer "In13.Cu")
		(net "M_B_CPU0_SB_CB<2>")
	)
	(segment
		(start 327.317862 -272.959576)
		(end 327.307448 -272.95348)
		(width 0.0889)
		(layer "In13.Cu")
		(net "M_B_CPU0_SB_CB<2>")
	)
	(segment
		(start 334.828134 -272.95348)
		(end 334.819752 -272.948654)
		(width 0.0889)
		(layer "In13.Cu")
		(net "M_B_CPU0_SB_CB<2>")
	)
	(segment
		(start 330.128118 -272.95348)
		(end 330.119736 -272.948654)
		(width 0.0889)
		(layer "In13.Cu")
		(net "M_B_CPU0_SB_CB<2>")
	)
	(segment
		(start 324.707758 -272.020792)
		(end 324.441566 -271.7546)
		(width 0.0889)
		(layer "In13.Cu")
		(net "M_B_CPU0_SB_CB<2>")
	)
	(segment
		(start 324.441566 -271.7546)
		(end 323.901054 -271.7546)
		(width 0.0889)
		(layer "In13.Cu")
		(net "M_B_CPU0_SB_CB<2>")
	)
	(segment
		(start 328.248264 -272.95348)
		(end 328.239882 -272.948654)
		(width 0.0889)
		(layer "In13.Cu")
		(net "M_B_CPU0_SB_CB<2>")
	)
	(segment
		(start 325.40829 -272.020792)
		(end 324.707758 -272.020792)
		(width 0.0889)
		(layer "In13.Cu")
		(net "M_B_CPU0_SB_CB<2>")
	)
	(arc
		(start 328.814176 -272.95348)
		(mid 328.53122 -273.029657)
		(end 328.248264 -272.95348)
		(width 0.0889)
		(layer "In13.Cu")
		(net "M_B_CPU0_SB_CB<2>")
	)
	(arc
		(start 329.188064 -272.95348)
		(mid 329.00112 -272.903225)
		(end 328.814176 -272.95348)
		(width 0.0889)
		(layer "In13.Cu")
		(net "M_B_CPU0_SB_CB<2>")
	)
	(arc
		(start 328.239882 -272.948654)
		(mid 328.05612 -272.903038)
		(end 327.873614 -272.95348)
		(width 0.0889)
		(layer "In13.Cu")
		(net "M_B_CPU0_SB_CB<2>")
	)
	(arc
		(start 334.453992 -272.95348)
		(mid 334.17118 -273.029529)
		(end 333.888334 -272.95348)
		(width 0.0889)
		(layer "In13.Cu")
		(net "M_B_CPU0_SB_CB<2>")
	)
	(arc
		(start 335.394046 -272.95348)
		(mid 335.11109 -273.029657)
		(end 334.828134 -272.95348)
		(width 0.0889)
		(layer "In13.Cu")
		(net "M_B_CPU0_SB_CB<2>")
	)
	(arc
		(start 332.948026 -272.95348)
		(mid 332.761082 -272.903225)
		(end 332.574138 -272.95348)
		(width 0.0889)
		(layer "In13.Cu")
		(net "M_B_CPU0_SB_CB<2>")
	)
	(arc
		(start 329.753976 -272.95348)
		(mid 329.47102 -273.029657)
		(end 329.188064 -272.95348)
		(width 0.0889)
		(layer "In13.Cu")
		(net "M_B_CPU0_SB_CB<2>")
	)
	(arc
		(start 332.574138 -272.95348)
		(mid 332.291182 -273.029657)
		(end 332.008226 -272.95348)
		(width 0.0889)
		(layer "In13.Cu")
		(net "M_B_CPU0_SB_CB<2>")
	)
	(arc
		(start 335.712816 -272.927318)
		(mid 335.555306 -272.90412)
		(end 335.402428 -272.948654)
		(width 0.0889)
		(layer "In13.Cu")
		(net "M_B_CPU0_SB_CB<2>")
	)
	(arc
		(start 326.917812 -272.962878)
		(mid 326.641503 -273.029854)
		(end 326.367648 -272.95348)
		(width 0.0889)
		(layer "In13.Cu")
		(net "M_B_CPU0_SB_CB<2>")
	)
	(arc
		(start 330.119736 -272.948654)
		(mid 329.936228 -272.90316)
		(end 329.753976 -272.95348)
		(width 0.0889)
		(layer "In13.Cu")
		(net "M_B_CPU0_SB_CB<2>")
	)
	(arc
		(start 330.69403 -272.95348)
		(mid 330.411074 -273.029657)
		(end 330.128118 -272.95348)
		(width 0.0889)
		(layer "In13.Cu")
		(net "M_B_CPU0_SB_CB<2>")
	)
	(arc
		(start 333.879698 -272.948654)
		(mid 333.69619 -272.90316)
		(end 333.513938 -272.95348)
		(width 0.0889)
		(layer "In13.Cu")
		(net "M_B_CPU0_SB_CB<2>")
	)
	(arc
		(start 334.819752 -272.948654)
		(mid 334.636244 -272.90316)
		(end 334.453992 -272.95348)
		(width 0.0889)
		(layer "In13.Cu")
		(net "M_B_CPU0_SB_CB<2>")
	)
	(arc
		(start 332.008226 -272.95348)
		(mid 331.825975 -272.90313)
		(end 331.642466 -272.948654)
		(width 0.0889)
		(layer "In13.Cu")
		(net "M_B_CPU0_SB_CB<2>")
	)
	(arc
		(start 326.367648 -272.95348)
		(mid 326.307124 -272.912886)
		(end 326.252332 -272.864834)
		(width 0.0889)
		(layer "In13.Cu")
		(net "M_B_CPU0_SB_CB<2>")
	)
	(arc
		(start 331.634084 -272.95348)
		(mid 331.351128 -273.029657)
		(end 331.068172 -272.95348)
		(width 0.0889)
		(layer "In13.Cu")
		(net "M_B_CPU0_SB_CB<2>")
	)
	(arc
		(start 331.068172 -272.95348)
		(mid 330.885921 -272.90313)
		(end 330.702412 -272.948654)
		(width 0.0889)
		(layer "In13.Cu")
		(net "M_B_CPU0_SB_CB<2>")
	)
	(arc
		(start 327.307448 -272.95348)
		(mid 327.129798 -272.90322)
		(end 326.949816 -272.944336)
		(width 0.0889)
		(layer "In13.Cu")
		(net "M_B_CPU0_SB_CB<2>")
	)
	(arc
		(start 333.513938 -272.95348)
		(mid 333.230982 -273.029657)
		(end 332.948026 -272.95348)
		(width 0.0889)
		(layer "In13.Cu")
		(net "M_B_CPU0_SB_CB<2>")
	)
	(arc
		(start 327.873614 -272.95348)
		(mid 327.596547 -273.029751)
		(end 327.317862 -272.959576)
		(width 0.0889)
		(layer "In13.Cu")
		(net "M_B_CPU0_SB_CB<2>")
	)
	(segment
		(start 337.92795 -273.010122)
		(end 337.461098 -273.27606)
		(width 0.10668)
		(layer "F.Cu")
		(net "M_B_CPU0_SB_CB<1>")
	)
	(segment
		(start 300.596808 -279.359868)
		(end 301.446946 -280.210006)
		(width 0.14478)
		(layer "In13.Cu")
		(net "M_B_CPU0_SB_CB<1>")
	)
	(segment
		(start 331.634084 -273.59864)
		(end 331.642466 -273.603466)
		(width 0.0889)
		(layer "In13.Cu")
		(net "M_B_CPU0_SB_CB<1>")
	)
	(segment
		(start 336.3341 -273.59864)
		(end 336.342482 -273.603466)
		(width 0.0889)
		(layer "In13.Cu")
		(net "M_B_CPU0_SB_CB<1>")
	)
	(segment
		(start 310.916828 -276.147022)
		(end 311.15635 -275.9075)
		(width 0.14478)
		(layer "In13.Cu")
		(net "M_B_CPU0_SB_CB<1>")
	)
	(segment
		(start 311.395872 -275.367242)
		(end 311.696608 -275.367242)
		(width 0.14478)
		(layer "In13.Cu")
		(net "M_B_CPU0_SB_CB<1>")
	)
	(segment
		(start 314.85459 -272.20926)
		(end 323.901054 -272.20926)
		(width 0.14478)
		(layer "In13.Cu")
		(net "M_B_CPU0_SB_CB<1>")
	)
	(segment
		(start 308.276752 -278.486362)
		(end 308.577488 -278.486362)
		(width 0.14478)
		(layer "In13.Cu")
		(net "M_B_CPU0_SB_CB<1>")
	)
	(segment
		(start 311.93613 -274.826984)
		(end 312.175652 -274.587462)
		(width 0.14478)
		(layer "In13.Cu")
		(net "M_B_CPU0_SB_CB<1>")
	)
	(segment
		(start 309.59679 -277.166324)
		(end 309.836312 -276.926802)
		(width 0.14478)
		(layer "In13.Cu")
		(net "M_B_CPU0_SB_CB<1>")
	)
	(segment
		(start 330.69403 -273.59864)
		(end 330.702412 -273.603466)
		(width 0.0889)
		(layer "In13.Cu")
		(net "M_B_CPU0_SB_CB<1>")
	)
	(segment
		(start 337.307174 -273.54149)
		(end 337.461098 -273.27606)
		(width 0.0889)
		(layer "In13.Cu")
		(net "M_B_CPU0_SB_CB<1>")
	)
	(segment
		(start 307.651912 -279.411938)
		(end 308.03723 -279.02662)
		(width 0.14478)
		(layer "In13.Cu")
		(net "M_B_CPU0_SB_CB<1>")
	)
	(segment
		(start 337.211162 -273.56689)
		(end 337.307174 -273.54149)
		(width 0.0889)
		(layer "In13.Cu")
		(net "M_B_CPU0_SB_CB<1>")
	)
	(segment
		(start 310.37657 -276.68728)
		(end 310.37657 -276.386544)
		(width 0.14478)
		(layer "In13.Cu")
		(net "M_B_CPU0_SB_CB<1>")
	)
	(segment
		(start 310.137048 -276.926802)
		(end 310.37657 -276.68728)
		(width 0.14478)
		(layer "In13.Cu")
		(net "M_B_CPU0_SB_CB<1>")
	)
	(segment
		(start 307.09997 -279.411938)
		(end 307.651912 -279.411938)
		(width 0.14478)
		(layer "In13.Cu")
		(net "M_B_CPU0_SB_CB<1>")
	)
	(segment
		(start 326.40778 -273.52244)
		(end 326.65162 -273.52244)
		(width 0.0889)
		(layer "In13.Cu")
		(net "M_B_CPU0_SB_CB<1>")
	)
	(segment
		(start 335.394046 -273.59864)
		(end 335.402428 -273.603466)
		(width 0.0889)
		(layer "In13.Cu")
		(net "M_B_CPU0_SB_CB<1>")
	)
	(segment
		(start 305.923696 -279.359868)
		(end 306.147724 -279.359868)
		(width 0.14478)
		(layer "In13.Cu")
		(net "M_B_CPU0_SB_CB<1>")
	)
	(segment
		(start 312.955432 -273.807682)
		(end 313.256168 -273.807682)
		(width 0.14478)
		(layer "In13.Cu")
		(net "M_B_CPU0_SB_CB<1>")
	)
	(segment
		(start 304.767996 -280.210006)
		(end 305.073558 -280.210006)
		(width 0.14478)
		(layer "In13.Cu")
		(net "M_B_CPU0_SB_CB<1>")
	)
	(segment
		(start 312.71591 -274.34794)
		(end 312.71591 -274.047204)
		(width 0.14478)
		(layer "In13.Cu")
		(net "M_B_CPU0_SB_CB<1>")
	)
	(segment
		(start 311.696608 -275.367242)
		(end 311.93613 -275.12772)
		(width 0.14478)
		(layer "In13.Cu")
		(net "M_B_CPU0_SB_CB<1>")
	)
	(segment
		(start 327.307194 -273.59864)
		(end 327.321926 -273.590004)
		(width 0.0889)
		(layer "In13.Cu")
		(net "M_B_CPU0_SB_CB<1>")
	)
	(segment
		(start 308.81701 -277.946104)
		(end 309.056532 -277.706582)
		(width 0.14478)
		(layer "In13.Cu")
		(net "M_B_CPU0_SB_CB<1>")
	)
	(segment
		(start 334.819752 -273.603466)
		(end 334.828134 -273.59864)
		(width 0.0889)
		(layer "In13.Cu")
		(net "M_B_CPU0_SB_CB<1>")
	)
	(segment
		(start 301.927768 -280.210006)
		(end 302.230282 -279.907492)
		(width 0.14478)
		(layer "In13.Cu")
		(net "M_B_CPU0_SB_CB<1>")
	)
	(segment
		(start 304.216562 -279.927812)
		(end 304.485802 -279.927812)
		(width 0.14478)
		(layer "In13.Cu")
		(net "M_B_CPU0_SB_CB<1>")
	)
	(segment
		(start 324.466458 -272.277332)
		(end 325.162672 -272.277332)
		(width 0.0889)
		(layer "In13.Cu")
		(net "M_B_CPU0_SB_CB<1>")
	)
	(segment
		(start 306.147724 -279.359868)
		(end 306.534566 -279.74671)
		(width 0.14478)
		(layer "In13.Cu")
		(net "M_B_CPU0_SB_CB<1>")
	)
	(segment
		(start 310.616092 -276.147022)
		(end 310.916828 -276.147022)
		(width 0.14478)
		(layer "In13.Cu")
		(net "M_B_CPU0_SB_CB<1>")
	)
	(segment
		(start 308.03723 -279.02662)
		(end 308.03723 -278.725884)
		(width 0.14478)
		(layer "In13.Cu")
		(net "M_B_CPU0_SB_CB<1>")
	)
	(segment
		(start 313.49569 -273.267424)
		(end 313.735212 -273.027902)
		(width 0.14478)
		(layer "In13.Cu")
		(net "M_B_CPU0_SB_CB<1>")
	)
	(segment
		(start 313.256168 -273.807682)
		(end 313.49569 -273.56816)
		(width 0.14478)
		(layer "In13.Cu")
		(net "M_B_CPU0_SB_CB<1>")
	)
	(segment
		(start 312.476388 -274.587462)
		(end 312.71591 -274.34794)
		(width 0.14478)
		(layer "In13.Cu")
		(net "M_B_CPU0_SB_CB<1>")
	)
	(segment
		(start 312.175652 -274.587462)
		(end 312.476388 -274.587462)
		(width 0.14478)
		(layer "In13.Cu")
		(net "M_B_CPU0_SB_CB<1>")
	)
	(segment
		(start 309.836312 -276.926802)
		(end 310.137048 -276.926802)
		(width 0.14478)
		(layer "In13.Cu")
		(net "M_B_CPU0_SB_CB<1>")
	)
	(segment
		(start 302.230282 -279.907492)
		(end 302.479202 -279.907492)
		(width 0.14478)
		(layer "In13.Cu")
		(net "M_B_CPU0_SB_CB<1>")
	)
	(segment
		(start 311.15635 -275.606764)
		(end 311.395872 -275.367242)
		(width 0.14478)
		(layer "In13.Cu")
		(net "M_B_CPU0_SB_CB<1>")
	)
	(segment
		(start 308.03723 -278.725884)
		(end 308.276752 -278.486362)
		(width 0.14478)
		(layer "In13.Cu")
		(net "M_B_CPU0_SB_CB<1>")
	)
	(segment
		(start 305.073558 -280.210006)
		(end 305.923696 -279.359868)
		(width 0.14478)
		(layer "In13.Cu")
		(net "M_B_CPU0_SB_CB<1>")
	)
	(segment
		(start 313.49569 -273.56816)
		(end 313.49569 -273.267424)
		(width 0.14478)
		(layer "In13.Cu")
		(net "M_B_CPU0_SB_CB<1>")
	)
	(segment
		(start 325.162672 -272.277332)
		(end 326.40778 -273.52244)
		(width 0.0889)
		(layer "In13.Cu")
		(net "M_B_CPU0_SB_CB<1>")
	)
	(segment
		(start 306.765198 -279.74671)
		(end 307.09997 -279.411938)
		(width 0.14478)
		(layer "In13.Cu")
		(net "M_B_CPU0_SB_CB<1>")
	)
	(segment
		(start 303.934368 -280.210006)
		(end 304.216562 -279.927812)
		(width 0.14478)
		(layer "In13.Cu")
		(net "M_B_CPU0_SB_CB<1>")
	)
	(segment
		(start 309.357268 -277.706582)
		(end 309.59679 -277.46706)
		(width 0.14478)
		(layer "In13.Cu")
		(net "M_B_CPU0_SB_CB<1>")
	)
	(segment
		(start 313.735212 -273.027902)
		(end 314.035948 -273.027902)
		(width 0.14478)
		(layer "In13.Cu")
		(net "M_B_CPU0_SB_CB<1>")
	)
	(segment
		(start 324.398386 -272.20926)
		(end 324.466458 -272.277332)
		(width 0.0889)
		(layer "In13.Cu")
		(net "M_B_CPU0_SB_CB<1>")
	)
	(segment
		(start 314.035948 -273.027902)
		(end 314.85459 -272.20926)
		(width 0.14478)
		(layer "In13.Cu")
		(net "M_B_CPU0_SB_CB<1>")
	)
	(segment
		(start 301.446946 -280.210006)
		(end 301.927768 -280.210006)
		(width 0.14478)
		(layer "In13.Cu")
		(net "M_B_CPU0_SB_CB<1>")
	)
	(segment
		(start 323.901054 -272.20926)
		(end 324.398386 -272.20926)
		(width 0.0889)
		(layer "In13.Cu")
		(net "M_B_CPU0_SB_CB<1>")
	)
	(segment
		(start 308.81701 -278.24684)
		(end 308.81701 -277.946104)
		(width 0.14478)
		(layer "In13.Cu")
		(net "M_B_CPU0_SB_CB<1>")
	)
	(segment
		(start 311.93613 -275.12772)
		(end 311.93613 -274.826984)
		(width 0.14478)
		(layer "In13.Cu")
		(net "M_B_CPU0_SB_CB<1>")
	)
	(segment
		(start 299.82414 -279.785064)
		(end 299.82414 -279.602438)
		(width 0.14478)
		(layer "In13.Cu")
		(net "M_B_CPU0_SB_CB<1>")
	)
	(segment
		(start 312.71591 -274.047204)
		(end 312.955432 -273.807682)
		(width 0.14478)
		(layer "In13.Cu")
		(net "M_B_CPU0_SB_CB<1>")
	)
	(segment
		(start 300.06671 -279.359868)
		(end 300.596808 -279.359868)
		(width 0.14478)
		(layer "In13.Cu")
		(net "M_B_CPU0_SB_CB<1>")
	)
	(segment
		(start 328.239882 -273.603466)
		(end 328.248264 -273.59864)
		(width 0.0889)
		(layer "In13.Cu")
		(net "M_B_CPU0_SB_CB<1>")
	)
	(segment
		(start 299.82414 -279.602438)
		(end 300.06671 -279.359868)
		(width 0.14478)
		(layer "In13.Cu")
		(net "M_B_CPU0_SB_CB<1>")
	)
	(segment
		(start 333.880714 -273.602958)
		(end 333.88808 -273.59864)
		(width 0.0889)
		(layer "In13.Cu")
		(net "M_B_CPU0_SB_CB<1>")
	)
	(segment
		(start 309.056532 -277.706582)
		(end 309.357268 -277.706582)
		(width 0.14478)
		(layer "In13.Cu")
		(net "M_B_CPU0_SB_CB<1>")
	)
	(segment
		(start 311.15635 -275.9075)
		(end 311.15635 -275.606764)
		(width 0.14478)
		(layer "In13.Cu")
		(net "M_B_CPU0_SB_CB<1>")
	)
	(segment
		(start 304.485802 -279.927812)
		(end 304.767996 -280.210006)
		(width 0.14478)
		(layer "In13.Cu")
		(net "M_B_CPU0_SB_CB<1>")
	)
	(segment
		(start 333.879698 -273.603466)
		(end 333.880714 -273.602958)
		(width 0.0889)
		(layer "In13.Cu")
		(net "M_B_CPU0_SB_CB<1>")
	)
	(segment
		(start 306.534566 -279.74671)
		(end 306.765198 -279.74671)
		(width 0.14478)
		(layer "In13.Cu")
		(net "M_B_CPU0_SB_CB<1>")
	)
	(segment
		(start 308.577488 -278.486362)
		(end 308.81701 -278.24684)
		(width 0.14478)
		(layer "In13.Cu")
		(net "M_B_CPU0_SB_CB<1>")
	)
	(segment
		(start 302.479202 -279.907492)
		(end 302.781716 -280.210006)
		(width 0.14478)
		(layer "In13.Cu")
		(net "M_B_CPU0_SB_CB<1>")
	)
	(segment
		(start 326.93356 -273.598386)
		(end 326.947276 -273.60626)
		(width 0.0889)
		(layer "In13.Cu")
		(net "M_B_CPU0_SB_CB<1>")
	)
	(segment
		(start 302.781716 -280.210006)
		(end 303.934368 -280.210006)
		(width 0.14478)
		(layer "In13.Cu")
		(net "M_B_CPU0_SB_CB<1>")
	)
	(segment
		(start 310.37657 -276.386544)
		(end 310.616092 -276.147022)
		(width 0.14478)
		(layer "In13.Cu")
		(net "M_B_CPU0_SB_CB<1>")
	)
	(segment
		(start 330.119736 -273.603466)
		(end 330.128118 -273.59864)
		(width 0.0889)
		(layer "In13.Cu")
		(net "M_B_CPU0_SB_CB<1>")
	)
	(segment
		(start 309.59679 -277.46706)
		(end 309.59679 -277.166324)
		(width 0.14478)
		(layer "In13.Cu")
		(net "M_B_CPU0_SB_CB<1>")
	)
	(arc
		(start 336.708242 -273.59864)
		(mid 336.955955 -273.52342)
		(end 337.211162 -273.56689)
		(width 0.0889)
		(layer "In13.Cu")
		(net "M_B_CPU0_SB_CB<1>")
	)
	(arc
		(start 330.702412 -273.603466)
		(mid 330.88592 -273.64896)
		(end 331.068172 -273.59864)
		(width 0.0889)
		(layer "In13.Cu")
		(net "M_B_CPU0_SB_CB<1>")
	)
	(arc
		(start 326.947276 -273.60626)
		(mid 327.128206 -273.648738)
		(end 327.307194 -273.59864)
		(width 0.0889)
		(layer "In13.Cu")
		(net "M_B_CPU0_SB_CB<1>")
	)
	(arc
		(start 334.828134 -273.59864)
		(mid 335.11109 -273.522463)
		(end 335.394046 -273.59864)
		(width 0.0889)
		(layer "In13.Cu")
		(net "M_B_CPU0_SB_CB<1>")
	)
	(arc
		(start 333.513938 -273.59864)
		(mid 333.696189 -273.64899)
		(end 333.879698 -273.603466)
		(width 0.0889)
		(layer "In13.Cu")
		(net "M_B_CPU0_SB_CB<1>")
	)
	(arc
		(start 329.188064 -273.59864)
		(mid 329.47102 -273.522463)
		(end 329.753976 -273.59864)
		(width 0.0889)
		(layer "In13.Cu")
		(net "M_B_CPU0_SB_CB<1>")
	)
	(arc
		(start 332.948026 -273.59864)
		(mid 333.230982 -273.522463)
		(end 333.513938 -273.59864)
		(width 0.0889)
		(layer "In13.Cu")
		(net "M_B_CPU0_SB_CB<1>")
	)
	(arc
		(start 335.402428 -273.603466)
		(mid 335.585936 -273.64896)
		(end 335.768188 -273.59864)
		(width 0.0889)
		(layer "In13.Cu")
		(net "M_B_CPU0_SB_CB<1>")
	)
	(arc
		(start 327.873614 -273.59864)
		(mid 328.056119 -273.649117)
		(end 328.239882 -273.603466)
		(width 0.0889)
		(layer "In13.Cu")
		(net "M_B_CPU0_SB_CB<1>")
	)
	(arc
		(start 328.814176 -273.59864)
		(mid 329.00112 -273.648895)
		(end 329.188064 -273.59864)
		(width 0.0889)
		(layer "In13.Cu")
		(net "M_B_CPU0_SB_CB<1>")
	)
	(arc
		(start 329.753976 -273.59864)
		(mid 329.936227 -273.64899)
		(end 330.119736 -273.603466)
		(width 0.0889)
		(layer "In13.Cu")
		(net "M_B_CPU0_SB_CB<1>")
	)
	(arc
		(start 326.68337 -273.523202)
		(mid 326.812874 -273.546116)
		(end 326.93356 -273.598386)
		(width 0.0889)
		(layer "In13.Cu")
		(net "M_B_CPU0_SB_CB<1>")
	)
	(arc
		(start 336.342482 -273.603466)
		(mid 336.52599 -273.64896)
		(end 336.708242 -273.59864)
		(width 0.0889)
		(layer "In13.Cu")
		(net "M_B_CPU0_SB_CB<1>")
	)
	(arc
		(start 332.574138 -273.59864)
		(mid 332.761082 -273.648895)
		(end 332.948026 -273.59864)
		(width 0.0889)
		(layer "In13.Cu")
		(net "M_B_CPU0_SB_CB<1>")
	)
	(arc
		(start 331.068172 -273.59864)
		(mid 331.351128 -273.522463)
		(end 331.634084 -273.59864)
		(width 0.0889)
		(layer "In13.Cu")
		(net "M_B_CPU0_SB_CB<1>")
	)
	(arc
		(start 332.008226 -273.59864)
		(mid 332.291182 -273.522463)
		(end 332.574138 -273.59864)
		(width 0.0889)
		(layer "In13.Cu")
		(net "M_B_CPU0_SB_CB<1>")
	)
	(arc
		(start 331.642466 -273.603466)
		(mid 331.825974 -273.64896)
		(end 332.008226 -273.59864)
		(width 0.0889)
		(layer "In13.Cu")
		(net "M_B_CPU0_SB_CB<1>")
	)
	(arc
		(start 328.248264 -273.59864)
		(mid 328.53122 -273.522463)
		(end 328.814176 -273.59864)
		(width 0.0889)
		(layer "In13.Cu")
		(net "M_B_CPU0_SB_CB<1>")
	)
	(arc
		(start 334.453992 -273.59864)
		(mid 334.636243 -273.64899)
		(end 334.819752 -273.603466)
		(width 0.0889)
		(layer "In13.Cu")
		(net "M_B_CPU0_SB_CB<1>")
	)
	(arc
		(start 335.768188 -273.59864)
		(mid 336.051144 -273.522463)
		(end 336.3341 -273.59864)
		(width 0.0889)
		(layer "In13.Cu")
		(net "M_B_CPU0_SB_CB<1>")
	)
	(arc
		(start 326.65162 -273.52244)
		(mid 326.6675 -273.522599)
		(end 326.68337 -273.523202)
		(width 0.0889)
		(layer "In13.Cu")
		(net "M_B_CPU0_SB_CB<1>")
	)
	(arc
		(start 333.88808 -273.59864)
		(mid 334.171036 -273.522463)
		(end 334.453992 -273.59864)
		(width 0.0889)
		(layer "In13.Cu")
		(net "M_B_CPU0_SB_CB<1>")
	)
	(arc
		(start 330.128118 -273.59864)
		(mid 330.411074 -273.522463)
		(end 330.69403 -273.59864)
		(width 0.0889)
		(layer "In13.Cu")
		(net "M_B_CPU0_SB_CB<1>")
	)
	(arc
		(start 327.321926 -273.590004)
		(mid 327.598909 -273.5222)
		(end 327.873614 -273.59864)
		(width 0.0889)
		(layer "In13.Cu")
		(net "M_B_CPU0_SB_CB<1>")
	)
	(segment
		(start 336.517996 -272.200116)
		(end 336.051144 -272.466054)
		(width 0.10668)
		(layer "F.Cu")
		(net "M_B_CPU0_SB_CB<0>")
	)
	(segment
		(start 332.469744 -272.79346)
		(end 332.478126 -272.788634)
		(width 0.0889)
		(layer "In13.Cu")
		(net "M_B_CPU0_SB_CB<0>")
	)
	(segment
		(start 306.539138 -277.38451)
		(end 306.79517 -277.38451)
		(width 0.14478)
		(layer "In13.Cu")
		(net "M_B_CPU0_SB_CB<0>")
	)
	(segment
		(start 303.372266 -278.349202)
		(end 303.533302 -278.188166)
		(width 0.14478)
		(layer "In13.Cu")
		(net "M_B_CPU0_SB_CB<0>")
	)
	(segment
		(start 303.372266 -278.671274)
		(end 303.372266 -278.349202)
		(width 0.14478)
		(layer "In13.Cu")
		(net "M_B_CPU0_SB_CB<0>")
	)
	(segment
		(start 304.32375 -278.83231)
		(end 304.645822 -278.510238)
		(width 0.14478)
		(layer "In13.Cu")
		(net "M_B_CPU0_SB_CB<0>")
	)
	(segment
		(start 305.732688 -277.690072)
		(end 305.937412 -277.690072)
		(width 0.14478)
		(layer "In13.Cu")
		(net "M_B_CPU0_SB_CB<0>")
	)
	(segment
		(start 303.533302 -278.188166)
		(end 303.76749 -278.188166)
		(width 0.14478)
		(layer "In13.Cu")
		(net "M_B_CPU0_SB_CB<0>")
	)
	(segment
		(start 305.593242 -278.125682)
		(end 305.547522 -278.079962)
		(width 0.14478)
		(layer "In13.Cu")
		(net "M_B_CPU0_SB_CB<0>")
	)
	(segment
		(start 305.937412 -277.690072)
		(end 305.983132 -277.735792)
		(width 0.14478)
		(layer "In13.Cu")
		(net "M_B_CPU0_SB_CB<0>")
	)
	(segment
		(start 305.41341 -278.510238)
		(end 305.593242 -278.330406)
		(width 0.14478)
		(layer "In13.Cu")
		(net "M_B_CPU0_SB_CB<0>")
	)
	(segment
		(start 302.977042 -278.83231)
		(end 303.21123 -278.83231)
		(width 0.14478)
		(layer "In13.Cu")
		(net "M_B_CPU0_SB_CB<0>")
	)
	(segment
		(start 335.8007 -272.756884)
		(end 335.896966 -272.731484)
		(width 0.0889)
		(layer "In13.Cu")
		(net "M_B_CPU0_SB_CB<0>")
	)
	(segment
		(start 307.34635 -278.031194)
		(end 307.49113 -277.886414)
		(width 0.14478)
		(layer "In13.Cu")
		(net "M_B_CPU0_SB_CB<0>")
	)
	(segment
		(start 303.928526 -278.671274)
		(end 304.089562 -278.83231)
		(width 0.14478)
		(layer "In13.Cu")
		(net "M_B_CPU0_SB_CB<0>")
	)
	(segment
		(start 300.35246 -277.669752)
		(end 300.610524 -277.927816)
		(width 0.14478)
		(layer "In13.Cu")
		(net "M_B_CPU0_SB_CB<0>")
	)
	(segment
		(start 335.896966 -272.731484)
		(end 336.051144 -272.466054)
		(width 0.0889)
		(layer "In13.Cu")
		(net "M_B_CPU0_SB_CB<0>")
	)
	(segment
		(start 302.09871 -278.83231)
		(end 302.259746 -278.671274)
		(width 0.14478)
		(layer "In13.Cu")
		(net "M_B_CPU0_SB_CB<0>")
	)
	(segment
		(start 305.547522 -277.875238)
		(end 305.732688 -277.690072)
		(width 0.14478)
		(layer "In13.Cu")
		(net "M_B_CPU0_SB_CB<0>")
	)
	(segment
		(start 307.08473 -278.031194)
		(end 307.34635 -278.031194)
		(width 0.14478)
		(layer "In13.Cu")
		(net "M_B_CPU0_SB_CB<0>")
	)
	(segment
		(start 304.645822 -278.510238)
		(end 305.41341 -278.510238)
		(width 0.14478)
		(layer "In13.Cu")
		(net "M_B_CPU0_SB_CB<0>")
	)
	(segment
		(start 305.547522 -278.079962)
		(end 305.547522 -277.875238)
		(width 0.14478)
		(layer "In13.Cu")
		(net "M_B_CPU0_SB_CB<0>")
	)
	(segment
		(start 301.345092 -277.97379)
		(end 301.344838 -278.178006)
		(width 0.14478)
		(layer "In13.Cu")
		(net "M_B_CPU0_SB_CB<0>")
	)
	(segment
		(start 300.954948 -277.78837)
		(end 301.159672 -277.78837)
		(width 0.14478)
		(layer "In13.Cu")
		(net "M_B_CPU0_SB_CB<0>")
	)
	(segment
		(start 306.93995 -277.886414)
		(end 307.08473 -278.031194)
		(width 0.14478)
		(layer "In13.Cu")
		(net "M_B_CPU0_SB_CB<0>")
	)
	(segment
		(start 303.21123 -278.83231)
		(end 303.372266 -278.671274)
		(width 0.14478)
		(layer "In13.Cu")
		(net "M_B_CPU0_SB_CB<0>")
	)
	(segment
		(start 324.339966 -271.29994)
		(end 324.827138 -271.787112)
		(width 0.0889)
		(layer "In13.Cu")
		(net "M_B_CPU0_SB_CB<0>")
	)
	(segment
		(start 301.205138 -278.52243)
		(end 301.515018 -278.83231)
		(width 0.14478)
		(layer "In13.Cu")
		(net "M_B_CPU0_SB_CB<0>")
	)
	(segment
		(start 302.816006 -278.671274)
		(end 302.977042 -278.83231)
		(width 0.14478)
		(layer "In13.Cu")
		(net "M_B_CPU0_SB_CB<0>")
	)
	(segment
		(start 300.815248 -277.92807)
		(end 300.954948 -277.78837)
		(width 0.14478)
		(layer "In13.Cu")
		(net "M_B_CPU0_SB_CB<0>")
	)
	(segment
		(start 328.709782 -272.79346)
		(end 328.718164 -272.788634)
		(width 0.0889)
		(layer "In13.Cu")
		(net "M_B_CPU0_SB_CB<0>")
	)
	(segment
		(start 313.986418 -271.29994)
		(end 323.901054 -271.29994)
		(width 0.14478)
		(layer "In13.Cu")
		(net "M_B_CPU0_SB_CB<0>")
	)
	(segment
		(start 328.333608 -272.782538)
		(end 328.344022 -272.788634)
		(width 0.0889)
		(layer "In13.Cu")
		(net "M_B_CPU0_SB_CB<0>")
	)
	(segment
		(start 307.901848 -277.38451)
		(end 313.986418 -271.29994)
		(width 0.14478)
		(layer "In13.Cu")
		(net "M_B_CPU0_SB_CB<0>")
	)
	(segment
		(start 307.49113 -277.52929)
		(end 307.63591 -277.38451)
		(width 0.14478)
		(layer "In13.Cu")
		(net "M_B_CPU0_SB_CB<0>")
	)
	(segment
		(start 300.033436 -277.669752)
		(end 300.35246 -277.669752)
		(width 0.14478)
		(layer "In13.Cu")
		(net "M_B_CPU0_SB_CB<0>")
	)
	(segment
		(start 299.82414 -278.085042)
		(end 299.82414 -277.879048)
		(width 0.14478)
		(layer "In13.Cu")
		(net "M_B_CPU0_SB_CB<0>")
	)
	(segment
		(start 306.79517 -277.38451)
		(end 306.93995 -277.52929)
		(width 0.14478)
		(layer "In13.Cu")
		(net "M_B_CPU0_SB_CB<0>")
	)
	(segment
		(start 325.444104 -271.787112)
		(end 326.386952 -272.72996)
		(width 0.0889)
		(layer "In13.Cu")
		(net "M_B_CPU0_SB_CB<0>")
	)
	(segment
		(start 306.93995 -277.52929)
		(end 306.93995 -277.886414)
		(width 0.14478)
		(layer "In13.Cu")
		(net "M_B_CPU0_SB_CB<0>")
	)
	(segment
		(start 326.819514 -272.798794)
		(end 326.837802 -272.78838)
		(width 0.0889)
		(layer "In13.Cu")
		(net "M_B_CPU0_SB_CB<0>")
	)
	(segment
		(start 326.463406 -272.788634)
		(end 326.46366 -272.788634)
		(width 0.0889)
		(layer "In13.Cu")
		(net "M_B_CPU0_SB_CB<0>")
	)
	(segment
		(start 326.837802 -272.78838)
		(end 326.84339 -272.785078)
		(width 0.0889)
		(layer "In13.Cu")
		(net "M_B_CPU0_SB_CB<0>")
	)
	(segment
		(start 303.76749 -278.188166)
		(end 303.928526 -278.349202)
		(width 0.14478)
		(layer "In13.Cu")
		(net "M_B_CPU0_SB_CB<0>")
	)
	(segment
		(start 333.044038 -272.788634)
		(end 333.05242 -272.79346)
		(width 0.0889)
		(layer "In13.Cu")
		(net "M_B_CPU0_SB_CB<0>")
	)
	(segment
		(start 300.610524 -277.927816)
		(end 300.815248 -277.92807)
		(width 0.14478)
		(layer "In13.Cu")
		(net "M_B_CPU0_SB_CB<0>")
	)
	(segment
		(start 307.63591 -277.38451)
		(end 307.901848 -277.38451)
		(width 0.14478)
		(layer "In13.Cu")
		(net "M_B_CPU0_SB_CB<0>")
	)
	(segment
		(start 303.928526 -278.349202)
		(end 303.928526 -278.671274)
		(width 0.14478)
		(layer "In13.Cu")
		(net "M_B_CPU0_SB_CB<0>")
	)
	(segment
		(start 302.816006 -278.349202)
		(end 302.816006 -278.671274)
		(width 0.14478)
		(layer "In13.Cu")
		(net "M_B_CPU0_SB_CB<0>")
	)
	(segment
		(start 302.259746 -278.349202)
		(end 302.420782 -278.188166)
		(width 0.14478)
		(layer "In13.Cu")
		(net "M_B_CPU0_SB_CB<0>")
	)
	(segment
		(start 301.205138 -278.317706)
		(end 301.205138 -278.52243)
		(width 0.14478)
		(layer "In13.Cu")
		(net "M_B_CPU0_SB_CB<0>")
	)
	(segment
		(start 323.901054 -271.29994)
		(end 324.339966 -271.29994)
		(width 0.0889)
		(layer "In13.Cu")
		(net "M_B_CPU0_SB_CB<0>")
	)
	(segment
		(start 331.52969 -272.79346)
		(end 331.538072 -272.788634)
		(width 0.0889)
		(layer "In13.Cu")
		(net "M_B_CPU0_SB_CB<0>")
	)
	(segment
		(start 301.515018 -278.83231)
		(end 302.09871 -278.83231)
		(width 0.14478)
		(layer "In13.Cu")
		(net "M_B_CPU0_SB_CB<0>")
	)
	(segment
		(start 302.259746 -278.671274)
		(end 302.259746 -278.349202)
		(width 0.14478)
		(layer "In13.Cu")
		(net "M_B_CPU0_SB_CB<0>")
	)
	(segment
		(start 302.420782 -278.188166)
		(end 302.65497 -278.188166)
		(width 0.14478)
		(layer "In13.Cu")
		(net "M_B_CPU0_SB_CB<0>")
	)
	(segment
		(start 305.983132 -277.735792)
		(end 306.187856 -277.735792)
		(width 0.14478)
		(layer "In13.Cu")
		(net "M_B_CPU0_SB_CB<0>")
	)
	(segment
		(start 301.344838 -278.178006)
		(end 301.205138 -278.317706)
		(width 0.14478)
		(layer "In13.Cu")
		(net "M_B_CPU0_SB_CB<0>")
	)
	(segment
		(start 327.403206 -272.788634)
		(end 327.411588 -272.79346)
		(width 0.0889)
		(layer "In13.Cu")
		(net "M_B_CPU0_SB_CB<0>")
	)
	(segment
		(start 305.593242 -278.330406)
		(end 305.593242 -278.125682)
		(width 0.14478)
		(layer "In13.Cu")
		(net "M_B_CPU0_SB_CB<0>")
	)
	(segment
		(start 302.65497 -278.188166)
		(end 302.816006 -278.349202)
		(width 0.14478)
		(layer "In13.Cu")
		(net "M_B_CPU0_SB_CB<0>")
	)
	(segment
		(start 304.089562 -278.83231)
		(end 304.32375 -278.83231)
		(width 0.14478)
		(layer "In13.Cu")
		(net "M_B_CPU0_SB_CB<0>")
	)
	(segment
		(start 307.49113 -277.886414)
		(end 307.49113 -277.52929)
		(width 0.14478)
		(layer "In13.Cu")
		(net "M_B_CPU0_SB_CB<0>")
	)
	(segment
		(start 306.187856 -277.735792)
		(end 306.539138 -277.38451)
		(width 0.14478)
		(layer "In13.Cu")
		(net "M_B_CPU0_SB_CB<0>")
	)
	(segment
		(start 299.82414 -277.879048)
		(end 300.033436 -277.669752)
		(width 0.14478)
		(layer "In13.Cu")
		(net "M_B_CPU0_SB_CB<0>")
	)
	(segment
		(start 329.284076 -272.788634)
		(end 329.292458 -272.79346)
		(width 0.0889)
		(layer "In13.Cu")
		(net "M_B_CPU0_SB_CB<0>")
	)
	(segment
		(start 301.159672 -277.78837)
		(end 301.345092 -277.97379)
		(width 0.14478)
		(layer "In13.Cu")
		(net "M_B_CPU0_SB_CB<0>")
	)
	(segment
		(start 333.984092 -272.788634)
		(end 333.992474 -272.79346)
		(width 0.0889)
		(layer "In13.Cu")
		(net "M_B_CPU0_SB_CB<0>")
	)
	(segment
		(start 324.827138 -271.787112)
		(end 325.444104 -271.787112)
		(width 0.0889)
		(layer "In13.Cu")
		(net "M_B_CPU0_SB_CB<0>")
	)
	(arc
		(start 332.103984 -272.788634)
		(mid 332.286235 -272.838984)
		(end 332.469744 -272.79346)
		(width 0.0889)
		(layer "In13.Cu")
		(net "M_B_CPU0_SB_CB<0>")
	)
	(arc
		(start 333.05242 -272.79346)
		(mid 333.235928 -272.838954)
		(end 333.41818 -272.788634)
		(width 0.0889)
		(layer "In13.Cu")
		(net "M_B_CPU0_SB_CB<0>")
	)
	(arc
		(start 327.411588 -272.79346)
		(mid 327.59535 -272.839076)
		(end 327.777856 -272.788634)
		(width 0.0889)
		(layer "In13.Cu")
		(net "M_B_CPU0_SB_CB<0>")
	)
	(arc
		(start 330.598018 -272.788634)
		(mid 330.880974 -272.712457)
		(end 331.16393 -272.788634)
		(width 0.0889)
		(layer "In13.Cu")
		(net "M_B_CPU0_SB_CB<0>")
	)
	(arc
		(start 328.344022 -272.788634)
		(mid 328.526273 -272.838984)
		(end 328.709782 -272.79346)
		(width 0.0889)
		(layer "In13.Cu")
		(net "M_B_CPU0_SB_CB<0>")
	)
	(arc
		(start 329.658218 -272.788634)
		(mid 329.941174 -272.712457)
		(end 330.22413 -272.788634)
		(width 0.0889)
		(layer "In13.Cu")
		(net "M_B_CPU0_SB_CB<0>")
	)
	(arc
		(start 333.41818 -272.788634)
		(mid 333.701136 -272.712457)
		(end 333.984092 -272.788634)
		(width 0.0889)
		(layer "In13.Cu")
		(net "M_B_CPU0_SB_CB<0>")
	)
	(arc
		(start 326.84339 -272.785078)
		(mid 327.123779 -272.712409)
		(end 327.403206 -272.788634)
		(width 0.0889)
		(layer "In13.Cu")
		(net "M_B_CPU0_SB_CB<0>")
	)
	(arc
		(start 334.924146 -272.788634)
		(mid 335.11109 -272.838889)
		(end 335.298034 -272.788634)
		(width 0.0889)
		(layer "In13.Cu")
		(net "M_B_CPU0_SB_CB<0>")
	)
	(arc
		(start 332.478126 -272.788634)
		(mid 332.761082 -272.712457)
		(end 333.044038 -272.788634)
		(width 0.0889)
		(layer "In13.Cu")
		(net "M_B_CPU0_SB_CB<0>")
	)
	(arc
		(start 327.777856 -272.788634)
		(mid 328.054923 -272.712363)
		(end 328.333608 -272.782538)
		(width 0.0889)
		(layer "In13.Cu")
		(net "M_B_CPU0_SB_CB<0>")
	)
	(arc
		(start 329.292458 -272.79346)
		(mid 329.475966 -272.838954)
		(end 329.658218 -272.788634)
		(width 0.0889)
		(layer "In13.Cu")
		(net "M_B_CPU0_SB_CB<0>")
	)
	(arc
		(start 333.992474 -272.79346)
		(mid 334.175982 -272.838954)
		(end 334.358234 -272.788634)
		(width 0.0889)
		(layer "In13.Cu")
		(net "M_B_CPU0_SB_CB<0>")
	)
	(arc
		(start 331.16393 -272.788634)
		(mid 331.346181 -272.838984)
		(end 331.52969 -272.79346)
		(width 0.0889)
		(layer "In13.Cu")
		(net "M_B_CPU0_SB_CB<0>")
	)
	(arc
		(start 328.718164 -272.788634)
		(mid 329.00112 -272.712457)
		(end 329.284076 -272.788634)
		(width 0.0889)
		(layer "In13.Cu")
		(net "M_B_CPU0_SB_CB<0>")
	)
	(arc
		(start 326.46366 -272.788634)
		(mid 326.640288 -272.838867)
		(end 326.819514 -272.798794)
		(width 0.0889)
		(layer "In13.Cu")
		(net "M_B_CPU0_SB_CB<0>")
	)
	(arc
		(start 335.298034 -272.788634)
		(mid 335.54563 -272.713456)
		(end 335.8007 -272.756884)
		(width 0.0889)
		(layer "In13.Cu")
		(net "M_B_CPU0_SB_CB<0>")
	)
	(arc
		(start 331.538072 -272.788634)
		(mid 331.821028 -272.712457)
		(end 332.103984 -272.788634)
		(width 0.0889)
		(layer "In13.Cu")
		(net "M_B_CPU0_SB_CB<0>")
	)
	(arc
		(start 326.386952 -272.72996)
		(mid 326.423279 -272.761773)
		(end 326.463406 -272.788634)
		(width 0.0889)
		(layer "In13.Cu")
		(net "M_B_CPU0_SB_CB<0>")
	)
	(arc
		(start 330.22413 -272.788634)
		(mid 330.411074 -272.838889)
		(end 330.598018 -272.788634)
		(width 0.0889)
		(layer "In13.Cu")
		(net "M_B_CPU0_SB_CB<0>")
	)
	(arc
		(start 334.358234 -272.788634)
		(mid 334.64119 -272.712457)
		(end 334.924146 -272.788634)
		(width 0.0889)
		(layer "In13.Cu")
		(net "M_B_CPU0_SB_CB<0>")
	)
	(segment
		(start 336.517996 -264.100056)
		(end 336.051144 -264.365994)
		(width 0.10668)
		(layer "F.Cu")
		(net "M_B_CPU0_SB_CA<6>")
	)
	(segment
		(start 324.20179 -264.61974)
		(end 324.484238 -264.337292)
		(width 0.0889)
		(layer "In13.Cu")
		(net "M_B_CPU0_SB_CA<6>")
	)
	(segment
		(start 302.115474 -265.911076)
		(end 302.260254 -266.055856)
		(width 0.14478)
		(layer "In13.Cu")
		(net "M_B_CPU0_SB_CA<6>")
	)
	(segment
		(start 300.317154 -266.055856)
		(end 300.461934 -265.911076)
		(width 0.14478)
		(layer "In13.Cu")
		(net "M_B_CPU0_SB_CA<6>")
	)
	(segment
		(start 300.606714 -265.45286)
		(end 300.868334 -265.45286)
		(width 0.14478)
		(layer "In13.Cu")
		(net "M_B_CPU0_SB_CA<6>")
	)
	(segment
		(start 301.013114 -265.911076)
		(end 301.157894 -266.055856)
		(width 0.14478)
		(layer "In13.Cu")
		(net "M_B_CPU0_SB_CA<6>")
	)
	(segment
		(start 328.333608 -264.682478)
		(end 328.344022 -264.688574)
		(width 0.0889)
		(layer "In13.Cu")
		(net "M_B_CPU0_SB_CA<6>")
	)
	(segment
		(start 301.970694 -265.45286)
		(end 302.115474 -265.59764)
		(width 0.14478)
		(layer "In13.Cu")
		(net "M_B_CPU0_SB_CA<6>")
	)
	(segment
		(start 326.094344 -264.337292)
		(end 326.386952 -264.6299)
		(width 0.0889)
		(layer "In13.Cu")
		(net "M_B_CPU0_SB_CA<6>")
	)
	(segment
		(start 302.260254 -266.055856)
		(end 302.655732 -266.055856)
		(width 0.14478)
		(layer "In13.Cu")
		(net "M_B_CPU0_SB_CA<6>")
	)
	(segment
		(start 302.951388 -265.7602)
		(end 303.739042 -265.7602)
		(width 0.14478)
		(layer "In13.Cu")
		(net "M_B_CPU0_SB_CA<6>")
	)
	(segment
		(start 304.295302 -266.08151)
		(end 304.616612 -265.7602)
		(width 0.14478)
		(layer "In13.Cu")
		(net "M_B_CPU0_SB_CA<6>")
	)
	(segment
		(start 304.616612 -265.7602)
		(end 304.851562 -265.7602)
		(width 0.14478)
		(layer "In13.Cu")
		(net "M_B_CPU0_SB_CA<6>")
	)
	(segment
		(start 301.157894 -266.055856)
		(end 301.419514 -266.055856)
		(width 0.14478)
		(layer "In13.Cu")
		(net "M_B_CPU0_SB_CA<6>")
	)
	(segment
		(start 304.851562 -265.7602)
		(end 305.172872 -266.08151)
		(width 0.14478)
		(layer "In13.Cu")
		(net "M_B_CPU0_SB_CA<6>")
	)
	(segment
		(start 301.564294 -265.911076)
		(end 301.564294 -265.59764)
		(width 0.14478)
		(layer "In13.Cu")
		(net "M_B_CPU0_SB_CA<6>")
	)
	(segment
		(start 305.964082 -265.7602)
		(end 306.285392 -266.08151)
		(width 0.14478)
		(layer "In13.Cu")
		(net "M_B_CPU0_SB_CA<6>")
	)
	(segment
		(start 335.896966 -264.631424)
		(end 336.051144 -264.365994)
		(width 0.0889)
		(layer "In13.Cu")
		(net "M_B_CPU0_SB_CA<6>")
	)
	(segment
		(start 299.82414 -266.185142)
		(end 299.953426 -266.055856)
		(width 0.14478)
		(layer "In13.Cu")
		(net "M_B_CPU0_SB_CA<6>")
	)
	(segment
		(start 300.461934 -265.911076)
		(end 300.461934 -265.59764)
		(width 0.14478)
		(layer "In13.Cu")
		(net "M_B_CPU0_SB_CA<6>")
	)
	(segment
		(start 305.172872 -266.08151)
		(end 305.407822 -266.08151)
		(width 0.14478)
		(layer "In13.Cu")
		(net "M_B_CPU0_SB_CA<6>")
	)
	(segment
		(start 327.403206 -264.688574)
		(end 327.411588 -264.6934)
		(width 0.0889)
		(layer "In13.Cu")
		(net "M_B_CPU0_SB_CA<6>")
	)
	(segment
		(start 324.484238 -264.337292)
		(end 326.094344 -264.337292)
		(width 0.0889)
		(layer "In13.Cu")
		(net "M_B_CPU0_SB_CA<6>")
	)
	(segment
		(start 307.076602 -265.7602)
		(end 307.397912 -266.08151)
		(width 0.14478)
		(layer "In13.Cu")
		(net "M_B_CPU0_SB_CA<6>")
	)
	(segment
		(start 323.901054 -264.61974)
		(end 324.20179 -264.61974)
		(width 0.0889)
		(layer "In13.Cu")
		(net "M_B_CPU0_SB_CA<6>")
	)
	(segment
		(start 301.709074 -265.45286)
		(end 301.970694 -265.45286)
		(width 0.14478)
		(layer "In13.Cu")
		(net "M_B_CPU0_SB_CA<6>")
	)
	(segment
		(start 301.564294 -265.59764)
		(end 301.709074 -265.45286)
		(width 0.14478)
		(layer "In13.Cu")
		(net "M_B_CPU0_SB_CA<6>")
	)
	(segment
		(start 307.632862 -266.08151)
		(end 309.094632 -264.61974)
		(width 0.14478)
		(layer "In13.Cu")
		(net "M_B_CPU0_SB_CA<6>")
	)
	(segment
		(start 326.837802 -264.68832)
		(end 326.84339 -264.685018)
		(width 0.0889)
		(layer "In13.Cu")
		(net "M_B_CPU0_SB_CA<6>")
	)
	(segment
		(start 304.060352 -266.08151)
		(end 304.295302 -266.08151)
		(width 0.14478)
		(layer "In13.Cu")
		(net "M_B_CPU0_SB_CA<6>")
	)
	(segment
		(start 326.819514 -264.698734)
		(end 326.837802 -264.68832)
		(width 0.0889)
		(layer "In13.Cu")
		(net "M_B_CPU0_SB_CA<6>")
	)
	(segment
		(start 306.841652 -265.7602)
		(end 307.076602 -265.7602)
		(width 0.14478)
		(layer "In13.Cu")
		(net "M_B_CPU0_SB_CA<6>")
	)
	(segment
		(start 302.655732 -266.055856)
		(end 302.951388 -265.7602)
		(width 0.14478)
		(layer "In13.Cu")
		(net "M_B_CPU0_SB_CA<6>")
	)
	(segment
		(start 328.709782 -264.6934)
		(end 328.718164 -264.688574)
		(width 0.0889)
		(layer "In13.Cu")
		(net "M_B_CPU0_SB_CA<6>")
	)
	(segment
		(start 332.469744 -264.6934)
		(end 332.478126 -264.688574)
		(width 0.0889)
		(layer "In13.Cu")
		(net "M_B_CPU0_SB_CA<6>")
	)
	(segment
		(start 333.984092 -264.688574)
		(end 333.992474 -264.6934)
		(width 0.0889)
		(layer "In13.Cu")
		(net "M_B_CPU0_SB_CA<6>")
	)
	(segment
		(start 301.013114 -265.59764)
		(end 301.013114 -265.911076)
		(width 0.14478)
		(layer "In13.Cu")
		(net "M_B_CPU0_SB_CA<6>")
	)
	(segment
		(start 299.953426 -266.055856)
		(end 300.317154 -266.055856)
		(width 0.14478)
		(layer "In13.Cu")
		(net "M_B_CPU0_SB_CA<6>")
	)
	(segment
		(start 305.729132 -265.7602)
		(end 305.964082 -265.7602)
		(width 0.14478)
		(layer "In13.Cu")
		(net "M_B_CPU0_SB_CA<6>")
	)
	(segment
		(start 306.285392 -266.08151)
		(end 306.520342 -266.08151)
		(width 0.14478)
		(layer "In13.Cu")
		(net "M_B_CPU0_SB_CA<6>")
	)
	(segment
		(start 301.419514 -266.055856)
		(end 301.564294 -265.911076)
		(width 0.14478)
		(layer "In13.Cu")
		(net "M_B_CPU0_SB_CA<6>")
	)
	(segment
		(start 309.094632 -264.61974)
		(end 323.901054 -264.61974)
		(width 0.14478)
		(layer "In13.Cu")
		(net "M_B_CPU0_SB_CA<6>")
	)
	(segment
		(start 306.520342 -266.08151)
		(end 306.841652 -265.7602)
		(width 0.14478)
		(layer "In13.Cu")
		(net "M_B_CPU0_SB_CA<6>")
	)
	(segment
		(start 329.284076 -264.688574)
		(end 329.292458 -264.6934)
		(width 0.0889)
		(layer "In13.Cu")
		(net "M_B_CPU0_SB_CA<6>")
	)
	(segment
		(start 330.22413 -264.688574)
		(end 330.232512 -264.6934)
		(width 0.0889)
		(layer "In13.Cu")
		(net "M_B_CPU0_SB_CA<6>")
	)
	(segment
		(start 300.461934 -265.59764)
		(end 300.606714 -265.45286)
		(width 0.14478)
		(layer "In13.Cu")
		(net "M_B_CPU0_SB_CA<6>")
	)
	(segment
		(start 333.044038 -264.688574)
		(end 333.05242 -264.6934)
		(width 0.0889)
		(layer "In13.Cu")
		(net "M_B_CPU0_SB_CA<6>")
	)
	(segment
		(start 307.397912 -266.08151)
		(end 307.632862 -266.08151)
		(width 0.14478)
		(layer "In13.Cu")
		(net "M_B_CPU0_SB_CA<6>")
	)
	(segment
		(start 326.463406 -264.688574)
		(end 326.46366 -264.688574)
		(width 0.0889)
		(layer "In13.Cu")
		(net "M_B_CPU0_SB_CA<6>")
	)
	(segment
		(start 335.8007 -264.656824)
		(end 335.896966 -264.631424)
		(width 0.0889)
		(layer "In13.Cu")
		(net "M_B_CPU0_SB_CA<6>")
	)
	(segment
		(start 300.868334 -265.45286)
		(end 301.013114 -265.59764)
		(width 0.14478)
		(layer "In13.Cu")
		(net "M_B_CPU0_SB_CA<6>")
	)
	(segment
		(start 305.407822 -266.08151)
		(end 305.729132 -265.7602)
		(width 0.14478)
		(layer "In13.Cu")
		(net "M_B_CPU0_SB_CA<6>")
	)
	(segment
		(start 302.115474 -265.59764)
		(end 302.115474 -265.911076)
		(width 0.14478)
		(layer "In13.Cu")
		(net "M_B_CPU0_SB_CA<6>")
	)
	(segment
		(start 303.739042 -265.7602)
		(end 304.060352 -266.08151)
		(width 0.14478)
		(layer "In13.Cu")
		(net "M_B_CPU0_SB_CA<6>")
	)
	(arc
		(start 329.658218 -264.688574)
		(mid 329.941174 -264.612397)
		(end 330.22413 -264.688574)
		(width 0.0889)
		(layer "In13.Cu")
		(net "M_B_CPU0_SB_CA<6>")
	)
	(arc
		(start 329.292458 -264.6934)
		(mid 329.475966 -264.738894)
		(end 329.658218 -264.688574)
		(width 0.0889)
		(layer "In13.Cu")
		(net "M_B_CPU0_SB_CA<6>")
	)
	(arc
		(start 326.84339 -264.685018)
		(mid 327.123779 -264.612349)
		(end 327.403206 -264.688574)
		(width 0.0889)
		(layer "In13.Cu")
		(net "M_B_CPU0_SB_CA<6>")
	)
	(arc
		(start 328.344022 -264.688574)
		(mid 328.526273 -264.738924)
		(end 328.709782 -264.6934)
		(width 0.0889)
		(layer "In13.Cu")
		(net "M_B_CPU0_SB_CA<6>")
	)
	(arc
		(start 334.358234 -264.688574)
		(mid 334.64119 -264.612397)
		(end 334.924146 -264.688574)
		(width 0.0889)
		(layer "In13.Cu")
		(net "M_B_CPU0_SB_CA<6>")
	)
	(arc
		(start 330.598272 -264.688574)
		(mid 330.881228 -264.612397)
		(end 331.164184 -264.688574)
		(width 0.0889)
		(layer "In13.Cu")
		(net "M_B_CPU0_SB_CA<6>")
	)
	(arc
		(start 334.924146 -264.688574)
		(mid 335.11109 -264.738829)
		(end 335.298034 -264.688574)
		(width 0.0889)
		(layer "In13.Cu")
		(net "M_B_CPU0_SB_CA<6>")
	)
	(arc
		(start 330.232512 -264.6934)
		(mid 330.41602 -264.738894)
		(end 330.598272 -264.688574)
		(width 0.0889)
		(layer "In13.Cu")
		(net "M_B_CPU0_SB_CA<6>")
	)
	(arc
		(start 333.992474 -264.6934)
		(mid 334.175982 -264.738894)
		(end 334.358234 -264.688574)
		(width 0.0889)
		(layer "In13.Cu")
		(net "M_B_CPU0_SB_CA<6>")
	)
	(arc
		(start 327.411588 -264.6934)
		(mid 327.59535 -264.739016)
		(end 327.777856 -264.688574)
		(width 0.0889)
		(layer "In13.Cu")
		(net "M_B_CPU0_SB_CA<6>")
	)
	(arc
		(start 332.103984 -264.688574)
		(mid 332.286235 -264.738924)
		(end 332.469744 -264.6934)
		(width 0.0889)
		(layer "In13.Cu")
		(net "M_B_CPU0_SB_CA<6>")
	)
	(arc
		(start 332.478126 -264.688574)
		(mid 332.761082 -264.612397)
		(end 333.044038 -264.688574)
		(width 0.0889)
		(layer "In13.Cu")
		(net "M_B_CPU0_SB_CA<6>")
	)
	(arc
		(start 328.718164 -264.688574)
		(mid 329.00112 -264.612397)
		(end 329.284076 -264.688574)
		(width 0.0889)
		(layer "In13.Cu")
		(net "M_B_CPU0_SB_CA<6>")
	)
	(arc
		(start 333.41818 -264.688574)
		(mid 333.701136 -264.612397)
		(end 333.984092 -264.688574)
		(width 0.0889)
		(layer "In13.Cu")
		(net "M_B_CPU0_SB_CA<6>")
	)
	(arc
		(start 326.46366 -264.688574)
		(mid 326.640288 -264.738807)
		(end 326.819514 -264.698734)
		(width 0.0889)
		(layer "In13.Cu")
		(net "M_B_CPU0_SB_CA<6>")
	)
	(arc
		(start 333.05242 -264.6934)
		(mid 333.235928 -264.738894)
		(end 333.41818 -264.688574)
		(width 0.0889)
		(layer "In13.Cu")
		(net "M_B_CPU0_SB_CA<6>")
	)
	(arc
		(start 331.538072 -264.688574)
		(mid 331.821028 -264.612397)
		(end 332.103984 -264.688574)
		(width 0.0889)
		(layer "In13.Cu")
		(net "M_B_CPU0_SB_CA<6>")
	)
	(arc
		(start 326.386952 -264.6299)
		(mid 326.423279 -264.661713)
		(end 326.463406 -264.688574)
		(width 0.0889)
		(layer "In13.Cu")
		(net "M_B_CPU0_SB_CA<6>")
	)
	(arc
		(start 331.164184 -264.688574)
		(mid 331.351128 -264.738829)
		(end 331.538072 -264.688574)
		(width 0.0889)
		(layer "In13.Cu")
		(net "M_B_CPU0_SB_CA<6>")
	)
	(arc
		(start 335.298034 -264.688574)
		(mid 335.54563 -264.613396)
		(end 335.8007 -264.656824)
		(width 0.0889)
		(layer "In13.Cu")
		(net "M_B_CPU0_SB_CA<6>")
	)
	(arc
		(start 327.777856 -264.688574)
		(mid 328.054923 -264.612303)
		(end 328.333608 -264.682478)
		(width 0.0889)
		(layer "In13.Cu")
		(net "M_B_CPU0_SB_CA<6>")
	)
	(segment
		(start 337.45805 -264.100056)
		(end 336.991198 -264.365994)
		(width 0.10668)
		(layer "F.Cu")
		(net "M_B_CPU0_SB_CA<5>")
	)
	(segment
		(start 331.52969 -264.038588)
		(end 331.538072 -264.043414)
		(width 0.0889)
		(layer "In13.Cu")
		(net "M_B_CPU0_SB_CA<5>")
	)
	(segment
		(start 329.284076 -264.043414)
		(end 329.292458 -264.038588)
		(width 0.0889)
		(layer "In13.Cu")
		(net "M_B_CPU0_SB_CA<5>")
	)
	(segment
		(start 336.229706 -264.038588)
		(end 336.238088 -264.043414)
		(width 0.0889)
		(layer "In13.Cu")
		(net "M_B_CPU0_SB_CA<5>")
	)
	(segment
		(start 324.300596 -263.992614)
		(end 327.589896 -263.992614)
		(width 0.0889)
		(layer "In13.Cu")
		(net "M_B_CPU0_SB_CA<5>")
	)
	(segment
		(start 308.70017 -264.16508)
		(end 323.861684 -264.16508)
		(width 0.14478)
		(layer "In13.Cu")
		(net "M_B_CPU0_SB_CA<5>")
	)
	(segment
		(start 328.709782 -264.038588)
		(end 328.718164 -264.043414)
		(width 0.0889)
		(layer "In13.Cu")
		(net "M_B_CPU0_SB_CA<5>")
	)
	(segment
		(start 296.098468 -264.910062)
		(end 307.955188 -264.910062)
		(width 0.14478)
		(layer "In13.Cu")
		(net "M_B_CPU0_SB_CA<5>")
	)
	(segment
		(start 328.32929 -264.05205)
		(end 328.344022 -264.043414)
		(width 0.0889)
		(layer "In13.Cu")
		(net "M_B_CPU0_SB_CA<5>")
	)
	(segment
		(start 323.861684 -264.16508)
		(end 324.12813 -264.16508)
		(width 0.0889)
		(layer "In13.Cu")
		(net "M_B_CPU0_SB_CA<5>")
	)
	(segment
		(start 333.984092 -264.043414)
		(end 333.992474 -264.038588)
		(width 0.0889)
		(layer "In13.Cu")
		(net "M_B_CPU0_SB_CA<5>")
	)
	(segment
		(start 337.145122 -264.100564)
		(end 336.991198 -264.365994)
		(width 0.0889)
		(layer "In13.Cu")
		(net "M_B_CPU0_SB_CA<5>")
	)
	(segment
		(start 295.724072 -265.335004)
		(end 295.724072 -265.284458)
		(width 0.14478)
		(layer "In13.Cu")
		(net "M_B_CPU0_SB_CA<5>")
	)
	(segment
		(start 333.044038 -264.043414)
		(end 333.05242 -264.038588)
		(width 0.0889)
		(layer "In13.Cu")
		(net "M_B_CPU0_SB_CA<5>")
	)
	(segment
		(start 307.955188 -264.910062)
		(end 308.70017 -264.16508)
		(width 0.14478)
		(layer "In13.Cu")
		(net "M_B_CPU0_SB_CA<5>")
	)
	(segment
		(start 324.12813 -264.16508)
		(end 324.300596 -263.992614)
		(width 0.0889)
		(layer "In13.Cu")
		(net "M_B_CPU0_SB_CA<5>")
	)
	(segment
		(start 337.12277 -264.017252)
		(end 337.145122 -264.100564)
		(width 0.0889)
		(layer "In13.Cu")
		(net "M_B_CPU0_SB_CA<5>")
	)
	(segment
		(start 295.724072 -265.284458)
		(end 296.098468 -264.910062)
		(width 0.14478)
		(layer "In13.Cu")
		(net "M_B_CPU0_SB_CA<5>")
	)
	(segment
		(start 332.469744 -264.038588)
		(end 332.478126 -264.043414)
		(width 0.0889)
		(layer "In13.Cu")
		(net "M_B_CPU0_SB_CA<5>")
	)
	(arc
		(start 328.718164 -264.043414)
		(mid 329.00112 -264.119591)
		(end 329.284076 -264.043414)
		(width 0.0889)
		(layer "In13.Cu")
		(net "M_B_CPU0_SB_CA<5>")
	)
	(arc
		(start 327.589896 -263.992614)
		(mid 327.687121 -264.005563)
		(end 327.777602 -264.043414)
		(width 0.0889)
		(layer "In13.Cu")
		(net "M_B_CPU0_SB_CA<5>")
	)
	(arc
		(start 333.41818 -264.043414)
		(mid 333.701136 -264.119591)
		(end 333.984092 -264.043414)
		(width 0.0889)
		(layer "In13.Cu")
		(net "M_B_CPU0_SB_CA<5>")
	)
	(arc
		(start 336.238088 -264.043414)
		(mid 336.521044 -264.119591)
		(end 336.804 -264.043414)
		(width 0.0889)
		(layer "In13.Cu")
		(net "M_B_CPU0_SB_CA<5>")
	)
	(arc
		(start 332.478126 -264.043414)
		(mid 332.761082 -264.119591)
		(end 333.044038 -264.043414)
		(width 0.0889)
		(layer "In13.Cu")
		(net "M_B_CPU0_SB_CA<5>")
	)
	(arc
		(start 332.103984 -264.043414)
		(mid 332.286235 -263.993064)
		(end 332.469744 -264.038588)
		(width 0.0889)
		(layer "In13.Cu")
		(net "M_B_CPU0_SB_CA<5>")
	)
	(arc
		(start 330.598018 -264.043414)
		(mid 330.880974 -264.119591)
		(end 331.16393 -264.043414)
		(width 0.0889)
		(layer "In13.Cu")
		(net "M_B_CPU0_SB_CA<5>")
	)
	(arc
		(start 336.804 -264.043414)
		(mid 336.960438 -263.994443)
		(end 337.12277 -264.017252)
		(width 0.0889)
		(layer "In13.Cu")
		(net "M_B_CPU0_SB_CA<5>")
	)
	(arc
		(start 328.344022 -264.043414)
		(mid 328.526273 -263.993064)
		(end 328.709782 -264.038588)
		(width 0.0889)
		(layer "In13.Cu")
		(net "M_B_CPU0_SB_CA<5>")
	)
	(arc
		(start 329.658218 -264.043414)
		(mid 329.941174 -264.119591)
		(end 330.22413 -264.043414)
		(width 0.0889)
		(layer "In13.Cu")
		(net "M_B_CPU0_SB_CA<5>")
	)
	(arc
		(start 327.777602 -264.043414)
		(mid 328.052308 -264.119778)
		(end 328.32929 -264.05205)
		(width 0.0889)
		(layer "In13.Cu")
		(net "M_B_CPU0_SB_CA<5>")
	)
	(arc
		(start 329.292458 -264.038588)
		(mid 329.475966 -263.993094)
		(end 329.658218 -264.043414)
		(width 0.0889)
		(layer "In13.Cu")
		(net "M_B_CPU0_SB_CA<5>")
	)
	(arc
		(start 331.538072 -264.043414)
		(mid 331.821028 -264.119591)
		(end 332.103984 -264.043414)
		(width 0.0889)
		(layer "In13.Cu")
		(net "M_B_CPU0_SB_CA<5>")
	)
	(arc
		(start 330.22413 -264.043414)
		(mid 330.411074 -263.993159)
		(end 330.598018 -264.043414)
		(width 0.0889)
		(layer "In13.Cu")
		(net "M_B_CPU0_SB_CA<5>")
	)
	(arc
		(start 335.298034 -264.043414)
		(mid 335.58099 -264.119591)
		(end 335.863946 -264.043414)
		(width 0.0889)
		(layer "In13.Cu")
		(net "M_B_CPU0_SB_CA<5>")
	)
	(arc
		(start 331.16393 -264.043414)
		(mid 331.346181 -263.993064)
		(end 331.52969 -264.038588)
		(width 0.0889)
		(layer "In13.Cu")
		(net "M_B_CPU0_SB_CA<5>")
	)
	(arc
		(start 335.863946 -264.043414)
		(mid 336.046197 -263.993064)
		(end 336.229706 -264.038588)
		(width 0.0889)
		(layer "In13.Cu")
		(net "M_B_CPU0_SB_CA<5>")
	)
	(arc
		(start 334.358234 -264.043414)
		(mid 334.64119 -264.119591)
		(end 334.924146 -264.043414)
		(width 0.0889)
		(layer "In13.Cu")
		(net "M_B_CPU0_SB_CA<5>")
	)
	(arc
		(start 333.992474 -264.038588)
		(mid 334.175982 -263.993094)
		(end 334.358234 -264.043414)
		(width 0.0889)
		(layer "In13.Cu")
		(net "M_B_CPU0_SB_CA<5>")
	)
	(arc
		(start 333.05242 -264.038588)
		(mid 333.235928 -263.993094)
		(end 333.41818 -264.043414)
		(width 0.0889)
		(layer "In13.Cu")
		(net "M_B_CPU0_SB_CA<5>")
	)
	(arc
		(start 334.924146 -264.043414)
		(mid 335.11109 -263.993159)
		(end 335.298034 -264.043414)
		(width 0.0889)
		(layer "In13.Cu")
		(net "M_B_CPU0_SB_CA<5>")
	)
	(segment
		(start 337.92795 -263.29005)
		(end 337.461098 -263.555988)
		(width 0.10668)
		(layer "F.Cu")
		(net "M_B_CPU0_SB_CA<4>")
	)
	(segment
		(start 306.584604 -264.37971)
		(end 306.90439 -264.059924)
		(width 0.14478)
		(layer "In13.Cu")
		(net "M_B_CPU0_SB_CA<4>")
	)
	(segment
		(start 304.915824 -264.059924)
		(end 305.23561 -264.37971)
		(width 0.14478)
		(layer "In13.Cu")
		(net "M_B_CPU0_SB_CA<4>")
	)
	(segment
		(start 334.819752 -263.883394)
		(end 334.828134 -263.878568)
		(width 0.0889)
		(layer "In13.Cu")
		(net "M_B_CPU0_SB_CA<4>")
	)
	(segment
		(start 337.211162 -263.846818)
		(end 337.307174 -263.821418)
		(width 0.0889)
		(layer "In13.Cu")
		(net "M_B_CPU0_SB_CA<4>")
	)
	(segment
		(start 299.82414 -264.48512)
		(end 299.82414 -264.315702)
		(width 0.14478)
		(layer "In13.Cu")
		(net "M_B_CPU0_SB_CA<4>")
	)
	(segment
		(start 328.239882 -263.883394)
		(end 328.248264 -263.878568)
		(width 0.0889)
		(layer "In13.Cu")
		(net "M_B_CPU0_SB_CA<4>")
	)
	(segment
		(start 301.12081 -264.442448)
		(end 301.26559 -264.297668)
		(width 0.14478)
		(layer "In13.Cu")
		(net "M_B_CPU0_SB_CA<4>")
	)
	(segment
		(start 307.697124 -264.37971)
		(end 308.366414 -263.71042)
		(width 0.14478)
		(layer "In13.Cu")
		(net "M_B_CPU0_SB_CA<4>")
	)
	(segment
		(start 306.34813 -264.37971)
		(end 306.584604 -264.37971)
		(width 0.14478)
		(layer "In13.Cu")
		(net "M_B_CPU0_SB_CA<4>")
	)
	(segment
		(start 301.81677 -264.297668)
		(end 301.96155 -264.442448)
		(width 0.14478)
		(layer "In13.Cu")
		(net "M_B_CPU0_SB_CA<4>")
	)
	(segment
		(start 333.879698 -263.883394)
		(end 333.88808 -263.878568)
		(width 0.0889)
		(layer "In13.Cu")
		(net "M_B_CPU0_SB_CA<4>")
	)
	(segment
		(start 324.943978 -263.802114)
		(end 327.59015 -263.802114)
		(width 0.0889)
		(layer "In13.Cu")
		(net "M_B_CPU0_SB_CA<4>")
	)
	(segment
		(start 300.56963 -264.059924)
		(end 300.71441 -264.204704)
		(width 0.14478)
		(layer "In13.Cu")
		(net "M_B_CPU0_SB_CA<4>")
	)
	(segment
		(start 335.394046 -263.878568)
		(end 335.402428 -263.883394)
		(width 0.0889)
		(layer "In13.Cu")
		(net "M_B_CPU0_SB_CA<4>")
	)
	(segment
		(start 299.82414 -264.315702)
		(end 300.079918 -264.059924)
		(width 0.14478)
		(layer "In13.Cu")
		(net "M_B_CPU0_SB_CA<4>")
	)
	(segment
		(start 302.22317 -264.442448)
		(end 302.36795 -264.297668)
		(width 0.14478)
		(layer "In13.Cu")
		(net "M_B_CPU0_SB_CA<4>")
	)
	(segment
		(start 300.71441 -264.204704)
		(end 300.71441 -264.297668)
		(width 0.14478)
		(layer "In13.Cu")
		(net "M_B_CPU0_SB_CA<4>")
	)
	(segment
		(start 305.23561 -264.37971)
		(end 305.472084 -264.37971)
		(width 0.14478)
		(layer "In13.Cu")
		(net "M_B_CPU0_SB_CA<4>")
	)
	(segment
		(start 306.90439 -264.059924)
		(end 307.140864 -264.059924)
		(width 0.14478)
		(layer "In13.Cu")
		(net "M_B_CPU0_SB_CA<4>")
	)
	(segment
		(start 337.307174 -263.821418)
		(end 337.461098 -263.555988)
		(width 0.0889)
		(layer "In13.Cu")
		(net "M_B_CPU0_SB_CA<4>")
	)
	(segment
		(start 300.85919 -264.442448)
		(end 301.12081 -264.442448)
		(width 0.14478)
		(layer "In13.Cu")
		(net "M_B_CPU0_SB_CA<4>")
	)
	(segment
		(start 301.26559 -264.297668)
		(end 301.26559 -264.204704)
		(width 0.14478)
		(layer "In13.Cu")
		(net "M_B_CPU0_SB_CA<4>")
	)
	(segment
		(start 301.96155 -264.442448)
		(end 302.22317 -264.442448)
		(width 0.14478)
		(layer "In13.Cu")
		(net "M_B_CPU0_SB_CA<4>")
	)
	(segment
		(start 304.67935 -264.059924)
		(end 304.915824 -264.059924)
		(width 0.14478)
		(layer "In13.Cu")
		(net "M_B_CPU0_SB_CA<4>")
	)
	(segment
		(start 300.71441 -264.297668)
		(end 300.85919 -264.442448)
		(width 0.14478)
		(layer "In13.Cu")
		(net "M_B_CPU0_SB_CA<4>")
	)
	(segment
		(start 301.81677 -264.204704)
		(end 301.81677 -264.297668)
		(width 0.14478)
		(layer "In13.Cu")
		(net "M_B_CPU0_SB_CA<4>")
	)
	(segment
		(start 302.51273 -264.059924)
		(end 303.803304 -264.059924)
		(width 0.14478)
		(layer "In13.Cu")
		(net "M_B_CPU0_SB_CA<4>")
	)
	(segment
		(start 308.366414 -263.71042)
		(end 323.892164 -263.71042)
		(width 0.14478)
		(layer "In13.Cu")
		(net "M_B_CPU0_SB_CA<4>")
	)
	(segment
		(start 330.69403 -263.878568)
		(end 330.702412 -263.883394)
		(width 0.0889)
		(layer "In13.Cu")
		(net "M_B_CPU0_SB_CA<4>")
	)
	(segment
		(start 336.3341 -263.878568)
		(end 336.342482 -263.883394)
		(width 0.0889)
		(layer "In13.Cu")
		(net "M_B_CPU0_SB_CA<4>")
	)
	(segment
		(start 323.892164 -263.71042)
		(end 324.852284 -263.71042)
		(width 0.0889)
		(layer "In13.Cu")
		(net "M_B_CPU0_SB_CA<4>")
	)
	(segment
		(start 305.79187 -264.059924)
		(end 306.028344 -264.059924)
		(width 0.14478)
		(layer "In13.Cu")
		(net "M_B_CPU0_SB_CA<4>")
	)
	(segment
		(start 300.079918 -264.059924)
		(end 300.56963 -264.059924)
		(width 0.14478)
		(layer "In13.Cu")
		(net "M_B_CPU0_SB_CA<4>")
	)
	(segment
		(start 331.634084 -263.878568)
		(end 331.642466 -263.883394)
		(width 0.0889)
		(layer "In13.Cu")
		(net "M_B_CPU0_SB_CA<4>")
	)
	(segment
		(start 302.36795 -264.297668)
		(end 302.36795 -264.204704)
		(width 0.14478)
		(layer "In13.Cu")
		(net "M_B_CPU0_SB_CA<4>")
	)
	(segment
		(start 303.803304 -264.059924)
		(end 304.12309 -264.37971)
		(width 0.14478)
		(layer "In13.Cu")
		(net "M_B_CPU0_SB_CA<4>")
	)
	(segment
		(start 324.852284 -263.71042)
		(end 324.943978 -263.802114)
		(width 0.0889)
		(layer "In13.Cu")
		(net "M_B_CPU0_SB_CA<4>")
	)
	(segment
		(start 307.46065 -264.37971)
		(end 307.697124 -264.37971)
		(width 0.14478)
		(layer "In13.Cu")
		(net "M_B_CPU0_SB_CA<4>")
	)
	(segment
		(start 301.26559 -264.204704)
		(end 301.41037 -264.059924)
		(width 0.14478)
		(layer "In13.Cu")
		(net "M_B_CPU0_SB_CA<4>")
	)
	(segment
		(start 304.359564 -264.37971)
		(end 304.67935 -264.059924)
		(width 0.14478)
		(layer "In13.Cu")
		(net "M_B_CPU0_SB_CA<4>")
	)
	(segment
		(start 307.140864 -264.059924)
		(end 307.46065 -264.37971)
		(width 0.14478)
		(layer "In13.Cu")
		(net "M_B_CPU0_SB_CA<4>")
	)
	(segment
		(start 304.12309 -264.37971)
		(end 304.359564 -264.37971)
		(width 0.14478)
		(layer "In13.Cu")
		(net "M_B_CPU0_SB_CA<4>")
	)
	(segment
		(start 301.67199 -264.059924)
		(end 301.81677 -264.204704)
		(width 0.14478)
		(layer "In13.Cu")
		(net "M_B_CPU0_SB_CA<4>")
	)
	(segment
		(start 301.41037 -264.059924)
		(end 301.67199 -264.059924)
		(width 0.14478)
		(layer "In13.Cu")
		(net "M_B_CPU0_SB_CA<4>")
	)
	(segment
		(start 302.36795 -264.204704)
		(end 302.51273 -264.059924)
		(width 0.14478)
		(layer "In13.Cu")
		(net "M_B_CPU0_SB_CA<4>")
	)
	(segment
		(start 330.119736 -263.883394)
		(end 330.128118 -263.878568)
		(width 0.0889)
		(layer "In13.Cu")
		(net "M_B_CPU0_SB_CA<4>")
	)
	(segment
		(start 305.472084 -264.37971)
		(end 305.79187 -264.059924)
		(width 0.14478)
		(layer "In13.Cu")
		(net "M_B_CPU0_SB_CA<4>")
	)
	(segment
		(start 306.028344 -264.059924)
		(end 306.34813 -264.37971)
		(width 0.14478)
		(layer "In13.Cu")
		(net "M_B_CPU0_SB_CA<4>")
	)
	(arc
		(start 332.008226 -263.878568)
		(mid 332.291182 -263.802391)
		(end 332.574138 -263.878568)
		(width 0.0889)
		(layer "In13.Cu")
		(net "M_B_CPU0_SB_CA<4>")
	)
	(arc
		(start 328.814176 -263.878568)
		(mid 329.00112 -263.928823)
		(end 329.188064 -263.878568)
		(width 0.0889)
		(layer "In13.Cu")
		(net "M_B_CPU0_SB_CA<4>")
	)
	(arc
		(start 330.128118 -263.878568)
		(mid 330.411074 -263.802391)
		(end 330.69403 -263.878568)
		(width 0.0889)
		(layer "In13.Cu")
		(net "M_B_CPU0_SB_CA<4>")
	)
	(arc
		(start 334.828134 -263.878568)
		(mid 335.11109 -263.802391)
		(end 335.394046 -263.878568)
		(width 0.0889)
		(layer "In13.Cu")
		(net "M_B_CPU0_SB_CA<4>")
	)
	(arc
		(start 335.768188 -263.878568)
		(mid 336.051144 -263.802391)
		(end 336.3341 -263.878568)
		(width 0.0889)
		(layer "In13.Cu")
		(net "M_B_CPU0_SB_CA<4>")
	)
	(arc
		(start 335.402428 -263.883394)
		(mid 335.585936 -263.928888)
		(end 335.768188 -263.878568)
		(width 0.0889)
		(layer "In13.Cu")
		(net "M_B_CPU0_SB_CA<4>")
	)
	(arc
		(start 327.59015 -263.802114)
		(mid 327.73695 -263.821558)
		(end 327.873614 -263.878568)
		(width 0.0889)
		(layer "In13.Cu")
		(net "M_B_CPU0_SB_CA<4>")
	)
	(arc
		(start 334.453992 -263.878568)
		(mid 334.636243 -263.928918)
		(end 334.819752 -263.883394)
		(width 0.0889)
		(layer "In13.Cu")
		(net "M_B_CPU0_SB_CA<4>")
	)
	(arc
		(start 331.068172 -263.878568)
		(mid 331.351128 -263.802391)
		(end 331.634084 -263.878568)
		(width 0.0889)
		(layer "In13.Cu")
		(net "M_B_CPU0_SB_CA<4>")
	)
	(arc
		(start 328.248264 -263.878568)
		(mid 328.53122 -263.802391)
		(end 328.814176 -263.878568)
		(width 0.0889)
		(layer "In13.Cu")
		(net "M_B_CPU0_SB_CA<4>")
	)
	(arc
		(start 332.948026 -263.878568)
		(mid 333.230982 -263.802391)
		(end 333.513938 -263.878568)
		(width 0.0889)
		(layer "In13.Cu")
		(net "M_B_CPU0_SB_CA<4>")
	)
	(arc
		(start 329.188064 -263.878568)
		(mid 329.47102 -263.802391)
		(end 329.753976 -263.878568)
		(width 0.0889)
		(layer "In13.Cu")
		(net "M_B_CPU0_SB_CA<4>")
	)
	(arc
		(start 329.753976 -263.878568)
		(mid 329.936227 -263.928918)
		(end 330.119736 -263.883394)
		(width 0.0889)
		(layer "In13.Cu")
		(net "M_B_CPU0_SB_CA<4>")
	)
	(arc
		(start 336.708242 -263.878568)
		(mid 336.955955 -263.803348)
		(end 337.211162 -263.846818)
		(width 0.0889)
		(layer "In13.Cu")
		(net "M_B_CPU0_SB_CA<4>")
	)
	(arc
		(start 333.88808 -263.878568)
		(mid 334.171036 -263.802391)
		(end 334.453992 -263.878568)
		(width 0.0889)
		(layer "In13.Cu")
		(net "M_B_CPU0_SB_CA<4>")
	)
	(arc
		(start 331.642466 -263.883394)
		(mid 331.825974 -263.928888)
		(end 332.008226 -263.878568)
		(width 0.0889)
		(layer "In13.Cu")
		(net "M_B_CPU0_SB_CA<4>")
	)
	(arc
		(start 333.513938 -263.878568)
		(mid 333.696189 -263.928918)
		(end 333.879698 -263.883394)
		(width 0.0889)
		(layer "In13.Cu")
		(net "M_B_CPU0_SB_CA<4>")
	)
	(arc
		(start 330.702412 -263.883394)
		(mid 330.88592 -263.928888)
		(end 331.068172 -263.878568)
		(width 0.0889)
		(layer "In13.Cu")
		(net "M_B_CPU0_SB_CA<4>")
	)
	(arc
		(start 327.873614 -263.878568)
		(mid 328.056119 -263.929045)
		(end 328.239882 -263.883394)
		(width 0.0889)
		(layer "In13.Cu")
		(net "M_B_CPU0_SB_CA<4>")
	)
	(arc
		(start 332.574138 -263.878568)
		(mid 332.761082 -263.928823)
		(end 332.948026 -263.878568)
		(width 0.0889)
		(layer "In13.Cu")
		(net "M_B_CPU0_SB_CA<4>")
	)
	(arc
		(start 336.342482 -263.883394)
		(mid 336.52599 -263.928888)
		(end 336.708242 -263.878568)
		(width 0.0889)
		(layer "In13.Cu")
		(net "M_B_CPU0_SB_CA<4>")
	)
	(segment
		(start 336.047842 -263.29005)
		(end 335.58099 -263.555988)
		(width 0.10668)
		(layer "F.Cu")
		(net "M_B_CPU0_SB_CA<3>")
	)
	(segment
		(start 295.724072 -263.634982)
		(end 295.81602 -263.634982)
		(width 0.14478)
		(layer "In13.Cu")
		(net "M_B_CPU0_SB_CA<3>")
	)
	(segment
		(start 334.819752 -263.228582)
		(end 334.828134 -263.233408)
		(width 0.0889)
		(layer "In13.Cu")
		(net "M_B_CPU0_SB_CA<3>")
	)
	(segment
		(start 330.69403 -263.233408)
		(end 330.702412 -263.228582)
		(width 0.0889)
		(layer "In13.Cu")
		(net "M_B_CPU0_SB_CA<3>")
	)
	(segment
		(start 324.39737 -263.21004)
		(end 324.712838 -262.894572)
		(width 0.0889)
		(layer "In13.Cu")
		(net "M_B_CPU0_SB_CA<3>")
	)
	(segment
		(start 296.240962 -263.21004)
		(end 323.903594 -263.21004)
		(width 0.14478)
		(layer "In13.Cu")
		(net "M_B_CPU0_SB_CA<3>")
	)
	(segment
		(start 335.735168 -263.290558)
		(end 335.58099 -263.555988)
		(width 0.0889)
		(layer "In13.Cu")
		(net "M_B_CPU0_SB_CA<3>")
	)
	(segment
		(start 295.81602 -263.634982)
		(end 296.240962 -263.21004)
		(width 0.14478)
		(layer "In13.Cu")
		(net "M_B_CPU0_SB_CA<3>")
	)
	(segment
		(start 323.903594 -263.21004)
		(end 324.39737 -263.21004)
		(width 0.0889)
		(layer "In13.Cu")
		(net "M_B_CPU0_SB_CA<3>")
	)
	(segment
		(start 330.119736 -263.228582)
		(end 330.128118 -263.233408)
		(width 0.0889)
		(layer "In13.Cu")
		(net "M_B_CPU0_SB_CA<3>")
	)
	(segment
		(start 335.394046 -263.233408)
		(end 335.402428 -263.228582)
		(width 0.0889)
		(layer "In13.Cu")
		(net "M_B_CPU0_SB_CA<3>")
	)
	(segment
		(start 335.712816 -263.207246)
		(end 335.735168 -263.290558)
		(width 0.0889)
		(layer "In13.Cu")
		(net "M_B_CPU0_SB_CA<3>")
	)
	(segment
		(start 325.523098 -262.894572)
		(end 325.938134 -263.309608)
		(width 0.0889)
		(layer "In13.Cu")
		(net "M_B_CPU0_SB_CA<3>")
	)
	(segment
		(start 328.239882 -263.228582)
		(end 328.248264 -263.233408)
		(width 0.0889)
		(layer "In13.Cu")
		(net "M_B_CPU0_SB_CA<3>")
	)
	(segment
		(start 324.712838 -262.894572)
		(end 325.523098 -262.894572)
		(width 0.0889)
		(layer "In13.Cu")
		(net "M_B_CPU0_SB_CA<3>")
	)
	(segment
		(start 325.938134 -263.309608)
		(end 327.590404 -263.309608)
		(width 0.0889)
		(layer "In13.Cu")
		(net "M_B_CPU0_SB_CA<3>")
	)
	(segment
		(start 333.879698 -263.228582)
		(end 333.88808 -263.233408)
		(width 0.0889)
		(layer "In13.Cu")
		(net "M_B_CPU0_SB_CA<3>")
	)
	(segment
		(start 331.634084 -263.233408)
		(end 331.642466 -263.228582)
		(width 0.0889)
		(layer "In13.Cu")
		(net "M_B_CPU0_SB_CA<3>")
	)
	(arc
		(start 329.753976 -263.233408)
		(mid 329.936227 -263.183058)
		(end 330.119736 -263.228582)
		(width 0.0889)
		(layer "In13.Cu")
		(net "M_B_CPU0_SB_CA<3>")
	)
	(arc
		(start 331.068172 -263.233408)
		(mid 331.351128 -263.309585)
		(end 331.634084 -263.233408)
		(width 0.0889)
		(layer "In13.Cu")
		(net "M_B_CPU0_SB_CA<3>")
	)
	(arc
		(start 335.402428 -263.228582)
		(mid 335.555298 -263.183941)
		(end 335.712816 -263.207246)
		(width 0.0889)
		(layer "In13.Cu")
		(net "M_B_CPU0_SB_CA<3>")
	)
	(arc
		(start 330.128118 -263.233408)
		(mid 330.411074 -263.309585)
		(end 330.69403 -263.233408)
		(width 0.0889)
		(layer "In13.Cu")
		(net "M_B_CPU0_SB_CA<3>")
	)
	(arc
		(start 328.814176 -263.233408)
		(mid 329.00112 -263.183153)
		(end 329.188064 -263.233408)
		(width 0.0889)
		(layer "In13.Cu")
		(net "M_B_CPU0_SB_CA<3>")
	)
	(arc
		(start 327.590404 -263.309608)
		(mid 327.737061 -263.290271)
		(end 327.873614 -263.233408)
		(width 0.0889)
		(layer "In13.Cu")
		(net "M_B_CPU0_SB_CA<3>")
	)
	(arc
		(start 328.248264 -263.233408)
		(mid 328.53122 -263.309585)
		(end 328.814176 -263.233408)
		(width 0.0889)
		(layer "In13.Cu")
		(net "M_B_CPU0_SB_CA<3>")
	)
	(arc
		(start 327.873614 -263.233408)
		(mid 328.056119 -263.182931)
		(end 328.239882 -263.228582)
		(width 0.0889)
		(layer "In13.Cu")
		(net "M_B_CPU0_SB_CA<3>")
	)
	(arc
		(start 332.948026 -263.233408)
		(mid 333.230982 -263.309585)
		(end 333.513938 -263.233408)
		(width 0.0889)
		(layer "In13.Cu")
		(net "M_B_CPU0_SB_CA<3>")
	)
	(arc
		(start 332.574138 -263.233408)
		(mid 332.761082 -263.183153)
		(end 332.948026 -263.233408)
		(width 0.0889)
		(layer "In13.Cu")
		(net "M_B_CPU0_SB_CA<3>")
	)
	(arc
		(start 330.702412 -263.228582)
		(mid 330.88592 -263.183088)
		(end 331.068172 -263.233408)
		(width 0.0889)
		(layer "In13.Cu")
		(net "M_B_CPU0_SB_CA<3>")
	)
	(arc
		(start 332.008226 -263.233408)
		(mid 332.291182 -263.309585)
		(end 332.574138 -263.233408)
		(width 0.0889)
		(layer "In13.Cu")
		(net "M_B_CPU0_SB_CA<3>")
	)
	(arc
		(start 334.453992 -263.233408)
		(mid 334.636243 -263.183058)
		(end 334.819752 -263.228582)
		(width 0.0889)
		(layer "In13.Cu")
		(net "M_B_CPU0_SB_CA<3>")
	)
	(arc
		(start 334.828134 -263.233408)
		(mid 335.11109 -263.309585)
		(end 335.394046 -263.233408)
		(width 0.0889)
		(layer "In13.Cu")
		(net "M_B_CPU0_SB_CA<3>")
	)
	(arc
		(start 333.88808 -263.233408)
		(mid 334.171036 -263.309585)
		(end 334.453992 -263.233408)
		(width 0.0889)
		(layer "In13.Cu")
		(net "M_B_CPU0_SB_CA<3>")
	)
	(arc
		(start 331.642466 -263.228582)
		(mid 331.825974 -263.183088)
		(end 332.008226 -263.233408)
		(width 0.0889)
		(layer "In13.Cu")
		(net "M_B_CPU0_SB_CA<3>")
	)
	(arc
		(start 329.188064 -263.233408)
		(mid 329.47102 -263.309585)
		(end 329.753976 -263.233408)
		(width 0.0889)
		(layer "In13.Cu")
		(net "M_B_CPU0_SB_CA<3>")
	)
	(arc
		(start 333.513938 -263.233408)
		(mid 333.696189 -263.183058)
		(end 333.879698 -263.228582)
		(width 0.0889)
		(layer "In13.Cu")
		(net "M_B_CPU0_SB_CA<3>")
	)
	(segment
		(start 336.517996 -262.480044)
		(end 336.051144 -262.745982)
		(width 0.10668)
		(layer "F.Cu")
		(net "M_B_CPU0_SB_CA<2>")
	)
	(segment
		(start 307.06695 -262.367268)
		(end 307.312568 -262.367268)
		(width 0.14478)
		(layer "In13.Cu")
		(net "M_B_CPU0_SB_CA<2>")
	)
	(segment
		(start 300.423072 -262.006334)
		(end 300.854872 -262.006334)
		(width 0.14478)
		(layer "In13.Cu")
		(net "M_B_CPU0_SB_CA<2>")
	)
	(segment
		(start 332.469744 -263.073388)
		(end 332.478126 -263.068562)
		(width 0.0889)
		(layer "In13.Cu")
		(net "M_B_CPU0_SB_CA<2>")
	)
	(segment
		(start 304.28565 -262.67791)
		(end 304.531268 -262.67791)
		(width 0.14478)
		(layer "In13.Cu")
		(net "M_B_CPU0_SB_CA<2>")
	)
	(segment
		(start 300.999652 -262.151114)
		(end 300.999652 -262.521446)
		(width 0.14478)
		(layer "In13.Cu")
		(net "M_B_CPU0_SB_CA<2>")
	)
	(segment
		(start 301.550832 -262.521446)
		(end 301.550832 -262.151114)
		(width 0.14478)
		(layer "In13.Cu")
		(net "M_B_CPU0_SB_CA<2>")
	)
	(segment
		(start 300.999652 -262.521446)
		(end 301.144432 -262.666226)
		(width 0.14478)
		(layer "In13.Cu")
		(net "M_B_CPU0_SB_CA<2>")
	)
	(segment
		(start 305.39817 -262.67791)
		(end 305.643788 -262.67791)
		(width 0.14478)
		(layer "In13.Cu")
		(net "M_B_CPU0_SB_CA<2>")
	)
	(segment
		(start 323.86905 -262.755126)
		(end 324.369684 -262.755126)
		(width 0.0889)
		(layer "In13.Cu")
		(net "M_B_CPU0_SB_CA<2>")
	)
	(segment
		(start 305.95443 -262.367268)
		(end 306.200048 -262.367268)
		(width 0.14478)
		(layer "In13.Cu")
		(net "M_B_CPU0_SB_CA<2>")
	)
	(segment
		(start 301.406052 -262.666226)
		(end 301.550832 -262.521446)
		(width 0.14478)
		(layer "In13.Cu")
		(net "M_B_CPU0_SB_CA<2>")
	)
	(segment
		(start 299.82414 -262.605266)
		(end 300.423072 -262.006334)
		(width 0.14478)
		(layer "In13.Cu")
		(net "M_B_CPU0_SB_CA<2>")
	)
	(segment
		(start 325.764906 -262.692134)
		(end 326.19188 -263.119108)
		(width 0.0889)
		(layer "In13.Cu")
		(net "M_B_CPU0_SB_CA<2>")
	)
	(segment
		(start 301.695612 -262.006334)
		(end 301.957232 -262.006334)
		(width 0.14478)
		(layer "In13.Cu")
		(net "M_B_CPU0_SB_CA<2>")
	)
	(segment
		(start 301.550832 -262.151114)
		(end 301.695612 -262.006334)
		(width 0.14478)
		(layer "In13.Cu")
		(net "M_B_CPU0_SB_CA<2>")
	)
	(segment
		(start 305.087528 -262.367268)
		(end 305.39817 -262.67791)
		(width 0.14478)
		(layer "In13.Cu")
		(net "M_B_CPU0_SB_CA<2>")
	)
	(segment
		(start 304.531268 -262.67791)
		(end 304.84191 -262.367268)
		(width 0.14478)
		(layer "In13.Cu")
		(net "M_B_CPU0_SB_CA<2>")
	)
	(segment
		(start 306.200048 -262.367268)
		(end 306.51069 -262.67791)
		(width 0.14478)
		(layer "In13.Cu")
		(net "M_B_CPU0_SB_CA<2>")
	)
	(segment
		(start 301.957232 -262.006334)
		(end 302.102012 -262.151114)
		(width 0.14478)
		(layer "In13.Cu")
		(net "M_B_CPU0_SB_CA<2>")
	)
	(segment
		(start 335.8007 -263.036812)
		(end 335.896966 -263.011412)
		(width 0.0889)
		(layer "In13.Cu")
		(net "M_B_CPU0_SB_CA<2>")
	)
	(segment
		(start 301.144432 -262.666226)
		(end 301.406052 -262.666226)
		(width 0.14478)
		(layer "In13.Cu")
		(net "M_B_CPU0_SB_CA<2>")
	)
	(segment
		(start 302.102012 -262.151114)
		(end 302.102012 -262.521446)
		(width 0.14478)
		(layer "In13.Cu")
		(net "M_B_CPU0_SB_CA<2>")
	)
	(segment
		(start 328.333608 -263.062466)
		(end 328.344022 -263.068562)
		(width 0.0889)
		(layer "In13.Cu")
		(net "M_B_CPU0_SB_CA<2>")
	)
	(segment
		(start 306.756308 -262.67791)
		(end 307.06695 -262.367268)
		(width 0.14478)
		(layer "In13.Cu")
		(net "M_B_CPU0_SB_CA<2>")
	)
	(segment
		(start 302.653192 -262.521446)
		(end 302.653192 -262.151114)
		(width 0.14478)
		(layer "In13.Cu")
		(net "M_B_CPU0_SB_CA<2>")
	)
	(segment
		(start 306.51069 -262.67791)
		(end 306.756308 -262.67791)
		(width 0.14478)
		(layer "In13.Cu")
		(net "M_B_CPU0_SB_CA<2>")
	)
	(segment
		(start 302.653192 -262.151114)
		(end 302.797972 -262.006334)
		(width 0.14478)
		(layer "In13.Cu")
		(net "M_B_CPU0_SB_CA<2>")
	)
	(segment
		(start 324.369684 -262.755126)
		(end 324.432676 -262.692134)
		(width 0.0889)
		(layer "In13.Cu")
		(net "M_B_CPU0_SB_CA<2>")
	)
	(segment
		(start 328.709782 -263.073388)
		(end 328.718164 -263.068562)
		(width 0.0889)
		(layer "In13.Cu")
		(net "M_B_CPU0_SB_CA<2>")
	)
	(segment
		(start 305.643788 -262.67791)
		(end 305.95443 -262.367268)
		(width 0.14478)
		(layer "In13.Cu")
		(net "M_B_CPU0_SB_CA<2>")
	)
	(segment
		(start 302.508412 -262.666226)
		(end 302.653192 -262.521446)
		(width 0.14478)
		(layer "In13.Cu")
		(net "M_B_CPU0_SB_CA<2>")
	)
	(segment
		(start 335.896966 -263.011412)
		(end 336.051144 -262.745982)
		(width 0.0889)
		(layer "In13.Cu")
		(net "M_B_CPU0_SB_CA<2>")
	)
	(segment
		(start 302.246792 -262.666226)
		(end 302.508412 -262.666226)
		(width 0.14478)
		(layer "In13.Cu")
		(net "M_B_CPU0_SB_CA<2>")
	)
	(segment
		(start 302.797972 -262.006334)
		(end 303.614074 -262.006334)
		(width 0.14478)
		(layer "In13.Cu")
		(net "M_B_CPU0_SB_CA<2>")
	)
	(segment
		(start 326.19188 -263.119108)
		(end 327.590658 -263.119108)
		(width 0.0889)
		(layer "In13.Cu")
		(net "M_B_CPU0_SB_CA<2>")
	)
	(segment
		(start 303.614074 -262.006334)
		(end 304.28565 -262.67791)
		(width 0.14478)
		(layer "In13.Cu")
		(net "M_B_CPU0_SB_CA<2>")
	)
	(segment
		(start 324.432676 -262.692134)
		(end 325.764906 -262.692134)
		(width 0.0889)
		(layer "In13.Cu")
		(net "M_B_CPU0_SB_CA<2>")
	)
	(segment
		(start 307.868828 -262.67791)
		(end 308.384448 -262.16229)
		(width 0.14478)
		(layer "In13.Cu")
		(net "M_B_CPU0_SB_CA<2>")
	)
	(segment
		(start 304.84191 -262.367268)
		(end 305.087528 -262.367268)
		(width 0.14478)
		(layer "In13.Cu")
		(net "M_B_CPU0_SB_CA<2>")
	)
	(segment
		(start 307.62321 -262.67791)
		(end 307.868828 -262.67791)
		(width 0.14478)
		(layer "In13.Cu")
		(net "M_B_CPU0_SB_CA<2>")
	)
	(segment
		(start 313.9694 -262.16229)
		(end 314.562236 -262.755126)
		(width 0.14478)
		(layer "In13.Cu")
		(net "M_B_CPU0_SB_CA<2>")
	)
	(segment
		(start 329.284076 -263.068562)
		(end 329.292458 -263.073388)
		(width 0.0889)
		(layer "In13.Cu")
		(net "M_B_CPU0_SB_CA<2>")
	)
	(segment
		(start 331.52969 -263.073388)
		(end 331.538072 -263.068562)
		(width 0.0889)
		(layer "In13.Cu")
		(net "M_B_CPU0_SB_CA<2>")
	)
	(segment
		(start 300.854872 -262.006334)
		(end 300.999652 -262.151114)
		(width 0.14478)
		(layer "In13.Cu")
		(net "M_B_CPU0_SB_CA<2>")
	)
	(segment
		(start 307.312568 -262.367268)
		(end 307.62321 -262.67791)
		(width 0.14478)
		(layer "In13.Cu")
		(net "M_B_CPU0_SB_CA<2>")
	)
	(segment
		(start 308.384448 -262.16229)
		(end 313.9694 -262.16229)
		(width 0.14478)
		(layer "In13.Cu")
		(net "M_B_CPU0_SB_CA<2>")
	)
	(segment
		(start 299.82414 -262.785098)
		(end 299.82414 -262.605266)
		(width 0.14478)
		(layer "In13.Cu")
		(net "M_B_CPU0_SB_CA<2>")
	)
	(segment
		(start 333.984092 -263.068562)
		(end 333.992474 -263.073388)
		(width 0.0889)
		(layer "In13.Cu")
		(net "M_B_CPU0_SB_CA<2>")
	)
	(segment
		(start 333.044038 -263.068562)
		(end 333.05242 -263.073388)
		(width 0.0889)
		(layer "In13.Cu")
		(net "M_B_CPU0_SB_CA<2>")
	)
	(segment
		(start 314.562236 -262.755126)
		(end 323.86905 -262.755126)
		(width 0.14478)
		(layer "In13.Cu")
		(net "M_B_CPU0_SB_CA<2>")
	)
	(segment
		(start 302.102012 -262.521446)
		(end 302.246792 -262.666226)
		(width 0.14478)
		(layer "In13.Cu")
		(net "M_B_CPU0_SB_CA<2>")
	)
	(arc
		(start 332.103984 -263.068562)
		(mid 332.286235 -263.118912)
		(end 332.469744 -263.073388)
		(width 0.0889)
		(layer "In13.Cu")
		(net "M_B_CPU0_SB_CA<2>")
	)
	(arc
		(start 328.718164 -263.068562)
		(mid 329.00112 -262.992385)
		(end 329.284076 -263.068562)
		(width 0.0889)
		(layer "In13.Cu")
		(net "M_B_CPU0_SB_CA<2>")
	)
	(arc
		(start 330.598018 -263.068562)
		(mid 330.880974 -262.992385)
		(end 331.16393 -263.068562)
		(width 0.0889)
		(layer "In13.Cu")
		(net "M_B_CPU0_SB_CA<2>")
	)
	(arc
		(start 330.22413 -263.068562)
		(mid 330.411074 -263.118817)
		(end 330.598018 -263.068562)
		(width 0.0889)
		(layer "In13.Cu")
		(net "M_B_CPU0_SB_CA<2>")
	)
	(arc
		(start 332.478126 -263.068562)
		(mid 332.761082 -262.992385)
		(end 333.044038 -263.068562)
		(width 0.0889)
		(layer "In13.Cu")
		(net "M_B_CPU0_SB_CA<2>")
	)
	(arc
		(start 335.298034 -263.068562)
		(mid 335.54563 -262.993384)
		(end 335.8007 -263.036812)
		(width 0.0889)
		(layer "In13.Cu")
		(net "M_B_CPU0_SB_CA<2>")
	)
	(arc
		(start 329.292458 -263.073388)
		(mid 329.475966 -263.118882)
		(end 329.658218 -263.068562)
		(width 0.0889)
		(layer "In13.Cu")
		(net "M_B_CPU0_SB_CA<2>")
	)
	(arc
		(start 331.16393 -263.068562)
		(mid 331.346181 -263.118912)
		(end 331.52969 -263.073388)
		(width 0.0889)
		(layer "In13.Cu")
		(net "M_B_CPU0_SB_CA<2>")
	)
	(arc
		(start 333.992474 -263.073388)
		(mid 334.175982 -263.118882)
		(end 334.358234 -263.068562)
		(width 0.0889)
		(layer "In13.Cu")
		(net "M_B_CPU0_SB_CA<2>")
	)
	(arc
		(start 329.658218 -263.068562)
		(mid 329.941174 -262.992385)
		(end 330.22413 -263.068562)
		(width 0.0889)
		(layer "In13.Cu")
		(net "M_B_CPU0_SB_CA<2>")
	)
	(arc
		(start 333.05242 -263.073388)
		(mid 333.235928 -263.118882)
		(end 333.41818 -263.068562)
		(width 0.0889)
		(layer "In13.Cu")
		(net "M_B_CPU0_SB_CA<2>")
	)
	(arc
		(start 334.924146 -263.068562)
		(mid 335.11109 -263.118817)
		(end 335.298034 -263.068562)
		(width 0.0889)
		(layer "In13.Cu")
		(net "M_B_CPU0_SB_CA<2>")
	)
	(arc
		(start 327.777856 -263.068562)
		(mid 328.054923 -262.992291)
		(end 328.333608 -263.062466)
		(width 0.0889)
		(layer "In13.Cu")
		(net "M_B_CPU0_SB_CA<2>")
	)
	(arc
		(start 334.358234 -263.068562)
		(mid 334.64119 -262.992385)
		(end 334.924146 -263.068562)
		(width 0.0889)
		(layer "In13.Cu")
		(net "M_B_CPU0_SB_CA<2>")
	)
	(arc
		(start 328.344022 -263.068562)
		(mid 328.526273 -263.118912)
		(end 328.709782 -263.073388)
		(width 0.0889)
		(layer "In13.Cu")
		(net "M_B_CPU0_SB_CA<2>")
	)
	(arc
		(start 333.41818 -263.068562)
		(mid 333.701136 -262.992385)
		(end 333.984092 -263.068562)
		(width 0.0889)
		(layer "In13.Cu")
		(net "M_B_CPU0_SB_CA<2>")
	)
	(arc
		(start 327.590658 -263.119108)
		(mid 327.687584 -263.106171)
		(end 327.777856 -263.068562)
		(width 0.0889)
		(layer "In13.Cu")
		(net "M_B_CPU0_SB_CA<2>")
	)
	(arc
		(start 331.538072 -263.068562)
		(mid 331.821028 -262.992385)
		(end 332.103984 -263.068562)
		(width 0.0889)
		(layer "In13.Cu")
		(net "M_B_CPU0_SB_CA<2>")
	)
	(segment
		(start 337.45805 -262.480044)
		(end 336.991198 -262.745982)
		(width 0.10668)
		(layer "F.Cu")
		(net "M_B_CPU0_SB_CA<1>")
	)
	(segment
		(start 323.926454 -262.24611)
		(end 325.710296 -262.24611)
		(width 0.0889)
		(layer "In13.Cu")
		(net "M_B_CPU0_SB_CA<1>")
	)
	(segment
		(start 333.984092 -262.423402)
		(end 333.992474 -262.418576)
		(width 0.0889)
		(layer "In13.Cu")
		(net "M_B_CPU0_SB_CA<1>")
	)
	(segment
		(start 328.32929 -262.432038)
		(end 328.344022 -262.423402)
		(width 0.0889)
		(layer "In13.Cu")
		(net "M_B_CPU0_SB_CA<1>")
	)
	(segment
		(start 333.044038 -262.423402)
		(end 333.05242 -262.418576)
		(width 0.0889)
		(layer "In13.Cu")
		(net "M_B_CPU0_SB_CA<1>")
	)
	(segment
		(start 332.469744 -262.418576)
		(end 332.478126 -262.423402)
		(width 0.0889)
		(layer "In13.Cu")
		(net "M_B_CPU0_SB_CA<1>")
	)
	(segment
		(start 295.724072 -261.93496)
		(end 295.724072 -261.884414)
		(width 0.14478)
		(layer "In13.Cu")
		(net "M_B_CPU0_SB_CA<1>")
	)
	(segment
		(start 325.749158 -262.284972)
		(end 327.406508 -262.284972)
		(width 0.0889)
		(layer "In13.Cu")
		(net "M_B_CPU0_SB_CA<1>")
	)
	(segment
		(start 314.689236 -262.24611)
		(end 323.926454 -262.24611)
		(width 0.14478)
		(layer "In13.Cu")
		(net "M_B_CPU0_SB_CA<1>")
	)
	(segment
		(start 337.12277 -262.39724)
		(end 337.145122 -262.480552)
		(width 0.0889)
		(layer "In13.Cu")
		(net "M_B_CPU0_SB_CA<1>")
	)
	(segment
		(start 336.229706 -262.418576)
		(end 336.238088 -262.423402)
		(width 0.0889)
		(layer "In13.Cu")
		(net "M_B_CPU0_SB_CA<1>")
	)
	(segment
		(start 325.710296 -262.24611)
		(end 325.749158 -262.284972)
		(width 0.0889)
		(layer "In13.Cu")
		(net "M_B_CPU0_SB_CA<1>")
	)
	(segment
		(start 328.709782 -262.418576)
		(end 328.718164 -262.423402)
		(width 0.0889)
		(layer "In13.Cu")
		(net "M_B_CPU0_SB_CA<1>")
	)
	(segment
		(start 337.145122 -262.480552)
		(end 336.991198 -262.745982)
		(width 0.0889)
		(layer "In13.Cu")
		(net "M_B_CPU0_SB_CA<1>")
	)
	(segment
		(start 313.953144 -261.510018)
		(end 314.689236 -262.24611)
		(width 0.14478)
		(layer "In13.Cu")
		(net "M_B_CPU0_SB_CA<1>")
	)
	(segment
		(start 329.284076 -262.423402)
		(end 329.292458 -262.418576)
		(width 0.0889)
		(layer "In13.Cu")
		(net "M_B_CPU0_SB_CA<1>")
	)
	(segment
		(start 296.098468 -261.510018)
		(end 313.953144 -261.510018)
		(width 0.14478)
		(layer "In13.Cu")
		(net "M_B_CPU0_SB_CA<1>")
	)
	(segment
		(start 331.52969 -262.418576)
		(end 331.538072 -262.423402)
		(width 0.0889)
		(layer "In13.Cu")
		(net "M_B_CPU0_SB_CA<1>")
	)
	(segment
		(start 295.724072 -261.884414)
		(end 296.098468 -261.510018)
		(width 0.14478)
		(layer "In13.Cu")
		(net "M_B_CPU0_SB_CA<1>")
	)
	(arc
		(start 327.494646 -262.298434)
		(mid 327.639595 -262.353059)
		(end 327.777602 -262.423402)
		(width 0.0889)
		(layer "In13.Cu")
		(net "M_B_CPU0_SB_CA<1>")
	)
	(arc
		(start 329.658218 -262.423402)
		(mid 329.941174 -262.499579)
		(end 330.22413 -262.423402)
		(width 0.0889)
		(layer "In13.Cu")
		(net "M_B_CPU0_SB_CA<1>")
	)
	(arc
		(start 336.238088 -262.423402)
		(mid 336.521044 -262.499579)
		(end 336.804 -262.423402)
		(width 0.0889)
		(layer "In13.Cu")
		(net "M_B_CPU0_SB_CA<1>")
	)
	(arc
		(start 330.598018 -262.423402)
		(mid 330.880974 -262.499579)
		(end 331.16393 -262.423402)
		(width 0.0889)
		(layer "In13.Cu")
		(net "M_B_CPU0_SB_CA<1>")
	)
	(arc
		(start 328.718164 -262.423402)
		(mid 329.00112 -262.499579)
		(end 329.284076 -262.423402)
		(width 0.0889)
		(layer "In13.Cu")
		(net "M_B_CPU0_SB_CA<1>")
	)
	(arc
		(start 333.05242 -262.418576)
		(mid 333.235928 -262.373082)
		(end 333.41818 -262.423402)
		(width 0.0889)
		(layer "In13.Cu")
		(net "M_B_CPU0_SB_CA<1>")
	)
	(arc
		(start 332.478126 -262.423402)
		(mid 332.761082 -262.499579)
		(end 333.044038 -262.423402)
		(width 0.0889)
		(layer "In13.Cu")
		(net "M_B_CPU0_SB_CA<1>")
	)
	(arc
		(start 334.358234 -262.423402)
		(mid 334.64119 -262.499579)
		(end 334.924146 -262.423402)
		(width 0.0889)
		(layer "In13.Cu")
		(net "M_B_CPU0_SB_CA<1>")
	)
	(arc
		(start 331.16393 -262.423402)
		(mid 331.346181 -262.373052)
		(end 331.52969 -262.418576)
		(width 0.0889)
		(layer "In13.Cu")
		(net "M_B_CPU0_SB_CA<1>")
	)
	(arc
		(start 333.41818 -262.423402)
		(mid 333.701136 -262.499579)
		(end 333.984092 -262.423402)
		(width 0.0889)
		(layer "In13.Cu")
		(net "M_B_CPU0_SB_CA<1>")
	)
	(arc
		(start 328.344022 -262.423402)
		(mid 328.526273 -262.373052)
		(end 328.709782 -262.418576)
		(width 0.0889)
		(layer "In13.Cu")
		(net "M_B_CPU0_SB_CA<1>")
	)
	(arc
		(start 327.406508 -262.284972)
		(mid 327.451088 -262.288346)
		(end 327.494646 -262.298434)
		(width 0.0889)
		(layer "In13.Cu")
		(net "M_B_CPU0_SB_CA<1>")
	)
	(arc
		(start 336.804 -262.423402)
		(mid 336.960438 -262.374431)
		(end 337.12277 -262.39724)
		(width 0.0889)
		(layer "In13.Cu")
		(net "M_B_CPU0_SB_CA<1>")
	)
	(arc
		(start 332.103984 -262.423402)
		(mid 332.286235 -262.373052)
		(end 332.469744 -262.418576)
		(width 0.0889)
		(layer "In13.Cu")
		(net "M_B_CPU0_SB_CA<1>")
	)
	(arc
		(start 335.863946 -262.423402)
		(mid 336.046197 -262.373052)
		(end 336.229706 -262.418576)
		(width 0.0889)
		(layer "In13.Cu")
		(net "M_B_CPU0_SB_CA<1>")
	)
	(arc
		(start 331.538072 -262.423402)
		(mid 331.821028 -262.499579)
		(end 332.103984 -262.423402)
		(width 0.0889)
		(layer "In13.Cu")
		(net "M_B_CPU0_SB_CA<1>")
	)
	(arc
		(start 334.924146 -262.423402)
		(mid 335.11109 -262.373147)
		(end 335.298034 -262.423402)
		(width 0.0889)
		(layer "In13.Cu")
		(net "M_B_CPU0_SB_CA<1>")
	)
	(arc
		(start 327.777602 -262.423402)
		(mid 328.052308 -262.499766)
		(end 328.32929 -262.432038)
		(width 0.0889)
		(layer "In13.Cu")
		(net "M_B_CPU0_SB_CA<1>")
	)
	(arc
		(start 335.298034 -262.423402)
		(mid 335.58099 -262.499579)
		(end 335.863946 -262.423402)
		(width 0.0889)
		(layer "In13.Cu")
		(net "M_B_CPU0_SB_CA<1>")
	)
	(arc
		(start 329.292458 -262.418576)
		(mid 329.475966 -262.373082)
		(end 329.658218 -262.423402)
		(width 0.0889)
		(layer "In13.Cu")
		(net "M_B_CPU0_SB_CA<1>")
	)
	(arc
		(start 333.992474 -262.418576)
		(mid 334.175982 -262.373082)
		(end 334.358234 -262.423402)
		(width 0.0889)
		(layer "In13.Cu")
		(net "M_B_CPU0_SB_CA<1>")
	)
	(arc
		(start 330.22413 -262.423402)
		(mid 330.411074 -262.373147)
		(end 330.598018 -262.423402)
		(width 0.0889)
		(layer "In13.Cu")
		(net "M_B_CPU0_SB_CA<1>")
	)
	(segment
		(start 337.92795 -261.670038)
		(end 337.461098 -261.935976)
		(width 0.10668)
		(layer "F.Cu")
		(net "M_B_CPU0_SB_CA<0>")
	)
	(segment
		(start 302.504856 -260.660134)
		(end 302.74514 -260.660134)
		(width 0.14478)
		(layer "In13.Cu")
		(net "M_B_CPU0_SB_CA<0>")
	)
	(segment
		(start 305.52644 -260.97611)
		(end 305.842416 -260.660134)
		(width 0.14478)
		(layer "In13.Cu")
		(net "M_B_CPU0_SB_CA<0>")
	)
	(segment
		(start 328.239882 -262.263382)
		(end 328.248264 -262.258556)
		(width 0.0889)
		(layer "In13.Cu")
		(net "M_B_CPU0_SB_CA<0>")
	)
	(segment
		(start 299.82414 -261.085076)
		(end 299.82414 -261.011416)
		(width 0.14478)
		(layer "In13.Cu")
		(net "M_B_CPU0_SB_CA<0>")
	)
	(segment
		(start 304.41392 -260.97611)
		(end 304.729896 -260.660134)
		(width 0.14478)
		(layer "In13.Cu")
		(net "M_B_CPU0_SB_CA<0>")
	)
	(segment
		(start 301.07636 -260.97611)
		(end 301.392336 -260.660134)
		(width 0.14478)
		(layer "In13.Cu")
		(net "M_B_CPU0_SB_CA<0>")
	)
	(segment
		(start 301.948596 -260.97611)
		(end 302.18888 -260.97611)
		(width 0.14478)
		(layer "In13.Cu")
		(net "M_B_CPU0_SB_CA<0>")
	)
	(segment
		(start 315.086238 -261.775956)
		(end 323.8881 -261.775956)
		(width 0.14478)
		(layer "In13.Cu")
		(net "M_B_CPU0_SB_CA<0>")
	)
	(segment
		(start 303.061116 -260.97611)
		(end 303.3014 -260.97611)
		(width 0.14478)
		(layer "In13.Cu")
		(net "M_B_CPU0_SB_CA<0>")
	)
	(segment
		(start 302.18888 -260.97611)
		(end 302.504856 -260.660134)
		(width 0.14478)
		(layer "In13.Cu")
		(net "M_B_CPU0_SB_CA<0>")
	)
	(segment
		(start 323.8881 -261.775956)
		(end 324.554342 -261.775956)
		(width 0.0889)
		(layer "In13.Cu")
		(net "M_B_CPU0_SB_CA<0>")
	)
	(segment
		(start 304.97018 -260.660134)
		(end 305.286156 -260.97611)
		(width 0.14478)
		(layer "In13.Cu")
		(net "M_B_CPU0_SB_CA<0>")
	)
	(segment
		(start 324.554342 -261.775956)
		(end 324.822058 -262.043672)
		(width 0.0889)
		(layer "In13.Cu")
		(net "M_B_CPU0_SB_CA<0>")
	)
	(segment
		(start 337.211162 -262.226806)
		(end 337.307174 -262.201406)
		(width 0.0889)
		(layer "In13.Cu")
		(net "M_B_CPU0_SB_CA<0>")
	)
	(segment
		(start 305.286156 -260.97611)
		(end 305.52644 -260.97611)
		(width 0.14478)
		(layer "In13.Cu")
		(net "M_B_CPU0_SB_CA<0>")
	)
	(segment
		(start 306.0827 -260.660134)
		(end 306.398676 -260.97611)
		(width 0.14478)
		(layer "In13.Cu")
		(net "M_B_CPU0_SB_CA<0>")
	)
	(segment
		(start 303.3014 -260.97611)
		(end 303.617376 -260.660134)
		(width 0.14478)
		(layer "In13.Cu")
		(net "M_B_CPU0_SB_CA<0>")
	)
	(segment
		(start 330.119736 -262.263382)
		(end 330.128118 -262.258556)
		(width 0.0889)
		(layer "In13.Cu")
		(net "M_B_CPU0_SB_CA<0>")
	)
	(segment
		(start 305.842416 -260.660134)
		(end 306.0827 -260.660134)
		(width 0.14478)
		(layer "In13.Cu")
		(net "M_B_CPU0_SB_CA<0>")
	)
	(segment
		(start 300.5201 -260.660134)
		(end 300.836076 -260.97611)
		(width 0.14478)
		(layer "In13.Cu")
		(net "M_B_CPU0_SB_CA<0>")
	)
	(segment
		(start 335.394046 -262.258556)
		(end 335.402428 -262.263382)
		(width 0.0889)
		(layer "In13.Cu")
		(net "M_B_CPU0_SB_CA<0>")
	)
	(segment
		(start 308.067456 -260.660134)
		(end 313.970416 -260.660134)
		(width 0.14478)
		(layer "In13.Cu")
		(net "M_B_CPU0_SB_CA<0>")
	)
	(segment
		(start 301.392336 -260.660134)
		(end 301.63262 -260.660134)
		(width 0.14478)
		(layer "In13.Cu")
		(net "M_B_CPU0_SB_CA<0>")
	)
	(segment
		(start 331.634084 -262.258556)
		(end 331.642466 -262.263382)
		(width 0.0889)
		(layer "In13.Cu")
		(net "M_B_CPU0_SB_CA<0>")
	)
	(segment
		(start 306.954936 -260.660134)
		(end 307.19522 -260.660134)
		(width 0.14478)
		(layer "In13.Cu")
		(net "M_B_CPU0_SB_CA<0>")
	)
	(segment
		(start 330.69403 -262.258556)
		(end 330.702412 -262.263382)
		(width 0.0889)
		(layer "In13.Cu")
		(net "M_B_CPU0_SB_CA<0>")
	)
	(segment
		(start 304.729896 -260.660134)
		(end 304.97018 -260.660134)
		(width 0.14478)
		(layer "In13.Cu")
		(net "M_B_CPU0_SB_CA<0>")
	)
	(segment
		(start 306.398676 -260.97611)
		(end 306.63896 -260.97611)
		(width 0.14478)
		(layer "In13.Cu")
		(net "M_B_CPU0_SB_CA<0>")
	)
	(segment
		(start 324.822058 -262.043672)
		(end 327.076054 -262.043672)
		(width 0.0889)
		(layer "In13.Cu")
		(net "M_B_CPU0_SB_CA<0>")
	)
	(segment
		(start 307.511196 -260.97611)
		(end 307.75148 -260.97611)
		(width 0.14478)
		(layer "In13.Cu")
		(net "M_B_CPU0_SB_CA<0>")
	)
	(segment
		(start 304.173636 -260.97611)
		(end 304.41392 -260.97611)
		(width 0.14478)
		(layer "In13.Cu")
		(net "M_B_CPU0_SB_CA<0>")
	)
	(segment
		(start 302.74514 -260.660134)
		(end 303.061116 -260.97611)
		(width 0.14478)
		(layer "In13.Cu")
		(net "M_B_CPU0_SB_CA<0>")
	)
	(segment
		(start 301.63262 -260.660134)
		(end 301.948596 -260.97611)
		(width 0.14478)
		(layer "In13.Cu")
		(net "M_B_CPU0_SB_CA<0>")
	)
	(segment
		(start 303.617376 -260.660134)
		(end 303.85766 -260.660134)
		(width 0.14478)
		(layer "In13.Cu")
		(net "M_B_CPU0_SB_CA<0>")
	)
	(segment
		(start 307.75148 -260.97611)
		(end 308.067456 -260.660134)
		(width 0.14478)
		(layer "In13.Cu")
		(net "M_B_CPU0_SB_CA<0>")
	)
	(segment
		(start 303.85766 -260.660134)
		(end 304.173636 -260.97611)
		(width 0.14478)
		(layer "In13.Cu")
		(net "M_B_CPU0_SB_CA<0>")
	)
	(segment
		(start 306.63896 -260.97611)
		(end 306.954936 -260.660134)
		(width 0.14478)
		(layer "In13.Cu")
		(net "M_B_CPU0_SB_CA<0>")
	)
	(segment
		(start 313.970416 -260.660134)
		(end 315.086238 -261.775956)
		(width 0.14478)
		(layer "In13.Cu")
		(net "M_B_CPU0_SB_CA<0>")
	)
	(segment
		(start 337.307174 -262.201406)
		(end 337.461098 -261.935976)
		(width 0.0889)
		(layer "In13.Cu")
		(net "M_B_CPU0_SB_CA<0>")
	)
	(segment
		(start 333.879698 -262.263382)
		(end 333.88808 -262.258556)
		(width 0.0889)
		(layer "In13.Cu")
		(net "M_B_CPU0_SB_CA<0>")
	)
	(segment
		(start 299.82414 -261.011416)
		(end 300.175422 -260.660134)
		(width 0.14478)
		(layer "In13.Cu")
		(net "M_B_CPU0_SB_CA<0>")
	)
	(segment
		(start 334.819752 -262.263382)
		(end 334.828134 -262.258556)
		(width 0.0889)
		(layer "In13.Cu")
		(net "M_B_CPU0_SB_CA<0>")
	)
	(segment
		(start 307.19522 -260.660134)
		(end 307.511196 -260.97611)
		(width 0.14478)
		(layer "In13.Cu")
		(net "M_B_CPU0_SB_CA<0>")
	)
	(segment
		(start 300.836076 -260.97611)
		(end 301.07636 -260.97611)
		(width 0.14478)
		(layer "In13.Cu")
		(net "M_B_CPU0_SB_CA<0>")
	)
	(segment
		(start 336.3341 -262.258556)
		(end 336.342482 -262.263382)
		(width 0.0889)
		(layer "In13.Cu")
		(net "M_B_CPU0_SB_CA<0>")
	)
	(segment
		(start 300.175422 -260.660134)
		(end 300.5201 -260.660134)
		(width 0.14478)
		(layer "In13.Cu")
		(net "M_B_CPU0_SB_CA<0>")
	)
	(arc
		(start 330.128118 -262.258556)
		(mid 330.411074 -262.182379)
		(end 330.69403 -262.258556)
		(width 0.0889)
		(layer "In13.Cu")
		(net "M_B_CPU0_SB_CA<0>")
	)
	(arc
		(start 334.828134 -262.258556)
		(mid 335.11109 -262.182379)
		(end 335.394046 -262.258556)
		(width 0.0889)
		(layer "In13.Cu")
		(net "M_B_CPU0_SB_CA<0>")
	)
	(arc
		(start 329.188064 -262.258556)
		(mid 329.47102 -262.182379)
		(end 329.753976 -262.258556)
		(width 0.0889)
		(layer "In13.Cu")
		(net "M_B_CPU0_SB_CA<0>")
	)
	(arc
		(start 331.068172 -262.258556)
		(mid 331.351128 -262.182379)
		(end 331.634084 -262.258556)
		(width 0.0889)
		(layer "In13.Cu")
		(net "M_B_CPU0_SB_CA<0>")
	)
	(arc
		(start 332.008226 -262.258556)
		(mid 332.291182 -262.182379)
		(end 332.574138 -262.258556)
		(width 0.0889)
		(layer "In13.Cu")
		(net "M_B_CPU0_SB_CA<0>")
	)
	(arc
		(start 328.248264 -262.258556)
		(mid 328.53122 -262.182379)
		(end 328.814176 -262.258556)
		(width 0.0889)
		(layer "In13.Cu")
		(net "M_B_CPU0_SB_CA<0>")
	)
	(arc
		(start 331.642466 -262.263382)
		(mid 331.825974 -262.308876)
		(end 332.008226 -262.258556)
		(width 0.0889)
		(layer "In13.Cu")
		(net "M_B_CPU0_SB_CA<0>")
	)
	(arc
		(start 336.708242 -262.258556)
		(mid 336.955955 -262.183336)
		(end 337.211162 -262.226806)
		(width 0.0889)
		(layer "In13.Cu")
		(net "M_B_CPU0_SB_CA<0>")
	)
	(arc
		(start 330.702412 -262.263382)
		(mid 330.88592 -262.308876)
		(end 331.068172 -262.258556)
		(width 0.0889)
		(layer "In13.Cu")
		(net "M_B_CPU0_SB_CA<0>")
	)
	(arc
		(start 333.88808 -262.258556)
		(mid 334.171036 -262.182379)
		(end 334.453992 -262.258556)
		(width 0.0889)
		(layer "In13.Cu")
		(net "M_B_CPU0_SB_CA<0>")
	)
	(arc
		(start 336.342482 -262.263382)
		(mid 336.52599 -262.308876)
		(end 336.708242 -262.258556)
		(width 0.0889)
		(layer "In13.Cu")
		(net "M_B_CPU0_SB_CA<0>")
	)
	(arc
		(start 334.453992 -262.258556)
		(mid 334.636243 -262.308906)
		(end 334.819752 -262.263382)
		(width 0.0889)
		(layer "In13.Cu")
		(net "M_B_CPU0_SB_CA<0>")
	)
	(arc
		(start 335.402428 -262.263382)
		(mid 335.585936 -262.308876)
		(end 335.768188 -262.258556)
		(width 0.0889)
		(layer "In13.Cu")
		(net "M_B_CPU0_SB_CA<0>")
	)
	(arc
		(start 327.076054 -262.043672)
		(mid 327.489049 -262.098343)
		(end 327.873614 -262.258556)
		(width 0.0889)
		(layer "In13.Cu")
		(net "M_B_CPU0_SB_CA<0>")
	)
	(arc
		(start 332.574138 -262.258556)
		(mid 332.761082 -262.308811)
		(end 332.948026 -262.258556)
		(width 0.0889)
		(layer "In13.Cu")
		(net "M_B_CPU0_SB_CA<0>")
	)
	(arc
		(start 332.948026 -262.258556)
		(mid 333.230982 -262.182379)
		(end 333.513938 -262.258556)
		(width 0.0889)
		(layer "In13.Cu")
		(net "M_B_CPU0_SB_CA<0>")
	)
	(arc
		(start 333.513938 -262.258556)
		(mid 333.696189 -262.308906)
		(end 333.879698 -262.263382)
		(width 0.0889)
		(layer "In13.Cu")
		(net "M_B_CPU0_SB_CA<0>")
	)
	(arc
		(start 328.814176 -262.258556)
		(mid 329.00112 -262.308811)
		(end 329.188064 -262.258556)
		(width 0.0889)
		(layer "In13.Cu")
		(net "M_B_CPU0_SB_CA<0>")
	)
	(arc
		(start 335.768188 -262.258556)
		(mid 336.051144 -262.182379)
		(end 336.3341 -262.258556)
		(width 0.0889)
		(layer "In13.Cu")
		(net "M_B_CPU0_SB_CA<0>")
	)
	(arc
		(start 329.753976 -262.258556)
		(mid 329.936227 -262.308906)
		(end 330.119736 -262.263382)
		(width 0.0889)
		(layer "In13.Cu")
		(net "M_B_CPU0_SB_CA<0>")
	)
	(arc
		(start 327.873614 -262.258556)
		(mid 328.056119 -262.309033)
		(end 328.239882 -262.263382)
		(width 0.0889)
		(layer "In13.Cu")
		(net "M_B_CPU0_SB_CA<0>")
	)
	(segment
		(start 337.92795 -266.530074)
		(end 337.461098 -266.796012)
		(width 0.10668)
		(layer "F.Cu")
		(net "M_B_CPU0_SA_RSP<0>")
	)
	(segment
		(start 308.057804 -268.344904)
		(end 309.978298 -266.42441)
		(width 0.11684)
		(layer "In13.Cu")
		(net "M_B_CPU0_SA_RSP<0>")
	)
	(segment
		(start 300.249336 -269.15999)
		(end 302.34001 -269.15999)
		(width 0.11684)
		(layer "In13.Cu")
		(net "M_B_CPU0_SA_RSP<0>")
	)
	(segment
		(start 335.394046 -267.118592)
		(end 335.402428 -267.123418)
		(width 0.0889)
		(layer "In13.Cu")
		(net "M_B_CPU0_SA_RSP<0>")
	)
	(segment
		(start 304.45329 -269.15999)
		(end 304.73777 -268.87551)
		(width 0.11684)
		(layer "In13.Cu")
		(net "M_B_CPU0_SA_RSP<0>")
	)
	(segment
		(start 306.32273 -269.15999)
		(end 307.773324 -269.15999)
		(width 0.11684)
		(layer "In13.Cu")
		(net "M_B_CPU0_SA_RSP<0>")
	)
	(segment
		(start 307.773324 -269.15999)
		(end 308.057804 -268.87551)
		(width 0.11684)
		(layer "In13.Cu")
		(net "M_B_CPU0_SA_RSP<0>")
	)
	(segment
		(start 302.62449 -268.87551)
		(end 302.86833 -268.87551)
		(width 0.11684)
		(layer "In13.Cu")
		(net "M_B_CPU0_SA_RSP<0>")
	)
	(segment
		(start 337.586574 -267.140182)
		(end 337.609942 -267.052298)
		(width 0.0889)
		(layer "In13.Cu")
		(net "M_B_CPU0_SA_RSP<0>")
	)
	(segment
		(start 330.69403 -267.118592)
		(end 330.702412 -267.123418)
		(width 0.0889)
		(layer "In13.Cu")
		(net "M_B_CPU0_SA_RSP<0>")
	)
	(segment
		(start 303.15281 -269.15999)
		(end 303.39665 -269.15999)
		(width 0.11684)
		(layer "In13.Cu")
		(net "M_B_CPU0_SA_RSP<0>")
	)
	(segment
		(start 308.057804 -268.87551)
		(end 308.057804 -268.344904)
		(width 0.11684)
		(layer "In13.Cu")
		(net "M_B_CPU0_SA_RSP<0>")
	)
	(segment
		(start 335.768188 -267.118592)
		(end 335.77784 -267.113258)
		(width 0.0889)
		(layer "In13.Cu")
		(net "M_B_CPU0_SA_RSP<0>")
	)
	(segment
		(start 303.68113 -268.87551)
		(end 303.92497 -268.87551)
		(width 0.11684)
		(layer "In13.Cu")
		(net "M_B_CPU0_SA_RSP<0>")
	)
	(segment
		(start 305.50993 -269.15999)
		(end 305.79441 -268.87551)
		(width 0.11684)
		(layer "In13.Cu")
		(net "M_B_CPU0_SA_RSP<0>")
	)
	(segment
		(start 337.609942 -267.052298)
		(end 337.461098 -266.796012)
		(width 0.0889)
		(layer "In13.Cu")
		(net "M_B_CPU0_SA_RSP<0>")
	)
	(segment
		(start 302.34001 -269.15999)
		(end 302.62449 -268.87551)
		(width 0.11684)
		(layer "In13.Cu")
		(net "M_B_CPU0_SA_RSP<0>")
	)
	(segment
		(start 324.890638 -266.915392)
		(end 326.079612 -266.915392)
		(width 0.0889)
		(layer "In13.Cu")
		(net "M_B_CPU0_SA_RSP<0>")
	)
	(segment
		(start 304.20945 -269.15999)
		(end 304.45329 -269.15999)
		(width 0.11684)
		(layer "In13.Cu")
		(net "M_B_CPU0_SA_RSP<0>")
	)
	(segment
		(start 305.79441 -268.87551)
		(end 306.03825 -268.87551)
		(width 0.11684)
		(layer "In13.Cu")
		(net "M_B_CPU0_SA_RSP<0>")
	)
	(segment
		(start 327.335134 -267.035534)
		(end 327.417938 -267.118338)
		(width 0.0889)
		(layer "In13.Cu")
		(net "M_B_CPU0_SA_RSP<0>")
	)
	(segment
		(start 324.399656 -266.42441)
		(end 324.890638 -266.915392)
		(width 0.0889)
		(layer "In13.Cu")
		(net "M_B_CPU0_SA_RSP<0>")
	)
	(segment
		(start 330.119736 -267.123418)
		(end 330.128118 -267.118592)
		(width 0.0889)
		(layer "In13.Cu")
		(net "M_B_CPU0_SA_RSP<0>")
	)
	(segment
		(start 306.03825 -268.87551)
		(end 306.32273 -269.15999)
		(width 0.11684)
		(layer "In13.Cu")
		(net "M_B_CPU0_SA_RSP<0>")
	)
	(segment
		(start 305.26609 -269.15999)
		(end 305.50993 -269.15999)
		(width 0.11684)
		(layer "In13.Cu")
		(net "M_B_CPU0_SA_RSP<0>")
	)
	(segment
		(start 309.978298 -266.42441)
		(end 323.989954 -266.42441)
		(width 0.11684)
		(layer "In13.Cu")
		(net "M_B_CPU0_SA_RSP<0>")
	)
	(segment
		(start 327.874376 -267.118338)
		(end 327.890632 -267.127736)
		(width 0.0889)
		(layer "In13.Cu")
		(net "M_B_CPU0_SA_RSP<0>")
	)
	(segment
		(start 303.92497 -268.87551)
		(end 304.20945 -269.15999)
		(width 0.11684)
		(layer "In13.Cu")
		(net "M_B_CPU0_SA_RSP<0>")
	)
	(segment
		(start 323.989954 -266.42441)
		(end 324.399656 -266.42441)
		(width 0.0889)
		(layer "In13.Cu")
		(net "M_B_CPU0_SA_RSP<0>")
	)
	(segment
		(start 326.079612 -266.915392)
		(end 326.199754 -267.035534)
		(width 0.0889)
		(layer "In13.Cu")
		(net "M_B_CPU0_SA_RSP<0>")
	)
	(segment
		(start 333.887826 -267.118592)
		(end 333.88808 -267.118592)
		(width 0.0889)
		(layer "In13.Cu")
		(net "M_B_CPU0_SA_RSP<0>")
	)
	(segment
		(start 304.98161 -268.87551)
		(end 305.26609 -269.15999)
		(width 0.11684)
		(layer "In13.Cu")
		(net "M_B_CPU0_SA_RSP<0>")
	)
	(segment
		(start 304.73777 -268.87551)
		(end 304.98161 -268.87551)
		(width 0.11684)
		(layer "In13.Cu")
		(net "M_B_CPU0_SA_RSP<0>")
	)
	(segment
		(start 303.39665 -269.15999)
		(end 303.68113 -268.87551)
		(width 0.11684)
		(layer "In13.Cu")
		(net "M_B_CPU0_SA_RSP<0>")
	)
	(segment
		(start 326.199754 -267.035534)
		(end 327.335134 -267.035534)
		(width 0.0889)
		(layer "In13.Cu")
		(net "M_B_CPU0_SA_RSP<0>")
	)
	(segment
		(start 302.86833 -268.87551)
		(end 303.15281 -269.15999)
		(width 0.11684)
		(layer "In13.Cu")
		(net "M_B_CPU0_SA_RSP<0>")
	)
	(segment
		(start 334.819752 -267.123418)
		(end 334.828134 -267.118592)
		(width 0.0889)
		(layer "In13.Cu")
		(net "M_B_CPU0_SA_RSP<0>")
	)
	(segment
		(start 327.417938 -267.118338)
		(end 327.874376 -267.118338)
		(width 0.0889)
		(layer "In13.Cu")
		(net "M_B_CPU0_SA_RSP<0>")
	)
	(segment
		(start 299.82414 -269.585186)
		(end 300.249336 -269.15999)
		(width 0.11684)
		(layer "In13.Cu")
		(net "M_B_CPU0_SA_RSP<0>")
	)
	(segment
		(start 331.634084 -267.118592)
		(end 331.642466 -267.123418)
		(width 0.0889)
		(layer "In13.Cu")
		(net "M_B_CPU0_SA_RSP<0>")
	)
	(arc
		(start 333.88808 -267.118592)
		(mid 334.171036 -267.042415)
		(end 334.453992 -267.118592)
		(width 0.0889)
		(layer "In13.Cu")
		(net "M_B_CPU0_SA_RSP<0>")
	)
	(arc
		(start 331.642466 -267.123418)
		(mid 331.825974 -267.168912)
		(end 332.008226 -267.118592)
		(width 0.0889)
		(layer "In13.Cu")
		(net "M_B_CPU0_SA_RSP<0>")
	)
	(arc
		(start 328.248264 -267.118592)
		(mid 328.53122 -267.042415)
		(end 328.814176 -267.118592)
		(width 0.0889)
		(layer "In13.Cu")
		(net "M_B_CPU0_SA_RSP<0>")
	)
	(arc
		(start 335.77784 -267.113258)
		(mid 336.057574 -267.03789)
		(end 336.337402 -267.113004)
		(width 0.0889)
		(layer "In13.Cu")
		(net "M_B_CPU0_SA_RSP<0>")
	)
	(arc
		(start 329.188064 -267.118592)
		(mid 329.47102 -267.042415)
		(end 329.753976 -267.118592)
		(width 0.0889)
		(layer "In13.Cu")
		(net "M_B_CPU0_SA_RSP<0>")
	)
	(arc
		(start 336.337402 -267.113004)
		(mid 336.521298 -267.162484)
		(end 336.705194 -267.113004)
		(width 0.0889)
		(layer "In13.Cu")
		(net "M_B_CPU0_SA_RSP<0>")
	)
	(arc
		(start 331.068172 -267.118592)
		(mid 331.351128 -267.042415)
		(end 331.634084 -267.118592)
		(width 0.0889)
		(layer "In13.Cu")
		(net "M_B_CPU0_SA_RSP<0>")
	)
	(arc
		(start 332.94828 -267.118592)
		(mid 333.231126 -267.042415)
		(end 333.513938 -267.118592)
		(width 0.0889)
		(layer "In13.Cu")
		(net "M_B_CPU0_SA_RSP<0>")
	)
	(arc
		(start 337.277202 -267.113004)
		(mid 337.428861 -267.160958)
		(end 337.586574 -267.140182)
		(width 0.0889)
		(layer "In13.Cu")
		(net "M_B_CPU0_SA_RSP<0>")
	)
	(arc
		(start 334.828134 -267.118592)
		(mid 335.11109 -267.042415)
		(end 335.394046 -267.118592)
		(width 0.0889)
		(layer "In13.Cu")
		(net "M_B_CPU0_SA_RSP<0>")
	)
	(arc
		(start 334.453992 -267.118592)
		(mid 334.636243 -267.168942)
		(end 334.819752 -267.123418)
		(width 0.0889)
		(layer "In13.Cu")
		(net "M_B_CPU0_SA_RSP<0>")
	)
	(arc
		(start 333.513938 -267.118592)
		(mid 333.700882 -267.168916)
		(end 333.887826 -267.118592)
		(width 0.0889)
		(layer "In13.Cu")
		(net "M_B_CPU0_SA_RSP<0>")
	)
	(arc
		(start 327.890632 -267.127736)
		(mid 328.070614 -267.168836)
		(end 328.248264 -267.118592)
		(width 0.0889)
		(layer "In13.Cu")
		(net "M_B_CPU0_SA_RSP<0>")
	)
	(arc
		(start 335.402428 -267.123418)
		(mid 335.585936 -267.168912)
		(end 335.768188 -267.118592)
		(width 0.0889)
		(layer "In13.Cu")
		(net "M_B_CPU0_SA_RSP<0>")
	)
	(arc
		(start 330.702412 -267.123418)
		(mid 330.88592 -267.168912)
		(end 331.068172 -267.118592)
		(width 0.0889)
		(layer "In13.Cu")
		(net "M_B_CPU0_SA_RSP<0>")
	)
	(arc
		(start 330.128118 -267.118592)
		(mid 330.411074 -267.042415)
		(end 330.69403 -267.118592)
		(width 0.0889)
		(layer "In13.Cu")
		(net "M_B_CPU0_SA_RSP<0>")
	)
	(arc
		(start 336.705194 -267.113004)
		(mid 336.991198 -267.036052)
		(end 337.277202 -267.113004)
		(width 0.0889)
		(layer "In13.Cu")
		(net "M_B_CPU0_SA_RSP<0>")
	)
	(arc
		(start 328.814176 -267.118592)
		(mid 329.00112 -267.168847)
		(end 329.188064 -267.118592)
		(width 0.0889)
		(layer "In13.Cu")
		(net "M_B_CPU0_SA_RSP<0>")
	)
	(arc
		(start 332.008226 -267.118592)
		(mid 332.291182 -267.042415)
		(end 332.574138 -267.118592)
		(width 0.0889)
		(layer "In13.Cu")
		(net "M_B_CPU0_SA_RSP<0>")
	)
	(arc
		(start 329.753976 -267.118592)
		(mid 329.936227 -267.168942)
		(end 330.119736 -267.123418)
		(width 0.0889)
		(layer "In13.Cu")
		(net "M_B_CPU0_SA_RSP<0>")
	)
	(arc
		(start 332.574138 -267.118592)
		(mid 332.761226 -267.168974)
		(end 332.94828 -267.118592)
		(width 0.0889)
		(layer "In13.Cu")
		(net "M_B_CPU0_SA_RSP<0>")
	)
	(segment
		(start 337.627976 -256.090166)
		(end 337.161124 -255.824228)
		(width 0.10668)
		(layer "F.Cu")
		(net "M_B_CPU0_SA_PAR")
	)
	(segment
		(start 301.0027 -255.427226)
		(end 301.207424 -255.427226)
		(width 0.14478)
		(layer "In13.Cu")
		(net "M_B_CPU0_SA_PAR")
	)
	(segment
		(start 336.034126 -255.501648)
		(end 336.042508 -255.496822)
		(width 0.0889)
		(layer "In13.Cu")
		(net "M_B_CPU0_SA_PAR")
	)
	(segment
		(start 301.207424 -255.427226)
		(end 301.36465 -255.27)
		(width 0.14478)
		(layer "In13.Cu")
		(net "M_B_CPU0_SA_PAR")
	)
	(segment
		(start 301.569374 -255.27)
		(end 302.043084 -255.74371)
		(width 0.14478)
		(layer "In13.Cu")
		(net "M_B_CPU0_SA_PAR")
	)
	(segment
		(start 336.911188 -255.533398)
		(end 337.0072 -255.558798)
		(width 0.0889)
		(layer "In13.Cu")
		(net "M_B_CPU0_SA_PAR")
	)
	(segment
		(start 331.33411 -255.501648)
		(end 331.342492 -255.496822)
		(width 0.0889)
		(layer "In13.Cu")
		(net "M_B_CPU0_SA_PAR")
	)
	(segment
		(start 329.819762 -255.496822)
		(end 329.828144 -255.501648)
		(width 0.0889)
		(layer "In13.Cu")
		(net "M_B_CPU0_SA_PAR")
	)
	(segment
		(start 325.791322 -255.577848)
		(end 326.351138 -255.577848)
		(width 0.0889)
		(layer "In13.Cu")
		(net "M_B_CPU0_SA_PAR")
	)
	(segment
		(start 334.519778 -255.496822)
		(end 334.52816 -255.501648)
		(width 0.0889)
		(layer "In13.Cu")
		(net "M_B_CPU0_SA_PAR")
	)
	(segment
		(start 335.094072 -255.501648)
		(end 335.102454 -255.496822)
		(width 0.0889)
		(layer "In13.Cu")
		(net "M_B_CPU0_SA_PAR")
	)
	(segment
		(start 320.967354 -256.60985)
		(end 324.500494 -256.60985)
		(width 0.14478)
		(layer "In13.Cu")
		(net "M_B_CPU0_SA_PAR")
	)
	(segment
		(start 312.928254 -255.74371)
		(end 313.516264 -255.1557)
		(width 0.14478)
		(layer "In13.Cu")
		(net "M_B_CPU0_SA_PAR")
	)
	(segment
		(start 302.043084 -255.74371)
		(end 312.928254 -255.74371)
		(width 0.14478)
		(layer "In13.Cu")
		(net "M_B_CPU0_SA_PAR")
	)
	(segment
		(start 337.0072 -255.558798)
		(end 337.161124 -255.824228)
		(width 0.0889)
		(layer "In13.Cu")
		(net "M_B_CPU0_SA_PAR")
	)
	(segment
		(start 327.939908 -255.496822)
		(end 327.94829 -255.501648)
		(width 0.0889)
		(layer "In13.Cu")
		(net "M_B_CPU0_SA_PAR")
	)
	(segment
		(start 330.394056 -255.501648)
		(end 330.402438 -255.496822)
		(width 0.0889)
		(layer "In13.Cu")
		(net "M_B_CPU0_SA_PAR")
	)
	(segment
		(start 300.817534 -255.24206)
		(end 301.0027 -255.427226)
		(width 0.14478)
		(layer "In13.Cu")
		(net "M_B_CPU0_SA_PAR")
	)
	(segment
		(start 300.817534 -255.037336)
		(end 300.817534 -255.24206)
		(width 0.14478)
		(layer "In13.Cu")
		(net "M_B_CPU0_SA_PAR")
	)
	(segment
		(start 326.633586 -255.501902)
		(end 326.649842 -255.492504)
		(width 0.0889)
		(layer "In13.Cu")
		(net "M_B_CPU0_SA_PAR")
	)
	(segment
		(start 299.82414 -254.284988)
		(end 300.584362 -254.284988)
		(width 0.14478)
		(layer "In13.Cu")
		(net "M_B_CPU0_SA_PAR")
	)
	(segment
		(start 324.500494 -256.60985)
		(end 324.75932 -256.60985)
		(width 0.0889)
		(layer "In13.Cu")
		(net "M_B_CPU0_SA_PAR")
	)
	(segment
		(start 333.579724 -255.496822)
		(end 333.588106 -255.501648)
		(width 0.0889)
		(layer "In13.Cu")
		(net "M_B_CPU0_SA_PAR")
	)
	(segment
		(start 324.75932 -256.60985)
		(end 325.791322 -255.577848)
		(width 0.0889)
		(layer "In13.Cu")
		(net "M_B_CPU0_SA_PAR")
	)
	(segment
		(start 313.516264 -255.1557)
		(end 319.513204 -255.1557)
		(width 0.14478)
		(layer "In13.Cu")
		(net "M_B_CPU0_SA_PAR")
	)
	(segment
		(start 327.007474 -255.501648)
		(end 327.017888 -255.507744)
		(width 0.0889)
		(layer "In13.Cu")
		(net "M_B_CPU0_SA_PAR")
	)
	(segment
		(start 300.97476 -254.88011)
		(end 300.817534 -255.037336)
		(width 0.14478)
		(layer "In13.Cu")
		(net "M_B_CPU0_SA_PAR")
	)
	(segment
		(start 301.36465 -255.27)
		(end 301.569374 -255.27)
		(width 0.14478)
		(layer "In13.Cu")
		(net "M_B_CPU0_SA_PAR")
	)
	(segment
		(start 319.513204 -255.1557)
		(end 320.967354 -256.60985)
		(width 0.14478)
		(layer "In13.Cu")
		(net "M_B_CPU0_SA_PAR")
	)
	(segment
		(start 300.97476 -254.675386)
		(end 300.97476 -254.88011)
		(width 0.14478)
		(layer "In13.Cu")
		(net "M_B_CPU0_SA_PAR")
	)
	(segment
		(start 300.584362 -254.284988)
		(end 300.97476 -254.675386)
		(width 0.14478)
		(layer "In13.Cu")
		(net "M_B_CPU0_SA_PAR")
	)
	(arc
		(start 334.154018 -255.501648)
		(mid 334.336269 -255.451298)
		(end 334.519778 -255.496822)
		(width 0.0889)
		(layer "In13.Cu")
		(net "M_B_CPU0_SA_PAR")
	)
	(arc
		(start 335.102454 -255.496822)
		(mid 335.285962 -255.451328)
		(end 335.468214 -255.501648)
		(width 0.0889)
		(layer "In13.Cu")
		(net "M_B_CPU0_SA_PAR")
	)
	(arc
		(start 326.351138 -255.577848)
		(mid 326.497386 -255.558543)
		(end 326.633586 -255.501902)
		(width 0.0889)
		(layer "In13.Cu")
		(net "M_B_CPU0_SA_PAR")
	)
	(arc
		(start 328.514202 -255.501648)
		(mid 328.701146 -255.451393)
		(end 328.88809 -255.501648)
		(width 0.0889)
		(layer "In13.Cu")
		(net "M_B_CPU0_SA_PAR")
	)
	(arc
		(start 334.52816 -255.501648)
		(mid 334.811116 -255.577825)
		(end 335.094072 -255.501648)
		(width 0.0889)
		(layer "In13.Cu")
		(net "M_B_CPU0_SA_PAR")
	)
	(arc
		(start 335.468214 -255.501648)
		(mid 335.75117 -255.577825)
		(end 336.034126 -255.501648)
		(width 0.0889)
		(layer "In13.Cu")
		(net "M_B_CPU0_SA_PAR")
	)
	(arc
		(start 327.017888 -255.507744)
		(mid 327.296574 -255.577964)
		(end 327.57364 -255.501648)
		(width 0.0889)
		(layer "In13.Cu")
		(net "M_B_CPU0_SA_PAR")
	)
	(arc
		(start 333.588106 -255.501648)
		(mid 333.871062 -255.577825)
		(end 334.154018 -255.501648)
		(width 0.0889)
		(layer "In13.Cu")
		(net "M_B_CPU0_SA_PAR")
	)
	(arc
		(start 333.213964 -255.501648)
		(mid 333.396215 -255.451298)
		(end 333.579724 -255.496822)
		(width 0.0889)
		(layer "In13.Cu")
		(net "M_B_CPU0_SA_PAR")
	)
	(arc
		(start 331.708252 -255.501648)
		(mid 331.991208 -255.577825)
		(end 332.274164 -255.501648)
		(width 0.0889)
		(layer "In13.Cu")
		(net "M_B_CPU0_SA_PAR")
	)
	(arc
		(start 331.342492 -255.496822)
		(mid 331.526 -255.451328)
		(end 331.708252 -255.501648)
		(width 0.0889)
		(layer "In13.Cu")
		(net "M_B_CPU0_SA_PAR")
	)
	(arc
		(start 327.57364 -255.501648)
		(mid 327.756145 -255.451171)
		(end 327.939908 -255.496822)
		(width 0.0889)
		(layer "In13.Cu")
		(net "M_B_CPU0_SA_PAR")
	)
	(arc
		(start 332.274164 -255.501648)
		(mid 332.461108 -255.451393)
		(end 332.648052 -255.501648)
		(width 0.0889)
		(layer "In13.Cu")
		(net "M_B_CPU0_SA_PAR")
	)
	(arc
		(start 330.768198 -255.501648)
		(mid 331.051154 -255.577825)
		(end 331.33411 -255.501648)
		(width 0.0889)
		(layer "In13.Cu")
		(net "M_B_CPU0_SA_PAR")
	)
	(arc
		(start 329.454002 -255.501648)
		(mid 329.636253 -255.451298)
		(end 329.819762 -255.496822)
		(width 0.0889)
		(layer "In13.Cu")
		(net "M_B_CPU0_SA_PAR")
	)
	(arc
		(start 329.828144 -255.501648)
		(mid 330.1111 -255.577825)
		(end 330.394056 -255.501648)
		(width 0.0889)
		(layer "In13.Cu")
		(net "M_B_CPU0_SA_PAR")
	)
	(arc
		(start 330.402438 -255.496822)
		(mid 330.585946 -255.451328)
		(end 330.768198 -255.501648)
		(width 0.0889)
		(layer "In13.Cu")
		(net "M_B_CPU0_SA_PAR")
	)
	(arc
		(start 336.408268 -255.501648)
		(mid 336.655981 -255.576868)
		(end 336.911188 -255.533398)
		(width 0.0889)
		(layer "In13.Cu")
		(net "M_B_CPU0_SA_PAR")
	)
	(arc
		(start 332.648052 -255.501648)
		(mid 332.931008 -255.577825)
		(end 333.213964 -255.501648)
		(width 0.0889)
		(layer "In13.Cu")
		(net "M_B_CPU0_SA_PAR")
	)
	(arc
		(start 328.88809 -255.501648)
		(mid 329.171046 -255.577825)
		(end 329.454002 -255.501648)
		(width 0.0889)
		(layer "In13.Cu")
		(net "M_B_CPU0_SA_PAR")
	)
	(arc
		(start 326.649842 -255.492504)
		(mid 326.829824 -255.451404)
		(end 327.007474 -255.501648)
		(width 0.0889)
		(layer "In13.Cu")
		(net "M_B_CPU0_SA_PAR")
	)
	(arc
		(start 327.94829 -255.501648)
		(mid 328.231246 -255.577825)
		(end 328.514202 -255.501648)
		(width 0.0889)
		(layer "In13.Cu")
		(net "M_B_CPU0_SA_PAR")
	)
	(arc
		(start 336.042508 -255.496822)
		(mid 336.226016 -255.451328)
		(end 336.408268 -255.501648)
		(width 0.0889)
		(layer "In13.Cu")
		(net "M_B_CPU0_SA_PAR")
	)
	(segment
		(start 337.627976 -247.990106)
		(end 337.161124 -247.724168)
		(width 0.12954)
		(layer "F.Cu")
		(net "M_B_CPU0_SA_DQS_DP<9>")
	)
	(segment
		(start 336.040984 -247.394222)
		(end 336.032602 -247.399048)
		(width 0.09525)
		(layer "In13.Cu")
		(net "M_B_CPU0_SA_DQS_DP<9>")
	)
	(segment
		(start 295.983406 -239.575848)
		(end 295.724072 -239.835182)
		(width 0.16002)
		(layer "In13.Cu")
		(net "M_B_CPU0_SA_DQS_DP<9>")
	)
	(segment
		(start 337.161124 -247.724168)
		(end 337.0072 -247.458738)
		(width 0.09525)
		(layer "In13.Cu")
		(net "M_B_CPU0_SA_DQS_DP<9>")
	)
	(segment
		(start 298.628562 -239.341152)
		(end 297.920918 -239.341152)
		(width 0.16002)
		(layer "In13.Cu")
		(net "M_B_CPU0_SA_DQS_DP<9>")
	)
	(segment
		(start 297.35399 -239.575848)
		(end 295.983406 -239.575848)
		(width 0.16002)
		(layer "In13.Cu")
		(net "M_B_CPU0_SA_DQS_DP<9>")
	)
	(segment
		(start 326.644 -247.39219)
		(end 326.632062 -247.399048)
		(width 0.09525)
		(layer "In13.Cu")
		(net "M_B_CPU0_SA_DQS_DP<9>")
	)
	(segment
		(start 323.919596 -247.335802)
		(end 323.895974 -247.335802)
		(width 0.09525)
		(layer "In13.Cu")
		(net "M_B_CPU0_SA_DQS_DP<9>")
	)
	(segment
		(start 325.727568 -247.347486)
		(end 325.492872 -247.582182)
		(width 0.09525)
		(layer "In13.Cu")
		(net "M_B_CPU0_SA_DQS_DP<9>")
	)
	(segment
		(start 331.340968 -247.394222)
		(end 331.332586 -247.399048)
		(width 0.09525)
		(layer "In13.Cu")
		(net "M_B_CPU0_SA_DQS_DP<9>")
	)
	(segment
		(start 307.80736 -242.26012)
		(end 307.002434 -242.26012)
		(width 0.16002)
		(layer "In13.Cu")
		(net "M_B_CPU0_SA_DQS_DP<9>")
	)
	(segment
		(start 323.028056 -247.164352)
		(end 312.711592 -247.164352)
		(width 0.16002)
		(layer "In13.Cu")
		(net "M_B_CPU0_SA_DQS_DP<9>")
	)
	(segment
		(start 302.423322 -240.137188)
		(end 301.894494 -240.137188)
		(width 0.16002)
		(layer "In13.Cu")
		(net "M_B_CPU0_SA_DQS_DP<9>")
	)
	(segment
		(start 304.76317 -240.020856)
		(end 303.983644 -239.698022)
		(width 0.16002)
		(layer "In13.Cu")
		(net "M_B_CPU0_SA_DQS_DP<9>")
	)
	(segment
		(start 307.002434 -242.26012)
		(end 304.76317 -240.020856)
		(width 0.16002)
		(layer "In13.Cu")
		(net "M_B_CPU0_SA_DQS_DP<9>")
	)
	(segment
		(start 312.711592 -247.164352)
		(end 307.80736 -242.26012)
		(width 0.16002)
		(layer "In13.Cu")
		(net "M_B_CPU0_SA_DQS_DP<9>")
	)
	(segment
		(start 303.483772 -239.698022)
		(end 302.423322 -240.137188)
		(width 0.16002)
		(layer "In13.Cu")
		(net "M_B_CPU0_SA_DQS_DP<9>")
	)
	(segment
		(start 323.895974 -247.335802)
		(end 323.199506 -247.335802)
		(width 0.16002)
		(layer "In13.Cu")
		(net "M_B_CPU0_SA_DQS_DP<9>")
	)
	(segment
		(start 329.829668 -247.399048)
		(end 329.821286 -247.394222)
		(width 0.09525)
		(layer "In13.Cu")
		(net "M_B_CPU0_SA_DQS_DP<9>")
	)
	(segment
		(start 325.492872 -247.582182)
		(end 324.443598 -247.582182)
		(width 0.09525)
		(layer "In13.Cu")
		(net "M_B_CPU0_SA_DQS_DP<9>")
	)
	(segment
		(start 334.529684 -247.399048)
		(end 334.521302 -247.394222)
		(width 0.09525)
		(layer "In13.Cu")
		(net "M_B_CPU0_SA_DQS_DP<9>")
	)
	(segment
		(start 323.978778 -247.27662)
		(end 323.919596 -247.335802)
		(width 0.09525)
		(layer "In13.Cu")
		(net "M_B_CPU0_SA_DQS_DP<9>")
	)
	(segment
		(start 324.443598 -247.582182)
		(end 324.138036 -247.27662)
		(width 0.09525)
		(layer "In13.Cu")
		(net "M_B_CPU0_SA_DQS_DP<9>")
	)
	(segment
		(start 335.10093 -247.394222)
		(end 335.092548 -247.399048)
		(width 0.09525)
		(layer "In13.Cu")
		(net "M_B_CPU0_SA_DQS_DP<9>")
	)
	(segment
		(start 333.58963 -247.399048)
		(end 333.581248 -247.394222)
		(width 0.09525)
		(layer "In13.Cu")
		(net "M_B_CPU0_SA_DQS_DP<9>")
	)
	(segment
		(start 337.0072 -247.458738)
		(end 336.906362 -247.432068)
		(width 0.09525)
		(layer "In13.Cu")
		(net "M_B_CPU0_SA_DQS_DP<9>")
	)
	(segment
		(start 323.199506 -247.335802)
		(end 323.028056 -247.164352)
		(width 0.16002)
		(layer "In13.Cu")
		(net "M_B_CPU0_SA_DQS_DP<9>")
	)
	(segment
		(start 299.519594 -239.710214)
		(end 298.628562 -239.341152)
		(width 0.16002)
		(layer "In13.Cu")
		(net "M_B_CPU0_SA_DQS_DP<9>")
	)
	(segment
		(start 300.863254 -239.710214)
		(end 299.519594 -239.710214)
		(width 0.16002)
		(layer "In13.Cu")
		(net "M_B_CPU0_SA_DQS_DP<9>")
	)
	(segment
		(start 326.632062 -247.399048)
		(end 326.611234 -247.41124)
		(width 0.09525)
		(layer "In13.Cu")
		(net "M_B_CPU0_SA_DQS_DP<9>")
	)
	(segment
		(start 324.138036 -247.27662)
		(end 323.978778 -247.27662)
		(width 0.09525)
		(layer "In13.Cu")
		(net "M_B_CPU0_SA_DQS_DP<9>")
	)
	(segment
		(start 303.983644 -239.698022)
		(end 303.483772 -239.698022)
		(width 0.16002)
		(layer "In13.Cu")
		(net "M_B_CPU0_SA_DQS_DP<9>")
	)
	(segment
		(start 297.920918 -239.341152)
		(end 297.35399 -239.575848)
		(width 0.16002)
		(layer "In13.Cu")
		(net "M_B_CPU0_SA_DQS_DP<9>")
	)
	(segment
		(start 301.894494 -240.137188)
		(end 300.863254 -239.710214)
		(width 0.16002)
		(layer "In13.Cu")
		(net "M_B_CPU0_SA_DQS_DP<9>")
	)
	(segment
		(start 325.880222 -247.347486)
		(end 325.727568 -247.347486)
		(width 0.09525)
		(layer "In13.Cu")
		(net "M_B_CPU0_SA_DQS_DP<9>")
	)
	(segment
		(start 330.400914 -247.394222)
		(end 330.392532 -247.399048)
		(width 0.09525)
		(layer "In13.Cu")
		(net "M_B_CPU0_SA_DQS_DP<9>")
	)
	(segment
		(start 327.019412 -247.405144)
		(end 327.008998 -247.399048)
		(width 0.09525)
		(layer "In13.Cu")
		(net "M_B_CPU0_SA_DQS_DP<9>")
	)
	(segment
		(start 327.949814 -247.399048)
		(end 327.941432 -247.394222)
		(width 0.09525)
		(layer "In13.Cu")
		(net "M_B_CPU0_SA_DQS_DP<9>")
	)
	(arc
		(start 328.512678 -247.399048)
		(mid 328.231246 -247.474803)
		(end 327.949814 -247.399048)
		(width 0.09525)
		(layer "In13.Cu")
		(net "M_B_CPU0_SA_DQS_DP<9>")
	)
	(arc
		(start 336.032602 -247.399048)
		(mid 335.75117 -247.474803)
		(end 335.469738 -247.399048)
		(width 0.09525)
		(layer "In13.Cu")
		(net "M_B_CPU0_SA_DQS_DP<9>")
	)
	(arc
		(start 331.332586 -247.399048)
		(mid 331.051154 -247.474803)
		(end 330.769722 -247.399048)
		(width 0.09525)
		(layer "In13.Cu")
		(net "M_B_CPU0_SA_DQS_DP<9>")
	)
	(arc
		(start 327.941432 -247.394222)
		(mid 327.756146 -247.348186)
		(end 327.572116 -247.399048)
		(width 0.09525)
		(layer "In13.Cu")
		(net "M_B_CPU0_SA_DQS_DP<9>")
	)
	(arc
		(start 327.572116 -247.399048)
		(mid 327.296573 -247.474897)
		(end 327.019412 -247.405144)
		(width 0.09525)
		(layer "In13.Cu")
		(net "M_B_CPU0_SA_DQS_DP<9>")
	)
	(arc
		(start 329.821286 -247.394222)
		(mid 329.636254 -247.348308)
		(end 329.452478 -247.399048)
		(width 0.09525)
		(layer "In13.Cu")
		(net "M_B_CPU0_SA_DQS_DP<9>")
	)
	(arc
		(start 333.581248 -247.394222)
		(mid 333.396216 -247.348308)
		(end 333.21244 -247.399048)
		(width 0.09525)
		(layer "In13.Cu")
		(net "M_B_CPU0_SA_DQS_DP<9>")
	)
	(arc
		(start 334.521302 -247.394222)
		(mid 334.33627 -247.348308)
		(end 334.152494 -247.399048)
		(width 0.09525)
		(layer "In13.Cu")
		(net "M_B_CPU0_SA_DQS_DP<9>")
	)
	(arc
		(start 329.452478 -247.399048)
		(mid 329.171046 -247.474803)
		(end 328.889614 -247.399048)
		(width 0.09525)
		(layer "In13.Cu")
		(net "M_B_CPU0_SA_DQS_DP<9>")
	)
	(arc
		(start 332.27264 -247.399048)
		(mid 331.991208 -247.474803)
		(end 331.709776 -247.399048)
		(width 0.09525)
		(layer "In13.Cu")
		(net "M_B_CPU0_SA_DQS_DP<9>")
	)
	(arc
		(start 326.069198 -247.399048)
		(mid 325.978121 -247.360764)
		(end 325.880222 -247.347486)
		(width 0.09525)
		(layer "In13.Cu")
		(net "M_B_CPU0_SA_DQS_DP<9>")
	)
	(arc
		(start 328.889614 -247.399048)
		(mid 328.701146 -247.348371)
		(end 328.512678 -247.399048)
		(width 0.09525)
		(layer "In13.Cu")
		(net "M_B_CPU0_SA_DQS_DP<9>")
	)
	(arc
		(start 335.469738 -247.399048)
		(mid 335.285963 -247.348276)
		(end 335.10093 -247.394222)
		(width 0.09525)
		(layer "In13.Cu")
		(net "M_B_CPU0_SA_DQS_DP<9>")
	)
	(arc
		(start 331.709776 -247.399048)
		(mid 331.526001 -247.348276)
		(end 331.340968 -247.394222)
		(width 0.09525)
		(layer "In13.Cu")
		(net "M_B_CPU0_SA_DQS_DP<9>")
	)
	(arc
		(start 336.409792 -247.399048)
		(mid 336.226017 -247.348276)
		(end 336.040984 -247.394222)
		(width 0.09525)
		(layer "In13.Cu")
		(net "M_B_CPU0_SA_DQS_DP<9>")
	)
	(arc
		(start 330.392532 -247.399048)
		(mid 330.1111 -247.474803)
		(end 329.829668 -247.399048)
		(width 0.09525)
		(layer "In13.Cu")
		(net "M_B_CPU0_SA_DQS_DP<9>")
	)
	(arc
		(start 332.649576 -247.399048)
		(mid 332.461108 -247.348371)
		(end 332.27264 -247.399048)
		(width 0.09525)
		(layer "In13.Cu")
		(net "M_B_CPU0_SA_DQS_DP<9>")
	)
	(arc
		(start 336.906362 -247.432068)
		(mid 336.89624 -247.436103)
		(end 336.886042 -247.439942)
		(width 0.09525)
		(layer "In13.Cu")
		(net "M_B_CPU0_SA_DQS_DP<9>")
	)
	(arc
		(start 336.886042 -247.439942)
		(mid 336.64333 -247.472825)
		(end 336.409792 -247.399048)
		(width 0.09525)
		(layer "In13.Cu")
		(net "M_B_CPU0_SA_DQS_DP<9>")
	)
	(arc
		(start 335.092548 -247.399048)
		(mid 334.811116 -247.474803)
		(end 334.529684 -247.399048)
		(width 0.09525)
		(layer "In13.Cu")
		(net "M_B_CPU0_SA_DQS_DP<9>")
	)
	(arc
		(start 333.21244 -247.399048)
		(mid 332.931008 -247.474803)
		(end 332.649576 -247.399048)
		(width 0.09525)
		(layer "In13.Cu")
		(net "M_B_CPU0_SA_DQS_DP<9>")
	)
	(arc
		(start 327.008998 -247.399048)
		(mid 326.827382 -247.348311)
		(end 326.644 -247.39219)
		(width 0.09525)
		(layer "In13.Cu")
		(net "M_B_CPU0_SA_DQS_DP<9>")
	)
	(arc
		(start 334.152494 -247.399048)
		(mid 333.871062 -247.474803)
		(end 333.58963 -247.399048)
		(width 0.09525)
		(layer "In13.Cu")
		(net "M_B_CPU0_SA_DQS_DP<9>")
	)
	(arc
		(start 330.769722 -247.399048)
		(mid 330.585947 -247.348276)
		(end 330.400914 -247.394222)
		(width 0.09525)
		(layer "In13.Cu")
		(net "M_B_CPU0_SA_DQS_DP<9>")
	)
	(arc
		(start 326.611234 -247.41124)
		(mid 326.338629 -247.475036)
		(end 326.069198 -247.399048)
		(width 0.09525)
		(layer "In13.Cu")
		(net "M_B_CPU0_SA_DQS_DP<9>")
	)
	(segment
		(start 337.627976 -243.13007)
		(end 337.161124 -242.864132)
		(width 0.12954)
		(layer "F.Cu")
		(net "M_B_CPU0_SA_DQS_DP<8>")
	)
	(segment
		(start 305.522122 -231.210358)
		(end 305.187096 -230.875332)
		(width 0.16002)
		(layer "In13.Cu")
		(net "M_B_CPU0_SA_DQS_DP<8>")
	)
	(segment
		(start 323.837808 -241.549174)
		(end 318.147446 -241.549174)
		(width 0.16002)
		(layer "In13.Cu")
		(net "M_B_CPU0_SA_DQS_DP<8>")
	)
	(segment
		(start 325.284084 -242.159282)
		(end 324.617334 -242.159282)
		(width 0.09525)
		(layer "In13.Cu")
		(net "M_B_CPU0_SA_DQS_DP<8>")
	)
	(segment
		(start 325.880222 -242.48745)
		(end 325.612252 -242.48745)
		(width 0.09525)
		(layer "In13.Cu")
		(net "M_B_CPU0_SA_DQS_DP<8>")
	)
	(segment
		(start 305.187096 -230.875332)
		(end 304.463196 -230.875332)
		(width 0.16002)
		(layer "In13.Cu")
		(net "M_B_CPU0_SA_DQS_DP<8>")
	)
	(segment
		(start 327.572624 -242.539012)
		(end 327.557892 -242.547648)
		(width 0.09525)
		(layer "In13.Cu")
		(net "M_B_CPU0_SA_DQS_DP<8>")
	)
	(segment
		(start 318.147446 -241.549174)
		(end 307.80863 -231.210358)
		(width 0.16002)
		(layer "In13.Cu")
		(net "M_B_CPU0_SA_DQS_DP<8>")
	)
	(segment
		(start 333.58963 -242.539012)
		(end 333.581248 -242.534186)
		(width 0.09525)
		(layer "In13.Cu")
		(net "M_B_CPU0_SA_DQS_DP<8>")
	)
	(segment
		(start 335.10093 -242.534186)
		(end 335.092548 -242.539012)
		(width 0.09525)
		(layer "In13.Cu")
		(net "M_B_CPU0_SA_DQS_DP<8>")
	)
	(segment
		(start 327.581006 -242.534186)
		(end 327.572624 -242.539012)
		(width 0.09525)
		(layer "In13.Cu")
		(net "M_B_CPU0_SA_DQS_DP<8>")
	)
	(segment
		(start 298.280836 -229.991158)
		(end 298.054522 -230.217472)
		(width 0.16002)
		(layer "In13.Cu")
		(net "M_B_CPU0_SA_DQS_DP<8>")
	)
	(segment
		(start 304.158904 -231.179624)
		(end 302.21682 -231.179624)
		(width 0.16002)
		(layer "In13.Cu")
		(net "M_B_CPU0_SA_DQS_DP<8>")
	)
	(segment
		(start 302.21682 -231.179624)
		(end 301.397416 -230.36022)
		(width 0.16002)
		(layer "In13.Cu")
		(net "M_B_CPU0_SA_DQS_DP<8>")
	)
	(segment
		(start 337.0072 -242.598702)
		(end 336.906362 -242.572032)
		(width 0.09525)
		(layer "In13.Cu")
		(net "M_B_CPU0_SA_DQS_DP<8>")
	)
	(segment
		(start 331.340968 -242.534186)
		(end 331.332586 -242.539012)
		(width 0.09525)
		(layer "In13.Cu")
		(net "M_B_CPU0_SA_DQS_DP<8>")
	)
	(segment
		(start 330.400914 -242.534186)
		(end 330.392532 -242.539012)
		(width 0.09525)
		(layer "In13.Cu")
		(net "M_B_CPU0_SA_DQS_DP<8>")
	)
	(segment
		(start 336.040984 -242.534186)
		(end 336.032602 -242.539012)
		(width 0.09525)
		(layer "In13.Cu")
		(net "M_B_CPU0_SA_DQS_DP<8>")
	)
	(segment
		(start 323.920612 -241.489992)
		(end 323.86143 -241.549174)
		(width 0.09525)
		(layer "In13.Cu")
		(net "M_B_CPU0_SA_DQS_DP<8>")
	)
	(segment
		(start 307.80863 -231.210358)
		(end 305.522122 -231.210358)
		(width 0.16002)
		(layer "In13.Cu")
		(net "M_B_CPU0_SA_DQS_DP<8>")
	)
	(segment
		(start 324.073774 -241.489992)
		(end 323.920612 -241.489992)
		(width 0.09525)
		(layer "In13.Cu")
		(net "M_B_CPU0_SA_DQS_DP<8>")
	)
	(segment
		(start 298.595542 -229.991158)
		(end 298.280836 -229.991158)
		(width 0.16002)
		(layer "In13.Cu")
		(net "M_B_CPU0_SA_DQS_DP<8>")
	)
	(segment
		(start 337.161124 -242.864132)
		(end 337.0072 -242.598702)
		(width 0.09525)
		(layer "In13.Cu")
		(net "M_B_CPU0_SA_DQS_DP<8>")
	)
	(segment
		(start 298.964604 -230.36022)
		(end 298.595542 -229.991158)
		(width 0.16002)
		(layer "In13.Cu")
		(net "M_B_CPU0_SA_DQS_DP<8>")
	)
	(segment
		(start 326.64654 -242.53063)
		(end 326.632062 -242.539012)
		(width 0.09525)
		(layer "In13.Cu")
		(net "M_B_CPU0_SA_DQS_DP<8>")
	)
	(segment
		(start 323.86143 -241.549174)
		(end 323.837808 -241.549174)
		(width 0.09525)
		(layer "In13.Cu")
		(net "M_B_CPU0_SA_DQS_DP<8>")
	)
	(segment
		(start 301.397416 -230.36022)
		(end 298.964604 -230.36022)
		(width 0.16002)
		(layer "In13.Cu")
		(net "M_B_CPU0_SA_DQS_DP<8>")
	)
	(segment
		(start 304.463196 -230.875332)
		(end 304.158904 -231.179624)
		(width 0.16002)
		(layer "In13.Cu")
		(net "M_B_CPU0_SA_DQS_DP<8>")
	)
	(segment
		(start 298.054522 -230.217472)
		(end 295.991788 -230.217472)
		(width 0.16002)
		(layer "In13.Cu")
		(net "M_B_CPU0_SA_DQS_DP<8>")
	)
	(segment
		(start 324.181978 -241.723926)
		(end 324.181978 -241.598196)
		(width 0.09525)
		(layer "In13.Cu")
		(net "M_B_CPU0_SA_DQS_DP<8>")
	)
	(segment
		(start 324.181978 -241.598196)
		(end 324.073774 -241.489992)
		(width 0.09525)
		(layer "In13.Cu")
		(net "M_B_CPU0_SA_DQS_DP<8>")
	)
	(segment
		(start 334.529684 -242.539012)
		(end 334.521302 -242.534186)
		(width 0.09525)
		(layer "In13.Cu")
		(net "M_B_CPU0_SA_DQS_DP<8>")
	)
	(segment
		(start 326.632062 -242.539012)
		(end 326.611234 -242.551204)
		(width 0.09525)
		(layer "In13.Cu")
		(net "M_B_CPU0_SA_DQS_DP<8>")
	)
	(segment
		(start 325.612252 -242.48745)
		(end 325.284084 -242.159282)
		(width 0.09525)
		(layer "In13.Cu")
		(net "M_B_CPU0_SA_DQS_DP<8>")
	)
	(segment
		(start 324.617334 -242.159282)
		(end 324.181978 -241.723926)
		(width 0.09525)
		(layer "In13.Cu")
		(net "M_B_CPU0_SA_DQS_DP<8>")
	)
	(segment
		(start 329.829668 -242.539012)
		(end 329.821286 -242.534186)
		(width 0.09525)
		(layer "In13.Cu")
		(net "M_B_CPU0_SA_DQS_DP<8>")
	)
	(segment
		(start 295.991788 -230.217472)
		(end 295.724072 -230.485188)
		(width 0.16002)
		(layer "In13.Cu")
		(net "M_B_CPU0_SA_DQS_DP<8>")
	)
	(arc
		(start 333.21244 -242.539012)
		(mid 332.931008 -242.614767)
		(end 332.649576 -242.539012)
		(width 0.09525)
		(layer "In13.Cu")
		(net "M_B_CPU0_SA_DQS_DP<8>")
	)
	(arc
		(start 336.409792 -242.539012)
		(mid 336.226017 -242.48824)
		(end 336.040984 -242.534186)
		(width 0.09525)
		(layer "In13.Cu")
		(net "M_B_CPU0_SA_DQS_DP<8>")
	)
	(arc
		(start 331.709776 -242.539012)
		(mid 331.526001 -242.48824)
		(end 331.340968 -242.534186)
		(width 0.09525)
		(layer "In13.Cu")
		(net "M_B_CPU0_SA_DQS_DP<8>")
	)
	(arc
		(start 327.949814 -242.539012)
		(mid 327.766039 -242.48824)
		(end 327.581006 -242.534186)
		(width 0.09525)
		(layer "In13.Cu")
		(net "M_B_CPU0_SA_DQS_DP<8>")
	)
	(arc
		(start 334.152494 -242.539012)
		(mid 333.871062 -242.614767)
		(end 333.58963 -242.539012)
		(width 0.09525)
		(layer "In13.Cu")
		(net "M_B_CPU0_SA_DQS_DP<8>")
	)
	(arc
		(start 330.392532 -242.539012)
		(mid 330.1111 -242.614767)
		(end 329.829668 -242.539012)
		(width 0.09525)
		(layer "In13.Cu")
		(net "M_B_CPU0_SA_DQS_DP<8>")
	)
	(arc
		(start 333.581248 -242.534186)
		(mid 333.396216 -242.488272)
		(end 333.21244 -242.539012)
		(width 0.09525)
		(layer "In13.Cu")
		(net "M_B_CPU0_SA_DQS_DP<8>")
	)
	(arc
		(start 335.469738 -242.539012)
		(mid 335.285963 -242.48824)
		(end 335.10093 -242.534186)
		(width 0.09525)
		(layer "In13.Cu")
		(net "M_B_CPU0_SA_DQS_DP<8>")
	)
	(arc
		(start 329.452478 -242.539012)
		(mid 329.171046 -242.614767)
		(end 328.889614 -242.539012)
		(width 0.09525)
		(layer "In13.Cu")
		(net "M_B_CPU0_SA_DQS_DP<8>")
	)
	(arc
		(start 328.889614 -242.539012)
		(mid 328.701146 -242.488335)
		(end 328.512678 -242.539012)
		(width 0.09525)
		(layer "In13.Cu")
		(net "M_B_CPU0_SA_DQS_DP<8>")
	)
	(arc
		(start 328.512678 -242.539012)
		(mid 328.231246 -242.614767)
		(end 327.949814 -242.539012)
		(width 0.09525)
		(layer "In13.Cu")
		(net "M_B_CPU0_SA_DQS_DP<8>")
	)
	(arc
		(start 326.611234 -242.551204)
		(mid 326.338629 -242.615)
		(end 326.069198 -242.539012)
		(width 0.09525)
		(layer "In13.Cu")
		(net "M_B_CPU0_SA_DQS_DP<8>")
	)
	(arc
		(start 327.557892 -242.547648)
		(mid 327.282433 -242.615033)
		(end 327.009252 -242.539012)
		(width 0.09525)
		(layer "In13.Cu")
		(net "M_B_CPU0_SA_DQS_DP<8>")
	)
	(arc
		(start 335.092548 -242.539012)
		(mid 334.811116 -242.614767)
		(end 334.529684 -242.539012)
		(width 0.09525)
		(layer "In13.Cu")
		(net "M_B_CPU0_SA_DQS_DP<8>")
	)
	(arc
		(start 332.649576 -242.539012)
		(mid 332.461108 -242.488335)
		(end 332.27264 -242.539012)
		(width 0.09525)
		(layer "In13.Cu")
		(net "M_B_CPU0_SA_DQS_DP<8>")
	)
	(arc
		(start 331.332586 -242.539012)
		(mid 331.051154 -242.614767)
		(end 330.769722 -242.539012)
		(width 0.09525)
		(layer "In13.Cu")
		(net "M_B_CPU0_SA_DQS_DP<8>")
	)
	(arc
		(start 326.069198 -242.539012)
		(mid 325.978121 -242.500728)
		(end 325.880222 -242.48745)
		(width 0.09525)
		(layer "In13.Cu")
		(net "M_B_CPU0_SA_DQS_DP<8>")
	)
	(arc
		(start 332.27264 -242.539012)
		(mid 331.991208 -242.614767)
		(end 331.709776 -242.539012)
		(width 0.09525)
		(layer "In13.Cu")
		(net "M_B_CPU0_SA_DQS_DP<8>")
	)
	(arc
		(start 327.009252 -242.539012)
		(mid 326.828973 -242.488181)
		(end 326.64654 -242.53063)
		(width 0.09525)
		(layer "In13.Cu")
		(net "M_B_CPU0_SA_DQS_DP<8>")
	)
	(arc
		(start 336.886042 -242.579906)
		(mid 336.64333 -242.612789)
		(end 336.409792 -242.539012)
		(width 0.09525)
		(layer "In13.Cu")
		(net "M_B_CPU0_SA_DQS_DP<8>")
	)
	(arc
		(start 329.821286 -242.534186)
		(mid 329.636254 -242.488272)
		(end 329.452478 -242.539012)
		(width 0.09525)
		(layer "In13.Cu")
		(net "M_B_CPU0_SA_DQS_DP<8>")
	)
	(arc
		(start 330.769722 -242.539012)
		(mid 330.585947 -242.48824)
		(end 330.400914 -242.534186)
		(width 0.09525)
		(layer "In13.Cu")
		(net "M_B_CPU0_SA_DQS_DP<8>")
	)
	(arc
		(start 336.906362 -242.572032)
		(mid 336.89624 -242.576067)
		(end 336.886042 -242.579906)
		(width 0.09525)
		(layer "In13.Cu")
		(net "M_B_CPU0_SA_DQS_DP<8>")
	)
	(arc
		(start 334.521302 -242.534186)
		(mid 334.33627 -242.488272)
		(end 334.152494 -242.539012)
		(width 0.09525)
		(layer "In13.Cu")
		(net "M_B_CPU0_SA_DQS_DP<8>")
	)
	(arc
		(start 336.032602 -242.539012)
		(mid 335.75117 -242.614767)
		(end 335.469738 -242.539012)
		(width 0.09525)
		(layer "In13.Cu")
		(net "M_B_CPU0_SA_DQS_DP<8>")
	)
	(segment
		(start 337.627976 -238.270034)
		(end 337.161124 -238.004096)
		(width 0.12954)
		(layer "F.Cu")
		(net "M_B_CPU0_SA_DQS_DP<7>")
	)
	(segment
		(start 337.161124 -238.004096)
		(end 337.0072 -237.738666)
		(width 0.09525)
		(layer "In13.Cu")
		(net "M_B_CPU0_SA_DQS_DP<7>")
	)
	(segment
		(start 305.152044 -221.525338)
		(end 304.463196 -221.525338)
		(width 0.16002)
		(layer "In13.Cu")
		(net "M_B_CPU0_SA_DQS_DP<7>")
	)
	(segment
		(start 305.486816 -221.86011)
		(end 305.152044 -221.525338)
		(width 0.16002)
		(layer "In13.Cu")
		(net "M_B_CPU0_SA_DQS_DP<7>")
	)
	(segment
		(start 301.376588 -221.010226)
		(end 298.964604 -221.010226)
		(width 0.16002)
		(layer "In13.Cu")
		(net "M_B_CPU0_SA_DQS_DP<7>")
	)
	(segment
		(start 298.964604 -221.010226)
		(end 298.595542 -220.641164)
		(width 0.16002)
		(layer "In13.Cu")
		(net "M_B_CPU0_SA_DQS_DP<7>")
	)
	(segment
		(start 323.978778 -235.87202)
		(end 323.919596 -235.931202)
		(width 0.09525)
		(layer "In13.Cu")
		(net "M_B_CPU0_SA_DQS_DP<7>")
	)
	(segment
		(start 304.463196 -221.525338)
		(end 304.158904 -221.82963)
		(width 0.16002)
		(layer "In13.Cu")
		(net "M_B_CPU0_SA_DQS_DP<7>")
	)
	(segment
		(start 335.10093 -237.67415)
		(end 335.092548 -237.678976)
		(width 0.09525)
		(layer "In13.Cu")
		(net "M_B_CPU0_SA_DQS_DP<7>")
	)
	(segment
		(start 325.148448 -236.793786)
		(end 325.148448 -236.50194)
		(width 0.09525)
		(layer "In13.Cu")
		(net "M_B_CPU0_SA_DQS_DP<7>")
	)
	(segment
		(start 327.592436 -237.668308)
		(end 327.57364 -237.678976)
		(width 0.09525)
		(layer "In13.Cu")
		(net "M_B_CPU0_SA_DQS_DP<7>")
	)
	(segment
		(start 323.895974 -235.931202)
		(end 321.617086 -235.931202)
		(width 0.16002)
		(layer "In13.Cu")
		(net "M_B_CPU0_SA_DQS_DP<7>")
	)
	(segment
		(start 324.473824 -236.232192)
		(end 324.113652 -235.87202)
		(width 0.09525)
		(layer "In13.Cu")
		(net "M_B_CPU0_SA_DQS_DP<7>")
	)
	(segment
		(start 325.148448 -236.50194)
		(end 324.8787 -236.232192)
		(width 0.09525)
		(layer "In13.Cu")
		(net "M_B_CPU0_SA_DQS_DP<7>")
	)
	(segment
		(start 331.340968 -237.67415)
		(end 331.332586 -237.678976)
		(width 0.09525)
		(layer "In13.Cu")
		(net "M_B_CPU0_SA_DQS_DP<7>")
	)
	(segment
		(start 308.406038 -222.363792)
		(end 307.902356 -221.86011)
		(width 0.16002)
		(layer "In13.Cu")
		(net "M_B_CPU0_SA_DQS_DP<7>")
	)
	(segment
		(start 296.856912 -220.867732)
		(end 295.99128 -220.867732)
		(width 0.16002)
		(layer "In13.Cu")
		(net "M_B_CPU0_SA_DQS_DP<7>")
	)
	(segment
		(start 330.400914 -237.67415)
		(end 330.392532 -237.678976)
		(width 0.09525)
		(layer "In13.Cu")
		(net "M_B_CPU0_SA_DQS_DP<7>")
	)
	(segment
		(start 337.0072 -237.738666)
		(end 336.906362 -237.711996)
		(width 0.09525)
		(layer "In13.Cu")
		(net "M_B_CPU0_SA_DQS_DP<7>")
	)
	(segment
		(start 302.195992 -221.82963)
		(end 301.376588 -221.010226)
		(width 0.16002)
		(layer "In13.Cu")
		(net "M_B_CPU0_SA_DQS_DP<7>")
	)
	(segment
		(start 333.58963 -237.678976)
		(end 333.581248 -237.67415)
		(width 0.09525)
		(layer "In13.Cu")
		(net "M_B_CPU0_SA_DQS_DP<7>")
	)
	(segment
		(start 324.113652 -235.87202)
		(end 323.978778 -235.87202)
		(width 0.09525)
		(layer "In13.Cu")
		(net "M_B_CPU0_SA_DQS_DP<7>")
	)
	(segment
		(start 323.919596 -235.931202)
		(end 323.895974 -235.931202)
		(width 0.09525)
		(layer "In13.Cu")
		(net "M_B_CPU0_SA_DQS_DP<7>")
	)
	(segment
		(start 298.595542 -220.641164)
		(end 297.08348 -220.641164)
		(width 0.16002)
		(layer "In13.Cu")
		(net "M_B_CPU0_SA_DQS_DP<7>")
	)
	(segment
		(start 336.040984 -237.67415)
		(end 336.032602 -237.678976)
		(width 0.09525)
		(layer "In13.Cu")
		(net "M_B_CPU0_SA_DQS_DP<7>")
	)
	(segment
		(start 307.902356 -221.86011)
		(end 305.486816 -221.86011)
		(width 0.16002)
		(layer "In13.Cu")
		(net "M_B_CPU0_SA_DQS_DP<7>")
	)
	(segment
		(start 295.99128 -220.867732)
		(end 295.724072 -221.13494)
		(width 0.16002)
		(layer "In13.Cu")
		(net "M_B_CPU0_SA_DQS_DP<7>")
	)
	(segment
		(start 327.57364 -237.678976)
		(end 327.546208 -237.694978)
		(width 0.09525)
		(layer "In13.Cu")
		(net "M_B_CPU0_SA_DQS_DP<7>")
	)
	(segment
		(start 321.617086 -235.931202)
		(end 308.406038 -222.720154)
		(width 0.16002)
		(layer "In13.Cu")
		(net "M_B_CPU0_SA_DQS_DP<7>")
	)
	(segment
		(start 327.012554 -237.678976)
		(end 326.99071 -237.666276)
		(width 0.09525)
		(layer "In13.Cu")
		(net "M_B_CPU0_SA_DQS_DP<7>")
	)
	(segment
		(start 304.158904 -221.82963)
		(end 302.195992 -221.82963)
		(width 0.16002)
		(layer "In13.Cu")
		(net "M_B_CPU0_SA_DQS_DP<7>")
	)
	(segment
		(start 308.406038 -222.720154)
		(end 308.406038 -222.363792)
		(width 0.16002)
		(layer "In13.Cu")
		(net "M_B_CPU0_SA_DQS_DP<7>")
	)
	(segment
		(start 329.829668 -237.678976)
		(end 329.821286 -237.67415)
		(width 0.09525)
		(layer "In13.Cu")
		(net "M_B_CPU0_SA_DQS_DP<7>")
	)
	(segment
		(start 326.110092 -237.75543)
		(end 325.148448 -236.793786)
		(width 0.09525)
		(layer "In13.Cu")
		(net "M_B_CPU0_SA_DQS_DP<7>")
	)
	(segment
		(start 297.08348 -220.641164)
		(end 296.856912 -220.867732)
		(width 0.16002)
		(layer "In13.Cu")
		(net "M_B_CPU0_SA_DQS_DP<7>")
	)
	(segment
		(start 324.8787 -236.232192)
		(end 324.473824 -236.232192)
		(width 0.09525)
		(layer "In13.Cu")
		(net "M_B_CPU0_SA_DQS_DP<7>")
	)
	(segment
		(start 334.529684 -237.678976)
		(end 334.521302 -237.67415)
		(width 0.09525)
		(layer "In13.Cu")
		(net "M_B_CPU0_SA_DQS_DP<7>")
	)
	(segment
		(start 326.351392 -237.75543)
		(end 326.110092 -237.75543)
		(width 0.09525)
		(layer "In13.Cu")
		(net "M_B_CPU0_SA_DQS_DP<7>")
	)
	(arc
		(start 336.409792 -237.678976)
		(mid 336.226017 -237.628204)
		(end 336.040984 -237.67415)
		(width 0.09525)
		(layer "In13.Cu")
		(net "M_B_CPU0_SA_DQS_DP<7>")
	)
	(arc
		(start 333.581248 -237.67415)
		(mid 333.396216 -237.628236)
		(end 333.21244 -237.678976)
		(width 0.09525)
		(layer "In13.Cu")
		(net "M_B_CPU0_SA_DQS_DP<7>")
	)
	(arc
		(start 328.889614 -237.678976)
		(mid 328.701146 -237.628299)
		(end 328.512678 -237.678976)
		(width 0.09525)
		(layer "In13.Cu")
		(net "M_B_CPU0_SA_DQS_DP<7>")
	)
	(arc
		(start 331.709776 -237.678976)
		(mid 331.526001 -237.628204)
		(end 331.340968 -237.67415)
		(width 0.09525)
		(layer "In13.Cu")
		(net "M_B_CPU0_SA_DQS_DP<7>")
	)
	(arc
		(start 335.092548 -237.678976)
		(mid 334.811116 -237.754731)
		(end 334.529684 -237.678976)
		(width 0.09525)
		(layer "In13.Cu")
		(net "M_B_CPU0_SA_DQS_DP<7>")
	)
	(arc
		(start 332.649576 -237.678976)
		(mid 332.461108 -237.628299)
		(end 332.27264 -237.678976)
		(width 0.09525)
		(layer "In13.Cu")
		(net "M_B_CPU0_SA_DQS_DP<7>")
	)
	(arc
		(start 332.27264 -237.678976)
		(mid 331.991208 -237.754731)
		(end 331.709776 -237.678976)
		(width 0.09525)
		(layer "In13.Cu")
		(net "M_B_CPU0_SA_DQS_DP<7>")
	)
	(arc
		(start 333.21244 -237.678976)
		(mid 332.931008 -237.754731)
		(end 332.649576 -237.678976)
		(width 0.09525)
		(layer "In13.Cu")
		(net "M_B_CPU0_SA_DQS_DP<7>")
	)
	(arc
		(start 327.546208 -237.694978)
		(mid 327.277365 -237.754529)
		(end 327.012554 -237.678976)
		(width 0.09525)
		(layer "In13.Cu")
		(net "M_B_CPU0_SA_DQS_DP<7>")
	)
	(arc
		(start 336.906362 -237.711996)
		(mid 336.89624 -237.716031)
		(end 336.886042 -237.71987)
		(width 0.09525)
		(layer "In13.Cu")
		(net "M_B_CPU0_SA_DQS_DP<7>")
	)
	(arc
		(start 330.769722 -237.678976)
		(mid 330.585947 -237.628204)
		(end 330.400914 -237.67415)
		(width 0.09525)
		(layer "In13.Cu")
		(net "M_B_CPU0_SA_DQS_DP<7>")
	)
	(arc
		(start 326.36587 -237.75543)
		(mid 326.358631 -237.755475)
		(end 326.351392 -237.75543)
		(width 0.09525)
		(layer "In13.Cu")
		(net "M_B_CPU0_SA_DQS_DP<7>")
	)
	(arc
		(start 336.886042 -237.71987)
		(mid 336.64333 -237.752753)
		(end 336.409792 -237.678976)
		(width 0.09525)
		(layer "In13.Cu")
		(net "M_B_CPU0_SA_DQS_DP<7>")
	)
	(arc
		(start 334.521302 -237.67415)
		(mid 334.33627 -237.628236)
		(end 334.152494 -237.678976)
		(width 0.09525)
		(layer "In13.Cu")
		(net "M_B_CPU0_SA_DQS_DP<7>")
	)
	(arc
		(start 334.152494 -237.678976)
		(mid 333.871062 -237.754731)
		(end 333.58963 -237.678976)
		(width 0.09525)
		(layer "In13.Cu")
		(net "M_B_CPU0_SA_DQS_DP<7>")
	)
	(arc
		(start 329.452478 -237.678976)
		(mid 329.171046 -237.754731)
		(end 328.889614 -237.678976)
		(width 0.09525)
		(layer "In13.Cu")
		(net "M_B_CPU0_SA_DQS_DP<7>")
	)
	(arc
		(start 326.634348 -237.678722)
		(mid 326.504955 -237.734042)
		(end 326.36587 -237.75543)
		(width 0.09525)
		(layer "In13.Cu")
		(net "M_B_CPU0_SA_DQS_DP<7>")
	)
	(arc
		(start 331.332586 -237.678976)
		(mid 331.051154 -237.754731)
		(end 330.769722 -237.678976)
		(width 0.09525)
		(layer "In13.Cu")
		(net "M_B_CPU0_SA_DQS_DP<7>")
	)
	(arc
		(start 330.392532 -237.678976)
		(mid 330.1111 -237.754731)
		(end 329.829668 -237.678976)
		(width 0.09525)
		(layer "In13.Cu")
		(net "M_B_CPU0_SA_DQS_DP<7>")
	)
	(arc
		(start 329.821286 -237.67415)
		(mid 329.636254 -237.628236)
		(end 329.452478 -237.678976)
		(width 0.09525)
		(layer "In13.Cu")
		(net "M_B_CPU0_SA_DQS_DP<7>")
	)
	(arc
		(start 336.032602 -237.678976)
		(mid 335.75117 -237.754731)
		(end 335.469738 -237.678976)
		(width 0.09525)
		(layer "In13.Cu")
		(net "M_B_CPU0_SA_DQS_DP<7>")
	)
	(arc
		(start 335.469738 -237.678976)
		(mid 335.285963 -237.628204)
		(end 335.10093 -237.67415)
		(width 0.09525)
		(layer "In13.Cu")
		(net "M_B_CPU0_SA_DQS_DP<7>")
	)
	(arc
		(start 328.512678 -237.678976)
		(mid 328.231246 -237.754731)
		(end 327.949814 -237.678976)
		(width 0.09525)
		(layer "In13.Cu")
		(net "M_B_CPU0_SA_DQS_DP<7>")
	)
	(arc
		(start 327.949814 -237.678976)
		(mid 327.772484 -237.628464)
		(end 327.592436 -237.668308)
		(width 0.09525)
		(layer "In13.Cu")
		(net "M_B_CPU0_SA_DQS_DP<7>")
	)
	(arc
		(start 326.99071 -237.666276)
		(mid 326.81096 -237.627647)
		(end 326.634348 -237.678722)
		(width 0.09525)
		(layer "In13.Cu")
		(net "M_B_CPU0_SA_DQS_DP<7>")
	)
	(segment
		(start 337.627976 -233.409998)
		(end 337.161124 -233.14406)
		(width 0.12954)
		(layer "F.Cu")
		(net "M_B_CPU0_SA_DQS_DP<6>")
	)
	(segment
		(start 337.0072 -232.87863)
		(end 337.161124 -233.14406)
		(width 0.09525)
		(layer "In13.Cu")
		(net "M_B_CPU0_SA_DQS_DP<6>")
	)
	(segment
		(start 335.092548 -232.81894)
		(end 335.10093 -232.814114)
		(width 0.09525)
		(layer "In13.Cu")
		(net "M_B_CPU0_SA_DQS_DP<6>")
	)
	(segment
		(start 334.521302 -232.814114)
		(end 334.529684 -232.81894)
		(width 0.09525)
		(layer "In13.Cu")
		(net "M_B_CPU0_SA_DQS_DP<6>")
	)
	(segment
		(start 336.032602 -232.81894)
		(end 336.040984 -232.814114)
		(width 0.09525)
		(layer "In13.Cu")
		(net "M_B_CPU0_SA_DQS_DP<6>")
	)
	(segment
		(start 305.20767 -212.190584)
		(end 305.527202 -212.510116)
		(width 0.16002)
		(layer "In13.Cu")
		(net "M_B_CPU0_SA_DQS_DP<6>")
	)
	(segment
		(start 301.92345 -212.190584)
		(end 305.20767 -212.190584)
		(width 0.16002)
		(layer "In13.Cu")
		(net "M_B_CPU0_SA_DQS_DP<6>")
	)
	(segment
		(start 333.581248 -232.814114)
		(end 333.58963 -232.81894)
		(width 0.09525)
		(layer "In13.Cu")
		(net "M_B_CPU0_SA_DQS_DP<6>")
	)
	(segment
		(start 320.905632 -227.165662)
		(end 324.084188 -230.344218)
		(width 0.16002)
		(layer "In13.Cu")
		(net "M_B_CPU0_SA_DQS_DP<6>")
	)
	(segment
		(start 305.527202 -212.510116)
		(end 307.777642 -212.510116)
		(width 0.16002)
		(layer "In13.Cu")
		(net "M_B_CPU0_SA_DQS_DP<6>")
	)
	(segment
		(start 324.100952 -230.360982)
		(end 324.184772 -230.360982)
		(width 0.09525)
		(layer "In13.Cu")
		(net "M_B_CPU0_SA_DQS_DP<6>")
	)
	(segment
		(start 329.821286 -232.814114)
		(end 329.829668 -232.81894)
		(width 0.09525)
		(layer "In13.Cu")
		(net "M_B_CPU0_SA_DQS_DP<6>")
	)
	(segment
		(start 296.893234 -211.30641)
		(end 298.589192 -211.30641)
		(width 0.16002)
		(layer "In13.Cu")
		(net "M_B_CPU0_SA_DQS_DP<6>")
	)
	(segment
		(start 296.68089 -211.518754)
		(end 296.893234 -211.30641)
		(width 0.16002)
		(layer "In13.Cu")
		(net "M_B_CPU0_SA_DQS_DP<6>")
	)
	(segment
		(start 320.577718 -226.837494)
		(end 320.905632 -227.165408)
		(width 0.16002)
		(layer "In13.Cu")
		(net "M_B_CPU0_SA_DQS_DP<6>")
	)
	(segment
		(start 307.777642 -212.510116)
		(end 320.577718 -225.310192)
		(width 0.16002)
		(layer "In13.Cu")
		(net "M_B_CPU0_SA_DQS_DP<6>")
	)
	(segment
		(start 325.362824 -230.772462)
		(end 327.357994 -232.767632)
		(width 0.09525)
		(layer "In13.Cu")
		(net "M_B_CPU0_SA_DQS_DP<6>")
	)
	(segment
		(start 324.084188 -230.344218)
		(end 324.100952 -230.360982)
		(width 0.09525)
		(layer "In13.Cu")
		(net "M_B_CPU0_SA_DQS_DP<6>")
	)
	(segment
		(start 320.577718 -225.310192)
		(end 320.577718 -226.837494)
		(width 0.16002)
		(layer "In13.Cu")
		(net "M_B_CPU0_SA_DQS_DP<6>")
	)
	(segment
		(start 331.332586 -232.81894)
		(end 331.340968 -232.814114)
		(width 0.09525)
		(layer "In13.Cu")
		(net "M_B_CPU0_SA_DQS_DP<6>")
	)
	(segment
		(start 295.990264 -211.518754)
		(end 296.68089 -211.518754)
		(width 0.16002)
		(layer "In13.Cu")
		(net "M_B_CPU0_SA_DQS_DP<6>")
	)
	(segment
		(start 336.906362 -232.85196)
		(end 337.0072 -232.87863)
		(width 0.09525)
		(layer "In13.Cu")
		(net "M_B_CPU0_SA_DQS_DP<6>")
	)
	(segment
		(start 301.393098 -211.660232)
		(end 301.92345 -212.190584)
		(width 0.16002)
		(layer "In13.Cu")
		(net "M_B_CPU0_SA_DQS_DP<6>")
	)
	(segment
		(start 324.596252 -230.772462)
		(end 325.362824 -230.772462)
		(width 0.09525)
		(layer "In13.Cu")
		(net "M_B_CPU0_SA_DQS_DP<6>")
	)
	(segment
		(start 295.724072 -211.784946)
		(end 295.990264 -211.518754)
		(width 0.16002)
		(layer "In13.Cu")
		(net "M_B_CPU0_SA_DQS_DP<6>")
	)
	(segment
		(start 330.392532 -232.81894)
		(end 330.400914 -232.814114)
		(width 0.09525)
		(layer "In13.Cu")
		(net "M_B_CPU0_SA_DQS_DP<6>")
	)
	(segment
		(start 327.357994 -232.767632)
		(end 327.761092 -232.767632)
		(width 0.09525)
		(layer "In13.Cu")
		(net "M_B_CPU0_SA_DQS_DP<6>")
	)
	(segment
		(start 298.589192 -211.30641)
		(end 298.943014 -211.660232)
		(width 0.16002)
		(layer "In13.Cu")
		(net "M_B_CPU0_SA_DQS_DP<6>")
	)
	(segment
		(start 298.943014 -211.660232)
		(end 301.393098 -211.660232)
		(width 0.16002)
		(layer "In13.Cu")
		(net "M_B_CPU0_SA_DQS_DP<6>")
	)
	(segment
		(start 324.184772 -230.360982)
		(end 324.596252 -230.772462)
		(width 0.09525)
		(layer "In13.Cu")
		(net "M_B_CPU0_SA_DQS_DP<6>")
	)
	(segment
		(start 320.905632 -227.165408)
		(end 320.905632 -227.165662)
		(width 0.16002)
		(layer "In13.Cu")
		(net "M_B_CPU0_SA_DQS_DP<6>")
	)
	(arc
		(start 334.152494 -232.81894)
		(mid 334.336269 -232.768168)
		(end 334.521302 -232.814114)
		(width 0.09525)
		(layer "In13.Cu")
		(net "M_B_CPU0_SA_DQS_DP<6>")
	)
	(arc
		(start 331.340968 -232.814114)
		(mid 331.526 -232.7682)
		(end 331.709776 -232.81894)
		(width 0.09525)
		(layer "In13.Cu")
		(net "M_B_CPU0_SA_DQS_DP<6>")
	)
	(arc
		(start 327.949814 -232.81894)
		(mid 328.231246 -232.894695)
		(end 328.512678 -232.81894)
		(width 0.09525)
		(layer "In13.Cu")
		(net "M_B_CPU0_SA_DQS_DP<6>")
	)
	(arc
		(start 328.512678 -232.81894)
		(mid 328.701146 -232.768263)
		(end 328.889614 -232.81894)
		(width 0.09525)
		(layer "In13.Cu")
		(net "M_B_CPU0_SA_DQS_DP<6>")
	)
	(arc
		(start 328.889614 -232.81894)
		(mid 329.171046 -232.894695)
		(end 329.452478 -232.81894)
		(width 0.09525)
		(layer "In13.Cu")
		(net "M_B_CPU0_SA_DQS_DP<6>")
	)
	(arc
		(start 330.400914 -232.814114)
		(mid 330.585946 -232.7682)
		(end 330.769722 -232.81894)
		(width 0.09525)
		(layer "In13.Cu")
		(net "M_B_CPU0_SA_DQS_DP<6>")
	)
	(arc
		(start 334.529684 -232.81894)
		(mid 334.811116 -232.894695)
		(end 335.092548 -232.81894)
		(width 0.09525)
		(layer "In13.Cu")
		(net "M_B_CPU0_SA_DQS_DP<6>")
	)
	(arc
		(start 333.21244 -232.81894)
		(mid 333.396215 -232.768168)
		(end 333.581248 -232.814114)
		(width 0.09525)
		(layer "In13.Cu")
		(net "M_B_CPU0_SA_DQS_DP<6>")
	)
	(arc
		(start 329.452478 -232.81894)
		(mid 329.636253 -232.768168)
		(end 329.821286 -232.814114)
		(width 0.09525)
		(layer "In13.Cu")
		(net "M_B_CPU0_SA_DQS_DP<6>")
	)
	(arc
		(start 336.886042 -232.859834)
		(mid 336.896241 -232.855997)
		(end 336.906362 -232.85196)
		(width 0.09525)
		(layer "In13.Cu")
		(net "M_B_CPU0_SA_DQS_DP<6>")
	)
	(arc
		(start 331.709776 -232.81894)
		(mid 331.991208 -232.894695)
		(end 332.27264 -232.81894)
		(width 0.09525)
		(layer "In13.Cu")
		(net "M_B_CPU0_SA_DQS_DP<6>")
	)
	(arc
		(start 332.649576 -232.81894)
		(mid 332.931008 -232.894695)
		(end 333.21244 -232.81894)
		(width 0.09525)
		(layer "In13.Cu")
		(net "M_B_CPU0_SA_DQS_DP<6>")
	)
	(arc
		(start 336.409792 -232.81894)
		(mid 336.643336 -232.892646)
		(end 336.886042 -232.859834)
		(width 0.09525)
		(layer "In13.Cu")
		(net "M_B_CPU0_SA_DQS_DP<6>")
	)
	(arc
		(start 330.769722 -232.81894)
		(mid 331.051154 -232.894695)
		(end 331.332586 -232.81894)
		(width 0.09525)
		(layer "In13.Cu")
		(net "M_B_CPU0_SA_DQS_DP<6>")
	)
	(arc
		(start 336.040984 -232.814114)
		(mid 336.226016 -232.7682)
		(end 336.409792 -232.81894)
		(width 0.09525)
		(layer "In13.Cu")
		(net "M_B_CPU0_SA_DQS_DP<6>")
	)
	(arc
		(start 333.58963 -232.81894)
		(mid 333.871062 -232.894695)
		(end 334.152494 -232.81894)
		(width 0.09525)
		(layer "In13.Cu")
		(net "M_B_CPU0_SA_DQS_DP<6>")
	)
	(arc
		(start 327.761092 -232.767632)
		(mid 327.858838 -232.780827)
		(end 327.949814 -232.81894)
		(width 0.09525)
		(layer "In13.Cu")
		(net "M_B_CPU0_SA_DQS_DP<6>")
	)
	(arc
		(start 332.27264 -232.81894)
		(mid 332.461108 -232.768263)
		(end 332.649576 -232.81894)
		(width 0.09525)
		(layer "In13.Cu")
		(net "M_B_CPU0_SA_DQS_DP<6>")
	)
	(arc
		(start 335.469738 -232.81894)
		(mid 335.75117 -232.894695)
		(end 336.032602 -232.81894)
		(width 0.09525)
		(layer "In13.Cu")
		(net "M_B_CPU0_SA_DQS_DP<6>")
	)
	(arc
		(start 335.10093 -232.814114)
		(mid 335.285962 -232.7682)
		(end 335.469738 -232.81894)
		(width 0.09525)
		(layer "In13.Cu")
		(net "M_B_CPU0_SA_DQS_DP<6>")
	)
	(arc
		(start 329.829668 -232.81894)
		(mid 330.1111 -232.894695)
		(end 330.392532 -232.81894)
		(width 0.09525)
		(layer "In13.Cu")
		(net "M_B_CPU0_SA_DQS_DP<6>")
	)
	(segment
		(start 337.627976 -228.550216)
		(end 337.161124 -228.284278)
		(width 0.12954)
		(layer "F.Cu")
		(net "M_B_CPU0_SA_DQS_DP<5>")
	)
	(segment
		(start 326.121522 -221.981014)
		(end 326.205342 -221.981014)
		(width 0.09525)
		(layer "In13.Cu")
		(net "M_B_CPU0_SA_DQS_DP<5>")
	)
	(segment
		(start 304.14214 -202.249278)
		(end 305.089814 -202.641708)
		(width 0.16002)
		(layer "In13.Cu")
		(net "M_B_CPU0_SA_DQS_DP<5>")
	)
	(segment
		(start 325.805038 -221.66453)
		(end 326.104758 -221.96425)
		(width 0.16002)
		(layer "In13.Cu")
		(net "M_B_CPU0_SA_DQS_DP<5>")
	)
	(segment
		(start 329.359768 -227.149152)
		(end 329.391264 -227.16744)
		(width 0.09525)
		(layer "In13.Cu")
		(net "M_B_CPU0_SA_DQS_DP<5>")
	)
	(segment
		(start 298.953682 -202.310238)
		(end 301.371762 -202.310238)
		(width 0.16002)
		(layer "In13.Cu")
		(net "M_B_CPU0_SA_DQS_DP<5>")
	)
	(segment
		(start 329.321668 -227.127054)
		(end 329.359768 -227.149152)
		(width 0.09525)
		(layer "In13.Cu")
		(net "M_B_CPU0_SA_DQS_DP<5>")
	)
	(segment
		(start 328.381614 -225.507042)
		(end 328.419714 -225.52914)
		(width 0.09525)
		(layer "In13.Cu")
		(net "M_B_CPU0_SA_DQS_DP<5>")
	)
	(segment
		(start 335.092548 -227.959158)
		(end 335.10093 -227.954332)
		(width 0.09525)
		(layer "In13.Cu")
		(net "M_B_CPU0_SA_DQS_DP<5>")
	)
	(segment
		(start 329.791568 -227.93706)
		(end 329.829668 -227.959158)
		(width 0.09525)
		(layer "In13.Cu")
		(net "M_B_CPU0_SA_DQS_DP<5>")
	)
	(segment
		(start 298.600876 -201.957432)
		(end 298.953682 -202.310238)
		(width 0.16002)
		(layer "In13.Cu")
		(net "M_B_CPU0_SA_DQS_DP<5>")
	)
	(segment
		(start 337.0072 -228.018848)
		(end 337.161124 -228.284278)
		(width 0.09525)
		(layer "In13.Cu")
		(net "M_B_CPU0_SA_DQS_DP<5>")
	)
	(segment
		(start 303.094136 -202.249278)
		(end 304.14214 -202.249278)
		(width 0.16002)
		(layer "In13.Cu")
		(net "M_B_CPU0_SA_DQS_DP<5>")
	)
	(segment
		(start 327.439274 -223.885506)
		(end 327.480168 -223.909128)
		(width 0.09525)
		(layer "In13.Cu")
		(net "M_B_CPU0_SA_DQS_DP<5>")
	)
	(segment
		(start 328.419714 -225.52914)
		(end 328.452226 -225.547936)
		(width 0.09525)
		(layer "In13.Cu")
		(net "M_B_CPU0_SA_DQS_DP<5>")
	)
	(segment
		(start 305.608228 -203.160122)
		(end 307.915056 -203.160122)
		(width 0.16002)
		(layer "In13.Cu")
		(net "M_B_CPU0_SA_DQS_DP<5>")
	)
	(segment
		(start 295.98747 -202.171554)
		(end 296.98569 -202.171554)
		(width 0.16002)
		(layer "In13.Cu")
		(net "M_B_CPU0_SA_DQS_DP<5>")
	)
	(segment
		(start 333.581248 -227.954332)
		(end 333.58963 -227.959158)
		(width 0.09525)
		(layer "In13.Cu")
		(net "M_B_CPU0_SA_DQS_DP<5>")
	)
	(segment
		(start 301.371762 -202.310238)
		(end 301.796704 -202.73518)
		(width 0.16002)
		(layer "In13.Cu")
		(net "M_B_CPU0_SA_DQS_DP<5>")
	)
	(segment
		(start 336.906362 -227.992178)
		(end 337.0072 -228.018848)
		(width 0.09525)
		(layer "In13.Cu")
		(net "M_B_CPU0_SA_DQS_DP<5>")
	)
	(segment
		(start 307.915056 -203.160122)
		(end 325.805038 -221.050104)
		(width 0.16002)
		(layer "In13.Cu")
		(net "M_B_CPU0_SA_DQS_DP<5>")
	)
	(segment
		(start 295.724072 -202.434952)
		(end 295.98747 -202.171554)
		(width 0.16002)
		(layer "In13.Cu")
		(net "M_B_CPU0_SA_DQS_DP<5>")
	)
	(segment
		(start 328.854562 -226.318572)
		(end 328.889614 -226.339146)
		(width 0.09525)
		(layer "In13.Cu")
		(net "M_B_CPU0_SA_DQS_DP<5>")
	)
	(segment
		(start 326.976486 -223.079564)
		(end 327.010014 -223.099122)
		(width 0.09525)
		(layer "In13.Cu")
		(net "M_B_CPU0_SA_DQS_DP<5>")
	)
	(segment
		(start 327.949814 -224.719134)
		(end 327.98131 -224.737422)
		(width 0.09525)
		(layer "In13.Cu")
		(net "M_B_CPU0_SA_DQS_DP<5>")
	)
	(segment
		(start 328.889614 -226.339146)
		(end 328.922126 -226.357942)
		(width 0.09525)
		(layer "In13.Cu")
		(net "M_B_CPU0_SA_DQS_DP<5>")
	)
	(segment
		(start 297.199812 -201.957432)
		(end 298.600876 -201.957432)
		(width 0.16002)
		(layer "In13.Cu")
		(net "M_B_CPU0_SA_DQS_DP<5>")
	)
	(segment
		(start 336.032602 -227.959158)
		(end 336.040984 -227.954332)
		(width 0.09525)
		(layer "In13.Cu")
		(net "M_B_CPU0_SA_DQS_DP<5>")
	)
	(segment
		(start 330.392532 -227.959158)
		(end 330.400914 -227.954332)
		(width 0.09525)
		(layer "In13.Cu")
		(net "M_B_CPU0_SA_DQS_DP<5>")
	)
	(segment
		(start 296.98569 -202.171554)
		(end 297.199812 -201.957432)
		(width 0.16002)
		(layer "In13.Cu")
		(net "M_B_CPU0_SA_DQS_DP<5>")
	)
	(segment
		(start 305.089814 -202.641708)
		(end 305.608228 -203.160122)
		(width 0.16002)
		(layer "In13.Cu")
		(net "M_B_CPU0_SA_DQS_DP<5>")
	)
	(segment
		(start 302.608234 -202.73518)
		(end 303.094136 -202.249278)
		(width 0.16002)
		(layer "In13.Cu")
		(net "M_B_CPU0_SA_DQS_DP<5>")
	)
	(segment
		(start 331.332586 -227.959158)
		(end 331.340968 -227.954332)
		(width 0.09525)
		(layer "In13.Cu")
		(net "M_B_CPU0_SA_DQS_DP<5>")
	)
	(segment
		(start 327.480168 -223.909128)
		(end 327.510394 -223.926654)
		(width 0.09525)
		(layer "In13.Cu")
		(net "M_B_CPU0_SA_DQS_DP<5>")
	)
	(segment
		(start 334.521302 -227.954332)
		(end 334.529684 -227.959158)
		(width 0.09525)
		(layer "In13.Cu")
		(net "M_B_CPU0_SA_DQS_DP<5>")
	)
	(segment
		(start 325.805038 -221.050104)
		(end 325.805038 -221.66453)
		(width 0.16002)
		(layer "In13.Cu")
		(net "M_B_CPU0_SA_DQS_DP<5>")
	)
	(segment
		(start 327.914762 -224.69856)
		(end 327.949814 -224.719134)
		(width 0.09525)
		(layer "In13.Cu")
		(net "M_B_CPU0_SA_DQS_DP<5>")
	)
	(segment
		(start 326.540114 -222.289116)
		(end 326.573896 -222.308674)
		(width 0.09525)
		(layer "In13.Cu")
		(net "M_B_CPU0_SA_DQS_DP<5>")
	)
	(segment
		(start 326.104758 -221.96425)
		(end 326.121522 -221.981014)
		(width 0.09525)
		(layer "In13.Cu")
		(net "M_B_CPU0_SA_DQS_DP<5>")
	)
	(segment
		(start 301.796704 -202.73518)
		(end 302.608234 -202.73518)
		(width 0.16002)
		(layer "In13.Cu")
		(net "M_B_CPU0_SA_DQS_DP<5>")
	)
	(segment
		(start 327.010014 -223.099122)
		(end 327.042526 -223.117918)
		(width 0.09525)
		(layer "In13.Cu")
		(net "M_B_CPU0_SA_DQS_DP<5>")
	)
	(segment
		(start 326.205342 -221.981014)
		(end 326.424798 -222.20047)
		(width 0.09525)
		(layer "In13.Cu")
		(net "M_B_CPU0_SA_DQS_DP<5>")
	)
	(arc
		(start 329.829668 -227.959158)
		(mid 330.1111 -228.034913)
		(end 330.392532 -227.959158)
		(width 0.09525)
		(layer "In13.Cu")
		(net "M_B_CPU0_SA_DQS_DP<5>")
	)
	(arc
		(start 327.19899 -223.424242)
		(mid 327.262663 -223.684289)
		(end 327.439274 -223.885506)
		(width 0.09525)
		(layer "In13.Cu")
		(net "M_B_CPU0_SA_DQS_DP<5>")
	)
	(arc
		(start 328.608944 -225.85426)
		(mid 328.674191 -226.116863)
		(end 328.854562 -226.318572)
		(width 0.09525)
		(layer "In13.Cu")
		(net "M_B_CPU0_SA_DQS_DP<5>")
	)
	(arc
		(start 330.769722 -227.959158)
		(mid 331.051154 -228.034913)
		(end 331.332586 -227.959158)
		(width 0.09525)
		(layer "In13.Cu")
		(net "M_B_CPU0_SA_DQS_DP<5>")
	)
	(arc
		(start 336.040984 -227.954332)
		(mid 336.226016 -227.908418)
		(end 336.409792 -227.959158)
		(width 0.09525)
		(layer "In13.Cu")
		(net "M_B_CPU0_SA_DQS_DP<5>")
	)
	(arc
		(start 326.424798 -222.20047)
		(mid 326.479573 -222.248543)
		(end 326.540114 -222.289116)
		(width 0.09525)
		(layer "In13.Cu")
		(net "M_B_CPU0_SA_DQS_DP<5>")
	)
	(arc
		(start 334.152494 -227.959158)
		(mid 334.336269 -227.908386)
		(end 334.521302 -227.954332)
		(width 0.09525)
		(layer "In13.Cu")
		(net "M_B_CPU0_SA_DQS_DP<5>")
	)
	(arc
		(start 331.709776 -227.959158)
		(mid 331.991208 -228.034913)
		(end 332.27264 -227.959158)
		(width 0.09525)
		(layer "In13.Cu")
		(net "M_B_CPU0_SA_DQS_DP<5>")
	)
	(arc
		(start 330.400914 -227.954332)
		(mid 330.585946 -227.908418)
		(end 330.769722 -227.959158)
		(width 0.09525)
		(layer "In13.Cu")
		(net "M_B_CPU0_SA_DQS_DP<5>")
	)
	(arc
		(start 327.98131 -224.737422)
		(mid 328.097108 -224.871816)
		(end 328.13879 -225.044254)
		(width 0.09525)
		(layer "In13.Cu")
		(net "M_B_CPU0_SA_DQS_DP<5>")
	)
	(arc
		(start 336.409792 -227.959158)
		(mid 336.643336 -228.032864)
		(end 336.886042 -228.000052)
		(width 0.09525)
		(layer "In13.Cu")
		(net "M_B_CPU0_SA_DQS_DP<5>")
	)
	(arc
		(start 326.573896 -222.308674)
		(mid 326.688424 -222.442765)
		(end 326.729598 -222.614236)
		(width 0.09525)
		(layer "In13.Cu")
		(net "M_B_CPU0_SA_DQS_DP<5>")
	)
	(arc
		(start 328.13879 -225.044254)
		(mid 328.203187 -225.30556)
		(end 328.381614 -225.507042)
		(width 0.09525)
		(layer "In13.Cu")
		(net "M_B_CPU0_SA_DQS_DP<5>")
	)
	(arc
		(start 333.21244 -227.959158)
		(mid 333.396215 -227.908386)
		(end 333.581248 -227.954332)
		(width 0.09525)
		(layer "In13.Cu")
		(net "M_B_CPU0_SA_DQS_DP<5>")
	)
	(arc
		(start 329.391264 -227.16744)
		(mid 329.507062 -227.301834)
		(end 329.548744 -227.474272)
		(width 0.09525)
		(layer "In13.Cu")
		(net "M_B_CPU0_SA_DQS_DP<5>")
	)
	(arc
		(start 335.10093 -227.954332)
		(mid 335.285962 -227.908418)
		(end 335.469738 -227.959158)
		(width 0.09525)
		(layer "In13.Cu")
		(net "M_B_CPU0_SA_DQS_DP<5>")
	)
	(arc
		(start 334.529684 -227.959158)
		(mid 334.811116 -228.034913)
		(end 335.092548 -227.959158)
		(width 0.09525)
		(layer "In13.Cu")
		(net "M_B_CPU0_SA_DQS_DP<5>")
	)
	(arc
		(start 336.886042 -228.000052)
		(mid 336.896241 -227.996215)
		(end 336.906362 -227.992178)
		(width 0.09525)
		(layer "In13.Cu")
		(net "M_B_CPU0_SA_DQS_DP<5>")
	)
	(arc
		(start 327.669144 -224.234248)
		(mid 327.734391 -224.496851)
		(end 327.914762 -224.69856)
		(width 0.09525)
		(layer "In13.Cu")
		(net "M_B_CPU0_SA_DQS_DP<5>")
	)
	(arc
		(start 329.548744 -227.474272)
		(mid 329.613141 -227.735578)
		(end 329.791568 -227.93706)
		(width 0.09525)
		(layer "In13.Cu")
		(net "M_B_CPU0_SA_DQS_DP<5>")
	)
	(arc
		(start 327.510394 -223.926654)
		(mid 327.627095 -224.061183)
		(end 327.669144 -224.234248)
		(width 0.09525)
		(layer "In13.Cu")
		(net "M_B_CPU0_SA_DQS_DP<5>")
	)
	(arc
		(start 331.340968 -227.954332)
		(mid 331.526 -227.908418)
		(end 331.709776 -227.959158)
		(width 0.09525)
		(layer "In13.Cu")
		(net "M_B_CPU0_SA_DQS_DP<5>")
	)
	(arc
		(start 326.729598 -222.614236)
		(mid 326.795151 -222.877608)
		(end 326.976486 -223.079564)
		(width 0.09525)
		(layer "In13.Cu")
		(net "M_B_CPU0_SA_DQS_DP<5>")
	)
	(arc
		(start 332.649576 -227.959158)
		(mid 332.931008 -228.034913)
		(end 333.21244 -227.959158)
		(width 0.09525)
		(layer "In13.Cu")
		(net "M_B_CPU0_SA_DQS_DP<5>")
	)
	(arc
		(start 328.922126 -226.357942)
		(mid 329.0374 -226.49222)
		(end 329.078844 -226.664266)
		(width 0.09525)
		(layer "In13.Cu")
		(net "M_B_CPU0_SA_DQS_DP<5>")
	)
	(arc
		(start 328.452226 -225.547936)
		(mid 328.5675 -225.682214)
		(end 328.608944 -225.85426)
		(width 0.09525)
		(layer "In13.Cu")
		(net "M_B_CPU0_SA_DQS_DP<5>")
	)
	(arc
		(start 333.58963 -227.959158)
		(mid 333.871062 -228.034913)
		(end 334.152494 -227.959158)
		(width 0.09525)
		(layer "In13.Cu")
		(net "M_B_CPU0_SA_DQS_DP<5>")
	)
	(arc
		(start 329.078844 -226.664266)
		(mid 329.143241 -226.925572)
		(end 329.321668 -227.127054)
		(width 0.09525)
		(layer "In13.Cu")
		(net "M_B_CPU0_SA_DQS_DP<5>")
	)
	(arc
		(start 327.042526 -223.117918)
		(mid 327.157576 -223.252268)
		(end 327.19899 -223.424242)
		(width 0.09525)
		(layer "In13.Cu")
		(net "M_B_CPU0_SA_DQS_DP<5>")
	)
	(arc
		(start 332.27264 -227.959158)
		(mid 332.461108 -227.908481)
		(end 332.649576 -227.959158)
		(width 0.09525)
		(layer "In13.Cu")
		(net "M_B_CPU0_SA_DQS_DP<5>")
	)
	(arc
		(start 335.469738 -227.959158)
		(mid 335.75117 -228.034913)
		(end 336.032602 -227.959158)
		(width 0.09525)
		(layer "In13.Cu")
		(net "M_B_CPU0_SA_DQS_DP<5>")
	)
	(segment
		(start 335.747868 -246.370094)
		(end 335.281016 -246.104156)
		(width 0.12954)
		(layer "F.Cu")
		(net "M_B_CPU0_SA_DQS_DP<4>")
	)
	(segment
		(start 324.393052 -246.253254)
		(end 324.393052 -246.538242)
		(width 0.09525)
		(layer "In13.Cu")
		(net "M_B_CPU0_SA_DQS_DP<4>")
	)
	(segment
		(start 311.391808 -242.756182)
		(end 311.765442 -243.129816)
		(width 0.16002)
		(layer "In13.Cu")
		(net "M_B_CPU0_SA_DQS_DP<4>")
	)
	(segment
		(start 324.190106 -246.050308)
		(end 324.393052 -246.253254)
		(width 0.09525)
		(layer "In13.Cu")
		(net "M_B_CPU0_SA_DQS_DP<4>")
	)
	(segment
		(start 312.85688 -245.312946)
		(end 312.85688 -245.589806)
		(width 0.16002)
		(layer "In13.Cu")
		(net "M_B_CPU0_SA_DQS_DP<4>")
	)
	(segment
		(start 313.139074 -245.030752)
		(end 312.85688 -245.312946)
		(width 0.16002)
		(layer "In13.Cu")
		(net "M_B_CPU0_SA_DQS_DP<4>")
	)
	(segment
		(start 334.521302 -246.434102)
		(end 334.529684 -246.429276)
		(width 0.09525)
		(layer "In13.Cu")
		(net "M_B_CPU0_SA_DQS_DP<4>")
	)
	(segment
		(start 312.76544 -244.129814)
		(end 313.139074 -244.503448)
		(width 0.16002)
		(layer "In13.Cu")
		(net "M_B_CPU0_SA_DQS_DP<4>")
	)
	(segment
		(start 303.796446 -238.288322)
		(end 305.639216 -239.051592)
		(width 0.16002)
		(layer "In13.Cu")
		(net "M_B_CPU0_SA_DQS_DP<4>")
	)
	(segment
		(start 308.931818 -241.664744)
		(end 309.208678 -241.664744)
		(width 0.16002)
		(layer "In13.Cu")
		(net "M_B_CPU0_SA_DQS_DP<4>")
	)
	(segment
		(start 307.841904 -240.34877)
		(end 307.841904 -240.57483)
		(width 0.16002)
		(layer "In13.Cu")
		(net "M_B_CPU0_SA_DQS_DP<4>")
	)
	(segment
		(start 305.639216 -239.051592)
		(end 306.318666 -239.051592)
		(width 0.16002)
		(layer "In13.Cu")
		(net "M_B_CPU0_SA_DQS_DP<4>")
	)
	(segment
		(start 327.547986 -246.414544)
		(end 327.573386 -246.429276)
		(width 0.09525)
		(layer "In13.Cu")
		(net "M_B_CPU0_SA_DQS_DP<4>")
	)
	(segment
		(start 306.941474 -239.44834)
		(end 307.142388 -239.247426)
		(width 0.16002)
		(layer "In13.Cu")
		(net "M_B_CPU0_SA_DQS_DP<4>")
	)
	(segment
		(start 308.042818 -240.147856)
		(end 307.841904 -240.34877)
		(width 0.16002)
		(layer "In13.Cu")
		(net "M_B_CPU0_SA_DQS_DP<4>")
	)
	(segment
		(start 310.39181 -241.756184)
		(end 310.39181 -242.283488)
		(width 0.16002)
		(layer "In13.Cu")
		(net "M_B_CPU0_SA_DQS_DP<4>")
	)
	(segment
		(start 331.332586 -246.429276)
		(end 331.340968 -246.434102)
		(width 0.09525)
		(layer "In13.Cu")
		(net "M_B_CPU0_SA_DQS_DP<4>")
	)
	(segment
		(start 311.765442 -243.129816)
		(end 311.765442 -243.65712)
		(width 0.16002)
		(layer "In13.Cu")
		(net "M_B_CPU0_SA_DQS_DP<4>")
	)
	(segment
		(start 335.411572 -246.456454)
		(end 335.43494 -246.369586)
		(width 0.09525)
		(layer "In13.Cu")
		(net "M_B_CPU0_SA_DQS_DP<4>")
	)
	(segment
		(start 311.765442 -243.65712)
		(end 311.483248 -243.939314)
		(width 0.16002)
		(layer "In13.Cu")
		(net "M_B_CPU0_SA_DQS_DP<4>")
	)
	(segment
		(start 324.393052 -246.538242)
		(end 324.617842 -246.763032)
		(width 0.09525)
		(layer "In13.Cu")
		(net "M_B_CPU0_SA_DQS_DP<4>")
	)
	(segment
		(start 312.238136 -244.129814)
		(end 312.76544 -244.129814)
		(width 0.16002)
		(layer "In13.Cu")
		(net "M_B_CPU0_SA_DQS_DP<4>")
	)
	(segment
		(start 307.618892 -239.247426)
		(end 308.042818 -239.671352)
		(width 0.16002)
		(layer "In13.Cu")
		(net "M_B_CPU0_SA_DQS_DP<4>")
	)
	(segment
		(start 300.730158 -238.288322)
		(end 303.796446 -238.288322)
		(width 0.16002)
		(layer "In13.Cu")
		(net "M_B_CPU0_SA_DQS_DP<4>")
	)
	(segment
		(start 327.573386 -246.429276)
		(end 327.59015 -246.438928)
		(width 0.09525)
		(layer "In13.Cu")
		(net "M_B_CPU0_SA_DQS_DP<4>")
	)
	(segment
		(start 311.955942 -244.412008)
		(end 312.238136 -244.129814)
		(width 0.16002)
		(layer "In13.Cu")
		(net "M_B_CPU0_SA_DQS_DP<4>")
	)
	(segment
		(start 313.139074 -244.503448)
		(end 313.139074 -245.030752)
		(width 0.16002)
		(layer "In13.Cu")
		(net "M_B_CPU0_SA_DQS_DP<4>")
	)
	(segment
		(start 325.546974 -246.480076)
		(end 325.883524 -246.480076)
		(width 0.09525)
		(layer "In13.Cu")
		(net "M_B_CPU0_SA_DQS_DP<4>")
	)
	(segment
		(start 325.264018 -246.763032)
		(end 325.546974 -246.480076)
		(width 0.09525)
		(layer "In13.Cu")
		(net "M_B_CPU0_SA_DQS_DP<4>")
	)
	(segment
		(start 329.821286 -246.434102)
		(end 329.829668 -246.429276)
		(width 0.09525)
		(layer "In13.Cu")
		(net "M_B_CPU0_SA_DQS_DP<4>")
	)
	(segment
		(start 310.30545 -243.038376)
		(end 310.58231 -243.038376)
		(width 0.16002)
		(layer "In13.Cu")
		(net "M_B_CPU0_SA_DQS_DP<4>")
	)
	(segment
		(start 311.483248 -244.216174)
		(end 311.679082 -244.412008)
		(width 0.16002)
		(layer "In13.Cu")
		(net "M_B_CPU0_SA_DQS_DP<4>")
	)
	(segment
		(start 310.018176 -241.38255)
		(end 310.39181 -241.756184)
		(width 0.16002)
		(layer "In13.Cu")
		(net "M_B_CPU0_SA_DQS_DP<4>")
	)
	(segment
		(start 310.39181 -242.283488)
		(end 310.109616 -242.565682)
		(width 0.16002)
		(layer "In13.Cu")
		(net "M_B_CPU0_SA_DQS_DP<4>")
	)
	(segment
		(start 323.843396 -245.99138)
		(end 323.902324 -246.050308)
		(width 0.09525)
		(layer "In13.Cu")
		(net "M_B_CPU0_SA_DQS_DP<4>")
	)
	(segment
		(start 312.85688 -245.589806)
		(end 313.258454 -245.99138)
		(width 0.16002)
		(layer "In13.Cu")
		(net "M_B_CPU0_SA_DQS_DP<4>")
	)
	(segment
		(start 326.99325 -246.440198)
		(end 327.012046 -246.429276)
		(width 0.09525)
		(layer "In13.Cu")
		(net "M_B_CPU0_SA_DQS_DP<4>")
	)
	(segment
		(start 306.318666 -239.051592)
		(end 306.715414 -239.44834)
		(width 0.16002)
		(layer "In13.Cu")
		(net "M_B_CPU0_SA_DQS_DP<4>")
	)
	(segment
		(start 330.392532 -246.429276)
		(end 330.400914 -246.434102)
		(width 0.09525)
		(layer "In13.Cu")
		(net "M_B_CPU0_SA_DQS_DP<4>")
	)
	(segment
		(start 307.142388 -239.247426)
		(end 307.618892 -239.247426)
		(width 0.16002)
		(layer "In13.Cu")
		(net "M_B_CPU0_SA_DQS_DP<4>")
	)
	(segment
		(start 326.07123 -246.429276)
		(end 326.105774 -246.40921)
		(width 0.09525)
		(layer "In13.Cu")
		(net "M_B_CPU0_SA_DQS_DP<4>")
	)
	(segment
		(start 299.82414 -238.13516)
		(end 300.11116 -238.42218)
		(width 0.16002)
		(layer "In13.Cu")
		(net "M_B_CPU0_SA_DQS_DP<4>")
	)
	(segment
		(start 311.679082 -244.412008)
		(end 311.955942 -244.412008)
		(width 0.16002)
		(layer "In13.Cu")
		(net "M_B_CPU0_SA_DQS_DP<4>")
	)
	(segment
		(start 324.617842 -246.763032)
		(end 325.264018 -246.763032)
		(width 0.09525)
		(layer "In13.Cu")
		(net "M_B_CPU0_SA_DQS_DP<4>")
	)
	(segment
		(start 313.258454 -245.99138)
		(end 323.819774 -245.99138)
		(width 0.16002)
		(layer "In13.Cu")
		(net "M_B_CPU0_SA_DQS_DP<4>")
	)
	(segment
		(start 310.58231 -243.038376)
		(end 310.864504 -242.756182)
		(width 0.16002)
		(layer "In13.Cu")
		(net "M_B_CPU0_SA_DQS_DP<4>")
	)
	(segment
		(start 333.581248 -246.434102)
		(end 333.58963 -246.429276)
		(width 0.09525)
		(layer "In13.Cu")
		(net "M_B_CPU0_SA_DQS_DP<4>")
	)
	(segment
		(start 335.43494 -246.369586)
		(end 335.281016 -246.104156)
		(width 0.09525)
		(layer "In13.Cu")
		(net "M_B_CPU0_SA_DQS_DP<4>")
	)
	(segment
		(start 323.819774 -245.99138)
		(end 323.843396 -245.99138)
		(width 0.09525)
		(layer "In13.Cu")
		(net "M_B_CPU0_SA_DQS_DP<4>")
	)
	(segment
		(start 306.715414 -239.44834)
		(end 306.941474 -239.44834)
		(width 0.16002)
		(layer "In13.Cu")
		(net "M_B_CPU0_SA_DQS_DP<4>")
	)
	(segment
		(start 300.11116 -238.42218)
		(end 300.5963 -238.42218)
		(width 0.16002)
		(layer "In13.Cu")
		(net "M_B_CPU0_SA_DQS_DP<4>")
	)
	(segment
		(start 309.208678 -241.664744)
		(end 309.490872 -241.38255)
		(width 0.16002)
		(layer "In13.Cu")
		(net "M_B_CPU0_SA_DQS_DP<4>")
	)
	(segment
		(start 311.483248 -243.939314)
		(end 311.483248 -244.216174)
		(width 0.16002)
		(layer "In13.Cu")
		(net "M_B_CPU0_SA_DQS_DP<4>")
	)
	(segment
		(start 307.841904 -240.57483)
		(end 308.931818 -241.664744)
		(width 0.16002)
		(layer "In13.Cu")
		(net "M_B_CPU0_SA_DQS_DP<4>")
	)
	(segment
		(start 310.109616 -242.842542)
		(end 310.30545 -243.038376)
		(width 0.16002)
		(layer "In13.Cu")
		(net "M_B_CPU0_SA_DQS_DP<4>")
	)
	(segment
		(start 323.902324 -246.050308)
		(end 324.190106 -246.050308)
		(width 0.09525)
		(layer "In13.Cu")
		(net "M_B_CPU0_SA_DQS_DP<4>")
	)
	(segment
		(start 309.490872 -241.38255)
		(end 310.018176 -241.38255)
		(width 0.16002)
		(layer "In13.Cu")
		(net "M_B_CPU0_SA_DQS_DP<4>")
	)
	(segment
		(start 300.5963 -238.42218)
		(end 300.730158 -238.288322)
		(width 0.16002)
		(layer "In13.Cu")
		(net "M_B_CPU0_SA_DQS_DP<4>")
	)
	(segment
		(start 308.042818 -239.671352)
		(end 308.042818 -240.147856)
		(width 0.16002)
		(layer "In13.Cu")
		(net "M_B_CPU0_SA_DQS_DP<4>")
	)
	(segment
		(start 335.092548 -246.429276)
		(end 335.10093 -246.434102)
		(width 0.09525)
		(layer "In13.Cu")
		(net "M_B_CPU0_SA_DQS_DP<4>")
	)
	(segment
		(start 310.109616 -242.565682)
		(end 310.109616 -242.842542)
		(width 0.16002)
		(layer "In13.Cu")
		(net "M_B_CPU0_SA_DQS_DP<4>")
	)
	(segment
		(start 310.864504 -242.756182)
		(end 311.391808 -242.756182)
		(width 0.16002)
		(layer "In13.Cu")
		(net "M_B_CPU0_SA_DQS_DP<4>")
	)
	(arc
		(start 327.012046 -246.429276)
		(mid 327.278133 -246.353731)
		(end 327.547986 -246.414544)
		(width 0.09525)
		(layer "In13.Cu")
		(net "M_B_CPU0_SA_DQS_DP<4>")
	)
	(arc
		(start 329.452478 -246.429276)
		(mid 329.636253 -246.480048)
		(end 329.821286 -246.434102)
		(width 0.09525)
		(layer "In13.Cu")
		(net "M_B_CPU0_SA_DQS_DP<4>")
	)
	(arc
		(start 325.96455 -246.470932)
		(mid 326.019478 -246.454176)
		(end 326.07123 -246.429276)
		(width 0.09525)
		(layer "In13.Cu")
		(net "M_B_CPU0_SA_DQS_DP<4>")
	)
	(arc
		(start 331.340968 -246.434102)
		(mid 331.526 -246.480016)
		(end 331.709776 -246.429276)
		(width 0.09525)
		(layer "In13.Cu")
		(net "M_B_CPU0_SA_DQS_DP<4>")
	)
	(arc
		(start 326.63384 -246.429276)
		(mid 326.812155 -246.480418)
		(end 326.99325 -246.440198)
		(width 0.09525)
		(layer "In13.Cu")
		(net "M_B_CPU0_SA_DQS_DP<4>")
	)
	(arc
		(start 331.709776 -246.429276)
		(mid 331.991208 -246.353521)
		(end 332.27264 -246.429276)
		(width 0.09525)
		(layer "In13.Cu")
		(net "M_B_CPU0_SA_DQS_DP<4>")
	)
	(arc
		(start 326.105774 -246.40921)
		(mid 326.3723 -246.353273)
		(end 326.63384 -246.429276)
		(width 0.09525)
		(layer "In13.Cu")
		(net "M_B_CPU0_SA_DQS_DP<4>")
	)
	(arc
		(start 330.400914 -246.434102)
		(mid 330.585946 -246.480016)
		(end 330.769722 -246.429276)
		(width 0.09525)
		(layer "In13.Cu")
		(net "M_B_CPU0_SA_DQS_DP<4>")
	)
	(arc
		(start 335.10093 -246.434102)
		(mid 335.253825 -246.47893)
		(end 335.411572 -246.456454)
		(width 0.09525)
		(layer "In13.Cu")
		(net "M_B_CPU0_SA_DQS_DP<4>")
	)
	(arc
		(start 325.883524 -246.480076)
		(mid 325.924288 -246.477719)
		(end 325.96455 -246.470932)
		(width 0.09525)
		(layer "In13.Cu")
		(net "M_B_CPU0_SA_DQS_DP<4>")
	)
	(arc
		(start 330.769722 -246.429276)
		(mid 331.051154 -246.353521)
		(end 331.332586 -246.429276)
		(width 0.09525)
		(layer "In13.Cu")
		(net "M_B_CPU0_SA_DQS_DP<4>")
	)
	(arc
		(start 327.59015 -246.438928)
		(mid 327.771207 -246.47991)
		(end 327.949814 -246.429276)
		(width 0.09525)
		(layer "In13.Cu")
		(net "M_B_CPU0_SA_DQS_DP<4>")
	)
	(arc
		(start 333.21244 -246.429276)
		(mid 333.396215 -246.480048)
		(end 333.581248 -246.434102)
		(width 0.09525)
		(layer "In13.Cu")
		(net "M_B_CPU0_SA_DQS_DP<4>")
	)
	(arc
		(start 328.512678 -246.429276)
		(mid 328.701146 -246.479953)
		(end 328.889614 -246.429276)
		(width 0.09525)
		(layer "In13.Cu")
		(net "M_B_CPU0_SA_DQS_DP<4>")
	)
	(arc
		(start 334.529684 -246.429276)
		(mid 334.811116 -246.353521)
		(end 335.092548 -246.429276)
		(width 0.09525)
		(layer "In13.Cu")
		(net "M_B_CPU0_SA_DQS_DP<4>")
	)
	(arc
		(start 328.889614 -246.429276)
		(mid 329.171046 -246.353521)
		(end 329.452478 -246.429276)
		(width 0.09525)
		(layer "In13.Cu")
		(net "M_B_CPU0_SA_DQS_DP<4>")
	)
	(arc
		(start 334.152494 -246.429276)
		(mid 334.336269 -246.480048)
		(end 334.521302 -246.434102)
		(width 0.09525)
		(layer "In13.Cu")
		(net "M_B_CPU0_SA_DQS_DP<4>")
	)
	(arc
		(start 329.829668 -246.429276)
		(mid 330.1111 -246.353521)
		(end 330.392532 -246.429276)
		(width 0.09525)
		(layer "In13.Cu")
		(net "M_B_CPU0_SA_DQS_DP<4>")
	)
	(arc
		(start 333.58963 -246.429276)
		(mid 333.871062 -246.353521)
		(end 334.152494 -246.429276)
		(width 0.09525)
		(layer "In13.Cu")
		(net "M_B_CPU0_SA_DQS_DP<4>")
	)
	(arc
		(start 332.649576 -246.429276)
		(mid 332.931008 -246.353521)
		(end 333.21244 -246.429276)
		(width 0.09525)
		(layer "In13.Cu")
		(net "M_B_CPU0_SA_DQS_DP<4>")
	)
	(arc
		(start 327.949814 -246.429276)
		(mid 328.231246 -246.353521)
		(end 328.512678 -246.429276)
		(width 0.09525)
		(layer "In13.Cu")
		(net "M_B_CPU0_SA_DQS_DP<4>")
	)
	(arc
		(start 332.27264 -246.429276)
		(mid 332.461108 -246.479953)
		(end 332.649576 -246.429276)
		(width 0.09525)
		(layer "In13.Cu")
		(net "M_B_CPU0_SA_DQS_DP<4>")
	)
	(segment
		(start 335.747868 -241.510058)
		(end 335.281016 -241.24412)
		(width 0.12954)
		(layer "F.Cu")
		(net "M_B_CPU0_SA_DQS_DP<3>")
	)
	(segment
		(start 313.460638 -235.20019)
		(end 313.460638 -234.92333)
		(width 0.16002)
		(layer "In13.Cu")
		(net "M_B_CPU0_SA_DQS_DP<3>")
	)
	(segment
		(start 325.757794 -241.493548)
		(end 325.167498 -240.903252)
		(width 0.09525)
		(layer "In13.Cu")
		(net "M_B_CPU0_SA_DQS_DP<3>")
	)
	(segment
		(start 310.9214 -231.440482)
		(end 310.547512 -231.066594)
		(width 0.16002)
		(layer "In13.Cu")
		(net "M_B_CPU0_SA_DQS_DP<3>")
	)
	(segment
		(start 312.28284 -234.022392)
		(end 312.087006 -233.826558)
		(width 0.16002)
		(layer "In13.Cu")
		(net "M_B_CPU0_SA_DQS_DP<3>")
	)
	(segment
		(start 329.829668 -241.56924)
		(end 329.821286 -241.574066)
		(width 0.09525)
		(layer "In13.Cu")
		(net "M_B_CPU0_SA_DQS_DP<3>")
	)
	(segment
		(start 303.174908 -229.750874)
		(end 303.174908 -229.58679)
		(width 0.16002)
		(layer "In13.Cu")
		(net "M_B_CPU0_SA_DQS_DP<3>")
	)
	(segment
		(start 302.142652 -229.249732)
		(end 301.95901 -229.06609)
		(width 0.16002)
		(layer "In13.Cu")
		(net "M_B_CPU0_SA_DQS_DP<3>")
	)
	(segment
		(start 301.95901 -229.06609)
		(end 300.105064 -229.06609)
		(width 0.16002)
		(layer "In13.Cu")
		(net "M_B_CPU0_SA_DQS_DP<3>")
	)
	(segment
		(start 310.713374 -232.176066)
		(end 310.921654 -231.967786)
		(width 0.16002)
		(layer "In13.Cu")
		(net "M_B_CPU0_SA_DQS_DP<3>")
	)
	(segment
		(start 312.087006 -233.826558)
		(end 312.087006 -233.549698)
		(width 0.16002)
		(layer "In13.Cu")
		(net "M_B_CPU0_SA_DQS_DP<3>")
	)
	(segment
		(start 312.087006 -233.549698)
		(end 312.295286 -233.341418)
		(width 0.16002)
		(layer "In13.Cu")
		(net "M_B_CPU0_SA_DQS_DP<3>")
	)
	(segment
		(start 335.10093 -241.574066)
		(end 335.092548 -241.56924)
		(width 0.09525)
		(layer "In13.Cu")
		(net "M_B_CPU0_SA_DQS_DP<3>")
	)
	(segment
		(start 303.334928 -229.910894)
		(end 303.174908 -229.750874)
		(width 0.16002)
		(layer "In13.Cu")
		(net "M_B_CPU0_SA_DQS_DP<3>")
	)
	(segment
		(start 326.351138 -241.493548)
		(end 325.757794 -241.493548)
		(width 0.09525)
		(layer "In13.Cu")
		(net "M_B_CPU0_SA_DQS_DP<3>")
	)
	(segment
		(start 323.919596 -240.357152)
		(end 323.895974 -240.357152)
		(width 0.09525)
		(layer "In13.Cu")
		(net "M_B_CPU0_SA_DQS_DP<3>")
	)
	(segment
		(start 331.340968 -241.574066)
		(end 331.332586 -241.56924)
		(width 0.09525)
		(layer "In13.Cu")
		(net "M_B_CPU0_SA_DQS_DP<3>")
	)
	(segment
		(start 327.581006 -241.574066)
		(end 327.572624 -241.56924)
		(width 0.09525)
		(layer "In13.Cu")
		(net "M_B_CPU0_SA_DQS_DP<3>")
	)
	(segment
		(start 309.548022 -230.594154)
		(end 309.547768 -230.067104)
		(width 0.16002)
		(layer "In13.Cu")
		(net "M_B_CPU0_SA_DQS_DP<3>")
	)
	(segment
		(start 330.400914 -241.574066)
		(end 330.392532 -241.56924)
		(width 0.09525)
		(layer "In13.Cu")
		(net "M_B_CPU0_SA_DQS_DP<3>")
	)
	(segment
		(start 318.6176 -240.357152)
		(end 313.460638 -235.20019)
		(width 0.16002)
		(layer "In13.Cu")
		(net "M_B_CPU0_SA_DQS_DP<3>")
	)
	(segment
		(start 304.179986 -229.249732)
		(end 303.842928 -229.58679)
		(width 0.16002)
		(layer "In13.Cu")
		(net "M_B_CPU0_SA_DQS_DP<3>")
	)
	(segment
		(start 324.727824 -240.903252)
		(end 324.240906 -240.416334)
		(width 0.09525)
		(layer "In13.Cu")
		(net "M_B_CPU0_SA_DQS_DP<3>")
	)
	(segment
		(start 312.295032 -232.814114)
		(end 311.921144 -232.440226)
		(width 0.16002)
		(layer "In13.Cu")
		(net "M_B_CPU0_SA_DQS_DP<3>")
	)
	(segment
		(start 333.58963 -241.56924)
		(end 333.581248 -241.574066)
		(width 0.09525)
		(layer "In13.Cu")
		(net "M_B_CPU0_SA_DQS_DP<3>")
	)
	(segment
		(start 311.921144 -232.440226)
		(end 311.394348 -232.44048)
		(width 0.16002)
		(layer "In13.Cu")
		(net "M_B_CPU0_SA_DQS_DP<3>")
	)
	(segment
		(start 308.367938 -229.262686)
		(end 308.03088 -228.925628)
		(width 0.16002)
		(layer "In13.Cu")
		(net "M_B_CPU0_SA_DQS_DP<3>")
	)
	(segment
		(start 310.909208 -232.64876)
		(end 310.713374 -232.452926)
		(width 0.16002)
		(layer "In13.Cu")
		(net "M_B_CPU0_SA_DQS_DP<3>")
	)
	(segment
		(start 309.535576 -231.275128)
		(end 309.339742 -231.079294)
		(width 0.16002)
		(layer "In13.Cu")
		(net "M_B_CPU0_SA_DQS_DP<3>")
	)
	(segment
		(start 307.095398 -229.48011)
		(end 306.935378 -229.64013)
		(width 0.16002)
		(layer "In13.Cu")
		(net "M_B_CPU0_SA_DQS_DP<3>")
	)
	(segment
		(start 323.895974 -240.357152)
		(end 318.6176 -240.357152)
		(width 0.16002)
		(layer "In13.Cu")
		(net "M_B_CPU0_SA_DQS_DP<3>")
	)
	(segment
		(start 309.339742 -230.802434)
		(end 309.548022 -230.594154)
		(width 0.16002)
		(layer "In13.Cu")
		(net "M_B_CPU0_SA_DQS_DP<3>")
	)
	(segment
		(start 334.529684 -241.56924)
		(end 334.521302 -241.574066)
		(width 0.09525)
		(layer "In13.Cu")
		(net "M_B_CPU0_SA_DQS_DP<3>")
	)
	(segment
		(start 324.240906 -240.416334)
		(end 323.978778 -240.416334)
		(width 0.09525)
		(layer "In13.Cu")
		(net "M_B_CPU0_SA_DQS_DP<3>")
	)
	(segment
		(start 307.432456 -228.925628)
		(end 307.095398 -229.262686)
		(width 0.16002)
		(layer "In13.Cu")
		(net "M_B_CPU0_SA_DQS_DP<3>")
	)
	(segment
		(start 312.5597 -234.022392)
		(end 312.28284 -234.022392)
		(width 0.16002)
		(layer "In13.Cu")
		(net "M_B_CPU0_SA_DQS_DP<3>")
	)
	(segment
		(start 323.978778 -240.416334)
		(end 323.919596 -240.357152)
		(width 0.09525)
		(layer "In13.Cu")
		(net "M_B_CPU0_SA_DQS_DP<3>")
	)
	(segment
		(start 302.83785 -229.249732)
		(end 302.142652 -229.249732)
		(width 0.16002)
		(layer "In13.Cu")
		(net "M_B_CPU0_SA_DQS_DP<3>")
	)
	(segment
		(start 307.095398 -229.262686)
		(end 307.095398 -229.48011)
		(width 0.16002)
		(layer "In13.Cu")
		(net "M_B_CPU0_SA_DQS_DP<3>")
	)
	(segment
		(start 303.842928 -229.750874)
		(end 303.682908 -229.910894)
		(width 0.16002)
		(layer "In13.Cu")
		(net "M_B_CPU0_SA_DQS_DP<3>")
	)
	(segment
		(start 313.460638 -234.92333)
		(end 313.668918 -234.71505)
		(width 0.16002)
		(layer "In13.Cu")
		(net "M_B_CPU0_SA_DQS_DP<3>")
	)
	(segment
		(start 309.339742 -231.079294)
		(end 309.339742 -230.802434)
		(width 0.16002)
		(layer "In13.Cu")
		(net "M_B_CPU0_SA_DQS_DP<3>")
	)
	(segment
		(start 310.921654 -231.967786)
		(end 310.9214 -231.440482)
		(width 0.16002)
		(layer "In13.Cu")
		(net "M_B_CPU0_SA_DQS_DP<3>")
	)
	(segment
		(start 326.640952 -241.574066)
		(end 326.63257 -241.56924)
		(width 0.09525)
		(layer "In13.Cu")
		(net "M_B_CPU0_SA_DQS_DP<3>")
	)
	(segment
		(start 335.281016 -241.24412)
		(end 335.43494 -241.50955)
		(width 0.09525)
		(layer "In13.Cu")
		(net "M_B_CPU0_SA_DQS_DP<3>")
	)
	(segment
		(start 308.367938 -229.48011)
		(end 308.367938 -229.262686)
		(width 0.16002)
		(layer "In13.Cu")
		(net "M_B_CPU0_SA_DQS_DP<3>")
	)
	(segment
		(start 309.547768 -230.067104)
		(end 309.120794 -229.64013)
		(width 0.16002)
		(layer "In13.Cu")
		(net "M_B_CPU0_SA_DQS_DP<3>")
	)
	(segment
		(start 335.43494 -241.50955)
		(end 335.411572 -241.596418)
		(width 0.09525)
		(layer "In13.Cu")
		(net "M_B_CPU0_SA_DQS_DP<3>")
	)
	(segment
		(start 303.842928 -229.58679)
		(end 303.842928 -229.750874)
		(width 0.16002)
		(layer "In13.Cu")
		(net "M_B_CPU0_SA_DQS_DP<3>")
	)
	(segment
		(start 300.105064 -229.06609)
		(end 299.82414 -228.785166)
		(width 0.16002)
		(layer "In13.Cu")
		(net "M_B_CPU0_SA_DQS_DP<3>")
	)
	(segment
		(start 306.935378 -229.64013)
		(end 305.846226 -229.64013)
		(width 0.16002)
		(layer "In13.Cu")
		(net "M_B_CPU0_SA_DQS_DP<3>")
	)
	(segment
		(start 312.295286 -233.341418)
		(end 312.295032 -232.814114)
		(width 0.16002)
		(layer "In13.Cu")
		(net "M_B_CPU0_SA_DQS_DP<3>")
	)
	(segment
		(start 308.03088 -228.925628)
		(end 307.432456 -228.925628)
		(width 0.16002)
		(layer "In13.Cu")
		(net "M_B_CPU0_SA_DQS_DP<3>")
	)
	(segment
		(start 312.76798 -233.814112)
		(end 312.5597 -234.022392)
		(width 0.16002)
		(layer "In13.Cu")
		(net "M_B_CPU0_SA_DQS_DP<3>")
	)
	(segment
		(start 303.682908 -229.910894)
		(end 303.334928 -229.910894)
		(width 0.16002)
		(layer "In13.Cu")
		(net "M_B_CPU0_SA_DQS_DP<3>")
	)
	(segment
		(start 311.186068 -232.64876)
		(end 310.909208 -232.64876)
		(width 0.16002)
		(layer "In13.Cu")
		(net "M_B_CPU0_SA_DQS_DP<3>")
	)
	(segment
		(start 313.668918 -234.71505)
		(end 313.668664 -234.187746)
		(width 0.16002)
		(layer "In13.Cu")
		(net "M_B_CPU0_SA_DQS_DP<3>")
	)
	(segment
		(start 309.120794 -229.64013)
		(end 308.527958 -229.64013)
		(width 0.16002)
		(layer "In13.Cu")
		(net "M_B_CPU0_SA_DQS_DP<3>")
	)
	(segment
		(start 310.020716 -231.066848)
		(end 309.812436 -231.275128)
		(width 0.16002)
		(layer "In13.Cu")
		(net "M_B_CPU0_SA_DQS_DP<3>")
	)
	(segment
		(start 310.713374 -232.452926)
		(end 310.713374 -232.176066)
		(width 0.16002)
		(layer "In13.Cu")
		(net "M_B_CPU0_SA_DQS_DP<3>")
	)
	(segment
		(start 309.812436 -231.275128)
		(end 309.535576 -231.275128)
		(width 0.16002)
		(layer "In13.Cu")
		(net "M_B_CPU0_SA_DQS_DP<3>")
	)
	(segment
		(start 303.174908 -229.58679)
		(end 302.83785 -229.249732)
		(width 0.16002)
		(layer "In13.Cu")
		(net "M_B_CPU0_SA_DQS_DP<3>")
	)
	(segment
		(start 310.547512 -231.066594)
		(end 310.020716 -231.066848)
		(width 0.16002)
		(layer "In13.Cu")
		(net "M_B_CPU0_SA_DQS_DP<3>")
	)
	(segment
		(start 311.394348 -232.44048)
		(end 311.186068 -232.64876)
		(width 0.16002)
		(layer "In13.Cu")
		(net "M_B_CPU0_SA_DQS_DP<3>")
	)
	(segment
		(start 325.167498 -240.903252)
		(end 324.727824 -240.903252)
		(width 0.09525)
		(layer "In13.Cu")
		(net "M_B_CPU0_SA_DQS_DP<3>")
	)
	(segment
		(start 305.846226 -229.64013)
		(end 305.455828 -229.249732)
		(width 0.16002)
		(layer "In13.Cu")
		(net "M_B_CPU0_SA_DQS_DP<3>")
	)
	(segment
		(start 308.527958 -229.64013)
		(end 308.367938 -229.48011)
		(width 0.16002)
		(layer "In13.Cu")
		(net "M_B_CPU0_SA_DQS_DP<3>")
	)
	(segment
		(start 305.455828 -229.249732)
		(end 304.179986 -229.249732)
		(width 0.16002)
		(layer "In13.Cu")
		(net "M_B_CPU0_SA_DQS_DP<3>")
	)
	(segment
		(start 313.668664 -234.187746)
		(end 313.294776 -233.813858)
		(width 0.16002)
		(layer "In13.Cu")
		(net "M_B_CPU0_SA_DQS_DP<3>")
	)
	(segment
		(start 313.294776 -233.813858)
		(end 312.76798 -233.814112)
		(width 0.16002)
		(layer "In13.Cu")
		(net "M_B_CPU0_SA_DQS_DP<3>")
	)
	(arc
		(start 329.452478 -241.56924)
		(mid 329.171046 -241.493485)
		(end 328.889614 -241.56924)
		(width 0.09525)
		(layer "In13.Cu")
		(net "M_B_CPU0_SA_DQS_DP<3>")
	)
	(arc
		(start 334.152494 -241.56924)
		(mid 333.871062 -241.493485)
		(end 333.58963 -241.56924)
		(width 0.09525)
		(layer "In13.Cu")
		(net "M_B_CPU0_SA_DQS_DP<3>")
	)
	(arc
		(start 334.521302 -241.574066)
		(mid 334.33627 -241.61998)
		(end 334.152494 -241.56924)
		(width 0.09525)
		(layer "In13.Cu")
		(net "M_B_CPU0_SA_DQS_DP<3>")
	)
	(arc
		(start 330.769722 -241.56924)
		(mid 330.585947 -241.620012)
		(end 330.400914 -241.574066)
		(width 0.09525)
		(layer "In13.Cu")
		(net "M_B_CPU0_SA_DQS_DP<3>")
	)
	(arc
		(start 332.649576 -241.56924)
		(mid 332.461108 -241.619917)
		(end 332.27264 -241.56924)
		(width 0.09525)
		(layer "In13.Cu")
		(net "M_B_CPU0_SA_DQS_DP<3>")
	)
	(arc
		(start 328.512678 -241.56924)
		(mid 328.231246 -241.493485)
		(end 327.949814 -241.56924)
		(width 0.09525)
		(layer "In13.Cu")
		(net "M_B_CPU0_SA_DQS_DP<3>")
	)
	(arc
		(start 327.949814 -241.56924)
		(mid 327.766039 -241.620012)
		(end 327.581006 -241.574066)
		(width 0.09525)
		(layer "In13.Cu")
		(net "M_B_CPU0_SA_DQS_DP<3>")
	)
	(arc
		(start 332.27264 -241.56924)
		(mid 331.991208 -241.493485)
		(end 331.709776 -241.56924)
		(width 0.09525)
		(layer "In13.Cu")
		(net "M_B_CPU0_SA_DQS_DP<3>")
	)
	(arc
		(start 335.411572 -241.596418)
		(mid 335.253822 -241.618937)
		(end 335.10093 -241.574066)
		(width 0.09525)
		(layer "In13.Cu")
		(net "M_B_CPU0_SA_DQS_DP<3>")
	)
	(arc
		(start 333.21244 -241.56924)
		(mid 332.931008 -241.493485)
		(end 332.649576 -241.56924)
		(width 0.09525)
		(layer "In13.Cu")
		(net "M_B_CPU0_SA_DQS_DP<3>")
	)
	(arc
		(start 326.63257 -241.56924)
		(mid 326.496863 -241.512755)
		(end 326.351138 -241.493548)
		(width 0.09525)
		(layer "In13.Cu")
		(net "M_B_CPU0_SA_DQS_DP<3>")
	)
	(arc
		(start 333.581248 -241.574066)
		(mid 333.396216 -241.61998)
		(end 333.21244 -241.56924)
		(width 0.09525)
		(layer "In13.Cu")
		(net "M_B_CPU0_SA_DQS_DP<3>")
	)
	(arc
		(start 328.889614 -241.56924)
		(mid 328.701146 -241.619917)
		(end 328.512678 -241.56924)
		(width 0.09525)
		(layer "In13.Cu")
		(net "M_B_CPU0_SA_DQS_DP<3>")
	)
	(arc
		(start 327.572624 -241.56924)
		(mid 327.291192 -241.493485)
		(end 327.00976 -241.56924)
		(width 0.09525)
		(layer "In13.Cu")
		(net "M_B_CPU0_SA_DQS_DP<3>")
	)
	(arc
		(start 327.00976 -241.56924)
		(mid 326.825985 -241.620012)
		(end 326.640952 -241.574066)
		(width 0.09525)
		(layer "In13.Cu")
		(net "M_B_CPU0_SA_DQS_DP<3>")
	)
	(arc
		(start 331.709776 -241.56924)
		(mid 331.526001 -241.620012)
		(end 331.340968 -241.574066)
		(width 0.09525)
		(layer "In13.Cu")
		(net "M_B_CPU0_SA_DQS_DP<3>")
	)
	(arc
		(start 335.092548 -241.56924)
		(mid 334.811116 -241.493485)
		(end 334.529684 -241.56924)
		(width 0.09525)
		(layer "In13.Cu")
		(net "M_B_CPU0_SA_DQS_DP<3>")
	)
	(arc
		(start 329.821286 -241.574066)
		(mid 329.636254 -241.61998)
		(end 329.452478 -241.56924)
		(width 0.09525)
		(layer "In13.Cu")
		(net "M_B_CPU0_SA_DQS_DP<3>")
	)
	(arc
		(start 330.392532 -241.56924)
		(mid 330.1111 -241.493485)
		(end 329.829668 -241.56924)
		(width 0.09525)
		(layer "In13.Cu")
		(net "M_B_CPU0_SA_DQS_DP<3>")
	)
	(arc
		(start 331.332586 -241.56924)
		(mid 331.051154 -241.493485)
		(end 330.769722 -241.56924)
		(width 0.09525)
		(layer "In13.Cu")
		(net "M_B_CPU0_SA_DQS_DP<3>")
	)
	(segment
		(start 335.747868 -236.650022)
		(end 335.281016 -236.384084)
		(width 0.12954)
		(layer "F.Cu")
		(net "M_B_CPU0_SA_DQS_DP<2>")
	)
	(segment
		(start 329.821286 -236.71403)
		(end 329.829668 -236.709204)
		(width 0.09525)
		(layer "In13.Cu")
		(net "M_B_CPU0_SA_DQS_DP<2>")
	)
	(segment
		(start 299.82414 -219.435172)
		(end 300.089062 -219.700094)
		(width 0.16002)
		(layer "In13.Cu")
		(net "M_B_CPU0_SA_DQS_DP<2>")
	)
	(segment
		(start 312.586116 -225.238564)
		(end 312.862976 -225.238564)
		(width 0.16002)
		(layer "In13.Cu")
		(net "M_B_CPU0_SA_DQS_DP<2>")
	)
	(segment
		(start 314.176156 -225.200718)
		(end 314.175902 -225.727514)
		(width 0.16002)
		(layer "In13.Cu")
		(net "M_B_CPU0_SA_DQS_DP<2>")
	)
	(segment
		(start 322.07581 -234.733846)
		(end 323.895974 -234.733846)
		(width 0.16002)
		(layer "In13.Cu")
		(net "M_B_CPU0_SA_DQS_DP<2>")
	)
	(segment
		(start 303.209452 -220.31833)
		(end 304.413158 -220.31833)
		(width 0.16002)
		(layer "In13.Cu")
		(net "M_B_CPU0_SA_DQS_DP<2>")
	)
	(segment
		(start 311.212484 -223.864932)
		(end 311.489344 -223.864932)
		(width 0.16002)
		(layer "In13.Cu")
		(net "M_B_CPU0_SA_DQS_DP<2>")
	)
	(segment
		(start 311.489344 -223.864932)
		(end 311.901332 -223.452944)
		(width 0.16002)
		(layer "In13.Cu")
		(net "M_B_CPU0_SA_DQS_DP<2>")
	)
	(segment
		(start 311.901332 -223.452944)
		(end 312.428636 -223.453198)
		(width 0.16002)
		(layer "In13.Cu")
		(net "M_B_CPU0_SA_DQS_DP<2>")
	)
	(segment
		(start 314.175902 -225.727514)
		(end 313.763914 -226.139502)
		(width 0.16002)
		(layer "In13.Cu")
		(net "M_B_CPU0_SA_DQS_DP<2>")
	)
	(segment
		(start 313.274964 -224.826576)
		(end 313.802268 -224.82683)
		(width 0.16002)
		(layer "In13.Cu")
		(net "M_B_CPU0_SA_DQS_DP<2>")
	)
	(segment
		(start 313.763914 -226.139502)
		(end 313.763914 -226.416362)
		(width 0.16002)
		(layer "In13.Cu")
		(net "M_B_CPU0_SA_DQS_DP<2>")
	)
	(segment
		(start 313.959748 -226.612196)
		(end 314.587382 -226.612196)
		(width 0.16002)
		(layer "In13.Cu")
		(net "M_B_CPU0_SA_DQS_DP<2>")
	)
	(segment
		(start 312.862976 -225.238564)
		(end 313.274964 -224.826576)
		(width 0.16002)
		(layer "In13.Cu")
		(net "M_B_CPU0_SA_DQS_DP<2>")
	)
	(segment
		(start 311.428638 -222.98025)
		(end 311.01665 -223.392238)
		(width 0.16002)
		(layer "In13.Cu")
		(net "M_B_CPU0_SA_DQS_DP<2>")
	)
	(segment
		(start 310.115712 -222.4913)
		(end 310.5277 -222.079312)
		(width 0.16002)
		(layer "In13.Cu")
		(net "M_B_CPU0_SA_DQS_DP<2>")
	)
	(segment
		(start 312.80227 -224.353882)
		(end 312.390282 -224.76587)
		(width 0.16002)
		(layer "In13.Cu")
		(net "M_B_CPU0_SA_DQS_DP<2>")
	)
	(segment
		(start 311.055004 -222.079566)
		(end 311.428892 -222.453454)
		(width 0.16002)
		(layer "In13.Cu")
		(net "M_B_CPU0_SA_DQS_DP<2>")
	)
	(segment
		(start 312.390282 -224.76587)
		(end 312.390282 -225.04273)
		(width 0.16002)
		(layer "In13.Cu")
		(net "M_B_CPU0_SA_DQS_DP<2>")
	)
	(segment
		(start 314.587382 -226.612196)
		(end 315.137546 -227.16236)
		(width 0.16002)
		(layer "In13.Cu")
		(net "M_B_CPU0_SA_DQS_DP<2>")
	)
	(segment
		(start 331.332586 -236.709204)
		(end 331.340968 -236.71403)
		(width 0.09525)
		(layer "In13.Cu")
		(net "M_B_CPU0_SA_DQS_DP<2>")
	)
	(segment
		(start 311.01665 -223.392238)
		(end 311.01665 -223.669098)
		(width 0.16002)
		(layer "In13.Cu")
		(net "M_B_CPU0_SA_DQS_DP<2>")
	)
	(segment
		(start 311.428892 -222.453454)
		(end 311.428638 -222.98025)
		(width 0.16002)
		(layer "In13.Cu")
		(net "M_B_CPU0_SA_DQS_DP<2>")
	)
	(segment
		(start 334.521302 -236.71403)
		(end 334.529684 -236.709204)
		(width 0.09525)
		(layer "In13.Cu")
		(net "M_B_CPU0_SA_DQS_DP<2>")
	)
	(segment
		(start 311.01665 -223.669098)
		(end 311.212484 -223.864932)
		(width 0.16002)
		(layer "In13.Cu")
		(net "M_B_CPU0_SA_DQS_DP<2>")
	)
	(segment
		(start 302.591216 -219.700094)
		(end 303.209452 -220.31833)
		(width 0.16002)
		(layer "In13.Cu")
		(net "M_B_CPU0_SA_DQS_DP<2>")
	)
	(segment
		(start 335.092548 -236.709204)
		(end 335.10093 -236.71403)
		(width 0.09525)
		(layer "In13.Cu")
		(net "M_B_CPU0_SA_DQS_DP<2>")
	)
	(segment
		(start 309.838852 -222.4913)
		(end 310.115712 -222.4913)
		(width 0.16002)
		(layer "In13.Cu")
		(net "M_B_CPU0_SA_DQS_DP<2>")
	)
	(segment
		(start 309.576978 -222.229426)
		(end 309.838852 -222.4913)
		(width 0.16002)
		(layer "In13.Cu")
		(net "M_B_CPU0_SA_DQS_DP<2>")
	)
	(segment
		(start 335.43494 -236.649514)
		(end 335.281016 -236.384084)
		(width 0.09525)
		(layer "In13.Cu")
		(net "M_B_CPU0_SA_DQS_DP<2>")
	)
	(segment
		(start 304.550318 -220.18117)
		(end 305.020218 -220.18117)
		(width 0.16002)
		(layer "In13.Cu")
		(net "M_B_CPU0_SA_DQS_DP<2>")
	)
	(segment
		(start 312.802524 -223.827086)
		(end 312.80227 -224.353882)
		(width 0.16002)
		(layer "In13.Cu")
		(net "M_B_CPU0_SA_DQS_DP<2>")
	)
	(segment
		(start 324.393052 -234.99572)
		(end 324.393052 -235.204762)
		(width 0.09525)
		(layer "In13.Cu")
		(net "M_B_CPU0_SA_DQS_DP<2>")
	)
	(segment
		(start 335.411572 -236.736382)
		(end 335.43494 -236.649514)
		(width 0.09525)
		(layer "In13.Cu")
		(net "M_B_CPU0_SA_DQS_DP<2>")
	)
	(segment
		(start 309.576978 -221.86011)
		(end 309.576978 -222.229426)
		(width 0.16002)
		(layer "In13.Cu")
		(net "M_B_CPU0_SA_DQS_DP<2>")
	)
	(segment
		(start 323.895974 -234.733846)
		(end 323.919596 -234.733846)
		(width 0.09525)
		(layer "In13.Cu")
		(net "M_B_CPU0_SA_DQS_DP<2>")
	)
	(segment
		(start 323.978524 -234.792774)
		(end 324.190106 -234.792774)
		(width 0.09525)
		(layer "In13.Cu")
		(net "M_B_CPU0_SA_DQS_DP<2>")
	)
	(segment
		(start 326.99325 -236.720126)
		(end 327.012046 -236.709204)
		(width 0.09525)
		(layer "In13.Cu")
		(net "M_B_CPU0_SA_DQS_DP<2>")
	)
	(segment
		(start 324.393052 -235.204762)
		(end 324.714362 -235.526072)
		(width 0.09525)
		(layer "In13.Cu")
		(net "M_B_CPU0_SA_DQS_DP<2>")
	)
	(segment
		(start 324.714362 -235.526072)
		(end 325.069962 -235.526072)
		(width 0.09525)
		(layer "In13.Cu")
		(net "M_B_CPU0_SA_DQS_DP<2>")
	)
	(segment
		(start 305.020218 -220.18117)
		(end 305.157378 -220.31833)
		(width 0.16002)
		(layer "In13.Cu")
		(net "M_B_CPU0_SA_DQS_DP<2>")
	)
	(segment
		(start 326.17664 -236.63275)
		(end 326.3519 -236.63275)
		(width 0.09525)
		(layer "In13.Cu")
		(net "M_B_CPU0_SA_DQS_DP<2>")
	)
	(segment
		(start 300.089062 -219.700094)
		(end 302.591216 -219.700094)
		(width 0.16002)
		(layer "In13.Cu")
		(net "M_B_CPU0_SA_DQS_DP<2>")
	)
	(segment
		(start 323.919596 -234.733846)
		(end 323.978524 -234.792774)
		(width 0.09525)
		(layer "In13.Cu")
		(net "M_B_CPU0_SA_DQS_DP<2>")
	)
	(segment
		(start 305.157378 -220.31833)
		(end 308.035198 -220.31833)
		(width 0.16002)
		(layer "In13.Cu")
		(net "M_B_CPU0_SA_DQS_DP<2>")
	)
	(segment
		(start 325.069962 -235.526072)
		(end 326.17664 -236.63275)
		(width 0.09525)
		(layer "In13.Cu")
		(net "M_B_CPU0_SA_DQS_DP<2>")
	)
	(segment
		(start 330.392532 -236.709204)
		(end 330.400914 -236.71403)
		(width 0.09525)
		(layer "In13.Cu")
		(net "M_B_CPU0_SA_DQS_DP<2>")
	)
	(segment
		(start 304.413158 -220.31833)
		(end 304.550318 -220.18117)
		(width 0.16002)
		(layer "In13.Cu")
		(net "M_B_CPU0_SA_DQS_DP<2>")
	)
	(segment
		(start 327.547986 -236.694472)
		(end 327.573386 -236.709204)
		(width 0.09525)
		(layer "In13.Cu")
		(net "M_B_CPU0_SA_DQS_DP<2>")
	)
	(segment
		(start 313.763914 -226.416362)
		(end 313.959748 -226.612196)
		(width 0.16002)
		(layer "In13.Cu")
		(net "M_B_CPU0_SA_DQS_DP<2>")
	)
	(segment
		(start 310.5277 -222.079312)
		(end 311.055004 -222.079566)
		(width 0.16002)
		(layer "In13.Cu")
		(net "M_B_CPU0_SA_DQS_DP<2>")
	)
	(segment
		(start 312.428636 -223.453198)
		(end 312.802524 -223.827086)
		(width 0.16002)
		(layer "In13.Cu")
		(net "M_B_CPU0_SA_DQS_DP<2>")
	)
	(segment
		(start 312.390282 -225.04273)
		(end 312.586116 -225.238564)
		(width 0.16002)
		(layer "In13.Cu")
		(net "M_B_CPU0_SA_DQS_DP<2>")
	)
	(segment
		(start 333.581248 -236.71403)
		(end 333.58963 -236.709204)
		(width 0.09525)
		(layer "In13.Cu")
		(net "M_B_CPU0_SA_DQS_DP<2>")
	)
	(segment
		(start 324.190106 -234.792774)
		(end 324.393052 -234.99572)
		(width 0.09525)
		(layer "In13.Cu")
		(net "M_B_CPU0_SA_DQS_DP<2>")
	)
	(segment
		(start 315.137546 -227.795582)
		(end 322.07581 -234.733846)
		(width 0.16002)
		(layer "In13.Cu")
		(net "M_B_CPU0_SA_DQS_DP<2>")
	)
	(segment
		(start 327.573386 -236.709204)
		(end 327.59015 -236.718856)
		(width 0.09525)
		(layer "In13.Cu")
		(net "M_B_CPU0_SA_DQS_DP<2>")
	)
	(segment
		(start 315.137546 -227.16236)
		(end 315.137546 -227.795582)
		(width 0.16002)
		(layer "In13.Cu")
		(net "M_B_CPU0_SA_DQS_DP<2>")
	)
	(segment
		(start 308.035198 -220.31833)
		(end 309.576978 -221.86011)
		(width 0.16002)
		(layer "In13.Cu")
		(net "M_B_CPU0_SA_DQS_DP<2>")
	)
	(segment
		(start 313.802268 -224.82683)
		(end 314.176156 -225.200718)
		(width 0.16002)
		(layer "In13.Cu")
		(net "M_B_CPU0_SA_DQS_DP<2>")
	)
	(arc
		(start 329.452478 -236.709204)
		(mid 329.636253 -236.759976)
		(end 329.821286 -236.71403)
		(width 0.09525)
		(layer "In13.Cu")
		(net "M_B_CPU0_SA_DQS_DP<2>")
	)
	(arc
		(start 327.949814 -236.709204)
		(mid 328.231246 -236.633449)
		(end 328.512678 -236.709204)
		(width 0.09525)
		(layer "In13.Cu")
		(net "M_B_CPU0_SA_DQS_DP<2>")
	)
	(arc
		(start 329.829668 -236.709204)
		(mid 330.1111 -236.633449)
		(end 330.392532 -236.709204)
		(width 0.09525)
		(layer "In13.Cu")
		(net "M_B_CPU0_SA_DQS_DP<2>")
	)
	(arc
		(start 333.21244 -236.709204)
		(mid 333.396215 -236.759976)
		(end 333.581248 -236.71403)
		(width 0.09525)
		(layer "In13.Cu")
		(net "M_B_CPU0_SA_DQS_DP<2>")
	)
	(arc
		(start 327.012046 -236.709204)
		(mid 327.278133 -236.633659)
		(end 327.547986 -236.694472)
		(width 0.09525)
		(layer "In13.Cu")
		(net "M_B_CPU0_SA_DQS_DP<2>")
	)
	(arc
		(start 328.512678 -236.709204)
		(mid 328.701146 -236.759881)
		(end 328.889614 -236.709204)
		(width 0.09525)
		(layer "In13.Cu")
		(net "M_B_CPU0_SA_DQS_DP<2>")
	)
	(arc
		(start 326.63384 -236.709204)
		(mid 326.812155 -236.760346)
		(end 326.99325 -236.720126)
		(width 0.09525)
		(layer "In13.Cu")
		(net "M_B_CPU0_SA_DQS_DP<2>")
	)
	(arc
		(start 333.58963 -236.709204)
		(mid 333.871062 -236.633449)
		(end 334.152494 -236.709204)
		(width 0.09525)
		(layer "In13.Cu")
		(net "M_B_CPU0_SA_DQS_DP<2>")
	)
	(arc
		(start 331.340968 -236.71403)
		(mid 331.526 -236.759944)
		(end 331.709776 -236.709204)
		(width 0.09525)
		(layer "In13.Cu")
		(net "M_B_CPU0_SA_DQS_DP<2>")
	)
	(arc
		(start 331.709776 -236.709204)
		(mid 331.991208 -236.633449)
		(end 332.27264 -236.709204)
		(width 0.09525)
		(layer "In13.Cu")
		(net "M_B_CPU0_SA_DQS_DP<2>")
	)
	(arc
		(start 330.769722 -236.709204)
		(mid 331.051154 -236.633449)
		(end 331.332586 -236.709204)
		(width 0.09525)
		(layer "In13.Cu")
		(net "M_B_CPU0_SA_DQS_DP<2>")
	)
	(arc
		(start 328.889614 -236.709204)
		(mid 329.171046 -236.633449)
		(end 329.452478 -236.709204)
		(width 0.09525)
		(layer "In13.Cu")
		(net "M_B_CPU0_SA_DQS_DP<2>")
	)
	(arc
		(start 334.152494 -236.709204)
		(mid 334.336269 -236.759976)
		(end 334.521302 -236.71403)
		(width 0.09525)
		(layer "In13.Cu")
		(net "M_B_CPU0_SA_DQS_DP<2>")
	)
	(arc
		(start 334.529684 -236.709204)
		(mid 334.811116 -236.633449)
		(end 335.092548 -236.709204)
		(width 0.09525)
		(layer "In13.Cu")
		(net "M_B_CPU0_SA_DQS_DP<2>")
	)
	(arc
		(start 335.10093 -236.71403)
		(mid 335.253825 -236.758858)
		(end 335.411572 -236.736382)
		(width 0.09525)
		(layer "In13.Cu")
		(net "M_B_CPU0_SA_DQS_DP<2>")
	)
	(arc
		(start 327.59015 -236.718856)
		(mid 327.771207 -236.759838)
		(end 327.949814 -236.709204)
		(width 0.09525)
		(layer "In13.Cu")
		(net "M_B_CPU0_SA_DQS_DP<2>")
	)
	(arc
		(start 330.400914 -236.71403)
		(mid 330.585946 -236.759944)
		(end 330.769722 -236.709204)
		(width 0.09525)
		(layer "In13.Cu")
		(net "M_B_CPU0_SA_DQS_DP<2>")
	)
	(arc
		(start 332.649576 -236.709204)
		(mid 332.931008 -236.633449)
		(end 333.21244 -236.709204)
		(width 0.09525)
		(layer "In13.Cu")
		(net "M_B_CPU0_SA_DQS_DP<2>")
	)
	(arc
		(start 332.27264 -236.709204)
		(mid 332.461108 -236.759881)
		(end 332.649576 -236.709204)
		(width 0.09525)
		(layer "In13.Cu")
		(net "M_B_CPU0_SA_DQS_DP<2>")
	)
	(arc
		(start 326.3519 -236.63275)
		(mid 326.497943 -236.652286)
		(end 326.63384 -236.709204)
		(width 0.09525)
		(layer "In13.Cu")
		(net "M_B_CPU0_SA_DQS_DP<2>")
	)
	(segment
		(start 335.747868 -231.789986)
		(end 335.281016 -231.524048)
		(width 0.12954)
		(layer "F.Cu")
		(net "M_B_CPU0_SA_DQS_DP<1>")
	)
	(segment
		(start 329.821286 -231.853994)
		(end 329.829668 -231.849168)
		(width 0.09525)
		(layer "In13.Cu")
		(net "M_B_CPU0_SA_DQS_DP<1>")
	)
	(segment
		(start 311.699656 -214.762588)
		(end 311.976516 -214.762588)
		(width 0.16002)
		(layer "In13.Cu")
		(net "M_B_CPU0_SA_DQS_DP<1>")
	)
	(segment
		(start 324.433946 -228.90607)
		(end 324.433946 -228.989128)
		(width 0.09525)
		(layer "In13.Cu")
		(net "M_B_CPU0_SA_DQS_DP<1>")
	)
	(segment
		(start 300.082712 -210.34375)
		(end 302.426116 -210.34375)
		(width 0.16002)
		(layer "In13.Cu")
		(net "M_B_CPU0_SA_DQS_DP<1>")
	)
	(segment
		(start 314.83046 -217.403172)
		(end 315.357764 -217.403172)
		(width 0.16002)
		(layer "In13.Cu")
		(net "M_B_CPU0_SA_DQS_DP<1>")
	)
	(segment
		(start 319.47866 -221.524068)
		(end 319.852294 -221.897702)
		(width 0.16002)
		(layer "In13.Cu")
		(net "M_B_CPU0_SA_DQS_DP<1>")
	)
	(segment
		(start 311.610502 -214.183214)
		(end 311.503822 -214.289894)
		(width 0.16002)
		(layer "In13.Cu")
		(net "M_B_CPU0_SA_DQS_DP<1>")
	)
	(segment
		(start 307.301392 -210.96859)
		(end 308.332886 -211.395818)
		(width 0.16002)
		(layer "In13.Cu")
		(net "M_B_CPU0_SA_DQS_DP<1>")
	)
	(segment
		(start 319.745614 -222.531686)
		(end 319.745614 -222.808546)
		(width 0.16002)
		(layer "In13.Cu")
		(net "M_B_CPU0_SA_DQS_DP<1>")
	)
	(segment
		(start 315.624718 -218.41079)
		(end 315.624718 -218.68765)
		(width 0.16002)
		(layer "In13.Cu")
		(net "M_B_CPU0_SA_DQS_DP<1>")
	)
	(segment
		(start 318.478662 -221.051374)
		(end 318.371982 -221.158054)
		(width 0.16002)
		(layer "In13.Cu")
		(net "M_B_CPU0_SA_DQS_DP<1>")
	)
	(segment
		(start 326.551798 -230.148892)
		(end 326.892158 -230.489252)
		(width 0.09525)
		(layer "In13.Cu")
		(net "M_B_CPU0_SA_DQS_DP<1>")
	)
	(segment
		(start 312.877454 -215.663526)
		(end 312.877454 -215.940386)
		(width 0.16002)
		(layer "In13.Cu")
		(net "M_B_CPU0_SA_DQS_DP<1>")
	)
	(segment
		(start 310.709564 -213.282276)
		(end 311.236868 -213.282276)
		(width 0.16002)
		(layer "In13.Cu")
		(net "M_B_CPU0_SA_DQS_DP<1>")
	)
	(segment
		(start 312.6105 -214.655908)
		(end 312.984134 -215.029542)
		(width 0.16002)
		(layer "In13.Cu")
		(net "M_B_CPU0_SA_DQS_DP<1>")
	)
	(segment
		(start 311.610502 -213.65591)
		(end 311.610502 -214.183214)
		(width 0.16002)
		(layer "In13.Cu")
		(net "M_B_CPU0_SA_DQS_DP<1>")
	)
	(segment
		(start 311.976516 -214.762588)
		(end 312.083196 -214.655908)
		(width 0.16002)
		(layer "In13.Cu")
		(net "M_B_CPU0_SA_DQS_DP<1>")
	)
	(segment
		(start 318.371982 -221.434914)
		(end 318.567816 -221.630748)
		(width 0.16002)
		(layer "In13.Cu")
		(net "M_B_CPU0_SA_DQS_DP<1>")
	)
	(segment
		(start 324.417182 -228.889306)
		(end 324.433946 -228.90607)
		(width 0.09525)
		(layer "In13.Cu")
		(net "M_B_CPU0_SA_DQS_DP<1>")
	)
	(segment
		(start 313.350148 -216.13622)
		(end 313.456828 -216.02954)
		(width 0.16002)
		(layer "In13.Cu")
		(net "M_B_CPU0_SA_DQS_DP<1>")
	)
	(segment
		(start 316.097412 -218.883484)
		(end 316.204092 -218.776804)
		(width 0.16002)
		(layer "In13.Cu")
		(net "M_B_CPU0_SA_DQS_DP<1>")
	)
	(segment
		(start 303.050956 -210.96859)
		(end 307.301392 -210.96859)
		(width 0.16002)
		(layer "In13.Cu")
		(net "M_B_CPU0_SA_DQS_DP<1>")
	)
	(segment
		(start 299.82414 -210.085178)
		(end 300.082712 -210.34375)
		(width 0.16002)
		(layer "In13.Cu")
		(net "M_B_CPU0_SA_DQS_DP<1>")
	)
	(segment
		(start 314.357766 -216.403174)
		(end 314.357766 -216.930478)
		(width 0.16002)
		(layer "In13.Cu")
		(net "M_B_CPU0_SA_DQS_DP<1>")
	)
	(segment
		(start 313.073288 -216.13622)
		(end 313.350148 -216.13622)
		(width 0.16002)
		(layer "In13.Cu")
		(net "M_B_CPU0_SA_DQS_DP<1>")
	)
	(segment
		(start 321.748658 -226.220782)
		(end 324.417182 -228.889306)
		(width 0.16002)
		(layer "In13.Cu")
		(net "M_B_CPU0_SA_DQS_DP<1>")
	)
	(segment
		(start 318.567816 -221.630748)
		(end 318.844676 -221.630748)
		(width 0.16002)
		(layer "In13.Cu")
		(net "M_B_CPU0_SA_DQS_DP<1>")
	)
	(segment
		(start 316.99835 -219.784422)
		(end 316.99835 -220.061282)
		(width 0.16002)
		(layer "In13.Cu")
		(net "M_B_CPU0_SA_DQS_DP<1>")
	)
	(segment
		(start 326.892158 -230.489252)
		(end 326.892158 -231.187498)
		(width 0.09525)
		(layer "In13.Cu")
		(net "M_B_CPU0_SA_DQS_DP<1>")
	)
	(segment
		(start 315.731398 -217.776806)
		(end 315.731398 -218.30411)
		(width 0.16002)
		(layer "In13.Cu")
		(net "M_B_CPU0_SA_DQS_DP<1>")
	)
	(segment
		(start 310.602884 -213.388956)
		(end 310.709564 -213.282276)
		(width 0.16002)
		(layer "In13.Cu")
		(net "M_B_CPU0_SA_DQS_DP<1>")
	)
	(segment
		(start 312.984134 -215.556846)
		(end 312.877454 -215.663526)
		(width 0.16002)
		(layer "In13.Cu")
		(net "M_B_CPU0_SA_DQS_DP<1>")
	)
	(segment
		(start 330.392532 -231.849168)
		(end 330.400914 -231.853994)
		(width 0.09525)
		(layer "In13.Cu")
		(net "M_B_CPU0_SA_DQS_DP<1>")
	)
	(segment
		(start 331.332586 -231.849168)
		(end 331.340968 -231.853994)
		(width 0.09525)
		(layer "In13.Cu")
		(net "M_B_CPU0_SA_DQS_DP<1>")
	)
	(segment
		(start 314.251086 -217.037158)
		(end 314.251086 -217.314018)
		(width 0.16002)
		(layer "In13.Cu")
		(net "M_B_CPU0_SA_DQS_DP<1>")
	)
	(segment
		(start 308.332886 -211.395818)
		(end 310.326024 -213.388956)
		(width 0.16002)
		(layer "In13.Cu")
		(net "M_B_CPU0_SA_DQS_DP<1>")
	)
	(segment
		(start 315.624718 -218.68765)
		(end 315.820552 -218.883484)
		(width 0.16002)
		(layer "In13.Cu")
		(net "M_B_CPU0_SA_DQS_DP<1>")
	)
	(segment
		(start 314.72378 -217.509852)
		(end 314.83046 -217.403172)
		(width 0.16002)
		(layer "In13.Cu")
		(net "M_B_CPU0_SA_DQS_DP<1>")
	)
	(segment
		(start 317.577724 -220.150436)
		(end 318.105028 -220.150436)
		(width 0.16002)
		(layer "In13.Cu")
		(net "M_B_CPU0_SA_DQS_DP<1>")
	)
	(segment
		(start 333.581248 -231.853994)
		(end 333.58963 -231.849168)
		(width 0.09525)
		(layer "In13.Cu")
		(net "M_B_CPU0_SA_DQS_DP<1>")
	)
	(segment
		(start 319.745614 -222.808546)
		(end 321.748658 -224.81159)
		(width 0.16002)
		(layer "In13.Cu")
		(net "M_B_CPU0_SA_DQS_DP<1>")
	)
	(segment
		(start 317.471044 -220.257116)
		(end 317.577724 -220.150436)
		(width 0.16002)
		(layer "In13.Cu")
		(net "M_B_CPU0_SA_DQS_DP<1>")
	)
	(segment
		(start 335.43494 -231.789478)
		(end 335.281016 -231.524048)
		(width 0.09525)
		(layer "In13.Cu")
		(net "M_B_CPU0_SA_DQS_DP<1>")
	)
	(segment
		(start 324.89394 -229.449122)
		(end 325.398892 -229.449122)
		(width 0.09525)
		(layer "In13.Cu")
		(net "M_B_CPU0_SA_DQS_DP<1>")
	)
	(segment
		(start 321.748658 -224.81159)
		(end 321.748658 -226.220782)
		(width 0.16002)
		(layer "In13.Cu")
		(net "M_B_CPU0_SA_DQS_DP<1>")
	)
	(segment
		(start 314.251086 -217.314018)
		(end 314.44692 -217.509852)
		(width 0.16002)
		(layer "In13.Cu")
		(net "M_B_CPU0_SA_DQS_DP<1>")
	)
	(segment
		(start 318.844676 -221.630748)
		(end 318.951356 -221.524068)
		(width 0.16002)
		(layer "In13.Cu")
		(net "M_B_CPU0_SA_DQS_DP<1>")
	)
	(segment
		(start 334.521302 -231.853994)
		(end 334.529684 -231.849168)
		(width 0.09525)
		(layer "In13.Cu")
		(net "M_B_CPU0_SA_DQS_DP<1>")
	)
	(segment
		(start 315.357764 -217.403172)
		(end 315.731398 -217.776806)
		(width 0.16002)
		(layer "In13.Cu")
		(net "M_B_CPU0_SA_DQS_DP<1>")
	)
	(segment
		(start 312.877454 -215.940386)
		(end 313.073288 -216.13622)
		(width 0.16002)
		(layer "In13.Cu")
		(net "M_B_CPU0_SA_DQS_DP<1>")
	)
	(segment
		(start 314.44692 -217.509852)
		(end 314.72378 -217.509852)
		(width 0.16002)
		(layer "In13.Cu")
		(net "M_B_CPU0_SA_DQS_DP<1>")
	)
	(segment
		(start 316.731396 -218.776804)
		(end 317.10503 -219.150438)
		(width 0.16002)
		(layer "In13.Cu")
		(net "M_B_CPU0_SA_DQS_DP<1>")
	)
	(segment
		(start 319.852294 -222.425006)
		(end 319.745614 -222.531686)
		(width 0.16002)
		(layer "In13.Cu")
		(net "M_B_CPU0_SA_DQS_DP<1>")
	)
	(segment
		(start 326.892158 -231.187498)
		(end 327.4949 -231.79024)
		(width 0.09525)
		(layer "In13.Cu")
		(net "M_B_CPU0_SA_DQS_DP<1>")
	)
	(segment
		(start 335.092548 -231.849168)
		(end 335.10093 -231.853994)
		(width 0.09525)
		(layer "In13.Cu")
		(net "M_B_CPU0_SA_DQS_DP<1>")
	)
	(segment
		(start 311.503822 -214.289894)
		(end 311.503822 -214.566754)
		(width 0.16002)
		(layer "In13.Cu")
		(net "M_B_CPU0_SA_DQS_DP<1>")
	)
	(segment
		(start 313.984132 -216.02954)
		(end 314.357766 -216.403174)
		(width 0.16002)
		(layer "In13.Cu")
		(net "M_B_CPU0_SA_DQS_DP<1>")
	)
	(segment
		(start 312.984134 -215.029542)
		(end 312.984134 -215.556846)
		(width 0.16002)
		(layer "In13.Cu")
		(net "M_B_CPU0_SA_DQS_DP<1>")
	)
	(segment
		(start 311.236868 -213.282276)
		(end 311.610502 -213.65591)
		(width 0.16002)
		(layer "In13.Cu")
		(net "M_B_CPU0_SA_DQS_DP<1>")
	)
	(segment
		(start 316.99835 -220.061282)
		(end 317.194184 -220.257116)
		(width 0.16002)
		(layer "In13.Cu")
		(net "M_B_CPU0_SA_DQS_DP<1>")
	)
	(segment
		(start 315.820552 -218.883484)
		(end 316.097412 -218.883484)
		(width 0.16002)
		(layer "In13.Cu")
		(net "M_B_CPU0_SA_DQS_DP<1>")
	)
	(segment
		(start 319.852294 -221.897702)
		(end 319.852294 -222.425006)
		(width 0.16002)
		(layer "In13.Cu")
		(net "M_B_CPU0_SA_DQS_DP<1>")
	)
	(segment
		(start 315.731398 -218.30411)
		(end 315.624718 -218.41079)
		(width 0.16002)
		(layer "In13.Cu")
		(net "M_B_CPU0_SA_DQS_DP<1>")
	)
	(segment
		(start 314.357766 -216.930478)
		(end 314.251086 -217.037158)
		(width 0.16002)
		(layer "In13.Cu")
		(net "M_B_CPU0_SA_DQS_DP<1>")
	)
	(segment
		(start 317.10503 -219.677742)
		(end 316.99835 -219.784422)
		(width 0.16002)
		(layer "In13.Cu")
		(net "M_B_CPU0_SA_DQS_DP<1>")
	)
	(segment
		(start 318.951356 -221.524068)
		(end 319.47866 -221.524068)
		(width 0.16002)
		(layer "In13.Cu")
		(net "M_B_CPU0_SA_DQS_DP<1>")
	)
	(segment
		(start 326.098662 -230.148892)
		(end 326.551798 -230.148892)
		(width 0.09525)
		(layer "In13.Cu")
		(net "M_B_CPU0_SA_DQS_DP<1>")
	)
	(segment
		(start 335.411572 -231.876346)
		(end 335.43494 -231.789478)
		(width 0.09525)
		(layer "In13.Cu")
		(net "M_B_CPU0_SA_DQS_DP<1>")
	)
	(segment
		(start 327.572624 -231.849168)
		(end 327.581006 -231.853994)
		(width 0.09525)
		(layer "In13.Cu")
		(net "M_B_CPU0_SA_DQS_DP<1>")
	)
	(segment
		(start 317.10503 -219.150438)
		(end 317.10503 -219.677742)
		(width 0.16002)
		(layer "In13.Cu")
		(net "M_B_CPU0_SA_DQS_DP<1>")
	)
	(segment
		(start 302.426116 -210.34375)
		(end 303.050956 -210.96859)
		(width 0.16002)
		(layer "In13.Cu")
		(net "M_B_CPU0_SA_DQS_DP<1>")
	)
	(segment
		(start 313.456828 -216.02954)
		(end 313.984132 -216.02954)
		(width 0.16002)
		(layer "In13.Cu")
		(net "M_B_CPU0_SA_DQS_DP<1>")
	)
	(segment
		(start 318.478662 -220.52407)
		(end 318.478662 -221.051374)
		(width 0.16002)
		(layer "In13.Cu")
		(net "M_B_CPU0_SA_DQS_DP<1>")
	)
	(segment
		(start 318.371982 -221.158054)
		(end 318.371982 -221.434914)
		(width 0.16002)
		(layer "In13.Cu")
		(net "M_B_CPU0_SA_DQS_DP<1>")
	)
	(segment
		(start 316.204092 -218.776804)
		(end 316.731396 -218.776804)
		(width 0.16002)
		(layer "In13.Cu")
		(net "M_B_CPU0_SA_DQS_DP<1>")
	)
	(segment
		(start 325.398892 -229.449122)
		(end 326.098662 -230.148892)
		(width 0.09525)
		(layer "In13.Cu")
		(net "M_B_CPU0_SA_DQS_DP<1>")
	)
	(segment
		(start 310.326024 -213.388956)
		(end 310.602884 -213.388956)
		(width 0.16002)
		(layer "In13.Cu")
		(net "M_B_CPU0_SA_DQS_DP<1>")
	)
	(segment
		(start 317.194184 -220.257116)
		(end 317.471044 -220.257116)
		(width 0.16002)
		(layer "In13.Cu")
		(net "M_B_CPU0_SA_DQS_DP<1>")
	)
	(segment
		(start 324.433946 -228.989128)
		(end 324.89394 -229.449122)
		(width 0.09525)
		(layer "In13.Cu")
		(net "M_B_CPU0_SA_DQS_DP<1>")
	)
	(segment
		(start 311.503822 -214.566754)
		(end 311.699656 -214.762588)
		(width 0.16002)
		(layer "In13.Cu")
		(net "M_B_CPU0_SA_DQS_DP<1>")
	)
	(segment
		(start 318.105028 -220.150436)
		(end 318.478662 -220.52407)
		(width 0.16002)
		(layer "In13.Cu")
		(net "M_B_CPU0_SA_DQS_DP<1>")
	)
	(segment
		(start 312.083196 -214.655908)
		(end 312.6105 -214.655908)
		(width 0.16002)
		(layer "In13.Cu")
		(net "M_B_CPU0_SA_DQS_DP<1>")
	)
	(arc
		(start 333.58963 -231.849168)
		(mid 333.871062 -231.773413)
		(end 334.152494 -231.849168)
		(width 0.09525)
		(layer "In13.Cu")
		(net "M_B_CPU0_SA_DQS_DP<1>")
	)
	(arc
		(start 328.889614 -231.849168)
		(mid 329.171046 -231.773413)
		(end 329.452478 -231.849168)
		(width 0.09525)
		(layer "In13.Cu")
		(net "M_B_CPU0_SA_DQS_DP<1>")
	)
	(arc
		(start 332.27264 -231.849168)
		(mid 332.461108 -231.899845)
		(end 332.649576 -231.849168)
		(width 0.09525)
		(layer "In13.Cu")
		(net "M_B_CPU0_SA_DQS_DP<1>")
	)
	(arc
		(start 330.769722 -231.849168)
		(mid 331.051154 -231.773413)
		(end 331.332586 -231.849168)
		(width 0.09525)
		(layer "In13.Cu")
		(net "M_B_CPU0_SA_DQS_DP<1>")
	)
	(arc
		(start 327.581006 -231.853994)
		(mid 327.766038 -231.899908)
		(end 327.949814 -231.849168)
		(width 0.09525)
		(layer "In13.Cu")
		(net "M_B_CPU0_SA_DQS_DP<1>")
	)
	(arc
		(start 335.10093 -231.853994)
		(mid 335.253825 -231.898822)
		(end 335.411572 -231.876346)
		(width 0.09525)
		(layer "In13.Cu")
		(net "M_B_CPU0_SA_DQS_DP<1>")
	)
	(arc
		(start 327.949814 -231.849168)
		(mid 328.231246 -231.773413)
		(end 328.512678 -231.849168)
		(width 0.09525)
		(layer "In13.Cu")
		(net "M_B_CPU0_SA_DQS_DP<1>")
	)
	(arc
		(start 329.452478 -231.849168)
		(mid 329.636253 -231.89994)
		(end 329.821286 -231.853994)
		(width 0.09525)
		(layer "In13.Cu")
		(net "M_B_CPU0_SA_DQS_DP<1>")
	)
	(arc
		(start 330.400914 -231.853994)
		(mid 330.585946 -231.899908)
		(end 330.769722 -231.849168)
		(width 0.09525)
		(layer "In13.Cu")
		(net "M_B_CPU0_SA_DQS_DP<1>")
	)
	(arc
		(start 333.21244 -231.849168)
		(mid 333.396215 -231.89994)
		(end 333.581248 -231.853994)
		(width 0.09525)
		(layer "In13.Cu")
		(net "M_B_CPU0_SA_DQS_DP<1>")
	)
	(arc
		(start 331.340968 -231.853994)
		(mid 331.526 -231.899908)
		(end 331.709776 -231.849168)
		(width 0.09525)
		(layer "In13.Cu")
		(net "M_B_CPU0_SA_DQS_DP<1>")
	)
	(arc
		(start 334.152494 -231.849168)
		(mid 334.336269 -231.89994)
		(end 334.521302 -231.853994)
		(width 0.09525)
		(layer "In13.Cu")
		(net "M_B_CPU0_SA_DQS_DP<1>")
	)
	(arc
		(start 329.829668 -231.849168)
		(mid 330.1111 -231.773413)
		(end 330.392532 -231.849168)
		(width 0.09525)
		(layer "In13.Cu")
		(net "M_B_CPU0_SA_DQS_DP<1>")
	)
	(arc
		(start 328.512678 -231.849168)
		(mid 328.701146 -231.899845)
		(end 328.889614 -231.849168)
		(width 0.09525)
		(layer "In13.Cu")
		(net "M_B_CPU0_SA_DQS_DP<1>")
	)
	(arc
		(start 331.709776 -231.849168)
		(mid 331.991208 -231.773413)
		(end 332.27264 -231.849168)
		(width 0.09525)
		(layer "In13.Cu")
		(net "M_B_CPU0_SA_DQS_DP<1>")
	)
	(arc
		(start 334.529684 -231.849168)
		(mid 334.811116 -231.773413)
		(end 335.092548 -231.849168)
		(width 0.09525)
		(layer "In13.Cu")
		(net "M_B_CPU0_SA_DQS_DP<1>")
	)
	(arc
		(start 332.649576 -231.849168)
		(mid 332.931008 -231.773413)
		(end 333.21244 -231.849168)
		(width 0.09525)
		(layer "In13.Cu")
		(net "M_B_CPU0_SA_DQS_DP<1>")
	)
	(arc
		(start 327.4949 -231.79024)
		(mid 327.531844 -231.822233)
		(end 327.572624 -231.849168)
		(width 0.09525)
		(layer "In13.Cu")
		(net "M_B_CPU0_SA_DQS_DP<1>")
	)
	(segment
		(start 335.747868 -226.930204)
		(end 335.281016 -226.664266)
		(width 0.12954)
		(layer "F.Cu")
		(net "M_B_CPU0_SA_DQS_DP<0>")
	)
	(segment
		(start 319.714626 -213.303358)
		(end 319.938654 -213.527386)
		(width 0.16002)
		(layer "In13.Cu")
		(net "M_B_CPU0_SA_DQS_DP<0>")
	)
	(segment
		(start 322.061586 -214.901018)
		(end 322.46189 -215.301322)
		(width 0.16002)
		(layer "In13.Cu")
		(net "M_B_CPU0_SA_DQS_DP<0>")
	)
	(segment
		(start 321.088258 -213.92769)
		(end 321.088258 -214.67699)
		(width 0.16002)
		(layer "In13.Cu")
		(net "M_B_CPU0_SA_DQS_DP<0>")
	)
	(segment
		(start 328.480166 -223.730566)
		(end 328.512678 -223.749362)
		(width 0.09525)
		(layer "In13.Cu")
		(net "M_B_CPU0_SA_DQS_DP<0>")
	)
	(segment
		(start 325.209154 -218.797886)
		(end 325.433182 -219.021914)
		(width 0.16002)
		(layer "In13.Cu")
		(net "M_B_CPU0_SA_DQS_DP<0>")
	)
	(segment
		(start 330.392532 -226.989386)
		(end 330.400914 -226.994212)
		(width 0.09525)
		(layer "In13.Cu")
		(net "M_B_CPU0_SA_DQS_DP<0>")
	)
	(segment
		(start 318.340994 -211.180426)
		(end 318.340994 -211.929726)
		(width 0.16002)
		(layer "In13.Cu")
		(net "M_B_CPU0_SA_DQS_DP<0>")
	)
	(segment
		(start 324.05955 -217.648282)
		(end 324.80885 -217.648282)
		(width 0.16002)
		(layer "In13.Cu")
		(net "M_B_CPU0_SA_DQS_DP<0>")
	)
	(segment
		(start 327.441814 -220.281246)
		(end 327.441814 -221.31655)
		(width 0.16002)
		(layer "In13.Cu")
		(net "M_B_CPU0_SA_DQS_DP<0>")
	)
	(segment
		(start 315.193426 -208.032858)
		(end 315.59373 -208.433162)
		(width 0.16002)
		(layer "In13.Cu")
		(net "M_B_CPU0_SA_DQS_DP<0>")
	)
	(segment
		(start 319.938654 -213.527386)
		(end 320.687954 -213.527386)
		(width 0.16002)
		(layer "In13.Cu")
		(net "M_B_CPU0_SA_DQS_DP<0>")
	)
	(segment
		(start 323.835522 -216.674954)
		(end 323.835522 -217.424254)
		(width 0.16002)
		(layer "In13.Cu")
		(net "M_B_CPU0_SA_DQS_DP<0>")
	)
	(segment
		(start 329.89012 -226.160584)
		(end 329.922632 -226.17938)
		(width 0.09525)
		(layer "In13.Cu")
		(net "M_B_CPU0_SA_DQS_DP<0>")
	)
	(segment
		(start 324.80885 -217.648282)
		(end 325.209154 -218.048586)
		(width 0.16002)
		(layer "In13.Cu")
		(net "M_B_CPU0_SA_DQS_DP<0>")
	)
	(segment
		(start 299.82414 -200.735184)
		(end 300.050454 -200.961498)
		(width 0.16002)
		(layer "In13.Cu")
		(net "M_B_CPU0_SA_DQS_DP<0>")
	)
	(segment
		(start 315.817758 -209.40649)
		(end 316.567058 -209.40649)
		(width 0.16002)
		(layer "In13.Cu")
		(net "M_B_CPU0_SA_DQS_DP<0>")
	)
	(segment
		(start 330.36002 -226.97059)
		(end 330.392532 -226.989386)
		(width 0.09525)
		(layer "In13.Cu")
		(net "M_B_CPU0_SA_DQS_DP<0>")
	)
	(segment
		(start 316.567058 -209.40649)
		(end 316.967362 -209.806794)
		(width 0.16002)
		(layer "In13.Cu")
		(net "M_B_CPU0_SA_DQS_DP<0>")
	)
	(segment
		(start 329.922632 -226.17938)
		(end 329.957684 -226.199954)
		(width 0.09525)
		(layer "In13.Cu")
		(net "M_B_CPU0_SA_DQS_DP<0>")
	)
	(segment
		(start 316.967362 -209.806794)
		(end 316.967362 -210.556094)
		(width 0.16002)
		(layer "In13.Cu")
		(net "M_B_CPU0_SA_DQS_DP<0>")
	)
	(segment
		(start 335.092548 -226.989386)
		(end 335.10093 -226.994212)
		(width 0.09525)
		(layer "In13.Cu")
		(net "M_B_CPU0_SA_DQS_DP<0>")
	)
	(segment
		(start 327.540112 -222.111062)
		(end 327.540112 -222.110554)
		(width 0.09525)
		(layer "In13.Cu")
		(net "M_B_CPU0_SA_DQS_DP<0>")
	)
	(segment
		(start 329.452478 -225.369374)
		(end 329.490578 -225.391472)
		(width 0.09525)
		(layer "In13.Cu")
		(net "M_B_CPU0_SA_DQS_DP<0>")
	)
	(segment
		(start 328.982578 -224.559368)
		(end 329.020678 -224.581466)
		(width 0.09525)
		(layer "In13.Cu")
		(net "M_B_CPU0_SA_DQS_DP<0>")
	)
	(segment
		(start 318.565022 -212.153754)
		(end 319.314322 -212.153754)
		(width 0.16002)
		(layer "In13.Cu")
		(net "M_B_CPU0_SA_DQS_DP<0>")
	)
	(segment
		(start 312.446162 -205.285594)
		(end 312.846466 -205.685898)
		(width 0.16002)
		(layer "In13.Cu")
		(net "M_B_CPU0_SA_DQS_DP<0>")
	)
	(segment
		(start 312.846466 -205.685898)
		(end 312.846466 -206.435198)
		(width 0.16002)
		(layer "In13.Cu")
		(net "M_B_CPU0_SA_DQS_DP<0>")
	)
	(segment
		(start 326.182482 -219.021914)
		(end 327.441814 -220.281246)
		(width 0.16002)
		(layer "In13.Cu")
		(net "M_B_CPU0_SA_DQS_DP<0>")
	)
	(segment
		(start 335.43494 -226.929696)
		(end 335.281016 -226.664266)
		(width 0.09525)
		(layer "In13.Cu")
		(net "M_B_CPU0_SA_DQS_DP<0>")
	)
	(segment
		(start 313.819794 -206.659226)
		(end 314.220098 -207.05953)
		(width 0.16002)
		(layer "In13.Cu")
		(net "M_B_CPU0_SA_DQS_DP<0>")
	)
	(segment
		(start 320.687954 -213.527386)
		(end 321.088258 -213.92769)
		(width 0.16002)
		(layer "In13.Cu")
		(net "M_B_CPU0_SA_DQS_DP<0>")
	)
	(segment
		(start 311.696862 -205.285594)
		(end 312.446162 -205.285594)
		(width 0.16002)
		(layer "In13.Cu")
		(net "M_B_CPU0_SA_DQS_DP<0>")
	)
	(segment
		(start 319.714626 -212.554058)
		(end 319.714626 -213.303358)
		(width 0.16002)
		(layer "In13.Cu")
		(net "M_B_CPU0_SA_DQS_DP<0>")
	)
	(segment
		(start 333.581248 -226.994212)
		(end 333.58963 -226.989386)
		(width 0.09525)
		(layer "In13.Cu")
		(net "M_B_CPU0_SA_DQS_DP<0>")
	)
	(segment
		(start 328.950066 -224.540572)
		(end 328.982578 -224.559368)
		(width 0.09525)
		(layer "In13.Cu")
		(net "M_B_CPU0_SA_DQS_DP<0>")
	)
	(segment
		(start 325.209154 -218.048586)
		(end 325.209154 -218.797886)
		(width 0.16002)
		(layer "In13.Cu")
		(net "M_B_CPU0_SA_DQS_DP<0>")
	)
	(segment
		(start 310.099202 -202.938634)
		(end 310.099202 -203.687934)
		(width 0.16002)
		(layer "In13.Cu")
		(net "M_B_CPU0_SA_DQS_DP<0>")
	)
	(segment
		(start 322.46189 -216.050622)
		(end 322.685918 -216.27465)
		(width 0.16002)
		(layer "In13.Cu")
		(net "M_B_CPU0_SA_DQS_DP<0>")
	)
	(segment
		(start 314.220098 -207.05953)
		(end 314.220098 -207.80883)
		(width 0.16002)
		(layer "In13.Cu")
		(net "M_B_CPU0_SA_DQS_DP<0>")
	)
	(segment
		(start 319.314322 -212.153754)
		(end 319.714626 -212.554058)
		(width 0.16002)
		(layer "In13.Cu")
		(net "M_B_CPU0_SA_DQS_DP<0>")
	)
	(segment
		(start 321.312286 -214.901018)
		(end 322.061586 -214.901018)
		(width 0.16002)
		(layer "In13.Cu")
		(net "M_B_CPU0_SA_DQS_DP<0>")
	)
	(segment
		(start 311.472834 -205.061566)
		(end 311.696862 -205.285594)
		(width 0.16002)
		(layer "In13.Cu")
		(net "M_B_CPU0_SA_DQS_DP<0>")
	)
	(segment
		(start 314.220098 -207.80883)
		(end 314.444126 -208.032858)
		(width 0.16002)
		(layer "In13.Cu")
		(net "M_B_CPU0_SA_DQS_DP<0>")
	)
	(segment
		(start 317.94069 -210.780122)
		(end 318.340994 -211.180426)
		(width 0.16002)
		(layer "In13.Cu")
		(net "M_B_CPU0_SA_DQS_DP<0>")
	)
	(segment
		(start 315.59373 -209.182462)
		(end 315.817758 -209.40649)
		(width 0.16002)
		(layer "In13.Cu")
		(net "M_B_CPU0_SA_DQS_DP<0>")
	)
	(segment
		(start 327.540112 -222.110554)
		(end 327.611994 -222.15221)
		(width 0.09525)
		(layer "In13.Cu")
		(net "M_B_CPU0_SA_DQS_DP<0>")
	)
	(segment
		(start 314.444126 -208.032858)
		(end 315.193426 -208.032858)
		(width 0.16002)
		(layer "In13.Cu")
		(net "M_B_CPU0_SA_DQS_DP<0>")
	)
	(segment
		(start 310.099202 -203.687934)
		(end 310.32323 -203.911962)
		(width 0.16002)
		(layer "In13.Cu")
		(net "M_B_CPU0_SA_DQS_DP<0>")
	)
	(segment
		(start 315.59373 -208.433162)
		(end 315.59373 -209.182462)
		(width 0.16002)
		(layer "In13.Cu")
		(net "M_B_CPU0_SA_DQS_DP<0>")
	)
	(segment
		(start 316.967362 -210.556094)
		(end 317.19139 -210.780122)
		(width 0.16002)
		(layer "In13.Cu")
		(net "M_B_CPU0_SA_DQS_DP<0>")
	)
	(segment
		(start 327.441814 -221.31655)
		(end 327.441814 -221.340172)
		(width 0.09525)
		(layer "In13.Cu")
		(net "M_B_CPU0_SA_DQS_DP<0>")
	)
	(segment
		(start 328.011282 -222.921068)
		(end 328.042778 -222.939356)
		(width 0.09525)
		(layer "In13.Cu")
		(net "M_B_CPU0_SA_DQS_DP<0>")
	)
	(segment
		(start 334.521302 -226.994212)
		(end 334.529684 -226.989386)
		(width 0.09525)
		(layer "In13.Cu")
		(net "M_B_CPU0_SA_DQS_DP<0>")
	)
	(segment
		(start 328.042778 -222.939356)
		(end 328.07783 -222.95993)
		(width 0.09525)
		(layer "In13.Cu")
		(net "M_B_CPU0_SA_DQS_DP<0>")
	)
	(segment
		(start 300.050454 -200.961498)
		(end 304.093372 -200.961498)
		(width 0.16002)
		(layer "In13.Cu")
		(net "M_B_CPU0_SA_DQS_DP<0>")
	)
	(segment
		(start 323.835522 -217.424254)
		(end 324.05955 -217.648282)
		(width 0.16002)
		(layer "In13.Cu")
		(net "M_B_CPU0_SA_DQS_DP<0>")
	)
	(segment
		(start 329.420982 -225.351086)
		(end 329.452478 -225.369374)
		(width 0.09525)
		(layer "In13.Cu")
		(net "M_B_CPU0_SA_DQS_DP<0>")
	)
	(segment
		(start 323.435218 -216.27465)
		(end 323.835522 -216.674954)
		(width 0.16002)
		(layer "In13.Cu")
		(net "M_B_CPU0_SA_DQS_DP<0>")
	)
	(segment
		(start 335.411572 -227.016564)
		(end 335.43494 -226.929696)
		(width 0.09525)
		(layer "In13.Cu")
		(net "M_B_CPU0_SA_DQS_DP<0>")
	)
	(segment
		(start 321.088258 -214.67699)
		(end 321.312286 -214.901018)
		(width 0.16002)
		(layer "In13.Cu")
		(net "M_B_CPU0_SA_DQS_DP<0>")
	)
	(segment
		(start 312.846466 -206.435198)
		(end 313.070494 -206.659226)
		(width 0.16002)
		(layer "In13.Cu")
		(net "M_B_CPU0_SA_DQS_DP<0>")
	)
	(segment
		(start 325.433182 -219.021914)
		(end 326.182482 -219.021914)
		(width 0.16002)
		(layer "In13.Cu")
		(net "M_B_CPU0_SA_DQS_DP<0>")
	)
	(segment
		(start 328.512678 -223.749362)
		(end 328.54773 -223.769936)
		(width 0.09525)
		(layer "In13.Cu")
		(net "M_B_CPU0_SA_DQS_DP<0>")
	)
	(segment
		(start 310.32323 -203.911962)
		(end 311.07253 -203.911962)
		(width 0.16002)
		(layer "In13.Cu")
		(net "M_B_CPU0_SA_DQS_DP<0>")
	)
	(segment
		(start 322.46189 -215.301322)
		(end 322.46189 -216.050622)
		(width 0.16002)
		(layer "In13.Cu")
		(net "M_B_CPU0_SA_DQS_DP<0>")
	)
	(segment
		(start 311.472834 -204.312266)
		(end 311.472834 -205.061566)
		(width 0.16002)
		(layer "In13.Cu")
		(net "M_B_CPU0_SA_DQS_DP<0>")
	)
	(segment
		(start 304.093372 -200.961498)
		(end 305.70678 -201.629772)
		(width 0.16002)
		(layer "In13.Cu")
		(net "M_B_CPU0_SA_DQS_DP<0>")
	)
	(segment
		(start 318.340994 -211.929726)
		(end 318.565022 -212.153754)
		(width 0.16002)
		(layer "In13.Cu")
		(net "M_B_CPU0_SA_DQS_DP<0>")
	)
	(segment
		(start 313.070494 -206.659226)
		(end 313.819794 -206.659226)
		(width 0.16002)
		(layer "In13.Cu")
		(net "M_B_CPU0_SA_DQS_DP<0>")
	)
	(segment
		(start 317.19139 -210.780122)
		(end 317.94069 -210.780122)
		(width 0.16002)
		(layer "In13.Cu")
		(net "M_B_CPU0_SA_DQS_DP<0>")
	)
	(segment
		(start 311.07253 -203.911962)
		(end 311.472834 -204.312266)
		(width 0.16002)
		(layer "In13.Cu")
		(net "M_B_CPU0_SA_DQS_DP<0>")
	)
	(segment
		(start 308.79034 -201.629772)
		(end 310.099202 -202.938634)
		(width 0.16002)
		(layer "In13.Cu")
		(net "M_B_CPU0_SA_DQS_DP<0>")
	)
	(segment
		(start 305.70678 -201.629772)
		(end 308.79034 -201.629772)
		(width 0.16002)
		(layer "In13.Cu")
		(net "M_B_CPU0_SA_DQS_DP<0>")
	)
	(segment
		(start 327.382886 -221.3991)
		(end 327.382886 -221.80423)
		(width 0.09525)
		(layer "In13.Cu")
		(net "M_B_CPU0_SA_DQS_DP<0>")
	)
	(segment
		(start 327.441814 -221.340172)
		(end 327.382886 -221.3991)
		(width 0.09525)
		(layer "In13.Cu")
		(net "M_B_CPU0_SA_DQS_DP<0>")
	)
	(segment
		(start 322.685918 -216.27465)
		(end 323.435218 -216.27465)
		(width 0.16002)
		(layer "In13.Cu")
		(net "M_B_CPU0_SA_DQS_DP<0>")
	)
	(segment
		(start 331.332586 -226.989386)
		(end 331.340968 -226.994212)
		(width 0.09525)
		(layer "In13.Cu")
		(net "M_B_CPU0_SA_DQS_DP<0>")
	)
	(arc
		(start 331.340968 -226.994212)
		(mid 331.526 -227.040126)
		(end 331.709776 -226.989386)
		(width 0.09525)
		(layer "In13.Cu")
		(net "M_B_CPU0_SA_DQS_DP<0>")
	)
	(arc
		(start 327.611994 -222.15221)
		(mid 327.78968 -222.353502)
		(end 327.853802 -222.614236)
		(width 0.09525)
		(layer "In13.Cu")
		(net "M_B_CPU0_SA_DQS_DP<0>")
	)
	(arc
		(start 334.152494 -226.989386)
		(mid 334.336269 -227.040158)
		(end 334.521302 -226.994212)
		(width 0.09525)
		(layer "In13.Cu")
		(net "M_B_CPU0_SA_DQS_DP<0>")
	)
	(arc
		(start 329.490578 -225.391472)
		(mid 329.669028 -225.592942)
		(end 329.733402 -225.85426)
		(width 0.09525)
		(layer "In13.Cu")
		(net "M_B_CPU0_SA_DQS_DP<0>")
	)
	(arc
		(start 333.21244 -226.989386)
		(mid 333.396215 -227.040158)
		(end 333.581248 -226.994212)
		(width 0.09525)
		(layer "In13.Cu")
		(net "M_B_CPU0_SA_DQS_DP<0>")
	)
	(arc
		(start 328.793348 -224.234248)
		(mid 328.834805 -224.406288)
		(end 328.950066 -224.540572)
		(width 0.09525)
		(layer "In13.Cu")
		(net "M_B_CPU0_SA_DQS_DP<0>")
	)
	(arc
		(start 330.769722 -226.989386)
		(mid 331.051154 -226.913631)
		(end 331.332586 -226.989386)
		(width 0.09525)
		(layer "In13.Cu")
		(net "M_B_CPU0_SA_DQS_DP<0>")
	)
	(arc
		(start 334.529684 -226.989386)
		(mid 334.811116 -226.913631)
		(end 335.092548 -226.989386)
		(width 0.09525)
		(layer "In13.Cu")
		(net "M_B_CPU0_SA_DQS_DP<0>")
	)
	(arc
		(start 331.709776 -226.989386)
		(mid 331.991208 -226.913631)
		(end 332.27264 -226.989386)
		(width 0.09525)
		(layer "In13.Cu")
		(net "M_B_CPU0_SA_DQS_DP<0>")
	)
	(arc
		(start 335.10093 -226.994212)
		(mid 335.253825 -227.03904)
		(end 335.411572 -227.016564)
		(width 0.09525)
		(layer "In13.Cu")
		(net "M_B_CPU0_SA_DQS_DP<0>")
	)
	(arc
		(start 329.957684 -226.199954)
		(mid 330.138139 -226.40162)
		(end 330.203302 -226.664266)
		(width 0.09525)
		(layer "In13.Cu")
		(net "M_B_CPU0_SA_DQS_DP<0>")
	)
	(arc
		(start 332.27264 -226.989386)
		(mid 332.461108 -227.040063)
		(end 332.649576 -226.989386)
		(width 0.09525)
		(layer "In13.Cu")
		(net "M_B_CPU0_SA_DQS_DP<0>")
	)
	(arc
		(start 328.54773 -223.769936)
		(mid 328.728185 -223.971602)
		(end 328.793348 -224.234248)
		(width 0.09525)
		(layer "In13.Cu")
		(net "M_B_CPU0_SA_DQS_DP<0>")
	)
	(arc
		(start 330.203302 -226.664266)
		(mid 330.244759 -226.836306)
		(end 330.36002 -226.97059)
		(width 0.09525)
		(layer "In13.Cu")
		(net "M_B_CPU0_SA_DQS_DP<0>")
	)
	(arc
		(start 327.382886 -221.80423)
		(mid 327.424485 -221.976609)
		(end 327.540112 -222.111062)
		(width 0.09525)
		(layer "In13.Cu")
		(net "M_B_CPU0_SA_DQS_DP<0>")
	)
	(arc
		(start 329.020678 -224.581466)
		(mid 329.199128 -224.782936)
		(end 329.263502 -225.044254)
		(width 0.09525)
		(layer "In13.Cu")
		(net "M_B_CPU0_SA_DQS_DP<0>")
	)
	(arc
		(start 329.263502 -225.044254)
		(mid 329.305167 -225.216701)
		(end 329.420982 -225.351086)
		(width 0.09525)
		(layer "In13.Cu")
		(net "M_B_CPU0_SA_DQS_DP<0>")
	)
	(arc
		(start 333.58963 -226.989386)
		(mid 333.871062 -226.913631)
		(end 334.152494 -226.989386)
		(width 0.09525)
		(layer "In13.Cu")
		(net "M_B_CPU0_SA_DQS_DP<0>")
	)
	(arc
		(start 328.323448 -223.424242)
		(mid 328.364905 -223.596282)
		(end 328.480166 -223.730566)
		(width 0.09525)
		(layer "In13.Cu")
		(net "M_B_CPU0_SA_DQS_DP<0>")
	)
	(arc
		(start 327.853802 -222.614236)
		(mid 327.895467 -222.786683)
		(end 328.011282 -222.921068)
		(width 0.09525)
		(layer "In13.Cu")
		(net "M_B_CPU0_SA_DQS_DP<0>")
	)
	(arc
		(start 328.07783 -222.95993)
		(mid 328.258285 -223.161596)
		(end 328.323448 -223.424242)
		(width 0.09525)
		(layer "In13.Cu")
		(net "M_B_CPU0_SA_DQS_DP<0>")
	)
	(arc
		(start 329.733402 -225.85426)
		(mid 329.774859 -226.0263)
		(end 329.89012 -226.160584)
		(width 0.09525)
		(layer "In13.Cu")
		(net "M_B_CPU0_SA_DQS_DP<0>")
	)
	(arc
		(start 332.649576 -226.989386)
		(mid 332.931008 -226.913631)
		(end 333.21244 -226.989386)
		(width 0.09525)
		(layer "In13.Cu")
		(net "M_B_CPU0_SA_DQS_DP<0>")
	)
	(arc
		(start 330.400914 -226.994212)
		(mid 330.585946 -227.040126)
		(end 330.769722 -226.989386)
		(width 0.09525)
		(layer "In13.Cu")
		(net "M_B_CPU0_SA_DQS_DP<0>")
	)
	(segment
		(start 337.158076 -247.1801)
		(end 336.691224 -246.914162)
		(width 0.12954)
		(layer "F.Cu")
		(net "M_B_CPU0_SA_DQS_DN<9>")
	)
	(segment
		(start 323.978524 -247.09247)
		(end 323.919596 -247.033542)
		(width 0.09525)
		(layer "In13.Cu")
		(net "M_B_CPU0_SA_DQS_DN<9>")
	)
	(segment
		(start 324.520052 -247.398032)
		(end 324.21449 -247.09247)
		(width 0.09525)
		(layer "In13.Cu")
		(net "M_B_CPU0_SA_DQS_DN<9>")
	)
	(segment
		(start 332.750922 -247.244108)
		(end 332.74254 -247.239282)
		(width 0.09525)
		(layer "In13.Cu")
		(net "M_B_CPU0_SA_DQS_DN<9>")
	)
	(segment
		(start 296.012616 -239.273588)
		(end 295.724072 -238.985044)
		(width 0.16002)
		(layer "In13.Cu")
		(net "M_B_CPU0_SA_DQS_DN<9>")
	)
	(segment
		(start 323.153278 -246.862092)
		(end 312.836814 -246.862092)
		(width 0.16002)
		(layer "In13.Cu")
		(net "M_B_CPU0_SA_DQS_DN<9>")
	)
	(segment
		(start 299.579792 -239.407954)
		(end 298.68876 -239.038892)
		(width 0.16002)
		(layer "In13.Cu")
		(net "M_B_CPU0_SA_DQS_DN<9>")
	)
	(segment
		(start 325.880222 -247.163336)
		(end 325.651114 -247.163336)
		(width 0.09525)
		(layer "In13.Cu")
		(net "M_B_CPU0_SA_DQS_DN<9>")
	)
	(segment
		(start 326.539352 -247.239282)
		(end 326.524874 -247.247664)
		(width 0.09525)
		(layer "In13.Cu")
		(net "M_B_CPU0_SA_DQS_DN<9>")
	)
	(segment
		(start 324.21449 -247.09247)
		(end 323.978524 -247.09247)
		(width 0.09525)
		(layer "In13.Cu")
		(net "M_B_CPU0_SA_DQS_DN<9>")
	)
	(segment
		(start 323.895974 -247.033542)
		(end 323.324728 -247.033542)
		(width 0.16002)
		(layer "In13.Cu")
		(net "M_B_CPU0_SA_DQS_DN<9>")
	)
	(segment
		(start 327.11009 -247.244108)
		(end 327.101708 -247.239282)
		(width 0.09525)
		(layer "In13.Cu")
		(net "M_B_CPU0_SA_DQS_DN<9>")
	)
	(segment
		(start 297.293792 -239.273588)
		(end 296.012616 -239.273588)
		(width 0.16002)
		(layer "In13.Cu")
		(net "M_B_CPU0_SA_DQS_DN<9>")
	)
	(segment
		(start 300.923706 -239.407954)
		(end 299.579792 -239.407954)
		(width 0.16002)
		(layer "In13.Cu")
		(net "M_B_CPU0_SA_DQS_DN<9>")
	)
	(segment
		(start 335.939638 -247.239282)
		(end 335.931256 -247.244108)
		(width 0.09525)
		(layer "In13.Cu")
		(net "M_B_CPU0_SA_DQS_DN<9>")
	)
	(segment
		(start 326.554084 -247.230646)
		(end 326.539352 -247.239282)
		(width 0.09525)
		(layer "In13.Cu")
		(net "M_B_CPU0_SA_DQS_DN<9>")
	)
	(segment
		(start 307.932582 -241.95786)
		(end 307.127656 -241.95786)
		(width 0.16002)
		(layer "In13.Cu")
		(net "M_B_CPU0_SA_DQS_DN<9>")
	)
	(segment
		(start 303.423574 -239.395762)
		(end 302.363124 -239.834928)
		(width 0.16002)
		(layer "In13.Cu")
		(net "M_B_CPU0_SA_DQS_DN<9>")
	)
	(segment
		(start 297.86072 -239.038892)
		(end 297.293792 -239.273588)
		(width 0.16002)
		(layer "In13.Cu")
		(net "M_B_CPU0_SA_DQS_DN<9>")
	)
	(segment
		(start 323.324728 -247.033542)
		(end 323.153278 -246.862092)
		(width 0.16002)
		(layer "In13.Cu")
		(net "M_B_CPU0_SA_DQS_DN<9>")
	)
	(segment
		(start 328.99096 -247.244108)
		(end 328.982578 -247.239282)
		(width 0.09525)
		(layer "In13.Cu")
		(net "M_B_CPU0_SA_DQS_DN<9>")
	)
	(segment
		(start 325.416418 -247.398032)
		(end 324.520052 -247.398032)
		(width 0.09525)
		(layer "In13.Cu")
		(net "M_B_CPU0_SA_DQS_DN<9>")
	)
	(segment
		(start 323.919596 -247.033542)
		(end 323.895974 -247.033542)
		(width 0.09525)
		(layer "In13.Cu")
		(net "M_B_CPU0_SA_DQS_DN<9>")
	)
	(segment
		(start 304.934366 -239.76457)
		(end 304.043842 -239.395762)
		(width 0.16002)
		(layer "In13.Cu")
		(net "M_B_CPU0_SA_DQS_DN<9>")
	)
	(segment
		(start 331.239622 -247.239282)
		(end 331.23124 -247.244108)
		(width 0.09525)
		(layer "In13.Cu")
		(net "M_B_CPU0_SA_DQS_DN<9>")
	)
	(segment
		(start 332.179676 -247.239282)
		(end 332.171294 -247.244108)
		(width 0.09525)
		(layer "In13.Cu")
		(net "M_B_CPU0_SA_DQS_DN<9>")
	)
	(segment
		(start 336.845148 -247.179592)
		(end 336.82178 -247.26646)
		(width 0.09525)
		(layer "In13.Cu")
		(net "M_B_CPU0_SA_DQS_DN<9>")
	)
	(segment
		(start 307.127656 -241.95786)
		(end 304.934366 -239.76457)
		(width 0.16002)
		(layer "In13.Cu")
		(net "M_B_CPU0_SA_DQS_DN<9>")
	)
	(segment
		(start 333.690976 -247.244108)
		(end 333.682594 -247.239282)
		(width 0.09525)
		(layer "In13.Cu")
		(net "M_B_CPU0_SA_DQS_DN<9>")
	)
	(segment
		(start 312.836814 -246.862092)
		(end 307.932582 -241.95786)
		(width 0.16002)
		(layer "In13.Cu")
		(net "M_B_CPU0_SA_DQS_DN<9>")
	)
	(segment
		(start 328.042524 -247.239282)
		(end 328.03211 -247.233186)
		(width 0.09525)
		(layer "In13.Cu")
		(net "M_B_CPU0_SA_DQS_DN<9>")
	)
	(segment
		(start 325.651114 -247.163336)
		(end 325.416418 -247.398032)
		(width 0.09525)
		(layer "In13.Cu")
		(net "M_B_CPU0_SA_DQS_DN<9>")
	)
	(segment
		(start 301.954692 -239.834928)
		(end 300.923706 -239.407954)
		(width 0.16002)
		(layer "In13.Cu")
		(net "M_B_CPU0_SA_DQS_DN<9>")
	)
	(segment
		(start 302.363124 -239.834928)
		(end 301.954692 -239.834928)
		(width 0.16002)
		(layer "In13.Cu")
		(net "M_B_CPU0_SA_DQS_DN<9>")
	)
	(segment
		(start 328.419714 -247.239282)
		(end 328.411332 -247.244108)
		(width 0.09525)
		(layer "In13.Cu")
		(net "M_B_CPU0_SA_DQS_DN<9>")
	)
	(segment
		(start 336.691224 -246.914162)
		(end 336.845148 -247.179592)
		(width 0.09525)
		(layer "In13.Cu")
		(net "M_B_CPU0_SA_DQS_DN<9>")
	)
	(segment
		(start 298.68876 -239.038892)
		(end 297.86072 -239.038892)
		(width 0.16002)
		(layer "In13.Cu")
		(net "M_B_CPU0_SA_DQS_DN<9>")
	)
	(segment
		(start 304.043842 -239.395762)
		(end 303.423574 -239.395762)
		(width 0.16002)
		(layer "In13.Cu")
		(net "M_B_CPU0_SA_DQS_DN<9>")
	)
	(arc
		(start 336.82178 -247.26646)
		(mid 336.659098 -247.288592)
		(end 336.502502 -247.239282)
		(width 0.09525)
		(layer "In13.Cu")
		(net "M_B_CPU0_SA_DQS_DN<9>")
	)
	(arc
		(start 326.524874 -247.247664)
		(mid 326.342442 -247.290104)
		(end 326.162162 -247.239282)
		(width 0.09525)
		(layer "In13.Cu")
		(net "M_B_CPU0_SA_DQS_DN<9>")
	)
	(arc
		(start 331.802486 -247.239282)
		(mid 331.521054 -247.163527)
		(end 331.239622 -247.239282)
		(width 0.09525)
		(layer "In13.Cu")
		(net "M_B_CPU0_SA_DQS_DN<9>")
	)
	(arc
		(start 334.999584 -247.239282)
		(mid 334.811116 -247.289959)
		(end 334.622648 -247.239282)
		(width 0.09525)
		(layer "In13.Cu")
		(net "M_B_CPU0_SA_DQS_DN<9>")
	)
	(arc
		(start 327.101708 -247.239282)
		(mid 326.829034 -247.163595)
		(end 326.554084 -247.230646)
		(width 0.09525)
		(layer "In13.Cu")
		(net "M_B_CPU0_SA_DQS_DN<9>")
	)
	(arc
		(start 330.299568 -247.239282)
		(mid 330.1111 -247.289959)
		(end 329.922632 -247.239282)
		(width 0.09525)
		(layer "In13.Cu")
		(net "M_B_CPU0_SA_DQS_DN<9>")
	)
	(arc
		(start 328.03211 -247.233186)
		(mid 327.754948 -247.163386)
		(end 327.479406 -247.239282)
		(width 0.09525)
		(layer "In13.Cu")
		(net "M_B_CPU0_SA_DQS_DN<9>")
	)
	(arc
		(start 330.862432 -247.239282)
		(mid 330.581 -247.163527)
		(end 330.299568 -247.239282)
		(width 0.09525)
		(layer "In13.Cu")
		(net "M_B_CPU0_SA_DQS_DN<9>")
	)
	(arc
		(start 332.171294 -247.244108)
		(mid 331.986262 -247.290022)
		(end 331.802486 -247.239282)
		(width 0.09525)
		(layer "In13.Cu")
		(net "M_B_CPU0_SA_DQS_DN<9>")
	)
	(arc
		(start 331.23124 -247.244108)
		(mid 331.046208 -247.290022)
		(end 330.862432 -247.239282)
		(width 0.09525)
		(layer "In13.Cu")
		(net "M_B_CPU0_SA_DQS_DN<9>")
	)
	(arc
		(start 328.411332 -247.244108)
		(mid 328.2263 -247.290022)
		(end 328.042524 -247.239282)
		(width 0.09525)
		(layer "In13.Cu")
		(net "M_B_CPU0_SA_DQS_DN<9>")
	)
	(arc
		(start 327.479406 -247.239282)
		(mid 327.295377 -247.290181)
		(end 327.11009 -247.244108)
		(width 0.09525)
		(layer "In13.Cu")
		(net "M_B_CPU0_SA_DQS_DN<9>")
	)
	(arc
		(start 335.562448 -247.239282)
		(mid 335.281016 -247.163527)
		(end 334.999584 -247.239282)
		(width 0.09525)
		(layer "In13.Cu")
		(net "M_B_CPU0_SA_DQS_DN<9>")
	)
	(arc
		(start 334.059784 -247.239282)
		(mid 333.876009 -247.290054)
		(end 333.690976 -247.244108)
		(width 0.09525)
		(layer "In13.Cu")
		(net "M_B_CPU0_SA_DQS_DN<9>")
	)
	(arc
		(start 333.682594 -247.239282)
		(mid 333.401162 -247.163527)
		(end 333.11973 -247.239282)
		(width 0.09525)
		(layer "In13.Cu")
		(net "M_B_CPU0_SA_DQS_DN<9>")
	)
	(arc
		(start 336.502502 -247.239282)
		(mid 336.22107 -247.163527)
		(end 335.939638 -247.239282)
		(width 0.09525)
		(layer "In13.Cu")
		(net "M_B_CPU0_SA_DQS_DN<9>")
	)
	(arc
		(start 328.982578 -247.239282)
		(mid 328.701146 -247.163527)
		(end 328.419714 -247.239282)
		(width 0.09525)
		(layer "In13.Cu")
		(net "M_B_CPU0_SA_DQS_DN<9>")
	)
	(arc
		(start 329.359768 -247.239282)
		(mid 329.175993 -247.290054)
		(end 328.99096 -247.244108)
		(width 0.09525)
		(layer "In13.Cu")
		(net "M_B_CPU0_SA_DQS_DN<9>")
	)
	(arc
		(start 334.622648 -247.239282)
		(mid 334.341216 -247.163527)
		(end 334.059784 -247.239282)
		(width 0.09525)
		(layer "In13.Cu")
		(net "M_B_CPU0_SA_DQS_DN<9>")
	)
	(arc
		(start 335.931256 -247.244108)
		(mid 335.746224 -247.290022)
		(end 335.562448 -247.239282)
		(width 0.09525)
		(layer "In13.Cu")
		(net "M_B_CPU0_SA_DQS_DN<9>")
	)
	(arc
		(start 326.162162 -247.239282)
		(mid 326.026216 -247.182658)
		(end 325.880222 -247.163336)
		(width 0.09525)
		(layer "In13.Cu")
		(net "M_B_CPU0_SA_DQS_DN<9>")
	)
	(arc
		(start 333.11973 -247.239282)
		(mid 332.935955 -247.290054)
		(end 332.750922 -247.244108)
		(width 0.09525)
		(layer "In13.Cu")
		(net "M_B_CPU0_SA_DQS_DN<9>")
	)
	(arc
		(start 329.922632 -247.239282)
		(mid 329.6412 -247.163527)
		(end 329.359768 -247.239282)
		(width 0.09525)
		(layer "In13.Cu")
		(net "M_B_CPU0_SA_DQS_DN<9>")
	)
	(arc
		(start 332.74254 -247.239282)
		(mid 332.461108 -247.163527)
		(end 332.179676 -247.239282)
		(width 0.09525)
		(layer "In13.Cu")
		(net "M_B_CPU0_SA_DQS_DN<9>")
	)
	(segment
		(start 337.158076 -242.320064)
		(end 336.691224 -242.054126)
		(width 0.12954)
		(layer "F.Cu")
		(net "M_B_CPU0_SA_DQS_DN<8>")
	)
	(segment
		(start 335.939638 -242.379246)
		(end 335.931256 -242.384072)
		(width 0.09525)
		(layer "In13.Cu")
		(net "M_B_CPU0_SA_DQS_DN<8>")
	)
	(segment
		(start 299.089826 -230.05796)
		(end 298.720764 -229.688898)
		(width 0.16002)
		(layer "In13.Cu")
		(net "M_B_CPU0_SA_DQS_DN<8>")
	)
	(segment
		(start 325.880222 -242.3033)
		(end 325.688706 -242.3033)
		(width 0.09525)
		(layer "In13.Cu")
		(net "M_B_CPU0_SA_DQS_DN<8>")
	)
	(segment
		(start 297.9293 -229.915212)
		(end 296.004234 -229.915212)
		(width 0.16002)
		(layer "In13.Cu")
		(net "M_B_CPU0_SA_DQS_DN<8>")
	)
	(segment
		(start 324.150228 -241.305842)
		(end 323.920358 -241.305842)
		(width 0.09525)
		(layer "In13.Cu")
		(net "M_B_CPU0_SA_DQS_DN<8>")
	)
	(segment
		(start 298.720764 -229.688898)
		(end 298.155614 -229.688898)
		(width 0.16002)
		(layer "In13.Cu")
		(net "M_B_CPU0_SA_DQS_DN<8>")
	)
	(segment
		(start 331.239622 -242.379246)
		(end 331.23124 -242.384072)
		(width 0.09525)
		(layer "In13.Cu")
		(net "M_B_CPU0_SA_DQS_DN<8>")
	)
	(segment
		(start 324.693788 -241.975132)
		(end 324.366128 -241.647472)
		(width 0.09525)
		(layer "In13.Cu")
		(net "M_B_CPU0_SA_DQS_DN<8>")
	)
	(segment
		(start 325.360538 -241.975132)
		(end 324.693788 -241.975132)
		(width 0.09525)
		(layer "In13.Cu")
		(net "M_B_CPU0_SA_DQS_DN<8>")
	)
	(segment
		(start 305.647344 -230.908098)
		(end 305.312318 -230.573072)
		(width 0.16002)
		(layer "In13.Cu")
		(net "M_B_CPU0_SA_DQS_DN<8>")
	)
	(segment
		(start 328.419714 -242.379246)
		(end 328.411332 -242.384072)
		(width 0.09525)
		(layer "In13.Cu")
		(net "M_B_CPU0_SA_DQS_DN<8>")
	)
	(segment
		(start 326.56018 -242.367054)
		(end 326.539352 -242.379246)
		(width 0.09525)
		(layer "In13.Cu")
		(net "M_B_CPU0_SA_DQS_DN<8>")
	)
	(segment
		(start 325.688706 -242.3033)
		(end 325.360538 -241.975132)
		(width 0.09525)
		(layer "In13.Cu")
		(net "M_B_CPU0_SA_DQS_DN<8>")
	)
	(segment
		(start 332.750922 -242.384072)
		(end 332.74254 -242.379246)
		(width 0.09525)
		(layer "In13.Cu")
		(net "M_B_CPU0_SA_DQS_DN<8>")
	)
	(segment
		(start 301.522638 -230.05796)
		(end 299.089826 -230.05796)
		(width 0.16002)
		(layer "In13.Cu")
		(net "M_B_CPU0_SA_DQS_DN<8>")
	)
	(segment
		(start 298.155614 -229.688898)
		(end 297.9293 -229.915212)
		(width 0.16002)
		(layer "In13.Cu")
		(net "M_B_CPU0_SA_DQS_DN<8>")
	)
	(segment
		(start 304.337974 -230.573072)
		(end 304.033682 -230.877364)
		(width 0.16002)
		(layer "In13.Cu")
		(net "M_B_CPU0_SA_DQS_DN<8>")
	)
	(segment
		(start 324.366128 -241.647472)
		(end 324.366128 -241.521742)
		(width 0.09525)
		(layer "In13.Cu")
		(net "M_B_CPU0_SA_DQS_DN<8>")
	)
	(segment
		(start 333.690976 -242.384072)
		(end 333.682594 -242.379246)
		(width 0.09525)
		(layer "In13.Cu")
		(net "M_B_CPU0_SA_DQS_DN<8>")
	)
	(segment
		(start 305.312318 -230.573072)
		(end 304.337974 -230.573072)
		(width 0.16002)
		(layer "In13.Cu")
		(net "M_B_CPU0_SA_DQS_DN<8>")
	)
	(segment
		(start 323.837808 -241.246914)
		(end 318.272668 -241.246914)
		(width 0.16002)
		(layer "In13.Cu")
		(net "M_B_CPU0_SA_DQS_DN<8>")
	)
	(segment
		(start 332.179676 -242.379246)
		(end 332.171294 -242.384072)
		(width 0.09525)
		(layer "In13.Cu")
		(net "M_B_CPU0_SA_DQS_DN<8>")
	)
	(segment
		(start 304.033682 -230.877364)
		(end 302.342042 -230.877364)
		(width 0.16002)
		(layer "In13.Cu")
		(net "M_B_CPU0_SA_DQS_DN<8>")
	)
	(segment
		(start 326.539352 -242.379246)
		(end 326.524874 -242.387628)
		(width 0.09525)
		(layer "In13.Cu")
		(net "M_B_CPU0_SA_DQS_DN<8>")
	)
	(segment
		(start 296.004234 -229.915212)
		(end 295.724072 -229.63505)
		(width 0.16002)
		(layer "In13.Cu")
		(net "M_B_CPU0_SA_DQS_DN<8>")
	)
	(segment
		(start 302.342042 -230.877364)
		(end 301.522638 -230.05796)
		(width 0.16002)
		(layer "In13.Cu")
		(net "M_B_CPU0_SA_DQS_DN<8>")
	)
	(segment
		(start 323.86143 -241.246914)
		(end 323.837808 -241.246914)
		(width 0.09525)
		(layer "In13.Cu")
		(net "M_B_CPU0_SA_DQS_DN<8>")
	)
	(segment
		(start 328.99096 -242.384072)
		(end 328.982578 -242.379246)
		(width 0.09525)
		(layer "In13.Cu")
		(net "M_B_CPU0_SA_DQS_DN<8>")
	)
	(segment
		(start 318.272668 -241.246914)
		(end 307.933852 -230.908098)
		(width 0.16002)
		(layer "In13.Cu")
		(net "M_B_CPU0_SA_DQS_DN<8>")
	)
	(segment
		(start 307.933852 -230.908098)
		(end 305.647344 -230.908098)
		(width 0.16002)
		(layer "In13.Cu")
		(net "M_B_CPU0_SA_DQS_DN<8>")
	)
	(segment
		(start 327.47966 -242.379246)
		(end 327.467722 -242.386104)
		(width 0.09525)
		(layer "In13.Cu")
		(net "M_B_CPU0_SA_DQS_DN<8>")
	)
	(segment
		(start 336.845148 -242.319556)
		(end 336.82178 -242.406424)
		(width 0.09525)
		(layer "In13.Cu")
		(net "M_B_CPU0_SA_DQS_DN<8>")
	)
	(segment
		(start 336.691224 -242.054126)
		(end 336.845148 -242.319556)
		(width 0.09525)
		(layer "In13.Cu")
		(net "M_B_CPU0_SA_DQS_DN<8>")
	)
	(segment
		(start 324.366128 -241.521742)
		(end 324.150228 -241.305842)
		(width 0.09525)
		(layer "In13.Cu")
		(net "M_B_CPU0_SA_DQS_DN<8>")
	)
	(segment
		(start 323.920358 -241.305842)
		(end 323.86143 -241.246914)
		(width 0.09525)
		(layer "In13.Cu")
		(net "M_B_CPU0_SA_DQS_DN<8>")
	)
	(arc
		(start 326.162162 -242.379246)
		(mid 326.026216 -242.322622)
		(end 325.880222 -242.3033)
		(width 0.09525)
		(layer "In13.Cu")
		(net "M_B_CPU0_SA_DQS_DN<8>")
	)
	(arc
		(start 334.059784 -242.379246)
		(mid 333.876009 -242.430018)
		(end 333.690976 -242.384072)
		(width 0.09525)
		(layer "In13.Cu")
		(net "M_B_CPU0_SA_DQS_DN<8>")
	)
	(arc
		(start 331.23124 -242.384072)
		(mid 331.046208 -242.429986)
		(end 330.862432 -242.379246)
		(width 0.09525)
		(layer "In13.Cu")
		(net "M_B_CPU0_SA_DQS_DN<8>")
	)
	(arc
		(start 334.999584 -242.379246)
		(mid 334.811116 -242.429923)
		(end 334.622648 -242.379246)
		(width 0.09525)
		(layer "In13.Cu")
		(net "M_B_CPU0_SA_DQS_DN<8>")
	)
	(arc
		(start 326.524874 -242.387628)
		(mid 326.342442 -242.430068)
		(end 326.162162 -242.379246)
		(width 0.09525)
		(layer "In13.Cu")
		(net "M_B_CPU0_SA_DQS_DN<8>")
	)
	(arc
		(start 328.042524 -242.379246)
		(mid 327.761092 -242.303491)
		(end 327.47966 -242.379246)
		(width 0.09525)
		(layer "In13.Cu")
		(net "M_B_CPU0_SA_DQS_DN<8>")
	)
	(arc
		(start 332.171294 -242.384072)
		(mid 331.986262 -242.429986)
		(end 331.802486 -242.379246)
		(width 0.09525)
		(layer "In13.Cu")
		(net "M_B_CPU0_SA_DQS_DN<8>")
	)
	(arc
		(start 327.102216 -242.379246)
		(mid 326.832783 -242.303375)
		(end 326.56018 -242.367054)
		(width 0.09525)
		(layer "In13.Cu")
		(net "M_B_CPU0_SA_DQS_DN<8>")
	)
	(arc
		(start 336.502502 -242.379246)
		(mid 336.22107 -242.303491)
		(end 335.939638 -242.379246)
		(width 0.09525)
		(layer "In13.Cu")
		(net "M_B_CPU0_SA_DQS_DN<8>")
	)
	(arc
		(start 329.359768 -242.379246)
		(mid 329.175993 -242.430018)
		(end 328.99096 -242.384072)
		(width 0.09525)
		(layer "In13.Cu")
		(net "M_B_CPU0_SA_DQS_DN<8>")
	)
	(arc
		(start 330.299568 -242.379246)
		(mid 330.1111 -242.429923)
		(end 329.922632 -242.379246)
		(width 0.09525)
		(layer "In13.Cu")
		(net "M_B_CPU0_SA_DQS_DN<8>")
	)
	(arc
		(start 335.931256 -242.384072)
		(mid 335.746224 -242.429986)
		(end 335.562448 -242.379246)
		(width 0.09525)
		(layer "In13.Cu")
		(net "M_B_CPU0_SA_DQS_DN<8>")
	)
	(arc
		(start 335.562448 -242.379246)
		(mid 335.281016 -242.303491)
		(end 334.999584 -242.379246)
		(width 0.09525)
		(layer "In13.Cu")
		(net "M_B_CPU0_SA_DQS_DN<8>")
	)
	(arc
		(start 334.622648 -242.379246)
		(mid 334.341216 -242.303491)
		(end 334.059784 -242.379246)
		(width 0.09525)
		(layer "In13.Cu")
		(net "M_B_CPU0_SA_DQS_DN<8>")
	)
	(arc
		(start 332.74254 -242.379246)
		(mid 332.461108 -242.303491)
		(end 332.179676 -242.379246)
		(width 0.09525)
		(layer "In13.Cu")
		(net "M_B_CPU0_SA_DQS_DN<8>")
	)
	(arc
		(start 328.982578 -242.379246)
		(mid 328.701146 -242.303491)
		(end 328.419714 -242.379246)
		(width 0.09525)
		(layer "In13.Cu")
		(net "M_B_CPU0_SA_DQS_DN<8>")
	)
	(arc
		(start 330.862432 -242.379246)
		(mid 330.581 -242.303491)
		(end 330.299568 -242.379246)
		(width 0.09525)
		(layer "In13.Cu")
		(net "M_B_CPU0_SA_DQS_DN<8>")
	)
	(arc
		(start 336.82178 -242.406424)
		(mid 336.659098 -242.428556)
		(end 336.502502 -242.379246)
		(width 0.09525)
		(layer "In13.Cu")
		(net "M_B_CPU0_SA_DQS_DN<8>")
	)
	(arc
		(start 331.802486 -242.379246)
		(mid 331.521054 -242.303491)
		(end 331.239622 -242.379246)
		(width 0.09525)
		(layer "In13.Cu")
		(net "M_B_CPU0_SA_DQS_DN<8>")
	)
	(arc
		(start 333.11973 -242.379246)
		(mid 332.935955 -242.430018)
		(end 332.750922 -242.384072)
		(width 0.09525)
		(layer "In13.Cu")
		(net "M_B_CPU0_SA_DQS_DN<8>")
	)
	(arc
		(start 333.682594 -242.379246)
		(mid 333.401162 -242.303491)
		(end 333.11973 -242.379246)
		(width 0.09525)
		(layer "In13.Cu")
		(net "M_B_CPU0_SA_DQS_DN<8>")
	)
	(arc
		(start 328.411332 -242.384072)
		(mid 328.2263 -242.429986)
		(end 328.042524 -242.379246)
		(width 0.09525)
		(layer "In13.Cu")
		(net "M_B_CPU0_SA_DQS_DN<8>")
	)
	(arc
		(start 327.467722 -242.386104)
		(mid 327.284087 -242.430054)
		(end 327.102216 -242.379246)
		(width 0.09525)
		(layer "In13.Cu")
		(net "M_B_CPU0_SA_DQS_DN<8>")
	)
	(arc
		(start 329.922632 -242.379246)
		(mid 329.6412 -242.303491)
		(end 329.359768 -242.379246)
		(width 0.09525)
		(layer "In13.Cu")
		(net "M_B_CPU0_SA_DQS_DN<8>")
	)
	(segment
		(start 337.158076 -237.460028)
		(end 336.691224 -237.19409)
		(width 0.12954)
		(layer "F.Cu")
		(net "M_B_CPU0_SA_DQS_DN<7>")
	)
	(segment
		(start 323.895974 -235.628942)
		(end 321.742308 -235.628942)
		(width 0.16002)
		(layer "In13.Cu")
		(net "M_B_CPU0_SA_DQS_DN<7>")
	)
	(segment
		(start 298.720764 -220.338904)
		(end 296.958258 -220.338904)
		(width 0.16002)
		(layer "In13.Cu")
		(net "M_B_CPU0_SA_DQS_DN<7>")
	)
	(segment
		(start 328.419714 -237.51921)
		(end 328.411332 -237.524036)
		(width 0.09525)
		(layer "In13.Cu")
		(net "M_B_CPU0_SA_DQS_DN<7>")
	)
	(segment
		(start 302.321214 -221.52737)
		(end 301.50181 -220.707966)
		(width 0.16002)
		(layer "In13.Cu")
		(net "M_B_CPU0_SA_DQS_DN<7>")
	)
	(segment
		(start 323.919596 -235.628942)
		(end 323.895974 -235.628942)
		(width 0.09525)
		(layer "In13.Cu")
		(net "M_B_CPU0_SA_DQS_DN<7>")
	)
	(segment
		(start 323.978524 -235.68787)
		(end 323.919596 -235.628942)
		(width 0.09525)
		(layer "In13.Cu")
		(net "M_B_CPU0_SA_DQS_DN<7>")
	)
	(segment
		(start 331.239622 -237.51921)
		(end 331.23124 -237.524036)
		(width 0.09525)
		(layer "In13.Cu")
		(net "M_B_CPU0_SA_DQS_DN<7>")
	)
	(segment
		(start 305.612038 -221.55785)
		(end 305.277266 -221.223078)
		(width 0.16002)
		(layer "In13.Cu")
		(net "M_B_CPU0_SA_DQS_DN<7>")
	)
	(segment
		(start 327.50887 -237.503208)
		(end 327.481438 -237.51921)
		(width 0.09525)
		(layer "In13.Cu")
		(net "M_B_CPU0_SA_DQS_DN<7>")
	)
	(segment
		(start 301.50181 -220.707966)
		(end 299.089826 -220.707966)
		(width 0.16002)
		(layer "In13.Cu")
		(net "M_B_CPU0_SA_DQS_DN<7>")
	)
	(segment
		(start 326.186546 -237.57128)
		(end 325.332598 -236.717332)
		(width 0.09525)
		(layer "In13.Cu")
		(net "M_B_CPU0_SA_DQS_DN<7>")
	)
	(segment
		(start 296.958258 -220.338904)
		(end 296.73169 -220.565472)
		(width 0.16002)
		(layer "In13.Cu")
		(net "M_B_CPU0_SA_DQS_DN<7>")
	)
	(segment
		(start 336.845148 -237.45952)
		(end 336.82178 -237.546388)
		(width 0.09525)
		(layer "In13.Cu")
		(net "M_B_CPU0_SA_DQS_DN<7>")
	)
	(segment
		(start 308.708298 -222.23857)
		(end 308.027578 -221.55785)
		(width 0.16002)
		(layer "In13.Cu")
		(net "M_B_CPU0_SA_DQS_DN<7>")
	)
	(segment
		(start 326.351138 -237.57128)
		(end 326.186546 -237.57128)
		(width 0.09525)
		(layer "In13.Cu")
		(net "M_B_CPU0_SA_DQS_DN<7>")
	)
	(segment
		(start 296.004488 -220.565472)
		(end 295.724072 -220.285056)
		(width 0.16002)
		(layer "In13.Cu")
		(net "M_B_CPU0_SA_DQS_DN<7>")
	)
	(segment
		(start 296.73169 -220.565472)
		(end 296.004488 -220.565472)
		(width 0.16002)
		(layer "In13.Cu")
		(net "M_B_CPU0_SA_DQS_DN<7>")
	)
	(segment
		(start 308.027578 -221.55785)
		(end 305.612038 -221.55785)
		(width 0.16002)
		(layer "In13.Cu")
		(net "M_B_CPU0_SA_DQS_DN<7>")
	)
	(segment
		(start 305.277266 -221.223078)
		(end 304.337974 -221.223078)
		(width 0.16002)
		(layer "In13.Cu")
		(net "M_B_CPU0_SA_DQS_DN<7>")
	)
	(segment
		(start 336.691224 -237.19409)
		(end 336.845148 -237.45952)
		(width 0.09525)
		(layer "In13.Cu")
		(net "M_B_CPU0_SA_DQS_DN<7>")
	)
	(segment
		(start 304.337974 -221.223078)
		(end 304.033682 -221.52737)
		(width 0.16002)
		(layer "In13.Cu")
		(net "M_B_CPU0_SA_DQS_DN<7>")
	)
	(segment
		(start 328.99096 -237.524036)
		(end 328.982578 -237.51921)
		(width 0.09525)
		(layer "In13.Cu")
		(net "M_B_CPU0_SA_DQS_DN<7>")
	)
	(segment
		(start 332.750922 -237.524036)
		(end 332.74254 -237.51921)
		(width 0.09525)
		(layer "In13.Cu")
		(net "M_B_CPU0_SA_DQS_DN<7>")
	)
	(segment
		(start 321.742308 -235.628942)
		(end 308.708298 -222.594932)
		(width 0.16002)
		(layer "In13.Cu")
		(net "M_B_CPU0_SA_DQS_DN<7>")
	)
	(segment
		(start 327.105518 -237.51921)
		(end 327.081642 -237.50524)
		(width 0.09525)
		(layer "In13.Cu")
		(net "M_B_CPU0_SA_DQS_DN<7>")
	)
	(segment
		(start 327.481438 -237.51921)
		(end 327.464674 -237.528862)
		(width 0.09525)
		(layer "In13.Cu")
		(net "M_B_CPU0_SA_DQS_DN<7>")
	)
	(segment
		(start 324.550278 -236.048042)
		(end 324.190106 -235.68787)
		(width 0.09525)
		(layer "In13.Cu")
		(net "M_B_CPU0_SA_DQS_DN<7>")
	)
	(segment
		(start 308.708298 -222.594932)
		(end 308.708298 -222.23857)
		(width 0.16002)
		(layer "In13.Cu")
		(net "M_B_CPU0_SA_DQS_DN<7>")
	)
	(segment
		(start 324.955154 -236.048042)
		(end 324.550278 -236.048042)
		(width 0.09525)
		(layer "In13.Cu")
		(net "M_B_CPU0_SA_DQS_DN<7>")
	)
	(segment
		(start 332.179676 -237.51921)
		(end 332.171294 -237.524036)
		(width 0.09525)
		(layer "In13.Cu")
		(net "M_B_CPU0_SA_DQS_DN<7>")
	)
	(segment
		(start 299.089826 -220.707966)
		(end 298.720764 -220.338904)
		(width 0.16002)
		(layer "In13.Cu")
		(net "M_B_CPU0_SA_DQS_DN<7>")
	)
	(segment
		(start 325.332598 -236.717332)
		(end 325.332598 -236.425486)
		(width 0.09525)
		(layer "In13.Cu")
		(net "M_B_CPU0_SA_DQS_DN<7>")
	)
	(segment
		(start 324.190106 -235.68787)
		(end 323.978524 -235.68787)
		(width 0.09525)
		(layer "In13.Cu")
		(net "M_B_CPU0_SA_DQS_DN<7>")
	)
	(segment
		(start 304.033682 -221.52737)
		(end 302.321214 -221.52737)
		(width 0.16002)
		(layer "In13.Cu")
		(net "M_B_CPU0_SA_DQS_DN<7>")
	)
	(segment
		(start 335.939638 -237.51921)
		(end 335.931256 -237.524036)
		(width 0.09525)
		(layer "In13.Cu")
		(net "M_B_CPU0_SA_DQS_DN<7>")
	)
	(segment
		(start 333.690976 -237.524036)
		(end 333.682594 -237.51921)
		(width 0.09525)
		(layer "In13.Cu")
		(net "M_B_CPU0_SA_DQS_DN<7>")
	)
	(segment
		(start 325.332598 -236.425486)
		(end 324.955154 -236.048042)
		(width 0.09525)
		(layer "In13.Cu")
		(net "M_B_CPU0_SA_DQS_DN<7>")
	)
	(arc
		(start 327.464674 -237.528862)
		(mid 327.283871 -237.569729)
		(end 327.105518 -237.51921)
		(width 0.09525)
		(layer "In13.Cu")
		(net "M_B_CPU0_SA_DQS_DN<7>")
	)
	(arc
		(start 336.502502 -237.51921)
		(mid 336.22107 -237.443455)
		(end 335.939638 -237.51921)
		(width 0.09525)
		(layer "In13.Cu")
		(net "M_B_CPU0_SA_DQS_DN<7>")
	)
	(arc
		(start 331.802486 -237.51921)
		(mid 331.521054 -237.443455)
		(end 331.239622 -237.51921)
		(width 0.09525)
		(layer "In13.Cu")
		(net "M_B_CPU0_SA_DQS_DN<7>")
	)
	(arc
		(start 335.931256 -237.524036)
		(mid 335.746224 -237.56995)
		(end 335.562448 -237.51921)
		(width 0.09525)
		(layer "In13.Cu")
		(net "M_B_CPU0_SA_DQS_DN<7>")
	)
	(arc
		(start 326.540876 -237.519464)
		(mid 326.449447 -237.557971)
		(end 326.351138 -237.57128)
		(width 0.09525)
		(layer "In13.Cu")
		(net "M_B_CPU0_SA_DQS_DN<7>")
	)
	(arc
		(start 329.922632 -237.51921)
		(mid 329.6412 -237.443455)
		(end 329.359768 -237.51921)
		(width 0.09525)
		(layer "In13.Cu")
		(net "M_B_CPU0_SA_DQS_DN<7>")
	)
	(arc
		(start 334.622648 -237.51921)
		(mid 334.341216 -237.443455)
		(end 334.059784 -237.51921)
		(width 0.09525)
		(layer "In13.Cu")
		(net "M_B_CPU0_SA_DQS_DN<7>")
	)
	(arc
		(start 330.299568 -237.51921)
		(mid 330.1111 -237.569887)
		(end 329.922632 -237.51921)
		(width 0.09525)
		(layer "In13.Cu")
		(net "M_B_CPU0_SA_DQS_DN<7>")
	)
	(arc
		(start 328.982578 -237.51921)
		(mid 328.701146 -237.443455)
		(end 328.419714 -237.51921)
		(width 0.09525)
		(layer "In13.Cu")
		(net "M_B_CPU0_SA_DQS_DN<7>")
	)
	(arc
		(start 328.411332 -237.524036)
		(mid 328.2263 -237.56995)
		(end 328.042524 -237.51921)
		(width 0.09525)
		(layer "In13.Cu")
		(net "M_B_CPU0_SA_DQS_DN<7>")
	)
	(arc
		(start 330.862432 -237.51921)
		(mid 330.581 -237.443455)
		(end 330.299568 -237.51921)
		(width 0.09525)
		(layer "In13.Cu")
		(net "M_B_CPU0_SA_DQS_DN<7>")
	)
	(arc
		(start 334.999584 -237.51921)
		(mid 334.811116 -237.569887)
		(end 334.622648 -237.51921)
		(width 0.09525)
		(layer "In13.Cu")
		(net "M_B_CPU0_SA_DQS_DN<7>")
	)
	(arc
		(start 327.081642 -237.50524)
		(mid 326.809418 -237.442868)
		(end 326.540876 -237.519464)
		(width 0.09525)
		(layer "In13.Cu")
		(net "M_B_CPU0_SA_DQS_DN<7>")
	)
	(arc
		(start 336.82178 -237.546388)
		(mid 336.659098 -237.56852)
		(end 336.502502 -237.51921)
		(width 0.09525)
		(layer "In13.Cu")
		(net "M_B_CPU0_SA_DQS_DN<7>")
	)
	(arc
		(start 331.23124 -237.524036)
		(mid 331.046208 -237.56995)
		(end 330.862432 -237.51921)
		(width 0.09525)
		(layer "In13.Cu")
		(net "M_B_CPU0_SA_DQS_DN<7>")
	)
	(arc
		(start 334.059784 -237.51921)
		(mid 333.876009 -237.569982)
		(end 333.690976 -237.524036)
		(width 0.09525)
		(layer "In13.Cu")
		(net "M_B_CPU0_SA_DQS_DN<7>")
	)
	(arc
		(start 333.11973 -237.51921)
		(mid 332.935955 -237.569982)
		(end 332.750922 -237.524036)
		(width 0.09525)
		(layer "In13.Cu")
		(net "M_B_CPU0_SA_DQS_DN<7>")
	)
	(arc
		(start 329.359768 -237.51921)
		(mid 329.175993 -237.569982)
		(end 328.99096 -237.524036)
		(width 0.09525)
		(layer "In13.Cu")
		(net "M_B_CPU0_SA_DQS_DN<7>")
	)
	(arc
		(start 333.682594 -237.51921)
		(mid 333.401162 -237.443455)
		(end 333.11973 -237.51921)
		(width 0.09525)
		(layer "In13.Cu")
		(net "M_B_CPU0_SA_DQS_DN<7>")
	)
	(arc
		(start 332.171294 -237.524036)
		(mid 331.986262 -237.56995)
		(end 331.802486 -237.51921)
		(width 0.09525)
		(layer "In13.Cu")
		(net "M_B_CPU0_SA_DQS_DN<7>")
	)
	(arc
		(start 328.042524 -237.51921)
		(mid 327.777715 -237.443581)
		(end 327.50887 -237.503208)
		(width 0.09525)
		(layer "In13.Cu")
		(net "M_B_CPU0_SA_DQS_DN<7>")
	)
	(arc
		(start 335.562448 -237.51921)
		(mid 335.281016 -237.443455)
		(end 334.999584 -237.51921)
		(width 0.09525)
		(layer "In13.Cu")
		(net "M_B_CPU0_SA_DQS_DN<7>")
	)
	(arc
		(start 332.74254 -237.51921)
		(mid 332.461108 -237.443455)
		(end 332.179676 -237.51921)
		(width 0.09525)
		(layer "In13.Cu")
		(net "M_B_CPU0_SA_DQS_DN<7>")
	)
	(segment
		(start 337.158076 -232.599992)
		(end 336.691224 -232.334054)
		(width 0.12954)
		(layer "F.Cu")
		(net "M_B_CPU0_SA_DQS_DN<6>")
	)
	(segment
		(start 320.879978 -226.712272)
		(end 324.298056 -230.13035)
		(width 0.16002)
		(layer "In13.Cu")
		(net "M_B_CPU0_SA_DQS_DN<6>")
	)
	(segment
		(start 325.439278 -230.588312)
		(end 327.434448 -232.583482)
		(width 0.09525)
		(layer "In13.Cu")
		(net "M_B_CPU0_SA_DQS_DN<6>")
	)
	(segment
		(start 332.74254 -232.659174)
		(end 332.750922 -232.664)
		(width 0.09525)
		(layer "In13.Cu")
		(net "M_B_CPU0_SA_DQS_DN<6>")
	)
	(segment
		(start 296.005504 -211.216494)
		(end 296.555668 -211.216494)
		(width 0.16002)
		(layer "In13.Cu")
		(net "M_B_CPU0_SA_DQS_DN<6>")
	)
	(segment
		(start 336.82178 -232.686352)
		(end 336.845148 -232.599484)
		(width 0.09525)
		(layer "In13.Cu")
		(net "M_B_CPU0_SA_DQS_DN<6>")
	)
	(segment
		(start 295.724072 -210.935062)
		(end 296.005504 -211.216494)
		(width 0.16002)
		(layer "In13.Cu")
		(net "M_B_CPU0_SA_DQS_DN<6>")
	)
	(segment
		(start 305.652424 -212.207856)
		(end 307.902864 -212.207856)
		(width 0.16002)
		(layer "In13.Cu")
		(net "M_B_CPU0_SA_DQS_DN<6>")
	)
	(segment
		(start 324.672706 -230.588312)
		(end 325.439278 -230.588312)
		(width 0.09525)
		(layer "In13.Cu")
		(net "M_B_CPU0_SA_DQS_DN<6>")
	)
	(segment
		(start 324.31482 -230.230426)
		(end 324.672706 -230.588312)
		(width 0.09525)
		(layer "In13.Cu")
		(net "M_B_CPU0_SA_DQS_DN<6>")
	)
	(segment
		(start 301.51832 -211.357972)
		(end 302.048672 -211.888324)
		(width 0.16002)
		(layer "In13.Cu")
		(net "M_B_CPU0_SA_DQS_DN<6>")
	)
	(segment
		(start 332.171294 -232.664)
		(end 332.179676 -232.659174)
		(width 0.09525)
		(layer "In13.Cu")
		(net "M_B_CPU0_SA_DQS_DN<6>")
	)
	(segment
		(start 296.768012 -211.00415)
		(end 298.714414 -211.00415)
		(width 0.16002)
		(layer "In13.Cu")
		(net "M_B_CPU0_SA_DQS_DN<6>")
	)
	(segment
		(start 328.411332 -232.664)
		(end 328.419714 -232.659174)
		(width 0.09525)
		(layer "In13.Cu")
		(net "M_B_CPU0_SA_DQS_DN<6>")
	)
	(segment
		(start 296.555668 -211.216494)
		(end 296.768012 -211.00415)
		(width 0.16002)
		(layer "In13.Cu")
		(net "M_B_CPU0_SA_DQS_DN<6>")
	)
	(segment
		(start 331.23124 -232.664)
		(end 331.239622 -232.659174)
		(width 0.09525)
		(layer "In13.Cu")
		(net "M_B_CPU0_SA_DQS_DN<6>")
	)
	(segment
		(start 320.879978 -225.18497)
		(end 320.879978 -226.712272)
		(width 0.16002)
		(layer "In13.Cu")
		(net "M_B_CPU0_SA_DQS_DN<6>")
	)
	(segment
		(start 336.845148 -232.599484)
		(end 336.691224 -232.334054)
		(width 0.09525)
		(layer "In13.Cu")
		(net "M_B_CPU0_SA_DQS_DN<6>")
	)
	(segment
		(start 328.982578 -232.659174)
		(end 328.99096 -232.664)
		(width 0.09525)
		(layer "In13.Cu")
		(net "M_B_CPU0_SA_DQS_DN<6>")
	)
	(segment
		(start 305.332892 -211.888324)
		(end 305.652424 -212.207856)
		(width 0.16002)
		(layer "In13.Cu")
		(net "M_B_CPU0_SA_DQS_DN<6>")
	)
	(segment
		(start 324.298056 -230.13035)
		(end 324.31482 -230.147114)
		(width 0.09525)
		(layer "In13.Cu")
		(net "M_B_CPU0_SA_DQS_DN<6>")
	)
	(segment
		(start 302.048672 -211.888324)
		(end 305.332892 -211.888324)
		(width 0.16002)
		(layer "In13.Cu")
		(net "M_B_CPU0_SA_DQS_DN<6>")
	)
	(segment
		(start 324.31482 -230.147114)
		(end 324.31482 -230.230426)
		(width 0.09525)
		(layer "In13.Cu")
		(net "M_B_CPU0_SA_DQS_DN<6>")
	)
	(segment
		(start 333.682594 -232.659174)
		(end 333.690976 -232.664)
		(width 0.09525)
		(layer "In13.Cu")
		(net "M_B_CPU0_SA_DQS_DN<6>")
	)
	(segment
		(start 299.068236 -211.357972)
		(end 301.51832 -211.357972)
		(width 0.16002)
		(layer "In13.Cu")
		(net "M_B_CPU0_SA_DQS_DN<6>")
	)
	(segment
		(start 327.434448 -232.583482)
		(end 327.761092 -232.583482)
		(width 0.09525)
		(layer "In13.Cu")
		(net "M_B_CPU0_SA_DQS_DN<6>")
	)
	(segment
		(start 307.902864 -212.207856)
		(end 320.879978 -225.18497)
		(width 0.16002)
		(layer "In13.Cu")
		(net "M_B_CPU0_SA_DQS_DN<6>")
	)
	(segment
		(start 298.714414 -211.00415)
		(end 299.068236 -211.357972)
		(width 0.16002)
		(layer "In13.Cu")
		(net "M_B_CPU0_SA_DQS_DN<6>")
	)
	(segment
		(start 335.931256 -232.664)
		(end 335.939638 -232.659174)
		(width 0.09525)
		(layer "In13.Cu")
		(net "M_B_CPU0_SA_DQS_DN<6>")
	)
	(arc
		(start 332.750922 -232.664)
		(mid 332.935954 -232.709914)
		(end 333.11973 -232.659174)
		(width 0.09525)
		(layer "In13.Cu")
		(net "M_B_CPU0_SA_DQS_DN<6>")
	)
	(arc
		(start 331.239622 -232.659174)
		(mid 331.521054 -232.583419)
		(end 331.802486 -232.659174)
		(width 0.09525)
		(layer "In13.Cu")
		(net "M_B_CPU0_SA_DQS_DN<6>")
	)
	(arc
		(start 327.761092 -232.583482)
		(mid 327.9068 -232.60275)
		(end 328.042524 -232.659174)
		(width 0.09525)
		(layer "In13.Cu")
		(net "M_B_CPU0_SA_DQS_DN<6>")
	)
	(arc
		(start 330.862432 -232.659174)
		(mid 331.046207 -232.709946)
		(end 331.23124 -232.664)
		(width 0.09525)
		(layer "In13.Cu")
		(net "M_B_CPU0_SA_DQS_DN<6>")
	)
	(arc
		(start 332.179676 -232.659174)
		(mid 332.461108 -232.583419)
		(end 332.74254 -232.659174)
		(width 0.09525)
		(layer "In13.Cu")
		(net "M_B_CPU0_SA_DQS_DN<6>")
	)
	(arc
		(start 328.419714 -232.659174)
		(mid 328.701146 -232.583419)
		(end 328.982578 -232.659174)
		(width 0.09525)
		(layer "In13.Cu")
		(net "M_B_CPU0_SA_DQS_DN<6>")
	)
	(arc
		(start 334.059784 -232.659174)
		(mid 334.341216 -232.583419)
		(end 334.622648 -232.659174)
		(width 0.09525)
		(layer "In13.Cu")
		(net "M_B_CPU0_SA_DQS_DN<6>")
	)
	(arc
		(start 329.359768 -232.659174)
		(mid 329.6412 -232.583419)
		(end 329.922632 -232.659174)
		(width 0.09525)
		(layer "In13.Cu")
		(net "M_B_CPU0_SA_DQS_DN<6>")
	)
	(arc
		(start 334.622648 -232.659174)
		(mid 334.811116 -232.709851)
		(end 334.999584 -232.659174)
		(width 0.09525)
		(layer "In13.Cu")
		(net "M_B_CPU0_SA_DQS_DN<6>")
	)
	(arc
		(start 333.690976 -232.664)
		(mid 333.876008 -232.709914)
		(end 334.059784 -232.659174)
		(width 0.09525)
		(layer "In13.Cu")
		(net "M_B_CPU0_SA_DQS_DN<6>")
	)
	(arc
		(start 334.999584 -232.659174)
		(mid 335.281016 -232.583419)
		(end 335.562448 -232.659174)
		(width 0.09525)
		(layer "In13.Cu")
		(net "M_B_CPU0_SA_DQS_DN<6>")
	)
	(arc
		(start 335.939638 -232.659174)
		(mid 336.22107 -232.583419)
		(end 336.502502 -232.659174)
		(width 0.09525)
		(layer "In13.Cu")
		(net "M_B_CPU0_SA_DQS_DN<6>")
	)
	(arc
		(start 336.502502 -232.659174)
		(mid 336.6591 -232.708463)
		(end 336.82178 -232.686352)
		(width 0.09525)
		(layer "In13.Cu")
		(net "M_B_CPU0_SA_DQS_DN<6>")
	)
	(arc
		(start 330.299568 -232.659174)
		(mid 330.581 -232.583419)
		(end 330.862432 -232.659174)
		(width 0.09525)
		(layer "In13.Cu")
		(net "M_B_CPU0_SA_DQS_DN<6>")
	)
	(arc
		(start 335.562448 -232.659174)
		(mid 335.746223 -232.709946)
		(end 335.931256 -232.664)
		(width 0.09525)
		(layer "In13.Cu")
		(net "M_B_CPU0_SA_DQS_DN<6>")
	)
	(arc
		(start 329.922632 -232.659174)
		(mid 330.1111 -232.709851)
		(end 330.299568 -232.659174)
		(width 0.09525)
		(layer "In13.Cu")
		(net "M_B_CPU0_SA_DQS_DN<6>")
	)
	(arc
		(start 333.11973 -232.659174)
		(mid 333.401162 -232.583419)
		(end 333.682594 -232.659174)
		(width 0.09525)
		(layer "In13.Cu")
		(net "M_B_CPU0_SA_DQS_DN<6>")
	)
	(arc
		(start 328.99096 -232.664)
		(mid 329.175992 -232.709914)
		(end 329.359768 -232.659174)
		(width 0.09525)
		(layer "In13.Cu")
		(net "M_B_CPU0_SA_DQS_DN<6>")
	)
	(arc
		(start 328.042524 -232.659174)
		(mid 328.226299 -232.709946)
		(end 328.411332 -232.664)
		(width 0.09525)
		(layer "In13.Cu")
		(net "M_B_CPU0_SA_DQS_DN<6>")
	)
	(arc
		(start 331.802486 -232.659174)
		(mid 331.986261 -232.709946)
		(end 332.171294 -232.664)
		(width 0.09525)
		(layer "In13.Cu")
		(net "M_B_CPU0_SA_DQS_DN<6>")
	)
	(segment
		(start 337.158076 -227.74021)
		(end 336.691224 -227.474272)
		(width 0.12954)
		(layer "F.Cu")
		(net "M_B_CPU0_SA_DQS_DN<5>")
	)
	(segment
		(start 301.921926 -202.43292)
		(end 301.496984 -202.007978)
		(width 0.16002)
		(layer "In13.Cu")
		(net "M_B_CPU0_SA_DQS_DN<5>")
	)
	(segment
		(start 301.496984 -202.007978)
		(end 299.078904 -202.007978)
		(width 0.16002)
		(layer "In13.Cu")
		(net "M_B_CPU0_SA_DQS_DN<5>")
	)
	(segment
		(start 326.33539 -221.850458)
		(end 326.33539 -221.767146)
		(width 0.09525)
		(layer "In13.Cu")
		(net "M_B_CPU0_SA_DQS_DN<5>")
	)
	(segment
		(start 297.07459 -201.655172)
		(end 296.860468 -201.869294)
		(width 0.16002)
		(layer "In13.Cu")
		(net "M_B_CPU0_SA_DQS_DN<5>")
	)
	(segment
		(start 331.239622 -227.799392)
		(end 331.23124 -227.804218)
		(width 0.09525)
		(layer "In13.Cu")
		(net "M_B_CPU0_SA_DQS_DN<5>")
	)
	(segment
		(start 336.691224 -227.474272)
		(end 336.845148 -227.739702)
		(width 0.09525)
		(layer "In13.Cu")
		(net "M_B_CPU0_SA_DQS_DN<5>")
	)
	(segment
		(start 296.008298 -201.869294)
		(end 295.724072 -201.585068)
		(width 0.16002)
		(layer "In13.Cu")
		(net "M_B_CPU0_SA_DQS_DN<5>")
	)
	(segment
		(start 327.102724 -222.939356)
		(end 327.072498 -222.92183)
		(width 0.09525)
		(layer "In13.Cu")
		(net "M_B_CPU0_SA_DQS_DN<5>")
	)
	(segment
		(start 305.26101 -202.385422)
		(end 304.202338 -201.947018)
		(width 0.16002)
		(layer "In13.Cu")
		(net "M_B_CPU0_SA_DQS_DN<5>")
	)
	(segment
		(start 333.690976 -227.804218)
		(end 333.682594 -227.799392)
		(width 0.09525)
		(layer "In13.Cu")
		(net "M_B_CPU0_SA_DQS_DN<5>")
	)
	(segment
		(start 326.107298 -220.924882)
		(end 308.040278 -202.857862)
		(width 0.16002)
		(layer "In13.Cu")
		(net "M_B_CPU0_SA_DQS_DN<5>")
	)
	(segment
		(start 327.142094 -222.962216)
		(end 327.102724 -222.939356)
		(width 0.09525)
		(layer "In13.Cu")
		(net "M_B_CPU0_SA_DQS_DN<5>")
	)
	(segment
		(start 332.179676 -227.799392)
		(end 332.171294 -227.804218)
		(width 0.09525)
		(layer "In13.Cu")
		(net "M_B_CPU0_SA_DQS_DN<5>")
	)
	(segment
		(start 329.020678 -226.201478)
		(end 328.982578 -226.17938)
		(width 0.09525)
		(layer "In13.Cu")
		(net "M_B_CPU0_SA_DQS_DN<5>")
	)
	(segment
		(start 329.452478 -226.989386)
		(end 329.420982 -226.971098)
		(width 0.09525)
		(layer "In13.Cu")
		(net "M_B_CPU0_SA_DQS_DN<5>")
	)
	(segment
		(start 304.202338 -201.947018)
		(end 302.968914 -201.947018)
		(width 0.16002)
		(layer "In13.Cu")
		(net "M_B_CPU0_SA_DQS_DN<5>")
	)
	(segment
		(start 299.078904 -202.007978)
		(end 298.726098 -201.655172)
		(width 0.16002)
		(layer "In13.Cu")
		(net "M_B_CPU0_SA_DQS_DN<5>")
	)
	(segment
		(start 298.726098 -201.655172)
		(end 297.07459 -201.655172)
		(width 0.16002)
		(layer "In13.Cu")
		(net "M_B_CPU0_SA_DQS_DN<5>")
	)
	(segment
		(start 328.982578 -226.17938)
		(end 328.950066 -226.160584)
		(width 0.09525)
		(layer "In13.Cu")
		(net "M_B_CPU0_SA_DQS_DN<5>")
	)
	(segment
		(start 302.968914 -201.947018)
		(end 302.483012 -202.43292)
		(width 0.16002)
		(layer "In13.Cu")
		(net "M_B_CPU0_SA_DQS_DN<5>")
	)
	(segment
		(start 335.939638 -227.799392)
		(end 335.931256 -227.804218)
		(width 0.09525)
		(layer "In13.Cu")
		(net "M_B_CPU0_SA_DQS_DN<5>")
	)
	(segment
		(start 328.042524 -224.559368)
		(end 328.013314 -224.542604)
		(width 0.09525)
		(layer "In13.Cu")
		(net "M_B_CPU0_SA_DQS_DN<5>")
	)
	(segment
		(start 329.922632 -227.799392)
		(end 329.89012 -227.780596)
		(width 0.09525)
		(layer "In13.Cu")
		(net "M_B_CPU0_SA_DQS_DN<5>")
	)
	(segment
		(start 328.512678 -225.369374)
		(end 328.480166 -225.350578)
		(width 0.09525)
		(layer "In13.Cu")
		(net "M_B_CPU0_SA_DQS_DN<5>")
	)
	(segment
		(start 326.107298 -221.539054)
		(end 326.107298 -220.924882)
		(width 0.16002)
		(layer "In13.Cu")
		(net "M_B_CPU0_SA_DQS_DN<5>")
	)
	(segment
		(start 326.670924 -222.151448)
		(end 326.632824 -222.12935)
		(width 0.09525)
		(layer "In13.Cu")
		(net "M_B_CPU0_SA_DQS_DN<5>")
	)
	(segment
		(start 326.318626 -221.750382)
		(end 326.107298 -221.539054)
		(width 0.16002)
		(layer "In13.Cu")
		(net "M_B_CPU0_SA_DQS_DN<5>")
	)
	(segment
		(start 328.080624 -224.581466)
		(end 328.042524 -224.559368)
		(width 0.09525)
		(layer "In13.Cu")
		(net "M_B_CPU0_SA_DQS_DN<5>")
	)
	(segment
		(start 302.483012 -202.43292)
		(end 301.921926 -202.43292)
		(width 0.16002)
		(layer "In13.Cu")
		(net "M_B_CPU0_SA_DQS_DN<5>")
	)
	(segment
		(start 332.750922 -227.804218)
		(end 332.74254 -227.799392)
		(width 0.09525)
		(layer "In13.Cu")
		(net "M_B_CPU0_SA_DQS_DN<5>")
	)
	(segment
		(start 327.573132 -223.749362)
		(end 327.538334 -223.729296)
		(width 0.09525)
		(layer "In13.Cu")
		(net "M_B_CPU0_SA_DQS_DN<5>")
	)
	(segment
		(start 336.845148 -227.739702)
		(end 336.82178 -227.82657)
		(width 0.09525)
		(layer "In13.Cu")
		(net "M_B_CPU0_SA_DQS_DN<5>")
	)
	(segment
		(start 308.040278 -202.857862)
		(end 305.73345 -202.857862)
		(width 0.16002)
		(layer "In13.Cu")
		(net "M_B_CPU0_SA_DQS_DN<5>")
	)
	(segment
		(start 328.54773 -225.389948)
		(end 328.512678 -225.369374)
		(width 0.09525)
		(layer "In13.Cu")
		(net "M_B_CPU0_SA_DQS_DN<5>")
	)
	(segment
		(start 326.33539 -221.767146)
		(end 326.318626 -221.750382)
		(width 0.09525)
		(layer "In13.Cu")
		(net "M_B_CPU0_SA_DQS_DN<5>")
	)
	(segment
		(start 305.73345 -202.857862)
		(end 305.26101 -202.385422)
		(width 0.16002)
		(layer "In13.Cu")
		(net "M_B_CPU0_SA_DQS_DN<5>")
	)
	(segment
		(start 327.608184 -223.769936)
		(end 327.573132 -223.749362)
		(width 0.09525)
		(layer "In13.Cu")
		(net "M_B_CPU0_SA_DQS_DN<5>")
	)
	(segment
		(start 329.490578 -227.011484)
		(end 329.452478 -226.989386)
		(width 0.09525)
		(layer "In13.Cu")
		(net "M_B_CPU0_SA_DQS_DN<5>")
	)
	(segment
		(start 296.860468 -201.869294)
		(end 296.008298 -201.869294)
		(width 0.16002)
		(layer "In13.Cu")
		(net "M_B_CPU0_SA_DQS_DN<5>")
	)
	(segment
		(start 326.5551 -222.070168)
		(end 326.33539 -221.850458)
		(width 0.09525)
		(layer "In13.Cu")
		(net "M_B_CPU0_SA_DQS_DN<5>")
	)
	(arc
		(start 332.171294 -227.804218)
		(mid 331.986262 -227.850132)
		(end 331.802486 -227.799392)
		(width 0.09525)
		(layer "In13.Cu")
		(net "M_B_CPU0_SA_DQS_DN<5>")
	)
	(arc
		(start 335.562448 -227.799392)
		(mid 335.281016 -227.723637)
		(end 334.999584 -227.799392)
		(width 0.09525)
		(layer "In13.Cu")
		(net "M_B_CPU0_SA_DQS_DN<5>")
	)
	(arc
		(start 329.420982 -226.971098)
		(mid 329.305184 -226.836704)
		(end 329.263502 -226.664266)
		(width 0.09525)
		(layer "In13.Cu")
		(net "M_B_CPU0_SA_DQS_DN<5>")
	)
	(arc
		(start 328.480166 -225.350578)
		(mid 328.364892 -225.2163)
		(end 328.323448 -225.044254)
		(width 0.09525)
		(layer "In13.Cu")
		(net "M_B_CPU0_SA_DQS_DN<5>")
	)
	(arc
		(start 326.914002 -222.614236)
		(mid 326.849537 -222.352863)
		(end 326.670924 -222.151448)
		(width 0.09525)
		(layer "In13.Cu")
		(net "M_B_CPU0_SA_DQS_DN<5>")
	)
	(arc
		(start 335.931256 -227.804218)
		(mid 335.746224 -227.850132)
		(end 335.562448 -227.799392)
		(width 0.09525)
		(layer "In13.Cu")
		(net "M_B_CPU0_SA_DQS_DN<5>")
	)
	(arc
		(start 327.383648 -223.424242)
		(mid 327.319613 -223.163565)
		(end 327.142094 -222.962216)
		(width 0.09525)
		(layer "In13.Cu")
		(net "M_B_CPU0_SA_DQS_DN<5>")
	)
	(arc
		(start 330.862432 -227.799392)
		(mid 330.581 -227.723637)
		(end 330.299568 -227.799392)
		(width 0.09525)
		(layer "In13.Cu")
		(net "M_B_CPU0_SA_DQS_DN<5>")
	)
	(arc
		(start 334.622648 -227.799392)
		(mid 334.341216 -227.723637)
		(end 334.059784 -227.799392)
		(width 0.09525)
		(layer "In13.Cu")
		(net "M_B_CPU0_SA_DQS_DN<5>")
	)
	(arc
		(start 327.853802 -224.234248)
		(mid 327.788555 -223.971645)
		(end 327.608184 -223.769936)
		(width 0.09525)
		(layer "In13.Cu")
		(net "M_B_CPU0_SA_DQS_DN<5>")
	)
	(arc
		(start 330.299568 -227.799392)
		(mid 330.1111 -227.850069)
		(end 329.922632 -227.799392)
		(width 0.09525)
		(layer "In13.Cu")
		(net "M_B_CPU0_SA_DQS_DN<5>")
	)
	(arc
		(start 327.538334 -223.729296)
		(mid 327.424549 -223.595252)
		(end 327.383648 -223.424242)
		(width 0.09525)
		(layer "In13.Cu")
		(net "M_B_CPU0_SA_DQS_DN<5>")
	)
	(arc
		(start 336.82178 -227.82657)
		(mid 336.659098 -227.848702)
		(end 336.502502 -227.799392)
		(width 0.09525)
		(layer "In13.Cu")
		(net "M_B_CPU0_SA_DQS_DN<5>")
	)
	(arc
		(start 329.733402 -227.474272)
		(mid 329.669005 -227.212966)
		(end 329.490578 -227.011484)
		(width 0.09525)
		(layer "In13.Cu")
		(net "M_B_CPU0_SA_DQS_DN<5>")
	)
	(arc
		(start 336.502502 -227.799392)
		(mid 336.22107 -227.723637)
		(end 335.939638 -227.799392)
		(width 0.09525)
		(layer "In13.Cu")
		(net "M_B_CPU0_SA_DQS_DN<5>")
	)
	(arc
		(start 334.999584 -227.799392)
		(mid 334.811116 -227.850069)
		(end 334.622648 -227.799392)
		(width 0.09525)
		(layer "In13.Cu")
		(net "M_B_CPU0_SA_DQS_DN<5>")
	)
	(arc
		(start 333.682594 -227.799392)
		(mid 333.401162 -227.723637)
		(end 333.11973 -227.799392)
		(width 0.09525)
		(layer "In13.Cu")
		(net "M_B_CPU0_SA_DQS_DN<5>")
	)
	(arc
		(start 327.072498 -222.92183)
		(mid 326.955949 -222.787252)
		(end 326.914002 -222.614236)
		(width 0.09525)
		(layer "In13.Cu")
		(net "M_B_CPU0_SA_DQS_DN<5>")
	)
	(arc
		(start 333.11973 -227.799392)
		(mid 332.935955 -227.850164)
		(end 332.750922 -227.804218)
		(width 0.09525)
		(layer "In13.Cu")
		(net "M_B_CPU0_SA_DQS_DN<5>")
	)
	(arc
		(start 328.950066 -226.160584)
		(mid 328.834792 -226.026306)
		(end 328.793348 -225.85426)
		(width 0.09525)
		(layer "In13.Cu")
		(net "M_B_CPU0_SA_DQS_DN<5>")
	)
	(arc
		(start 331.802486 -227.799392)
		(mid 331.521054 -227.723637)
		(end 331.239622 -227.799392)
		(width 0.09525)
		(layer "In13.Cu")
		(net "M_B_CPU0_SA_DQS_DN<5>")
	)
	(arc
		(start 334.059784 -227.799392)
		(mid 333.876009 -227.850164)
		(end 333.690976 -227.804218)
		(width 0.09525)
		(layer "In13.Cu")
		(net "M_B_CPU0_SA_DQS_DN<5>")
	)
	(arc
		(start 332.74254 -227.799392)
		(mid 332.461108 -227.723637)
		(end 332.179676 -227.799392)
		(width 0.09525)
		(layer "In13.Cu")
		(net "M_B_CPU0_SA_DQS_DN<5>")
	)
	(arc
		(start 329.263502 -226.664266)
		(mid 329.199105 -226.40296)
		(end 329.020678 -226.201478)
		(width 0.09525)
		(layer "In13.Cu")
		(net "M_B_CPU0_SA_DQS_DN<5>")
	)
	(arc
		(start 329.89012 -227.780596)
		(mid 329.774846 -227.646318)
		(end 329.733402 -227.474272)
		(width 0.09525)
		(layer "In13.Cu")
		(net "M_B_CPU0_SA_DQS_DN<5>")
	)
	(arc
		(start 328.793348 -225.85426)
		(mid 328.728101 -225.591657)
		(end 328.54773 -225.389948)
		(width 0.09525)
		(layer "In13.Cu")
		(net "M_B_CPU0_SA_DQS_DN<5>")
	)
	(arc
		(start 331.23124 -227.804218)
		(mid 331.046208 -227.850132)
		(end 330.862432 -227.799392)
		(width 0.09525)
		(layer "In13.Cu")
		(net "M_B_CPU0_SA_DQS_DN<5>")
	)
	(arc
		(start 326.632824 -222.12935)
		(mid 326.592032 -222.102294)
		(end 326.5551 -222.070168)
		(width 0.09525)
		(layer "In13.Cu")
		(net "M_B_CPU0_SA_DQS_DN<5>")
	)
	(arc
		(start 328.013314 -224.542604)
		(mid 327.89601 -224.407843)
		(end 327.853802 -224.234248)
		(width 0.09525)
		(layer "In13.Cu")
		(net "M_B_CPU0_SA_DQS_DN<5>")
	)
	(arc
		(start 328.323448 -225.044254)
		(mid 328.259051 -224.782948)
		(end 328.080624 -224.581466)
		(width 0.09525)
		(layer "In13.Cu")
		(net "M_B_CPU0_SA_DQS_DN<5>")
	)
	(segment
		(start 336.218022 -247.1801)
		(end 335.75117 -246.914162)
		(width 0.12954)
		(layer "F.Cu")
		(net "M_B_CPU0_SA_DQS_DN<4>")
	)
	(segment
		(start 300.084744 -238.72444)
		(end 300.721522 -238.72444)
		(width 0.16002)
		(layer "In13.Cu")
		(net "M_B_CPU0_SA_DQS_DN<4>")
	)
	(segment
		(start 303.736248 -238.590582)
		(end 305.579018 -239.353852)
		(width 0.16002)
		(layer "In13.Cu")
		(net "M_B_CPU0_SA_DQS_DN<4>")
	)
	(segment
		(start 307.26761 -239.549686)
		(end 307.49367 -239.549686)
		(width 0.16002)
		(layer "In13.Cu")
		(net "M_B_CPU0_SA_DQS_DN<4>")
	)
	(segment
		(start 307.740558 -239.796574)
		(end 307.740558 -240.022634)
		(width 0.16002)
		(layer "In13.Cu")
		(net "M_B_CPU0_SA_DQS_DN<4>")
	)
	(segment
		(start 312.836814 -244.62867)
		(end 312.836814 -244.90553)
		(width 0.16002)
		(layer "In13.Cu")
		(net "M_B_CPU0_SA_DQS_DN<4>")
	)
	(segment
		(start 332.74254 -246.589042)
		(end 332.750922 -246.584216)
		(width 0.09525)
		(layer "In13.Cu")
		(net "M_B_CPU0_SA_DQS_DN<4>")
	)
	(segment
		(start 327.081642 -246.602504)
		(end 327.10501 -246.589042)
		(width 0.09525)
		(layer "In13.Cu")
		(net "M_B_CPU0_SA_DQS_DN<4>")
	)
	(segment
		(start 308.806596 -241.967004)
		(end 309.3339 -241.967004)
		(width 0.16002)
		(layer "In13.Cu")
		(net "M_B_CPU0_SA_DQS_DN<4>")
	)
	(segment
		(start 328.982578 -246.589042)
		(end 328.99096 -246.584216)
		(width 0.09525)
		(layer "In13.Cu")
		(net "M_B_CPU0_SA_DQS_DN<4>")
	)
	(segment
		(start 309.616094 -241.68481)
		(end 309.892954 -241.68481)
		(width 0.16002)
		(layer "In13.Cu")
		(net "M_B_CPU0_SA_DQS_DN<4>")
	)
	(segment
		(start 335.597246 -246.648732)
		(end 335.75117 -246.914162)
		(width 0.09525)
		(layer "In13.Cu")
		(net "M_B_CPU0_SA_DQS_DN<4>")
	)
	(segment
		(start 307.539644 -240.223548)
		(end 307.539644 -240.700052)
		(width 0.16002)
		(layer "In13.Cu")
		(net "M_B_CPU0_SA_DQS_DN<4>")
	)
	(segment
		(start 307.740558 -240.022634)
		(end 307.539644 -240.223548)
		(width 0.16002)
		(layer "In13.Cu")
		(net "M_B_CPU0_SA_DQS_DN<4>")
	)
	(segment
		(start 312.55462 -245.715028)
		(end 313.133232 -246.29364)
		(width 0.16002)
		(layer "In13.Cu")
		(net "M_B_CPU0_SA_DQS_DN<4>")
	)
	(segment
		(start 323.902578 -246.234458)
		(end 324.113652 -246.234458)
		(width 0.09525)
		(layer "In13.Cu")
		(net "M_B_CPU0_SA_DQS_DN<4>")
	)
	(segment
		(start 328.411332 -246.584216)
		(end 328.419714 -246.589042)
		(width 0.09525)
		(layer "In13.Cu")
		(net "M_B_CPU0_SA_DQS_DN<4>")
	)
	(segment
		(start 312.363358 -244.432074)
		(end 312.640218 -244.432074)
		(width 0.16002)
		(layer "In13.Cu")
		(net "M_B_CPU0_SA_DQS_DN<4>")
	)
	(segment
		(start 324.541388 -246.947182)
		(end 325.340472 -246.947182)
		(width 0.09525)
		(layer "In13.Cu")
		(net "M_B_CPU0_SA_DQS_DN<4>")
	)
	(segment
		(start 310.180228 -243.340636)
		(end 310.707532 -243.340636)
		(width 0.16002)
		(layer "In13.Cu")
		(net "M_B_CPU0_SA_DQS_DN<4>")
	)
	(segment
		(start 312.081164 -244.714268)
		(end 312.363358 -244.432074)
		(width 0.16002)
		(layer "In13.Cu")
		(net "M_B_CPU0_SA_DQS_DN<4>")
	)
	(segment
		(start 324.113652 -246.234458)
		(end 324.208902 -246.329708)
		(width 0.09525)
		(layer "In13.Cu")
		(net "M_B_CPU0_SA_DQS_DN<4>")
	)
	(segment
		(start 312.640218 -244.432074)
		(end 312.836814 -244.62867)
		(width 0.16002)
		(layer "In13.Cu")
		(net "M_B_CPU0_SA_DQS_DN<4>")
	)
	(segment
		(start 307.49367 -239.549686)
		(end 307.740558 -239.796574)
		(width 0.16002)
		(layer "In13.Cu")
		(net "M_B_CPU0_SA_DQS_DN<4>")
	)
	(segment
		(start 312.55462 -245.187724)
		(end 312.55462 -245.715028)
		(width 0.16002)
		(layer "In13.Cu")
		(net "M_B_CPU0_SA_DQS_DN<4>")
	)
	(segment
		(start 306.590192 -239.7506)
		(end 307.066696 -239.7506)
		(width 0.16002)
		(layer "In13.Cu")
		(net "M_B_CPU0_SA_DQS_DN<4>")
	)
	(segment
		(start 311.55386 -244.714268)
		(end 312.081164 -244.714268)
		(width 0.16002)
		(layer "In13.Cu")
		(net "M_B_CPU0_SA_DQS_DN<4>")
	)
	(segment
		(start 309.3339 -241.967004)
		(end 309.616094 -241.68481)
		(width 0.16002)
		(layer "In13.Cu")
		(net "M_B_CPU0_SA_DQS_DN<4>")
	)
	(segment
		(start 325.623428 -246.664226)
		(end 325.883778 -246.664226)
		(width 0.09525)
		(layer "In13.Cu")
		(net "M_B_CPU0_SA_DQS_DN<4>")
	)
	(segment
		(start 307.539644 -240.700052)
		(end 308.806596 -241.967004)
		(width 0.16002)
		(layer "In13.Cu")
		(net "M_B_CPU0_SA_DQS_DN<4>")
	)
	(segment
		(start 311.180988 -243.814092)
		(end 311.180988 -244.341396)
		(width 0.16002)
		(layer "In13.Cu")
		(net "M_B_CPU0_SA_DQS_DN<4>")
	)
	(segment
		(start 335.496408 -246.622062)
		(end 335.597246 -246.648732)
		(width 0.09525)
		(layer "In13.Cu")
		(net "M_B_CPU0_SA_DQS_DN<4>")
	)
	(segment
		(start 310.08955 -242.158266)
		(end 309.807356 -242.44046)
		(width 0.16002)
		(layer "In13.Cu")
		(net "M_B_CPU0_SA_DQS_DN<4>")
	)
	(segment
		(start 313.133232 -246.29364)
		(end 323.819774 -246.29364)
		(width 0.16002)
		(layer "In13.Cu")
		(net "M_B_CPU0_SA_DQS_DN<4>")
	)
	(segment
		(start 326.163686 -246.589042)
		(end 326.189086 -246.574564)
		(width 0.09525)
		(layer "In13.Cu")
		(net "M_B_CPU0_SA_DQS_DN<4>")
	)
	(segment
		(start 311.463182 -243.255038)
		(end 311.463182 -243.531898)
		(width 0.16002)
		(layer "In13.Cu")
		(net "M_B_CPU0_SA_DQS_DN<4>")
	)
	(segment
		(start 309.807356 -242.44046)
		(end 309.807356 -242.967764)
		(width 0.16002)
		(layer "In13.Cu")
		(net "M_B_CPU0_SA_DQS_DN<4>")
	)
	(segment
		(start 309.807356 -242.967764)
		(end 310.180228 -243.340636)
		(width 0.16002)
		(layer "In13.Cu")
		(net "M_B_CPU0_SA_DQS_DN<4>")
	)
	(segment
		(start 311.266586 -243.058442)
		(end 311.463182 -243.255038)
		(width 0.16002)
		(layer "In13.Cu")
		(net "M_B_CPU0_SA_DQS_DN<4>")
	)
	(segment
		(start 312.836814 -244.90553)
		(end 312.55462 -245.187724)
		(width 0.16002)
		(layer "In13.Cu")
		(net "M_B_CPU0_SA_DQS_DN<4>")
	)
	(segment
		(start 324.208902 -246.329708)
		(end 324.208902 -246.614696)
		(width 0.09525)
		(layer "In13.Cu")
		(net "M_B_CPU0_SA_DQS_DN<4>")
	)
	(segment
		(start 324.208902 -246.614696)
		(end 324.541388 -246.947182)
		(width 0.09525)
		(layer "In13.Cu")
		(net "M_B_CPU0_SA_DQS_DN<4>")
	)
	(segment
		(start 307.066696 -239.7506)
		(end 307.26761 -239.549686)
		(width 0.16002)
		(layer "In13.Cu")
		(net "M_B_CPU0_SA_DQS_DN<4>")
	)
	(segment
		(start 331.23124 -246.584216)
		(end 331.239622 -246.589042)
		(width 0.09525)
		(layer "In13.Cu")
		(net "M_B_CPU0_SA_DQS_DN<4>")
	)
	(segment
		(start 299.82414 -238.985044)
		(end 300.084744 -238.72444)
		(width 0.16002)
		(layer "In13.Cu")
		(net "M_B_CPU0_SA_DQS_DN<4>")
	)
	(segment
		(start 325.340472 -246.947182)
		(end 325.623428 -246.664226)
		(width 0.09525)
		(layer "In13.Cu")
		(net "M_B_CPU0_SA_DQS_DN<4>")
	)
	(segment
		(start 310.707532 -243.340636)
		(end 310.989726 -243.058442)
		(width 0.16002)
		(layer "In13.Cu")
		(net "M_B_CPU0_SA_DQS_DN<4>")
	)
	(segment
		(start 323.819774 -246.29364)
		(end 323.843396 -246.29364)
		(width 0.09525)
		(layer "In13.Cu")
		(net "M_B_CPU0_SA_DQS_DN<4>")
	)
	(segment
		(start 327.481184 -246.589042)
		(end 327.506584 -246.603774)
		(width 0.09525)
		(layer "In13.Cu")
		(net "M_B_CPU0_SA_DQS_DN<4>")
	)
	(segment
		(start 327.466706 -246.58066)
		(end 327.481184 -246.589042)
		(width 0.09525)
		(layer "In13.Cu")
		(net "M_B_CPU0_SA_DQS_DN<4>")
	)
	(segment
		(start 332.171294 -246.584216)
		(end 332.179676 -246.589042)
		(width 0.09525)
		(layer "In13.Cu")
		(net "M_B_CPU0_SA_DQS_DN<4>")
	)
	(segment
		(start 306.193444 -239.353852)
		(end 306.590192 -239.7506)
		(width 0.16002)
		(layer "In13.Cu")
		(net "M_B_CPU0_SA_DQS_DN<4>")
	)
	(segment
		(start 305.579018 -239.353852)
		(end 306.193444 -239.353852)
		(width 0.16002)
		(layer "In13.Cu")
		(net "M_B_CPU0_SA_DQS_DN<4>")
	)
	(segment
		(start 323.843396 -246.29364)
		(end 323.902578 -246.234458)
		(width 0.09525)
		(layer "In13.Cu")
		(net "M_B_CPU0_SA_DQS_DN<4>")
	)
	(segment
		(start 310.989726 -243.058442)
		(end 311.266586 -243.058442)
		(width 0.16002)
		(layer "In13.Cu")
		(net "M_B_CPU0_SA_DQS_DN<4>")
	)
	(segment
		(start 311.180988 -244.341396)
		(end 311.55386 -244.714268)
		(width 0.16002)
		(layer "In13.Cu")
		(net "M_B_CPU0_SA_DQS_DN<4>")
	)
	(segment
		(start 310.08955 -241.881406)
		(end 310.08955 -242.158266)
		(width 0.16002)
		(layer "In13.Cu")
		(net "M_B_CPU0_SA_DQS_DN<4>")
	)
	(segment
		(start 311.463182 -243.531898)
		(end 311.180988 -243.814092)
		(width 0.16002)
		(layer "In13.Cu")
		(net "M_B_CPU0_SA_DQS_DN<4>")
	)
	(segment
		(start 309.892954 -241.68481)
		(end 310.08955 -241.881406)
		(width 0.16002)
		(layer "In13.Cu")
		(net "M_B_CPU0_SA_DQS_DN<4>")
	)
	(segment
		(start 300.85538 -238.590582)
		(end 303.736248 -238.590582)
		(width 0.16002)
		(layer "In13.Cu")
		(net "M_B_CPU0_SA_DQS_DN<4>")
	)
	(segment
		(start 333.682594 -246.589042)
		(end 333.690976 -246.584216)
		(width 0.09525)
		(layer "In13.Cu")
		(net "M_B_CPU0_SA_DQS_DN<4>")
	)
	(segment
		(start 300.721522 -238.72444)
		(end 300.85538 -238.590582)
		(width 0.16002)
		(layer "In13.Cu")
		(net "M_B_CPU0_SA_DQS_DN<4>")
	)
	(arc
		(start 331.239622 -246.589042)
		(mid 331.521054 -246.664797)
		(end 331.802486 -246.589042)
		(width 0.09525)
		(layer "In13.Cu")
		(net "M_B_CPU0_SA_DQS_DN<4>")
	)
	(arc
		(start 332.179676 -246.589042)
		(mid 332.461108 -246.664797)
		(end 332.74254 -246.589042)
		(width 0.09525)
		(layer "In13.Cu")
		(net "M_B_CPU0_SA_DQS_DN<4>")
	)
	(arc
		(start 332.750922 -246.584216)
		(mid 332.935954 -246.538302)
		(end 333.11973 -246.589042)
		(width 0.09525)
		(layer "In13.Cu")
		(net "M_B_CPU0_SA_DQS_DN<4>")
	)
	(arc
		(start 327.506584 -246.603774)
		(mid 327.776438 -246.664653)
		(end 328.042524 -246.589042)
		(width 0.09525)
		(layer "In13.Cu")
		(net "M_B_CPU0_SA_DQS_DN<4>")
	)
	(arc
		(start 326.004682 -246.651018)
		(mid 326.086563 -246.626131)
		(end 326.163686 -246.589042)
		(width 0.09525)
		(layer "In13.Cu")
		(net "M_B_CPU0_SA_DQS_DN<4>")
	)
	(arc
		(start 333.690976 -246.584216)
		(mid 333.876008 -246.538302)
		(end 334.059784 -246.589042)
		(width 0.09525)
		(layer "In13.Cu")
		(net "M_B_CPU0_SA_DQS_DN<4>")
	)
	(arc
		(start 326.189086 -246.574564)
		(mid 326.366791 -246.538086)
		(end 326.540876 -246.589042)
		(width 0.09525)
		(layer "In13.Cu")
		(net "M_B_CPU0_SA_DQS_DN<4>")
	)
	(arc
		(start 326.540876 -246.589042)
		(mid 326.809539 -246.66526)
		(end 327.081642 -246.602504)
		(width 0.09525)
		(layer "In13.Cu")
		(net "M_B_CPU0_SA_DQS_DN<4>")
	)
	(arc
		(start 325.883778 -246.664226)
		(mid 325.94459 -246.660915)
		(end 326.004682 -246.651018)
		(width 0.09525)
		(layer "In13.Cu")
		(net "M_B_CPU0_SA_DQS_DN<4>")
	)
	(arc
		(start 327.10501 -246.589042)
		(mid 327.284782 -246.538466)
		(end 327.466706 -246.58066)
		(width 0.09525)
		(layer "In13.Cu")
		(net "M_B_CPU0_SA_DQS_DN<4>")
	)
	(arc
		(start 334.622648 -246.589042)
		(mid 334.811116 -246.538365)
		(end 334.999584 -246.589042)
		(width 0.09525)
		(layer "In13.Cu")
		(net "M_B_CPU0_SA_DQS_DN<4>")
	)
	(arc
		(start 329.359768 -246.589042)
		(mid 329.6412 -246.664797)
		(end 329.922632 -246.589042)
		(width 0.09525)
		(layer "In13.Cu")
		(net "M_B_CPU0_SA_DQS_DN<4>")
	)
	(arc
		(start 328.99096 -246.584216)
		(mid 329.175992 -246.538302)
		(end 329.359768 -246.589042)
		(width 0.09525)
		(layer "In13.Cu")
		(net "M_B_CPU0_SA_DQS_DN<4>")
	)
	(arc
		(start 334.999584 -246.589042)
		(mid 335.233098 -246.662885)
		(end 335.475834 -246.63019)
		(width 0.09525)
		(layer "In13.Cu")
		(net "M_B_CPU0_SA_DQS_DN<4>")
	)
	(arc
		(start 328.419714 -246.589042)
		(mid 328.701146 -246.664797)
		(end 328.982578 -246.589042)
		(width 0.09525)
		(layer "In13.Cu")
		(net "M_B_CPU0_SA_DQS_DN<4>")
	)
	(arc
		(start 330.862432 -246.589042)
		(mid 331.046207 -246.53827)
		(end 331.23124 -246.584216)
		(width 0.09525)
		(layer "In13.Cu")
		(net "M_B_CPU0_SA_DQS_DN<4>")
	)
	(arc
		(start 335.475834 -246.63019)
		(mid 335.486162 -246.62623)
		(end 335.496408 -246.622062)
		(width 0.09525)
		(layer "In13.Cu")
		(net "M_B_CPU0_SA_DQS_DN<4>")
	)
	(arc
		(start 334.059784 -246.589042)
		(mid 334.341216 -246.664797)
		(end 334.622648 -246.589042)
		(width 0.09525)
		(layer "In13.Cu")
		(net "M_B_CPU0_SA_DQS_DN<4>")
	)
	(arc
		(start 333.11973 -246.589042)
		(mid 333.401162 -246.664797)
		(end 333.682594 -246.589042)
		(width 0.09525)
		(layer "In13.Cu")
		(net "M_B_CPU0_SA_DQS_DN<4>")
	)
	(arc
		(start 330.299568 -246.589042)
		(mid 330.581 -246.664797)
		(end 330.862432 -246.589042)
		(width 0.09525)
		(layer "In13.Cu")
		(net "M_B_CPU0_SA_DQS_DN<4>")
	)
	(arc
		(start 329.922632 -246.589042)
		(mid 330.1111 -246.538365)
		(end 330.299568 -246.589042)
		(width 0.09525)
		(layer "In13.Cu")
		(net "M_B_CPU0_SA_DQS_DN<4>")
	)
	(arc
		(start 328.042524 -246.589042)
		(mid 328.226299 -246.53827)
		(end 328.411332 -246.584216)
		(width 0.09525)
		(layer "In13.Cu")
		(net "M_B_CPU0_SA_DQS_DN<4>")
	)
	(arc
		(start 331.802486 -246.589042)
		(mid 331.986261 -246.53827)
		(end 332.171294 -246.584216)
		(width 0.09525)
		(layer "In13.Cu")
		(net "M_B_CPU0_SA_DQS_DN<4>")
	)
	(segment
		(start 336.218022 -242.320064)
		(end 335.75117 -242.054126)
		(width 0.12954)
		(layer "F.Cu")
		(net "M_B_CPU0_SA_DQS_DN<3>")
	)
	(segment
		(start 311.992772 -233.216196)
		(end 311.992772 -232.93959)
		(width 0.16002)
		(layer "In13.Cu")
		(net "M_B_CPU0_SA_DQS_DN<3>")
	)
	(segment
		(start 310.411114 -232.05059)
		(end 310.61914 -231.842564)
		(width 0.16002)
		(layer "In13.Cu")
		(net "M_B_CPU0_SA_DQS_DN<3>")
	)
	(segment
		(start 312.157618 -234.324652)
		(end 311.784746 -233.95178)
		(width 0.16002)
		(layer "In13.Cu")
		(net "M_B_CPU0_SA_DQS_DN<3>")
	)
	(segment
		(start 333.690976 -241.72418)
		(end 333.682594 -241.729006)
		(width 0.09525)
		(layer "In13.Cu")
		(net "M_B_CPU0_SA_DQS_DN<3>")
	)
	(segment
		(start 325.091044 -241.087402)
		(end 324.65137 -241.087402)
		(width 0.09525)
		(layer "In13.Cu")
		(net "M_B_CPU0_SA_DQS_DN<3>")
	)
	(segment
		(start 311.795922 -232.74274)
		(end 311.51957 -232.74274)
		(width 0.16002)
		(layer "In13.Cu")
		(net "M_B_CPU0_SA_DQS_DN<3>")
	)
	(segment
		(start 307.0606 -229.94239)
		(end 305.721004 -229.94239)
		(width 0.16002)
		(layer "In13.Cu")
		(net "M_B_CPU0_SA_DQS_DN<3>")
	)
	(segment
		(start 310.61914 -231.565958)
		(end 310.42229 -231.369108)
		(width 0.16002)
		(layer "In13.Cu")
		(net "M_B_CPU0_SA_DQS_DN<3>")
	)
	(segment
		(start 302.872648 -229.876096)
		(end 302.872648 -229.712012)
		(width 0.16002)
		(layer "In13.Cu")
		(net "M_B_CPU0_SA_DQS_DN<3>")
	)
	(segment
		(start 328.99096 -241.72418)
		(end 328.982578 -241.729006)
		(width 0.09525)
		(layer "In13.Cu")
		(net "M_B_CPU0_SA_DQS_DN<3>")
	)
	(segment
		(start 302.01743 -229.551992)
		(end 301.833788 -229.36835)
		(width 0.16002)
		(layer "In13.Cu")
		(net "M_B_CPU0_SA_DQS_DN<3>")
	)
	(segment
		(start 335.75117 -242.054126)
		(end 335.597246 -241.788696)
		(width 0.09525)
		(layer "In13.Cu")
		(net "M_B_CPU0_SA_DQS_DN<3>")
	)
	(segment
		(start 335.597246 -241.788696)
		(end 335.496408 -241.762026)
		(width 0.09525)
		(layer "In13.Cu")
		(net "M_B_CPU0_SA_DQS_DN<3>")
	)
	(segment
		(start 310.783986 -232.95102)
		(end 310.411114 -232.578148)
		(width 0.16002)
		(layer "In13.Cu")
		(net "M_B_CPU0_SA_DQS_DN<3>")
	)
	(segment
		(start 307.557678 -229.227888)
		(end 307.397658 -229.387908)
		(width 0.16002)
		(layer "In13.Cu")
		(net "M_B_CPU0_SA_DQS_DN<3>")
	)
	(segment
		(start 308.065678 -229.605332)
		(end 308.065678 -229.387908)
		(width 0.16002)
		(layer "In13.Cu")
		(net "M_B_CPU0_SA_DQS_DN<3>")
	)
	(segment
		(start 325.68134 -241.677698)
		(end 325.091044 -241.087402)
		(width 0.09525)
		(layer "In13.Cu")
		(net "M_B_CPU0_SA_DQS_DN<3>")
	)
	(segment
		(start 309.037482 -230.676958)
		(end 309.245508 -230.468932)
		(width 0.16002)
		(layer "In13.Cu")
		(net "M_B_CPU0_SA_DQS_DN<3>")
	)
	(segment
		(start 313.366404 -234.589828)
		(end 313.366404 -234.313222)
		(width 0.16002)
		(layer "In13.Cu")
		(net "M_B_CPU0_SA_DQS_DN<3>")
	)
	(segment
		(start 326.351138 -241.677698)
		(end 325.68134 -241.677698)
		(width 0.09525)
		(layer "In13.Cu")
		(net "M_B_CPU0_SA_DQS_DN<3>")
	)
	(segment
		(start 305.721004 -229.94239)
		(end 305.330606 -229.551992)
		(width 0.16002)
		(layer "In13.Cu")
		(net "M_B_CPU0_SA_DQS_DN<3>")
	)
	(segment
		(start 313.158378 -235.325412)
		(end 313.158378 -234.797854)
		(width 0.16002)
		(layer "In13.Cu")
		(net "M_B_CPU0_SA_DQS_DN<3>")
	)
	(segment
		(start 303.80813 -230.213154)
		(end 303.209706 -230.213154)
		(width 0.16002)
		(layer "In13.Cu")
		(net "M_B_CPU0_SA_DQS_DN<3>")
	)
	(segment
		(start 310.145938 -231.369108)
		(end 309.937658 -231.577388)
		(width 0.16002)
		(layer "In13.Cu")
		(net "M_B_CPU0_SA_DQS_DN<3>")
	)
	(segment
		(start 302.712628 -229.551992)
		(end 302.01743 -229.551992)
		(width 0.16002)
		(layer "In13.Cu")
		(net "M_B_CPU0_SA_DQS_DN<3>")
	)
	(segment
		(start 304.305208 -229.551992)
		(end 304.145188 -229.712012)
		(width 0.16002)
		(layer "In13.Cu")
		(net "M_B_CPU0_SA_DQS_DN<3>")
	)
	(segment
		(start 327.47966 -241.729006)
		(end 327.471278 -241.72418)
		(width 0.09525)
		(layer "In13.Cu")
		(net "M_B_CPU0_SA_DQS_DN<3>")
	)
	(segment
		(start 310.411114 -232.578148)
		(end 310.411114 -232.05059)
		(width 0.16002)
		(layer "In13.Cu")
		(net "M_B_CPU0_SA_DQS_DN<3>")
	)
	(segment
		(start 300.09084 -229.36835)
		(end 299.82414 -229.63505)
		(width 0.16002)
		(layer "In13.Cu")
		(net "M_B_CPU0_SA_DQS_DN<3>")
	)
	(segment
		(start 302.872648 -229.712012)
		(end 302.712628 -229.551992)
		(width 0.16002)
		(layer "In13.Cu")
		(net "M_B_CPU0_SA_DQS_DN<3>")
	)
	(segment
		(start 303.209706 -230.213154)
		(end 302.872648 -229.876096)
		(width 0.16002)
		(layer "In13.Cu")
		(net "M_B_CPU0_SA_DQS_DN<3>")
	)
	(segment
		(start 311.784746 -233.95178)
		(end 311.784746 -233.424222)
		(width 0.16002)
		(layer "In13.Cu")
		(net "M_B_CPU0_SA_DQS_DN<3>")
	)
	(segment
		(start 311.31129 -232.95102)
		(end 310.783986 -232.95102)
		(width 0.16002)
		(layer "In13.Cu")
		(net "M_B_CPU0_SA_DQS_DN<3>")
	)
	(segment
		(start 323.919596 -240.659412)
		(end 323.895974 -240.659412)
		(width 0.09525)
		(layer "In13.Cu")
		(net "M_B_CPU0_SA_DQS_DN<3>")
	)
	(segment
		(start 309.937658 -231.577388)
		(end 309.410354 -231.577388)
		(width 0.16002)
		(layer "In13.Cu")
		(net "M_B_CPU0_SA_DQS_DN<3>")
	)
	(segment
		(start 310.42229 -231.369108)
		(end 310.145938 -231.369108)
		(width 0.16002)
		(layer "In13.Cu")
		(net "M_B_CPU0_SA_DQS_DN<3>")
	)
	(segment
		(start 312.684922 -234.324652)
		(end 312.157618 -234.324652)
		(width 0.16002)
		(layer "In13.Cu")
		(net "M_B_CPU0_SA_DQS_DN<3>")
	)
	(segment
		(start 324.164452 -240.600484)
		(end 323.978524 -240.600484)
		(width 0.09525)
		(layer "In13.Cu")
		(net "M_B_CPU0_SA_DQS_DN<3>")
	)
	(segment
		(start 304.145188 -229.712012)
		(end 304.145188 -229.876096)
		(width 0.16002)
		(layer "In13.Cu")
		(net "M_B_CPU0_SA_DQS_DN<3>")
	)
	(segment
		(start 324.65137 -241.087402)
		(end 324.164452 -240.600484)
		(width 0.09525)
		(layer "In13.Cu")
		(net "M_B_CPU0_SA_DQS_DN<3>")
	)
	(segment
		(start 313.158378 -234.797854)
		(end 313.366404 -234.589828)
		(width 0.16002)
		(layer "In13.Cu")
		(net "M_B_CPU0_SA_DQS_DN<3>")
	)
	(segment
		(start 309.245508 -230.192326)
		(end 308.995572 -229.94239)
		(width 0.16002)
		(layer "In13.Cu")
		(net "M_B_CPU0_SA_DQS_DN<3>")
	)
	(segment
		(start 313.366404 -234.313222)
		(end 313.169554 -234.116372)
		(width 0.16002)
		(layer "In13.Cu")
		(net "M_B_CPU0_SA_DQS_DN<3>")
	)
	(segment
		(start 311.784746 -233.424222)
		(end 311.992772 -233.216196)
		(width 0.16002)
		(layer "In13.Cu")
		(net "M_B_CPU0_SA_DQS_DN<3>")
	)
	(segment
		(start 308.995572 -229.94239)
		(end 308.402736 -229.94239)
		(width 0.16002)
		(layer "In13.Cu")
		(net "M_B_CPU0_SA_DQS_DN<3>")
	)
	(segment
		(start 301.833788 -229.36835)
		(end 300.09084 -229.36835)
		(width 0.16002)
		(layer "In13.Cu")
		(net "M_B_CPU0_SA_DQS_DN<3>")
	)
	(segment
		(start 309.037482 -231.204516)
		(end 309.037482 -230.676958)
		(width 0.16002)
		(layer "In13.Cu")
		(net "M_B_CPU0_SA_DQS_DN<3>")
	)
	(segment
		(start 307.397658 -229.387908)
		(end 307.397658 -229.605332)
		(width 0.16002)
		(layer "In13.Cu")
		(net "M_B_CPU0_SA_DQS_DN<3>")
	)
	(segment
		(start 313.169554 -234.116372)
		(end 312.893202 -234.116372)
		(width 0.16002)
		(layer "In13.Cu")
		(net "M_B_CPU0_SA_DQS_DN<3>")
	)
	(segment
		(start 309.245508 -230.468932)
		(end 309.245508 -230.192326)
		(width 0.16002)
		(layer "In13.Cu")
		(net "M_B_CPU0_SA_DQS_DN<3>")
	)
	(segment
		(start 304.145188 -229.876096)
		(end 303.80813 -230.213154)
		(width 0.16002)
		(layer "In13.Cu")
		(net "M_B_CPU0_SA_DQS_DN<3>")
	)
	(segment
		(start 332.750922 -241.72418)
		(end 332.74254 -241.729006)
		(width 0.09525)
		(layer "In13.Cu")
		(net "M_B_CPU0_SA_DQS_DN<3>")
	)
	(segment
		(start 323.978524 -240.600484)
		(end 323.919596 -240.659412)
		(width 0.09525)
		(layer "In13.Cu")
		(net "M_B_CPU0_SA_DQS_DN<3>")
	)
	(segment
		(start 312.893202 -234.116372)
		(end 312.684922 -234.324652)
		(width 0.16002)
		(layer "In13.Cu")
		(net "M_B_CPU0_SA_DQS_DN<3>")
	)
	(segment
		(start 310.61914 -231.842564)
		(end 310.61914 -231.565958)
		(width 0.16002)
		(layer "In13.Cu")
		(net "M_B_CPU0_SA_DQS_DN<3>")
	)
	(segment
		(start 332.179676 -241.729006)
		(end 332.171294 -241.72418)
		(width 0.09525)
		(layer "In13.Cu")
		(net "M_B_CPU0_SA_DQS_DN<3>")
	)
	(segment
		(start 331.239622 -241.729006)
		(end 331.23124 -241.72418)
		(width 0.09525)
		(layer "In13.Cu")
		(net "M_B_CPU0_SA_DQS_DN<3>")
	)
	(segment
		(start 318.492378 -240.659412)
		(end 313.158378 -235.325412)
		(width 0.16002)
		(layer "In13.Cu")
		(net "M_B_CPU0_SA_DQS_DN<3>")
	)
	(segment
		(start 307.905658 -229.227888)
		(end 307.557678 -229.227888)
		(width 0.16002)
		(layer "In13.Cu")
		(net "M_B_CPU0_SA_DQS_DN<3>")
	)
	(segment
		(start 307.397658 -229.605332)
		(end 307.0606 -229.94239)
		(width 0.16002)
		(layer "In13.Cu")
		(net "M_B_CPU0_SA_DQS_DN<3>")
	)
	(segment
		(start 311.992772 -232.93959)
		(end 311.795922 -232.74274)
		(width 0.16002)
		(layer "In13.Cu")
		(net "M_B_CPU0_SA_DQS_DN<3>")
	)
	(segment
		(start 308.065678 -229.387908)
		(end 307.905658 -229.227888)
		(width 0.16002)
		(layer "In13.Cu")
		(net "M_B_CPU0_SA_DQS_DN<3>")
	)
	(segment
		(start 308.402736 -229.94239)
		(end 308.065678 -229.605332)
		(width 0.16002)
		(layer "In13.Cu")
		(net "M_B_CPU0_SA_DQS_DN<3>")
	)
	(segment
		(start 311.51957 -232.74274)
		(end 311.31129 -232.95102)
		(width 0.16002)
		(layer "In13.Cu")
		(net "M_B_CPU0_SA_DQS_DN<3>")
	)
	(segment
		(start 305.330606 -229.551992)
		(end 304.305208 -229.551992)
		(width 0.16002)
		(layer "In13.Cu")
		(net "M_B_CPU0_SA_DQS_DN<3>")
	)
	(segment
		(start 323.895974 -240.659412)
		(end 318.492378 -240.659412)
		(width 0.16002)
		(layer "In13.Cu")
		(net "M_B_CPU0_SA_DQS_DN<3>")
	)
	(segment
		(start 309.410354 -231.577388)
		(end 309.037482 -231.204516)
		(width 0.16002)
		(layer "In13.Cu")
		(net "M_B_CPU0_SA_DQS_DN<3>")
	)
	(segment
		(start 328.419714 -241.729006)
		(end 328.411332 -241.72418)
		(width 0.09525)
		(layer "In13.Cu")
		(net "M_B_CPU0_SA_DQS_DN<3>")
	)
	(arc
		(start 331.23124 -241.72418)
		(mid 331.046208 -241.678266)
		(end 330.862432 -241.729006)
		(width 0.09525)
		(layer "In13.Cu")
		(net "M_B_CPU0_SA_DQS_DN<3>")
	)
	(arc
		(start 326.539606 -241.729006)
		(mid 326.448763 -241.690887)
		(end 326.351138 -241.677698)
		(width 0.09525)
		(layer "In13.Cu")
		(net "M_B_CPU0_SA_DQS_DN<3>")
	)
	(arc
		(start 328.411332 -241.72418)
		(mid 328.2263 -241.678266)
		(end 328.042524 -241.729006)
		(width 0.09525)
		(layer "In13.Cu")
		(net "M_B_CPU0_SA_DQS_DN<3>")
	)
	(arc
		(start 335.475834 -241.770154)
		(mid 335.233092 -241.802924)
		(end 334.999584 -241.729006)
		(width 0.09525)
		(layer "In13.Cu")
		(net "M_B_CPU0_SA_DQS_DN<3>")
	)
	(arc
		(start 328.982578 -241.729006)
		(mid 328.701146 -241.804761)
		(end 328.419714 -241.729006)
		(width 0.09525)
		(layer "In13.Cu")
		(net "M_B_CPU0_SA_DQS_DN<3>")
	)
	(arc
		(start 328.042524 -241.729006)
		(mid 327.761092 -241.804761)
		(end 327.47966 -241.729006)
		(width 0.09525)
		(layer "In13.Cu")
		(net "M_B_CPU0_SA_DQS_DN<3>")
	)
	(arc
		(start 329.359768 -241.729006)
		(mid 329.175993 -241.678234)
		(end 328.99096 -241.72418)
		(width 0.09525)
		(layer "In13.Cu")
		(net "M_B_CPU0_SA_DQS_DN<3>")
	)
	(arc
		(start 327.10247 -241.729006)
		(mid 326.821038 -241.804761)
		(end 326.539606 -241.729006)
		(width 0.09525)
		(layer "In13.Cu")
		(net "M_B_CPU0_SA_DQS_DN<3>")
	)
	(arc
		(start 333.11973 -241.729006)
		(mid 332.935955 -241.678234)
		(end 332.750922 -241.72418)
		(width 0.09525)
		(layer "In13.Cu")
		(net "M_B_CPU0_SA_DQS_DN<3>")
	)
	(arc
		(start 335.496408 -241.762026)
		(mid 335.48616 -241.766189)
		(end 335.475834 -241.770154)
		(width 0.09525)
		(layer "In13.Cu")
		(net "M_B_CPU0_SA_DQS_DN<3>")
	)
	(arc
		(start 330.862432 -241.729006)
		(mid 330.581 -241.804761)
		(end 330.299568 -241.729006)
		(width 0.09525)
		(layer "In13.Cu")
		(net "M_B_CPU0_SA_DQS_DN<3>")
	)
	(arc
		(start 332.171294 -241.72418)
		(mid 331.986262 -241.678266)
		(end 331.802486 -241.729006)
		(width 0.09525)
		(layer "In13.Cu")
		(net "M_B_CPU0_SA_DQS_DN<3>")
	)
	(arc
		(start 333.682594 -241.729006)
		(mid 333.401162 -241.804761)
		(end 333.11973 -241.729006)
		(width 0.09525)
		(layer "In13.Cu")
		(net "M_B_CPU0_SA_DQS_DN<3>")
	)
	(arc
		(start 334.059784 -241.729006)
		(mid 333.876009 -241.678234)
		(end 333.690976 -241.72418)
		(width 0.09525)
		(layer "In13.Cu")
		(net "M_B_CPU0_SA_DQS_DN<3>")
	)
	(arc
		(start 329.922632 -241.729006)
		(mid 329.6412 -241.804761)
		(end 329.359768 -241.729006)
		(width 0.09525)
		(layer "In13.Cu")
		(net "M_B_CPU0_SA_DQS_DN<3>")
	)
	(arc
		(start 327.471278 -241.72418)
		(mid 327.286246 -241.678266)
		(end 327.10247 -241.729006)
		(width 0.09525)
		(layer "In13.Cu")
		(net "M_B_CPU0_SA_DQS_DN<3>")
	)
	(arc
		(start 334.622648 -241.729006)
		(mid 334.341216 -241.804761)
		(end 334.059784 -241.729006)
		(width 0.09525)
		(layer "In13.Cu")
		(net "M_B_CPU0_SA_DQS_DN<3>")
	)
	(arc
		(start 331.802486 -241.729006)
		(mid 331.521054 -241.804761)
		(end 331.239622 -241.729006)
		(width 0.09525)
		(layer "In13.Cu")
		(net "M_B_CPU0_SA_DQS_DN<3>")
	)
	(arc
		(start 330.299568 -241.729006)
		(mid 330.1111 -241.678329)
		(end 329.922632 -241.729006)
		(width 0.09525)
		(layer "In13.Cu")
		(net "M_B_CPU0_SA_DQS_DN<3>")
	)
	(arc
		(start 334.999584 -241.729006)
		(mid 334.811116 -241.678329)
		(end 334.622648 -241.729006)
		(width 0.09525)
		(layer "In13.Cu")
		(net "M_B_CPU0_SA_DQS_DN<3>")
	)
	(arc
		(start 332.74254 -241.729006)
		(mid 332.461108 -241.804761)
		(end 332.179676 -241.729006)
		(width 0.09525)
		(layer "In13.Cu")
		(net "M_B_CPU0_SA_DQS_DN<3>")
	)
	(segment
		(start 336.218022 -237.460028)
		(end 335.75117 -237.19409)
		(width 0.12954)
		(layer "F.Cu")
		(net "M_B_CPU0_SA_DQS_DN<2>")
	)
	(segment
		(start 324.113652 -234.976924)
		(end 324.208902 -235.072174)
		(width 0.09525)
		(layer "In13.Cu")
		(net "M_B_CPU0_SA_DQS_DN<2>")
	)
	(segment
		(start 309.71363 -222.79356)
		(end 310.241188 -222.79356)
		(width 0.16002)
		(layer "In13.Cu")
		(net "M_B_CPU0_SA_DQS_DN<2>")
	)
	(segment
		(start 310.71439 -223.267016)
		(end 310.71439 -223.79432)
		(width 0.16002)
		(layer "In13.Cu")
		(net "M_B_CPU0_SA_DQS_DN<2>")
	)
	(segment
		(start 323.919596 -235.036106)
		(end 323.978778 -234.976924)
		(width 0.09525)
		(layer "In13.Cu")
		(net "M_B_CPU0_SA_DQS_DN<2>")
	)
	(segment
		(start 335.496408 -236.90199)
		(end 335.597246 -236.92866)
		(width 0.09525)
		(layer "In13.Cu")
		(net "M_B_CPU0_SA_DQS_DN<2>")
	)
	(segment
		(start 303.08423 -220.62059)
		(end 307.909976 -220.62059)
		(width 0.16002)
		(layer "In13.Cu")
		(net "M_B_CPU0_SA_DQS_DN<2>")
	)
	(segment
		(start 324.993508 -235.710222)
		(end 326.100186 -236.8169)
		(width 0.09525)
		(layer "In13.Cu")
		(net "M_B_CPU0_SA_DQS_DN<2>")
	)
	(segment
		(start 312.088022 -225.167952)
		(end 312.460894 -225.540824)
		(width 0.16002)
		(layer "In13.Cu")
		(net "M_B_CPU0_SA_DQS_DN<2>")
	)
	(segment
		(start 328.982578 -236.86897)
		(end 328.99096 -236.864144)
		(width 0.09525)
		(layer "In13.Cu")
		(net "M_B_CPU0_SA_DQS_DN<2>")
	)
	(segment
		(start 328.411332 -236.864144)
		(end 328.419714 -236.86897)
		(width 0.09525)
		(layer "In13.Cu")
		(net "M_B_CPU0_SA_DQS_DN<2>")
	)
	(segment
		(start 332.74254 -236.86897)
		(end 332.750922 -236.864144)
		(width 0.09525)
		(layer "In13.Cu")
		(net "M_B_CPU0_SA_DQS_DN<2>")
	)
	(segment
		(start 312.50001 -224.22866)
		(end 312.088022 -224.640648)
		(width 0.16002)
		(layer "In13.Cu")
		(net "M_B_CPU0_SA_DQS_DN<2>")
	)
	(segment
		(start 310.652922 -222.381826)
		(end 310.929782 -222.381826)
		(width 0.16002)
		(layer "In13.Cu")
		(net "M_B_CPU0_SA_DQS_DN<2>")
	)
	(segment
		(start 314.46216 -226.914456)
		(end 314.835286 -227.287582)
		(width 0.16002)
		(layer "In13.Cu")
		(net "M_B_CPU0_SA_DQS_DN<2>")
	)
	(segment
		(start 313.834526 -226.914456)
		(end 314.46216 -226.914456)
		(width 0.16002)
		(layer "In13.Cu")
		(net "M_B_CPU0_SA_DQS_DN<2>")
	)
	(segment
		(start 313.461654 -226.01428)
		(end 313.461654 -226.541584)
		(width 0.16002)
		(layer "In13.Cu")
		(net "M_B_CPU0_SA_DQS_DN<2>")
	)
	(segment
		(start 324.208902 -235.281216)
		(end 324.637908 -235.710222)
		(width 0.09525)
		(layer "In13.Cu")
		(net "M_B_CPU0_SA_DQS_DN<2>")
	)
	(segment
		(start 324.208902 -235.072174)
		(end 324.208902 -235.281216)
		(width 0.09525)
		(layer "In13.Cu")
		(net "M_B_CPU0_SA_DQS_DN<2>")
	)
	(segment
		(start 307.909976 -220.62059)
		(end 309.274718 -221.985332)
		(width 0.16002)
		(layer "In13.Cu")
		(net "M_B_CPU0_SA_DQS_DN<2>")
	)
	(segment
		(start 309.274718 -221.985332)
		(end 309.274718 -222.354648)
		(width 0.16002)
		(layer "In13.Cu")
		(net "M_B_CPU0_SA_DQS_DN<2>")
	)
	(segment
		(start 310.929782 -222.381826)
		(end 311.126378 -222.578422)
		(width 0.16002)
		(layer "In13.Cu")
		(net "M_B_CPU0_SA_DQS_DN<2>")
	)
	(segment
		(start 323.895974 -235.036106)
		(end 323.919596 -235.036106)
		(width 0.09525)
		(layer "In13.Cu")
		(net "M_B_CPU0_SA_DQS_DN<2>")
	)
	(segment
		(start 312.988452 -225.540824)
		(end 313.400186 -225.12909)
		(width 0.16002)
		(layer "In13.Cu")
		(net "M_B_CPU0_SA_DQS_DN<2>")
	)
	(segment
		(start 314.835286 -227.920804)
		(end 321.950588 -235.036106)
		(width 0.16002)
		(layer "In13.Cu")
		(net "M_B_CPU0_SA_DQS_DN<2>")
	)
	(segment
		(start 302.465994 -220.002354)
		(end 303.08423 -220.62059)
		(width 0.16002)
		(layer "In13.Cu")
		(net "M_B_CPU0_SA_DQS_DN<2>")
	)
	(segment
		(start 312.303414 -223.755458)
		(end 312.50001 -223.952054)
		(width 0.16002)
		(layer "In13.Cu")
		(net "M_B_CPU0_SA_DQS_DN<2>")
	)
	(segment
		(start 299.82414 -220.285056)
		(end 300.106842 -220.002354)
		(width 0.16002)
		(layer "In13.Cu")
		(net "M_B_CPU0_SA_DQS_DN<2>")
	)
	(segment
		(start 327.466706 -236.860588)
		(end 327.481184 -236.86897)
		(width 0.09525)
		(layer "In13.Cu")
		(net "M_B_CPU0_SA_DQS_DN<2>")
	)
	(segment
		(start 311.126378 -222.855028)
		(end 310.71439 -223.267016)
		(width 0.16002)
		(layer "In13.Cu")
		(net "M_B_CPU0_SA_DQS_DN<2>")
	)
	(segment
		(start 310.71439 -223.79432)
		(end 311.087262 -224.167192)
		(width 0.16002)
		(layer "In13.Cu")
		(net "M_B_CPU0_SA_DQS_DN<2>")
	)
	(segment
		(start 309.274718 -222.354648)
		(end 309.71363 -222.79356)
		(width 0.16002)
		(layer "In13.Cu")
		(net "M_B_CPU0_SA_DQS_DN<2>")
	)
	(segment
		(start 312.460894 -225.540824)
		(end 312.988452 -225.540824)
		(width 0.16002)
		(layer "In13.Cu")
		(net "M_B_CPU0_SA_DQS_DN<2>")
	)
	(segment
		(start 312.50001 -223.952054)
		(end 312.50001 -224.22866)
		(width 0.16002)
		(layer "In13.Cu")
		(net "M_B_CPU0_SA_DQS_DN<2>")
	)
	(segment
		(start 331.23124 -236.864144)
		(end 331.239622 -236.86897)
		(width 0.09525)
		(layer "In13.Cu")
		(net "M_B_CPU0_SA_DQS_DN<2>")
	)
	(segment
		(start 332.171294 -236.864144)
		(end 332.179676 -236.86897)
		(width 0.09525)
		(layer "In13.Cu")
		(net "M_B_CPU0_SA_DQS_DN<2>")
	)
	(segment
		(start 313.873642 -225.602292)
		(end 313.461654 -226.01428)
		(width 0.16002)
		(layer "In13.Cu")
		(net "M_B_CPU0_SA_DQS_DN<2>")
	)
	(segment
		(start 323.978778 -234.976924)
		(end 324.113652 -234.976924)
		(width 0.09525)
		(layer "In13.Cu")
		(net "M_B_CPU0_SA_DQS_DN<2>")
	)
	(segment
		(start 311.126378 -222.578422)
		(end 311.126378 -222.855028)
		(width 0.16002)
		(layer "In13.Cu")
		(net "M_B_CPU0_SA_DQS_DN<2>")
	)
	(segment
		(start 313.400186 -225.12909)
		(end 313.677046 -225.12909)
		(width 0.16002)
		(layer "In13.Cu")
		(net "M_B_CPU0_SA_DQS_DN<2>")
	)
	(segment
		(start 314.835286 -227.287582)
		(end 314.835286 -227.920804)
		(width 0.16002)
		(layer "In13.Cu")
		(net "M_B_CPU0_SA_DQS_DN<2>")
	)
	(segment
		(start 326.100186 -236.8169)
		(end 326.351138 -236.8169)
		(width 0.09525)
		(layer "In13.Cu")
		(net "M_B_CPU0_SA_DQS_DN<2>")
	)
	(segment
		(start 313.873642 -225.325686)
		(end 313.873642 -225.602292)
		(width 0.16002)
		(layer "In13.Cu")
		(net "M_B_CPU0_SA_DQS_DN<2>")
	)
	(segment
		(start 335.597246 -236.92866)
		(end 335.75117 -237.19409)
		(width 0.09525)
		(layer "In13.Cu")
		(net "M_B_CPU0_SA_DQS_DN<2>")
	)
	(segment
		(start 333.682594 -236.86897)
		(end 333.690976 -236.864144)
		(width 0.09525)
		(layer "In13.Cu")
		(net "M_B_CPU0_SA_DQS_DN<2>")
	)
	(segment
		(start 311.61482 -224.167192)
		(end 312.026554 -223.755458)
		(width 0.16002)
		(layer "In13.Cu")
		(net "M_B_CPU0_SA_DQS_DN<2>")
	)
	(segment
		(start 313.677046 -225.12909)
		(end 313.873642 -225.325686)
		(width 0.16002)
		(layer "In13.Cu")
		(net "M_B_CPU0_SA_DQS_DN<2>")
	)
	(segment
		(start 313.461654 -226.541584)
		(end 313.834526 -226.914456)
		(width 0.16002)
		(layer "In13.Cu")
		(net "M_B_CPU0_SA_DQS_DN<2>")
	)
	(segment
		(start 321.950588 -235.036106)
		(end 323.895974 -235.036106)
		(width 0.16002)
		(layer "In13.Cu")
		(net "M_B_CPU0_SA_DQS_DN<2>")
	)
	(segment
		(start 310.241188 -222.79356)
		(end 310.652922 -222.381826)
		(width 0.16002)
		(layer "In13.Cu")
		(net "M_B_CPU0_SA_DQS_DN<2>")
	)
	(segment
		(start 324.637908 -235.710222)
		(end 324.993508 -235.710222)
		(width 0.09525)
		(layer "In13.Cu")
		(net "M_B_CPU0_SA_DQS_DN<2>")
	)
	(segment
		(start 300.106842 -220.002354)
		(end 302.465994 -220.002354)
		(width 0.16002)
		(layer "In13.Cu")
		(net "M_B_CPU0_SA_DQS_DN<2>")
	)
	(segment
		(start 327.481184 -236.86897)
		(end 327.506584 -236.883702)
		(width 0.09525)
		(layer "In13.Cu")
		(net "M_B_CPU0_SA_DQS_DN<2>")
	)
	(segment
		(start 327.081642 -236.882432)
		(end 327.10501 -236.86897)
		(width 0.09525)
		(layer "In13.Cu")
		(net "M_B_CPU0_SA_DQS_DN<2>")
	)
	(segment
		(start 312.088022 -224.640648)
		(end 312.088022 -225.167952)
		(width 0.16002)
		(layer "In13.Cu")
		(net "M_B_CPU0_SA_DQS_DN<2>")
	)
	(segment
		(start 311.087262 -224.167192)
		(end 311.61482 -224.167192)
		(width 0.16002)
		(layer "In13.Cu")
		(net "M_B_CPU0_SA_DQS_DN<2>")
	)
	(segment
		(start 312.026554 -223.755458)
		(end 312.303414 -223.755458)
		(width 0.16002)
		(layer "In13.Cu")
		(net "M_B_CPU0_SA_DQS_DN<2>")
	)
	(arc
		(start 331.239622 -236.86897)
		(mid 331.521054 -236.944725)
		(end 331.802486 -236.86897)
		(width 0.09525)
		(layer "In13.Cu")
		(net "M_B_CPU0_SA_DQS_DN<2>")
	)
	(arc
		(start 335.475834 -236.910118)
		(mid 335.486162 -236.906158)
		(end 335.496408 -236.90199)
		(width 0.09525)
		(layer "In13.Cu")
		(net "M_B_CPU0_SA_DQS_DN<2>")
	)
	(arc
		(start 327.506584 -236.883702)
		(mid 327.776438 -236.944581)
		(end 328.042524 -236.86897)
		(width 0.09525)
		(layer "In13.Cu")
		(net "M_B_CPU0_SA_DQS_DN<2>")
	)
	(arc
		(start 334.622648 -236.86897)
		(mid 334.811116 -236.818293)
		(end 334.999584 -236.86897)
		(width 0.09525)
		(layer "In13.Cu")
		(net "M_B_CPU0_SA_DQS_DN<2>")
	)
	(arc
		(start 326.540876 -236.86897)
		(mid 326.809539 -236.945188)
		(end 327.081642 -236.882432)
		(width 0.09525)
		(layer "In13.Cu")
		(net "M_B_CPU0_SA_DQS_DN<2>")
	)
	(arc
		(start 327.10501 -236.86897)
		(mid 327.284782 -236.818394)
		(end 327.466706 -236.860588)
		(width 0.09525)
		(layer "In13.Cu")
		(net "M_B_CPU0_SA_DQS_DN<2>")
	)
	(arc
		(start 331.802486 -236.86897)
		(mid 331.986261 -236.818198)
		(end 332.171294 -236.864144)
		(width 0.09525)
		(layer "In13.Cu")
		(net "M_B_CPU0_SA_DQS_DN<2>")
	)
	(arc
		(start 330.299568 -236.86897)
		(mid 330.581 -236.944725)
		(end 330.862432 -236.86897)
		(width 0.09525)
		(layer "In13.Cu")
		(net "M_B_CPU0_SA_DQS_DN<2>")
	)
	(arc
		(start 333.11973 -236.86897)
		(mid 333.401162 -236.944725)
		(end 333.682594 -236.86897)
		(width 0.09525)
		(layer "In13.Cu")
		(net "M_B_CPU0_SA_DQS_DN<2>")
	)
	(arc
		(start 332.750922 -236.864144)
		(mid 332.935954 -236.81823)
		(end 333.11973 -236.86897)
		(width 0.09525)
		(layer "In13.Cu")
		(net "M_B_CPU0_SA_DQS_DN<2>")
	)
	(arc
		(start 329.922632 -236.86897)
		(mid 330.1111 -236.818293)
		(end 330.299568 -236.86897)
		(width 0.09525)
		(layer "In13.Cu")
		(net "M_B_CPU0_SA_DQS_DN<2>")
	)
	(arc
		(start 328.042524 -236.86897)
		(mid 328.226299 -236.818198)
		(end 328.411332 -236.864144)
		(width 0.09525)
		(layer "In13.Cu")
		(net "M_B_CPU0_SA_DQS_DN<2>")
	)
	(arc
		(start 334.999584 -236.86897)
		(mid 335.233098 -236.942813)
		(end 335.475834 -236.910118)
		(width 0.09525)
		(layer "In13.Cu")
		(net "M_B_CPU0_SA_DQS_DN<2>")
	)
	(arc
		(start 333.690976 -236.864144)
		(mid 333.876008 -236.81823)
		(end 334.059784 -236.86897)
		(width 0.09525)
		(layer "In13.Cu")
		(net "M_B_CPU0_SA_DQS_DN<2>")
	)
	(arc
		(start 328.419714 -236.86897)
		(mid 328.701146 -236.944725)
		(end 328.982578 -236.86897)
		(width 0.09525)
		(layer "In13.Cu")
		(net "M_B_CPU0_SA_DQS_DN<2>")
	)
	(arc
		(start 328.99096 -236.864144)
		(mid 329.175992 -236.81823)
		(end 329.359768 -236.86897)
		(width 0.09525)
		(layer "In13.Cu")
		(net "M_B_CPU0_SA_DQS_DN<2>")
	)
	(arc
		(start 330.862432 -236.86897)
		(mid 331.046207 -236.818198)
		(end 331.23124 -236.864144)
		(width 0.09525)
		(layer "In13.Cu")
		(net "M_B_CPU0_SA_DQS_DN<2>")
	)
	(arc
		(start 332.179676 -236.86897)
		(mid 332.461108 -236.944725)
		(end 332.74254 -236.86897)
		(width 0.09525)
		(layer "In13.Cu")
		(net "M_B_CPU0_SA_DQS_DN<2>")
	)
	(arc
		(start 326.351138 -236.8169)
		(mid 326.449476 -236.830306)
		(end 326.540876 -236.86897)
		(width 0.09525)
		(layer "In13.Cu")
		(net "M_B_CPU0_SA_DQS_DN<2>")
	)
	(arc
		(start 329.359768 -236.86897)
		(mid 329.6412 -236.944725)
		(end 329.922632 -236.86897)
		(width 0.09525)
		(layer "In13.Cu")
		(net "M_B_CPU0_SA_DQS_DN<2>")
	)
	(arc
		(start 334.059784 -236.86897)
		(mid 334.341216 -236.944725)
		(end 334.622648 -236.86897)
		(width 0.09525)
		(layer "In13.Cu")
		(net "M_B_CPU0_SA_DQS_DN<2>")
	)
	(segment
		(start 336.218022 -232.599992)
		(end 335.75117 -232.334054)
		(width 0.12954)
		(layer "F.Cu")
		(net "M_B_CPU0_SA_DQS_DN<1>")
	)
	(segment
		(start 316.80277 -219.55252)
		(end 316.69609 -219.6592)
		(width 0.16002)
		(layer "In13.Cu")
		(net "M_B_CPU0_SA_DQS_DN<1>")
	)
	(segment
		(start 302.925734 -211.27085)
		(end 307.241194 -211.27085)
		(width 0.16002)
		(layer "In13.Cu")
		(net "M_B_CPU0_SA_DQS_DN<1>")
	)
	(segment
		(start 311.201562 -214.691976)
		(end 311.574434 -215.064848)
		(width 0.16002)
		(layer "In13.Cu")
		(net "M_B_CPU0_SA_DQS_DN<1>")
	)
	(segment
		(start 326.708008 -231.263952)
		(end 327.364598 -231.920542)
		(width 0.09525)
		(layer "In13.Cu")
		(net "M_B_CPU0_SA_DQS_DN<1>")
	)
	(segment
		(start 299.82414 -210.935062)
		(end 300.113192 -210.64601)
		(width 0.16002)
		(layer "In13.Cu")
		(net "M_B_CPU0_SA_DQS_DN<1>")
	)
	(segment
		(start 316.69609 -219.6592)
		(end 316.69609 -220.186504)
		(width 0.16002)
		(layer "In13.Cu")
		(net "M_B_CPU0_SA_DQS_DN<1>")
	)
	(segment
		(start 312.575194 -216.065608)
		(end 312.948066 -216.43848)
		(width 0.16002)
		(layer "In13.Cu")
		(net "M_B_CPU0_SA_DQS_DN<1>")
	)
	(segment
		(start 312.101738 -215.064848)
		(end 312.208418 -214.958168)
		(width 0.16002)
		(layer "In13.Cu")
		(net "M_B_CPU0_SA_DQS_DN<1>")
	)
	(segment
		(start 324.203314 -229.10292)
		(end 324.220078 -229.119684)
		(width 0.09525)
		(layer "In13.Cu")
		(net "M_B_CPU0_SA_DQS_DN<1>")
	)
	(segment
		(start 319.443354 -222.406464)
		(end 319.443354 -222.933768)
		(width 0.16002)
		(layer "In13.Cu")
		(net "M_B_CPU0_SA_DQS_DN<1>")
	)
	(segment
		(start 314.055506 -216.528396)
		(end 314.055506 -216.805256)
		(width 0.16002)
		(layer "In13.Cu")
		(net "M_B_CPU0_SA_DQS_DN<1>")
	)
	(segment
		(start 311.201562 -214.164672)
		(end 311.201562 -214.691976)
		(width 0.16002)
		(layer "In13.Cu")
		(net "M_B_CPU0_SA_DQS_DN<1>")
	)
	(segment
		(start 312.575194 -215.538304)
		(end 312.575194 -216.065608)
		(width 0.16002)
		(layer "In13.Cu")
		(net "M_B_CPU0_SA_DQS_DN<1>")
	)
	(segment
		(start 318.442594 -221.933008)
		(end 318.969898 -221.933008)
		(width 0.16002)
		(layer "In13.Cu")
		(net "M_B_CPU0_SA_DQS_DN<1>")
	)
	(segment
		(start 310.200802 -213.691216)
		(end 310.728106 -213.691216)
		(width 0.16002)
		(layer "In13.Cu")
		(net "M_B_CPU0_SA_DQS_DN<1>")
	)
	(segment
		(start 319.443354 -222.933768)
		(end 321.446398 -224.936812)
		(width 0.16002)
		(layer "In13.Cu")
		(net "M_B_CPU0_SA_DQS_DN<1>")
	)
	(segment
		(start 313.948826 -217.43924)
		(end 314.321698 -217.812112)
		(width 0.16002)
		(layer "In13.Cu")
		(net "M_B_CPU0_SA_DQS_DN<1>")
	)
	(segment
		(start 321.446398 -224.936812)
		(end 321.446398 -226.346004)
		(width 0.16002)
		(layer "In13.Cu")
		(net "M_B_CPU0_SA_DQS_DN<1>")
	)
	(segment
		(start 318.176402 -220.926152)
		(end 318.069722 -221.032832)
		(width 0.16002)
		(layer "In13.Cu")
		(net "M_B_CPU0_SA_DQS_DN<1>")
	)
	(segment
		(start 318.069722 -221.032832)
		(end 318.069722 -221.560136)
		(width 0.16002)
		(layer "In13.Cu")
		(net "M_B_CPU0_SA_DQS_DN<1>")
	)
	(segment
		(start 314.055506 -216.805256)
		(end 313.948826 -216.911936)
		(width 0.16002)
		(layer "In13.Cu")
		(net "M_B_CPU0_SA_DQS_DN<1>")
	)
	(segment
		(start 315.232542 -217.705432)
		(end 315.429138 -217.902028)
		(width 0.16002)
		(layer "In13.Cu")
		(net "M_B_CPU0_SA_DQS_DN<1>")
	)
	(segment
		(start 312.485278 -214.958168)
		(end 312.681874 -215.154764)
		(width 0.16002)
		(layer "In13.Cu")
		(net "M_B_CPU0_SA_DQS_DN<1>")
	)
	(segment
		(start 312.681874 -215.154764)
		(end 312.681874 -215.431624)
		(width 0.16002)
		(layer "In13.Cu")
		(net "M_B_CPU0_SA_DQS_DN<1>")
	)
	(segment
		(start 319.353438 -221.826328)
		(end 319.550034 -222.022924)
		(width 0.16002)
		(layer "In13.Cu")
		(net "M_B_CPU0_SA_DQS_DN<1>")
	)
	(segment
		(start 316.80277 -219.27566)
		(end 316.80277 -219.55252)
		(width 0.16002)
		(layer "In13.Cu")
		(net "M_B_CPU0_SA_DQS_DN<1>")
	)
	(segment
		(start 332.171294 -232.004108)
		(end 332.179676 -232.008934)
		(width 0.09525)
		(layer "In13.Cu")
		(net "M_B_CPU0_SA_DQS_DN<1>")
	)
	(segment
		(start 307.241194 -211.27085)
		(end 308.16169 -211.652104)
		(width 0.16002)
		(layer "In13.Cu")
		(net "M_B_CPU0_SA_DQS_DN<1>")
	)
	(segment
		(start 313.948826 -216.911936)
		(end 313.948826 -217.43924)
		(width 0.16002)
		(layer "In13.Cu")
		(net "M_B_CPU0_SA_DQS_DN<1>")
	)
	(segment
		(start 331.23124 -232.004108)
		(end 331.239622 -232.008934)
		(width 0.09525)
		(layer "In13.Cu")
		(net "M_B_CPU0_SA_DQS_DN<1>")
	)
	(segment
		(start 315.429138 -218.178888)
		(end 315.322458 -218.285568)
		(width 0.16002)
		(layer "In13.Cu")
		(net "M_B_CPU0_SA_DQS_DN<1>")
	)
	(segment
		(start 319.550034 -222.299784)
		(end 319.443354 -222.406464)
		(width 0.16002)
		(layer "In13.Cu")
		(net "M_B_CPU0_SA_DQS_DN<1>")
	)
	(segment
		(start 313.47537 -216.43848)
		(end 313.58205 -216.3318)
		(width 0.16002)
		(layer "In13.Cu")
		(net "M_B_CPU0_SA_DQS_DN<1>")
	)
	(segment
		(start 325.322438 -229.633272)
		(end 326.022208 -230.333042)
		(width 0.09525)
		(layer "In13.Cu")
		(net "M_B_CPU0_SA_DQS_DN<1>")
	)
	(segment
		(start 311.574434 -215.064848)
		(end 312.101738 -215.064848)
		(width 0.16002)
		(layer "In13.Cu")
		(net "M_B_CPU0_SA_DQS_DN<1>")
	)
	(segment
		(start 332.74254 -232.008934)
		(end 332.750922 -232.004108)
		(width 0.09525)
		(layer "In13.Cu")
		(net "M_B_CPU0_SA_DQS_DN<1>")
	)
	(segment
		(start 318.176402 -220.649292)
		(end 318.176402 -220.926152)
		(width 0.16002)
		(layer "In13.Cu")
		(net "M_B_CPU0_SA_DQS_DN<1>")
	)
	(segment
		(start 311.111646 -213.584536)
		(end 311.308242 -213.781132)
		(width 0.16002)
		(layer "In13.Cu")
		(net "M_B_CPU0_SA_DQS_DN<1>")
	)
	(segment
		(start 317.702946 -220.452696)
		(end 317.979806 -220.452696)
		(width 0.16002)
		(layer "In13.Cu")
		(net "M_B_CPU0_SA_DQS_DN<1>")
	)
	(segment
		(start 324.817486 -229.633272)
		(end 325.322438 -229.633272)
		(width 0.09525)
		(layer "In13.Cu")
		(net "M_B_CPU0_SA_DQS_DN<1>")
	)
	(segment
		(start 317.979806 -220.452696)
		(end 318.176402 -220.649292)
		(width 0.16002)
		(layer "In13.Cu")
		(net "M_B_CPU0_SA_DQS_DN<1>")
	)
	(segment
		(start 308.16169 -211.652104)
		(end 310.200802 -213.691216)
		(width 0.16002)
		(layer "In13.Cu")
		(net "M_B_CPU0_SA_DQS_DN<1>")
	)
	(segment
		(start 326.475344 -230.333042)
		(end 326.708008 -230.565706)
		(width 0.09525)
		(layer "In13.Cu")
		(net "M_B_CPU0_SA_DQS_DN<1>")
	)
	(segment
		(start 315.69533 -219.185744)
		(end 316.222634 -219.185744)
		(width 0.16002)
		(layer "In13.Cu")
		(net "M_B_CPU0_SA_DQS_DN<1>")
	)
	(segment
		(start 318.969898 -221.933008)
		(end 319.076578 -221.826328)
		(width 0.16002)
		(layer "In13.Cu")
		(net "M_B_CPU0_SA_DQS_DN<1>")
	)
	(segment
		(start 326.708008 -230.565706)
		(end 326.708008 -231.263952)
		(width 0.09525)
		(layer "In13.Cu")
		(net "M_B_CPU0_SA_DQS_DN<1>")
	)
	(segment
		(start 315.322458 -218.812872)
		(end 315.69533 -219.185744)
		(width 0.16002)
		(layer "In13.Cu")
		(net "M_B_CPU0_SA_DQS_DN<1>")
	)
	(segment
		(start 314.955682 -217.705432)
		(end 315.232542 -217.705432)
		(width 0.16002)
		(layer "In13.Cu")
		(net "M_B_CPU0_SA_DQS_DN<1>")
	)
	(segment
		(start 319.550034 -222.022924)
		(end 319.550034 -222.299784)
		(width 0.16002)
		(layer "In13.Cu")
		(net "M_B_CPU0_SA_DQS_DN<1>")
	)
	(segment
		(start 310.834786 -213.584536)
		(end 311.111646 -213.584536)
		(width 0.16002)
		(layer "In13.Cu")
		(net "M_B_CPU0_SA_DQS_DN<1>")
	)
	(segment
		(start 316.69609 -220.186504)
		(end 317.068962 -220.559376)
		(width 0.16002)
		(layer "In13.Cu")
		(net "M_B_CPU0_SA_DQS_DN<1>")
	)
	(segment
		(start 315.322458 -218.285568)
		(end 315.322458 -218.812872)
		(width 0.16002)
		(layer "In13.Cu")
		(net "M_B_CPU0_SA_DQS_DN<1>")
	)
	(segment
		(start 314.849002 -217.812112)
		(end 314.955682 -217.705432)
		(width 0.16002)
		(layer "In13.Cu")
		(net "M_B_CPU0_SA_DQS_DN<1>")
	)
	(segment
		(start 328.982578 -232.008934)
		(end 328.99096 -232.004108)
		(width 0.09525)
		(layer "In13.Cu")
		(net "M_B_CPU0_SA_DQS_DN<1>")
	)
	(segment
		(start 313.85891 -216.3318)
		(end 314.055506 -216.528396)
		(width 0.16002)
		(layer "In13.Cu")
		(net "M_B_CPU0_SA_DQS_DN<1>")
	)
	(segment
		(start 302.300894 -210.64601)
		(end 302.925734 -211.27085)
		(width 0.16002)
		(layer "In13.Cu")
		(net "M_B_CPU0_SA_DQS_DN<1>")
	)
	(segment
		(start 316.606174 -219.079064)
		(end 316.80277 -219.27566)
		(width 0.16002)
		(layer "In13.Cu")
		(net "M_B_CPU0_SA_DQS_DN<1>")
	)
	(segment
		(start 312.948066 -216.43848)
		(end 313.47537 -216.43848)
		(width 0.16002)
		(layer "In13.Cu")
		(net "M_B_CPU0_SA_DQS_DN<1>")
	)
	(segment
		(start 312.681874 -215.431624)
		(end 312.575194 -215.538304)
		(width 0.16002)
		(layer "In13.Cu")
		(net "M_B_CPU0_SA_DQS_DN<1>")
	)
	(segment
		(start 315.429138 -217.902028)
		(end 315.429138 -218.178888)
		(width 0.16002)
		(layer "In13.Cu")
		(net "M_B_CPU0_SA_DQS_DN<1>")
	)
	(segment
		(start 300.113192 -210.64601)
		(end 302.300894 -210.64601)
		(width 0.16002)
		(layer "In13.Cu")
		(net "M_B_CPU0_SA_DQS_DN<1>")
	)
	(segment
		(start 321.446398 -226.346004)
		(end 324.203314 -229.10292)
		(width 0.16002)
		(layer "In13.Cu")
		(net "M_B_CPU0_SA_DQS_DN<1>")
	)
	(segment
		(start 326.022208 -230.333042)
		(end 326.475344 -230.333042)
		(width 0.09525)
		(layer "In13.Cu")
		(net "M_B_CPU0_SA_DQS_DN<1>")
	)
	(segment
		(start 316.329314 -219.079064)
		(end 316.606174 -219.079064)
		(width 0.16002)
		(layer "In13.Cu")
		(net "M_B_CPU0_SA_DQS_DN<1>")
	)
	(segment
		(start 310.728106 -213.691216)
		(end 310.834786 -213.584536)
		(width 0.16002)
		(layer "In13.Cu")
		(net "M_B_CPU0_SA_DQS_DN<1>")
	)
	(segment
		(start 319.076578 -221.826328)
		(end 319.353438 -221.826328)
		(width 0.16002)
		(layer "In13.Cu")
		(net "M_B_CPU0_SA_DQS_DN<1>")
	)
	(segment
		(start 324.303898 -229.119684)
		(end 324.817486 -229.633272)
		(width 0.09525)
		(layer "In13.Cu")
		(net "M_B_CPU0_SA_DQS_DN<1>")
	)
	(segment
		(start 316.222634 -219.185744)
		(end 316.329314 -219.079064)
		(width 0.16002)
		(layer "In13.Cu")
		(net "M_B_CPU0_SA_DQS_DN<1>")
	)
	(segment
		(start 313.58205 -216.3318)
		(end 313.85891 -216.3318)
		(width 0.16002)
		(layer "In13.Cu")
		(net "M_B_CPU0_SA_DQS_DN<1>")
	)
	(segment
		(start 312.208418 -214.958168)
		(end 312.485278 -214.958168)
		(width 0.16002)
		(layer "In13.Cu")
		(net "M_B_CPU0_SA_DQS_DN<1>")
	)
	(segment
		(start 333.682594 -232.008934)
		(end 333.690976 -232.004108)
		(width 0.09525)
		(layer "In13.Cu")
		(net "M_B_CPU0_SA_DQS_DN<1>")
	)
	(segment
		(start 318.069722 -221.560136)
		(end 318.442594 -221.933008)
		(width 0.16002)
		(layer "In13.Cu")
		(net "M_B_CPU0_SA_DQS_DN<1>")
	)
	(segment
		(start 311.308242 -214.057992)
		(end 311.201562 -214.164672)
		(width 0.16002)
		(layer "In13.Cu")
		(net "M_B_CPU0_SA_DQS_DN<1>")
	)
	(segment
		(start 311.308242 -213.781132)
		(end 311.308242 -214.057992)
		(width 0.16002)
		(layer "In13.Cu")
		(net "M_B_CPU0_SA_DQS_DN<1>")
	)
	(segment
		(start 324.220078 -229.119684)
		(end 324.303898 -229.119684)
		(width 0.09525)
		(layer "In13.Cu")
		(net "M_B_CPU0_SA_DQS_DN<1>")
	)
	(segment
		(start 314.321698 -217.812112)
		(end 314.849002 -217.812112)
		(width 0.16002)
		(layer "In13.Cu")
		(net "M_B_CPU0_SA_DQS_DN<1>")
	)
	(segment
		(start 335.597246 -232.068624)
		(end 335.75117 -232.334054)
		(width 0.09525)
		(layer "In13.Cu")
		(net "M_B_CPU0_SA_DQS_DN<1>")
	)
	(segment
		(start 335.496408 -232.041954)
		(end 335.597246 -232.068624)
		(width 0.09525)
		(layer "In13.Cu")
		(net "M_B_CPU0_SA_DQS_DN<1>")
	)
	(segment
		(start 317.596266 -220.559376)
		(end 317.702946 -220.452696)
		(width 0.16002)
		(layer "In13.Cu")
		(net "M_B_CPU0_SA_DQS_DN<1>")
	)
	(segment
		(start 317.068962 -220.559376)
		(end 317.596266 -220.559376)
		(width 0.16002)
		(layer "In13.Cu")
		(net "M_B_CPU0_SA_DQS_DN<1>")
	)
	(segment
		(start 328.411332 -232.004108)
		(end 328.419714 -232.008934)
		(width 0.09525)
		(layer "In13.Cu")
		(net "M_B_CPU0_SA_DQS_DN<1>")
	)
	(arc
		(start 332.750922 -232.004108)
		(mid 332.935954 -231.958194)
		(end 333.11973 -232.008934)
		(width 0.09525)
		(layer "In13.Cu")
		(net "M_B_CPU0_SA_DQS_DN<1>")
	)
	(arc
		(start 328.99096 -232.004108)
		(mid 329.175992 -231.958194)
		(end 329.359768 -232.008934)
		(width 0.09525)
		(layer "In13.Cu")
		(net "M_B_CPU0_SA_DQS_DN<1>")
	)
	(arc
		(start 329.922632 -232.008934)
		(mid 330.1111 -231.958257)
		(end 330.299568 -232.008934)
		(width 0.09525)
		(layer "In13.Cu")
		(net "M_B_CPU0_SA_DQS_DN<1>")
	)
	(arc
		(start 334.622648 -232.008934)
		(mid 334.811116 -231.958257)
		(end 334.999584 -232.008934)
		(width 0.09525)
		(layer "In13.Cu")
		(net "M_B_CPU0_SA_DQS_DN<1>")
	)
	(arc
		(start 333.690976 -232.004108)
		(mid 333.876008 -231.958194)
		(end 334.059784 -232.008934)
		(width 0.09525)
		(layer "In13.Cu")
		(net "M_B_CPU0_SA_DQS_DN<1>")
	)
	(arc
		(start 331.802486 -232.008934)
		(mid 331.986261 -231.958162)
		(end 332.171294 -232.004108)
		(width 0.09525)
		(layer "In13.Cu")
		(net "M_B_CPU0_SA_DQS_DN<1>")
	)
	(arc
		(start 328.042524 -232.008934)
		(mid 328.226299 -231.958162)
		(end 328.411332 -232.004108)
		(width 0.09525)
		(layer "In13.Cu")
		(net "M_B_CPU0_SA_DQS_DN<1>")
	)
	(arc
		(start 331.239622 -232.008934)
		(mid 331.521054 -232.084689)
		(end 331.802486 -232.008934)
		(width 0.09525)
		(layer "In13.Cu")
		(net "M_B_CPU0_SA_DQS_DN<1>")
	)
	(arc
		(start 332.179676 -232.008934)
		(mid 332.461108 -232.084689)
		(end 332.74254 -232.008934)
		(width 0.09525)
		(layer "In13.Cu")
		(net "M_B_CPU0_SA_DQS_DN<1>")
	)
	(arc
		(start 333.11973 -232.008934)
		(mid 333.401162 -232.084689)
		(end 333.682594 -232.008934)
		(width 0.09525)
		(layer "In13.Cu")
		(net "M_B_CPU0_SA_DQS_DN<1>")
	)
	(arc
		(start 335.475834 -232.050082)
		(mid 335.486162 -232.046122)
		(end 335.496408 -232.041954)
		(width 0.09525)
		(layer "In13.Cu")
		(net "M_B_CPU0_SA_DQS_DN<1>")
	)
	(arc
		(start 328.419714 -232.008934)
		(mid 328.701146 -232.084689)
		(end 328.982578 -232.008934)
		(width 0.09525)
		(layer "In13.Cu")
		(net "M_B_CPU0_SA_DQS_DN<1>")
	)
	(arc
		(start 330.862432 -232.008934)
		(mid 331.046207 -231.958162)
		(end 331.23124 -232.004108)
		(width 0.09525)
		(layer "In13.Cu")
		(net "M_B_CPU0_SA_DQS_DN<1>")
	)
	(arc
		(start 334.999584 -232.008934)
		(mid 335.233098 -232.082777)
		(end 335.475834 -232.050082)
		(width 0.09525)
		(layer "In13.Cu")
		(net "M_B_CPU0_SA_DQS_DN<1>")
	)
	(arc
		(start 334.059784 -232.008934)
		(mid 334.341216 -232.084689)
		(end 334.622648 -232.008934)
		(width 0.09525)
		(layer "In13.Cu")
		(net "M_B_CPU0_SA_DQS_DN<1>")
	)
	(arc
		(start 327.47966 -232.008934)
		(mid 327.761092 -232.084689)
		(end 328.042524 -232.008934)
		(width 0.09525)
		(layer "In13.Cu")
		(net "M_B_CPU0_SA_DQS_DN<1>")
	)
	(arc
		(start 329.359768 -232.008934)
		(mid 329.6412 -232.084689)
		(end 329.922632 -232.008934)
		(width 0.09525)
		(layer "In13.Cu")
		(net "M_B_CPU0_SA_DQS_DN<1>")
	)
	(arc
		(start 327.364598 -231.920542)
		(mid 327.41926 -231.968473)
		(end 327.47966 -232.008934)
		(width 0.09525)
		(layer "In13.Cu")
		(net "M_B_CPU0_SA_DQS_DN<1>")
	)
	(arc
		(start 330.299568 -232.008934)
		(mid 330.581 -232.084689)
		(end 330.862432 -232.008934)
		(width 0.09525)
		(layer "In13.Cu")
		(net "M_B_CPU0_SA_DQS_DN<1>")
	)
	(segment
		(start 336.218022 -227.74021)
		(end 335.75117 -227.474272)
		(width 0.12954)
		(layer "F.Cu")
		(net "M_B_CPU0_SA_DQS_DN<0>")
	)
	(segment
		(start 299.82414 -201.585068)
		(end 300.14545 -201.263758)
		(width 0.16002)
		(layer "In13.Cu")
		(net "M_B_CPU0_SA_DQS_DN<0>")
	)
	(segment
		(start 315.29147 -209.307684)
		(end 315.692536 -209.70875)
		(width 0.16002)
		(layer "In13.Cu")
		(net "M_B_CPU0_SA_DQS_DN<0>")
	)
	(segment
		(start 324.906894 -218.173808)
		(end 324.906894 -218.923108)
		(width 0.16002)
		(layer "In13.Cu")
		(net "M_B_CPU0_SA_DQS_DN<0>")
	)
	(segment
		(start 310.947308 -204.214222)
		(end 311.170574 -204.437488)
		(width 0.16002)
		(layer "In13.Cu")
		(net "M_B_CPU0_SA_DQS_DN<0>")
	)
	(segment
		(start 335.597246 -227.208842)
		(end 335.75117 -227.474272)
		(width 0.09525)
		(layer "In13.Cu")
		(net "M_B_CPU0_SA_DQS_DN<0>")
	)
	(segment
		(start 321.187064 -215.203278)
		(end 321.936364 -215.203278)
		(width 0.16002)
		(layer "In13.Cu")
		(net "M_B_CPU0_SA_DQS_DN<0>")
	)
	(segment
		(start 319.1891 -212.456014)
		(end 319.412366 -212.67928)
		(width 0.16002)
		(layer "In13.Cu")
		(net "M_B_CPU0_SA_DQS_DN<0>")
	)
	(segment
		(start 309.796942 -203.813156)
		(end 310.198008 -204.214222)
		(width 0.16002)
		(layer "In13.Cu")
		(net "M_B_CPU0_SA_DQS_DN<0>")
	)
	(segment
		(start 316.665102 -210.681316)
		(end 317.066168 -211.082382)
		(width 0.16002)
		(layer "In13.Cu")
		(net "M_B_CPU0_SA_DQS_DN<0>")
	)
	(segment
		(start 320.785998 -214.052912)
		(end 320.785998 -214.802212)
		(width 0.16002)
		(layer "In13.Cu")
		(net "M_B_CPU0_SA_DQS_DN<0>")
	)
	(segment
		(start 319.412366 -213.42858)
		(end 319.813432 -213.829646)
		(width 0.16002)
		(layer "In13.Cu")
		(net "M_B_CPU0_SA_DQS_DN<0>")
	)
	(segment
		(start 323.309996 -216.57691)
		(end 323.533262 -216.800176)
		(width 0.16002)
		(layer "In13.Cu")
		(net "M_B_CPU0_SA_DQS_DN<0>")
	)
	(segment
		(start 314.318904 -208.335118)
		(end 315.068204 -208.335118)
		(width 0.16002)
		(layer "In13.Cu")
		(net "M_B_CPU0_SA_DQS_DN<0>")
	)
	(segment
		(start 316.665102 -209.932016)
		(end 316.665102 -210.681316)
		(width 0.16002)
		(layer "In13.Cu")
		(net "M_B_CPU0_SA_DQS_DN<0>")
	)
	(segment
		(start 313.917838 -207.934052)
		(end 314.318904 -208.335118)
		(width 0.16002)
		(layer "In13.Cu")
		(net "M_B_CPU0_SA_DQS_DN<0>")
	)
	(segment
		(start 311.170574 -204.437488)
		(end 311.170574 -205.186788)
		(width 0.16002)
		(layer "In13.Cu")
		(net "M_B_CPU0_SA_DQS_DN<0>")
	)
	(segment
		(start 321.936364 -215.203278)
		(end 322.15963 -215.426544)
		(width 0.16002)
		(layer "In13.Cu")
		(net "M_B_CPU0_SA_DQS_DN<0>")
	)
	(segment
		(start 329.829668 -226.339146)
		(end 329.86218 -226.357942)
		(width 0.09525)
		(layer "In13.Cu")
		(net "M_B_CPU0_SA_DQS_DN<0>")
	)
	(segment
		(start 315.068204 -208.335118)
		(end 315.29147 -208.558384)
		(width 0.16002)
		(layer "In13.Cu")
		(net "M_B_CPU0_SA_DQS_DN<0>")
	)
	(segment
		(start 300.14545 -201.263758)
		(end 302.38954 -201.263758)
		(width 0.16002)
		(layer "In13.Cu")
		(net "M_B_CPU0_SA_DQS_DN<0>")
	)
	(segment
		(start 304.033174 -201.263758)
		(end 305.646582 -201.932032)
		(width 0.16002)
		(layer "In13.Cu")
		(net "M_B_CPU0_SA_DQS_DN<0>")
	)
	(segment
		(start 328.854562 -224.69856)
		(end 328.856594 -224.69983)
		(width 0.09525)
		(layer "In13.Cu")
		(net "M_B_CPU0_SA_DQS_DN<0>")
	)
	(segment
		(start 308.665118 -201.932032)
		(end 309.796942 -203.063856)
		(width 0.16002)
		(layer "In13.Cu")
		(net "M_B_CPU0_SA_DQS_DN<0>")
	)
	(segment
		(start 327.479914 -222.289116)
		(end 327.512426 -222.307912)
		(width 0.09525)
		(layer "In13.Cu")
		(net "M_B_CPU0_SA_DQS_DN<0>")
	)
	(segment
		(start 332.171294 -227.144326)
		(end 332.179676 -227.149152)
		(width 0.09525)
		(layer "In13.Cu")
		(net "M_B_CPU0_SA_DQS_DN<0>")
	)
	(segment
		(start 309.796942 -203.063856)
		(end 309.796942 -203.813156)
		(width 0.16002)
		(layer "In13.Cu")
		(net "M_B_CPU0_SA_DQS_DN<0>")
	)
	(segment
		(start 319.412366 -212.67928)
		(end 319.412366 -213.42858)
		(width 0.16002)
		(layer "In13.Cu")
		(net "M_B_CPU0_SA_DQS_DN<0>")
	)
	(segment
		(start 310.198008 -204.214222)
		(end 310.947308 -204.214222)
		(width 0.16002)
		(layer "In13.Cu")
		(net "M_B_CPU0_SA_DQS_DN<0>")
	)
	(segment
		(start 319.813432 -213.829646)
		(end 320.562732 -213.829646)
		(width 0.16002)
		(layer "In13.Cu")
		(net "M_B_CPU0_SA_DQS_DN<0>")
	)
	(segment
		(start 328.856594 -224.69983)
		(end 328.889614 -224.719134)
		(width 0.09525)
		(layer "In13.Cu")
		(net "M_B_CPU0_SA_DQS_DN<0>")
	)
	(segment
		(start 317.066168 -211.082382)
		(end 317.815468 -211.082382)
		(width 0.16002)
		(layer "In13.Cu")
		(net "M_B_CPU0_SA_DQS_DN<0>")
	)
	(segment
		(start 318.038734 -212.054948)
		(end 318.4398 -212.456014)
		(width 0.16002)
		(layer "In13.Cu")
		(net "M_B_CPU0_SA_DQS_DN<0>")
	)
	(segment
		(start 302.38954 -201.263758)
		(end 302.50638 -201.380598)
		(width 0.16002)
		(layer "In13.Cu")
		(net "M_B_CPU0_SA_DQS_DN<0>")
	)
	(segment
		(start 327.139554 -221.31655)
		(end 327.139554 -221.340172)
		(width 0.09525)
		(layer "In13.Cu")
		(net "M_B_CPU0_SA_DQS_DN<0>")
	)
	(segment
		(start 312.544206 -206.56042)
		(end 312.945272 -206.961486)
		(width 0.16002)
		(layer "In13.Cu")
		(net "M_B_CPU0_SA_DQS_DN<0>")
	)
	(segment
		(start 325.30796 -219.324174)
		(end 326.05726 -219.324174)
		(width 0.16002)
		(layer "In13.Cu")
		(net "M_B_CPU0_SA_DQS_DN<0>")
	)
	(segment
		(start 335.496408 -227.182172)
		(end 335.597246 -227.208842)
		(width 0.09525)
		(layer "In13.Cu")
		(net "M_B_CPU0_SA_DQS_DN<0>")
	)
	(segment
		(start 327.139554 -221.340172)
		(end 327.198736 -221.399354)
		(width 0.09525)
		(layer "In13.Cu")
		(net "M_B_CPU0_SA_DQS_DN<0>")
	)
	(segment
		(start 303.10328 -201.263758)
		(end 304.033174 -201.263758)
		(width 0.16002)
		(layer "In13.Cu")
		(net "M_B_CPU0_SA_DQS_DN<0>")
	)
	(segment
		(start 313.917838 -207.184752)
		(end 313.917838 -207.934052)
		(width 0.16002)
		(layer "In13.Cu")
		(net "M_B_CPU0_SA_DQS_DN<0>")
	)
	(segment
		(start 322.560696 -216.57691)
		(end 323.309996 -216.57691)
		(width 0.16002)
		(layer "In13.Cu")
		(net "M_B_CPU0_SA_DQS_DN<0>")
	)
	(segment
		(start 317.815468 -211.082382)
		(end 318.038734 -211.305648)
		(width 0.16002)
		(layer "In13.Cu")
		(net "M_B_CPU0_SA_DQS_DN<0>")
	)
	(segment
		(start 312.32094 -205.587854)
		(end 312.544206 -205.81112)
		(width 0.16002)
		(layer "In13.Cu")
		(net "M_B_CPU0_SA_DQS_DN<0>")
	)
	(segment
		(start 313.694572 -206.961486)
		(end 313.917838 -207.184752)
		(width 0.16002)
		(layer "In13.Cu")
		(net "M_B_CPU0_SA_DQS_DN<0>")
	)
	(segment
		(start 312.945272 -206.961486)
		(end 313.694572 -206.961486)
		(width 0.16002)
		(layer "In13.Cu")
		(net "M_B_CPU0_SA_DQS_DN<0>")
	)
	(segment
		(start 324.906894 -218.923108)
		(end 325.30796 -219.324174)
		(width 0.16002)
		(layer "In13.Cu")
		(net "M_B_CPU0_SA_DQS_DN<0>")
	)
	(segment
		(start 327.911968 -223.077024)
		(end 327.950068 -223.099122)
		(width 0.09525)
		(layer "In13.Cu")
		(net "M_B_CPU0_SA_DQS_DN<0>")
	)
	(segment
		(start 327.198736 -221.399354)
		(end 327.198736 -221.80423)
		(width 0.09525)
		(layer "In13.Cu")
		(net "M_B_CPU0_SA_DQS_DN<0>")
	)
	(segment
		(start 327.950068 -223.099122)
		(end 327.981564 -223.11741)
		(width 0.09525)
		(layer "In13.Cu")
		(net "M_B_CPU0_SA_DQS_DN<0>")
	)
	(segment
		(start 333.682594 -227.149152)
		(end 333.690976 -227.144326)
		(width 0.09525)
		(layer "In13.Cu")
		(net "M_B_CPU0_SA_DQS_DN<0>")
	)
	(segment
		(start 318.038734 -211.305648)
		(end 318.038734 -212.054948)
		(width 0.16002)
		(layer "In13.Cu")
		(net "M_B_CPU0_SA_DQS_DN<0>")
	)
	(segment
		(start 311.57164 -205.587854)
		(end 312.32094 -205.587854)
		(width 0.16002)
		(layer "In13.Cu")
		(net "M_B_CPU0_SA_DQS_DN<0>")
	)
	(segment
		(start 322.15963 -216.175844)
		(end 322.560696 -216.57691)
		(width 0.16002)
		(layer "In13.Cu")
		(net "M_B_CPU0_SA_DQS_DN<0>")
	)
	(segment
		(start 315.692536 -209.70875)
		(end 316.441836 -209.70875)
		(width 0.16002)
		(layer "In13.Cu")
		(net "M_B_CPU0_SA_DQS_DN<0>")
	)
	(segment
		(start 316.441836 -209.70875)
		(end 316.665102 -209.932016)
		(width 0.16002)
		(layer "In13.Cu")
		(net "M_B_CPU0_SA_DQS_DN<0>")
	)
	(segment
		(start 328.386694 -223.889824)
		(end 328.419714 -223.909128)
		(width 0.09525)
		(layer "In13.Cu")
		(net "M_B_CPU0_SA_DQS_DN<0>")
	)
	(segment
		(start 329.321668 -225.507042)
		(end 329.359768 -225.52914)
		(width 0.09525)
		(layer "In13.Cu")
		(net "M_B_CPU0_SA_DQS_DN<0>")
	)
	(segment
		(start 302.98644 -201.380598)
		(end 303.10328 -201.263758)
		(width 0.16002)
		(layer "In13.Cu")
		(net "M_B_CPU0_SA_DQS_DN<0>")
	)
	(segment
		(start 311.170574 -205.186788)
		(end 311.57164 -205.587854)
		(width 0.16002)
		(layer "In13.Cu")
		(net "M_B_CPU0_SA_DQS_DN<0>")
	)
	(segment
		(start 324.683628 -217.950542)
		(end 324.906894 -218.173808)
		(width 0.16002)
		(layer "In13.Cu")
		(net "M_B_CPU0_SA_DQS_DN<0>")
	)
	(segment
		(start 331.23124 -227.144326)
		(end 331.239622 -227.149152)
		(width 0.09525)
		(layer "In13.Cu")
		(net "M_B_CPU0_SA_DQS_DN<0>")
	)
	(segment
		(start 327.440544 -222.266256)
		(end 327.479914 -222.289116)
		(width 0.09525)
		(layer "In13.Cu")
		(net "M_B_CPU0_SA_DQS_DN<0>")
	)
	(segment
		(start 327.139554 -220.406468)
		(end 327.139554 -221.31655)
		(width 0.16002)
		(layer "In13.Cu")
		(net "M_B_CPU0_SA_DQS_DN<0>")
	)
	(segment
		(start 328.889614 -224.719134)
		(end 328.922126 -224.73793)
		(width 0.09525)
		(layer "In13.Cu")
		(net "M_B_CPU0_SA_DQS_DN<0>")
	)
	(segment
		(start 323.533262 -217.549476)
		(end 323.934328 -217.950542)
		(width 0.16002)
		(layer "In13.Cu")
		(net "M_B_CPU0_SA_DQS_DN<0>")
	)
	(segment
		(start 320.562732 -213.829646)
		(end 320.785998 -214.052912)
		(width 0.16002)
		(layer "In13.Cu")
		(net "M_B_CPU0_SA_DQS_DN<0>")
	)
	(segment
		(start 320.785998 -214.802212)
		(end 321.187064 -215.203278)
		(width 0.16002)
		(layer "In13.Cu")
		(net "M_B_CPU0_SA_DQS_DN<0>")
	)
	(segment
		(start 323.934328 -217.950542)
		(end 324.683628 -217.950542)
		(width 0.16002)
		(layer "In13.Cu")
		(net "M_B_CPU0_SA_DQS_DN<0>")
	)
	(segment
		(start 330.266548 -227.129848)
		(end 330.299568 -227.149152)
		(width 0.09525)
		(layer "In13.Cu")
		(net "M_B_CPU0_SA_DQS_DN<0>")
	)
	(segment
		(start 329.791568 -226.317048)
		(end 329.829668 -226.339146)
		(width 0.09525)
		(layer "In13.Cu")
		(net "M_B_CPU0_SA_DQS_DN<0>")
	)
	(segment
		(start 326.05726 -219.324174)
		(end 327.139554 -220.406468)
		(width 0.16002)
		(layer "In13.Cu")
		(net "M_B_CPU0_SA_DQS_DN<0>")
	)
	(segment
		(start 328.419714 -223.909128)
		(end 328.452226 -223.927924)
		(width 0.09525)
		(layer "In13.Cu")
		(net "M_B_CPU0_SA_DQS_DN<0>")
	)
	(segment
		(start 323.533262 -216.800176)
		(end 323.533262 -217.549476)
		(width 0.16002)
		(layer "In13.Cu")
		(net "M_B_CPU0_SA_DQS_DN<0>")
	)
	(segment
		(start 329.359768 -225.52914)
		(end 329.391264 -225.547428)
		(width 0.09525)
		(layer "In13.Cu")
		(net "M_B_CPU0_SA_DQS_DN<0>")
	)
	(segment
		(start 332.74254 -227.149152)
		(end 332.750922 -227.144326)
		(width 0.09525)
		(layer "In13.Cu")
		(net "M_B_CPU0_SA_DQS_DN<0>")
	)
	(segment
		(start 315.29147 -208.558384)
		(end 315.29147 -209.307684)
		(width 0.16002)
		(layer "In13.Cu")
		(net "M_B_CPU0_SA_DQS_DN<0>")
	)
	(segment
		(start 328.384662 -223.888554)
		(end 328.386694 -223.889824)
		(width 0.09525)
		(layer "In13.Cu")
		(net "M_B_CPU0_SA_DQS_DN<0>")
	)
	(segment
		(start 302.50638 -201.380598)
		(end 302.98644 -201.380598)
		(width 0.16002)
		(layer "In13.Cu")
		(net "M_B_CPU0_SA_DQS_DN<0>")
	)
	(segment
		(start 318.4398 -212.456014)
		(end 319.1891 -212.456014)
		(width 0.16002)
		(layer "In13.Cu")
		(net "M_B_CPU0_SA_DQS_DN<0>")
	)
	(segment
		(start 330.264516 -227.128578)
		(end 330.266548 -227.129848)
		(width 0.09525)
		(layer "In13.Cu")
		(net "M_B_CPU0_SA_DQS_DN<0>")
	)
	(segment
		(start 312.544206 -205.81112)
		(end 312.544206 -206.56042)
		(width 0.16002)
		(layer "In13.Cu")
		(net "M_B_CPU0_SA_DQS_DN<0>")
	)
	(segment
		(start 322.15963 -215.426544)
		(end 322.15963 -216.175844)
		(width 0.16002)
		(layer "In13.Cu")
		(net "M_B_CPU0_SA_DQS_DN<0>")
	)
	(segment
		(start 305.646582 -201.932032)
		(end 308.665118 -201.932032)
		(width 0.16002)
		(layer "In13.Cu")
		(net "M_B_CPU0_SA_DQS_DN<0>")
	)
	(arc
		(start 327.981564 -223.11741)
		(mid 328.097362 -223.251804)
		(end 328.139044 -223.424242)
		(width 0.09525)
		(layer "In13.Cu")
		(net "M_B_CPU0_SA_DQS_DN<0>")
	)
	(arc
		(start 330.018898 -226.664266)
		(mid 330.084091 -226.926895)
		(end 330.264516 -227.128578)
		(width 0.09525)
		(layer "In13.Cu")
		(net "M_B_CPU0_SA_DQS_DN<0>")
	)
	(arc
		(start 330.862432 -227.149152)
		(mid 331.046207 -227.09838)
		(end 331.23124 -227.144326)
		(width 0.09525)
		(layer "In13.Cu")
		(net "M_B_CPU0_SA_DQS_DN<0>")
	)
	(arc
		(start 334.999584 -227.149152)
		(mid 335.233098 -227.222995)
		(end 335.475834 -227.1903)
		(width 0.09525)
		(layer "In13.Cu")
		(net "M_B_CPU0_SA_DQS_DN<0>")
	)
	(arc
		(start 327.669144 -222.614236)
		(mid 327.733541 -222.875542)
		(end 327.911968 -223.077024)
		(width 0.09525)
		(layer "In13.Cu")
		(net "M_B_CPU0_SA_DQS_DN<0>")
	)
	(arc
		(start 329.078844 -225.044254)
		(mid 329.143241 -225.30556)
		(end 329.321668 -225.507042)
		(width 0.09525)
		(layer "In13.Cu")
		(net "M_B_CPU0_SA_DQS_DN<0>")
	)
	(arc
		(start 332.750922 -227.144326)
		(mid 332.935954 -227.098412)
		(end 333.11973 -227.149152)
		(width 0.09525)
		(layer "In13.Cu")
		(net "M_B_CPU0_SA_DQS_DN<0>")
	)
	(arc
		(start 328.608944 -224.234248)
		(mid 328.674137 -224.496877)
		(end 328.854562 -224.69856)
		(width 0.09525)
		(layer "In13.Cu")
		(net "M_B_CPU0_SA_DQS_DN<0>")
	)
	(arc
		(start 333.690976 -227.144326)
		(mid 333.876008 -227.098412)
		(end 334.059784 -227.149152)
		(width 0.09525)
		(layer "In13.Cu")
		(net "M_B_CPU0_SA_DQS_DN<0>")
	)
	(arc
		(start 329.86218 -226.357942)
		(mid 329.977454 -226.49222)
		(end 330.018898 -226.664266)
		(width 0.09525)
		(layer "In13.Cu")
		(net "M_B_CPU0_SA_DQS_DN<0>")
	)
	(arc
		(start 329.391264 -225.547428)
		(mid 329.507062 -225.681822)
		(end 329.548744 -225.85426)
		(width 0.09525)
		(layer "In13.Cu")
		(net "M_B_CPU0_SA_DQS_DN<0>")
	)
	(arc
		(start 334.059784 -227.149152)
		(mid 334.341216 -227.224907)
		(end 334.622648 -227.149152)
		(width 0.09525)
		(layer "In13.Cu")
		(net "M_B_CPU0_SA_DQS_DN<0>")
	)
	(arc
		(start 333.11973 -227.149152)
		(mid 333.401162 -227.224907)
		(end 333.682594 -227.149152)
		(width 0.09525)
		(layer "In13.Cu")
		(net "M_B_CPU0_SA_DQS_DN<0>")
	)
	(arc
		(start 334.622648 -227.149152)
		(mid 334.811116 -227.098475)
		(end 334.999584 -227.149152)
		(width 0.09525)
		(layer "In13.Cu")
		(net "M_B_CPU0_SA_DQS_DN<0>")
	)
	(arc
		(start 327.512426 -222.307912)
		(mid 327.6277 -222.44219)
		(end 327.669144 -222.614236)
		(width 0.09525)
		(layer "In13.Cu")
		(net "M_B_CPU0_SA_DQS_DN<0>")
	)
	(arc
		(start 331.239622 -227.149152)
		(mid 331.521054 -227.224907)
		(end 331.802486 -227.149152)
		(width 0.09525)
		(layer "In13.Cu")
		(net "M_B_CPU0_SA_DQS_DN<0>")
	)
	(arc
		(start 328.922126 -224.73793)
		(mid 329.0374 -224.872208)
		(end 329.078844 -225.044254)
		(width 0.09525)
		(layer "In13.Cu")
		(net "M_B_CPU0_SA_DQS_DN<0>")
	)
	(arc
		(start 330.299568 -227.149152)
		(mid 330.581 -227.224907)
		(end 330.862432 -227.149152)
		(width 0.09525)
		(layer "In13.Cu")
		(net "M_B_CPU0_SA_DQS_DN<0>")
	)
	(arc
		(start 328.139044 -223.424242)
		(mid 328.204237 -223.686871)
		(end 328.384662 -223.888554)
		(width 0.09525)
		(layer "In13.Cu")
		(net "M_B_CPU0_SA_DQS_DN<0>")
	)
	(arc
		(start 331.802486 -227.149152)
		(mid 331.986261 -227.09838)
		(end 332.171294 -227.144326)
		(width 0.09525)
		(layer "In13.Cu")
		(net "M_B_CPU0_SA_DQS_DN<0>")
	)
	(arc
		(start 332.179676 -227.149152)
		(mid 332.461108 -227.224907)
		(end 332.74254 -227.149152)
		(width 0.09525)
		(layer "In13.Cu")
		(net "M_B_CPU0_SA_DQS_DN<0>")
	)
	(arc
		(start 327.198736 -221.80423)
		(mid 327.262838 -222.064974)
		(end 327.440544 -222.266256)
		(width 0.09525)
		(layer "In13.Cu")
		(net "M_B_CPU0_SA_DQS_DN<0>")
	)
	(arc
		(start 335.475834 -227.1903)
		(mid 335.486162 -227.18634)
		(end 335.496408 -227.182172)
		(width 0.09525)
		(layer "In13.Cu")
		(net "M_B_CPU0_SA_DQS_DN<0>")
	)
	(arc
		(start 328.452226 -223.927924)
		(mid 328.5675 -224.062202)
		(end 328.608944 -224.234248)
		(width 0.09525)
		(layer "In13.Cu")
		(net "M_B_CPU0_SA_DQS_DN<0>")
	)
	(arc
		(start 329.548744 -225.85426)
		(mid 329.613141 -226.115566)
		(end 329.791568 -226.317048)
		(width 0.09525)
		(layer "In13.Cu")
		(net "M_B_CPU0_SA_DQS_DN<0>")
	)
	(segment
		(start 337.158076 -230.97998)
		(end 336.691224 -230.714296)
		(width 0.10668)
		(layer "F.Cu")
		(net "M_B_CPU0_SA_DQ<9>")
	)
	(segment
		(start 301.42434 -208.810098)
		(end 302.30572 -208.810098)
		(width 0.14478)
		(layer "In13.Cu")
		(net "M_B_CPU0_SA_DQ<9>")
	)
	(segment
		(start 326.407018 -228.490272)
		(end 326.986138 -229.069392)
		(width 0.0889)
		(layer "In13.Cu")
		(net "M_B_CPU0_SA_DQ<9>")
	)
	(segment
		(start 301.13478 -208.195926)
		(end 301.27956 -208.340706)
		(width 0.14478)
		(layer "In13.Cu")
		(net "M_B_CPU0_SA_DQ<9>")
	)
	(segment
		(start 304.13833 -208.973166)
		(end 304.301398 -208.810098)
		(width 0.14478)
		(layer "In13.Cu")
		(net "M_B_CPU0_SA_DQ<9>")
	)
	(segment
		(start 333.684118 -231.036622)
		(end 333.6925 -231.041448)
		(width 0.0889)
		(layer "In13.Cu")
		(net "M_B_CPU0_SA_DQ<9>")
	)
	(segment
		(start 303.581816 -208.973166)
		(end 303.581816 -209.030062)
		(width 0.14478)
		(layer "In13.Cu")
		(net "M_B_CPU0_SA_DQ<9>")
	)
	(segment
		(start 306.894738 -209.00644)
		(end 307.025548 -208.690718)
		(width 0.14478)
		(layer "In13.Cu")
		(net "M_B_CPU0_SA_DQ<9>")
	)
	(segment
		(start 301.27956 -208.340706)
		(end 301.27956 -208.665318)
		(width 0.14478)
		(layer "In13.Cu")
		(net "M_B_CPU0_SA_DQ<9>")
	)
	(segment
		(start 303.025302 -208.973166)
		(end 303.18837 -208.810098)
		(width 0.14478)
		(layer "In13.Cu")
		(net "M_B_CPU0_SA_DQ<9>")
	)
	(segment
		(start 308.50078 -209.828384)
		(end 309.710328 -210.329018)
		(width 0.14478)
		(layer "In13.Cu")
		(net "M_B_CPU0_SA_DQ<9>")
	)
	(segment
		(start 320.933318 -221.552008)
		(end 320.933318 -222.381572)
		(width 0.14478)
		(layer "In13.Cu")
		(net "M_B_CPU0_SA_DQ<9>")
	)
	(segment
		(start 302.30572 -208.810098)
		(end 302.468788 -208.973166)
		(width 0.14478)
		(layer "In13.Cu")
		(net "M_B_CPU0_SA_DQ<9>")
	)
	(segment
		(start 300.249082 -208.810098)
		(end 300.5836 -208.810098)
		(width 0.14478)
		(layer "In13.Cu")
		(net "M_B_CPU0_SA_DQ<9>")
	)
	(segment
		(start 326.986138 -229.069392)
		(end 326.986138 -229.280212)
		(width 0.0889)
		(layer "In13.Cu")
		(net "M_B_CPU0_SA_DQ<9>")
	)
	(segment
		(start 322.851018 -225.684334)
		(end 324.020434 -226.85375)
		(width 0.14478)
		(layer "In13.Cu")
		(net "M_B_CPU0_SA_DQ<9>")
	)
	(segment
		(start 308.044088 -209.112866)
		(end 308.233064 -209.034634)
		(width 0.14478)
		(layer "In13.Cu")
		(net "M_B_CPU0_SA_DQ<9>")
	)
	(segment
		(start 332.16977 -231.041448)
		(end 332.178152 -231.036622)
		(width 0.0889)
		(layer "In13.Cu")
		(net "M_B_CPU0_SA_DQ<9>")
	)
	(segment
		(start 307.456586 -208.712816)
		(end 307.534818 -208.901792)
		(width 0.14478)
		(layer "In13.Cu")
		(net "M_B_CPU0_SA_DQ<9>")
	)
	(segment
		(start 327.574148 -230.226616)
		(end 327.610724 -230.247952)
		(width 0.0889)
		(layer "In13.Cu")
		(net "M_B_CPU0_SA_DQ<9>")
	)
	(segment
		(start 308.475126 -209.134964)
		(end 308.553358 -209.32394)
		(width 0.14478)
		(layer "In13.Cu")
		(net "M_B_CPU0_SA_DQ<9>")
	)
	(segment
		(start 328.409808 -231.041448)
		(end 328.41819 -231.036622)
		(width 0.0889)
		(layer "In13.Cu")
		(net "M_B_CPU0_SA_DQ<9>")
	)
	(segment
		(start 326.165718 -228.490272)
		(end 326.407018 -228.490272)
		(width 0.0889)
		(layer "In13.Cu")
		(net "M_B_CPU0_SA_DQ<9>")
	)
	(segment
		(start 300.72838 -208.665318)
		(end 300.72838 -208.340706)
		(width 0.14478)
		(layer "In13.Cu")
		(net "M_B_CPU0_SA_DQ<9>")
	)
	(segment
		(start 335.929732 -231.041448)
		(end 335.938114 -231.036622)
		(width 0.0889)
		(layer "In13.Cu")
		(net "M_B_CPU0_SA_DQ<9>")
	)
	(segment
		(start 299.82414 -208.385156)
		(end 300.249082 -208.810098)
		(width 0.14478)
		(layer "In13.Cu")
		(net "M_B_CPU0_SA_DQ<9>")
	)
	(segment
		(start 308.233064 -209.034634)
		(end 308.475126 -209.134964)
		(width 0.14478)
		(layer "In13.Cu")
		(net "M_B_CPU0_SA_DQ<9>")
	)
	(segment
		(start 303.18837 -208.810098)
		(end 303.418748 -208.810098)
		(width 0.14478)
		(layer "In13.Cu")
		(net "M_B_CPU0_SA_DQ<9>")
	)
	(segment
		(start 328.011536 -231.017826)
		(end 328.044048 -231.036622)
		(width 0.0889)
		(layer "In13.Cu")
		(net "M_B_CPU0_SA_DQ<9>")
	)
	(segment
		(start 324.511416 -227.344732)
		(end 325.020178 -227.344732)
		(width 0.0889)
		(layer "In13.Cu")
		(net "M_B_CPU0_SA_DQ<9>")
	)
	(segment
		(start 303.975262 -209.19313)
		(end 304.13833 -209.030062)
		(width 0.14478)
		(layer "In13.Cu")
		(net "M_B_CPU0_SA_DQ<9>")
	)
	(segment
		(start 307.025548 -208.690718)
		(end 307.214524 -208.612486)
		(width 0.14478)
		(layer "In13.Cu")
		(net "M_B_CPU0_SA_DQ<9>")
	)
	(segment
		(start 307.404008 -209.217514)
		(end 307.48224 -209.40649)
		(width 0.14478)
		(layer "In13.Cu")
		(net "M_B_CPU0_SA_DQ<9>")
	)
	(segment
		(start 302.468788 -209.030062)
		(end 302.631856 -209.19313)
		(width 0.14478)
		(layer "In13.Cu")
		(net "M_B_CPU0_SA_DQ<9>")
	)
	(segment
		(start 322.851018 -224.299272)
		(end 322.851018 -225.684334)
		(width 0.14478)
		(layer "In13.Cu")
		(net "M_B_CPU0_SA_DQ<9>")
	)
	(segment
		(start 332.744064 -231.036622)
		(end 332.752446 -231.041448)
		(width 0.0889)
		(layer "In13.Cu")
		(net "M_B_CPU0_SA_DQ<9>")
	)
	(segment
		(start 300.5836 -208.810098)
		(end 300.72838 -208.665318)
		(width 0.14478)
		(layer "In13.Cu")
		(net "M_B_CPU0_SA_DQ<9>")
	)
	(segment
		(start 336.845148 -230.979726)
		(end 336.691224 -230.714296)
		(width 0.0889)
		(layer "In13.Cu")
		(net "M_B_CPU0_SA_DQ<9>")
	)
	(segment
		(start 303.025302 -209.030062)
		(end 303.025302 -208.973166)
		(width 0.14478)
		(layer "In13.Cu")
		(net "M_B_CPU0_SA_DQ<9>")
	)
	(segment
		(start 304.13833 -209.030062)
		(end 304.13833 -208.973166)
		(width 0.14478)
		(layer "In13.Cu")
		(net "M_B_CPU0_SA_DQ<9>")
	)
	(segment
		(start 307.214524 -208.612486)
		(end 307.456586 -208.712816)
		(width 0.14478)
		(layer "In13.Cu")
		(net "M_B_CPU0_SA_DQ<9>")
	)
	(segment
		(start 302.631856 -209.19313)
		(end 302.862234 -209.19313)
		(width 0.14478)
		(layer "In13.Cu")
		(net "M_B_CPU0_SA_DQ<9>")
	)
	(segment
		(start 308.422548 -209.639662)
		(end 308.50078 -209.828384)
		(width 0.14478)
		(layer "In13.Cu")
		(net "M_B_CPU0_SA_DQ<9>")
	)
	(segment
		(start 327.542398 -230.208328)
		(end 327.574148 -230.226616)
		(width 0.0889)
		(layer "In13.Cu")
		(net "M_B_CPU0_SA_DQ<9>")
	)
	(segment
		(start 302.862234 -209.19313)
		(end 303.025302 -209.030062)
		(width 0.14478)
		(layer "In13.Cu")
		(net "M_B_CPU0_SA_DQ<9>")
	)
	(segment
		(start 326.986138 -229.280212)
		(end 327.278746 -229.57282)
		(width 0.0889)
		(layer "In13.Cu")
		(net "M_B_CPU0_SA_DQ<9>")
	)
	(segment
		(start 301.27956 -208.665318)
		(end 301.42434 -208.810098)
		(width 0.14478)
		(layer "In13.Cu")
		(net "M_B_CPU0_SA_DQ<9>")
	)
	(segment
		(start 307.913278 -209.428588)
		(end 308.044088 -209.112866)
		(width 0.14478)
		(layer "In13.Cu")
		(net "M_B_CPU0_SA_DQ<9>")
	)
	(segment
		(start 304.301398 -208.810098)
		(end 306.04333 -208.810098)
		(width 0.14478)
		(layer "In13.Cu")
		(net "M_B_CPU0_SA_DQ<9>")
	)
	(segment
		(start 320.933318 -222.381572)
		(end 322.851018 -224.299272)
		(width 0.14478)
		(layer "In13.Cu")
		(net "M_B_CPU0_SA_DQ<9>")
	)
	(segment
		(start 303.418748 -208.810098)
		(end 303.581816 -208.973166)
		(width 0.14478)
		(layer "In13.Cu")
		(net "M_B_CPU0_SA_DQ<9>")
	)
	(segment
		(start 307.724302 -209.50682)
		(end 307.913278 -209.428588)
		(width 0.14478)
		(layer "In13.Cu")
		(net "M_B_CPU0_SA_DQ<9>")
	)
	(segment
		(start 300.72838 -208.340706)
		(end 300.87316 -208.195926)
		(width 0.14478)
		(layer "In13.Cu")
		(net "M_B_CPU0_SA_DQ<9>")
	)
	(segment
		(start 300.87316 -208.195926)
		(end 301.13478 -208.195926)
		(width 0.14478)
		(layer "In13.Cu")
		(net "M_B_CPU0_SA_DQ<9>")
	)
	(segment
		(start 306.04333 -208.810098)
		(end 306.705762 -209.084672)
		(width 0.14478)
		(layer "In13.Cu")
		(net "M_B_CPU0_SA_DQ<9>")
	)
	(segment
		(start 303.744884 -209.19313)
		(end 303.975262 -209.19313)
		(width 0.14478)
		(layer "In13.Cu")
		(net "M_B_CPU0_SA_DQ<9>")
	)
	(segment
		(start 331.229716 -231.041448)
		(end 331.238098 -231.036622)
		(width 0.0889)
		(layer "In13.Cu")
		(net "M_B_CPU0_SA_DQ<9>")
	)
	(segment
		(start 324.020434 -226.85375)
		(end 324.511416 -227.344732)
		(width 0.0889)
		(layer "In13.Cu")
		(net "M_B_CPU0_SA_DQ<9>")
	)
	(segment
		(start 308.553358 -209.32394)
		(end 308.422548 -209.639662)
		(width 0.14478)
		(layer "In13.Cu")
		(net "M_B_CPU0_SA_DQ<9>")
	)
	(segment
		(start 302.468788 -208.973166)
		(end 302.468788 -209.030062)
		(width 0.14478)
		(layer "In13.Cu")
		(net "M_B_CPU0_SA_DQ<9>")
	)
	(segment
		(start 325.020178 -227.344732)
		(end 326.165718 -228.490272)
		(width 0.0889)
		(layer "In13.Cu")
		(net "M_B_CPU0_SA_DQ<9>")
	)
	(segment
		(start 328.984102 -231.036622)
		(end 328.992484 -231.041448)
		(width 0.0889)
		(layer "In13.Cu")
		(net "M_B_CPU0_SA_DQ<9>")
	)
	(segment
		(start 307.48224 -209.40649)
		(end 307.724302 -209.50682)
		(width 0.14478)
		(layer "In13.Cu")
		(net "M_B_CPU0_SA_DQ<9>")
	)
	(segment
		(start 303.581816 -209.030062)
		(end 303.744884 -209.19313)
		(width 0.14478)
		(layer "In13.Cu")
		(net "M_B_CPU0_SA_DQ<9>")
	)
	(segment
		(start 336.822796 -231.062784)
		(end 336.845148 -230.979726)
		(width 0.0889)
		(layer "In13.Cu")
		(net "M_B_CPU0_SA_DQ<9>")
	)
	(segment
		(start 309.710328 -210.329018)
		(end 320.933318 -221.552008)
		(width 0.14478)
		(layer "In13.Cu")
		(net "M_B_CPU0_SA_DQ<9>")
	)
	(segment
		(start 306.705762 -209.084672)
		(end 306.894738 -209.00644)
		(width 0.14478)
		(layer "In13.Cu")
		(net "M_B_CPU0_SA_DQ<9>")
	)
	(segment
		(start 307.534818 -208.901792)
		(end 307.404008 -209.217514)
		(width 0.14478)
		(layer "In13.Cu")
		(net "M_B_CPU0_SA_DQ<9>")
	)
	(arc
		(start 334.99806 -231.036622)
		(mid 335.281016 -230.960445)
		(end 335.563972 -231.036622)
		(width 0.0889)
		(layer "In13.Cu")
		(net "M_B_CPU0_SA_DQ<9>")
	)
	(arc
		(start 327.610724 -230.247952)
		(mid 327.791376 -230.450697)
		(end 327.856596 -230.714296)
		(width 0.0889)
		(layer "In13.Cu")
		(net "M_B_CPU0_SA_DQ<9>")
	)
	(arc
		(start 328.044048 -231.036622)
		(mid 328.226299 -231.087006)
		(end 328.409808 -231.041448)
		(width 0.0889)
		(layer "In13.Cu")
		(net "M_B_CPU0_SA_DQ<9>")
	)
	(arc
		(start 327.856596 -230.714296)
		(mid 327.897562 -230.884702)
		(end 328.011536 -231.017826)
		(width 0.0889)
		(layer "In13.Cu")
		(net "M_B_CPU0_SA_DQ<9>")
	)
	(arc
		(start 328.41819 -231.036622)
		(mid 328.701146 -230.960445)
		(end 328.984102 -231.036622)
		(width 0.0889)
		(layer "In13.Cu")
		(net "M_B_CPU0_SA_DQ<9>")
	)
	(arc
		(start 330.863956 -231.036622)
		(mid 331.046207 -231.087006)
		(end 331.229716 -231.041448)
		(width 0.0889)
		(layer "In13.Cu")
		(net "M_B_CPU0_SA_DQ<9>")
	)
	(arc
		(start 335.938114 -231.036622)
		(mid 336.22107 -230.960445)
		(end 336.504026 -231.036622)
		(width 0.0889)
		(layer "In13.Cu")
		(net "M_B_CPU0_SA_DQ<9>")
	)
	(arc
		(start 333.6925 -231.041448)
		(mid 333.876008 -231.086973)
		(end 334.05826 -231.036622)
		(width 0.0889)
		(layer "In13.Cu")
		(net "M_B_CPU0_SA_DQ<9>")
	)
	(arc
		(start 336.504026 -231.036622)
		(mid 336.660464 -231.085627)
		(end 336.822796 -231.062784)
		(width 0.0889)
		(layer "In13.Cu")
		(net "M_B_CPU0_SA_DQ<9>")
	)
	(arc
		(start 333.118206 -231.036622)
		(mid 333.401162 -230.960445)
		(end 333.684118 -231.036622)
		(width 0.0889)
		(layer "In13.Cu")
		(net "M_B_CPU0_SA_DQ<9>")
	)
	(arc
		(start 335.563972 -231.036622)
		(mid 335.746223 -231.087006)
		(end 335.929732 -231.041448)
		(width 0.0889)
		(layer "In13.Cu")
		(net "M_B_CPU0_SA_DQ<9>")
	)
	(arc
		(start 332.752446 -231.041448)
		(mid 332.935954 -231.086973)
		(end 333.118206 -231.036622)
		(width 0.0889)
		(layer "In13.Cu")
		(net "M_B_CPU0_SA_DQ<9>")
	)
	(arc
		(start 329.924156 -231.036622)
		(mid 330.1111 -231.086911)
		(end 330.298044 -231.036622)
		(width 0.0889)
		(layer "In13.Cu")
		(net "M_B_CPU0_SA_DQ<9>")
	)
	(arc
		(start 327.386442 -229.904036)
		(mid 327.427697 -230.075007)
		(end 327.542398 -230.208328)
		(width 0.0889)
		(layer "In13.Cu")
		(net "M_B_CPU0_SA_DQ<9>")
	)
	(arc
		(start 327.278746 -229.57282)
		(mid 327.358778 -229.72992)
		(end 327.386442 -229.904036)
		(width 0.0889)
		(layer "In13.Cu")
		(net "M_B_CPU0_SA_DQ<9>")
	)
	(arc
		(start 334.05826 -231.036622)
		(mid 334.341216 -230.960445)
		(end 334.624172 -231.036622)
		(width 0.0889)
		(layer "In13.Cu")
		(net "M_B_CPU0_SA_DQ<9>")
	)
	(arc
		(start 334.624172 -231.036622)
		(mid 334.811116 -231.086911)
		(end 334.99806 -231.036622)
		(width 0.0889)
		(layer "In13.Cu")
		(net "M_B_CPU0_SA_DQ<9>")
	)
	(arc
		(start 331.80401 -231.036622)
		(mid 331.986261 -231.087006)
		(end 332.16977 -231.041448)
		(width 0.0889)
		(layer "In13.Cu")
		(net "M_B_CPU0_SA_DQ<9>")
	)
	(arc
		(start 329.358244 -231.036622)
		(mid 329.6412 -230.960445)
		(end 329.924156 -231.036622)
		(width 0.0889)
		(layer "In13.Cu")
		(net "M_B_CPU0_SA_DQ<9>")
	)
	(arc
		(start 332.178152 -231.036622)
		(mid 332.461108 -230.960445)
		(end 332.744064 -231.036622)
		(width 0.0889)
		(layer "In13.Cu")
		(net "M_B_CPU0_SA_DQ<9>")
	)
	(arc
		(start 328.992484 -231.041448)
		(mid 329.175992 -231.086973)
		(end 329.358244 -231.036622)
		(width 0.0889)
		(layer "In13.Cu")
		(net "M_B_CPU0_SA_DQ<9>")
	)
	(arc
		(start 331.238098 -231.036622)
		(mid 331.521054 -230.960445)
		(end 331.80401 -231.036622)
		(width 0.0889)
		(layer "In13.Cu")
		(net "M_B_CPU0_SA_DQ<9>")
	)
	(arc
		(start 330.298044 -231.036622)
		(mid 330.581 -230.960445)
		(end 330.863956 -231.036622)
		(width 0.0889)
		(layer "In13.Cu")
		(net "M_B_CPU0_SA_DQ<9>")
	)
	(segment
		(start 335.747868 -230.169974)
		(end 335.281016 -229.904036)
		(width 0.10668)
		(layer "F.Cu")
		(net "M_B_CPU0_SA_DQ<8>")
	)
	(segment
		(start 306.43195 -207.484472)
		(end 306.830984 -207.484472)
		(width 0.14478)
		(layer "In13.Cu")
		(net "M_B_CPU0_SA_DQ<8>")
	)
	(segment
		(start 303.669446 -207.110076)
		(end 303.83099 -207.27162)
		(width 0.14478)
		(layer "In13.Cu")
		(net "M_B_CPU0_SA_DQ<8>")
	)
	(segment
		(start 323.823838 -223.971612)
		(end 323.823838 -224.968054)
		(width 0.14478)
		(layer "In13.Cu")
		(net "M_B_CPU0_SA_DQ<8>")
	)
	(segment
		(start 303.83099 -207.322928)
		(end 303.992534 -207.484472)
		(width 0.14478)
		(layer "In13.Cu")
		(net "M_B_CPU0_SA_DQ<8>")
	)
	(segment
		(start 328.482452 -230.208328)
		(end 328.514202 -230.226616)
		(width 0.0889)
		(layer "In13.Cu")
		(net "M_B_CPU0_SA_DQ<8>")
	)
	(segment
		(start 299.848778 -206.660496)
		(end 300.444916 -206.660496)
		(width 0.14478)
		(layer "In13.Cu")
		(net "M_B_CPU0_SA_DQ<8>")
	)
	(segment
		(start 325.849996 -226.994212)
		(end 326.511158 -226.994212)
		(width 0.0889)
		(layer "In13.Cu")
		(net "M_B_CPU0_SA_DQ<8>")
	)
	(segment
		(start 305.73599 -206.967582)
		(end 305.88077 -206.822802)
		(width 0.14478)
		(layer "In13.Cu")
		(net "M_B_CPU0_SA_DQ<8>")
	)
	(segment
		(start 305.18481 -206.967582)
		(end 305.18481 -207.339692)
		(width 0.14478)
		(layer "In13.Cu")
		(net "M_B_CPU0_SA_DQ<8>")
	)
	(segment
		(start 301.574962 -206.660496)
		(end 302.024542 -207.110076)
		(width 0.14478)
		(layer "In13.Cu")
		(net "M_B_CPU0_SA_DQ<8>")
	)
	(segment
		(start 301.285656 -206.660496)
		(end 301.574962 -206.660496)
		(width 0.14478)
		(layer "In13.Cu")
		(net "M_B_CPU0_SA_DQ<8>")
	)
	(segment
		(start 306.14239 -206.822802)
		(end 306.28717 -206.967582)
		(width 0.14478)
		(layer "In13.Cu")
		(net "M_B_CPU0_SA_DQ<8>")
	)
	(segment
		(start 327.574148 -228.606858)
		(end 327.613264 -228.629718)
		(width 0.0889)
		(layer "In13.Cu")
		(net "M_B_CPU0_SA_DQ<8>")
	)
	(segment
		(start 306.28717 -206.967582)
		(end 306.28717 -207.339692)
		(width 0.14478)
		(layer "In13.Cu")
		(net "M_B_CPU0_SA_DQ<8>")
	)
	(segment
		(start 302.889666 -207.484472)
		(end 303.118012 -207.484472)
		(width 0.14478)
		(layer "In13.Cu")
		(net "M_B_CPU0_SA_DQ<8>")
	)
	(segment
		(start 327.542398 -228.58857)
		(end 327.574148 -228.606858)
		(width 0.0889)
		(layer "In13.Cu")
		(net "M_B_CPU0_SA_DQ<8>")
	)
	(segment
		(start 300.734476 -206.068422)
		(end 300.996096 -206.068422)
		(width 0.14478)
		(layer "In13.Cu")
		(net "M_B_CPU0_SA_DQ<8>")
	)
	(segment
		(start 308.12867 -207.686656)
		(end 308.12867 -207.89138)
		(width 0.14478)
		(layer "In13.Cu")
		(net "M_B_CPU0_SA_DQ<8>")
	)
	(segment
		(start 301.140876 -206.213202)
		(end 301.140876 -206.515716)
		(width 0.14478)
		(layer "In13.Cu")
		(net "M_B_CPU0_SA_DQ<8>")
	)
	(segment
		(start 302.024542 -207.110076)
		(end 302.583342 -207.110076)
		(width 0.14478)
		(layer "In13.Cu")
		(net "M_B_CPU0_SA_DQ<8>")
	)
	(segment
		(start 303.4411 -207.110076)
		(end 303.669446 -207.110076)
		(width 0.14478)
		(layer "In13.Cu")
		(net "M_B_CPU0_SA_DQ<8>")
	)
	(segment
		(start 304.48885 -207.484472)
		(end 304.63363 -207.339692)
		(width 0.14478)
		(layer "In13.Cu")
		(net "M_B_CPU0_SA_DQ<8>")
	)
	(segment
		(start 326.511158 -226.994212)
		(end 327.386442 -227.869496)
		(width 0.0889)
		(layer "In13.Cu")
		(net "M_B_CPU0_SA_DQ<8>")
	)
	(segment
		(start 300.589696 -206.515716)
		(end 300.589696 -206.213202)
		(width 0.14478)
		(layer "In13.Cu")
		(net "M_B_CPU0_SA_DQ<8>")
	)
	(segment
		(start 307.763418 -207.110076)
		(end 308.131972 -207.47863)
		(width 0.14478)
		(layer "In13.Cu")
		(net "M_B_CPU0_SA_DQ<8>")
	)
	(segment
		(start 308.313836 -208.076546)
		(end 308.51856 -208.076546)
		(width 0.14478)
		(layer "In13.Cu")
		(net "M_B_CPU0_SA_DQ<8>")
	)
	(segment
		(start 307.20538 -207.110076)
		(end 307.763418 -207.110076)
		(width 0.14478)
		(layer "In13.Cu")
		(net "M_B_CPU0_SA_DQ<8>")
	)
	(segment
		(start 327.386442 -227.869496)
		(end 327.386442 -228.284278)
		(width 0.0889)
		(layer "In13.Cu")
		(net "M_B_CPU0_SA_DQ<8>")
	)
	(segment
		(start 308.131972 -207.683354)
		(end 308.12867 -207.686656)
		(width 0.14478)
		(layer "In13.Cu")
		(net "M_B_CPU0_SA_DQ<8>")
	)
	(segment
		(start 321.850258 -221.998032)
		(end 323.823838 -223.971612)
		(width 0.14478)
		(layer "In13.Cu")
		(net "M_B_CPU0_SA_DQ<8>")
	)
	(segment
		(start 334.519778 -230.231442)
		(end 334.52816 -230.226616)
		(width 0.0889)
		(layer "In13.Cu")
		(net "M_B_CPU0_SA_DQ<8>")
	)
	(segment
		(start 301.140876 -206.515716)
		(end 301.285656 -206.660496)
		(width 0.14478)
		(layer "In13.Cu")
		(net "M_B_CPU0_SA_DQ<8>")
	)
	(segment
		(start 329.819762 -230.231442)
		(end 329.828144 -230.226616)
		(width 0.0889)
		(layer "In13.Cu")
		(net "M_B_CPU0_SA_DQ<8>")
	)
	(segment
		(start 335.435194 -230.169466)
		(end 335.281016 -229.904036)
		(width 0.0889)
		(layer "In13.Cu")
		(net "M_B_CPU0_SA_DQ<8>")
	)
	(segment
		(start 335.094072 -230.226616)
		(end 335.102454 -230.231442)
		(width 0.0889)
		(layer "In13.Cu")
		(net "M_B_CPU0_SA_DQ<8>")
	)
	(segment
		(start 308.726586 -208.073244)
		(end 321.850258 -221.196916)
		(width 0.14478)
		(layer "In13.Cu")
		(net "M_B_CPU0_SA_DQ<8>")
	)
	(segment
		(start 304.77841 -206.822802)
		(end 305.04003 -206.822802)
		(width 0.14478)
		(layer "In13.Cu")
		(net "M_B_CPU0_SA_DQ<8>")
	)
	(segment
		(start 303.992534 -207.484472)
		(end 304.48885 -207.484472)
		(width 0.14478)
		(layer "In13.Cu")
		(net "M_B_CPU0_SA_DQ<8>")
	)
	(segment
		(start 305.73599 -207.339692)
		(end 305.73599 -206.967582)
		(width 0.14478)
		(layer "In13.Cu")
		(net "M_B_CPU0_SA_DQ<8>")
	)
	(segment
		(start 300.996096 -206.068422)
		(end 301.140876 -206.213202)
		(width 0.14478)
		(layer "In13.Cu")
		(net "M_B_CPU0_SA_DQ<8>")
	)
	(segment
		(start 305.32959 -207.484472)
		(end 305.59121 -207.484472)
		(width 0.14478)
		(layer "In13.Cu")
		(net "M_B_CPU0_SA_DQ<8>")
	)
	(segment
		(start 308.521862 -208.073244)
		(end 308.726586 -208.073244)
		(width 0.14478)
		(layer "In13.Cu")
		(net "M_B_CPU0_SA_DQ<8>")
	)
	(segment
		(start 324.862444 -226.00666)
		(end 325.849996 -226.994212)
		(width 0.0889)
		(layer "In13.Cu")
		(net "M_B_CPU0_SA_DQ<8>")
	)
	(segment
		(start 306.830984 -207.484472)
		(end 307.20538 -207.110076)
		(width 0.14478)
		(layer "In13.Cu")
		(net "M_B_CPU0_SA_DQ<8>")
	)
	(segment
		(start 303.279556 -207.27162)
		(end 303.4411 -207.110076)
		(width 0.14478)
		(layer "In13.Cu")
		(net "M_B_CPU0_SA_DQ<8>")
	)
	(segment
		(start 306.28717 -207.339692)
		(end 306.43195 -207.484472)
		(width 0.14478)
		(layer "In13.Cu")
		(net "M_B_CPU0_SA_DQ<8>")
	)
	(segment
		(start 302.728122 -207.254856)
		(end 302.728122 -207.322928)
		(width 0.14478)
		(layer "In13.Cu")
		(net "M_B_CPU0_SA_DQ<8>")
	)
	(segment
		(start 304.63363 -207.339692)
		(end 304.63363 -206.967582)
		(width 0.14478)
		(layer "In13.Cu")
		(net "M_B_CPU0_SA_DQ<8>")
	)
	(segment
		(start 333.579724 -230.231442)
		(end 333.588106 -230.226616)
		(width 0.0889)
		(layer "In13.Cu")
		(net "M_B_CPU0_SA_DQ<8>")
	)
	(segment
		(start 308.131972 -207.47863)
		(end 308.131972 -207.683354)
		(width 0.14478)
		(layer "In13.Cu")
		(net "M_B_CPU0_SA_DQ<8>")
	)
	(segment
		(start 303.83099 -207.27162)
		(end 303.83099 -207.322928)
		(width 0.14478)
		(layer "In13.Cu")
		(net "M_B_CPU0_SA_DQ<8>")
	)
	(segment
		(start 308.51856 -208.076546)
		(end 308.521862 -208.073244)
		(width 0.14478)
		(layer "In13.Cu")
		(net "M_B_CPU0_SA_DQ<8>")
	)
	(segment
		(start 330.394056 -230.226616)
		(end 330.402438 -230.231442)
		(width 0.0889)
		(layer "In13.Cu")
		(net "M_B_CPU0_SA_DQ<8>")
	)
	(segment
		(start 300.444916 -206.660496)
		(end 300.589696 -206.515716)
		(width 0.14478)
		(layer "In13.Cu")
		(net "M_B_CPU0_SA_DQ<8>")
	)
	(segment
		(start 328.044048 -229.41661)
		(end 328.081132 -229.437946)
		(width 0.0889)
		(layer "In13.Cu")
		(net "M_B_CPU0_SA_DQ<8>")
	)
	(segment
		(start 303.118012 -207.484472)
		(end 303.279556 -207.322928)
		(width 0.14478)
		(layer "In13.Cu")
		(net "M_B_CPU0_SA_DQ<8>")
	)
	(segment
		(start 331.33411 -230.226616)
		(end 331.342492 -230.231442)
		(width 0.0889)
		(layer "In13.Cu")
		(net "M_B_CPU0_SA_DQ<8>")
	)
	(segment
		(start 305.59121 -207.484472)
		(end 305.73599 -207.339692)
		(width 0.14478)
		(layer "In13.Cu")
		(net "M_B_CPU0_SA_DQ<8>")
	)
	(segment
		(start 303.279556 -207.322928)
		(end 303.279556 -207.27162)
		(width 0.14478)
		(layer "In13.Cu")
		(net "M_B_CPU0_SA_DQ<8>")
	)
	(segment
		(start 302.583342 -207.110076)
		(end 302.728122 -207.254856)
		(width 0.14478)
		(layer "In13.Cu")
		(net "M_B_CPU0_SA_DQ<8>")
	)
	(segment
		(start 305.88077 -206.822802)
		(end 306.14239 -206.822802)
		(width 0.14478)
		(layer "In13.Cu")
		(net "M_B_CPU0_SA_DQ<8>")
	)
	(segment
		(start 335.412842 -230.252778)
		(end 335.435194 -230.169466)
		(width 0.0889)
		(layer "In13.Cu")
		(net "M_B_CPU0_SA_DQ<8>")
	)
	(segment
		(start 323.823838 -224.968054)
		(end 324.862444 -226.00666)
		(width 0.14478)
		(layer "In13.Cu")
		(net "M_B_CPU0_SA_DQ<8>")
	)
	(segment
		(start 300.589696 -206.213202)
		(end 300.734476 -206.068422)
		(width 0.14478)
		(layer "In13.Cu")
		(net "M_B_CPU0_SA_DQ<8>")
	)
	(segment
		(start 304.63363 -206.967582)
		(end 304.77841 -206.822802)
		(width 0.14478)
		(layer "In13.Cu")
		(net "M_B_CPU0_SA_DQ<8>")
	)
	(segment
		(start 328.081132 -229.437946)
		(end 328.083164 -229.43947)
		(width 0.0889)
		(layer "In13.Cu")
		(net "M_B_CPU0_SA_DQ<8>")
	)
	(segment
		(start 321.850258 -221.196916)
		(end 321.850258 -221.998032)
		(width 0.14478)
		(layer "In13.Cu")
		(net "M_B_CPU0_SA_DQ<8>")
	)
	(segment
		(start 308.12867 -207.89138)
		(end 308.313836 -208.076546)
		(width 0.14478)
		(layer "In13.Cu")
		(net "M_B_CPU0_SA_DQ<8>")
	)
	(segment
		(start 328.011536 -229.397814)
		(end 328.044048 -229.41661)
		(width 0.0889)
		(layer "In13.Cu")
		(net "M_B_CPU0_SA_DQ<8>")
	)
	(segment
		(start 305.04003 -206.822802)
		(end 305.18481 -206.967582)
		(width 0.14478)
		(layer "In13.Cu")
		(net "M_B_CPU0_SA_DQ<8>")
	)
	(segment
		(start 299.82414 -206.685134)
		(end 299.848778 -206.660496)
		(width 0.14478)
		(layer "In13.Cu")
		(net "M_B_CPU0_SA_DQ<8>")
	)
	(segment
		(start 305.18481 -207.339692)
		(end 305.32959 -207.484472)
		(width 0.14478)
		(layer "In13.Cu")
		(net "M_B_CPU0_SA_DQ<8>")
	)
	(segment
		(start 302.728122 -207.322928)
		(end 302.889666 -207.484472)
		(width 0.14478)
		(layer "In13.Cu")
		(net "M_B_CPU0_SA_DQ<8>")
	)
	(arc
		(start 331.708252 -230.226616)
		(mid 331.991208 -230.150473)
		(end 332.274164 -230.226616)
		(width 0.0889)
		(layer "In13.Cu")
		(net "M_B_CPU0_SA_DQ<8>")
	)
	(arc
		(start 330.402438 -230.231442)
		(mid 330.585946 -230.276936)
		(end 330.768198 -230.226616)
		(width 0.0889)
		(layer "In13.Cu")
		(net "M_B_CPU0_SA_DQ<8>")
	)
	(arc
		(start 331.342492 -230.231442)
		(mid 331.526 -230.276936)
		(end 331.708252 -230.226616)
		(width 0.0889)
		(layer "In13.Cu")
		(net "M_B_CPU0_SA_DQ<8>")
	)
	(arc
		(start 327.613264 -228.629718)
		(mid 327.792077 -228.832068)
		(end 327.856596 -229.094284)
		(width 0.0889)
		(layer "In13.Cu")
		(net "M_B_CPU0_SA_DQ<8>")
	)
	(arc
		(start 332.274164 -230.226616)
		(mid 332.461108 -230.276871)
		(end 332.648052 -230.226616)
		(width 0.0889)
		(layer "In13.Cu")
		(net "M_B_CPU0_SA_DQ<8>")
	)
	(arc
		(start 333.213964 -230.226616)
		(mid 333.396215 -230.276966)
		(end 333.579724 -230.231442)
		(width 0.0889)
		(layer "In13.Cu")
		(net "M_B_CPU0_SA_DQ<8>")
	)
	(arc
		(start 333.588106 -230.226616)
		(mid 333.871062 -230.150473)
		(end 334.154018 -230.226616)
		(width 0.0889)
		(layer "In13.Cu")
		(net "M_B_CPU0_SA_DQ<8>")
	)
	(arc
		(start 329.454002 -230.226616)
		(mid 329.636253 -230.276966)
		(end 329.819762 -230.231442)
		(width 0.0889)
		(layer "In13.Cu")
		(net "M_B_CPU0_SA_DQ<8>")
	)
	(arc
		(start 327.386442 -228.284278)
		(mid 327.427697 -228.455249)
		(end 327.542398 -228.58857)
		(width 0.0889)
		(layer "In13.Cu")
		(net "M_B_CPU0_SA_DQ<8>")
	)
	(arc
		(start 327.856596 -229.094284)
		(mid 327.897562 -229.26469)
		(end 328.011536 -229.397814)
		(width 0.0889)
		(layer "In13.Cu")
		(net "M_B_CPU0_SA_DQ<8>")
	)
	(arc
		(start 332.648052 -230.226616)
		(mid 332.931008 -230.150473)
		(end 333.213964 -230.226616)
		(width 0.0889)
		(layer "In13.Cu")
		(net "M_B_CPU0_SA_DQ<8>")
	)
	(arc
		(start 328.514202 -230.226616)
		(mid 328.701146 -230.276871)
		(end 328.88809 -230.226616)
		(width 0.0889)
		(layer "In13.Cu")
		(net "M_B_CPU0_SA_DQ<8>")
	)
	(arc
		(start 329.828144 -230.226616)
		(mid 330.1111 -230.150473)
		(end 330.394056 -230.226616)
		(width 0.0889)
		(layer "In13.Cu")
		(net "M_B_CPU0_SA_DQ<8>")
	)
	(arc
		(start 334.52816 -230.226616)
		(mid 334.811116 -230.150473)
		(end 335.094072 -230.226616)
		(width 0.0889)
		(layer "In13.Cu")
		(net "M_B_CPU0_SA_DQ<8>")
	)
	(arc
		(start 335.102454 -230.231442)
		(mid 335.255324 -230.276083)
		(end 335.412842 -230.252778)
		(width 0.0889)
		(layer "In13.Cu")
		(net "M_B_CPU0_SA_DQ<8>")
	)
	(arc
		(start 328.083164 -229.43947)
		(mid 328.261977 -229.64182)
		(end 328.326496 -229.904036)
		(width 0.0889)
		(layer "In13.Cu")
		(net "M_B_CPU0_SA_DQ<8>")
	)
	(arc
		(start 328.88809 -230.226616)
		(mid 329.171046 -230.150473)
		(end 329.454002 -230.226616)
		(width 0.0889)
		(layer "In13.Cu")
		(net "M_B_CPU0_SA_DQ<8>")
	)
	(arc
		(start 328.326496 -229.904036)
		(mid 328.367751 -230.075007)
		(end 328.482452 -230.208328)
		(width 0.0889)
		(layer "In13.Cu")
		(net "M_B_CPU0_SA_DQ<8>")
	)
	(arc
		(start 330.768198 -230.226616)
		(mid 331.051154 -230.150473)
		(end 331.33411 -230.226616)
		(width 0.0889)
		(layer "In13.Cu")
		(net "M_B_CPU0_SA_DQ<8>")
	)
	(arc
		(start 334.154018 -230.226616)
		(mid 334.336269 -230.276966)
		(end 334.519778 -230.231442)
		(width 0.0889)
		(layer "In13.Cu")
		(net "M_B_CPU0_SA_DQ<8>")
	)
	(segment
		(start 337.627976 -230.169974)
		(end 337.161124 -229.904036)
		(width 0.10668)
		(layer "F.Cu")
		(net "M_B_CPU0_SA_DQ<7>")
	)
	(segment
		(start 325.467218 -224.977452)
		(end 325.72579 -225.236024)
		(width 0.0889)
		(layer "In13.Cu")
		(net "M_B_CPU0_SA_DQ<7>")
	)
	(segment
		(start 296.514266 -206.053944)
		(end 296.659046 -206.198724)
		(width 0.14478)
		(layer "In13.Cu")
		(net "M_B_CPU0_SA_DQ<7>")
	)
	(segment
		(start 331.33411 -229.58171)
		(end 331.342492 -229.576884)
		(width 0.0889)
		(layer "In13.Cu")
		(net "M_B_CPU0_SA_DQ<7>")
	)
	(segment
		(start 337.0072 -229.638606)
		(end 337.161124 -229.904036)
		(width 0.0889)
		(layer "In13.Cu")
		(net "M_B_CPU0_SA_DQ<7>")
	)
	(segment
		(start 295.724072 -205.834996)
		(end 296.369486 -205.834996)
		(width 0.14478)
		(layer "In13.Cu")
		(net "M_B_CPU0_SA_DQ<7>")
	)
	(segment
		(start 297.210226 -205.834996)
		(end 297.73753 -205.834996)
		(width 0.14478)
		(layer "In13.Cu")
		(net "M_B_CPU0_SA_DQ<7>")
	)
	(segment
		(start 307.69306 -206.260192)
		(end 323.504814 -222.071946)
		(width 0.14478)
		(layer "In13.Cu")
		(net "M_B_CPU0_SA_DQ<7>")
	)
	(segment
		(start 324.904354 -224.414588)
		(end 325.467218 -224.977452)
		(width 0.14478)
		(layer "In13.Cu")
		(net "M_B_CPU0_SA_DQ<7>")
	)
	(segment
		(start 325.830438 -225.4885)
		(end 325.830438 -225.602292)
		(width 0.0889)
		(layer "In13.Cu")
		(net "M_B_CPU0_SA_DQ<7>")
	)
	(segment
		(start 334.519778 -229.576884)
		(end 334.52816 -229.58171)
		(width 0.0889)
		(layer "In13.Cu")
		(net "M_B_CPU0_SA_DQ<7>")
	)
	(segment
		(start 324.904354 -224.25025)
		(end 324.904354 -224.414588)
		(width 0.14478)
		(layer "In13.Cu")
		(net "M_B_CPU0_SA_DQ<7>")
	)
	(segment
		(start 301.196502 -205.410054)
		(end 302.04664 -206.260192)
		(width 0.14478)
		(layer "In13.Cu")
		(net "M_B_CPU0_SA_DQ<7>")
	)
	(segment
		(start 328.379074 -228.748844)
		(end 328.41819 -228.771704)
		(width 0.0889)
		(layer "In13.Cu")
		(net "M_B_CPU0_SA_DQ<7>")
	)
	(segment
		(start 336.034126 -229.58171)
		(end 336.042508 -229.576884)
		(width 0.0889)
		(layer "In13.Cu")
		(net "M_B_CPU0_SA_DQ<7>")
	)
	(segment
		(start 329.819762 -229.576884)
		(end 329.828144 -229.58171)
		(width 0.0889)
		(layer "In13.Cu")
		(net "M_B_CPU0_SA_DQ<7>")
	)
	(segment
		(start 298.162472 -205.410054)
		(end 301.196502 -205.410054)
		(width 0.14478)
		(layer "In13.Cu")
		(net "M_B_CPU0_SA_DQ<7>")
	)
	(segment
		(start 328.41819 -228.771704)
		(end 328.44994 -228.789992)
		(width 0.0889)
		(layer "In13.Cu")
		(net "M_B_CPU0_SA_DQ<7>")
	)
	(segment
		(start 328.851768 -229.560628)
		(end 328.88809 -229.58171)
		(width 0.0889)
		(layer "In13.Cu")
		(net "M_B_CPU0_SA_DQ<7>")
	)
	(segment
		(start 327.911968 -227.940616)
		(end 327.97877 -227.979478)
		(width 0.0889)
		(layer "In13.Cu")
		(net "M_B_CPU0_SA_DQ<7>")
	)
	(segment
		(start 296.514266 -205.979776)
		(end 296.514266 -206.053944)
		(width 0.14478)
		(layer "In13.Cu")
		(net "M_B_CPU0_SA_DQ<7>")
	)
	(segment
		(start 296.369486 -205.834996)
		(end 296.514266 -205.979776)
		(width 0.14478)
		(layer "In13.Cu")
		(net "M_B_CPU0_SA_DQ<7>")
	)
	(segment
		(start 297.065446 -206.053944)
		(end 297.065446 -205.979776)
		(width 0.14478)
		(layer "In13.Cu")
		(net "M_B_CPU0_SA_DQ<7>")
	)
	(segment
		(start 296.920666 -206.198724)
		(end 297.065446 -206.053944)
		(width 0.14478)
		(layer "In13.Cu")
		(net "M_B_CPU0_SA_DQ<7>")
	)
	(segment
		(start 330.394056 -229.58171)
		(end 330.402438 -229.576884)
		(width 0.0889)
		(layer "In13.Cu")
		(net "M_B_CPU0_SA_DQ<7>")
	)
	(segment
		(start 336.911442 -229.613206)
		(end 337.0072 -229.638606)
		(width 0.0889)
		(layer "In13.Cu")
		(net "M_B_CPU0_SA_DQ<7>")
	)
	(segment
		(start 302.04664 -206.260192)
		(end 307.69306 -206.260192)
		(width 0.14478)
		(layer "In13.Cu")
		(net "M_B_CPU0_SA_DQ<7>")
	)
	(segment
		(start 297.065446 -205.979776)
		(end 297.210226 -205.834996)
		(width 0.14478)
		(layer "In13.Cu")
		(net "M_B_CPU0_SA_DQ<7>")
	)
	(segment
		(start 323.504814 -222.85071)
		(end 324.904354 -224.25025)
		(width 0.14478)
		(layer "In13.Cu")
		(net "M_B_CPU0_SA_DQ<7>")
	)
	(segment
		(start 325.991982 -225.992436)
		(end 327.658984 -227.659438)
		(width 0.0889)
		(layer "In13.Cu")
		(net "M_B_CPU0_SA_DQ<7>")
	)
	(segment
		(start 335.094072 -229.58171)
		(end 335.102454 -229.576884)
		(width 0.0889)
		(layer "In13.Cu")
		(net "M_B_CPU0_SA_DQ<7>")
	)
	(segment
		(start 333.579724 -229.576884)
		(end 333.588106 -229.58171)
		(width 0.0889)
		(layer "In13.Cu")
		(net "M_B_CPU0_SA_DQ<7>")
	)
	(segment
		(start 297.73753 -205.834996)
		(end 298.162472 -205.410054)
		(width 0.14478)
		(layer "In13.Cu")
		(net "M_B_CPU0_SA_DQ<7>")
	)
	(segment
		(start 323.504814 -222.071946)
		(end 323.504814 -222.85071)
		(width 0.14478)
		(layer "In13.Cu")
		(net "M_B_CPU0_SA_DQ<7>")
	)
	(segment
		(start 296.659046 -206.198724)
		(end 296.920666 -206.198724)
		(width 0.14478)
		(layer "In13.Cu")
		(net "M_B_CPU0_SA_DQ<7>")
	)
	(arc
		(start 336.408268 -229.58171)
		(mid 336.656128 -229.656793)
		(end 336.911442 -229.613206)
		(width 0.0889)
		(layer "In13.Cu")
		(net "M_B_CPU0_SA_DQ<7>")
	)
	(arc
		(start 334.52816 -229.58171)
		(mid 334.811116 -229.657887)
		(end 335.094072 -229.58171)
		(width 0.0889)
		(layer "In13.Cu")
		(net "M_B_CPU0_SA_DQ<7>")
	)
	(arc
		(start 331.342492 -229.576884)
		(mid 331.526 -229.531359)
		(end 331.708252 -229.58171)
		(width 0.0889)
		(layer "In13.Cu")
		(net "M_B_CPU0_SA_DQ<7>")
	)
	(arc
		(start 329.454002 -229.58171)
		(mid 329.636253 -229.531326)
		(end 329.819762 -229.576884)
		(width 0.0889)
		(layer "In13.Cu")
		(net "M_B_CPU0_SA_DQ<7>")
	)
	(arc
		(start 327.658984 -227.659438)
		(mid 327.710354 -227.716651)
		(end 327.75525 -227.779072)
		(width 0.0889)
		(layer "In13.Cu")
		(net "M_B_CPU0_SA_DQ<7>")
	)
	(arc
		(start 328.44994 -228.789992)
		(mid 328.564616 -228.923326)
		(end 328.605896 -229.094284)
		(width 0.0889)
		(layer "In13.Cu")
		(net "M_B_CPU0_SA_DQ<7>")
	)
	(arc
		(start 325.72579 -225.236024)
		(mid 325.803244 -225.351847)
		(end 325.830438 -225.4885)
		(width 0.0889)
		(layer "In13.Cu")
		(net "M_B_CPU0_SA_DQ<7>")
	)
	(arc
		(start 334.154018 -229.58171)
		(mid 334.336269 -229.531326)
		(end 334.519778 -229.576884)
		(width 0.0889)
		(layer "In13.Cu")
		(net "M_B_CPU0_SA_DQ<7>")
	)
	(arc
		(start 325.830438 -225.602292)
		(mid 325.872418 -225.813428)
		(end 325.991982 -225.992436)
		(width 0.0889)
		(layer "In13.Cu")
		(net "M_B_CPU0_SA_DQ<7>")
	)
	(arc
		(start 327.75525 -227.779072)
		(mid 327.825469 -227.867744)
		(end 327.911968 -227.940616)
		(width 0.0889)
		(layer "In13.Cu")
		(net "M_B_CPU0_SA_DQ<7>")
	)
	(arc
		(start 329.828144 -229.58171)
		(mid 330.1111 -229.657887)
		(end 330.394056 -229.58171)
		(width 0.0889)
		(layer "In13.Cu")
		(net "M_B_CPU0_SA_DQ<7>")
	)
	(arc
		(start 332.648052 -229.58171)
		(mid 332.931008 -229.657887)
		(end 333.213964 -229.58171)
		(width 0.0889)
		(layer "In13.Cu")
		(net "M_B_CPU0_SA_DQ<7>")
	)
	(arc
		(start 332.274164 -229.58171)
		(mid 332.461108 -229.531421)
		(end 332.648052 -229.58171)
		(width 0.0889)
		(layer "In13.Cu")
		(net "M_B_CPU0_SA_DQ<7>")
	)
	(arc
		(start 328.605896 -229.094284)
		(mid 328.671132 -229.357875)
		(end 328.851768 -229.560628)
		(width 0.0889)
		(layer "In13.Cu")
		(net "M_B_CPU0_SA_DQ<7>")
	)
	(arc
		(start 330.402438 -229.576884)
		(mid 330.585946 -229.531359)
		(end 330.768198 -229.58171)
		(width 0.0889)
		(layer "In13.Cu")
		(net "M_B_CPU0_SA_DQ<7>")
	)
	(arc
		(start 336.042508 -229.576884)
		(mid 336.226016 -229.531359)
		(end 336.408268 -229.58171)
		(width 0.0889)
		(layer "In13.Cu")
		(net "M_B_CPU0_SA_DQ<7>")
	)
	(arc
		(start 333.213964 -229.58171)
		(mid 333.396215 -229.531326)
		(end 333.579724 -229.576884)
		(width 0.0889)
		(layer "In13.Cu")
		(net "M_B_CPU0_SA_DQ<7>")
	)
	(arc
		(start 331.708252 -229.58171)
		(mid 331.991208 -229.657887)
		(end 332.274164 -229.58171)
		(width 0.0889)
		(layer "In13.Cu")
		(net "M_B_CPU0_SA_DQ<7>")
	)
	(arc
		(start 333.588106 -229.58171)
		(mid 333.871062 -229.657887)
		(end 334.154018 -229.58171)
		(width 0.0889)
		(layer "In13.Cu")
		(net "M_B_CPU0_SA_DQ<7>")
	)
	(arc
		(start 327.97877 -227.979478)
		(mid 328.094197 -228.112854)
		(end 328.135742 -228.284278)
		(width 0.0889)
		(layer "In13.Cu")
		(net "M_B_CPU0_SA_DQ<7>")
	)
	(arc
		(start 328.88809 -229.58171)
		(mid 329.171046 -229.657887)
		(end 329.454002 -229.58171)
		(width 0.0889)
		(layer "In13.Cu")
		(net "M_B_CPU0_SA_DQ<7>")
	)
	(arc
		(start 335.468214 -229.58171)
		(mid 335.75117 -229.657887)
		(end 336.034126 -229.58171)
		(width 0.0889)
		(layer "In13.Cu")
		(net "M_B_CPU0_SA_DQ<7>")
	)
	(arc
		(start 328.135742 -228.284278)
		(mid 328.200257 -228.546497)
		(end 328.379074 -228.748844)
		(width 0.0889)
		(layer "In13.Cu")
		(net "M_B_CPU0_SA_DQ<7>")
	)
	(arc
		(start 335.102454 -229.576884)
		(mid 335.285962 -229.531359)
		(end 335.468214 -229.58171)
		(width 0.0889)
		(layer "In13.Cu")
		(net "M_B_CPU0_SA_DQ<7>")
	)
	(arc
		(start 330.768198 -229.58171)
		(mid 331.051154 -229.657887)
		(end 331.33411 -229.58171)
		(width 0.0889)
		(layer "In13.Cu")
		(net "M_B_CPU0_SA_DQ<7>")
	)
	(segment
		(start 336.218022 -229.360222)
		(end 335.75117 -229.094284)
		(width 0.10668)
		(layer "F.Cu")
		(net "M_B_CPU0_SA_DQ<6>")
	)
	(segment
		(start 332.16977 -228.766878)
		(end 332.178152 -228.771704)
		(width 0.0889)
		(layer "In13.Cu")
		(net "M_B_CPU0_SA_DQ<6>")
	)
	(segment
		(start 328.41819 -227.151692)
		(end 328.44994 -227.16998)
		(width 0.0889)
		(layer "In13.Cu")
		(net "M_B_CPU0_SA_DQ<6>")
	)
	(segment
		(start 298.162472 -203.710032)
		(end 301.196502 -203.710032)
		(width 0.14478)
		(layer "In13.Cu")
		(net "M_B_CPU0_SA_DQ<6>")
	)
	(segment
		(start 328.88809 -227.961698)
		(end 328.91984 -227.979986)
		(width 0.0889)
		(layer "In13.Cu")
		(net "M_B_CPU0_SA_DQ<6>")
	)
	(segment
		(start 329.319128 -228.748844)
		(end 329.358244 -228.771704)
		(width 0.0889)
		(layer "In13.Cu")
		(net "M_B_CPU0_SA_DQ<6>")
	)
	(segment
		(start 297.091862 -204.658214)
		(end 297.236642 -204.513434)
		(width 0.14478)
		(layer "In13.Cu")
		(net "M_B_CPU0_SA_DQ<6>")
	)
	(segment
		(start 324.447154 -222.44685)
		(end 324.591934 -222.59163)
		(width 0.14478)
		(layer "In13.Cu")
		(net "M_B_CPU0_SA_DQ<6>")
	)
	(segment
		(start 327.911968 -226.320604)
		(end 327.94829 -226.341686)
		(width 0.0889)
		(layer "In13.Cu")
		(net "M_B_CPU0_SA_DQ<6>")
	)
	(segment
		(start 327.47839 -225.53168)
		(end 327.51014 -225.549968)
		(width 0.0889)
		(layer "In13.Cu")
		(net "M_B_CPU0_SA_DQ<6>")
	)
	(segment
		(start 296.685462 -204.513434)
		(end 296.830242 -204.658214)
		(width 0.14478)
		(layer "In13.Cu")
		(net "M_B_CPU0_SA_DQ<6>")
	)
	(segment
		(start 326.968104 -224.698052)
		(end 327.00849 -224.721674)
		(width 0.0889)
		(layer "In13.Cu")
		(net "M_B_CPU0_SA_DQ<6>")
	)
	(segment
		(start 324.447154 -221.119192)
		(end 324.447154 -222.44685)
		(width 0.14478)
		(layer "In13.Cu")
		(net "M_B_CPU0_SA_DQ<6>")
	)
	(segment
		(start 297.381422 -204.134974)
		(end 297.73753 -204.134974)
		(width 0.14478)
		(layer "In13.Cu")
		(net "M_B_CPU0_SA_DQ<6>")
	)
	(segment
		(start 325.892668 -223.074992)
		(end 325.900288 -223.074992)
		(width 0.0889)
		(layer "In13.Cu")
		(net "M_B_CPU0_SA_DQ<6>")
	)
	(segment
		(start 327.00849 -224.721674)
		(end 327.037954 -224.738692)
		(width 0.0889)
		(layer "In13.Cu")
		(net "M_B_CPU0_SA_DQ<6>")
	)
	(segment
		(start 324.591934 -222.59163)
		(end 325.148194 -222.59163)
		(width 0.14478)
		(layer "In13.Cu")
		(net "M_B_CPU0_SA_DQ<6>")
	)
	(segment
		(start 307.316886 -204.56017)
		(end 311.164478 -208.407762)
		(width 0.14478)
		(layer "In13.Cu")
		(net "M_B_CPU0_SA_DQ<6>")
	)
	(segment
		(start 327.94829 -226.341686)
		(end 327.97877 -226.359466)
		(width 0.0889)
		(layer "In13.Cu")
		(net "M_B_CPU0_SA_DQ<6>")
	)
	(segment
		(start 296.830242 -204.658214)
		(end 297.091862 -204.658214)
		(width 0.14478)
		(layer "In13.Cu")
		(net "M_B_CPU0_SA_DQ<6>")
	)
	(segment
		(start 335.596992 -228.828854)
		(end 335.75117 -229.094284)
		(width 0.0889)
		(layer "In13.Cu")
		(net "M_B_CPU0_SA_DQ<6>")
	)
	(segment
		(start 297.236642 -204.279754)
		(end 297.381422 -204.134974)
		(width 0.14478)
		(layer "In13.Cu")
		(net "M_B_CPU0_SA_DQ<6>")
	)
	(segment
		(start 328.851768 -227.940616)
		(end 328.88809 -227.961698)
		(width 0.0889)
		(layer "In13.Cu")
		(net "M_B_CPU0_SA_DQ<6>")
	)
	(segment
		(start 326.504808 -223.892364)
		(end 326.571864 -223.931226)
		(width 0.0889)
		(layer "In13.Cu")
		(net "M_B_CPU0_SA_DQ<6>")
	)
	(segment
		(start 326.41032 -223.812608)
		(end 326.421496 -223.823784)
		(width 0.0889)
		(layer "In13.Cu")
		(net "M_B_CPU0_SA_DQ<6>")
	)
	(segment
		(start 311.735724 -208.407762)
		(end 324.447154 -221.119192)
		(width 0.14478)
		(layer "In13.Cu")
		(net "M_B_CPU0_SA_DQ<6>")
	)
	(segment
		(start 301.196502 -203.710032)
		(end 302.04664 -204.56017)
		(width 0.14478)
		(layer "In13.Cu")
		(net "M_B_CPU0_SA_DQ<6>")
	)
	(segment
		(start 296.540682 -204.134974)
		(end 296.685462 -204.279754)
		(width 0.14478)
		(layer "In13.Cu")
		(net "M_B_CPU0_SA_DQ<6>")
	)
	(segment
		(start 332.744064 -228.771704)
		(end 332.752446 -228.766878)
		(width 0.0889)
		(layer "In13.Cu")
		(net "M_B_CPU0_SA_DQ<6>")
	)
	(segment
		(start 328.379074 -227.128832)
		(end 328.41819 -227.151692)
		(width 0.0889)
		(layer "In13.Cu")
		(net "M_B_CPU0_SA_DQ<6>")
	)
	(segment
		(start 327.438004 -225.508058)
		(end 327.47839 -225.53168)
		(width 0.0889)
		(layer "In13.Cu")
		(net "M_B_CPU0_SA_DQ<6>")
	)
	(segment
		(start 302.04664 -204.56017)
		(end 307.316886 -204.56017)
		(width 0.14478)
		(layer "In13.Cu")
		(net "M_B_CPU0_SA_DQ<6>")
	)
	(segment
		(start 297.236642 -204.513434)
		(end 297.236642 -204.279754)
		(width 0.14478)
		(layer "In13.Cu")
		(net "M_B_CPU0_SA_DQ<6>")
	)
	(segment
		(start 333.684118 -228.771704)
		(end 333.6925 -228.766878)
		(width 0.0889)
		(layer "In13.Cu")
		(net "M_B_CPU0_SA_DQ<6>")
	)
	(segment
		(start 325.148194 -222.59163)
		(end 325.446898 -222.890334)
		(width 0.0889)
		(layer "In13.Cu")
		(net "M_B_CPU0_SA_DQ<6>")
	)
	(segment
		(start 335.500726 -228.803454)
		(end 335.596992 -228.828854)
		(width 0.0889)
		(layer "In13.Cu")
		(net "M_B_CPU0_SA_DQ<6>")
	)
	(segment
		(start 297.73753 -204.134974)
		(end 298.162472 -203.710032)
		(width 0.14478)
		(layer "In13.Cu")
		(net "M_B_CPU0_SA_DQ<6>")
	)
	(segment
		(start 295.724072 -204.134974)
		(end 296.540682 -204.134974)
		(width 0.14478)
		(layer "In13.Cu")
		(net "M_B_CPU0_SA_DQ<6>")
	)
	(segment
		(start 296.685462 -204.279754)
		(end 296.685462 -204.513434)
		(width 0.14478)
		(layer "In13.Cu")
		(net "M_B_CPU0_SA_DQ<6>")
	)
	(segment
		(start 331.229716 -228.766878)
		(end 331.238098 -228.771704)
		(width 0.0889)
		(layer "In13.Cu")
		(net "M_B_CPU0_SA_DQ<6>")
	)
	(segment
		(start 311.164478 -208.407762)
		(end 311.735724 -208.407762)
		(width 0.14478)
		(layer "In13.Cu")
		(net "M_B_CPU0_SA_DQ<6>")
	)
	(arc
		(start 329.924156 -228.771704)
		(mid 330.1111 -228.721449)
		(end 330.298044 -228.771704)
		(width 0.0889)
		(layer "In13.Cu")
		(net "M_B_CPU0_SA_DQ<6>")
	)
	(arc
		(start 332.178152 -228.771704)
		(mid 332.461108 -228.847881)
		(end 332.744064 -228.771704)
		(width 0.0889)
		(layer "In13.Cu")
		(net "M_B_CPU0_SA_DQ<6>")
	)
	(arc
		(start 326.571864 -223.931226)
		(mid 326.685271 -224.064256)
		(end 326.726042 -224.234248)
		(width 0.0889)
		(layer "In13.Cu")
		(net "M_B_CPU0_SA_DQ<6>")
	)
	(arc
		(start 334.05826 -228.771704)
		(mid 334.341216 -228.847881)
		(end 334.624172 -228.771704)
		(width 0.0889)
		(layer "In13.Cu")
		(net "M_B_CPU0_SA_DQ<6>")
	)
	(arc
		(start 330.298044 -228.771704)
		(mid 330.581 -228.847881)
		(end 330.863956 -228.771704)
		(width 0.0889)
		(layer "In13.Cu")
		(net "M_B_CPU0_SA_DQ<6>")
	)
	(arc
		(start 325.900288 -223.074992)
		(mid 326.147245 -223.177285)
		(end 326.249538 -223.424242)
		(width 0.0889)
		(layer "In13.Cu")
		(net "M_B_CPU0_SA_DQ<6>")
	)
	(arc
		(start 333.118206 -228.771704)
		(mid 333.401162 -228.847881)
		(end 333.684118 -228.771704)
		(width 0.0889)
		(layer "In13.Cu")
		(net "M_B_CPU0_SA_DQ<6>")
	)
	(arc
		(start 334.99806 -228.771704)
		(mid 335.245656 -228.846882)
		(end 335.500726 -228.803454)
		(width 0.0889)
		(layer "In13.Cu")
		(net "M_B_CPU0_SA_DQ<6>")
	)
	(arc
		(start 325.446898 -222.890334)
		(mid 325.651419 -223.026991)
		(end 325.892668 -223.074992)
		(width 0.0889)
		(layer "In13.Cu")
		(net "M_B_CPU0_SA_DQ<6>")
	)
	(arc
		(start 327.97877 -226.359466)
		(mid 328.094197 -226.492842)
		(end 328.135742 -226.664266)
		(width 0.0889)
		(layer "In13.Cu")
		(net "M_B_CPU0_SA_DQ<6>")
	)
	(arc
		(start 326.249538 -223.424242)
		(mid 326.291324 -223.634406)
		(end 326.41032 -223.812608)
		(width 0.0889)
		(layer "In13.Cu")
		(net "M_B_CPU0_SA_DQ<6>")
	)
	(arc
		(start 330.863956 -228.771704)
		(mid 331.046207 -228.721354)
		(end 331.229716 -228.766878)
		(width 0.0889)
		(layer "In13.Cu")
		(net "M_B_CPU0_SA_DQ<6>")
	)
	(arc
		(start 334.624172 -228.771704)
		(mid 334.811116 -228.721449)
		(end 334.99806 -228.771704)
		(width 0.0889)
		(layer "In13.Cu")
		(net "M_B_CPU0_SA_DQ<6>")
	)
	(arc
		(start 328.135742 -226.664266)
		(mid 328.200257 -226.926485)
		(end 328.379074 -227.128832)
		(width 0.0889)
		(layer "In13.Cu")
		(net "M_B_CPU0_SA_DQ<6>")
	)
	(arc
		(start 327.51014 -225.549968)
		(mid 327.624816 -225.683302)
		(end 327.666096 -225.85426)
		(width 0.0889)
		(layer "In13.Cu")
		(net "M_B_CPU0_SA_DQ<6>")
	)
	(arc
		(start 327.195688 -225.044254)
		(mid 327.259981 -225.305859)
		(end 327.438004 -225.508058)
		(width 0.0889)
		(layer "In13.Cu")
		(net "M_B_CPU0_SA_DQ<6>")
	)
	(arc
		(start 329.358244 -228.771704)
		(mid 329.6412 -228.847881)
		(end 329.924156 -228.771704)
		(width 0.0889)
		(layer "In13.Cu")
		(net "M_B_CPU0_SA_DQ<6>")
	)
	(arc
		(start 331.238098 -228.771704)
		(mid 331.521054 -228.847881)
		(end 331.80401 -228.771704)
		(width 0.0889)
		(layer "In13.Cu")
		(net "M_B_CPU0_SA_DQ<6>")
	)
	(arc
		(start 333.6925 -228.766878)
		(mid 333.876008 -228.721384)
		(end 334.05826 -228.771704)
		(width 0.0889)
		(layer "In13.Cu")
		(net "M_B_CPU0_SA_DQ<6>")
	)
	(arc
		(start 331.80401 -228.771704)
		(mid 331.986261 -228.721354)
		(end 332.16977 -228.766878)
		(width 0.0889)
		(layer "In13.Cu")
		(net "M_B_CPU0_SA_DQ<6>")
	)
	(arc
		(start 329.075796 -228.284278)
		(mid 329.140311 -228.546497)
		(end 329.319128 -228.748844)
		(width 0.0889)
		(layer "In13.Cu")
		(net "M_B_CPU0_SA_DQ<6>")
	)
	(arc
		(start 327.666096 -225.85426)
		(mid 327.731332 -226.117851)
		(end 327.911968 -226.320604)
		(width 0.0889)
		(layer "In13.Cu")
		(net "M_B_CPU0_SA_DQ<6>")
	)
	(arc
		(start 328.91984 -227.979986)
		(mid 329.034516 -228.11332)
		(end 329.075796 -228.284278)
		(width 0.0889)
		(layer "In13.Cu")
		(net "M_B_CPU0_SA_DQ<6>")
	)
	(arc
		(start 327.037954 -224.738692)
		(mid 327.153907 -224.872325)
		(end 327.195688 -225.044254)
		(width 0.0889)
		(layer "In13.Cu")
		(net "M_B_CPU0_SA_DQ<6>")
	)
	(arc
		(start 328.605896 -227.474272)
		(mid 328.671132 -227.737863)
		(end 328.851768 -227.940616)
		(width 0.0889)
		(layer "In13.Cu")
		(net "M_B_CPU0_SA_DQ<6>")
	)
	(arc
		(start 332.752446 -228.766878)
		(mid 332.935954 -228.721384)
		(end 333.118206 -228.771704)
		(width 0.0889)
		(layer "In13.Cu")
		(net "M_B_CPU0_SA_DQ<6>")
	)
	(arc
		(start 326.726042 -224.234248)
		(mid 326.790195 -224.495837)
		(end 326.968104 -224.698052)
		(width 0.0889)
		(layer "In13.Cu")
		(net "M_B_CPU0_SA_DQ<6>")
	)
	(arc
		(start 328.44994 -227.16998)
		(mid 328.564616 -227.303314)
		(end 328.605896 -227.474272)
		(width 0.0889)
		(layer "In13.Cu")
		(net "M_B_CPU0_SA_DQ<6>")
	)
	(arc
		(start 326.421496 -223.823784)
		(mid 326.461508 -223.860071)
		(end 326.504808 -223.892364)
		(width 0.0889)
		(layer "In13.Cu")
		(net "M_B_CPU0_SA_DQ<6>")
	)
	(segment
		(start 337.158076 -229.360222)
		(end 336.691224 -229.094284)
		(width 0.10668)
		(layer "F.Cu")
		(net "M_B_CPU0_SA_DQ<5>")
	)
	(segment
		(start 303.50714 -205.410054)
		(end 303.737518 -205.410054)
		(width 0.14478)
		(layer "In13.Cu")
		(net "M_B_CPU0_SA_DQ<5>")
	)
	(segment
		(start 312.636154 -210.515454)
		(end 312.821574 -210.700874)
		(width 0.14478)
		(layer "In13.Cu")
		(net "M_B_CPU0_SA_DQ<5>")
	)
	(segment
		(start 305.582066 -205.808072)
		(end 305.74361 -205.646528)
		(width 0.14478)
		(layer "In13.Cu")
		(net "M_B_CPU0_SA_DQ<5>")
	)
	(segment
		(start 306.684934 -205.808072)
		(end 306.846478 -205.646528)
		(width 0.14478)
		(layer "In13.Cu")
		(net "M_B_CPU0_SA_DQ<5>")
	)
	(segment
		(start 304.063654 -205.79207)
		(end 304.294032 -205.79207)
		(width 0.14478)
		(layer "In13.Cu")
		(net "M_B_CPU0_SA_DQ<5>")
	)
	(segment
		(start 312.659268 -210.287616)
		(end 312.636154 -210.31073)
		(width 0.14478)
		(layer "In13.Cu")
		(net "M_B_CPU0_SA_DQ<5>")
	)
	(segment
		(start 323.969634 -222.65005)
		(end 324.365874 -223.04629)
		(width 0.14478)
		(layer "In13.Cu")
		(net "M_B_CPU0_SA_DQ<5>")
	)
	(segment
		(start 312.269124 -209.897726)
		(end 312.473848 -209.897726)
		(width 0.14478)
		(layer "In13.Cu")
		(net "M_B_CPU0_SA_DQ<5>")
	)
	(segment
		(start 311.489344 -209.117946)
		(end 311.694068 -209.117946)
		(width 0.14478)
		(layer "In13.Cu")
		(net "M_B_CPU0_SA_DQ<5>")
	)
	(segment
		(start 316.720474 -214.599774)
		(end 316.92469 -214.59952)
		(width 0.14478)
		(layer "In13.Cu")
		(net "M_B_CPU0_SA_DQ<5>")
	)
	(segment
		(start 328.514202 -228.606858)
		(end 328.550524 -228.62794)
		(width 0.0889)
		(layer "In13.Cu")
		(net "M_B_CPU0_SA_DQ<5>")
	)
	(segment
		(start 305.74361 -205.367636)
		(end 305.905154 -205.206092)
		(width 0.14478)
		(layer "In13.Cu")
		(net "M_B_CPU0_SA_DQ<5>")
	)
	(segment
		(start 314.608464 -212.237066)
		(end 314.813188 -212.237066)
		(width 0.14478)
		(layer "In13.Cu")
		(net "M_B_CPU0_SA_DQ<5>")
	)
	(segment
		(start 325.121016 -223.04629)
		(end 325.315834 -223.241108)
		(width 0.0889)
		(layer "In13.Cu")
		(net "M_B_CPU0_SA_DQ<5>")
	)
	(segment
		(start 313.80557 -211.4804)
		(end 313.828684 -211.457286)
		(width 0.14478)
		(layer "In13.Cu")
		(net "M_B_CPU0_SA_DQ<5>")
	)
	(segment
		(start 304.620168 -205.410054)
		(end 305.030632 -205.410054)
		(width 0.14478)
		(layer "In13.Cu")
		(net "M_B_CPU0_SA_DQ<5>")
	)
	(segment
		(start 313.601354 -211.480654)
		(end 313.80557 -211.4804)
		(width 0.14478)
		(layer "In13.Cu")
		(net "M_B_CPU0_SA_DQ<5>")
	)
	(segment
		(start 313.02579 -210.70062)
		(end 313.048904 -210.677506)
		(width 0.14478)
		(layer "In13.Cu")
		(net "M_B_CPU0_SA_DQ<5>")
	)
	(segment
		(start 316.535054 -214.414354)
		(end 316.720474 -214.599774)
		(width 0.14478)
		(layer "In13.Cu")
		(net "M_B_CPU0_SA_DQ<5>")
	)
	(segment
		(start 303.900586 -205.573122)
		(end 303.900586 -205.629002)
		(width 0.14478)
		(layer "In13.Cu")
		(net "M_B_CPU0_SA_DQ<5>")
	)
	(segment
		(start 313.415934 -211.09051)
		(end 313.415934 -211.295234)
		(width 0.14478)
		(layer "In13.Cu")
		(net "M_B_CPU0_SA_DQ<5>")
	)
	(segment
		(start 306.846478 -205.646528)
		(end 306.846478 -205.571598)
		(width 0.14478)
		(layer "In13.Cu")
		(net "M_B_CPU0_SA_DQ<5>")
	)
	(segment
		(start 300.249082 -204.56017)
		(end 301.174658 -204.56017)
		(width 0.14478)
		(layer "In13.Cu")
		(net "M_B_CPU0_SA_DQ<5>")
	)
	(segment
		(start 323.969634 -221.848934)
		(end 323.969634 -222.65005)
		(width 0.14478)
		(layer "In13.Cu")
		(net "M_B_CPU0_SA_DQ<5>")
	)
	(segment
		(start 311.262014 -209.141314)
		(end 311.46623 -209.14106)
		(width 0.14478)
		(layer "In13.Cu")
		(net "M_B_CPU0_SA_DQ<5>")
	)
	(segment
		(start 335.929732 -229.421436)
		(end 335.938114 -229.41661)
		(width 0.0889)
		(layer "In13.Cu")
		(net "M_B_CPU0_SA_DQ<5>")
	)
	(segment
		(start 325.654924 -223.724724)
		(end 325.694548 -223.747584)
		(width 0.0889)
		(layer "In13.Cu")
		(net "M_B_CPU0_SA_DQ<5>")
	)
	(segment
		(start 302.787558 -205.573122)
		(end 302.787558 -205.629002)
		(width 0.14478)
		(layer "In13.Cu")
		(net "M_B_CPU0_SA_DQ<5>")
	)
	(segment
		(start 313.828684 -211.457286)
		(end 314.033408 -211.457286)
		(width 0.14478)
		(layer "In13.Cu")
		(net "M_B_CPU0_SA_DQ<5>")
	)
	(segment
		(start 315.36513 -213.03996)
		(end 315.388244 -213.016846)
		(width 0.14478)
		(layer "In13.Cu")
		(net "M_B_CPU0_SA_DQ<5>")
	)
	(segment
		(start 331.229716 -229.421436)
		(end 331.238098 -229.41661)
		(width 0.0889)
		(layer "In13.Cu")
		(net "M_B_CPU0_SA_DQ<5>")
	)
	(segment
		(start 315.940694 -213.819994)
		(end 316.14491 -213.81974)
		(width 0.14478)
		(layer "In13.Cu")
		(net "M_B_CPU0_SA_DQ<5>")
	)
	(segment
		(start 314.381134 -212.260434)
		(end 314.58535 -212.26018)
		(width 0.14478)
		(layer "In13.Cu")
		(net "M_B_CPU0_SA_DQ<5>")
	)
	(segment
		(start 315.160914 -213.040214)
		(end 315.36513 -213.03996)
		(width 0.14478)
		(layer "In13.Cu")
		(net "M_B_CPU0_SA_DQ<5>")
	)
	(segment
		(start 315.388244 -213.016846)
		(end 315.592968 -213.016846)
		(width 0.14478)
		(layer "In13.Cu")
		(net "M_B_CPU0_SA_DQ<5>")
	)
	(segment
		(start 315.755274 -213.42985)
		(end 315.755274 -213.634574)
		(width 0.14478)
		(layer "In13.Cu")
		(net "M_B_CPU0_SA_DQ<5>")
	)
	(segment
		(start 332.744064 -229.41661)
		(end 332.752446 -229.421436)
		(width 0.0889)
		(layer "In13.Cu")
		(net "M_B_CPU0_SA_DQ<5>")
	)
	(segment
		(start 328.044048 -227.796852)
		(end 328.083164 -227.819712)
		(width 0.0889)
		(layer "In13.Cu")
		(net "M_B_CPU0_SA_DQ<5>")
	)
	(segment
		(start 315.592968 -213.016846)
		(end 315.778134 -213.202012)
		(width 0.14478)
		(layer "In13.Cu")
		(net "M_B_CPU0_SA_DQ<5>")
	)
	(segment
		(start 304.4571 -205.629002)
		(end 304.4571 -205.573122)
		(width 0.14478)
		(layer "In13.Cu")
		(net "M_B_CPU0_SA_DQ<5>")
	)
	(segment
		(start 312.636154 -210.31073)
		(end 312.636154 -210.515454)
		(width 0.14478)
		(layer "In13.Cu")
		(net "M_B_CPU0_SA_DQ<5>")
	)
	(segment
		(start 304.4571 -205.573122)
		(end 304.620168 -205.410054)
		(width 0.14478)
		(layer "In13.Cu")
		(net "M_B_CPU0_SA_DQ<5>")
	)
	(segment
		(start 311.46623 -209.14106)
		(end 311.489344 -209.117946)
		(width 0.14478)
		(layer "In13.Cu")
		(net "M_B_CPU0_SA_DQ<5>")
	)
	(segment
		(start 314.195714 -212.075014)
		(end 314.381134 -212.260434)
		(width 0.14478)
		(layer "In13.Cu")
		(net "M_B_CPU0_SA_DQ<5>")
	)
	(segment
		(start 312.041794 -209.921094)
		(end 312.24601 -209.92084)
		(width 0.14478)
		(layer "In13.Cu")
		(net "M_B_CPU0_SA_DQ<5>")
	)
	(segment
		(start 326.136508 -224.541334)
		(end 326.164194 -224.557336)
		(width 0.0889)
		(layer "In13.Cu")
		(net "M_B_CPU0_SA_DQ<5>")
	)
	(segment
		(start 317.314834 -215.194134)
		(end 323.969634 -221.848934)
		(width 0.14478)
		(layer "In13.Cu")
		(net "M_B_CPU0_SA_DQ<5>")
	)
	(segment
		(start 327.104502 -226.177602)
		(end 327.140824 -226.198684)
		(width 0.0889)
		(layer "In13.Cu")
		(net "M_B_CPU0_SA_DQ<5>")
	)
	(segment
		(start 327.574148 -226.9871)
		(end 327.609454 -227.007674)
		(width 0.0889)
		(layer "In13.Cu")
		(net "M_B_CPU0_SA_DQ<5>")
	)
	(segment
		(start 312.659014 -210.082892)
		(end 312.659268 -210.287616)
		(width 0.14478)
		(layer "In13.Cu")
		(net "M_B_CPU0_SA_DQ<5>")
	)
	(segment
		(start 316.947804 -214.576406)
		(end 317.152528 -214.576406)
		(width 0.14478)
		(layer "In13.Cu")
		(net "M_B_CPU0_SA_DQ<5>")
	)
	(segment
		(start 324.365874 -223.04629)
		(end 324.904354 -223.04629)
		(width 0.14478)
		(layer "In13.Cu")
		(net "M_B_CPU0_SA_DQ<5>")
	)
	(segment
		(start 311.879488 -209.507836)
		(end 311.856374 -209.53095)
		(width 0.14478)
		(layer "In13.Cu")
		(net "M_B_CPU0_SA_DQ<5>")
	)
	(segment
		(start 306.295044 -205.367636)
		(end 306.295044 -205.646528)
		(width 0.14478)
		(layer "In13.Cu")
		(net "M_B_CPU0_SA_DQ<5>")
	)
	(segment
		(start 302.62449 -205.410054)
		(end 302.787558 -205.573122)
		(width 0.14478)
		(layer "In13.Cu")
		(net "M_B_CPU0_SA_DQ<5>")
	)
	(segment
		(start 316.92469 -214.59952)
		(end 316.947804 -214.576406)
		(width 0.14478)
		(layer "In13.Cu")
		(net "M_B_CPU0_SA_DQ<5>")
	)
	(segment
		(start 315.778388 -213.406736)
		(end 315.755274 -213.42985)
		(width 0.14478)
		(layer "In13.Cu")
		(net "M_B_CPU0_SA_DQ<5>")
	)
	(segment
		(start 304.294032 -205.79207)
		(end 304.4571 -205.629002)
		(width 0.14478)
		(layer "In13.Cu")
		(net "M_B_CPU0_SA_DQ<5>")
	)
	(segment
		(start 317.337948 -214.966296)
		(end 317.314834 -214.98941)
		(width 0.14478)
		(layer "In13.Cu")
		(net "M_B_CPU0_SA_DQ<5>")
	)
	(segment
		(start 324.904354 -223.04629)
		(end 325.121016 -223.04629)
		(width 0.0889)
		(layer "In13.Cu")
		(net "M_B_CPU0_SA_DQ<5>")
	)
	(segment
		(start 305.192176 -205.571598)
		(end 305.192176 -205.646528)
		(width 0.14478)
		(layer "In13.Cu")
		(net "M_B_CPU0_SA_DQ<5>")
	)
	(segment
		(start 314.218828 -211.847176)
		(end 314.195714 -211.87029)
		(width 0.14478)
		(layer "In13.Cu")
		(net "M_B_CPU0_SA_DQ<5>")
	)
	(segment
		(start 316.372748 -213.796626)
		(end 316.557914 -213.981792)
		(width 0.14478)
		(layer "In13.Cu")
		(net "M_B_CPU0_SA_DQ<5>")
	)
	(segment
		(start 327.54697 -226.971352)
		(end 327.574148 -226.9871)
		(width 0.0889)
		(layer "In13.Cu")
		(net "M_B_CPU0_SA_DQ<5>")
	)
	(segment
		(start 305.74361 -205.646528)
		(end 305.74361 -205.367636)
		(width 0.14478)
		(layer "In13.Cu")
		(net "M_B_CPU0_SA_DQ<5>")
	)
	(segment
		(start 314.218574 -211.642452)
		(end 314.218828 -211.847176)
		(width 0.14478)
		(layer "In13.Cu")
		(net "M_B_CPU0_SA_DQ<5>")
	)
	(segment
		(start 333.684118 -229.41661)
		(end 333.6925 -229.421436)
		(width 0.0889)
		(layer "In13.Cu")
		(net "M_B_CPU0_SA_DQ<5>")
	)
	(segment
		(start 313.415934 -211.295234)
		(end 313.601354 -211.480654)
		(width 0.14478)
		(layer "In13.Cu")
		(net "M_B_CPU0_SA_DQ<5>")
	)
	(segment
		(start 312.821574 -210.700874)
		(end 313.02579 -210.70062)
		(width 0.14478)
		(layer "In13.Cu")
		(net "M_B_CPU0_SA_DQ<5>")
	)
	(segment
		(start 336.822796 -229.442772)
		(end 336.845148 -229.359714)
		(width 0.0889)
		(layer "In13.Cu")
		(net "M_B_CPU0_SA_DQ<5>")
	)
	(segment
		(start 312.473848 -209.897726)
		(end 312.659014 -210.082892)
		(width 0.14478)
		(layer "In13.Cu")
		(net "M_B_CPU0_SA_DQ<5>")
	)
	(segment
		(start 307.008022 -205.410054)
		(end 307.530754 -205.410054)
		(width 0.14478)
		(layer "In13.Cu")
		(net "M_B_CPU0_SA_DQ<5>")
	)
	(segment
		(start 317.314834 -214.98941)
		(end 317.314834 -215.194134)
		(width 0.14478)
		(layer "In13.Cu")
		(net "M_B_CPU0_SA_DQ<5>")
	)
	(segment
		(start 302.950626 -205.79207)
		(end 303.181004 -205.79207)
		(width 0.14478)
		(layer "In13.Cu")
		(net "M_B_CPU0_SA_DQ<5>")
	)
	(segment
		(start 328.950574 -229.397052)
		(end 328.984102 -229.41661)
		(width 0.0889)
		(layer "In13.Cu")
		(net "M_B_CPU0_SA_DQ<5>")
	)
	(segment
		(start 317.337694 -214.761572)
		(end 317.337948 -214.966296)
		(width 0.14478)
		(layer "In13.Cu")
		(net "M_B_CPU0_SA_DQ<5>")
	)
	(segment
		(start 316.558168 -214.186516)
		(end 316.535054 -214.20963)
		(width 0.14478)
		(layer "In13.Cu")
		(net "M_B_CPU0_SA_DQ<5>")
	)
	(segment
		(start 299.82414 -204.985112)
		(end 300.249082 -204.56017)
		(width 0.14478)
		(layer "In13.Cu")
		(net "M_B_CPU0_SA_DQ<5>")
	)
	(segment
		(start 306.295044 -205.646528)
		(end 306.456588 -205.808072)
		(width 0.14478)
		(layer "In13.Cu")
		(net "M_B_CPU0_SA_DQ<5>")
	)
	(segment
		(start 332.16977 -229.421436)
		(end 332.178152 -229.41661)
		(width 0.0889)
		(layer "In13.Cu")
		(net "M_B_CPU0_SA_DQ<5>")
	)
	(segment
		(start 311.879234 -209.303112)
		(end 311.879488 -209.507836)
		(width 0.14478)
		(layer "In13.Cu")
		(net "M_B_CPU0_SA_DQ<5>")
	)
	(segment
		(start 314.58535 -212.26018)
		(end 314.608464 -212.237066)
		(width 0.14478)
		(layer "In13.Cu")
		(net "M_B_CPU0_SA_DQ<5>")
	)
	(segment
		(start 301.174658 -204.56017)
		(end 302.024542 -205.410054)
		(width 0.14478)
		(layer "In13.Cu")
		(net "M_B_CPU0_SA_DQ<5>")
	)
	(segment
		(start 314.975494 -212.65007)
		(end 314.975494 -212.854794)
		(width 0.14478)
		(layer "In13.Cu")
		(net "M_B_CPU0_SA_DQ<5>")
	)
	(segment
		(start 325.417942 -223.487742)
		(end 325.654924 -223.724724)
		(width 0.0889)
		(layer "In13.Cu")
		(net "M_B_CPU0_SA_DQ<5>")
	)
	(segment
		(start 303.344072 -205.573122)
		(end 303.50714 -205.410054)
		(width 0.14478)
		(layer "In13.Cu")
		(net "M_B_CPU0_SA_DQ<5>")
	)
	(segment
		(start 326.60463 -225.349816)
		(end 326.634094 -225.366834)
		(width 0.0889)
		(layer "In13.Cu")
		(net "M_B_CPU0_SA_DQ<5>")
	)
	(segment
		(start 302.787558 -205.629002)
		(end 302.950626 -205.79207)
		(width 0.14478)
		(layer "In13.Cu")
		(net "M_B_CPU0_SA_DQ<5>")
	)
	(segment
		(start 326.164194 -224.557336)
		(end 326.191626 -224.573338)
		(width 0.0889)
		(layer "In13.Cu")
		(net "M_B_CPU0_SA_DQ<5>")
	)
	(segment
		(start 316.535054 -214.20963)
		(end 316.535054 -214.414354)
		(width 0.14478)
		(layer "In13.Cu")
		(net "M_B_CPU0_SA_DQ<5>")
	)
	(segment
		(start 328.482452 -228.58857)
		(end 328.514202 -228.606858)
		(width 0.0889)
		(layer "In13.Cu")
		(net "M_B_CPU0_SA_DQ<5>")
	)
	(segment
		(start 303.181004 -205.79207)
		(end 303.344072 -205.629002)
		(width 0.14478)
		(layer "In13.Cu")
		(net "M_B_CPU0_SA_DQ<5>")
	)
	(segment
		(start 313.048904 -210.677506)
		(end 313.253628 -210.677506)
		(width 0.14478)
		(layer "In13.Cu")
		(net "M_B_CPU0_SA_DQ<5>")
	)
	(segment
		(start 306.456588 -205.808072)
		(end 306.684934 -205.808072)
		(width 0.14478)
		(layer "In13.Cu")
		(net "M_B_CPU0_SA_DQ<5>")
	)
	(segment
		(start 305.35372 -205.808072)
		(end 305.582066 -205.808072)
		(width 0.14478)
		(layer "In13.Cu")
		(net "M_B_CPU0_SA_DQ<5>")
	)
	(segment
		(start 314.813188 -212.237066)
		(end 314.998354 -212.422232)
		(width 0.14478)
		(layer "In13.Cu")
		(net "M_B_CPU0_SA_DQ<5>")
	)
	(segment
		(start 303.900586 -205.629002)
		(end 304.063654 -205.79207)
		(width 0.14478)
		(layer "In13.Cu")
		(net "M_B_CPU0_SA_DQ<5>")
	)
	(segment
		(start 315.755274 -213.634574)
		(end 315.940694 -213.819994)
		(width 0.14478)
		(layer "In13.Cu")
		(net "M_B_CPU0_SA_DQ<5>")
	)
	(segment
		(start 305.905154 -205.206092)
		(end 306.1335 -205.206092)
		(width 0.14478)
		(layer "In13.Cu")
		(net "M_B_CPU0_SA_DQ<5>")
	)
	(segment
		(start 311.856374 -209.53095)
		(end 311.856374 -209.735674)
		(width 0.14478)
		(layer "In13.Cu")
		(net "M_B_CPU0_SA_DQ<5>")
	)
	(segment
		(start 315.778134 -213.202012)
		(end 315.778388 -213.406736)
		(width 0.14478)
		(layer "In13.Cu")
		(net "M_B_CPU0_SA_DQ<5>")
	)
	(segment
		(start 316.14491 -213.81974)
		(end 316.168024 -213.796626)
		(width 0.14478)
		(layer "In13.Cu")
		(net "M_B_CPU0_SA_DQ<5>")
	)
	(segment
		(start 305.030632 -205.410054)
		(end 305.192176 -205.571598)
		(width 0.14478)
		(layer "In13.Cu")
		(net "M_B_CPU0_SA_DQ<5>")
	)
	(segment
		(start 312.24601 -209.92084)
		(end 312.269124 -209.897726)
		(width 0.14478)
		(layer "In13.Cu")
		(net "M_B_CPU0_SA_DQ<5>")
	)
	(segment
		(start 327.068942 -226.157028)
		(end 327.104502 -226.177602)
		(width 0.0889)
		(layer "In13.Cu")
		(net "M_B_CPU0_SA_DQ<5>")
	)
	(segment
		(start 316.168024 -213.796626)
		(end 316.372748 -213.796626)
		(width 0.14478)
		(layer "In13.Cu")
		(net "M_B_CPU0_SA_DQ<5>")
	)
	(segment
		(start 314.975494 -212.854794)
		(end 315.160914 -213.040214)
		(width 0.14478)
		(layer "In13.Cu")
		(net "M_B_CPU0_SA_DQ<5>")
	)
	(segment
		(start 328.013568 -227.779072)
		(end 328.044048 -227.796852)
		(width 0.0889)
		(layer "In13.Cu")
		(net "M_B_CPU0_SA_DQ<5>")
	)
	(segment
		(start 314.998608 -212.626956)
		(end 314.975494 -212.65007)
		(width 0.14478)
		(layer "In13.Cu")
		(net "M_B_CPU0_SA_DQ<5>")
	)
	(segment
		(start 302.024542 -205.410054)
		(end 302.62449 -205.410054)
		(width 0.14478)
		(layer "In13.Cu")
		(net "M_B_CPU0_SA_DQ<5>")
	)
	(segment
		(start 311.856374 -209.735674)
		(end 312.041794 -209.921094)
		(width 0.14478)
		(layer "In13.Cu")
		(net "M_B_CPU0_SA_DQ<5>")
	)
	(segment
		(start 326.634094 -225.366834)
		(end 326.67321 -225.389694)
		(width 0.0889)
		(layer "In13.Cu")
		(net "M_B_CPU0_SA_DQ<5>")
	)
	(segment
		(start 313.438794 -210.862672)
		(end 313.439048 -211.067396)
		(width 0.14478)
		(layer "In13.Cu")
		(net "M_B_CPU0_SA_DQ<5>")
	)
	(segment
		(start 314.998354 -212.422232)
		(end 314.998608 -212.626956)
		(width 0.14478)
		(layer "In13.Cu")
		(net "M_B_CPU0_SA_DQ<5>")
	)
	(segment
		(start 316.557914 -213.981792)
		(end 316.558168 -214.186516)
		(width 0.14478)
		(layer "In13.Cu")
		(net "M_B_CPU0_SA_DQ<5>")
	)
	(segment
		(start 305.192176 -205.646528)
		(end 305.35372 -205.808072)
		(width 0.14478)
		(layer "In13.Cu")
		(net "M_B_CPU0_SA_DQ<5>")
	)
	(segment
		(start 314.195714 -211.87029)
		(end 314.195714 -212.075014)
		(width 0.14478)
		(layer "In13.Cu")
		(net "M_B_CPU0_SA_DQ<5>")
	)
	(segment
		(start 336.845148 -229.359714)
		(end 336.691224 -229.094284)
		(width 0.0889)
		(layer "In13.Cu")
		(net "M_B_CPU0_SA_DQ<5>")
	)
	(segment
		(start 307.530754 -205.410054)
		(end 311.262014 -209.141314)
		(width 0.14478)
		(layer "In13.Cu")
		(net "M_B_CPU0_SA_DQ<5>")
	)
	(segment
		(start 314.033408 -211.457286)
		(end 314.218574 -211.642452)
		(width 0.14478)
		(layer "In13.Cu")
		(net "M_B_CPU0_SA_DQ<5>")
	)
	(segment
		(start 313.439048 -211.067396)
		(end 313.415934 -211.09051)
		(width 0.14478)
		(layer "In13.Cu")
		(net "M_B_CPU0_SA_DQ<5>")
	)
	(segment
		(start 325.694548 -223.747584)
		(end 325.737728 -223.77273)
		(width 0.0889)
		(layer "In13.Cu")
		(net "M_B_CPU0_SA_DQ<5>")
	)
	(segment
		(start 317.152528 -214.576406)
		(end 317.337694 -214.761572)
		(width 0.14478)
		(layer "In13.Cu")
		(net "M_B_CPU0_SA_DQ<5>")
	)
	(segment
		(start 306.1335 -205.206092)
		(end 306.295044 -205.367636)
		(width 0.14478)
		(layer "In13.Cu")
		(net "M_B_CPU0_SA_DQ<5>")
	)
	(segment
		(start 311.694068 -209.117946)
		(end 311.879234 -209.303112)
		(width 0.14478)
		(layer "In13.Cu")
		(net "M_B_CPU0_SA_DQ<5>")
	)
	(segment
		(start 313.253628 -210.677506)
		(end 313.438794 -210.862672)
		(width 0.14478)
		(layer "In13.Cu")
		(net "M_B_CPU0_SA_DQ<5>")
	)
	(segment
		(start 328.984102 -229.41661)
		(end 328.992484 -229.421436)
		(width 0.0889)
		(layer "In13.Cu")
		(net "M_B_CPU0_SA_DQ<5>")
	)
	(segment
		(start 303.737518 -205.410054)
		(end 303.900586 -205.573122)
		(width 0.14478)
		(layer "In13.Cu")
		(net "M_B_CPU0_SA_DQ<5>")
	)
	(segment
		(start 303.344072 -205.629002)
		(end 303.344072 -205.573122)
		(width 0.14478)
		(layer "In13.Cu")
		(net "M_B_CPU0_SA_DQ<5>")
	)
	(segment
		(start 306.846478 -205.571598)
		(end 307.008022 -205.410054)
		(width 0.14478)
		(layer "In13.Cu")
		(net "M_B_CPU0_SA_DQ<5>")
	)
	(arc
		(start 325.403718 -223.453452)
		(mid 325.407411 -223.472018)
		(end 325.417942 -223.487742)
		(width 0.0889)
		(layer "In13.Cu")
		(net "M_B_CPU0_SA_DQ<5>")
	)
	(arc
		(start 333.6925 -229.421436)
		(mid 333.876008 -229.466961)
		(end 334.05826 -229.41661)
		(width 0.0889)
		(layer "In13.Cu")
		(net "M_B_CPU0_SA_DQ<5>")
	)
	(arc
		(start 335.563972 -229.41661)
		(mid 335.746223 -229.466994)
		(end 335.929732 -229.421436)
		(width 0.0889)
		(layer "In13.Cu")
		(net "M_B_CPU0_SA_DQ<5>")
	)
	(arc
		(start 336.504026 -229.41661)
		(mid 336.660464 -229.465615)
		(end 336.822796 -229.442772)
		(width 0.0889)
		(layer "In13.Cu")
		(net "M_B_CPU0_SA_DQ<5>")
	)
	(arc
		(start 325.737728 -223.77273)
		(mid 325.913272 -223.974435)
		(end 325.976488 -224.234248)
		(width 0.0889)
		(layer "In13.Cu")
		(net "M_B_CPU0_SA_DQ<5>")
	)
	(arc
		(start 328.796396 -229.094284)
		(mid 328.837158 -229.264168)
		(end 328.950574 -229.397052)
		(width 0.0889)
		(layer "In13.Cu")
		(net "M_B_CPU0_SA_DQ<5>")
	)
	(arc
		(start 327.386696 -226.66452)
		(mid 327.429228 -226.837583)
		(end 327.54697 -226.971352)
		(width 0.0889)
		(layer "In13.Cu")
		(net "M_B_CPU0_SA_DQ<5>")
	)
	(arc
		(start 332.178152 -229.41661)
		(mid 332.461108 -229.340433)
		(end 332.744064 -229.41661)
		(width 0.0889)
		(layer "In13.Cu")
		(net "M_B_CPU0_SA_DQ<5>")
	)
	(arc
		(start 327.856596 -227.474272)
		(mid 327.898145 -227.645694)
		(end 328.013568 -227.779072)
		(width 0.0889)
		(layer "In13.Cu")
		(net "M_B_CPU0_SA_DQ<5>")
	)
	(arc
		(start 326.67321 -225.389694)
		(mid 326.852122 -225.592407)
		(end 326.916542 -225.855022)
		(width 0.0889)
		(layer "In13.Cu")
		(net "M_B_CPU0_SA_DQ<5>")
	)
	(arc
		(start 332.752446 -229.421436)
		(mid 332.935954 -229.466961)
		(end 333.118206 -229.41661)
		(width 0.0889)
		(layer "In13.Cu")
		(net "M_B_CPU0_SA_DQ<5>")
	)
	(arc
		(start 334.624172 -229.41661)
		(mid 334.811116 -229.466899)
		(end 334.99806 -229.41661)
		(width 0.0889)
		(layer "In13.Cu")
		(net "M_B_CPU0_SA_DQ<5>")
	)
	(arc
		(start 331.238098 -229.41661)
		(mid 331.521054 -229.340433)
		(end 331.80401 -229.41661)
		(width 0.0889)
		(layer "In13.Cu")
		(net "M_B_CPU0_SA_DQ<5>")
	)
	(arc
		(start 329.924156 -229.41661)
		(mid 330.1111 -229.466899)
		(end 330.298044 -229.41661)
		(width 0.0889)
		(layer "In13.Cu")
		(net "M_B_CPU0_SA_DQ<5>")
	)
	(arc
		(start 325.976488 -224.234248)
		(mid 326.018894 -224.407385)
		(end 326.136508 -224.541334)
		(width 0.0889)
		(layer "In13.Cu")
		(net "M_B_CPU0_SA_DQ<5>")
	)
	(arc
		(start 333.118206 -229.41661)
		(mid 333.401162 -229.340433)
		(end 333.684118 -229.41661)
		(width 0.0889)
		(layer "In13.Cu")
		(net "M_B_CPU0_SA_DQ<5>")
	)
	(arc
		(start 334.99806 -229.41661)
		(mid 335.281016 -229.340433)
		(end 335.563972 -229.41661)
		(width 0.0889)
		(layer "In13.Cu")
		(net "M_B_CPU0_SA_DQ<5>")
	)
	(arc
		(start 331.80401 -229.41661)
		(mid 331.986261 -229.466994)
		(end 332.16977 -229.421436)
		(width 0.0889)
		(layer "In13.Cu")
		(net "M_B_CPU0_SA_DQ<5>")
	)
	(arc
		(start 326.446642 -225.044508)
		(mid 326.488541 -225.216353)
		(end 326.60463 -225.349816)
		(width 0.0889)
		(layer "In13.Cu")
		(net "M_B_CPU0_SA_DQ<5>")
	)
	(arc
		(start 327.609454 -227.007674)
		(mid 327.790836 -227.210343)
		(end 327.856596 -227.474272)
		(width 0.0889)
		(layer "In13.Cu")
		(net "M_B_CPU0_SA_DQ<5>")
	)
	(arc
		(start 328.992484 -229.421436)
		(mid 329.175992 -229.466961)
		(end 329.358244 -229.41661)
		(width 0.0889)
		(layer "In13.Cu")
		(net "M_B_CPU0_SA_DQ<5>")
	)
	(arc
		(start 334.05826 -229.41661)
		(mid 334.341216 -229.340433)
		(end 334.624172 -229.41661)
		(width 0.0889)
		(layer "In13.Cu")
		(net "M_B_CPU0_SA_DQ<5>")
	)
	(arc
		(start 326.191626 -224.573338)
		(mid 326.378496 -224.776778)
		(end 326.446642 -225.044508)
		(width 0.0889)
		(layer "In13.Cu")
		(net "M_B_CPU0_SA_DQ<5>")
	)
	(arc
		(start 330.298044 -229.41661)
		(mid 330.581 -229.340433)
		(end 330.863956 -229.41661)
		(width 0.0889)
		(layer "In13.Cu")
		(net "M_B_CPU0_SA_DQ<5>")
	)
	(arc
		(start 326.916542 -225.855022)
		(mid 326.956749 -226.024187)
		(end 327.068942 -226.157028)
		(width 0.0889)
		(layer "In13.Cu")
		(net "M_B_CPU0_SA_DQ<5>")
	)
	(arc
		(start 328.326496 -228.284278)
		(mid 328.367751 -228.455249)
		(end 328.482452 -228.58857)
		(width 0.0889)
		(layer "In13.Cu")
		(net "M_B_CPU0_SA_DQ<5>")
	)
	(arc
		(start 328.550524 -228.62794)
		(mid 328.731176 -228.830685)
		(end 328.796396 -229.094284)
		(width 0.0889)
		(layer "In13.Cu")
		(net "M_B_CPU0_SA_DQ<5>")
	)
	(arc
		(start 328.083164 -227.819712)
		(mid 328.261977 -228.022062)
		(end 328.326496 -228.284278)
		(width 0.0889)
		(layer "In13.Cu")
		(net "M_B_CPU0_SA_DQ<5>")
	)
	(arc
		(start 335.938114 -229.41661)
		(mid 336.22107 -229.340433)
		(end 336.504026 -229.41661)
		(width 0.0889)
		(layer "In13.Cu")
		(net "M_B_CPU0_SA_DQ<5>")
	)
	(arc
		(start 327.140824 -226.198684)
		(mid 327.321358 -226.401204)
		(end 327.386696 -226.66452)
		(width 0.0889)
		(layer "In13.Cu")
		(net "M_B_CPU0_SA_DQ<5>")
	)
	(arc
		(start 329.358244 -229.41661)
		(mid 329.6412 -229.340433)
		(end 329.924156 -229.41661)
		(width 0.0889)
		(layer "In13.Cu")
		(net "M_B_CPU0_SA_DQ<5>")
	)
	(arc
		(start 325.315834 -223.241108)
		(mid 325.380877 -223.338546)
		(end 325.403718 -223.453452)
		(width 0.0889)
		(layer "In13.Cu")
		(net "M_B_CPU0_SA_DQ<5>")
	)
	(arc
		(start 330.863956 -229.41661)
		(mid 331.046207 -229.466994)
		(end 331.229716 -229.421436)
		(width 0.0889)
		(layer "In13.Cu")
		(net "M_B_CPU0_SA_DQ<5>")
	)
	(segment
		(start 335.747868 -228.550216)
		(end 335.281016 -228.284278)
		(width 0.10668)
		(layer "F.Cu")
		(net "M_B_CPU0_SA_DQ<4>")
	)
	(segment
		(start 309.955946 -206.285846)
		(end 310.00065 -206.241142)
		(width 0.14478)
		(layer "In13.Cu")
		(net "M_B_CPU0_SA_DQ<4>")
	)
	(segment
		(start 328.044048 -226.17684)
		(end 328.083164 -226.1997)
		(width 0.0889)
		(layer "In13.Cu")
		(net "M_B_CPU0_SA_DQ<4>")
	)
	(segment
		(start 305.373278 -204.079602)
		(end 305.518058 -203.934822)
		(width 0.14478)
		(layer "In13.Cu")
		(net "M_B_CPU0_SA_DQ<4>")
	)
	(segment
		(start 309.751222 -206.285846)
		(end 309.955946 -206.285846)
		(width 0.14478)
		(layer "In13.Cu")
		(net "M_B_CPU0_SA_DQ<4>")
	)
	(segment
		(start 309.566056 -205.895956)
		(end 309.566056 -206.10068)
		(width 0.14478)
		(layer "In13.Cu")
		(net "M_B_CPU0_SA_DQ<4>")
	)
	(segment
		(start 306.214018 -204.079602)
		(end 306.475638 -204.079602)
		(width 0.14478)
		(layer "In13.Cu")
		(net "M_B_CPU0_SA_DQ<4>")
	)
	(segment
		(start 308.786276 -205.116176)
		(end 308.786276 -205.3209)
		(width 0.14478)
		(layer "In13.Cu")
		(net "M_B_CPU0_SA_DQ<4>")
	)
	(segment
		(start 306.620418 -203.864464)
		(end 306.765198 -203.719684)
		(width 0.14478)
		(layer "In13.Cu")
		(net "M_B_CPU0_SA_DQ<4>")
	)
	(segment
		(start 306.069238 -203.864464)
		(end 306.069238 -203.934822)
		(width 0.14478)
		(layer "In13.Cu")
		(net "M_B_CPU0_SA_DQ<4>")
	)
	(segment
		(start 311.310782 -207.845406)
		(end 311.515506 -207.845406)
		(width 0.14478)
		(layer "In13.Cu")
		(net "M_B_CPU0_SA_DQ<4>")
	)
	(segment
		(start 303.720754 -202.968352)
		(end 303.720754 -203.857352)
		(width 0.14478)
		(layer "In13.Cu")
		(net "M_B_CPU0_SA_DQ<4>")
	)
	(segment
		(start 302.184562 -204.002132)
		(end 303.024794 -204.002132)
		(width 0.14478)
		(layer "In13.Cu")
		(net "M_B_CPU0_SA_DQ<4>")
	)
	(segment
		(start 305.924458 -203.719684)
		(end 306.069238 -203.864464)
		(width 0.14478)
		(layer "In13.Cu")
		(net "M_B_CPU0_SA_DQ<4>")
	)
	(segment
		(start 300.557438 -203.115672)
		(end 300.557438 -203.034392)
		(width 0.14478)
		(layer "In13.Cu")
		(net "M_B_CPU0_SA_DQ<4>")
	)
	(segment
		(start 335.435194 -228.549708)
		(end 335.281016 -228.284278)
		(width 0.0889)
		(layer "In13.Cu")
		(net "M_B_CPU0_SA_DQ<4>")
	)
	(segment
		(start 327.542398 -225.348546)
		(end 327.574148 -225.366834)
		(width 0.0889)
		(layer "In13.Cu")
		(net "M_B_CPU0_SA_DQ<4>")
	)
	(segment
		(start 308.971442 -205.506066)
		(end 309.176166 -205.506066)
		(width 0.14478)
		(layer "In13.Cu")
		(net "M_B_CPU0_SA_DQ<4>")
	)
	(segment
		(start 308.83098 -205.071472)
		(end 308.786276 -205.116176)
		(width 0.14478)
		(layer "In13.Cu")
		(net "M_B_CPU0_SA_DQ<4>")
	)
	(segment
		(start 335.412842 -228.63302)
		(end 335.435194 -228.549708)
		(width 0.0889)
		(layer "In13.Cu")
		(net "M_B_CPU0_SA_DQ<4>")
	)
	(segment
		(start 311.17032 -207.410812)
		(end 311.125616 -207.455516)
		(width 0.14478)
		(layer "In13.Cu")
		(net "M_B_CPU0_SA_DQ<4>")
	)
	(segment
		(start 309.566056 -206.10068)
		(end 309.751222 -206.285846)
		(width 0.14478)
		(layer "In13.Cu")
		(net "M_B_CPU0_SA_DQ<4>")
	)
	(segment
		(start 304.966878 -203.934822)
		(end 305.111658 -204.079602)
		(width 0.14478)
		(layer "In13.Cu")
		(net "M_B_CPU0_SA_DQ<4>")
	)
	(segment
		(start 300.557438 -203.034392)
		(end 300.702218 -202.889612)
		(width 0.14478)
		(layer "In13.Cu")
		(net "M_B_CPU0_SA_DQ<4>")
	)
	(segment
		(start 311.764934 -207.800702)
		(end 325.167498 -221.203266)
		(width 0.14478)
		(layer "In13.Cu")
		(net "M_B_CPU0_SA_DQ<4>")
	)
	(segment
		(start 307.683916 -203.719684)
		(end 308.0512 -204.086968)
		(width 0.14478)
		(layer "In13.Cu")
		(net "M_B_CPU0_SA_DQ<4>")
	)
	(segment
		(start 304.158396 -204.002132)
		(end 304.440844 -203.719684)
		(width 0.14478)
		(layer "In13.Cu")
		(net "M_B_CPU0_SA_DQ<4>")
	)
	(segment
		(start 308.0512 -204.291692)
		(end 308.006496 -204.336396)
		(width 0.14478)
		(layer "In13.Cu")
		(net "M_B_CPU0_SA_DQ<4>")
	)
	(segment
		(start 311.56021 -207.800702)
		(end 311.764934 -207.800702)
		(width 0.14478)
		(layer "In13.Cu")
		(net "M_B_CPU0_SA_DQ<4>")
	)
	(segment
		(start 310.985154 -207.020922)
		(end 311.17032 -207.206088)
		(width 0.14478)
		(layer "In13.Cu")
		(net "M_B_CPU0_SA_DQ<4>")
	)
	(segment
		(start 303.024794 -204.002132)
		(end 303.169574 -203.857352)
		(width 0.14478)
		(layer "In13.Cu")
		(net "M_B_CPU0_SA_DQ<4>")
	)
	(segment
		(start 310.205374 -206.241142)
		(end 310.39054 -206.426308)
		(width 0.14478)
		(layer "In13.Cu")
		(net "M_B_CPU0_SA_DQ<4>")
	)
	(segment
		(start 308.645814 -204.681582)
		(end 308.83098 -204.866748)
		(width 0.14478)
		(layer "In13.Cu")
		(net "M_B_CPU0_SA_DQ<4>")
	)
	(segment
		(start 329.819762 -228.611684)
		(end 329.828144 -228.606858)
		(width 0.0889)
		(layer "In13.Cu")
		(net "M_B_CPU0_SA_DQ<4>")
	)
	(segment
		(start 303.169574 -202.964288)
		(end 303.314354 -202.819508)
		(width 0.14478)
		(layer "In13.Cu")
		(net "M_B_CPU0_SA_DQ<4>")
	)
	(segment
		(start 308.0512 -204.086968)
		(end 308.0512 -204.291692)
		(width 0.14478)
		(layer "In13.Cu")
		(net "M_B_CPU0_SA_DQ<4>")
	)
	(segment
		(start 325.657718 -222.442532)
		(end 326.134222 -222.919036)
		(width 0.0889)
		(layer "In13.Cu")
		(net "M_B_CPU0_SA_DQ<4>")
	)
	(segment
		(start 326.164702 -222.936816)
		(end 326.197976 -222.95612)
		(width 0.0889)
		(layer "In13.Cu")
		(net "M_B_CPU0_SA_DQ<4>")
	)
	(segment
		(start 335.094072 -228.606858)
		(end 335.102454 -228.611684)
		(width 0.0889)
		(layer "In13.Cu")
		(net "M_B_CPU0_SA_DQ<4>")
	)
	(segment
		(start 303.865534 -204.002132)
		(end 304.158396 -204.002132)
		(width 0.14478)
		(layer "In13.Cu")
		(net "M_B_CPU0_SA_DQ<4>")
	)
	(segment
		(start 308.44109 -204.681582)
		(end 308.645814 -204.681582)
		(width 0.14478)
		(layer "In13.Cu")
		(net "M_B_CPU0_SA_DQ<4>")
	)
	(segment
		(start 311.17032 -207.206088)
		(end 311.17032 -207.410812)
		(width 0.14478)
		(layer "In13.Cu")
		(net "M_B_CPU0_SA_DQ<4>")
	)
	(segment
		(start 328.013568 -226.15906)
		(end 328.044048 -226.17684)
		(width 0.0889)
		(layer "In13.Cu")
		(net "M_B_CPU0_SA_DQ<4>")
	)
	(segment
		(start 311.515506 -207.845406)
		(end 311.56021 -207.800702)
		(width 0.14478)
		(layer "In13.Cu")
		(net "M_B_CPU0_SA_DQ<4>")
	)
	(segment
		(start 328.514202 -226.986846)
		(end 328.550524 -227.007928)
		(width 0.0889)
		(layer "In13.Cu")
		(net "M_B_CPU0_SA_DQ<4>")
	)
	(segment
		(start 306.620418 -203.934822)
		(end 306.620418 -203.864464)
		(width 0.14478)
		(layer "In13.Cu")
		(net "M_B_CPU0_SA_DQ<4>")
	)
	(segment
		(start 326.634094 -223.746822)
		(end 326.676004 -223.771206)
		(width 0.0889)
		(layer "In13.Cu")
		(net "M_B_CPU0_SA_DQ<4>")
	)
	(segment
		(start 310.735726 -207.065626)
		(end 310.78043 -207.020922)
		(width 0.14478)
		(layer "In13.Cu")
		(net "M_B_CPU0_SA_DQ<4>")
	)
	(segment
		(start 325.167498 -221.967552)
		(end 325.642478 -222.442532)
		(width 0.14478)
		(layer "In13.Cu")
		(net "M_B_CPU0_SA_DQ<4>")
	)
	(segment
		(start 309.425594 -205.461362)
		(end 309.61076 -205.646528)
		(width 0.14478)
		(layer "In13.Cu")
		(net "M_B_CPU0_SA_DQ<4>")
	)
	(segment
		(start 309.61076 -205.646528)
		(end 309.61076 -205.851252)
		(width 0.14478)
		(layer "In13.Cu")
		(net "M_B_CPU0_SA_DQ<4>")
	)
	(segment
		(start 310.78043 -207.020922)
		(end 310.985154 -207.020922)
		(width 0.14478)
		(layer "In13.Cu")
		(net "M_B_CPU0_SA_DQ<4>")
	)
	(segment
		(start 329.423522 -228.589078)
		(end 329.454002 -228.606858)
		(width 0.0889)
		(layer "In13.Cu")
		(net "M_B_CPU0_SA_DQ<4>")
	)
	(segment
		(start 310.345836 -206.88046)
		(end 310.531002 -207.065626)
		(width 0.14478)
		(layer "In13.Cu")
		(net "M_B_CPU0_SA_DQ<4>")
	)
	(segment
		(start 304.822098 -203.719684)
		(end 304.966878 -203.864464)
		(width 0.14478)
		(layer "In13.Cu")
		(net "M_B_CPU0_SA_DQ<4>")
	)
	(segment
		(start 303.720754 -203.857352)
		(end 303.865534 -204.002132)
		(width 0.14478)
		(layer "In13.Cu")
		(net "M_B_CPU0_SA_DQ<4>")
	)
	(segment
		(start 299.82414 -203.28509)
		(end 299.848778 -203.260452)
		(width 0.14478)
		(layer "In13.Cu")
		(net "M_B_CPU0_SA_DQ<4>")
	)
	(segment
		(start 327.574148 -225.366834)
		(end 327.611994 -225.388678)
		(width 0.0889)
		(layer "In13.Cu")
		(net "M_B_CPU0_SA_DQ<4>")
	)
	(segment
		(start 309.176166 -205.506066)
		(end 309.22087 -205.461362)
		(width 0.14478)
		(layer "In13.Cu")
		(net "M_B_CPU0_SA_DQ<4>")
	)
	(segment
		(start 306.475638 -204.079602)
		(end 306.620418 -203.934822)
		(width 0.14478)
		(layer "In13.Cu")
		(net "M_B_CPU0_SA_DQ<4>")
	)
	(segment
		(start 305.518058 -203.934822)
		(end 305.518058 -203.864464)
		(width 0.14478)
		(layer "In13.Cu")
		(net "M_B_CPU0_SA_DQ<4>")
	)
	(segment
		(start 326.60463 -223.729804)
		(end 326.634094 -223.746822)
		(width 0.0889)
		(layer "In13.Cu")
		(net "M_B_CPU0_SA_DQ<4>")
	)
	(segment
		(start 310.00065 -206.241142)
		(end 310.205374 -206.241142)
		(width 0.14478)
		(layer "In13.Cu")
		(net "M_B_CPU0_SA_DQ<4>")
	)
	(segment
		(start 303.314354 -202.819508)
		(end 303.57191 -202.819508)
		(width 0.14478)
		(layer "In13.Cu")
		(net "M_B_CPU0_SA_DQ<4>")
	)
	(segment
		(start 311.125616 -207.66024)
		(end 311.310782 -207.845406)
		(width 0.14478)
		(layer "In13.Cu")
		(net "M_B_CPU0_SA_DQ<4>")
	)
	(segment
		(start 308.396386 -204.726286)
		(end 308.44109 -204.681582)
		(width 0.14478)
		(layer "In13.Cu")
		(net "M_B_CPU0_SA_DQ<4>")
	)
	(segment
		(start 325.167498 -221.203266)
		(end 325.167498 -221.967552)
		(width 0.14478)
		(layer "In13.Cu")
		(net "M_B_CPU0_SA_DQ<4>")
	)
	(segment
		(start 325.642478 -222.442532)
		(end 325.657718 -222.442532)
		(width 0.0889)
		(layer "In13.Cu")
		(net "M_B_CPU0_SA_DQ<4>")
	)
	(segment
		(start 300.412658 -203.260452)
		(end 300.557438 -203.115672)
		(width 0.14478)
		(layer "In13.Cu")
		(net "M_B_CPU0_SA_DQ<4>")
	)
	(segment
		(start 300.963838 -202.889612)
		(end 301.108618 -203.034392)
		(width 0.14478)
		(layer "In13.Cu")
		(net "M_B_CPU0_SA_DQ<4>")
	)
	(segment
		(start 305.518058 -203.864464)
		(end 305.662838 -203.719684)
		(width 0.14478)
		(layer "In13.Cu")
		(net "M_B_CPU0_SA_DQ<4>")
	)
	(segment
		(start 327.072498 -224.53854)
		(end 327.104248 -224.556828)
		(width 0.0889)
		(layer "In13.Cu")
		(net "M_B_CPU0_SA_DQ<4>")
	)
	(segment
		(start 328.952352 -227.778564)
		(end 328.984102 -227.796852)
		(width 0.0889)
		(layer "In13.Cu")
		(net "M_B_CPU0_SA_DQ<4>")
	)
	(segment
		(start 303.57191 -202.819508)
		(end 303.720754 -202.968352)
		(width 0.14478)
		(layer "In13.Cu")
		(net "M_B_CPU0_SA_DQ<4>")
	)
	(segment
		(start 310.39054 -206.426308)
		(end 310.39054 -206.631032)
		(width 0.14478)
		(layer "In13.Cu")
		(net "M_B_CPU0_SA_DQ<4>")
	)
	(segment
		(start 308.006496 -204.54112)
		(end 308.191662 -204.726286)
		(width 0.14478)
		(layer "In13.Cu")
		(net "M_B_CPU0_SA_DQ<4>")
	)
	(segment
		(start 328.482452 -226.968558)
		(end 328.514202 -226.986846)
		(width 0.0889)
		(layer "In13.Cu")
		(net "M_B_CPU0_SA_DQ<4>")
	)
	(segment
		(start 301.108618 -203.115672)
		(end 301.253398 -203.260452)
		(width 0.14478)
		(layer "In13.Cu")
		(net "M_B_CPU0_SA_DQ<4>")
	)
	(segment
		(start 333.579724 -228.611684)
		(end 333.588106 -228.606858)
		(width 0.0889)
		(layer "In13.Cu")
		(net "M_B_CPU0_SA_DQ<4>")
	)
	(segment
		(start 305.662838 -203.719684)
		(end 305.924458 -203.719684)
		(width 0.14478)
		(layer "In13.Cu")
		(net "M_B_CPU0_SA_DQ<4>")
	)
	(segment
		(start 299.848778 -203.260452)
		(end 300.412658 -203.260452)
		(width 0.14478)
		(layer "In13.Cu")
		(net "M_B_CPU0_SA_DQ<4>")
	)
	(segment
		(start 308.006496 -204.336396)
		(end 308.006496 -204.54112)
		(width 0.14478)
		(layer "In13.Cu")
		(net "M_B_CPU0_SA_DQ<4>")
	)
	(segment
		(start 326.134222 -222.919036)
		(end 326.164702 -222.936816)
		(width 0.0889)
		(layer "In13.Cu")
		(net "M_B_CPU0_SA_DQ<4>")
	)
	(segment
		(start 311.125616 -207.455516)
		(end 311.125616 -207.66024)
		(width 0.14478)
		(layer "In13.Cu")
		(net "M_B_CPU0_SA_DQ<4>")
	)
	(segment
		(start 301.442882 -203.260452)
		(end 302.184562 -204.002132)
		(width 0.14478)
		(layer "In13.Cu")
		(net "M_B_CPU0_SA_DQ<4>")
	)
	(segment
		(start 310.345836 -206.675736)
		(end 310.345836 -206.88046)
		(width 0.14478)
		(layer "In13.Cu")
		(net "M_B_CPU0_SA_DQ<4>")
	)
	(segment
		(start 328.984102 -227.796852)
		(end 329.023218 -227.819712)
		(width 0.0889)
		(layer "In13.Cu")
		(net "M_B_CPU0_SA_DQ<4>")
	)
	(segment
		(start 310.39054 -206.631032)
		(end 310.345836 -206.675736)
		(width 0.14478)
		(layer "In13.Cu")
		(net "M_B_CPU0_SA_DQ<4>")
	)
	(segment
		(start 310.531002 -207.065626)
		(end 310.735726 -207.065626)
		(width 0.14478)
		(layer "In13.Cu")
		(net "M_B_CPU0_SA_DQ<4>")
	)
	(segment
		(start 306.069238 -203.934822)
		(end 306.214018 -204.079602)
		(width 0.14478)
		(layer "In13.Cu")
		(net "M_B_CPU0_SA_DQ<4>")
	)
	(segment
		(start 308.83098 -204.866748)
		(end 308.83098 -205.071472)
		(width 0.14478)
		(layer "In13.Cu")
		(net "M_B_CPU0_SA_DQ<4>")
	)
	(segment
		(start 304.966878 -203.864464)
		(end 304.966878 -203.934822)
		(width 0.14478)
		(layer "In13.Cu")
		(net "M_B_CPU0_SA_DQ<4>")
	)
	(segment
		(start 303.169574 -203.857352)
		(end 303.169574 -202.964288)
		(width 0.14478)
		(layer "In13.Cu")
		(net "M_B_CPU0_SA_DQ<4>")
	)
	(segment
		(start 309.22087 -205.461362)
		(end 309.425594 -205.461362)
		(width 0.14478)
		(layer "In13.Cu")
		(net "M_B_CPU0_SA_DQ<4>")
	)
	(segment
		(start 301.253398 -203.260452)
		(end 301.442882 -203.260452)
		(width 0.14478)
		(layer "In13.Cu")
		(net "M_B_CPU0_SA_DQ<4>")
	)
	(segment
		(start 327.104248 -224.556828)
		(end 327.14184 -224.578672)
		(width 0.0889)
		(layer "In13.Cu")
		(net "M_B_CPU0_SA_DQ<4>")
	)
	(segment
		(start 331.33411 -228.606858)
		(end 331.342492 -228.611684)
		(width 0.0889)
		(layer "In13.Cu")
		(net "M_B_CPU0_SA_DQ<4>")
	)
	(segment
		(start 305.111658 -204.079602)
		(end 305.373278 -204.079602)
		(width 0.14478)
		(layer "In13.Cu")
		(net "M_B_CPU0_SA_DQ<4>")
	)
	(segment
		(start 308.786276 -205.3209)
		(end 308.971442 -205.506066)
		(width 0.14478)
		(layer "In13.Cu")
		(net "M_B_CPU0_SA_DQ<4>")
	)
	(segment
		(start 330.394056 -228.606858)
		(end 330.402438 -228.611684)
		(width 0.0889)
		(layer "In13.Cu")
		(net "M_B_CPU0_SA_DQ<4>")
	)
	(segment
		(start 308.191662 -204.726286)
		(end 308.396386 -204.726286)
		(width 0.14478)
		(layer "In13.Cu")
		(net "M_B_CPU0_SA_DQ<4>")
	)
	(segment
		(start 309.61076 -205.851252)
		(end 309.566056 -205.895956)
		(width 0.14478)
		(layer "In13.Cu")
		(net "M_B_CPU0_SA_DQ<4>")
	)
	(segment
		(start 304.440844 -203.719684)
		(end 304.822098 -203.719684)
		(width 0.14478)
		(layer "In13.Cu")
		(net "M_B_CPU0_SA_DQ<4>")
	)
	(segment
		(start 334.519778 -228.611684)
		(end 334.52816 -228.606858)
		(width 0.0889)
		(layer "In13.Cu")
		(net "M_B_CPU0_SA_DQ<4>")
	)
	(segment
		(start 301.108618 -203.034392)
		(end 301.108618 -203.115672)
		(width 0.14478)
		(layer "In13.Cu")
		(net "M_B_CPU0_SA_DQ<4>")
	)
	(segment
		(start 306.765198 -203.719684)
		(end 307.683916 -203.719684)
		(width 0.14478)
		(layer "In13.Cu")
		(net "M_B_CPU0_SA_DQ<4>")
	)
	(segment
		(start 300.702218 -202.889612)
		(end 300.963838 -202.889612)
		(width 0.14478)
		(layer "In13.Cu")
		(net "M_B_CPU0_SA_DQ<4>")
	)
	(arc
		(start 332.274164 -228.606858)
		(mid 332.461108 -228.657113)
		(end 332.648052 -228.606858)
		(width 0.0889)
		(layer "In13.Cu")
		(net "M_B_CPU0_SA_DQ<4>")
	)
	(arc
		(start 330.768198 -228.606858)
		(mid 331.051154 -228.530681)
		(end 331.33411 -228.606858)
		(width 0.0889)
		(layer "In13.Cu")
		(net "M_B_CPU0_SA_DQ<4>")
	)
	(arc
		(start 327.611994 -225.388678)
		(mid 327.791723 -225.591298)
		(end 327.856596 -225.85426)
		(width 0.0889)
		(layer "In13.Cu")
		(net "M_B_CPU0_SA_DQ<4>")
	)
	(arc
		(start 329.26655 -228.284278)
		(mid 329.308099 -228.4557)
		(end 329.423522 -228.589078)
		(width 0.0889)
		(layer "In13.Cu")
		(net "M_B_CPU0_SA_DQ<4>")
	)
	(arc
		(start 329.023218 -227.819712)
		(mid 329.202031 -228.022062)
		(end 329.26655 -228.284278)
		(width 0.0889)
		(layer "In13.Cu")
		(net "M_B_CPU0_SA_DQ<4>")
	)
	(arc
		(start 329.828144 -228.606858)
		(mid 330.1111 -228.530681)
		(end 330.394056 -228.606858)
		(width 0.0889)
		(layer "In13.Cu")
		(net "M_B_CPU0_SA_DQ<4>")
	)
	(arc
		(start 332.648052 -228.606858)
		(mid 332.931008 -228.530681)
		(end 333.213964 -228.606858)
		(width 0.0889)
		(layer "In13.Cu")
		(net "M_B_CPU0_SA_DQ<4>")
	)
	(arc
		(start 333.588106 -228.606858)
		(mid 333.871062 -228.530681)
		(end 334.154018 -228.606858)
		(width 0.0889)
		(layer "In13.Cu")
		(net "M_B_CPU0_SA_DQ<4>")
	)
	(arc
		(start 327.856596 -225.85426)
		(mid 327.898145 -226.025682)
		(end 328.013568 -226.15906)
		(width 0.0889)
		(layer "In13.Cu")
		(net "M_B_CPU0_SA_DQ<4>")
	)
	(arc
		(start 326.197976 -222.95612)
		(mid 326.380638 -223.159201)
		(end 326.446642 -223.424242)
		(width 0.0889)
		(layer "In13.Cu")
		(net "M_B_CPU0_SA_DQ<4>")
	)
	(arc
		(start 334.52816 -228.606858)
		(mid 334.811116 -228.530681)
		(end 335.094072 -228.606858)
		(width 0.0889)
		(layer "In13.Cu")
		(net "M_B_CPU0_SA_DQ<4>")
	)
	(arc
		(start 329.454002 -228.606858)
		(mid 329.636253 -228.657208)
		(end 329.819762 -228.611684)
		(width 0.0889)
		(layer "In13.Cu")
		(net "M_B_CPU0_SA_DQ<4>")
	)
	(arc
		(start 327.14184 -224.578672)
		(mid 327.321569 -224.781292)
		(end 327.386442 -225.044254)
		(width 0.0889)
		(layer "In13.Cu")
		(net "M_B_CPU0_SA_DQ<4>")
	)
	(arc
		(start 328.796396 -227.474272)
		(mid 328.837651 -227.645243)
		(end 328.952352 -227.778564)
		(width 0.0889)
		(layer "In13.Cu")
		(net "M_B_CPU0_SA_DQ<4>")
	)
	(arc
		(start 334.154018 -228.606858)
		(mid 334.336269 -228.657208)
		(end 334.519778 -228.611684)
		(width 0.0889)
		(layer "In13.Cu")
		(net "M_B_CPU0_SA_DQ<4>")
	)
	(arc
		(start 331.342492 -228.611684)
		(mid 331.526 -228.657178)
		(end 331.708252 -228.606858)
		(width 0.0889)
		(layer "In13.Cu")
		(net "M_B_CPU0_SA_DQ<4>")
	)
	(arc
		(start 326.446642 -223.424242)
		(mid 326.488482 -223.596228)
		(end 326.60463 -223.729804)
		(width 0.0889)
		(layer "In13.Cu")
		(net "M_B_CPU0_SA_DQ<4>")
	)
	(arc
		(start 327.386442 -225.044254)
		(mid 327.427697 -225.215225)
		(end 327.542398 -225.348546)
		(width 0.0889)
		(layer "In13.Cu")
		(net "M_B_CPU0_SA_DQ<4>")
	)
	(arc
		(start 328.083164 -226.1997)
		(mid 328.261977 -226.40205)
		(end 328.326496 -226.664266)
		(width 0.0889)
		(layer "In13.Cu")
		(net "M_B_CPU0_SA_DQ<4>")
	)
	(arc
		(start 326.916796 -224.234248)
		(mid 326.957985 -224.405152)
		(end 327.072498 -224.53854)
		(width 0.0889)
		(layer "In13.Cu")
		(net "M_B_CPU0_SA_DQ<4>")
	)
	(arc
		(start 326.676004 -223.771206)
		(mid 326.852986 -223.973298)
		(end 326.916796 -224.234248)
		(width 0.0889)
		(layer "In13.Cu")
		(net "M_B_CPU0_SA_DQ<4>")
	)
	(arc
		(start 331.708252 -228.606858)
		(mid 331.991208 -228.530681)
		(end 332.274164 -228.606858)
		(width 0.0889)
		(layer "In13.Cu")
		(net "M_B_CPU0_SA_DQ<4>")
	)
	(arc
		(start 333.213964 -228.606858)
		(mid 333.396215 -228.657208)
		(end 333.579724 -228.611684)
		(width 0.0889)
		(layer "In13.Cu")
		(net "M_B_CPU0_SA_DQ<4>")
	)
	(arc
		(start 335.102454 -228.611684)
		(mid 335.255324 -228.656325)
		(end 335.412842 -228.63302)
		(width 0.0889)
		(layer "In13.Cu")
		(net "M_B_CPU0_SA_DQ<4>")
	)
	(arc
		(start 330.402438 -228.611684)
		(mid 330.585946 -228.657178)
		(end 330.768198 -228.606858)
		(width 0.0889)
		(layer "In13.Cu")
		(net "M_B_CPU0_SA_DQ<4>")
	)
	(arc
		(start 328.326496 -226.664266)
		(mid 328.367751 -226.835237)
		(end 328.482452 -226.968558)
		(width 0.0889)
		(layer "In13.Cu")
		(net "M_B_CPU0_SA_DQ<4>")
	)
	(arc
		(start 328.550524 -227.007928)
		(mid 328.731176 -227.210673)
		(end 328.796396 -227.474272)
		(width 0.0889)
		(layer "In13.Cu")
		(net "M_B_CPU0_SA_DQ<4>")
	)
	(segment
		(start 337.627976 -226.930204)
		(end 337.161124 -226.664266)
		(width 0.10668)
		(layer "F.Cu")
		(net "M_B_CPU0_SA_DQ<3>")
	)
	(segment
		(start 329.358244 -223.911668)
		(end 329.319128 -223.888808)
		(width 0.0889)
		(layer "In13.Cu")
		(net "M_B_CPU0_SA_DQ<3>")
	)
	(segment
		(start 328.135996 -221.80423)
		(end 328.135996 -221.52483)
		(width 0.0889)
		(layer "In13.Cu")
		(net "M_B_CPU0_SA_DQ<3>")
	)
	(segment
		(start 328.88809 -223.101662)
		(end 328.851768 -223.08058)
		(width 0.0889)
		(layer "In13.Cu")
		(net "M_B_CPU0_SA_DQ<3>")
	)
	(segment
		(start 334.52816 -226.341686)
		(end 334.519778 -226.33686)
		(width 0.0889)
		(layer "In13.Cu")
		(net "M_B_CPU0_SA_DQ<3>")
	)
	(segment
		(start 298.56684 -199.488044)
		(end 298.475908 -199.450452)
		(width 0.14478)
		(layer "In13.Cu")
		(net "M_B_CPU0_SA_DQ<3>")
	)
	(segment
		(start 329.388724 -223.929448)
		(end 329.358244 -223.911668)
		(width 0.0889)
		(layer "In13.Cu")
		(net "M_B_CPU0_SA_DQ<3>")
	)
	(segment
		(start 328.015854 -220.006926)
		(end 309.205884 -201.196956)
		(width 0.14478)
		(layer "In13.Cu")
		(net "M_B_CPU0_SA_DQ<3>")
	)
	(segment
		(start 333.588106 -226.341686)
		(end 333.579724 -226.33686)
		(width 0.0889)
		(layer "In13.Cu")
		(net "M_B_CPU0_SA_DQ<3>")
	)
	(segment
		(start 309.205884 -201.196956)
		(end 308.953916 -201.092562)
		(width 0.14478)
		(layer "In13.Cu")
		(net "M_B_CPU0_SA_DQ<3>")
	)
	(segment
		(start 329.859894 -224.739962)
		(end 329.828144 -224.721674)
		(width 0.0889)
		(layer "In13.Cu")
		(net "M_B_CPU0_SA_DQ<3>")
	)
	(segment
		(start 335.102454 -226.33686)
		(end 335.094072 -226.341686)
		(width 0.0889)
		(layer "In13.Cu")
		(net "M_B_CPU0_SA_DQ<3>")
	)
	(segment
		(start 298.475908 -199.450452)
		(end 297.90009 -199.450452)
		(width 0.14478)
		(layer "In13.Cu")
		(net "M_B_CPU0_SA_DQ<3>")
	)
	(segment
		(start 308.953916 -201.092562)
		(end 305.021234 -200.310242)
		(width 0.14478)
		(layer "In13.Cu")
		(net "M_B_CPU0_SA_DQ<3>")
	)
	(segment
		(start 330.329794 -225.549968)
		(end 330.298044 -225.53168)
		(width 0.0889)
		(layer "In13.Cu")
		(net "M_B_CPU0_SA_DQ<3>")
	)
	(segment
		(start 330.768198 -226.341686)
		(end 330.729082 -226.318826)
		(width 0.0889)
		(layer "In13.Cu")
		(net "M_B_CPU0_SA_DQ<3>")
	)
	(segment
		(start 297.90009 -199.450452)
		(end 296.850816 -199.885046)
		(width 0.14478)
		(layer "In13.Cu")
		(net "M_B_CPU0_SA_DQ<3>")
	)
	(segment
		(start 328.446892 -222.307912)
		(end 328.418698 -222.291656)
		(width 0.0889)
		(layer "In13.Cu")
		(net "M_B_CPU0_SA_DQ<3>")
	)
	(segment
		(start 328.015854 -221.23527)
		(end 328.015854 -220.006926)
		(width 0.14478)
		(layer "In13.Cu")
		(net "M_B_CPU0_SA_DQ<3>")
	)
	(segment
		(start 330.298044 -225.53168)
		(end 330.261722 -225.510598)
		(width 0.0889)
		(layer "In13.Cu")
		(net "M_B_CPU0_SA_DQ<3>")
	)
	(segment
		(start 328.91984 -223.11995)
		(end 328.88809 -223.101662)
		(width 0.0889)
		(layer "In13.Cu")
		(net "M_B_CPU0_SA_DQ<3>")
	)
	(segment
		(start 337.161124 -226.664266)
		(end 337.0072 -226.398836)
		(width 0.0889)
		(layer "In13.Cu")
		(net "M_B_CPU0_SA_DQ<3>")
	)
	(segment
		(start 328.015854 -221.404688)
		(end 328.015854 -221.23527)
		(width 0.0889)
		(layer "In13.Cu")
		(net "M_B_CPU0_SA_DQ<3>")
	)
	(segment
		(start 328.135996 -221.52483)
		(end 328.015854 -221.404688)
		(width 0.0889)
		(layer "In13.Cu")
		(net "M_B_CPU0_SA_DQ<3>")
	)
	(segment
		(start 336.042508 -226.33686)
		(end 336.034126 -226.341686)
		(width 0.0889)
		(layer "In13.Cu")
		(net "M_B_CPU0_SA_DQ<3>")
	)
	(segment
		(start 296.850816 -199.885046)
		(end 295.724072 -199.885046)
		(width 0.14478)
		(layer "In13.Cu")
		(net "M_B_CPU0_SA_DQ<3>")
	)
	(segment
		(start 305.021234 -200.310242)
		(end 302.701198 -200.310242)
		(width 0.14478)
		(layer "In13.Cu")
		(net "M_B_CPU0_SA_DQ<3>")
	)
	(segment
		(start 331.342492 -226.33686)
		(end 331.33411 -226.341686)
		(width 0.0889)
		(layer "In13.Cu")
		(net "M_B_CPU0_SA_DQ<3>")
	)
	(segment
		(start 328.418698 -222.291656)
		(end 328.376788 -222.267272)
		(width 0.0889)
		(layer "In13.Cu")
		(net "M_B_CPU0_SA_DQ<3>")
	)
	(segment
		(start 302.701198 -200.310242)
		(end 298.56684 -199.488044)
		(width 0.14478)
		(layer "In13.Cu")
		(net "M_B_CPU0_SA_DQ<3>")
	)
	(segment
		(start 337.0072 -226.398836)
		(end 336.911188 -226.373436)
		(width 0.0889)
		(layer "In13.Cu")
		(net "M_B_CPU0_SA_DQ<3>")
	)
	(segment
		(start 329.828144 -224.721674)
		(end 329.789028 -224.698814)
		(width 0.0889)
		(layer "In13.Cu")
		(net "M_B_CPU0_SA_DQ<3>")
	)
	(arc
		(start 328.851768 -223.08058)
		(mid 328.671116 -222.877835)
		(end 328.605896 -222.614236)
		(width 0.0889)
		(layer "In13.Cu")
		(net "M_B_CPU0_SA_DQ<3>")
	)
	(arc
		(start 328.605896 -222.614236)
		(mid 328.563783 -222.441662)
		(end 328.446892 -222.307912)
		(width 0.0889)
		(layer "In13.Cu")
		(net "M_B_CPU0_SA_DQ<3>")
	)
	(arc
		(start 334.519778 -226.33686)
		(mid 334.33627 -226.291366)
		(end 334.154018 -226.341686)
		(width 0.0889)
		(layer "In13.Cu")
		(net "M_B_CPU0_SA_DQ<3>")
	)
	(arc
		(start 331.33411 -226.341686)
		(mid 331.051154 -226.417863)
		(end 330.768198 -226.341686)
		(width 0.0889)
		(layer "In13.Cu")
		(net "M_B_CPU0_SA_DQ<3>")
	)
	(arc
		(start 332.274164 -226.341686)
		(mid 331.991208 -226.417863)
		(end 331.708252 -226.341686)
		(width 0.0889)
		(layer "In13.Cu")
		(net "M_B_CPU0_SA_DQ<3>")
	)
	(arc
		(start 330.01585 -225.044254)
		(mid 329.974595 -224.873283)
		(end 329.859894 -224.739962)
		(width 0.0889)
		(layer "In13.Cu")
		(net "M_B_CPU0_SA_DQ<3>")
	)
	(arc
		(start 335.468214 -226.341686)
		(mid 335.285963 -226.291336)
		(end 335.102454 -226.33686)
		(width 0.0889)
		(layer "In13.Cu")
		(net "M_B_CPU0_SA_DQ<3>")
	)
	(arc
		(start 329.789028 -224.698814)
		(mid 329.610215 -224.496464)
		(end 329.545696 -224.234248)
		(width 0.0889)
		(layer "In13.Cu")
		(net "M_B_CPU0_SA_DQ<3>")
	)
	(arc
		(start 328.376788 -222.267272)
		(mid 328.199806 -222.06518)
		(end 328.135996 -221.80423)
		(width 0.0889)
		(layer "In13.Cu")
		(net "M_B_CPU0_SA_DQ<3>")
	)
	(arc
		(start 329.319128 -223.888808)
		(mid 329.140315 -223.686458)
		(end 329.075796 -223.424242)
		(width 0.0889)
		(layer "In13.Cu")
		(net "M_B_CPU0_SA_DQ<3>")
	)
	(arc
		(start 334.154018 -226.341686)
		(mid 333.871062 -226.417863)
		(end 333.588106 -226.341686)
		(width 0.0889)
		(layer "In13.Cu")
		(net "M_B_CPU0_SA_DQ<3>")
	)
	(arc
		(start 330.729082 -226.318826)
		(mid 330.550269 -226.116476)
		(end 330.48575 -225.85426)
		(width 0.0889)
		(layer "In13.Cu")
		(net "M_B_CPU0_SA_DQ<3>")
	)
	(arc
		(start 335.094072 -226.341686)
		(mid 334.811116 -226.417863)
		(end 334.52816 -226.341686)
		(width 0.0889)
		(layer "In13.Cu")
		(net "M_B_CPU0_SA_DQ<3>")
	)
	(arc
		(start 331.708252 -226.341686)
		(mid 331.526001 -226.291336)
		(end 331.342492 -226.33686)
		(width 0.0889)
		(layer "In13.Cu")
		(net "M_B_CPU0_SA_DQ<3>")
	)
	(arc
		(start 330.48575 -225.85426)
		(mid 330.444495 -225.683289)
		(end 330.329794 -225.549968)
		(width 0.0889)
		(layer "In13.Cu")
		(net "M_B_CPU0_SA_DQ<3>")
	)
	(arc
		(start 330.261722 -225.510598)
		(mid 330.08107 -225.307853)
		(end 330.01585 -225.044254)
		(width 0.0889)
		(layer "In13.Cu")
		(net "M_B_CPU0_SA_DQ<3>")
	)
	(arc
		(start 332.648052 -226.341686)
		(mid 332.461108 -226.291431)
		(end 332.274164 -226.341686)
		(width 0.0889)
		(layer "In13.Cu")
		(net "M_B_CPU0_SA_DQ<3>")
	)
	(arc
		(start 329.075796 -223.424242)
		(mid 329.034541 -223.253271)
		(end 328.91984 -223.11995)
		(width 0.0889)
		(layer "In13.Cu")
		(net "M_B_CPU0_SA_DQ<3>")
	)
	(arc
		(start 336.911188 -226.373436)
		(mid 336.65598 -226.416913)
		(end 336.408268 -226.341686)
		(width 0.0889)
		(layer "In13.Cu")
		(net "M_B_CPU0_SA_DQ<3>")
	)
	(arc
		(start 336.408268 -226.341686)
		(mid 336.226017 -226.291336)
		(end 336.042508 -226.33686)
		(width 0.0889)
		(layer "In13.Cu")
		(net "M_B_CPU0_SA_DQ<3>")
	)
	(arc
		(start 333.213964 -226.341686)
		(mid 332.931008 -226.417863)
		(end 332.648052 -226.341686)
		(width 0.0889)
		(layer "In13.Cu")
		(net "M_B_CPU0_SA_DQ<3>")
	)
	(arc
		(start 329.545696 -224.234248)
		(mid 329.504147 -224.062826)
		(end 329.388724 -223.929448)
		(width 0.0889)
		(layer "In13.Cu")
		(net "M_B_CPU0_SA_DQ<3>")
	)
	(arc
		(start 336.034126 -226.341686)
		(mid 335.75117 -226.417863)
		(end 335.468214 -226.341686)
		(width 0.0889)
		(layer "In13.Cu")
		(net "M_B_CPU0_SA_DQ<3>")
	)
	(arc
		(start 333.579724 -226.33686)
		(mid 333.396216 -226.291366)
		(end 333.213964 -226.341686)
		(width 0.0889)
		(layer "In13.Cu")
		(net "M_B_CPU0_SA_DQ<3>")
	)
	(segment
		(start 337.627976 -244.750082)
		(end 337.161124 -244.484144)
		(width 0.10668)
		(layer "F.Cu")
		(net "M_B_CPU0_SA_DQ<31>")
	)
	(segment
		(start 325.436484 -244.111018)
		(end 325.880476 -244.111018)
		(width 0.0889)
		(layer "In13.Cu")
		(net "M_B_CPU0_SA_DQ<31>")
	)
	(segment
		(start 336.911188 -244.193314)
		(end 337.0072 -244.218714)
		(width 0.0889)
		(layer "In13.Cu")
		(net "M_B_CPU0_SA_DQ<31>")
	)
	(segment
		(start 329.819762 -244.156738)
		(end 329.828144 -244.161564)
		(width 0.0889)
		(layer "In13.Cu")
		(net "M_B_CPU0_SA_DQ<31>")
	)
	(segment
		(start 295.724072 -233.884978)
		(end 297.73753 -233.884978)
		(width 0.14478)
		(layer "In13.Cu")
		(net "M_B_CPU0_SA_DQ<31>")
	)
	(segment
		(start 315.953394 -243.510054)
		(end 323.868034 -243.510054)
		(width 0.14478)
		(layer "In13.Cu")
		(net "M_B_CPU0_SA_DQ<31>")
	)
	(segment
		(start 327.939908 -244.156738)
		(end 327.94829 -244.161564)
		(width 0.0889)
		(layer "In13.Cu")
		(net "M_B_CPU0_SA_DQ<31>")
	)
	(segment
		(start 335.094072 -244.161564)
		(end 335.102454 -244.156738)
		(width 0.0889)
		(layer "In13.Cu")
		(net "M_B_CPU0_SA_DQ<31>")
	)
	(segment
		(start 330.394056 -244.161564)
		(end 330.402438 -244.156738)
		(width 0.0889)
		(layer "In13.Cu")
		(net "M_B_CPU0_SA_DQ<31>")
	)
	(segment
		(start 336.034126 -244.161564)
		(end 336.042508 -244.156738)
		(width 0.0889)
		(layer "In13.Cu")
		(net "M_B_CPU0_SA_DQ<31>")
	)
	(segment
		(start 324.400418 -243.765832)
		(end 325.091298 -243.765832)
		(width 0.0889)
		(layer "In13.Cu")
		(net "M_B_CPU0_SA_DQ<31>")
	)
	(segment
		(start 325.091298 -243.765832)
		(end 325.436484 -244.111018)
		(width 0.0889)
		(layer "In13.Cu")
		(net "M_B_CPU0_SA_DQ<31>")
	)
	(segment
		(start 311.310782 -238.092742)
		(end 311.310782 -238.867442)
		(width 0.14478)
		(layer "In13.Cu")
		(net "M_B_CPU0_SA_DQ<31>")
	)
	(segment
		(start 337.0072 -244.218714)
		(end 337.161124 -244.484144)
		(width 0.0889)
		(layer "In13.Cu")
		(net "M_B_CPU0_SA_DQ<31>")
	)
	(segment
		(start 333.579724 -244.156738)
		(end 333.588106 -244.161564)
		(width 0.0889)
		(layer "In13.Cu")
		(net "M_B_CPU0_SA_DQ<31>")
	)
	(segment
		(start 327.007474 -244.161564)
		(end 327.017888 -244.16766)
		(width 0.0889)
		(layer "In13.Cu")
		(net "M_B_CPU0_SA_DQ<31>")
	)
	(segment
		(start 307.528214 -234.310174)
		(end 311.310782 -238.092742)
		(width 0.14478)
		(layer "In13.Cu")
		(net "M_B_CPU0_SA_DQ<31>")
	)
	(segment
		(start 297.73753 -233.884978)
		(end 298.162472 -233.460036)
		(width 0.14478)
		(layer "In13.Cu")
		(net "M_B_CPU0_SA_DQ<31>")
	)
	(segment
		(start 311.310782 -238.867442)
		(end 315.953394 -243.510054)
		(width 0.14478)
		(layer "In13.Cu")
		(net "M_B_CPU0_SA_DQ<31>")
	)
	(segment
		(start 326.617838 -244.170962)
		(end 326.633586 -244.161818)
		(width 0.0889)
		(layer "In13.Cu")
		(net "M_B_CPU0_SA_DQ<31>")
	)
	(segment
		(start 301.989744 -234.310174)
		(end 307.528214 -234.310174)
		(width 0.14478)
		(layer "In13.Cu")
		(net "M_B_CPU0_SA_DQ<31>")
	)
	(segment
		(start 331.33411 -244.161564)
		(end 331.342492 -244.156738)
		(width 0.0889)
		(layer "In13.Cu")
		(net "M_B_CPU0_SA_DQ<31>")
	)
	(segment
		(start 334.519778 -244.156738)
		(end 334.52816 -244.161564)
		(width 0.0889)
		(layer "In13.Cu")
		(net "M_B_CPU0_SA_DQ<31>")
	)
	(segment
		(start 324.14464 -243.510054)
		(end 324.400418 -243.765832)
		(width 0.0889)
		(layer "In13.Cu")
		(net "M_B_CPU0_SA_DQ<31>")
	)
	(segment
		(start 326.633586 -244.161818)
		(end 326.649842 -244.15242)
		(width 0.0889)
		(layer "In13.Cu")
		(net "M_B_CPU0_SA_DQ<31>")
	)
	(segment
		(start 301.139606 -233.460036)
		(end 301.989744 -234.310174)
		(width 0.14478)
		(layer "In13.Cu")
		(net "M_B_CPU0_SA_DQ<31>")
	)
	(segment
		(start 323.868034 -243.510054)
		(end 324.14464 -243.510054)
		(width 0.0889)
		(layer "In13.Cu")
		(net "M_B_CPU0_SA_DQ<31>")
	)
	(segment
		(start 298.162472 -233.460036)
		(end 301.139606 -233.460036)
		(width 0.14478)
		(layer "In13.Cu")
		(net "M_B_CPU0_SA_DQ<31>")
	)
	(arc
		(start 335.468214 -244.161564)
		(mid 335.75117 -244.237741)
		(end 336.034126 -244.161564)
		(width 0.0889)
		(layer "In13.Cu")
		(net "M_B_CPU0_SA_DQ<31>")
	)
	(arc
		(start 327.017888 -244.16766)
		(mid 327.296574 -244.23788)
		(end 327.57364 -244.161564)
		(width 0.0889)
		(layer "In13.Cu")
		(net "M_B_CPU0_SA_DQ<31>")
	)
	(arc
		(start 330.402438 -244.156738)
		(mid 330.585946 -244.111244)
		(end 330.768198 -244.161564)
		(width 0.0889)
		(layer "In13.Cu")
		(net "M_B_CPU0_SA_DQ<31>")
	)
	(arc
		(start 328.514202 -244.161564)
		(mid 328.701146 -244.111309)
		(end 328.88809 -244.161564)
		(width 0.0889)
		(layer "In13.Cu")
		(net "M_B_CPU0_SA_DQ<31>")
	)
	(arc
		(start 333.588106 -244.161564)
		(mid 333.871062 -244.237741)
		(end 334.154018 -244.161564)
		(width 0.0889)
		(layer "In13.Cu")
		(net "M_B_CPU0_SA_DQ<31>")
	)
	(arc
		(start 334.52816 -244.161564)
		(mid 334.811116 -244.237741)
		(end 335.094072 -244.161564)
		(width 0.0889)
		(layer "In13.Cu")
		(net "M_B_CPU0_SA_DQ<31>")
	)
	(arc
		(start 326.067674 -244.161564)
		(mid 326.341529 -244.237914)
		(end 326.617838 -244.170962)
		(width 0.0889)
		(layer "In13.Cu")
		(net "M_B_CPU0_SA_DQ<31>")
	)
	(arc
		(start 327.57364 -244.161564)
		(mid 327.756145 -244.111087)
		(end 327.939908 -244.156738)
		(width 0.0889)
		(layer "In13.Cu")
		(net "M_B_CPU0_SA_DQ<31>")
	)
	(arc
		(start 336.408268 -244.161564)
		(mid 336.655981 -244.236784)
		(end 336.911188 -244.193314)
		(width 0.0889)
		(layer "In13.Cu")
		(net "M_B_CPU0_SA_DQ<31>")
	)
	(arc
		(start 330.768198 -244.161564)
		(mid 331.051154 -244.237741)
		(end 331.33411 -244.161564)
		(width 0.0889)
		(layer "In13.Cu")
		(net "M_B_CPU0_SA_DQ<31>")
	)
	(arc
		(start 326.649842 -244.15242)
		(mid 326.829824 -244.11132)
		(end 327.007474 -244.161564)
		(width 0.0889)
		(layer "In13.Cu")
		(net "M_B_CPU0_SA_DQ<31>")
	)
	(arc
		(start 325.880476 -244.111018)
		(mid 325.977427 -244.123893)
		(end 326.067674 -244.161564)
		(width 0.0889)
		(layer "In13.Cu")
		(net "M_B_CPU0_SA_DQ<31>")
	)
	(arc
		(start 333.213964 -244.161564)
		(mid 333.396215 -244.111214)
		(end 333.579724 -244.156738)
		(width 0.0889)
		(layer "In13.Cu")
		(net "M_B_CPU0_SA_DQ<31>")
	)
	(arc
		(start 336.042508 -244.156738)
		(mid 336.226016 -244.111244)
		(end 336.408268 -244.161564)
		(width 0.0889)
		(layer "In13.Cu")
		(net "M_B_CPU0_SA_DQ<31>")
	)
	(arc
		(start 327.94829 -244.161564)
		(mid 328.231246 -244.237741)
		(end 328.514202 -244.161564)
		(width 0.0889)
		(layer "In13.Cu")
		(net "M_B_CPU0_SA_DQ<31>")
	)
	(arc
		(start 328.88809 -244.161564)
		(mid 329.171046 -244.237741)
		(end 329.454002 -244.161564)
		(width 0.0889)
		(layer "In13.Cu")
		(net "M_B_CPU0_SA_DQ<31>")
	)
	(arc
		(start 329.828144 -244.161564)
		(mid 330.1111 -244.237741)
		(end 330.394056 -244.161564)
		(width 0.0889)
		(layer "In13.Cu")
		(net "M_B_CPU0_SA_DQ<31>")
	)
	(arc
		(start 331.708252 -244.161564)
		(mid 331.991208 -244.237741)
		(end 332.274164 -244.161564)
		(width 0.0889)
		(layer "In13.Cu")
		(net "M_B_CPU0_SA_DQ<31>")
	)
	(arc
		(start 332.274164 -244.161564)
		(mid 332.461108 -244.111309)
		(end 332.648052 -244.161564)
		(width 0.0889)
		(layer "In13.Cu")
		(net "M_B_CPU0_SA_DQ<31>")
	)
	(arc
		(start 335.102454 -244.156738)
		(mid 335.285962 -244.111244)
		(end 335.468214 -244.161564)
		(width 0.0889)
		(layer "In13.Cu")
		(net "M_B_CPU0_SA_DQ<31>")
	)
	(arc
		(start 332.648052 -244.161564)
		(mid 332.931008 -244.237741)
		(end 333.213964 -244.161564)
		(width 0.0889)
		(layer "In13.Cu")
		(net "M_B_CPU0_SA_DQ<31>")
	)
	(arc
		(start 329.454002 -244.161564)
		(mid 329.636253 -244.111214)
		(end 329.819762 -244.156738)
		(width 0.0889)
		(layer "In13.Cu")
		(net "M_B_CPU0_SA_DQ<31>")
	)
	(arc
		(start 331.342492 -244.156738)
		(mid 331.526 -244.111244)
		(end 331.708252 -244.161564)
		(width 0.0889)
		(layer "In13.Cu")
		(net "M_B_CPU0_SA_DQ<31>")
	)
	(arc
		(start 334.154018 -244.161564)
		(mid 334.336269 -244.111214)
		(end 334.519778 -244.156738)
		(width 0.0889)
		(layer "In13.Cu")
		(net "M_B_CPU0_SA_DQ<31>")
	)
	(segment
		(start 336.218022 -243.940076)
		(end 335.75117 -243.674138)
		(width 0.10668)
		(layer "F.Cu")
		(net "M_B_CPU0_SA_DQ<30>")
	)
	(segment
		(start 328.409808 -243.346732)
		(end 328.41819 -243.351558)
		(width 0.0889)
		(layer "In13.Cu")
		(net "M_B_CPU0_SA_DQ<30>")
	)
	(segment
		(start 296.4815 -232.184956)
		(end 296.62628 -232.329736)
		(width 0.14478)
		(layer "In13.Cu")
		(net "M_B_CPU0_SA_DQ<30>")
	)
	(segment
		(start 327.083166 -243.365274)
		(end 327.106534 -243.351558)
		(width 0.0889)
		(layer "In13.Cu")
		(net "M_B_CPU0_SA_DQ<30>")
	)
	(segment
		(start 301.196502 -231.760014)
		(end 302.04664 -232.610152)
		(width 0.14478)
		(layer "In13.Cu")
		(net "M_B_CPU0_SA_DQ<30>")
	)
	(segment
		(start 295.724072 -232.184956)
		(end 296.4815 -232.184956)
		(width 0.14478)
		(layer "In13.Cu")
		(net "M_B_CPU0_SA_DQ<30>")
	)
	(segment
		(start 335.596992 -243.408708)
		(end 335.75117 -243.674138)
		(width 0.0889)
		(layer "In13.Cu")
		(net "M_B_CPU0_SA_DQ<30>")
	)
	(segment
		(start 332.744064 -243.351558)
		(end 332.752446 -243.346732)
		(width 0.0889)
		(layer "In13.Cu")
		(net "M_B_CPU0_SA_DQ<30>")
	)
	(segment
		(start 316.354968 -242.595654)
		(end 323.900038 -242.595654)
		(width 0.14478)
		(layer "In13.Cu")
		(net "M_B_CPU0_SA_DQ<30>")
	)
	(segment
		(start 327.461372 -243.341398)
		(end 327.47966 -243.351812)
		(width 0.0889)
		(layer "In13.Cu")
		(net "M_B_CPU0_SA_DQ<30>")
	)
	(segment
		(start 323.900038 -242.595654)
		(end 324.24878 -242.595654)
		(width 0.0889)
		(layer "In13.Cu")
		(net "M_B_CPU0_SA_DQ<30>")
	)
	(segment
		(start 328.984102 -243.351558)
		(end 328.992484 -243.346732)
		(width 0.0889)
		(layer "In13.Cu")
		(net "M_B_CPU0_SA_DQ<30>")
	)
	(segment
		(start 296.62628 -232.958132)
		(end 296.77106 -233.102912)
		(width 0.14478)
		(layer "In13.Cu")
		(net "M_B_CPU0_SA_DQ<30>")
	)
	(segment
		(start 332.16977 -243.346732)
		(end 332.178152 -243.351558)
		(width 0.0889)
		(layer "In13.Cu")
		(net "M_B_CPU0_SA_DQ<30>")
	)
	(segment
		(start 307.413152 -232.610152)
		(end 312.451496 -237.648496)
		(width 0.14478)
		(layer "In13.Cu")
		(net "M_B_CPU0_SA_DQ<30>")
	)
	(segment
		(start 297.32224 -232.184956)
		(end 297.73753 -232.184956)
		(width 0.14478)
		(layer "In13.Cu")
		(net "M_B_CPU0_SA_DQ<30>")
	)
	(segment
		(start 324.994778 -242.737132)
		(end 325.55815 -243.300504)
		(width 0.0889)
		(layer "In13.Cu")
		(net "M_B_CPU0_SA_DQ<30>")
	)
	(segment
		(start 312.451496 -238.692182)
		(end 316.354968 -242.595654)
		(width 0.14478)
		(layer "In13.Cu")
		(net "M_B_CPU0_SA_DQ<30>")
	)
	(segment
		(start 333.684118 -243.351558)
		(end 333.6925 -243.346732)
		(width 0.0889)
		(layer "In13.Cu")
		(net "M_B_CPU0_SA_DQ<30>")
	)
	(segment
		(start 298.162472 -231.760014)
		(end 301.196502 -231.760014)
		(width 0.14478)
		(layer "In13.Cu")
		(net "M_B_CPU0_SA_DQ<30>")
	)
	(segment
		(start 335.500726 -243.383308)
		(end 335.596992 -243.408708)
		(width 0.0889)
		(layer "In13.Cu")
		(net "M_B_CPU0_SA_DQ<30>")
	)
	(segment
		(start 297.73753 -232.184956)
		(end 298.162472 -231.760014)
		(width 0.14478)
		(layer "In13.Cu")
		(net "M_B_CPU0_SA_DQ<30>")
	)
	(segment
		(start 324.24878 -242.595654)
		(end 324.390258 -242.737132)
		(width 0.0889)
		(layer "In13.Cu")
		(net "M_B_CPU0_SA_DQ<30>")
	)
	(segment
		(start 297.17746 -232.958132)
		(end 297.17746 -232.329736)
		(width 0.14478)
		(layer "In13.Cu")
		(net "M_B_CPU0_SA_DQ<30>")
	)
	(segment
		(start 327.47966 -243.351812)
		(end 327.50125 -243.364258)
		(width 0.0889)
		(layer "In13.Cu")
		(net "M_B_CPU0_SA_DQ<30>")
	)
	(segment
		(start 331.229716 -243.346732)
		(end 331.238098 -243.351558)
		(width 0.0889)
		(layer "In13.Cu")
		(net "M_B_CPU0_SA_DQ<30>")
	)
	(segment
		(start 296.62628 -232.329736)
		(end 296.62628 -232.958132)
		(width 0.14478)
		(layer "In13.Cu")
		(net "M_B_CPU0_SA_DQ<30>")
	)
	(segment
		(start 324.390258 -242.737132)
		(end 324.994778 -242.737132)
		(width 0.0889)
		(layer "In13.Cu")
		(net "M_B_CPU0_SA_DQ<30>")
	)
	(segment
		(start 297.17746 -232.329736)
		(end 297.32224 -232.184956)
		(width 0.14478)
		(layer "In13.Cu")
		(net "M_B_CPU0_SA_DQ<30>")
	)
	(segment
		(start 325.55815 -243.300504)
		(end 326.351138 -243.300504)
		(width 0.0889)
		(layer "In13.Cu")
		(net "M_B_CPU0_SA_DQ<30>")
	)
	(segment
		(start 302.04664 -232.610152)
		(end 307.413152 -232.610152)
		(width 0.14478)
		(layer "In13.Cu")
		(net "M_B_CPU0_SA_DQ<30>")
	)
	(segment
		(start 312.451496 -237.648496)
		(end 312.451496 -238.692182)
		(width 0.14478)
		(layer "In13.Cu")
		(net "M_B_CPU0_SA_DQ<30>")
	)
	(segment
		(start 296.77106 -233.102912)
		(end 297.03268 -233.102912)
		(width 0.14478)
		(layer "In13.Cu")
		(net "M_B_CPU0_SA_DQ<30>")
	)
	(segment
		(start 297.03268 -233.102912)
		(end 297.17746 -232.958132)
		(width 0.14478)
		(layer "In13.Cu")
		(net "M_B_CPU0_SA_DQ<30>")
	)
	(arc
		(start 332.178152 -243.351558)
		(mid 332.461108 -243.427735)
		(end 332.744064 -243.351558)
		(width 0.0889)
		(layer "In13.Cu")
		(net "M_B_CPU0_SA_DQ<30>")
	)
	(arc
		(start 326.351138 -243.300504)
		(mid 326.448641 -243.313519)
		(end 326.539352 -243.351558)
		(width 0.0889)
		(layer "In13.Cu")
		(net "M_B_CPU0_SA_DQ<30>")
	)
	(arc
		(start 334.624172 -243.351558)
		(mid 334.811116 -243.301303)
		(end 334.99806 -243.351558)
		(width 0.0889)
		(layer "In13.Cu")
		(net "M_B_CPU0_SA_DQ<30>")
	)
	(arc
		(start 331.238098 -243.351558)
		(mid 331.521054 -243.427735)
		(end 331.80401 -243.351558)
		(width 0.0889)
		(layer "In13.Cu")
		(net "M_B_CPU0_SA_DQ<30>")
	)
	(arc
		(start 328.992484 -243.346732)
		(mid 329.175992 -243.301238)
		(end 329.358244 -243.351558)
		(width 0.0889)
		(layer "In13.Cu")
		(net "M_B_CPU0_SA_DQ<30>")
	)
	(arc
		(start 334.05826 -243.351558)
		(mid 334.341216 -243.427735)
		(end 334.624172 -243.351558)
		(width 0.0889)
		(layer "In13.Cu")
		(net "M_B_CPU0_SA_DQ<30>")
	)
	(arc
		(start 327.50125 -243.364258)
		(mid 327.774279 -243.427577)
		(end 328.044048 -243.351558)
		(width 0.0889)
		(layer "In13.Cu")
		(net "M_B_CPU0_SA_DQ<30>")
	)
	(arc
		(start 327.106534 -243.351558)
		(mid 327.282654 -243.30158)
		(end 327.461372 -243.341398)
		(width 0.0889)
		(layer "In13.Cu")
		(net "M_B_CPU0_SA_DQ<30>")
	)
	(arc
		(start 326.539352 -243.351558)
		(mid 326.809509 -243.42832)
		(end 327.083166 -243.365274)
		(width 0.0889)
		(layer "In13.Cu")
		(net "M_B_CPU0_SA_DQ<30>")
	)
	(arc
		(start 333.118206 -243.351558)
		(mid 333.401162 -243.427735)
		(end 333.684118 -243.351558)
		(width 0.0889)
		(layer "In13.Cu")
		(net "M_B_CPU0_SA_DQ<30>")
	)
	(arc
		(start 328.044048 -243.351558)
		(mid 328.226299 -243.301208)
		(end 328.409808 -243.346732)
		(width 0.0889)
		(layer "In13.Cu")
		(net "M_B_CPU0_SA_DQ<30>")
	)
	(arc
		(start 330.863956 -243.351558)
		(mid 331.046207 -243.301208)
		(end 331.229716 -243.346732)
		(width 0.0889)
		(layer "In13.Cu")
		(net "M_B_CPU0_SA_DQ<30>")
	)
	(arc
		(start 329.924156 -243.351558)
		(mid 330.1111 -243.301303)
		(end 330.298044 -243.351558)
		(width 0.0889)
		(layer "In13.Cu")
		(net "M_B_CPU0_SA_DQ<30>")
	)
	(arc
		(start 331.80401 -243.351558)
		(mid 331.986261 -243.301208)
		(end 332.16977 -243.346732)
		(width 0.0889)
		(layer "In13.Cu")
		(net "M_B_CPU0_SA_DQ<30>")
	)
	(arc
		(start 334.99806 -243.351558)
		(mid 335.245656 -243.426736)
		(end 335.500726 -243.383308)
		(width 0.0889)
		(layer "In13.Cu")
		(net "M_B_CPU0_SA_DQ<30>")
	)
	(arc
		(start 332.752446 -243.346732)
		(mid 332.935954 -243.301238)
		(end 333.118206 -243.351558)
		(width 0.0889)
		(layer "In13.Cu")
		(net "M_B_CPU0_SA_DQ<30>")
	)
	(arc
		(start 333.6925 -243.346732)
		(mid 333.876008 -243.301238)
		(end 334.05826 -243.351558)
		(width 0.0889)
		(layer "In13.Cu")
		(net "M_B_CPU0_SA_DQ<30>")
	)
	(arc
		(start 329.358244 -243.351558)
		(mid 329.6412 -243.427735)
		(end 329.924156 -243.351558)
		(width 0.0889)
		(layer "In13.Cu")
		(net "M_B_CPU0_SA_DQ<30>")
	)
	(arc
		(start 328.41819 -243.351558)
		(mid 328.701146 -243.427735)
		(end 328.984102 -243.351558)
		(width 0.0889)
		(layer "In13.Cu")
		(net "M_B_CPU0_SA_DQ<30>")
	)
	(arc
		(start 330.298044 -243.351558)
		(mid 330.581 -243.427735)
		(end 330.863956 -243.351558)
		(width 0.0889)
		(layer "In13.Cu")
		(net "M_B_CPU0_SA_DQ<30>")
	)
	(segment
		(start 336.218022 -226.120198)
		(end 335.75117 -225.85426)
		(width 0.10668)
		(layer "F.Cu")
		(net "M_B_CPU0_SA_DQ<2>")
	)
	(segment
		(start 329.859894 -223.11995)
		(end 329.828144 -223.101662)
		(width 0.0889)
		(layer "In13.Cu")
		(net "M_B_CPU0_SA_DQ<2>")
	)
	(segment
		(start 333.6925 -225.526854)
		(end 333.684118 -225.53168)
		(width 0.0889)
		(layer "In13.Cu")
		(net "M_B_CPU0_SA_DQ<2>")
	)
	(segment
		(start 329.545696 -222.614236)
		(end 329.545696 -222.03283)
		(width 0.0889)
		(layer "In13.Cu")
		(net "M_B_CPU0_SA_DQ<2>")
	)
	(segment
		(start 307.905404 -198.61022)
		(end 302.04664 -198.61022)
		(width 0.14478)
		(layer "In13.Cu")
		(net "M_B_CPU0_SA_DQ<2>")
	)
	(segment
		(start 330.768198 -224.721674)
		(end 330.729082 -224.698814)
		(width 0.0889)
		(layer "In13.Cu")
		(net "M_B_CPU0_SA_DQ<2>")
	)
	(segment
		(start 335.596992 -225.58883)
		(end 335.500726 -225.56343)
		(width 0.0889)
		(layer "In13.Cu")
		(net "M_B_CPU0_SA_DQ<2>")
	)
	(segment
		(start 297.73753 -198.185024)
		(end 295.724072 -198.185024)
		(width 0.14478)
		(layer "In13.Cu")
		(net "M_B_CPU0_SA_DQ<2>")
	)
	(segment
		(start 298.162472 -197.760082)
		(end 297.73753 -198.185024)
		(width 0.14478)
		(layer "In13.Cu")
		(net "M_B_CPU0_SA_DQ<2>")
	)
	(segment
		(start 329.828144 -223.101662)
		(end 329.789028 -223.078802)
		(width 0.0889)
		(layer "In13.Cu")
		(net "M_B_CPU0_SA_DQ<2>")
	)
	(segment
		(start 329.034394 -221.521528)
		(end 329.034394 -221.30385)
		(width 0.0889)
		(layer "In13.Cu")
		(net "M_B_CPU0_SA_DQ<2>")
	)
	(segment
		(start 301.196502 -197.760082)
		(end 298.162472 -197.760082)
		(width 0.14478)
		(layer "In13.Cu")
		(net "M_B_CPU0_SA_DQ<2>")
	)
	(segment
		(start 332.178152 -225.53168)
		(end 332.16977 -225.526854)
		(width 0.0889)
		(layer "In13.Cu")
		(net "M_B_CPU0_SA_DQ<2>")
	)
	(segment
		(start 330.329794 -223.929956)
		(end 330.298044 -223.911668)
		(width 0.0889)
		(layer "In13.Cu")
		(net "M_B_CPU0_SA_DQ<2>")
	)
	(segment
		(start 331.238098 -225.53168)
		(end 331.198982 -225.50882)
		(width 0.0889)
		(layer "In13.Cu")
		(net "M_B_CPU0_SA_DQ<2>")
	)
	(segment
		(start 330.298044 -223.911668)
		(end 330.261722 -223.890586)
		(width 0.0889)
		(layer "In13.Cu")
		(net "M_B_CPU0_SA_DQ<2>")
	)
	(segment
		(start 302.04664 -198.61022)
		(end 301.196502 -197.760082)
		(width 0.14478)
		(layer "In13.Cu")
		(net "M_B_CPU0_SA_DQ<2>")
	)
	(segment
		(start 335.75117 -225.85426)
		(end 335.596992 -225.58883)
		(width 0.0889)
		(layer "In13.Cu")
		(net "M_B_CPU0_SA_DQ<2>")
	)
	(segment
		(start 329.545696 -222.03283)
		(end 329.034394 -221.521528)
		(width 0.0889)
		(layer "In13.Cu")
		(net "M_B_CPU0_SA_DQ<2>")
	)
	(segment
		(start 332.752446 -225.526854)
		(end 332.744064 -225.53168)
		(width 0.0889)
		(layer "In13.Cu")
		(net "M_B_CPU0_SA_DQ<2>")
	)
	(segment
		(start 330.798678 -224.739454)
		(end 330.768198 -224.721674)
		(width 0.0889)
		(layer "In13.Cu")
		(net "M_B_CPU0_SA_DQ<2>")
	)
	(segment
		(start 329.034394 -219.73921)
		(end 307.905404 -198.61022)
		(width 0.14478)
		(layer "In13.Cu")
		(net "M_B_CPU0_SA_DQ<2>")
	)
	(segment
		(start 329.034394 -221.30385)
		(end 329.034394 -219.73921)
		(width 0.14478)
		(layer "In13.Cu")
		(net "M_B_CPU0_SA_DQ<2>")
	)
	(arc
		(start 330.729082 -224.698814)
		(mid 330.550269 -224.496464)
		(end 330.48575 -224.234248)
		(width 0.0889)
		(layer "In13.Cu")
		(net "M_B_CPU0_SA_DQ<2>")
	)
	(arc
		(start 334.624172 -225.53168)
		(mid 334.341216 -225.607857)
		(end 334.05826 -225.53168)
		(width 0.0889)
		(layer "In13.Cu")
		(net "M_B_CPU0_SA_DQ<2>")
	)
	(arc
		(start 330.48575 -224.234248)
		(mid 330.444495 -224.063277)
		(end 330.329794 -223.929956)
		(width 0.0889)
		(layer "In13.Cu")
		(net "M_B_CPU0_SA_DQ<2>")
	)
	(arc
		(start 332.744064 -225.53168)
		(mid 332.461108 -225.607857)
		(end 332.178152 -225.53168)
		(width 0.0889)
		(layer "In13.Cu")
		(net "M_B_CPU0_SA_DQ<2>")
	)
	(arc
		(start 330.261722 -223.890586)
		(mid 330.08107 -223.687841)
		(end 330.01585 -223.424242)
		(width 0.0889)
		(layer "In13.Cu")
		(net "M_B_CPU0_SA_DQ<2>")
	)
	(arc
		(start 334.05826 -225.53168)
		(mid 333.876009 -225.48133)
		(end 333.6925 -225.526854)
		(width 0.0889)
		(layer "In13.Cu")
		(net "M_B_CPU0_SA_DQ<2>")
	)
	(arc
		(start 334.99806 -225.53168)
		(mid 334.811116 -225.481425)
		(end 334.624172 -225.53168)
		(width 0.0889)
		(layer "In13.Cu")
		(net "M_B_CPU0_SA_DQ<2>")
	)
	(arc
		(start 330.01585 -223.424242)
		(mid 329.974595 -223.253271)
		(end 329.859894 -223.11995)
		(width 0.0889)
		(layer "In13.Cu")
		(net "M_B_CPU0_SA_DQ<2>")
	)
	(arc
		(start 333.118206 -225.53168)
		(mid 332.935955 -225.48133)
		(end 332.752446 -225.526854)
		(width 0.0889)
		(layer "In13.Cu")
		(net "M_B_CPU0_SA_DQ<2>")
	)
	(arc
		(start 330.95565 -225.044254)
		(mid 330.914101 -224.872832)
		(end 330.798678 -224.739454)
		(width 0.0889)
		(layer "In13.Cu")
		(net "M_B_CPU0_SA_DQ<2>")
	)
	(arc
		(start 331.198982 -225.50882)
		(mid 331.020169 -225.30647)
		(end 330.95565 -225.044254)
		(width 0.0889)
		(layer "In13.Cu")
		(net "M_B_CPU0_SA_DQ<2>")
	)
	(arc
		(start 333.684118 -225.53168)
		(mid 333.401162 -225.607857)
		(end 333.118206 -225.53168)
		(width 0.0889)
		(layer "In13.Cu")
		(net "M_B_CPU0_SA_DQ<2>")
	)
	(arc
		(start 335.500726 -225.56343)
		(mid 335.245661 -225.606781)
		(end 334.99806 -225.53168)
		(width 0.0889)
		(layer "In13.Cu")
		(net "M_B_CPU0_SA_DQ<2>")
	)
	(arc
		(start 329.789028 -223.078802)
		(mid 329.610215 -222.876452)
		(end 329.545696 -222.614236)
		(width 0.0889)
		(layer "In13.Cu")
		(net "M_B_CPU0_SA_DQ<2>")
	)
	(arc
		(start 331.80401 -225.53168)
		(mid 331.521054 -225.607857)
		(end 331.238098 -225.53168)
		(width 0.0889)
		(layer "In13.Cu")
		(net "M_B_CPU0_SA_DQ<2>")
	)
	(arc
		(start 332.16977 -225.526854)
		(mid 331.986262 -225.48136)
		(end 331.80401 -225.53168)
		(width 0.0889)
		(layer "In13.Cu")
		(net "M_B_CPU0_SA_DQ<2>")
	)
	(segment
		(start 337.158076 -243.940076)
		(end 336.691224 -243.674138)
		(width 0.10668)
		(layer "F.Cu")
		(net "M_B_CPU0_SA_DQ<29>")
	)
	(segment
		(start 304.218594 -233.062272)
		(end 304.44694 -233.062272)
		(width 0.14478)
		(layer "In13.Cu")
		(net "M_B_CPU0_SA_DQ<29>")
	)
	(segment
		(start 306.262786 -233.696256)
		(end 306.262786 -233.223816)
		(width 0.14478)
		(layer "In13.Cu")
		(net "M_B_CPU0_SA_DQ<29>")
	)
	(segment
		(start 328.033634 -243.990622)
		(end 328.044048 -243.996718)
		(width 0.0889)
		(layer "In13.Cu")
		(net "M_B_CPU0_SA_DQ<29>")
	)
	(segment
		(start 323.882258 -243.050314)
		(end 324.12686 -243.050314)
		(width 0.0889)
		(layer "In13.Cu")
		(net "M_B_CPU0_SA_DQ<29>")
	)
	(segment
		(start 305.872896 -233.8578)
		(end 306.101242 -233.8578)
		(width 0.14478)
		(layer "In13.Cu")
		(net "M_B_CPU0_SA_DQ<29>")
	)
	(segment
		(start 306.652676 -233.062272)
		(end 306.81422 -233.223816)
		(width 0.14478)
		(layer "In13.Cu")
		(net "M_B_CPU0_SA_DQ<29>")
	)
	(segment
		(start 300.249082 -232.610152)
		(end 300.93793 -232.610152)
		(width 0.14478)
		(layer "In13.Cu")
		(net "M_B_CPU0_SA_DQ<29>")
	)
	(segment
		(start 336.822796 -244.02288)
		(end 336.845148 -243.939568)
		(width 0.0889)
		(layer "In13.Cu")
		(net "M_B_CPU0_SA_DQ<29>")
	)
	(segment
		(start 305.321462 -233.062272)
		(end 305.549808 -233.062272)
		(width 0.14478)
		(layer "In13.Cu")
		(net "M_B_CPU0_SA_DQ<29>")
	)
	(segment
		(start 336.845148 -243.939568)
		(end 336.691224 -243.674138)
		(width 0.0889)
		(layer "In13.Cu")
		(net "M_B_CPU0_SA_DQ<29>")
	)
	(segment
		(start 328.409808 -244.001544)
		(end 328.41819 -243.996718)
		(width 0.0889)
		(layer "In13.Cu")
		(net "M_B_CPU0_SA_DQ<29>")
	)
	(segment
		(start 311.93105 -237.847124)
		(end 311.93105 -238.851694)
		(width 0.14478)
		(layer "In13.Cu")
		(net "M_B_CPU0_SA_DQ<29>")
	)
	(segment
		(start 306.81422 -233.298492)
		(end 306.975764 -233.460036)
		(width 0.14478)
		(layer "In13.Cu")
		(net "M_B_CPU0_SA_DQ<29>")
	)
	(segment
		(start 325.221092 -243.519452)
		(end 325.622158 -243.920518)
		(width 0.0889)
		(layer "In13.Cu")
		(net "M_B_CPU0_SA_DQ<29>")
	)
	(segment
		(start 306.975764 -233.460036)
		(end 307.543962 -233.460036)
		(width 0.14478)
		(layer "In13.Cu")
		(net "M_B_CPU0_SA_DQ<29>")
	)
	(segment
		(start 304.05705 -233.223816)
		(end 304.218594 -233.062272)
		(width 0.14478)
		(layer "In13.Cu")
		(net "M_B_CPU0_SA_DQ<29>")
	)
	(segment
		(start 307.543962 -233.460036)
		(end 311.93105 -237.847124)
		(width 0.14478)
		(layer "In13.Cu")
		(net "M_B_CPU0_SA_DQ<29>")
	)
	(segment
		(start 304.44694 -233.062272)
		(end 304.608484 -233.223816)
		(width 0.14478)
		(layer "In13.Cu")
		(net "M_B_CPU0_SA_DQ<29>")
	)
	(segment
		(start 328.984102 -243.996718)
		(end 328.992484 -244.001544)
		(width 0.0889)
		(layer "In13.Cu")
		(net "M_B_CPU0_SA_DQ<29>")
	)
	(segment
		(start 306.101242 -233.8578)
		(end 306.262786 -233.696256)
		(width 0.14478)
		(layer "In13.Cu")
		(net "M_B_CPU0_SA_DQ<29>")
	)
	(segment
		(start 305.159918 -233.696256)
		(end 305.159918 -233.223816)
		(width 0.14478)
		(layer "In13.Cu")
		(net "M_B_CPU0_SA_DQ<29>")
	)
	(segment
		(start 302.211994 -233.296968)
		(end 302.211994 -233.237278)
		(width 0.14478)
		(layer "In13.Cu")
		(net "M_B_CPU0_SA_DQ<29>")
	)
	(segment
		(start 305.711352 -233.696256)
		(end 305.872896 -233.8578)
		(width 0.14478)
		(layer "In13.Cu")
		(net "M_B_CPU0_SA_DQ<29>")
	)
	(segment
		(start 304.608484 -233.223816)
		(end 304.608484 -233.696256)
		(width 0.14478)
		(layer "In13.Cu")
		(net "M_B_CPU0_SA_DQ<29>")
	)
	(segment
		(start 302.211994 -233.237278)
		(end 302.375062 -233.07421)
		(width 0.14478)
		(layer "In13.Cu")
		(net "M_B_CPU0_SA_DQ<29>")
	)
	(segment
		(start 335.929732 -244.001544)
		(end 335.938114 -243.996718)
		(width 0.0889)
		(layer "In13.Cu")
		(net "M_B_CPU0_SA_DQ<29>")
	)
	(segment
		(start 303.895506 -233.849672)
		(end 304.05705 -233.688128)
		(width 0.14478)
		(layer "In13.Cu")
		(net "M_B_CPU0_SA_DQ<29>")
	)
	(segment
		(start 306.42433 -233.062272)
		(end 306.652676 -233.062272)
		(width 0.14478)
		(layer "In13.Cu")
		(net "M_B_CPU0_SA_DQ<29>")
	)
	(segment
		(start 332.744064 -243.996718)
		(end 332.752446 -244.001544)
		(width 0.0889)
		(layer "In13.Cu")
		(net "M_B_CPU0_SA_DQ<29>")
	)
	(segment
		(start 305.549808 -233.062272)
		(end 305.711352 -233.223816)
		(width 0.14478)
		(layer "In13.Cu")
		(net "M_B_CPU0_SA_DQ<29>")
	)
	(segment
		(start 326.537828 -243.996464)
		(end 326.543416 -243.993162)
		(width 0.0889)
		(layer "In13.Cu")
		(net "M_B_CPU0_SA_DQ<29>")
	)
	(segment
		(start 327.103232 -243.996718)
		(end 327.111614 -244.001544)
		(width 0.0889)
		(layer "In13.Cu")
		(net "M_B_CPU0_SA_DQ<29>")
	)
	(segment
		(start 302.048926 -233.460036)
		(end 302.211994 -233.296968)
		(width 0.14478)
		(layer "In13.Cu")
		(net "M_B_CPU0_SA_DQ<29>")
	)
	(segment
		(start 300.93793 -232.610152)
		(end 301.787814 -233.460036)
		(width 0.14478)
		(layer "In13.Cu")
		(net "M_B_CPU0_SA_DQ<29>")
	)
	(segment
		(start 326.51954 -244.006878)
		(end 326.537828 -243.996464)
		(width 0.0889)
		(layer "In13.Cu")
		(net "M_B_CPU0_SA_DQ<29>")
	)
	(segment
		(start 325.622158 -243.920518)
		(end 325.880476 -243.920518)
		(width 0.0889)
		(layer "In13.Cu")
		(net "M_B_CPU0_SA_DQ<29>")
	)
	(segment
		(start 302.375062 -233.07421)
		(end 302.60544 -233.07421)
		(width 0.14478)
		(layer "In13.Cu")
		(net "M_B_CPU0_SA_DQ<29>")
	)
	(segment
		(start 306.262786 -233.223816)
		(end 306.42433 -233.062272)
		(width 0.14478)
		(layer "In13.Cu")
		(net "M_B_CPU0_SA_DQ<29>")
	)
	(segment
		(start 305.711352 -233.223816)
		(end 305.711352 -233.696256)
		(width 0.14478)
		(layer "In13.Cu")
		(net "M_B_CPU0_SA_DQ<29>")
	)
	(segment
		(start 316.12967 -243.050314)
		(end 323.882258 -243.050314)
		(width 0.14478)
		(layer "In13.Cu")
		(net "M_B_CPU0_SA_DQ<29>")
	)
	(segment
		(start 332.16977 -244.001544)
		(end 332.178152 -243.996718)
		(width 0.0889)
		(layer "In13.Cu")
		(net "M_B_CPU0_SA_DQ<29>")
	)
	(segment
		(start 304.05705 -233.688128)
		(end 304.05705 -233.223816)
		(width 0.14478)
		(layer "In13.Cu")
		(net "M_B_CPU0_SA_DQ<29>")
	)
	(segment
		(start 302.768508 -233.686604)
		(end 302.931576 -233.849672)
		(width 0.14478)
		(layer "In13.Cu")
		(net "M_B_CPU0_SA_DQ<29>")
	)
	(segment
		(start 311.93105 -238.851694)
		(end 316.12967 -243.050314)
		(width 0.14478)
		(layer "In13.Cu")
		(net "M_B_CPU0_SA_DQ<29>")
	)
	(segment
		(start 324.12686 -243.050314)
		(end 324.595998 -243.519452)
		(width 0.0889)
		(layer "In13.Cu")
		(net "M_B_CPU0_SA_DQ<29>")
	)
	(segment
		(start 302.60544 -233.07421)
		(end 302.768508 -233.237278)
		(width 0.14478)
		(layer "In13.Cu")
		(net "M_B_CPU0_SA_DQ<29>")
	)
	(segment
		(start 304.998374 -233.8578)
		(end 305.159918 -233.696256)
		(width 0.14478)
		(layer "In13.Cu")
		(net "M_B_CPU0_SA_DQ<29>")
	)
	(segment
		(start 306.81422 -233.223816)
		(end 306.81422 -233.298492)
		(width 0.14478)
		(layer "In13.Cu")
		(net "M_B_CPU0_SA_DQ<29>")
	)
	(segment
		(start 331.229716 -244.001544)
		(end 331.238098 -243.996718)
		(width 0.0889)
		(layer "In13.Cu")
		(net "M_B_CPU0_SA_DQ<29>")
	)
	(segment
		(start 324.595998 -243.519452)
		(end 325.221092 -243.519452)
		(width 0.0889)
		(layer "In13.Cu")
		(net "M_B_CPU0_SA_DQ<29>")
	)
	(segment
		(start 333.684118 -243.996718)
		(end 333.6925 -244.001544)
		(width 0.0889)
		(layer "In13.Cu")
		(net "M_B_CPU0_SA_DQ<29>")
	)
	(segment
		(start 299.82414 -233.035094)
		(end 300.249082 -232.610152)
		(width 0.14478)
		(layer "In13.Cu")
		(net "M_B_CPU0_SA_DQ<29>")
	)
	(segment
		(start 302.768508 -233.237278)
		(end 302.768508 -233.686604)
		(width 0.14478)
		(layer "In13.Cu")
		(net "M_B_CPU0_SA_DQ<29>")
	)
	(segment
		(start 305.159918 -233.223816)
		(end 305.321462 -233.062272)
		(width 0.14478)
		(layer "In13.Cu")
		(net "M_B_CPU0_SA_DQ<29>")
	)
	(segment
		(start 304.608484 -233.696256)
		(end 304.770028 -233.8578)
		(width 0.14478)
		(layer "In13.Cu")
		(net "M_B_CPU0_SA_DQ<29>")
	)
	(segment
		(start 304.770028 -233.8578)
		(end 304.998374 -233.8578)
		(width 0.14478)
		(layer "In13.Cu")
		(net "M_B_CPU0_SA_DQ<29>")
	)
	(segment
		(start 301.787814 -233.460036)
		(end 302.048926 -233.460036)
		(width 0.14478)
		(layer "In13.Cu")
		(net "M_B_CPU0_SA_DQ<29>")
	)
	(segment
		(start 302.931576 -233.849672)
		(end 303.895506 -233.849672)
		(width 0.14478)
		(layer "In13.Cu")
		(net "M_B_CPU0_SA_DQ<29>")
	)
	(arc
		(start 333.118206 -243.996718)
		(mid 333.401162 -243.920541)
		(end 333.684118 -243.996718)
		(width 0.0889)
		(layer "In13.Cu")
		(net "M_B_CPU0_SA_DQ<29>")
	)
	(arc
		(start 328.41819 -243.996718)
		(mid 328.701146 -243.920541)
		(end 328.984102 -243.996718)
		(width 0.0889)
		(layer "In13.Cu")
		(net "M_B_CPU0_SA_DQ<29>")
	)
	(arc
		(start 326.163686 -243.996718)
		(mid 326.340314 -244.046951)
		(end 326.51954 -244.006878)
		(width 0.0889)
		(layer "In13.Cu")
		(net "M_B_CPU0_SA_DQ<29>")
	)
	(arc
		(start 334.05826 -243.996718)
		(mid 334.341216 -243.920541)
		(end 334.624172 -243.996718)
		(width 0.0889)
		(layer "In13.Cu")
		(net "M_B_CPU0_SA_DQ<29>")
	)
	(arc
		(start 327.477882 -243.996718)
		(mid 327.754949 -243.920447)
		(end 328.033634 -243.990622)
		(width 0.0889)
		(layer "In13.Cu")
		(net "M_B_CPU0_SA_DQ<29>")
	)
	(arc
		(start 329.924156 -243.996718)
		(mid 330.1111 -244.046973)
		(end 330.298044 -243.996718)
		(width 0.0889)
		(layer "In13.Cu")
		(net "M_B_CPU0_SA_DQ<29>")
	)
	(arc
		(start 335.563972 -243.996718)
		(mid 335.746223 -244.047068)
		(end 335.929732 -244.001544)
		(width 0.0889)
		(layer "In13.Cu")
		(net "M_B_CPU0_SA_DQ<29>")
	)
	(arc
		(start 330.298044 -243.996718)
		(mid 330.581 -243.920541)
		(end 330.863956 -243.996718)
		(width 0.0889)
		(layer "In13.Cu")
		(net "M_B_CPU0_SA_DQ<29>")
	)
	(arc
		(start 333.6925 -244.001544)
		(mid 333.876008 -244.047038)
		(end 334.05826 -243.996718)
		(width 0.0889)
		(layer "In13.Cu")
		(net "M_B_CPU0_SA_DQ<29>")
	)
	(arc
		(start 335.938114 -243.996718)
		(mid 336.22107 -243.920541)
		(end 336.504026 -243.996718)
		(width 0.0889)
		(layer "In13.Cu")
		(net "M_B_CPU0_SA_DQ<29>")
	)
	(arc
		(start 327.111614 -244.001544)
		(mid 327.295376 -244.04716)
		(end 327.477882 -243.996718)
		(width 0.0889)
		(layer "In13.Cu")
		(net "M_B_CPU0_SA_DQ<29>")
	)
	(arc
		(start 332.752446 -244.001544)
		(mid 332.935954 -244.047038)
		(end 333.118206 -243.996718)
		(width 0.0889)
		(layer "In13.Cu")
		(net "M_B_CPU0_SA_DQ<29>")
	)
	(arc
		(start 328.044048 -243.996718)
		(mid 328.226299 -244.047068)
		(end 328.409808 -244.001544)
		(width 0.0889)
		(layer "In13.Cu")
		(net "M_B_CPU0_SA_DQ<29>")
	)
	(arc
		(start 328.992484 -244.001544)
		(mid 329.175992 -244.047038)
		(end 329.358244 -243.996718)
		(width 0.0889)
		(layer "In13.Cu")
		(net "M_B_CPU0_SA_DQ<29>")
	)
	(arc
		(start 331.80401 -243.996718)
		(mid 331.986261 -244.047068)
		(end 332.16977 -244.001544)
		(width 0.0889)
		(layer "In13.Cu")
		(net "M_B_CPU0_SA_DQ<29>")
	)
	(arc
		(start 326.543416 -243.993162)
		(mid 326.823805 -243.920493)
		(end 327.103232 -243.996718)
		(width 0.0889)
		(layer "In13.Cu")
		(net "M_B_CPU0_SA_DQ<29>")
	)
	(arc
		(start 331.238098 -243.996718)
		(mid 331.521054 -243.920541)
		(end 331.80401 -243.996718)
		(width 0.0889)
		(layer "In13.Cu")
		(net "M_B_CPU0_SA_DQ<29>")
	)
	(arc
		(start 332.178152 -243.996718)
		(mid 332.461108 -243.920541)
		(end 332.744064 -243.996718)
		(width 0.0889)
		(layer "In13.Cu")
		(net "M_B_CPU0_SA_DQ<29>")
	)
	(arc
		(start 330.863956 -243.996718)
		(mid 331.046207 -244.047068)
		(end 331.229716 -244.001544)
		(width 0.0889)
		(layer "In13.Cu")
		(net "M_B_CPU0_SA_DQ<29>")
	)
	(arc
		(start 329.358244 -243.996718)
		(mid 329.6412 -243.920541)
		(end 329.924156 -243.996718)
		(width 0.0889)
		(layer "In13.Cu")
		(net "M_B_CPU0_SA_DQ<29>")
	)
	(arc
		(start 334.99806 -243.996718)
		(mid 335.281016 -243.920541)
		(end 335.563972 -243.996718)
		(width 0.0889)
		(layer "In13.Cu")
		(net "M_B_CPU0_SA_DQ<29>")
	)
	(arc
		(start 336.504026 -243.996718)
		(mid 336.660464 -244.045689)
		(end 336.822796 -244.02288)
		(width 0.0889)
		(layer "In13.Cu")
		(net "M_B_CPU0_SA_DQ<29>")
	)
	(arc
		(start 325.880476 -243.920518)
		(mid 326.027133 -243.939855)
		(end 326.163686 -243.996718)
		(width 0.0889)
		(layer "In13.Cu")
		(net "M_B_CPU0_SA_DQ<29>")
	)
	(arc
		(start 334.624172 -243.996718)
		(mid 334.811116 -244.046973)
		(end 334.99806 -243.996718)
		(width 0.0889)
		(layer "In13.Cu")
		(net "M_B_CPU0_SA_DQ<29>")
	)
	(segment
		(start 335.747868 -243.13007)
		(end 335.281016 -242.864132)
		(width 0.10668)
		(layer "F.Cu")
		(net "M_B_CPU0_SA_DQ<28>")
	)
	(segment
		(start 315.086746 -239.291114)
		(end 315.086492 -239.49533)
		(width 0.14478)
		(layer "In13.Cu")
		(net "M_B_CPU0_SA_DQ<28>")
	)
	(segment
		(start 306.982368 -231.769666)
		(end 307.565298 -231.769666)
		(width 0.14478)
		(layer "In13.Cu")
		(net "M_B_CPU0_SA_DQ<28>")
	)
	(segment
		(start 324.552818 -242.480592)
		(end 325.207884 -242.480592)
		(width 0.0889)
		(layer "In13.Cu")
		(net "M_B_CPU0_SA_DQ<28>")
	)
	(segment
		(start 314.130436 -238.891826)
		(end 314.130436 -239.09655)
		(width 0.14478)
		(layer "In13.Cu")
		(net "M_B_CPU0_SA_DQ<28>")
	)
	(segment
		(start 301.048166 -230.919782)
		(end 301.888398 -231.760014)
		(width 0.14478)
		(layer "In13.Cu")
		(net "M_B_CPU0_SA_DQ<28>")
	)
	(segment
		(start 316.079886 -240.84153)
		(end 316.256162 -240.665254)
		(width 0.14478)
		(layer "In13.Cu")
		(net "M_B_CPU0_SA_DQ<28>")
	)
	(segment
		(start 313.350656 -238.31677)
		(end 313.535822 -238.501936)
		(width 0.14478)
		(layer "In13.Cu")
		(net "M_B_CPU0_SA_DQ<28>")
	)
	(segment
		(start 315.689996 -240.65611)
		(end 315.875162 -240.841276)
		(width 0.14478)
		(layer "In13.Cu")
		(net "M_B_CPU0_SA_DQ<28>")
	)
	(segment
		(start 315.300106 -240.06175)
		(end 315.476382 -239.885474)
		(width 0.14478)
		(layer "In13.Cu")
		(net "M_B_CPU0_SA_DQ<28>")
	)
	(segment
		(start 312.203846 -236.47908)
		(end 312.274458 -236.478826)
		(width 0.14478)
		(layer "In13.Cu")
		(net "M_B_CPU0_SA_DQ<28>")
	)
	(segment
		(start 306.26939 -231.996488)
		(end 306.430934 -232.158032)
		(width 0.14478)
		(layer "In13.Cu")
		(net "M_B_CPU0_SA_DQ<28>")
	)
	(segment
		(start 305.8795 -231.769666)
		(end 306.107846 -231.769666)
		(width 0.14478)
		(layer "In13.Cu")
		(net "M_B_CPU0_SA_DQ<28>")
	)
	(segment
		(start 302.559466 -231.991662)
		(end 302.722534 -232.15473)
		(width 0.14478)
		(layer "In13.Cu")
		(net "M_B_CPU0_SA_DQ<28>")
	)
	(segment
		(start 305.328066 -232.158032)
		(end 305.556412 -232.158032)
		(width 0.14478)
		(layer "In13.Cu")
		(net "M_B_CPU0_SA_DQ<28>")
	)
	(segment
		(start 308.61381 -233.117136)
		(end 308.854602 -233.357928)
		(width 0.14478)
		(layer "In13.Cu")
		(net "M_B_CPU0_SA_DQ<28>")
	)
	(segment
		(start 315.086492 -239.49533)
		(end 314.910216 -239.671606)
		(width 0.14478)
		(layer "In13.Cu")
		(net "M_B_CPU0_SA_DQ<28>")
	)
	(segment
		(start 306.26939 -231.93121)
		(end 306.26939 -231.996488)
		(width 0.14478)
		(layer "In13.Cu")
		(net "M_B_CPU0_SA_DQ<28>")
	)
	(segment
		(start 325.837296 -243.110004)
		(end 326.351138 -243.110004)
		(width 0.0889)
		(layer "In13.Cu")
		(net "M_B_CPU0_SA_DQ<28>")
	)
	(segment
		(start 313.916822 -238.325914)
		(end 314.121546 -238.325914)
		(width 0.14478)
		(layer "In13.Cu")
		(net "M_B_CPU0_SA_DQ<28>")
	)
	(segment
		(start 326.991726 -243.197634)
		(end 327.010522 -243.186712)
		(width 0.0889)
		(layer "In13.Cu")
		(net "M_B_CPU0_SA_DQ<28>")
	)
	(segment
		(start 311.734962 -235.93933)
		(end 311.734962 -236.238288)
		(width 0.14478)
		(layer "In13.Cu")
		(net "M_B_CPU0_SA_DQ<28>")
	)
	(segment
		(start 309.862982 -234.138216)
		(end 309.933594 -234.137962)
		(width 0.14478)
		(layer "In13.Cu")
		(net "M_B_CPU0_SA_DQ<28>")
	)
	(segment
		(start 302.396398 -231.760014)
		(end 302.559466 -231.923082)
		(width 0.14478)
		(layer "In13.Cu")
		(net "M_B_CPU0_SA_DQ<28>")
	)
	(segment
		(start 314.306712 -238.71555)
		(end 314.130436 -238.891826)
		(width 0.14478)
		(layer "In13.Cu")
		(net "M_B_CPU0_SA_DQ<28>")
	)
	(segment
		(start 314.910216 -239.87633)
		(end 315.095382 -240.061496)
		(width 0.14478)
		(layer "In13.Cu")
		(net "M_B_CPU0_SA_DQ<28>")
	)
	(segment
		(start 312.756042 -237.259368)
		(end 312.984134 -237.259368)
		(width 0.14478)
		(layer "In13.Cu")
		(net "M_B_CPU0_SA_DQ<28>")
	)
	(segment
		(start 311.195466 -235.698792)
		(end 311.423558 -235.698792)
		(width 0.14478)
		(layer "In13.Cu")
		(net "M_B_CPU0_SA_DQ<28>")
	)
	(segment
		(start 335.412842 -243.212874)
		(end 335.435194 -243.129562)
		(width 0.0889)
		(layer "In13.Cu")
		(net "M_B_CPU0_SA_DQ<28>")
	)
	(segment
		(start 304.06594 -232.15473)
		(end 304.229008 -231.991662)
		(width 0.14478)
		(layer "In13.Cu")
		(net "M_B_CPU0_SA_DQ<28>")
	)
	(segment
		(start 310.713882 -234.91825)
		(end 310.954674 -235.159042)
		(width 0.14478)
		(layer "In13.Cu")
		(net "M_B_CPU0_SA_DQ<28>")
	)
	(segment
		(start 314.130436 -239.09655)
		(end 314.315602 -239.281716)
		(width 0.14478)
		(layer "In13.Cu")
		(net "M_B_CPU0_SA_DQ<28>")
	)
	(segment
		(start 304.229008 -231.923082)
		(end 304.382424 -231.769666)
		(width 0.14478)
		(layer "In13.Cu")
		(net "M_B_CPU0_SA_DQ<28>")
	)
	(segment
		(start 335.094072 -243.186712)
		(end 335.102454 -243.191538)
		(width 0.0889)
		(layer "In13.Cu")
		(net "M_B_CPU0_SA_DQ<28>")
	)
	(segment
		(start 304.229008 -231.991662)
		(end 304.229008 -231.923082)
		(width 0.14478)
		(layer "In13.Cu")
		(net "M_B_CPU0_SA_DQ<28>")
	)
	(segment
		(start 300.23054 -230.919782)
		(end 301.048166 -230.919782)
		(width 0.14478)
		(layer "In13.Cu")
		(net "M_B_CPU0_SA_DQ<28>")
	)
	(segment
		(start 312.51525 -236.719618)
		(end 312.51525 -237.018576)
		(width 0.14478)
		(layer "In13.Cu")
		(net "M_B_CPU0_SA_DQ<28>")
	)
	(segment
		(start 305.166522 -231.996488)
		(end 305.328066 -232.158032)
		(width 0.14478)
		(layer "In13.Cu")
		(net "M_B_CPU0_SA_DQ<28>")
	)
	(segment
		(start 303.835562 -232.15473)
		(end 304.06594 -232.15473)
		(width 0.14478)
		(layer "In13.Cu")
		(net "M_B_CPU0_SA_DQ<28>")
	)
	(segment
		(start 313.054746 -237.259114)
		(end 313.527186 -237.731554)
		(width 0.14478)
		(layer "In13.Cu")
		(net "M_B_CPU0_SA_DQ<28>")
	)
	(segment
		(start 327.55332 -243.174012)
		(end 327.57491 -243.186458)
		(width 0.0889)
		(layer "In13.Cu")
		(net "M_B_CPU0_SA_DQ<28>")
	)
	(segment
		(start 327.57491 -243.186458)
		(end 327.594976 -243.197888)
		(width 0.0889)
		(layer "In13.Cu")
		(net "M_B_CPU0_SA_DQ<28>")
	)
	(segment
		(start 307.565298 -231.769666)
		(end 308.61381 -232.818178)
		(width 0.14478)
		(layer "In13.Cu")
		(net "M_B_CPU0_SA_DQ<28>")
	)
	(segment
		(start 313.350656 -238.112046)
		(end 313.350656 -238.31677)
		(width 0.14478)
		(layer "In13.Cu")
		(net "M_B_CPU0_SA_DQ<28>")
	)
	(segment
		(start 313.740546 -238.50219)
		(end 313.916822 -238.325914)
		(width 0.14478)
		(layer "In13.Cu")
		(net "M_B_CPU0_SA_DQ<28>")
	)
	(segment
		(start 314.315602 -239.281716)
		(end 314.520326 -239.28197)
		(width 0.14478)
		(layer "In13.Cu")
		(net "M_B_CPU0_SA_DQ<28>")
	)
	(segment
		(start 310.64327 -234.918504)
		(end 310.713882 -234.91825)
		(width 0.14478)
		(layer "In13.Cu")
		(net "M_B_CPU0_SA_DQ<28>")
	)
	(segment
		(start 311.975754 -236.47908)
		(end 312.203846 -236.47908)
		(width 0.14478)
		(layer "In13.Cu")
		(net "M_B_CPU0_SA_DQ<28>")
	)
	(segment
		(start 308.854602 -233.357928)
		(end 309.15356 -233.357928)
		(width 0.14478)
		(layer "In13.Cu")
		(net "M_B_CPU0_SA_DQ<28>")
	)
	(segment
		(start 302.722534 -232.15473)
		(end 302.952912 -232.15473)
		(width 0.14478)
		(layer "In13.Cu")
		(net "M_B_CPU0_SA_DQ<28>")
	)
	(segment
		(start 304.382424 -231.769666)
		(end 305.004978 -231.769666)
		(width 0.14478)
		(layer "In13.Cu")
		(net "M_B_CPU0_SA_DQ<28>")
	)
	(segment
		(start 302.559466 -231.923082)
		(end 302.559466 -231.991662)
		(width 0.14478)
		(layer "In13.Cu")
		(net "M_B_CPU0_SA_DQ<28>")
	)
	(segment
		(start 315.689996 -240.451386)
		(end 315.689996 -240.65611)
		(width 0.14478)
		(layer "In13.Cu")
		(net "M_B_CPU0_SA_DQ<28>")
	)
	(segment
		(start 314.306966 -238.511334)
		(end 314.306712 -238.71555)
		(width 0.14478)
		(layer "In13.Cu")
		(net "M_B_CPU0_SA_DQ<28>")
	)
	(segment
		(start 335.435194 -243.129562)
		(end 335.281016 -242.864132)
		(width 0.0889)
		(layer "In13.Cu")
		(net "M_B_CPU0_SA_DQ<28>")
	)
	(segment
		(start 324.21322 -242.140994)
		(end 324.552818 -242.480592)
		(width 0.0889)
		(layer "In13.Cu")
		(net "M_B_CPU0_SA_DQ<28>")
	)
	(segment
		(start 310.954674 -235.458)
		(end 311.195466 -235.698792)
		(width 0.14478)
		(layer "In13.Cu")
		(net "M_B_CPU0_SA_DQ<28>")
	)
	(segment
		(start 329.819762 -243.191538)
		(end 329.828144 -243.186712)
		(width 0.0889)
		(layer "In13.Cu")
		(net "M_B_CPU0_SA_DQ<28>")
	)
	(segment
		(start 314.901326 -239.105694)
		(end 315.086746 -239.291114)
		(width 0.14478)
		(layer "In13.Cu")
		(net "M_B_CPU0_SA_DQ<28>")
	)
	(segment
		(start 312.274458 -236.478826)
		(end 312.51525 -236.719618)
		(width 0.14478)
		(layer "In13.Cu")
		(net "M_B_CPU0_SA_DQ<28>")
	)
	(segment
		(start 310.954674 -235.159042)
		(end 310.954674 -235.458)
		(width 0.14478)
		(layer "In13.Cu")
		(net "M_B_CPU0_SA_DQ<28>")
	)
	(segment
		(start 303.11598 -231.991662)
		(end 303.11598 -231.923082)
		(width 0.14478)
		(layer "In13.Cu")
		(net "M_B_CPU0_SA_DQ<28>")
	)
	(segment
		(start 313.526932 -237.93577)
		(end 313.350656 -238.112046)
		(width 0.14478)
		(layer "In13.Cu")
		(net "M_B_CPU0_SA_DQ<28>")
	)
	(segment
		(start 331.33411 -243.186712)
		(end 331.342492 -243.191538)
		(width 0.0889)
		(layer "In13.Cu")
		(net "M_B_CPU0_SA_DQ<28>")
	)
	(segment
		(start 309.15356 -233.357928)
		(end 309.394098 -233.598466)
		(width 0.14478)
		(layer "In13.Cu")
		(net "M_B_CPU0_SA_DQ<28>")
	)
	(segment
		(start 306.820824 -231.996488)
		(end 306.820824 -231.93121)
		(width 0.14478)
		(layer "In13.Cu")
		(net "M_B_CPU0_SA_DQ<28>")
	)
	(segment
		(start 312.51525 -237.018576)
		(end 312.756042 -237.259368)
		(width 0.14478)
		(layer "In13.Cu")
		(net "M_B_CPU0_SA_DQ<28>")
	)
	(segment
		(start 314.121546 -238.325914)
		(end 314.306966 -238.511334)
		(width 0.14478)
		(layer "In13.Cu")
		(net "M_B_CPU0_SA_DQ<28>")
	)
	(segment
		(start 315.875162 -240.841276)
		(end 316.079886 -240.84153)
		(width 0.14478)
		(layer "In13.Cu")
		(net "M_B_CPU0_SA_DQ<28>")
	)
	(segment
		(start 311.49417 -235.698538)
		(end 311.734962 -235.93933)
		(width 0.14478)
		(layer "In13.Cu")
		(net "M_B_CPU0_SA_DQ<28>")
	)
	(segment
		(start 315.866272 -240.27511)
		(end 315.689996 -240.451386)
		(width 0.14478)
		(layer "In13.Cu")
		(net "M_B_CPU0_SA_DQ<28>")
	)
	(segment
		(start 315.681106 -239.885474)
		(end 315.866526 -240.070894)
		(width 0.14478)
		(layer "In13.Cu")
		(net "M_B_CPU0_SA_DQ<28>")
	)
	(segment
		(start 309.63489 -234.138216)
		(end 309.862982 -234.138216)
		(width 0.14478)
		(layer "In13.Cu")
		(net "M_B_CPU0_SA_DQ<28>")
	)
	(segment
		(start 306.430934 -232.158032)
		(end 306.65928 -232.158032)
		(width 0.14478)
		(layer "In13.Cu")
		(net "M_B_CPU0_SA_DQ<28>")
	)
	(segment
		(start 314.696602 -239.105694)
		(end 314.901326 -239.105694)
		(width 0.14478)
		(layer "In13.Cu")
		(net "M_B_CPU0_SA_DQ<28>")
	)
	(segment
		(start 333.579724 -243.191538)
		(end 333.588106 -243.186712)
		(width 0.0889)
		(layer "In13.Cu")
		(net "M_B_CPU0_SA_DQ<28>")
	)
	(segment
		(start 306.107846 -231.769666)
		(end 306.26939 -231.93121)
		(width 0.14478)
		(layer "In13.Cu")
		(net "M_B_CPU0_SA_DQ<28>")
	)
	(segment
		(start 308.61381 -232.818178)
		(end 308.61381 -233.117136)
		(width 0.14478)
		(layer "In13.Cu")
		(net "M_B_CPU0_SA_DQ<28>")
	)
	(segment
		(start 303.279048 -231.760014)
		(end 303.509426 -231.760014)
		(width 0.14478)
		(layer "In13.Cu")
		(net "M_B_CPU0_SA_DQ<28>")
	)
	(segment
		(start 306.65928 -232.158032)
		(end 306.820824 -231.996488)
		(width 0.14478)
		(layer "In13.Cu")
		(net "M_B_CPU0_SA_DQ<28>")
	)
	(segment
		(start 330.394056 -243.186712)
		(end 330.402438 -243.191538)
		(width 0.0889)
		(layer "In13.Cu")
		(net "M_B_CPU0_SA_DQ<28>")
	)
	(segment
		(start 315.095382 -240.061496)
		(end 315.300106 -240.06175)
		(width 0.14478)
		(layer "In13.Cu")
		(net "M_B_CPU0_SA_DQ<28>")
	)
	(segment
		(start 305.717956 -231.93121)
		(end 305.8795 -231.769666)
		(width 0.14478)
		(layer "In13.Cu")
		(net "M_B_CPU0_SA_DQ<28>")
	)
	(segment
		(start 305.717956 -231.996488)
		(end 305.717956 -231.93121)
		(width 0.14478)
		(layer "In13.Cu")
		(net "M_B_CPU0_SA_DQ<28>")
	)
	(segment
		(start 315.866526 -240.070894)
		(end 315.866272 -240.27511)
		(width 0.14478)
		(layer "In13.Cu")
		(net "M_B_CPU0_SA_DQ<28>")
	)
	(segment
		(start 317.936626 -242.140994)
		(end 323.869558 -242.140994)
		(width 0.14478)
		(layer "In13.Cu")
		(net "M_B_CPU0_SA_DQ<28>")
	)
	(segment
		(start 305.556412 -232.158032)
		(end 305.717956 -231.996488)
		(width 0.14478)
		(layer "In13.Cu")
		(net "M_B_CPU0_SA_DQ<28>")
	)
	(segment
		(start 323.869558 -242.140994)
		(end 324.21322 -242.140994)
		(width 0.0889)
		(layer "In13.Cu")
		(net "M_B_CPU0_SA_DQ<28>")
	)
	(segment
		(start 299.82414 -231.326182)
		(end 300.23054 -230.919782)
		(width 0.14478)
		(layer "In13.Cu")
		(net "M_B_CPU0_SA_DQ<28>")
	)
	(segment
		(start 311.734962 -236.238288)
		(end 311.975754 -236.47908)
		(width 0.14478)
		(layer "In13.Cu")
		(net "M_B_CPU0_SA_DQ<28>")
	)
	(segment
		(start 310.174386 -234.378754)
		(end 310.174386 -234.677712)
		(width 0.14478)
		(layer "In13.Cu")
		(net "M_B_CPU0_SA_DQ<28>")
	)
	(segment
		(start 325.207884 -242.480592)
		(end 325.837296 -243.110004)
		(width 0.0889)
		(layer "In13.Cu")
		(net "M_B_CPU0_SA_DQ<28>")
	)
	(segment
		(start 299.82414 -231.335072)
		(end 299.82414 -231.326182)
		(width 0.14478)
		(layer "In13.Cu")
		(net "M_B_CPU0_SA_DQ<28>")
	)
	(segment
		(start 302.952912 -232.15473)
		(end 303.11598 -231.991662)
		(width 0.14478)
		(layer "In13.Cu")
		(net "M_B_CPU0_SA_DQ<28>")
	)
	(segment
		(start 314.910216 -239.671606)
		(end 314.910216 -239.87633)
		(width 0.14478)
		(layer "In13.Cu")
		(net "M_B_CPU0_SA_DQ<28>")
	)
	(segment
		(start 309.394098 -233.598466)
		(end 309.394098 -233.897424)
		(width 0.14478)
		(layer "In13.Cu")
		(net "M_B_CPU0_SA_DQ<28>")
	)
	(segment
		(start 303.672494 -231.923082)
		(end 303.672494 -231.991662)
		(width 0.14478)
		(layer "In13.Cu")
		(net "M_B_CPU0_SA_DQ<28>")
	)
	(segment
		(start 316.256162 -240.665254)
		(end 316.460886 -240.665254)
		(width 0.14478)
		(layer "In13.Cu")
		(net "M_B_CPU0_SA_DQ<28>")
	)
	(segment
		(start 309.394098 -233.897424)
		(end 309.63489 -234.138216)
		(width 0.14478)
		(layer "In13.Cu")
		(net "M_B_CPU0_SA_DQ<28>")
	)
	(segment
		(start 313.535822 -238.501936)
		(end 313.740546 -238.50219)
		(width 0.14478)
		(layer "In13.Cu")
		(net "M_B_CPU0_SA_DQ<28>")
	)
	(segment
		(start 310.415178 -234.918504)
		(end 310.64327 -234.918504)
		(width 0.14478)
		(layer "In13.Cu")
		(net "M_B_CPU0_SA_DQ<28>")
	)
	(segment
		(start 316.460886 -240.665254)
		(end 317.936626 -242.140994)
		(width 0.14478)
		(layer "In13.Cu")
		(net "M_B_CPU0_SA_DQ<28>")
	)
	(segment
		(start 305.166522 -231.93121)
		(end 305.166522 -231.996488)
		(width 0.14478)
		(layer "In13.Cu")
		(net "M_B_CPU0_SA_DQ<28>")
	)
	(segment
		(start 306.820824 -231.93121)
		(end 306.982368 -231.769666)
		(width 0.14478)
		(layer "In13.Cu")
		(net "M_B_CPU0_SA_DQ<28>")
	)
	(segment
		(start 303.11598 -231.923082)
		(end 303.279048 -231.760014)
		(width 0.14478)
		(layer "In13.Cu")
		(net "M_B_CPU0_SA_DQ<28>")
	)
	(segment
		(start 315.476382 -239.885474)
		(end 315.681106 -239.885474)
		(width 0.14478)
		(layer "In13.Cu")
		(net "M_B_CPU0_SA_DQ<28>")
	)
	(segment
		(start 303.509426 -231.760014)
		(end 303.672494 -231.923082)
		(width 0.14478)
		(layer "In13.Cu")
		(net "M_B_CPU0_SA_DQ<28>")
	)
	(segment
		(start 313.527186 -237.731554)
		(end 313.526932 -237.93577)
		(width 0.14478)
		(layer "In13.Cu")
		(net "M_B_CPU0_SA_DQ<28>")
	)
	(segment
		(start 314.520326 -239.28197)
		(end 314.696602 -239.105694)
		(width 0.14478)
		(layer "In13.Cu")
		(net "M_B_CPU0_SA_DQ<28>")
	)
	(segment
		(start 312.984134 -237.259368)
		(end 313.054746 -237.259114)
		(width 0.14478)
		(layer "In13.Cu")
		(net "M_B_CPU0_SA_DQ<28>")
	)
	(segment
		(start 311.423558 -235.698792)
		(end 311.49417 -235.698538)
		(width 0.14478)
		(layer "In13.Cu")
		(net "M_B_CPU0_SA_DQ<28>")
	)
	(segment
		(start 310.174386 -234.677712)
		(end 310.415178 -234.918504)
		(width 0.14478)
		(layer "In13.Cu")
		(net "M_B_CPU0_SA_DQ<28>")
	)
	(segment
		(start 305.004978 -231.769666)
		(end 305.166522 -231.93121)
		(width 0.14478)
		(layer "In13.Cu")
		(net "M_B_CPU0_SA_DQ<28>")
	)
	(segment
		(start 309.933594 -234.137962)
		(end 310.174386 -234.378754)
		(width 0.14478)
		(layer "In13.Cu")
		(net "M_B_CPU0_SA_DQ<28>")
	)
	(segment
		(start 301.888398 -231.760014)
		(end 302.396398 -231.760014)
		(width 0.14478)
		(layer "In13.Cu")
		(net "M_B_CPU0_SA_DQ<28>")
	)
	(segment
		(start 303.672494 -231.991662)
		(end 303.835562 -232.15473)
		(width 0.14478)
		(layer "In13.Cu")
		(net "M_B_CPU0_SA_DQ<28>")
	)
	(segment
		(start 334.519778 -243.191538)
		(end 334.52816 -243.186712)
		(width 0.0889)
		(layer "In13.Cu")
		(net "M_B_CPU0_SA_DQ<28>")
	)
	(arc
		(start 329.454002 -243.186712)
		(mid 329.636253 -243.237062)
		(end 329.819762 -243.191538)
		(width 0.0889)
		(layer "In13.Cu")
		(net "M_B_CPU0_SA_DQ<28>")
	)
	(arc
		(start 332.274164 -243.186712)
		(mid 332.461108 -243.236967)
		(end 332.648052 -243.186712)
		(width 0.0889)
		(layer "In13.Cu")
		(net "M_B_CPU0_SA_DQ<28>")
	)
	(arc
		(start 334.154018 -243.186712)
		(mid 334.336269 -243.237062)
		(end 334.519778 -243.191538)
		(width 0.0889)
		(layer "In13.Cu")
		(net "M_B_CPU0_SA_DQ<28>")
	)
	(arc
		(start 330.768198 -243.186712)
		(mid 331.051154 -243.110535)
		(end 331.33411 -243.186712)
		(width 0.0889)
		(layer "In13.Cu")
		(net "M_B_CPU0_SA_DQ<28>")
	)
	(arc
		(start 333.213964 -243.186712)
		(mid 333.396215 -243.237062)
		(end 333.579724 -243.191538)
		(width 0.0889)
		(layer "In13.Cu")
		(net "M_B_CPU0_SA_DQ<28>")
	)
	(arc
		(start 330.402438 -243.191538)
		(mid 330.585946 -243.237032)
		(end 330.768198 -243.186712)
		(width 0.0889)
		(layer "In13.Cu")
		(net "M_B_CPU0_SA_DQ<28>")
	)
	(arc
		(start 332.648052 -243.186712)
		(mid 332.931008 -243.110535)
		(end 333.213964 -243.186712)
		(width 0.0889)
		(layer "In13.Cu")
		(net "M_B_CPU0_SA_DQ<28>")
	)
	(arc
		(start 331.342492 -243.191538)
		(mid 331.526 -243.237032)
		(end 331.708252 -243.186712)
		(width 0.0889)
		(layer "In13.Cu")
		(net "M_B_CPU0_SA_DQ<28>")
	)
	(arc
		(start 333.588106 -243.186712)
		(mid 333.871062 -243.110535)
		(end 334.154018 -243.186712)
		(width 0.0889)
		(layer "In13.Cu")
		(net "M_B_CPU0_SA_DQ<28>")
	)
	(arc
		(start 327.594976 -243.197888)
		(mid 327.773054 -243.236872)
		(end 327.94829 -243.186712)
		(width 0.0889)
		(layer "In13.Cu")
		(net "M_B_CPU0_SA_DQ<28>")
	)
	(arc
		(start 326.635364 -243.186712)
		(mid 326.812155 -243.237431)
		(end 326.991726 -243.197634)
		(width 0.0889)
		(layer "In13.Cu")
		(net "M_B_CPU0_SA_DQ<28>")
	)
	(arc
		(start 334.52816 -243.186712)
		(mid 334.811116 -243.110535)
		(end 335.094072 -243.186712)
		(width 0.0889)
		(layer "In13.Cu")
		(net "M_B_CPU0_SA_DQ<28>")
	)
	(arc
		(start 331.708252 -243.186712)
		(mid 331.991208 -243.110535)
		(end 332.274164 -243.186712)
		(width 0.0889)
		(layer "In13.Cu")
		(net "M_B_CPU0_SA_DQ<28>")
	)
	(arc
		(start 335.102454 -243.191538)
		(mid 335.255324 -243.236179)
		(end 335.412842 -243.212874)
		(width 0.0889)
		(layer "In13.Cu")
		(net "M_B_CPU0_SA_DQ<28>")
	)
	(arc
		(start 329.828144 -243.186712)
		(mid 330.1111 -243.110535)
		(end 330.394056 -243.186712)
		(width 0.0889)
		(layer "In13.Cu")
		(net "M_B_CPU0_SA_DQ<28>")
	)
	(arc
		(start 327.010522 -243.186712)
		(mid 327.280291 -243.110689)
		(end 327.55332 -243.174012)
		(width 0.0889)
		(layer "In13.Cu")
		(net "M_B_CPU0_SA_DQ<28>")
	)
	(arc
		(start 328.88809 -243.186712)
		(mid 329.171046 -243.110535)
		(end 329.454002 -243.186712)
		(width 0.0889)
		(layer "In13.Cu")
		(net "M_B_CPU0_SA_DQ<28>")
	)
	(arc
		(start 326.351138 -243.110004)
		(mid 326.498347 -243.129481)
		(end 326.635364 -243.186712)
		(width 0.0889)
		(layer "In13.Cu")
		(net "M_B_CPU0_SA_DQ<28>")
	)
	(arc
		(start 327.94829 -243.186712)
		(mid 328.231246 -243.110535)
		(end 328.514202 -243.186712)
		(width 0.0889)
		(layer "In13.Cu")
		(net "M_B_CPU0_SA_DQ<28>")
	)
	(arc
		(start 328.514202 -243.186712)
		(mid 328.701146 -243.236967)
		(end 328.88809 -243.186712)
		(width 0.0889)
		(layer "In13.Cu")
		(net "M_B_CPU0_SA_DQ<28>")
	)
	(segment
		(start 337.627976 -241.510058)
		(end 337.161124 -241.24412)
		(width 0.10668)
		(layer "F.Cu")
		(net "M_B_CPU0_SA_DQ<27>")
	)
	(segment
		(start 314.271914 -235.221018)
		(end 314.271914 -233.972354)
		(width 0.14478)
		(layer "In13.Cu")
		(net "M_B_CPU0_SA_DQ<27>")
	)
	(segment
		(start 331.342492 -240.916714)
		(end 331.33411 -240.92154)
		(width 0.0889)
		(layer "In13.Cu")
		(net "M_B_CPU0_SA_DQ<27>")
	)
	(segment
		(start 334.52816 -240.92154)
		(end 334.519778 -240.916714)
		(width 0.0889)
		(layer "In13.Cu")
		(net "M_B_CPU0_SA_DQ<27>")
	)
	(segment
		(start 314.271914 -233.972354)
		(end 309.037228 -228.737668)
		(width 0.14478)
		(layer "In13.Cu")
		(net "M_B_CPU0_SA_DQ<27>")
	)
	(segment
		(start 337.161124 -241.24412)
		(end 337.0072 -240.97869)
		(width 0.0889)
		(layer "In13.Cu")
		(net "M_B_CPU0_SA_DQ<27>")
	)
	(segment
		(start 297.870372 -227.500434)
		(end 297.834812 -227.515166)
		(width 0.14478)
		(layer "In13.Cu")
		(net "M_B_CPU0_SA_DQ<27>")
	)
	(segment
		(start 308.12613 -228.360224)
		(end 302.672496 -228.360224)
		(width 0.14478)
		(layer "In13.Cu")
		(net "M_B_CPU0_SA_DQ<27>")
	)
	(segment
		(start 335.102454 -240.916714)
		(end 335.094072 -240.92154)
		(width 0.0889)
		(layer "In13.Cu")
		(net "M_B_CPU0_SA_DQ<27>")
	)
	(segment
		(start 329.828144 -240.92154)
		(end 329.819762 -240.916714)
		(width 0.0889)
		(layer "In13.Cu")
		(net "M_B_CPU0_SA_DQ<27>")
	)
	(segment
		(start 327.02246 -240.930176)
		(end 327.007728 -240.92154)
		(width 0.0889)
		(layer "In13.Cu")
		(net "M_B_CPU0_SA_DQ<27>")
	)
	(segment
		(start 309.037228 -228.737668)
		(end 308.12613 -228.360224)
		(width 0.14478)
		(layer "In13.Cu")
		(net "M_B_CPU0_SA_DQ<27>")
	)
	(segment
		(start 324.02653 -239.782604)
		(end 323.886068 -239.782604)
		(width 0.0889)
		(layer "In13.Cu")
		(net "M_B_CPU0_SA_DQ<27>")
	)
	(segment
		(start 337.0072 -240.97869)
		(end 336.911188 -240.95329)
		(width 0.0889)
		(layer "In13.Cu")
		(net "M_B_CPU0_SA_DQ<27>")
	)
	(segment
		(start 327.007728 -240.92154)
		(end 326.999346 -240.916714)
		(width 0.0889)
		(layer "In13.Cu")
		(net "M_B_CPU0_SA_DQ<27>")
	)
	(segment
		(start 326.351138 -240.99774)
		(end 325.764906 -240.99774)
		(width 0.0889)
		(layer "In13.Cu")
		(net "M_B_CPU0_SA_DQ<27>")
	)
	(segment
		(start 327.94829 -240.92154)
		(end 327.939908 -240.916714)
		(width 0.0889)
		(layer "In13.Cu")
		(net "M_B_CPU0_SA_DQ<27>")
	)
	(segment
		(start 325.175118 -240.407952)
		(end 324.651878 -240.407952)
		(width 0.0889)
		(layer "In13.Cu")
		(net "M_B_CPU0_SA_DQ<27>")
	)
	(segment
		(start 336.042508 -240.916714)
		(end 336.034126 -240.92154)
		(width 0.0889)
		(layer "In13.Cu")
		(net "M_B_CPU0_SA_DQ<27>")
	)
	(segment
		(start 323.886068 -239.782604)
		(end 318.8335 -239.782604)
		(width 0.14478)
		(layer "In13.Cu")
		(net "M_B_CPU0_SA_DQ<27>")
	)
	(segment
		(start 333.588106 -240.92154)
		(end 333.579724 -240.916714)
		(width 0.0889)
		(layer "In13.Cu")
		(net "M_B_CPU0_SA_DQ<27>")
	)
	(segment
		(start 324.651878 -240.407952)
		(end 324.02653 -239.782604)
		(width 0.0889)
		(layer "In13.Cu")
		(net "M_B_CPU0_SA_DQ<27>")
	)
	(segment
		(start 299.414184 -227.71227)
		(end 298.902882 -227.500434)
		(width 0.14478)
		(layer "In13.Cu")
		(net "M_B_CPU0_SA_DQ<27>")
	)
	(segment
		(start 298.902882 -227.500434)
		(end 297.870372 -227.500434)
		(width 0.14478)
		(layer "In13.Cu")
		(net "M_B_CPU0_SA_DQ<27>")
	)
	(segment
		(start 330.402438 -240.916714)
		(end 330.394056 -240.92154)
		(width 0.0889)
		(layer "In13.Cu")
		(net "M_B_CPU0_SA_DQ<27>")
	)
	(segment
		(start 318.8335 -239.782604)
		(end 314.271914 -235.221018)
		(width 0.14478)
		(layer "In13.Cu")
		(net "M_B_CPU0_SA_DQ<27>")
	)
	(segment
		(start 302.672496 -228.360224)
		(end 299.414184 -227.71227)
		(width 0.14478)
		(layer "In13.Cu")
		(net "M_B_CPU0_SA_DQ<27>")
	)
	(segment
		(start 325.764906 -240.99774)
		(end 325.175118 -240.407952)
		(width 0.0889)
		(layer "In13.Cu")
		(net "M_B_CPU0_SA_DQ<27>")
	)
	(segment
		(start 297.834812 -227.515166)
		(end 295.724072 -227.935028)
		(width 0.14478)
		(layer "In13.Cu")
		(net "M_B_CPU0_SA_DQ<27>")
	)
	(arc
		(start 334.154018 -240.92154)
		(mid 333.871062 -240.997717)
		(end 333.588106 -240.92154)
		(width 0.0889)
		(layer "In13.Cu")
		(net "M_B_CPU0_SA_DQ<27>")
	)
	(arc
		(start 334.519778 -240.916714)
		(mid 334.33627 -240.87122)
		(end 334.154018 -240.92154)
		(width 0.0889)
		(layer "In13.Cu")
		(net "M_B_CPU0_SA_DQ<27>")
	)
	(arc
		(start 329.454002 -240.92154)
		(mid 329.171046 -240.997717)
		(end 328.88809 -240.92154)
		(width 0.0889)
		(layer "In13.Cu")
		(net "M_B_CPU0_SA_DQ<27>")
	)
	(arc
		(start 332.648052 -240.92154)
		(mid 332.461108 -240.871285)
		(end 332.274164 -240.92154)
		(width 0.0889)
		(layer "In13.Cu")
		(net "M_B_CPU0_SA_DQ<27>")
	)
	(arc
		(start 326.999346 -240.916714)
		(mid 326.816092 -240.871341)
		(end 326.634094 -240.92154)
		(width 0.0889)
		(layer "In13.Cu")
		(net "M_B_CPU0_SA_DQ<27>")
	)
	(arc
		(start 333.579724 -240.916714)
		(mid 333.396216 -240.87122)
		(end 333.213964 -240.92154)
		(width 0.0889)
		(layer "In13.Cu")
		(net "M_B_CPU0_SA_DQ<27>")
	)
	(arc
		(start 327.57364 -240.92154)
		(mid 327.299188 -240.997776)
		(end 327.02246 -240.930176)
		(width 0.0889)
		(layer "In13.Cu")
		(net "M_B_CPU0_SA_DQ<27>")
	)
	(arc
		(start 331.708252 -240.92154)
		(mid 331.526001 -240.87119)
		(end 331.342492 -240.916714)
		(width 0.0889)
		(layer "In13.Cu")
		(net "M_B_CPU0_SA_DQ<27>")
	)
	(arc
		(start 333.213964 -240.92154)
		(mid 332.931008 -240.997717)
		(end 332.648052 -240.92154)
		(width 0.0889)
		(layer "In13.Cu")
		(net "M_B_CPU0_SA_DQ<27>")
	)
	(arc
		(start 336.034126 -240.92154)
		(mid 335.75117 -240.997717)
		(end 335.468214 -240.92154)
		(width 0.0889)
		(layer "In13.Cu")
		(net "M_B_CPU0_SA_DQ<27>")
	)
	(arc
		(start 328.88809 -240.92154)
		(mid 328.701146 -240.871285)
		(end 328.514202 -240.92154)
		(width 0.0889)
		(layer "In13.Cu")
		(net "M_B_CPU0_SA_DQ<27>")
	)
	(arc
		(start 335.468214 -240.92154)
		(mid 335.285963 -240.87119)
		(end 335.102454 -240.916714)
		(width 0.0889)
		(layer "In13.Cu")
		(net "M_B_CPU0_SA_DQ<27>")
	)
	(arc
		(start 336.911188 -240.95329)
		(mid 336.65598 -240.996767)
		(end 336.408268 -240.92154)
		(width 0.0889)
		(layer "In13.Cu")
		(net "M_B_CPU0_SA_DQ<27>")
	)
	(arc
		(start 330.768198 -240.92154)
		(mid 330.585947 -240.87119)
		(end 330.402438 -240.916714)
		(width 0.0889)
		(layer "In13.Cu")
		(net "M_B_CPU0_SA_DQ<27>")
	)
	(arc
		(start 331.33411 -240.92154)
		(mid 331.051154 -240.997717)
		(end 330.768198 -240.92154)
		(width 0.0889)
		(layer "In13.Cu")
		(net "M_B_CPU0_SA_DQ<27>")
	)
	(arc
		(start 328.514202 -240.92154)
		(mid 328.231246 -240.997717)
		(end 327.94829 -240.92154)
		(width 0.0889)
		(layer "In13.Cu")
		(net "M_B_CPU0_SA_DQ<27>")
	)
	(arc
		(start 330.394056 -240.92154)
		(mid 330.1111 -240.997717)
		(end 329.828144 -240.92154)
		(width 0.0889)
		(layer "In13.Cu")
		(net "M_B_CPU0_SA_DQ<27>")
	)
	(arc
		(start 335.094072 -240.92154)
		(mid 334.811116 -240.997717)
		(end 334.52816 -240.92154)
		(width 0.0889)
		(layer "In13.Cu")
		(net "M_B_CPU0_SA_DQ<27>")
	)
	(arc
		(start 329.819762 -240.916714)
		(mid 329.636254 -240.87122)
		(end 329.454002 -240.92154)
		(width 0.0889)
		(layer "In13.Cu")
		(net "M_B_CPU0_SA_DQ<27>")
	)
	(arc
		(start 326.634094 -240.92154)
		(mid 326.497658 -240.978365)
		(end 326.351138 -240.99774)
		(width 0.0889)
		(layer "In13.Cu")
		(net "M_B_CPU0_SA_DQ<27>")
	)
	(arc
		(start 327.939908 -240.916714)
		(mid 327.756146 -240.871098)
		(end 327.57364 -240.92154)
		(width 0.0889)
		(layer "In13.Cu")
		(net "M_B_CPU0_SA_DQ<27>")
	)
	(arc
		(start 336.408268 -240.92154)
		(mid 336.226017 -240.87119)
		(end 336.042508 -240.916714)
		(width 0.0889)
		(layer "In13.Cu")
		(net "M_B_CPU0_SA_DQ<27>")
	)
	(arc
		(start 332.274164 -240.92154)
		(mid 331.991208 -240.997717)
		(end 331.708252 -240.92154)
		(width 0.0889)
		(layer "In13.Cu")
		(net "M_B_CPU0_SA_DQ<27>")
	)
	(segment
		(start 336.218022 -240.700052)
		(end 335.75117 -240.434114)
		(width 0.10668)
		(layer "F.Cu")
		(net "M_B_CPU0_SA_DQ<26>")
	)
	(segment
		(start 302.04664 -226.660202)
		(end 301.196502 -225.810064)
		(width 0.14478)
		(layer "In13.Cu")
		(net "M_B_CPU0_SA_DQ<26>")
	)
	(segment
		(start 309.535576 -227.963984)
		(end 307.087778 -226.950016)
		(width 0.14478)
		(layer "In13.Cu")
		(net "M_B_CPU0_SA_DQ<26>")
	)
	(segment
		(start 307.087778 -226.950016)
		(end 304.605436 -226.950016)
		(width 0.14478)
		(layer "In13.Cu")
		(net "M_B_CPU0_SA_DQ<26>")
	)
	(segment
		(start 328.41819 -240.111534)
		(end 328.409808 -240.106708)
		(width 0.0889)
		(layer "In13.Cu")
		(net "M_B_CPU0_SA_DQ<26>")
	)
	(segment
		(start 333.6925 -240.106708)
		(end 333.684118 -240.111534)
		(width 0.0889)
		(layer "In13.Cu")
		(net "M_B_CPU0_SA_DQ<26>")
	)
	(segment
		(start 324.352158 -239.051592)
		(end 324.17385 -238.873284)
		(width 0.0889)
		(layer "In13.Cu")
		(net "M_B_CPU0_SA_DQ<26>")
	)
	(segment
		(start 335.75117 -240.434114)
		(end 335.596992 -240.168684)
		(width 0.0889)
		(layer "In13.Cu")
		(net "M_B_CPU0_SA_DQ<26>")
	)
	(segment
		(start 298.162472 -225.810064)
		(end 297.73753 -226.235006)
		(width 0.14478)
		(layer "In13.Cu")
		(net "M_B_CPU0_SA_DQ<26>")
	)
	(segment
		(start 335.596992 -240.168684)
		(end 335.500726 -240.143284)
		(width 0.0889)
		(layer "In13.Cu")
		(net "M_B_CPU0_SA_DQ<26>")
	)
	(segment
		(start 326.351138 -240.060988)
		(end 326.062594 -240.060988)
		(width 0.0889)
		(layer "In13.Cu")
		(net "M_B_CPU0_SA_DQ<26>")
	)
	(segment
		(start 304.315622 -226.660202)
		(end 302.04664 -226.660202)
		(width 0.14478)
		(layer "In13.Cu")
		(net "M_B_CPU0_SA_DQ<26>")
	)
	(segment
		(start 323.865748 -238.873284)
		(end 319.196212 -238.873284)
		(width 0.14478)
		(layer "In13.Cu")
		(net "M_B_CPU0_SA_DQ<26>")
	)
	(segment
		(start 297.73753 -226.235006)
		(end 295.724072 -226.235006)
		(width 0.14478)
		(layer "In13.Cu")
		(net "M_B_CPU0_SA_DQ<26>")
	)
	(segment
		(start 326.062594 -240.060988)
		(end 325.053198 -239.051592)
		(width 0.0889)
		(layer "In13.Cu")
		(net "M_B_CPU0_SA_DQ<26>")
	)
	(segment
		(start 327.112376 -240.106708)
		(end 327.103994 -240.111534)
		(width 0.0889)
		(layer "In13.Cu")
		(net "M_B_CPU0_SA_DQ<26>")
	)
	(segment
		(start 328.992484 -240.106708)
		(end 328.984102 -240.111534)
		(width 0.0889)
		(layer "In13.Cu")
		(net "M_B_CPU0_SA_DQ<26>")
	)
	(segment
		(start 319.196212 -238.873284)
		(end 315.211714 -234.888786)
		(width 0.14478)
		(layer "In13.Cu")
		(net "M_B_CPU0_SA_DQ<26>")
	)
	(segment
		(start 325.053198 -239.051592)
		(end 324.352158 -239.051592)
		(width 0.0889)
		(layer "In13.Cu")
		(net "M_B_CPU0_SA_DQ<26>")
	)
	(segment
		(start 332.752446 -240.106708)
		(end 332.744064 -240.111534)
		(width 0.0889)
		(layer "In13.Cu")
		(net "M_B_CPU0_SA_DQ<26>")
	)
	(segment
		(start 304.605436 -226.950016)
		(end 304.315622 -226.660202)
		(width 0.14478)
		(layer "In13.Cu")
		(net "M_B_CPU0_SA_DQ<26>")
	)
	(segment
		(start 315.211714 -233.640122)
		(end 309.535576 -227.963984)
		(width 0.14478)
		(layer "In13.Cu")
		(net "M_B_CPU0_SA_DQ<26>")
	)
	(segment
		(start 315.211714 -234.888786)
		(end 315.211714 -233.640122)
		(width 0.14478)
		(layer "In13.Cu")
		(net "M_B_CPU0_SA_DQ<26>")
	)
	(segment
		(start 324.17385 -238.873284)
		(end 323.865748 -238.873284)
		(width 0.0889)
		(layer "In13.Cu")
		(net "M_B_CPU0_SA_DQ<26>")
	)
	(segment
		(start 332.178152 -240.111534)
		(end 332.16977 -240.106708)
		(width 0.0889)
		(layer "In13.Cu")
		(net "M_B_CPU0_SA_DQ<26>")
	)
	(segment
		(start 331.238098 -240.111534)
		(end 331.229716 -240.106708)
		(width 0.0889)
		(layer "In13.Cu")
		(net "M_B_CPU0_SA_DQ<26>")
	)
	(segment
		(start 301.196502 -225.810064)
		(end 298.162472 -225.810064)
		(width 0.14478)
		(layer "In13.Cu")
		(net "M_B_CPU0_SA_DQ<26>")
	)
	(arc
		(start 332.16977 -240.106708)
		(mid 331.986262 -240.061214)
		(end 331.80401 -240.111534)
		(width 0.0889)
		(layer "In13.Cu")
		(net "M_B_CPU0_SA_DQ<26>")
	)
	(arc
		(start 331.229716 -240.106708)
		(mid 331.046208 -240.061214)
		(end 330.863956 -240.111534)
		(width 0.0889)
		(layer "In13.Cu")
		(net "M_B_CPU0_SA_DQ<26>")
	)
	(arc
		(start 326.538082 -240.111534)
		(mid 326.447949 -240.073914)
		(end 326.351138 -240.060988)
		(width 0.0889)
		(layer "In13.Cu")
		(net "M_B_CPU0_SA_DQ<26>")
	)
	(arc
		(start 334.05826 -240.111534)
		(mid 333.876009 -240.061184)
		(end 333.6925 -240.106708)
		(width 0.0889)
		(layer "In13.Cu")
		(net "M_B_CPU0_SA_DQ<26>")
	)
	(arc
		(start 335.500726 -240.143284)
		(mid 335.245661 -240.186635)
		(end 334.99806 -240.111534)
		(width 0.0889)
		(layer "In13.Cu")
		(net "M_B_CPU0_SA_DQ<26>")
	)
	(arc
		(start 329.924156 -240.111534)
		(mid 329.6412 -240.187711)
		(end 329.358244 -240.111534)
		(width 0.0889)
		(layer "In13.Cu")
		(net "M_B_CPU0_SA_DQ<26>")
	)
	(arc
		(start 329.358244 -240.111534)
		(mid 329.175993 -240.061184)
		(end 328.992484 -240.106708)
		(width 0.0889)
		(layer "In13.Cu")
		(net "M_B_CPU0_SA_DQ<26>")
	)
	(arc
		(start 328.409808 -240.106708)
		(mid 328.2263 -240.061214)
		(end 328.044048 -240.111534)
		(width 0.0889)
		(layer "In13.Cu")
		(net "M_B_CPU0_SA_DQ<26>")
	)
	(arc
		(start 333.684118 -240.111534)
		(mid 333.401162 -240.187711)
		(end 333.118206 -240.111534)
		(width 0.0889)
		(layer "In13.Cu")
		(net "M_B_CPU0_SA_DQ<26>")
	)
	(arc
		(start 327.478136 -240.111534)
		(mid 327.295885 -240.061184)
		(end 327.112376 -240.106708)
		(width 0.0889)
		(layer "In13.Cu")
		(net "M_B_CPU0_SA_DQ<26>")
	)
	(arc
		(start 334.624172 -240.111534)
		(mid 334.341216 -240.187711)
		(end 334.05826 -240.111534)
		(width 0.0889)
		(layer "In13.Cu")
		(net "M_B_CPU0_SA_DQ<26>")
	)
	(arc
		(start 333.118206 -240.111534)
		(mid 332.935955 -240.061184)
		(end 332.752446 -240.106708)
		(width 0.0889)
		(layer "In13.Cu")
		(net "M_B_CPU0_SA_DQ<26>")
	)
	(arc
		(start 332.744064 -240.111534)
		(mid 332.461108 -240.187711)
		(end 332.178152 -240.111534)
		(width 0.0889)
		(layer "In13.Cu")
		(net "M_B_CPU0_SA_DQ<26>")
	)
	(arc
		(start 327.103994 -240.111534)
		(mid 326.821038 -240.187711)
		(end 326.538082 -240.111534)
		(width 0.0889)
		(layer "In13.Cu")
		(net "M_B_CPU0_SA_DQ<26>")
	)
	(arc
		(start 330.863956 -240.111534)
		(mid 330.581 -240.187711)
		(end 330.298044 -240.111534)
		(width 0.0889)
		(layer "In13.Cu")
		(net "M_B_CPU0_SA_DQ<26>")
	)
	(arc
		(start 334.99806 -240.111534)
		(mid 334.811116 -240.061279)
		(end 334.624172 -240.111534)
		(width 0.0889)
		(layer "In13.Cu")
		(net "M_B_CPU0_SA_DQ<26>")
	)
	(arc
		(start 328.044048 -240.111534)
		(mid 327.761092 -240.187711)
		(end 327.478136 -240.111534)
		(width 0.0889)
		(layer "In13.Cu")
		(net "M_B_CPU0_SA_DQ<26>")
	)
	(arc
		(start 330.298044 -240.111534)
		(mid 330.1111 -240.061279)
		(end 329.924156 -240.111534)
		(width 0.0889)
		(layer "In13.Cu")
		(net "M_B_CPU0_SA_DQ<26>")
	)
	(arc
		(start 331.80401 -240.111534)
		(mid 331.521054 -240.187711)
		(end 331.238098 -240.111534)
		(width 0.0889)
		(layer "In13.Cu")
		(net "M_B_CPU0_SA_DQ<26>")
	)
	(arc
		(start 328.984102 -240.111534)
		(mid 328.701146 -240.187711)
		(end 328.41819 -240.111534)
		(width 0.0889)
		(layer "In13.Cu")
		(net "M_B_CPU0_SA_DQ<26>")
	)
	(segment
		(start 337.158076 -240.700052)
		(end 336.691224 -240.434114)
		(width 0.10668)
		(layer "F.Cu")
		(net "M_B_CPU0_SA_DQ<25>")
	)
	(segment
		(start 327.118218 -240.765076)
		(end 327.10374 -240.756694)
		(width 0.0889)
		(layer "In13.Cu")
		(net "M_B_CPU0_SA_DQ<25>")
	)
	(segment
		(start 333.6925 -240.76152)
		(end 333.684118 -240.756694)
		(width 0.0889)
		(layer "In13.Cu")
		(net "M_B_CPU0_SA_DQ<25>")
	)
	(segment
		(start 303.278286 -227.510086)
		(end 303.133506 -227.654866)
		(width 0.14478)
		(layer "In13.Cu")
		(net "M_B_CPU0_SA_DQ<25>")
	)
	(segment
		(start 324.278498 -239.450372)
		(end 324.15607 -239.327944)
		(width 0.0889)
		(layer "In13.Cu")
		(net "M_B_CPU0_SA_DQ<25>")
	)
	(segment
		(start 302.582326 -227.654866)
		(end 302.437546 -227.510086)
		(width 0.14478)
		(layer "In13.Cu")
		(net "M_B_CPU0_SA_DQ<25>")
	)
	(segment
		(start 336.691224 -240.434114)
		(end 336.845148 -240.699544)
		(width 0.0889)
		(layer "In13.Cu")
		(net "M_B_CPU0_SA_DQ<25>")
	)
	(segment
		(start 324.964298 -239.450372)
		(end 324.278498 -239.450372)
		(width 0.0889)
		(layer "In13.Cu")
		(net "M_B_CPU0_SA_DQ<25>")
	)
	(segment
		(start 325.429118 -239.915192)
		(end 324.964298 -239.450372)
		(width 0.0889)
		(layer "In13.Cu")
		(net "M_B_CPU0_SA_DQ<25>")
	)
	(segment
		(start 302.727106 -227.907088)
		(end 302.582326 -227.762308)
		(width 0.14478)
		(layer "In13.Cu")
		(net "M_B_CPU0_SA_DQ<25>")
	)
	(segment
		(start 332.752446 -240.76152)
		(end 332.744064 -240.756694)
		(width 0.0889)
		(layer "In13.Cu")
		(net "M_B_CPU0_SA_DQ<25>")
	)
	(segment
		(start 301.93361 -227.419154)
		(end 301.728886 -227.419154)
		(width 0.14478)
		(layer "In13.Cu")
		(net "M_B_CPU0_SA_DQ<25>")
	)
	(segment
		(start 301.338996 -227.029264)
		(end 301.338996 -226.82454)
		(width 0.14478)
		(layer "In13.Cu")
		(net "M_B_CPU0_SA_DQ<25>")
	)
	(segment
		(start 336.845148 -240.699544)
		(end 336.822796 -240.782856)
		(width 0.0889)
		(layer "In13.Cu")
		(net "M_B_CPU0_SA_DQ<25>")
	)
	(segment
		(start 314.751974 -235.065062)
		(end 314.751974 -233.816398)
		(width 0.14478)
		(layer "In13.Cu")
		(net "M_B_CPU0_SA_DQ<25>")
	)
	(segment
		(start 324.15607 -239.327944)
		(end 323.859398 -239.327944)
		(width 0.0889)
		(layer "In13.Cu")
		(net "M_B_CPU0_SA_DQ<25>")
	)
	(segment
		(start 303.684686 -227.654866)
		(end 303.539906 -227.510086)
		(width 0.14478)
		(layer "In13.Cu")
		(net "M_B_CPU0_SA_DQ<25>")
	)
	(segment
		(start 319.014856 -239.327944)
		(end 314.751974 -235.065062)
		(width 0.14478)
		(layer "In13.Cu")
		(net "M_B_CPU0_SA_DQ<25>")
	)
	(segment
		(start 301.126906 -227.446078)
		(end 301.126906 -227.241354)
		(width 0.14478)
		(layer "In13.Cu")
		(net "M_B_CPU0_SA_DQ<25>")
	)
	(segment
		(start 328.992484 -240.76152)
		(end 328.984102 -240.756694)
		(width 0.0889)
		(layer "In13.Cu")
		(net "M_B_CPU0_SA_DQ<25>")
	)
	(segment
		(start 302.988726 -227.907088)
		(end 302.727106 -227.907088)
		(width 0.14478)
		(layer "In13.Cu")
		(net "M_B_CPU0_SA_DQ<25>")
	)
	(segment
		(start 299.82414 -226.948746)
		(end 299.82414 -227.085144)
		(width 0.14478)
		(layer "In13.Cu")
		(net "M_B_CPU0_SA_DQ<25>")
	)
	(segment
		(start 325.429118 -240.392458)
		(end 325.429118 -239.915192)
		(width 0.0889)
		(layer "In13.Cu")
		(net "M_B_CPU0_SA_DQ<25>")
	)
	(segment
		(start 304.235866 -227.654866)
		(end 304.235866 -227.762308)
		(width 0.14478)
		(layer "In13.Cu")
		(net "M_B_CPU0_SA_DQ<25>")
	)
	(segment
		(start 335.938114 -240.756694)
		(end 335.929732 -240.76152)
		(width 0.0889)
		(layer "In13.Cu")
		(net "M_B_CPU0_SA_DQ<25>")
	)
	(segment
		(start 300.112684 -226.660202)
		(end 299.82414 -226.948746)
		(width 0.14478)
		(layer "In13.Cu")
		(net "M_B_CPU0_SA_DQ<25>")
	)
	(segment
		(start 305.338226 -227.762308)
		(end 305.193446 -227.907088)
		(width 0.14478)
		(layer "In13.Cu")
		(net "M_B_CPU0_SA_DQ<25>")
	)
	(segment
		(start 301.338996 -226.82454)
		(end 301.174658 -226.660202)
		(width 0.14478)
		(layer "In13.Cu")
		(net "M_B_CPU0_SA_DQ<25>")
	)
	(segment
		(start 304.091086 -227.907088)
		(end 303.829466 -227.907088)
		(width 0.14478)
		(layer "In13.Cu")
		(net "M_B_CPU0_SA_DQ<25>")
	)
	(segment
		(start 327.10374 -240.756694)
		(end 327.093326 -240.750598)
		(width 0.0889)
		(layer "In13.Cu")
		(net "M_B_CPU0_SA_DQ<25>")
	)
	(segment
		(start 304.931826 -227.907088)
		(end 304.787046 -227.762308)
		(width 0.14478)
		(layer "In13.Cu")
		(net "M_B_CPU0_SA_DQ<25>")
	)
	(segment
		(start 303.539906 -227.510086)
		(end 303.278286 -227.510086)
		(width 0.14478)
		(layer "In13.Cu")
		(net "M_B_CPU0_SA_DQ<25>")
	)
	(segment
		(start 303.829466 -227.907088)
		(end 303.684686 -227.762308)
		(width 0.14478)
		(layer "In13.Cu")
		(net "M_B_CPU0_SA_DQ<25>")
	)
	(segment
		(start 301.728886 -227.419154)
		(end 301.516796 -227.631244)
		(width 0.14478)
		(layer "In13.Cu")
		(net "M_B_CPU0_SA_DQ<25>")
	)
	(segment
		(start 304.787046 -227.654866)
		(end 304.642266 -227.510086)
		(width 0.14478)
		(layer "In13.Cu")
		(net "M_B_CPU0_SA_DQ<25>")
	)
	(segment
		(start 303.133506 -227.654866)
		(end 303.133506 -227.762308)
		(width 0.14478)
		(layer "In13.Cu")
		(net "M_B_CPU0_SA_DQ<25>")
	)
	(segment
		(start 301.312072 -227.631244)
		(end 301.126906 -227.446078)
		(width 0.14478)
		(layer "In13.Cu")
		(net "M_B_CPU0_SA_DQ<25>")
	)
	(segment
		(start 307.249068 -227.510086)
		(end 305.483006 -227.510086)
		(width 0.14478)
		(layer "In13.Cu")
		(net "M_B_CPU0_SA_DQ<25>")
	)
	(segment
		(start 304.642266 -227.510086)
		(end 304.380646 -227.510086)
		(width 0.14478)
		(layer "In13.Cu")
		(net "M_B_CPU0_SA_DQ<25>")
	)
	(segment
		(start 325.8439 -240.80724)
		(end 325.429118 -240.392458)
		(width 0.0889)
		(layer "In13.Cu")
		(net "M_B_CPU0_SA_DQ<25>")
	)
	(segment
		(start 301.174658 -226.660202)
		(end 300.112684 -226.660202)
		(width 0.14478)
		(layer "In13.Cu")
		(net "M_B_CPU0_SA_DQ<25>")
	)
	(segment
		(start 314.751974 -233.816398)
		(end 309.29199 -228.356414)
		(width 0.14478)
		(layer "In13.Cu")
		(net "M_B_CPU0_SA_DQ<25>")
	)
	(segment
		(start 323.859398 -239.327944)
		(end 319.014856 -239.327944)
		(width 0.14478)
		(layer "In13.Cu")
		(net "M_B_CPU0_SA_DQ<25>")
	)
	(segment
		(start 332.178152 -240.756694)
		(end 332.16977 -240.76152)
		(width 0.0889)
		(layer "In13.Cu")
		(net "M_B_CPU0_SA_DQ<25>")
	)
	(segment
		(start 305.483006 -227.510086)
		(end 305.338226 -227.654866)
		(width 0.14478)
		(layer "In13.Cu")
		(net "M_B_CPU0_SA_DQ<25>")
	)
	(segment
		(start 331.238098 -240.756694)
		(end 331.229716 -240.76152)
		(width 0.0889)
		(layer "In13.Cu")
		(net "M_B_CPU0_SA_DQ<25>")
	)
	(segment
		(start 302.582326 -227.762308)
		(end 302.582326 -227.654866)
		(width 0.14478)
		(layer "In13.Cu")
		(net "M_B_CPU0_SA_DQ<25>")
	)
	(segment
		(start 304.787046 -227.762308)
		(end 304.787046 -227.654866)
		(width 0.14478)
		(layer "In13.Cu")
		(net "M_B_CPU0_SA_DQ<25>")
	)
	(segment
		(start 326.351138 -240.80724)
		(end 325.8439 -240.80724)
		(width 0.0889)
		(layer "In13.Cu")
		(net "M_B_CPU0_SA_DQ<25>")
	)
	(segment
		(start 303.684686 -227.762308)
		(end 303.684686 -227.654866)
		(width 0.14478)
		(layer "In13.Cu")
		(net "M_B_CPU0_SA_DQ<25>")
	)
	(segment
		(start 302.024542 -227.510086)
		(end 301.93361 -227.419154)
		(width 0.14478)
		(layer "In13.Cu")
		(net "M_B_CPU0_SA_DQ<25>")
	)
	(segment
		(start 301.516796 -227.631244)
		(end 301.312072 -227.631244)
		(width 0.14478)
		(layer "In13.Cu")
		(net "M_B_CPU0_SA_DQ<25>")
	)
	(segment
		(start 304.380646 -227.510086)
		(end 304.235866 -227.654866)
		(width 0.14478)
		(layer "In13.Cu")
		(net "M_B_CPU0_SA_DQ<25>")
	)
	(segment
		(start 303.133506 -227.762308)
		(end 302.988726 -227.907088)
		(width 0.14478)
		(layer "In13.Cu")
		(net "M_B_CPU0_SA_DQ<25>")
	)
	(segment
		(start 328.044048 -240.756694)
		(end 328.033634 -240.750598)
		(width 0.0889)
		(layer "In13.Cu")
		(net "M_B_CPU0_SA_DQ<25>")
	)
	(segment
		(start 305.193446 -227.907088)
		(end 304.931826 -227.907088)
		(width 0.14478)
		(layer "In13.Cu")
		(net "M_B_CPU0_SA_DQ<25>")
	)
	(segment
		(start 304.235866 -227.762308)
		(end 304.091086 -227.907088)
		(width 0.14478)
		(layer "In13.Cu")
		(net "M_B_CPU0_SA_DQ<25>")
	)
	(segment
		(start 305.338226 -227.654866)
		(end 305.338226 -227.762308)
		(width 0.14478)
		(layer "In13.Cu")
		(net "M_B_CPU0_SA_DQ<25>")
	)
	(segment
		(start 309.29199 -228.356414)
		(end 307.249068 -227.510086)
		(width 0.14478)
		(layer "In13.Cu")
		(net "M_B_CPU0_SA_DQ<25>")
	)
	(segment
		(start 328.41819 -240.756694)
		(end 328.409808 -240.76152)
		(width 0.0889)
		(layer "In13.Cu")
		(net "M_B_CPU0_SA_DQ<25>")
	)
	(segment
		(start 302.437546 -227.510086)
		(end 302.024542 -227.510086)
		(width 0.14478)
		(layer "In13.Cu")
		(net "M_B_CPU0_SA_DQ<25>")
	)
	(segment
		(start 301.126906 -227.241354)
		(end 301.338996 -227.029264)
		(width 0.14478)
		(layer "In13.Cu")
		(net "M_B_CPU0_SA_DQ<25>")
	)
	(arc
		(start 334.99806 -240.756694)
		(mid 334.811116 -240.806949)
		(end 334.624172 -240.756694)
		(width 0.0889)
		(layer "In13.Cu")
		(net "M_B_CPU0_SA_DQ<25>")
	)
	(arc
		(start 330.863956 -240.756694)
		(mid 330.581 -240.680517)
		(end 330.298044 -240.756694)
		(width 0.0889)
		(layer "In13.Cu")
		(net "M_B_CPU0_SA_DQ<25>")
	)
	(arc
		(start 328.984102 -240.756694)
		(mid 328.701146 -240.680517)
		(end 328.41819 -240.756694)
		(width 0.0889)
		(layer "In13.Cu")
		(net "M_B_CPU0_SA_DQ<25>")
	)
	(arc
		(start 334.624172 -240.756694)
		(mid 334.341216 -240.680517)
		(end 334.05826 -240.756694)
		(width 0.0889)
		(layer "In13.Cu")
		(net "M_B_CPU0_SA_DQ<25>")
	)
	(arc
		(start 335.929732 -240.76152)
		(mid 335.746224 -240.807014)
		(end 335.563972 -240.756694)
		(width 0.0889)
		(layer "In13.Cu")
		(net "M_B_CPU0_SA_DQ<25>")
	)
	(arc
		(start 336.822796 -240.782856)
		(mid 336.660464 -240.805674)
		(end 336.504026 -240.756694)
		(width 0.0889)
		(layer "In13.Cu")
		(net "M_B_CPU0_SA_DQ<25>")
	)
	(arc
		(start 327.093326 -240.750598)
		(mid 326.814894 -240.6805)
		(end 326.538082 -240.756694)
		(width 0.0889)
		(layer "In13.Cu")
		(net "M_B_CPU0_SA_DQ<25>")
	)
	(arc
		(start 333.118206 -240.756694)
		(mid 332.935955 -240.807044)
		(end 332.752446 -240.76152)
		(width 0.0889)
		(layer "In13.Cu")
		(net "M_B_CPU0_SA_DQ<25>")
	)
	(arc
		(start 328.033634 -240.750598)
		(mid 327.754948 -240.680378)
		(end 327.477882 -240.756694)
		(width 0.0889)
		(layer "In13.Cu")
		(net "M_B_CPU0_SA_DQ<25>")
	)
	(arc
		(start 336.504026 -240.756694)
		(mid 336.22107 -240.680517)
		(end 335.938114 -240.756694)
		(width 0.0889)
		(layer "In13.Cu")
		(net "M_B_CPU0_SA_DQ<25>")
	)
	(arc
		(start 332.16977 -240.76152)
		(mid 331.986262 -240.807014)
		(end 331.80401 -240.756694)
		(width 0.0889)
		(layer "In13.Cu")
		(net "M_B_CPU0_SA_DQ<25>")
	)
	(arc
		(start 328.409808 -240.76152)
		(mid 328.2263 -240.807014)
		(end 328.044048 -240.756694)
		(width 0.0889)
		(layer "In13.Cu")
		(net "M_B_CPU0_SA_DQ<25>")
	)
	(arc
		(start 334.05826 -240.756694)
		(mid 333.876009 -240.807044)
		(end 333.6925 -240.76152)
		(width 0.0889)
		(layer "In13.Cu")
		(net "M_B_CPU0_SA_DQ<25>")
	)
	(arc
		(start 327.477882 -240.756694)
		(mid 327.299127 -240.807103)
		(end 327.118218 -240.765076)
		(width 0.0889)
		(layer "In13.Cu")
		(net "M_B_CPU0_SA_DQ<25>")
	)
	(arc
		(start 333.684118 -240.756694)
		(mid 333.401162 -240.680517)
		(end 333.118206 -240.756694)
		(width 0.0889)
		(layer "In13.Cu")
		(net "M_B_CPU0_SA_DQ<25>")
	)
	(arc
		(start 332.744064 -240.756694)
		(mid 332.461108 -240.680517)
		(end 332.178152 -240.756694)
		(width 0.0889)
		(layer "In13.Cu")
		(net "M_B_CPU0_SA_DQ<25>")
	)
	(arc
		(start 329.358244 -240.756694)
		(mid 329.175993 -240.807044)
		(end 328.992484 -240.76152)
		(width 0.0889)
		(layer "In13.Cu")
		(net "M_B_CPU0_SA_DQ<25>")
	)
	(arc
		(start 326.538082 -240.756694)
		(mid 326.447949 -240.794314)
		(end 326.351138 -240.80724)
		(width 0.0889)
		(layer "In13.Cu")
		(net "M_B_CPU0_SA_DQ<25>")
	)
	(arc
		(start 329.924156 -240.756694)
		(mid 329.6412 -240.680517)
		(end 329.358244 -240.756694)
		(width 0.0889)
		(layer "In13.Cu")
		(net "M_B_CPU0_SA_DQ<25>")
	)
	(arc
		(start 331.229716 -240.76152)
		(mid 331.046208 -240.807014)
		(end 330.863956 -240.756694)
		(width 0.0889)
		(layer "In13.Cu")
		(net "M_B_CPU0_SA_DQ<25>")
	)
	(arc
		(start 335.563972 -240.756694)
		(mid 335.281016 -240.680517)
		(end 334.99806 -240.756694)
		(width 0.0889)
		(layer "In13.Cu")
		(net "M_B_CPU0_SA_DQ<25>")
	)
	(arc
		(start 331.80401 -240.756694)
		(mid 331.521054 -240.680517)
		(end 331.238098 -240.756694)
		(width 0.0889)
		(layer "In13.Cu")
		(net "M_B_CPU0_SA_DQ<25>")
	)
	(arc
		(start 330.298044 -240.756694)
		(mid 330.1111 -240.806949)
		(end 329.924156 -240.756694)
		(width 0.0889)
		(layer "In13.Cu")
		(net "M_B_CPU0_SA_DQ<25>")
	)
	(segment
		(start 335.747868 -239.890046)
		(end 335.281016 -239.624108)
		(width 0.10668)
		(layer "F.Cu")
		(net "M_B_CPU0_SA_DQ<24>")
	)
	(segment
		(start 319.377568 -238.418624)
		(end 315.666374 -234.70743)
		(width 0.14478)
		(layer "In13.Cu")
		(net "M_B_CPU0_SA_DQ<24>")
	)
	(segment
		(start 306.377848 -226.432618)
		(end 306.233068 -226.287838)
		(width 0.14478)
		(layer "In13.Cu")
		(net "M_B_CPU0_SA_DQ<24>")
	)
	(segment
		(start 302.61052 -225.973132)
		(end 302.447452 -225.810064)
		(width 0.14478)
		(layer "In13.Cu")
		(net "M_B_CPU0_SA_DQ<24>")
	)
	(segment
		(start 308.510178 -226.956874)
		(end 308.305454 -226.95662)
		(width 0.14478)
		(layer "In13.Cu")
		(net "M_B_CPU0_SA_DQ<24>")
	)
	(segment
		(start 326.141588 -239.870488)
		(end 325.012812 -238.741712)
		(width 0.0889)
		(layer "In13.Cu")
		(net "M_B_CPU0_SA_DQ<24>")
	)
	(segment
		(start 303.886616 -226.19843)
		(end 303.723548 -226.035362)
		(width 0.14478)
		(layer "In13.Cu")
		(net "M_B_CPU0_SA_DQ<24>")
	)
	(segment
		(start 308.345078 -226.34194)
		(end 308.345332 -226.137724)
		(width 0.14478)
		(layer "In13.Cu")
		(net "M_B_CPU0_SA_DQ<24>")
	)
	(segment
		(start 305.681888 -225.954844)
		(end 305.681888 -226.287838)
		(width 0.14478)
		(layer "In13.Cu")
		(net "M_B_CPU0_SA_DQ<24>")
	)
	(segment
		(start 308.345332 -226.137724)
		(end 308.017672 -225.810064)
		(width 0.14478)
		(layer "In13.Cu")
		(net "M_B_CPU0_SA_DQ<24>")
	)
	(segment
		(start 308.939692 -226.732084)
		(end 308.734968 -226.732084)
		(width 0.14478)
		(layer "In13.Cu")
		(net "M_B_CPU0_SA_DQ<24>")
	)
	(segment
		(start 323.889878 -238.418624)
		(end 319.377568 -238.418624)
		(width 0.14478)
		(layer "In13.Cu")
		(net "M_B_CPU0_SA_DQ<24>")
	)
	(segment
		(start 301.174658 -224.96018)
		(end 300.061884 -224.96018)
		(width 0.14478)
		(layer "In13.Cu")
		(net "M_B_CPU0_SA_DQ<24>")
	)
	(segment
		(start 305.275488 -226.432618)
		(end 305.130708 -226.287838)
		(width 0.14478)
		(layer "In13.Cu")
		(net "M_B_CPU0_SA_DQ<24>")
	)
	(segment
		(start 325.012812 -238.741712)
		(end 324.598538 -238.741712)
		(width 0.0889)
		(layer "In13.Cu")
		(net "M_B_CPU0_SA_DQ<24>")
	)
	(segment
		(start 324.598538 -238.741712)
		(end 324.27545 -238.418624)
		(width 0.0889)
		(layer "In13.Cu")
		(net "M_B_CPU0_SA_DQ<24>")
	)
	(segment
		(start 308.734968 -226.732084)
		(end 308.510178 -226.956874)
		(width 0.14478)
		(layer "In13.Cu")
		(net "M_B_CPU0_SA_DQ<24>")
	)
	(segment
		(start 306.639468 -226.432618)
		(end 306.377848 -226.432618)
		(width 0.14478)
		(layer "In13.Cu")
		(net "M_B_CPU0_SA_DQ<24>")
	)
	(segment
		(start 304.280062 -226.035362)
		(end 304.116994 -226.19843)
		(width 0.14478)
		(layer "In13.Cu")
		(net "M_B_CPU0_SA_DQ<24>")
	)
	(segment
		(start 304.280062 -225.973132)
		(end 304.280062 -226.035362)
		(width 0.14478)
		(layer "In13.Cu")
		(net "M_B_CPU0_SA_DQ<24>")
	)
	(segment
		(start 305.826668 -225.810064)
		(end 305.681888 -225.954844)
		(width 0.14478)
		(layer "In13.Cu")
		(net "M_B_CPU0_SA_DQ<24>")
	)
	(segment
		(start 303.56048 -225.810064)
		(end 303.330102 -225.810064)
		(width 0.14478)
		(layer "In13.Cu")
		(net "M_B_CPU0_SA_DQ<24>")
	)
	(segment
		(start 302.024542 -225.810064)
		(end 301.174658 -224.96018)
		(width 0.14478)
		(layer "In13.Cu")
		(net "M_B_CPU0_SA_DQ<24>")
	)
	(segment
		(start 306.088288 -225.810064)
		(end 305.826668 -225.810064)
		(width 0.14478)
		(layer "In13.Cu")
		(net "M_B_CPU0_SA_DQ<24>")
	)
	(segment
		(start 326.351138 -239.870488)
		(end 326.141588 -239.870488)
		(width 0.0889)
		(layer "In13.Cu")
		(net "M_B_CPU0_SA_DQ<24>")
	)
	(segment
		(start 305.681888 -226.287838)
		(end 305.537108 -226.432618)
		(width 0.14478)
		(layer "In13.Cu")
		(net "M_B_CPU0_SA_DQ<24>")
	)
	(segment
		(start 330.402438 -239.951514)
		(end 330.394056 -239.946688)
		(width 0.0889)
		(layer "In13.Cu")
		(net "M_B_CPU0_SA_DQ<24>")
	)
	(segment
		(start 305.130708 -226.287838)
		(end 305.130708 -225.954844)
		(width 0.14478)
		(layer "In13.Cu")
		(net "M_B_CPU0_SA_DQ<24>")
	)
	(segment
		(start 306.233068 -225.954844)
		(end 306.088288 -225.810064)
		(width 0.14478)
		(layer "In13.Cu")
		(net "M_B_CPU0_SA_DQ<24>")
	)
	(segment
		(start 305.537108 -226.432618)
		(end 305.275488 -226.432618)
		(width 0.14478)
		(layer "In13.Cu")
		(net "M_B_CPU0_SA_DQ<24>")
	)
	(segment
		(start 304.116994 -226.19843)
		(end 303.886616 -226.19843)
		(width 0.14478)
		(layer "In13.Cu")
		(net "M_B_CPU0_SA_DQ<24>")
	)
	(segment
		(start 303.723548 -226.035362)
		(end 303.723548 -225.973132)
		(width 0.14478)
		(layer "In13.Cu")
		(net "M_B_CPU0_SA_DQ<24>")
	)
	(segment
		(start 304.985928 -225.810064)
		(end 304.44313 -225.810064)
		(width 0.14478)
		(layer "In13.Cu")
		(net "M_B_CPU0_SA_DQ<24>")
	)
	(segment
		(start 334.52816 -239.946688)
		(end 334.519778 -239.951514)
		(width 0.0889)
		(layer "In13.Cu")
		(net "M_B_CPU0_SA_DQ<24>")
	)
	(segment
		(start 302.447452 -225.810064)
		(end 302.024542 -225.810064)
		(width 0.14478)
		(layer "In13.Cu")
		(net "M_B_CPU0_SA_DQ<24>")
	)
	(segment
		(start 303.723548 -225.973132)
		(end 303.56048 -225.810064)
		(width 0.14478)
		(layer "In13.Cu")
		(net "M_B_CPU0_SA_DQ<24>")
	)
	(segment
		(start 308.305454 -226.95662)
		(end 308.120288 -226.771454)
		(width 0.14478)
		(layer "In13.Cu")
		(net "M_B_CPU0_SA_DQ<24>")
	)
	(segment
		(start 308.017672 -225.810064)
		(end 306.929028 -225.810064)
		(width 0.14478)
		(layer "In13.Cu")
		(net "M_B_CPU0_SA_DQ<24>")
	)
	(segment
		(start 308.120288 -226.56673)
		(end 308.345078 -226.34194)
		(width 0.14478)
		(layer "In13.Cu")
		(net "M_B_CPU0_SA_DQ<24>")
	)
	(segment
		(start 305.130708 -225.954844)
		(end 304.985928 -225.810064)
		(width 0.14478)
		(layer "In13.Cu")
		(net "M_B_CPU0_SA_DQ<24>")
	)
	(segment
		(start 335.281016 -239.624108)
		(end 335.435194 -239.889538)
		(width 0.0889)
		(layer "In13.Cu")
		(net "M_B_CPU0_SA_DQ<24>")
	)
	(segment
		(start 303.330102 -225.810064)
		(end 303.167034 -225.973132)
		(width 0.14478)
		(layer "In13.Cu")
		(net "M_B_CPU0_SA_DQ<24>")
	)
	(segment
		(start 331.342492 -239.951514)
		(end 331.33411 -239.946688)
		(width 0.0889)
		(layer "In13.Cu")
		(net "M_B_CPU0_SA_DQ<24>")
	)
	(segment
		(start 299.82414 -225.197924)
		(end 299.82414 -225.385122)
		(width 0.14478)
		(layer "In13.Cu")
		(net "M_B_CPU0_SA_DQ<24>")
	)
	(segment
		(start 303.167034 -225.973132)
		(end 303.167034 -226.035362)
		(width 0.14478)
		(layer "In13.Cu")
		(net "M_B_CPU0_SA_DQ<24>")
	)
	(segment
		(start 329.828144 -239.946688)
		(end 329.819762 -239.951514)
		(width 0.0889)
		(layer "In13.Cu")
		(net "M_B_CPU0_SA_DQ<24>")
	)
	(segment
		(start 303.167034 -226.035362)
		(end 303.003966 -226.19843)
		(width 0.14478)
		(layer "In13.Cu")
		(net "M_B_CPU0_SA_DQ<24>")
	)
	(segment
		(start 306.784248 -226.287838)
		(end 306.639468 -226.432618)
		(width 0.14478)
		(layer "In13.Cu")
		(net "M_B_CPU0_SA_DQ<24>")
	)
	(segment
		(start 306.929028 -225.810064)
		(end 306.784248 -225.954844)
		(width 0.14478)
		(layer "In13.Cu")
		(net "M_B_CPU0_SA_DQ<24>")
	)
	(segment
		(start 333.588106 -239.946688)
		(end 333.579724 -239.951514)
		(width 0.0889)
		(layer "In13.Cu")
		(net "M_B_CPU0_SA_DQ<24>")
	)
	(segment
		(start 335.102454 -239.951514)
		(end 335.094072 -239.946688)
		(width 0.0889)
		(layer "In13.Cu")
		(net "M_B_CPU0_SA_DQ<24>")
	)
	(segment
		(start 304.44313 -225.810064)
		(end 304.280062 -225.973132)
		(width 0.14478)
		(layer "In13.Cu")
		(net "M_B_CPU0_SA_DQ<24>")
	)
	(segment
		(start 324.27545 -238.418624)
		(end 323.889878 -238.418624)
		(width 0.0889)
		(layer "In13.Cu")
		(net "M_B_CPU0_SA_DQ<24>")
	)
	(segment
		(start 306.233068 -226.287838)
		(end 306.233068 -225.954844)
		(width 0.14478)
		(layer "In13.Cu")
		(net "M_B_CPU0_SA_DQ<24>")
	)
	(segment
		(start 315.666374 -233.458766)
		(end 308.939692 -226.732084)
		(width 0.14478)
		(layer "In13.Cu")
		(net "M_B_CPU0_SA_DQ<24>")
	)
	(segment
		(start 302.61052 -226.035362)
		(end 302.61052 -225.973132)
		(width 0.14478)
		(layer "In13.Cu")
		(net "M_B_CPU0_SA_DQ<24>")
	)
	(segment
		(start 306.784248 -225.954844)
		(end 306.784248 -226.287838)
		(width 0.14478)
		(layer "In13.Cu")
		(net "M_B_CPU0_SA_DQ<24>")
	)
	(segment
		(start 300.061884 -224.96018)
		(end 299.82414 -225.197924)
		(width 0.14478)
		(layer "In13.Cu")
		(net "M_B_CPU0_SA_DQ<24>")
	)
	(segment
		(start 302.773588 -226.19843)
		(end 302.61052 -226.035362)
		(width 0.14478)
		(layer "In13.Cu")
		(net "M_B_CPU0_SA_DQ<24>")
	)
	(segment
		(start 315.666374 -234.70743)
		(end 315.666374 -233.458766)
		(width 0.14478)
		(layer "In13.Cu")
		(net "M_B_CPU0_SA_DQ<24>")
	)
	(segment
		(start 303.003966 -226.19843)
		(end 302.773588 -226.19843)
		(width 0.14478)
		(layer "In13.Cu")
		(net "M_B_CPU0_SA_DQ<24>")
	)
	(segment
		(start 308.120288 -226.771454)
		(end 308.120288 -226.56673)
		(width 0.14478)
		(layer "In13.Cu")
		(net "M_B_CPU0_SA_DQ<24>")
	)
	(segment
		(start 335.435194 -239.889538)
		(end 335.412842 -239.97285)
		(width 0.0889)
		(layer "In13.Cu")
		(net "M_B_CPU0_SA_DQ<24>")
	)
	(arc
		(start 332.648052 -239.946688)
		(mid 332.461108 -239.996943)
		(end 332.274164 -239.946688)
		(width 0.0889)
		(layer "In13.Cu")
		(net "M_B_CPU0_SA_DQ<24>")
	)
	(arc
		(start 331.33411 -239.946688)
		(mid 331.051154 -239.870511)
		(end 330.768198 -239.946688)
		(width 0.0889)
		(layer "In13.Cu")
		(net "M_B_CPU0_SA_DQ<24>")
	)
	(arc
		(start 335.094072 -239.946688)
		(mid 334.811116 -239.870511)
		(end 334.52816 -239.946688)
		(width 0.0889)
		(layer "In13.Cu")
		(net "M_B_CPU0_SA_DQ<24>")
	)
	(arc
		(start 326.634094 -239.946688)
		(mid 326.497658 -239.889863)
		(end 326.351138 -239.870488)
		(width 0.0889)
		(layer "In13.Cu")
		(net "M_B_CPU0_SA_DQ<24>")
	)
	(arc
		(start 327.94829 -239.946688)
		(mid 327.761092 -239.99707)
		(end 327.573894 -239.946688)
		(width 0.0889)
		(layer "In13.Cu")
		(net "M_B_CPU0_SA_DQ<24>")
	)
	(arc
		(start 333.579724 -239.951514)
		(mid 333.396216 -239.997008)
		(end 333.213964 -239.946688)
		(width 0.0889)
		(layer "In13.Cu")
		(net "M_B_CPU0_SA_DQ<24>")
	)
	(arc
		(start 335.412842 -239.97285)
		(mid 335.255332 -239.996048)
		(end 335.102454 -239.951514)
		(width 0.0889)
		(layer "In13.Cu")
		(net "M_B_CPU0_SA_DQ<24>")
	)
	(arc
		(start 334.154018 -239.946688)
		(mid 333.871062 -239.870511)
		(end 333.588106 -239.946688)
		(width 0.0889)
		(layer "In13.Cu")
		(net "M_B_CPU0_SA_DQ<24>")
	)
	(arc
		(start 330.768198 -239.946688)
		(mid 330.585947 -239.997038)
		(end 330.402438 -239.951514)
		(width 0.0889)
		(layer "In13.Cu")
		(net "M_B_CPU0_SA_DQ<24>")
	)
	(arc
		(start 334.519778 -239.951514)
		(mid 334.33627 -239.997008)
		(end 334.154018 -239.946688)
		(width 0.0889)
		(layer "In13.Cu")
		(net "M_B_CPU0_SA_DQ<24>")
	)
	(arc
		(start 328.88809 -239.946688)
		(mid 328.701146 -239.996943)
		(end 328.514202 -239.946688)
		(width 0.0889)
		(layer "In13.Cu")
		(net "M_B_CPU0_SA_DQ<24>")
	)
	(arc
		(start 329.454002 -239.946688)
		(mid 329.171046 -239.870511)
		(end 328.88809 -239.946688)
		(width 0.0889)
		(layer "In13.Cu")
		(net "M_B_CPU0_SA_DQ<24>")
	)
	(arc
		(start 327.007982 -239.946688)
		(mid 326.821038 -239.996943)
		(end 326.634094 -239.946688)
		(width 0.0889)
		(layer "In13.Cu")
		(net "M_B_CPU0_SA_DQ<24>")
	)
	(arc
		(start 332.274164 -239.946688)
		(mid 331.991208 -239.870511)
		(end 331.708252 -239.946688)
		(width 0.0889)
		(layer "In13.Cu")
		(net "M_B_CPU0_SA_DQ<24>")
	)
	(arc
		(start 330.394056 -239.946688)
		(mid 330.1111 -239.870511)
		(end 329.828144 -239.946688)
		(width 0.0889)
		(layer "In13.Cu")
		(net "M_B_CPU0_SA_DQ<24>")
	)
	(arc
		(start 328.514202 -239.946688)
		(mid 328.231246 -239.870511)
		(end 327.94829 -239.946688)
		(width 0.0889)
		(layer "In13.Cu")
		(net "M_B_CPU0_SA_DQ<24>")
	)
	(arc
		(start 329.819762 -239.951514)
		(mid 329.636254 -239.997008)
		(end 329.454002 -239.946688)
		(width 0.0889)
		(layer "In13.Cu")
		(net "M_B_CPU0_SA_DQ<24>")
	)
	(arc
		(start 331.708252 -239.946688)
		(mid 331.526001 -239.997038)
		(end 331.342492 -239.951514)
		(width 0.0889)
		(layer "In13.Cu")
		(net "M_B_CPU0_SA_DQ<24>")
	)
	(arc
		(start 327.573894 -239.946688)
		(mid 327.290938 -239.870511)
		(end 327.007982 -239.946688)
		(width 0.0889)
		(layer "In13.Cu")
		(net "M_B_CPU0_SA_DQ<24>")
	)
	(arc
		(start 333.213964 -239.946688)
		(mid 332.931008 -239.870511)
		(end 332.648052 -239.946688)
		(width 0.0889)
		(layer "In13.Cu")
		(net "M_B_CPU0_SA_DQ<24>")
	)
	(segment
		(start 337.627976 -239.890046)
		(end 337.161124 -239.624108)
		(width 0.10668)
		(layer "F.Cu")
		(net "M_B_CPU0_SA_DQ<23>")
	)
	(segment
		(start 336.034126 -239.301528)
		(end 336.042508 -239.296702)
		(width 0.0889)
		(layer "In13.Cu")
		(net "M_B_CPU0_SA_DQ<23>")
	)
	(segment
		(start 326.594978 -239.352328)
		(end 326.63257 -239.314736)
		(width 0.0889)
		(layer "In13.Cu")
		(net "M_B_CPU0_SA_DQ<23>")
	)
	(segment
		(start 333.579724 -239.296702)
		(end 333.588106 -239.301528)
		(width 0.0889)
		(layer "In13.Cu")
		(net "M_B_CPU0_SA_DQ<23>")
	)
	(segment
		(start 331.33411 -239.301528)
		(end 331.342492 -239.296702)
		(width 0.0889)
		(layer "In13.Cu")
		(net "M_B_CPU0_SA_DQ<23>")
	)
	(segment
		(start 329.819762 -239.296702)
		(end 329.828144 -239.301528)
		(width 0.0889)
		(layer "In13.Cu")
		(net "M_B_CPU0_SA_DQ<23>")
	)
	(segment
		(start 335.094072 -239.301528)
		(end 335.102454 -239.296702)
		(width 0.0889)
		(layer "In13.Cu")
		(net "M_B_CPU0_SA_DQ<23>")
	)
	(segment
		(start 298.162472 -224.110042)
		(end 301.196502 -224.110042)
		(width 0.14478)
		(layer "In13.Cu")
		(net "M_B_CPU0_SA_DQ<23>")
	)
	(segment
		(start 319.62725 -237.862364)
		(end 323.886068 -237.862364)
		(width 0.14478)
		(layer "In13.Cu")
		(net "M_B_CPU0_SA_DQ<23>")
	)
	(segment
		(start 324.93077 -237.862364)
		(end 325.705978 -238.637572)
		(width 0.0889)
		(layer "In13.Cu")
		(net "M_B_CPU0_SA_DQ<23>")
	)
	(segment
		(start 326.337422 -239.37849)
		(end 326.531986 -239.37849)
		(width 0.0889)
		(layer "In13.Cu")
		(net "M_B_CPU0_SA_DQ<23>")
	)
	(segment
		(start 297.73753 -224.534984)
		(end 298.162472 -224.110042)
		(width 0.14478)
		(layer "In13.Cu")
		(net "M_B_CPU0_SA_DQ<23>")
	)
	(segment
		(start 316.222634 -234.457748)
		(end 319.62725 -237.862364)
		(width 0.14478)
		(layer "In13.Cu")
		(net "M_B_CPU0_SA_DQ<23>")
	)
	(segment
		(start 323.886068 -237.862364)
		(end 324.93077 -237.862364)
		(width 0.0889)
		(layer "In13.Cu")
		(net "M_B_CPU0_SA_DQ<23>")
	)
	(segment
		(start 302.04664 -224.96018)
		(end 307.947568 -224.96018)
		(width 0.14478)
		(layer "In13.Cu")
		(net "M_B_CPU0_SA_DQ<23>")
	)
	(segment
		(start 295.724072 -224.534984)
		(end 297.73753 -224.534984)
		(width 0.14478)
		(layer "In13.Cu")
		(net "M_B_CPU0_SA_DQ<23>")
	)
	(segment
		(start 337.0072 -239.358678)
		(end 337.161124 -239.624108)
		(width 0.0889)
		(layer "In13.Cu")
		(net "M_B_CPU0_SA_DQ<23>")
	)
	(segment
		(start 336.911188 -239.333278)
		(end 337.0072 -239.358678)
		(width 0.0889)
		(layer "In13.Cu")
		(net "M_B_CPU0_SA_DQ<23>")
	)
	(segment
		(start 330.394056 -239.301528)
		(end 330.402438 -239.296702)
		(width 0.0889)
		(layer "In13.Cu")
		(net "M_B_CPU0_SA_DQ<23>")
	)
	(segment
		(start 334.519778 -239.296702)
		(end 334.52816 -239.301528)
		(width 0.0889)
		(layer "In13.Cu")
		(net "M_B_CPU0_SA_DQ<23>")
	)
	(segment
		(start 325.705978 -238.637572)
		(end 325.705978 -238.747046)
		(width 0.0889)
		(layer "In13.Cu")
		(net "M_B_CPU0_SA_DQ<23>")
	)
	(segment
		(start 327.574148 -239.301528)
		(end 327.573894 -239.301528)
		(width 0.0889)
		(layer "In13.Cu")
		(net "M_B_CPU0_SA_DQ<23>")
	)
	(segment
		(start 301.196502 -224.110042)
		(end 302.04664 -224.96018)
		(width 0.14478)
		(layer "In13.Cu")
		(net "M_B_CPU0_SA_DQ<23>")
	)
	(segment
		(start 307.947568 -224.96018)
		(end 316.222634 -233.235246)
		(width 0.14478)
		(layer "In13.Cu")
		(net "M_B_CPU0_SA_DQ<23>")
	)
	(segment
		(start 316.222634 -233.235246)
		(end 316.222634 -234.457748)
		(width 0.14478)
		(layer "In13.Cu")
		(net "M_B_CPU0_SA_DQ<23>")
	)
	(arc
		(start 333.213964 -239.301528)
		(mid 333.396215 -239.251178)
		(end 333.579724 -239.296702)
		(width 0.0889)
		(layer "In13.Cu")
		(net "M_B_CPU0_SA_DQ<23>")
	)
	(arc
		(start 329.828144 -239.301528)
		(mid 330.1111 -239.377705)
		(end 330.394056 -239.301528)
		(width 0.0889)
		(layer "In13.Cu")
		(net "M_B_CPU0_SA_DQ<23>")
	)
	(arc
		(start 326.63257 -239.314736)
		(mid 326.667761 -239.287052)
		(end 326.708516 -239.268508)
		(width 0.0889)
		(layer "In13.Cu")
		(net "M_B_CPU0_SA_DQ<23>")
	)
	(arc
		(start 327.573894 -239.301528)
		(mid 327.761092 -239.251146)
		(end 327.94829 -239.301528)
		(width 0.0889)
		(layer "In13.Cu")
		(net "M_B_CPU0_SA_DQ<23>")
	)
	(arc
		(start 331.708252 -239.301528)
		(mid 331.991208 -239.377705)
		(end 332.274164 -239.301528)
		(width 0.0889)
		(layer "In13.Cu")
		(net "M_B_CPU0_SA_DQ<23>")
	)
	(arc
		(start 326.531986 -239.37849)
		(mid 326.56609 -239.371688)
		(end 326.594978 -239.352328)
		(width 0.0889)
		(layer "In13.Cu")
		(net "M_B_CPU0_SA_DQ<23>")
	)
	(arc
		(start 328.88809 -239.301528)
		(mid 329.171046 -239.377705)
		(end 329.454002 -239.301528)
		(width 0.0889)
		(layer "In13.Cu")
		(net "M_B_CPU0_SA_DQ<23>")
	)
	(arc
		(start 335.468214 -239.301528)
		(mid 335.75117 -239.377705)
		(end 336.034126 -239.301528)
		(width 0.0889)
		(layer "In13.Cu")
		(net "M_B_CPU0_SA_DQ<23>")
	)
	(arc
		(start 330.768198 -239.301528)
		(mid 331.051154 -239.377705)
		(end 331.33411 -239.301528)
		(width 0.0889)
		(layer "In13.Cu")
		(net "M_B_CPU0_SA_DQ<23>")
	)
	(arc
		(start 336.042508 -239.296702)
		(mid 336.226016 -239.251208)
		(end 336.408268 -239.301528)
		(width 0.0889)
		(layer "In13.Cu")
		(net "M_B_CPU0_SA_DQ<23>")
	)
	(arc
		(start 327.94829 -239.301528)
		(mid 328.231246 -239.377705)
		(end 328.514202 -239.301528)
		(width 0.0889)
		(layer "In13.Cu")
		(net "M_B_CPU0_SA_DQ<23>")
	)
	(arc
		(start 326.708516 -239.268508)
		(mid 326.861864 -239.253371)
		(end 327.008236 -239.301528)
		(width 0.0889)
		(layer "In13.Cu")
		(net "M_B_CPU0_SA_DQ<23>")
	)
	(arc
		(start 332.274164 -239.301528)
		(mid 332.461108 -239.251273)
		(end 332.648052 -239.301528)
		(width 0.0889)
		(layer "In13.Cu")
		(net "M_B_CPU0_SA_DQ<23>")
	)
	(arc
		(start 334.154018 -239.301528)
		(mid 334.336269 -239.251178)
		(end 334.519778 -239.296702)
		(width 0.0889)
		(layer "In13.Cu")
		(net "M_B_CPU0_SA_DQ<23>")
	)
	(arc
		(start 336.408268 -239.301528)
		(mid 336.655981 -239.376748)
		(end 336.911188 -239.333278)
		(width 0.0889)
		(layer "In13.Cu")
		(net "M_B_CPU0_SA_DQ<23>")
	)
	(arc
		(start 325.705978 -238.747046)
		(mid 325.890924 -239.193544)
		(end 326.337422 -239.37849)
		(width 0.0889)
		(layer "In13.Cu")
		(net "M_B_CPU0_SA_DQ<23>")
	)
	(arc
		(start 334.52816 -239.301528)
		(mid 334.811116 -239.377705)
		(end 335.094072 -239.301528)
		(width 0.0889)
		(layer "In13.Cu")
		(net "M_B_CPU0_SA_DQ<23>")
	)
	(arc
		(start 333.588106 -239.301528)
		(mid 333.871062 -239.377705)
		(end 334.154018 -239.301528)
		(width 0.0889)
		(layer "In13.Cu")
		(net "M_B_CPU0_SA_DQ<23>")
	)
	(arc
		(start 331.342492 -239.296702)
		(mid 331.526 -239.251208)
		(end 331.708252 -239.301528)
		(width 0.0889)
		(layer "In13.Cu")
		(net "M_B_CPU0_SA_DQ<23>")
	)
	(arc
		(start 328.514202 -239.301528)
		(mid 328.701146 -239.251273)
		(end 328.88809 -239.301528)
		(width 0.0889)
		(layer "In13.Cu")
		(net "M_B_CPU0_SA_DQ<23>")
	)
	(arc
		(start 332.648052 -239.301528)
		(mid 332.931008 -239.377705)
		(end 333.213964 -239.301528)
		(width 0.0889)
		(layer "In13.Cu")
		(net "M_B_CPU0_SA_DQ<23>")
	)
	(arc
		(start 335.102454 -239.296702)
		(mid 335.285962 -239.251208)
		(end 335.468214 -239.301528)
		(width 0.0889)
		(layer "In13.Cu")
		(net "M_B_CPU0_SA_DQ<23>")
	)
	(arc
		(start 330.402438 -239.296702)
		(mid 330.585946 -239.251208)
		(end 330.768198 -239.301528)
		(width 0.0889)
		(layer "In13.Cu")
		(net "M_B_CPU0_SA_DQ<23>")
	)
	(arc
		(start 329.454002 -239.301528)
		(mid 329.636253 -239.251178)
		(end 329.819762 -239.296702)
		(width 0.0889)
		(layer "In13.Cu")
		(net "M_B_CPU0_SA_DQ<23>")
	)
	(arc
		(start 327.008236 -239.301528)
		(mid 327.291192 -239.377705)
		(end 327.574148 -239.301528)
		(width 0.0889)
		(layer "In13.Cu")
		(net "M_B_CPU0_SA_DQ<23>")
	)
	(segment
		(start 336.218022 -239.08004)
		(end 335.75117 -238.814102)
		(width 0.10668)
		(layer "F.Cu")
		(net "M_B_CPU0_SA_DQ<22>")
	)
	(segment
		(start 305.237896 -223.044512)
		(end 305.237896 -223.115378)
		(width 0.14478)
		(layer "In13.Cu")
		(net "M_B_CPU0_SA_DQ<22>")
	)
	(segment
		(start 332.752446 -238.486696)
		(end 332.744064 -238.491522)
		(width 0.0889)
		(layer "In13.Cu")
		(net "M_B_CPU0_SA_DQ<22>")
	)
	(segment
		(start 304.686716 -223.044512)
		(end 304.541936 -222.899732)
		(width 0.14478)
		(layer "In13.Cu")
		(net "M_B_CPU0_SA_DQ<22>")
	)
	(segment
		(start 298.162472 -222.41002)
		(end 297.73753 -222.834962)
		(width 0.14478)
		(layer "In13.Cu")
		(net "M_B_CPU0_SA_DQ<22>")
	)
	(segment
		(start 328.41819 -238.491522)
		(end 328.409808 -238.486696)
		(width 0.0889)
		(layer "In13.Cu")
		(net "M_B_CPU0_SA_DQ<22>")
	)
	(segment
		(start 302.04664 -223.260158)
		(end 301.196502 -222.41002)
		(width 0.14478)
		(layer "In13.Cu")
		(net "M_B_CPU0_SA_DQ<22>")
	)
	(segment
		(start 307.036216 -223.260158)
		(end 306.891436 -223.115378)
		(width 0.14478)
		(layer "In13.Cu")
		(net "M_B_CPU0_SA_DQ<22>")
	)
	(segment
		(start 317.131954 -232.872534)
		(end 307.519578 -223.260158)
		(width 0.14478)
		(layer "In13.Cu")
		(net "M_B_CPU0_SA_DQ<22>")
	)
	(segment
		(start 325.010018 -237.304072)
		(end 324.430898 -237.304072)
		(width 0.0889)
		(layer "In13.Cu")
		(net "M_B_CPU0_SA_DQ<22>")
	)
	(segment
		(start 326.450452 -238.440468)
		(end 326.146414 -238.440468)
		(width 0.0889)
		(layer "In13.Cu")
		(net "M_B_CPU0_SA_DQ<22>")
	)
	(segment
		(start 304.831496 -223.260158)
		(end 304.686716 -223.115378)
		(width 0.14478)
		(layer "In13.Cu")
		(net "M_B_CPU0_SA_DQ<22>")
	)
	(segment
		(start 307.519578 -223.260158)
		(end 307.036216 -223.260158)
		(width 0.14478)
		(layer "In13.Cu")
		(net "M_B_CPU0_SA_DQ<22>")
	)
	(segment
		(start 326.146414 -238.440468)
		(end 325.010018 -237.304072)
		(width 0.0889)
		(layer "In13.Cu")
		(net "M_B_CPU0_SA_DQ<22>")
	)
	(segment
		(start 306.891436 -223.115378)
		(end 306.891436 -223.044512)
		(width 0.14478)
		(layer "In13.Cu")
		(net "M_B_CPU0_SA_DQ<22>")
	)
	(segment
		(start 305.237896 -223.115378)
		(end 305.093116 -223.260158)
		(width 0.14478)
		(layer "In13.Cu")
		(net "M_B_CPU0_SA_DQ<22>")
	)
	(segment
		(start 306.485036 -222.899732)
		(end 306.340256 -223.044512)
		(width 0.14478)
		(layer "In13.Cu")
		(net "M_B_CPU0_SA_DQ<22>")
	)
	(segment
		(start 304.541936 -222.899732)
		(end 304.280316 -222.899732)
		(width 0.14478)
		(layer "In13.Cu")
		(net "M_B_CPU0_SA_DQ<22>")
	)
	(segment
		(start 304.135536 -223.115378)
		(end 303.990756 -223.260158)
		(width 0.14478)
		(layer "In13.Cu")
		(net "M_B_CPU0_SA_DQ<22>")
	)
	(segment
		(start 305.789076 -223.115378)
		(end 305.789076 -223.044512)
		(width 0.14478)
		(layer "In13.Cu")
		(net "M_B_CPU0_SA_DQ<22>")
	)
	(segment
		(start 306.340256 -223.044512)
		(end 306.340256 -223.115378)
		(width 0.14478)
		(layer "In13.Cu")
		(net "M_B_CPU0_SA_DQ<22>")
	)
	(segment
		(start 305.789076 -223.044512)
		(end 305.644296 -222.899732)
		(width 0.14478)
		(layer "In13.Cu")
		(net "M_B_CPU0_SA_DQ<22>")
	)
	(segment
		(start 332.178152 -238.491522)
		(end 332.16977 -238.486696)
		(width 0.0889)
		(layer "In13.Cu")
		(net "M_B_CPU0_SA_DQ<22>")
	)
	(segment
		(start 328.992484 -238.486696)
		(end 328.984102 -238.491522)
		(width 0.0889)
		(layer "In13.Cu")
		(net "M_B_CPU0_SA_DQ<22>")
	)
	(segment
		(start 304.280316 -222.899732)
		(end 304.135536 -223.044512)
		(width 0.14478)
		(layer "In13.Cu")
		(net "M_B_CPU0_SA_DQ<22>")
	)
	(segment
		(start 305.933856 -223.260158)
		(end 305.789076 -223.115378)
		(width 0.14478)
		(layer "In13.Cu")
		(net "M_B_CPU0_SA_DQ<22>")
	)
	(segment
		(start 323.903848 -236.953044)
		(end 319.990216 -236.953044)
		(width 0.14478)
		(layer "In13.Cu")
		(net "M_B_CPU0_SA_DQ<22>")
	)
	(segment
		(start 304.135536 -223.044512)
		(end 304.135536 -223.115378)
		(width 0.14478)
		(layer "In13.Cu")
		(net "M_B_CPU0_SA_DQ<22>")
	)
	(segment
		(start 301.196502 -222.41002)
		(end 298.162472 -222.41002)
		(width 0.14478)
		(layer "In13.Cu")
		(net "M_B_CPU0_SA_DQ<22>")
	)
	(segment
		(start 331.238098 -238.491522)
		(end 331.229716 -238.486696)
		(width 0.0889)
		(layer "In13.Cu")
		(net "M_B_CPU0_SA_DQ<22>")
	)
	(segment
		(start 306.340256 -223.115378)
		(end 306.195476 -223.260158)
		(width 0.14478)
		(layer "In13.Cu")
		(net "M_B_CPU0_SA_DQ<22>")
	)
	(segment
		(start 306.891436 -223.044512)
		(end 306.746656 -222.899732)
		(width 0.14478)
		(layer "In13.Cu")
		(net "M_B_CPU0_SA_DQ<22>")
	)
	(segment
		(start 324.430898 -237.304072)
		(end 324.07987 -236.953044)
		(width 0.0889)
		(layer "In13.Cu")
		(net "M_B_CPU0_SA_DQ<22>")
	)
	(segment
		(start 317.131954 -234.094782)
		(end 317.131954 -232.872534)
		(width 0.14478)
		(layer "In13.Cu")
		(net "M_B_CPU0_SA_DQ<22>")
	)
	(segment
		(start 306.195476 -223.260158)
		(end 305.933856 -223.260158)
		(width 0.14478)
		(layer "In13.Cu")
		(net "M_B_CPU0_SA_DQ<22>")
	)
	(segment
		(start 305.382676 -222.899732)
		(end 305.237896 -223.044512)
		(width 0.14478)
		(layer "In13.Cu")
		(net "M_B_CPU0_SA_DQ<22>")
	)
	(segment
		(start 305.644296 -222.899732)
		(end 305.382676 -222.899732)
		(width 0.14478)
		(layer "In13.Cu")
		(net "M_B_CPU0_SA_DQ<22>")
	)
	(segment
		(start 335.75117 -238.814102)
		(end 335.596992 -238.548672)
		(width 0.0889)
		(layer "In13.Cu")
		(net "M_B_CPU0_SA_DQ<22>")
	)
	(segment
		(start 297.73753 -222.834962)
		(end 295.724072 -222.834962)
		(width 0.14478)
		(layer "In13.Cu")
		(net "M_B_CPU0_SA_DQ<22>")
	)
	(segment
		(start 304.686716 -223.115378)
		(end 304.686716 -223.044512)
		(width 0.14478)
		(layer "In13.Cu")
		(net "M_B_CPU0_SA_DQ<22>")
	)
	(segment
		(start 306.746656 -222.899732)
		(end 306.485036 -222.899732)
		(width 0.14478)
		(layer "In13.Cu")
		(net "M_B_CPU0_SA_DQ<22>")
	)
	(segment
		(start 326.538336 -238.491522)
		(end 326.450452 -238.440468)
		(width 0.0889)
		(layer "In13.Cu")
		(net "M_B_CPU0_SA_DQ<22>")
	)
	(segment
		(start 319.990216 -236.953044)
		(end 317.131954 -234.094782)
		(width 0.14478)
		(layer "In13.Cu")
		(net "M_B_CPU0_SA_DQ<22>")
	)
	(segment
		(start 327.47839 -238.491522)
		(end 327.470008 -238.486696)
		(width 0.0889)
		(layer "In13.Cu")
		(net "M_B_CPU0_SA_DQ<22>")
	)
	(segment
		(start 303.990756 -223.260158)
		(end 302.04664 -223.260158)
		(width 0.14478)
		(layer "In13.Cu")
		(net "M_B_CPU0_SA_DQ<22>")
	)
	(segment
		(start 305.093116 -223.260158)
		(end 304.831496 -223.260158)
		(width 0.14478)
		(layer "In13.Cu")
		(net "M_B_CPU0_SA_DQ<22>")
	)
	(segment
		(start 327.488804 -238.497618)
		(end 327.47839 -238.491522)
		(width 0.0889)
		(layer "In13.Cu")
		(net "M_B_CPU0_SA_DQ<22>")
	)
	(segment
		(start 333.6925 -238.486696)
		(end 333.684118 -238.491522)
		(width 0.0889)
		(layer "In13.Cu")
		(net "M_B_CPU0_SA_DQ<22>")
	)
	(segment
		(start 335.596992 -238.548672)
		(end 335.500726 -238.523272)
		(width 0.0889)
		(layer "In13.Cu")
		(net "M_B_CPU0_SA_DQ<22>")
	)
	(segment
		(start 324.07987 -236.953044)
		(end 323.903848 -236.953044)
		(width 0.0889)
		(layer "In13.Cu")
		(net "M_B_CPU0_SA_DQ<22>")
	)
	(arc
		(start 329.358244 -238.491522)
		(mid 329.175993 -238.441172)
		(end 328.992484 -238.486696)
		(width 0.0889)
		(layer "In13.Cu")
		(net "M_B_CPU0_SA_DQ<22>")
	)
	(arc
		(start 334.05826 -238.491522)
		(mid 333.876009 -238.441172)
		(end 333.6925 -238.486696)
		(width 0.0889)
		(layer "In13.Cu")
		(net "M_B_CPU0_SA_DQ<22>")
	)
	(arc
		(start 328.044048 -238.491522)
		(mid 327.767235 -238.567665)
		(end 327.488804 -238.497618)
		(width 0.0889)
		(layer "In13.Cu")
		(net "M_B_CPU0_SA_DQ<22>")
	)
	(arc
		(start 334.624172 -238.491522)
		(mid 334.341216 -238.567699)
		(end 334.05826 -238.491522)
		(width 0.0889)
		(layer "In13.Cu")
		(net "M_B_CPU0_SA_DQ<22>")
	)
	(arc
		(start 333.684118 -238.491522)
		(mid 333.401162 -238.567699)
		(end 333.118206 -238.491522)
		(width 0.0889)
		(layer "In13.Cu")
		(net "M_B_CPU0_SA_DQ<22>")
	)
	(arc
		(start 333.118206 -238.491522)
		(mid 332.935955 -238.441172)
		(end 332.752446 -238.486696)
		(width 0.0889)
		(layer "In13.Cu")
		(net "M_B_CPU0_SA_DQ<22>")
	)
	(arc
		(start 327.470008 -238.486696)
		(mid 327.2865 -238.441202)
		(end 327.104248 -238.491522)
		(width 0.0889)
		(layer "In13.Cu")
		(net "M_B_CPU0_SA_DQ<22>")
	)
	(arc
		(start 328.984102 -238.491522)
		(mid 328.701146 -238.567699)
		(end 328.41819 -238.491522)
		(width 0.0889)
		(layer "In13.Cu")
		(net "M_B_CPU0_SA_DQ<22>")
	)
	(arc
		(start 334.99806 -238.491522)
		(mid 334.811116 -238.441267)
		(end 334.624172 -238.491522)
		(width 0.0889)
		(layer "In13.Cu")
		(net "M_B_CPU0_SA_DQ<22>")
	)
	(arc
		(start 330.298044 -238.491522)
		(mid 330.1111 -238.441267)
		(end 329.924156 -238.491522)
		(width 0.0889)
		(layer "In13.Cu")
		(net "M_B_CPU0_SA_DQ<22>")
	)
	(arc
		(start 328.409808 -238.486696)
		(mid 328.2263 -238.441202)
		(end 328.044048 -238.491522)
		(width 0.0889)
		(layer "In13.Cu")
		(net "M_B_CPU0_SA_DQ<22>")
	)
	(arc
		(start 335.500726 -238.523272)
		(mid 335.245661 -238.566623)
		(end 334.99806 -238.491522)
		(width 0.0889)
		(layer "In13.Cu")
		(net "M_B_CPU0_SA_DQ<22>")
	)
	(arc
		(start 331.80401 -238.491522)
		(mid 331.521054 -238.567699)
		(end 331.238098 -238.491522)
		(width 0.0889)
		(layer "In13.Cu")
		(net "M_B_CPU0_SA_DQ<22>")
	)
	(arc
		(start 330.863956 -238.491522)
		(mid 330.581 -238.567699)
		(end 330.298044 -238.491522)
		(width 0.0889)
		(layer "In13.Cu")
		(net "M_B_CPU0_SA_DQ<22>")
	)
	(arc
		(start 332.744064 -238.491522)
		(mid 332.461108 -238.567699)
		(end 332.178152 -238.491522)
		(width 0.0889)
		(layer "In13.Cu")
		(net "M_B_CPU0_SA_DQ<22>")
	)
	(arc
		(start 331.229716 -238.486696)
		(mid 331.046208 -238.441202)
		(end 330.863956 -238.491522)
		(width 0.0889)
		(layer "In13.Cu")
		(net "M_B_CPU0_SA_DQ<22>")
	)
	(arc
		(start 332.16977 -238.486696)
		(mid 331.986262 -238.441202)
		(end 331.80401 -238.491522)
		(width 0.0889)
		(layer "In13.Cu")
		(net "M_B_CPU0_SA_DQ<22>")
	)
	(arc
		(start 327.104248 -238.491522)
		(mid 326.821292 -238.567699)
		(end 326.538336 -238.491522)
		(width 0.0889)
		(layer "In13.Cu")
		(net "M_B_CPU0_SA_DQ<22>")
	)
	(arc
		(start 329.924156 -238.491522)
		(mid 329.6412 -238.567699)
		(end 329.358244 -238.491522)
		(width 0.0889)
		(layer "In13.Cu")
		(net "M_B_CPU0_SA_DQ<22>")
	)
	(segment
		(start 337.158076 -239.08004)
		(end 336.691224 -238.814102)
		(width 0.10668)
		(layer "F.Cu")
		(net "M_B_CPU0_SA_DQ<21>")
	)
	(segment
		(start 326.486774 -239.18799)
		(end 326.538082 -239.136682)
		(width 0.0889)
		(layer "In13.Cu")
		(net "M_B_CPU0_SA_DQ<21>")
	)
	(segment
		(start 300.661324 -223.042226)
		(end 300.922944 -223.042226)
		(width 0.14478)
		(layer "In13.Cu")
		(net "M_B_CPU0_SA_DQ<21>")
	)
	(segment
		(start 324.189598 -237.558072)
		(end 324.895972 -237.558072)
		(width 0.0889)
		(layer "In13.Cu")
		(net "M_B_CPU0_SA_DQ<21>")
	)
	(segment
		(start 306.39004 -224.46488)
		(end 306.65166 -224.46488)
		(width 0.14478)
		(layer "In13.Cu")
		(net "M_B_CPU0_SA_DQ<21>")
	)
	(segment
		(start 303.184814 -224.110042)
		(end 304.157888 -224.110042)
		(width 0.14478)
		(layer "In13.Cu")
		(net "M_B_CPU0_SA_DQ<21>")
	)
	(segment
		(start 332.744064 -239.136682)
		(end 332.752446 -239.141508)
		(width 0.0889)
		(layer "In13.Cu")
		(net "M_B_CPU0_SA_DQ<21>")
	)
	(segment
		(start 305.83886 -223.7232)
		(end 306.10048 -223.7232)
		(width 0.14478)
		(layer "In13.Cu")
		(net "M_B_CPU0_SA_DQ<21>")
	)
	(segment
		(start 327.478136 -239.136682)
		(end 327.477882 -239.136682)
		(width 0.0889)
		(layer "In13.Cu")
		(net "M_B_CPU0_SA_DQ<21>")
	)
	(segment
		(start 301.067724 -223.515682)
		(end 301.212504 -223.660462)
		(width 0.14478)
		(layer "In13.Cu")
		(net "M_B_CPU0_SA_DQ<21>")
	)
	(segment
		(start 325.896478 -238.558578)
		(end 325.896478 -238.746792)
		(width 0.0889)
		(layer "In13.Cu")
		(net "M_B_CPU0_SA_DQ<21>")
	)
	(segment
		(start 299.848778 -223.660462)
		(end 300.371764 -223.660462)
		(width 0.14478)
		(layer "In13.Cu")
		(net "M_B_CPU0_SA_DQ<21>")
	)
	(segment
		(start 327.469754 -239.141508)
		(end 327.478136 -239.136682)
		(width 0.0889)
		(layer "In13.Cu")
		(net "M_B_CPU0_SA_DQ<21>")
	)
	(segment
		(start 302.488854 -224.328228)
		(end 302.633634 -224.473008)
		(width 0.14478)
		(layer "In13.Cu")
		(net "M_B_CPU0_SA_DQ<21>")
	)
	(segment
		(start 335.929732 -239.141508)
		(end 335.938114 -239.136682)
		(width 0.0889)
		(layer "In13.Cu")
		(net "M_B_CPU0_SA_DQ<21>")
	)
	(segment
		(start 316.677294 -233.05389)
		(end 316.677294 -234.276392)
		(width 0.14478)
		(layer "In13.Cu")
		(net "M_B_CPU0_SA_DQ<21>")
	)
	(segment
		(start 319.808606 -237.407704)
		(end 323.873368 -237.407704)
		(width 0.14478)
		(layer "In13.Cu")
		(net "M_B_CPU0_SA_DQ<21>")
	)
	(segment
		(start 302.344074 -224.110042)
		(end 302.488854 -224.254822)
		(width 0.14478)
		(layer "In13.Cu")
		(net "M_B_CPU0_SA_DQ<21>")
	)
	(segment
		(start 300.516544 -223.187006)
		(end 300.661324 -223.042226)
		(width 0.14478)
		(layer "In13.Cu")
		(net "M_B_CPU0_SA_DQ<21>")
	)
	(segment
		(start 302.488854 -224.254822)
		(end 302.488854 -224.328228)
		(width 0.14478)
		(layer "In13.Cu")
		(net "M_B_CPU0_SA_DQ<21>")
	)
	(segment
		(start 306.10048 -223.7232)
		(end 306.24526 -223.86798)
		(width 0.14478)
		(layer "In13.Cu")
		(net "M_B_CPU0_SA_DQ<21>")
	)
	(segment
		(start 306.79644 -223.86798)
		(end 306.94122 -223.7232)
		(width 0.14478)
		(layer "In13.Cu")
		(net "M_B_CPU0_SA_DQ<21>")
	)
	(segment
		(start 316.677294 -234.276392)
		(end 319.808606 -237.407704)
		(width 0.14478)
		(layer "In13.Cu")
		(net "M_B_CPU0_SA_DQ<21>")
	)
	(segment
		(start 304.157888 -224.110042)
		(end 304.54473 -223.7232)
		(width 0.14478)
		(layer "In13.Cu")
		(net "M_B_CPU0_SA_DQ<21>")
	)
	(segment
		(start 301.212504 -223.660462)
		(end 301.574962 -223.660462)
		(width 0.14478)
		(layer "In13.Cu")
		(net "M_B_CPU0_SA_DQ<21>")
	)
	(segment
		(start 336.822796 -239.162844)
		(end 336.845148 -239.079532)
		(width 0.0889)
		(layer "In13.Cu")
		(net "M_B_CPU0_SA_DQ<21>")
	)
	(segment
		(start 305.28768 -224.46488)
		(end 305.5493 -224.46488)
		(width 0.14478)
		(layer "In13.Cu")
		(net "M_B_CPU0_SA_DQ<21>")
	)
	(segment
		(start 332.16977 -239.141508)
		(end 332.178152 -239.136682)
		(width 0.0889)
		(layer "In13.Cu")
		(net "M_B_CPU0_SA_DQ<21>")
	)
	(segment
		(start 328.409808 -239.141508)
		(end 328.41819 -239.136682)
		(width 0.0889)
		(layer "In13.Cu")
		(net "M_B_CPU0_SA_DQ<21>")
	)
	(segment
		(start 301.574962 -223.660462)
		(end 302.024542 -224.110042)
		(width 0.14478)
		(layer "In13.Cu")
		(net "M_B_CPU0_SA_DQ<21>")
	)
	(segment
		(start 302.024542 -224.110042)
		(end 302.344074 -224.110042)
		(width 0.14478)
		(layer "In13.Cu")
		(net "M_B_CPU0_SA_DQ<21>")
	)
	(segment
		(start 304.54473 -223.7232)
		(end 304.99812 -223.7232)
		(width 0.14478)
		(layer "In13.Cu")
		(net "M_B_CPU0_SA_DQ<21>")
	)
	(segment
		(start 305.69408 -224.3201)
		(end 305.69408 -223.86798)
		(width 0.14478)
		(layer "In13.Cu")
		(net "M_B_CPU0_SA_DQ<21>")
	)
	(segment
		(start 305.5493 -224.46488)
		(end 305.69408 -224.3201)
		(width 0.14478)
		(layer "In13.Cu")
		(net "M_B_CPU0_SA_DQ<21>")
	)
	(segment
		(start 302.895254 -224.473008)
		(end 303.040034 -224.328228)
		(width 0.14478)
		(layer "In13.Cu")
		(net "M_B_CPU0_SA_DQ<21>")
	)
	(segment
		(start 301.067724 -223.187006)
		(end 301.067724 -223.515682)
		(width 0.14478)
		(layer "In13.Cu")
		(net "M_B_CPU0_SA_DQ<21>")
	)
	(segment
		(start 324.895972 -237.558072)
		(end 325.896478 -238.558578)
		(width 0.0889)
		(layer "In13.Cu")
		(net "M_B_CPU0_SA_DQ<21>")
	)
	(segment
		(start 328.984102 -239.136682)
		(end 328.992484 -239.141508)
		(width 0.0889)
		(layer "In13.Cu")
		(net "M_B_CPU0_SA_DQ<21>")
	)
	(segment
		(start 306.24526 -223.86798)
		(end 306.24526 -224.3201)
		(width 0.14478)
		(layer "In13.Cu")
		(net "M_B_CPU0_SA_DQ<21>")
	)
	(segment
		(start 305.1429 -223.86798)
		(end 305.1429 -224.3201)
		(width 0.14478)
		(layer "In13.Cu")
		(net "M_B_CPU0_SA_DQ<21>")
	)
	(segment
		(start 300.922944 -223.042226)
		(end 301.067724 -223.187006)
		(width 0.14478)
		(layer "In13.Cu")
		(net "M_B_CPU0_SA_DQ<21>")
	)
	(segment
		(start 306.65166 -224.46488)
		(end 306.79644 -224.3201)
		(width 0.14478)
		(layer "In13.Cu")
		(net "M_B_CPU0_SA_DQ<21>")
	)
	(segment
		(start 306.94122 -223.7232)
		(end 307.346604 -223.7232)
		(width 0.14478)
		(layer "In13.Cu")
		(net "M_B_CPU0_SA_DQ<21>")
	)
	(segment
		(start 303.040034 -224.254822)
		(end 303.184814 -224.110042)
		(width 0.14478)
		(layer "In13.Cu")
		(net "M_B_CPU0_SA_DQ<21>")
	)
	(segment
		(start 300.371764 -223.660462)
		(end 300.516544 -223.515682)
		(width 0.14478)
		(layer "In13.Cu")
		(net "M_B_CPU0_SA_DQ<21>")
	)
	(segment
		(start 306.24526 -224.3201)
		(end 306.39004 -224.46488)
		(width 0.14478)
		(layer "In13.Cu")
		(net "M_B_CPU0_SA_DQ<21>")
	)
	(segment
		(start 331.229716 -239.141508)
		(end 331.238098 -239.136682)
		(width 0.0889)
		(layer "In13.Cu")
		(net "M_B_CPU0_SA_DQ<21>")
	)
	(segment
		(start 303.040034 -224.328228)
		(end 303.040034 -224.254822)
		(width 0.14478)
		(layer "In13.Cu")
		(net "M_B_CPU0_SA_DQ<21>")
	)
	(segment
		(start 299.82414 -223.6851)
		(end 299.848778 -223.660462)
		(width 0.14478)
		(layer "In13.Cu")
		(net "M_B_CPU0_SA_DQ<21>")
	)
	(segment
		(start 305.69408 -223.86798)
		(end 305.83886 -223.7232)
		(width 0.14478)
		(layer "In13.Cu")
		(net "M_B_CPU0_SA_DQ<21>")
	)
	(segment
		(start 304.99812 -223.7232)
		(end 305.1429 -223.86798)
		(width 0.14478)
		(layer "In13.Cu")
		(net "M_B_CPU0_SA_DQ<21>")
	)
	(segment
		(start 307.346604 -223.7232)
		(end 316.677294 -233.05389)
		(width 0.14478)
		(layer "In13.Cu")
		(net "M_B_CPU0_SA_DQ<21>")
	)
	(segment
		(start 323.873368 -237.407704)
		(end 324.03923 -237.407704)
		(width 0.0889)
		(layer "In13.Cu")
		(net "M_B_CPU0_SA_DQ<21>")
	)
	(segment
		(start 336.845148 -239.079532)
		(end 336.691224 -238.814102)
		(width 0.0889)
		(layer "In13.Cu")
		(net "M_B_CPU0_SA_DQ<21>")
	)
	(segment
		(start 324.03923 -237.407704)
		(end 324.189598 -237.558072)
		(width 0.0889)
		(layer "In13.Cu")
		(net "M_B_CPU0_SA_DQ<21>")
	)
	(segment
		(start 326.337676 -239.18799)
		(end 326.486774 -239.18799)
		(width 0.0889)
		(layer "In13.Cu")
		(net "M_B_CPU0_SA_DQ<21>")
	)
	(segment
		(start 333.684118 -239.136682)
		(end 333.6925 -239.141508)
		(width 0.0889)
		(layer "In13.Cu")
		(net "M_B_CPU0_SA_DQ<21>")
	)
	(segment
		(start 302.633634 -224.473008)
		(end 302.895254 -224.473008)
		(width 0.14478)
		(layer "In13.Cu")
		(net "M_B_CPU0_SA_DQ<21>")
	)
	(segment
		(start 306.79644 -224.3201)
		(end 306.79644 -223.86798)
		(width 0.14478)
		(layer "In13.Cu")
		(net "M_B_CPU0_SA_DQ<21>")
	)
	(segment
		(start 305.1429 -224.3201)
		(end 305.28768 -224.46488)
		(width 0.14478)
		(layer "In13.Cu")
		(net "M_B_CPU0_SA_DQ<21>")
	)
	(segment
		(start 300.516544 -223.515682)
		(end 300.516544 -223.187006)
		(width 0.14478)
		(layer "In13.Cu")
		(net "M_B_CPU0_SA_DQ<21>")
	)
	(segment
		(start 328.033634 -239.130586)
		(end 328.044048 -239.136682)
		(width 0.0889)
		(layer "In13.Cu")
		(net "M_B_CPU0_SA_DQ<21>")
	)
	(arc
		(start 329.924156 -239.136682)
		(mid 330.1111 -239.186937)
		(end 330.298044 -239.136682)
		(width 0.0889)
		(layer "In13.Cu")
		(net "M_B_CPU0_SA_DQ<21>")
	)
	(arc
		(start 331.238098 -239.136682)
		(mid 331.521054 -239.060505)
		(end 331.80401 -239.136682)
		(width 0.0889)
		(layer "In13.Cu")
		(net "M_B_CPU0_SA_DQ<21>")
	)
	(arc
		(start 332.752446 -239.141508)
		(mid 332.935954 -239.187002)
		(end 333.118206 -239.136682)
		(width 0.0889)
		(layer "In13.Cu")
		(net "M_B_CPU0_SA_DQ<21>")
	)
	(arc
		(start 329.358244 -239.136682)
		(mid 329.6412 -239.060505)
		(end 329.924156 -239.136682)
		(width 0.0889)
		(layer "In13.Cu")
		(net "M_B_CPU0_SA_DQ<21>")
	)
	(arc
		(start 334.99806 -239.136682)
		(mid 335.281016 -239.060505)
		(end 335.563972 -239.136682)
		(width 0.0889)
		(layer "In13.Cu")
		(net "M_B_CPU0_SA_DQ<21>")
	)
	(arc
		(start 327.103994 -239.136682)
		(mid 327.286245 -239.187032)
		(end 327.469754 -239.141508)
		(width 0.0889)
		(layer "In13.Cu")
		(net "M_B_CPU0_SA_DQ<21>")
	)
	(arc
		(start 335.563972 -239.136682)
		(mid 335.746223 -239.187032)
		(end 335.929732 -239.141508)
		(width 0.0889)
		(layer "In13.Cu")
		(net "M_B_CPU0_SA_DQ<21>")
	)
	(arc
		(start 331.80401 -239.136682)
		(mid 331.986261 -239.187032)
		(end 332.16977 -239.141508)
		(width 0.0889)
		(layer "In13.Cu")
		(net "M_B_CPU0_SA_DQ<21>")
	)
	(arc
		(start 334.05826 -239.136682)
		(mid 334.341216 -239.060505)
		(end 334.624172 -239.136682)
		(width 0.0889)
		(layer "In13.Cu")
		(net "M_B_CPU0_SA_DQ<21>")
	)
	(arc
		(start 327.477882 -239.136682)
		(mid 327.754949 -239.060411)
		(end 328.033634 -239.130586)
		(width 0.0889)
		(layer "In13.Cu")
		(net "M_B_CPU0_SA_DQ<21>")
	)
	(arc
		(start 326.538082 -239.136682)
		(mid 326.821038 -239.060505)
		(end 327.103994 -239.136682)
		(width 0.0889)
		(layer "In13.Cu")
		(net "M_B_CPU0_SA_DQ<21>")
	)
	(arc
		(start 328.41819 -239.136682)
		(mid 328.701146 -239.060505)
		(end 328.984102 -239.136682)
		(width 0.0889)
		(layer "In13.Cu")
		(net "M_B_CPU0_SA_DQ<21>")
	)
	(arc
		(start 328.044048 -239.136682)
		(mid 328.226299 -239.187032)
		(end 328.409808 -239.141508)
		(width 0.0889)
		(layer "In13.Cu")
		(net "M_B_CPU0_SA_DQ<21>")
	)
	(arc
		(start 332.178152 -239.136682)
		(mid 332.461108 -239.060505)
		(end 332.744064 -239.136682)
		(width 0.0889)
		(layer "In13.Cu")
		(net "M_B_CPU0_SA_DQ<21>")
	)
	(arc
		(start 336.504026 -239.136682)
		(mid 336.660464 -239.185653)
		(end 336.822796 -239.162844)
		(width 0.0889)
		(layer "In13.Cu")
		(net "M_B_CPU0_SA_DQ<21>")
	)
	(arc
		(start 328.992484 -239.141508)
		(mid 329.175992 -239.187002)
		(end 329.358244 -239.136682)
		(width 0.0889)
		(layer "In13.Cu")
		(net "M_B_CPU0_SA_DQ<21>")
	)
	(arc
		(start 330.863956 -239.136682)
		(mid 331.046207 -239.187032)
		(end 331.229716 -239.141508)
		(width 0.0889)
		(layer "In13.Cu")
		(net "M_B_CPU0_SA_DQ<21>")
	)
	(arc
		(start 333.6925 -239.141508)
		(mid 333.876008 -239.187002)
		(end 334.05826 -239.136682)
		(width 0.0889)
		(layer "In13.Cu")
		(net "M_B_CPU0_SA_DQ<21>")
	)
	(arc
		(start 330.298044 -239.136682)
		(mid 330.581 -239.060505)
		(end 330.863956 -239.136682)
		(width 0.0889)
		(layer "In13.Cu")
		(net "M_B_CPU0_SA_DQ<21>")
	)
	(arc
		(start 335.938114 -239.136682)
		(mid 336.22107 -239.060505)
		(end 336.504026 -239.136682)
		(width 0.0889)
		(layer "In13.Cu")
		(net "M_B_CPU0_SA_DQ<21>")
	)
	(arc
		(start 334.624172 -239.136682)
		(mid 334.811116 -239.186937)
		(end 334.99806 -239.136682)
		(width 0.0889)
		(layer "In13.Cu")
		(net "M_B_CPU0_SA_DQ<21>")
	)
	(arc
		(start 325.896478 -238.746792)
		(mid 326.025702 -239.058766)
		(end 326.337676 -239.18799)
		(width 0.0889)
		(layer "In13.Cu")
		(net "M_B_CPU0_SA_DQ<21>")
	)
	(arc
		(start 333.118206 -239.136682)
		(mid 333.401162 -239.060505)
		(end 333.684118 -239.136682)
		(width 0.0889)
		(layer "In13.Cu")
		(net "M_B_CPU0_SA_DQ<21>")
	)
	(segment
		(start 335.747868 -238.270034)
		(end 335.281016 -238.004096)
		(width 0.10668)
		(layer "F.Cu")
		(net "M_B_CPU0_SA_DQ<20>")
	)
	(segment
		(start 318.054228 -234.15244)
		(end 317.825882 -234.15244)
		(width 0.14478)
		(layer "In13.Cu")
		(net "M_B_CPU0_SA_DQ<20>")
	)
	(segment
		(start 330.402438 -238.331502)
		(end 330.394056 -238.326676)
		(width 0.0889)
		(layer "In13.Cu")
		(net "M_B_CPU0_SA_DQ<20>")
	)
	(segment
		(start 318.82715 -233.931714)
		(end 318.665098 -233.769662)
		(width 0.14478)
		(layer "In13.Cu")
		(net "M_B_CPU0_SA_DQ<20>")
	)
	(segment
		(start 324.07987 -236.498384)
		(end 323.897498 -236.498384)
		(width 0.0889)
		(layer "In13.Cu")
		(net "M_B_CPU0_SA_DQ<20>")
	)
	(segment
		(start 320.387726 -235.720128)
		(end 320.387726 -235.49229)
		(width 0.14478)
		(layer "In13.Cu")
		(net "M_B_CPU0_SA_DQ<20>")
	)
	(segment
		(start 319.386458 -235.713016)
		(end 319.224406 -235.550964)
		(width 0.14478)
		(layer "In13.Cu")
		(net "M_B_CPU0_SA_DQ<20>")
	)
	(segment
		(start 324.997572 -237.022132)
		(end 324.603618 -237.022132)
		(width 0.0889)
		(layer "In13.Cu")
		(net "M_B_CPU0_SA_DQ<20>")
	)
	(segment
		(start 318.046862 -233.151426)
		(end 307.824378 -222.928942)
		(width 0.14478)
		(layer "In13.Cu")
		(net "M_B_CPU0_SA_DQ<20>")
	)
	(segment
		(start 303.690274 -222.419672)
		(end 303.545494 -222.564452)
		(width 0.14478)
		(layer "In13.Cu")
		(net "M_B_CPU0_SA_DQ<20>")
	)
	(segment
		(start 318.82715 -234.159552)
		(end 318.82715 -233.931714)
		(width 0.14478)
		(layer "In13.Cu")
		(net "M_B_CPU0_SA_DQ<20>")
	)
	(segment
		(start 303.400714 -222.802196)
		(end 303.139094 -222.802196)
		(width 0.14478)
		(layer "In13.Cu")
		(net "M_B_CPU0_SA_DQ<20>")
	)
	(segment
		(start 301.955962 -222.419672)
		(end 301.106078 -221.569788)
		(width 0.14478)
		(layer "In13.Cu")
		(net "M_B_CPU0_SA_DQ<20>")
	)
	(segment
		(start 335.281016 -238.004096)
		(end 335.435194 -238.269526)
		(width 0.0889)
		(layer "In13.Cu")
		(net "M_B_CPU0_SA_DQ<20>")
	)
	(segment
		(start 320.77787 -236.110526)
		(end 320.395092 -236.493304)
		(width 0.14478)
		(layer "In13.Cu")
		(net "M_B_CPU0_SA_DQ<20>")
	)
	(segment
		(start 318.046862 -233.379264)
		(end 318.046862 -233.151426)
		(width 0.14478)
		(layer "In13.Cu")
		(net "M_B_CPU0_SA_DQ<20>")
	)
	(segment
		(start 320.166746 -236.493304)
		(end 320.004694 -236.331252)
		(width 0.14478)
		(layer "In13.Cu")
		(net "M_B_CPU0_SA_DQ<20>")
	)
	(segment
		(start 301.106078 -221.569788)
		(end 300.191932 -221.569788)
		(width 0.14478)
		(layer "In13.Cu")
		(net "M_B_CPU0_SA_DQ<20>")
	)
	(segment
		(start 300.191932 -221.569788)
		(end 299.82414 -221.93758)
		(width 0.14478)
		(layer "In13.Cu")
		(net "M_B_CPU0_SA_DQ<20>")
	)
	(segment
		(start 327.58253 -238.331502)
		(end 327.574148 -238.326676)
		(width 0.0889)
		(layer "In13.Cu")
		(net "M_B_CPU0_SA_DQ<20>")
	)
	(segment
		(start 303.139094 -222.802196)
		(end 302.994314 -222.657416)
		(width 0.14478)
		(layer "In13.Cu")
		(net "M_B_CPU0_SA_DQ<20>")
	)
	(segment
		(start 321.005962 -236.110526)
		(end 320.77787 -236.110526)
		(width 0.14478)
		(layer "In13.Cu")
		(net "M_B_CPU0_SA_DQ<20>")
	)
	(segment
		(start 324.603618 -237.022132)
		(end 324.07987 -236.498384)
		(width 0.0889)
		(layer "In13.Cu")
		(net "M_B_CPU0_SA_DQ<20>")
	)
	(segment
		(start 302.849534 -222.419672)
		(end 301.955962 -222.419672)
		(width 0.14478)
		(layer "In13.Cu")
		(net "M_B_CPU0_SA_DQ<20>")
	)
	(segment
		(start 319.614804 -235.713016)
		(end 319.386458 -235.713016)
		(width 0.14478)
		(layer "In13.Cu")
		(net "M_B_CPU0_SA_DQ<20>")
	)
	(segment
		(start 319.997582 -235.330238)
		(end 319.614804 -235.713016)
		(width 0.14478)
		(layer "In13.Cu")
		(net "M_B_CPU0_SA_DQ<20>")
	)
	(segment
		(start 327.574148 -238.326676)
		(end 327.563734 -238.32058)
		(width 0.0889)
		(layer "In13.Cu")
		(net "M_B_CPU0_SA_DQ<20>")
	)
	(segment
		(start 319.217294 -234.54995)
		(end 318.834516 -234.932728)
		(width 0.14478)
		(layer "In13.Cu")
		(net "M_B_CPU0_SA_DQ<20>")
	)
	(segment
		(start 335.102454 -238.331502)
		(end 335.094072 -238.326676)
		(width 0.0889)
		(layer "In13.Cu")
		(net "M_B_CPU0_SA_DQ<20>")
	)
	(segment
		(start 307.644038 -222.419672)
		(end 303.690274 -222.419672)
		(width 0.14478)
		(layer "In13.Cu")
		(net "M_B_CPU0_SA_DQ<20>")
	)
	(segment
		(start 326.225408 -238.249968)
		(end 324.997572 -237.022132)
		(width 0.0889)
		(layer "In13.Cu")
		(net "M_B_CPU0_SA_DQ<20>")
	)
	(segment
		(start 320.004694 -236.10316)
		(end 320.387726 -235.720128)
		(width 0.14478)
		(layer "In13.Cu")
		(net "M_B_CPU0_SA_DQ<20>")
	)
	(segment
		(start 319.445386 -234.54995)
		(end 319.217294 -234.54995)
		(width 0.14478)
		(layer "In13.Cu")
		(net "M_B_CPU0_SA_DQ<20>")
	)
	(segment
		(start 319.607438 -234.712002)
		(end 319.445386 -234.54995)
		(width 0.14478)
		(layer "In13.Cu")
		(net "M_B_CPU0_SA_DQ<20>")
	)
	(segment
		(start 302.994314 -222.564452)
		(end 302.849534 -222.419672)
		(width 0.14478)
		(layer "In13.Cu")
		(net "M_B_CPU0_SA_DQ<20>")
	)
	(segment
		(start 320.004694 -236.331252)
		(end 320.004694 -236.10316)
		(width 0.14478)
		(layer "In13.Cu")
		(net "M_B_CPU0_SA_DQ<20>")
	)
	(segment
		(start 303.545494 -222.564452)
		(end 303.545494 -222.657416)
		(width 0.14478)
		(layer "In13.Cu")
		(net "M_B_CPU0_SA_DQ<20>")
	)
	(segment
		(start 326.502014 -238.249968)
		(end 326.225408 -238.249968)
		(width 0.0889)
		(layer "In13.Cu")
		(net "M_B_CPU0_SA_DQ<20>")
	)
	(segment
		(start 318.60617 -234.932728)
		(end 318.444118 -234.770676)
		(width 0.14478)
		(layer "In13.Cu")
		(net "M_B_CPU0_SA_DQ<20>")
	)
	(segment
		(start 335.435194 -238.269526)
		(end 335.412842 -238.352838)
		(width 0.0889)
		(layer "In13.Cu")
		(net "M_B_CPU0_SA_DQ<20>")
	)
	(segment
		(start 334.52816 -238.326676)
		(end 334.519778 -238.331502)
		(width 0.0889)
		(layer "In13.Cu")
		(net "M_B_CPU0_SA_DQ<20>")
	)
	(segment
		(start 319.224406 -235.550964)
		(end 319.224406 -235.322872)
		(width 0.14478)
		(layer "In13.Cu")
		(net "M_B_CPU0_SA_DQ<20>")
	)
	(segment
		(start 333.588106 -238.326676)
		(end 333.579724 -238.331502)
		(width 0.0889)
		(layer "In13.Cu")
		(net "M_B_CPU0_SA_DQ<20>")
	)
	(segment
		(start 321.39382 -236.498384)
		(end 321.005962 -236.110526)
		(width 0.14478)
		(layer "In13.Cu")
		(net "M_B_CPU0_SA_DQ<20>")
	)
	(segment
		(start 331.342492 -238.331502)
		(end 331.33411 -238.326676)
		(width 0.0889)
		(layer "In13.Cu")
		(net "M_B_CPU0_SA_DQ<20>")
	)
	(segment
		(start 317.66383 -233.762296)
		(end 318.046862 -233.379264)
		(width 0.14478)
		(layer "In13.Cu")
		(net "M_B_CPU0_SA_DQ<20>")
	)
	(segment
		(start 307.824378 -222.600012)
		(end 307.644038 -222.419672)
		(width 0.14478)
		(layer "In13.Cu")
		(net "M_B_CPU0_SA_DQ<20>")
	)
	(segment
		(start 329.828144 -238.326676)
		(end 329.819762 -238.331502)
		(width 0.0889)
		(layer "In13.Cu")
		(net "M_B_CPU0_SA_DQ<20>")
	)
	(segment
		(start 326.634094 -238.326676)
		(end 326.502014 -238.249968)
		(width 0.0889)
		(layer "In13.Cu")
		(net "M_B_CPU0_SA_DQ<20>")
	)
	(segment
		(start 317.825882 -234.15244)
		(end 317.66383 -233.990388)
		(width 0.14478)
		(layer "In13.Cu")
		(net "M_B_CPU0_SA_DQ<20>")
	)
	(segment
		(start 319.224406 -235.322872)
		(end 319.607438 -234.93984)
		(width 0.14478)
		(layer "In13.Cu")
		(net "M_B_CPU0_SA_DQ<20>")
	)
	(segment
		(start 303.545494 -222.657416)
		(end 303.400714 -222.802196)
		(width 0.14478)
		(layer "In13.Cu")
		(net "M_B_CPU0_SA_DQ<20>")
	)
	(segment
		(start 307.824378 -222.928942)
		(end 307.824378 -222.600012)
		(width 0.14478)
		(layer "In13.Cu")
		(net "M_B_CPU0_SA_DQ<20>")
	)
	(segment
		(start 320.387726 -235.49229)
		(end 320.225674 -235.330238)
		(width 0.14478)
		(layer "In13.Cu")
		(net "M_B_CPU0_SA_DQ<20>")
	)
	(segment
		(start 317.66383 -233.990388)
		(end 317.66383 -233.762296)
		(width 0.14478)
		(layer "In13.Cu")
		(net "M_B_CPU0_SA_DQ<20>")
	)
	(segment
		(start 299.82414 -221.93758)
		(end 299.82414 -221.985078)
		(width 0.14478)
		(layer "In13.Cu")
		(net "M_B_CPU0_SA_DQ<20>")
	)
	(segment
		(start 302.994314 -222.657416)
		(end 302.994314 -222.564452)
		(width 0.14478)
		(layer "In13.Cu")
		(net "M_B_CPU0_SA_DQ<20>")
	)
	(segment
		(start 320.225674 -235.330238)
		(end 319.997582 -235.330238)
		(width 0.14478)
		(layer "In13.Cu")
		(net "M_B_CPU0_SA_DQ<20>")
	)
	(segment
		(start 318.444118 -234.542584)
		(end 318.82715 -234.159552)
		(width 0.14478)
		(layer "In13.Cu")
		(net "M_B_CPU0_SA_DQ<20>")
	)
	(segment
		(start 318.834516 -234.932728)
		(end 318.60617 -234.932728)
		(width 0.14478)
		(layer "In13.Cu")
		(net "M_B_CPU0_SA_DQ<20>")
	)
	(segment
		(start 319.607438 -234.93984)
		(end 319.607438 -234.712002)
		(width 0.14478)
		(layer "In13.Cu")
		(net "M_B_CPU0_SA_DQ<20>")
	)
	(segment
		(start 318.437006 -233.769662)
		(end 318.054228 -234.15244)
		(width 0.14478)
		(layer "In13.Cu")
		(net "M_B_CPU0_SA_DQ<20>")
	)
	(segment
		(start 320.395092 -236.493304)
		(end 320.166746 -236.493304)
		(width 0.14478)
		(layer "In13.Cu")
		(net "M_B_CPU0_SA_DQ<20>")
	)
	(segment
		(start 318.444118 -234.770676)
		(end 318.444118 -234.542584)
		(width 0.14478)
		(layer "In13.Cu")
		(net "M_B_CPU0_SA_DQ<20>")
	)
	(segment
		(start 318.665098 -233.769662)
		(end 318.437006 -233.769662)
		(width 0.14478)
		(layer "In13.Cu")
		(net "M_B_CPU0_SA_DQ<20>")
	)
	(segment
		(start 323.897498 -236.498384)
		(end 321.39382 -236.498384)
		(width 0.14478)
		(layer "In13.Cu")
		(net "M_B_CPU0_SA_DQ<20>")
	)
	(arc
		(start 331.708252 -238.326676)
		(mid 331.526001 -238.377026)
		(end 331.342492 -238.331502)
		(width 0.0889)
		(layer "In13.Cu")
		(net "M_B_CPU0_SA_DQ<20>")
	)
	(arc
		(start 327.563734 -238.32058)
		(mid 327.285302 -238.250482)
		(end 327.00849 -238.326676)
		(width 0.0889)
		(layer "In13.Cu")
		(net "M_B_CPU0_SA_DQ<20>")
	)
	(arc
		(start 334.154018 -238.326676)
		(mid 333.871062 -238.250499)
		(end 333.588106 -238.326676)
		(width 0.0889)
		(layer "In13.Cu")
		(net "M_B_CPU0_SA_DQ<20>")
	)
	(arc
		(start 327.94829 -238.326676)
		(mid 327.766039 -238.377026)
		(end 327.58253 -238.331502)
		(width 0.0889)
		(layer "In13.Cu")
		(net "M_B_CPU0_SA_DQ<20>")
	)
	(arc
		(start 330.394056 -238.326676)
		(mid 330.1111 -238.250499)
		(end 329.828144 -238.326676)
		(width 0.0889)
		(layer "In13.Cu")
		(net "M_B_CPU0_SA_DQ<20>")
	)
	(arc
		(start 334.519778 -238.331502)
		(mid 334.33627 -238.376996)
		(end 334.154018 -238.326676)
		(width 0.0889)
		(layer "In13.Cu")
		(net "M_B_CPU0_SA_DQ<20>")
	)
	(arc
		(start 328.88809 -238.326676)
		(mid 328.701146 -238.376931)
		(end 328.514202 -238.326676)
		(width 0.0889)
		(layer "In13.Cu")
		(net "M_B_CPU0_SA_DQ<20>")
	)
	(arc
		(start 327.00849 -238.326676)
		(mid 326.821292 -238.377058)
		(end 326.634094 -238.326676)
		(width 0.0889)
		(layer "In13.Cu")
		(net "M_B_CPU0_SA_DQ<20>")
	)
	(arc
		(start 329.819762 -238.331502)
		(mid 329.636254 -238.376996)
		(end 329.454002 -238.326676)
		(width 0.0889)
		(layer "In13.Cu")
		(net "M_B_CPU0_SA_DQ<20>")
	)
	(arc
		(start 330.768198 -238.326676)
		(mid 330.585947 -238.377026)
		(end 330.402438 -238.331502)
		(width 0.0889)
		(layer "In13.Cu")
		(net "M_B_CPU0_SA_DQ<20>")
	)
	(arc
		(start 331.33411 -238.326676)
		(mid 331.051154 -238.250499)
		(end 330.768198 -238.326676)
		(width 0.0889)
		(layer "In13.Cu")
		(net "M_B_CPU0_SA_DQ<20>")
	)
	(arc
		(start 329.454002 -238.326676)
		(mid 329.171046 -238.250499)
		(end 328.88809 -238.326676)
		(width 0.0889)
		(layer "In13.Cu")
		(net "M_B_CPU0_SA_DQ<20>")
	)
	(arc
		(start 333.213964 -238.326676)
		(mid 332.931008 -238.250499)
		(end 332.648052 -238.326676)
		(width 0.0889)
		(layer "In13.Cu")
		(net "M_B_CPU0_SA_DQ<20>")
	)
	(arc
		(start 328.514202 -238.326676)
		(mid 328.231246 -238.250499)
		(end 327.94829 -238.326676)
		(width 0.0889)
		(layer "In13.Cu")
		(net "M_B_CPU0_SA_DQ<20>")
	)
	(arc
		(start 335.094072 -238.326676)
		(mid 334.811116 -238.250499)
		(end 334.52816 -238.326676)
		(width 0.0889)
		(layer "In13.Cu")
		(net "M_B_CPU0_SA_DQ<20>")
	)
	(arc
		(start 332.274164 -238.326676)
		(mid 331.991208 -238.250499)
		(end 331.708252 -238.326676)
		(width 0.0889)
		(layer "In13.Cu")
		(net "M_B_CPU0_SA_DQ<20>")
	)
	(arc
		(start 332.648052 -238.326676)
		(mid 332.461108 -238.376931)
		(end 332.274164 -238.326676)
		(width 0.0889)
		(layer "In13.Cu")
		(net "M_B_CPU0_SA_DQ<20>")
	)
	(arc
		(start 335.412842 -238.352838)
		(mid 335.255332 -238.376036)
		(end 335.102454 -238.331502)
		(width 0.0889)
		(layer "In13.Cu")
		(net "M_B_CPU0_SA_DQ<20>")
	)
	(arc
		(start 333.579724 -238.331502)
		(mid 333.396216 -238.376996)
		(end 333.213964 -238.326676)
		(width 0.0889)
		(layer "In13.Cu")
		(net "M_B_CPU0_SA_DQ<20>")
	)
	(segment
		(start 337.158076 -226.120198)
		(end 336.691224 -225.85426)
		(width 0.10668)
		(layer "F.Cu")
		(net "M_B_CPU0_SA_DQ<1>")
	)
	(segment
		(start 328.473054 -221.18955)
		(end 328.473054 -222.000572)
		(width 0.0889)
		(layer "In13.Cu")
		(net "M_B_CPU0_SA_DQ<1>")
	)
	(segment
		(start 303.496726 -199.460104)
		(end 303.659794 -199.623172)
		(width 0.14478)
		(layer "In13.Cu")
		(net "M_B_CPU0_SA_DQ<1>")
	)
	(segment
		(start 302.024542 -199.460104)
		(end 302.383698 -199.460104)
		(width 0.14478)
		(layer "In13.Cu")
		(net "M_B_CPU0_SA_DQ<1>")
	)
	(segment
		(start 328.984102 -222.936816)
		(end 329.023218 -222.959676)
		(width 0.0889)
		(layer "In13.Cu")
		(net "M_B_CPU0_SA_DQ<1>")
	)
	(segment
		(start 302.546766 -199.623172)
		(end 302.546766 -199.690482)
		(width 0.14478)
		(layer "In13.Cu")
		(net "M_B_CPU0_SA_DQ<1>")
	)
	(segment
		(start 332.744064 -226.17684)
		(end 332.752446 -226.181666)
		(width 0.0889)
		(layer "In13.Cu")
		(net "M_B_CPU0_SA_DQ<1>")
	)
	(segment
		(start 303.10328 -199.690482)
		(end 303.10328 -199.623172)
		(width 0.14478)
		(layer "In13.Cu")
		(net "M_B_CPU0_SA_DQ<1>")
	)
	(segment
		(start 330.362306 -225.348546)
		(end 330.394056 -225.366834)
		(width 0.0889)
		(layer "In13.Cu")
		(net "M_B_CPU0_SA_DQ<1>")
	)
	(segment
		(start 307.329586 -200.248774)
		(end 307.474366 -200.103994)
		(width 0.14478)
		(layer "In13.Cu")
		(net "M_B_CPU0_SA_DQ<1>")
	)
	(segment
		(start 336.822796 -226.203002)
		(end 336.845148 -226.11969)
		(width 0.0889)
		(layer "In13.Cu")
		(net "M_B_CPU0_SA_DQ<1>")
	)
	(segment
		(start 306.778406 -199.460104)
		(end 306.923186 -199.604884)
		(width 0.14478)
		(layer "In13.Cu")
		(net "M_B_CPU0_SA_DQ<1>")
	)
	(segment
		(start 307.067966 -200.248774)
		(end 307.329586 -200.248774)
		(width 0.14478)
		(layer "In13.Cu")
		(net "M_B_CPU0_SA_DQ<1>")
	)
	(segment
		(start 328.954638 -222.919798)
		(end 328.984102 -222.936816)
		(width 0.0889)
		(layer "In13.Cu")
		(net "M_B_CPU0_SA_DQ<1>")
	)
	(segment
		(start 302.383698 -199.460104)
		(end 302.546766 -199.623172)
		(width 0.14478)
		(layer "In13.Cu")
		(net "M_B_CPU0_SA_DQ<1>")
	)
	(segment
		(start 329.423522 -223.729042)
		(end 329.454002 -223.746822)
		(width 0.0889)
		(layer "In13.Cu")
		(net "M_B_CPU0_SA_DQ<1>")
	)
	(segment
		(start 302.709834 -199.85355)
		(end 302.940212 -199.85355)
		(width 0.14478)
		(layer "In13.Cu")
		(net "M_B_CPU0_SA_DQ<1>")
	)
	(segment
		(start 307.474366 -199.604884)
		(end 307.619146 -199.460104)
		(width 0.14478)
		(layer "In13.Cu")
		(net "M_B_CPU0_SA_DQ<1>")
	)
	(segment
		(start 302.940212 -199.85355)
		(end 303.10328 -199.690482)
		(width 0.14478)
		(layer "In13.Cu")
		(net "M_B_CPU0_SA_DQ<1>")
	)
	(segment
		(start 307.474366 -200.103994)
		(end 307.474366 -199.604884)
		(width 0.14478)
		(layer "In13.Cu")
		(net "M_B_CPU0_SA_DQ<1>")
	)
	(segment
		(start 302.546766 -199.690482)
		(end 302.709834 -199.85355)
		(width 0.14478)
		(layer "In13.Cu")
		(net "M_B_CPU0_SA_DQ<1>")
	)
	(segment
		(start 303.10328 -199.623172)
		(end 303.266348 -199.460104)
		(width 0.14478)
		(layer "In13.Cu")
		(net "M_B_CPU0_SA_DQ<1>")
	)
	(segment
		(start 303.659794 -199.690482)
		(end 303.822862 -199.85355)
		(width 0.14478)
		(layer "In13.Cu")
		(net "M_B_CPU0_SA_DQ<1>")
	)
	(segment
		(start 336.845148 -226.11969)
		(end 336.691224 -225.85426)
		(width 0.0889)
		(layer "In13.Cu")
		(net "M_B_CPU0_SA_DQ<1>")
	)
	(segment
		(start 308.11216 -199.460104)
		(end 328.473054 -219.820998)
		(width 0.14478)
		(layer "In13.Cu")
		(net "M_B_CPU0_SA_DQ<1>")
	)
	(segment
		(start 330.833476 -226.15906)
		(end 330.863956 -226.17684)
		(width 0.0889)
		(layer "In13.Cu")
		(net "M_B_CPU0_SA_DQ<1>")
	)
	(segment
		(start 304.05324 -199.85355)
		(end 304.216308 -199.690482)
		(width 0.14478)
		(layer "In13.Cu")
		(net "M_B_CPU0_SA_DQ<1>")
	)
	(segment
		(start 333.684118 -226.17684)
		(end 333.6925 -226.181666)
		(width 0.0889)
		(layer "In13.Cu")
		(net "M_B_CPU0_SA_DQ<1>")
	)
	(segment
		(start 330.394056 -225.366834)
		(end 330.433172 -225.389694)
		(width 0.0889)
		(layer "In13.Cu")
		(net "M_B_CPU0_SA_DQ<1>")
	)
	(segment
		(start 306.923186 -200.103994)
		(end 307.067966 -200.248774)
		(width 0.14478)
		(layer "In13.Cu")
		(net "M_B_CPU0_SA_DQ<1>")
	)
	(segment
		(start 332.16977 -226.181666)
		(end 332.178152 -226.17684)
		(width 0.0889)
		(layer "In13.Cu")
		(net "M_B_CPU0_SA_DQ<1>")
	)
	(segment
		(start 307.619146 -199.460104)
		(end 308.11216 -199.460104)
		(width 0.14478)
		(layer "In13.Cu")
		(net "M_B_CPU0_SA_DQ<1>")
	)
	(segment
		(start 328.473054 -219.820998)
		(end 328.473054 -221.18955)
		(width 0.14478)
		(layer "In13.Cu")
		(net "M_B_CPU0_SA_DQ<1>")
	)
	(segment
		(start 304.216308 -199.690482)
		(end 304.216308 -199.623172)
		(width 0.14478)
		(layer "In13.Cu")
		(net "M_B_CPU0_SA_DQ<1>")
	)
	(segment
		(start 335.929732 -226.181666)
		(end 335.938114 -226.17684)
		(width 0.0889)
		(layer "In13.Cu")
		(net "M_B_CPU0_SA_DQ<1>")
	)
	(segment
		(start 329.892406 -224.53854)
		(end 329.924156 -224.556828)
		(width 0.0889)
		(layer "In13.Cu")
		(net "M_B_CPU0_SA_DQ<1>")
	)
	(segment
		(start 303.659794 -199.623172)
		(end 303.659794 -199.690482)
		(width 0.14478)
		(layer "In13.Cu")
		(net "M_B_CPU0_SA_DQ<1>")
	)
	(segment
		(start 303.266348 -199.460104)
		(end 303.496726 -199.460104)
		(width 0.14478)
		(layer "In13.Cu")
		(net "M_B_CPU0_SA_DQ<1>")
	)
	(segment
		(start 331.229716 -226.181666)
		(end 331.238098 -226.17684)
		(width 0.0889)
		(layer "In13.Cu")
		(net "M_B_CPU0_SA_DQ<1>")
	)
	(segment
		(start 304.379376 -199.460104)
		(end 306.778406 -199.460104)
		(width 0.14478)
		(layer "In13.Cu")
		(net "M_B_CPU0_SA_DQ<1>")
	)
	(segment
		(start 304.216308 -199.623172)
		(end 304.379376 -199.460104)
		(width 0.14478)
		(layer "In13.Cu")
		(net "M_B_CPU0_SA_DQ<1>")
	)
	(segment
		(start 301.174658 -198.61022)
		(end 302.024542 -199.460104)
		(width 0.14478)
		(layer "In13.Cu")
		(net "M_B_CPU0_SA_DQ<1>")
	)
	(segment
		(start 306.923186 -199.604884)
		(end 306.923186 -200.103994)
		(width 0.14478)
		(layer "In13.Cu")
		(net "M_B_CPU0_SA_DQ<1>")
	)
	(segment
		(start 329.454002 -223.746822)
		(end 329.493118 -223.769682)
		(width 0.0889)
		(layer "In13.Cu")
		(net "M_B_CPU0_SA_DQ<1>")
	)
	(segment
		(start 329.924156 -224.556828)
		(end 329.960478 -224.57791)
		(width 0.0889)
		(layer "In13.Cu")
		(net "M_B_CPU0_SA_DQ<1>")
	)
	(segment
		(start 299.82414 -198.755254)
		(end 299.969174 -198.61022)
		(width 0.14478)
		(layer "In13.Cu")
		(net "M_B_CPU0_SA_DQ<1>")
	)
	(segment
		(start 299.82414 -199.035162)
		(end 299.82414 -198.755254)
		(width 0.14478)
		(layer "In13.Cu")
		(net "M_B_CPU0_SA_DQ<1>")
	)
	(segment
		(start 299.969174 -198.61022)
		(end 301.174658 -198.61022)
		(width 0.14478)
		(layer "In13.Cu")
		(net "M_B_CPU0_SA_DQ<1>")
	)
	(segment
		(start 303.822862 -199.85355)
		(end 304.05324 -199.85355)
		(width 0.14478)
		(layer "In13.Cu")
		(net "M_B_CPU0_SA_DQ<1>")
	)
	(arc
		(start 332.178152 -226.17684)
		(mid 332.461108 -226.100663)
		(end 332.744064 -226.17684)
		(width 0.0889)
		(layer "In13.Cu")
		(net "M_B_CPU0_SA_DQ<1>")
	)
	(arc
		(start 329.73645 -224.234248)
		(mid 329.777705 -224.405219)
		(end 329.892406 -224.53854)
		(width 0.0889)
		(layer "In13.Cu")
		(net "M_B_CPU0_SA_DQ<1>")
	)
	(arc
		(start 330.20635 -225.044254)
		(mid 330.247605 -225.215225)
		(end 330.362306 -225.348546)
		(width 0.0889)
		(layer "In13.Cu")
		(net "M_B_CPU0_SA_DQ<1>")
	)
	(arc
		(start 329.493118 -223.769682)
		(mid 329.671931 -223.972032)
		(end 329.73645 -224.234248)
		(width 0.0889)
		(layer "In13.Cu")
		(net "M_B_CPU0_SA_DQ<1>")
	)
	(arc
		(start 335.563972 -226.17684)
		(mid 335.746223 -226.22719)
		(end 335.929732 -226.181666)
		(width 0.0889)
		(layer "In13.Cu")
		(net "M_B_CPU0_SA_DQ<1>")
	)
	(arc
		(start 328.473054 -222.000572)
		(mid 328.49367 -222.083863)
		(end 328.550778 -222.147892)
		(width 0.0889)
		(layer "In13.Cu")
		(net "M_B_CPU0_SA_DQ<1>")
	)
	(arc
		(start 330.676504 -225.85426)
		(mid 330.718053 -226.025682)
		(end 330.833476 -226.15906)
		(width 0.0889)
		(layer "In13.Cu")
		(net "M_B_CPU0_SA_DQ<1>")
	)
	(arc
		(start 329.960478 -224.57791)
		(mid 330.14113 -224.780655)
		(end 330.20635 -225.044254)
		(width 0.0889)
		(layer "In13.Cu")
		(net "M_B_CPU0_SA_DQ<1>")
	)
	(arc
		(start 328.550778 -222.147892)
		(mid 328.73143 -222.350637)
		(end 328.79665 -222.614236)
		(width 0.0889)
		(layer "In13.Cu")
		(net "M_B_CPU0_SA_DQ<1>")
	)
	(arc
		(start 334.05826 -226.17684)
		(mid 334.341216 -226.100663)
		(end 334.624172 -226.17684)
		(width 0.0889)
		(layer "In13.Cu")
		(net "M_B_CPU0_SA_DQ<1>")
	)
	(arc
		(start 333.6925 -226.181666)
		(mid 333.876008 -226.22716)
		(end 334.05826 -226.17684)
		(width 0.0889)
		(layer "In13.Cu")
		(net "M_B_CPU0_SA_DQ<1>")
	)
	(arc
		(start 334.624172 -226.17684)
		(mid 334.811116 -226.227095)
		(end 334.99806 -226.17684)
		(width 0.0889)
		(layer "In13.Cu")
		(net "M_B_CPU0_SA_DQ<1>")
	)
	(arc
		(start 335.938114 -226.17684)
		(mid 336.22107 -226.100663)
		(end 336.504026 -226.17684)
		(width 0.0889)
		(layer "In13.Cu")
		(net "M_B_CPU0_SA_DQ<1>")
	)
	(arc
		(start 331.238098 -226.17684)
		(mid 331.521054 -226.100663)
		(end 331.80401 -226.17684)
		(width 0.0889)
		(layer "In13.Cu")
		(net "M_B_CPU0_SA_DQ<1>")
	)
	(arc
		(start 331.80401 -226.17684)
		(mid 331.986261 -226.22719)
		(end 332.16977 -226.181666)
		(width 0.0889)
		(layer "In13.Cu")
		(net "M_B_CPU0_SA_DQ<1>")
	)
	(arc
		(start 330.433172 -225.389694)
		(mid 330.611985 -225.592044)
		(end 330.676504 -225.85426)
		(width 0.0889)
		(layer "In13.Cu")
		(net "M_B_CPU0_SA_DQ<1>")
	)
	(arc
		(start 329.26655 -223.424242)
		(mid 329.308099 -223.595664)
		(end 329.423522 -223.729042)
		(width 0.0889)
		(layer "In13.Cu")
		(net "M_B_CPU0_SA_DQ<1>")
	)
	(arc
		(start 336.504026 -226.17684)
		(mid 336.660464 -226.225811)
		(end 336.822796 -226.203002)
		(width 0.0889)
		(layer "In13.Cu")
		(net "M_B_CPU0_SA_DQ<1>")
	)
	(arc
		(start 328.79665 -222.614236)
		(mid 328.83849 -222.786222)
		(end 328.954638 -222.919798)
		(width 0.0889)
		(layer "In13.Cu")
		(net "M_B_CPU0_SA_DQ<1>")
	)
	(arc
		(start 329.023218 -222.959676)
		(mid 329.202031 -223.162026)
		(end 329.26655 -223.424242)
		(width 0.0889)
		(layer "In13.Cu")
		(net "M_B_CPU0_SA_DQ<1>")
	)
	(arc
		(start 333.118206 -226.17684)
		(mid 333.401162 -226.100663)
		(end 333.684118 -226.17684)
		(width 0.0889)
		(layer "In13.Cu")
		(net "M_B_CPU0_SA_DQ<1>")
	)
	(arc
		(start 332.752446 -226.181666)
		(mid 332.935954 -226.22716)
		(end 333.118206 -226.17684)
		(width 0.0889)
		(layer "In13.Cu")
		(net "M_B_CPU0_SA_DQ<1>")
	)
	(arc
		(start 334.99806 -226.17684)
		(mid 335.281016 -226.100663)
		(end 335.563972 -226.17684)
		(width 0.0889)
		(layer "In13.Cu")
		(net "M_B_CPU0_SA_DQ<1>")
	)
	(arc
		(start 330.863956 -226.17684)
		(mid 331.046207 -226.22719)
		(end 331.229716 -226.181666)
		(width 0.0889)
		(layer "In13.Cu")
		(net "M_B_CPU0_SA_DQ<1>")
	)
	(segment
		(start 337.627976 -236.650022)
		(end 337.161124 -236.384084)
		(width 0.10668)
		(layer "F.Cu")
		(net "M_B_CPU0_SA_DQ<19>")
	)
	(segment
		(start 297.978068 -218.15044)
		(end 296.928794 -218.585034)
		(width 0.14478)
		(layer "In13.Cu")
		(net "M_B_CPU0_SA_DQ<19>")
	)
	(segment
		(start 331.342492 -236.056678)
		(end 331.33411 -236.061504)
		(width 0.0889)
		(layer "In13.Cu")
		(net "M_B_CPU0_SA_DQ<19>")
	)
	(segment
		(start 336.042508 -236.056678)
		(end 336.034126 -236.061504)
		(width 0.0889)
		(layer "In13.Cu")
		(net "M_B_CPU0_SA_DQ<19>")
	)
	(segment
		(start 322.291456 -234.159044)
		(end 315.749178 -227.616766)
		(width 0.14478)
		(layer "In13.Cu")
		(net "M_B_CPU0_SA_DQ<19>")
	)
	(segment
		(start 327.94829 -236.061504)
		(end 327.939908 -236.056678)
		(width 0.0889)
		(layer "In13.Cu")
		(net "M_B_CPU0_SA_DQ<19>")
	)
	(segment
		(start 330.402438 -236.056678)
		(end 330.394056 -236.061504)
		(width 0.0889)
		(layer "In13.Cu")
		(net "M_B_CPU0_SA_DQ<19>")
	)
	(segment
		(start 329.828144 -236.061504)
		(end 329.819762 -236.056678)
		(width 0.0889)
		(layer "In13.Cu")
		(net "M_B_CPU0_SA_DQ<19>")
	)
	(segment
		(start 324.408038 -234.502452)
		(end 324.06463 -234.159044)
		(width 0.0889)
		(layer "In13.Cu")
		(net "M_B_CPU0_SA_DQ<19>")
	)
	(segment
		(start 301.035212 -219.01023)
		(end 298.95927 -218.15044)
		(width 0.14478)
		(layer "In13.Cu")
		(net "M_B_CPU0_SA_DQ<19>")
	)
	(segment
		(start 323.879718 -234.159044)
		(end 322.291456 -234.159044)
		(width 0.14478)
		(layer "In13.Cu")
		(net "M_B_CPU0_SA_DQ<19>")
	)
	(segment
		(start 333.588106 -236.061504)
		(end 333.579724 -236.056678)
		(width 0.0889)
		(layer "In13.Cu")
		(net "M_B_CPU0_SA_DQ<19>")
	)
	(segment
		(start 337.0072 -236.118654)
		(end 336.911188 -236.093254)
		(width 0.0889)
		(layer "In13.Cu")
		(net "M_B_CPU0_SA_DQ<19>")
	)
	(segment
		(start 325.266558 -234.868212)
		(end 324.900798 -234.502452)
		(width 0.0889)
		(layer "In13.Cu")
		(net "M_B_CPU0_SA_DQ<19>")
	)
	(segment
		(start 306.337462 -219.01023)
		(end 301.035212 -219.01023)
		(width 0.14478)
		(layer "In13.Cu")
		(net "M_B_CPU0_SA_DQ<19>")
	)
	(segment
		(start 326.119744 -236.137958)
		(end 325.266558 -235.284772)
		(width 0.0889)
		(layer "In13.Cu")
		(net "M_B_CPU0_SA_DQ<19>")
	)
	(segment
		(start 298.95927 -218.15044)
		(end 297.978068 -218.15044)
		(width 0.14478)
		(layer "In13.Cu")
		(net "M_B_CPU0_SA_DQ<19>")
	)
	(segment
		(start 296.928794 -218.585034)
		(end 295.724072 -218.585034)
		(width 0.14478)
		(layer "In13.Cu")
		(net "M_B_CPU0_SA_DQ<19>")
	)
	(segment
		(start 337.161124 -236.384084)
		(end 337.0072 -236.118654)
		(width 0.0889)
		(layer "In13.Cu")
		(net "M_B_CPU0_SA_DQ<19>")
	)
	(segment
		(start 324.06463 -234.159044)
		(end 323.879718 -234.159044)
		(width 0.0889)
		(layer "In13.Cu")
		(net "M_B_CPU0_SA_DQ<19>")
	)
	(segment
		(start 325.266558 -235.284772)
		(end 325.266558 -234.868212)
		(width 0.0889)
		(layer "In13.Cu")
		(net "M_B_CPU0_SA_DQ<19>")
	)
	(segment
		(start 334.52816 -236.061504)
		(end 334.519778 -236.056678)
		(width 0.0889)
		(layer "In13.Cu")
		(net "M_B_CPU0_SA_DQ<19>")
	)
	(segment
		(start 310.500522 -220.734636)
		(end 306.337462 -219.01023)
		(width 0.14478)
		(layer "In13.Cu")
		(net "M_B_CPU0_SA_DQ<19>")
	)
	(segment
		(start 324.900798 -234.502452)
		(end 324.408038 -234.502452)
		(width 0.0889)
		(layer "In13.Cu")
		(net "M_B_CPU0_SA_DQ<19>")
	)
	(segment
		(start 327.290176 -236.137958)
		(end 326.119744 -236.137958)
		(width 0.0889)
		(layer "In13.Cu")
		(net "M_B_CPU0_SA_DQ<19>")
	)
	(segment
		(start 315.749178 -225.983292)
		(end 310.500522 -220.734636)
		(width 0.14478)
		(layer "In13.Cu")
		(net "M_B_CPU0_SA_DQ<19>")
	)
	(segment
		(start 335.102454 -236.056678)
		(end 335.094072 -236.061504)
		(width 0.0889)
		(layer "In13.Cu")
		(net "M_B_CPU0_SA_DQ<19>")
	)
	(segment
		(start 315.749178 -227.616766)
		(end 315.749178 -225.983292)
		(width 0.14478)
		(layer "In13.Cu")
		(net "M_B_CPU0_SA_DQ<19>")
	)
	(arc
		(start 336.034126 -236.061504)
		(mid 335.75117 -236.137681)
		(end 335.468214 -236.061504)
		(width 0.0889)
		(layer "In13.Cu")
		(net "M_B_CPU0_SA_DQ<19>")
	)
	(arc
		(start 330.768198 -236.061504)
		(mid 330.585947 -236.011154)
		(end 330.402438 -236.056678)
		(width 0.0889)
		(layer "In13.Cu")
		(net "M_B_CPU0_SA_DQ<19>")
	)
	(arc
		(start 329.454002 -236.061504)
		(mid 329.171046 -236.137681)
		(end 328.88809 -236.061504)
		(width 0.0889)
		(layer "In13.Cu")
		(net "M_B_CPU0_SA_DQ<19>")
	)
	(arc
		(start 334.519778 -236.056678)
		(mid 334.33627 -236.011184)
		(end 334.154018 -236.061504)
		(width 0.0889)
		(layer "In13.Cu")
		(net "M_B_CPU0_SA_DQ<19>")
	)
	(arc
		(start 329.819762 -236.056678)
		(mid 329.636254 -236.011184)
		(end 329.454002 -236.061504)
		(width 0.0889)
		(layer "In13.Cu")
		(net "M_B_CPU0_SA_DQ<19>")
	)
	(arc
		(start 330.394056 -236.061504)
		(mid 330.1111 -236.137681)
		(end 329.828144 -236.061504)
		(width 0.0889)
		(layer "In13.Cu")
		(net "M_B_CPU0_SA_DQ<19>")
	)
	(arc
		(start 333.213964 -236.061504)
		(mid 332.931008 -236.137681)
		(end 332.648052 -236.061504)
		(width 0.0889)
		(layer "In13.Cu")
		(net "M_B_CPU0_SA_DQ<19>")
	)
	(arc
		(start 332.274164 -236.061504)
		(mid 331.991208 -236.137681)
		(end 331.708252 -236.061504)
		(width 0.0889)
		(layer "In13.Cu")
		(net "M_B_CPU0_SA_DQ<19>")
	)
	(arc
		(start 327.939908 -236.056678)
		(mid 327.756146 -236.011062)
		(end 327.57364 -236.061504)
		(width 0.0889)
		(layer "In13.Cu")
		(net "M_B_CPU0_SA_DQ<19>")
	)
	(arc
		(start 334.154018 -236.061504)
		(mid 333.871062 -236.137681)
		(end 333.588106 -236.061504)
		(width 0.0889)
		(layer "In13.Cu")
		(net "M_B_CPU0_SA_DQ<19>")
	)
	(arc
		(start 328.88809 -236.061504)
		(mid 328.701146 -236.011249)
		(end 328.514202 -236.061504)
		(width 0.0889)
		(layer "In13.Cu")
		(net "M_B_CPU0_SA_DQ<19>")
	)
	(arc
		(start 333.579724 -236.056678)
		(mid 333.396216 -236.011184)
		(end 333.213964 -236.061504)
		(width 0.0889)
		(layer "In13.Cu")
		(net "M_B_CPU0_SA_DQ<19>")
	)
	(arc
		(start 336.408268 -236.061504)
		(mid 336.226017 -236.011154)
		(end 336.042508 -236.056678)
		(width 0.0889)
		(layer "In13.Cu")
		(net "M_B_CPU0_SA_DQ<19>")
	)
	(arc
		(start 335.468214 -236.061504)
		(mid 335.285963 -236.011154)
		(end 335.102454 -236.056678)
		(width 0.0889)
		(layer "In13.Cu")
		(net "M_B_CPU0_SA_DQ<19>")
	)
	(arc
		(start 336.911188 -236.093254)
		(mid 336.65598 -236.136731)
		(end 336.408268 -236.061504)
		(width 0.0889)
		(layer "In13.Cu")
		(net "M_B_CPU0_SA_DQ<19>")
	)
	(arc
		(start 331.708252 -236.061504)
		(mid 331.526001 -236.011154)
		(end 331.342492 -236.056678)
		(width 0.0889)
		(layer "In13.Cu")
		(net "M_B_CPU0_SA_DQ<19>")
	)
	(arc
		(start 331.33411 -236.061504)
		(mid 331.051154 -236.137681)
		(end 330.768198 -236.061504)
		(width 0.0889)
		(layer "In13.Cu")
		(net "M_B_CPU0_SA_DQ<19>")
	)
	(arc
		(start 328.514202 -236.061504)
		(mid 328.231246 -236.137681)
		(end 327.94829 -236.061504)
		(width 0.0889)
		(layer "In13.Cu")
		(net "M_B_CPU0_SA_DQ<19>")
	)
	(arc
		(start 335.094072 -236.061504)
		(mid 334.811116 -236.137681)
		(end 334.52816 -236.061504)
		(width 0.0889)
		(layer "In13.Cu")
		(net "M_B_CPU0_SA_DQ<19>")
	)
	(arc
		(start 327.57364 -236.061504)
		(mid 327.436965 -236.118467)
		(end 327.290176 -236.137958)
		(width 0.0889)
		(layer "In13.Cu")
		(net "M_B_CPU0_SA_DQ<19>")
	)
	(arc
		(start 332.648052 -236.061504)
		(mid 332.461108 -236.011249)
		(end 332.274164 -236.061504)
		(width 0.0889)
		(layer "In13.Cu")
		(net "M_B_CPU0_SA_DQ<19>")
	)
	(segment
		(start 336.218022 -235.840016)
		(end 335.75117 -235.574078)
		(width 0.10668)
		(layer "F.Cu")
		(net "M_B_CPU0_SA_DQ<18>")
	)
	(segment
		(start 297.73753 -216.885012)
		(end 295.724072 -216.885012)
		(width 0.14478)
		(layer "In13.Cu")
		(net "M_B_CPU0_SA_DQ<18>")
	)
	(segment
		(start 302.04664 -217.310208)
		(end 301.196502 -216.46007)
		(width 0.14478)
		(layer "In13.Cu")
		(net "M_B_CPU0_SA_DQ<18>")
	)
	(segment
		(start 327.50125 -235.264198)
		(end 327.47966 -235.251752)
		(width 0.0889)
		(layer "In13.Cu")
		(net "M_B_CPU0_SA_DQ<18>")
	)
	(segment
		(start 332.752446 -235.246672)
		(end 332.744064 -235.251498)
		(width 0.0889)
		(layer "In13.Cu")
		(net "M_B_CPU0_SA_DQ<18>")
	)
	(segment
		(start 298.162472 -216.46007)
		(end 297.73753 -216.885012)
		(width 0.14478)
		(layer "In13.Cu")
		(net "M_B_CPU0_SA_DQ<18>")
	)
	(segment
		(start 306.353718 -217.310208)
		(end 302.04664 -217.310208)
		(width 0.14478)
		(layer "In13.Cu")
		(net "M_B_CPU0_SA_DQ<18>")
	)
	(segment
		(start 301.196502 -216.46007)
		(end 298.162472 -216.46007)
		(width 0.14478)
		(layer "In13.Cu")
		(net "M_B_CPU0_SA_DQ<18>")
	)
	(segment
		(start 335.75117 -235.574078)
		(end 335.596992 -235.308648)
		(width 0.0889)
		(layer "In13.Cu")
		(net "M_B_CPU0_SA_DQ<18>")
	)
	(segment
		(start 328.41819 -235.251498)
		(end 328.409808 -235.246672)
		(width 0.0889)
		(layer "In13.Cu")
		(net "M_B_CPU0_SA_DQ<18>")
	)
	(segment
		(start 333.6925 -235.246672)
		(end 333.684118 -235.251498)
		(width 0.0889)
		(layer "In13.Cu")
		(net "M_B_CPU0_SA_DQ<18>")
	)
	(segment
		(start 323.867018 -233.247184)
		(end 322.651628 -233.247184)
		(width 0.14478)
		(layer "In13.Cu")
		(net "M_B_CPU0_SA_DQ<18>")
	)
	(segment
		(start 325.203058 -233.918252)
		(end 324.722998 -233.918252)
		(width 0.0889)
		(layer "In13.Cu")
		(net "M_B_CPU0_SA_DQ<18>")
	)
	(segment
		(start 324.05193 -233.247184)
		(end 323.867018 -233.247184)
		(width 0.0889)
		(layer "In13.Cu")
		(net "M_B_CPU0_SA_DQ<18>")
	)
	(segment
		(start 326.894444 -235.215938)
		(end 326.292718 -234.614212)
		(width 0.0889)
		(layer "In13.Cu")
		(net "M_B_CPU0_SA_DQ<18>")
	)
	(segment
		(start 326.292718 -234.614212)
		(end 325.899018 -234.614212)
		(width 0.0889)
		(layer "In13.Cu")
		(net "M_B_CPU0_SA_DQ<18>")
	)
	(segment
		(start 328.992484 -235.246672)
		(end 328.984102 -235.251498)
		(width 0.0889)
		(layer "In13.Cu")
		(net "M_B_CPU0_SA_DQ<18>")
	)
	(segment
		(start 309.814214 -218.74353)
		(end 306.353718 -217.310208)
		(width 0.14478)
		(layer "In13.Cu")
		(net "M_B_CPU0_SA_DQ<18>")
	)
	(segment
		(start 332.178152 -235.251498)
		(end 332.16977 -235.246672)
		(width 0.0889)
		(layer "In13.Cu")
		(net "M_B_CPU0_SA_DQ<18>")
	)
	(segment
		(start 324.722998 -233.918252)
		(end 324.05193 -233.247184)
		(width 0.0889)
		(layer "In13.Cu")
		(net "M_B_CPU0_SA_DQ<18>")
	)
	(segment
		(start 316.676278 -225.605594)
		(end 309.814214 -218.74353)
		(width 0.14478)
		(layer "In13.Cu")
		(net "M_B_CPU0_SA_DQ<18>")
	)
	(segment
		(start 316.676278 -227.271834)
		(end 316.676278 -225.605594)
		(width 0.14478)
		(layer "In13.Cu")
		(net "M_B_CPU0_SA_DQ<18>")
	)
	(segment
		(start 325.899018 -234.614212)
		(end 325.203058 -233.918252)
		(width 0.0889)
		(layer "In13.Cu")
		(net "M_B_CPU0_SA_DQ<18>")
	)
	(segment
		(start 331.238098 -235.251498)
		(end 331.229716 -235.246672)
		(width 0.0889)
		(layer "In13.Cu")
		(net "M_B_CPU0_SA_DQ<18>")
	)
	(segment
		(start 327.395078 -235.215938)
		(end 326.894444 -235.215938)
		(width 0.0889)
		(layer "In13.Cu")
		(net "M_B_CPU0_SA_DQ<18>")
	)
	(segment
		(start 322.651628 -233.247184)
		(end 316.676278 -227.271834)
		(width 0.14478)
		(layer "In13.Cu")
		(net "M_B_CPU0_SA_DQ<18>")
	)
	(segment
		(start 335.596992 -235.308648)
		(end 335.500726 -235.283248)
		(width 0.0889)
		(layer "In13.Cu")
		(net "M_B_CPU0_SA_DQ<18>")
	)
	(arc
		(start 330.298044 -235.251498)
		(mid 330.1111 -235.201243)
		(end 329.924156 -235.251498)
		(width 0.0889)
		(layer "In13.Cu")
		(net "M_B_CPU0_SA_DQ<18>")
	)
	(arc
		(start 335.500726 -235.283248)
		(mid 335.245661 -235.326599)
		(end 334.99806 -235.251498)
		(width 0.0889)
		(layer "In13.Cu")
		(net "M_B_CPU0_SA_DQ<18>")
	)
	(arc
		(start 334.624172 -235.251498)
		(mid 334.341216 -235.327675)
		(end 334.05826 -235.251498)
		(width 0.0889)
		(layer "In13.Cu")
		(net "M_B_CPU0_SA_DQ<18>")
	)
	(arc
		(start 330.863956 -235.251498)
		(mid 330.581 -235.327675)
		(end 330.298044 -235.251498)
		(width 0.0889)
		(layer "In13.Cu")
		(net "M_B_CPU0_SA_DQ<18>")
	)
	(arc
		(start 328.409808 -235.246672)
		(mid 328.2263 -235.201178)
		(end 328.044048 -235.251498)
		(width 0.0889)
		(layer "In13.Cu")
		(net "M_B_CPU0_SA_DQ<18>")
	)
	(arc
		(start 329.924156 -235.251498)
		(mid 329.6412 -235.327675)
		(end 329.358244 -235.251498)
		(width 0.0889)
		(layer "In13.Cu")
		(net "M_B_CPU0_SA_DQ<18>")
	)
	(arc
		(start 327.47966 -235.251752)
		(mid 327.438476 -235.231231)
		(end 327.395078 -235.215938)
		(width 0.0889)
		(layer "In13.Cu")
		(net "M_B_CPU0_SA_DQ<18>")
	)
	(arc
		(start 333.118206 -235.251498)
		(mid 332.935955 -235.201148)
		(end 332.752446 -235.246672)
		(width 0.0889)
		(layer "In13.Cu")
		(net "M_B_CPU0_SA_DQ<18>")
	)
	(arc
		(start 328.984102 -235.251498)
		(mid 328.701146 -235.327675)
		(end 328.41819 -235.251498)
		(width 0.0889)
		(layer "In13.Cu")
		(net "M_B_CPU0_SA_DQ<18>")
	)
	(arc
		(start 334.99806 -235.251498)
		(mid 334.811116 -235.201243)
		(end 334.624172 -235.251498)
		(width 0.0889)
		(layer "In13.Cu")
		(net "M_B_CPU0_SA_DQ<18>")
	)
	(arc
		(start 333.684118 -235.251498)
		(mid 333.401162 -235.327675)
		(end 333.118206 -235.251498)
		(width 0.0889)
		(layer "In13.Cu")
		(net "M_B_CPU0_SA_DQ<18>")
	)
	(arc
		(start 334.05826 -235.251498)
		(mid 333.876009 -235.201148)
		(end 333.6925 -235.246672)
		(width 0.0889)
		(layer "In13.Cu")
		(net "M_B_CPU0_SA_DQ<18>")
	)
	(arc
		(start 331.229716 -235.246672)
		(mid 331.046208 -235.201178)
		(end 330.863956 -235.251498)
		(width 0.0889)
		(layer "In13.Cu")
		(net "M_B_CPU0_SA_DQ<18>")
	)
	(arc
		(start 331.80401 -235.251498)
		(mid 331.521054 -235.327675)
		(end 331.238098 -235.251498)
		(width 0.0889)
		(layer "In13.Cu")
		(net "M_B_CPU0_SA_DQ<18>")
	)
	(arc
		(start 332.16977 -235.246672)
		(mid 331.986262 -235.201178)
		(end 331.80401 -235.251498)
		(width 0.0889)
		(layer "In13.Cu")
		(net "M_B_CPU0_SA_DQ<18>")
	)
	(arc
		(start 329.358244 -235.251498)
		(mid 329.175993 -235.201148)
		(end 328.992484 -235.246672)
		(width 0.0889)
		(layer "In13.Cu")
		(net "M_B_CPU0_SA_DQ<18>")
	)
	(arc
		(start 328.044048 -235.251498)
		(mid 327.774279 -235.327521)
		(end 327.50125 -235.264198)
		(width 0.0889)
		(layer "In13.Cu")
		(net "M_B_CPU0_SA_DQ<18>")
	)
	(arc
		(start 332.744064 -235.251498)
		(mid 332.461108 -235.327675)
		(end 332.178152 -235.251498)
		(width 0.0889)
		(layer "In13.Cu")
		(net "M_B_CPU0_SA_DQ<18>")
	)
	(segment
		(start 337.158076 -235.840016)
		(end 336.691224 -235.574078)
		(width 0.10668)
		(layer "F.Cu")
		(net "M_B_CPU0_SA_DQ<17>")
	)
	(segment
		(start 308.745128 -219.12326)
		(end 308.808374 -218.970606)
		(width 0.14478)
		(layer "In13.Cu")
		(net "M_B_CPU0_SA_DQ<17>")
	)
	(segment
		(start 332.16977 -235.901484)
		(end 332.178152 -235.896658)
		(width 0.0889)
		(layer "In13.Cu")
		(net "M_B_CPU0_SA_DQ<17>")
	)
	(segment
		(start 310.342788 -219.940886)
		(end 316.221618 -225.819716)
		(width 0.14478)
		(layer "In13.Cu")
		(net "M_B_CPU0_SA_DQ<17>")
	)
	(segment
		(start 309.317644 -219.18168)
		(end 309.254398 -219.334334)
		(width 0.14478)
		(layer "In13.Cu")
		(net "M_B_CPU0_SA_DQ<17>")
	)
	(segment
		(start 336.845148 -235.839508)
		(end 336.691224 -235.574078)
		(width 0.0889)
		(layer "In13.Cu")
		(net "M_B_CPU0_SA_DQ<17>")
	)
	(segment
		(start 304.666142 -218.160092)
		(end 306.043838 -218.160092)
		(width 0.14478)
		(layer "In13.Cu")
		(net "M_B_CPU0_SA_DQ<17>")
	)
	(segment
		(start 308.31409 -219.101162)
		(end 308.556152 -219.201492)
		(width 0.14478)
		(layer "In13.Cu")
		(net "M_B_CPU0_SA_DQ<17>")
	)
	(segment
		(start 309.33263 -219.523056)
		(end 310.342788 -219.940886)
		(width 0.14478)
		(layer "In13.Cu")
		(net "M_B_CPU0_SA_DQ<17>")
	)
	(segment
		(start 307.217318 -218.490038)
		(end 307.29555 -218.679014)
		(width 0.14478)
		(layer "In13.Cu")
		(net "M_B_CPU0_SA_DQ<17>")
	)
	(segment
		(start 302.833532 -218.389962)
		(end 302.9966 -218.55303)
		(width 0.14478)
		(layer "In13.Cu")
		(net "M_B_CPU0_SA_DQ<17>")
	)
	(segment
		(start 336.822796 -235.92282)
		(end 336.845148 -235.839508)
		(width 0.0889)
		(layer "In13.Cu")
		(net "M_B_CPU0_SA_DQ<17>")
	)
	(segment
		(start 316.221618 -225.819716)
		(end 316.221618 -227.45319)
		(width 0.14478)
		(layer "In13.Cu")
		(net "M_B_CPU0_SA_DQ<17>")
	)
	(segment
		(start 308.556152 -219.201492)
		(end 308.745128 -219.12326)
		(width 0.14478)
		(layer "In13.Cu")
		(net "M_B_CPU0_SA_DQ<17>")
	)
	(segment
		(start 322.470272 -233.701844)
		(end 323.879718 -233.701844)
		(width 0.14478)
		(layer "In13.Cu")
		(net "M_B_CPU0_SA_DQ<17>")
	)
	(segment
		(start 307.280564 -218.337384)
		(end 307.217318 -218.490038)
		(width 0.14478)
		(layer "In13.Cu")
		(net "M_B_CPU0_SA_DQ<17>")
	)
	(segment
		(start 307.789834 -218.548458)
		(end 307.97881 -218.470226)
		(width 0.14478)
		(layer "In13.Cu")
		(net "M_B_CPU0_SA_DQ<17>")
	)
	(segment
		(start 308.299104 -218.759532)
		(end 308.235858 -218.912186)
		(width 0.14478)
		(layer "In13.Cu")
		(net "M_B_CPU0_SA_DQ<17>")
	)
	(segment
		(start 328.033634 -235.890562)
		(end 328.044048 -235.896658)
		(width 0.0889)
		(layer "In13.Cu")
		(net "M_B_CPU0_SA_DQ<17>")
	)
	(segment
		(start 308.235858 -218.912186)
		(end 308.31409 -219.101162)
		(width 0.14478)
		(layer "In13.Cu")
		(net "M_B_CPU0_SA_DQ<17>")
	)
	(segment
		(start 302.024542 -218.160092)
		(end 302.670464 -218.160092)
		(width 0.14478)
		(layer "In13.Cu")
		(net "M_B_CPU0_SA_DQ<17>")
	)
	(segment
		(start 325.535798 -234.731052)
		(end 325.535798 -235.284518)
		(width 0.0889)
		(layer "In13.Cu")
		(net "M_B_CPU0_SA_DQ<17>")
	)
	(segment
		(start 302.9966 -218.55303)
		(end 303.226978 -218.55303)
		(width 0.14478)
		(layer "In13.Cu")
		(net "M_B_CPU0_SA_DQ<17>")
	)
	(segment
		(start 303.783492 -218.160092)
		(end 303.94656 -218.32316)
		(width 0.14478)
		(layer "In13.Cu")
		(net "M_B_CPU0_SA_DQ<17>")
	)
	(segment
		(start 306.96027 -218.048078)
		(end 307.202332 -218.148408)
		(width 0.14478)
		(layer "In13.Cu")
		(net "M_B_CPU0_SA_DQ<17>")
	)
	(segment
		(start 332.744064 -235.896658)
		(end 332.752446 -235.901484)
		(width 0.0889)
		(layer "In13.Cu")
		(net "M_B_CPU0_SA_DQ<17>")
	)
	(segment
		(start 302.670464 -218.160092)
		(end 302.833532 -218.32316)
		(width 0.14478)
		(layer "In13.Cu")
		(net "M_B_CPU0_SA_DQ<17>")
	)
	(segment
		(start 304.503074 -218.389962)
		(end 304.503074 -218.32316)
		(width 0.14478)
		(layer "In13.Cu")
		(net "M_B_CPU0_SA_DQ<17>")
	)
	(segment
		(start 333.684118 -235.896658)
		(end 333.6925 -235.901484)
		(width 0.0889)
		(layer "In13.Cu")
		(net "M_B_CPU0_SA_DQ<17>")
	)
	(segment
		(start 309.239412 -218.992704)
		(end 309.317644 -219.18168)
		(width 0.14478)
		(layer "In13.Cu")
		(net "M_B_CPU0_SA_DQ<17>")
	)
	(segment
		(start 302.833532 -218.32316)
		(end 302.833532 -218.389962)
		(width 0.14478)
		(layer "In13.Cu")
		(net "M_B_CPU0_SA_DQ<17>")
	)
	(segment
		(start 324.976998 -234.172252)
		(end 325.535798 -234.731052)
		(width 0.0889)
		(layer "In13.Cu")
		(net "M_B_CPU0_SA_DQ<17>")
	)
	(segment
		(start 306.519072 -218.357196)
		(end 306.708048 -218.278964)
		(width 0.14478)
		(layer "In13.Cu")
		(net "M_B_CPU0_SA_DQ<17>")
	)
	(segment
		(start 307.537612 -218.779344)
		(end 307.726588 -218.701112)
		(width 0.14478)
		(layer "In13.Cu")
		(net "M_B_CPU0_SA_DQ<17>")
	)
	(segment
		(start 303.94656 -218.32316)
		(end 303.94656 -218.389962)
		(width 0.14478)
		(layer "In13.Cu")
		(net "M_B_CPU0_SA_DQ<17>")
	)
	(segment
		(start 304.340006 -218.55303)
		(end 304.503074 -218.389962)
		(width 0.14478)
		(layer "In13.Cu")
		(net "M_B_CPU0_SA_DQ<17>")
	)
	(segment
		(start 308.220872 -218.570556)
		(end 308.299104 -218.759532)
		(width 0.14478)
		(layer "In13.Cu")
		(net "M_B_CPU0_SA_DQ<17>")
	)
	(segment
		(start 301.174658 -217.310208)
		(end 302.024542 -218.160092)
		(width 0.14478)
		(layer "In13.Cu")
		(net "M_B_CPU0_SA_DQ<17>")
	)
	(segment
		(start 316.221618 -227.45319)
		(end 322.470272 -233.701844)
		(width 0.14478)
		(layer "In13.Cu")
		(net "M_B_CPU0_SA_DQ<17>")
	)
	(segment
		(start 299.82414 -217.73515)
		(end 299.82414 -217.729562)
		(width 0.14478)
		(layer "In13.Cu")
		(net "M_B_CPU0_SA_DQ<17>")
	)
	(segment
		(start 303.94656 -218.389962)
		(end 304.109628 -218.55303)
		(width 0.14478)
		(layer "In13.Cu")
		(net "M_B_CPU0_SA_DQ<17>")
	)
	(segment
		(start 306.043838 -218.160092)
		(end 306.519072 -218.357196)
		(width 0.14478)
		(layer "In13.Cu")
		(net "M_B_CPU0_SA_DQ<17>")
	)
	(segment
		(start 303.226978 -218.55303)
		(end 303.390046 -218.389962)
		(width 0.14478)
		(layer "In13.Cu")
		(net "M_B_CPU0_SA_DQ<17>")
	)
	(segment
		(start 304.503074 -218.32316)
		(end 304.666142 -218.160092)
		(width 0.14478)
		(layer "In13.Cu")
		(net "M_B_CPU0_SA_DQ<17>")
	)
	(segment
		(start 306.708048 -218.278964)
		(end 306.771294 -218.12631)
		(width 0.14478)
		(layer "In13.Cu")
		(net "M_B_CPU0_SA_DQ<17>")
	)
	(segment
		(start 324.14591 -233.701844)
		(end 324.616318 -234.172252)
		(width 0.0889)
		(layer "In13.Cu")
		(net "M_B_CPU0_SA_DQ<17>")
	)
	(segment
		(start 300.243494 -217.310208)
		(end 301.174658 -217.310208)
		(width 0.14478)
		(layer "In13.Cu")
		(net "M_B_CPU0_SA_DQ<17>")
	)
	(segment
		(start 308.99735 -218.892374)
		(end 309.239412 -218.992704)
		(width 0.14478)
		(layer "In13.Cu")
		(net "M_B_CPU0_SA_DQ<17>")
	)
	(segment
		(start 331.229716 -235.901484)
		(end 331.238098 -235.896658)
		(width 0.0889)
		(layer "In13.Cu")
		(net "M_B_CPU0_SA_DQ<17>")
	)
	(segment
		(start 306.771294 -218.12631)
		(end 306.96027 -218.048078)
		(width 0.14478)
		(layer "In13.Cu")
		(net "M_B_CPU0_SA_DQ<17>")
	)
	(segment
		(start 303.390046 -218.32316)
		(end 303.553114 -218.160092)
		(width 0.14478)
		(layer "In13.Cu")
		(net "M_B_CPU0_SA_DQ<17>")
	)
	(segment
		(start 335.929732 -235.901484)
		(end 335.938114 -235.896658)
		(width 0.0889)
		(layer "In13.Cu")
		(net "M_B_CPU0_SA_DQ<17>")
	)
	(segment
		(start 299.82414 -217.729562)
		(end 300.243494 -217.310208)
		(width 0.14478)
		(layer "In13.Cu")
		(net "M_B_CPU0_SA_DQ<17>")
	)
	(segment
		(start 324.616318 -234.172252)
		(end 324.976998 -234.172252)
		(width 0.0889)
		(layer "In13.Cu")
		(net "M_B_CPU0_SA_DQ<17>")
	)
	(segment
		(start 326.198738 -235.947458)
		(end 327.289922 -235.947458)
		(width 0.0889)
		(layer "In13.Cu")
		(net "M_B_CPU0_SA_DQ<17>")
	)
	(segment
		(start 328.984102 -235.896658)
		(end 328.992484 -235.901484)
		(width 0.0889)
		(layer "In13.Cu")
		(net "M_B_CPU0_SA_DQ<17>")
	)
	(segment
		(start 307.726588 -218.701112)
		(end 307.789834 -218.548458)
		(width 0.14478)
		(layer "In13.Cu")
		(net "M_B_CPU0_SA_DQ<17>")
	)
	(segment
		(start 303.390046 -218.389962)
		(end 303.390046 -218.32316)
		(width 0.14478)
		(layer "In13.Cu")
		(net "M_B_CPU0_SA_DQ<17>")
	)
	(segment
		(start 307.202332 -218.148408)
		(end 307.280564 -218.337384)
		(width 0.14478)
		(layer "In13.Cu")
		(net "M_B_CPU0_SA_DQ<17>")
	)
	(segment
		(start 307.97881 -218.470226)
		(end 308.220872 -218.570556)
		(width 0.14478)
		(layer "In13.Cu")
		(net "M_B_CPU0_SA_DQ<17>")
	)
	(segment
		(start 304.109628 -218.55303)
		(end 304.340006 -218.55303)
		(width 0.14478)
		(layer "In13.Cu")
		(net "M_B_CPU0_SA_DQ<17>")
	)
	(segment
		(start 308.808374 -218.970606)
		(end 308.99735 -218.892374)
		(width 0.14478)
		(layer "In13.Cu")
		(net "M_B_CPU0_SA_DQ<17>")
	)
	(segment
		(start 325.535798 -235.284518)
		(end 326.198738 -235.947458)
		(width 0.0889)
		(layer "In13.Cu")
		(net "M_B_CPU0_SA_DQ<17>")
	)
	(segment
		(start 307.29555 -218.679014)
		(end 307.537612 -218.779344)
		(width 0.14478)
		(layer "In13.Cu")
		(net "M_B_CPU0_SA_DQ<17>")
	)
	(segment
		(start 303.553114 -218.160092)
		(end 303.783492 -218.160092)
		(width 0.14478)
		(layer "In13.Cu")
		(net "M_B_CPU0_SA_DQ<17>")
	)
	(segment
		(start 323.879718 -233.701844)
		(end 324.14591 -233.701844)
		(width 0.0889)
		(layer "In13.Cu")
		(net "M_B_CPU0_SA_DQ<17>")
	)
	(segment
		(start 328.409808 -235.901484)
		(end 328.41819 -235.896658)
		(width 0.0889)
		(layer "In13.Cu")
		(net "M_B_CPU0_SA_DQ<17>")
	)
	(segment
		(start 309.254398 -219.334334)
		(end 309.33263 -219.523056)
		(width 0.14478)
		(layer "In13.Cu")
		(net "M_B_CPU0_SA_DQ<17>")
	)
	(arc
		(start 328.044048 -235.896658)
		(mid 328.226299 -235.947008)
		(end 328.409808 -235.901484)
		(width 0.0889)
		(layer "In13.Cu")
		(net "M_B_CPU0_SA_DQ<17>")
	)
	(arc
		(start 329.924156 -235.896658)
		(mid 330.1111 -235.946913)
		(end 330.298044 -235.896658)
		(width 0.0889)
		(layer "In13.Cu")
		(net "M_B_CPU0_SA_DQ<17>")
	)
	(arc
		(start 332.752446 -235.901484)
		(mid 332.935954 -235.946978)
		(end 333.118206 -235.896658)
		(width 0.0889)
		(layer "In13.Cu")
		(net "M_B_CPU0_SA_DQ<17>")
	)
	(arc
		(start 333.6925 -235.901484)
		(mid 333.876008 -235.946978)
		(end 334.05826 -235.896658)
		(width 0.0889)
		(layer "In13.Cu")
		(net "M_B_CPU0_SA_DQ<17>")
	)
	(arc
		(start 335.938114 -235.896658)
		(mid 336.22107 -235.820481)
		(end 336.504026 -235.896658)
		(width 0.0889)
		(layer "In13.Cu")
		(net "M_B_CPU0_SA_DQ<17>")
	)
	(arc
		(start 327.289922 -235.947458)
		(mid 327.387283 -235.93455)
		(end 327.477882 -235.896658)
		(width 0.0889)
		(layer "In13.Cu")
		(net "M_B_CPU0_SA_DQ<17>")
	)
	(arc
		(start 334.99806 -235.896658)
		(mid 335.281016 -235.820481)
		(end 335.563972 -235.896658)
		(width 0.0889)
		(layer "In13.Cu")
		(net "M_B_CPU0_SA_DQ<17>")
	)
	(arc
		(start 329.358244 -235.896658)
		(mid 329.6412 -235.820481)
		(end 329.924156 -235.896658)
		(width 0.0889)
		(layer "In13.Cu")
		(net "M_B_CPU0_SA_DQ<17>")
	)
	(arc
		(start 328.992484 -235.901484)
		(mid 329.175992 -235.946978)
		(end 329.358244 -235.896658)
		(width 0.0889)
		(layer "In13.Cu")
		(net "M_B_CPU0_SA_DQ<17>")
	)
	(arc
		(start 333.118206 -235.896658)
		(mid 333.401162 -235.820481)
		(end 333.684118 -235.896658)
		(width 0.0889)
		(layer "In13.Cu")
		(net "M_B_CPU0_SA_DQ<17>")
	)
	(arc
		(start 328.41819 -235.896658)
		(mid 328.701146 -235.820481)
		(end 328.984102 -235.896658)
		(width 0.0889)
		(layer "In13.Cu")
		(net "M_B_CPU0_SA_DQ<17>")
	)
	(arc
		(start 331.238098 -235.896658)
		(mid 331.521054 -235.820481)
		(end 331.80401 -235.896658)
		(width 0.0889)
		(layer "In13.Cu")
		(net "M_B_CPU0_SA_DQ<17>")
	)
	(arc
		(start 330.863956 -235.896658)
		(mid 331.046207 -235.947008)
		(end 331.229716 -235.901484)
		(width 0.0889)
		(layer "In13.Cu")
		(net "M_B_CPU0_SA_DQ<17>")
	)
	(arc
		(start 331.80401 -235.896658)
		(mid 331.986261 -235.947008)
		(end 332.16977 -235.901484)
		(width 0.0889)
		(layer "In13.Cu")
		(net "M_B_CPU0_SA_DQ<17>")
	)
	(arc
		(start 336.504026 -235.896658)
		(mid 336.660464 -235.945629)
		(end 336.822796 -235.92282)
		(width 0.0889)
		(layer "In13.Cu")
		(net "M_B_CPU0_SA_DQ<17>")
	)
	(arc
		(start 330.298044 -235.896658)
		(mid 330.581 -235.820481)
		(end 330.863956 -235.896658)
		(width 0.0889)
		(layer "In13.Cu")
		(net "M_B_CPU0_SA_DQ<17>")
	)
	(arc
		(start 332.178152 -235.896658)
		(mid 332.461108 -235.820481)
		(end 332.744064 -235.896658)
		(width 0.0889)
		(layer "In13.Cu")
		(net "M_B_CPU0_SA_DQ<17>")
	)
	(arc
		(start 335.563972 -235.896658)
		(mid 335.746223 -235.947008)
		(end 335.929732 -235.901484)
		(width 0.0889)
		(layer "In13.Cu")
		(net "M_B_CPU0_SA_DQ<17>")
	)
	(arc
		(start 334.05826 -235.896658)
		(mid 334.341216 -235.820481)
		(end 334.624172 -235.896658)
		(width 0.0889)
		(layer "In13.Cu")
		(net "M_B_CPU0_SA_DQ<17>")
	)
	(arc
		(start 327.477882 -235.896658)
		(mid 327.754949 -235.820387)
		(end 328.033634 -235.890562)
		(width 0.0889)
		(layer "In13.Cu")
		(net "M_B_CPU0_SA_DQ<17>")
	)
	(arc
		(start 334.624172 -235.896658)
		(mid 334.811116 -235.946913)
		(end 334.99806 -235.896658)
		(width 0.0889)
		(layer "In13.Cu")
		(net "M_B_CPU0_SA_DQ<17>")
	)
	(segment
		(start 335.747868 -235.03001)
		(end 335.281016 -234.764072)
		(width 0.10668)
		(layer "F.Cu")
		(net "M_B_CPU0_SA_DQ<16>")
	)
	(segment
		(start 308.30774 -217.312748)
		(end 308.30774 -217.517472)
		(width 0.14478)
		(layer "In13.Cu")
		(net "M_B_CPU0_SA_DQ<16>")
	)
	(segment
		(start 303.773078 -216.698068)
		(end 303.934622 -216.859612)
		(width 0.14478)
		(layer "In13.Cu")
		(net "M_B_CPU0_SA_DQ<16>")
	)
	(segment
		(start 327.57491 -235.086652)
		(end 327.57491 -235.086398)
		(width 0.0889)
		(layer "In13.Cu")
		(net "M_B_CPU0_SA_DQ<16>")
	)
	(segment
		(start 317.130938 -225.424238)
		(end 317.130938 -227.090478)
		(width 0.14478)
		(layer "In13.Cu")
		(net "M_B_CPU0_SA_DQ<16>")
	)
	(segment
		(start 305.42738 -216.330276)
		(end 305.588924 -216.168732)
		(width 0.14478)
		(layer "In13.Cu")
		(net "M_B_CPU0_SA_DQ<16>")
	)
	(segment
		(start 308.951122 -217.449146)
		(end 309.155846 -217.449146)
		(width 0.14478)
		(layer "In13.Cu")
		(net "M_B_CPU0_SA_DQ<16>")
	)
	(segment
		(start 299.82414 -216.035128)
		(end 299.82414 -215.92413)
		(width 0.14478)
		(layer "In13.Cu")
		(net "M_B_CPU0_SA_DQ<16>")
	)
	(segment
		(start 303.773078 -216.621614)
		(end 303.773078 -216.698068)
		(width 0.14478)
		(layer "In13.Cu")
		(net "M_B_CPU0_SA_DQ<16>")
	)
	(segment
		(start 325.355458 -233.613198)
		(end 326.165972 -234.423712)
		(width 0.0889)
		(layer "In13.Cu")
		(net "M_B_CPU0_SA_DQ<16>")
	)
	(segment
		(start 304.162968 -216.859612)
		(end 304.324512 -216.698068)
		(width 0.14478)
		(layer "In13.Cu")
		(net "M_B_CPU0_SA_DQ<16>")
	)
	(segment
		(start 309.155846 -217.449146)
		(end 317.130938 -225.424238)
		(width 0.14478)
		(layer "In13.Cu")
		(net "M_B_CPU0_SA_DQ<16>")
	)
	(segment
		(start 327.14311 -235.025438)
		(end 327.418954 -235.025438)
		(width 0.0889)
		(layer "In13.Cu")
		(net "M_B_CPU0_SA_DQ<16>")
	)
	(segment
		(start 308.16677 -216.46007)
		(end 308.561232 -216.854532)
		(width 0.14478)
		(layer "In13.Cu")
		(net "M_B_CPU0_SA_DQ<16>")
	)
	(segment
		(start 323.889878 -232.792524)
		(end 324.68693 -232.792524)
		(width 0.0889)
		(layer "In13.Cu")
		(net "M_B_CPU0_SA_DQ<16>")
	)
	(segment
		(start 326.165972 -234.423712)
		(end 326.541384 -234.423712)
		(width 0.0889)
		(layer "In13.Cu")
		(net "M_B_CPU0_SA_DQ<16>")
	)
	(segment
		(start 329.819762 -235.091478)
		(end 329.828144 -235.086652)
		(width 0.0889)
		(layer "In13.Cu")
		(net "M_B_CPU0_SA_DQ<16>")
	)
	(segment
		(start 305.588924 -216.168732)
		(end 305.81727 -216.168732)
		(width 0.14478)
		(layer "In13.Cu")
		(net "M_B_CPU0_SA_DQ<16>")
	)
	(segment
		(start 308.30774 -217.517472)
		(end 308.492906 -217.702638)
		(width 0.14478)
		(layer "In13.Cu")
		(net "M_B_CPU0_SA_DQ<16>")
	)
	(segment
		(start 302.900588 -216.747852)
		(end 303.18837 -216.46007)
		(width 0.14478)
		(layer "In13.Cu")
		(net "M_B_CPU0_SA_DQ<16>")
	)
	(segment
		(start 304.875946 -216.330276)
		(end 304.875946 -216.698068)
		(width 0.14478)
		(layer "In13.Cu")
		(net "M_B_CPU0_SA_DQ<16>")
	)
	(segment
		(start 326.541384 -234.423712)
		(end 327.14311 -235.025438)
		(width 0.0889)
		(layer "In13.Cu")
		(net "M_B_CPU0_SA_DQ<16>")
	)
	(segment
		(start 299.82414 -215.92413)
		(end 300.138084 -215.610186)
		(width 0.14478)
		(layer "In13.Cu")
		(net "M_B_CPU0_SA_DQ<16>")
	)
	(segment
		(start 306.691792 -216.46007)
		(end 308.16677 -216.46007)
		(width 0.14478)
		(layer "In13.Cu")
		(net "M_B_CPU0_SA_DQ<16>")
	)
	(segment
		(start 305.81727 -216.168732)
		(end 305.978814 -216.330276)
		(width 0.14478)
		(layer "In13.Cu")
		(net "M_B_CPU0_SA_DQ<16>")
	)
	(segment
		(start 306.530248 -216.621614)
		(end 306.691792 -216.46007)
		(width 0.14478)
		(layer "In13.Cu")
		(net "M_B_CPU0_SA_DQ<16>")
	)
	(segment
		(start 334.519778 -235.091478)
		(end 334.52816 -235.086652)
		(width 0.0889)
		(layer "In13.Cu")
		(net "M_B_CPU0_SA_DQ<16>")
	)
	(segment
		(start 301.174658 -215.610186)
		(end 302.024542 -216.46007)
		(width 0.14478)
		(layer "In13.Cu")
		(net "M_B_CPU0_SA_DQ<16>")
	)
	(segment
		(start 325.355458 -233.461052)
		(end 325.355458 -233.613198)
		(width 0.0889)
		(layer "In13.Cu")
		(net "M_B_CPU0_SA_DQ<16>")
	)
	(segment
		(start 304.324512 -216.698068)
		(end 304.324512 -216.330276)
		(width 0.14478)
		(layer "In13.Cu")
		(net "M_B_CPU0_SA_DQ<16>")
	)
	(segment
		(start 327.57491 -235.086398)
		(end 327.594976 -235.097828)
		(width 0.0889)
		(layer "In13.Cu")
		(net "M_B_CPU0_SA_DQ<16>")
	)
	(segment
		(start 302.636936 -216.747852)
		(end 302.900588 -216.747852)
		(width 0.14478)
		(layer "In13.Cu")
		(net "M_B_CPU0_SA_DQ<16>")
	)
	(segment
		(start 308.561232 -216.854532)
		(end 308.561232 -217.059256)
		(width 0.14478)
		(layer "In13.Cu")
		(net "M_B_CPU0_SA_DQ<16>")
	)
	(segment
		(start 304.714402 -216.168732)
		(end 304.875946 -216.330276)
		(width 0.14478)
		(layer "In13.Cu")
		(net "M_B_CPU0_SA_DQ<16>")
	)
	(segment
		(start 331.33411 -235.086652)
		(end 331.342492 -235.091478)
		(width 0.0889)
		(layer "In13.Cu")
		(net "M_B_CPU0_SA_DQ<16>")
	)
	(segment
		(start 322.832984 -232.792524)
		(end 323.889878 -232.792524)
		(width 0.14478)
		(layer "In13.Cu")
		(net "M_B_CPU0_SA_DQ<16>")
	)
	(segment
		(start 330.394056 -235.086652)
		(end 330.402438 -235.091478)
		(width 0.0889)
		(layer "In13.Cu")
		(net "M_B_CPU0_SA_DQ<16>")
	)
	(segment
		(start 305.978814 -216.330276)
		(end 305.978814 -216.698068)
		(width 0.14478)
		(layer "In13.Cu")
		(net "M_B_CPU0_SA_DQ<16>")
	)
	(segment
		(start 308.492906 -217.702638)
		(end 308.69763 -217.702638)
		(width 0.14478)
		(layer "In13.Cu")
		(net "M_B_CPU0_SA_DQ<16>")
	)
	(segment
		(start 324.68693 -232.792524)
		(end 325.355458 -233.461052)
		(width 0.0889)
		(layer "In13.Cu")
		(net "M_B_CPU0_SA_DQ<16>")
	)
	(segment
		(start 304.486056 -216.168732)
		(end 304.714402 -216.168732)
		(width 0.14478)
		(layer "In13.Cu")
		(net "M_B_CPU0_SA_DQ<16>")
	)
	(segment
		(start 306.140358 -216.859612)
		(end 306.368704 -216.859612)
		(width 0.14478)
		(layer "In13.Cu")
		(net "M_B_CPU0_SA_DQ<16>")
	)
	(segment
		(start 335.412842 -235.112814)
		(end 335.435194 -235.029502)
		(width 0.0889)
		(layer "In13.Cu")
		(net "M_B_CPU0_SA_DQ<16>")
	)
	(segment
		(start 305.42738 -216.698068)
		(end 305.42738 -216.330276)
		(width 0.14478)
		(layer "In13.Cu")
		(net "M_B_CPU0_SA_DQ<16>")
	)
	(segment
		(start 302.349154 -216.46007)
		(end 302.636936 -216.747852)
		(width 0.14478)
		(layer "In13.Cu")
		(net "M_B_CPU0_SA_DQ<16>")
	)
	(segment
		(start 305.265836 -216.859612)
		(end 305.42738 -216.698068)
		(width 0.14478)
		(layer "In13.Cu")
		(net "M_B_CPU0_SA_DQ<16>")
	)
	(segment
		(start 305.978814 -216.698068)
		(end 306.140358 -216.859612)
		(width 0.14478)
		(layer "In13.Cu")
		(net "M_B_CPU0_SA_DQ<16>")
	)
	(segment
		(start 302.024542 -216.46007)
		(end 302.349154 -216.46007)
		(width 0.14478)
		(layer "In13.Cu")
		(net "M_B_CPU0_SA_DQ<16>")
	)
	(segment
		(start 303.611534 -216.46007)
		(end 303.773078 -216.621614)
		(width 0.14478)
		(layer "In13.Cu")
		(net "M_B_CPU0_SA_DQ<16>")
	)
	(segment
		(start 317.130938 -227.090478)
		(end 322.832984 -232.792524)
		(width 0.14478)
		(layer "In13.Cu")
		(net "M_B_CPU0_SA_DQ<16>")
	)
	(segment
		(start 304.324512 -216.330276)
		(end 304.486056 -216.168732)
		(width 0.14478)
		(layer "In13.Cu")
		(net "M_B_CPU0_SA_DQ<16>")
	)
	(segment
		(start 303.18837 -216.46007)
		(end 303.611534 -216.46007)
		(width 0.14478)
		(layer "In13.Cu")
		(net "M_B_CPU0_SA_DQ<16>")
	)
	(segment
		(start 306.368704 -216.859612)
		(end 306.530248 -216.698068)
		(width 0.14478)
		(layer "In13.Cu")
		(net "M_B_CPU0_SA_DQ<16>")
	)
	(segment
		(start 305.03749 -216.859612)
		(end 305.265836 -216.859612)
		(width 0.14478)
		(layer "In13.Cu")
		(net "M_B_CPU0_SA_DQ<16>")
	)
	(segment
		(start 304.875946 -216.698068)
		(end 305.03749 -216.859612)
		(width 0.14478)
		(layer "In13.Cu")
		(net "M_B_CPU0_SA_DQ<16>")
	)
	(segment
		(start 306.530248 -216.698068)
		(end 306.530248 -216.621614)
		(width 0.14478)
		(layer "In13.Cu")
		(net "M_B_CPU0_SA_DQ<16>")
	)
	(segment
		(start 333.579724 -235.091478)
		(end 333.588106 -235.086652)
		(width 0.0889)
		(layer "In13.Cu")
		(net "M_B_CPU0_SA_DQ<16>")
	)
	(segment
		(start 335.435194 -235.029502)
		(end 335.281016 -234.764072)
		(width 0.0889)
		(layer "In13.Cu")
		(net "M_B_CPU0_SA_DQ<16>")
	)
	(segment
		(start 300.138084 -215.610186)
		(end 301.174658 -215.610186)
		(width 0.14478)
		(layer "In13.Cu")
		(net "M_B_CPU0_SA_DQ<16>")
	)
	(segment
		(start 308.561232 -217.059256)
		(end 308.30774 -217.312748)
		(width 0.14478)
		(layer "In13.Cu")
		(net "M_B_CPU0_SA_DQ<16>")
	)
	(segment
		(start 335.094072 -235.086652)
		(end 335.102454 -235.091478)
		(width 0.0889)
		(layer "In13.Cu")
		(net "M_B_CPU0_SA_DQ<16>")
	)
	(segment
		(start 303.934622 -216.859612)
		(end 304.162968 -216.859612)
		(width 0.14478)
		(layer "In13.Cu")
		(net "M_B_CPU0_SA_DQ<16>")
	)
	(segment
		(start 308.69763 -217.702638)
		(end 308.951122 -217.449146)
		(width 0.14478)
		(layer "In13.Cu")
		(net "M_B_CPU0_SA_DQ<16>")
	)
	(arc
		(start 328.88809 -235.086652)
		(mid 329.171046 -235.010475)
		(end 329.454002 -235.086652)
		(width 0.0889)
		(layer "In13.Cu")
		(net "M_B_CPU0_SA_DQ<16>")
	)
	(arc
		(start 330.402438 -235.091478)
		(mid 330.585946 -235.136972)
		(end 330.768198 -235.086652)
		(width 0.0889)
		(layer "In13.Cu")
		(net "M_B_CPU0_SA_DQ<16>")
	)
	(arc
		(start 332.274164 -235.086652)
		(mid 332.461108 -235.136907)
		(end 332.648052 -235.086652)
		(width 0.0889)
		(layer "In13.Cu")
		(net "M_B_CPU0_SA_DQ<16>")
	)
	(arc
		(start 330.768198 -235.086652)
		(mid 331.051154 -235.010475)
		(end 331.33411 -235.086652)
		(width 0.0889)
		(layer "In13.Cu")
		(net "M_B_CPU0_SA_DQ<16>")
	)
	(arc
		(start 327.594976 -235.097828)
		(mid 327.773054 -235.136812)
		(end 327.94829 -235.086652)
		(width 0.0889)
		(layer "In13.Cu")
		(net "M_B_CPU0_SA_DQ<16>")
	)
	(arc
		(start 333.213964 -235.086652)
		(mid 333.396215 -235.137002)
		(end 333.579724 -235.091478)
		(width 0.0889)
		(layer "In13.Cu")
		(net "M_B_CPU0_SA_DQ<16>")
	)
	(arc
		(start 335.102454 -235.091478)
		(mid 335.255324 -235.136119)
		(end 335.412842 -235.112814)
		(width 0.0889)
		(layer "In13.Cu")
		(net "M_B_CPU0_SA_DQ<16>")
	)
	(arc
		(start 331.342492 -235.091478)
		(mid 331.526 -235.136972)
		(end 331.708252 -235.086652)
		(width 0.0889)
		(layer "In13.Cu")
		(net "M_B_CPU0_SA_DQ<16>")
	)
	(arc
		(start 333.588106 -235.086652)
		(mid 333.871062 -235.010475)
		(end 334.154018 -235.086652)
		(width 0.0889)
		(layer "In13.Cu")
		(net "M_B_CPU0_SA_DQ<16>")
	)
	(arc
		(start 334.154018 -235.086652)
		(mid 334.336269 -235.137002)
		(end 334.519778 -235.091478)
		(width 0.0889)
		(layer "In13.Cu")
		(net "M_B_CPU0_SA_DQ<16>")
	)
	(arc
		(start 327.94829 -235.086652)
		(mid 328.231246 -235.010475)
		(end 328.514202 -235.086652)
		(width 0.0889)
		(layer "In13.Cu")
		(net "M_B_CPU0_SA_DQ<16>")
	)
	(arc
		(start 332.648052 -235.086652)
		(mid 332.931008 -235.010475)
		(end 333.213964 -235.086652)
		(width 0.0889)
		(layer "In13.Cu")
		(net "M_B_CPU0_SA_DQ<16>")
	)
	(arc
		(start 329.828144 -235.086652)
		(mid 330.1111 -235.010475)
		(end 330.394056 -235.086652)
		(width 0.0889)
		(layer "In13.Cu")
		(net "M_B_CPU0_SA_DQ<16>")
	)
	(arc
		(start 328.514202 -235.086652)
		(mid 328.701146 -235.136907)
		(end 328.88809 -235.086652)
		(width 0.0889)
		(layer "In13.Cu")
		(net "M_B_CPU0_SA_DQ<16>")
	)
	(arc
		(start 327.418954 -235.025438)
		(mid 327.49922 -235.050215)
		(end 327.57491 -235.086652)
		(width 0.0889)
		(layer "In13.Cu")
		(net "M_B_CPU0_SA_DQ<16>")
	)
	(arc
		(start 334.52816 -235.086652)
		(mid 334.811116 -235.010475)
		(end 335.094072 -235.086652)
		(width 0.0889)
		(layer "In13.Cu")
		(net "M_B_CPU0_SA_DQ<16>")
	)
	(arc
		(start 331.708252 -235.086652)
		(mid 331.991208 -235.010475)
		(end 332.274164 -235.086652)
		(width 0.0889)
		(layer "In13.Cu")
		(net "M_B_CPU0_SA_DQ<16>")
	)
	(arc
		(start 329.454002 -235.086652)
		(mid 329.636253 -235.137002)
		(end 329.819762 -235.091478)
		(width 0.0889)
		(layer "In13.Cu")
		(net "M_B_CPU0_SA_DQ<16>")
	)
	(segment
		(start 337.627976 -235.03001)
		(end 337.161124 -234.764072)
		(width 0.10668)
		(layer "F.Cu")
		(net "M_B_CPU0_SA_DQ<15>")
	)
	(segment
		(start 331.33411 -234.441492)
		(end 331.342492 -234.436666)
		(width 0.0889)
		(layer "In13.Cu")
		(net "M_B_CPU0_SA_DQ<15>")
	)
	(segment
		(start 330.394056 -234.441492)
		(end 330.402438 -234.436666)
		(width 0.0889)
		(layer "In13.Cu")
		(net "M_B_CPU0_SA_DQ<15>")
	)
	(segment
		(start 300.562772 -214.760048)
		(end 301.644558 -215.208104)
		(width 0.14478)
		(layer "In13.Cu")
		(net "M_B_CPU0_SA_DQ<15>")
	)
	(segment
		(start 297.234864 -215.18499)
		(end 297.73753 -215.18499)
		(width 0.14478)
		(layer "In13.Cu")
		(net "M_B_CPU0_SA_DQ<15>")
	)
	(segment
		(start 326.539098 -233.598212)
		(end 327.331832 -234.390946)
		(width 0.0889)
		(layer "In13.Cu")
		(net "M_B_CPU0_SA_DQ<15>")
	)
	(segment
		(start 296.538904 -215.32977)
		(end 296.538904 -215.60663)
		(width 0.14478)
		(layer "In13.Cu")
		(net "M_B_CPU0_SA_DQ<15>")
	)
	(segment
		(start 325.843138 -233.598212)
		(end 326.539098 -233.598212)
		(width 0.0889)
		(layer "In13.Cu")
		(net "M_B_CPU0_SA_DQ<15>")
	)
	(segment
		(start 295.724072 -215.18499)
		(end 296.394124 -215.18499)
		(width 0.14478)
		(layer "In13.Cu")
		(net "M_B_CPU0_SA_DQ<15>")
	)
	(segment
		(start 302.04664 -215.610186)
		(end 308.096412 -215.610186)
		(width 0.14478)
		(layer "In13.Cu")
		(net "M_B_CPU0_SA_DQ<15>")
	)
	(segment
		(start 296.945304 -215.75141)
		(end 297.090084 -215.60663)
		(width 0.14478)
		(layer "In13.Cu")
		(net "M_B_CPU0_SA_DQ<15>")
	)
	(segment
		(start 297.73753 -215.18499)
		(end 298.162472 -214.760048)
		(width 0.14478)
		(layer "In13.Cu")
		(net "M_B_CPU0_SA_DQ<15>")
	)
	(segment
		(start 323.874638 -232.236264)
		(end 324.09511 -232.236264)
		(width 0.0889)
		(layer "In13.Cu")
		(net "M_B_CPU0_SA_DQ<15>")
	)
	(segment
		(start 317.682118 -226.862132)
		(end 323.05625 -232.236264)
		(width 0.14478)
		(layer "In13.Cu")
		(net "M_B_CPU0_SA_DQ<15>")
	)
	(segment
		(start 301.644558 -215.208104)
		(end 302.04664 -215.610186)
		(width 0.14478)
		(layer "In13.Cu")
		(net "M_B_CPU0_SA_DQ<15>")
	)
	(segment
		(start 323.05625 -232.236264)
		(end 323.874638 -232.236264)
		(width 0.14478)
		(layer "In13.Cu")
		(net "M_B_CPU0_SA_DQ<15>")
	)
	(segment
		(start 298.162472 -214.760048)
		(end 300.562772 -214.760048)
		(width 0.14478)
		(layer "In13.Cu")
		(net "M_B_CPU0_SA_DQ<15>")
	)
	(segment
		(start 335.094072 -234.441492)
		(end 335.102454 -234.436666)
		(width 0.0889)
		(layer "In13.Cu")
		(net "M_B_CPU0_SA_DQ<15>")
	)
	(segment
		(start 336.034126 -234.441492)
		(end 336.042508 -234.436666)
		(width 0.0889)
		(layer "In13.Cu")
		(net "M_B_CPU0_SA_DQ<15>")
	)
	(segment
		(start 297.090084 -215.60663)
		(end 297.090084 -215.32977)
		(width 0.14478)
		(layer "In13.Cu")
		(net "M_B_CPU0_SA_DQ<15>")
	)
	(segment
		(start 333.579724 -234.436666)
		(end 333.588106 -234.441492)
		(width 0.0889)
		(layer "In13.Cu")
		(net "M_B_CPU0_SA_DQ<15>")
	)
	(segment
		(start 317.682118 -225.195892)
		(end 317.682118 -226.862132)
		(width 0.14478)
		(layer "In13.Cu")
		(net "M_B_CPU0_SA_DQ<15>")
	)
	(segment
		(start 324.09511 -232.236264)
		(end 324.400418 -232.541572)
		(width 0.0889)
		(layer "In13.Cu")
		(net "M_B_CPU0_SA_DQ<15>")
	)
	(segment
		(start 329.819762 -234.436666)
		(end 329.828144 -234.441492)
		(width 0.0889)
		(layer "In13.Cu")
		(net "M_B_CPU0_SA_DQ<15>")
	)
	(segment
		(start 296.394124 -215.18499)
		(end 296.538904 -215.32977)
		(width 0.14478)
		(layer "In13.Cu")
		(net "M_B_CPU0_SA_DQ<15>")
	)
	(segment
		(start 308.096412 -215.610186)
		(end 317.682118 -225.195892)
		(width 0.14478)
		(layer "In13.Cu")
		(net "M_B_CPU0_SA_DQ<15>")
	)
	(segment
		(start 324.786498 -232.541572)
		(end 325.843138 -233.598212)
		(width 0.0889)
		(layer "In13.Cu")
		(net "M_B_CPU0_SA_DQ<15>")
	)
	(segment
		(start 296.538904 -215.60663)
		(end 296.683684 -215.75141)
		(width 0.14478)
		(layer "In13.Cu")
		(net "M_B_CPU0_SA_DQ<15>")
	)
	(segment
		(start 296.683684 -215.75141)
		(end 296.945304 -215.75141)
		(width 0.14478)
		(layer "In13.Cu")
		(net "M_B_CPU0_SA_DQ<15>")
	)
	(segment
		(start 324.400418 -232.541572)
		(end 324.786498 -232.541572)
		(width 0.0889)
		(layer "In13.Cu")
		(net "M_B_CPU0_SA_DQ<15>")
	)
	(segment
		(start 337.0072 -234.498642)
		(end 337.161124 -234.764072)
		(width 0.0889)
		(layer "In13.Cu")
		(net "M_B_CPU0_SA_DQ<15>")
	)
	(segment
		(start 297.090084 -215.32977)
		(end 297.234864 -215.18499)
		(width 0.14478)
		(layer "In13.Cu")
		(net "M_B_CPU0_SA_DQ<15>")
	)
	(segment
		(start 327.331832 -234.390946)
		(end 327.761092 -234.390946)
		(width 0.0889)
		(layer "In13.Cu")
		(net "M_B_CPU0_SA_DQ<15>")
	)
	(segment
		(start 334.519778 -234.436666)
		(end 334.52816 -234.441492)
		(width 0.0889)
		(layer "In13.Cu")
		(net "M_B_CPU0_SA_DQ<15>")
	)
	(segment
		(start 336.911188 -234.473242)
		(end 337.0072 -234.498642)
		(width 0.0889)
		(layer "In13.Cu")
		(net "M_B_CPU0_SA_DQ<15>")
	)
	(arc
		(start 335.468214 -234.441492)
		(mid 335.75117 -234.517669)
		(end 336.034126 -234.441492)
		(width 0.0889)
		(layer "In13.Cu")
		(net "M_B_CPU0_SA_DQ<15>")
	)
	(arc
		(start 330.402438 -234.436666)
		(mid 330.585946 -234.391172)
		(end 330.768198 -234.441492)
		(width 0.0889)
		(layer "In13.Cu")
		(net "M_B_CPU0_SA_DQ<15>")
	)
	(arc
		(start 333.213964 -234.441492)
		(mid 333.396215 -234.391142)
		(end 333.579724 -234.436666)
		(width 0.0889)
		(layer "In13.Cu")
		(net "M_B_CPU0_SA_DQ<15>")
	)
	(arc
		(start 328.514202 -234.441492)
		(mid 328.701146 -234.391237)
		(end 328.88809 -234.441492)
		(width 0.0889)
		(layer "In13.Cu")
		(net "M_B_CPU0_SA_DQ<15>")
	)
	(arc
		(start 330.768198 -234.441492)
		(mid 331.051154 -234.517669)
		(end 331.33411 -234.441492)
		(width 0.0889)
		(layer "In13.Cu")
		(net "M_B_CPU0_SA_DQ<15>")
	)
	(arc
		(start 334.154018 -234.441492)
		(mid 334.336269 -234.391142)
		(end 334.519778 -234.436666)
		(width 0.0889)
		(layer "In13.Cu")
		(net "M_B_CPU0_SA_DQ<15>")
	)
	(arc
		(start 336.042508 -234.436666)
		(mid 336.226016 -234.391172)
		(end 336.408268 -234.441492)
		(width 0.0889)
		(layer "In13.Cu")
		(net "M_B_CPU0_SA_DQ<15>")
	)
	(arc
		(start 328.88809 -234.441492)
		(mid 329.171046 -234.517669)
		(end 329.454002 -234.441492)
		(width 0.0889)
		(layer "In13.Cu")
		(net "M_B_CPU0_SA_DQ<15>")
	)
	(arc
		(start 329.454002 -234.441492)
		(mid 329.636253 -234.391142)
		(end 329.819762 -234.436666)
		(width 0.0889)
		(layer "In13.Cu")
		(net "M_B_CPU0_SA_DQ<15>")
	)
	(arc
		(start 332.274164 -234.441492)
		(mid 332.461108 -234.391237)
		(end 332.648052 -234.441492)
		(width 0.0889)
		(layer "In13.Cu")
		(net "M_B_CPU0_SA_DQ<15>")
	)
	(arc
		(start 329.828144 -234.441492)
		(mid 330.1111 -234.517669)
		(end 330.394056 -234.441492)
		(width 0.0889)
		(layer "In13.Cu")
		(net "M_B_CPU0_SA_DQ<15>")
	)
	(arc
		(start 331.708252 -234.441492)
		(mid 331.991208 -234.517669)
		(end 332.274164 -234.441492)
		(width 0.0889)
		(layer "In13.Cu")
		(net "M_B_CPU0_SA_DQ<15>")
	)
	(arc
		(start 332.648052 -234.441492)
		(mid 332.931008 -234.517669)
		(end 333.213964 -234.441492)
		(width 0.0889)
		(layer "In13.Cu")
		(net "M_B_CPU0_SA_DQ<15>")
	)
	(arc
		(start 336.408268 -234.441492)
		(mid 336.655981 -234.516712)
		(end 336.911188 -234.473242)
		(width 0.0889)
		(layer "In13.Cu")
		(net "M_B_CPU0_SA_DQ<15>")
	)
	(arc
		(start 331.342492 -234.436666)
		(mid 331.526 -234.391172)
		(end 331.708252 -234.441492)
		(width 0.0889)
		(layer "In13.Cu")
		(net "M_B_CPU0_SA_DQ<15>")
	)
	(arc
		(start 334.52816 -234.441492)
		(mid 334.811116 -234.517669)
		(end 335.094072 -234.441492)
		(width 0.0889)
		(layer "In13.Cu")
		(net "M_B_CPU0_SA_DQ<15>")
	)
	(arc
		(start 333.588106 -234.441492)
		(mid 333.871062 -234.517669)
		(end 334.154018 -234.441492)
		(width 0.0889)
		(layer "In13.Cu")
		(net "M_B_CPU0_SA_DQ<15>")
	)
	(arc
		(start 335.102454 -234.436666)
		(mid 335.285962 -234.391172)
		(end 335.468214 -234.441492)
		(width 0.0889)
		(layer "In13.Cu")
		(net "M_B_CPU0_SA_DQ<15>")
	)
	(arc
		(start 327.761092 -234.390946)
		(mid 327.858039 -234.403829)
		(end 327.94829 -234.441492)
		(width 0.0889)
		(layer "In13.Cu")
		(net "M_B_CPU0_SA_DQ<15>")
	)
	(arc
		(start 327.94829 -234.441492)
		(mid 328.231246 -234.517669)
		(end 328.514202 -234.441492)
		(width 0.0889)
		(layer "In13.Cu")
		(net "M_B_CPU0_SA_DQ<15>")
	)
	(segment
		(start 336.218022 -234.220004)
		(end 335.75117 -233.954066)
		(width 0.10668)
		(layer "F.Cu")
		(net "M_B_CPU0_SA_DQ<14>")
	)
	(segment
		(start 297.07586 -214.30869)
		(end 297.22064 -214.16391)
		(width 0.14478)
		(layer "In13.Cu")
		(net "M_B_CPU0_SA_DQ<14>")
	)
	(segment
		(start 328.984102 -233.631486)
		(end 328.992484 -233.62666)
		(width 0.0889)
		(layer "In13.Cu")
		(net "M_B_CPU0_SA_DQ<14>")
	)
	(segment
		(start 327.47966 -233.63174)
		(end 327.50125 -233.644186)
		(width 0.0889)
		(layer "In13.Cu")
		(net "M_B_CPU0_SA_DQ<14>")
	)
	(segment
		(start 302.73371 -213.910164)
		(end 307.668676 -213.910164)
		(width 0.14478)
		(layer "In13.Cu")
		(net "M_B_CPU0_SA_DQ<14>")
	)
	(segment
		(start 324.83552 -231.320594)
		(end 325.157338 -231.642412)
		(width 0.0889)
		(layer "In13.Cu")
		(net "M_B_CPU0_SA_DQ<14>")
	)
	(segment
		(start 325.157338 -231.642412)
		(end 325.157338 -231.957372)
		(width 0.0889)
		(layer "In13.Cu")
		(net "M_B_CPU0_SA_DQ<14>")
	)
	(segment
		(start 297.36542 -213.484968)
		(end 297.73753 -213.484968)
		(width 0.14478)
		(layer "In13.Cu")
		(net "M_B_CPU0_SA_DQ<14>")
	)
	(segment
		(start 318.597788 -226.505516)
		(end 323.412866 -231.320594)
		(width 0.14478)
		(layer "In13.Cu")
		(net "M_B_CPU0_SA_DQ<14>")
	)
	(segment
		(start 301.060358 -213.060026)
		(end 301.328582 -213.32825)
		(width 0.14478)
		(layer "In13.Cu")
		(net "M_B_CPU0_SA_DQ<14>")
	)
	(segment
		(start 296.66946 -214.16391)
		(end 296.81424 -214.30869)
		(width 0.14478)
		(layer "In13.Cu")
		(net "M_B_CPU0_SA_DQ<14>")
	)
	(segment
		(start 326.743568 -232.922572)
		(end 327.363074 -233.542078)
		(width 0.0889)
		(layer "In13.Cu")
		(net "M_B_CPU0_SA_DQ<14>")
	)
	(segment
		(start 323.412866 -231.320594)
		(end 323.859398 -231.320594)
		(width 0.14478)
		(layer "In13.Cu")
		(net "M_B_CPU0_SA_DQ<14>")
	)
	(segment
		(start 335.500726 -233.663236)
		(end 335.596992 -233.688636)
		(width 0.0889)
		(layer "In13.Cu")
		(net "M_B_CPU0_SA_DQ<14>")
	)
	(segment
		(start 297.22064 -214.16391)
		(end 297.22064 -213.629748)
		(width 0.14478)
		(layer "In13.Cu")
		(net "M_B_CPU0_SA_DQ<14>")
	)
	(segment
		(start 298.162472 -213.060026)
		(end 301.060358 -213.060026)
		(width 0.14478)
		(layer "In13.Cu")
		(net "M_B_CPU0_SA_DQ<14>")
	)
	(segment
		(start 326.122538 -232.922572)
		(end 326.743568 -232.922572)
		(width 0.0889)
		(layer "In13.Cu")
		(net "M_B_CPU0_SA_DQ<14>")
	)
	(segment
		(start 335.596992 -233.688636)
		(end 335.75117 -233.954066)
		(width 0.0889)
		(layer "In13.Cu")
		(net "M_B_CPU0_SA_DQ<14>")
	)
	(segment
		(start 333.684118 -233.631486)
		(end 333.6925 -233.62666)
		(width 0.0889)
		(layer "In13.Cu")
		(net "M_B_CPU0_SA_DQ<14>")
	)
	(segment
		(start 296.52468 -213.484968)
		(end 296.66946 -213.629748)
		(width 0.14478)
		(layer "In13.Cu")
		(net "M_B_CPU0_SA_DQ<14>")
	)
	(segment
		(start 295.724072 -213.484968)
		(end 296.52468 -213.484968)
		(width 0.14478)
		(layer "In13.Cu")
		(net "M_B_CPU0_SA_DQ<14>")
	)
	(segment
		(start 328.409808 -233.62666)
		(end 328.41819 -233.631486)
		(width 0.0889)
		(layer "In13.Cu")
		(net "M_B_CPU0_SA_DQ<14>")
	)
	(segment
		(start 332.16977 -233.62666)
		(end 332.178152 -233.631486)
		(width 0.0889)
		(layer "In13.Cu")
		(net "M_B_CPU0_SA_DQ<14>")
	)
	(segment
		(start 296.66946 -213.629748)
		(end 296.66946 -214.16391)
		(width 0.14478)
		(layer "In13.Cu")
		(net "M_B_CPU0_SA_DQ<14>")
	)
	(segment
		(start 301.328582 -213.32825)
		(end 302.73371 -213.910164)
		(width 0.14478)
		(layer "In13.Cu")
		(net "M_B_CPU0_SA_DQ<14>")
	)
	(segment
		(start 307.668676 -213.910164)
		(end 318.597788 -224.839276)
		(width 0.14478)
		(layer "In13.Cu")
		(net "M_B_CPU0_SA_DQ<14>")
	)
	(segment
		(start 297.73753 -213.484968)
		(end 298.162472 -213.060026)
		(width 0.14478)
		(layer "In13.Cu")
		(net "M_B_CPU0_SA_DQ<14>")
	)
	(segment
		(start 331.229716 -233.62666)
		(end 331.238098 -233.631486)
		(width 0.0889)
		(layer "In13.Cu")
		(net "M_B_CPU0_SA_DQ<14>")
	)
	(segment
		(start 318.597788 -224.839276)
		(end 318.597788 -226.505516)
		(width 0.14478)
		(layer "In13.Cu")
		(net "M_B_CPU0_SA_DQ<14>")
	)
	(segment
		(start 297.22064 -213.629748)
		(end 297.36542 -213.484968)
		(width 0.14478)
		(layer "In13.Cu")
		(net "M_B_CPU0_SA_DQ<14>")
	)
	(segment
		(start 325.157338 -231.957372)
		(end 326.122538 -232.922572)
		(width 0.0889)
		(layer "In13.Cu")
		(net "M_B_CPU0_SA_DQ<14>")
	)
	(segment
		(start 296.81424 -214.30869)
		(end 297.07586 -214.30869)
		(width 0.14478)
		(layer "In13.Cu")
		(net "M_B_CPU0_SA_DQ<14>")
	)
	(segment
		(start 332.744064 -233.631486)
		(end 332.752446 -233.62666)
		(width 0.0889)
		(layer "In13.Cu")
		(net "M_B_CPU0_SA_DQ<14>")
	)
	(segment
		(start 323.859398 -231.320594)
		(end 324.83552 -231.320594)
		(width 0.0889)
		(layer "In13.Cu")
		(net "M_B_CPU0_SA_DQ<14>")
	)
	(arc
		(start 334.05826 -233.631486)
		(mid 334.341216 -233.707663)
		(end 334.624172 -233.631486)
		(width 0.0889)
		(layer "In13.Cu")
		(net "M_B_CPU0_SA_DQ<14>")
	)
	(arc
		(start 332.752446 -233.62666)
		(mid 332.935954 -233.581166)
		(end 333.118206 -233.631486)
		(width 0.0889)
		(layer "In13.Cu")
		(net "M_B_CPU0_SA_DQ<14>")
	)
	(arc
		(start 329.924156 -233.631486)
		(mid 330.1111 -233.581231)
		(end 330.298044 -233.631486)
		(width 0.0889)
		(layer "In13.Cu")
		(net "M_B_CPU0_SA_DQ<14>")
	)
	(arc
		(start 329.358244 -233.631486)
		(mid 329.6412 -233.707663)
		(end 329.924156 -233.631486)
		(width 0.0889)
		(layer "In13.Cu")
		(net "M_B_CPU0_SA_DQ<14>")
	)
	(arc
		(start 328.044048 -233.631486)
		(mid 328.226299 -233.581136)
		(end 328.409808 -233.62666)
		(width 0.0889)
		(layer "In13.Cu")
		(net "M_B_CPU0_SA_DQ<14>")
	)
	(arc
		(start 333.118206 -233.631486)
		(mid 333.401162 -233.707663)
		(end 333.684118 -233.631486)
		(width 0.0889)
		(layer "In13.Cu")
		(net "M_B_CPU0_SA_DQ<14>")
	)
	(arc
		(start 328.41819 -233.631486)
		(mid 328.701146 -233.707663)
		(end 328.984102 -233.631486)
		(width 0.0889)
		(layer "In13.Cu")
		(net "M_B_CPU0_SA_DQ<14>")
	)
	(arc
		(start 327.363074 -233.542078)
		(mid 327.418423 -233.590737)
		(end 327.47966 -233.63174)
		(width 0.0889)
		(layer "In13.Cu")
		(net "M_B_CPU0_SA_DQ<14>")
	)
	(arc
		(start 333.6925 -233.62666)
		(mid 333.876008 -233.581166)
		(end 334.05826 -233.631486)
		(width 0.0889)
		(layer "In13.Cu")
		(net "M_B_CPU0_SA_DQ<14>")
	)
	(arc
		(start 331.80401 -233.631486)
		(mid 331.986261 -233.581136)
		(end 332.16977 -233.62666)
		(width 0.0889)
		(layer "In13.Cu")
		(net "M_B_CPU0_SA_DQ<14>")
	)
	(arc
		(start 334.624172 -233.631486)
		(mid 334.811116 -233.581231)
		(end 334.99806 -233.631486)
		(width 0.0889)
		(layer "In13.Cu")
		(net "M_B_CPU0_SA_DQ<14>")
	)
	(arc
		(start 334.99806 -233.631486)
		(mid 335.245656 -233.706664)
		(end 335.500726 -233.663236)
		(width 0.0889)
		(layer "In13.Cu")
		(net "M_B_CPU0_SA_DQ<14>")
	)
	(arc
		(start 330.298044 -233.631486)
		(mid 330.581 -233.707663)
		(end 330.863956 -233.631486)
		(width 0.0889)
		(layer "In13.Cu")
		(net "M_B_CPU0_SA_DQ<14>")
	)
	(arc
		(start 327.50125 -233.644186)
		(mid 327.774279 -233.707505)
		(end 328.044048 -233.631486)
		(width 0.0889)
		(layer "In13.Cu")
		(net "M_B_CPU0_SA_DQ<14>")
	)
	(arc
		(start 331.238098 -233.631486)
		(mid 331.521054 -233.707663)
		(end 331.80401 -233.631486)
		(width 0.0889)
		(layer "In13.Cu")
		(net "M_B_CPU0_SA_DQ<14>")
	)
	(arc
		(start 330.863956 -233.631486)
		(mid 331.046207 -233.581136)
		(end 331.229716 -233.62666)
		(width 0.0889)
		(layer "In13.Cu")
		(net "M_B_CPU0_SA_DQ<14>")
	)
	(arc
		(start 328.992484 -233.62666)
		(mid 329.175992 -233.581166)
		(end 329.358244 -233.631486)
		(width 0.0889)
		(layer "In13.Cu")
		(net "M_B_CPU0_SA_DQ<14>")
	)
	(arc
		(start 332.178152 -233.631486)
		(mid 332.461108 -233.707663)
		(end 332.744064 -233.631486)
		(width 0.0889)
		(layer "In13.Cu")
		(net "M_B_CPU0_SA_DQ<14>")
	)
	(segment
		(start 337.158076 -234.220004)
		(end 336.691224 -233.954066)
		(width 0.10668)
		(layer "F.Cu")
		(net "M_B_CPU0_SA_DQ<13>")
	)
	(segment
		(start 300.331124 -214.310468)
		(end 300.475904 -214.165688)
		(width 0.14478)
		(layer "In13.Cu")
		(net "M_B_CPU0_SA_DQ<13>")
	)
	(segment
		(start 301.027084 -214.165688)
		(end 301.171864 -214.310468)
		(width 0.14478)
		(layer "In13.Cu")
		(net "M_B_CPU0_SA_DQ<13>")
	)
	(segment
		(start 306.115466 -214.510874)
		(end 306.260246 -214.366094)
		(width 0.14478)
		(layer "In13.Cu")
		(net "M_B_CPU0_SA_DQ<13>")
	)
	(segment
		(start 336.822796 -234.302808)
		(end 336.845148 -234.219496)
		(width 0.0889)
		(layer "In13.Cu")
		(net "M_B_CPU0_SA_DQ<13>")
	)
	(segment
		(start 305.419506 -214.366094)
		(end 305.564286 -214.510874)
		(width 0.14478)
		(layer "In13.Cu")
		(net "M_B_CPU0_SA_DQ<13>")
	)
	(segment
		(start 301.027084 -213.663022)
		(end 301.027084 -214.165688)
		(width 0.14478)
		(layer "In13.Cu")
		(net "M_B_CPU0_SA_DQ<13>")
	)
	(segment
		(start 327.410826 -234.200446)
		(end 327.761346 -234.200446)
		(width 0.0889)
		(layer "In13.Cu")
		(net "M_B_CPU0_SA_DQ<13>")
	)
	(segment
		(start 318.143128 -226.686872)
		(end 323.23151 -231.775254)
		(width 0.14478)
		(layer "In13.Cu")
		(net "M_B_CPU0_SA_DQ<13>")
	)
	(segment
		(start 323.910198 -231.775254)
		(end 324.09638 -231.775254)
		(width 0.0889)
		(layer "In13.Cu")
		(net "M_B_CPU0_SA_DQ<13>")
	)
	(segment
		(start 302.785018 -215.14943)
		(end 303.015396 -215.14943)
		(width 0.14478)
		(layer "In13.Cu")
		(net "M_B_CPU0_SA_DQ<13>")
	)
	(segment
		(start 304.868326 -215.115902)
		(end 305.013106 -214.971122)
		(width 0.14478)
		(layer "In13.Cu")
		(net "M_B_CPU0_SA_DQ<13>")
	)
	(segment
		(start 303.015396 -215.14943)
		(end 303.178464 -214.986362)
		(width 0.14478)
		(layer "In13.Cu")
		(net "M_B_CPU0_SA_DQ<13>")
	)
	(segment
		(start 306.260246 -214.366094)
		(end 307.48859 -214.366094)
		(width 0.14478)
		(layer "In13.Cu")
		(net "M_B_CPU0_SA_DQ<13>")
	)
	(segment
		(start 300.475904 -214.165688)
		(end 300.475904 -213.663022)
		(width 0.14478)
		(layer "In13.Cu")
		(net "M_B_CPU0_SA_DQ<13>")
	)
	(segment
		(start 300.475904 -213.663022)
		(end 300.620684 -213.518242)
		(width 0.14478)
		(layer "In13.Cu")
		(net "M_B_CPU0_SA_DQ<13>")
	)
	(segment
		(start 324.560438 -232.239312)
		(end 324.877684 -232.239312)
		(width 0.0889)
		(layer "In13.Cu")
		(net "M_B_CPU0_SA_DQ<13>")
	)
	(segment
		(start 323.23151 -231.775254)
		(end 323.910198 -231.775254)
		(width 0.14478)
		(layer "In13.Cu")
		(net "M_B_CPU0_SA_DQ<13>")
	)
	(segment
		(start 301.171864 -214.310468)
		(end 302.47717 -214.310468)
		(width 0.14478)
		(layer "In13.Cu")
		(net "M_B_CPU0_SA_DQ<13>")
	)
	(segment
		(start 305.564286 -214.971122)
		(end 305.709066 -215.115902)
		(width 0.14478)
		(layer "In13.Cu")
		(net "M_B_CPU0_SA_DQ<13>")
	)
	(segment
		(start 305.970686 -215.115902)
		(end 306.115466 -214.971122)
		(width 0.14478)
		(layer "In13.Cu")
		(net "M_B_CPU0_SA_DQ<13>")
	)
	(segment
		(start 304.461926 -214.971122)
		(end 304.606706 -215.115902)
		(width 0.14478)
		(layer "In13.Cu")
		(net "M_B_CPU0_SA_DQ<13>")
	)
	(segment
		(start 331.229716 -234.281472)
		(end 331.238098 -234.276646)
		(width 0.0889)
		(layer "In13.Cu")
		(net "M_B_CPU0_SA_DQ<13>")
	)
	(segment
		(start 307.48859 -214.366094)
		(end 318.143128 -225.020632)
		(width 0.14478)
		(layer "In13.Cu")
		(net "M_B_CPU0_SA_DQ<13>")
	)
	(segment
		(start 300.620684 -213.518242)
		(end 300.882304 -213.518242)
		(width 0.14478)
		(layer "In13.Cu")
		(net "M_B_CPU0_SA_DQ<13>")
	)
	(segment
		(start 305.013106 -214.510874)
		(end 305.157886 -214.366094)
		(width 0.14478)
		(layer "In13.Cu")
		(net "M_B_CPU0_SA_DQ<13>")
	)
	(segment
		(start 336.845148 -234.219496)
		(end 336.691224 -233.954066)
		(width 0.0889)
		(layer "In13.Cu")
		(net "M_B_CPU0_SA_DQ<13>")
	)
	(segment
		(start 299.82414 -214.335106)
		(end 299.848778 -214.310468)
		(width 0.14478)
		(layer "In13.Cu")
		(net "M_B_CPU0_SA_DQ<13>")
	)
	(segment
		(start 305.157886 -214.366094)
		(end 305.419506 -214.366094)
		(width 0.14478)
		(layer "In13.Cu")
		(net "M_B_CPU0_SA_DQ<13>")
	)
	(segment
		(start 300.882304 -213.518242)
		(end 301.027084 -213.663022)
		(width 0.14478)
		(layer "In13.Cu")
		(net "M_B_CPU0_SA_DQ<13>")
	)
	(segment
		(start 326.618092 -233.407712)
		(end 327.410826 -234.200446)
		(width 0.0889)
		(layer "In13.Cu")
		(net "M_B_CPU0_SA_DQ<13>")
	)
	(segment
		(start 299.848778 -214.310468)
		(end 300.331124 -214.310468)
		(width 0.14478)
		(layer "In13.Cu")
		(net "M_B_CPU0_SA_DQ<13>")
	)
	(segment
		(start 324.09638 -231.775254)
		(end 324.560438 -232.239312)
		(width 0.0889)
		(layer "In13.Cu")
		(net "M_B_CPU0_SA_DQ<13>")
	)
	(segment
		(start 318.143128 -225.020632)
		(end 318.143128 -226.686872)
		(width 0.14478)
		(layer "In13.Cu")
		(net "M_B_CPU0_SA_DQ<13>")
	)
	(segment
		(start 302.62195 -214.986362)
		(end 302.785018 -215.14943)
		(width 0.14478)
		(layer "In13.Cu")
		(net "M_B_CPU0_SA_DQ<13>")
	)
	(segment
		(start 332.16977 -234.281472)
		(end 332.178152 -234.276646)
		(width 0.0889)
		(layer "In13.Cu")
		(net "M_B_CPU0_SA_DQ<13>")
	)
	(segment
		(start 303.341532 -214.760048)
		(end 303.531778 -214.760048)
		(width 0.14478)
		(layer "In13.Cu")
		(net "M_B_CPU0_SA_DQ<13>")
	)
	(segment
		(start 324.877684 -232.239312)
		(end 326.046084 -233.407712)
		(width 0.0889)
		(layer "In13.Cu")
		(net "M_B_CPU0_SA_DQ<13>")
	)
	(segment
		(start 303.178464 -214.923116)
		(end 303.341532 -214.760048)
		(width 0.14478)
		(layer "In13.Cu")
		(net "M_B_CPU0_SA_DQ<13>")
	)
	(segment
		(start 302.47717 -214.310468)
		(end 302.62195 -214.455248)
		(width 0.14478)
		(layer "In13.Cu")
		(net "M_B_CPU0_SA_DQ<13>")
	)
	(segment
		(start 303.531778 -214.760048)
		(end 303.925732 -214.366094)
		(width 0.14478)
		(layer "In13.Cu")
		(net "M_B_CPU0_SA_DQ<13>")
	)
	(segment
		(start 328.409808 -234.281472)
		(end 328.41819 -234.276646)
		(width 0.0889)
		(layer "In13.Cu")
		(net "M_B_CPU0_SA_DQ<13>")
	)
	(segment
		(start 303.925732 -214.366094)
		(end 304.317146 -214.366094)
		(width 0.14478)
		(layer "In13.Cu")
		(net "M_B_CPU0_SA_DQ<13>")
	)
	(segment
		(start 326.046084 -233.407712)
		(end 326.618092 -233.407712)
		(width 0.0889)
		(layer "In13.Cu")
		(net "M_B_CPU0_SA_DQ<13>")
	)
	(segment
		(start 333.684118 -234.276646)
		(end 333.6925 -234.281472)
		(width 0.0889)
		(layer "In13.Cu")
		(net "M_B_CPU0_SA_DQ<13>")
	)
	(segment
		(start 335.929732 -234.281472)
		(end 335.938114 -234.276646)
		(width 0.0889)
		(layer "In13.Cu")
		(net "M_B_CPU0_SA_DQ<13>")
	)
	(segment
		(start 304.606706 -215.115902)
		(end 304.868326 -215.115902)
		(width 0.14478)
		(layer "In13.Cu")
		(net "M_B_CPU0_SA_DQ<13>")
	)
	(segment
		(start 304.317146 -214.366094)
		(end 304.461926 -214.510874)
		(width 0.14478)
		(layer "In13.Cu")
		(net "M_B_CPU0_SA_DQ<13>")
	)
	(segment
		(start 305.013106 -214.971122)
		(end 305.013106 -214.510874)
		(width 0.14478)
		(layer "In13.Cu")
		(net "M_B_CPU0_SA_DQ<13>")
	)
	(segment
		(start 328.984102 -234.276646)
		(end 328.992484 -234.281472)
		(width 0.0889)
		(layer "In13.Cu")
		(net "M_B_CPU0_SA_DQ<13>")
	)
	(segment
		(start 304.461926 -214.510874)
		(end 304.461926 -214.971122)
		(width 0.14478)
		(layer "In13.Cu")
		(net "M_B_CPU0_SA_DQ<13>")
	)
	(segment
		(start 305.709066 -215.115902)
		(end 305.970686 -215.115902)
		(width 0.14478)
		(layer "In13.Cu")
		(net "M_B_CPU0_SA_DQ<13>")
	)
	(segment
		(start 302.62195 -214.455248)
		(end 302.62195 -214.986362)
		(width 0.14478)
		(layer "In13.Cu")
		(net "M_B_CPU0_SA_DQ<13>")
	)
	(segment
		(start 303.178464 -214.986362)
		(end 303.178464 -214.923116)
		(width 0.14478)
		(layer "In13.Cu")
		(net "M_B_CPU0_SA_DQ<13>")
	)
	(segment
		(start 306.115466 -214.971122)
		(end 306.115466 -214.510874)
		(width 0.14478)
		(layer "In13.Cu")
		(net "M_B_CPU0_SA_DQ<13>")
	)
	(segment
		(start 305.564286 -214.510874)
		(end 305.564286 -214.971122)
		(width 0.14478)
		(layer "In13.Cu")
		(net "M_B_CPU0_SA_DQ<13>")
	)
	(segment
		(start 332.744064 -234.276646)
		(end 332.752446 -234.281472)
		(width 0.0889)
		(layer "In13.Cu")
		(net "M_B_CPU0_SA_DQ<13>")
	)
	(arc
		(start 331.238098 -234.276646)
		(mid 331.521054 -234.200469)
		(end 331.80401 -234.276646)
		(width 0.0889)
		(layer "In13.Cu")
		(net "M_B_CPU0_SA_DQ<13>")
	)
	(arc
		(start 332.752446 -234.281472)
		(mid 332.935954 -234.326966)
		(end 333.118206 -234.276646)
		(width 0.0889)
		(layer "In13.Cu")
		(net "M_B_CPU0_SA_DQ<13>")
	)
	(arc
		(start 334.624172 -234.276646)
		(mid 334.811116 -234.326901)
		(end 334.99806 -234.276646)
		(width 0.0889)
		(layer "In13.Cu")
		(net "M_B_CPU0_SA_DQ<13>")
	)
	(arc
		(start 333.6925 -234.281472)
		(mid 333.876008 -234.326966)
		(end 334.05826 -234.276646)
		(width 0.0889)
		(layer "In13.Cu")
		(net "M_B_CPU0_SA_DQ<13>")
	)
	(arc
		(start 330.863956 -234.276646)
		(mid 331.046207 -234.326996)
		(end 331.229716 -234.281472)
		(width 0.0889)
		(layer "In13.Cu")
		(net "M_B_CPU0_SA_DQ<13>")
	)
	(arc
		(start 335.563972 -234.276646)
		(mid 335.746223 -234.326996)
		(end 335.929732 -234.281472)
		(width 0.0889)
		(layer "In13.Cu")
		(net "M_B_CPU0_SA_DQ<13>")
	)
	(arc
		(start 333.118206 -234.276646)
		(mid 333.401162 -234.200469)
		(end 333.684118 -234.276646)
		(width 0.0889)
		(layer "In13.Cu")
		(net "M_B_CPU0_SA_DQ<13>")
	)
	(arc
		(start 334.05826 -234.276646)
		(mid 334.341216 -234.200469)
		(end 334.624172 -234.276646)
		(width 0.0889)
		(layer "In13.Cu")
		(net "M_B_CPU0_SA_DQ<13>")
	)
	(arc
		(start 334.99806 -234.276646)
		(mid 335.281016 -234.200469)
		(end 335.563972 -234.276646)
		(width 0.0889)
		(layer "In13.Cu")
		(net "M_B_CPU0_SA_DQ<13>")
	)
	(arc
		(start 328.992484 -234.281472)
		(mid 329.175992 -234.326966)
		(end 329.358244 -234.276646)
		(width 0.0889)
		(layer "In13.Cu")
		(net "M_B_CPU0_SA_DQ<13>")
	)
	(arc
		(start 331.80401 -234.276646)
		(mid 331.986261 -234.326996)
		(end 332.16977 -234.281472)
		(width 0.0889)
		(layer "In13.Cu")
		(net "M_B_CPU0_SA_DQ<13>")
	)
	(arc
		(start 328.41819 -234.276646)
		(mid 328.701146 -234.200469)
		(end 328.984102 -234.276646)
		(width 0.0889)
		(layer "In13.Cu")
		(net "M_B_CPU0_SA_DQ<13>")
	)
	(arc
		(start 336.504026 -234.276646)
		(mid 336.660464 -234.325617)
		(end 336.822796 -234.302808)
		(width 0.0889)
		(layer "In13.Cu")
		(net "M_B_CPU0_SA_DQ<13>")
	)
	(arc
		(start 329.358244 -234.276646)
		(mid 329.6412 -234.200469)
		(end 329.924156 -234.276646)
		(width 0.0889)
		(layer "In13.Cu")
		(net "M_B_CPU0_SA_DQ<13>")
	)
	(arc
		(start 327.761346 -234.200446)
		(mid 327.907736 -234.219857)
		(end 328.044048 -234.276646)
		(width 0.0889)
		(layer "In13.Cu")
		(net "M_B_CPU0_SA_DQ<13>")
	)
	(arc
		(start 335.938114 -234.276646)
		(mid 336.22107 -234.200469)
		(end 336.504026 -234.276646)
		(width 0.0889)
		(layer "In13.Cu")
		(net "M_B_CPU0_SA_DQ<13>")
	)
	(arc
		(start 328.044048 -234.276646)
		(mid 328.226299 -234.326996)
		(end 328.409808 -234.281472)
		(width 0.0889)
		(layer "In13.Cu")
		(net "M_B_CPU0_SA_DQ<13>")
	)
	(arc
		(start 332.178152 -234.276646)
		(mid 332.461108 -234.200469)
		(end 332.744064 -234.276646)
		(width 0.0889)
		(layer "In13.Cu")
		(net "M_B_CPU0_SA_DQ<13>")
	)
	(arc
		(start 330.298044 -234.276646)
		(mid 330.581 -234.200469)
		(end 330.863956 -234.276646)
		(width 0.0889)
		(layer "In13.Cu")
		(net "M_B_CPU0_SA_DQ<13>")
	)
	(arc
		(start 329.924156 -234.276646)
		(mid 330.1111 -234.326901)
		(end 330.298044 -234.276646)
		(width 0.0889)
		(layer "In13.Cu")
		(net "M_B_CPU0_SA_DQ<13>")
	)
	(segment
		(start 335.747868 -233.409998)
		(end 335.281016 -233.14406)
		(width 0.10668)
		(layer "F.Cu")
		(net "M_B_CPU0_SA_DQ<12>")
	)
	(segment
		(start 325.469758 -232.000298)
		(end 326.201532 -232.732072)
		(width 0.0889)
		(layer "In13.Cu")
		(net "M_B_CPU0_SA_DQ<12>")
	)
	(segment
		(start 324.979538 -231.070912)
		(end 325.469758 -231.561132)
		(width 0.0889)
		(layer "In13.Cu")
		(net "M_B_CPU0_SA_DQ<12>")
	)
	(segment
		(start 321.694302 -228.966014)
		(end 321.977258 -229.24897)
		(width 0.14478)
		(layer "In13.Cu")
		(net "M_B_CPU0_SA_DQ<12>")
	)
	(segment
		(start 306.510944 -213.294468)
		(end 306.510944 -213.231222)
		(width 0.14478)
		(layer "In13.Cu")
		(net "M_B_CPU0_SA_DQ<12>")
	)
	(segment
		(start 329.819762 -233.471466)
		(end 329.828144 -233.46664)
		(width 0.0889)
		(layer "In13.Cu")
		(net "M_B_CPU0_SA_DQ<12>")
	)
	(segment
		(start 319.185544 -224.91319)
		(end 319.063116 -225.035618)
		(width 0.14478)
		(layer "In13.Cu")
		(net "M_B_CPU0_SA_DQ<12>")
	)
	(segment
		(start 320.018918 -225.857562)
		(end 319.874138 -226.002342)
		(width 0.14478)
		(layer "In13.Cu")
		(net "M_B_CPU0_SA_DQ<12>")
	)
	(segment
		(start 300.298612 -212.610446)
		(end 300.443392 -212.465666)
		(width 0.14478)
		(layer "In13.Cu")
		(net "M_B_CPU0_SA_DQ<12>")
	)
	(segment
		(start 320.914522 -227.972366)
		(end 320.914522 -228.186234)
		(width 0.14478)
		(layer "In13.Cu")
		(net "M_B_CPU0_SA_DQ<12>")
	)
	(segment
		(start 300.994572 -212.465666)
		(end 301.139352 -212.610446)
		(width 0.14478)
		(layer "In13.Cu")
		(net "M_B_CPU0_SA_DQ<12>")
	)
	(segment
		(start 319.248536 -225.425762)
		(end 319.452752 -225.425508)
		(width 0.14478)
		(layer "In13.Cu")
		(net "M_B_CPU0_SA_DQ<12>")
	)
	(segment
		(start 330.394056 -233.46664)
		(end 330.402438 -233.471466)
		(width 0.0889)
		(layer "In13.Cu")
		(net "M_B_CPU0_SA_DQ<12>")
	)
	(segment
		(start 305.018186 -213.456012)
		(end 305.246532 -213.456012)
		(width 0.14478)
		(layer "In13.Cu")
		(net "M_B_CPU0_SA_DQ<12>")
	)
	(segment
		(start 319.57518 -225.30308)
		(end 319.779904 -225.30308)
		(width 0.14478)
		(layer "In13.Cu")
		(net "M_B_CPU0_SA_DQ<12>")
	)
	(segment
		(start 302.506126 -213.069678)
		(end 302.650906 -213.214458)
		(width 0.14478)
		(layer "In13.Cu")
		(net "M_B_CPU0_SA_DQ<12>")
	)
	(segment
		(start 303.040796 -213.456012)
		(end 303.20234 -213.294468)
		(width 0.14478)
		(layer "In13.Cu")
		(net "M_B_CPU0_SA_DQ<12>")
	)
	(segment
		(start 304.305208 -213.231222)
		(end 304.466752 -213.069678)
		(width 0.14478)
		(layer "In13.Cu")
		(net "M_B_CPU0_SA_DQ<12>")
	)
	(segment
		(start 320.018918 -226.698302)
		(end 320.018918 -227.29063)
		(width 0.14478)
		(layer "In13.Cu")
		(net "M_B_CPU0_SA_DQ<12>")
	)
	(segment
		(start 320.914522 -228.186234)
		(end 321.197478 -228.46919)
		(width 0.14478)
		(layer "In13.Cu")
		(net "M_B_CPU0_SA_DQ<12>")
	)
	(segment
		(start 304.466752 -213.069678)
		(end 304.695098 -213.069678)
		(width 0.14478)
		(layer "In13.Cu")
		(net "M_B_CPU0_SA_DQ<12>")
	)
	(segment
		(start 334.519778 -233.471466)
		(end 334.52816 -233.46664)
		(width 0.0889)
		(layer "In13.Cu")
		(net "M_B_CPU0_SA_DQ<12>")
	)
	(segment
		(start 300.849792 -212.226652)
		(end 300.994572 -212.371432)
		(width 0.14478)
		(layer "In13.Cu")
		(net "M_B_CPU0_SA_DQ<12>")
	)
	(segment
		(start 299.848778 -212.610446)
		(end 300.298612 -212.610446)
		(width 0.14478)
		(layer "In13.Cu")
		(net "M_B_CPU0_SA_DQ<12>")
	)
	(segment
		(start 303.35982 -212.749384)
		(end 303.588166 -212.749384)
		(width 0.14478)
		(layer "In13.Cu")
		(net "M_B_CPU0_SA_DQ<12>")
	)
	(segment
		(start 322.474082 -229.745794)
		(end 322.757038 -230.02875)
		(width 0.14478)
		(layer "In13.Cu")
		(net "M_B_CPU0_SA_DQ<12>")
	)
	(segment
		(start 335.094072 -233.46664)
		(end 335.102454 -233.471466)
		(width 0.0889)
		(layer "In13.Cu")
		(net "M_B_CPU0_SA_DQ<12>")
	)
	(segment
		(start 304.143664 -213.456012)
		(end 304.305208 -213.294468)
		(width 0.14478)
		(layer "In13.Cu")
		(net "M_B_CPU0_SA_DQ<12>")
	)
	(segment
		(start 321.197478 -228.46919)
		(end 321.411346 -228.46919)
		(width 0.14478)
		(layer "In13.Cu")
		(net "M_B_CPU0_SA_DQ<12>")
	)
	(segment
		(start 321.411346 -228.46919)
		(end 321.694302 -228.752146)
		(width 0.14478)
		(layer "In13.Cu")
		(net "M_B_CPU0_SA_DQ<12>")
	)
	(segment
		(start 305.797966 -213.069678)
		(end 305.95951 -213.231222)
		(width 0.14478)
		(layer "In13.Cu")
		(net "M_B_CPU0_SA_DQ<12>")
	)
	(segment
		(start 322.474082 -229.531926)
		(end 322.474082 -229.745794)
		(width 0.14478)
		(layer "In13.Cu")
		(net "M_B_CPU0_SA_DQ<12>")
	)
	(segment
		(start 303.753774 -212.914992)
		(end 303.753774 -213.294468)
		(width 0.14478)
		(layer "In13.Cu")
		(net "M_B_CPU0_SA_DQ<12>")
	)
	(segment
		(start 319.452752 -225.425508)
		(end 319.57518 -225.30308)
		(width 0.14478)
		(layer "In13.Cu")
		(net "M_B_CPU0_SA_DQ<12>")
	)
	(segment
		(start 302.650906 -213.294468)
		(end 302.81245 -213.456012)
		(width 0.14478)
		(layer "In13.Cu")
		(net "M_B_CPU0_SA_DQ<12>")
	)
	(segment
		(start 323.253862 -230.525574)
		(end 323.599302 -230.871014)
		(width 0.14478)
		(layer "In13.Cu")
		(net "M_B_CPU0_SA_DQ<12>")
	)
	(segment
		(start 300.588172 -212.226652)
		(end 300.849792 -212.226652)
		(width 0.14478)
		(layer "In13.Cu")
		(net "M_B_CPU0_SA_DQ<12>")
	)
	(segment
		(start 319.063116 -225.035618)
		(end 319.063116 -225.240342)
		(width 0.14478)
		(layer "In13.Cu")
		(net "M_B_CPU0_SA_DQ<12>")
	)
	(segment
		(start 305.408076 -213.294468)
		(end 305.408076 -213.231222)
		(width 0.14478)
		(layer "In13.Cu")
		(net "M_B_CPU0_SA_DQ<12>")
	)
	(segment
		(start 300.443392 -212.371432)
		(end 300.588172 -212.226652)
		(width 0.14478)
		(layer "In13.Cu")
		(net "M_B_CPU0_SA_DQ<12>")
	)
	(segment
		(start 320.018918 -227.29063)
		(end 320.417698 -227.68941)
		(width 0.14478)
		(layer "In13.Cu")
		(net "M_B_CPU0_SA_DQ<12>")
	)
	(segment
		(start 331.33411 -233.46664)
		(end 331.342492 -233.471466)
		(width 0.0889)
		(layer "In13.Cu")
		(net "M_B_CPU0_SA_DQ<12>")
	)
	(segment
		(start 303.915318 -213.456012)
		(end 304.143664 -213.456012)
		(width 0.14478)
		(layer "In13.Cu")
		(net "M_B_CPU0_SA_DQ<12>")
	)
	(segment
		(start 305.95951 -213.231222)
		(end 305.95951 -213.294468)
		(width 0.14478)
		(layer "In13.Cu")
		(net "M_B_CPU0_SA_DQ<12>")
	)
	(segment
		(start 306.672488 -213.069678)
		(end 307.546502 -213.069678)
		(width 0.14478)
		(layer "In13.Cu")
		(net "M_B_CPU0_SA_DQ<12>")
	)
	(segment
		(start 319.134744 -226.147122)
		(end 319.134744 -226.406456)
		(width 0.14478)
		(layer "In13.Cu")
		(net "M_B_CPU0_SA_DQ<12>")
	)
	(segment
		(start 300.994572 -212.371432)
		(end 300.994572 -212.465666)
		(width 0.14478)
		(layer "In13.Cu")
		(net "M_B_CPU0_SA_DQ<12>")
	)
	(segment
		(start 304.856642 -213.294468)
		(end 305.018186 -213.456012)
		(width 0.14478)
		(layer "In13.Cu")
		(net "M_B_CPU0_SA_DQ<12>")
	)
	(segment
		(start 305.408076 -213.231222)
		(end 305.56962 -213.069678)
		(width 0.14478)
		(layer "In13.Cu")
		(net "M_B_CPU0_SA_DQ<12>")
	)
	(segment
		(start 305.246532 -213.456012)
		(end 305.408076 -213.294468)
		(width 0.14478)
		(layer "In13.Cu")
		(net "M_B_CPU0_SA_DQ<12>")
	)
	(segment
		(start 325.469758 -231.561132)
		(end 325.469758 -232.000298)
		(width 0.0889)
		(layer "In13.Cu")
		(net "M_B_CPU0_SA_DQ<12>")
	)
	(segment
		(start 306.510944 -213.231222)
		(end 306.672488 -213.069678)
		(width 0.14478)
		(layer "In13.Cu")
		(net "M_B_CPU0_SA_DQ<12>")
	)
	(segment
		(start 302.011842 -213.069678)
		(end 302.506126 -213.069678)
		(width 0.14478)
		(layer "In13.Cu")
		(net "M_B_CPU0_SA_DQ<12>")
	)
	(segment
		(start 302.81245 -213.456012)
		(end 303.040796 -213.456012)
		(width 0.14478)
		(layer "In13.Cu")
		(net "M_B_CPU0_SA_DQ<12>")
	)
	(segment
		(start 304.305208 -213.294468)
		(end 304.305208 -213.231222)
		(width 0.14478)
		(layer "In13.Cu")
		(net "M_B_CPU0_SA_DQ<12>")
	)
	(segment
		(start 303.753774 -213.294468)
		(end 303.915318 -213.456012)
		(width 0.14478)
		(layer "In13.Cu")
		(net "M_B_CPU0_SA_DQ<12>")
	)
	(segment
		(start 304.856642 -213.231222)
		(end 304.856642 -213.294468)
		(width 0.14478)
		(layer "In13.Cu")
		(net "M_B_CPU0_SA_DQ<12>")
	)
	(segment
		(start 327.57491 -233.466386)
		(end 327.594976 -233.477816)
		(width 0.0889)
		(layer "In13.Cu")
		(net "M_B_CPU0_SA_DQ<12>")
	)
	(segment
		(start 320.018918 -225.542094)
		(end 320.018918 -225.857562)
		(width 0.14478)
		(layer "In13.Cu")
		(net "M_B_CPU0_SA_DQ<12>")
	)
	(segment
		(start 319.279524 -226.002342)
		(end 319.134744 -226.147122)
		(width 0.14478)
		(layer "In13.Cu")
		(net "M_B_CPU0_SA_DQ<12>")
	)
	(segment
		(start 335.435194 -233.40949)
		(end 335.281016 -233.14406)
		(width 0.0889)
		(layer "In13.Cu")
		(net "M_B_CPU0_SA_DQ<12>")
	)
	(segment
		(start 323.253862 -230.311706)
		(end 323.253862 -230.525574)
		(width 0.14478)
		(layer "In13.Cu")
		(net "M_B_CPU0_SA_DQ<12>")
	)
	(segment
		(start 305.95951 -213.294468)
		(end 306.121054 -213.456012)
		(width 0.14478)
		(layer "In13.Cu")
		(net "M_B_CPU0_SA_DQ<12>")
	)
	(segment
		(start 319.063116 -225.240342)
		(end 319.248536 -225.425762)
		(width 0.14478)
		(layer "In13.Cu")
		(net "M_B_CPU0_SA_DQ<12>")
	)
	(segment
		(start 322.970906 -230.02875)
		(end 323.253862 -230.311706)
		(width 0.14478)
		(layer "In13.Cu")
		(net "M_B_CPU0_SA_DQ<12>")
	)
	(segment
		(start 302.650906 -213.214458)
		(end 302.650906 -213.294468)
		(width 0.14478)
		(layer "In13.Cu")
		(net "M_B_CPU0_SA_DQ<12>")
	)
	(segment
		(start 304.695098 -213.069678)
		(end 304.856642 -213.231222)
		(width 0.14478)
		(layer "In13.Cu")
		(net "M_B_CPU0_SA_DQ<12>")
	)
	(segment
		(start 301.55261 -212.610446)
		(end 302.011842 -213.069678)
		(width 0.14478)
		(layer "In13.Cu")
		(net "M_B_CPU0_SA_DQ<12>")
	)
	(segment
		(start 323.599302 -230.871014)
		(end 323.859398 -230.871014)
		(width 0.14478)
		(layer "In13.Cu")
		(net "M_B_CPU0_SA_DQ<12>")
	)
	(segment
		(start 326.201532 -232.732072)
		(end 326.822562 -232.732072)
		(width 0.0889)
		(layer "In13.Cu")
		(net "M_B_CPU0_SA_DQ<12>")
	)
	(segment
		(start 324.372478 -231.070912)
		(end 324.979538 -231.070912)
		(width 0.0889)
		(layer "In13.Cu")
		(net "M_B_CPU0_SA_DQ<12>")
	)
	(segment
		(start 307.546502 -213.069678)
		(end 319.18529 -224.708466)
		(width 0.14478)
		(layer "In13.Cu")
		(net "M_B_CPU0_SA_DQ<12>")
	)
	(segment
		(start 326.822562 -232.732072)
		(end 327.497948 -233.407458)
		(width 0.0889)
		(layer "In13.Cu")
		(net "M_B_CPU0_SA_DQ<12>")
	)
	(segment
		(start 299.82414 -212.635084)
		(end 299.848778 -212.610446)
		(width 0.14478)
		(layer "In13.Cu")
		(net "M_B_CPU0_SA_DQ<12>")
	)
	(segment
		(start 322.757038 -230.02875)
		(end 322.970906 -230.02875)
		(width 0.14478)
		(layer "In13.Cu")
		(net "M_B_CPU0_SA_DQ<12>")
	)
	(segment
		(start 322.191126 -229.24897)
		(end 322.474082 -229.531926)
		(width 0.14478)
		(layer "In13.Cu")
		(net "M_B_CPU0_SA_DQ<12>")
	)
	(segment
		(start 327.497948 -233.407458)
		(end 327.497948 -233.407204)
		(width 0.0889)
		(layer "In13.Cu")
		(net "M_B_CPU0_SA_DQ<12>")
	)
	(segment
		(start 303.20234 -213.294468)
		(end 303.20234 -212.906864)
		(width 0.14478)
		(layer "In13.Cu")
		(net "M_B_CPU0_SA_DQ<12>")
	)
	(segment
		(start 320.417698 -227.68941)
		(end 320.631566 -227.68941)
		(width 0.14478)
		(layer "In13.Cu")
		(net "M_B_CPU0_SA_DQ<12>")
	)
	(segment
		(start 301.139352 -212.610446)
		(end 301.55261 -212.610446)
		(width 0.14478)
		(layer "In13.Cu")
		(net "M_B_CPU0_SA_DQ<12>")
	)
	(segment
		(start 319.18529 -224.708466)
		(end 319.185544 -224.91319)
		(width 0.14478)
		(layer "In13.Cu")
		(net "M_B_CPU0_SA_DQ<12>")
	)
	(segment
		(start 305.56962 -213.069678)
		(end 305.797966 -213.069678)
		(width 0.14478)
		(layer "In13.Cu")
		(net "M_B_CPU0_SA_DQ<12>")
	)
	(segment
		(start 319.28181 -226.553522)
		(end 319.874138 -226.553522)
		(width 0.14478)
		(layer "In13.Cu")
		(net "M_B_CPU0_SA_DQ<12>")
	)
	(segment
		(start 319.134744 -226.406456)
		(end 319.28181 -226.553522)
		(width 0.14478)
		(layer "In13.Cu")
		(net "M_B_CPU0_SA_DQ<12>")
	)
	(segment
		(start 300.443392 -212.465666)
		(end 300.443392 -212.371432)
		(width 0.14478)
		(layer "In13.Cu")
		(net "M_B_CPU0_SA_DQ<12>")
	)
	(segment
		(start 321.977258 -229.24897)
		(end 322.191126 -229.24897)
		(width 0.14478)
		(layer "In13.Cu")
		(net "M_B_CPU0_SA_DQ<12>")
	)
	(segment
		(start 303.20234 -212.906864)
		(end 303.35982 -212.749384)
		(width 0.14478)
		(layer "In13.Cu")
		(net "M_B_CPU0_SA_DQ<12>")
	)
	(segment
		(start 303.588166 -212.749384)
		(end 303.753774 -212.914992)
		(width 0.14478)
		(layer "In13.Cu")
		(net "M_B_CPU0_SA_DQ<12>")
	)
	(segment
		(start 306.121054 -213.456012)
		(end 306.3494 -213.456012)
		(width 0.14478)
		(layer "In13.Cu")
		(net "M_B_CPU0_SA_DQ<12>")
	)
	(segment
		(start 306.3494 -213.456012)
		(end 306.510944 -213.294468)
		(width 0.14478)
		(layer "In13.Cu")
		(net "M_B_CPU0_SA_DQ<12>")
	)
	(segment
		(start 324.17258 -230.871014)
		(end 324.372478 -231.070912)
		(width 0.0889)
		(layer "In13.Cu")
		(net "M_B_CPU0_SA_DQ<12>")
	)
	(segment
		(start 319.874138 -226.002342)
		(end 319.279524 -226.002342)
		(width 0.14478)
		(layer "In13.Cu")
		(net "M_B_CPU0_SA_DQ<12>")
	)
	(segment
		(start 333.579724 -233.471466)
		(end 333.588106 -233.46664)
		(width 0.0889)
		(layer "In13.Cu")
		(net "M_B_CPU0_SA_DQ<12>")
	)
	(segment
		(start 321.694302 -228.752146)
		(end 321.694302 -228.966014)
		(width 0.14478)
		(layer "In13.Cu")
		(net "M_B_CPU0_SA_DQ<12>")
	)
	(segment
		(start 335.412842 -233.492802)
		(end 335.435194 -233.40949)
		(width 0.0889)
		(layer "In13.Cu")
		(net "M_B_CPU0_SA_DQ<12>")
	)
	(segment
		(start 319.779904 -225.30308)
		(end 320.018918 -225.542094)
		(width 0.14478)
		(layer "In13.Cu")
		(net "M_B_CPU0_SA_DQ<12>")
	)
	(segment
		(start 323.859398 -230.871014)
		(end 324.17258 -230.871014)
		(width 0.0889)
		(layer "In13.Cu")
		(net "M_B_CPU0_SA_DQ<12>")
	)
	(segment
		(start 319.874138 -226.553522)
		(end 320.018918 -226.698302)
		(width 0.14478)
		(layer "In13.Cu")
		(net "M_B_CPU0_SA_DQ<12>")
	)
	(segment
		(start 320.631566 -227.68941)
		(end 320.914522 -227.972366)
		(width 0.14478)
		(layer "In13.Cu")
		(net "M_B_CPU0_SA_DQ<12>")
	)
	(arc
		(start 335.102454 -233.471466)
		(mid 335.255324 -233.516107)
		(end 335.412842 -233.492802)
		(width 0.0889)
		(layer "In13.Cu")
		(net "M_B_CPU0_SA_DQ<12>")
	)
	(arc
		(start 329.454002 -233.46664)
		(mid 329.636253 -233.51699)
		(end 329.819762 -233.471466)
		(width 0.0889)
		(layer "In13.Cu")
		(net "M_B_CPU0_SA_DQ<12>")
	)
	(arc
		(start 327.594976 -233.477816)
		(mid 327.773054 -233.5168)
		(end 327.94829 -233.46664)
		(width 0.0889)
		(layer "In13.Cu")
		(net "M_B_CPU0_SA_DQ<12>")
	)
	(arc
		(start 329.828144 -233.46664)
		(mid 330.1111 -233.390463)
		(end 330.394056 -233.46664)
		(width 0.0889)
		(layer "In13.Cu")
		(net "M_B_CPU0_SA_DQ<12>")
	)
	(arc
		(start 333.213964 -233.46664)
		(mid 333.396215 -233.51699)
		(end 333.579724 -233.471466)
		(width 0.0889)
		(layer "In13.Cu")
		(net "M_B_CPU0_SA_DQ<12>")
	)
	(arc
		(start 334.52816 -233.46664)
		(mid 334.811116 -233.390463)
		(end 335.094072 -233.46664)
		(width 0.0889)
		(layer "In13.Cu")
		(net "M_B_CPU0_SA_DQ<12>")
	)
	(arc
		(start 328.88809 -233.46664)
		(mid 329.171046 -233.390463)
		(end 329.454002 -233.46664)
		(width 0.0889)
		(layer "In13.Cu")
		(net "M_B_CPU0_SA_DQ<12>")
	)
	(arc
		(start 330.402438 -233.471466)
		(mid 330.585946 -233.51696)
		(end 330.768198 -233.46664)
		(width 0.0889)
		(layer "In13.Cu")
		(net "M_B_CPU0_SA_DQ<12>")
	)
	(arc
		(start 330.768198 -233.46664)
		(mid 331.051154 -233.390463)
		(end 331.33411 -233.46664)
		(width 0.0889)
		(layer "In13.Cu")
		(net "M_B_CPU0_SA_DQ<12>")
	)
	(arc
		(start 327.497948 -233.407204)
		(mid 327.53449 -233.439316)
		(end 327.57491 -233.466386)
		(width 0.0889)
		(layer "In13.Cu")
		(net "M_B_CPU0_SA_DQ<12>")
	)
	(arc
		(start 331.342492 -233.471466)
		(mid 331.526 -233.51696)
		(end 331.708252 -233.46664)
		(width 0.0889)
		(layer "In13.Cu")
		(net "M_B_CPU0_SA_DQ<12>")
	)
	(arc
		(start 331.708252 -233.46664)
		(mid 331.991208 -233.390463)
		(end 332.274164 -233.46664)
		(width 0.0889)
		(layer "In13.Cu")
		(net "M_B_CPU0_SA_DQ<12>")
	)
	(arc
		(start 332.648052 -233.46664)
		(mid 332.931008 -233.390463)
		(end 333.213964 -233.46664)
		(width 0.0889)
		(layer "In13.Cu")
		(net "M_B_CPU0_SA_DQ<12>")
	)
	(arc
		(start 334.154018 -233.46664)
		(mid 334.336269 -233.51699)
		(end 334.519778 -233.471466)
		(width 0.0889)
		(layer "In13.Cu")
		(net "M_B_CPU0_SA_DQ<12>")
	)
	(arc
		(start 328.514202 -233.46664)
		(mid 328.701146 -233.516895)
		(end 328.88809 -233.46664)
		(width 0.0889)
		(layer "In13.Cu")
		(net "M_B_CPU0_SA_DQ<12>")
	)
	(arc
		(start 327.94829 -233.46664)
		(mid 328.231246 -233.390463)
		(end 328.514202 -233.46664)
		(width 0.0889)
		(layer "In13.Cu")
		(net "M_B_CPU0_SA_DQ<12>")
	)
	(arc
		(start 333.588106 -233.46664)
		(mid 333.871062 -233.390463)
		(end 334.154018 -233.46664)
		(width 0.0889)
		(layer "In13.Cu")
		(net "M_B_CPU0_SA_DQ<12>")
	)
	(arc
		(start 332.274164 -233.46664)
		(mid 332.461108 -233.516895)
		(end 332.648052 -233.46664)
		(width 0.0889)
		(layer "In13.Cu")
		(net "M_B_CPU0_SA_DQ<12>")
	)
	(segment
		(start 337.627976 -231.789986)
		(end 337.161124 -231.524048)
		(width 0.10668)
		(layer "F.Cu")
		(net "M_B_CPU0_SA_DQ<11>")
	)
	(segment
		(start 335.102454 -231.196896)
		(end 335.094072 -231.201722)
		(width 0.0889)
		(layer "In13.Cu")
		(net "M_B_CPU0_SA_DQ<11>")
	)
	(segment
		(start 299.30598 -208.983834)
		(end 298.384468 -208.800446)
		(width 0.14478)
		(layer "In13.Cu")
		(net "M_B_CPU0_SA_DQ<11>")
	)
	(segment
		(start 322.307458 -225.989134)
		(end 322.307458 -224.395792)
		(width 0.14478)
		(layer "In13.Cu")
		(net "M_B_CPU0_SA_DQ<11>")
	)
	(segment
		(start 323.992494 -227.67417)
		(end 322.307458 -225.989134)
		(width 0.14478)
		(layer "In13.Cu")
		(net "M_B_CPU0_SA_DQ<11>")
	)
	(segment
		(start 337.161124 -231.524048)
		(end 337.0072 -231.258618)
		(width 0.0889)
		(layer "In13.Cu")
		(net "M_B_CPU0_SA_DQ<11>")
	)
	(segment
		(start 299.857668 -209.21218)
		(end 299.30598 -208.983834)
		(width 0.14478)
		(layer "In13.Cu")
		(net "M_B_CPU0_SA_DQ<11>")
	)
	(segment
		(start 327.94829 -231.201722)
		(end 327.909174 -231.178862)
		(width 0.0889)
		(layer "In13.Cu")
		(net "M_B_CPU0_SA_DQ<11>")
	)
	(segment
		(start 331.342492 -231.196896)
		(end 331.33411 -231.201722)
		(width 0.0889)
		(layer "In13.Cu")
		(net "M_B_CPU0_SA_DQ<11>")
	)
	(segment
		(start 326.686418 -229.793292)
		(end 326.330818 -229.793292)
		(width 0.0889)
		(layer "In13.Cu")
		(net "M_B_CPU0_SA_DQ<11>")
	)
	(segment
		(start 309.422292 -211.397596)
		(end 309.163974 -211.20608)
		(width 0.14478)
		(layer "In13.Cu")
		(net "M_B_CPU0_SA_DQ<11>")
	)
	(segment
		(start 325.700898 -229.163372)
		(end 325.700898 -228.464872)
		(width 0.0889)
		(layer "In13.Cu")
		(net "M_B_CPU0_SA_DQ<11>")
	)
	(segment
		(start 330.402438 -231.196896)
		(end 330.394056 -231.201722)
		(width 0.0889)
		(layer "In13.Cu")
		(net "M_B_CPU0_SA_DQ<11>")
	)
	(segment
		(start 304.71999 -209.660236)
		(end 302.110394 -209.660236)
		(width 0.14478)
		(layer "In13.Cu")
		(net "M_B_CPU0_SA_DQ<11>")
	)
	(segment
		(start 337.0072 -231.258618)
		(end 336.911442 -231.233218)
		(width 0.0889)
		(layer "In13.Cu")
		(net "M_B_CPU0_SA_DQ<11>")
	)
	(segment
		(start 325.058278 -227.822252)
		(end 324.140576 -227.822252)
		(width 0.0889)
		(layer "In13.Cu")
		(net "M_B_CPU0_SA_DQ<11>")
	)
	(segment
		(start 325.700898 -228.464872)
		(end 325.058278 -227.822252)
		(width 0.0889)
		(layer "In13.Cu")
		(net "M_B_CPU0_SA_DQ<11>")
	)
	(segment
		(start 326.330818 -229.793292)
		(end 325.700898 -229.163372)
		(width 0.0889)
		(layer "In13.Cu")
		(net "M_B_CPU0_SA_DQ<11>")
	)
	(segment
		(start 302.110394 -209.660236)
		(end 299.857668 -209.21218)
		(width 0.14478)
		(layer "In13.Cu")
		(net "M_B_CPU0_SA_DQ<11>")
	)
	(segment
		(start 324.140576 -227.822252)
		(end 323.992494 -227.67417)
		(width 0.0889)
		(layer "In13.Cu")
		(net "M_B_CPU0_SA_DQ<11>")
	)
	(segment
		(start 298.060364 -208.800446)
		(end 295.874948 -209.23504)
		(width 0.14478)
		(layer "In13.Cu")
		(net "M_B_CPU0_SA_DQ<11>")
	)
	(segment
		(start 308.025292 -210.59775)
		(end 306.259992 -209.96656)
		(width 0.14478)
		(layer "In13.Cu")
		(net "M_B_CPU0_SA_DQ<11>")
	)
	(segment
		(start 306.259992 -209.96656)
		(end 304.71999 -209.660236)
		(width 0.14478)
		(layer "In13.Cu")
		(net "M_B_CPU0_SA_DQ<11>")
	)
	(segment
		(start 322.307458 -224.395792)
		(end 320.453258 -222.541592)
		(width 0.14478)
		(layer "In13.Cu")
		(net "M_B_CPU0_SA_DQ<11>")
	)
	(segment
		(start 336.042508 -231.196896)
		(end 336.034126 -231.201722)
		(width 0.0889)
		(layer "In13.Cu")
		(net "M_B_CPU0_SA_DQ<11>")
	)
	(segment
		(start 309.163974 -211.20608)
		(end 308.025292 -210.59775)
		(width 0.14478)
		(layer "In13.Cu")
		(net "M_B_CPU0_SA_DQ<11>")
	)
	(segment
		(start 333.588106 -231.201722)
		(end 333.579724 -231.196896)
		(width 0.0889)
		(layer "In13.Cu")
		(net "M_B_CPU0_SA_DQ<11>")
	)
	(segment
		(start 311.594246 -212.848952)
		(end 309.422292 -211.397596)
		(width 0.14478)
		(layer "In13.Cu")
		(net "M_B_CPU0_SA_DQ<11>")
	)
	(segment
		(start 298.384468 -208.800446)
		(end 298.060364 -208.800446)
		(width 0.14478)
		(layer "In13.Cu")
		(net "M_B_CPU0_SA_DQ<11>")
	)
	(segment
		(start 295.874948 -209.23504)
		(end 295.724072 -209.23504)
		(width 0.14478)
		(layer "In13.Cu")
		(net "M_B_CPU0_SA_DQ<11>")
	)
	(segment
		(start 320.453258 -221.707964)
		(end 311.594246 -212.848952)
		(width 0.14478)
		(layer "In13.Cu")
		(net "M_B_CPU0_SA_DQ<11>")
	)
	(segment
		(start 327.14565 -230.252524)
		(end 326.686418 -229.793292)
		(width 0.0889)
		(layer "In13.Cu")
		(net "M_B_CPU0_SA_DQ<11>")
	)
	(segment
		(start 329.828144 -231.201722)
		(end 329.819762 -231.196896)
		(width 0.0889)
		(layer "In13.Cu")
		(net "M_B_CPU0_SA_DQ<11>")
	)
	(segment
		(start 334.52816 -231.201722)
		(end 334.519778 -231.196896)
		(width 0.0889)
		(layer "In13.Cu")
		(net "M_B_CPU0_SA_DQ<11>")
	)
	(segment
		(start 320.453258 -222.541592)
		(end 320.453258 -221.707964)
		(width 0.14478)
		(layer "In13.Cu")
		(net "M_B_CPU0_SA_DQ<11>")
	)
	(arc
		(start 332.648052 -231.201722)
		(mid 332.461108 -231.151433)
		(end 332.274164 -231.201722)
		(width 0.0889)
		(layer "In13.Cu")
		(net "M_B_CPU0_SA_DQ<11>")
	)
	(arc
		(start 333.213964 -231.201722)
		(mid 332.931008 -231.277899)
		(end 332.648052 -231.201722)
		(width 0.0889)
		(layer "In13.Cu")
		(net "M_B_CPU0_SA_DQ<11>")
	)
	(arc
		(start 332.274164 -231.201722)
		(mid 331.991208 -231.277899)
		(end 331.708252 -231.201722)
		(width 0.0889)
		(layer "In13.Cu")
		(net "M_B_CPU0_SA_DQ<11>")
	)
	(arc
		(start 336.911442 -231.233218)
		(mid 336.65612 -231.276918)
		(end 336.408268 -231.201722)
		(width 0.0889)
		(layer "In13.Cu")
		(net "M_B_CPU0_SA_DQ<11>")
	)
	(arc
		(start 335.468214 -231.201722)
		(mid 335.285963 -231.151338)
		(end 335.102454 -231.196896)
		(width 0.0889)
		(layer "In13.Cu")
		(net "M_B_CPU0_SA_DQ<11>")
	)
	(arc
		(start 328.514202 -231.201722)
		(mid 328.231246 -231.277899)
		(end 327.94829 -231.201722)
		(width 0.0889)
		(layer "In13.Cu")
		(net "M_B_CPU0_SA_DQ<11>")
	)
	(arc
		(start 327.909174 -231.178862)
		(mid 327.730361 -230.976512)
		(end 327.665842 -230.714296)
		(width 0.0889)
		(layer "In13.Cu")
		(net "M_B_CPU0_SA_DQ<11>")
	)
	(arc
		(start 335.094072 -231.201722)
		(mid 334.811116 -231.277899)
		(end 334.52816 -231.201722)
		(width 0.0889)
		(layer "In13.Cu")
		(net "M_B_CPU0_SA_DQ<11>")
	)
	(arc
		(start 329.454002 -231.201722)
		(mid 329.171046 -231.277899)
		(end 328.88809 -231.201722)
		(width 0.0889)
		(layer "In13.Cu")
		(net "M_B_CPU0_SA_DQ<11>")
	)
	(arc
		(start 327.665842 -230.714296)
		(mid 327.616226 -230.528993)
		(end 327.480676 -230.39324)
		(width 0.0889)
		(layer "In13.Cu")
		(net "M_B_CPU0_SA_DQ<11>")
	)
	(arc
		(start 331.708252 -231.201722)
		(mid 331.526001 -231.151338)
		(end 331.342492 -231.196896)
		(width 0.0889)
		(layer "In13.Cu")
		(net "M_B_CPU0_SA_DQ<11>")
	)
	(arc
		(start 330.768198 -231.201722)
		(mid 330.585947 -231.151338)
		(end 330.402438 -231.196896)
		(width 0.0889)
		(layer "In13.Cu")
		(net "M_B_CPU0_SA_DQ<11>")
	)
	(arc
		(start 336.034126 -231.201722)
		(mid 335.75117 -231.277899)
		(end 335.468214 -231.201722)
		(width 0.0889)
		(layer "In13.Cu")
		(net "M_B_CPU0_SA_DQ<11>")
	)
	(arc
		(start 327.480676 -230.39324)
		(mid 327.410341 -230.361098)
		(end 327.33488 -230.344218)
		(width 0.0889)
		(layer "In13.Cu")
		(net "M_B_CPU0_SA_DQ<11>")
	)
	(arc
		(start 330.394056 -231.201722)
		(mid 330.1111 -231.277899)
		(end 329.828144 -231.201722)
		(width 0.0889)
		(layer "In13.Cu")
		(net "M_B_CPU0_SA_DQ<11>")
	)
	(arc
		(start 336.408268 -231.201722)
		(mid 336.226017 -231.151338)
		(end 336.042508 -231.196896)
		(width 0.0889)
		(layer "In13.Cu")
		(net "M_B_CPU0_SA_DQ<11>")
	)
	(arc
		(start 334.519778 -231.196896)
		(mid 334.33627 -231.151371)
		(end 334.154018 -231.201722)
		(width 0.0889)
		(layer "In13.Cu")
		(net "M_B_CPU0_SA_DQ<11>")
	)
	(arc
		(start 328.88809 -231.201722)
		(mid 328.701146 -231.151433)
		(end 328.514202 -231.201722)
		(width 0.0889)
		(layer "In13.Cu")
		(net "M_B_CPU0_SA_DQ<11>")
	)
	(arc
		(start 327.33488 -230.344218)
		(mid 327.232537 -230.314329)
		(end 327.14565 -230.252524)
		(width 0.0889)
		(layer "In13.Cu")
		(net "M_B_CPU0_SA_DQ<11>")
	)
	(arc
		(start 334.154018 -231.201722)
		(mid 333.871062 -231.277899)
		(end 333.588106 -231.201722)
		(width 0.0889)
		(layer "In13.Cu")
		(net "M_B_CPU0_SA_DQ<11>")
	)
	(arc
		(start 331.33411 -231.201722)
		(mid 331.051154 -231.277899)
		(end 330.768198 -231.201722)
		(width 0.0889)
		(layer "In13.Cu")
		(net "M_B_CPU0_SA_DQ<11>")
	)
	(arc
		(start 333.579724 -231.196896)
		(mid 333.396216 -231.151371)
		(end 333.213964 -231.201722)
		(width 0.0889)
		(layer "In13.Cu")
		(net "M_B_CPU0_SA_DQ<11>")
	)
	(arc
		(start 329.819762 -231.196896)
		(mid 329.636254 -231.151371)
		(end 329.454002 -231.201722)
		(width 0.0889)
		(layer "In13.Cu")
		(net "M_B_CPU0_SA_DQ<11>")
	)
	(segment
		(start 336.218022 -230.97998)
		(end 335.75117 -230.714296)
		(width 0.10668)
		(layer "F.Cu")
		(net "M_B_CPU0_SA_DQ<10>")
	)
	(segment
		(start 306.814728 -207.960214)
		(end 302.024034 -207.960214)
		(width 0.14478)
		(layer "In13.Cu")
		(net "M_B_CPU0_SA_DQ<10>")
	)
	(segment
		(start 324.489318 -226.514914)
		(end 324.318884 -226.34448)
		(width 0.0889)
		(layer "In13.Cu")
		(net "M_B_CPU0_SA_DQ<10>")
	)
	(segment
		(start 299.97146 -207.110076)
		(end 298.162472 -207.110076)
		(width 0.14478)
		(layer "In13.Cu")
		(net "M_B_CPU0_SA_DQ<10>")
	)
	(segment
		(start 326.158098 -227.857812)
		(end 325.332598 -227.032312)
		(width 0.0889)
		(layer "In13.Cu")
		(net "M_B_CPU0_SA_DQ<10>")
	)
	(segment
		(start 326.307958 -227.857812)
		(end 326.158098 -227.857812)
		(width 0.0889)
		(layer "In13.Cu")
		(net "M_B_CPU0_SA_DQ<10>")
	)
	(segment
		(start 333.6925 -230.38689)
		(end 333.684118 -230.391716)
		(width 0.0889)
		(layer "In13.Cu")
		(net "M_B_CPU0_SA_DQ<10>")
	)
	(segment
		(start 308.799738 -208.782412)
		(end 306.814728 -207.960214)
		(width 0.14478)
		(layer "In13.Cu")
		(net "M_B_CPU0_SA_DQ<10>")
	)
	(segment
		(start 335.596992 -230.448866)
		(end 335.500726 -230.423466)
		(width 0.0889)
		(layer "In13.Cu")
		(net "M_B_CPU0_SA_DQ<10>")
	)
	(segment
		(start 332.752446 -230.38689)
		(end 332.744064 -230.391716)
		(width 0.0889)
		(layer "In13.Cu")
		(net "M_B_CPU0_SA_DQ<10>")
	)
	(segment
		(start 321.390518 -221.373192)
		(end 308.799738 -208.782412)
		(width 0.14478)
		(layer "In13.Cu")
		(net "M_B_CPU0_SA_DQ<10>")
	)
	(segment
		(start 324.318884 -226.34448)
		(end 323.311774 -225.33737)
		(width 0.14478)
		(layer "In13.Cu")
		(net "M_B_CPU0_SA_DQ<10>")
	)
	(segment
		(start 321.390518 -222.201232)
		(end 321.390518 -221.373192)
		(width 0.14478)
		(layer "In13.Cu")
		(net "M_B_CPU0_SA_DQ<10>")
	)
	(segment
		(start 323.311774 -224.122488)
		(end 321.390518 -222.201232)
		(width 0.14478)
		(layer "In13.Cu")
		(net "M_B_CPU0_SA_DQ<10>")
	)
	(segment
		(start 298.162472 -207.110076)
		(end 297.73753 -207.535018)
		(width 0.14478)
		(layer "In13.Cu")
		(net "M_B_CPU0_SA_DQ<10>")
	)
	(segment
		(start 324.489318 -226.742752)
		(end 324.489318 -226.514914)
		(width 0.0889)
		(layer "In13.Cu")
		(net "M_B_CPU0_SA_DQ<10>")
	)
	(segment
		(start 331.238098 -230.391716)
		(end 331.229716 -230.38689)
		(width 0.0889)
		(layer "In13.Cu")
		(net "M_B_CPU0_SA_DQ<10>")
	)
	(segment
		(start 323.311774 -225.33737)
		(end 323.311774 -224.122488)
		(width 0.14478)
		(layer "In13.Cu")
		(net "M_B_CPU0_SA_DQ<10>")
	)
	(segment
		(start 328.41819 -230.391716)
		(end 328.381614 -230.37038)
		(width 0.0889)
		(layer "In13.Cu")
		(net "M_B_CPU0_SA_DQ<10>")
	)
	(segment
		(start 302.024034 -207.960214)
		(end 299.97146 -207.110076)
		(width 0.14478)
		(layer "In13.Cu")
		(net "M_B_CPU0_SA_DQ<10>")
	)
	(segment
		(start 327.57237 -229.122224)
		(end 326.307958 -227.857812)
		(width 0.0889)
		(layer "In13.Cu")
		(net "M_B_CPU0_SA_DQ<10>")
	)
	(segment
		(start 335.75117 -230.714296)
		(end 335.596992 -230.448866)
		(width 0.0889)
		(layer "In13.Cu")
		(net "M_B_CPU0_SA_DQ<10>")
	)
	(segment
		(start 327.980802 -229.600506)
		(end 327.909174 -229.55885)
		(width 0.0889)
		(layer "In13.Cu")
		(net "M_B_CPU0_SA_DQ<10>")
	)
	(segment
		(start 332.178152 -230.391716)
		(end 332.16977 -230.38689)
		(width 0.0889)
		(layer "In13.Cu")
		(net "M_B_CPU0_SA_DQ<10>")
	)
	(segment
		(start 328.992484 -230.38689)
		(end 328.984102 -230.391716)
		(width 0.0889)
		(layer "In13.Cu")
		(net "M_B_CPU0_SA_DQ<10>")
	)
	(segment
		(start 297.73753 -207.535018)
		(end 295.724072 -207.535018)
		(width 0.14478)
		(layer "In13.Cu")
		(net "M_B_CPU0_SA_DQ<10>")
	)
	(segment
		(start 324.778878 -227.032312)
		(end 324.489318 -226.742752)
		(width 0.0889)
		(layer "In13.Cu")
		(net "M_B_CPU0_SA_DQ<10>")
	)
	(segment
		(start 325.332598 -227.032312)
		(end 324.778878 -227.032312)
		(width 0.0889)
		(layer "In13.Cu")
		(net "M_B_CPU0_SA_DQ<10>")
	)
	(arc
		(start 333.684118 -230.391716)
		(mid 333.401162 -230.467859)
		(end 333.118206 -230.391716)
		(width 0.0889)
		(layer "In13.Cu")
		(net "M_B_CPU0_SA_DQ<10>")
	)
	(arc
		(start 330.298044 -230.391716)
		(mid 330.1111 -230.341461)
		(end 329.924156 -230.391716)
		(width 0.0889)
		(layer "In13.Cu")
		(net "M_B_CPU0_SA_DQ<10>")
	)
	(arc
		(start 335.500726 -230.423466)
		(mid 335.245661 -230.466797)
		(end 334.99806 -230.391716)
		(width 0.0889)
		(layer "In13.Cu")
		(net "M_B_CPU0_SA_DQ<10>")
	)
	(arc
		(start 332.16977 -230.38689)
		(mid 331.986262 -230.341396)
		(end 331.80401 -230.391716)
		(width 0.0889)
		(layer "In13.Cu")
		(net "M_B_CPU0_SA_DQ<10>")
	)
	(arc
		(start 334.05826 -230.391716)
		(mid 333.876009 -230.341366)
		(end 333.6925 -230.38689)
		(width 0.0889)
		(layer "In13.Cu")
		(net "M_B_CPU0_SA_DQ<10>")
	)
	(arc
		(start 333.118206 -230.391716)
		(mid 332.935955 -230.341366)
		(end 332.752446 -230.38689)
		(width 0.0889)
		(layer "In13.Cu")
		(net "M_B_CPU0_SA_DQ<10>")
	)
	(arc
		(start 327.717658 -229.330758)
		(mid 327.654253 -229.220055)
		(end 327.57237 -229.122224)
		(width 0.0889)
		(layer "In13.Cu")
		(net "M_B_CPU0_SA_DQ<10>")
	)
	(arc
		(start 328.381614 -230.37038)
		(mid 328.200962 -230.167635)
		(end 328.135742 -229.904036)
		(width 0.0889)
		(layer "In13.Cu")
		(net "M_B_CPU0_SA_DQ<10>")
	)
	(arc
		(start 328.135742 -229.904036)
		(mid 328.094776 -229.73363)
		(end 327.980802 -229.600506)
		(width 0.0889)
		(layer "In13.Cu")
		(net "M_B_CPU0_SA_DQ<10>")
	)
	(arc
		(start 334.99806 -230.391716)
		(mid 334.811116 -230.341461)
		(end 334.624172 -230.391716)
		(width 0.0889)
		(layer "In13.Cu")
		(net "M_B_CPU0_SA_DQ<10>")
	)
	(arc
		(start 327.909174 -229.55885)
		(mid 327.798137 -229.457636)
		(end 327.717658 -229.330758)
		(width 0.0889)
		(layer "In13.Cu")
		(net "M_B_CPU0_SA_DQ<10>")
	)
	(arc
		(start 332.744064 -230.391716)
		(mid 332.461108 -230.467859)
		(end 332.178152 -230.391716)
		(width 0.0889)
		(layer "In13.Cu")
		(net "M_B_CPU0_SA_DQ<10>")
	)
	(arc
		(start 329.924156 -230.391716)
		(mid 329.6412 -230.467859)
		(end 329.358244 -230.391716)
		(width 0.0889)
		(layer "In13.Cu")
		(net "M_B_CPU0_SA_DQ<10>")
	)
	(arc
		(start 328.984102 -230.391716)
		(mid 328.701146 -230.467859)
		(end 328.41819 -230.391716)
		(width 0.0889)
		(layer "In13.Cu")
		(net "M_B_CPU0_SA_DQ<10>")
	)
	(arc
		(start 330.863956 -230.391716)
		(mid 330.581 -230.467859)
		(end 330.298044 -230.391716)
		(width 0.0889)
		(layer "In13.Cu")
		(net "M_B_CPU0_SA_DQ<10>")
	)
	(arc
		(start 329.358244 -230.391716)
		(mid 329.175993 -230.341366)
		(end 328.992484 -230.38689)
		(width 0.0889)
		(layer "In13.Cu")
		(net "M_B_CPU0_SA_DQ<10>")
	)
	(arc
		(start 331.80401 -230.391716)
		(mid 331.521054 -230.467859)
		(end 331.238098 -230.391716)
		(width 0.0889)
		(layer "In13.Cu")
		(net "M_B_CPU0_SA_DQ<10>")
	)
	(arc
		(start 334.624172 -230.391716)
		(mid 334.341216 -230.467859)
		(end 334.05826 -230.391716)
		(width 0.0889)
		(layer "In13.Cu")
		(net "M_B_CPU0_SA_DQ<10>")
	)
	(arc
		(start 331.229716 -230.38689)
		(mid 331.046208 -230.341396)
		(end 330.863956 -230.391716)
		(width 0.0889)
		(layer "In13.Cu")
		(net "M_B_CPU0_SA_DQ<10>")
	)
	(segment
		(start 335.747868 -225.310192)
		(end 335.281016 -225.044254)
		(width 0.10668)
		(layer "F.Cu")
		(net "M_B_CPU0_SA_DQ<0>")
	)
	(segment
		(start 330.394056 -223.746822)
		(end 330.433172 -223.769682)
		(width 0.0889)
		(layer "In13.Cu")
		(net "M_B_CPU0_SA_DQ<0>")
	)
	(segment
		(start 303.91735 -197.760082)
		(end 304.06213 -197.615302)
		(width 0.14478)
		(layer "In13.Cu")
		(net "M_B_CPU0_SA_DQ<0>")
	)
	(segment
		(start 335.435194 -225.309684)
		(end 335.281016 -225.044254)
		(width 0.0889)
		(layer "In13.Cu")
		(net "M_B_CPU0_SA_DQ<0>")
	)
	(segment
		(start 330.863956 -224.556828)
		(end 330.903072 -224.579688)
		(width 0.0889)
		(layer "In13.Cu")
		(net "M_B_CPU0_SA_DQ<0>")
	)
	(segment
		(start 305.16449 -197.157594)
		(end 305.30927 -197.012814)
		(width 0.14478)
		(layer "In13.Cu")
		(net "M_B_CPU0_SA_DQ<0>")
	)
	(segment
		(start 305.16449 -197.615302)
		(end 305.16449 -197.157594)
		(width 0.14478)
		(layer "In13.Cu")
		(net "M_B_CPU0_SA_DQ<0>")
	)
	(segment
		(start 304.46853 -197.012814)
		(end 304.61331 -197.157594)
		(width 0.14478)
		(layer "In13.Cu")
		(net "M_B_CPU0_SA_DQ<0>")
	)
	(segment
		(start 334.519778 -225.37166)
		(end 334.52816 -225.366834)
		(width 0.0889)
		(layer "In13.Cu")
		(net "M_B_CPU0_SA_DQ<0>")
	)
	(segment
		(start 302.024288 -197.760082)
		(end 303.91735 -197.760082)
		(width 0.14478)
		(layer "In13.Cu")
		(net "M_B_CPU0_SA_DQ<0>")
	)
	(segment
		(start 306.41163 -197.012814)
		(end 306.67325 -197.012814)
		(width 0.14478)
		(layer "In13.Cu")
		(net "M_B_CPU0_SA_DQ<0>")
	)
	(segment
		(start 306.12207 -197.760082)
		(end 306.26685 -197.615302)
		(width 0.14478)
		(layer "In13.Cu")
		(net "M_B_CPU0_SA_DQ<0>")
	)
	(segment
		(start 305.71567 -197.157594)
		(end 305.71567 -197.615302)
		(width 0.14478)
		(layer "In13.Cu")
		(net "M_B_CPU0_SA_DQ<0>")
	)
	(segment
		(start 306.26685 -197.615302)
		(end 306.26685 -197.157594)
		(width 0.14478)
		(layer "In13.Cu")
		(net "M_B_CPU0_SA_DQ<0>")
	)
	(segment
		(start 335.094072 -225.366834)
		(end 335.102454 -225.37166)
		(width 0.0889)
		(layer "In13.Cu")
		(net "M_B_CPU0_SA_DQ<0>")
	)
	(segment
		(start 305.86045 -197.760082)
		(end 306.12207 -197.760082)
		(width 0.14478)
		(layer "In13.Cu")
		(net "M_B_CPU0_SA_DQ<0>")
	)
	(segment
		(start 306.26685 -197.157594)
		(end 306.41163 -197.012814)
		(width 0.14478)
		(layer "In13.Cu")
		(net "M_B_CPU0_SA_DQ<0>")
	)
	(segment
		(start 331.30236 -225.348546)
		(end 331.33411 -225.366834)
		(width 0.0889)
		(layer "In13.Cu")
		(net "M_B_CPU0_SA_DQ<0>")
	)
	(segment
		(start 305.01971 -197.760082)
		(end 305.16449 -197.615302)
		(width 0.14478)
		(layer "In13.Cu")
		(net "M_B_CPU0_SA_DQ<0>")
	)
	(segment
		(start 330.362306 -223.728534)
		(end 330.394056 -223.746822)
		(width 0.0889)
		(layer "In13.Cu")
		(net "M_B_CPU0_SA_DQ<0>")
	)
	(segment
		(start 335.412842 -225.392996)
		(end 335.435194 -225.309684)
		(width 0.0889)
		(layer "In13.Cu")
		(net "M_B_CPU0_SA_DQ<0>")
	)
	(segment
		(start 305.71567 -197.615302)
		(end 305.86045 -197.760082)
		(width 0.14478)
		(layer "In13.Cu")
		(net "M_B_CPU0_SA_DQ<0>")
	)
	(segment
		(start 304.06213 -197.157594)
		(end 304.20691 -197.012814)
		(width 0.14478)
		(layer "In13.Cu")
		(net "M_B_CPU0_SA_DQ<0>")
	)
	(segment
		(start 305.30927 -197.012814)
		(end 305.57089 -197.012814)
		(width 0.14478)
		(layer "In13.Cu")
		(net "M_B_CPU0_SA_DQ<0>")
	)
	(segment
		(start 330.833476 -224.539048)
		(end 330.863956 -224.556828)
		(width 0.0889)
		(layer "In13.Cu")
		(net "M_B_CPU0_SA_DQ<0>")
	)
	(segment
		(start 329.514454 -219.576142)
		(end 329.514454 -221.25305)
		(width 0.14478)
		(layer "In13.Cu")
		(net "M_B_CPU0_SA_DQ<0>")
	)
	(segment
		(start 307.698394 -197.760082)
		(end 329.514454 -219.576142)
		(width 0.14478)
		(layer "In13.Cu")
		(net "M_B_CPU0_SA_DQ<0>")
	)
	(segment
		(start 305.57089 -197.012814)
		(end 305.71567 -197.157594)
		(width 0.14478)
		(layer "In13.Cu")
		(net "M_B_CPU0_SA_DQ<0>")
	)
	(segment
		(start 306.96281 -197.760082)
		(end 307.698394 -197.760082)
		(width 0.14478)
		(layer "In13.Cu")
		(net "M_B_CPU0_SA_DQ<0>")
	)
	(segment
		(start 331.33411 -225.366834)
		(end 331.342492 -225.37166)
		(width 0.0889)
		(layer "In13.Cu")
		(net "M_B_CPU0_SA_DQ<0>")
	)
	(segment
		(start 329.73645 -221.583504)
		(end 329.73645 -222.614236)
		(width 0.0889)
		(layer "In13.Cu")
		(net "M_B_CPU0_SA_DQ<0>")
	)
	(segment
		(start 304.61331 -197.157594)
		(end 304.61331 -197.615302)
		(width 0.14478)
		(layer "In13.Cu")
		(net "M_B_CPU0_SA_DQ<0>")
	)
	(segment
		(start 333.579724 -225.37166)
		(end 333.588106 -225.366834)
		(width 0.0889)
		(layer "In13.Cu")
		(net "M_B_CPU0_SA_DQ<0>")
	)
	(segment
		(start 304.61331 -197.615302)
		(end 304.75809 -197.760082)
		(width 0.14478)
		(layer "In13.Cu")
		(net "M_B_CPU0_SA_DQ<0>")
	)
	(segment
		(start 300.249082 -196.910198)
		(end 301.174404 -196.910198)
		(width 0.14478)
		(layer "In13.Cu")
		(net "M_B_CPU0_SA_DQ<0>")
	)
	(segment
		(start 306.81803 -197.615302)
		(end 306.96281 -197.760082)
		(width 0.14478)
		(layer "In13.Cu")
		(net "M_B_CPU0_SA_DQ<0>")
	)
	(segment
		(start 329.514454 -221.361508)
		(end 329.73645 -221.583504)
		(width 0.0889)
		(layer "In13.Cu")
		(net "M_B_CPU0_SA_DQ<0>")
	)
	(segment
		(start 304.75809 -197.760082)
		(end 305.01971 -197.760082)
		(width 0.14478)
		(layer "In13.Cu")
		(net "M_B_CPU0_SA_DQ<0>")
	)
	(segment
		(start 329.892406 -222.918528)
		(end 329.960478 -222.957898)
		(width 0.0889)
		(layer "In13.Cu")
		(net "M_B_CPU0_SA_DQ<0>")
	)
	(segment
		(start 301.174404 -196.910198)
		(end 302.024288 -197.760082)
		(width 0.14478)
		(layer "In13.Cu")
		(net "M_B_CPU0_SA_DQ<0>")
	)
	(segment
		(start 306.81803 -197.157594)
		(end 306.81803 -197.615302)
		(width 0.14478)
		(layer "In13.Cu")
		(net "M_B_CPU0_SA_DQ<0>")
	)
	(segment
		(start 329.514454 -221.25305)
		(end 329.514454 -221.361508)
		(width 0.0889)
		(layer "In13.Cu")
		(net "M_B_CPU0_SA_DQ<0>")
	)
	(segment
		(start 299.82414 -197.33514)
		(end 300.249082 -196.910198)
		(width 0.14478)
		(layer "In13.Cu")
		(net "M_B_CPU0_SA_DQ<0>")
	)
	(segment
		(start 304.06213 -197.615302)
		(end 304.06213 -197.157594)
		(width 0.14478)
		(layer "In13.Cu")
		(net "M_B_CPU0_SA_DQ<0>")
	)
	(segment
		(start 304.20691 -197.012814)
		(end 304.46853 -197.012814)
		(width 0.14478)
		(layer "In13.Cu")
		(net "M_B_CPU0_SA_DQ<0>")
	)
	(segment
		(start 306.67325 -197.012814)
		(end 306.81803 -197.157594)
		(width 0.14478)
		(layer "In13.Cu")
		(net "M_B_CPU0_SA_DQ<0>")
	)
	(arc
		(start 333.588106 -225.366834)
		(mid 333.871062 -225.290657)
		(end 334.154018 -225.366834)
		(width 0.0889)
		(layer "In13.Cu")
		(net "M_B_CPU0_SA_DQ<0>")
	)
	(arc
		(start 331.708252 -225.366834)
		(mid 331.991208 -225.290657)
		(end 332.274164 -225.366834)
		(width 0.0889)
		(layer "In13.Cu")
		(net "M_B_CPU0_SA_DQ<0>")
	)
	(arc
		(start 335.102454 -225.37166)
		(mid 335.255324 -225.416301)
		(end 335.412842 -225.392996)
		(width 0.0889)
		(layer "In13.Cu")
		(net "M_B_CPU0_SA_DQ<0>")
	)
	(arc
		(start 332.648052 -225.366834)
		(mid 332.931008 -225.290657)
		(end 333.213964 -225.366834)
		(width 0.0889)
		(layer "In13.Cu")
		(net "M_B_CPU0_SA_DQ<0>")
	)
	(arc
		(start 333.213964 -225.366834)
		(mid 333.396215 -225.417184)
		(end 333.579724 -225.37166)
		(width 0.0889)
		(layer "In13.Cu")
		(net "M_B_CPU0_SA_DQ<0>")
	)
	(arc
		(start 330.20635 -223.424242)
		(mid 330.247605 -223.595213)
		(end 330.362306 -223.728534)
		(width 0.0889)
		(layer "In13.Cu")
		(net "M_B_CPU0_SA_DQ<0>")
	)
	(arc
		(start 329.73645 -222.614236)
		(mid 329.777705 -222.785207)
		(end 329.892406 -222.918528)
		(width 0.0889)
		(layer "In13.Cu")
		(net "M_B_CPU0_SA_DQ<0>")
	)
	(arc
		(start 331.146404 -225.044254)
		(mid 331.187659 -225.215225)
		(end 331.30236 -225.348546)
		(width 0.0889)
		(layer "In13.Cu")
		(net "M_B_CPU0_SA_DQ<0>")
	)
	(arc
		(start 331.342492 -225.37166)
		(mid 331.526 -225.417154)
		(end 331.708252 -225.366834)
		(width 0.0889)
		(layer "In13.Cu")
		(net "M_B_CPU0_SA_DQ<0>")
	)
	(arc
		(start 330.903072 -224.579688)
		(mid 331.081885 -224.782038)
		(end 331.146404 -225.044254)
		(width 0.0889)
		(layer "In13.Cu")
		(net "M_B_CPU0_SA_DQ<0>")
	)
	(arc
		(start 330.433172 -223.769682)
		(mid 330.611985 -223.972032)
		(end 330.676504 -224.234248)
		(width 0.0889)
		(layer "In13.Cu")
		(net "M_B_CPU0_SA_DQ<0>")
	)
	(arc
		(start 334.154018 -225.366834)
		(mid 334.336269 -225.417184)
		(end 334.519778 -225.37166)
		(width 0.0889)
		(layer "In13.Cu")
		(net "M_B_CPU0_SA_DQ<0>")
	)
	(arc
		(start 330.676504 -224.234248)
		(mid 330.718053 -224.40567)
		(end 330.833476 -224.539048)
		(width 0.0889)
		(layer "In13.Cu")
		(net "M_B_CPU0_SA_DQ<0>")
	)
	(arc
		(start 332.274164 -225.366834)
		(mid 332.461108 -225.417089)
		(end 332.648052 -225.366834)
		(width 0.0889)
		(layer "In13.Cu")
		(net "M_B_CPU0_SA_DQ<0>")
	)
	(arc
		(start 329.960478 -222.957898)
		(mid 330.14113 -223.160643)
		(end 330.20635 -223.424242)
		(width 0.0889)
		(layer "In13.Cu")
		(net "M_B_CPU0_SA_DQ<0>")
	)
	(arc
		(start 334.52816 -225.366834)
		(mid 334.811116 -225.290657)
		(end 335.094072 -225.366834)
		(width 0.0889)
		(layer "In13.Cu")
		(net "M_B_CPU0_SA_DQ<0>")
	)
	(segment
		(start 337.627976 -252.850142)
		(end 337.161124 -252.584204)
		(width 0.10668)
		(layer "F.Cu")
		(net "M_B_CPU0_SA_CS_N<1>")
	)
	(segment
		(start 337.0072 -252.318774)
		(end 337.161124 -252.584204)
		(width 0.0889)
		(layer "In13.Cu")
		(net "M_B_CPU0_SA_CS_N<1>")
	)
	(segment
		(start 336.911188 -252.293374)
		(end 337.0072 -252.318774)
		(width 0.0889)
		(layer "In13.Cu")
		(net "M_B_CPU0_SA_CS_N<1>")
	)
	(segment
		(start 325.480934 -252.212856)
		(end 325.915274 -252.212856)
		(width 0.0889)
		(layer "In13.Cu")
		(net "M_B_CPU0_SA_CS_N<1>")
	)
	(segment
		(start 325.404988 -252.13691)
		(end 325.480934 -252.212856)
		(width 0.0889)
		(layer "In13.Cu")
		(net "M_B_CPU0_SA_CS_N<1>")
	)
	(segment
		(start 295.724072 -246.635016)
		(end 297.06316 -246.635016)
		(width 0.14478)
		(layer "In13.Cu")
		(net "M_B_CPU0_SA_CS_N<1>")
	)
	(segment
		(start 331.33411 -252.261624)
		(end 331.342492 -252.256798)
		(width 0.0889)
		(layer "In13.Cu")
		(net "M_B_CPU0_SA_CS_N<1>")
	)
	(segment
		(start 335.094072 -252.261624)
		(end 335.102454 -252.256798)
		(width 0.0889)
		(layer "In13.Cu")
		(net "M_B_CPU0_SA_CS_N<1>")
	)
	(segment
		(start 297.488102 -247.059958)
		(end 301.233332 -247.059958)
		(width 0.14478)
		(layer "In13.Cu")
		(net "M_B_CPU0_SA_CS_N<1>")
	)
	(segment
		(start 326.633586 -252.261878)
		(end 326.649842 -252.25248)
		(width 0.0889)
		(layer "In13.Cu")
		(net "M_B_CPU0_SA_CS_N<1>")
	)
	(segment
		(start 307.796946 -248.75998)
		(end 310.555386 -251.51842)
		(width 0.14478)
		(layer "In13.Cu")
		(net "M_B_CPU0_SA_CS_N<1>")
	)
	(segment
		(start 302.933354 -248.75998)
		(end 307.796946 -248.75998)
		(width 0.14478)
		(layer "In13.Cu")
		(net "M_B_CPU0_SA_CS_N<1>")
	)
	(segment
		(start 327.007474 -252.261624)
		(end 327.017888 -252.26772)
		(width 0.0889)
		(layer "In13.Cu")
		(net "M_B_CPU0_SA_CS_N<1>")
	)
	(segment
		(start 321.805554 -252.13691)
		(end 324.007734 -252.13691)
		(width 0.14478)
		(layer "In13.Cu")
		(net "M_B_CPU0_SA_CS_N<1>")
	)
	(segment
		(start 336.034126 -252.261624)
		(end 336.042508 -252.256798)
		(width 0.0889)
		(layer "In13.Cu")
		(net "M_B_CPU0_SA_CS_N<1>")
	)
	(segment
		(start 326.617838 -252.271022)
		(end 326.633586 -252.261878)
		(width 0.0889)
		(layer "In13.Cu")
		(net "M_B_CPU0_SA_CS_N<1>")
	)
	(segment
		(start 301.233332 -247.059958)
		(end 302.933354 -248.75998)
		(width 0.14478)
		(layer "In13.Cu")
		(net "M_B_CPU0_SA_CS_N<1>")
	)
	(segment
		(start 297.06316 -246.635016)
		(end 297.488102 -247.059958)
		(width 0.14478)
		(layer "In13.Cu")
		(net "M_B_CPU0_SA_CS_N<1>")
	)
	(segment
		(start 321.187064 -251.51842)
		(end 321.805554 -252.13691)
		(width 0.14478)
		(layer "In13.Cu")
		(net "M_B_CPU0_SA_CS_N<1>")
	)
	(segment
		(start 324.007734 -252.13691)
		(end 325.404988 -252.13691)
		(width 0.0889)
		(layer "In13.Cu")
		(net "M_B_CPU0_SA_CS_N<1>")
	)
	(segment
		(start 310.555386 -251.51842)
		(end 321.187064 -251.51842)
		(width 0.14478)
		(layer "In13.Cu")
		(net "M_B_CPU0_SA_CS_N<1>")
	)
	(segment
		(start 334.527906 -252.261624)
		(end 334.52816 -252.261624)
		(width 0.0889)
		(layer "In13.Cu")
		(net "M_B_CPU0_SA_CS_N<1>")
	)
	(segment
		(start 330.394056 -252.261624)
		(end 330.402438 -252.256798)
		(width 0.0889)
		(layer "In13.Cu")
		(net "M_B_CPU0_SA_CS_N<1>")
	)
	(segment
		(start 333.579724 -252.256798)
		(end 333.588106 -252.261624)
		(width 0.0889)
		(layer "In13.Cu")
		(net "M_B_CPU0_SA_CS_N<1>")
	)
	(segment
		(start 329.819762 -252.256798)
		(end 329.828144 -252.261624)
		(width 0.0889)
		(layer "In13.Cu")
		(net "M_B_CPU0_SA_CS_N<1>")
	)
	(segment
		(start 327.939908 -252.256798)
		(end 327.94829 -252.261624)
		(width 0.0889)
		(layer "In13.Cu")
		(net "M_B_CPU0_SA_CS_N<1>")
	)
	(arc
		(start 330.402438 -252.256798)
		(mid 330.585946 -252.211304)
		(end 330.768198 -252.261624)
		(width 0.0889)
		(layer "In13.Cu")
		(net "M_B_CPU0_SA_CS_N<1>")
	)
	(arc
		(start 326.649842 -252.25248)
		(mid 326.829824 -252.21138)
		(end 327.007474 -252.261624)
		(width 0.0889)
		(layer "In13.Cu")
		(net "M_B_CPU0_SA_CS_N<1>")
	)
	(arc
		(start 334.154018 -252.261624)
		(mid 334.340962 -252.2113)
		(end 334.527906 -252.261624)
		(width 0.0889)
		(layer "In13.Cu")
		(net "M_B_CPU0_SA_CS_N<1>")
	)
	(arc
		(start 325.915274 -252.212856)
		(mid 325.994123 -252.228965)
		(end 326.067674 -252.261624)
		(width 0.0889)
		(layer "In13.Cu")
		(net "M_B_CPU0_SA_CS_N<1>")
	)
	(arc
		(start 327.94829 -252.261624)
		(mid 328.231246 -252.337801)
		(end 328.514202 -252.261624)
		(width 0.0889)
		(layer "In13.Cu")
		(net "M_B_CPU0_SA_CS_N<1>")
	)
	(arc
		(start 327.017888 -252.26772)
		(mid 327.296574 -252.33794)
		(end 327.57364 -252.261624)
		(width 0.0889)
		(layer "In13.Cu")
		(net "M_B_CPU0_SA_CS_N<1>")
	)
	(arc
		(start 328.88809 -252.261624)
		(mid 329.171046 -252.337801)
		(end 329.454002 -252.261624)
		(width 0.0889)
		(layer "In13.Cu")
		(net "M_B_CPU0_SA_CS_N<1>")
	)
	(arc
		(start 327.57364 -252.261624)
		(mid 327.756145 -252.211147)
		(end 327.939908 -252.256798)
		(width 0.0889)
		(layer "In13.Cu")
		(net "M_B_CPU0_SA_CS_N<1>")
	)
	(arc
		(start 336.042508 -252.256798)
		(mid 336.226016 -252.211304)
		(end 336.408268 -252.261624)
		(width 0.0889)
		(layer "In13.Cu")
		(net "M_B_CPU0_SA_CS_N<1>")
	)
	(arc
		(start 332.274164 -252.261624)
		(mid 332.461108 -252.211369)
		(end 332.648052 -252.261624)
		(width 0.0889)
		(layer "In13.Cu")
		(net "M_B_CPU0_SA_CS_N<1>")
	)
	(arc
		(start 335.468214 -252.261624)
		(mid 335.75117 -252.337801)
		(end 336.034126 -252.261624)
		(width 0.0889)
		(layer "In13.Cu")
		(net "M_B_CPU0_SA_CS_N<1>")
	)
	(arc
		(start 331.708252 -252.261624)
		(mid 331.991208 -252.337801)
		(end 332.274164 -252.261624)
		(width 0.0889)
		(layer "In13.Cu")
		(net "M_B_CPU0_SA_CS_N<1>")
	)
	(arc
		(start 335.102454 -252.256798)
		(mid 335.285962 -252.211304)
		(end 335.468214 -252.261624)
		(width 0.0889)
		(layer "In13.Cu")
		(net "M_B_CPU0_SA_CS_N<1>")
	)
	(arc
		(start 326.067674 -252.261624)
		(mid 326.341529 -252.337974)
		(end 326.617838 -252.271022)
		(width 0.0889)
		(layer "In13.Cu")
		(net "M_B_CPU0_SA_CS_N<1>")
	)
	(arc
		(start 329.454002 -252.261624)
		(mid 329.636253 -252.211274)
		(end 329.819762 -252.256798)
		(width 0.0889)
		(layer "In13.Cu")
		(net "M_B_CPU0_SA_CS_N<1>")
	)
	(arc
		(start 333.588106 -252.261624)
		(mid 333.871062 -252.337801)
		(end 334.154018 -252.261624)
		(width 0.0889)
		(layer "In13.Cu")
		(net "M_B_CPU0_SA_CS_N<1>")
	)
	(arc
		(start 336.408268 -252.261624)
		(mid 336.655981 -252.336844)
		(end 336.911188 -252.293374)
		(width 0.0889)
		(layer "In13.Cu")
		(net "M_B_CPU0_SA_CS_N<1>")
	)
	(arc
		(start 331.342492 -252.256798)
		(mid 331.526 -252.211304)
		(end 331.708252 -252.261624)
		(width 0.0889)
		(layer "In13.Cu")
		(net "M_B_CPU0_SA_CS_N<1>")
	)
	(arc
		(start 328.514202 -252.261624)
		(mid 328.701146 -252.211369)
		(end 328.88809 -252.261624)
		(width 0.0889)
		(layer "In13.Cu")
		(net "M_B_CPU0_SA_CS_N<1>")
	)
	(arc
		(start 334.52816 -252.261624)
		(mid 334.811116 -252.337801)
		(end 335.094072 -252.261624)
		(width 0.0889)
		(layer "In13.Cu")
		(net "M_B_CPU0_SA_CS_N<1>")
	)
	(arc
		(start 329.828144 -252.261624)
		(mid 330.1111 -252.337801)
		(end 330.394056 -252.261624)
		(width 0.0889)
		(layer "In13.Cu")
		(net "M_B_CPU0_SA_CS_N<1>")
	)
	(arc
		(start 333.213964 -252.261624)
		(mid 333.396215 -252.211274)
		(end 333.579724 -252.256798)
		(width 0.0889)
		(layer "In13.Cu")
		(net "M_B_CPU0_SA_CS_N<1>")
	)
	(arc
		(start 330.768198 -252.261624)
		(mid 331.051154 -252.337801)
		(end 331.33411 -252.261624)
		(width 0.0889)
		(layer "In13.Cu")
		(net "M_B_CPU0_SA_CS_N<1>")
	)
	(arc
		(start 332.648052 -252.261624)
		(mid 332.931008 -252.337801)
		(end 333.213964 -252.261624)
		(width 0.0889)
		(layer "In13.Cu")
		(net "M_B_CPU0_SA_CS_N<1>")
	)
	(segment
		(start 336.218022 -252.040136)
		(end 335.75117 -251.774198)
		(width 0.10668)
		(layer "F.Cu")
		(net "M_B_CPU0_SA_CS_N<0>")
	)
	(segment
		(start 305.64074 -248.054876)
		(end 305.64074 -248.15673)
		(width 0.14478)
		(layer "In13.Cu")
		(net "M_B_CPU0_SA_CS_N<0>")
	)
	(segment
		(start 305.08956 -248.054876)
		(end 305.23434 -247.910096)
		(width 0.14478)
		(layer "In13.Cu")
		(net "M_B_CPU0_SA_CS_N<0>")
	)
	(segment
		(start 335.501234 -251.483368)
		(end 335.597246 -251.508768)
		(width 0.0889)
		(layer "In13.Cu")
		(net "M_B_CPU0_SA_CS_N<0>")
	)
	(segment
		(start 304.68316 -248.30151)
		(end 304.94478 -248.30151)
		(width 0.14478)
		(layer "In13.Cu")
		(net "M_B_CPU0_SA_CS_N<0>")
	)
	(segment
		(start 300.358302 -246.319294)
		(end 301.432214 -246.319294)
		(width 0.14478)
		(layer "In13.Cu")
		(net "M_B_CPU0_SA_CS_N<0>")
	)
	(segment
		(start 326.526398 -251.44476)
		(end 326.538082 -251.451618)
		(width 0.0889)
		(layer "In13.Cu")
		(net "M_B_CPU0_SA_CS_N<0>")
	)
	(segment
		(start 303.84242 -248.30151)
		(end 303.9872 -248.15673)
		(width 0.14478)
		(layer "In13.Cu")
		(net "M_B_CPU0_SA_CS_N<0>")
	)
	(segment
		(start 324.010274 -251.59335)
		(end 325.137018 -251.59335)
		(width 0.0889)
		(layer "In13.Cu")
		(net "M_B_CPU0_SA_CS_N<0>")
	)
	(segment
		(start 306.3367 -247.910096)
		(end 307.606446 -247.910096)
		(width 0.14478)
		(layer "In13.Cu")
		(net "M_B_CPU0_SA_CS_N<0>")
	)
	(segment
		(start 328.409808 -251.446792)
		(end 328.41819 -251.451618)
		(width 0.0889)
		(layer "In13.Cu")
		(net "M_B_CPU0_SA_CS_N<0>")
	)
	(segment
		(start 327.10374 -251.451618)
		(end 327.118218 -251.443236)
		(width 0.0889)
		(layer "In13.Cu")
		(net "M_B_CPU0_SA_CS_N<0>")
	)
	(segment
		(start 303.43602 -248.15673)
		(end 303.5808 -248.30151)
		(width 0.14478)
		(layer "In13.Cu")
		(net "M_B_CPU0_SA_CS_N<0>")
	)
	(segment
		(start 303.29124 -247.910096)
		(end 303.43602 -248.054876)
		(width 0.14478)
		(layer "In13.Cu")
		(net "M_B_CPU0_SA_CS_N<0>")
	)
	(segment
		(start 302.310038 -247.197118)
		(end 303.023016 -247.910096)
		(width 0.14478)
		(layer "In13.Cu")
		(net "M_B_CPU0_SA_CS_N<0>")
	)
	(segment
		(start 335.597246 -251.508768)
		(end 335.75117 -251.774198)
		(width 0.0889)
		(layer "In13.Cu")
		(net "M_B_CPU0_SA_CS_N<0>")
	)
	(segment
		(start 332.744064 -251.451618)
		(end 332.752446 -251.446792)
		(width 0.0889)
		(layer "In13.Cu")
		(net "M_B_CPU0_SA_CS_N<0>")
	)
	(segment
		(start 321.905122 -251.59335)
		(end 324.010274 -251.59335)
		(width 0.14478)
		(layer "In13.Cu")
		(net "M_B_CPU0_SA_CS_N<0>")
	)
	(segment
		(start 299.82414 -245.785132)
		(end 300.358302 -246.319294)
		(width 0.14478)
		(layer "In13.Cu")
		(net "M_B_CPU0_SA_CS_N<0>")
	)
	(segment
		(start 325.137018 -251.59335)
		(end 325.202296 -251.528072)
		(width 0.0889)
		(layer "In13.Cu")
		(net "M_B_CPU0_SA_CS_N<0>")
	)
	(segment
		(start 304.53838 -248.054876)
		(end 304.53838 -248.15673)
		(width 0.14478)
		(layer "In13.Cu")
		(net "M_B_CPU0_SA_CS_N<0>")
	)
	(segment
		(start 302.000158 -246.522494)
		(end 302.204882 -246.522494)
		(width 0.14478)
		(layer "In13.Cu")
		(net "M_B_CPU0_SA_CS_N<0>")
	)
	(segment
		(start 302.390048 -246.70766)
		(end 302.390048 -246.912384)
		(width 0.14478)
		(layer "In13.Cu")
		(net "M_B_CPU0_SA_CS_N<0>")
	)
	(segment
		(start 305.49596 -247.910096)
		(end 305.64074 -248.054876)
		(width 0.14478)
		(layer "In13.Cu")
		(net "M_B_CPU0_SA_CS_N<0>")
	)
	(segment
		(start 303.023016 -247.910096)
		(end 303.29124 -247.910096)
		(width 0.14478)
		(layer "In13.Cu")
		(net "M_B_CPU0_SA_CS_N<0>")
	)
	(segment
		(start 306.04714 -248.30151)
		(end 306.19192 -248.15673)
		(width 0.14478)
		(layer "In13.Cu")
		(net "M_B_CPU0_SA_CS_N<0>")
	)
	(segment
		(start 301.715424 -246.602504)
		(end 301.920148 -246.602504)
		(width 0.14478)
		(layer "In13.Cu")
		(net "M_B_CPU0_SA_CS_N<0>")
	)
	(segment
		(start 303.5808 -248.30151)
		(end 303.84242 -248.30151)
		(width 0.14478)
		(layer "In13.Cu")
		(net "M_B_CPU0_SA_CS_N<0>")
	)
	(segment
		(start 305.08956 -248.15673)
		(end 305.08956 -248.054876)
		(width 0.14478)
		(layer "In13.Cu")
		(net "M_B_CPU0_SA_CS_N<0>")
	)
	(segment
		(start 305.23434 -247.910096)
		(end 305.49596 -247.910096)
		(width 0.14478)
		(layer "In13.Cu")
		(net "M_B_CPU0_SA_CS_N<0>")
	)
	(segment
		(start 304.53838 -248.15673)
		(end 304.68316 -248.30151)
		(width 0.14478)
		(layer "In13.Cu")
		(net "M_B_CPU0_SA_CS_N<0>")
	)
	(segment
		(start 302.204882 -246.522494)
		(end 302.390048 -246.70766)
		(width 0.14478)
		(layer "In13.Cu")
		(net "M_B_CPU0_SA_CS_N<0>")
	)
	(segment
		(start 327.093326 -251.457714)
		(end 327.10374 -251.451618)
		(width 0.0889)
		(layer "In13.Cu")
		(net "M_B_CPU0_SA_CS_N<0>")
	)
	(segment
		(start 321.375532 -251.06376)
		(end 321.905122 -251.59335)
		(width 0.14478)
		(layer "In13.Cu")
		(net "M_B_CPU0_SA_CS_N<0>")
	)
	(segment
		(start 310.76011 -251.06376)
		(end 321.375532 -251.06376)
		(width 0.14478)
		(layer "In13.Cu")
		(net "M_B_CPU0_SA_CS_N<0>")
	)
	(segment
		(start 333.684118 -251.451618)
		(end 333.6925 -251.446792)
		(width 0.0889)
		(layer "In13.Cu")
		(net "M_B_CPU0_SA_CS_N<0>")
	)
	(segment
		(start 307.606446 -247.910096)
		(end 310.76011 -251.06376)
		(width 0.14478)
		(layer "In13.Cu")
		(net "M_B_CPU0_SA_CS_N<0>")
	)
	(segment
		(start 305.64074 -248.15673)
		(end 305.78552 -248.30151)
		(width 0.14478)
		(layer "In13.Cu")
		(net "M_B_CPU0_SA_CS_N<0>")
	)
	(segment
		(start 328.033634 -251.457714)
		(end 328.044048 -251.451618)
		(width 0.0889)
		(layer "In13.Cu")
		(net "M_B_CPU0_SA_CS_N<0>")
	)
	(segment
		(start 303.43602 -248.054876)
		(end 303.43602 -248.15673)
		(width 0.14478)
		(layer "In13.Cu")
		(net "M_B_CPU0_SA_CS_N<0>")
	)
	(segment
		(start 306.19192 -248.15673)
		(end 306.19192 -248.054876)
		(width 0.14478)
		(layer "In13.Cu")
		(net "M_B_CPU0_SA_CS_N<0>")
	)
	(segment
		(start 302.310038 -246.992394)
		(end 302.310038 -247.197118)
		(width 0.14478)
		(layer "In13.Cu")
		(net "M_B_CPU0_SA_CS_N<0>")
	)
	(segment
		(start 325.202296 -251.528072)
		(end 325.880222 -251.528072)
		(width 0.0889)
		(layer "In13.Cu")
		(net "M_B_CPU0_SA_CS_N<0>")
	)
	(segment
		(start 331.229716 -251.446792)
		(end 331.238098 -251.451618)
		(width 0.0889)
		(layer "In13.Cu")
		(net "M_B_CPU0_SA_CS_N<0>")
	)
	(segment
		(start 302.390048 -246.912384)
		(end 302.310038 -246.992394)
		(width 0.14478)
		(layer "In13.Cu")
		(net "M_B_CPU0_SA_CS_N<0>")
	)
	(segment
		(start 301.432214 -246.319294)
		(end 301.715424 -246.602504)
		(width 0.14478)
		(layer "In13.Cu")
		(net "M_B_CPU0_SA_CS_N<0>")
	)
	(segment
		(start 332.16977 -251.446792)
		(end 332.178152 -251.451618)
		(width 0.0889)
		(layer "In13.Cu")
		(net "M_B_CPU0_SA_CS_N<0>")
	)
	(segment
		(start 328.984102 -251.451618)
		(end 328.992484 -251.446792)
		(width 0.0889)
		(layer "In13.Cu")
		(net "M_B_CPU0_SA_CS_N<0>")
	)
	(segment
		(start 303.9872 -248.054876)
		(end 304.13198 -247.910096)
		(width 0.14478)
		(layer "In13.Cu")
		(net "M_B_CPU0_SA_CS_N<0>")
	)
	(segment
		(start 304.94478 -248.30151)
		(end 305.08956 -248.15673)
		(width 0.14478)
		(layer "In13.Cu")
		(net "M_B_CPU0_SA_CS_N<0>")
	)
	(segment
		(start 304.13198 -247.910096)
		(end 304.3936 -247.910096)
		(width 0.14478)
		(layer "In13.Cu")
		(net "M_B_CPU0_SA_CS_N<0>")
	)
	(segment
		(start 304.3936 -247.910096)
		(end 304.53838 -248.054876)
		(width 0.14478)
		(layer "In13.Cu")
		(net "M_B_CPU0_SA_CS_N<0>")
	)
	(segment
		(start 306.19192 -248.054876)
		(end 306.3367 -247.910096)
		(width 0.14478)
		(layer "In13.Cu")
		(net "M_B_CPU0_SA_CS_N<0>")
	)
	(segment
		(start 334.624172 -251.451618)
		(end 334.632554 -251.446792)
		(width 0.0889)
		(layer "In13.Cu")
		(net "M_B_CPU0_SA_CS_N<0>")
	)
	(segment
		(start 305.78552 -248.30151)
		(end 306.04714 -248.30151)
		(width 0.14478)
		(layer "In13.Cu")
		(net "M_B_CPU0_SA_CS_N<0>")
	)
	(segment
		(start 301.920148 -246.602504)
		(end 302.000158 -246.522494)
		(width 0.14478)
		(layer "In13.Cu")
		(net "M_B_CPU0_SA_CS_N<0>")
	)
	(segment
		(start 303.9872 -248.15673)
		(end 303.9872 -248.054876)
		(width 0.14478)
		(layer "In13.Cu")
		(net "M_B_CPU0_SA_CS_N<0>")
	)
	(arc
		(start 329.358244 -251.451618)
		(mid 329.6412 -251.527795)
		(end 329.924156 -251.451618)
		(width 0.0889)
		(layer "In13.Cu")
		(net "M_B_CPU0_SA_CS_N<0>")
	)
	(arc
		(start 327.477882 -251.451618)
		(mid 327.754949 -251.527889)
		(end 328.033634 -251.457714)
		(width 0.0889)
		(layer "In13.Cu")
		(net "M_B_CPU0_SA_CS_N<0>")
	)
	(arc
		(start 331.238098 -251.451618)
		(mid 331.521054 -251.527795)
		(end 331.80401 -251.451618)
		(width 0.0889)
		(layer "In13.Cu")
		(net "M_B_CPU0_SA_CS_N<0>")
	)
	(arc
		(start 327.118218 -251.443236)
		(mid 327.299126 -251.401214)
		(end 327.477882 -251.451618)
		(width 0.0889)
		(layer "In13.Cu")
		(net "M_B_CPU0_SA_CS_N<0>")
	)
	(arc
		(start 326.538082 -251.451618)
		(mid 326.814895 -251.527761)
		(end 327.093326 -251.457714)
		(width 0.0889)
		(layer "In13.Cu")
		(net "M_B_CPU0_SA_CS_N<0>")
	)
	(arc
		(start 333.6925 -251.446792)
		(mid 333.876008 -251.401298)
		(end 334.05826 -251.451618)
		(width 0.0889)
		(layer "In13.Cu")
		(net "M_B_CPU0_SA_CS_N<0>")
	)
	(arc
		(start 326.163686 -251.451618)
		(mid 326.344144 -251.401174)
		(end 326.526398 -251.44476)
		(width 0.0889)
		(layer "In13.Cu")
		(net "M_B_CPU0_SA_CS_N<0>")
	)
	(arc
		(start 325.880222 -251.528072)
		(mid 326.027026 -251.508636)
		(end 326.163686 -251.451618)
		(width 0.0889)
		(layer "In13.Cu")
		(net "M_B_CPU0_SA_CS_N<0>")
	)
	(arc
		(start 328.044048 -251.451618)
		(mid 328.226299 -251.401268)
		(end 328.409808 -251.446792)
		(width 0.0889)
		(layer "In13.Cu")
		(net "M_B_CPU0_SA_CS_N<0>")
	)
	(arc
		(start 330.863956 -251.451618)
		(mid 331.046207 -251.401268)
		(end 331.229716 -251.446792)
		(width 0.0889)
		(layer "In13.Cu")
		(net "M_B_CPU0_SA_CS_N<0>")
	)
	(arc
		(start 333.118206 -251.451618)
		(mid 333.401162 -251.527795)
		(end 333.684118 -251.451618)
		(width 0.0889)
		(layer "In13.Cu")
		(net "M_B_CPU0_SA_CS_N<0>")
	)
	(arc
		(start 334.632554 -251.446792)
		(mid 334.816062 -251.401298)
		(end 334.998314 -251.451618)
		(width 0.0889)
		(layer "In13.Cu")
		(net "M_B_CPU0_SA_CS_N<0>")
	)
	(arc
		(start 334.05826 -251.451618)
		(mid 334.341216 -251.527795)
		(end 334.624172 -251.451618)
		(width 0.0889)
		(layer "In13.Cu")
		(net "M_B_CPU0_SA_CS_N<0>")
	)
	(arc
		(start 332.752446 -251.446792)
		(mid 332.935954 -251.401298)
		(end 333.118206 -251.451618)
		(width 0.0889)
		(layer "In13.Cu")
		(net "M_B_CPU0_SA_CS_N<0>")
	)
	(arc
		(start 334.998314 -251.451618)
		(mid 335.246027 -251.526838)
		(end 335.501234 -251.483368)
		(width 0.0889)
		(layer "In13.Cu")
		(net "M_B_CPU0_SA_CS_N<0>")
	)
	(arc
		(start 329.924156 -251.451618)
		(mid 330.1111 -251.401363)
		(end 330.298044 -251.451618)
		(width 0.0889)
		(layer "In13.Cu")
		(net "M_B_CPU0_SA_CS_N<0>")
	)
	(arc
		(start 330.298044 -251.451618)
		(mid 330.581 -251.527795)
		(end 330.863956 -251.451618)
		(width 0.0889)
		(layer "In13.Cu")
		(net "M_B_CPU0_SA_CS_N<0>")
	)
	(arc
		(start 331.80401 -251.451618)
		(mid 331.986261 -251.401268)
		(end 332.16977 -251.446792)
		(width 0.0889)
		(layer "In13.Cu")
		(net "M_B_CPU0_SA_CS_N<0>")
	)
	(arc
		(start 332.178152 -251.451618)
		(mid 332.461108 -251.527795)
		(end 332.744064 -251.451618)
		(width 0.0889)
		(layer "In13.Cu")
		(net "M_B_CPU0_SA_CS_N<0>")
	)
	(arc
		(start 328.992484 -251.446792)
		(mid 329.175992 -251.401298)
		(end 329.358244 -251.451618)
		(width 0.0889)
		(layer "In13.Cu")
		(net "M_B_CPU0_SA_CS_N<0>")
	)
	(arc
		(start 328.41819 -251.451618)
		(mid 328.701146 -251.527795)
		(end 328.984102 -251.451618)
		(width 0.0889)
		(layer "In13.Cu")
		(net "M_B_CPU0_SA_CS_N<0>")
	)
	(segment
		(start 337.627976 -249.610118)
		(end 337.161124 -249.34418)
		(width 0.10668)
		(layer "F.Cu")
		(net "M_B_CPU0_SA_CB<7>")
	)
	(segment
		(start 329.819762 -249.016774)
		(end 329.828144 -249.0216)
		(width 0.0889)
		(layer "In13.Cu")
		(net "M_B_CPU0_SA_CB<7>")
	)
	(segment
		(start 331.33411 -249.0216)
		(end 331.342492 -249.016774)
		(width 0.0889)
		(layer "In13.Cu")
		(net "M_B_CPU0_SA_CB<7>")
	)
	(segment
		(start 327.939908 -249.016774)
		(end 327.94829 -249.0216)
		(width 0.0889)
		(layer "In13.Cu")
		(net "M_B_CPU0_SA_CB<7>")
	)
	(segment
		(start 322.208144 -249.14606)
		(end 322.521834 -249.45975)
		(width 0.14478)
		(layer "In13.Cu")
		(net "M_B_CPU0_SA_CB<7>")
	)
	(segment
		(start 334.519778 -249.016774)
		(end 334.52816 -249.0216)
		(width 0.0889)
		(layer "In13.Cu")
		(net "M_B_CPU0_SA_CB<7>")
	)
	(segment
		(start 326.617838 -249.030998)
		(end 326.633586 -249.021854)
		(width 0.0889)
		(layer "In13.Cu")
		(net "M_B_CPU0_SA_CB<7>")
	)
	(segment
		(start 324.618858 -249.201432)
		(end 325.025258 -249.201432)
		(width 0.0889)
		(layer "In13.Cu")
		(net "M_B_CPU0_SA_CB<7>")
	)
	(segment
		(start 324.36054 -249.45975)
		(end 324.618858 -249.201432)
		(width 0.0889)
		(layer "In13.Cu")
		(net "M_B_CPU0_SA_CB<7>")
	)
	(segment
		(start 303.601374 -243.660168)
		(end 305.41087 -245.469664)
		(width 0.14478)
		(layer "In13.Cu")
		(net "M_B_CPU0_SA_CB<7>")
	)
	(segment
		(start 311.824624 -249.14606)
		(end 322.208144 -249.14606)
		(width 0.14478)
		(layer "In13.Cu")
		(net "M_B_CPU0_SA_CB<7>")
	)
	(segment
		(start 333.579724 -249.016774)
		(end 333.588106 -249.0216)
		(width 0.0889)
		(layer "In13.Cu")
		(net "M_B_CPU0_SA_CB<7>")
	)
	(segment
		(start 305.41087 -245.469664)
		(end 308.148228 -245.469664)
		(width 0.14478)
		(layer "In13.Cu")
		(net "M_B_CPU0_SA_CB<7>")
	)
	(segment
		(start 297.951652 -243.234972)
		(end 298.376848 -243.660168)
		(width 0.14478)
		(layer "In13.Cu")
		(net "M_B_CPU0_SA_CB<7>")
	)
	(segment
		(start 295.724072 -243.234972)
		(end 297.951652 -243.234972)
		(width 0.14478)
		(layer "In13.Cu")
		(net "M_B_CPU0_SA_CB<7>")
	)
	(segment
		(start 336.911188 -249.05335)
		(end 337.0072 -249.07875)
		(width 0.0889)
		(layer "In13.Cu")
		(net "M_B_CPU0_SA_CB<7>")
	)
	(segment
		(start 326.633586 -249.021854)
		(end 326.649842 -249.012456)
		(width 0.0889)
		(layer "In13.Cu")
		(net "M_B_CPU0_SA_CB<7>")
	)
	(segment
		(start 322.521834 -249.45975)
		(end 323.880734 -249.45975)
		(width 0.14478)
		(layer "In13.Cu")
		(net "M_B_CPU0_SA_CB<7>")
	)
	(segment
		(start 337.0072 -249.07875)
		(end 337.161124 -249.34418)
		(width 0.0889)
		(layer "In13.Cu")
		(net "M_B_CPU0_SA_CB<7>")
	)
	(segment
		(start 336.034126 -249.0216)
		(end 336.042508 -249.016774)
		(width 0.0889)
		(layer "In13.Cu")
		(net "M_B_CPU0_SA_CB<7>")
	)
	(segment
		(start 330.394056 -249.0216)
		(end 330.402438 -249.016774)
		(width 0.0889)
		(layer "In13.Cu")
		(net "M_B_CPU0_SA_CB<7>")
	)
	(segment
		(start 308.148228 -245.469664)
		(end 311.824624 -249.14606)
		(width 0.14478)
		(layer "In13.Cu")
		(net "M_B_CPU0_SA_CB<7>")
	)
	(segment
		(start 323.880734 -249.45975)
		(end 324.36054 -249.45975)
		(width 0.0889)
		(layer "In13.Cu")
		(net "M_B_CPU0_SA_CB<7>")
	)
	(segment
		(start 298.376848 -243.660168)
		(end 303.601374 -243.660168)
		(width 0.14478)
		(layer "In13.Cu")
		(net "M_B_CPU0_SA_CB<7>")
	)
	(segment
		(start 325.693278 -249.0216)
		(end 325.704962 -249.014742)
		(width 0.0889)
		(layer "In13.Cu")
		(net "M_B_CPU0_SA_CB<7>")
	)
	(segment
		(start 327.007474 -249.0216)
		(end 327.017888 -249.027696)
		(width 0.0889)
		(layer "In13.Cu")
		(net "M_B_CPU0_SA_CB<7>")
	)
	(segment
		(start 335.094072 -249.0216)
		(end 335.102454 -249.016774)
		(width 0.0889)
		(layer "In13.Cu")
		(net "M_B_CPU0_SA_CB<7>")
	)
	(arc
		(start 329.454002 -249.0216)
		(mid 329.636253 -248.97125)
		(end 329.819762 -249.016774)
		(width 0.0889)
		(layer "In13.Cu")
		(net "M_B_CPU0_SA_CB<7>")
	)
	(arc
		(start 327.57364 -249.0216)
		(mid 327.756145 -248.971123)
		(end 327.939908 -249.016774)
		(width 0.0889)
		(layer "In13.Cu")
		(net "M_B_CPU0_SA_CB<7>")
	)
	(arc
		(start 331.708252 -249.0216)
		(mid 331.991208 -249.097777)
		(end 332.274164 -249.0216)
		(width 0.0889)
		(layer "In13.Cu")
		(net "M_B_CPU0_SA_CB<7>")
	)
	(arc
		(start 335.468214 -249.0216)
		(mid 335.75117 -249.097777)
		(end 336.034126 -249.0216)
		(width 0.0889)
		(layer "In13.Cu")
		(net "M_B_CPU0_SA_CB<7>")
	)
	(arc
		(start 326.649842 -249.012456)
		(mid 326.829824 -248.971356)
		(end 327.007474 -249.0216)
		(width 0.0889)
		(layer "In13.Cu")
		(net "M_B_CPU0_SA_CB<7>")
	)
	(arc
		(start 331.342492 -249.016774)
		(mid 331.526 -248.97128)
		(end 331.708252 -249.0216)
		(width 0.0889)
		(layer "In13.Cu")
		(net "M_B_CPU0_SA_CB<7>")
	)
	(arc
		(start 334.52816 -249.0216)
		(mid 334.811116 -249.097777)
		(end 335.094072 -249.0216)
		(width 0.0889)
		(layer "In13.Cu")
		(net "M_B_CPU0_SA_CB<7>")
	)
	(arc
		(start 334.154018 -249.0216)
		(mid 334.336269 -248.97125)
		(end 334.519778 -249.016774)
		(width 0.0889)
		(layer "In13.Cu")
		(net "M_B_CPU0_SA_CB<7>")
	)
	(arc
		(start 330.402438 -249.016774)
		(mid 330.585946 -248.97128)
		(end 330.768198 -249.0216)
		(width 0.0889)
		(layer "In13.Cu")
		(net "M_B_CPU0_SA_CB<7>")
	)
	(arc
		(start 327.94829 -249.0216)
		(mid 328.231246 -249.097777)
		(end 328.514202 -249.0216)
		(width 0.0889)
		(layer "In13.Cu")
		(net "M_B_CPU0_SA_CB<7>")
	)
	(arc
		(start 335.102454 -249.016774)
		(mid 335.285962 -248.97128)
		(end 335.468214 -249.0216)
		(width 0.0889)
		(layer "In13.Cu")
		(net "M_B_CPU0_SA_CB<7>")
	)
	(arc
		(start 329.828144 -249.0216)
		(mid 330.1111 -249.097777)
		(end 330.394056 -249.0216)
		(width 0.0889)
		(layer "In13.Cu")
		(net "M_B_CPU0_SA_CB<7>")
	)
	(arc
		(start 332.274164 -249.0216)
		(mid 332.461108 -248.971345)
		(end 332.648052 -249.0216)
		(width 0.0889)
		(layer "In13.Cu")
		(net "M_B_CPU0_SA_CB<7>")
	)
	(arc
		(start 330.768198 -249.0216)
		(mid 331.051154 -249.097777)
		(end 331.33411 -249.0216)
		(width 0.0889)
		(layer "In13.Cu")
		(net "M_B_CPU0_SA_CB<7>")
	)
	(arc
		(start 327.017888 -249.027696)
		(mid 327.296574 -249.097916)
		(end 327.57364 -249.0216)
		(width 0.0889)
		(layer "In13.Cu")
		(net "M_B_CPU0_SA_CB<7>")
	)
	(arc
		(start 328.514202 -249.0216)
		(mid 328.701146 -248.971345)
		(end 328.88809 -249.0216)
		(width 0.0889)
		(layer "In13.Cu")
		(net "M_B_CPU0_SA_CB<7>")
	)
	(arc
		(start 325.025258 -249.201432)
		(mid 325.371151 -249.155673)
		(end 325.693278 -249.0216)
		(width 0.0889)
		(layer "In13.Cu")
		(net "M_B_CPU0_SA_CB<7>")
	)
	(arc
		(start 336.042508 -249.016774)
		(mid 336.226016 -248.97128)
		(end 336.408268 -249.0216)
		(width 0.0889)
		(layer "In13.Cu")
		(net "M_B_CPU0_SA_CB<7>")
	)
	(arc
		(start 325.704962 -249.014742)
		(mid 325.887217 -248.971089)
		(end 326.067674 -249.0216)
		(width 0.0889)
		(layer "In13.Cu")
		(net "M_B_CPU0_SA_CB<7>")
	)
	(arc
		(start 332.648052 -249.0216)
		(mid 332.931008 -249.097777)
		(end 333.213964 -249.0216)
		(width 0.0889)
		(layer "In13.Cu")
		(net "M_B_CPU0_SA_CB<7>")
	)
	(arc
		(start 333.213964 -249.0216)
		(mid 333.396215 -248.97125)
		(end 333.579724 -249.016774)
		(width 0.0889)
		(layer "In13.Cu")
		(net "M_B_CPU0_SA_CB<7>")
	)
	(arc
		(start 333.588106 -249.0216)
		(mid 333.871062 -249.097777)
		(end 334.154018 -249.0216)
		(width 0.0889)
		(layer "In13.Cu")
		(net "M_B_CPU0_SA_CB<7>")
	)
	(arc
		(start 326.067674 -249.0216)
		(mid 326.341529 -249.09795)
		(end 326.617838 -249.030998)
		(width 0.0889)
		(layer "In13.Cu")
		(net "M_B_CPU0_SA_CB<7>")
	)
	(arc
		(start 328.88809 -249.0216)
		(mid 329.171046 -249.097777)
		(end 329.454002 -249.0216)
		(width 0.0889)
		(layer "In13.Cu")
		(net "M_B_CPU0_SA_CB<7>")
	)
	(arc
		(start 336.408268 -249.0216)
		(mid 336.655981 -249.09682)
		(end 336.911188 -249.05335)
		(width 0.0889)
		(layer "In13.Cu")
		(net "M_B_CPU0_SA_CB<7>")
	)
	(segment
		(start 336.218022 -248.800112)
		(end 335.75117 -248.534174)
		(width 0.10668)
		(layer "F.Cu")
		(net "M_B_CPU0_SA_CB<6>")
	)
	(segment
		(start 324.201536 -248.54281)
		(end 324.293738 -248.635012)
		(width 0.0889)
		(layer "In13.Cu")
		(net "M_B_CPU0_SA_CB<6>")
	)
	(segment
		(start 328.984102 -248.211594)
		(end 328.992484 -248.206768)
		(width 0.0889)
		(layer "In13.Cu")
		(net "M_B_CPU0_SA_CB<6>")
	)
	(segment
		(start 306.445666 -243.666772)
		(end 307.683916 -243.666772)
		(width 0.14478)
		(layer "In13.Cu")
		(net "M_B_CPU0_SA_CB<6>")
	)
	(segment
		(start 332.16977 -248.206768)
		(end 332.178152 -248.211594)
		(width 0.0889)
		(layer "In13.Cu")
		(net "M_B_CPU0_SA_CB<6>")
	)
	(segment
		(start 312.253884 -248.23674)
		(end 322.606924 -248.23674)
		(width 0.14478)
		(layer "In13.Cu")
		(net "M_B_CPU0_SA_CB<6>")
	)
	(segment
		(start 296.821606 -241.67973)
		(end 296.821606 -241.88801)
		(width 0.14478)
		(layer "In13.Cu")
		(net "M_B_CPU0_SA_CB<6>")
	)
	(segment
		(start 325.373238 -248.635012)
		(end 325.464678 -248.543572)
		(width 0.0889)
		(layer "In13.Cu")
		(net "M_B_CPU0_SA_CB<6>")
	)
	(segment
		(start 298.475146 -241.67973)
		(end 298.619926 -241.53495)
		(width 0.14478)
		(layer "In13.Cu")
		(net "M_B_CPU0_SA_CB<6>")
	)
	(segment
		(start 296.966386 -242.03279)
		(end 297.228006 -242.03279)
		(width 0.14478)
		(layer "In13.Cu")
		(net "M_B_CPU0_SA_CB<6>")
	)
	(segment
		(start 327.083166 -248.22531)
		(end 327.106534 -248.211594)
		(width 0.0889)
		(layer "In13.Cu")
		(net "M_B_CPU0_SA_CB<6>")
	)
	(segment
		(start 297.372786 -241.88801)
		(end 297.372786 -241.67973)
		(width 0.14478)
		(layer "In13.Cu")
		(net "M_B_CPU0_SA_CB<6>")
	)
	(segment
		(start 297.923966 -241.67973)
		(end 297.923966 -241.88801)
		(width 0.14478)
		(layer "In13.Cu")
		(net "M_B_CPU0_SA_CB<6>")
	)
	(segment
		(start 335.500726 -248.243344)
		(end 335.596992 -248.268744)
		(width 0.0889)
		(layer "In13.Cu")
		(net "M_B_CPU0_SA_CB<6>")
	)
	(segment
		(start 298.475146 -241.88801)
		(end 298.475146 -241.67973)
		(width 0.14478)
		(layer "In13.Cu")
		(net "M_B_CPU0_SA_CB<6>")
	)
	(segment
		(start 299.492924 -241.960146)
		(end 304.73904 -241.960146)
		(width 0.14478)
		(layer "In13.Cu")
		(net "M_B_CPU0_SA_CB<6>")
	)
	(segment
		(start 296.676826 -241.53495)
		(end 296.821606 -241.67973)
		(width 0.14478)
		(layer "In13.Cu")
		(net "M_B_CPU0_SA_CB<6>")
	)
	(segment
		(start 335.596992 -248.268744)
		(end 335.75117 -248.534174)
		(width 0.0889)
		(layer "In13.Cu")
		(net "M_B_CPU0_SA_CB<6>")
	)
	(segment
		(start 298.068746 -242.03279)
		(end 298.330366 -242.03279)
		(width 0.14478)
		(layer "In13.Cu")
		(net "M_B_CPU0_SA_CB<6>")
	)
	(segment
		(start 297.779186 -241.53495)
		(end 297.923966 -241.67973)
		(width 0.14478)
		(layer "In13.Cu")
		(net "M_B_CPU0_SA_CB<6>")
	)
	(segment
		(start 327.461372 -248.201434)
		(end 327.47966 -248.211848)
		(width 0.0889)
		(layer "In13.Cu")
		(net "M_B_CPU0_SA_CB<6>")
	)
	(segment
		(start 295.724072 -241.53495)
		(end 296.676826 -241.53495)
		(width 0.14478)
		(layer "In13.Cu")
		(net "M_B_CPU0_SA_CB<6>")
	)
	(segment
		(start 332.744064 -248.211594)
		(end 332.752446 -248.206768)
		(width 0.0889)
		(layer "In13.Cu")
		(net "M_B_CPU0_SA_CB<6>")
	)
	(segment
		(start 322.912994 -248.54281)
		(end 323.868034 -248.54281)
		(width 0.14478)
		(layer "In13.Cu")
		(net "M_B_CPU0_SA_CB<6>")
	)
	(segment
		(start 331.229716 -248.206768)
		(end 331.238098 -248.211594)
		(width 0.0889)
		(layer "In13.Cu")
		(net "M_B_CPU0_SA_CB<6>")
	)
	(segment
		(start 325.815452 -248.543572)
		(end 326.087994 -248.27103)
		(width 0.0889)
		(layer "In13.Cu")
		(net "M_B_CPU0_SA_CB<6>")
	)
	(segment
		(start 323.868034 -248.54281)
		(end 324.201536 -248.54281)
		(width 0.0889)
		(layer "In13.Cu")
		(net "M_B_CPU0_SA_CB<6>")
	)
	(segment
		(start 298.619926 -241.53495)
		(end 299.067728 -241.53495)
		(width 0.14478)
		(layer "In13.Cu")
		(net "M_B_CPU0_SA_CB<6>")
	)
	(segment
		(start 327.47966 -248.211848)
		(end 327.50125 -248.224294)
		(width 0.0889)
		(layer "In13.Cu")
		(net "M_B_CPU0_SA_CB<6>")
	)
	(segment
		(start 304.73904 -241.960146)
		(end 306.445666 -243.666772)
		(width 0.14478)
		(layer "In13.Cu")
		(net "M_B_CPU0_SA_CB<6>")
	)
	(segment
		(start 307.683916 -243.666772)
		(end 312.253884 -248.23674)
		(width 0.14478)
		(layer "In13.Cu")
		(net "M_B_CPU0_SA_CB<6>")
	)
	(segment
		(start 296.821606 -241.88801)
		(end 296.966386 -242.03279)
		(width 0.14478)
		(layer "In13.Cu")
		(net "M_B_CPU0_SA_CB<6>")
	)
	(segment
		(start 297.923966 -241.88801)
		(end 298.068746 -242.03279)
		(width 0.14478)
		(layer "In13.Cu")
		(net "M_B_CPU0_SA_CB<6>")
	)
	(segment
		(start 324.293738 -248.635012)
		(end 325.373238 -248.635012)
		(width 0.0889)
		(layer "In13.Cu")
		(net "M_B_CPU0_SA_CB<6>")
	)
	(segment
		(start 297.517566 -241.53495)
		(end 297.779186 -241.53495)
		(width 0.14478)
		(layer "In13.Cu")
		(net "M_B_CPU0_SA_CB<6>")
	)
	(segment
		(start 333.684118 -248.211594)
		(end 333.6925 -248.206768)
		(width 0.0889)
		(layer "In13.Cu")
		(net "M_B_CPU0_SA_CB<6>")
	)
	(segment
		(start 326.16521 -248.211848)
		(end 326.192642 -248.1961)
		(width 0.0889)
		(layer "In13.Cu")
		(net "M_B_CPU0_SA_CB<6>")
	)
	(segment
		(start 322.606924 -248.23674)
		(end 322.912994 -248.54281)
		(width 0.14478)
		(layer "In13.Cu")
		(net "M_B_CPU0_SA_CB<6>")
	)
	(segment
		(start 299.067728 -241.53495)
		(end 299.492924 -241.960146)
		(width 0.14478)
		(layer "In13.Cu")
		(net "M_B_CPU0_SA_CB<6>")
	)
	(segment
		(start 298.330366 -242.03279)
		(end 298.475146 -241.88801)
		(width 0.14478)
		(layer "In13.Cu")
		(net "M_B_CPU0_SA_CB<6>")
	)
	(segment
		(start 328.409808 -248.206768)
		(end 328.41819 -248.211594)
		(width 0.0889)
		(layer "In13.Cu")
		(net "M_B_CPU0_SA_CB<6>")
	)
	(segment
		(start 297.372786 -241.67973)
		(end 297.517566 -241.53495)
		(width 0.14478)
		(layer "In13.Cu")
		(net "M_B_CPU0_SA_CB<6>")
	)
	(segment
		(start 297.228006 -242.03279)
		(end 297.372786 -241.88801)
		(width 0.14478)
		(layer "In13.Cu")
		(net "M_B_CPU0_SA_CB<6>")
	)
	(segment
		(start 325.464678 -248.543572)
		(end 325.815452 -248.543572)
		(width 0.0889)
		(layer "In13.Cu")
		(net "M_B_CPU0_SA_CB<6>")
	)
	(arc
		(start 328.992484 -248.206768)
		(mid 329.175992 -248.161274)
		(end 329.358244 -248.211594)
		(width 0.0889)
		(layer "In13.Cu")
		(net "M_B_CPU0_SA_CB<6>")
	)
	(arc
		(start 330.863956 -248.211594)
		(mid 331.046207 -248.161244)
		(end 331.229716 -248.206768)
		(width 0.0889)
		(layer "In13.Cu")
		(net "M_B_CPU0_SA_CB<6>")
	)
	(arc
		(start 326.539352 -248.211594)
		(mid 326.809509 -248.288356)
		(end 327.083166 -248.22531)
		(width 0.0889)
		(layer "In13.Cu")
		(net "M_B_CPU0_SA_CB<6>")
	)
	(arc
		(start 333.6925 -248.206768)
		(mid 333.876008 -248.161274)
		(end 334.05826 -248.211594)
		(width 0.0889)
		(layer "In13.Cu")
		(net "M_B_CPU0_SA_CB<6>")
	)
	(arc
		(start 331.238098 -248.211594)
		(mid 331.521054 -248.287771)
		(end 331.80401 -248.211594)
		(width 0.0889)
		(layer "In13.Cu")
		(net "M_B_CPU0_SA_CB<6>")
	)
	(arc
		(start 328.044048 -248.211594)
		(mid 328.226299 -248.161244)
		(end 328.409808 -248.206768)
		(width 0.0889)
		(layer "In13.Cu")
		(net "M_B_CPU0_SA_CB<6>")
	)
	(arc
		(start 327.106534 -248.211594)
		(mid 327.282654 -248.161616)
		(end 327.461372 -248.201434)
		(width 0.0889)
		(layer "In13.Cu")
		(net "M_B_CPU0_SA_CB<6>")
	)
	(arc
		(start 332.178152 -248.211594)
		(mid 332.461108 -248.287771)
		(end 332.744064 -248.211594)
		(width 0.0889)
		(layer "In13.Cu")
		(net "M_B_CPU0_SA_CB<6>")
	)
	(arc
		(start 327.50125 -248.224294)
		(mid 327.774279 -248.287613)
		(end 328.044048 -248.211594)
		(width 0.0889)
		(layer "In13.Cu")
		(net "M_B_CPU0_SA_CB<6>")
	)
	(arc
		(start 334.624172 -248.211594)
		(mid 334.811116 -248.161339)
		(end 334.99806 -248.211594)
		(width 0.0889)
		(layer "In13.Cu")
		(net "M_B_CPU0_SA_CB<6>")
	)
	(arc
		(start 334.05826 -248.211594)
		(mid 334.341216 -248.287771)
		(end 334.624172 -248.211594)
		(width 0.0889)
		(layer "In13.Cu")
		(net "M_B_CPU0_SA_CB<6>")
	)
	(arc
		(start 331.80401 -248.211594)
		(mid 331.986261 -248.161244)
		(end 332.16977 -248.206768)
		(width 0.0889)
		(layer "In13.Cu")
		(net "M_B_CPU0_SA_CB<6>")
	)
	(arc
		(start 329.358244 -248.211594)
		(mid 329.6412 -248.287771)
		(end 329.924156 -248.211594)
		(width 0.0889)
		(layer "In13.Cu")
		(net "M_B_CPU0_SA_CB<6>")
	)
	(arc
		(start 334.99806 -248.211594)
		(mid 335.245656 -248.286772)
		(end 335.500726 -248.243344)
		(width 0.0889)
		(layer "In13.Cu")
		(net "M_B_CPU0_SA_CB<6>")
	)
	(arc
		(start 332.752446 -248.206768)
		(mid 332.935954 -248.161274)
		(end 333.118206 -248.211594)
		(width 0.0889)
		(layer "In13.Cu")
		(net "M_B_CPU0_SA_CB<6>")
	)
	(arc
		(start 330.298044 -248.211594)
		(mid 330.581 -248.287771)
		(end 330.863956 -248.211594)
		(width 0.0889)
		(layer "In13.Cu")
		(net "M_B_CPU0_SA_CB<6>")
	)
	(arc
		(start 329.924156 -248.211594)
		(mid 330.1111 -248.161339)
		(end 330.298044 -248.211594)
		(width 0.0889)
		(layer "In13.Cu")
		(net "M_B_CPU0_SA_CB<6>")
	)
	(arc
		(start 326.087994 -248.27103)
		(mid 326.12465 -248.23889)
		(end 326.16521 -248.211848)
		(width 0.0889)
		(layer "In13.Cu")
		(net "M_B_CPU0_SA_CB<6>")
	)
	(arc
		(start 328.41819 -248.211594)
		(mid 328.701146 -248.287771)
		(end 328.984102 -248.211594)
		(width 0.0889)
		(layer "In13.Cu")
		(net "M_B_CPU0_SA_CB<6>")
	)
	(arc
		(start 326.192642 -248.1961)
		(mid 326.367893 -248.161167)
		(end 326.539352 -248.211594)
		(width 0.0889)
		(layer "In13.Cu")
		(net "M_B_CPU0_SA_CB<6>")
	)
	(arc
		(start 333.118206 -248.211594)
		(mid 333.401162 -248.287771)
		(end 333.684118 -248.211594)
		(width 0.0889)
		(layer "In13.Cu")
		(net "M_B_CPU0_SA_CB<6>")
	)
	(segment
		(start 337.158076 -248.800112)
		(end 336.691224 -248.534174)
		(width 0.10668)
		(layer "F.Cu")
		(net "M_B_CPU0_SA_CB<5>")
	)
	(segment
		(start 324.189598 -248.904252)
		(end 324.42023 -248.904252)
		(width 0.0889)
		(layer "In13.Cu")
		(net "M_B_CPU0_SA_CB<5>")
	)
	(segment
		(start 301.4345 -242.524788)
		(end 301.57928 -242.669568)
		(width 0.14478)
		(layer "In13.Cu")
		(net "M_B_CPU0_SA_CB<5>")
	)
	(segment
		(start 304.871628 -242.781836)
		(end 305.033172 -242.94338)
		(width 0.14478)
		(layer "In13.Cu")
		(net "M_B_CPU0_SA_CB<5>")
	)
	(segment
		(start 331.229716 -248.86158)
		(end 331.238098 -248.856754)
		(width 0.0889)
		(layer "In13.Cu")
		(net "M_B_CPU0_SA_CB<5>")
	)
	(segment
		(start 300.526958 -243.210588)
		(end 300.88332 -243.210588)
		(width 0.14478)
		(layer "In13.Cu")
		(net "M_B_CPU0_SA_CB<5>")
	)
	(segment
		(start 336.822796 -248.882916)
		(end 336.845148 -248.799604)
		(width 0.0889)
		(layer "In13.Cu")
		(net "M_B_CPU0_SA_CB<5>")
	)
	(segment
		(start 306.34813 -244.515132)
		(end 307.866796 -244.515132)
		(width 0.14478)
		(layer "In13.Cu")
		(net "M_B_CPU0_SA_CB<5>")
	)
	(segment
		(start 323.890894 -249.00255)
		(end 324.0913 -249.00255)
		(width 0.0889)
		(layer "In13.Cu")
		(net "M_B_CPU0_SA_CB<5>")
	)
	(segment
		(start 328.033634 -248.850658)
		(end 328.044048 -248.856754)
		(width 0.0889)
		(layer "In13.Cu")
		(net "M_B_CPU0_SA_CB<5>")
	)
	(segment
		(start 305.50739 -244.515132)
		(end 305.65217 -244.659912)
		(width 0.14478)
		(layer "In13.Cu")
		(net "M_B_CPU0_SA_CB<5>")
	)
	(segment
		(start 335.929732 -248.86158)
		(end 335.938114 -248.856754)
		(width 0.0889)
		(layer "In13.Cu")
		(net "M_B_CPU0_SA_CB<5>")
	)
	(segment
		(start 302.27524 -242.524788)
		(end 302.53686 -242.524788)
		(width 0.14478)
		(layer "In13.Cu")
		(net "M_B_CPU0_SA_CB<5>")
	)
	(segment
		(start 302.68164 -242.669568)
		(end 302.68164 -243.065808)
		(width 0.14478)
		(layer "In13.Cu")
		(net "M_B_CPU0_SA_CB<5>")
	)
	(segment
		(start 332.744064 -248.856754)
		(end 332.752446 -248.86158)
		(width 0.0889)
		(layer "In13.Cu")
		(net "M_B_CPU0_SA_CB<5>")
	)
	(segment
		(start 302.13046 -242.669568)
		(end 302.27524 -242.524788)
		(width 0.14478)
		(layer "In13.Cu")
		(net "M_B_CPU0_SA_CB<5>")
	)
	(segment
		(start 322.714874 -249.00255)
		(end 323.890894 -249.00255)
		(width 0.14478)
		(layer "In13.Cu")
		(net "M_B_CPU0_SA_CB<5>")
	)
	(segment
		(start 305.033172 -243.17198)
		(end 304.521616 -243.683536)
		(width 0.14478)
		(layer "In13.Cu")
		(net "M_B_CPU0_SA_CB<5>")
	)
	(segment
		(start 302.68164 -243.065808)
		(end 302.82642 -243.210588)
		(width 0.14478)
		(layer "In13.Cu")
		(net "M_B_CPU0_SA_CB<5>")
	)
	(segment
		(start 306.20335 -244.791738)
		(end 306.20335 -244.659912)
		(width 0.14478)
		(layer "In13.Cu")
		(net "M_B_CPU0_SA_CB<5>")
	)
	(segment
		(start 299.82414 -242.385088)
		(end 299.82414 -242.50777)
		(width 0.14478)
		(layer "In13.Cu")
		(net "M_B_CPU0_SA_CB<5>")
	)
	(segment
		(start 325.409814 -248.9073)
		(end 325.410068 -248.907046)
		(width 0.0889)
		(layer "In13.Cu")
		(net "M_B_CPU0_SA_CB<5>")
	)
	(segment
		(start 336.845148 -248.799604)
		(end 336.691224 -248.534174)
		(width 0.0889)
		(layer "In13.Cu")
		(net "M_B_CPU0_SA_CB<5>")
	)
	(segment
		(start 324.42023 -248.904252)
		(end 324.423278 -248.9073)
		(width 0.0889)
		(layer "In13.Cu")
		(net "M_B_CPU0_SA_CB<5>")
	)
	(segment
		(start 301.98568 -243.210588)
		(end 302.13046 -243.065808)
		(width 0.14478)
		(layer "In13.Cu")
		(net "M_B_CPU0_SA_CB<5>")
	)
	(segment
		(start 300.88332 -243.210588)
		(end 301.0281 -243.065808)
		(width 0.14478)
		(layer "In13.Cu")
		(net "M_B_CPU0_SA_CB<5>")
	)
	(segment
		(start 302.82642 -243.210588)
		(end 304.214276 -243.210588)
		(width 0.14478)
		(layer "In13.Cu")
		(net "M_B_CPU0_SA_CB<5>")
	)
	(segment
		(start 307.866796 -244.515132)
		(end 312.043064 -248.6914)
		(width 0.14478)
		(layer "In13.Cu")
		(net "M_B_CPU0_SA_CB<5>")
	)
	(segment
		(start 301.0281 -242.669568)
		(end 301.17288 -242.524788)
		(width 0.14478)
		(layer "In13.Cu")
		(net "M_B_CPU0_SA_CB<5>")
	)
	(segment
		(start 325.597266 -248.856754)
		(end 325.611998 -248.848118)
		(width 0.0889)
		(layer "In13.Cu")
		(net "M_B_CPU0_SA_CB<5>")
	)
	(segment
		(start 305.65217 -244.659912)
		(end 305.65217 -244.791738)
		(width 0.14478)
		(layer "In13.Cu")
		(net "M_B_CPU0_SA_CB<5>")
	)
	(segment
		(start 301.0281 -243.065808)
		(end 301.0281 -242.669568)
		(width 0.14478)
		(layer "In13.Cu")
		(net "M_B_CPU0_SA_CB<5>")
	)
	(segment
		(start 301.57928 -242.669568)
		(end 301.57928 -243.065808)
		(width 0.14478)
		(layer "In13.Cu")
		(net "M_B_CPU0_SA_CB<5>")
	)
	(segment
		(start 301.17288 -242.524788)
		(end 301.4345 -242.524788)
		(width 0.14478)
		(layer "In13.Cu")
		(net "M_B_CPU0_SA_CB<5>")
	)
	(segment
		(start 305.033172 -242.94338)
		(end 305.033172 -243.17198)
		(width 0.14478)
		(layer "In13.Cu")
		(net "M_B_CPU0_SA_CB<5>")
	)
	(segment
		(start 306.20335 -244.659912)
		(end 306.34813 -244.515132)
		(width 0.14478)
		(layer "In13.Cu")
		(net "M_B_CPU0_SA_CB<5>")
	)
	(segment
		(start 302.53686 -242.524788)
		(end 302.68164 -242.669568)
		(width 0.14478)
		(layer "In13.Cu")
		(net "M_B_CPU0_SA_CB<5>")
	)
	(segment
		(start 328.984102 -248.856754)
		(end 328.992484 -248.86158)
		(width 0.0889)
		(layer "In13.Cu")
		(net "M_B_CPU0_SA_CB<5>")
	)
	(segment
		(start 326.51954 -248.866914)
		(end 326.537828 -248.8565)
		(width 0.0889)
		(layer "In13.Cu")
		(net "M_B_CPU0_SA_CB<5>")
	)
	(segment
		(start 304.214276 -243.210588)
		(end 304.643028 -242.781836)
		(width 0.14478)
		(layer "In13.Cu")
		(net "M_B_CPU0_SA_CB<5>")
	)
	(segment
		(start 322.403724 -248.6914)
		(end 322.714874 -249.00255)
		(width 0.14478)
		(layer "In13.Cu")
		(net "M_B_CPU0_SA_CB<5>")
	)
	(segment
		(start 305.79695 -244.936518)
		(end 306.05857 -244.936518)
		(width 0.14478)
		(layer "In13.Cu")
		(net "M_B_CPU0_SA_CB<5>")
	)
	(segment
		(start 326.537828 -248.8565)
		(end 326.543416 -248.853198)
		(width 0.0889)
		(layer "In13.Cu")
		(net "M_B_CPU0_SA_CB<5>")
	)
	(segment
		(start 305.092608 -244.515132)
		(end 305.50739 -244.515132)
		(width 0.14478)
		(layer "In13.Cu")
		(net "M_B_CPU0_SA_CB<5>")
	)
	(segment
		(start 312.043064 -248.6914)
		(end 322.403724 -248.6914)
		(width 0.14478)
		(layer "In13.Cu")
		(net "M_B_CPU0_SA_CB<5>")
	)
	(segment
		(start 302.13046 -243.065808)
		(end 302.13046 -242.669568)
		(width 0.14478)
		(layer "In13.Cu")
		(net "M_B_CPU0_SA_CB<5>")
	)
	(segment
		(start 304.643028 -242.781836)
		(end 304.871628 -242.781836)
		(width 0.14478)
		(layer "In13.Cu")
		(net "M_B_CPU0_SA_CB<5>")
	)
	(segment
		(start 324.423278 -248.9073)
		(end 325.409814 -248.9073)
		(width 0.0889)
		(layer "In13.Cu")
		(net "M_B_CPU0_SA_CB<5>")
	)
	(segment
		(start 305.65217 -244.791738)
		(end 305.79695 -244.936518)
		(width 0.14478)
		(layer "In13.Cu")
		(net "M_B_CPU0_SA_CB<5>")
	)
	(segment
		(start 324.0913 -249.00255)
		(end 324.189598 -248.904252)
		(width 0.0889)
		(layer "In13.Cu")
		(net "M_B_CPU0_SA_CB<5>")
	)
	(segment
		(start 332.16977 -248.86158)
		(end 332.178152 -248.856754)
		(width 0.0889)
		(layer "In13.Cu")
		(net "M_B_CPU0_SA_CB<5>")
	)
	(segment
		(start 304.521616 -243.683536)
		(end 304.521616 -243.94414)
		(width 0.14478)
		(layer "In13.Cu")
		(net "M_B_CPU0_SA_CB<5>")
	)
	(segment
		(start 306.05857 -244.936518)
		(end 306.20335 -244.791738)
		(width 0.14478)
		(layer "In13.Cu")
		(net "M_B_CPU0_SA_CB<5>")
	)
	(segment
		(start 299.82414 -242.50777)
		(end 300.526958 -243.210588)
		(width 0.14478)
		(layer "In13.Cu")
		(net "M_B_CPU0_SA_CB<5>")
	)
	(segment
		(start 327.103232 -248.856754)
		(end 327.111614 -248.86158)
		(width 0.0889)
		(layer "In13.Cu")
		(net "M_B_CPU0_SA_CB<5>")
	)
	(segment
		(start 333.684118 -248.856754)
		(end 333.6925 -248.86158)
		(width 0.0889)
		(layer "In13.Cu")
		(net "M_B_CPU0_SA_CB<5>")
	)
	(segment
		(start 301.72406 -243.210588)
		(end 301.98568 -243.210588)
		(width 0.14478)
		(layer "In13.Cu")
		(net "M_B_CPU0_SA_CB<5>")
	)
	(segment
		(start 304.521616 -243.94414)
		(end 305.092608 -244.515132)
		(width 0.14478)
		(layer "In13.Cu")
		(net "M_B_CPU0_SA_CB<5>")
	)
	(segment
		(start 301.57928 -243.065808)
		(end 301.72406 -243.210588)
		(width 0.14478)
		(layer "In13.Cu")
		(net "M_B_CPU0_SA_CB<5>")
	)
	(segment
		(start 328.409808 -248.86158)
		(end 328.41819 -248.856754)
		(width 0.0889)
		(layer "In13.Cu")
		(net "M_B_CPU0_SA_CB<5>")
	)
	(arc
		(start 325.611998 -248.848118)
		(mid 325.888981 -248.780314)
		(end 326.163686 -248.856754)
		(width 0.0889)
		(layer "In13.Cu")
		(net "M_B_CPU0_SA_CB<5>")
	)
	(arc
		(start 327.111614 -248.86158)
		(mid 327.295376 -248.907196)
		(end 327.477882 -248.856754)
		(width 0.0889)
		(layer "In13.Cu")
		(net "M_B_CPU0_SA_CB<5>")
	)
	(arc
		(start 334.05826 -248.856754)
		(mid 334.341216 -248.780577)
		(end 334.624172 -248.856754)
		(width 0.0889)
		(layer "In13.Cu")
		(net "M_B_CPU0_SA_CB<5>")
	)
	(arc
		(start 332.752446 -248.86158)
		(mid 332.935954 -248.907074)
		(end 333.118206 -248.856754)
		(width 0.0889)
		(layer "In13.Cu")
		(net "M_B_CPU0_SA_CB<5>")
	)
	(arc
		(start 327.477882 -248.856754)
		(mid 327.754949 -248.780483)
		(end 328.033634 -248.850658)
		(width 0.0889)
		(layer "In13.Cu")
		(net "M_B_CPU0_SA_CB<5>")
	)
	(arc
		(start 326.163686 -248.856754)
		(mid 326.340314 -248.906987)
		(end 326.51954 -248.866914)
		(width 0.0889)
		(layer "In13.Cu")
		(net "M_B_CPU0_SA_CB<5>")
	)
	(arc
		(start 325.410068 -248.907046)
		(mid 325.507 -248.894295)
		(end 325.597266 -248.856754)
		(width 0.0889)
		(layer "In13.Cu")
		(net "M_B_CPU0_SA_CB<5>")
	)
	(arc
		(start 329.358244 -248.856754)
		(mid 329.6412 -248.780577)
		(end 329.924156 -248.856754)
		(width 0.0889)
		(layer "In13.Cu")
		(net "M_B_CPU0_SA_CB<5>")
	)
	(arc
		(start 328.044048 -248.856754)
		(mid 328.226299 -248.907104)
		(end 328.409808 -248.86158)
		(width 0.0889)
		(layer "In13.Cu")
		(net "M_B_CPU0_SA_CB<5>")
	)
	(arc
		(start 326.543416 -248.853198)
		(mid 326.823805 -248.780529)
		(end 327.103232 -248.856754)
		(width 0.0889)
		(layer "In13.Cu")
		(net "M_B_CPU0_SA_CB<5>")
	)
	(arc
		(start 335.938114 -248.856754)
		(mid 336.22107 -248.780577)
		(end 336.504026 -248.856754)
		(width 0.0889)
		(layer "In13.Cu")
		(net "M_B_CPU0_SA_CB<5>")
	)
	(arc
		(start 333.6925 -248.86158)
		(mid 333.876008 -248.907074)
		(end 334.05826 -248.856754)
		(width 0.0889)
		(layer "In13.Cu")
		(net "M_B_CPU0_SA_CB<5>")
	)
	(arc
		(start 330.863956 -248.856754)
		(mid 331.046207 -248.907104)
		(end 331.229716 -248.86158)
		(width 0.0889)
		(layer "In13.Cu")
		(net "M_B_CPU0_SA_CB<5>")
	)
	(arc
		(start 328.41819 -248.856754)
		(mid 328.701146 -248.780577)
		(end 328.984102 -248.856754)
		(width 0.0889)
		(layer "In13.Cu")
		(net "M_B_CPU0_SA_CB<5>")
	)
	(arc
		(start 328.992484 -248.86158)
		(mid 329.175992 -248.907074)
		(end 329.358244 -248.856754)
		(width 0.0889)
		(layer "In13.Cu")
		(net "M_B_CPU0_SA_CB<5>")
	)
	(arc
		(start 329.924156 -248.856754)
		(mid 330.1111 -248.907009)
		(end 330.298044 -248.856754)
		(width 0.0889)
		(layer "In13.Cu")
		(net "M_B_CPU0_SA_CB<5>")
	)
	(arc
		(start 335.563972 -248.856754)
		(mid 335.746223 -248.907104)
		(end 335.929732 -248.86158)
		(width 0.0889)
		(layer "In13.Cu")
		(net "M_B_CPU0_SA_CB<5>")
	)
	(arc
		(start 336.504026 -248.856754)
		(mid 336.660464 -248.905725)
		(end 336.822796 -248.882916)
		(width 0.0889)
		(layer "In13.Cu")
		(net "M_B_CPU0_SA_CB<5>")
	)
	(arc
		(start 332.178152 -248.856754)
		(mid 332.461108 -248.780577)
		(end 332.744064 -248.856754)
		(width 0.0889)
		(layer "In13.Cu")
		(net "M_B_CPU0_SA_CB<5>")
	)
	(arc
		(start 331.80401 -248.856754)
		(mid 331.986261 -248.907104)
		(end 332.16977 -248.86158)
		(width 0.0889)
		(layer "In13.Cu")
		(net "M_B_CPU0_SA_CB<5>")
	)
	(arc
		(start 330.298044 -248.856754)
		(mid 330.581 -248.780577)
		(end 330.863956 -248.856754)
		(width 0.0889)
		(layer "In13.Cu")
		(net "M_B_CPU0_SA_CB<5>")
	)
	(arc
		(start 334.624172 -248.856754)
		(mid 334.811116 -248.907009)
		(end 334.99806 -248.856754)
		(width 0.0889)
		(layer "In13.Cu")
		(net "M_B_CPU0_SA_CB<5>")
	)
	(arc
		(start 334.99806 -248.856754)
		(mid 335.281016 -248.780577)
		(end 335.563972 -248.856754)
		(width 0.0889)
		(layer "In13.Cu")
		(net "M_B_CPU0_SA_CB<5>")
	)
	(arc
		(start 331.238098 -248.856754)
		(mid 331.521054 -248.780577)
		(end 331.80401 -248.856754)
		(width 0.0889)
		(layer "In13.Cu")
		(net "M_B_CPU0_SA_CB<5>")
	)
	(arc
		(start 333.118206 -248.856754)
		(mid 333.401162 -248.780577)
		(end 333.684118 -248.856754)
		(width 0.0889)
		(layer "In13.Cu")
		(net "M_B_CPU0_SA_CB<5>")
	)
	(segment
		(start 335.747868 -247.990106)
		(end 335.281016 -247.724168)
		(width 0.10668)
		(layer "F.Cu")
		(net "M_B_CPU0_SA_CB<4>")
	)
	(segment
		(start 301.420784 -240.649506)
		(end 301.420784 -241.365786)
		(width 0.14478)
		(layer "In13.Cu")
		(net "M_B_CPU0_SA_CB<4>")
	)
	(segment
		(start 302.122586 -241.365786)
		(end 302.122586 -240.876836)
		(width 0.14478)
		(layer "In13.Cu")
		(net "M_B_CPU0_SA_CB<4>")
	)
	(segment
		(start 335.435194 -247.989598)
		(end 335.281016 -247.724168)
		(width 0.0889)
		(layer "In13.Cu")
		(net "M_B_CPU0_SA_CB<4>")
	)
	(segment
		(start 303.62144 -240.271808)
		(end 303.88306 -240.271808)
		(width 0.14478)
		(layer "In13.Cu")
		(net "M_B_CPU0_SA_CB<4>")
	)
	(segment
		(start 299.82414 -240.685066)
		(end 299.82414 -240.947194)
		(width 0.14478)
		(layer "In13.Cu")
		(net "M_B_CPU0_SA_CB<4>")
	)
	(segment
		(start 301.977806 -241.510566)
		(end 302.122586 -241.365786)
		(width 0.14478)
		(layer "In13.Cu")
		(net "M_B_CPU0_SA_CB<4>")
	)
	(segment
		(start 305.281076 -241.510566)
		(end 306.590192 -242.819682)
		(width 0.14478)
		(layer "In13.Cu")
		(net "M_B_CPU0_SA_CB<4>")
	)
	(segment
		(start 301.420784 -241.365786)
		(end 301.565564 -241.510566)
		(width 0.14478)
		(layer "In13.Cu")
		(net "M_B_CPU0_SA_CB<4>")
	)
	(segment
		(start 302.122586 -240.876836)
		(end 302.267366 -240.732056)
		(width 0.14478)
		(layer "In13.Cu")
		(net "M_B_CPU0_SA_CB<4>")
	)
	(segment
		(start 300.869604 -240.649506)
		(end 301.014638 -240.504472)
		(width 0.14478)
		(layer "In13.Cu")
		(net "M_B_CPU0_SA_CB<4>")
	)
	(segment
		(start 325.736458 -248.353072)
		(end 325.95312 -248.136156)
		(width 0.0889)
		(layer "In13.Cu")
		(net "M_B_CPU0_SA_CB<4>")
	)
	(segment
		(start 303.47666 -241.337338)
		(end 303.47666 -240.416588)
		(width 0.14478)
		(layer "In13.Cu")
		(net "M_B_CPU0_SA_CB<4>")
	)
	(segment
		(start 323.895974 -248.08307)
		(end 324.285356 -248.08307)
		(width 0.0889)
		(layer "In13.Cu")
		(net "M_B_CPU0_SA_CB<4>")
	)
	(segment
		(start 301.565564 -241.510566)
		(end 301.977806 -241.510566)
		(width 0.14478)
		(layer "In13.Cu")
		(net "M_B_CPU0_SA_CB<4>")
	)
	(segment
		(start 322.807584 -247.78208)
		(end 323.108574 -248.08307)
		(width 0.14478)
		(layer "In13.Cu")
		(net "M_B_CPU0_SA_CB<4>")
	)
	(segment
		(start 300.724824 -241.510566)
		(end 300.869604 -241.365786)
		(width 0.14478)
		(layer "In13.Cu")
		(net "M_B_CPU0_SA_CB<4>")
	)
	(segment
		(start 304.02784 -241.337338)
		(end 304.201068 -241.510566)
		(width 0.14478)
		(layer "In13.Cu")
		(net "M_B_CPU0_SA_CB<4>")
	)
	(segment
		(start 302.673766 -240.876836)
		(end 302.673766 -241.365786)
		(width 0.14478)
		(layer "In13.Cu")
		(net "M_B_CPU0_SA_CB<4>")
	)
	(segment
		(start 301.014638 -240.504472)
		(end 301.27575 -240.504472)
		(width 0.14478)
		(layer "In13.Cu")
		(net "M_B_CPU0_SA_CB<4>")
	)
	(segment
		(start 323.108574 -248.08307)
		(end 323.895974 -248.08307)
		(width 0.14478)
		(layer "In13.Cu")
		(net "M_B_CPU0_SA_CB<4>")
	)
	(segment
		(start 302.818546 -241.510566)
		(end 303.303432 -241.510566)
		(width 0.14478)
		(layer "In13.Cu")
		(net "M_B_CPU0_SA_CB<4>")
	)
	(segment
		(start 303.303432 -241.510566)
		(end 303.47666 -241.337338)
		(width 0.14478)
		(layer "In13.Cu")
		(net "M_B_CPU0_SA_CB<4>")
	)
	(segment
		(start 326.069706 -248.046494)
		(end 326.101456 -248.028206)
		(width 0.0889)
		(layer "In13.Cu")
		(net "M_B_CPU0_SA_CB<4>")
	)
	(segment
		(start 334.519778 -248.051574)
		(end 334.52816 -248.046748)
		(width 0.0889)
		(layer "In13.Cu")
		(net "M_B_CPU0_SA_CB<4>")
	)
	(segment
		(start 330.394056 -248.046748)
		(end 330.402438 -248.051574)
		(width 0.0889)
		(layer "In13.Cu")
		(net "M_B_CPU0_SA_CB<4>")
	)
	(segment
		(start 299.82414 -240.947194)
		(end 300.387512 -241.510566)
		(width 0.14478)
		(layer "In13.Cu")
		(net "M_B_CPU0_SA_CB<4>")
	)
	(segment
		(start 300.869604 -241.365786)
		(end 300.869604 -240.649506)
		(width 0.14478)
		(layer "In13.Cu")
		(net "M_B_CPU0_SA_CB<4>")
	)
	(segment
		(start 335.412842 -248.07291)
		(end 335.435194 -247.989598)
		(width 0.0889)
		(layer "In13.Cu")
		(net "M_B_CPU0_SA_CB<4>")
	)
	(segment
		(start 333.579724 -248.051574)
		(end 333.588106 -248.046748)
		(width 0.0889)
		(layer "In13.Cu")
		(net "M_B_CPU0_SA_CB<4>")
	)
	(segment
		(start 303.88306 -240.271808)
		(end 304.02784 -240.416588)
		(width 0.14478)
		(layer "In13.Cu")
		(net "M_B_CPU0_SA_CB<4>")
	)
	(segment
		(start 331.33411 -248.046748)
		(end 331.342492 -248.051574)
		(width 0.0889)
		(layer "In13.Cu")
		(net "M_B_CPU0_SA_CB<4>")
	)
	(segment
		(start 301.27575 -240.504472)
		(end 301.420784 -240.649506)
		(width 0.14478)
		(layer "In13.Cu")
		(net "M_B_CPU0_SA_CB<4>")
	)
	(segment
		(start 304.201068 -241.510566)
		(end 305.281076 -241.510566)
		(width 0.14478)
		(layer "In13.Cu")
		(net "M_B_CPU0_SA_CB<4>")
	)
	(segment
		(start 306.590192 -242.819682)
		(end 307.554122 -242.819682)
		(width 0.14478)
		(layer "In13.Cu")
		(net "M_B_CPU0_SA_CB<4>")
	)
	(segment
		(start 303.47666 -240.416588)
		(end 303.62144 -240.271808)
		(width 0.14478)
		(layer "In13.Cu")
		(net "M_B_CPU0_SA_CB<4>")
	)
	(segment
		(start 327.55332 -248.034048)
		(end 327.57491 -248.046494)
		(width 0.0889)
		(layer "In13.Cu")
		(net "M_B_CPU0_SA_CB<4>")
	)
	(segment
		(start 326.991726 -248.05767)
		(end 327.010522 -248.046748)
		(width 0.0889)
		(layer "In13.Cu")
		(net "M_B_CPU0_SA_CB<4>")
	)
	(segment
		(start 335.094072 -248.046748)
		(end 335.102454 -248.051574)
		(width 0.0889)
		(layer "In13.Cu")
		(net "M_B_CPU0_SA_CB<4>")
	)
	(segment
		(start 324.285356 -248.08307)
		(end 324.555358 -248.353072)
		(width 0.0889)
		(layer "In13.Cu")
		(net "M_B_CPU0_SA_CB<4>")
	)
	(segment
		(start 324.555358 -248.353072)
		(end 325.736458 -248.353072)
		(width 0.0889)
		(layer "In13.Cu")
		(net "M_B_CPU0_SA_CB<4>")
	)
	(segment
		(start 302.267366 -240.732056)
		(end 302.528986 -240.732056)
		(width 0.14478)
		(layer "In13.Cu")
		(net "M_B_CPU0_SA_CB<4>")
	)
	(segment
		(start 300.387512 -241.510566)
		(end 300.724824 -241.510566)
		(width 0.14478)
		(layer "In13.Cu")
		(net "M_B_CPU0_SA_CB<4>")
	)
	(segment
		(start 302.673766 -241.365786)
		(end 302.818546 -241.510566)
		(width 0.14478)
		(layer "In13.Cu")
		(net "M_B_CPU0_SA_CB<4>")
	)
	(segment
		(start 304.02784 -240.416588)
		(end 304.02784 -241.337338)
		(width 0.14478)
		(layer "In13.Cu")
		(net "M_B_CPU0_SA_CB<4>")
	)
	(segment
		(start 312.51652 -247.78208)
		(end 322.807584 -247.78208)
		(width 0.14478)
		(layer "In13.Cu")
		(net "M_B_CPU0_SA_CB<4>")
	)
	(segment
		(start 307.554122 -242.819682)
		(end 312.51652 -247.78208)
		(width 0.14478)
		(layer "In13.Cu")
		(net "M_B_CPU0_SA_CB<4>")
	)
	(segment
		(start 302.528986 -240.732056)
		(end 302.673766 -240.876836)
		(width 0.14478)
		(layer "In13.Cu")
		(net "M_B_CPU0_SA_CB<4>")
	)
	(segment
		(start 327.57491 -248.046494)
		(end 327.594976 -248.057924)
		(width 0.0889)
		(layer "In13.Cu")
		(net "M_B_CPU0_SA_CB<4>")
	)
	(segment
		(start 329.819762 -248.051574)
		(end 329.828144 -248.046748)
		(width 0.0889)
		(layer "In13.Cu")
		(net "M_B_CPU0_SA_CB<4>")
	)
	(arc
		(start 333.588106 -248.046748)
		(mid 333.871062 -247.970571)
		(end 334.154018 -248.046748)
		(width 0.0889)
		(layer "In13.Cu")
		(net "M_B_CPU0_SA_CB<4>")
	)
	(arc
		(start 326.101456 -248.028206)
		(mid 326.370741 -247.970294)
		(end 326.635364 -248.046748)
		(width 0.0889)
		(layer "In13.Cu")
		(net "M_B_CPU0_SA_CB<4>")
	)
	(arc
		(start 333.213964 -248.046748)
		(mid 333.396215 -248.097098)
		(end 333.579724 -248.051574)
		(width 0.0889)
		(layer "In13.Cu")
		(net "M_B_CPU0_SA_CB<4>")
	)
	(arc
		(start 335.102454 -248.051574)
		(mid 335.255324 -248.096215)
		(end 335.412842 -248.07291)
		(width 0.0889)
		(layer "In13.Cu")
		(net "M_B_CPU0_SA_CB<4>")
	)
	(arc
		(start 328.88809 -248.046748)
		(mid 329.171046 -247.970571)
		(end 329.454002 -248.046748)
		(width 0.0889)
		(layer "In13.Cu")
		(net "M_B_CPU0_SA_CB<4>")
	)
	(arc
		(start 334.52816 -248.046748)
		(mid 334.811116 -247.970571)
		(end 335.094072 -248.046748)
		(width 0.0889)
		(layer "In13.Cu")
		(net "M_B_CPU0_SA_CB<4>")
	)
	(arc
		(start 332.648052 -248.046748)
		(mid 332.931008 -247.970571)
		(end 333.213964 -248.046748)
		(width 0.0889)
		(layer "In13.Cu")
		(net "M_B_CPU0_SA_CB<4>")
	)
	(arc
		(start 331.708252 -248.046748)
		(mid 331.991208 -247.970571)
		(end 332.274164 -248.046748)
		(width 0.0889)
		(layer "In13.Cu")
		(net "M_B_CPU0_SA_CB<4>")
	)
	(arc
		(start 334.154018 -248.046748)
		(mid 334.336269 -248.097098)
		(end 334.519778 -248.051574)
		(width 0.0889)
		(layer "In13.Cu")
		(net "M_B_CPU0_SA_CB<4>")
	)
	(arc
		(start 332.274164 -248.046748)
		(mid 332.461108 -248.097003)
		(end 332.648052 -248.046748)
		(width 0.0889)
		(layer "In13.Cu")
		(net "M_B_CPU0_SA_CB<4>")
	)
	(arc
		(start 328.514202 -248.046748)
		(mid 328.701146 -248.097003)
		(end 328.88809 -248.046748)
		(width 0.0889)
		(layer "In13.Cu")
		(net "M_B_CPU0_SA_CB<4>")
	)
	(arc
		(start 330.768198 -248.046748)
		(mid 331.051154 -247.970571)
		(end 331.33411 -248.046748)
		(width 0.0889)
		(layer "In13.Cu")
		(net "M_B_CPU0_SA_CB<4>")
	)
	(arc
		(start 329.454002 -248.046748)
		(mid 329.636253 -248.097098)
		(end 329.819762 -248.051574)
		(width 0.0889)
		(layer "In13.Cu")
		(net "M_B_CPU0_SA_CB<4>")
	)
	(arc
		(start 327.010522 -248.046748)
		(mid 327.280291 -247.970725)
		(end 327.55332 -248.034048)
		(width 0.0889)
		(layer "In13.Cu")
		(net "M_B_CPU0_SA_CB<4>")
	)
	(arc
		(start 329.828144 -248.046748)
		(mid 330.1111 -247.970571)
		(end 330.394056 -248.046748)
		(width 0.0889)
		(layer "In13.Cu")
		(net "M_B_CPU0_SA_CB<4>")
	)
	(arc
		(start 330.402438 -248.051574)
		(mid 330.585946 -248.097068)
		(end 330.768198 -248.046748)
		(width 0.0889)
		(layer "In13.Cu")
		(net "M_B_CPU0_SA_CB<4>")
	)
	(arc
		(start 326.635364 -248.046748)
		(mid 326.812155 -248.097467)
		(end 326.991726 -248.05767)
		(width 0.0889)
		(layer "In13.Cu")
		(net "M_B_CPU0_SA_CB<4>")
	)
	(arc
		(start 331.342492 -248.051574)
		(mid 331.526 -248.097068)
		(end 331.708252 -248.046748)
		(width 0.0889)
		(layer "In13.Cu")
		(net "M_B_CPU0_SA_CB<4>")
	)
	(arc
		(start 325.95312 -248.136156)
		(mid 326.008469 -248.087497)
		(end 326.069706 -248.046494)
		(width 0.0889)
		(layer "In13.Cu")
		(net "M_B_CPU0_SA_CB<4>")
	)
	(arc
		(start 327.594976 -248.057924)
		(mid 327.773054 -248.096908)
		(end 327.94829 -248.046748)
		(width 0.0889)
		(layer "In13.Cu")
		(net "M_B_CPU0_SA_CB<4>")
	)
	(arc
		(start 327.94829 -248.046748)
		(mid 328.231246 -247.970571)
		(end 328.514202 -248.046748)
		(width 0.0889)
		(layer "In13.Cu")
		(net "M_B_CPU0_SA_CB<4>")
	)
	(segment
		(start 337.627976 -246.370094)
		(end 337.161124 -246.104156)
		(width 0.10668)
		(layer "F.Cu")
		(net "M_B_CPU0_SA_CB<3>")
	)
	(segment
		(start 298.172124 -236.850428)
		(end 299.43425 -236.850428)
		(width 0.14478)
		(layer "In13.Cu")
		(net "M_B_CPU0_SA_CB<3>")
	)
	(segment
		(start 297.73753 -237.285022)
		(end 298.172124 -236.850428)
		(width 0.14478)
		(layer "In13.Cu")
		(net "M_B_CPU0_SA_CB<3>")
	)
	(segment
		(start 314.8711 -245.43258)
		(end 323.810884 -245.43258)
		(width 0.14478)
		(layer "In13.Cu")
		(net "M_B_CPU0_SA_CB<3>")
	)
	(segment
		(start 299.43425 -236.850428)
		(end 300.29404 -237.710218)
		(width 0.14478)
		(layer "In13.Cu")
		(net "M_B_CPU0_SA_CB<3>")
	)
	(segment
		(start 326.617838 -245.790974)
		(end 326.633586 -245.78183)
		(width 0.0889)
		(layer "In13.Cu")
		(net "M_B_CPU0_SA_CB<3>")
	)
	(segment
		(start 324.176898 -245.43258)
		(end 324.475348 -245.73103)
		(width 0.0889)
		(layer "In13.Cu")
		(net "M_B_CPU0_SA_CB<3>")
	)
	(segment
		(start 337.0072 -245.838726)
		(end 337.161124 -246.104156)
		(width 0.0889)
		(layer "In13.Cu")
		(net "M_B_CPU0_SA_CB<3>")
	)
	(segment
		(start 333.579724 -245.77675)
		(end 333.588106 -245.781576)
		(width 0.0889)
		(layer "In13.Cu")
		(net "M_B_CPU0_SA_CB<3>")
	)
	(segment
		(start 327.939908 -245.77675)
		(end 327.94829 -245.781576)
		(width 0.0889)
		(layer "In13.Cu")
		(net "M_B_CPU0_SA_CB<3>")
	)
	(segment
		(start 327.007474 -245.781576)
		(end 327.017888 -245.787672)
		(width 0.0889)
		(layer "In13.Cu")
		(net "M_B_CPU0_SA_CB<3>")
	)
	(segment
		(start 295.724072 -237.285022)
		(end 297.73753 -237.285022)
		(width 0.14478)
		(layer "In13.Cu")
		(net "M_B_CPU0_SA_CB<3>")
	)
	(segment
		(start 300.29404 -237.710218)
		(end 307.148738 -237.710218)
		(width 0.14478)
		(layer "In13.Cu")
		(net "M_B_CPU0_SA_CB<3>")
	)
	(segment
		(start 326.633586 -245.78183)
		(end 326.649842 -245.772432)
		(width 0.0889)
		(layer "In13.Cu")
		(net "M_B_CPU0_SA_CB<3>")
	)
	(segment
		(start 330.394056 -245.781576)
		(end 330.402438 -245.77675)
		(width 0.0889)
		(layer "In13.Cu")
		(net "M_B_CPU0_SA_CB<3>")
	)
	(segment
		(start 329.819762 -245.77675)
		(end 329.828144 -245.781576)
		(width 0.0889)
		(layer "In13.Cu")
		(net "M_B_CPU0_SA_CB<3>")
	)
	(segment
		(start 307.148738 -237.710218)
		(end 314.8711 -245.43258)
		(width 0.14478)
		(layer "In13.Cu")
		(net "M_B_CPU0_SA_CB<3>")
	)
	(segment
		(start 323.810884 -245.43258)
		(end 324.176898 -245.43258)
		(width 0.0889)
		(layer "In13.Cu")
		(net "M_B_CPU0_SA_CB<3>")
	)
	(segment
		(start 331.33411 -245.781576)
		(end 331.342492 -245.77675)
		(width 0.0889)
		(layer "In13.Cu")
		(net "M_B_CPU0_SA_CB<3>")
	)
	(segment
		(start 336.034126 -245.781576)
		(end 336.042508 -245.77675)
		(width 0.0889)
		(layer "In13.Cu")
		(net "M_B_CPU0_SA_CB<3>")
	)
	(segment
		(start 335.094072 -245.781576)
		(end 335.102454 -245.77675)
		(width 0.0889)
		(layer "In13.Cu")
		(net "M_B_CPU0_SA_CB<3>")
	)
	(segment
		(start 324.475348 -245.73103)
		(end 325.880476 -245.73103)
		(width 0.0889)
		(layer "In13.Cu")
		(net "M_B_CPU0_SA_CB<3>")
	)
	(segment
		(start 336.911188 -245.813326)
		(end 337.0072 -245.838726)
		(width 0.0889)
		(layer "In13.Cu")
		(net "M_B_CPU0_SA_CB<3>")
	)
	(segment
		(start 334.519778 -245.77675)
		(end 334.52816 -245.781576)
		(width 0.0889)
		(layer "In13.Cu")
		(net "M_B_CPU0_SA_CB<3>")
	)
	(arc
		(start 333.213964 -245.781576)
		(mid 333.396215 -245.731226)
		(end 333.579724 -245.77675)
		(width 0.0889)
		(layer "In13.Cu")
		(net "M_B_CPU0_SA_CB<3>")
	)
	(arc
		(start 330.402438 -245.77675)
		(mid 330.585946 -245.731256)
		(end 330.768198 -245.781576)
		(width 0.0889)
		(layer "In13.Cu")
		(net "M_B_CPU0_SA_CB<3>")
	)
	(arc
		(start 335.468214 -245.781576)
		(mid 335.75117 -245.857753)
		(end 336.034126 -245.781576)
		(width 0.0889)
		(layer "In13.Cu")
		(net "M_B_CPU0_SA_CB<3>")
	)
	(arc
		(start 331.708252 -245.781576)
		(mid 331.991208 -245.857753)
		(end 332.274164 -245.781576)
		(width 0.0889)
		(layer "In13.Cu")
		(net "M_B_CPU0_SA_CB<3>")
	)
	(arc
		(start 334.52816 -245.781576)
		(mid 334.811116 -245.857753)
		(end 335.094072 -245.781576)
		(width 0.0889)
		(layer "In13.Cu")
		(net "M_B_CPU0_SA_CB<3>")
	)
	(arc
		(start 334.154018 -245.781576)
		(mid 334.336269 -245.731226)
		(end 334.519778 -245.77675)
		(width 0.0889)
		(layer "In13.Cu")
		(net "M_B_CPU0_SA_CB<3>")
	)
	(arc
		(start 327.94829 -245.781576)
		(mid 328.231246 -245.857753)
		(end 328.514202 -245.781576)
		(width 0.0889)
		(layer "In13.Cu")
		(net "M_B_CPU0_SA_CB<3>")
	)
	(arc
		(start 326.649842 -245.772432)
		(mid 326.829824 -245.731332)
		(end 327.007474 -245.781576)
		(width 0.0889)
		(layer "In13.Cu")
		(net "M_B_CPU0_SA_CB<3>")
	)
	(arc
		(start 327.017888 -245.787672)
		(mid 327.296574 -245.857892)
		(end 327.57364 -245.781576)
		(width 0.0889)
		(layer "In13.Cu")
		(net "M_B_CPU0_SA_CB<3>")
	)
	(arc
		(start 329.828144 -245.781576)
		(mid 330.1111 -245.857753)
		(end 330.394056 -245.781576)
		(width 0.0889)
		(layer "In13.Cu")
		(net "M_B_CPU0_SA_CB<3>")
	)
	(arc
		(start 331.342492 -245.77675)
		(mid 331.526 -245.731256)
		(end 331.708252 -245.781576)
		(width 0.0889)
		(layer "In13.Cu")
		(net "M_B_CPU0_SA_CB<3>")
	)
	(arc
		(start 335.102454 -245.77675)
		(mid 335.285962 -245.731256)
		(end 335.468214 -245.781576)
		(width 0.0889)
		(layer "In13.Cu")
		(net "M_B_CPU0_SA_CB<3>")
	)
	(arc
		(start 329.454002 -245.781576)
		(mid 329.636253 -245.731226)
		(end 329.819762 -245.77675)
		(width 0.0889)
		(layer "In13.Cu")
		(net "M_B_CPU0_SA_CB<3>")
	)
	(arc
		(start 326.067674 -245.781576)
		(mid 326.341529 -245.857926)
		(end 326.617838 -245.790974)
		(width 0.0889)
		(layer "In13.Cu")
		(net "M_B_CPU0_SA_CB<3>")
	)
	(arc
		(start 328.88809 -245.781576)
		(mid 329.171046 -245.857753)
		(end 329.454002 -245.781576)
		(width 0.0889)
		(layer "In13.Cu")
		(net "M_B_CPU0_SA_CB<3>")
	)
	(arc
		(start 333.588106 -245.781576)
		(mid 333.871062 -245.857753)
		(end 334.154018 -245.781576)
		(width 0.0889)
		(layer "In13.Cu")
		(net "M_B_CPU0_SA_CB<3>")
	)
	(arc
		(start 327.57364 -245.781576)
		(mid 327.756145 -245.731099)
		(end 327.939908 -245.77675)
		(width 0.0889)
		(layer "In13.Cu")
		(net "M_B_CPU0_SA_CB<3>")
	)
	(arc
		(start 328.514202 -245.781576)
		(mid 328.701146 -245.731321)
		(end 328.88809 -245.781576)
		(width 0.0889)
		(layer "In13.Cu")
		(net "M_B_CPU0_SA_CB<3>")
	)
	(arc
		(start 325.880476 -245.73103)
		(mid 325.977427 -245.743905)
		(end 326.067674 -245.781576)
		(width 0.0889)
		(layer "In13.Cu")
		(net "M_B_CPU0_SA_CB<3>")
	)
	(arc
		(start 336.042508 -245.77675)
		(mid 336.226016 -245.731256)
		(end 336.408268 -245.781576)
		(width 0.0889)
		(layer "In13.Cu")
		(net "M_B_CPU0_SA_CB<3>")
	)
	(arc
		(start 330.768198 -245.781576)
		(mid 331.051154 -245.857753)
		(end 331.33411 -245.781576)
		(width 0.0889)
		(layer "In13.Cu")
		(net "M_B_CPU0_SA_CB<3>")
	)
	(arc
		(start 336.408268 -245.781576)
		(mid 336.655981 -245.856796)
		(end 336.911188 -245.813326)
		(width 0.0889)
		(layer "In13.Cu")
		(net "M_B_CPU0_SA_CB<3>")
	)
	(arc
		(start 332.648052 -245.781576)
		(mid 332.931008 -245.857753)
		(end 333.213964 -245.781576)
		(width 0.0889)
		(layer "In13.Cu")
		(net "M_B_CPU0_SA_CB<3>")
	)
	(arc
		(start 332.274164 -245.781576)
		(mid 332.461108 -245.731321)
		(end 332.648052 -245.781576)
		(width 0.0889)
		(layer "In13.Cu")
		(net "M_B_CPU0_SA_CB<3>")
	)
	(segment
		(start 336.218022 -245.560088)
		(end 335.75117 -245.29415)
		(width 0.10668)
		(layer "F.Cu")
		(net "M_B_CPU0_SA_CB<2>")
	)
	(segment
		(start 331.238098 -244.97157)
		(end 331.229716 -244.966744)
		(width 0.0889)
		(layer "In13.Cu")
		(net "M_B_CPU0_SA_CB<2>")
	)
	(segment
		(start 328.41819 -244.97157)
		(end 328.409808 -244.966744)
		(width 0.0889)
		(layer "In13.Cu")
		(net "M_B_CPU0_SA_CB<2>")
	)
	(segment
		(start 333.6925 -244.966744)
		(end 333.684118 -244.97157)
		(width 0.0889)
		(layer "In13.Cu")
		(net "M_B_CPU0_SA_CB<2>")
	)
	(segment
		(start 298.162472 -235.160058)
		(end 297.73753 -235.585)
		(width 0.14478)
		(layer "In13.Cu")
		(net "M_B_CPU0_SA_CB<2>")
	)
	(segment
		(start 307.835554 -236.812328)
		(end 307.980588 -236.667294)
		(width 0.14478)
		(layer "In13.Cu")
		(net "M_B_CPU0_SA_CB<2>")
	)
	(segment
		(start 306.804568 -236.010196)
		(end 300.884336 -236.010196)
		(width 0.14478)
		(layer "In13.Cu")
		(net "M_B_CPU0_SA_CB<2>")
	)
	(segment
		(start 307.81879 -236.277404)
		(end 307.590444 -236.277404)
		(width 0.14478)
		(layer "In13.Cu")
		(net "M_B_CPU0_SA_CB<2>")
	)
	(segment
		(start 327.47966 -244.971824)
		(end 327.461372 -244.96141)
		(width 0.0889)
		(layer "In13.Cu")
		(net "M_B_CPU0_SA_CB<2>")
	)
	(segment
		(start 297.73753 -235.585)
		(end 295.724072 -235.585)
		(width 0.14478)
		(layer "In13.Cu")
		(net "M_B_CPU0_SA_CB<2>")
	)
	(segment
		(start 307.980588 -236.439202)
		(end 307.81879 -236.277404)
		(width 0.14478)
		(layer "In13.Cu")
		(net "M_B_CPU0_SA_CB<2>")
	)
	(segment
		(start 307.590444 -236.277404)
		(end 307.44541 -236.422438)
		(width 0.14478)
		(layer "In13.Cu")
		(net "M_B_CPU0_SA_CB<2>")
	)
	(segment
		(start 335.75117 -245.29415)
		(end 335.596992 -245.02872)
		(width 0.0889)
		(layer "In13.Cu")
		(net "M_B_CPU0_SA_CB<2>")
	)
	(segment
		(start 332.752446 -244.966744)
		(end 332.744064 -244.97157)
		(width 0.0889)
		(layer "In13.Cu")
		(net "M_B_CPU0_SA_CB<2>")
	)
	(segment
		(start 307.21681 -236.422438)
		(end 306.804568 -236.010196)
		(width 0.14478)
		(layer "In13.Cu")
		(net "M_B_CPU0_SA_CB<2>")
	)
	(segment
		(start 327.106534 -244.97157)
		(end 327.083166 -244.985286)
		(width 0.0889)
		(layer "In13.Cu")
		(net "M_B_CPU0_SA_CB<2>")
	)
	(segment
		(start 324.138544 -244.53342)
		(end 315.327792 -244.53342)
		(width 0.14478)
		(layer "In13.Cu")
		(net "M_B_CPU0_SA_CB<2>")
	)
	(segment
		(start 300.884336 -236.010196)
		(end 300.034198 -235.160058)
		(width 0.14478)
		(layer "In13.Cu")
		(net "M_B_CPU0_SA_CB<2>")
	)
	(segment
		(start 300.034198 -235.160058)
		(end 298.162472 -235.160058)
		(width 0.14478)
		(layer "In13.Cu")
		(net "M_B_CPU0_SA_CB<2>")
	)
	(segment
		(start 315.327792 -244.53342)
		(end 307.835554 -237.041182)
		(width 0.14478)
		(layer "In13.Cu")
		(net "M_B_CPU0_SA_CB<2>")
	)
	(segment
		(start 327.50125 -244.98427)
		(end 327.47966 -244.971824)
		(width 0.0889)
		(layer "In13.Cu")
		(net "M_B_CPU0_SA_CB<2>")
	)
	(segment
		(start 307.835554 -237.041182)
		(end 307.835554 -236.812328)
		(width 0.14478)
		(layer "In13.Cu")
		(net "M_B_CPU0_SA_CB<2>")
	)
	(segment
		(start 325.504302 -244.920516)
		(end 324.961758 -244.377972)
		(width 0.0889)
		(layer "In13.Cu")
		(net "M_B_CPU0_SA_CB<2>")
	)
	(segment
		(start 328.992484 -244.966744)
		(end 328.984102 -244.97157)
		(width 0.0889)
		(layer "In13.Cu")
		(net "M_B_CPU0_SA_CB<2>")
	)
	(segment
		(start 326.351138 -244.920516)
		(end 325.504302 -244.920516)
		(width 0.0889)
		(layer "In13.Cu")
		(net "M_B_CPU0_SA_CB<2>")
	)
	(segment
		(start 332.178152 -244.97157)
		(end 332.16977 -244.966744)
		(width 0.0889)
		(layer "In13.Cu")
		(net "M_B_CPU0_SA_CB<2>")
	)
	(segment
		(start 307.980588 -236.667294)
		(end 307.980588 -236.439202)
		(width 0.14478)
		(layer "In13.Cu")
		(net "M_B_CPU0_SA_CB<2>")
	)
	(segment
		(start 307.44541 -236.422438)
		(end 307.21681 -236.422438)
		(width 0.14478)
		(layer "In13.Cu")
		(net "M_B_CPU0_SA_CB<2>")
	)
	(segment
		(start 324.961758 -244.377972)
		(end 324.293992 -244.377972)
		(width 0.0889)
		(layer "In13.Cu")
		(net "M_B_CPU0_SA_CB<2>")
	)
	(segment
		(start 324.293992 -244.377972)
		(end 324.138544 -244.53342)
		(width 0.0889)
		(layer "In13.Cu")
		(net "M_B_CPU0_SA_CB<2>")
	)
	(segment
		(start 335.596992 -245.02872)
		(end 335.500726 -245.00332)
		(width 0.0889)
		(layer "In13.Cu")
		(net "M_B_CPU0_SA_CB<2>")
	)
	(arc
		(start 332.16977 -244.966744)
		(mid 331.986262 -244.92125)
		(end 331.80401 -244.97157)
		(width 0.0889)
		(layer "In13.Cu")
		(net "M_B_CPU0_SA_CB<2>")
	)
	(arc
		(start 329.924156 -244.97157)
		(mid 329.6412 -245.047747)
		(end 329.358244 -244.97157)
		(width 0.0889)
		(layer "In13.Cu")
		(net "M_B_CPU0_SA_CB<2>")
	)
	(arc
		(start 331.229716 -244.966744)
		(mid 331.046208 -244.92125)
		(end 330.863956 -244.97157)
		(width 0.0889)
		(layer "In13.Cu")
		(net "M_B_CPU0_SA_CB<2>")
	)
	(arc
		(start 331.80401 -244.97157)
		(mid 331.521054 -245.047747)
		(end 331.238098 -244.97157)
		(width 0.0889)
		(layer "In13.Cu")
		(net "M_B_CPU0_SA_CB<2>")
	)
	(arc
		(start 334.624172 -244.97157)
		(mid 334.341216 -245.047747)
		(end 334.05826 -244.97157)
		(width 0.0889)
		(layer "In13.Cu")
		(net "M_B_CPU0_SA_CB<2>")
	)
	(arc
		(start 330.298044 -244.97157)
		(mid 330.1111 -244.921315)
		(end 329.924156 -244.97157)
		(width 0.0889)
		(layer "In13.Cu")
		(net "M_B_CPU0_SA_CB<2>")
	)
	(arc
		(start 328.409808 -244.966744)
		(mid 328.2263 -244.92125)
		(end 328.044048 -244.97157)
		(width 0.0889)
		(layer "In13.Cu")
		(net "M_B_CPU0_SA_CB<2>")
	)
	(arc
		(start 326.539352 -244.97157)
		(mid 326.448633 -244.933563)
		(end 326.351138 -244.920516)
		(width 0.0889)
		(layer "In13.Cu")
		(net "M_B_CPU0_SA_CB<2>")
	)
	(arc
		(start 329.358244 -244.97157)
		(mid 329.175993 -244.92122)
		(end 328.992484 -244.966744)
		(width 0.0889)
		(layer "In13.Cu")
		(net "M_B_CPU0_SA_CB<2>")
	)
	(arc
		(start 328.044048 -244.97157)
		(mid 327.774279 -245.047593)
		(end 327.50125 -244.98427)
		(width 0.0889)
		(layer "In13.Cu")
		(net "M_B_CPU0_SA_CB<2>")
	)
	(arc
		(start 330.863956 -244.97157)
		(mid 330.581 -245.047747)
		(end 330.298044 -244.97157)
		(width 0.0889)
		(layer "In13.Cu")
		(net "M_B_CPU0_SA_CB<2>")
	)
	(arc
		(start 332.744064 -244.97157)
		(mid 332.461108 -245.047747)
		(end 332.178152 -244.97157)
		(width 0.0889)
		(layer "In13.Cu")
		(net "M_B_CPU0_SA_CB<2>")
	)
	(arc
		(start 333.684118 -244.97157)
		(mid 333.401162 -245.047747)
		(end 333.118206 -244.97157)
		(width 0.0889)
		(layer "In13.Cu")
		(net "M_B_CPU0_SA_CB<2>")
	)
	(arc
		(start 335.500726 -245.00332)
		(mid 335.245661 -245.046671)
		(end 334.99806 -244.97157)
		(width 0.0889)
		(layer "In13.Cu")
		(net "M_B_CPU0_SA_CB<2>")
	)
	(arc
		(start 334.05826 -244.97157)
		(mid 333.876009 -244.92122)
		(end 333.6925 -244.966744)
		(width 0.0889)
		(layer "In13.Cu")
		(net "M_B_CPU0_SA_CB<2>")
	)
	(arc
		(start 328.984102 -244.97157)
		(mid 328.701146 -245.047747)
		(end 328.41819 -244.97157)
		(width 0.0889)
		(layer "In13.Cu")
		(net "M_B_CPU0_SA_CB<2>")
	)
	(arc
		(start 334.99806 -244.97157)
		(mid 334.811116 -244.921315)
		(end 334.624172 -244.97157)
		(width 0.0889)
		(layer "In13.Cu")
		(net "M_B_CPU0_SA_CB<2>")
	)
	(arc
		(start 333.118206 -244.97157)
		(mid 332.935955 -244.92122)
		(end 332.752446 -244.966744)
		(width 0.0889)
		(layer "In13.Cu")
		(net "M_B_CPU0_SA_CB<2>")
	)
	(arc
		(start 327.083166 -244.985286)
		(mid 326.809512 -245.048229)
		(end 326.539352 -244.97157)
		(width 0.0889)
		(layer "In13.Cu")
		(net "M_B_CPU0_SA_CB<2>")
	)
	(arc
		(start 327.461372 -244.96141)
		(mid 327.282651 -244.921487)
		(end 327.106534 -244.97157)
		(width 0.0889)
		(layer "In13.Cu")
		(net "M_B_CPU0_SA_CB<2>")
	)
	(segment
		(start 337.158076 -245.560088)
		(end 336.691224 -245.29415)
		(width 0.10668)
		(layer "F.Cu")
		(net "M_B_CPU0_SA_CB<1>")
	)
	(segment
		(start 333.6925 -245.621556)
		(end 333.684118 -245.61673)
		(width 0.0889)
		(layer "In13.Cu")
		(net "M_B_CPU0_SA_CB<1>")
	)
	(segment
		(start 302.295306 -236.605318)
		(end 302.150526 -236.750098)
		(width 0.14478)
		(layer "In13.Cu")
		(net "M_B_CPU0_SA_CB<1>")
	)
	(segment
		(start 302.846486 -237.25251)
		(end 302.701706 -237.10773)
		(width 0.14478)
		(layer "In13.Cu")
		(net "M_B_CPU0_SA_CB<1>")
	)
	(segment
		(start 304.500026 -236.605318)
		(end 304.355246 -236.750098)
		(width 0.14478)
		(layer "In13.Cu")
		(net "M_B_CPU0_SA_CB<1>")
	)
	(segment
		(start 301.048166 -236.750098)
		(end 301.048166 -237.10773)
		(width 0.14478)
		(layer "In13.Cu")
		(net "M_B_CPU0_SA_CB<1>")
	)
	(segment
		(start 328.992484 -245.621556)
		(end 328.984102 -245.61673)
		(width 0.0889)
		(layer "In13.Cu")
		(net "M_B_CPU0_SA_CB<1>")
	)
	(segment
		(start 324.569836 -245.373652)
		(end 324.179184 -244.983)
		(width 0.0889)
		(layer "In13.Cu")
		(net "M_B_CPU0_SA_CB<1>")
	)
	(segment
		(start 328.044048 -245.61673)
		(end 328.033634 -245.610634)
		(width 0.0889)
		(layer "In13.Cu")
		(net "M_B_CPU0_SA_CB<1>")
	)
	(segment
		(start 301.599346 -237.10773)
		(end 301.599346 -236.750098)
		(width 0.14478)
		(layer "In13.Cu")
		(net "M_B_CPU0_SA_CB<1>")
	)
	(segment
		(start 332.178152 -245.61673)
		(end 332.16977 -245.621556)
		(width 0.0889)
		(layer "In13.Cu")
		(net "M_B_CPU0_SA_CB<1>")
	)
	(segment
		(start 332.752446 -245.621556)
		(end 332.744064 -245.61673)
		(width 0.0889)
		(layer "In13.Cu")
		(net "M_B_CPU0_SA_CB<1>")
	)
	(segment
		(start 300.903386 -237.25251)
		(end 300.49978 -237.25251)
		(width 0.14478)
		(layer "In13.Cu")
		(net "M_B_CPU0_SA_CB<1>")
	)
	(segment
		(start 327.111614 -245.621556)
		(end 327.103232 -245.61673)
		(width 0.0889)
		(layer "In13.Cu")
		(net "M_B_CPU0_SA_CB<1>")
	)
	(segment
		(start 303.108106 -237.25251)
		(end 302.846486 -237.25251)
		(width 0.14478)
		(layer "In13.Cu")
		(net "M_B_CPU0_SA_CB<1>")
	)
	(segment
		(start 325.880476 -245.54053)
		(end 325.645272 -245.54053)
		(width 0.0889)
		(layer "In13.Cu")
		(net "M_B_CPU0_SA_CB<1>")
	)
	(segment
		(start 325.478394 -245.373652)
		(end 324.569836 -245.373652)
		(width 0.0889)
		(layer "In13.Cu")
		(net "M_B_CPU0_SA_CB<1>")
	)
	(segment
		(start 305.758342 -236.86008)
		(end 305.365912 -237.25251)
		(width 0.14478)
		(layer "In13.Cu")
		(net "M_B_CPU0_SA_CB<1>")
	)
	(segment
		(start 301.048166 -237.10773)
		(end 300.903386 -237.25251)
		(width 0.14478)
		(layer "In13.Cu")
		(net "M_B_CPU0_SA_CB<1>")
	)
	(segment
		(start 328.41819 -245.61673)
		(end 328.409808 -245.621556)
		(width 0.0889)
		(layer "In13.Cu")
		(net "M_B_CPU0_SA_CB<1>")
	)
	(segment
		(start 301.454566 -236.605318)
		(end 301.192946 -236.605318)
		(width 0.14478)
		(layer "In13.Cu")
		(net "M_B_CPU0_SA_CB<1>")
	)
	(segment
		(start 306.940712 -236.86008)
		(end 305.758342 -236.86008)
		(width 0.14478)
		(layer "In13.Cu")
		(net "M_B_CPU0_SA_CB<1>")
	)
	(segment
		(start 303.804066 -237.10773)
		(end 303.804066 -237.002828)
		(width 0.14478)
		(layer "In13.Cu")
		(net "M_B_CPU0_SA_CB<1>")
	)
	(segment
		(start 301.192946 -236.605318)
		(end 301.048166 -236.750098)
		(width 0.14478)
		(layer "In13.Cu")
		(net "M_B_CPU0_SA_CB<1>")
	)
	(segment
		(start 303.397666 -236.858048)
		(end 303.252886 -237.002828)
		(width 0.14478)
		(layer "In13.Cu")
		(net "M_B_CPU0_SA_CB<1>")
	)
	(segment
		(start 326.537828 -245.616476)
		(end 326.51954 -245.62689)
		(width 0.0889)
		(layer "In13.Cu")
		(net "M_B_CPU0_SA_CB<1>")
	)
	(segment
		(start 302.701706 -237.10773)
		(end 302.701706 -236.750098)
		(width 0.14478)
		(layer "In13.Cu")
		(net "M_B_CPU0_SA_CB<1>")
	)
	(segment
		(start 302.701706 -236.750098)
		(end 302.556926 -236.605318)
		(width 0.14478)
		(layer "In13.Cu")
		(net "M_B_CPU0_SA_CB<1>")
	)
	(segment
		(start 324.179184 -244.983)
		(end 315.063632 -244.983)
		(width 0.14478)
		(layer "In13.Cu")
		(net "M_B_CPU0_SA_CB<1>")
	)
	(segment
		(start 335.938114 -245.61673)
		(end 335.929732 -245.621556)
		(width 0.0889)
		(layer "In13.Cu")
		(net "M_B_CPU0_SA_CB<1>")
	)
	(segment
		(start 303.252886 -237.10773)
		(end 303.108106 -237.25251)
		(width 0.14478)
		(layer "In13.Cu")
		(net "M_B_CPU0_SA_CB<1>")
	)
	(segment
		(start 303.252886 -237.002828)
		(end 303.252886 -237.10773)
		(width 0.14478)
		(layer "In13.Cu")
		(net "M_B_CPU0_SA_CB<1>")
	)
	(segment
		(start 301.744126 -237.25251)
		(end 301.599346 -237.10773)
		(width 0.14478)
		(layer "In13.Cu")
		(net "M_B_CPU0_SA_CB<1>")
	)
	(segment
		(start 299.82414 -236.57687)
		(end 299.82414 -236.435138)
		(width 0.14478)
		(layer "In13.Cu")
		(net "M_B_CPU0_SA_CB<1>")
	)
	(segment
		(start 301.599346 -236.750098)
		(end 301.454566 -236.605318)
		(width 0.14478)
		(layer "In13.Cu")
		(net "M_B_CPU0_SA_CB<1>")
	)
	(segment
		(start 315.063632 -244.983)
		(end 306.940712 -236.86008)
		(width 0.14478)
		(layer "In13.Cu")
		(net "M_B_CPU0_SA_CB<1>")
	)
	(segment
		(start 302.150526 -236.750098)
		(end 302.150526 -237.10773)
		(width 0.14478)
		(layer "In13.Cu")
		(net "M_B_CPU0_SA_CB<1>")
	)
	(segment
		(start 336.691224 -245.29415)
		(end 336.845148 -245.55958)
		(width 0.0889)
		(layer "In13.Cu")
		(net "M_B_CPU0_SA_CB<1>")
	)
	(segment
		(start 303.948846 -237.25251)
		(end 303.804066 -237.10773)
		(width 0.14478)
		(layer "In13.Cu")
		(net "M_B_CPU0_SA_CB<1>")
	)
	(segment
		(start 326.543416 -245.613174)
		(end 326.537828 -245.616476)
		(width 0.0889)
		(layer "In13.Cu")
		(net "M_B_CPU0_SA_CB<1>")
	)
	(segment
		(start 304.210466 -237.25251)
		(end 303.948846 -237.25251)
		(width 0.14478)
		(layer "In13.Cu")
		(net "M_B_CPU0_SA_CB<1>")
	)
	(segment
		(start 331.238098 -245.61673)
		(end 331.229716 -245.621556)
		(width 0.0889)
		(layer "In13.Cu")
		(net "M_B_CPU0_SA_CB<1>")
	)
	(segment
		(start 302.150526 -237.10773)
		(end 302.005746 -237.25251)
		(width 0.14478)
		(layer "In13.Cu")
		(net "M_B_CPU0_SA_CB<1>")
	)
	(segment
		(start 302.556926 -236.605318)
		(end 302.295306 -236.605318)
		(width 0.14478)
		(layer "In13.Cu")
		(net "M_B_CPU0_SA_CB<1>")
	)
	(segment
		(start 304.355246 -236.750098)
		(end 304.355246 -237.10773)
		(width 0.14478)
		(layer "In13.Cu")
		(net "M_B_CPU0_SA_CB<1>")
	)
	(segment
		(start 303.659286 -236.858048)
		(end 303.397666 -236.858048)
		(width 0.14478)
		(layer "In13.Cu")
		(net "M_B_CPU0_SA_CB<1>")
	)
	(segment
		(start 336.845148 -245.55958)
		(end 336.822796 -245.642892)
		(width 0.0889)
		(layer "In13.Cu")
		(net "M_B_CPU0_SA_CB<1>")
	)
	(segment
		(start 304.355246 -237.10773)
		(end 304.210466 -237.25251)
		(width 0.14478)
		(layer "In13.Cu")
		(net "M_B_CPU0_SA_CB<1>")
	)
	(segment
		(start 304.906426 -237.10773)
		(end 304.906426 -236.750098)
		(width 0.14478)
		(layer "In13.Cu")
		(net "M_B_CPU0_SA_CB<1>")
	)
	(segment
		(start 304.761646 -236.605318)
		(end 304.500026 -236.605318)
		(width 0.14478)
		(layer "In13.Cu")
		(net "M_B_CPU0_SA_CB<1>")
	)
	(segment
		(start 302.005746 -237.25251)
		(end 301.744126 -237.25251)
		(width 0.14478)
		(layer "In13.Cu")
		(net "M_B_CPU0_SA_CB<1>")
	)
	(segment
		(start 325.645272 -245.54053)
		(end 325.478394 -245.373652)
		(width 0.0889)
		(layer "In13.Cu")
		(net "M_B_CPU0_SA_CB<1>")
	)
	(segment
		(start 300.49978 -237.25251)
		(end 299.82414 -236.57687)
		(width 0.14478)
		(layer "In13.Cu")
		(net "M_B_CPU0_SA_CB<1>")
	)
	(segment
		(start 303.804066 -237.002828)
		(end 303.659286 -236.858048)
		(width 0.14478)
		(layer "In13.Cu")
		(net "M_B_CPU0_SA_CB<1>")
	)
	(segment
		(start 304.906426 -236.750098)
		(end 304.761646 -236.605318)
		(width 0.14478)
		(layer "In13.Cu")
		(net "M_B_CPU0_SA_CB<1>")
	)
	(segment
		(start 305.365912 -237.25251)
		(end 305.051206 -237.25251)
		(width 0.14478)
		(layer "In13.Cu")
		(net "M_B_CPU0_SA_CB<1>")
	)
	(segment
		(start 305.051206 -237.25251)
		(end 304.906426 -237.10773)
		(width 0.14478)
		(layer "In13.Cu")
		(net "M_B_CPU0_SA_CB<1>")
	)
	(arc
		(start 336.822796 -245.642892)
		(mid 336.660464 -245.66571)
		(end 336.504026 -245.61673)
		(width 0.0889)
		(layer "In13.Cu")
		(net "M_B_CPU0_SA_CB<1>")
	)
	(arc
		(start 335.929732 -245.621556)
		(mid 335.746224 -245.66705)
		(end 335.563972 -245.61673)
		(width 0.0889)
		(layer "In13.Cu")
		(net "M_B_CPU0_SA_CB<1>")
	)
	(arc
		(start 328.033634 -245.610634)
		(mid 327.754948 -245.540414)
		(end 327.477882 -245.61673)
		(width 0.0889)
		(layer "In13.Cu")
		(net "M_B_CPU0_SA_CB<1>")
	)
	(arc
		(start 332.16977 -245.621556)
		(mid 331.986262 -245.66705)
		(end 331.80401 -245.61673)
		(width 0.0889)
		(layer "In13.Cu")
		(net "M_B_CPU0_SA_CB<1>")
	)
	(arc
		(start 326.51954 -245.62689)
		(mid 326.340311 -245.667043)
		(end 326.163686 -245.61673)
		(width 0.0889)
		(layer "In13.Cu")
		(net "M_B_CPU0_SA_CB<1>")
	)
	(arc
		(start 330.863956 -245.61673)
		(mid 330.581 -245.540553)
		(end 330.298044 -245.61673)
		(width 0.0889)
		(layer "In13.Cu")
		(net "M_B_CPU0_SA_CB<1>")
	)
	(arc
		(start 328.984102 -245.61673)
		(mid 328.701146 -245.540553)
		(end 328.41819 -245.61673)
		(width 0.0889)
		(layer "In13.Cu")
		(net "M_B_CPU0_SA_CB<1>")
	)
	(arc
		(start 331.229716 -245.621556)
		(mid 331.046208 -245.66705)
		(end 330.863956 -245.61673)
		(width 0.0889)
		(layer "In13.Cu")
		(net "M_B_CPU0_SA_CB<1>")
	)
	(arc
		(start 330.298044 -245.61673)
		(mid 330.1111 -245.666985)
		(end 329.924156 -245.61673)
		(width 0.0889)
		(layer "In13.Cu")
		(net "M_B_CPU0_SA_CB<1>")
	)
	(arc
		(start 333.118206 -245.61673)
		(mid 332.935955 -245.66708)
		(end 332.752446 -245.621556)
		(width 0.0889)
		(layer "In13.Cu")
		(net "M_B_CPU0_SA_CB<1>")
	)
	(arc
		(start 332.744064 -245.61673)
		(mid 332.461108 -245.540553)
		(end 332.178152 -245.61673)
		(width 0.0889)
		(layer "In13.Cu")
		(net "M_B_CPU0_SA_CB<1>")
	)
	(arc
		(start 335.563972 -245.61673)
		(mid 335.281016 -245.540553)
		(end 334.99806 -245.61673)
		(width 0.0889)
		(layer "In13.Cu")
		(net "M_B_CPU0_SA_CB<1>")
	)
	(arc
		(start 327.103232 -245.61673)
		(mid 326.823804 -245.540564)
		(end 326.543416 -245.613174)
		(width 0.0889)
		(layer "In13.Cu")
		(net "M_B_CPU0_SA_CB<1>")
	)
	(arc
		(start 334.99806 -245.61673)
		(mid 334.811116 -245.666985)
		(end 334.624172 -245.61673)
		(width 0.0889)
		(layer "In13.Cu")
		(net "M_B_CPU0_SA_CB<1>")
	)
	(arc
		(start 336.504026 -245.61673)
		(mid 336.22107 -245.540553)
		(end 335.938114 -245.61673)
		(width 0.0889)
		(layer "In13.Cu")
		(net "M_B_CPU0_SA_CB<1>")
	)
	(arc
		(start 329.358244 -245.61673)
		(mid 329.175993 -245.66708)
		(end 328.992484 -245.621556)
		(width 0.0889)
		(layer "In13.Cu")
		(net "M_B_CPU0_SA_CB<1>")
	)
	(arc
		(start 327.477882 -245.61673)
		(mid 327.295377 -245.667207)
		(end 327.111614 -245.621556)
		(width 0.0889)
		(layer "In13.Cu")
		(net "M_B_CPU0_SA_CB<1>")
	)
	(arc
		(start 334.05826 -245.61673)
		(mid 333.876009 -245.66708)
		(end 333.6925 -245.621556)
		(width 0.0889)
		(layer "In13.Cu")
		(net "M_B_CPU0_SA_CB<1>")
	)
	(arc
		(start 333.684118 -245.61673)
		(mid 333.401162 -245.540553)
		(end 333.118206 -245.61673)
		(width 0.0889)
		(layer "In13.Cu")
		(net "M_B_CPU0_SA_CB<1>")
	)
	(arc
		(start 331.80401 -245.61673)
		(mid 331.521054 -245.540553)
		(end 331.238098 -245.61673)
		(width 0.0889)
		(layer "In13.Cu")
		(net "M_B_CPU0_SA_CB<1>")
	)
	(arc
		(start 329.924156 -245.61673)
		(mid 329.6412 -245.540553)
		(end 329.358244 -245.61673)
		(width 0.0889)
		(layer "In13.Cu")
		(net "M_B_CPU0_SA_CB<1>")
	)
	(arc
		(start 326.163686 -245.61673)
		(mid 326.027118 -245.559923)
		(end 325.880476 -245.54053)
		(width 0.0889)
		(layer "In13.Cu")
		(net "M_B_CPU0_SA_CB<1>")
	)
	(arc
		(start 328.409808 -245.621556)
		(mid 328.2263 -245.66705)
		(end 328.044048 -245.61673)
		(width 0.0889)
		(layer "In13.Cu")
		(net "M_B_CPU0_SA_CB<1>")
	)
	(arc
		(start 334.624172 -245.61673)
		(mid 334.341216 -245.540553)
		(end 334.05826 -245.61673)
		(width 0.0889)
		(layer "In13.Cu")
		(net "M_B_CPU0_SA_CB<1>")
	)
	(segment
		(start 335.747868 -244.750082)
		(end 335.281016 -244.484144)
		(width 0.10668)
		(layer "F.Cu")
		(net "M_B_CPU0_SA_CB<0>")
	)
	(segment
		(start 310.167274 -238.275368)
		(end 310.310784 -238.131604)
		(width 0.14478)
		(layer "In13.Cu")
		(net "M_B_CPU0_SA_CB<0>")
	)
	(segment
		(start 310.700928 -238.521748)
		(end 310.557418 -238.665258)
		(width 0.14478)
		(layer "In13.Cu")
		(net "M_B_CPU0_SA_CB<0>")
	)
	(segment
		(start 301.563786 -235.288074)
		(end 301.691802 -235.160058)
		(width 0.14478)
		(layer "In13.Cu")
		(net "M_B_CPU0_SA_CB<0>")
	)
	(segment
		(start 302.643794 -235.549948)
		(end 302.905414 -235.549948)
		(width 0.14478)
		(layer "In13.Cu")
		(net "M_B_CPU0_SA_CB<0>")
	)
	(segment
		(start 327.57491 -244.80647)
		(end 327.594976 -244.8179)
		(width 0.0889)
		(layer "In13.Cu")
		(net "M_B_CPU0_SA_CB<0>")
	)
	(segment
		(start 310.557418 -238.893604)
		(end 315.730128 -244.066314)
		(width 0.14478)
		(layer "In13.Cu")
		(net "M_B_CPU0_SA_CB<0>")
	)
	(segment
		(start 308.996842 -237.333028)
		(end 309.158894 -237.49508)
		(width 0.14478)
		(layer "In13.Cu")
		(net "M_B_CPU0_SA_CB<0>")
	)
	(segment
		(start 309.758588 -237.351316)
		(end 309.92064 -237.513368)
		(width 0.14478)
		(layer "In13.Cu")
		(net "M_B_CPU0_SA_CB<0>")
	)
	(segment
		(start 315.730128 -244.066314)
		(end 323.864478 -244.066314)
		(width 0.14478)
		(layer "In13.Cu")
		(net "M_B_CPU0_SA_CB<0>")
	)
	(segment
		(start 309.92064 -237.74146)
		(end 309.77713 -237.88497)
		(width 0.14478)
		(layer "In13.Cu")
		(net "M_B_CPU0_SA_CB<0>")
	)
	(segment
		(start 304.848514 -235.549948)
		(end 305.110134 -235.549948)
		(width 0.14478)
		(layer "In13.Cu")
		(net "M_B_CPU0_SA_CB<0>")
	)
	(segment
		(start 305.950874 -235.549948)
		(end 306.212494 -235.549948)
		(width 0.14478)
		(layer "In13.Cu")
		(net "M_B_CPU0_SA_CB<0>")
	)
	(segment
		(start 299.82414 -234.735116)
		(end 300.249082 -234.310174)
		(width 0.14478)
		(layer "In13.Cu")
		(net "M_B_CPU0_SA_CB<0>")
	)
	(segment
		(start 300.249082 -234.310174)
		(end 301.174658 -234.310174)
		(width 0.14478)
		(layer "In13.Cu")
		(net "M_B_CPU0_SA_CB<0>")
	)
	(segment
		(start 301.173896 -235.102654)
		(end 301.359062 -235.28782)
		(width 0.14478)
		(layer "In13.Cu")
		(net "M_B_CPU0_SA_CB<0>")
	)
	(segment
		(start 309.140352 -236.961426)
		(end 308.996842 -237.104936)
		(width 0.14478)
		(layer "In13.Cu")
		(net "M_B_CPU0_SA_CB<0>")
	)
	(segment
		(start 331.33411 -244.806724)
		(end 331.342492 -244.81155)
		(width 0.0889)
		(layer "In13.Cu")
		(net "M_B_CPU0_SA_CB<0>")
	)
	(segment
		(start 330.394056 -244.806724)
		(end 330.402438 -244.81155)
		(width 0.0889)
		(layer "In13.Cu")
		(net "M_B_CPU0_SA_CB<0>")
	)
	(segment
		(start 306.502054 -235.160058)
		(end 307.56733 -235.160058)
		(width 0.14478)
		(layer "In13.Cu")
		(net "M_B_CPU0_SA_CB<0>")
	)
	(segment
		(start 310.310784 -238.131604)
		(end 310.538876 -238.131604)
		(width 0.14478)
		(layer "In13.Cu")
		(net "M_B_CPU0_SA_CB<0>")
	)
	(segment
		(start 303.601374 -235.405168)
		(end 303.746154 -235.549948)
		(width 0.14478)
		(layer "In13.Cu")
		(net "M_B_CPU0_SA_CB<0>")
	)
	(segment
		(start 335.435194 -244.749574)
		(end 335.281016 -244.484144)
		(width 0.0889)
		(layer "In13.Cu")
		(net "M_B_CPU0_SA_CB<0>")
	)
	(segment
		(start 325.583296 -244.730016)
		(end 326.351138 -244.730016)
		(width 0.0889)
		(layer "In13.Cu")
		(net "M_B_CPU0_SA_CB<0>")
	)
	(segment
		(start 303.601374 -235.304838)
		(end 303.601374 -235.405168)
		(width 0.14478)
		(layer "In13.Cu")
		(net "M_B_CPU0_SA_CB<0>")
	)
	(segment
		(start 305.254914 -235.304838)
		(end 305.399694 -235.160058)
		(width 0.14478)
		(layer "In13.Cu")
		(net "M_B_CPU0_SA_CB<0>")
	)
	(segment
		(start 309.386986 -237.49508)
		(end 309.530496 -237.351316)
		(width 0.14478)
		(layer "In13.Cu")
		(net "M_B_CPU0_SA_CB<0>")
	)
	(segment
		(start 301.359062 -235.28782)
		(end 301.563786 -235.288074)
		(width 0.14478)
		(layer "In13.Cu")
		(net "M_B_CPU0_SA_CB<0>")
	)
	(segment
		(start 305.399694 -235.160058)
		(end 305.661314 -235.160058)
		(width 0.14478)
		(layer "In13.Cu")
		(net "M_B_CPU0_SA_CB<0>")
	)
	(segment
		(start 304.152554 -235.304838)
		(end 304.297334 -235.160058)
		(width 0.14478)
		(layer "In13.Cu")
		(net "M_B_CPU0_SA_CB<0>")
	)
	(segment
		(start 306.357274 -235.405168)
		(end 306.357274 -235.304838)
		(width 0.14478)
		(layer "In13.Cu")
		(net "M_B_CPU0_SA_CB<0>")
	)
	(segment
		(start 306.357274 -235.304838)
		(end 306.502054 -235.160058)
		(width 0.14478)
		(layer "In13.Cu")
		(net "M_B_CPU0_SA_CB<0>")
	)
	(segment
		(start 333.579724 -244.81155)
		(end 333.588106 -244.806724)
		(width 0.0889)
		(layer "In13.Cu")
		(net "M_B_CPU0_SA_CB<0>")
	)
	(segment
		(start 309.939182 -238.275368)
		(end 310.167274 -238.275368)
		(width 0.14478)
		(layer "In13.Cu")
		(net "M_B_CPU0_SA_CB<0>")
	)
	(segment
		(start 309.530496 -237.351316)
		(end 309.758588 -237.351316)
		(width 0.14478)
		(layer "In13.Cu")
		(net "M_B_CPU0_SA_CB<0>")
	)
	(segment
		(start 309.140352 -236.73308)
		(end 309.140352 -236.961426)
		(width 0.14478)
		(layer "In13.Cu")
		(net "M_B_CPU0_SA_CB<0>")
	)
	(segment
		(start 305.661314 -235.160058)
		(end 305.806094 -235.304838)
		(width 0.14478)
		(layer "In13.Cu")
		(net "M_B_CPU0_SA_CB<0>")
	)
	(segment
		(start 323.864478 -244.066314)
		(end 324.919594 -244.066314)
		(width 0.0889)
		(layer "In13.Cu")
		(net "M_B_CPU0_SA_CB<0>")
	)
	(segment
		(start 304.007774 -235.549948)
		(end 304.152554 -235.405168)
		(width 0.14478)
		(layer "In13.Cu")
		(net "M_B_CPU0_SA_CB<0>")
	)
	(segment
		(start 302.499014 -235.304838)
		(end 302.499014 -235.405168)
		(width 0.14478)
		(layer "In13.Cu")
		(net "M_B_CPU0_SA_CB<0>")
	)
	(segment
		(start 306.212494 -235.549948)
		(end 306.357274 -235.405168)
		(width 0.14478)
		(layer "In13.Cu")
		(net "M_B_CPU0_SA_CB<0>")
	)
	(segment
		(start 301.174658 -234.310174)
		(end 301.366174 -234.50169)
		(width 0.14478)
		(layer "In13.Cu")
		(net "M_B_CPU0_SA_CB<0>")
	)
	(segment
		(start 304.558954 -235.160058)
		(end 304.703734 -235.304838)
		(width 0.14478)
		(layer "In13.Cu")
		(net "M_B_CPU0_SA_CB<0>")
	)
	(segment
		(start 302.354234 -235.160058)
		(end 302.499014 -235.304838)
		(width 0.14478)
		(layer "In13.Cu")
		(net "M_B_CPU0_SA_CB<0>")
	)
	(segment
		(start 307.56733 -235.160058)
		(end 309.140352 -236.73308)
		(width 0.14478)
		(layer "In13.Cu")
		(net "M_B_CPU0_SA_CB<0>")
	)
	(segment
		(start 305.806094 -235.304838)
		(end 305.806094 -235.405168)
		(width 0.14478)
		(layer "In13.Cu")
		(net "M_B_CPU0_SA_CB<0>")
	)
	(segment
		(start 304.703734 -235.405168)
		(end 304.848514 -235.549948)
		(width 0.14478)
		(layer "In13.Cu")
		(net "M_B_CPU0_SA_CB<0>")
	)
	(segment
		(start 326.991726 -244.817646)
		(end 327.010522 -244.806724)
		(width 0.0889)
		(layer "In13.Cu")
		(net "M_B_CPU0_SA_CB<0>")
	)
	(segment
		(start 310.700928 -238.293656)
		(end 310.700928 -238.521748)
		(width 0.14478)
		(layer "In13.Cu")
		(net "M_B_CPU0_SA_CB<0>")
	)
	(segment
		(start 335.412842 -244.832886)
		(end 335.435194 -244.749574)
		(width 0.0889)
		(layer "In13.Cu")
		(net "M_B_CPU0_SA_CB<0>")
	)
	(segment
		(start 335.094072 -244.806724)
		(end 335.102454 -244.81155)
		(width 0.0889)
		(layer "In13.Cu")
		(net "M_B_CPU0_SA_CB<0>")
	)
	(segment
		(start 303.194974 -235.160058)
		(end 303.456594 -235.160058)
		(width 0.14478)
		(layer "In13.Cu")
		(net "M_B_CPU0_SA_CB<0>")
	)
	(segment
		(start 305.254914 -235.405168)
		(end 305.254914 -235.304838)
		(width 0.14478)
		(layer "In13.Cu")
		(net "M_B_CPU0_SA_CB<0>")
	)
	(segment
		(start 304.152554 -235.405168)
		(end 304.152554 -235.304838)
		(width 0.14478)
		(layer "In13.Cu")
		(net "M_B_CPU0_SA_CB<0>")
	)
	(segment
		(start 309.158894 -237.49508)
		(end 309.386986 -237.49508)
		(width 0.14478)
		(layer "In13.Cu")
		(net "M_B_CPU0_SA_CB<0>")
	)
	(segment
		(start 303.456594 -235.160058)
		(end 303.601374 -235.304838)
		(width 0.14478)
		(layer "In13.Cu")
		(net "M_B_CPU0_SA_CB<0>")
	)
	(segment
		(start 301.36592 -234.705906)
		(end 301.173896 -234.89793)
		(width 0.14478)
		(layer "In13.Cu")
		(net "M_B_CPU0_SA_CB<0>")
	)
	(segment
		(start 334.519778 -244.81155)
		(end 334.52816 -244.806724)
		(width 0.0889)
		(layer "In13.Cu")
		(net "M_B_CPU0_SA_CB<0>")
	)
	(segment
		(start 308.996842 -237.104936)
		(end 308.996842 -237.333028)
		(width 0.14478)
		(layer "In13.Cu")
		(net "M_B_CPU0_SA_CB<0>")
	)
	(segment
		(start 324.919594 -244.066314)
		(end 325.583296 -244.730016)
		(width 0.0889)
		(layer "In13.Cu")
		(net "M_B_CPU0_SA_CB<0>")
	)
	(segment
		(start 303.746154 -235.549948)
		(end 304.007774 -235.549948)
		(width 0.14478)
		(layer "In13.Cu")
		(net "M_B_CPU0_SA_CB<0>")
	)
	(segment
		(start 304.703734 -235.304838)
		(end 304.703734 -235.405168)
		(width 0.14478)
		(layer "In13.Cu")
		(net "M_B_CPU0_SA_CB<0>")
	)
	(segment
		(start 309.92064 -237.513368)
		(end 309.92064 -237.74146)
		(width 0.14478)
		(layer "In13.Cu")
		(net "M_B_CPU0_SA_CB<0>")
	)
	(segment
		(start 327.55332 -244.794024)
		(end 327.57491 -244.80647)
		(width 0.0889)
		(layer "In13.Cu")
		(net "M_B_CPU0_SA_CB<0>")
	)
	(segment
		(start 301.173896 -234.89793)
		(end 301.173896 -235.102654)
		(width 0.14478)
		(layer "In13.Cu")
		(net "M_B_CPU0_SA_CB<0>")
	)
	(segment
		(start 310.538876 -238.131604)
		(end 310.700928 -238.293656)
		(width 0.14478)
		(layer "In13.Cu")
		(net "M_B_CPU0_SA_CB<0>")
	)
	(segment
		(start 305.110134 -235.549948)
		(end 305.254914 -235.405168)
		(width 0.14478)
		(layer "In13.Cu")
		(net "M_B_CPU0_SA_CB<0>")
	)
	(segment
		(start 309.77713 -237.88497)
		(end 309.77713 -238.113316)
		(width 0.14478)
		(layer "In13.Cu")
		(net "M_B_CPU0_SA_CB<0>")
	)
	(segment
		(start 310.557418 -238.665258)
		(end 310.557418 -238.893604)
		(width 0.14478)
		(layer "In13.Cu")
		(net "M_B_CPU0_SA_CB<0>")
	)
	(segment
		(start 301.366174 -234.50169)
		(end 301.36592 -234.705906)
		(width 0.14478)
		(layer "In13.Cu")
		(net "M_B_CPU0_SA_CB<0>")
	)
	(segment
		(start 301.691802 -235.160058)
		(end 302.354234 -235.160058)
		(width 0.14478)
		(layer "In13.Cu")
		(net "M_B_CPU0_SA_CB<0>")
	)
	(segment
		(start 303.050194 -235.304838)
		(end 303.194974 -235.160058)
		(width 0.14478)
		(layer "In13.Cu")
		(net "M_B_CPU0_SA_CB<0>")
	)
	(segment
		(start 303.050194 -235.405168)
		(end 303.050194 -235.304838)
		(width 0.14478)
		(layer "In13.Cu")
		(net "M_B_CPU0_SA_CB<0>")
	)
	(segment
		(start 329.819762 -244.81155)
		(end 329.828144 -244.806724)
		(width 0.0889)
		(layer "In13.Cu")
		(net "M_B_CPU0_SA_CB<0>")
	)
	(segment
		(start 302.499014 -235.405168)
		(end 302.643794 -235.549948)
		(width 0.14478)
		(layer "In13.Cu")
		(net "M_B_CPU0_SA_CB<0>")
	)
	(segment
		(start 305.806094 -235.405168)
		(end 305.950874 -235.549948)
		(width 0.14478)
		(layer "In13.Cu")
		(net "M_B_CPU0_SA_CB<0>")
	)
	(segment
		(start 309.77713 -238.113316)
		(end 309.939182 -238.275368)
		(width 0.14478)
		(layer "In13.Cu")
		(net "M_B_CPU0_SA_CB<0>")
	)
	(segment
		(start 304.297334 -235.160058)
		(end 304.558954 -235.160058)
		(width 0.14478)
		(layer "In13.Cu")
		(net "M_B_CPU0_SA_CB<0>")
	)
	(segment
		(start 302.905414 -235.549948)
		(end 303.050194 -235.405168)
		(width 0.14478)
		(layer "In13.Cu")
		(net "M_B_CPU0_SA_CB<0>")
	)
	(arc
		(start 331.708252 -244.806724)
		(mid 331.991208 -244.730547)
		(end 332.274164 -244.806724)
		(width 0.0889)
		(layer "In13.Cu")
		(net "M_B_CPU0_SA_CB<0>")
	)
	(arc
		(start 326.351138 -244.730016)
		(mid 326.498347 -244.749493)
		(end 326.635364 -244.806724)
		(width 0.0889)
		(layer "In13.Cu")
		(net "M_B_CPU0_SA_CB<0>")
	)
	(arc
		(start 327.594976 -244.8179)
		(mid 327.773054 -244.856884)
		(end 327.94829 -244.806724)
		(width 0.0889)
		(layer "In13.Cu")
		(net "M_B_CPU0_SA_CB<0>")
	)
	(arc
		(start 327.94829 -244.806724)
		(mid 328.231246 -244.730547)
		(end 328.514202 -244.806724)
		(width 0.0889)
		(layer "In13.Cu")
		(net "M_B_CPU0_SA_CB<0>")
	)
	(arc
		(start 330.768198 -244.806724)
		(mid 331.051154 -244.730547)
		(end 331.33411 -244.806724)
		(width 0.0889)
		(layer "In13.Cu")
		(net "M_B_CPU0_SA_CB<0>")
	)
	(arc
		(start 327.010522 -244.806724)
		(mid 327.280291 -244.730701)
		(end 327.55332 -244.794024)
		(width 0.0889)
		(layer "In13.Cu")
		(net "M_B_CPU0_SA_CB<0>")
	)
	(arc
		(start 329.454002 -244.806724)
		(mid 329.636253 -244.857074)
		(end 329.819762 -244.81155)
		(width 0.0889)
		(layer "In13.Cu")
		(net "M_B_CPU0_SA_CB<0>")
	)
	(arc
		(start 334.154018 -244.806724)
		(mid 334.336269 -244.857074)
		(end 334.519778 -244.81155)
		(width 0.0889)
		(layer "In13.Cu")
		(net "M_B_CPU0_SA_CB<0>")
	)
	(arc
		(start 333.213964 -244.806724)
		(mid 333.396215 -244.857074)
		(end 333.579724 -244.81155)
		(width 0.0889)
		(layer "In13.Cu")
		(net "M_B_CPU0_SA_CB<0>")
	)
	(arc
		(start 335.102454 -244.81155)
		(mid 335.255324 -244.856191)
		(end 335.412842 -244.832886)
		(width 0.0889)
		(layer "In13.Cu")
		(net "M_B_CPU0_SA_CB<0>")
	)
	(arc
		(start 326.635364 -244.806724)
		(mid 326.812155 -244.857443)
		(end 326.991726 -244.817646)
		(width 0.0889)
		(layer "In13.Cu")
		(net "M_B_CPU0_SA_CB<0>")
	)
	(arc
		(start 334.52816 -244.806724)
		(mid 334.811116 -244.730547)
		(end 335.094072 -244.806724)
		(width 0.0889)
		(layer "In13.Cu")
		(net "M_B_CPU0_SA_CB<0>")
	)
	(arc
		(start 328.88809 -244.806724)
		(mid 329.171046 -244.730547)
		(end 329.454002 -244.806724)
		(width 0.0889)
		(layer "In13.Cu")
		(net "M_B_CPU0_SA_CB<0>")
	)
	(arc
		(start 331.342492 -244.81155)
		(mid 331.526 -244.857044)
		(end 331.708252 -244.806724)
		(width 0.0889)
		(layer "In13.Cu")
		(net "M_B_CPU0_SA_CB<0>")
	)
	(arc
		(start 333.588106 -244.806724)
		(mid 333.871062 -244.730547)
		(end 334.154018 -244.806724)
		(width 0.0889)
		(layer "In13.Cu")
		(net "M_B_CPU0_SA_CB<0>")
	)
	(arc
		(start 328.514202 -244.806724)
		(mid 328.701146 -244.856979)
		(end 328.88809 -244.806724)
		(width 0.0889)
		(layer "In13.Cu")
		(net "M_B_CPU0_SA_CB<0>")
	)
	(arc
		(start 332.274164 -244.806724)
		(mid 332.461108 -244.856979)
		(end 332.648052 -244.806724)
		(width 0.0889)
		(layer "In13.Cu")
		(net "M_B_CPU0_SA_CB<0>")
	)
	(arc
		(start 330.402438 -244.81155)
		(mid 330.585946 -244.857044)
		(end 330.768198 -244.806724)
		(width 0.0889)
		(layer "In13.Cu")
		(net "M_B_CPU0_SA_CB<0>")
	)
	(arc
		(start 332.648052 -244.806724)
		(mid 332.931008 -244.730547)
		(end 333.213964 -244.806724)
		(width 0.0889)
		(layer "In13.Cu")
		(net "M_B_CPU0_SA_CB<0>")
	)
	(arc
		(start 329.828144 -244.806724)
		(mid 330.1111 -244.730547)
		(end 330.394056 -244.806724)
		(width 0.0889)
		(layer "In13.Cu")
		(net "M_B_CPU0_SA_CB<0>")
	)
	(segment
		(start 337.158076 -255.28016)
		(end 336.691224 -255.014222)
		(width 0.10668)
		(layer "F.Cu")
		(net "M_B_CPU0_SA_CA<6>")
	)
	(segment
		(start 308.544214 -254.710184)
		(end 308.553358 -254.70104)
		(width 0.14478)
		(layer "In13.Cu")
		(net "M_B_CPU0_SA_CA<6>")
	)
	(segment
		(start 304.594006 -255.208278)
		(end 304.738786 -255.063498)
		(width 0.14478)
		(layer "In13.Cu")
		(net "M_B_CPU0_SA_CA<6>")
	)
	(segment
		(start 320.80581 -255.68275)
		(end 323.941694 -255.68275)
		(width 0.14478)
		(layer "In13.Cu")
		(net "M_B_CPU0_SA_CA<6>")
	)
	(segment
		(start 325.392542 -255.387348)
		(end 326.350884 -255.387348)
		(width 0.0889)
		(layer "In13.Cu")
		(net "M_B_CPU0_SA_CA<6>")
	)
	(segment
		(start 335.929732 -255.341628)
		(end 335.938114 -255.336802)
		(width 0.0889)
		(layer "In13.Cu")
		(net "M_B_CPU0_SA_CA<6>")
	)
	(segment
		(start 319.8241 -254.70104)
		(end 320.80581 -255.68275)
		(width 0.14478)
		(layer "In13.Cu")
		(net "M_B_CPU0_SA_CA<6>")
	)
	(segment
		(start 325.09714 -255.68275)
		(end 325.392542 -255.387348)
		(width 0.0889)
		(layer "In13.Cu")
		(net "M_B_CPU0_SA_CA<6>")
	)
	(segment
		(start 305.985926 -254.710184)
		(end 308.544214 -254.710184)
		(width 0.14478)
		(layer "In13.Cu")
		(net "M_B_CPU0_SA_CA<6>")
	)
	(segment
		(start 327.103232 -255.336802)
		(end 327.111614 -255.341628)
		(width 0.0889)
		(layer "In13.Cu")
		(net "M_B_CPU0_SA_CA<6>")
	)
	(segment
		(start 333.684118 -255.336802)
		(end 333.6925 -255.341628)
		(width 0.0889)
		(layer "In13.Cu")
		(net "M_B_CPU0_SA_CA<6>")
	)
	(segment
		(start 332.16977 -255.341628)
		(end 332.178152 -255.336802)
		(width 0.0889)
		(layer "In13.Cu")
		(net "M_B_CPU0_SA_CA<6>")
	)
	(segment
		(start 336.845148 -255.279652)
		(end 336.691224 -255.014222)
		(width 0.0889)
		(layer "In13.Cu")
		(net "M_B_CPU0_SA_CA<6>")
	)
	(segment
		(start 331.229716 -255.341628)
		(end 331.238098 -255.336802)
		(width 0.0889)
		(layer "In13.Cu")
		(net "M_B_CPU0_SA_CA<6>")
	)
	(segment
		(start 300.314868 -253.075694)
		(end 300.848268 -253.075694)
		(width 0.14478)
		(layer "In13.Cu")
		(net "M_B_CPU0_SA_CA<6>")
	)
	(segment
		(start 304.042826 -254.710184)
		(end 304.187606 -254.854964)
		(width 0.14478)
		(layer "In13.Cu")
		(net "M_B_CPU0_SA_CA<6>")
	)
	(segment
		(start 323.941694 -255.68275)
		(end 325.09714 -255.68275)
		(width 0.0889)
		(layer "In13.Cu")
		(net "M_B_CPU0_SA_CA<6>")
	)
	(segment
		(start 304.738786 -255.063498)
		(end 304.738786 -254.854964)
		(width 0.14478)
		(layer "In13.Cu")
		(net "M_B_CPU0_SA_CA<6>")
	)
	(segment
		(start 304.883566 -254.710184)
		(end 305.145186 -254.710184)
		(width 0.14478)
		(layer "In13.Cu")
		(net "M_B_CPU0_SA_CA<6>")
	)
	(segment
		(start 304.187606 -255.063498)
		(end 304.332386 -255.208278)
		(width 0.14478)
		(layer "In13.Cu")
		(net "M_B_CPU0_SA_CA<6>")
	)
	(segment
		(start 299.82414 -252.584966)
		(end 300.314868 -253.075694)
		(width 0.14478)
		(layer "In13.Cu")
		(net "M_B_CPU0_SA_CA<6>")
	)
	(segment
		(start 328.033634 -255.330706)
		(end 328.044048 -255.336802)
		(width 0.0889)
		(layer "In13.Cu")
		(net "M_B_CPU0_SA_CA<6>")
	)
	(segment
		(start 328.409808 -255.341628)
		(end 328.41819 -255.336802)
		(width 0.0889)
		(layer "In13.Cu")
		(net "M_B_CPU0_SA_CA<6>")
	)
	(segment
		(start 305.696366 -255.208278)
		(end 305.841146 -255.063498)
		(width 0.14478)
		(layer "In13.Cu")
		(net "M_B_CPU0_SA_CA<6>")
	)
	(segment
		(start 305.289966 -254.854964)
		(end 305.289966 -255.063498)
		(width 0.14478)
		(layer "In13.Cu")
		(net "M_B_CPU0_SA_CA<6>")
	)
	(segment
		(start 336.822796 -255.362964)
		(end 336.845148 -255.279652)
		(width 0.0889)
		(layer "In13.Cu")
		(net "M_B_CPU0_SA_CA<6>")
	)
	(segment
		(start 305.841146 -255.063498)
		(end 305.841146 -254.854964)
		(width 0.14478)
		(layer "In13.Cu")
		(net "M_B_CPU0_SA_CA<6>")
	)
	(segment
		(start 302.482758 -254.710184)
		(end 304.042826 -254.710184)
		(width 0.14478)
		(layer "In13.Cu")
		(net "M_B_CPU0_SA_CA<6>")
	)
	(segment
		(start 332.744064 -255.336802)
		(end 332.752446 -255.341628)
		(width 0.0889)
		(layer "In13.Cu")
		(net "M_B_CPU0_SA_CA<6>")
	)
	(segment
		(start 308.553358 -254.70104)
		(end 319.8241 -254.70104)
		(width 0.14478)
		(layer "In13.Cu")
		(net "M_B_CPU0_SA_CA<6>")
	)
	(segment
		(start 305.289966 -255.063498)
		(end 305.434746 -255.208278)
		(width 0.14478)
		(layer "In13.Cu")
		(net "M_B_CPU0_SA_CA<6>")
	)
	(segment
		(start 304.187606 -254.854964)
		(end 304.187606 -255.063498)
		(width 0.14478)
		(layer "In13.Cu")
		(net "M_B_CPU0_SA_CA<6>")
	)
	(segment
		(start 305.434746 -255.208278)
		(end 305.696366 -255.208278)
		(width 0.14478)
		(layer "In13.Cu")
		(net "M_B_CPU0_SA_CA<6>")
	)
	(segment
		(start 326.537828 -255.336548)
		(end 326.543416 -255.333246)
		(width 0.0889)
		(layer "In13.Cu")
		(net "M_B_CPU0_SA_CA<6>")
	)
	(segment
		(start 304.332386 -255.208278)
		(end 304.594006 -255.208278)
		(width 0.14478)
		(layer "In13.Cu")
		(net "M_B_CPU0_SA_CA<6>")
	)
	(segment
		(start 328.984102 -255.336802)
		(end 328.992484 -255.341628)
		(width 0.0889)
		(layer "In13.Cu")
		(net "M_B_CPU0_SA_CA<6>")
	)
	(segment
		(start 305.145186 -254.710184)
		(end 305.289966 -254.854964)
		(width 0.14478)
		(layer "In13.Cu")
		(net "M_B_CPU0_SA_CA<6>")
	)
	(segment
		(start 304.738786 -254.854964)
		(end 304.883566 -254.710184)
		(width 0.14478)
		(layer "In13.Cu")
		(net "M_B_CPU0_SA_CA<6>")
	)
	(segment
		(start 305.841146 -254.854964)
		(end 305.985926 -254.710184)
		(width 0.14478)
		(layer "In13.Cu")
		(net "M_B_CPU0_SA_CA<6>")
	)
	(segment
		(start 300.848268 -253.075694)
		(end 302.482758 -254.710184)
		(width 0.14478)
		(layer "In13.Cu")
		(net "M_B_CPU0_SA_CA<6>")
	)
	(arc
		(start 333.6925 -255.341628)
		(mid 333.876008 -255.387122)
		(end 334.05826 -255.336802)
		(width 0.0889)
		(layer "In13.Cu")
		(net "M_B_CPU0_SA_CA<6>")
	)
	(arc
		(start 334.05826 -255.336802)
		(mid 334.341216 -255.260625)
		(end 334.624172 -255.336802)
		(width 0.0889)
		(layer "In13.Cu")
		(net "M_B_CPU0_SA_CA<6>")
	)
	(arc
		(start 326.543416 -255.333246)
		(mid 326.823805 -255.260577)
		(end 327.103232 -255.336802)
		(width 0.0889)
		(layer "In13.Cu")
		(net "M_B_CPU0_SA_CA<6>")
	)
	(arc
		(start 332.752446 -255.341628)
		(mid 332.935954 -255.387122)
		(end 333.118206 -255.336802)
		(width 0.0889)
		(layer "In13.Cu")
		(net "M_B_CPU0_SA_CA<6>")
	)
	(arc
		(start 332.178152 -255.336802)
		(mid 332.461108 -255.260625)
		(end 332.744064 -255.336802)
		(width 0.0889)
		(layer "In13.Cu")
		(net "M_B_CPU0_SA_CA<6>")
	)
	(arc
		(start 327.477882 -255.336802)
		(mid 327.754949 -255.260531)
		(end 328.033634 -255.330706)
		(width 0.0889)
		(layer "In13.Cu")
		(net "M_B_CPU0_SA_CA<6>")
	)
	(arc
		(start 335.938114 -255.336802)
		(mid 336.22107 -255.260625)
		(end 336.504026 -255.336802)
		(width 0.0889)
		(layer "In13.Cu")
		(net "M_B_CPU0_SA_CA<6>")
	)
	(arc
		(start 328.044048 -255.336802)
		(mid 328.226299 -255.387152)
		(end 328.409808 -255.341628)
		(width 0.0889)
		(layer "In13.Cu")
		(net "M_B_CPU0_SA_CA<6>")
	)
	(arc
		(start 334.99806 -255.336802)
		(mid 335.281016 -255.260625)
		(end 335.563972 -255.336802)
		(width 0.0889)
		(layer "In13.Cu")
		(net "M_B_CPU0_SA_CA<6>")
	)
	(arc
		(start 329.924156 -255.336802)
		(mid 330.1111 -255.387057)
		(end 330.298044 -255.336802)
		(width 0.0889)
		(layer "In13.Cu")
		(net "M_B_CPU0_SA_CA<6>")
	)
	(arc
		(start 335.563972 -255.336802)
		(mid 335.746223 -255.387152)
		(end 335.929732 -255.341628)
		(width 0.0889)
		(layer "In13.Cu")
		(net "M_B_CPU0_SA_CA<6>")
	)
	(arc
		(start 327.111614 -255.341628)
		(mid 327.295376 -255.387244)
		(end 327.477882 -255.336802)
		(width 0.0889)
		(layer "In13.Cu")
		(net "M_B_CPU0_SA_CA<6>")
	)
	(arc
		(start 331.80401 -255.336802)
		(mid 331.986261 -255.387152)
		(end 332.16977 -255.341628)
		(width 0.0889)
		(layer "In13.Cu")
		(net "M_B_CPU0_SA_CA<6>")
	)
	(arc
		(start 331.238098 -255.336802)
		(mid 331.521054 -255.260625)
		(end 331.80401 -255.336802)
		(width 0.0889)
		(layer "In13.Cu")
		(net "M_B_CPU0_SA_CA<6>")
	)
	(arc
		(start 330.863956 -255.336802)
		(mid 331.046207 -255.387152)
		(end 331.229716 -255.341628)
		(width 0.0889)
		(layer "In13.Cu")
		(net "M_B_CPU0_SA_CA<6>")
	)
	(arc
		(start 329.358244 -255.336802)
		(mid 329.6412 -255.260625)
		(end 329.924156 -255.336802)
		(width 0.0889)
		(layer "In13.Cu")
		(net "M_B_CPU0_SA_CA<6>")
	)
	(arc
		(start 333.118206 -255.336802)
		(mid 333.401162 -255.260625)
		(end 333.684118 -255.336802)
		(width 0.0889)
		(layer "In13.Cu")
		(net "M_B_CPU0_SA_CA<6>")
	)
	(arc
		(start 334.624172 -255.336802)
		(mid 334.811116 -255.387057)
		(end 334.99806 -255.336802)
		(width 0.0889)
		(layer "In13.Cu")
		(net "M_B_CPU0_SA_CA<6>")
	)
	(arc
		(start 326.350884 -255.387348)
		(mid 326.447702 -255.374277)
		(end 326.537828 -255.336548)
		(width 0.0889)
		(layer "In13.Cu")
		(net "M_B_CPU0_SA_CA<6>")
	)
	(arc
		(start 330.298044 -255.336802)
		(mid 330.581 -255.260625)
		(end 330.863956 -255.336802)
		(width 0.0889)
		(layer "In13.Cu")
		(net "M_B_CPU0_SA_CA<6>")
	)
	(arc
		(start 336.504026 -255.336802)
		(mid 336.660464 -255.385773)
		(end 336.822796 -255.362964)
		(width 0.0889)
		(layer "In13.Cu")
		(net "M_B_CPU0_SA_CA<6>")
	)
	(arc
		(start 328.41819 -255.336802)
		(mid 328.701146 -255.260625)
		(end 328.984102 -255.336802)
		(width 0.0889)
		(layer "In13.Cu")
		(net "M_B_CPU0_SA_CA<6>")
	)
	(arc
		(start 328.992484 -255.341628)
		(mid 329.175992 -255.387122)
		(end 329.358244 -255.336802)
		(width 0.0889)
		(layer "In13.Cu")
		(net "M_B_CPU0_SA_CA<6>")
	)
	(segment
		(start 336.218022 -255.28016)
		(end 335.75117 -255.014222)
		(width 0.10668)
		(layer "F.Cu")
		(net "M_B_CPU0_SA_CA<5>")
	)
	(segment
		(start 325.86676 -254.972312)
		(end 326.087994 -254.751078)
		(width 0.0889)
		(layer "In13.Cu")
		(net "M_B_CPU0_SA_CA<5>")
	)
	(segment
		(start 335.500726 -254.723392)
		(end 335.596992 -254.748792)
		(width 0.0889)
		(layer "In13.Cu")
		(net "M_B_CPU0_SA_CA<5>")
	)
	(segment
		(start 326.16521 -254.691896)
		(end 326.192642 -254.676148)
		(width 0.0889)
		(layer "In13.Cu")
		(net "M_B_CPU0_SA_CA<5>")
	)
	(segment
		(start 306.260246 -253.860046)
		(end 306.64658 -254.24638)
		(width 0.14478)
		(layer "In13.Cu")
		(net "M_B_CPU0_SA_CA<5>")
	)
	(segment
		(start 325.0438 -255.22555)
		(end 325.297038 -254.972312)
		(width 0.0889)
		(layer "In13.Cu")
		(net "M_B_CPU0_SA_CA<5>")
	)
	(segment
		(start 302.372014 -253.860046)
		(end 306.260246 -253.860046)
		(width 0.14478)
		(layer "In13.Cu")
		(net "M_B_CPU0_SA_CA<5>")
	)
	(segment
		(start 327.461372 -254.681482)
		(end 327.47966 -254.691896)
		(width 0.0889)
		(layer "In13.Cu")
		(net "M_B_CPU0_SA_CA<5>")
	)
	(segment
		(start 332.744064 -254.691642)
		(end 332.752446 -254.686816)
		(width 0.0889)
		(layer "In13.Cu")
		(net "M_B_CPU0_SA_CA<5>")
	)
	(segment
		(start 320.991738 -255.22555)
		(end 323.913754 -255.22555)
		(width 0.14478)
		(layer "In13.Cu")
		(net "M_B_CPU0_SA_CA<5>")
	)
	(segment
		(start 335.596992 -254.748792)
		(end 335.75117 -255.014222)
		(width 0.0889)
		(layer "In13.Cu")
		(net "M_B_CPU0_SA_CA<5>")
	)
	(segment
		(start 325.297038 -254.972312)
		(end 325.86676 -254.972312)
		(width 0.0889)
		(layer "In13.Cu")
		(net "M_B_CPU0_SA_CA<5>")
	)
	(segment
		(start 331.229716 -254.686816)
		(end 331.238098 -254.691642)
		(width 0.0889)
		(layer "In13.Cu")
		(net "M_B_CPU0_SA_CA<5>")
	)
	(segment
		(start 332.16977 -254.686816)
		(end 332.178152 -254.691642)
		(width 0.0889)
		(layer "In13.Cu")
		(net "M_B_CPU0_SA_CA<5>")
	)
	(segment
		(start 327.083166 -254.705358)
		(end 327.106534 -254.691642)
		(width 0.0889)
		(layer "In13.Cu")
		(net "M_B_CPU0_SA_CA<5>")
	)
	(segment
		(start 297.984418 -251.735082)
		(end 298.40936 -252.160024)
		(width 0.14478)
		(layer "In13.Cu")
		(net "M_B_CPU0_SA_CA<5>")
	)
	(segment
		(start 306.64658 -254.24638)
		(end 320.012568 -254.24638)
		(width 0.14478)
		(layer "In13.Cu")
		(net "M_B_CPU0_SA_CA<5>")
	)
	(segment
		(start 328.984102 -254.691642)
		(end 328.992484 -254.686816)
		(width 0.0889)
		(layer "In13.Cu")
		(net "M_B_CPU0_SA_CA<5>")
	)
	(segment
		(start 295.724072 -251.735082)
		(end 297.984418 -251.735082)
		(width 0.14478)
		(layer "In13.Cu")
		(net "M_B_CPU0_SA_CA<5>")
	)
	(segment
		(start 327.47966 -254.691896)
		(end 327.50125 -254.704342)
		(width 0.0889)
		(layer "In13.Cu")
		(net "M_B_CPU0_SA_CA<5>")
	)
	(segment
		(start 328.409808 -254.686816)
		(end 328.41819 -254.691642)
		(width 0.0889)
		(layer "In13.Cu")
		(net "M_B_CPU0_SA_CA<5>")
	)
	(segment
		(start 320.012568 -254.24638)
		(end 320.991738 -255.22555)
		(width 0.14478)
		(layer "In13.Cu")
		(net "M_B_CPU0_SA_CA<5>")
	)
	(segment
		(start 298.40936 -252.160024)
		(end 300.671992 -252.160024)
		(width 0.14478)
		(layer "In13.Cu")
		(net "M_B_CPU0_SA_CA<5>")
	)
	(segment
		(start 333.684118 -254.691642)
		(end 333.6925 -254.686816)
		(width 0.0889)
		(layer "In13.Cu")
		(net "M_B_CPU0_SA_CA<5>")
	)
	(segment
		(start 323.913754 -255.22555)
		(end 325.0438 -255.22555)
		(width 0.0889)
		(layer "In13.Cu")
		(net "M_B_CPU0_SA_CA<5>")
	)
	(segment
		(start 300.671992 -252.160024)
		(end 302.372014 -253.860046)
		(width 0.14478)
		(layer "In13.Cu")
		(net "M_B_CPU0_SA_CA<5>")
	)
	(arc
		(start 326.087994 -254.751078)
		(mid 326.12465 -254.718938)
		(end 326.16521 -254.691896)
		(width 0.0889)
		(layer "In13.Cu")
		(net "M_B_CPU0_SA_CA<5>")
	)
	(arc
		(start 331.238098 -254.691642)
		(mid 331.521054 -254.767819)
		(end 331.80401 -254.691642)
		(width 0.0889)
		(layer "In13.Cu")
		(net "M_B_CPU0_SA_CA<5>")
	)
	(arc
		(start 330.298044 -254.691642)
		(mid 330.581 -254.767819)
		(end 330.863956 -254.691642)
		(width 0.0889)
		(layer "In13.Cu")
		(net "M_B_CPU0_SA_CA<5>")
	)
	(arc
		(start 332.752446 -254.686816)
		(mid 332.935954 -254.641322)
		(end 333.118206 -254.691642)
		(width 0.0889)
		(layer "In13.Cu")
		(net "M_B_CPU0_SA_CA<5>")
	)
	(arc
		(start 326.539352 -254.691642)
		(mid 326.809509 -254.768404)
		(end 327.083166 -254.705358)
		(width 0.0889)
		(layer "In13.Cu")
		(net "M_B_CPU0_SA_CA<5>")
	)
	(arc
		(start 334.99806 -254.691642)
		(mid 335.245656 -254.76682)
		(end 335.500726 -254.723392)
		(width 0.0889)
		(layer "In13.Cu")
		(net "M_B_CPU0_SA_CA<5>")
	)
	(arc
		(start 327.50125 -254.704342)
		(mid 327.774279 -254.767661)
		(end 328.044048 -254.691642)
		(width 0.0889)
		(layer "In13.Cu")
		(net "M_B_CPU0_SA_CA<5>")
	)
	(arc
		(start 334.05826 -254.691642)
		(mid 334.341216 -254.767819)
		(end 334.624172 -254.691642)
		(width 0.0889)
		(layer "In13.Cu")
		(net "M_B_CPU0_SA_CA<5>")
	)
	(arc
		(start 334.624172 -254.691642)
		(mid 334.811116 -254.641387)
		(end 334.99806 -254.691642)
		(width 0.0889)
		(layer "In13.Cu")
		(net "M_B_CPU0_SA_CA<5>")
	)
	(arc
		(start 331.80401 -254.691642)
		(mid 331.986261 -254.641292)
		(end 332.16977 -254.686816)
		(width 0.0889)
		(layer "In13.Cu")
		(net "M_B_CPU0_SA_CA<5>")
	)
	(arc
		(start 333.118206 -254.691642)
		(mid 333.401162 -254.767819)
		(end 333.684118 -254.691642)
		(width 0.0889)
		(layer "In13.Cu")
		(net "M_B_CPU0_SA_CA<5>")
	)
	(arc
		(start 326.192642 -254.676148)
		(mid 326.367893 -254.641215)
		(end 326.539352 -254.691642)
		(width 0.0889)
		(layer "In13.Cu")
		(net "M_B_CPU0_SA_CA<5>")
	)
	(arc
		(start 328.992484 -254.686816)
		(mid 329.175992 -254.641322)
		(end 329.358244 -254.691642)
		(width 0.0889)
		(layer "In13.Cu")
		(net "M_B_CPU0_SA_CA<5>")
	)
	(arc
		(start 333.6925 -254.686816)
		(mid 333.876008 -254.641322)
		(end 334.05826 -254.691642)
		(width 0.0889)
		(layer "In13.Cu")
		(net "M_B_CPU0_SA_CA<5>")
	)
	(arc
		(start 327.106534 -254.691642)
		(mid 327.282654 -254.641664)
		(end 327.461372 -254.681482)
		(width 0.0889)
		(layer "In13.Cu")
		(net "M_B_CPU0_SA_CA<5>")
	)
	(arc
		(start 329.924156 -254.691642)
		(mid 330.1111 -254.641387)
		(end 330.298044 -254.691642)
		(width 0.0889)
		(layer "In13.Cu")
		(net "M_B_CPU0_SA_CA<5>")
	)
	(arc
		(start 330.863956 -254.691642)
		(mid 331.046207 -254.641292)
		(end 331.229716 -254.686816)
		(width 0.0889)
		(layer "In13.Cu")
		(net "M_B_CPU0_SA_CA<5>")
	)
	(arc
		(start 332.178152 -254.691642)
		(mid 332.461108 -254.767819)
		(end 332.744064 -254.691642)
		(width 0.0889)
		(layer "In13.Cu")
		(net "M_B_CPU0_SA_CA<5>")
	)
	(arc
		(start 328.044048 -254.691642)
		(mid 328.226299 -254.641292)
		(end 328.409808 -254.686816)
		(width 0.0889)
		(layer "In13.Cu")
		(net "M_B_CPU0_SA_CA<5>")
	)
	(arc
		(start 329.358244 -254.691642)
		(mid 329.6412 -254.767819)
		(end 329.924156 -254.691642)
		(width 0.0889)
		(layer "In13.Cu")
		(net "M_B_CPU0_SA_CA<5>")
	)
	(arc
		(start 328.41819 -254.691642)
		(mid 328.701146 -254.767819)
		(end 328.984102 -254.691642)
		(width 0.0889)
		(layer "In13.Cu")
		(net "M_B_CPU0_SA_CA<5>")
	)
	(segment
		(start 335.747868 -254.470154)
		(end 335.281016 -254.204216)
		(width 0.10668)
		(layer "F.Cu")
		(net "M_B_CPU0_SA_CA<4>")
	)
	(segment
		(start 302.238664 -252.333506)
		(end 302.053498 -252.14834)
		(width 0.14478)
		(layer "In13.Cu")
		(net "M_B_CPU0_SA_CA<4>")
	)
	(segment
		(start 304.69586 -253.009908)
		(end 304.55108 -253.154688)
		(width 0.14478)
		(layer "In13.Cu")
		(net "M_B_CPU0_SA_CA<4>")
	)
	(segment
		(start 321.210686 -254.76073)
		(end 320.241676 -253.79172)
		(width 0.14478)
		(layer "In13.Cu")
		(net "M_B_CPU0_SA_CA<4>")
	)
	(segment
		(start 305.79822 -253.009908)
		(end 305.65344 -253.154688)
		(width 0.14478)
		(layer "In13.Cu")
		(net "M_B_CPU0_SA_CA<4>")
	)
	(segment
		(start 302.18253 -252.799088)
		(end 302.18253 -252.594364)
		(width 0.14478)
		(layer "In13.Cu")
		(net "M_B_CPU0_SA_CA<4>")
	)
	(segment
		(start 301.273718 -251.36856)
		(end 301.068994 -251.36856)
		(width 0.14478)
		(layer "In13.Cu")
		(net "M_B_CPU0_SA_CA<4>")
	)
	(segment
		(start 300.630336 -251.246894)
		(end 300.18609 -251.246894)
		(width 0.14478)
		(layer "In13.Cu")
		(net "M_B_CPU0_SA_CA<4>")
	)
	(segment
		(start 326.101456 -254.508254)
		(end 326.069706 -254.526542)
		(width 0.0889)
		(layer "In13.Cu")
		(net "M_B_CPU0_SA_CA<4>")
	)
	(segment
		(start 324.313296 -254.76073)
		(end 324.203314 -254.76073)
		(width 0.0889)
		(layer "In13.Cu")
		(net "M_B_CPU0_SA_CA<4>")
	)
	(segment
		(start 330.402438 -254.531622)
		(end 330.394056 -254.526796)
		(width 0.0889)
		(layer "In13.Cu")
		(net "M_B_CPU0_SA_CA<4>")
	)
	(segment
		(start 302.89754 -253.154688)
		(end 302.75276 -253.009908)
		(width 0.14478)
		(layer "In13.Cu")
		(net "M_B_CPU0_SA_CA<4>")
	)
	(segment
		(start 333.588106 -254.526796)
		(end 333.579724 -254.531622)
		(width 0.0889)
		(layer "In13.Cu")
		(net "M_B_CPU0_SA_CA<4>")
	)
	(segment
		(start 306.20462 -253.154688)
		(end 306.05984 -253.009908)
		(width 0.14478)
		(layer "In13.Cu")
		(net "M_B_CPU0_SA_CA<4>")
	)
	(segment
		(start 335.102454 -254.531622)
		(end 335.094072 -254.526796)
		(width 0.0889)
		(layer "In13.Cu")
		(net "M_B_CPU0_SA_CA<4>")
	)
	(segment
		(start 302.39335 -253.009908)
		(end 302.18253 -252.799088)
		(width 0.14478)
		(layer "In13.Cu")
		(net "M_B_CPU0_SA_CA<4>")
	)
	(segment
		(start 302.75276 -253.009908)
		(end 302.39335 -253.009908)
		(width 0.14478)
		(layer "In13.Cu")
		(net "M_B_CPU0_SA_CA<4>")
	)
	(segment
		(start 335.435194 -254.469646)
		(end 335.412842 -254.552958)
		(width 0.0889)
		(layer "In13.Cu")
		(net "M_B_CPU0_SA_CA<4>")
	)
	(segment
		(start 303.44872 -253.24943)
		(end 303.30394 -253.39421)
		(width 0.14478)
		(layer "In13.Cu")
		(net "M_B_CPU0_SA_CA<4>")
	)
	(segment
		(start 325.858632 -254.710692)
		(end 325.157084 -254.710692)
		(width 0.0889)
		(layer "In13.Cu")
		(net "M_B_CPU0_SA_CA<4>")
	)
	(segment
		(start 324.203314 -254.76073)
		(end 321.210686 -254.76073)
		(width 0.14478)
		(layer "In13.Cu")
		(net "M_B_CPU0_SA_CA<4>")
	)
	(segment
		(start 329.828144 -254.526796)
		(end 329.819762 -254.531622)
		(width 0.0889)
		(layer "In13.Cu")
		(net "M_B_CPU0_SA_CA<4>")
	)
	(segment
		(start 301.458884 -251.75845)
		(end 301.458884 -251.553726)
		(width 0.14478)
		(layer "In13.Cu")
		(net "M_B_CPU0_SA_CA<4>")
	)
	(segment
		(start 308.54269 -253.79172)
		(end 307.760878 -253.009908)
		(width 0.14478)
		(layer "In13.Cu")
		(net "M_B_CPU0_SA_CA<4>")
	)
	(segment
		(start 304.4063 -253.39421)
		(end 304.14468 -253.39421)
		(width 0.14478)
		(layer "In13.Cu")
		(net "M_B_CPU0_SA_CA<4>")
	)
	(segment
		(start 301.068994 -251.36856)
		(end 301.01286 -251.424694)
		(width 0.14478)
		(layer "In13.Cu")
		(net "M_B_CPU0_SA_CA<4>")
	)
	(segment
		(start 306.7558 -253.154688)
		(end 306.7558 -253.24943)
		(width 0.14478)
		(layer "In13.Cu")
		(net "M_B_CPU0_SA_CA<4>")
	)
	(segment
		(start 302.18253 -252.594364)
		(end 302.238664 -252.53823)
		(width 0.14478)
		(layer "In13.Cu")
		(net "M_B_CPU0_SA_CA<4>")
	)
	(segment
		(start 304.95748 -253.009908)
		(end 304.69586 -253.009908)
		(width 0.14478)
		(layer "In13.Cu")
		(net "M_B_CPU0_SA_CA<4>")
	)
	(segment
		(start 300.18609 -251.246894)
		(end 299.82414 -250.884944)
		(width 0.14478)
		(layer "In13.Cu")
		(net "M_B_CPU0_SA_CA<4>")
	)
	(segment
		(start 303.85512 -253.009908)
		(end 303.5935 -253.009908)
		(width 0.14478)
		(layer "In13.Cu")
		(net "M_B_CPU0_SA_CA<4>")
	)
	(segment
		(start 320.241676 -253.79172)
		(end 308.54269 -253.79172)
		(width 0.14478)
		(layer "In13.Cu")
		(net "M_B_CPU0_SA_CA<4>")
	)
	(segment
		(start 331.342492 -254.531622)
		(end 331.33411 -254.526796)
		(width 0.0889)
		(layer "In13.Cu")
		(net "M_B_CPU0_SA_CA<4>")
	)
	(segment
		(start 306.7558 -253.24943)
		(end 306.61102 -253.39421)
		(width 0.14478)
		(layer "In13.Cu")
		(net "M_B_CPU0_SA_CA<4>")
	)
	(segment
		(start 302.238664 -252.53823)
		(end 302.238664 -252.333506)
		(width 0.14478)
		(layer "In13.Cu")
		(net "M_B_CPU0_SA_CA<4>")
	)
	(segment
		(start 303.9999 -253.24943)
		(end 303.9999 -253.154688)
		(width 0.14478)
		(layer "In13.Cu")
		(net "M_B_CPU0_SA_CA<4>")
	)
	(segment
		(start 305.24704 -253.39421)
		(end 305.10226 -253.24943)
		(width 0.14478)
		(layer "In13.Cu")
		(net "M_B_CPU0_SA_CA<4>")
	)
	(segment
		(start 305.65344 -253.24943)
		(end 305.50866 -253.39421)
		(width 0.14478)
		(layer "In13.Cu")
		(net "M_B_CPU0_SA_CA<4>")
	)
	(segment
		(start 325.95312 -254.616204)
		(end 325.858632 -254.710692)
		(width 0.0889)
		(layer "In13.Cu")
		(net "M_B_CPU0_SA_CA<4>")
	)
	(segment
		(start 301.01286 -251.424694)
		(end 300.808136 -251.424694)
		(width 0.14478)
		(layer "In13.Cu")
		(net "M_B_CPU0_SA_CA<4>")
	)
	(segment
		(start 327.010522 -254.526796)
		(end 326.991726 -254.537718)
		(width 0.0889)
		(layer "In13.Cu")
		(net "M_B_CPU0_SA_CA<4>")
	)
	(segment
		(start 306.90058 -253.009908)
		(end 306.7558 -253.154688)
		(width 0.14478)
		(layer "In13.Cu")
		(net "M_B_CPU0_SA_CA<4>")
	)
	(segment
		(start 302.89754 -253.24943)
		(end 302.89754 -253.154688)
		(width 0.14478)
		(layer "In13.Cu")
		(net "M_B_CPU0_SA_CA<4>")
	)
	(segment
		(start 307.760878 -253.009908)
		(end 306.90058 -253.009908)
		(width 0.14478)
		(layer "In13.Cu")
		(net "M_B_CPU0_SA_CA<4>")
	)
	(segment
		(start 303.30394 -253.39421)
		(end 303.04232 -253.39421)
		(width 0.14478)
		(layer "In13.Cu")
		(net "M_B_CPU0_SA_CA<4>")
	)
	(segment
		(start 306.20462 -253.24943)
		(end 306.20462 -253.154688)
		(width 0.14478)
		(layer "In13.Cu")
		(net "M_B_CPU0_SA_CA<4>")
	)
	(segment
		(start 301.40275 -252.019308)
		(end 301.40275 -251.814584)
		(width 0.14478)
		(layer "In13.Cu")
		(net "M_B_CPU0_SA_CA<4>")
	)
	(segment
		(start 304.14468 -253.39421)
		(end 303.9999 -253.24943)
		(width 0.14478)
		(layer "In13.Cu")
		(net "M_B_CPU0_SA_CA<4>")
	)
	(segment
		(start 304.55108 -253.24943)
		(end 304.4063 -253.39421)
		(width 0.14478)
		(layer "In13.Cu")
		(net "M_B_CPU0_SA_CA<4>")
	)
	(segment
		(start 335.281016 -254.204216)
		(end 335.435194 -254.469646)
		(width 0.0889)
		(layer "In13.Cu")
		(net "M_B_CPU0_SA_CA<4>")
	)
	(segment
		(start 303.9999 -253.154688)
		(end 303.85512 -253.009908)
		(width 0.14478)
		(layer "In13.Cu")
		(net "M_B_CPU0_SA_CA<4>")
	)
	(segment
		(start 325.028306 -254.83947)
		(end 324.392036 -254.83947)
		(width 0.0889)
		(layer "In13.Cu")
		(net "M_B_CPU0_SA_CA<4>")
	)
	(segment
		(start 327.57491 -254.526542)
		(end 327.55332 -254.514096)
		(width 0.0889)
		(layer "In13.Cu")
		(net "M_B_CPU0_SA_CA<4>")
	)
	(segment
		(start 334.52816 -254.526796)
		(end 334.519778 -254.531622)
		(width 0.0889)
		(layer "In13.Cu")
		(net "M_B_CPU0_SA_CA<4>")
	)
	(segment
		(start 324.392036 -254.83947)
		(end 324.313296 -254.76073)
		(width 0.0889)
		(layer "In13.Cu")
		(net "M_B_CPU0_SA_CA<4>")
	)
	(segment
		(start 325.157084 -254.710692)
		(end 325.028306 -254.83947)
		(width 0.0889)
		(layer "In13.Cu")
		(net "M_B_CPU0_SA_CA<4>")
	)
	(segment
		(start 305.10226 -253.24943)
		(end 305.10226 -253.154688)
		(width 0.14478)
		(layer "In13.Cu")
		(net "M_B_CPU0_SA_CA<4>")
	)
	(segment
		(start 306.61102 -253.39421)
		(end 306.3494 -253.39421)
		(width 0.14478)
		(layer "In13.Cu")
		(net "M_B_CPU0_SA_CA<4>")
	)
	(segment
		(start 301.587916 -252.204474)
		(end 301.40275 -252.019308)
		(width 0.14478)
		(layer "In13.Cu")
		(net "M_B_CPU0_SA_CA<4>")
	)
	(segment
		(start 306.3494 -253.39421)
		(end 306.20462 -253.24943)
		(width 0.14478)
		(layer "In13.Cu")
		(net "M_B_CPU0_SA_CA<4>")
	)
	(segment
		(start 327.594976 -254.537972)
		(end 327.57491 -254.526542)
		(width 0.0889)
		(layer "In13.Cu")
		(net "M_B_CPU0_SA_CA<4>")
	)
	(segment
		(start 301.40275 -251.814584)
		(end 301.458884 -251.75845)
		(width 0.14478)
		(layer "In13.Cu")
		(net "M_B_CPU0_SA_CA<4>")
	)
	(segment
		(start 305.10226 -253.154688)
		(end 304.95748 -253.009908)
		(width 0.14478)
		(layer "In13.Cu")
		(net "M_B_CPU0_SA_CA<4>")
	)
	(segment
		(start 301.79264 -252.204474)
		(end 301.587916 -252.204474)
		(width 0.14478)
		(layer "In13.Cu")
		(net "M_B_CPU0_SA_CA<4>")
	)
	(segment
		(start 303.5935 -253.009908)
		(end 303.44872 -253.154688)
		(width 0.14478)
		(layer "In13.Cu")
		(net "M_B_CPU0_SA_CA<4>")
	)
	(segment
		(start 304.55108 -253.154688)
		(end 304.55108 -253.24943)
		(width 0.14478)
		(layer "In13.Cu")
		(net "M_B_CPU0_SA_CA<4>")
	)
	(segment
		(start 303.44872 -253.154688)
		(end 303.44872 -253.24943)
		(width 0.14478)
		(layer "In13.Cu")
		(net "M_B_CPU0_SA_CA<4>")
	)
	(segment
		(start 302.053498 -252.14834)
		(end 301.848774 -252.14834)
		(width 0.14478)
		(layer "In13.Cu")
		(net "M_B_CPU0_SA_CA<4>")
	)
	(segment
		(start 305.65344 -253.154688)
		(end 305.65344 -253.24943)
		(width 0.14478)
		(layer "In13.Cu")
		(net "M_B_CPU0_SA_CA<4>")
	)
	(segment
		(start 301.848774 -252.14834)
		(end 301.79264 -252.204474)
		(width 0.14478)
		(layer "In13.Cu")
		(net "M_B_CPU0_SA_CA<4>")
	)
	(segment
		(start 301.458884 -251.553726)
		(end 301.273718 -251.36856)
		(width 0.14478)
		(layer "In13.Cu")
		(net "M_B_CPU0_SA_CA<4>")
	)
	(segment
		(start 300.808136 -251.424694)
		(end 300.630336 -251.246894)
		(width 0.14478)
		(layer "In13.Cu")
		(net "M_B_CPU0_SA_CA<4>")
	)
	(segment
		(start 303.04232 -253.39421)
		(end 302.89754 -253.24943)
		(width 0.14478)
		(layer "In13.Cu")
		(net "M_B_CPU0_SA_CA<4>")
	)
	(segment
		(start 305.50866 -253.39421)
		(end 305.24704 -253.39421)
		(width 0.14478)
		(layer "In13.Cu")
		(net "M_B_CPU0_SA_CA<4>")
	)
	(segment
		(start 306.05984 -253.009908)
		(end 305.79822 -253.009908)
		(width 0.14478)
		(layer "In13.Cu")
		(net "M_B_CPU0_SA_CA<4>")
	)
	(arc
		(start 328.88809 -254.526796)
		(mid 328.701146 -254.577051)
		(end 328.514202 -254.526796)
		(width 0.0889)
		(layer "In13.Cu")
		(net "M_B_CPU0_SA_CA<4>")
	)
	(arc
		(start 327.94829 -254.526796)
		(mid 327.773051 -254.576867)
		(end 327.594976 -254.537972)
		(width 0.0889)
		(layer "In13.Cu")
		(net "M_B_CPU0_SA_CA<4>")
	)
	(arc
		(start 330.394056 -254.526796)
		(mid 330.1111 -254.450619)
		(end 329.828144 -254.526796)
		(width 0.0889)
		(layer "In13.Cu")
		(net "M_B_CPU0_SA_CA<4>")
	)
	(arc
		(start 328.514202 -254.526796)
		(mid 328.231246 -254.450619)
		(end 327.94829 -254.526796)
		(width 0.0889)
		(layer "In13.Cu")
		(net "M_B_CPU0_SA_CA<4>")
	)
	(arc
		(start 332.274164 -254.526796)
		(mid 331.991208 -254.450619)
		(end 331.708252 -254.526796)
		(width 0.0889)
		(layer "In13.Cu")
		(net "M_B_CPU0_SA_CA<4>")
	)
	(arc
		(start 333.213964 -254.526796)
		(mid 332.931008 -254.450619)
		(end 332.648052 -254.526796)
		(width 0.0889)
		(layer "In13.Cu")
		(net "M_B_CPU0_SA_CA<4>")
	)
	(arc
		(start 326.991726 -254.537718)
		(mid 326.812155 -254.577535)
		(end 326.635364 -254.526796)
		(width 0.0889)
		(layer "In13.Cu")
		(net "M_B_CPU0_SA_CA<4>")
	)
	(arc
		(start 333.579724 -254.531622)
		(mid 333.396216 -254.577116)
		(end 333.213964 -254.526796)
		(width 0.0889)
		(layer "In13.Cu")
		(net "M_B_CPU0_SA_CA<4>")
	)
	(arc
		(start 335.094072 -254.526796)
		(mid 334.811116 -254.450619)
		(end 334.52816 -254.526796)
		(width 0.0889)
		(layer "In13.Cu")
		(net "M_B_CPU0_SA_CA<4>")
	)
	(arc
		(start 327.55332 -254.514096)
		(mid 327.280291 -254.450777)
		(end 327.010522 -254.526796)
		(width 0.0889)
		(layer "In13.Cu")
		(net "M_B_CPU0_SA_CA<4>")
	)
	(arc
		(start 331.33411 -254.526796)
		(mid 331.051154 -254.450619)
		(end 330.768198 -254.526796)
		(width 0.0889)
		(layer "In13.Cu")
		(net "M_B_CPU0_SA_CA<4>")
	)
	(arc
		(start 329.819762 -254.531622)
		(mid 329.636254 -254.577116)
		(end 329.454002 -254.526796)
		(width 0.0889)
		(layer "In13.Cu")
		(net "M_B_CPU0_SA_CA<4>")
	)
	(arc
		(start 332.648052 -254.526796)
		(mid 332.461108 -254.577051)
		(end 332.274164 -254.526796)
		(width 0.0889)
		(layer "In13.Cu")
		(net "M_B_CPU0_SA_CA<4>")
	)
	(arc
		(start 335.412842 -254.552958)
		(mid 335.255332 -254.576156)
		(end 335.102454 -254.531622)
		(width 0.0889)
		(layer "In13.Cu")
		(net "M_B_CPU0_SA_CA<4>")
	)
	(arc
		(start 326.069706 -254.526542)
		(mid 326.008475 -254.567552)
		(end 325.95312 -254.616204)
		(width 0.0889)
		(layer "In13.Cu")
		(net "M_B_CPU0_SA_CA<4>")
	)
	(arc
		(start 330.768198 -254.526796)
		(mid 330.585947 -254.577146)
		(end 330.402438 -254.531622)
		(width 0.0889)
		(layer "In13.Cu")
		(net "M_B_CPU0_SA_CA<4>")
	)
	(arc
		(start 334.519778 -254.531622)
		(mid 334.33627 -254.577116)
		(end 334.154018 -254.526796)
		(width 0.0889)
		(layer "In13.Cu")
		(net "M_B_CPU0_SA_CA<4>")
	)
	(arc
		(start 334.154018 -254.526796)
		(mid 333.871062 -254.450619)
		(end 333.588106 -254.526796)
		(width 0.0889)
		(layer "In13.Cu")
		(net "M_B_CPU0_SA_CA<4>")
	)
	(arc
		(start 331.708252 -254.526796)
		(mid 331.526001 -254.577146)
		(end 331.342492 -254.531622)
		(width 0.0889)
		(layer "In13.Cu")
		(net "M_B_CPU0_SA_CA<4>")
	)
	(arc
		(start 326.635364 -254.526796)
		(mid 326.370741 -254.450321)
		(end 326.101456 -254.508254)
		(width 0.0889)
		(layer "In13.Cu")
		(net "M_B_CPU0_SA_CA<4>")
	)
	(arc
		(start 329.454002 -254.526796)
		(mid 329.171046 -254.450619)
		(end 328.88809 -254.526796)
		(width 0.0889)
		(layer "In13.Cu")
		(net "M_B_CPU0_SA_CA<4>")
	)
	(segment
		(start 337.627976 -254.470154)
		(end 337.161124 -254.204216)
		(width 0.10668)
		(layer "F.Cu")
		(net "M_B_CPU0_SA_CA<3>")
	)
	(segment
		(start 334.519778 -253.87681)
		(end 334.52816 -253.881636)
		(width 0.0889)
		(layer "In13.Cu")
		(net "M_B_CPU0_SA_CA<3>")
	)
	(segment
		(start 327.939908 -253.87681)
		(end 327.94829 -253.881636)
		(width 0.0889)
		(layer "In13.Cu")
		(net "M_B_CPU0_SA_CA<3>")
	)
	(segment
		(start 336.911188 -253.913386)
		(end 337.0072 -253.938786)
		(width 0.0889)
		(layer "In13.Cu")
		(net "M_B_CPU0_SA_CA<3>")
	)
	(segment
		(start 326.633586 -253.88189)
		(end 326.649842 -253.872492)
		(width 0.0889)
		(layer "In13.Cu")
		(net "M_B_CPU0_SA_CA<3>")
	)
	(segment
		(start 297.948096 -250.03506)
		(end 298.373038 -250.460002)
		(width 0.14478)
		(layer "In13.Cu")
		(net "M_B_CPU0_SA_CA<3>")
	)
	(segment
		(start 320.430144 -253.33706)
		(end 321.394074 -254.30099)
		(width 0.14478)
		(layer "In13.Cu")
		(net "M_B_CPU0_SA_CA<3>")
	)
	(segment
		(start 335.094072 -253.881636)
		(end 335.102454 -253.87681)
		(width 0.0889)
		(layer "In13.Cu")
		(net "M_B_CPU0_SA_CA<3>")
	)
	(segment
		(start 324.21576 -254.30099)
		(end 324.435978 -254.080772)
		(width 0.0889)
		(layer "In13.Cu")
		(net "M_B_CPU0_SA_CA<3>")
	)
	(segment
		(start 326.617838 -253.891034)
		(end 326.633586 -253.88189)
		(width 0.0889)
		(layer "In13.Cu")
		(net "M_B_CPU0_SA_CA<3>")
	)
	(segment
		(start 301.14748 -250.460002)
		(end 302.847502 -252.160024)
		(width 0.14478)
		(layer "In13.Cu")
		(net "M_B_CPU0_SA_CA<3>")
	)
	(segment
		(start 330.394056 -253.881636)
		(end 330.402438 -253.87681)
		(width 0.0889)
		(layer "In13.Cu")
		(net "M_B_CPU0_SA_CA<3>")
	)
	(segment
		(start 333.579724 -253.87681)
		(end 333.588106 -253.881636)
		(width 0.0889)
		(layer "In13.Cu")
		(net "M_B_CPU0_SA_CA<3>")
	)
	(segment
		(start 295.724072 -250.03506)
		(end 297.948096 -250.03506)
		(width 0.14478)
		(layer "In13.Cu")
		(net "M_B_CPU0_SA_CA<3>")
	)
	(segment
		(start 324.435978 -254.080772)
		(end 324.95363 -254.080772)
		(width 0.0889)
		(layer "In13.Cu")
		(net "M_B_CPU0_SA_CA<3>")
	)
	(segment
		(start 329.819762 -253.87681)
		(end 329.828144 -253.881636)
		(width 0.0889)
		(layer "In13.Cu")
		(net "M_B_CPU0_SA_CA<3>")
	)
	(segment
		(start 302.847502 -252.160024)
		(end 307.54701 -252.160024)
		(width 0.14478)
		(layer "In13.Cu")
		(net "M_B_CPU0_SA_CA<3>")
	)
	(segment
		(start 331.33411 -253.881636)
		(end 331.342492 -253.87681)
		(width 0.0889)
		(layer "In13.Cu")
		(net "M_B_CPU0_SA_CA<3>")
	)
	(segment
		(start 298.373038 -250.460002)
		(end 301.14748 -250.460002)
		(width 0.14478)
		(layer "In13.Cu")
		(net "M_B_CPU0_SA_CA<3>")
	)
	(segment
		(start 325.693278 -253.881636)
		(end 325.704962 -253.874778)
		(width 0.0889)
		(layer "In13.Cu")
		(net "M_B_CPU0_SA_CA<3>")
	)
	(segment
		(start 336.034126 -253.881636)
		(end 336.042508 -253.87681)
		(width 0.0889)
		(layer "In13.Cu")
		(net "M_B_CPU0_SA_CA<3>")
	)
	(segment
		(start 327.007474 -253.881636)
		(end 327.017888 -253.887732)
		(width 0.0889)
		(layer "In13.Cu")
		(net "M_B_CPU0_SA_CA<3>")
	)
	(segment
		(start 321.394074 -254.30099)
		(end 323.895974 -254.30099)
		(width 0.14478)
		(layer "In13.Cu")
		(net "M_B_CPU0_SA_CA<3>")
	)
	(segment
		(start 308.724046 -253.33706)
		(end 320.430144 -253.33706)
		(width 0.14478)
		(layer "In13.Cu")
		(net "M_B_CPU0_SA_CA<3>")
	)
	(segment
		(start 323.895974 -254.30099)
		(end 324.21576 -254.30099)
		(width 0.0889)
		(layer "In13.Cu")
		(net "M_B_CPU0_SA_CA<3>")
	)
	(segment
		(start 337.0072 -253.938786)
		(end 337.161124 -254.204216)
		(width 0.0889)
		(layer "In13.Cu")
		(net "M_B_CPU0_SA_CA<3>")
	)
	(segment
		(start 307.54701 -252.160024)
		(end 308.724046 -253.33706)
		(width 0.14478)
		(layer "In13.Cu")
		(net "M_B_CPU0_SA_CA<3>")
	)
	(arc
		(start 328.88809 -253.881636)
		(mid 329.171046 -253.957813)
		(end 329.454002 -253.881636)
		(width 0.0889)
		(layer "In13.Cu")
		(net "M_B_CPU0_SA_CA<3>")
	)
	(arc
		(start 328.514202 -253.881636)
		(mid 328.701146 -253.831381)
		(end 328.88809 -253.881636)
		(width 0.0889)
		(layer "In13.Cu")
		(net "M_B_CPU0_SA_CA<3>")
	)
	(arc
		(start 330.768198 -253.881636)
		(mid 331.051154 -253.957813)
		(end 331.33411 -253.881636)
		(width 0.0889)
		(layer "In13.Cu")
		(net "M_B_CPU0_SA_CA<3>")
	)
	(arc
		(start 333.213964 -253.881636)
		(mid 333.396215 -253.831286)
		(end 333.579724 -253.87681)
		(width 0.0889)
		(layer "In13.Cu")
		(net "M_B_CPU0_SA_CA<3>")
	)
	(arc
		(start 330.402438 -253.87681)
		(mid 330.585946 -253.831316)
		(end 330.768198 -253.881636)
		(width 0.0889)
		(layer "In13.Cu")
		(net "M_B_CPU0_SA_CA<3>")
	)
	(arc
		(start 331.708252 -253.881636)
		(mid 331.991208 -253.957813)
		(end 332.274164 -253.881636)
		(width 0.0889)
		(layer "In13.Cu")
		(net "M_B_CPU0_SA_CA<3>")
	)
	(arc
		(start 334.52816 -253.881636)
		(mid 334.811116 -253.957813)
		(end 335.094072 -253.881636)
		(width 0.0889)
		(layer "In13.Cu")
		(net "M_B_CPU0_SA_CA<3>")
	)
	(arc
		(start 329.454002 -253.881636)
		(mid 329.636253 -253.831286)
		(end 329.819762 -253.87681)
		(width 0.0889)
		(layer "In13.Cu")
		(net "M_B_CPU0_SA_CA<3>")
	)
	(arc
		(start 329.828144 -253.881636)
		(mid 330.1111 -253.957813)
		(end 330.394056 -253.881636)
		(width 0.0889)
		(layer "In13.Cu")
		(net "M_B_CPU0_SA_CA<3>")
	)
	(arc
		(start 332.274164 -253.881636)
		(mid 332.461108 -253.831381)
		(end 332.648052 -253.881636)
		(width 0.0889)
		(layer "In13.Cu")
		(net "M_B_CPU0_SA_CA<3>")
	)
	(arc
		(start 336.042508 -253.87681)
		(mid 336.226016 -253.831316)
		(end 336.408268 -253.881636)
		(width 0.0889)
		(layer "In13.Cu")
		(net "M_B_CPU0_SA_CA<3>")
	)
	(arc
		(start 324.95363 -254.080772)
		(mid 325.336623 -254.030117)
		(end 325.693278 -253.881636)
		(width 0.0889)
		(layer "In13.Cu")
		(net "M_B_CPU0_SA_CA<3>")
	)
	(arc
		(start 327.017888 -253.887732)
		(mid 327.296574 -253.957952)
		(end 327.57364 -253.881636)
		(width 0.0889)
		(layer "In13.Cu")
		(net "M_B_CPU0_SA_CA<3>")
	)
	(arc
		(start 336.408268 -253.881636)
		(mid 336.655981 -253.956856)
		(end 336.911188 -253.913386)
		(width 0.0889)
		(layer "In13.Cu")
		(net "M_B_CPU0_SA_CA<3>")
	)
	(arc
		(start 327.94829 -253.881636)
		(mid 328.231246 -253.957813)
		(end 328.514202 -253.881636)
		(width 0.0889)
		(layer "In13.Cu")
		(net "M_B_CPU0_SA_CA<3>")
	)
	(arc
		(start 332.648052 -253.881636)
		(mid 332.931008 -253.957813)
		(end 333.213964 -253.881636)
		(width 0.0889)
		(layer "In13.Cu")
		(net "M_B_CPU0_SA_CA<3>")
	)
	(arc
		(start 327.57364 -253.881636)
		(mid 327.756145 -253.831159)
		(end 327.939908 -253.87681)
		(width 0.0889)
		(layer "In13.Cu")
		(net "M_B_CPU0_SA_CA<3>")
	)
	(arc
		(start 335.102454 -253.87681)
		(mid 335.285962 -253.831316)
		(end 335.468214 -253.881636)
		(width 0.0889)
		(layer "In13.Cu")
		(net "M_B_CPU0_SA_CA<3>")
	)
	(arc
		(start 334.154018 -253.881636)
		(mid 334.336269 -253.831286)
		(end 334.519778 -253.87681)
		(width 0.0889)
		(layer "In13.Cu")
		(net "M_B_CPU0_SA_CA<3>")
	)
	(arc
		(start 333.588106 -253.881636)
		(mid 333.871062 -253.957813)
		(end 334.154018 -253.881636)
		(width 0.0889)
		(layer "In13.Cu")
		(net "M_B_CPU0_SA_CA<3>")
	)
	(arc
		(start 326.649842 -253.872492)
		(mid 326.829824 -253.831392)
		(end 327.007474 -253.881636)
		(width 0.0889)
		(layer "In13.Cu")
		(net "M_B_CPU0_SA_CA<3>")
	)
	(arc
		(start 325.704962 -253.874778)
		(mid 325.887217 -253.831125)
		(end 326.067674 -253.881636)
		(width 0.0889)
		(layer "In13.Cu")
		(net "M_B_CPU0_SA_CA<3>")
	)
	(arc
		(start 331.342492 -253.87681)
		(mid 331.526 -253.831316)
		(end 331.708252 -253.881636)
		(width 0.0889)
		(layer "In13.Cu")
		(net "M_B_CPU0_SA_CA<3>")
	)
	(arc
		(start 335.468214 -253.881636)
		(mid 335.75117 -253.957813)
		(end 336.034126 -253.881636)
		(width 0.0889)
		(layer "In13.Cu")
		(net "M_B_CPU0_SA_CA<3>")
	)
	(arc
		(start 326.067674 -253.881636)
		(mid 326.341529 -253.957986)
		(end 326.617838 -253.891034)
		(width 0.0889)
		(layer "In13.Cu")
		(net "M_B_CPU0_SA_CA<3>")
	)
	(segment
		(start 337.158076 -253.660148)
		(end 336.691224 -253.39421)
		(width 0.10668)
		(layer "F.Cu")
		(net "M_B_CPU0_SA_CA<2>")
	)
	(segment
		(start 328.984102 -253.71679)
		(end 328.992484 -253.721616)
		(width 0.0889)
		(layer "In13.Cu")
		(net "M_B_CPU0_SA_CA<2>")
	)
	(segment
		(start 302.91405 -251.309886)
		(end 303.454054 -251.309886)
		(width 0.14478)
		(layer "In13.Cu")
		(net "M_B_CPU0_SA_CA<2>")
	)
	(segment
		(start 306.499514 -251.309886)
		(end 307.552598 -251.309886)
		(width 0.14478)
		(layer "In13.Cu")
		(net "M_B_CPU0_SA_CA<2>")
	)
	(segment
		(start 299.82414 -249.185176)
		(end 300.158658 -249.519694)
		(width 0.14478)
		(layer "In13.Cu")
		(net "M_B_CPU0_SA_CA<2>")
	)
	(segment
		(start 300.158658 -249.519694)
		(end 301.123858 -249.519694)
		(width 0.14478)
		(layer "In13.Cu")
		(net "M_B_CPU0_SA_CA<2>")
	)
	(segment
		(start 325.597266 -253.71679)
		(end 325.611998 -253.708154)
		(width 0.0889)
		(layer "In13.Cu")
		(net "M_B_CPU0_SA_CA<2>")
	)
	(segment
		(start 336.822796 -253.742952)
		(end 336.845148 -253.65964)
		(width 0.0889)
		(layer "In13.Cu")
		(net "M_B_CPU0_SA_CA<2>")
	)
	(segment
		(start 305.252374 -251.521976)
		(end 305.252374 -251.454666)
		(width 0.14478)
		(layer "In13.Cu")
		(net "M_B_CPU0_SA_CA<2>")
	)
	(segment
		(start 332.744064 -253.71679)
		(end 332.752446 -253.721616)
		(width 0.0889)
		(layer "In13.Cu")
		(net "M_B_CPU0_SA_CA<2>")
	)
	(segment
		(start 306.209954 -251.666756)
		(end 306.354734 -251.521976)
		(width 0.14478)
		(layer "In13.Cu")
		(net "M_B_CPU0_SA_CA<2>")
	)
	(segment
		(start 304.556414 -251.309886)
		(end 304.701194 -251.454666)
		(width 0.14478)
		(layer "In13.Cu")
		(net "M_B_CPU0_SA_CA<2>")
	)
	(segment
		(start 326.537828 -253.716536)
		(end 326.543416 -253.713234)
		(width 0.0889)
		(layer "In13.Cu")
		(net "M_B_CPU0_SA_CA<2>")
	)
	(segment
		(start 304.845974 -251.666756)
		(end 305.107594 -251.666756)
		(width 0.14478)
		(layer "In13.Cu")
		(net "M_B_CPU0_SA_CA<2>")
	)
	(segment
		(start 321.580002 -253.84379)
		(end 323.901054 -253.84379)
		(width 0.14478)
		(layer "In13.Cu")
		(net "M_B_CPU0_SA_CA<2>")
	)
	(segment
		(start 331.229716 -253.721616)
		(end 331.238098 -253.71679)
		(width 0.0889)
		(layer "In13.Cu")
		(net "M_B_CPU0_SA_CA<2>")
	)
	(segment
		(start 323.901054 -253.84379)
		(end 324.18528 -253.84379)
		(width 0.0889)
		(layer "In13.Cu")
		(net "M_B_CPU0_SA_CA<2>")
	)
	(segment
		(start 306.354734 -251.454666)
		(end 306.499514 -251.309886)
		(width 0.14478)
		(layer "In13.Cu")
		(net "M_B_CPU0_SA_CA<2>")
	)
	(segment
		(start 327.103232 -253.71679)
		(end 327.111614 -253.721616)
		(width 0.0889)
		(layer "In13.Cu")
		(net "M_B_CPU0_SA_CA<2>")
	)
	(segment
		(start 332.16977 -253.721616)
		(end 332.178152 -253.71679)
		(width 0.0889)
		(layer "In13.Cu")
		(net "M_B_CPU0_SA_CA<2>")
	)
	(segment
		(start 305.397154 -251.309886)
		(end 305.658774 -251.309886)
		(width 0.14478)
		(layer "In13.Cu")
		(net "M_B_CPU0_SA_CA<2>")
	)
	(segment
		(start 303.743614 -251.666756)
		(end 304.005234 -251.666756)
		(width 0.14478)
		(layer "In13.Cu")
		(net "M_B_CPU0_SA_CA<2>")
	)
	(segment
		(start 320.618612 -252.8824)
		(end 321.580002 -253.84379)
		(width 0.14478)
		(layer "In13.Cu")
		(net "M_B_CPU0_SA_CA<2>")
	)
	(segment
		(start 304.294794 -251.309886)
		(end 304.556414 -251.309886)
		(width 0.14478)
		(layer "In13.Cu")
		(net "M_B_CPU0_SA_CA<2>")
	)
	(segment
		(start 336.845148 -253.65964)
		(end 336.691224 -253.39421)
		(width 0.0889)
		(layer "In13.Cu")
		(net "M_B_CPU0_SA_CA<2>")
	)
	(segment
		(start 304.150014 -251.454666)
		(end 304.294794 -251.309886)
		(width 0.14478)
		(layer "In13.Cu")
		(net "M_B_CPU0_SA_CA<2>")
	)
	(segment
		(start 309.125112 -252.8824)
		(end 320.618612 -252.8824)
		(width 0.14478)
		(layer "In13.Cu")
		(net "M_B_CPU0_SA_CA<2>")
	)
	(segment
		(start 324.261734 -253.767336)
		(end 325.409814 -253.767336)
		(width 0.0889)
		(layer "In13.Cu")
		(net "M_B_CPU0_SA_CA<2>")
	)
	(segment
		(start 333.684118 -253.71679)
		(end 333.6925 -253.721616)
		(width 0.0889)
		(layer "In13.Cu")
		(net "M_B_CPU0_SA_CA<2>")
	)
	(segment
		(start 325.409814 -253.767336)
		(end 325.410068 -253.767082)
		(width 0.0889)
		(layer "In13.Cu")
		(net "M_B_CPU0_SA_CA<2>")
	)
	(segment
		(start 328.033634 -253.710694)
		(end 328.044048 -253.71679)
		(width 0.0889)
		(layer "In13.Cu")
		(net "M_B_CPU0_SA_CA<2>")
	)
	(segment
		(start 335.929732 -253.721616)
		(end 335.938114 -253.71679)
		(width 0.0889)
		(layer "In13.Cu")
		(net "M_B_CPU0_SA_CA<2>")
	)
	(segment
		(start 306.354734 -251.521976)
		(end 306.354734 -251.454666)
		(width 0.14478)
		(layer "In13.Cu")
		(net "M_B_CPU0_SA_CA<2>")
	)
	(segment
		(start 301.123858 -249.519694)
		(end 302.91405 -251.309886)
		(width 0.14478)
		(layer "In13.Cu")
		(net "M_B_CPU0_SA_CA<2>")
	)
	(segment
		(start 307.552598 -251.309886)
		(end 309.125112 -252.8824)
		(width 0.14478)
		(layer "In13.Cu")
		(net "M_B_CPU0_SA_CA<2>")
	)
	(segment
		(start 326.51954 -253.72695)
		(end 326.537828 -253.716536)
		(width 0.0889)
		(layer "In13.Cu")
		(net "M_B_CPU0_SA_CA<2>")
	)
	(segment
		(start 305.803554 -251.521976)
		(end 305.948334 -251.666756)
		(width 0.14478)
		(layer "In13.Cu")
		(net "M_B_CPU0_SA_CA<2>")
	)
	(segment
		(start 328.409808 -253.721616)
		(end 328.41819 -253.71679)
		(width 0.0889)
		(layer "In13.Cu")
		(net "M_B_CPU0_SA_CA<2>")
	)
	(segment
		(start 303.598834 -251.521976)
		(end 303.743614 -251.666756)
		(width 0.14478)
		(layer "In13.Cu")
		(net "M_B_CPU0_SA_CA<2>")
	)
	(segment
		(start 305.948334 -251.666756)
		(end 306.209954 -251.666756)
		(width 0.14478)
		(layer "In13.Cu")
		(net "M_B_CPU0_SA_CA<2>")
	)
	(segment
		(start 305.803554 -251.454666)
		(end 305.803554 -251.521976)
		(width 0.14478)
		(layer "In13.Cu")
		(net "M_B_CPU0_SA_CA<2>")
	)
	(segment
		(start 303.454054 -251.309886)
		(end 303.598834 -251.454666)
		(width 0.14478)
		(layer "In13.Cu")
		(net "M_B_CPU0_SA_CA<2>")
	)
	(segment
		(start 305.658774 -251.309886)
		(end 305.803554 -251.454666)
		(width 0.14478)
		(layer "In13.Cu")
		(net "M_B_CPU0_SA_CA<2>")
	)
	(segment
		(start 304.150014 -251.521976)
		(end 304.150014 -251.454666)
		(width 0.14478)
		(layer "In13.Cu")
		(net "M_B_CPU0_SA_CA<2>")
	)
	(segment
		(start 303.598834 -251.454666)
		(end 303.598834 -251.521976)
		(width 0.14478)
		(layer "In13.Cu")
		(net "M_B_CPU0_SA_CA<2>")
	)
	(segment
		(start 324.18528 -253.84379)
		(end 324.261734 -253.767336)
		(width 0.0889)
		(layer "In13.Cu")
		(net "M_B_CPU0_SA_CA<2>")
	)
	(segment
		(start 304.701194 -251.454666)
		(end 304.701194 -251.521976)
		(width 0.14478)
		(layer "In13.Cu")
		(net "M_B_CPU0_SA_CA<2>")
	)
	(segment
		(start 305.107594 -251.666756)
		(end 305.252374 -251.521976)
		(width 0.14478)
		(layer "In13.Cu")
		(net "M_B_CPU0_SA_CA<2>")
	)
	(segment
		(start 304.701194 -251.521976)
		(end 304.845974 -251.666756)
		(width 0.14478)
		(layer "In13.Cu")
		(net "M_B_CPU0_SA_CA<2>")
	)
	(segment
		(start 304.005234 -251.666756)
		(end 304.150014 -251.521976)
		(width 0.14478)
		(layer "In13.Cu")
		(net "M_B_CPU0_SA_CA<2>")
	)
	(segment
		(start 305.252374 -251.454666)
		(end 305.397154 -251.309886)
		(width 0.14478)
		(layer "In13.Cu")
		(net "M_B_CPU0_SA_CA<2>")
	)
	(arc
		(start 328.044048 -253.71679)
		(mid 328.226299 -253.76714)
		(end 328.409808 -253.721616)
		(width 0.0889)
		(layer "In13.Cu")
		(net "M_B_CPU0_SA_CA<2>")
	)
	(arc
		(start 331.238098 -253.71679)
		(mid 331.521054 -253.640613)
		(end 331.80401 -253.71679)
		(width 0.0889)
		(layer "In13.Cu")
		(net "M_B_CPU0_SA_CA<2>")
	)
	(arc
		(start 333.118206 -253.71679)
		(mid 333.401162 -253.640613)
		(end 333.684118 -253.71679)
		(width 0.0889)
		(layer "In13.Cu")
		(net "M_B_CPU0_SA_CA<2>")
	)
	(arc
		(start 334.99806 -253.71679)
		(mid 335.281016 -253.640613)
		(end 335.563972 -253.71679)
		(width 0.0889)
		(layer "In13.Cu")
		(net "M_B_CPU0_SA_CA<2>")
	)
	(arc
		(start 335.938114 -253.71679)
		(mid 336.22107 -253.640613)
		(end 336.504026 -253.71679)
		(width 0.0889)
		(layer "In13.Cu")
		(net "M_B_CPU0_SA_CA<2>")
	)
	(arc
		(start 325.611998 -253.708154)
		(mid 325.888981 -253.64035)
		(end 326.163686 -253.71679)
		(width 0.0889)
		(layer "In13.Cu")
		(net "M_B_CPU0_SA_CA<2>")
	)
	(arc
		(start 325.410068 -253.767082)
		(mid 325.507 -253.754331)
		(end 325.597266 -253.71679)
		(width 0.0889)
		(layer "In13.Cu")
		(net "M_B_CPU0_SA_CA<2>")
	)
	(arc
		(start 333.6925 -253.721616)
		(mid 333.876008 -253.76711)
		(end 334.05826 -253.71679)
		(width 0.0889)
		(layer "In13.Cu")
		(net "M_B_CPU0_SA_CA<2>")
	)
	(arc
		(start 326.163686 -253.71679)
		(mid 326.340314 -253.767023)
		(end 326.51954 -253.72695)
		(width 0.0889)
		(layer "In13.Cu")
		(net "M_B_CPU0_SA_CA<2>")
	)
	(arc
		(start 331.80401 -253.71679)
		(mid 331.986261 -253.76714)
		(end 332.16977 -253.721616)
		(width 0.0889)
		(layer "In13.Cu")
		(net "M_B_CPU0_SA_CA<2>")
	)
	(arc
		(start 327.111614 -253.721616)
		(mid 327.295376 -253.767232)
		(end 327.477882 -253.71679)
		(width 0.0889)
		(layer "In13.Cu")
		(net "M_B_CPU0_SA_CA<2>")
	)
	(arc
		(start 334.624172 -253.71679)
		(mid 334.811116 -253.767045)
		(end 334.99806 -253.71679)
		(width 0.0889)
		(layer "In13.Cu")
		(net "M_B_CPU0_SA_CA<2>")
	)
	(arc
		(start 330.298044 -253.71679)
		(mid 330.581 -253.640613)
		(end 330.863956 -253.71679)
		(width 0.0889)
		(layer "In13.Cu")
		(net "M_B_CPU0_SA_CA<2>")
	)
	(arc
		(start 334.05826 -253.71679)
		(mid 334.341216 -253.640613)
		(end 334.624172 -253.71679)
		(width 0.0889)
		(layer "In13.Cu")
		(net "M_B_CPU0_SA_CA<2>")
	)
	(arc
		(start 332.178152 -253.71679)
		(mid 332.461108 -253.640613)
		(end 332.744064 -253.71679)
		(width 0.0889)
		(layer "In13.Cu")
		(net "M_B_CPU0_SA_CA<2>")
	)
	(arc
		(start 326.543416 -253.713234)
		(mid 326.823805 -253.640565)
		(end 327.103232 -253.71679)
		(width 0.0889)
		(layer "In13.Cu")
		(net "M_B_CPU0_SA_CA<2>")
	)
	(arc
		(start 330.863956 -253.71679)
		(mid 331.046207 -253.76714)
		(end 331.229716 -253.721616)
		(width 0.0889)
		(layer "In13.Cu")
		(net "M_B_CPU0_SA_CA<2>")
	)
	(arc
		(start 336.504026 -253.71679)
		(mid 336.660464 -253.765761)
		(end 336.822796 -253.742952)
		(width 0.0889)
		(layer "In13.Cu")
		(net "M_B_CPU0_SA_CA<2>")
	)
	(arc
		(start 328.41819 -253.71679)
		(mid 328.701146 -253.640613)
		(end 328.984102 -253.71679)
		(width 0.0889)
		(layer "In13.Cu")
		(net "M_B_CPU0_SA_CA<2>")
	)
	(arc
		(start 327.477882 -253.71679)
		(mid 327.754949 -253.640519)
		(end 328.033634 -253.710694)
		(width 0.0889)
		(layer "In13.Cu")
		(net "M_B_CPU0_SA_CA<2>")
	)
	(arc
		(start 329.924156 -253.71679)
		(mid 330.1111 -253.767045)
		(end 330.298044 -253.71679)
		(width 0.0889)
		(layer "In13.Cu")
		(net "M_B_CPU0_SA_CA<2>")
	)
	(arc
		(start 329.358244 -253.71679)
		(mid 329.6412 -253.640613)
		(end 329.924156 -253.71679)
		(width 0.0889)
		(layer "In13.Cu")
		(net "M_B_CPU0_SA_CA<2>")
	)
	(arc
		(start 328.992484 -253.721616)
		(mid 329.175992 -253.76711)
		(end 329.358244 -253.71679)
		(width 0.0889)
		(layer "In13.Cu")
		(net "M_B_CPU0_SA_CA<2>")
	)
	(arc
		(start 335.563972 -253.71679)
		(mid 335.746223 -253.76714)
		(end 335.929732 -253.721616)
		(width 0.0889)
		(layer "In13.Cu")
		(net "M_B_CPU0_SA_CA<2>")
	)
	(arc
		(start 332.752446 -253.721616)
		(mid 332.935954 -253.76711)
		(end 333.118206 -253.71679)
		(width 0.0889)
		(layer "In13.Cu")
		(net "M_B_CPU0_SA_CA<2>")
	)
	(segment
		(start 336.218022 -253.660148)
		(end 335.75117 -253.39421)
		(width 0.10668)
		(layer "F.Cu")
		(net "M_B_CPU0_SA_CA<1>")
	)
	(segment
		(start 325.234808 -253.147322)
		(end 325.883524 -253.147322)
		(width 0.0889)
		(layer "In13.Cu")
		(net "M_B_CPU0_SA_CA<1>")
	)
	(segment
		(start 298.360084 -248.75998)
		(end 301.153068 -248.75998)
		(width 0.14478)
		(layer "In13.Cu")
		(net "M_B_CPU0_SA_CA<1>")
	)
	(segment
		(start 335.500726 -253.10338)
		(end 335.596992 -253.12878)
		(width 0.0889)
		(layer "In13.Cu")
		(net "M_B_CPU0_SA_CA<1>")
	)
	(segment
		(start 309.306468 -252.42774)
		(end 320.810128 -252.42774)
		(width 0.14478)
		(layer "In13.Cu")
		(net "M_B_CPU0_SA_CA<1>")
	)
	(segment
		(start 328.409808 -253.066804)
		(end 328.41819 -253.07163)
		(width 0.0889)
		(layer "In13.Cu")
		(net "M_B_CPU0_SA_CA<1>")
	)
	(segment
		(start 321.763898 -253.38151)
		(end 323.908674 -253.38151)
		(width 0.14478)
		(layer "In13.Cu")
		(net "M_B_CPU0_SA_CA<1>")
	)
	(segment
		(start 325.00062 -253.38151)
		(end 325.234808 -253.147322)
		(width 0.0889)
		(layer "In13.Cu")
		(net "M_B_CPU0_SA_CA<1>")
	)
	(segment
		(start 327.461372 -253.06147)
		(end 327.47966 -253.071884)
		(width 0.0889)
		(layer "In13.Cu")
		(net "M_B_CPU0_SA_CA<1>")
	)
	(segment
		(start 327.47966 -253.071884)
		(end 327.50125 -253.08433)
		(width 0.0889)
		(layer "In13.Cu")
		(net "M_B_CPU0_SA_CA<1>")
	)
	(segment
		(start 332.744064 -253.07163)
		(end 332.752446 -253.066804)
		(width 0.0889)
		(layer "In13.Cu")
		(net "M_B_CPU0_SA_CA<1>")
	)
	(segment
		(start 332.16977 -253.066804)
		(end 332.178152 -253.07163)
		(width 0.0889)
		(layer "In13.Cu")
		(net "M_B_CPU0_SA_CA<1>")
	)
	(segment
		(start 335.596992 -253.12878)
		(end 335.75117 -253.39421)
		(width 0.0889)
		(layer "In13.Cu")
		(net "M_B_CPU0_SA_CA<1>")
	)
	(segment
		(start 295.724072 -248.335038)
		(end 297.935142 -248.335038)
		(width 0.14478)
		(layer "In13.Cu")
		(net "M_B_CPU0_SA_CA<1>")
	)
	(segment
		(start 333.684118 -253.07163)
		(end 333.6925 -253.066804)
		(width 0.0889)
		(layer "In13.Cu")
		(net "M_B_CPU0_SA_CA<1>")
	)
	(segment
		(start 326.16521 -253.071884)
		(end 326.192642 -253.056136)
		(width 0.0889)
		(layer "In13.Cu")
		(net "M_B_CPU0_SA_CA<1>")
	)
	(segment
		(start 331.229716 -253.066804)
		(end 331.238098 -253.07163)
		(width 0.0889)
		(layer "In13.Cu")
		(net "M_B_CPU0_SA_CA<1>")
	)
	(segment
		(start 328.984102 -253.07163)
		(end 328.992484 -253.066804)
		(width 0.0889)
		(layer "In13.Cu")
		(net "M_B_CPU0_SA_CA<1>")
	)
	(segment
		(start 297.935142 -248.335038)
		(end 298.360084 -248.75998)
		(width 0.14478)
		(layer "In13.Cu")
		(net "M_B_CPU0_SA_CA<1>")
	)
	(segment
		(start 323.908674 -253.38151)
		(end 325.00062 -253.38151)
		(width 0.0889)
		(layer "In13.Cu")
		(net "M_B_CPU0_SA_CA<1>")
	)
	(segment
		(start 301.153068 -248.75998)
		(end 302.85309 -250.460002)
		(width 0.14478)
		(layer "In13.Cu")
		(net "M_B_CPU0_SA_CA<1>")
	)
	(segment
		(start 327.083166 -253.085346)
		(end 327.106534 -253.07163)
		(width 0.0889)
		(layer "In13.Cu")
		(net "M_B_CPU0_SA_CA<1>")
	)
	(segment
		(start 302.85309 -250.460002)
		(end 307.33873 -250.460002)
		(width 0.14478)
		(layer "In13.Cu")
		(net "M_B_CPU0_SA_CA<1>")
	)
	(segment
		(start 307.33873 -250.460002)
		(end 309.306468 -252.42774)
		(width 0.14478)
		(layer "In13.Cu")
		(net "M_B_CPU0_SA_CA<1>")
	)
	(segment
		(start 320.810128 -252.42774)
		(end 321.763898 -253.38151)
		(width 0.14478)
		(layer "In13.Cu")
		(net "M_B_CPU0_SA_CA<1>")
	)
	(arc
		(start 329.358244 -253.07163)
		(mid 329.6412 -253.147807)
		(end 329.924156 -253.07163)
		(width 0.0889)
		(layer "In13.Cu")
		(net "M_B_CPU0_SA_CA<1>")
	)
	(arc
		(start 334.05826 -253.07163)
		(mid 334.341216 -253.147807)
		(end 334.624172 -253.07163)
		(width 0.0889)
		(layer "In13.Cu")
		(net "M_B_CPU0_SA_CA<1>")
	)
	(arc
		(start 334.99806 -253.07163)
		(mid 335.245656 -253.146808)
		(end 335.500726 -253.10338)
		(width 0.0889)
		(layer "In13.Cu")
		(net "M_B_CPU0_SA_CA<1>")
	)
	(arc
		(start 328.41819 -253.07163)
		(mid 328.701146 -253.147807)
		(end 328.984102 -253.07163)
		(width 0.0889)
		(layer "In13.Cu")
		(net "M_B_CPU0_SA_CA<1>")
	)
	(arc
		(start 332.752446 -253.066804)
		(mid 332.935954 -253.02131)
		(end 333.118206 -253.07163)
		(width 0.0889)
		(layer "In13.Cu")
		(net "M_B_CPU0_SA_CA<1>")
	)
	(arc
		(start 330.298044 -253.07163)
		(mid 330.581 -253.147807)
		(end 330.863956 -253.07163)
		(width 0.0889)
		(layer "In13.Cu")
		(net "M_B_CPU0_SA_CA<1>")
	)
	(arc
		(start 334.624172 -253.07163)
		(mid 334.811116 -253.021375)
		(end 334.99806 -253.07163)
		(width 0.0889)
		(layer "In13.Cu")
		(net "M_B_CPU0_SA_CA<1>")
	)
	(arc
		(start 325.883524 -253.147322)
		(mid 326.029347 -253.128182)
		(end 326.16521 -253.071884)
		(width 0.0889)
		(layer "In13.Cu")
		(net "M_B_CPU0_SA_CA<1>")
	)
	(arc
		(start 331.238098 -253.07163)
		(mid 331.521054 -253.147807)
		(end 331.80401 -253.07163)
		(width 0.0889)
		(layer "In13.Cu")
		(net "M_B_CPU0_SA_CA<1>")
	)
	(arc
		(start 326.192642 -253.056136)
		(mid 326.367893 -253.021203)
		(end 326.539352 -253.07163)
		(width 0.0889)
		(layer "In13.Cu")
		(net "M_B_CPU0_SA_CA<1>")
	)
	(arc
		(start 331.80401 -253.07163)
		(mid 331.986261 -253.02128)
		(end 332.16977 -253.066804)
		(width 0.0889)
		(layer "In13.Cu")
		(net "M_B_CPU0_SA_CA<1>")
	)
	(arc
		(start 328.992484 -253.066804)
		(mid 329.175992 -253.02131)
		(end 329.358244 -253.07163)
		(width 0.0889)
		(layer "In13.Cu")
		(net "M_B_CPU0_SA_CA<1>")
	)
	(arc
		(start 333.118206 -253.07163)
		(mid 333.401162 -253.147807)
		(end 333.684118 -253.07163)
		(width 0.0889)
		(layer "In13.Cu")
		(net "M_B_CPU0_SA_CA<1>")
	)
	(arc
		(start 327.50125 -253.08433)
		(mid 327.774279 -253.147649)
		(end 328.044048 -253.07163)
		(width 0.0889)
		(layer "In13.Cu")
		(net "M_B_CPU0_SA_CA<1>")
	)
	(arc
		(start 329.924156 -253.07163)
		(mid 330.1111 -253.021375)
		(end 330.298044 -253.07163)
		(width 0.0889)
		(layer "In13.Cu")
		(net "M_B_CPU0_SA_CA<1>")
	)
	(arc
		(start 330.863956 -253.07163)
		(mid 331.046207 -253.02128)
		(end 331.229716 -253.066804)
		(width 0.0889)
		(layer "In13.Cu")
		(net "M_B_CPU0_SA_CA<1>")
	)
	(arc
		(start 326.539352 -253.07163)
		(mid 326.809509 -253.148392)
		(end 327.083166 -253.085346)
		(width 0.0889)
		(layer "In13.Cu")
		(net "M_B_CPU0_SA_CA<1>")
	)
	(arc
		(start 328.044048 -253.07163)
		(mid 328.226299 -253.02128)
		(end 328.409808 -253.066804)
		(width 0.0889)
		(layer "In13.Cu")
		(net "M_B_CPU0_SA_CA<1>")
	)
	(arc
		(start 333.6925 -253.066804)
		(mid 333.876008 -253.02131)
		(end 334.05826 -253.07163)
		(width 0.0889)
		(layer "In13.Cu")
		(net "M_B_CPU0_SA_CA<1>")
	)
	(arc
		(start 332.178152 -253.07163)
		(mid 332.461108 -253.147807)
		(end 332.744064 -253.07163)
		(width 0.0889)
		(layer "In13.Cu")
		(net "M_B_CPU0_SA_CA<1>")
	)
	(arc
		(start 327.106534 -253.07163)
		(mid 327.282654 -253.021652)
		(end 327.461372 -253.06147)
		(width 0.0889)
		(layer "In13.Cu")
		(net "M_B_CPU0_SA_CA<1>")
	)
	(segment
		(start 335.747868 -252.850142)
		(end 335.281016 -252.584204)
		(width 0.10668)
		(layer "F.Cu")
		(net "M_B_CPU0_SA_CA<0>")
	)
	(segment
		(start 306.707286 -249.8598)
		(end 306.707286 -249.754898)
		(width 0.14478)
		(layer "In13.Cu")
		(net "M_B_CPU0_SA_CA<0>")
	)
	(segment
		(start 335.412842 -252.932946)
		(end 335.435194 -252.849634)
		(width 0.0889)
		(layer "In13.Cu")
		(net "M_B_CPU0_SA_CA<0>")
	)
	(segment
		(start 305.604926 -249.754898)
		(end 305.749706 -249.610118)
		(width 0.14478)
		(layer "In13.Cu")
		(net "M_B_CPU0_SA_CA<0>")
	)
	(segment
		(start 305.604926 -249.8598)
		(end 305.604926 -249.754898)
		(width 0.14478)
		(layer "In13.Cu")
		(net "M_B_CPU0_SA_CA<0>")
	)
	(segment
		(start 304.096166 -250.00458)
		(end 304.357786 -250.00458)
		(width 0.14478)
		(layer "In13.Cu")
		(net "M_B_CPU0_SA_CA<0>")
	)
	(segment
		(start 299.82414 -247.62079)
		(end 300.148244 -247.944894)
		(width 0.14478)
		(layer "In13.Cu")
		(net "M_B_CPU0_SA_CA<0>")
	)
	(segment
		(start 308.628288 -250.622816)
		(end 308.70779 -250.543314)
		(width 0.14478)
		(layer "In13.Cu")
		(net "M_B_CPU0_SA_CA<0>")
	)
	(segment
		(start 324.489318 -252.467872)
		(end 324.973188 -252.467872)
		(width 0.0889)
		(layer "In13.Cu")
		(net "M_B_CPU0_SA_CA<0>")
	)
	(segment
		(start 304.502566 -249.8598)
		(end 304.502566 -249.754898)
		(width 0.14478)
		(layer "In13.Cu")
		(net "M_B_CPU0_SA_CA<0>")
	)
	(segment
		(start 304.647346 -249.610118)
		(end 304.908966 -249.610118)
		(width 0.14478)
		(layer "In13.Cu")
		(net "M_B_CPU0_SA_CA<0>")
	)
	(segment
		(start 326.06996 -252.90653)
		(end 326.069706 -252.90653)
		(width 0.0889)
		(layer "In13.Cu")
		(net "M_B_CPU0_SA_CA<0>")
	)
	(segment
		(start 308.3179 -250.153424)
		(end 308.238398 -250.232926)
		(width 0.14478)
		(layer "In13.Cu")
		(net "M_B_CPU0_SA_CA<0>")
	)
	(segment
		(start 306.852066 -249.610118)
		(end 307.979318 -249.610118)
		(width 0.14478)
		(layer "In13.Cu")
		(net "M_B_CPU0_SA_CA<0>")
	)
	(segment
		(start 333.579724 -252.91161)
		(end 333.588106 -252.906784)
		(width 0.0889)
		(layer "In13.Cu")
		(net "M_B_CPU0_SA_CA<0>")
	)
	(segment
		(start 306.300886 -250.00458)
		(end 306.562506 -250.00458)
		(width 0.14478)
		(layer "In13.Cu")
		(net "M_B_CPU0_SA_CA<0>")
	)
	(segment
		(start 310.34228 -251.97308)
		(end 320.998596 -251.97308)
		(width 0.14478)
		(layer "In13.Cu")
		(net "M_B_CPU0_SA_CA<0>")
	)
	(segment
		(start 303.806606 -249.610118)
		(end 303.951386 -249.754898)
		(width 0.14478)
		(layer "In13.Cu")
		(net "M_B_CPU0_SA_CA<0>")
	)
	(segment
		(start 299.82414 -247.485154)
		(end 299.82414 -247.62079)
		(width 0.14478)
		(layer "In13.Cu")
		(net "M_B_CPU0_SA_CA<0>")
	)
	(segment
		(start 300.148244 -247.944894)
		(end 301.265082 -247.944894)
		(width 0.14478)
		(layer "In13.Cu")
		(net "M_B_CPU0_SA_CA<0>")
	)
	(segment
		(start 327.57491 -252.90653)
		(end 327.594976 -252.91796)
		(width 0.0889)
		(layer "In13.Cu")
		(net "M_B_CPU0_SA_CA<0>")
	)
	(segment
		(start 326.06996 -252.906784)
		(end 326.06996 -252.90653)
		(width 0.0889)
		(layer "In13.Cu")
		(net "M_B_CPU0_SA_CA<0>")
	)
	(segment
		(start 306.707286 -249.754898)
		(end 306.852066 -249.610118)
		(width 0.14478)
		(layer "In13.Cu")
		(net "M_B_CPU0_SA_CA<0>")
	)
	(segment
		(start 321.749166 -252.72365)
		(end 324.063614 -252.72365)
		(width 0.14478)
		(layer "In13.Cu")
		(net "M_B_CPU0_SA_CA<0>")
	)
	(segment
		(start 335.094072 -252.906784)
		(end 335.102454 -252.91161)
		(width 0.0889)
		(layer "In13.Cu")
		(net "M_B_CPU0_SA_CA<0>")
	)
	(segment
		(start 324.973188 -252.467872)
		(end 325.462138 -252.956822)
		(width 0.0889)
		(layer "In13.Cu")
		(net "M_B_CPU0_SA_CA<0>")
	)
	(segment
		(start 304.908966 -249.610118)
		(end 305.053746 -249.754898)
		(width 0.14478)
		(layer "In13.Cu")
		(net "M_B_CPU0_SA_CA<0>")
	)
	(segment
		(start 308.3179 -249.9487)
		(end 308.3179 -250.153424)
		(width 0.14478)
		(layer "In13.Cu")
		(net "M_B_CPU0_SA_CA<0>")
	)
	(segment
		(start 307.979318 -249.610118)
		(end 308.3179 -249.9487)
		(width 0.14478)
		(layer "In13.Cu")
		(net "M_B_CPU0_SA_CA<0>")
	)
	(segment
		(start 302.930306 -249.610118)
		(end 303.806606 -249.610118)
		(width 0.14478)
		(layer "In13.Cu")
		(net "M_B_CPU0_SA_CA<0>")
	)
	(segment
		(start 305.053746 -249.8598)
		(end 305.198526 -250.00458)
		(width 0.14478)
		(layer "In13.Cu")
		(net "M_B_CPU0_SA_CA<0>")
	)
	(segment
		(start 306.011326 -249.610118)
		(end 306.156106 -249.754898)
		(width 0.14478)
		(layer "In13.Cu")
		(net "M_B_CPU0_SA_CA<0>")
	)
	(segment
		(start 331.33411 -252.906784)
		(end 331.342492 -252.91161)
		(width 0.0889)
		(layer "In13.Cu")
		(net "M_B_CPU0_SA_CA<0>")
	)
	(segment
		(start 305.460146 -250.00458)
		(end 305.604926 -249.8598)
		(width 0.14478)
		(layer "In13.Cu")
		(net "M_B_CPU0_SA_CA<0>")
	)
	(segment
		(start 308.238398 -250.43765)
		(end 308.423564 -250.622816)
		(width 0.14478)
		(layer "In13.Cu")
		(net "M_B_CPU0_SA_CA<0>")
	)
	(segment
		(start 306.156106 -249.8598)
		(end 306.300886 -250.00458)
		(width 0.14478)
		(layer "In13.Cu")
		(net "M_B_CPU0_SA_CA<0>")
	)
	(segment
		(start 326.991726 -252.917706)
		(end 327.010522 -252.906784)
		(width 0.0889)
		(layer "In13.Cu")
		(net "M_B_CPU0_SA_CA<0>")
	)
	(segment
		(start 304.502566 -249.754898)
		(end 304.647346 -249.610118)
		(width 0.14478)
		(layer "In13.Cu")
		(net "M_B_CPU0_SA_CA<0>")
	)
	(segment
		(start 335.435194 -252.849634)
		(end 335.281016 -252.584204)
		(width 0.0889)
		(layer "In13.Cu")
		(net "M_B_CPU0_SA_CA<0>")
	)
	(segment
		(start 334.519778 -252.91161)
		(end 334.52816 -252.906784)
		(width 0.0889)
		(layer "In13.Cu")
		(net "M_B_CPU0_SA_CA<0>")
	)
	(segment
		(start 305.053746 -249.754898)
		(end 305.053746 -249.8598)
		(width 0.14478)
		(layer "In13.Cu")
		(net "M_B_CPU0_SA_CA<0>")
	)
	(segment
		(start 304.357786 -250.00458)
		(end 304.502566 -249.8598)
		(width 0.14478)
		(layer "In13.Cu")
		(net "M_B_CPU0_SA_CA<0>")
	)
	(segment
		(start 308.70779 -250.543314)
		(end 308.912514 -250.543314)
		(width 0.14478)
		(layer "In13.Cu")
		(net "M_B_CPU0_SA_CA<0>")
	)
	(segment
		(start 306.156106 -249.754898)
		(end 306.156106 -249.8598)
		(width 0.14478)
		(layer "In13.Cu")
		(net "M_B_CPU0_SA_CA<0>")
	)
	(segment
		(start 330.394056 -252.906784)
		(end 330.402438 -252.91161)
		(width 0.0889)
		(layer "In13.Cu")
		(net "M_B_CPU0_SA_CA<0>")
	)
	(segment
		(start 308.912514 -250.543314)
		(end 310.34228 -251.97308)
		(width 0.14478)
		(layer "In13.Cu")
		(net "M_B_CPU0_SA_CA<0>")
	)
	(segment
		(start 303.951386 -249.8598)
		(end 304.096166 -250.00458)
		(width 0.14478)
		(layer "In13.Cu")
		(net "M_B_CPU0_SA_CA<0>")
	)
	(segment
		(start 305.749706 -249.610118)
		(end 306.011326 -249.610118)
		(width 0.14478)
		(layer "In13.Cu")
		(net "M_B_CPU0_SA_CA<0>")
	)
	(segment
		(start 329.819762 -252.91161)
		(end 329.828144 -252.906784)
		(width 0.0889)
		(layer "In13.Cu")
		(net "M_B_CPU0_SA_CA<0>")
	)
	(segment
		(start 324.063614 -252.72365)
		(end 324.23354 -252.72365)
		(width 0.0889)
		(layer "In13.Cu")
		(net "M_B_CPU0_SA_CA<0>")
	)
	(segment
		(start 320.998596 -251.97308)
		(end 321.749166 -252.72365)
		(width 0.14478)
		(layer "In13.Cu")
		(net "M_B_CPU0_SA_CA<0>")
	)
	(segment
		(start 327.55332 -252.894084)
		(end 327.57491 -252.90653)
		(width 0.0889)
		(layer "In13.Cu")
		(net "M_B_CPU0_SA_CA<0>")
	)
	(segment
		(start 305.198526 -250.00458)
		(end 305.460146 -250.00458)
		(width 0.14478)
		(layer "In13.Cu")
		(net "M_B_CPU0_SA_CA<0>")
	)
	(segment
		(start 308.238398 -250.232926)
		(end 308.238398 -250.43765)
		(width 0.14478)
		(layer "In13.Cu")
		(net "M_B_CPU0_SA_CA<0>")
	)
	(segment
		(start 325.462138 -252.956822)
		(end 325.883778 -252.956822)
		(width 0.0889)
		(layer "In13.Cu")
		(net "M_B_CPU0_SA_CA<0>")
	)
	(segment
		(start 301.265082 -247.944894)
		(end 302.930306 -249.610118)
		(width 0.14478)
		(layer "In13.Cu")
		(net "M_B_CPU0_SA_CA<0>")
	)
	(segment
		(start 303.951386 -249.754898)
		(end 303.951386 -249.8598)
		(width 0.14478)
		(layer "In13.Cu")
		(net "M_B_CPU0_SA_CA<0>")
	)
	(segment
		(start 324.23354 -252.72365)
		(end 324.489318 -252.467872)
		(width 0.0889)
		(layer "In13.Cu")
		(net "M_B_CPU0_SA_CA<0>")
	)
	(segment
		(start 308.423564 -250.622816)
		(end 308.628288 -250.622816)
		(width 0.14478)
		(layer "In13.Cu")
		(net "M_B_CPU0_SA_CA<0>")
	)
	(segment
		(start 326.069706 -252.90653)
		(end 326.101456 -252.888242)
		(width 0.0889)
		(layer "In13.Cu")
		(net "M_B_CPU0_SA_CA<0>")
	)
	(segment
		(start 306.562506 -250.00458)
		(end 306.707286 -249.8598)
		(width 0.14478)
		(layer "In13.Cu")
		(net "M_B_CPU0_SA_CA<0>")
	)
	(arc
		(start 334.154018 -252.906784)
		(mid 334.336269 -252.957134)
		(end 334.519778 -252.91161)
		(width 0.0889)
		(layer "In13.Cu")
		(net "M_B_CPU0_SA_CA<0>")
	)
	(arc
		(start 333.588106 -252.906784)
		(mid 333.871062 -252.830607)
		(end 334.154018 -252.906784)
		(width 0.0889)
		(layer "In13.Cu")
		(net "M_B_CPU0_SA_CA<0>")
	)
	(arc
		(start 329.454002 -252.906784)
		(mid 329.636253 -252.957134)
		(end 329.819762 -252.91161)
		(width 0.0889)
		(layer "In13.Cu")
		(net "M_B_CPU0_SA_CA<0>")
	)
	(arc
		(start 327.594976 -252.91796)
		(mid 327.773054 -252.956944)
		(end 327.94829 -252.906784)
		(width 0.0889)
		(layer "In13.Cu")
		(net "M_B_CPU0_SA_CA<0>")
	)
	(arc
		(start 334.52816 -252.906784)
		(mid 334.811116 -252.830607)
		(end 335.094072 -252.906784)
		(width 0.0889)
		(layer "In13.Cu")
		(net "M_B_CPU0_SA_CA<0>")
	)
	(arc
		(start 331.708252 -252.906784)
		(mid 331.991208 -252.830607)
		(end 332.274164 -252.906784)
		(width 0.0889)
		(layer "In13.Cu")
		(net "M_B_CPU0_SA_CA<0>")
	)
	(arc
		(start 331.342492 -252.91161)
		(mid 331.526 -252.957104)
		(end 331.708252 -252.906784)
		(width 0.0889)
		(layer "In13.Cu")
		(net "M_B_CPU0_SA_CA<0>")
	)
	(arc
		(start 328.88809 -252.906784)
		(mid 329.171046 -252.830607)
		(end 329.454002 -252.906784)
		(width 0.0889)
		(layer "In13.Cu")
		(net "M_B_CPU0_SA_CA<0>")
	)
	(arc
		(start 330.768198 -252.906784)
		(mid 331.051154 -252.830607)
		(end 331.33411 -252.906784)
		(width 0.0889)
		(layer "In13.Cu")
		(net "M_B_CPU0_SA_CA<0>")
	)
	(arc
		(start 328.514202 -252.906784)
		(mid 328.701146 -252.957039)
		(end 328.88809 -252.906784)
		(width 0.0889)
		(layer "In13.Cu")
		(net "M_B_CPU0_SA_CA<0>")
	)
	(arc
		(start 332.648052 -252.906784)
		(mid 332.931008 -252.830607)
		(end 333.213964 -252.906784)
		(width 0.0889)
		(layer "In13.Cu")
		(net "M_B_CPU0_SA_CA<0>")
	)
	(arc
		(start 332.274164 -252.906784)
		(mid 332.461108 -252.957039)
		(end 332.648052 -252.906784)
		(width 0.0889)
		(layer "In13.Cu")
		(net "M_B_CPU0_SA_CA<0>")
	)
	(arc
		(start 326.635364 -252.906784)
		(mid 326.812155 -252.957503)
		(end 326.991726 -252.917706)
		(width 0.0889)
		(layer "In13.Cu")
		(net "M_B_CPU0_SA_CA<0>")
	)
	(arc
		(start 326.101456 -252.888242)
		(mid 326.370741 -252.83033)
		(end 326.635364 -252.906784)
		(width 0.0889)
		(layer "In13.Cu")
		(net "M_B_CPU0_SA_CA<0>")
	)
	(arc
		(start 327.010522 -252.906784)
		(mid 327.280291 -252.830761)
		(end 327.55332 -252.894084)
		(width 0.0889)
		(layer "In13.Cu")
		(net "M_B_CPU0_SA_CA<0>")
	)
	(arc
		(start 330.402438 -252.91161)
		(mid 330.585946 -252.957104)
		(end 330.768198 -252.906784)
		(width 0.0889)
		(layer "In13.Cu")
		(net "M_B_CPU0_SA_CA<0>")
	)
	(arc
		(start 329.828144 -252.906784)
		(mid 330.1111 -252.830607)
		(end 330.394056 -252.906784)
		(width 0.0889)
		(layer "In13.Cu")
		(net "M_B_CPU0_SA_CA<0>")
	)
	(arc
		(start 327.94829 -252.906784)
		(mid 328.231246 -252.830607)
		(end 328.514202 -252.906784)
		(width 0.0889)
		(layer "In13.Cu")
		(net "M_B_CPU0_SA_CA<0>")
	)
	(arc
		(start 325.883778 -252.956822)
		(mid 325.980169 -252.944071)
		(end 326.06996 -252.906784)
		(width 0.0889)
		(layer "In13.Cu")
		(net "M_B_CPU0_SA_CA<0>")
	)
	(arc
		(start 333.213964 -252.906784)
		(mid 333.396215 -252.957134)
		(end 333.579724 -252.91161)
		(width 0.0889)
		(layer "In13.Cu")
		(net "M_B_CPU0_SA_CA<0>")
	)
	(arc
		(start 335.102454 -252.91161)
		(mid 335.255324 -252.956251)
		(end 335.412842 -252.932946)
		(width 0.0889)
		(layer "In13.Cu")
		(net "M_B_CPU0_SA_CA<0>")
	)
	(segment
		(start 337.627976 -251.23013)
		(end 337.161124 -250.964192)
		(width 0.10668)
		(layer "F.Cu")
		(net "M_B_CPU0_RESET_N")
	)
	(segment
		(start 324.25386 -250.83389)
		(end 324.316598 -250.771152)
		(width 0.0889)
		(layer "In13.Cu")
		(net "M_B_CPU0_RESET_N")
	)
	(segment
		(start 337.0072 -250.698762)
		(end 337.161124 -250.964192)
		(width 0.0889)
		(layer "In13.Cu")
		(net "M_B_CPU0_RESET_N")
	)
	(segment
		(start 331.33411 -250.641612)
		(end 331.342492 -250.636786)
		(width 0.0889)
		(layer "In13.Cu")
		(net "M_B_CPU0_RESET_N")
	)
	(segment
		(start 336.034126 -250.641612)
		(end 336.042508 -250.636786)
		(width 0.0889)
		(layer "In13.Cu")
		(net "M_B_CPU0_RESET_N")
	)
	(segment
		(start 321.68465 -250.31827)
		(end 322.20027 -250.83389)
		(width 0.11684)
		(layer "In13.Cu")
		(net "M_B_CPU0_RESET_N")
	)
	(segment
		(start 302.138588 -245.36019)
		(end 302.988472 -246.210074)
		(width 0.11684)
		(layer "In13.Cu")
		(net "M_B_CPU0_RESET_N")
	)
	(segment
		(start 302.988472 -246.210074)
		(end 303.611026 -246.210074)
		(width 0.11684)
		(layer "In13.Cu")
		(net "M_B_CPU0_RESET_N")
	)
	(segment
		(start 324.316598 -250.771152)
		(end 326.451468 -250.771152)
		(width 0.0889)
		(layer "In13.Cu")
		(net "M_B_CPU0_RESET_N")
	)
	(segment
		(start 304.46091 -247.059958)
		(end 308.038754 -247.059958)
		(width 0.11684)
		(layer "In13.Cu")
		(net "M_B_CPU0_RESET_N")
	)
	(segment
		(start 298.291758 -244.934994)
		(end 298.716954 -245.36019)
		(width 0.11684)
		(layer "In13.Cu")
		(net "M_B_CPU0_RESET_N")
	)
	(segment
		(start 333.579724 -250.636786)
		(end 333.588106 -250.641612)
		(width 0.0889)
		(layer "In13.Cu")
		(net "M_B_CPU0_RESET_N")
	)
	(segment
		(start 311.297066 -250.31827)
		(end 321.68465 -250.31827)
		(width 0.11684)
		(layer "In13.Cu")
		(net "M_B_CPU0_RESET_N")
	)
	(segment
		(start 308.038754 -247.059958)
		(end 311.297066 -250.31827)
		(width 0.11684)
		(layer "In13.Cu")
		(net "M_B_CPU0_RESET_N")
	)
	(segment
		(start 326.531732 -250.737878)
		(end 326.595232 -250.674378)
		(width 0.0889)
		(layer "In13.Cu")
		(net "M_B_CPU0_RESET_N")
	)
	(segment
		(start 295.724072 -244.934994)
		(end 298.291758 -244.934994)
		(width 0.11684)
		(layer "In13.Cu")
		(net "M_B_CPU0_RESET_N")
	)
	(segment
		(start 303.611026 -246.210074)
		(end 304.46091 -247.059958)
		(width 0.11684)
		(layer "In13.Cu")
		(net "M_B_CPU0_RESET_N")
	)
	(segment
		(start 327.574148 -250.641612)
		(end 327.58253 -250.636786)
		(width 0.0889)
		(layer "In13.Cu")
		(net "M_B_CPU0_RESET_N")
	)
	(segment
		(start 322.20027 -250.83389)
		(end 323.954394 -250.83389)
		(width 0.11684)
		(layer "In13.Cu")
		(net "M_B_CPU0_RESET_N")
	)
	(segment
		(start 329.819762 -250.636786)
		(end 329.828144 -250.641612)
		(width 0.0889)
		(layer "In13.Cu")
		(net "M_B_CPU0_RESET_N")
	)
	(segment
		(start 323.954394 -250.83389)
		(end 324.25386 -250.83389)
		(width 0.0889)
		(layer "In13.Cu")
		(net "M_B_CPU0_RESET_N")
	)
	(segment
		(start 334.519778 -250.636786)
		(end 334.52816 -250.641612)
		(width 0.0889)
		(layer "In13.Cu")
		(net "M_B_CPU0_RESET_N")
	)
	(segment
		(start 336.911188 -250.673362)
		(end 337.0072 -250.698762)
		(width 0.0889)
		(layer "In13.Cu")
		(net "M_B_CPU0_RESET_N")
	)
	(segment
		(start 298.716954 -245.36019)
		(end 302.138588 -245.36019)
		(width 0.11684)
		(layer "In13.Cu")
		(net "M_B_CPU0_RESET_N")
	)
	(segment
		(start 335.094072 -250.641612)
		(end 335.102454 -250.636786)
		(width 0.0889)
		(layer "In13.Cu")
		(net "M_B_CPU0_RESET_N")
	)
	(segment
		(start 330.394056 -250.641612)
		(end 330.402438 -250.636786)
		(width 0.0889)
		(layer "In13.Cu")
		(net "M_B_CPU0_RESET_N")
	)
	(arc
		(start 333.588106 -250.641612)
		(mid 333.871062 -250.717789)
		(end 334.154018 -250.641612)
		(width 0.0889)
		(layer "In13.Cu")
		(net "M_B_CPU0_RESET_N")
	)
	(arc
		(start 334.154018 -250.641612)
		(mid 334.336269 -250.591262)
		(end 334.519778 -250.636786)
		(width 0.0889)
		(layer "In13.Cu")
		(net "M_B_CPU0_RESET_N")
	)
	(arc
		(start 335.468214 -250.641612)
		(mid 335.75117 -250.717789)
		(end 336.034126 -250.641612)
		(width 0.0889)
		(layer "In13.Cu")
		(net "M_B_CPU0_RESET_N")
	)
	(arc
		(start 336.042508 -250.636786)
		(mid 336.226016 -250.591292)
		(end 336.408268 -250.641612)
		(width 0.0889)
		(layer "In13.Cu")
		(net "M_B_CPU0_RESET_N")
	)
	(arc
		(start 326.595232 -250.674378)
		(mid 326.629496 -250.645758)
		(end 326.668384 -250.623832)
		(width 0.0889)
		(layer "In13.Cu")
		(net "M_B_CPU0_RESET_N")
	)
	(arc
		(start 326.668384 -250.623832)
		(mid 326.840465 -250.591673)
		(end 327.008236 -250.641612)
		(width 0.0889)
		(layer "In13.Cu")
		(net "M_B_CPU0_RESET_N")
	)
	(arc
		(start 327.94829 -250.641612)
		(mid 328.231246 -250.717789)
		(end 328.514202 -250.641612)
		(width 0.0889)
		(layer "In13.Cu")
		(net "M_B_CPU0_RESET_N")
	)
	(arc
		(start 335.102454 -250.636786)
		(mid 335.285962 -250.591292)
		(end 335.468214 -250.641612)
		(width 0.0889)
		(layer "In13.Cu")
		(net "M_B_CPU0_RESET_N")
	)
	(arc
		(start 330.402438 -250.636786)
		(mid 330.585946 -250.591292)
		(end 330.768198 -250.641612)
		(width 0.0889)
		(layer "In13.Cu")
		(net "M_B_CPU0_RESET_N")
	)
	(arc
		(start 332.274164 -250.641612)
		(mid 332.461108 -250.591357)
		(end 332.648052 -250.641612)
		(width 0.0889)
		(layer "In13.Cu")
		(net "M_B_CPU0_RESET_N")
	)
	(arc
		(start 334.52816 -250.641612)
		(mid 334.811116 -250.717789)
		(end 335.094072 -250.641612)
		(width 0.0889)
		(layer "In13.Cu")
		(net "M_B_CPU0_RESET_N")
	)
	(arc
		(start 328.514202 -250.641612)
		(mid 328.701146 -250.591357)
		(end 328.88809 -250.641612)
		(width 0.0889)
		(layer "In13.Cu")
		(net "M_B_CPU0_RESET_N")
	)
	(arc
		(start 329.828144 -250.641612)
		(mid 330.1111 -250.717789)
		(end 330.394056 -250.641612)
		(width 0.0889)
		(layer "In13.Cu")
		(net "M_B_CPU0_RESET_N")
	)
	(arc
		(start 327.58253 -250.636786)
		(mid 327.766038 -250.591292)
		(end 327.94829 -250.641612)
		(width 0.0889)
		(layer "In13.Cu")
		(net "M_B_CPU0_RESET_N")
	)
	(arc
		(start 331.342492 -250.636786)
		(mid 331.526 -250.591292)
		(end 331.708252 -250.641612)
		(width 0.0889)
		(layer "In13.Cu")
		(net "M_B_CPU0_RESET_N")
	)
	(arc
		(start 327.008236 -250.641612)
		(mid 327.291192 -250.717789)
		(end 327.574148 -250.641612)
		(width 0.0889)
		(layer "In13.Cu")
		(net "M_B_CPU0_RESET_N")
	)
	(arc
		(start 333.213964 -250.641612)
		(mid 333.396215 -250.591262)
		(end 333.579724 -250.636786)
		(width 0.0889)
		(layer "In13.Cu")
		(net "M_B_CPU0_RESET_N")
	)
	(arc
		(start 328.88809 -250.641612)
		(mid 329.171046 -250.717789)
		(end 329.454002 -250.641612)
		(width 0.0889)
		(layer "In13.Cu")
		(net "M_B_CPU0_RESET_N")
	)
	(arc
		(start 330.768198 -250.641612)
		(mid 331.051154 -250.717789)
		(end 331.33411 -250.641612)
		(width 0.0889)
		(layer "In13.Cu")
		(net "M_B_CPU0_RESET_N")
	)
	(arc
		(start 329.454002 -250.641612)
		(mid 329.636253 -250.591262)
		(end 329.819762 -250.636786)
		(width 0.0889)
		(layer "In13.Cu")
		(net "M_B_CPU0_RESET_N")
	)
	(arc
		(start 332.648052 -250.641612)
		(mid 332.931008 -250.717789)
		(end 333.213964 -250.641612)
		(width 0.0889)
		(layer "In13.Cu")
		(net "M_B_CPU0_RESET_N")
	)
	(arc
		(start 326.451468 -250.771152)
		(mid 326.494903 -250.762494)
		(end 326.531732 -250.737878)
		(width 0.0889)
		(layer "In13.Cu")
		(net "M_B_CPU0_RESET_N")
	)
	(arc
		(start 336.408268 -250.641612)
		(mid 336.655981 -250.716832)
		(end 336.911188 -250.673362)
		(width 0.0889)
		(layer "In13.Cu")
		(net "M_B_CPU0_RESET_N")
	)
	(arc
		(start 331.708252 -250.641612)
		(mid 331.991208 -250.717789)
		(end 332.274164 -250.641612)
		(width 0.0889)
		(layer "In13.Cu")
		(net "M_B_CPU0_RESET_N")
	)
	(segment
		(start 335.747868 -256.090166)
		(end 335.281016 -255.824228)
		(width 0.14732)
		(layer "F.Cu")
		(net "M_B_CPU0_CLK_DP<0>")
	)
	(segment
		(start 335.10093 -256.154174)
		(end 335.092548 -256.149348)
		(width 0.09525)
		(layer "In13.Cu")
		(net "M_B_CPU0_CLK_DP<0>")
	)
	(segment
		(start 329.829668 -256.149348)
		(end 329.821286 -256.154174)
		(width 0.09525)
		(layer "In13.Cu")
		(net "M_B_CPU0_CLK_DP<0>")
	)
	(segment
		(start 335.43494 -256.089658)
		(end 335.411572 -256.176526)
		(width 0.09525)
		(layer "In13.Cu")
		(net "M_B_CPU0_CLK_DP<0>")
	)
	(segment
		(start 335.281016 -255.824228)
		(end 335.43494 -256.089658)
		(width 0.09525)
		(layer "In13.Cu")
		(net "M_B_CPU0_CLK_DP<0>")
	)
	(segment
		(start 327.036684 -256.134616)
		(end 327.011284 -256.149348)
		(width 0.09525)
		(layer "In13.Cu")
		(net "M_B_CPU0_CLK_DP<0>")
	)
	(segment
		(start 299.958506 -256.43205)
		(end 297.26255 -253.736094)
		(width 0.16002)
		(layer "In13.Cu")
		(net "M_B_CPU0_CLK_DP<0>")
	)
	(segment
		(start 297.26255 -253.736094)
		(end 296.025062 -253.736094)
		(width 0.16002)
		(layer "In13.Cu")
		(net "M_B_CPU0_CLK_DP<0>")
	)
	(segment
		(start 325.955406 -256.237994)
		(end 324.843648 -257.349752)
		(width 0.09525)
		(layer "In13.Cu")
		(net "M_B_CPU0_CLK_DP<0>")
	)
	(segment
		(start 327.581006 -256.154174)
		(end 327.572624 -256.149348)
		(width 0.09525)
		(layer "In13.Cu")
		(net "M_B_CPU0_CLK_DP<0>")
	)
	(segment
		(start 331.340968 -256.154174)
		(end 331.332586 -256.149348)
		(width 0.09525)
		(layer "In13.Cu")
		(net "M_B_CPU0_CLK_DP<0>")
	)
	(segment
		(start 326.105774 -256.129282)
		(end 326.07123 -256.149348)
		(width 0.09525)
		(layer "In13.Cu")
		(net "M_B_CPU0_CLK_DP<0>")
	)
	(segment
		(start 324.165976 -257.29057)
		(end 324.142354 -257.29057)
		(width 0.09525)
		(layer "In13.Cu")
		(net "M_B_CPU0_CLK_DP<0>")
	)
	(segment
		(start 319.117726 -255.83007)
		(end 313.939174 -255.83007)
		(width 0.16002)
		(layer "In13.Cu")
		(net "M_B_CPU0_CLK_DP<0>")
	)
	(segment
		(start 333.58963 -256.149348)
		(end 333.581248 -256.154174)
		(width 0.09525)
		(layer "In13.Cu")
		(net "M_B_CPU0_CLK_DP<0>")
	)
	(segment
		(start 324.142354 -257.29057)
		(end 320.578226 -257.29057)
		(width 0.16002)
		(layer "In13.Cu")
		(net "M_B_CPU0_CLK_DP<0>")
	)
	(segment
		(start 324.843648 -257.349752)
		(end 324.225158 -257.349752)
		(width 0.09525)
		(layer "In13.Cu")
		(net "M_B_CPU0_CLK_DP<0>")
	)
	(segment
		(start 334.529684 -256.149348)
		(end 334.521302 -256.154174)
		(width 0.09525)
		(layer "In13.Cu")
		(net "M_B_CPU0_CLK_DP<0>")
	)
	(segment
		(start 330.400914 -256.154174)
		(end 330.392532 -256.149348)
		(width 0.09525)
		(layer "In13.Cu")
		(net "M_B_CPU0_CLK_DP<0>")
	)
	(segment
		(start 313.939174 -255.83007)
		(end 313.337194 -256.43205)
		(width 0.16002)
		(layer "In13.Cu")
		(net "M_B_CPU0_CLK_DP<0>")
	)
	(segment
		(start 324.225158 -257.349752)
		(end 324.165976 -257.29057)
		(width 0.09525)
		(layer "In13.Cu")
		(net "M_B_CPU0_CLK_DP<0>")
	)
	(segment
		(start 313.337194 -256.43205)
		(end 299.958506 -256.43205)
		(width 0.16002)
		(layer "In13.Cu")
		(net "M_B_CPU0_CLK_DP<0>")
	)
	(segment
		(start 320.578226 -257.29057)
		(end 319.117726 -255.83007)
		(width 0.16002)
		(layer "In13.Cu")
		(net "M_B_CPU0_CLK_DP<0>")
	)
	(segment
		(start 296.025062 -253.736094)
		(end 295.724072 -253.435104)
		(width 0.16002)
		(layer "In13.Cu")
		(net "M_B_CPU0_CLK_DP<0>")
	)
	(segment
		(start 327.011284 -256.149348)
		(end 326.987408 -256.163064)
		(width 0.09525)
		(layer "In13.Cu")
		(net "M_B_CPU0_CLK_DP<0>")
	)
	(arc
		(start 326.63384 -256.149348)
		(mid 326.372304 -256.073235)
		(end 326.105774 -256.129282)
		(width 0.09525)
		(layer "In13.Cu")
		(net "M_B_CPU0_CLK_DP<0>")
	)
	(arc
		(start 334.521302 -256.154174)
		(mid 334.33627 -256.200088)
		(end 334.152494 -256.149348)
		(width 0.09525)
		(layer "In13.Cu")
		(net "M_B_CPU0_CLK_DP<0>")
	)
	(arc
		(start 328.512678 -256.149348)
		(mid 328.231246 -256.073593)
		(end 327.949814 -256.149348)
		(width 0.09525)
		(layer "In13.Cu")
		(net "M_B_CPU0_CLK_DP<0>")
	)
	(arc
		(start 333.21244 -256.149348)
		(mid 332.931008 -256.073593)
		(end 332.649576 -256.149348)
		(width 0.09525)
		(layer "In13.Cu")
		(net "M_B_CPU0_CLK_DP<0>")
	)
	(arc
		(start 332.27264 -256.149348)
		(mid 331.991208 -256.073593)
		(end 331.709776 -256.149348)
		(width 0.09525)
		(layer "In13.Cu")
		(net "M_B_CPU0_CLK_DP<0>")
	)
	(arc
		(start 335.092548 -256.149348)
		(mid 334.811116 -256.073593)
		(end 334.529684 -256.149348)
		(width 0.09525)
		(layer "In13.Cu")
		(net "M_B_CPU0_CLK_DP<0>")
	)
	(arc
		(start 329.452478 -256.149348)
		(mid 329.171046 -256.073593)
		(end 328.889614 -256.149348)
		(width 0.09525)
		(layer "In13.Cu")
		(net "M_B_CPU0_CLK_DP<0>")
	)
	(arc
		(start 328.889614 -256.149348)
		(mid 328.701146 -256.200025)
		(end 328.512678 -256.149348)
		(width 0.09525)
		(layer "In13.Cu")
		(net "M_B_CPU0_CLK_DP<0>")
	)
	(arc
		(start 327.572624 -256.149348)
		(mid 327.306537 -256.073803)
		(end 327.036684 -256.134616)
		(width 0.09525)
		(layer "In13.Cu")
		(net "M_B_CPU0_CLK_DP<0>")
	)
	(arc
		(start 325.981568 -256.21361)
		(mid 325.968292 -256.225593)
		(end 325.955406 -256.237994)
		(width 0.09525)
		(layer "In13.Cu")
		(net "M_B_CPU0_CLK_DP<0>")
	)
	(arc
		(start 334.152494 -256.149348)
		(mid 333.871062 -256.073593)
		(end 333.58963 -256.149348)
		(width 0.09525)
		(layer "In13.Cu")
		(net "M_B_CPU0_CLK_DP<0>")
	)
	(arc
		(start 329.821286 -256.154174)
		(mid 329.636254 -256.200088)
		(end 329.452478 -256.149348)
		(width 0.09525)
		(layer "In13.Cu")
		(net "M_B_CPU0_CLK_DP<0>")
	)
	(arc
		(start 326.987408 -256.163064)
		(mid 326.808922 -256.200307)
		(end 326.63384 -256.149348)
		(width 0.09525)
		(layer "In13.Cu")
		(net "M_B_CPU0_CLK_DP<0>")
	)
	(arc
		(start 330.392532 -256.149348)
		(mid 330.1111 -256.073593)
		(end 329.829668 -256.149348)
		(width 0.09525)
		(layer "In13.Cu")
		(net "M_B_CPU0_CLK_DP<0>")
	)
	(arc
		(start 333.581248 -256.154174)
		(mid 333.396216 -256.200088)
		(end 333.21244 -256.149348)
		(width 0.09525)
		(layer "In13.Cu")
		(net "M_B_CPU0_CLK_DP<0>")
	)
	(arc
		(start 331.709776 -256.149348)
		(mid 331.526001 -256.20012)
		(end 331.340968 -256.154174)
		(width 0.09525)
		(layer "In13.Cu")
		(net "M_B_CPU0_CLK_DP<0>")
	)
	(arc
		(start 327.949814 -256.149348)
		(mid 327.766039 -256.20012)
		(end 327.581006 -256.154174)
		(width 0.09525)
		(layer "In13.Cu")
		(net "M_B_CPU0_CLK_DP<0>")
	)
	(arc
		(start 326.07123 -256.149348)
		(mid 326.024812 -256.179264)
		(end 325.981568 -256.21361)
		(width 0.09525)
		(layer "In13.Cu")
		(net "M_B_CPU0_CLK_DP<0>")
	)
	(arc
		(start 335.411572 -256.176526)
		(mid 335.253822 -256.199045)
		(end 335.10093 -256.154174)
		(width 0.09525)
		(layer "In13.Cu")
		(net "M_B_CPU0_CLK_DP<0>")
	)
	(arc
		(start 331.332586 -256.149348)
		(mid 331.051154 -256.073593)
		(end 330.769722 -256.149348)
		(width 0.09525)
		(layer "In13.Cu")
		(net "M_B_CPU0_CLK_DP<0>")
	)
	(arc
		(start 330.769722 -256.149348)
		(mid 330.585947 -256.20012)
		(end 330.400914 -256.154174)
		(width 0.09525)
		(layer "In13.Cu")
		(net "M_B_CPU0_CLK_DP<0>")
	)
	(arc
		(start 332.649576 -256.149348)
		(mid 332.461108 -256.200025)
		(end 332.27264 -256.149348)
		(width 0.09525)
		(layer "In13.Cu")
		(net "M_B_CPU0_CLK_DP<0>")
	)
	(segment
		(start 336.218022 -256.900172)
		(end 335.75117 -256.634234)
		(width 0.14732)
		(layer "F.Cu")
		(net "M_B_CPU0_CLK_DN<0>")
	)
	(segment
		(start 326.189086 -256.294636)
		(end 326.163686 -256.309114)
		(width 0.09525)
		(layer "In13.Cu")
		(net "M_B_CPU0_CLK_DN<0>")
	)
	(segment
		(start 320.453004 -257.59283)
		(end 318.992504 -256.13233)
		(width 0.16002)
		(layer "In13.Cu")
		(net "M_B_CPU0_CLK_DN<0>")
	)
	(segment
		(start 295.970706 -254.038354)
		(end 295.724072 -254.284988)
		(width 0.16002)
		(layer "In13.Cu")
		(net "M_B_CPU0_CLK_DN<0>")
	)
	(segment
		(start 297.137328 -254.038354)
		(end 295.970706 -254.038354)
		(width 0.16002)
		(layer "In13.Cu")
		(net "M_B_CPU0_CLK_DN<0>")
	)
	(segment
		(start 328.99096 -256.304288)
		(end 328.982578 -256.309114)
		(width 0.09525)
		(layer "In13.Cu")
		(net "M_B_CPU0_CLK_DN<0>")
	)
	(segment
		(start 299.833284 -256.73431)
		(end 297.137328 -254.038354)
		(width 0.16002)
		(layer "In13.Cu")
		(net "M_B_CPU0_CLK_DN<0>")
	)
	(segment
		(start 318.992504 -256.13233)
		(end 314.064396 -256.13233)
		(width 0.16002)
		(layer "In13.Cu")
		(net "M_B_CPU0_CLK_DN<0>")
	)
	(segment
		(start 327.103486 -256.309114)
		(end 327.068942 -256.32918)
		(width 0.09525)
		(layer "In13.Cu")
		(net "M_B_CPU0_CLK_DN<0>")
	)
	(segment
		(start 335.75117 -256.634234)
		(end 335.597246 -256.368804)
		(width 0.09525)
		(layer "In13.Cu")
		(net "M_B_CPU0_CLK_DN<0>")
	)
	(segment
		(start 328.419714 -256.309114)
		(end 328.411332 -256.304288)
		(width 0.09525)
		(layer "In13.Cu")
		(net "M_B_CPU0_CLK_DN<0>")
	)
	(segment
		(start 326.085454 -256.36855)
		(end 324.920102 -257.533902)
		(width 0.09525)
		(layer "In13.Cu")
		(net "M_B_CPU0_CLK_DN<0>")
	)
	(segment
		(start 331.239622 -256.309114)
		(end 331.23124 -256.304288)
		(width 0.09525)
		(layer "In13.Cu")
		(net "M_B_CPU0_CLK_DN<0>")
	)
	(segment
		(start 335.597246 -256.368804)
		(end 335.496408 -256.342134)
		(width 0.09525)
		(layer "In13.Cu")
		(net "M_B_CPU0_CLK_DN<0>")
	)
	(segment
		(start 314.064396 -256.13233)
		(end 313.462416 -256.73431)
		(width 0.16002)
		(layer "In13.Cu")
		(net "M_B_CPU0_CLK_DN<0>")
	)
	(segment
		(start 327.117964 -256.300732)
		(end 327.103486 -256.309114)
		(width 0.09525)
		(layer "In13.Cu")
		(net "M_B_CPU0_CLK_DN<0>")
	)
	(segment
		(start 313.462416 -256.73431)
		(end 299.833284 -256.73431)
		(width 0.16002)
		(layer "In13.Cu")
		(net "M_B_CPU0_CLK_DN<0>")
	)
	(segment
		(start 332.179676 -256.309114)
		(end 332.171294 -256.304288)
		(width 0.09525)
		(layer "In13.Cu")
		(net "M_B_CPU0_CLK_DN<0>")
	)
	(segment
		(start 332.750922 -256.304288)
		(end 332.74254 -256.309114)
		(width 0.09525)
		(layer "In13.Cu")
		(net "M_B_CPU0_CLK_DN<0>")
	)
	(segment
		(start 324.224904 -257.533902)
		(end 324.165976 -257.59283)
		(width 0.09525)
		(layer "In13.Cu")
		(net "M_B_CPU0_CLK_DN<0>")
	)
	(segment
		(start 324.165976 -257.59283)
		(end 324.142354 -257.59283)
		(width 0.09525)
		(layer "In13.Cu")
		(net "M_B_CPU0_CLK_DN<0>")
	)
	(segment
		(start 324.142354 -257.59283)
		(end 320.453004 -257.59283)
		(width 0.16002)
		(layer "In13.Cu")
		(net "M_B_CPU0_CLK_DN<0>")
	)
	(segment
		(start 324.920102 -257.533902)
		(end 324.224904 -257.533902)
		(width 0.09525)
		(layer "In13.Cu")
		(net "M_B_CPU0_CLK_DN<0>")
	)
	(segment
		(start 333.690976 -256.304288)
		(end 333.682594 -256.309114)
		(width 0.09525)
		(layer "In13.Cu")
		(net "M_B_CPU0_CLK_DN<0>")
	)
	(arc
		(start 328.042524 -256.309114)
		(mid 327.761092 -256.384869)
		(end 327.47966 -256.309114)
		(width 0.09525)
		(layer "In13.Cu")
		(net "M_B_CPU0_CLK_DN<0>")
	)
	(arc
		(start 332.74254 -256.309114)
		(mid 332.461108 -256.384869)
		(end 332.179676 -256.309114)
		(width 0.09525)
		(layer "In13.Cu")
		(net "M_B_CPU0_CLK_DN<0>")
	)
	(arc
		(start 335.496408 -256.342134)
		(mid 335.244124 -256.383828)
		(end 334.999584 -256.309114)
		(width 0.09525)
		(layer "In13.Cu")
		(net "M_B_CPU0_CLK_DN<0>")
	)
	(arc
		(start 330.299568 -256.309114)
		(mid 330.1111 -256.258437)
		(end 329.922632 -256.309114)
		(width 0.09525)
		(layer "In13.Cu")
		(net "M_B_CPU0_CLK_DN<0>")
	)
	(arc
		(start 332.171294 -256.304288)
		(mid 331.986262 -256.258374)
		(end 331.802486 -256.309114)
		(width 0.09525)
		(layer "In13.Cu")
		(net "M_B_CPU0_CLK_DN<0>")
	)
	(arc
		(start 326.540876 -256.309114)
		(mid 326.366787 -256.258242)
		(end 326.189086 -256.294636)
		(width 0.09525)
		(layer "In13.Cu")
		(net "M_B_CPU0_CLK_DN<0>")
	)
	(arc
		(start 326.102726 -256.352548)
		(mid 326.093965 -256.360414)
		(end 326.085454 -256.36855)
		(width 0.09525)
		(layer "In13.Cu")
		(net "M_B_CPU0_CLK_DN<0>")
	)
	(arc
		(start 333.11973 -256.309114)
		(mid 332.935955 -256.258342)
		(end 332.750922 -256.304288)
		(width 0.09525)
		(layer "In13.Cu")
		(net "M_B_CPU0_CLK_DN<0>")
	)
	(arc
		(start 333.682594 -256.309114)
		(mid 333.401162 -256.384869)
		(end 333.11973 -256.309114)
		(width 0.09525)
		(layer "In13.Cu")
		(net "M_B_CPU0_CLK_DN<0>")
	)
	(arc
		(start 328.982578 -256.309114)
		(mid 328.701146 -256.384869)
		(end 328.419714 -256.309114)
		(width 0.09525)
		(layer "In13.Cu")
		(net "M_B_CPU0_CLK_DN<0>")
	)
	(arc
		(start 330.862432 -256.309114)
		(mid 330.581 -256.384869)
		(end 330.299568 -256.309114)
		(width 0.09525)
		(layer "In13.Cu")
		(net "M_B_CPU0_CLK_DN<0>")
	)
	(arc
		(start 329.922632 -256.309114)
		(mid 329.6412 -256.384869)
		(end 329.359768 -256.309114)
		(width 0.09525)
		(layer "In13.Cu")
		(net "M_B_CPU0_CLK_DN<0>")
	)
	(arc
		(start 326.163686 -256.309114)
		(mid 326.132131 -256.329321)
		(end 326.102726 -256.352548)
		(width 0.09525)
		(layer "In13.Cu")
		(net "M_B_CPU0_CLK_DN<0>")
	)
	(arc
		(start 327.47966 -256.309114)
		(mid 327.299888 -256.258538)
		(end 327.117964 -256.300732)
		(width 0.09525)
		(layer "In13.Cu")
		(net "M_B_CPU0_CLK_DN<0>")
	)
	(arc
		(start 327.068942 -256.32918)
		(mid 326.802416 -256.385117)
		(end 326.540876 -256.309114)
		(width 0.09525)
		(layer "In13.Cu")
		(net "M_B_CPU0_CLK_DN<0>")
	)
	(arc
		(start 328.411332 -256.304288)
		(mid 328.2263 -256.258374)
		(end 328.042524 -256.309114)
		(width 0.09525)
		(layer "In13.Cu")
		(net "M_B_CPU0_CLK_DN<0>")
	)
	(arc
		(start 334.059784 -256.309114)
		(mid 333.876009 -256.258342)
		(end 333.690976 -256.304288)
		(width 0.09525)
		(layer "In13.Cu")
		(net "M_B_CPU0_CLK_DN<0>")
	)
	(arc
		(start 331.802486 -256.309114)
		(mid 331.521054 -256.384869)
		(end 331.239622 -256.309114)
		(width 0.09525)
		(layer "In13.Cu")
		(net "M_B_CPU0_CLK_DN<0>")
	)
	(arc
		(start 329.359768 -256.309114)
		(mid 329.175993 -256.258342)
		(end 328.99096 -256.304288)
		(width 0.09525)
		(layer "In13.Cu")
		(net "M_B_CPU0_CLK_DN<0>")
	)
	(arc
		(start 334.999584 -256.309114)
		(mid 334.811116 -256.258437)
		(end 334.622648 -256.309114)
		(width 0.09525)
		(layer "In13.Cu")
		(net "M_B_CPU0_CLK_DN<0>")
	)
	(arc
		(start 331.23124 -256.304288)
		(mid 331.046208 -256.258374)
		(end 330.862432 -256.309114)
		(width 0.09525)
		(layer "In13.Cu")
		(net "M_B_CPU0_CLK_DN<0>")
	)
	(arc
		(start 334.622648 -256.309114)
		(mid 334.341216 -256.384869)
		(end 334.059784 -256.309114)
		(width 0.09525)
		(layer "In13.Cu")
		(net "M_B_CPU0_CLK_DN<0>")
	)
	(segment
		(start 337.158076 -250.420124)
		(end 336.691224 -250.154186)
		(width 0.10668)
		(layer "F.Cu")
		(net "M_B_CPU0_ALERT_R_N")
	)
	(segment
		(start 324.247002 -250.338844)
		(end 324.90029 -250.338844)
		(width 0.0889)
		(layer "In13.Cu")
		(net "M_B_CPU0_ALERT_R_N")
	)
	(segment
		(start 301.67326 -244.53723)
		(end 302.468026 -244.53723)
		(width 0.11684)
		(layer "In13.Cu")
		(net "M_B_CPU0_ALERT_R_N")
	)
	(segment
		(start 335.929732 -250.481592)
		(end 335.938114 -250.476766)
		(width 0.0889)
		(layer "In13.Cu")
		(net "M_B_CPU0_ALERT_R_N")
	)
	(segment
		(start 326.526398 -250.483624)
		(end 326.538082 -250.476766)
		(width 0.0889)
		(layer "In13.Cu")
		(net "M_B_CPU0_ALERT_R_N")
	)
	(segment
		(start 304.791618 -246.210074)
		(end 307.811678 -246.210074)
		(width 0.11684)
		(layer "In13.Cu")
		(net "M_B_CPU0_ALERT_R_N")
	)
	(segment
		(start 307.811678 -246.210074)
		(end 311.493154 -249.89155)
		(width 0.11684)
		(layer "In13.Cu")
		(net "M_B_CPU0_ALERT_R_N")
	)
	(segment
		(start 331.229716 -250.481592)
		(end 331.238098 -250.476766)
		(width 0.0889)
		(layer "In13.Cu")
		(net "M_B_CPU0_ALERT_R_N")
	)
	(segment
		(start 332.16977 -250.481592)
		(end 332.178152 -250.476766)
		(width 0.0889)
		(layer "In13.Cu")
		(net "M_B_CPU0_ALERT_R_N")
	)
	(segment
		(start 302.468026 -244.53723)
		(end 303.290986 -245.36019)
		(width 0.11684)
		(layer "In13.Cu")
		(net "M_B_CPU0_ALERT_R_N")
	)
	(segment
		(start 324.961758 -250.400312)
		(end 325.880222 -250.400312)
		(width 0.0889)
		(layer "In13.Cu")
		(net "M_B_CPU0_ALERT_R_N")
	)
	(segment
		(start 328.409808 -250.481592)
		(end 328.41819 -250.476766)
		(width 0.0889)
		(layer "In13.Cu")
		(net "M_B_CPU0_ALERT_R_N")
	)
	(segment
		(start 321.861434 -249.89155)
		(end 322.308728 -250.338844)
		(width 0.11684)
		(layer "In13.Cu")
		(net "M_B_CPU0_ALERT_R_N")
	)
	(segment
		(start 303.941734 -245.36019)
		(end 304.791618 -246.210074)
		(width 0.11684)
		(layer "In13.Cu")
		(net "M_B_CPU0_ALERT_R_N")
	)
	(segment
		(start 303.290986 -245.36019)
		(end 303.941734 -245.36019)
		(width 0.11684)
		(layer "In13.Cu")
		(net "M_B_CPU0_ALERT_R_N")
	)
	(segment
		(start 332.744064 -250.476766)
		(end 332.752446 -250.481592)
		(width 0.0889)
		(layer "In13.Cu")
		(net "M_B_CPU0_ALERT_R_N")
	)
	(segment
		(start 336.845148 -250.419616)
		(end 336.691224 -250.154186)
		(width 0.0889)
		(layer "In13.Cu")
		(net "M_B_CPU0_ALERT_R_N")
	)
	(segment
		(start 328.984102 -250.476766)
		(end 328.992484 -250.481592)
		(width 0.0889)
		(layer "In13.Cu")
		(net "M_B_CPU0_ALERT_R_N")
	)
	(segment
		(start 301.22114 -244.08511)
		(end 301.67326 -244.53723)
		(width 0.11684)
		(layer "In13.Cu")
		(net "M_B_CPU0_ALERT_R_N")
	)
	(segment
		(start 322.308728 -250.338844)
		(end 324.247002 -250.338844)
		(width 0.11684)
		(layer "In13.Cu")
		(net "M_B_CPU0_ALERT_R_N")
	)
	(segment
		(start 311.493154 -249.89155)
		(end 321.861434 -249.89155)
		(width 0.11684)
		(layer "In13.Cu")
		(net "M_B_CPU0_ALERT_R_N")
	)
	(segment
		(start 327.469754 -250.481592)
		(end 327.478136 -250.476766)
		(width 0.0889)
		(layer "In13.Cu")
		(net "M_B_CPU0_ALERT_R_N")
	)
	(segment
		(start 324.90029 -250.338844)
		(end 324.961758 -250.400312)
		(width 0.0889)
		(layer "In13.Cu")
		(net "M_B_CPU0_ALERT_R_N")
	)
	(segment
		(start 336.822796 -250.502928)
		(end 336.845148 -250.419616)
		(width 0.0889)
		(layer "In13.Cu")
		(net "M_B_CPU0_ALERT_R_N")
	)
	(segment
		(start 333.684118 -250.476766)
		(end 333.6925 -250.481592)
		(width 0.0889)
		(layer "In13.Cu")
		(net "M_B_CPU0_ALERT_R_N")
	)
	(arc
		(start 332.752446 -250.481592)
		(mid 332.935954 -250.527086)
		(end 333.118206 -250.476766)
		(width 0.0889)
		(layer "In13.Cu")
		(net "M_B_CPU0_ALERT_R_N")
	)
	(arc
		(start 329.358244 -250.476766)
		(mid 329.6412 -250.400589)
		(end 329.924156 -250.476766)
		(width 0.0889)
		(layer "In13.Cu")
		(net "M_B_CPU0_ALERT_R_N")
	)
	(arc
		(start 333.118206 -250.476766)
		(mid 333.401162 -250.400589)
		(end 333.684118 -250.476766)
		(width 0.0889)
		(layer "In13.Cu")
		(net "M_B_CPU0_ALERT_R_N")
	)
	(arc
		(start 334.99806 -250.476766)
		(mid 335.281016 -250.400589)
		(end 335.563972 -250.476766)
		(width 0.0889)
		(layer "In13.Cu")
		(net "M_B_CPU0_ALERT_R_N")
	)
	(arc
		(start 326.538082 -250.476766)
		(mid 326.821038 -250.400589)
		(end 327.103994 -250.476766)
		(width 0.0889)
		(layer "In13.Cu")
		(net "M_B_CPU0_ALERT_R_N")
	)
	(arc
		(start 327.478136 -250.476766)
		(mid 327.761092 -250.400589)
		(end 328.044048 -250.476766)
		(width 0.0889)
		(layer "In13.Cu")
		(net "M_B_CPU0_ALERT_R_N")
	)
	(arc
		(start 329.924156 -250.476766)
		(mid 330.1111 -250.527021)
		(end 330.298044 -250.476766)
		(width 0.0889)
		(layer "In13.Cu")
		(net "M_B_CPU0_ALERT_R_N")
	)
	(arc
		(start 327.103994 -250.476766)
		(mid 327.286245 -250.527116)
		(end 327.469754 -250.481592)
		(width 0.0889)
		(layer "In13.Cu")
		(net "M_B_CPU0_ALERT_R_N")
	)
	(arc
		(start 326.012048 -250.415806)
		(mid 326.090089 -250.440759)
		(end 326.163686 -250.476766)
		(width 0.0889)
		(layer "In13.Cu")
		(net "M_B_CPU0_ALERT_R_N")
	)
	(arc
		(start 330.298044 -250.476766)
		(mid 330.581 -250.400589)
		(end 330.863956 -250.476766)
		(width 0.0889)
		(layer "In13.Cu")
		(net "M_B_CPU0_ALERT_R_N")
	)
	(arc
		(start 334.624172 -250.476766)
		(mid 334.811116 -250.527021)
		(end 334.99806 -250.476766)
		(width 0.0889)
		(layer "In13.Cu")
		(net "M_B_CPU0_ALERT_R_N")
	)
	(arc
		(start 332.178152 -250.476766)
		(mid 332.461108 -250.400589)
		(end 332.744064 -250.476766)
		(width 0.0889)
		(layer "In13.Cu")
		(net "M_B_CPU0_ALERT_R_N")
	)
	(arc
		(start 326.163686 -250.476766)
		(mid 326.344144 -250.52721)
		(end 326.526398 -250.483624)
		(width 0.0889)
		(layer "In13.Cu")
		(net "M_B_CPU0_ALERT_R_N")
	)
	(arc
		(start 328.044048 -250.476766)
		(mid 328.226299 -250.527116)
		(end 328.409808 -250.481592)
		(width 0.0889)
		(layer "In13.Cu")
		(net "M_B_CPU0_ALERT_R_N")
	)
	(arc
		(start 325.880222 -250.400312)
		(mid 325.946594 -250.404154)
		(end 326.012048 -250.415806)
		(width 0.0889)
		(layer "In13.Cu")
		(net "M_B_CPU0_ALERT_R_N")
	)
	(arc
		(start 328.41819 -250.476766)
		(mid 328.701146 -250.400589)
		(end 328.984102 -250.476766)
		(width 0.0889)
		(layer "In13.Cu")
		(net "M_B_CPU0_ALERT_R_N")
	)
	(arc
		(start 335.563972 -250.476766)
		(mid 335.746223 -250.527116)
		(end 335.929732 -250.481592)
		(width 0.0889)
		(layer "In13.Cu")
		(net "M_B_CPU0_ALERT_R_N")
	)
	(arc
		(start 335.938114 -250.476766)
		(mid 336.22107 -250.400589)
		(end 336.504026 -250.476766)
		(width 0.0889)
		(layer "In13.Cu")
		(net "M_B_CPU0_ALERT_R_N")
	)
	(arc
		(start 328.992484 -250.481592)
		(mid 329.175992 -250.527086)
		(end 329.358244 -250.476766)
		(width 0.0889)
		(layer "In13.Cu")
		(net "M_B_CPU0_ALERT_R_N")
	)
	(arc
		(start 331.238098 -250.476766)
		(mid 331.521054 -250.400589)
		(end 331.80401 -250.476766)
		(width 0.0889)
		(layer "In13.Cu")
		(net "M_B_CPU0_ALERT_R_N")
	)
	(arc
		(start 331.80401 -250.476766)
		(mid 331.986261 -250.527116)
		(end 332.16977 -250.481592)
		(width 0.0889)
		(layer "In13.Cu")
		(net "M_B_CPU0_ALERT_R_N")
	)
	(arc
		(start 336.504026 -250.476766)
		(mid 336.660464 -250.525737)
		(end 336.822796 -250.502928)
		(width 0.0889)
		(layer "In13.Cu")
		(net "M_B_CPU0_ALERT_R_N")
	)
	(arc
		(start 333.6925 -250.481592)
		(mid 333.876008 -250.527086)
		(end 334.05826 -250.476766)
		(width 0.0889)
		(layer "In13.Cu")
		(net "M_B_CPU0_ALERT_R_N")
	)
	(arc
		(start 334.05826 -250.476766)
		(mid 334.341216 -250.400589)
		(end 334.624172 -250.476766)
		(width 0.0889)
		(layer "In13.Cu")
		(net "M_B_CPU0_ALERT_R_N")
	)
	(arc
		(start 330.863956 -250.476766)
		(mid 331.046207 -250.527116)
		(end 331.229716 -250.481592)
		(width 0.0889)
		(layer "In13.Cu")
		(net "M_B_CPU0_ALERT_R_N")
	)
	(via
		(at 299.82414 -244.08511)
		(size 0.4826)
		(drill 0.254)
		(layers "F.Cu" "B.Cu")
		(net "M_B_CPU0_ALERT_N")
	)
	(segment
		(start 300.42104 -244.08511)
		(end 299.82414 -244.08511)
		(width 0.10668)
		(layer "B.Cu")
		(net "M_B_CPU0_ALERT_N")
	)
	(segment
		(start 78.237842 -267.340334)
		(end 78.33614 -267.509498)
		(width 0.0762)
		(layer "F.Cu")
		(net "M_A_CPU1_SB_RSP<0>")
	)
	(segment
		(start 62.512448 -269.58544)
		(end 62.38113 -269.716758)
		(width 0.10668)
		(layer "F.Cu")
		(net "M_A_CPU1_SB_RSP<0>")
	)
	(segment
		(start 62.865762 -269.039086)
		(end 62.865762 -268.858746)
		(width 0.10668)
		(layer "F.Cu")
		(net "M_A_CPU1_SB_RSP<0>")
	)
	(segment
		(start 61.665866 -270.2814)
		(end 61.320426 -269.93596)
		(width 0.10668)
		(layer "F.Cu")
		(net "M_A_CPU1_SB_RSP<0>")
	)
	(segment
		(start 61.60262 -269.653512)
		(end 61.94806 -269.998952)
		(width 0.10668)
		(layer "F.Cu")
		(net "M_A_CPU1_SB_RSP<0>")
	)
	(segment
		(start 62.230254 -269.717012)
		(end 61.884814 -269.371572)
		(width 0.10668)
		(layer "F.Cu")
		(net "M_A_CPU1_SB_RSP<0>")
	)
	(segment
		(start 61.816742 -270.281146)
		(end 61.665866 -270.2814)
		(width 0.10668)
		(layer "F.Cu")
		(net "M_A_CPU1_SB_RSP<0>")
	)
	(segment
		(start 62.759082 -268.752066)
		(end 62.353444 -268.752066)
		(width 0.10668)
		(layer "F.Cu")
		(net "M_A_CPU1_SB_RSP<0>")
	)
	(segment
		(start 62.38113 -269.716758)
		(end 62.230254 -269.717012)
		(width 0.10668)
		(layer "F.Cu")
		(net "M_A_CPU1_SB_RSP<0>")
	)
	(segment
		(start 76.30033 -267.521944)
		(end 75.444096 -266.66571)
		(width 0.10668)
		(layer "F.Cu")
		(net "M_A_CPU1_SB_RSP<0>")
	)
	(segment
		(start 63.264796 -269.039086)
		(end 63.158116 -269.145766)
		(width 0.10668)
		(layer "F.Cu")
		(net "M_A_CPU1_SB_RSP<0>")
	)
	(segment
		(start 77.767942 -267.586714)
		(end 76.551536 -267.586714)
		(width 0.0762)
		(layer "F.Cu")
		(net "M_A_CPU1_SB_RSP<0>")
	)
	(segment
		(start 63.264796 -268.858746)
		(end 63.264796 -269.039086)
		(width 0.10668)
		(layer "F.Cu")
		(net "M_A_CPU1_SB_RSP<0>")
	)
	(segment
		(start 63.158116 -269.145766)
		(end 62.972442 -269.145766)
		(width 0.10668)
		(layer "F.Cu")
		(net "M_A_CPU1_SB_RSP<0>")
	)
	(segment
		(start 75.444096 -266.66571)
		(end 65.457832 -266.66571)
		(width 0.10668)
		(layer "F.Cu")
		(net "M_A_CPU1_SB_RSP<0>")
	)
	(segment
		(start 61.16955 -269.93596)
		(end 60.670186 -270.435324)
		(width 0.10668)
		(layer "F.Cu")
		(net "M_A_CPU1_SB_RSP<0>")
	)
	(segment
		(start 76.486766 -267.521944)
		(end 76.30033 -267.521944)
		(width 0.10668)
		(layer "F.Cu")
		(net "M_A_CPU1_SB_RSP<0>")
	)
	(segment
		(start 76.551536 -267.586714)
		(end 76.486766 -267.521944)
		(width 0.0762)
		(layer "F.Cu")
		(net "M_A_CPU1_SB_RSP<0>")
	)
	(segment
		(start 62.353444 -268.752066)
		(end 62.166754 -268.938756)
		(width 0.10668)
		(layer "F.Cu")
		(net "M_A_CPU1_SB_RSP<0>")
	)
	(segment
		(start 60.670186 -270.435324)
		(end 59.428126 -270.435324)
		(width 0.10668)
		(layer "F.Cu")
		(net "M_A_CPU1_SB_RSP<0>")
	)
	(segment
		(start 62.972442 -269.145766)
		(end 62.865762 -269.039086)
		(width 0.10668)
		(layer "F.Cu")
		(net "M_A_CPU1_SB_RSP<0>")
	)
	(segment
		(start 78.05928 -267.66774)
		(end 78.050898 -267.662914)
		(width 0.0762)
		(layer "F.Cu")
		(net "M_A_CPU1_SB_RSP<0>")
	)
	(segment
		(start 62.167008 -269.089124)
		(end 62.512448 -269.434564)
		(width 0.10668)
		(layer "F.Cu")
		(net "M_A_CPU1_SB_RSP<0>")
	)
	(segment
		(start 61.94806 -270.149828)
		(end 61.816742 -270.281146)
		(width 0.10668)
		(layer "F.Cu")
		(net "M_A_CPU1_SB_RSP<0>")
	)
	(segment
		(start 61.733938 -269.371572)
		(end 61.602366 -269.503144)
		(width 0.10668)
		(layer "F.Cu")
		(net "M_A_CPU1_SB_RSP<0>")
	)
	(segment
		(start 62.166754 -268.938756)
		(end 62.167008 -269.089124)
		(width 0.10668)
		(layer "F.Cu")
		(net "M_A_CPU1_SB_RSP<0>")
	)
	(segment
		(start 65.457832 -266.66571)
		(end 63.264796 -268.858746)
		(width 0.10668)
		(layer "F.Cu")
		(net "M_A_CPU1_SB_RSP<0>")
	)
	(segment
		(start 61.320426 -269.93596)
		(end 61.16955 -269.93596)
		(width 0.10668)
		(layer "F.Cu")
		(net "M_A_CPU1_SB_RSP<0>")
	)
	(segment
		(start 61.94806 -269.998952)
		(end 61.94806 -270.149828)
		(width 0.10668)
		(layer "F.Cu")
		(net "M_A_CPU1_SB_RSP<0>")
	)
	(segment
		(start 62.865762 -268.858746)
		(end 62.759082 -268.752066)
		(width 0.10668)
		(layer "F.Cu")
		(net "M_A_CPU1_SB_RSP<0>")
	)
	(segment
		(start 62.512448 -269.434564)
		(end 62.512448 -269.58544)
		(width 0.10668)
		(layer "F.Cu")
		(net "M_A_CPU1_SB_RSP<0>")
	)
	(segment
		(start 61.884814 -269.371572)
		(end 61.733938 -269.371572)
		(width 0.10668)
		(layer "F.Cu")
		(net "M_A_CPU1_SB_RSP<0>")
	)
	(segment
		(start 61.602366 -269.503144)
		(end 61.60262 -269.653512)
		(width 0.10668)
		(layer "F.Cu")
		(net "M_A_CPU1_SB_RSP<0>")
	)
	(arc
		(start 78.198472 -267.711174)
		(mid 78.126734 -267.696322)
		(end 78.05928 -267.66774)
		(width 0.0762)
		(layer "F.Cu")
		(net "M_A_CPU1_SB_RSP<0>")
	)
	(arc
		(start 78.050898 -267.662914)
		(mid 77.914462 -267.606089)
		(end 77.767942 -267.586714)
		(width 0.0762)
		(layer "F.Cu")
		(net "M_A_CPU1_SB_RSP<0>")
	)
	(arc
		(start 78.33614 -267.509498)
		(mid 78.327547 -267.651377)
		(end 78.198472 -267.711174)
		(width 0.0762)
		(layer "F.Cu")
		(net "M_A_CPU1_SB_RSP<0>")
	)
	(segment
		(start 63.798958 -266.397232)
		(end 60.883292 -266.397232)
		(width 0.10668)
		(layer "F.Cu")
		(net "M_A_CPU1_SB_PAR")
	)
	(segment
		(start 56.496458 -267.03528)
		(end 55.328058 -267.03528)
		(width 0.101346)
		(layer "F.Cu")
		(net "M_A_CPU1_SB_PAR")
	)
	(segment
		(start 60.670186 -266.610338)
		(end 56.719978 -266.610338)
		(width 0.101346)
		(layer "F.Cu")
		(net "M_A_CPU1_SB_PAR")
	)
	(segment
		(start 76.471526 -264.537444)
		(end 73.448418 -264.537444)
		(width 0.10668)
		(layer "F.Cu")
		(net "M_A_CPU1_SB_PAR")
	)
	(segment
		(start 76.47178 -264.53719)
		(end 76.471526 -264.537444)
		(width 0.0762)
		(layer "F.Cu")
		(net "M_A_CPU1_SB_PAR")
	)
	(segment
		(start 60.883292 -266.397232)
		(end 60.67044 -266.610084)
		(width 0.10668)
		(layer "F.Cu")
		(net "M_A_CPU1_SB_PAR")
	)
	(segment
		(start 56.613298 -266.717018)
		(end 56.613298 -266.91844)
		(width 0.101346)
		(layer "F.Cu")
		(net "M_A_CPU1_SB_PAR")
	)
	(segment
		(start 56.613298 -266.91844)
		(end 56.496458 -267.03528)
		(width 0.101346)
		(layer "F.Cu")
		(net "M_A_CPU1_SB_PAR")
	)
	(segment
		(start 65.094358 -265.101832)
		(end 63.798958 -266.397232)
		(width 0.10668)
		(layer "F.Cu")
		(net "M_A_CPU1_SB_PAR")
	)
	(segment
		(start 72.88403 -265.101832)
		(end 65.094358 -265.101832)
		(width 0.10668)
		(layer "F.Cu")
		(net "M_A_CPU1_SB_PAR")
	)
	(segment
		(start 60.67044 -266.610084)
		(end 60.670186 -266.610338)
		(width 0.101346)
		(layer "F.Cu")
		(net "M_A_CPU1_SB_PAR")
	)
	(segment
		(start 56.719978 -266.610338)
		(end 56.613298 -266.717018)
		(width 0.101346)
		(layer "F.Cu")
		(net "M_A_CPU1_SB_PAR")
	)
	(segment
		(start 73.448418 -264.537444)
		(end 72.88403 -265.101832)
		(width 0.10668)
		(layer "F.Cu")
		(net "M_A_CPU1_SB_PAR")
	)
	(segment
		(start 77.767942 -264.53719)
		(end 76.47178 -264.53719)
		(width 0.0762)
		(layer "F.Cu")
		(net "M_A_CPU1_SB_PAR")
	)
	(arc
		(start 78.707996 -264.910316)
		(mid 78.465679 -264.740596)
		(end 78.180692 -264.661142)
		(width 0.0762)
		(layer "F.Cu")
		(net "M_A_CPU1_SB_PAR")
	)
	(arc
		(start 77.954886 -264.587736)
		(mid 77.864753 -264.550116)
		(end 77.767942 -264.53719)
		(width 0.0762)
		(layer "F.Cu")
		(net "M_A_CPU1_SB_PAR")
	)
	(arc
		(start 78.180692 -264.661142)
		(mid 78.063879 -264.636466)
		(end 77.954886 -264.587736)
		(width 0.0762)
		(layer "F.Cu")
		(net "M_A_CPU1_SB_PAR")
	)
	(segment
		(start 64.274192 -271.952466)
		(end 63.881508 -272.34515)
		(width 0.12954)
		(layer "F.Cu")
		(net "M_A_CPU1_SB_DQS_DP<9>")
	)
	(segment
		(start 62.744858 -273.4818)
		(end 62.744858 -274.02028)
		(width 0.12954)
		(layer "F.Cu")
		(net "M_A_CPU1_SB_DQS_DP<9>")
	)
	(segment
		(start 65.018158 -271.2085)
		(end 65.018158 -271.74698)
		(width 0.12954)
		(layer "F.Cu")
		(net "M_A_CPU1_SB_DQS_DP<9>")
	)
	(segment
		(start 60.427616 -275.799042)
		(end 60.226448 -275.799042)
		(width 0.12954)
		(layer "F.Cu")
		(net "M_A_CPU1_SB_DQS_DP<9>")
	)
	(segment
		(start 71.297546 -269.754858)
		(end 71.297546 -269.989046)
		(width 0.12954)
		(layer "F.Cu")
		(net "M_A_CPU1_SB_DQS_DP<9>")
	)
	(segment
		(start 72.903334 -269.754858)
		(end 72.903334 -269.989046)
		(width 0.12954)
		(layer "F.Cu")
		(net "M_A_CPU1_SB_DQS_DP<9>")
	)
	(segment
		(start 62.000892 -274.225766)
		(end 61.608208 -274.61845)
		(width 0.12954)
		(layer "F.Cu")
		(net "M_A_CPU1_SB_DQS_DP<9>")
	)
	(segment
		(start 72.773794 -270.118586)
		(end 72.55256 -270.118586)
		(width 0.12954)
		(layer "F.Cu")
		(net "M_A_CPU1_SB_DQS_DP<9>")
	)
	(segment
		(start 67.95643 -270.118586)
		(end 67.735196 -270.118586)
		(width 0.12954)
		(layer "F.Cu")
		(net "M_A_CPU1_SB_DQS_DP<9>")
	)
	(segment
		(start 77.767942 -270.826738)
		(end 76.464668 -270.826738)
		(width 0.0762)
		(layer "F.Cu")
		(net "M_A_CPU1_SB_DQS_DP<9>")
	)
	(segment
		(start 64.812672 -271.952466)
		(end 64.274192 -271.952466)
		(width 0.12954)
		(layer "F.Cu")
		(net "M_A_CPU1_SB_DQS_DP<9>")
	)
	(segment
		(start 68.404232 -269.436596)
		(end 68.08597 -269.754858)
		(width 0.12954)
		(layer "F.Cu")
		(net "M_A_CPU1_SB_DQS_DP<9>")
	)
	(segment
		(start 72.55256 -270.118586)
		(end 72.42302 -269.989046)
		(width 0.12954)
		(layer "F.Cu")
		(net "M_A_CPU1_SB_DQS_DP<9>")
	)
	(segment
		(start 60.864242 -275.362416)
		(end 60.427616 -275.799042)
		(width 0.12954)
		(layer "F.Cu")
		(net "M_A_CPU1_SB_DQS_DP<9>")
	)
	(segment
		(start 72.903334 -269.989046)
		(end 72.773794 -270.118586)
		(width 0.12954)
		(layer "F.Cu")
		(net "M_A_CPU1_SB_DQS_DP<9>")
	)
	(segment
		(start 61.608208 -275.15693)
		(end 61.402722 -275.362416)
		(width 0.12954)
		(layer "F.Cu")
		(net "M_A_CPU1_SB_DQS_DP<9>")
	)
	(segment
		(start 78.237842 -270.580358)
		(end 78.33614 -270.749522)
		(width 0.0762)
		(layer "F.Cu")
		(net "M_A_CPU1_SB_DQS_DP<9>")
	)
	(segment
		(start 60.226448 -275.799042)
		(end 59.962796 -275.53539)
		(width 0.12954)
		(layer "F.Cu")
		(net "M_A_CPU1_SB_DQS_DP<9>")
	)
	(segment
		(start 69.340984 -270.118586)
		(end 69.211444 -269.989046)
		(width 0.12954)
		(layer "F.Cu")
		(net "M_A_CPU1_SB_DQS_DP<9>")
	)
	(segment
		(start 62.539372 -274.225766)
		(end 62.000892 -274.225766)
		(width 0.12954)
		(layer "F.Cu")
		(net "M_A_CPU1_SB_DQS_DP<9>")
	)
	(segment
		(start 71.615808 -269.436596)
		(end 71.297546 -269.754858)
		(width 0.12954)
		(layer "F.Cu")
		(net "M_A_CPU1_SB_DQS_DP<9>")
	)
	(segment
		(start 71.297546 -269.989046)
		(end 71.168006 -270.118586)
		(width 0.12954)
		(layer "F.Cu")
		(net "M_A_CPU1_SB_DQS_DP<9>")
	)
	(segment
		(start 63.881508 -272.88363)
		(end 63.676022 -273.089116)
		(width 0.12954)
		(layer "F.Cu")
		(net "M_A_CPU1_SB_DQS_DP<9>")
	)
	(segment
		(start 62.744858 -274.02028)
		(end 62.539372 -274.225766)
		(width 0.12954)
		(layer "F.Cu")
		(net "M_A_CPU1_SB_DQS_DP<9>")
	)
	(segment
		(start 69.691758 -269.754858)
		(end 69.691758 -269.989046)
		(width 0.12954)
		(layer "F.Cu")
		(net "M_A_CPU1_SB_DQS_DP<9>")
	)
	(segment
		(start 65.949322 -270.815816)
		(end 65.410842 -270.815816)
		(width 0.12954)
		(layer "F.Cu")
		(net "M_A_CPU1_SB_DQS_DP<9>")
	)
	(segment
		(start 66.790062 -269.436596)
		(end 66.154808 -270.07185)
		(width 0.12954)
		(layer "F.Cu")
		(net "M_A_CPU1_SB_DQS_DP<9>")
	)
	(segment
		(start 72.42302 -269.989046)
		(end 72.42302 -269.754858)
		(width 0.12954)
		(layer "F.Cu")
		(net "M_A_CPU1_SB_DQS_DP<9>")
	)
	(segment
		(start 63.676022 -273.089116)
		(end 63.137542 -273.089116)
		(width 0.12954)
		(layer "F.Cu")
		(net "M_A_CPU1_SB_DQS_DP<9>")
	)
	(segment
		(start 61.402722 -275.362416)
		(end 60.864242 -275.362416)
		(width 0.12954)
		(layer "F.Cu")
		(net "M_A_CPU1_SB_DQS_DP<9>")
	)
	(segment
		(start 68.893182 -269.436596)
		(end 68.404232 -269.436596)
		(width 0.12954)
		(layer "F.Cu")
		(net "M_A_CPU1_SB_DQS_DP<9>")
	)
	(segment
		(start 67.287394 -269.436596)
		(end 66.790062 -269.436596)
		(width 0.12954)
		(layer "F.Cu")
		(net "M_A_CPU1_SB_DQS_DP<9>")
	)
	(segment
		(start 70.817232 -269.754858)
		(end 70.49897 -269.436596)
		(width 0.12954)
		(layer "F.Cu")
		(net "M_A_CPU1_SB_DQS_DP<9>")
	)
	(segment
		(start 76.379578 -270.760698)
		(end 75.068684 -270.760698)
		(width 0.12954)
		(layer "F.Cu")
		(net "M_A_CPU1_SB_DQS_DP<9>")
	)
	(segment
		(start 75.068684 -270.760698)
		(end 73.744582 -269.436596)
		(width 0.12954)
		(layer "F.Cu")
		(net "M_A_CPU1_SB_DQS_DP<9>")
	)
	(segment
		(start 66.154808 -270.61033)
		(end 65.949322 -270.815816)
		(width 0.12954)
		(layer "F.Cu")
		(net "M_A_CPU1_SB_DQS_DP<9>")
	)
	(segment
		(start 68.08597 -269.754858)
		(end 68.08597 -269.989046)
		(width 0.12954)
		(layer "F.Cu")
		(net "M_A_CPU1_SB_DQS_DP<9>")
	)
	(segment
		(start 67.605656 -269.989046)
		(end 67.605656 -269.754858)
		(width 0.12954)
		(layer "F.Cu")
		(net "M_A_CPU1_SB_DQS_DP<9>")
	)
	(segment
		(start 69.691758 -269.989046)
		(end 69.562218 -270.118586)
		(width 0.12954)
		(layer "F.Cu")
		(net "M_A_CPU1_SB_DQS_DP<9>")
	)
	(segment
		(start 70.946772 -270.118586)
		(end 70.817232 -269.989046)
		(width 0.12954)
		(layer "F.Cu")
		(net "M_A_CPU1_SB_DQS_DP<9>")
	)
	(segment
		(start 71.168006 -270.118586)
		(end 70.946772 -270.118586)
		(width 0.12954)
		(layer "F.Cu")
		(net "M_A_CPU1_SB_DQS_DP<9>")
	)
	(segment
		(start 70.817232 -269.989046)
		(end 70.817232 -269.754858)
		(width 0.12954)
		(layer "F.Cu")
		(net "M_A_CPU1_SB_DQS_DP<9>")
	)
	(segment
		(start 61.608208 -274.61845)
		(end 61.608208 -275.15693)
		(width 0.12954)
		(layer "F.Cu")
		(net "M_A_CPU1_SB_DQS_DP<9>")
	)
	(segment
		(start 76.464668 -270.826738)
		(end 76.398628 -270.760698)
		(width 0.0762)
		(layer "F.Cu")
		(net "M_A_CPU1_SB_DQS_DP<9>")
	)
	(segment
		(start 69.562218 -270.118586)
		(end 69.340984 -270.118586)
		(width 0.12954)
		(layer "F.Cu")
		(net "M_A_CPU1_SB_DQS_DP<9>")
	)
	(segment
		(start 59.962796 -275.53539)
		(end 59.428126 -275.53539)
		(width 0.12954)
		(layer "F.Cu")
		(net "M_A_CPU1_SB_DQS_DP<9>")
	)
	(segment
		(start 63.881508 -272.34515)
		(end 63.881508 -272.88363)
		(width 0.12954)
		(layer "F.Cu")
		(net "M_A_CPU1_SB_DQS_DP<9>")
	)
	(segment
		(start 72.104758 -269.436596)
		(end 71.615808 -269.436596)
		(width 0.12954)
		(layer "F.Cu")
		(net "M_A_CPU1_SB_DQS_DP<9>")
	)
	(segment
		(start 70.49897 -269.436596)
		(end 70.01002 -269.436596)
		(width 0.12954)
		(layer "F.Cu")
		(net "M_A_CPU1_SB_DQS_DP<9>")
	)
	(segment
		(start 66.154808 -270.07185)
		(end 66.154808 -270.61033)
		(width 0.12954)
		(layer "F.Cu")
		(net "M_A_CPU1_SB_DQS_DP<9>")
	)
	(segment
		(start 73.744582 -269.436596)
		(end 73.221596 -269.436596)
		(width 0.12954)
		(layer "F.Cu")
		(net "M_A_CPU1_SB_DQS_DP<9>")
	)
	(segment
		(start 65.018158 -271.74698)
		(end 64.812672 -271.952466)
		(width 0.12954)
		(layer "F.Cu")
		(net "M_A_CPU1_SB_DQS_DP<9>")
	)
	(segment
		(start 72.42302 -269.754858)
		(end 72.104758 -269.436596)
		(width 0.12954)
		(layer "F.Cu")
		(net "M_A_CPU1_SB_DQS_DP<9>")
	)
	(segment
		(start 70.01002 -269.436596)
		(end 69.691758 -269.754858)
		(width 0.12954)
		(layer "F.Cu")
		(net "M_A_CPU1_SB_DQS_DP<9>")
	)
	(segment
		(start 69.211444 -269.754858)
		(end 68.893182 -269.436596)
		(width 0.12954)
		(layer "F.Cu")
		(net "M_A_CPU1_SB_DQS_DP<9>")
	)
	(segment
		(start 67.735196 -270.118586)
		(end 67.605656 -269.989046)
		(width 0.12954)
		(layer "F.Cu")
		(net "M_A_CPU1_SB_DQS_DP<9>")
	)
	(segment
		(start 68.08597 -269.989046)
		(end 67.95643 -270.118586)
		(width 0.12954)
		(layer "F.Cu")
		(net "M_A_CPU1_SB_DQS_DP<9>")
	)
	(segment
		(start 73.221596 -269.436596)
		(end 72.903334 -269.754858)
		(width 0.12954)
		(layer "F.Cu")
		(net "M_A_CPU1_SB_DQS_DP<9>")
	)
	(segment
		(start 78.05928 -270.907764)
		(end 78.050898 -270.902938)
		(width 0.0762)
		(layer "F.Cu")
		(net "M_A_CPU1_SB_DQS_DP<9>")
	)
	(segment
		(start 67.605656 -269.754858)
		(end 67.287394 -269.436596)
		(width 0.12954)
		(layer "F.Cu")
		(net "M_A_CPU1_SB_DQS_DP<9>")
	)
	(segment
		(start 76.398628 -270.760698)
		(end 76.379578 -270.760698)
		(width 0.0762)
		(layer "F.Cu")
		(net "M_A_CPU1_SB_DQS_DP<9>")
	)
	(segment
		(start 63.137542 -273.089116)
		(end 62.744858 -273.4818)
		(width 0.12954)
		(layer "F.Cu")
		(net "M_A_CPU1_SB_DQS_DP<9>")
	)
	(segment
		(start 65.410842 -270.815816)
		(end 65.018158 -271.2085)
		(width 0.12954)
		(layer "F.Cu")
		(net "M_A_CPU1_SB_DQS_DP<9>")
	)
	(segment
		(start 69.211444 -269.989046)
		(end 69.211444 -269.754858)
		(width 0.12954)
		(layer "F.Cu")
		(net "M_A_CPU1_SB_DQS_DP<9>")
	)
	(arc
		(start 78.198472 -270.951198)
		(mid 78.126734 -270.936346)
		(end 78.05928 -270.907764)
		(width 0.0762)
		(layer "F.Cu")
		(net "M_A_CPU1_SB_DQS_DP<9>")
	)
	(arc
		(start 78.050898 -270.902938)
		(mid 77.914462 -270.846113)
		(end 77.767942 -270.826738)
		(width 0.0762)
		(layer "F.Cu")
		(net "M_A_CPU1_SB_DQS_DP<9>")
	)
	(arc
		(start 78.33614 -270.749522)
		(mid 78.327547 -270.891401)
		(end 78.198472 -270.951198)
		(width 0.0762)
		(layer "F.Cu")
		(net "M_A_CPU1_SB_DQS_DP<9>")
	)
	(segment
		(start 74.885296 -300.559216)
		(end 61.623956 -313.820556)
		(width 0.12954)
		(layer "F.Cu")
		(net "M_A_CPU1_SB_DQS_DP<8>")
	)
	(segment
		(start 60.977526 -314.806584)
		(end 60.546996 -314.806584)
		(width 0.12954)
		(layer "F.Cu")
		(net "M_A_CPU1_SB_DQS_DP<8>")
	)
	(segment
		(start 76.148946 -291.562282)
		(end 74.885296 -292.825424)
		(width 0.12954)
		(layer "F.Cu")
		(net "M_A_CPU1_SB_DQS_DP<8>")
	)
	(segment
		(start 56.183784 -314.317888)
		(end 55.866284 -314.635388)
		(width 0.101346)
		(layer "F.Cu")
		(net "M_A_CPU1_SB_DQS_DP<8>")
	)
	(segment
		(start 57.859168 -315.06033)
		(end 57.542938 -314.7441)
		(width 0.101346)
		(layer "F.Cu")
		(net "M_A_CPU1_SB_DQS_DP<8>")
	)
	(segment
		(start 74.885296 -292.825424)
		(end 74.885296 -300.559216)
		(width 0.12954)
		(layer "F.Cu")
		(net "M_A_CPU1_SB_DQS_DP<8>")
	)
	(segment
		(start 57.183782 -314.7441)
		(end 56.75757 -314.317888)
		(width 0.101346)
		(layer "F.Cu")
		(net "M_A_CPU1_SB_DQS_DP<8>")
	)
	(segment
		(start 78.05928 -291.312854)
		(end 78.050898 -291.31768)
		(width 0.0762)
		(layer "F.Cu")
		(net "M_A_CPU1_SB_DQS_DP<8>")
	)
	(segment
		(start 57.542938 -314.7441)
		(end 57.183782 -314.7441)
		(width 0.101346)
		(layer "F.Cu")
		(net "M_A_CPU1_SB_DQS_DP<8>")
	)
	(segment
		(start 56.75757 -314.317888)
		(end 56.183784 -314.317888)
		(width 0.101346)
		(layer "F.Cu")
		(net "M_A_CPU1_SB_DQS_DP<8>")
	)
	(segment
		(start 77.768196 -291.39388)
		(end 76.223368 -291.39388)
		(width 0.0762)
		(layer "F.Cu")
		(net "M_A_CPU1_SB_DQS_DP<8>")
	)
	(segment
		(start 61.623956 -314.160154)
		(end 60.977526 -314.806584)
		(width 0.12954)
		(layer "F.Cu")
		(net "M_A_CPU1_SB_DQS_DP<8>")
	)
	(segment
		(start 60.29325 -315.06033)
		(end 57.859168 -315.06033)
		(width 0.101346)
		(layer "F.Cu")
		(net "M_A_CPU1_SB_DQS_DP<8>")
	)
	(segment
		(start 55.866284 -314.635388)
		(end 55.328058 -314.635388)
		(width 0.101346)
		(layer "F.Cu")
		(net "M_A_CPU1_SB_DQS_DP<8>")
	)
	(segment
		(start 76.223368 -291.39388)
		(end 76.162408 -291.45484)
		(width 0.0762)
		(layer "F.Cu")
		(net "M_A_CPU1_SB_DQS_DP<8>")
	)
	(segment
		(start 76.162408 -291.54882)
		(end 76.148946 -291.562282)
		(width 0.0762)
		(layer "F.Cu")
		(net "M_A_CPU1_SB_DQS_DP<8>")
	)
	(segment
		(start 76.162408 -291.45484)
		(end 76.162408 -291.54882)
		(width 0.0762)
		(layer "F.Cu")
		(net "M_A_CPU1_SB_DQS_DP<8>")
	)
	(segment
		(start 61.623956 -313.820556)
		(end 61.623956 -314.160154)
		(width 0.12954)
		(layer "F.Cu")
		(net "M_A_CPU1_SB_DQS_DP<8>")
	)
	(segment
		(start 60.546996 -314.806584)
		(end 60.29325 -315.06033)
		(width 0.12954)
		(layer "F.Cu")
		(net "M_A_CPU1_SB_DQS_DP<8>")
	)
	(arc
		(start 79.36484 -291.31768)
		(mid 79.177896 -291.267425)
		(end 78.990952 -291.31768)
		(width 0.0762)
		(layer "F.Cu")
		(net "M_A_CPU1_SB_DQS_DP<8>")
	)
	(arc
		(start 78.42504 -291.31768)
		(mid 78.242789 -291.26733)
		(end 78.05928 -291.312854)
		(width 0.0762)
		(layer "F.Cu")
		(net "M_A_CPU1_SB_DQS_DP<8>")
	)
	(arc
		(start 77.815186 -291.392102)
		(mid 77.791709 -291.393478)
		(end 77.768196 -291.39388)
		(width 0.0762)
		(layer "F.Cu")
		(net "M_A_CPU1_SB_DQS_DP<8>")
	)
	(arc
		(start 80.11795 -291.64026)
		(mid 79.880338 -291.469272)
		(end 79.598012 -291.391848)
		(width 0.0762)
		(layer "F.Cu")
		(net "M_A_CPU1_SB_DQS_DP<8>")
	)
	(arc
		(start 79.598012 -291.391848)
		(mid 79.477363 -291.367547)
		(end 79.36484 -291.31768)
		(width 0.0762)
		(layer "F.Cu")
		(net "M_A_CPU1_SB_DQS_DP<8>")
	)
	(arc
		(start 78.050898 -291.31768)
		(mid 77.937174 -291.367981)
		(end 77.815186 -291.392102)
		(width 0.0762)
		(layer "F.Cu")
		(net "M_A_CPU1_SB_DQS_DP<8>")
	)
	(arc
		(start 78.990952 -291.31768)
		(mid 78.707996 -291.393857)
		(end 78.42504 -291.31768)
		(width 0.0762)
		(layer "F.Cu")
		(net "M_A_CPU1_SB_DQS_DP<8>")
	)
	(segment
		(start 55.866284 -305.285394)
		(end 55.328058 -305.285394)
		(width 0.101346)
		(layer "F.Cu")
		(net "M_A_CPU1_SB_DQS_DP<7>")
	)
	(segment
		(start 76.738226 -286.534098)
		(end 76.450698 -286.24657)
		(width 0.0762)
		(layer "F.Cu")
		(net "M_A_CPU1_SB_DQS_DP<7>")
	)
	(segment
		(start 74.704448 -286.31261)
		(end 70.463664 -290.553394)
		(width 0.12954)
		(layer "F.Cu")
		(net "M_A_CPU1_SB_DQS_DP<7>")
	)
	(segment
		(start 56.726582 -304.967894)
		(end 56.183784 -304.967894)
		(width 0.101346)
		(layer "F.Cu")
		(net "M_A_CPU1_SB_DQS_DP<7>")
	)
	(segment
		(start 57.859168 -305.710336)
		(end 57.542938 -305.394106)
		(width 0.101346)
		(layer "F.Cu")
		(net "M_A_CPU1_SB_DQS_DP<7>")
	)
	(segment
		(start 77.768196 -286.534098)
		(end 76.738226 -286.534098)
		(width 0.0762)
		(layer "F.Cu")
		(net "M_A_CPU1_SB_DQS_DP<7>")
	)
	(segment
		(start 60.29325 -305.710336)
		(end 57.859168 -305.710336)
		(width 0.101346)
		(layer "F.Cu")
		(net "M_A_CPU1_SB_DQS_DP<7>")
	)
	(segment
		(start 61.293502 -305.457352)
		(end 60.546234 -305.457352)
		(width 0.12954)
		(layer "F.Cu")
		(net "M_A_CPU1_SB_DQS_DP<7>")
	)
	(segment
		(start 76.450698 -286.24657)
		(end 76.040996 -286.24657)
		(width 0.0762)
		(layer "F.Cu")
		(net "M_A_CPU1_SB_DQS_DP<7>")
	)
	(segment
		(start 60.546234 -305.457352)
		(end 60.29325 -305.710336)
		(width 0.12954)
		(layer "F.Cu")
		(net "M_A_CPU1_SB_DQS_DP<7>")
	)
	(segment
		(start 57.152794 -305.394106)
		(end 56.726582 -304.967894)
		(width 0.101346)
		(layer "F.Cu")
		(net "M_A_CPU1_SB_DQS_DP<7>")
	)
	(segment
		(start 75.955906 -286.31261)
		(end 74.704448 -286.31261)
		(width 0.12954)
		(layer "F.Cu")
		(net "M_A_CPU1_SB_DQS_DP<7>")
	)
	(segment
		(start 78.05928 -286.453072)
		(end 78.050898 -286.457898)
		(width 0.0762)
		(layer "F.Cu")
		(net "M_A_CPU1_SB_DQS_DP<7>")
	)
	(segment
		(start 57.542938 -305.394106)
		(end 57.152794 -305.394106)
		(width 0.101346)
		(layer "F.Cu")
		(net "M_A_CPU1_SB_DQS_DP<7>")
	)
	(segment
		(start 76.040996 -286.24657)
		(end 75.974956 -286.31261)
		(width 0.0762)
		(layer "F.Cu")
		(net "M_A_CPU1_SB_DQS_DP<7>")
	)
	(segment
		(start 70.463664 -296.28719)
		(end 61.293502 -305.457352)
		(width 0.12954)
		(layer "F.Cu")
		(net "M_A_CPU1_SB_DQS_DP<7>")
	)
	(segment
		(start 70.463664 -290.553394)
		(end 70.463664 -296.28719)
		(width 0.12954)
		(layer "F.Cu")
		(net "M_A_CPU1_SB_DQS_DP<7>")
	)
	(segment
		(start 56.183784 -304.967894)
		(end 55.866284 -305.285394)
		(width 0.101346)
		(layer "F.Cu")
		(net "M_A_CPU1_SB_DQS_DP<7>")
	)
	(segment
		(start 75.974956 -286.31261)
		(end 75.955906 -286.31261)
		(width 0.0762)
		(layer "F.Cu")
		(net "M_A_CPU1_SB_DQS_DP<7>")
	)
	(arc
		(start 79.598012 -286.532066)
		(mid 79.477363 -286.507765)
		(end 79.36484 -286.457898)
		(width 0.0762)
		(layer "F.Cu")
		(net "M_A_CPU1_SB_DQS_DP<7>")
	)
	(arc
		(start 78.42504 -286.457898)
		(mid 78.242789 -286.407548)
		(end 78.05928 -286.453072)
		(width 0.0762)
		(layer "F.Cu")
		(net "M_A_CPU1_SB_DQS_DP<7>")
	)
	(arc
		(start 78.990952 -286.457898)
		(mid 78.707996 -286.534075)
		(end 78.42504 -286.457898)
		(width 0.0762)
		(layer "F.Cu")
		(net "M_A_CPU1_SB_DQS_DP<7>")
	)
	(arc
		(start 79.36484 -286.457898)
		(mid 79.177896 -286.407643)
		(end 78.990952 -286.457898)
		(width 0.0762)
		(layer "F.Cu")
		(net "M_A_CPU1_SB_DQS_DP<7>")
	)
	(arc
		(start 77.815186 -286.53232)
		(mid 77.791709 -286.533696)
		(end 77.768196 -286.534098)
		(width 0.0762)
		(layer "F.Cu")
		(net "M_A_CPU1_SB_DQS_DP<7>")
	)
	(arc
		(start 78.050898 -286.457898)
		(mid 77.937174 -286.508199)
		(end 77.815186 -286.53232)
		(width 0.0762)
		(layer "F.Cu")
		(net "M_A_CPU1_SB_DQS_DP<7>")
	)
	(arc
		(start 80.11795 -286.780478)
		(mid 79.880338 -286.60949)
		(end 79.598012 -286.532066)
		(width 0.0762)
		(layer "F.Cu")
		(net "M_A_CPU1_SB_DQS_DP<7>")
	)
	(segment
		(start 55.866284 -295.9354)
		(end 55.328058 -295.9354)
		(width 0.101346)
		(layer "F.Cu")
		(net "M_A_CPU1_SB_DQS_DP<6>")
	)
	(segment
		(start 78.05928 -281.593036)
		(end 78.050898 -281.597862)
		(width 0.0762)
		(layer "F.Cu")
		(net "M_A_CPU1_SB_DQS_DP<6>")
	)
	(segment
		(start 61.58738 -296.10685)
		(end 60.546742 -296.10685)
		(width 0.12954)
		(layer "F.Cu")
		(net "M_A_CPU1_SB_DQS_DP<6>")
	)
	(segment
		(start 66.030094 -291.664136)
		(end 61.58738 -296.10685)
		(width 0.12954)
		(layer "F.Cu")
		(net "M_A_CPU1_SB_DQS_DP<6>")
	)
	(segment
		(start 66.030094 -288.73323)
		(end 66.030094 -291.664136)
		(width 0.12954)
		(layer "F.Cu")
		(net "M_A_CPU1_SB_DQS_DP<6>")
	)
	(segment
		(start 76.80579 -281.674062)
		(end 76.491592 -281.359864)
		(width 0.0762)
		(layer "F.Cu")
		(net "M_A_CPU1_SB_DQS_DP<6>")
	)
	(segment
		(start 57.175654 -296.044112)
		(end 56.749442 -295.6179)
		(width 0.101346)
		(layer "F.Cu")
		(net "M_A_CPU1_SB_DQS_DP<6>")
	)
	(segment
		(start 60.29325 -296.360342)
		(end 57.859168 -296.360342)
		(width 0.101346)
		(layer "F.Cu")
		(net "M_A_CPU1_SB_DQS_DP<6>")
	)
	(segment
		(start 56.183784 -295.6179)
		(end 55.866284 -295.9354)
		(width 0.101346)
		(layer "F.Cu")
		(net "M_A_CPU1_SB_DQS_DP<6>")
	)
	(segment
		(start 57.859168 -296.360342)
		(end 57.542938 -296.044112)
		(width 0.101346)
		(layer "F.Cu")
		(net "M_A_CPU1_SB_DQS_DP<6>")
	)
	(segment
		(start 73.33742 -281.425904)
		(end 66.030094 -288.73323)
		(width 0.12954)
		(layer "F.Cu")
		(net "M_A_CPU1_SB_DQS_DP<6>")
	)
	(segment
		(start 76.491592 -281.359864)
		(end 76.021946 -281.359864)
		(width 0.0762)
		(layer "F.Cu")
		(net "M_A_CPU1_SB_DQS_DP<6>")
	)
	(segment
		(start 57.542938 -296.044112)
		(end 57.175654 -296.044112)
		(width 0.101346)
		(layer "F.Cu")
		(net "M_A_CPU1_SB_DQS_DP<6>")
	)
	(segment
		(start 75.955906 -281.425904)
		(end 73.33742 -281.425904)
		(width 0.12954)
		(layer "F.Cu")
		(net "M_A_CPU1_SB_DQS_DP<6>")
	)
	(segment
		(start 76.021946 -281.359864)
		(end 75.955906 -281.425904)
		(width 0.0762)
		(layer "F.Cu")
		(net "M_A_CPU1_SB_DQS_DP<6>")
	)
	(segment
		(start 56.749442 -295.6179)
		(end 56.183784 -295.6179)
		(width 0.101346)
		(layer "F.Cu")
		(net "M_A_CPU1_SB_DQS_DP<6>")
	)
	(segment
		(start 77.768196 -281.674062)
		(end 76.80579 -281.674062)
		(width 0.0762)
		(layer "F.Cu")
		(net "M_A_CPU1_SB_DQS_DP<6>")
	)
	(segment
		(start 60.546742 -296.10685)
		(end 60.29325 -296.360342)
		(width 0.12954)
		(layer "F.Cu")
		(net "M_A_CPU1_SB_DQS_DP<6>")
	)
	(arc
		(start 79.36484 -281.597862)
		(mid 79.177896 -281.547607)
		(end 78.990952 -281.597862)
		(width 0.0762)
		(layer "F.Cu")
		(net "M_A_CPU1_SB_DQS_DP<6>")
	)
	(arc
		(start 78.050898 -281.597862)
		(mid 77.937174 -281.648163)
		(end 77.815186 -281.672284)
		(width 0.0762)
		(layer "F.Cu")
		(net "M_A_CPU1_SB_DQS_DP<6>")
	)
	(arc
		(start 79.598012 -281.67203)
		(mid 79.477363 -281.647729)
		(end 79.36484 -281.597862)
		(width 0.0762)
		(layer "F.Cu")
		(net "M_A_CPU1_SB_DQS_DP<6>")
	)
	(arc
		(start 77.815186 -281.672284)
		(mid 77.791709 -281.67366)
		(end 77.768196 -281.674062)
		(width 0.0762)
		(layer "F.Cu")
		(net "M_A_CPU1_SB_DQS_DP<6>")
	)
	(arc
		(start 78.42504 -281.597862)
		(mid 78.242789 -281.547512)
		(end 78.05928 -281.593036)
		(width 0.0762)
		(layer "F.Cu")
		(net "M_A_CPU1_SB_DQS_DP<6>")
	)
	(arc
		(start 78.990952 -281.597862)
		(mid 78.707996 -281.674039)
		(end 78.42504 -281.597862)
		(width 0.0762)
		(layer "F.Cu")
		(net "M_A_CPU1_SB_DQS_DP<6>")
	)
	(arc
		(start 80.11795 -281.920442)
		(mid 79.880338 -281.749454)
		(end 79.598012 -281.67203)
		(width 0.0762)
		(layer "F.Cu")
		(net "M_A_CPU1_SB_DQS_DP<6>")
	)
	(segment
		(start 60.29325 -287.010348)
		(end 57.859168 -287.010348)
		(width 0.101346)
		(layer "F.Cu")
		(net "M_A_CPU1_SB_DQS_DP<5>")
	)
	(segment
		(start 70.427088 -276.640798)
		(end 61.888624 -285.179262)
		(width 0.12954)
		(layer "F.Cu")
		(net "M_A_CPU1_SB_DQS_DP<5>")
	)
	(segment
		(start 57.542938 -286.694118)
		(end 57.198006 -286.694118)
		(width 0.101346)
		(layer "F.Cu")
		(net "M_A_CPU1_SB_DQS_DP<5>")
	)
	(segment
		(start 61.888624 -285.858712)
		(end 60.990734 -286.756602)
		(width 0.12954)
		(layer "F.Cu")
		(net "M_A_CPU1_SB_DQS_DP<5>")
	)
	(segment
		(start 60.546996 -286.756602)
		(end 60.29325 -287.010348)
		(width 0.12954)
		(layer "F.Cu")
		(net "M_A_CPU1_SB_DQS_DP<5>")
	)
	(segment
		(start 61.888624 -285.179262)
		(end 61.888624 -285.858712)
		(width 0.12954)
		(layer "F.Cu")
		(net "M_A_CPU1_SB_DQS_DP<5>")
	)
	(segment
		(start 57.859168 -287.010348)
		(end 57.542938 -286.694118)
		(width 0.101346)
		(layer "F.Cu")
		(net "M_A_CPU1_SB_DQS_DP<5>")
	)
	(segment
		(start 56.183784 -286.267906)
		(end 55.866284 -286.585406)
		(width 0.101346)
		(layer "F.Cu")
		(net "M_A_CPU1_SB_DQS_DP<5>")
	)
	(segment
		(start 76.821792 -276.814026)
		(end 76.582524 -276.574758)
		(width 0.0762)
		(layer "F.Cu")
		(net "M_A_CPU1_SB_DQS_DP<5>")
	)
	(segment
		(start 57.198006 -286.694118)
		(end 56.771794 -286.267906)
		(width 0.101346)
		(layer "F.Cu")
		(net "M_A_CPU1_SB_DQS_DP<5>")
	)
	(segment
		(start 76.021946 -276.574758)
		(end 75.955906 -276.640798)
		(width 0.0762)
		(layer "F.Cu")
		(net "M_A_CPU1_SB_DQS_DP<5>")
	)
	(segment
		(start 56.771794 -286.267906)
		(end 56.183784 -286.267906)
		(width 0.101346)
		(layer "F.Cu")
		(net "M_A_CPU1_SB_DQS_DP<5>")
	)
	(segment
		(start 55.866284 -286.585406)
		(end 55.328058 -286.585406)
		(width 0.101346)
		(layer "F.Cu")
		(net "M_A_CPU1_SB_DQS_DP<5>")
	)
	(segment
		(start 76.582524 -276.574758)
		(end 76.021946 -276.574758)
		(width 0.0762)
		(layer "F.Cu")
		(net "M_A_CPU1_SB_DQS_DP<5>")
	)
	(segment
		(start 60.990734 -286.756602)
		(end 60.546996 -286.756602)
		(width 0.12954)
		(layer "F.Cu")
		(net "M_A_CPU1_SB_DQS_DP<5>")
	)
	(segment
		(start 75.955906 -276.640798)
		(end 70.427088 -276.640798)
		(width 0.12954)
		(layer "F.Cu")
		(net "M_A_CPU1_SB_DQS_DP<5>")
	)
	(segment
		(start 77.768196 -276.814026)
		(end 76.821792 -276.814026)
		(width 0.0762)
		(layer "F.Cu")
		(net "M_A_CPU1_SB_DQS_DP<5>")
	)
	(segment
		(start 78.05928 -276.733)
		(end 78.050898 -276.737826)
		(width 0.0762)
		(layer "F.Cu")
		(net "M_A_CPU1_SB_DQS_DP<5>")
	)
	(arc
		(start 80.11795 -277.060406)
		(mid 79.880338 -276.889418)
		(end 79.598012 -276.811994)
		(width 0.0762)
		(layer "F.Cu")
		(net "M_A_CPU1_SB_DQS_DP<5>")
	)
	(arc
		(start 79.36484 -276.737826)
		(mid 79.177896 -276.687571)
		(end 78.990952 -276.737826)
		(width 0.0762)
		(layer "F.Cu")
		(net "M_A_CPU1_SB_DQS_DP<5>")
	)
	(arc
		(start 78.990952 -276.737826)
		(mid 78.707996 -276.814003)
		(end 78.42504 -276.737826)
		(width 0.0762)
		(layer "F.Cu")
		(net "M_A_CPU1_SB_DQS_DP<5>")
	)
	(arc
		(start 79.598012 -276.811994)
		(mid 79.477363 -276.787693)
		(end 79.36484 -276.737826)
		(width 0.0762)
		(layer "F.Cu")
		(net "M_A_CPU1_SB_DQS_DP<5>")
	)
	(arc
		(start 78.42504 -276.737826)
		(mid 78.242789 -276.687476)
		(end 78.05928 -276.733)
		(width 0.0762)
		(layer "F.Cu")
		(net "M_A_CPU1_SB_DQS_DP<5>")
	)
	(arc
		(start 78.050898 -276.737826)
		(mid 77.937174 -276.788127)
		(end 77.815186 -276.812248)
		(width 0.0762)
		(layer "F.Cu")
		(net "M_A_CPU1_SB_DQS_DP<5>")
	)
	(arc
		(start 77.815186 -276.812248)
		(mid 77.791709 -276.813624)
		(end 77.768196 -276.814026)
		(width 0.0762)
		(layer "F.Cu")
		(net "M_A_CPU1_SB_DQS_DP<5>")
	)
	(segment
		(start 73.982072 -271.185386)
		(end 67.186556 -271.185386)
		(width 0.12954)
		(layer "F.Cu")
		(net "M_A_CPU1_SB_DQS_DP<4>")
	)
	(segment
		(start 76.246482 -271.769078)
		(end 76.180442 -271.835118)
		(width 0.0762)
		(layer "F.Cu")
		(net "M_A_CPU1_SB_DQS_DP<4>")
	)
	(segment
		(start 76.578206 -271.769078)
		(end 76.246482 -271.769078)
		(width 0.0762)
		(layer "F.Cu")
		(net "M_A_CPU1_SB_DQS_DP<4>")
	)
	(segment
		(start 55.866284 -277.235412)
		(end 55.328058 -277.235412)
		(width 0.101346)
		(layer "F.Cu")
		(net "M_A_CPU1_SB_DQS_DP<4>")
	)
	(segment
		(start 78.05928 -271.872964)
		(end 78.050898 -271.87779)
		(width 0.0762)
		(layer "F.Cu")
		(net "M_A_CPU1_SB_DQS_DP<4>")
	)
	(segment
		(start 57.179718 -277.344124)
		(end 56.753506 -276.917912)
		(width 0.101346)
		(layer "F.Cu")
		(net "M_A_CPU1_SB_DQS_DP<4>")
	)
	(segment
		(start 76.763118 -271.95399)
		(end 76.578206 -271.769078)
		(width 0.0762)
		(layer "F.Cu")
		(net "M_A_CPU1_SB_DQS_DP<4>")
	)
	(segment
		(start 74.631804 -271.835118)
		(end 73.982072 -271.185386)
		(width 0.12954)
		(layer "F.Cu")
		(net "M_A_CPU1_SB_DQS_DP<4>")
	)
	(segment
		(start 76.180442 -271.835118)
		(end 76.161392 -271.835118)
		(width 0.0762)
		(layer "F.Cu")
		(net "M_A_CPU1_SB_DQS_DP<4>")
	)
	(segment
		(start 56.183784 -276.917912)
		(end 55.866284 -277.235412)
		(width 0.101346)
		(layer "F.Cu")
		(net "M_A_CPU1_SB_DQS_DP<4>")
	)
	(segment
		(start 60.396882 -277.660354)
		(end 57.859168 -277.660354)
		(width 0.101346)
		(layer "F.Cu")
		(net "M_A_CPU1_SB_DQS_DP<4>")
	)
	(segment
		(start 60.971176 -277.400766)
		(end 60.65647 -277.400766)
		(width 0.12954)
		(layer "F.Cu")
		(net "M_A_CPU1_SB_DQS_DP<4>")
	)
	(segment
		(start 57.542938 -277.344124)
		(end 57.179718 -277.344124)
		(width 0.101346)
		(layer "F.Cu")
		(net "M_A_CPU1_SB_DQS_DP<4>")
	)
	(segment
		(start 76.161392 -271.835118)
		(end 74.631804 -271.835118)
		(width 0.12954)
		(layer "F.Cu")
		(net "M_A_CPU1_SB_DQS_DP<4>")
	)
	(segment
		(start 67.186556 -271.185386)
		(end 60.971176 -277.400766)
		(width 0.12954)
		(layer "F.Cu")
		(net "M_A_CPU1_SB_DQS_DP<4>")
	)
	(segment
		(start 56.753506 -276.917912)
		(end 56.183784 -276.917912)
		(width 0.101346)
		(layer "F.Cu")
		(net "M_A_CPU1_SB_DQS_DP<4>")
	)
	(segment
		(start 60.65647 -277.400766)
		(end 60.396882 -277.660354)
		(width 0.12954)
		(layer "F.Cu")
		(net "M_A_CPU1_SB_DQS_DP<4>")
	)
	(segment
		(start 57.859168 -277.660354)
		(end 57.542938 -277.344124)
		(width 0.101346)
		(layer "F.Cu")
		(net "M_A_CPU1_SB_DQS_DP<4>")
	)
	(segment
		(start 77.768196 -271.95399)
		(end 76.763118 -271.95399)
		(width 0.0762)
		(layer "F.Cu")
		(net "M_A_CPU1_SB_DQS_DP<4>")
	)
	(arc
		(start 78.990952 -271.87779)
		(mid 78.707996 -271.953967)
		(end 78.42504 -271.87779)
		(width 0.0762)
		(layer "F.Cu")
		(net "M_A_CPU1_SB_DQS_DP<4>")
	)
	(arc
		(start 79.598012 -271.951958)
		(mid 79.477363 -271.927657)
		(end 79.36484 -271.87779)
		(width 0.0762)
		(layer "F.Cu")
		(net "M_A_CPU1_SB_DQS_DP<4>")
	)
	(arc
		(start 78.050898 -271.87779)
		(mid 77.937174 -271.928091)
		(end 77.815186 -271.952212)
		(width 0.0762)
		(layer "F.Cu")
		(net "M_A_CPU1_SB_DQS_DP<4>")
	)
	(arc
		(start 79.36484 -271.87779)
		(mid 79.177896 -271.827535)
		(end 78.990952 -271.87779)
		(width 0.0762)
		(layer "F.Cu")
		(net "M_A_CPU1_SB_DQS_DP<4>")
	)
	(arc
		(start 80.11795 -272.20037)
		(mid 79.880338 -272.029382)
		(end 79.598012 -271.951958)
		(width 0.0762)
		(layer "F.Cu")
		(net "M_A_CPU1_SB_DQS_DP<4>")
	)
	(arc
		(start 78.42504 -271.87779)
		(mid 78.242789 -271.82744)
		(end 78.05928 -271.872964)
		(width 0.0762)
		(layer "F.Cu")
		(net "M_A_CPU1_SB_DQS_DP<4>")
	)
	(arc
		(start 77.815186 -271.952212)
		(mid 77.791709 -271.953588)
		(end 77.768196 -271.95399)
		(width 0.0762)
		(layer "F.Cu")
		(net "M_A_CPU1_SB_DQS_DP<4>")
	)
	(segment
		(start 71.936102 -301.037244)
		(end 72.325738 -301.42688)
		(width 0.12954)
		(layer "F.Cu")
		(net "M_A_CPU1_SB_DQS_DP<3>")
	)
	(segment
		(start 72.325738 -301.609252)
		(end 72.16775 -301.76724)
		(width 0.12954)
		(layer "F.Cu")
		(net "M_A_CPU1_SB_DQS_DP<3>")
	)
	(segment
		(start 70.799452 -301.72279)
		(end 70.799452 -302.173894)
		(width 0.12954)
		(layer "F.Cu")
		(net "M_A_CPU1_SB_DQS_DP<3>")
	)
	(segment
		(start 60.98921 -312.687208)
		(end 60.98921 -312.924444)
		(width 0.12954)
		(layer "F.Cu")
		(net "M_A_CPU1_SB_DQS_DP<3>")
	)
	(segment
		(start 78.05928 -290.347654)
		(end 78.050898 -290.342828)
		(width 0.0762)
		(layer "F.Cu")
		(net "M_A_CPU1_SB_DQS_DP<3>")
	)
	(segment
		(start 77.767942 -290.266628)
		(end 77.362304 -290.266628)
		(width 0.0762)
		(layer "F.Cu")
		(net "M_A_CPU1_SB_DQS_DP<3>")
	)
	(segment
		(start 75.703684 -290.16198)
		(end 73.815956 -292.049708)
		(width 0.12954)
		(layer "F.Cu")
		(net "M_A_CPU1_SB_DQS_DP<3>")
	)
	(segment
		(start 71.144638 -301.377604)
		(end 70.799452 -301.72279)
		(width 0.12954)
		(layer "F.Cu")
		(net "M_A_CPU1_SB_DQS_DP<3>")
	)
	(segment
		(start 70.007988 -302.514254)
		(end 69.662802 -302.85944)
		(width 0.12954)
		(layer "F.Cu")
		(net "M_A_CPU1_SB_DQS_DP<3>")
	)
	(segment
		(start 77.362304 -290.266628)
		(end 77.323696 -290.22802)
		(width 0.0762)
		(layer "F.Cu")
		(net "M_A_CPU1_SB_DQS_DP<3>")
	)
	(segment
		(start 68.370958 -304.151284)
		(end 68.370958 -305.542696)
		(width 0.12954)
		(layer "F.Cu")
		(net "M_A_CPU1_SB_DQS_DP<3>")
	)
	(segment
		(start 71.595742 -301.377604)
		(end 71.144638 -301.377604)
		(width 0.12954)
		(layer "F.Cu")
		(net "M_A_CPU1_SB_DQS_DP<3>")
	)
	(segment
		(start 72.281288 -300.240954)
		(end 71.936102 -300.58614)
		(width 0.12954)
		(layer "F.Cu")
		(net "M_A_CPU1_SB_DQS_DP<3>")
	)
	(segment
		(start 69.89445 -304.04054)
		(end 69.712078 -304.04054)
		(width 0.12954)
		(layer "F.Cu")
		(net "M_A_CPU1_SB_DQS_DP<3>")
	)
	(segment
		(start 70.848728 -302.90389)
		(end 70.459092 -302.514254)
		(width 0.12954)
		(layer "F.Cu")
		(net "M_A_CPU1_SB_DQS_DP<3>")
	)
	(segment
		(start 71.936102 -300.58614)
		(end 71.936102 -301.037244)
		(width 0.12954)
		(layer "F.Cu")
		(net "M_A_CPU1_SB_DQS_DP<3>")
	)
	(segment
		(start 73.462388 -300.472602)
		(end 73.3044 -300.63059)
		(width 0.12954)
		(layer "F.Cu")
		(net "M_A_CPU1_SB_DQS_DP<3>")
	)
	(segment
		(start 73.122028 -300.63059)
		(end 72.732392 -300.240954)
		(width 0.12954)
		(layer "F.Cu")
		(net "M_A_CPU1_SB_DQS_DP<3>")
	)
	(segment
		(start 72.325738 -301.42688)
		(end 72.325738 -301.609252)
		(width 0.12954)
		(layer "F.Cu")
		(net "M_A_CPU1_SB_DQS_DP<3>")
	)
	(segment
		(start 76.040996 -290.22802)
		(end 75.974956 -290.16198)
		(width 0.0762)
		(layer "F.Cu")
		(net "M_A_CPU1_SB_DQS_DP<3>")
	)
	(segment
		(start 73.072752 -299.44949)
		(end 73.072752 -299.900594)
		(width 0.12954)
		(layer "F.Cu")
		(net "M_A_CPU1_SB_DQS_DP<3>")
	)
	(segment
		(start 73.815956 -292.049708)
		(end 73.815956 -298.706286)
		(width 0.12954)
		(layer "F.Cu")
		(net "M_A_CPU1_SB_DQS_DP<3>")
	)
	(segment
		(start 71.985378 -301.76724)
		(end 71.595742 -301.377604)
		(width 0.12954)
		(layer "F.Cu")
		(net "M_A_CPU1_SB_DQS_DP<3>")
	)
	(segment
		(start 70.052438 -303.70018)
		(end 70.052438 -303.882552)
		(width 0.12954)
		(layer "F.Cu")
		(net "M_A_CPU1_SB_DQS_DP<3>")
	)
	(segment
		(start 69.712078 -304.04054)
		(end 69.322442 -303.650904)
		(width 0.12954)
		(layer "F.Cu")
		(net "M_A_CPU1_SB_DQS_DP<3>")
	)
	(segment
		(start 71.189088 -302.745902)
		(end 71.0311 -302.90389)
		(width 0.12954)
		(layer "F.Cu")
		(net "M_A_CPU1_SB_DQS_DP<3>")
	)
	(segment
		(start 61.501528 -312.412126)
		(end 61.264292 -312.412126)
		(width 0.12954)
		(layer "F.Cu")
		(net "M_A_CPU1_SB_DQS_DP<3>")
	)
	(segment
		(start 61.264292 -312.412126)
		(end 60.98921 -312.687208)
		(width 0.12954)
		(layer "F.Cu")
		(net "M_A_CPU1_SB_DQS_DP<3>")
	)
	(segment
		(start 60.98921 -312.924444)
		(end 60.714636 -313.199018)
		(width 0.12954)
		(layer "F.Cu")
		(net "M_A_CPU1_SB_DQS_DP<3>")
	)
	(segment
		(start 73.3044 -300.63059)
		(end 73.122028 -300.63059)
		(width 0.12954)
		(layer "F.Cu")
		(net "M_A_CPU1_SB_DQS_DP<3>")
	)
	(segment
		(start 68.370958 -305.542696)
		(end 61.501528 -312.412126)
		(width 0.12954)
		(layer "F.Cu")
		(net "M_A_CPU1_SB_DQS_DP<3>")
	)
	(segment
		(start 60.714636 -313.199018)
		(end 60.226448 -313.199018)
		(width 0.12954)
		(layer "F.Cu")
		(net "M_A_CPU1_SB_DQS_DP<3>")
	)
	(segment
		(start 71.189088 -302.56353)
		(end 71.189088 -302.745902)
		(width 0.12954)
		(layer "F.Cu")
		(net "M_A_CPU1_SB_DQS_DP<3>")
	)
	(segment
		(start 75.955906 -290.16198)
		(end 75.703684 -290.16198)
		(width 0.12954)
		(layer "F.Cu")
		(net "M_A_CPU1_SB_DQS_DP<3>")
	)
	(segment
		(start 60.226448 -313.199018)
		(end 59.962796 -312.935366)
		(width 0.12954)
		(layer "F.Cu")
		(net "M_A_CPU1_SB_DQS_DP<3>")
	)
	(segment
		(start 72.16775 -301.76724)
		(end 71.985378 -301.76724)
		(width 0.12954)
		(layer "F.Cu")
		(net "M_A_CPU1_SB_DQS_DP<3>")
	)
	(segment
		(start 72.732392 -300.240954)
		(end 72.281288 -300.240954)
		(width 0.12954)
		(layer "F.Cu")
		(net "M_A_CPU1_SB_DQS_DP<3>")
	)
	(segment
		(start 69.662802 -303.310544)
		(end 70.052438 -303.70018)
		(width 0.12954)
		(layer "F.Cu")
		(net "M_A_CPU1_SB_DQS_DP<3>")
	)
	(segment
		(start 59.962796 -312.935366)
		(end 59.428126 -312.935366)
		(width 0.12954)
		(layer "F.Cu")
		(net "M_A_CPU1_SB_DQS_DP<3>")
	)
	(segment
		(start 70.799452 -302.173894)
		(end 71.189088 -302.56353)
		(width 0.12954)
		(layer "F.Cu")
		(net "M_A_CPU1_SB_DQS_DP<3>")
	)
	(segment
		(start 75.974956 -290.16198)
		(end 75.955906 -290.16198)
		(width 0.0762)
		(layer "F.Cu")
		(net "M_A_CPU1_SB_DQS_DP<3>")
	)
	(segment
		(start 77.323696 -290.22802)
		(end 76.040996 -290.22802)
		(width 0.0762)
		(layer "F.Cu")
		(net "M_A_CPU1_SB_DQS_DP<3>")
	)
	(segment
		(start 73.072752 -299.900594)
		(end 73.462388 -300.29023)
		(width 0.12954)
		(layer "F.Cu")
		(net "M_A_CPU1_SB_DQS_DP<3>")
	)
	(segment
		(start 73.462388 -300.29023)
		(end 73.462388 -300.472602)
		(width 0.12954)
		(layer "F.Cu")
		(net "M_A_CPU1_SB_DQS_DP<3>")
	)
	(segment
		(start 68.871338 -303.650904)
		(end 68.370958 -304.151284)
		(width 0.12954)
		(layer "F.Cu")
		(net "M_A_CPU1_SB_DQS_DP<3>")
	)
	(segment
		(start 69.662802 -302.85944)
		(end 69.662802 -303.310544)
		(width 0.12954)
		(layer "F.Cu")
		(net "M_A_CPU1_SB_DQS_DP<3>")
	)
	(segment
		(start 78.237842 -290.020248)
		(end 78.33614 -290.189412)
		(width 0.0762)
		(layer "F.Cu")
		(net "M_A_CPU1_SB_DQS_DP<3>")
	)
	(segment
		(start 71.0311 -302.90389)
		(end 70.848728 -302.90389)
		(width 0.12954)
		(layer "F.Cu")
		(net "M_A_CPU1_SB_DQS_DP<3>")
	)
	(segment
		(start 70.052438 -303.882552)
		(end 69.89445 -304.04054)
		(width 0.12954)
		(layer "F.Cu")
		(net "M_A_CPU1_SB_DQS_DP<3>")
	)
	(segment
		(start 69.322442 -303.650904)
		(end 68.871338 -303.650904)
		(width 0.12954)
		(layer "F.Cu")
		(net "M_A_CPU1_SB_DQS_DP<3>")
	)
	(segment
		(start 73.815956 -298.706286)
		(end 73.072752 -299.44949)
		(width 0.12954)
		(layer "F.Cu")
		(net "M_A_CPU1_SB_DQS_DP<3>")
	)
	(segment
		(start 70.459092 -302.514254)
		(end 70.007988 -302.514254)
		(width 0.12954)
		(layer "F.Cu")
		(net "M_A_CPU1_SB_DQS_DP<3>")
	)
	(arc
		(start 78.198472 -290.391088)
		(mid 78.126734 -290.376236)
		(end 78.05928 -290.347654)
		(width 0.0762)
		(layer "F.Cu")
		(net "M_A_CPU1_SB_DQS_DP<3>")
	)
	(arc
		(start 78.33614 -290.189412)
		(mid 78.327547 -290.331291)
		(end 78.198472 -290.391088)
		(width 0.0762)
		(layer "F.Cu")
		(net "M_A_CPU1_SB_DQS_DP<3>")
	)
	(arc
		(start 78.050898 -290.342828)
		(mid 77.914462 -290.286003)
		(end 77.767942 -290.266628)
		(width 0.0762)
		(layer "F.Cu")
		(net "M_A_CPU1_SB_DQS_DP<3>")
	)
	(segment
		(start 63.755016 -300.448726)
		(end 63.40983 -300.793912)
		(width 0.12954)
		(layer "F.Cu")
		(net "M_A_CPU1_SB_DQS_DP<2>")
	)
	(segment
		(start 65.88506 -299.356018)
		(end 65.727072 -299.514006)
		(width 0.12954)
		(layer "F.Cu")
		(net "M_A_CPU1_SB_DQS_DP<2>")
	)
	(segment
		(start 64.20612 -300.448726)
		(end 63.755016 -300.448726)
		(width 0.12954)
		(layer "F.Cu")
		(net "M_A_CPU1_SB_DQS_DP<2>")
	)
	(segment
		(start 77.265022 -285.309564)
		(end 76.040996 -285.309564)
		(width 0.0762)
		(layer "F.Cu")
		(net "M_A_CPU1_SB_DQS_DP<2>")
	)
	(segment
		(start 77.362304 -285.406846)
		(end 77.265022 -285.309564)
		(width 0.0762)
		(layer "F.Cu")
		(net "M_A_CPU1_SB_DQS_DP<2>")
	)
	(segment
		(start 61.93282 -302.722026)
		(end 61.481716 -302.722026)
		(width 0.12954)
		(layer "F.Cu")
		(net "M_A_CPU1_SB_DQS_DP<2>")
	)
	(segment
		(start 62.27318 -301.930562)
		(end 62.27318 -302.381666)
		(width 0.12954)
		(layer "F.Cu")
		(net "M_A_CPU1_SB_DQS_DP<2>")
	)
	(segment
		(start 67.818 -297.240706)
		(end 67.61607 -297.038776)
		(width 0.12954)
		(layer "F.Cu")
		(net "M_A_CPU1_SB_DQS_DP<2>")
	)
	(segment
		(start 69.09308 -295.110662)
		(end 69.09308 -295.561766)
		(width 0.12954)
		(layer "F.Cu")
		(net "M_A_CPU1_SB_DQS_DP<2>")
	)
	(segment
		(start 65.34277 -299.312076)
		(end 64.891666 -299.312076)
		(width 0.12954)
		(layer "F.Cu")
		(net "M_A_CPU1_SB_DQS_DP<2>")
	)
	(segment
		(start 62.27318 -302.381666)
		(end 62.47511 -302.583596)
		(width 0.12954)
		(layer "F.Cu")
		(net "M_A_CPU1_SB_DQS_DP<2>")
	)
	(segment
		(start 69.29501 -295.946068)
		(end 69.137022 -296.104056)
		(width 0.12954)
		(layer "F.Cu")
		(net "M_A_CPU1_SB_DQS_DP<2>")
	)
	(segment
		(start 66.81978 -297.835066)
		(end 67.02171 -298.036996)
		(width 0.12954)
		(layer "F.Cu")
		(net "M_A_CPU1_SB_DQS_DP<2>")
	)
	(segment
		(start 64.54648 -299.657262)
		(end 64.54648 -300.108366)
		(width 0.12954)
		(layer "F.Cu")
		(net "M_A_CPU1_SB_DQS_DP<2>")
	)
	(segment
		(start 60.150248 -303.849024)
		(end 59.886596 -303.585372)
		(width 0.12954)
		(layer "F.Cu")
		(net "M_A_CPU1_SB_DQS_DP<2>")
	)
	(segment
		(start 74.26198 -285.243524)
		(end 69.387974 -290.11753)
		(width 0.12954)
		(layer "F.Cu")
		(net "M_A_CPU1_SB_DQS_DP<2>")
	)
	(segment
		(start 65.5447 -299.514006)
		(end 65.34277 -299.312076)
		(width 0.12954)
		(layer "F.Cu")
		(net "M_A_CPU1_SB_DQS_DP<2>")
	)
	(segment
		(start 59.886596 -303.585372)
		(end 59.428126 -303.585372)
		(width 0.12954)
		(layer "F.Cu")
		(net "M_A_CPU1_SB_DQS_DP<2>")
	)
	(segment
		(start 67.61607 -297.038776)
		(end 67.164966 -297.038776)
		(width 0.12954)
		(layer "F.Cu")
		(net "M_A_CPU1_SB_DQS_DP<2>")
	)
	(segment
		(start 65.68313 -298.971716)
		(end 65.88506 -299.173646)
		(width 0.12954)
		(layer "F.Cu")
		(net "M_A_CPU1_SB_DQS_DP<2>")
	)
	(segment
		(start 67.164966 -297.038776)
		(end 66.81978 -297.383962)
		(width 0.12954)
		(layer "F.Cu")
		(net "M_A_CPU1_SB_DQS_DP<2>")
	)
	(segment
		(start 68.75272 -295.902126)
		(end 68.301616 -295.902126)
		(width 0.12954)
		(layer "F.Cu")
		(net "M_A_CPU1_SB_DQS_DP<2>")
	)
	(segment
		(start 68.301616 -295.902126)
		(end 67.95643 -296.247312)
		(width 0.12954)
		(layer "F.Cu")
		(net "M_A_CPU1_SB_DQS_DP<2>")
	)
	(segment
		(start 65.88506 -299.173646)
		(end 65.88506 -299.356018)
		(width 0.12954)
		(layer "F.Cu")
		(net "M_A_CPU1_SB_DQS_DP<2>")
	)
	(segment
		(start 66.68135 -298.377356)
		(end 66.47942 -298.175426)
		(width 0.12954)
		(layer "F.Cu")
		(net "M_A_CPU1_SB_DQS_DP<2>")
	)
	(segment
		(start 66.81978 -297.383962)
		(end 66.81978 -297.835066)
		(width 0.12954)
		(layer "F.Cu")
		(net "M_A_CPU1_SB_DQS_DP<2>")
	)
	(segment
		(start 77.767942 -285.406846)
		(end 77.362304 -285.406846)
		(width 0.0762)
		(layer "F.Cu")
		(net "M_A_CPU1_SB_DQS_DP<2>")
	)
	(segment
		(start 67.02171 -298.036996)
		(end 67.02171 -298.219368)
		(width 0.12954)
		(layer "F.Cu")
		(net "M_A_CPU1_SB_DQS_DP<2>")
	)
	(segment
		(start 64.54648 -300.108366)
		(end 64.74841 -300.310296)
		(width 0.12954)
		(layer "F.Cu")
		(net "M_A_CPU1_SB_DQS_DP<2>")
	)
	(segment
		(start 64.74841 -300.310296)
		(end 64.74841 -300.492668)
		(width 0.12954)
		(layer "F.Cu")
		(net "M_A_CPU1_SB_DQS_DP<2>")
	)
	(segment
		(start 62.618366 -301.585376)
		(end 62.27318 -301.930562)
		(width 0.12954)
		(layer "F.Cu")
		(net "M_A_CPU1_SB_DQS_DP<2>")
	)
	(segment
		(start 75.955906 -285.243524)
		(end 74.26198 -285.243524)
		(width 0.12954)
		(layer "F.Cu")
		(net "M_A_CPU1_SB_DQS_DP<2>")
	)
	(segment
		(start 66.028316 -298.175426)
		(end 65.68313 -298.520612)
		(width 0.12954)
		(layer "F.Cu")
		(net "M_A_CPU1_SB_DQS_DP<2>")
	)
	(segment
		(start 62.47511 -302.583596)
		(end 62.47511 -302.765968)
		(width 0.12954)
		(layer "F.Cu")
		(net "M_A_CPU1_SB_DQS_DP<2>")
	)
	(segment
		(start 63.61176 -301.629318)
		(end 63.453772 -301.787306)
		(width 0.12954)
		(layer "F.Cu")
		(net "M_A_CPU1_SB_DQS_DP<2>")
	)
	(segment
		(start 66.863722 -298.377356)
		(end 66.68135 -298.377356)
		(width 0.12954)
		(layer "F.Cu")
		(net "M_A_CPU1_SB_DQS_DP<2>")
	)
	(segment
		(start 67.95643 -296.698416)
		(end 68.15836 -296.900346)
		(width 0.12954)
		(layer "F.Cu")
		(net "M_A_CPU1_SB_DQS_DP<2>")
	)
	(segment
		(start 63.453772 -301.787306)
		(end 63.2714 -301.787306)
		(width 0.12954)
		(layer "F.Cu")
		(net "M_A_CPU1_SB_DQS_DP<2>")
	)
	(segment
		(start 78.237842 -285.160466)
		(end 78.33614 -285.32963)
		(width 0.0762)
		(layer "F.Cu")
		(net "M_A_CPU1_SB_DQS_DP<2>")
	)
	(segment
		(start 69.09308 -295.561766)
		(end 69.29501 -295.763696)
		(width 0.12954)
		(layer "F.Cu")
		(net "M_A_CPU1_SB_DQS_DP<2>")
	)
	(segment
		(start 75.974956 -285.243524)
		(end 75.955906 -285.243524)
		(width 0.0762)
		(layer "F.Cu")
		(net "M_A_CPU1_SB_DQS_DP<2>")
	)
	(segment
		(start 68.15836 -296.900346)
		(end 68.15836 -297.082718)
		(width 0.12954)
		(layer "F.Cu")
		(net "M_A_CPU1_SB_DQS_DP<2>")
	)
	(segment
		(start 61.481716 -302.722026)
		(end 60.354718 -303.849024)
		(width 0.12954)
		(layer "F.Cu")
		(net "M_A_CPU1_SB_DQS_DP<2>")
	)
	(segment
		(start 68.15836 -297.082718)
		(end 68.000372 -297.240706)
		(width 0.12954)
		(layer "F.Cu")
		(net "M_A_CPU1_SB_DQS_DP<2>")
	)
	(segment
		(start 67.02171 -298.219368)
		(end 66.863722 -298.377356)
		(width 0.12954)
		(layer "F.Cu")
		(net "M_A_CPU1_SB_DQS_DP<2>")
	)
	(segment
		(start 63.06947 -301.585376)
		(end 62.618366 -301.585376)
		(width 0.12954)
		(layer "F.Cu")
		(net "M_A_CPU1_SB_DQS_DP<2>")
	)
	(segment
		(start 78.05928 -285.487872)
		(end 78.050898 -285.483046)
		(width 0.0762)
		(layer "F.Cu")
		(net "M_A_CPU1_SB_DQS_DP<2>")
	)
	(segment
		(start 65.68313 -298.520612)
		(end 65.68313 -298.971716)
		(width 0.12954)
		(layer "F.Cu")
		(net "M_A_CPU1_SB_DQS_DP<2>")
	)
	(segment
		(start 62.317122 -302.923956)
		(end 62.13475 -302.923956)
		(width 0.12954)
		(layer "F.Cu")
		(net "M_A_CPU1_SB_DQS_DP<2>")
	)
	(segment
		(start 63.61176 -301.446946)
		(end 63.61176 -301.629318)
		(width 0.12954)
		(layer "F.Cu")
		(net "M_A_CPU1_SB_DQS_DP<2>")
	)
	(segment
		(start 69.137022 -296.104056)
		(end 68.95465 -296.104056)
		(width 0.12954)
		(layer "F.Cu")
		(net "M_A_CPU1_SB_DQS_DP<2>")
	)
	(segment
		(start 68.95465 -296.104056)
		(end 68.75272 -295.902126)
		(width 0.12954)
		(layer "F.Cu")
		(net "M_A_CPU1_SB_DQS_DP<2>")
	)
	(segment
		(start 62.13475 -302.923956)
		(end 61.93282 -302.722026)
		(width 0.12954)
		(layer "F.Cu")
		(net "M_A_CPU1_SB_DQS_DP<2>")
	)
	(segment
		(start 64.40805 -300.650656)
		(end 64.20612 -300.448726)
		(width 0.12954)
		(layer "F.Cu")
		(net "M_A_CPU1_SB_DQS_DP<2>")
	)
	(segment
		(start 60.354718 -303.849024)
		(end 60.150248 -303.849024)
		(width 0.12954)
		(layer "F.Cu")
		(net "M_A_CPU1_SB_DQS_DP<2>")
	)
	(segment
		(start 63.40983 -301.245016)
		(end 63.61176 -301.446946)
		(width 0.12954)
		(layer "F.Cu")
		(net "M_A_CPU1_SB_DQS_DP<2>")
	)
	(segment
		(start 64.74841 -300.492668)
		(end 64.590422 -300.650656)
		(width 0.12954)
		(layer "F.Cu")
		(net "M_A_CPU1_SB_DQS_DP<2>")
	)
	(segment
		(start 63.40983 -300.793912)
		(end 63.40983 -301.245016)
		(width 0.12954)
		(layer "F.Cu")
		(net "M_A_CPU1_SB_DQS_DP<2>")
	)
	(segment
		(start 62.47511 -302.765968)
		(end 62.317122 -302.923956)
		(width 0.12954)
		(layer "F.Cu")
		(net "M_A_CPU1_SB_DQS_DP<2>")
	)
	(segment
		(start 64.590422 -300.650656)
		(end 64.40805 -300.650656)
		(width 0.12954)
		(layer "F.Cu")
		(net "M_A_CPU1_SB_DQS_DP<2>")
	)
	(segment
		(start 68.000372 -297.240706)
		(end 67.818 -297.240706)
		(width 0.12954)
		(layer "F.Cu")
		(net "M_A_CPU1_SB_DQS_DP<2>")
	)
	(segment
		(start 63.2714 -301.787306)
		(end 63.06947 -301.585376)
		(width 0.12954)
		(layer "F.Cu")
		(net "M_A_CPU1_SB_DQS_DP<2>")
	)
	(segment
		(start 69.387974 -290.11753)
		(end 69.387974 -294.815768)
		(width 0.12954)
		(layer "F.Cu")
		(net "M_A_CPU1_SB_DQS_DP<2>")
	)
	(segment
		(start 65.727072 -299.514006)
		(end 65.5447 -299.514006)
		(width 0.12954)
		(layer "F.Cu")
		(net "M_A_CPU1_SB_DQS_DP<2>")
	)
	(segment
		(start 64.891666 -299.312076)
		(end 64.54648 -299.657262)
		(width 0.12954)
		(layer "F.Cu")
		(net "M_A_CPU1_SB_DQS_DP<2>")
	)
	(segment
		(start 67.95643 -296.247312)
		(end 67.95643 -296.698416)
		(width 0.12954)
		(layer "F.Cu")
		(net "M_A_CPU1_SB_DQS_DP<2>")
	)
	(segment
		(start 69.387974 -294.815768)
		(end 69.09308 -295.110662)
		(width 0.12954)
		(layer "F.Cu")
		(net "M_A_CPU1_SB_DQS_DP<2>")
	)
	(segment
		(start 69.29501 -295.763696)
		(end 69.29501 -295.946068)
		(width 0.12954)
		(layer "F.Cu")
		(net "M_A_CPU1_SB_DQS_DP<2>")
	)
	(segment
		(start 76.040996 -285.309564)
		(end 75.974956 -285.243524)
		(width 0.0762)
		(layer "F.Cu")
		(net "M_A_CPU1_SB_DQS_DP<2>")
	)
	(segment
		(start 66.47942 -298.175426)
		(end 66.028316 -298.175426)
		(width 0.12954)
		(layer "F.Cu")
		(net "M_A_CPU1_SB_DQS_DP<2>")
	)
	(arc
		(start 78.050898 -285.483046)
		(mid 77.914462 -285.426221)
		(end 77.767942 -285.406846)
		(width 0.0762)
		(layer "F.Cu")
		(net "M_A_CPU1_SB_DQS_DP<2>")
	)
	(arc
		(start 78.33614 -285.32963)
		(mid 78.327547 -285.471509)
		(end 78.198472 -285.531306)
		(width 0.0762)
		(layer "F.Cu")
		(net "M_A_CPU1_SB_DQS_DP<2>")
	)
	(arc
		(start 78.198472 -285.531306)
		(mid 78.126734 -285.516454)
		(end 78.05928 -285.487872)
		(width 0.0762)
		(layer "F.Cu")
		(net "M_A_CPU1_SB_DQS_DP<2>")
	)
	(segment
		(start 67.14617 -286.103568)
		(end 66.596006 -286.103568)
		(width 0.12954)
		(layer "F.Cu")
		(net "M_A_CPU1_SB_DQS_DP<1>")
	)
	(segment
		(start 63.733172 -291.898578)
		(end 63.733172 -292.445186)
		(width 0.12954)
		(layer "F.Cu")
		(net "M_A_CPU1_SB_DQS_DP<1>")
	)
	(segment
		(start 61.773054 -292.5572)
		(end 61.322966 -292.557454)
		(width 0.12954)
		(layer "F.Cu")
		(net "M_A_CPU1_SB_DQS_DP<1>")
	)
	(segment
		(start 61.679328 -294.49903)
		(end 60.226448 -294.49903)
		(width 0.12954)
		(layer "F.Cu")
		(net "M_A_CPU1_SB_DQS_DP<1>")
	)
	(segment
		(start 75.955906 -280.315924)
		(end 72.38365 -280.315924)
		(width 0.12954)
		(layer "F.Cu")
		(net "M_A_CPU1_SB_DQS_DP<1>")
	)
	(segment
		(start 62.605412 -293.389558)
		(end 61.773054 -292.5572)
		(width 0.12954)
		(layer "F.Cu")
		(net "M_A_CPU1_SB_DQS_DP<1>")
	)
	(segment
		(start 67.732656 -284.966918)
		(end 67.345814 -285.35376)
		(width 0.12954)
		(layer "F.Cu")
		(net "M_A_CPU1_SB_DQS_DP<1>")
	)
	(segment
		(start 63.733172 -292.445186)
		(end 62.7888 -293.389558)
		(width 0.12954)
		(layer "F.Cu")
		(net "M_A_CPU1_SB_DQS_DP<1>")
	)
	(segment
		(start 70.755764 -282.493974)
		(end 70.55612 -282.693618)
		(width 0.12954)
		(layer "F.Cu")
		(net "M_A_CPU1_SB_DQS_DP<1>")
	)
	(segment
		(start 70.755764 -281.94381)
		(end 70.755764 -282.493974)
		(width 0.12954)
		(layer "F.Cu")
		(net "M_A_CPU1_SB_DQS_DP<1>")
	)
	(segment
		(start 67.345814 -285.903924)
		(end 67.14617 -286.103568)
		(width 0.12954)
		(layer "F.Cu")
		(net "M_A_CPU1_SB_DQS_DP<1>")
	)
	(segment
		(start 77.216508 -280.401014)
		(end 76.223876 -280.401014)
		(width 0.0762)
		(layer "F.Cu")
		(net "M_A_CPU1_SB_DQS_DP<1>")
	)
	(segment
		(start 71.142606 -281.556968)
		(end 70.755764 -281.94381)
		(width 0.12954)
		(layer "F.Cu")
		(net "M_A_CPU1_SB_DQS_DP<1>")
	)
	(segment
		(start 67.345814 -285.35376)
		(end 67.345814 -285.903924)
		(width 0.12954)
		(layer "F.Cu")
		(net "M_A_CPU1_SB_DQS_DP<1>")
	)
	(segment
		(start 77.362304 -280.54681)
		(end 77.216508 -280.401014)
		(width 0.0762)
		(layer "F.Cu")
		(net "M_A_CPU1_SB_DQS_DP<1>")
	)
	(segment
		(start 68.28282 -284.966918)
		(end 67.732656 -284.966918)
		(width 0.12954)
		(layer "F.Cu")
		(net "M_A_CPU1_SB_DQS_DP<1>")
	)
	(segment
		(start 68.482464 -284.767274)
		(end 68.28282 -284.966918)
		(width 0.12954)
		(layer "F.Cu")
		(net "M_A_CPU1_SB_DQS_DP<1>")
	)
	(segment
		(start 64.58077 -289.085782)
		(end 64.956436 -289.461448)
		(width 0.12954)
		(layer "F.Cu")
		(net "M_A_CPU1_SB_DQS_DP<1>")
	)
	(segment
		(start 68.869306 -283.830268)
		(end 68.482464 -284.21711)
		(width 0.12954)
		(layer "F.Cu")
		(net "M_A_CPU1_SB_DQS_DP<1>")
	)
	(segment
		(start 78.05928 -280.627836)
		(end 78.050898 -280.62301)
		(width 0.0762)
		(layer "F.Cu")
		(net "M_A_CPU1_SB_DQS_DP<1>")
	)
	(segment
		(start 75.974956 -280.315924)
		(end 75.955906 -280.315924)
		(width 0.0762)
		(layer "F.Cu")
		(net "M_A_CPU1_SB_DQS_DP<1>")
	)
	(segment
		(start 59.962796 -294.235378)
		(end 59.428126 -294.235378)
		(width 0.12954)
		(layer "F.Cu")
		(net "M_A_CPU1_SB_DQS_DP<1>")
	)
	(segment
		(start 70.55612 -282.693618)
		(end 70.005956 -282.693618)
		(width 0.12954)
		(layer "F.Cu")
		(net "M_A_CPU1_SB_DQS_DP<1>")
	)
	(segment
		(start 66.596006 -286.103568)
		(end 66.209164 -286.49041)
		(width 0.12954)
		(layer "F.Cu")
		(net "M_A_CPU1_SB_DQS_DP<1>")
	)
	(segment
		(start 69.619114 -283.08046)
		(end 69.619114 -283.630624)
		(width 0.12954)
		(layer "F.Cu")
		(net "M_A_CPU1_SB_DQS_DP<1>")
	)
	(segment
		(start 62.7888 -293.389558)
		(end 62.605412 -293.389558)
		(width 0.12954)
		(layer "F.Cu")
		(net "M_A_CPU1_SB_DQS_DP<1>")
	)
	(segment
		(start 78.237842 -280.30043)
		(end 78.33614 -280.469594)
		(width 0.0762)
		(layer "F.Cu")
		(net "M_A_CPU1_SB_DQS_DP<1>")
	)
	(segment
		(start 65.459356 -287.240218)
		(end 64.956436 -287.743138)
		(width 0.12954)
		(layer "F.Cu")
		(net "M_A_CPU1_SB_DQS_DP<1>")
	)
	(segment
		(start 71.69277 -281.556968)
		(end 71.142606 -281.556968)
		(width 0.12954)
		(layer "F.Cu")
		(net "M_A_CPU1_SB_DQS_DP<1>")
	)
	(segment
		(start 70.005956 -282.693618)
		(end 69.619114 -283.08046)
		(width 0.12954)
		(layer "F.Cu")
		(net "M_A_CPU1_SB_DQS_DP<1>")
	)
	(segment
		(start 77.767942 -280.54681)
		(end 77.362304 -280.54681)
		(width 0.0762)
		(layer "F.Cu")
		(net "M_A_CPU1_SB_DQS_DP<1>")
	)
	(segment
		(start 64.58077 -288.524696)
		(end 64.58077 -289.085782)
		(width 0.12954)
		(layer "F.Cu")
		(net "M_A_CPU1_SB_DQS_DP<1>")
	)
	(segment
		(start 71.892414 -281.357324)
		(end 71.69277 -281.556968)
		(width 0.12954)
		(layer "F.Cu")
		(net "M_A_CPU1_SB_DQS_DP<1>")
	)
	(segment
		(start 61.322966 -292.557454)
		(end 60.976002 -292.904418)
		(width 0.12954)
		(layer "F.Cu")
		(net "M_A_CPU1_SB_DQS_DP<1>")
	)
	(segment
		(start 64.956436 -289.461448)
		(end 64.956436 -291.221922)
		(width 0.12954)
		(layer "F.Cu")
		(net "M_A_CPU1_SB_DQS_DP<1>")
	)
	(segment
		(start 60.226448 -294.49903)
		(end 59.962796 -294.235378)
		(width 0.12954)
		(layer "F.Cu")
		(net "M_A_CPU1_SB_DQS_DP<1>")
	)
	(segment
		(start 72.38365 -280.315924)
		(end 71.892414 -280.80716)
		(width 0.12954)
		(layer "F.Cu")
		(net "M_A_CPU1_SB_DQS_DP<1>")
	)
	(segment
		(start 76.040996 -280.381964)
		(end 75.974956 -280.315924)
		(width 0.0762)
		(layer "F.Cu")
		(net "M_A_CPU1_SB_DQS_DP<1>")
	)
	(segment
		(start 66.00952 -287.240218)
		(end 65.459356 -287.240218)
		(width 0.12954)
		(layer "F.Cu")
		(net "M_A_CPU1_SB_DQS_DP<1>")
	)
	(segment
		(start 64.956436 -288.14903)
		(end 64.58077 -288.524696)
		(width 0.12954)
		(layer "F.Cu")
		(net "M_A_CPU1_SB_DQS_DP<1>")
	)
	(segment
		(start 61.808868 -294.36949)
		(end 61.679328 -294.49903)
		(width 0.12954)
		(layer "F.Cu")
		(net "M_A_CPU1_SB_DQS_DP<1>")
	)
	(segment
		(start 71.892414 -280.80716)
		(end 71.892414 -281.357324)
		(width 0.12954)
		(layer "F.Cu")
		(net "M_A_CPU1_SB_DQS_DP<1>")
	)
	(segment
		(start 66.209164 -287.040574)
		(end 66.00952 -287.240218)
		(width 0.12954)
		(layer "F.Cu")
		(net "M_A_CPU1_SB_DQS_DP<1>")
	)
	(segment
		(start 76.223876 -280.401014)
		(end 76.040996 -280.381964)
		(width 0.0762)
		(layer "F.Cu")
		(net "M_A_CPU1_SB_DQS_DP<1>")
	)
	(segment
		(start 68.482464 -284.21711)
		(end 68.482464 -284.767274)
		(width 0.12954)
		(layer "F.Cu")
		(net "M_A_CPU1_SB_DQS_DP<1>")
	)
	(segment
		(start 64.956436 -291.221922)
		(end 64.669924 -291.508434)
		(width 0.12954)
		(layer "F.Cu")
		(net "M_A_CPU1_SB_DQS_DP<1>")
	)
	(segment
		(start 64.123316 -291.508434)
		(end 63.733172 -291.898578)
		(width 0.12954)
		(layer "F.Cu")
		(net "M_A_CPU1_SB_DQS_DP<1>")
	)
	(segment
		(start 60.976002 -292.904418)
		(end 60.976256 -293.353998)
		(width 0.12954)
		(layer "F.Cu")
		(net "M_A_CPU1_SB_DQS_DP<1>")
	)
	(segment
		(start 69.619114 -283.630624)
		(end 69.41947 -283.830268)
		(width 0.12954)
		(layer "F.Cu")
		(net "M_A_CPU1_SB_DQS_DP<1>")
	)
	(segment
		(start 64.669924 -291.508434)
		(end 64.123316 -291.508434)
		(width 0.12954)
		(layer "F.Cu")
		(net "M_A_CPU1_SB_DQS_DP<1>")
	)
	(segment
		(start 60.976256 -293.353998)
		(end 61.808868 -294.18661)
		(width 0.12954)
		(layer "F.Cu")
		(net "M_A_CPU1_SB_DQS_DP<1>")
	)
	(segment
		(start 61.808868 -294.18661)
		(end 61.808868 -294.36949)
		(width 0.12954)
		(layer "F.Cu")
		(net "M_A_CPU1_SB_DQS_DP<1>")
	)
	(segment
		(start 66.209164 -286.49041)
		(end 66.209164 -287.040574)
		(width 0.12954)
		(layer "F.Cu")
		(net "M_A_CPU1_SB_DQS_DP<1>")
	)
	(segment
		(start 69.41947 -283.830268)
		(end 68.869306 -283.830268)
		(width 0.12954)
		(layer "F.Cu")
		(net "M_A_CPU1_SB_DQS_DP<1>")
	)
	(segment
		(start 64.956436 -287.743138)
		(end 64.956436 -288.14903)
		(width 0.12954)
		(layer "F.Cu")
		(net "M_A_CPU1_SB_DQS_DP<1>")
	)
	(arc
		(start 78.198472 -280.67127)
		(mid 78.126734 -280.656418)
		(end 78.05928 -280.627836)
		(width 0.0762)
		(layer "F.Cu")
		(net "M_A_CPU1_SB_DQS_DP<1>")
	)
	(arc
		(start 78.050898 -280.62301)
		(mid 77.914462 -280.566185)
		(end 77.767942 -280.54681)
		(width 0.0762)
		(layer "F.Cu")
		(net "M_A_CPU1_SB_DQS_DP<1>")
	)
	(arc
		(start 78.33614 -280.469594)
		(mid 78.327547 -280.611473)
		(end 78.198472 -280.67127)
		(width 0.0762)
		(layer "F.Cu")
		(net "M_A_CPU1_SB_DQS_DP<1>")
	)
	(segment
		(start 67.029584 -277.695152)
		(end 66.684398 -278.040338)
		(width 0.12954)
		(layer "F.Cu")
		(net "M_A_CPU1_SB_DQS_DP<0>")
	)
	(segment
		(start 67.921124 -277.63724)
		(end 67.763136 -277.795228)
		(width 0.12954)
		(layer "F.Cu")
		(net "M_A_CPU1_SB_DQS_DP<0>")
	)
	(segment
		(start 65.547748 -279.176988)
		(end 65.547748 -279.628092)
		(width 0.12954)
		(layer "F.Cu")
		(net "M_A_CPU1_SB_DQS_DP<0>")
	)
	(segment
		(start 64.070738 -281.105102)
		(end 63.619634 -281.105102)
		(width 0.12954)
		(layer "F.Cu")
		(net "M_A_CPU1_SB_DQS_DP<0>")
	)
	(segment
		(start 61.897514 -283.478478)
		(end 61.797438 -283.378402)
		(width 0.12954)
		(layer "F.Cu")
		(net "M_A_CPU1_SB_DQS_DP<0>")
	)
	(segment
		(start 76.803758 -275.686774)
		(end 76.48448 -275.367496)
		(width 0.0762)
		(layer "F.Cu")
		(net "M_A_CPU1_SB_DQS_DP<0>")
	)
	(segment
		(start 64.511174 -281.04719)
		(end 64.353186 -281.205178)
		(width 0.12954)
		(layer "F.Cu")
		(net "M_A_CPU1_SB_DQS_DP<0>")
	)
	(segment
		(start 64.411098 -280.764742)
		(end 64.511174 -280.864818)
		(width 0.12954)
		(layer "F.Cu")
		(net "M_A_CPU1_SB_DQS_DP<0>")
	)
	(segment
		(start 76.48448 -275.367496)
		(end 76.1746 -275.367496)
		(width 0.0762)
		(layer "F.Cu")
		(net "M_A_CPU1_SB_DQS_DP<0>")
	)
	(segment
		(start 76.08951 -275.301456)
		(end 75.75931 -275.301456)
		(width 0.12954)
		(layer "F.Cu")
		(net "M_A_CPU1_SB_DQS_DP<0>")
	)
	(segment
		(start 73.166224 -275.301456)
		(end 72.547734 -275.301456)
		(width 0.12954)
		(layer "F.Cu")
		(net "M_A_CPU1_SB_DQS_DP<0>")
	)
	(segment
		(start 68.899786 -276.658578)
		(end 68.717414 -276.658578)
		(width 0.12954)
		(layer "F.Cu")
		(net "M_A_CPU1_SB_DQS_DP<0>")
	)
	(segment
		(start 68.717414 -276.658578)
		(end 68.617338 -276.558502)
		(width 0.12954)
		(layer "F.Cu")
		(net "M_A_CPU1_SB_DQS_DP<0>")
	)
	(segment
		(start 65.489836 -280.068528)
		(end 65.307464 -280.068528)
		(width 0.12954)
		(layer "F.Cu")
		(net "M_A_CPU1_SB_DQS_DP<0>")
	)
	(segment
		(start 65.892934 -278.831802)
		(end 65.547748 -279.176988)
		(width 0.12954)
		(layer "F.Cu")
		(net "M_A_CPU1_SB_DQS_DP<0>")
	)
	(segment
		(start 78.05928 -275.7678)
		(end 78.050898 -275.762974)
		(width 0.0762)
		(layer "F.Cu")
		(net "M_A_CPU1_SB_DQS_DP<0>")
	)
	(segment
		(start 66.444114 -278.931878)
		(end 66.344038 -278.831802)
		(width 0.12954)
		(layer "F.Cu")
		(net "M_A_CPU1_SB_DQS_DP<0>")
	)
	(segment
		(start 62.482984 -282.241752)
		(end 62.137798 -282.586938)
		(width 0.12954)
		(layer "F.Cu")
		(net "M_A_CPU1_SB_DQS_DP<0>")
	)
	(segment
		(start 62.137798 -282.586938)
		(end 62.137798 -283.038042)
		(width 0.12954)
		(layer "F.Cu")
		(net "M_A_CPU1_SB_DQS_DP<0>")
	)
	(segment
		(start 66.684398 -278.491442)
		(end 66.784474 -278.591518)
		(width 0.12954)
		(layer "F.Cu")
		(net "M_A_CPU1_SB_DQS_DP<0>")
	)
	(segment
		(start 60.490354 -285.149036)
		(end 60.226448 -285.149036)
		(width 0.12954)
		(layer "F.Cu")
		(net "M_A_CPU1_SB_DQS_DP<0>")
	)
	(segment
		(start 78.237842 -275.440394)
		(end 78.33614 -275.609558)
		(width 0.0762)
		(layer "F.Cu")
		(net "M_A_CPU1_SB_DQS_DP<0>")
	)
	(segment
		(start 67.763136 -277.795228)
		(end 67.580764 -277.795228)
		(width 0.12954)
		(layer "F.Cu")
		(net "M_A_CPU1_SB_DQS_DP<0>")
	)
	(segment
		(start 65.647824 -279.728168)
		(end 65.647824 -279.91054)
		(width 0.12954)
		(layer "F.Cu")
		(net "M_A_CPU1_SB_DQS_DP<0>")
	)
	(segment
		(start 69.954648 -275.301456)
		(end 69.42328 -275.301456)
		(width 0.12954)
		(layer "F.Cu")
		(net "M_A_CPU1_SB_DQS_DP<0>")
	)
	(segment
		(start 69.42328 -275.301456)
		(end 68.957698 -275.767038)
		(width 0.12954)
		(layer "F.Cu")
		(net "M_A_CPU1_SB_DQS_DP<0>")
	)
	(segment
		(start 75.039982 -275.569426)
		(end 74.772012 -275.301456)
		(width 0.12954)
		(layer "F.Cu")
		(net "M_A_CPU1_SB_DQS_DP<0>")
	)
	(segment
		(start 68.166234 -276.558502)
		(end 67.821048 -276.903688)
		(width 0.12954)
		(layer "F.Cu")
		(net "M_A_CPU1_SB_DQS_DP<0>")
	)
	(segment
		(start 77.767942 -275.686774)
		(end 76.803758 -275.686774)
		(width 0.0762)
		(layer "F.Cu")
		(net "M_A_CPU1_SB_DQS_DP<0>")
	)
	(segment
		(start 64.511174 -280.864818)
		(end 64.511174 -281.04719)
		(width 0.12954)
		(layer "F.Cu")
		(net "M_A_CPU1_SB_DQS_DP<0>")
	)
	(segment
		(start 76.1746 -275.367496)
		(end 76.10856 -275.301456)
		(width 0.0762)
		(layer "F.Cu")
		(net "M_A_CPU1_SB_DQS_DP<0>")
	)
	(segment
		(start 66.626486 -278.931878)
		(end 66.444114 -278.931878)
		(width 0.12954)
		(layer "F.Cu")
		(net "M_A_CPU1_SB_DQS_DP<0>")
	)
	(segment
		(start 63.034164 -282.341828)
		(end 62.934088 -282.241752)
		(width 0.12954)
		(layer "F.Cu")
		(net "M_A_CPU1_SB_DQS_DP<0>")
	)
	(segment
		(start 68.617338 -276.558502)
		(end 68.166234 -276.558502)
		(width 0.12954)
		(layer "F.Cu")
		(net "M_A_CPU1_SB_DQS_DP<0>")
	)
	(segment
		(start 63.374524 -282.18384)
		(end 63.216536 -282.341828)
		(width 0.12954)
		(layer "F.Cu")
		(net "M_A_CPU1_SB_DQS_DP<0>")
	)
	(segment
		(start 63.374524 -282.001468)
		(end 63.374524 -282.18384)
		(width 0.12954)
		(layer "F.Cu")
		(net "M_A_CPU1_SB_DQS_DP<0>")
	)
	(segment
		(start 62.934088 -282.241752)
		(end 62.482984 -282.241752)
		(width 0.12954)
		(layer "F.Cu")
		(net "M_A_CPU1_SB_DQS_DP<0>")
	)
	(segment
		(start 71.560436 -275.301456)
		(end 70.941946 -275.301456)
		(width 0.12954)
		(layer "F.Cu")
		(net "M_A_CPU1_SB_DQS_DP<0>")
	)
	(segment
		(start 65.647824 -279.91054)
		(end 65.489836 -280.068528)
		(width 0.12954)
		(layer "F.Cu")
		(net "M_A_CPU1_SB_DQS_DP<0>")
	)
	(segment
		(start 74.153522 -275.301456)
		(end 73.885552 -275.569426)
		(width 0.12954)
		(layer "F.Cu")
		(net "M_A_CPU1_SB_DQS_DP<0>")
	)
	(segment
		(start 67.821048 -277.354792)
		(end 67.921124 -277.454868)
		(width 0.12954)
		(layer "F.Cu")
		(net "M_A_CPU1_SB_DQS_DP<0>")
	)
	(segment
		(start 64.353186 -281.205178)
		(end 64.170814 -281.205178)
		(width 0.12954)
		(layer "F.Cu")
		(net "M_A_CPU1_SB_DQS_DP<0>")
	)
	(segment
		(start 66.684398 -278.040338)
		(end 66.684398 -278.491442)
		(width 0.12954)
		(layer "F.Cu")
		(net "M_A_CPU1_SB_DQS_DP<0>")
	)
	(segment
		(start 62.237874 -283.138118)
		(end 62.237874 -283.32049)
		(width 0.12954)
		(layer "F.Cu")
		(net "M_A_CPU1_SB_DQS_DP<0>")
	)
	(segment
		(start 64.756284 -279.968452)
		(end 64.411098 -280.313638)
		(width 0.12954)
		(layer "F.Cu")
		(net "M_A_CPU1_SB_DQS_DP<0>")
	)
	(segment
		(start 73.434194 -275.569426)
		(end 73.166224 -275.301456)
		(width 0.12954)
		(layer "F.Cu")
		(net "M_A_CPU1_SB_DQS_DP<0>")
	)
	(segment
		(start 68.957698 -276.218142)
		(end 69.057774 -276.318218)
		(width 0.12954)
		(layer "F.Cu")
		(net "M_A_CPU1_SB_DQS_DP<0>")
	)
	(segment
		(start 61.346334 -283.378402)
		(end 60.816236 -283.9085)
		(width 0.12954)
		(layer "F.Cu")
		(net "M_A_CPU1_SB_DQS_DP<0>")
	)
	(segment
		(start 62.079886 -283.478478)
		(end 61.897514 -283.478478)
		(width 0.12954)
		(layer "F.Cu")
		(net "M_A_CPU1_SB_DQS_DP<0>")
	)
	(segment
		(start 75.49134 -275.569426)
		(end 75.039982 -275.569426)
		(width 0.12954)
		(layer "F.Cu")
		(net "M_A_CPU1_SB_DQS_DP<0>")
	)
	(segment
		(start 63.274448 -281.450288)
		(end 63.274448 -281.901392)
		(width 0.12954)
		(layer "F.Cu")
		(net "M_A_CPU1_SB_DQS_DP<0>")
	)
	(segment
		(start 73.885552 -275.569426)
		(end 73.434194 -275.569426)
		(width 0.12954)
		(layer "F.Cu")
		(net "M_A_CPU1_SB_DQS_DP<0>")
	)
	(segment
		(start 76.10856 -275.301456)
		(end 76.08951 -275.301456)
		(width 0.0762)
		(layer "F.Cu")
		(net "M_A_CPU1_SB_DQS_DP<0>")
	)
	(segment
		(start 67.921124 -277.454868)
		(end 67.921124 -277.63724)
		(width 0.12954)
		(layer "F.Cu")
		(net "M_A_CPU1_SB_DQS_DP<0>")
	)
	(segment
		(start 68.957698 -275.767038)
		(end 68.957698 -276.218142)
		(width 0.12954)
		(layer "F.Cu")
		(net "M_A_CPU1_SB_DQS_DP<0>")
	)
	(segment
		(start 64.411098 -280.313638)
		(end 64.411098 -280.764742)
		(width 0.12954)
		(layer "F.Cu")
		(net "M_A_CPU1_SB_DQS_DP<0>")
	)
	(segment
		(start 69.057774 -276.318218)
		(end 69.057774 -276.50059)
		(width 0.12954)
		(layer "F.Cu")
		(net "M_A_CPU1_SB_DQS_DP<0>")
	)
	(segment
		(start 62.137798 -283.038042)
		(end 62.237874 -283.138118)
		(width 0.12954)
		(layer "F.Cu")
		(net "M_A_CPU1_SB_DQS_DP<0>")
	)
	(segment
		(start 66.344038 -278.831802)
		(end 65.892934 -278.831802)
		(width 0.12954)
		(layer "F.Cu")
		(net "M_A_CPU1_SB_DQS_DP<0>")
	)
	(segment
		(start 63.274448 -281.901392)
		(end 63.374524 -282.001468)
		(width 0.12954)
		(layer "F.Cu")
		(net "M_A_CPU1_SB_DQS_DP<0>")
	)
	(segment
		(start 67.821048 -276.903688)
		(end 67.821048 -277.354792)
		(width 0.12954)
		(layer "F.Cu")
		(net "M_A_CPU1_SB_DQS_DP<0>")
	)
	(segment
		(start 66.784474 -278.77389)
		(end 66.626486 -278.931878)
		(width 0.12954)
		(layer "F.Cu")
		(net "M_A_CPU1_SB_DQS_DP<0>")
	)
	(segment
		(start 65.547748 -279.628092)
		(end 65.647824 -279.728168)
		(width 0.12954)
		(layer "F.Cu")
		(net "M_A_CPU1_SB_DQS_DP<0>")
	)
	(segment
		(start 62.237874 -283.32049)
		(end 62.079886 -283.478478)
		(width 0.12954)
		(layer "F.Cu")
		(net "M_A_CPU1_SB_DQS_DP<0>")
	)
	(segment
		(start 60.816236 -283.9085)
		(end 60.816236 -284.823154)
		(width 0.12954)
		(layer "F.Cu")
		(net "M_A_CPU1_SB_DQS_DP<0>")
	)
	(segment
		(start 63.619634 -281.105102)
		(end 63.274448 -281.450288)
		(width 0.12954)
		(layer "F.Cu")
		(net "M_A_CPU1_SB_DQS_DP<0>")
	)
	(segment
		(start 72.279764 -275.569426)
		(end 71.828406 -275.569426)
		(width 0.12954)
		(layer "F.Cu")
		(net "M_A_CPU1_SB_DQS_DP<0>")
	)
	(segment
		(start 59.962796 -284.885384)
		(end 59.428126 -284.885384)
		(width 0.12954)
		(layer "F.Cu")
		(net "M_A_CPU1_SB_DQS_DP<0>")
	)
	(segment
		(start 65.207388 -279.968452)
		(end 64.756284 -279.968452)
		(width 0.12954)
		(layer "F.Cu")
		(net "M_A_CPU1_SB_DQS_DP<0>")
	)
	(segment
		(start 64.170814 -281.205178)
		(end 64.070738 -281.105102)
		(width 0.12954)
		(layer "F.Cu")
		(net "M_A_CPU1_SB_DQS_DP<0>")
	)
	(segment
		(start 72.547734 -275.301456)
		(end 72.279764 -275.569426)
		(width 0.12954)
		(layer "F.Cu")
		(net "M_A_CPU1_SB_DQS_DP<0>")
	)
	(segment
		(start 69.057774 -276.50059)
		(end 68.899786 -276.658578)
		(width 0.12954)
		(layer "F.Cu")
		(net "M_A_CPU1_SB_DQS_DP<0>")
	)
	(segment
		(start 63.216536 -282.341828)
		(end 63.034164 -282.341828)
		(width 0.12954)
		(layer "F.Cu")
		(net "M_A_CPU1_SB_DQS_DP<0>")
	)
	(segment
		(start 61.797438 -283.378402)
		(end 61.346334 -283.378402)
		(width 0.12954)
		(layer "F.Cu")
		(net "M_A_CPU1_SB_DQS_DP<0>")
	)
	(segment
		(start 74.772012 -275.301456)
		(end 74.153522 -275.301456)
		(width 0.12954)
		(layer "F.Cu")
		(net "M_A_CPU1_SB_DQS_DP<0>")
	)
	(segment
		(start 70.941946 -275.301456)
		(end 70.673976 -275.569426)
		(width 0.12954)
		(layer "F.Cu")
		(net "M_A_CPU1_SB_DQS_DP<0>")
	)
	(segment
		(start 70.222618 -275.569426)
		(end 69.954648 -275.301456)
		(width 0.12954)
		(layer "F.Cu")
		(net "M_A_CPU1_SB_DQS_DP<0>")
	)
	(segment
		(start 71.828406 -275.569426)
		(end 71.560436 -275.301456)
		(width 0.12954)
		(layer "F.Cu")
		(net "M_A_CPU1_SB_DQS_DP<0>")
	)
	(segment
		(start 60.816236 -284.823154)
		(end 60.490354 -285.149036)
		(width 0.12954)
		(layer "F.Cu")
		(net "M_A_CPU1_SB_DQS_DP<0>")
	)
	(segment
		(start 65.307464 -280.068528)
		(end 65.207388 -279.968452)
		(width 0.12954)
		(layer "F.Cu")
		(net "M_A_CPU1_SB_DQS_DP<0>")
	)
	(segment
		(start 67.580764 -277.795228)
		(end 67.480688 -277.695152)
		(width 0.12954)
		(layer "F.Cu")
		(net "M_A_CPU1_SB_DQS_DP<0>")
	)
	(segment
		(start 66.784474 -278.591518)
		(end 66.784474 -278.77389)
		(width 0.12954)
		(layer "F.Cu")
		(net "M_A_CPU1_SB_DQS_DP<0>")
	)
	(segment
		(start 70.673976 -275.569426)
		(end 70.222618 -275.569426)
		(width 0.12954)
		(layer "F.Cu")
		(net "M_A_CPU1_SB_DQS_DP<0>")
	)
	(segment
		(start 67.480688 -277.695152)
		(end 67.029584 -277.695152)
		(width 0.12954)
		(layer "F.Cu")
		(net "M_A_CPU1_SB_DQS_DP<0>")
	)
	(segment
		(start 75.75931 -275.301456)
		(end 75.49134 -275.569426)
		(width 0.12954)
		(layer "F.Cu")
		(net "M_A_CPU1_SB_DQS_DP<0>")
	)
	(segment
		(start 60.226448 -285.149036)
		(end 59.962796 -284.885384)
		(width 0.12954)
		(layer "F.Cu")
		(net "M_A_CPU1_SB_DQS_DP<0>")
	)
	(arc
		(start 78.33614 -275.609558)
		(mid 78.327547 -275.751437)
		(end 78.198472 -275.811234)
		(width 0.0762)
		(layer "F.Cu")
		(net "M_A_CPU1_SB_DQS_DP<0>")
	)
	(arc
		(start 78.050898 -275.762974)
		(mid 77.914462 -275.706149)
		(end 77.767942 -275.686774)
		(width 0.0762)
		(layer "F.Cu")
		(net "M_A_CPU1_SB_DQS_DP<0>")
	)
	(arc
		(start 78.198472 -275.811234)
		(mid 78.126734 -275.796382)
		(end 78.05928 -275.7678)
		(width 0.0762)
		(layer "F.Cu")
		(net "M_A_CPU1_SB_DQS_DP<0>")
	)
	(segment
		(start 63.067438 -274.154138)
		(end 62.67323 -274.548346)
		(width 0.12954)
		(layer "F.Cu")
		(net "M_A_CPU1_SB_DQS_DN<9>")
	)
	(segment
		(start 63.067438 -273.615658)
		(end 63.067438 -274.154138)
		(width 0.12954)
		(layer "F.Cu")
		(net "M_A_CPU1_SB_DQS_DN<9>")
	)
	(segment
		(start 70.812914 -270.441166)
		(end 70.494652 -270.122904)
		(width 0.12954)
		(layer "F.Cu")
		(net "M_A_CPU1_SB_DQS_DN<9>")
	)
	(segment
		(start 66.477388 -270.744188)
		(end 66.08318 -271.138396)
		(width 0.12954)
		(layer "F.Cu")
		(net "M_A_CPU1_SB_DQS_DN<9>")
	)
	(segment
		(start 76.398628 -271.083278)
		(end 76.379578 -271.083278)
		(width 0.0762)
		(layer "F.Cu")
		(net "M_A_CPU1_SB_DQS_DN<9>")
	)
	(segment
		(start 73.355454 -269.759176)
		(end 73.225914 -269.888716)
		(width 0.12954)
		(layer "F.Cu")
		(net "M_A_CPU1_SB_DQS_DN<9>")
	)
	(segment
		(start 62.67323 -274.548346)
		(end 62.13475 -274.548346)
		(width 0.12954)
		(layer "F.Cu")
		(net "M_A_CPU1_SB_DQS_DN<9>")
	)
	(segment
		(start 71.620126 -269.888716)
		(end 71.620126 -270.122904)
		(width 0.12954)
		(layer "F.Cu")
		(net "M_A_CPU1_SB_DQS_DN<9>")
	)
	(segment
		(start 67.283076 -269.888716)
		(end 67.153536 -269.759176)
		(width 0.12954)
		(layer "F.Cu")
		(net "M_A_CPU1_SB_DQS_DN<9>")
	)
	(segment
		(start 72.10044 -269.888716)
		(end 71.9709 -269.759176)
		(width 0.12954)
		(layer "F.Cu")
		(net "M_A_CPU1_SB_DQS_DN<9>")
	)
	(segment
		(start 71.749666 -269.759176)
		(end 71.620126 -269.888716)
		(width 0.12954)
		(layer "F.Cu")
		(net "M_A_CPU1_SB_DQS_DN<9>")
	)
	(segment
		(start 63.80988 -273.411696)
		(end 63.2714 -273.411696)
		(width 0.12954)
		(layer "F.Cu")
		(net "M_A_CPU1_SB_DQS_DN<9>")
	)
	(segment
		(start 64.40805 -272.275046)
		(end 64.204088 -272.479008)
		(width 0.12954)
		(layer "F.Cu")
		(net "M_A_CPU1_SB_DQS_DN<9>")
	)
	(segment
		(start 64.204088 -273.017488)
		(end 63.80988 -273.411696)
		(width 0.12954)
		(layer "F.Cu")
		(net "M_A_CPU1_SB_DQS_DN<9>")
	)
	(segment
		(start 68.40855 -270.122904)
		(end 68.090288 -270.441166)
		(width 0.12954)
		(layer "F.Cu")
		(net "M_A_CPU1_SB_DQS_DN<9>")
	)
	(segment
		(start 61.930788 -275.290788)
		(end 61.53658 -275.684996)
		(width 0.12954)
		(layer "F.Cu")
		(net "M_A_CPU1_SB_DQS_DN<9>")
	)
	(segment
		(start 65.340738 -271.880838)
		(end 64.94653 -272.275046)
		(width 0.12954)
		(layer "F.Cu")
		(net "M_A_CPU1_SB_DQS_DN<9>")
	)
	(segment
		(start 67.153536 -269.759176)
		(end 66.92392 -269.759176)
		(width 0.12954)
		(layer "F.Cu")
		(net "M_A_CPU1_SB_DQS_DN<9>")
	)
	(segment
		(start 73.225914 -269.888716)
		(end 73.225914 -270.122904)
		(width 0.12954)
		(layer "F.Cu")
		(net "M_A_CPU1_SB_DQS_DN<9>")
	)
	(segment
		(start 68.090288 -270.441166)
		(end 67.601338 -270.441166)
		(width 0.12954)
		(layer "F.Cu")
		(net "M_A_CPU1_SB_DQS_DN<9>")
	)
	(segment
		(start 59.962796 -276.385274)
		(end 59.428126 -276.385274)
		(width 0.12954)
		(layer "F.Cu")
		(net "M_A_CPU1_SB_DQS_DN<9>")
	)
	(segment
		(start 72.418702 -270.441166)
		(end 72.10044 -270.122904)
		(width 0.12954)
		(layer "F.Cu")
		(net "M_A_CPU1_SB_DQS_DN<9>")
	)
	(segment
		(start 70.014338 -269.888716)
		(end 70.014338 -270.122904)
		(width 0.12954)
		(layer "F.Cu")
		(net "M_A_CPU1_SB_DQS_DN<9>")
	)
	(segment
		(start 72.10044 -270.122904)
		(end 72.10044 -269.888716)
		(width 0.12954)
		(layer "F.Cu")
		(net "M_A_CPU1_SB_DQS_DN<9>")
	)
	(segment
		(start 60.9981 -275.684996)
		(end 60.561474 -276.121622)
		(width 0.12954)
		(layer "F.Cu")
		(net "M_A_CPU1_SB_DQS_DN<9>")
	)
	(segment
		(start 71.620126 -270.122904)
		(end 71.301864 -270.441166)
		(width 0.12954)
		(layer "F.Cu")
		(net "M_A_CPU1_SB_DQS_DN<9>")
	)
	(segment
		(start 76.379578 -271.083278)
		(end 74.934826 -271.083278)
		(width 0.12954)
		(layer "F.Cu")
		(net "M_A_CPU1_SB_DQS_DN<9>")
	)
	(segment
		(start 61.53658 -275.684996)
		(end 60.9981 -275.684996)
		(width 0.12954)
		(layer "F.Cu")
		(net "M_A_CPU1_SB_DQS_DN<9>")
	)
	(segment
		(start 69.207126 -270.441166)
		(end 68.888864 -270.122904)
		(width 0.12954)
		(layer "F.Cu")
		(net "M_A_CPU1_SB_DQS_DN<9>")
	)
	(segment
		(start 68.40855 -269.888716)
		(end 68.40855 -270.122904)
		(width 0.12954)
		(layer "F.Cu")
		(net "M_A_CPU1_SB_DQS_DN<9>")
	)
	(segment
		(start 64.204088 -272.479008)
		(end 64.204088 -273.017488)
		(width 0.12954)
		(layer "F.Cu")
		(net "M_A_CPU1_SB_DQS_DN<9>")
	)
	(segment
		(start 68.53809 -269.759176)
		(end 68.40855 -269.888716)
		(width 0.12954)
		(layer "F.Cu")
		(net "M_A_CPU1_SB_DQS_DN<9>")
	)
	(segment
		(start 66.92392 -269.759176)
		(end 66.477388 -270.205708)
		(width 0.12954)
		(layer "F.Cu")
		(net "M_A_CPU1_SB_DQS_DN<9>")
	)
	(segment
		(start 71.9709 -269.759176)
		(end 71.749666 -269.759176)
		(width 0.12954)
		(layer "F.Cu")
		(net "M_A_CPU1_SB_DQS_DN<9>")
	)
	(segment
		(start 73.610724 -269.759176)
		(end 73.355454 -269.759176)
		(width 0.12954)
		(layer "F.Cu")
		(net "M_A_CPU1_SB_DQS_DN<9>")
	)
	(segment
		(start 77.767942 -271.017238)
		(end 76.464668 -271.017238)
		(width 0.0762)
		(layer "F.Cu")
		(net "M_A_CPU1_SB_DQS_DN<9>")
	)
	(segment
		(start 66.477388 -270.205708)
		(end 66.477388 -270.744188)
		(width 0.12954)
		(layer "F.Cu")
		(net "M_A_CPU1_SB_DQS_DN<9>")
	)
	(segment
		(start 68.888864 -269.888716)
		(end 68.759324 -269.759176)
		(width 0.12954)
		(layer "F.Cu")
		(net "M_A_CPU1_SB_DQS_DN<9>")
	)
	(segment
		(start 64.94653 -272.275046)
		(end 64.40805 -272.275046)
		(width 0.12954)
		(layer "F.Cu")
		(net "M_A_CPU1_SB_DQS_DN<9>")
	)
	(segment
		(start 60.226448 -276.121622)
		(end 59.962796 -276.385274)
		(width 0.12954)
		(layer "F.Cu")
		(net "M_A_CPU1_SB_DQS_DN<9>")
	)
	(segment
		(start 61.930788 -274.752308)
		(end 61.930788 -275.290788)
		(width 0.12954)
		(layer "F.Cu")
		(net "M_A_CPU1_SB_DQS_DN<9>")
	)
	(segment
		(start 72.907652 -270.441166)
		(end 72.418702 -270.441166)
		(width 0.12954)
		(layer "F.Cu")
		(net "M_A_CPU1_SB_DQS_DN<9>")
	)
	(segment
		(start 70.494652 -269.888716)
		(end 70.365112 -269.759176)
		(width 0.12954)
		(layer "F.Cu")
		(net "M_A_CPU1_SB_DQS_DN<9>")
	)
	(segment
		(start 63.2714 -273.411696)
		(end 63.067438 -273.615658)
		(width 0.12954)
		(layer "F.Cu")
		(net "M_A_CPU1_SB_DQS_DN<9>")
	)
	(segment
		(start 76.464668 -271.017238)
		(end 76.398628 -271.083278)
		(width 0.0762)
		(layer "F.Cu")
		(net "M_A_CPU1_SB_DQS_DN<9>")
	)
	(segment
		(start 62.13475 -274.548346)
		(end 61.930788 -274.752308)
		(width 0.12954)
		(layer "F.Cu")
		(net "M_A_CPU1_SB_DQS_DN<9>")
	)
	(segment
		(start 74.934826 -271.083278)
		(end 73.610724 -269.759176)
		(width 0.12954)
		(layer "F.Cu")
		(net "M_A_CPU1_SB_DQS_DN<9>")
	)
	(segment
		(start 70.365112 -269.759176)
		(end 70.143878 -269.759176)
		(width 0.12954)
		(layer "F.Cu")
		(net "M_A_CPU1_SB_DQS_DN<9>")
	)
	(segment
		(start 69.696076 -270.441166)
		(end 69.207126 -270.441166)
		(width 0.12954)
		(layer "F.Cu")
		(net "M_A_CPU1_SB_DQS_DN<9>")
	)
	(segment
		(start 70.014338 -270.122904)
		(end 69.696076 -270.441166)
		(width 0.12954)
		(layer "F.Cu")
		(net "M_A_CPU1_SB_DQS_DN<9>")
	)
	(segment
		(start 65.5447 -271.138396)
		(end 65.340738 -271.342358)
		(width 0.12954)
		(layer "F.Cu")
		(net "M_A_CPU1_SB_DQS_DN<9>")
	)
	(segment
		(start 70.143878 -269.759176)
		(end 70.014338 -269.888716)
		(width 0.12954)
		(layer "F.Cu")
		(net "M_A_CPU1_SB_DQS_DN<9>")
	)
	(segment
		(start 73.225914 -270.122904)
		(end 72.907652 -270.441166)
		(width 0.12954)
		(layer "F.Cu")
		(net "M_A_CPU1_SB_DQS_DN<9>")
	)
	(segment
		(start 66.08318 -271.138396)
		(end 65.5447 -271.138396)
		(width 0.12954)
		(layer "F.Cu")
		(net "M_A_CPU1_SB_DQS_DN<9>")
	)
	(segment
		(start 71.301864 -270.441166)
		(end 70.812914 -270.441166)
		(width 0.12954)
		(layer "F.Cu")
		(net "M_A_CPU1_SB_DQS_DN<9>")
	)
	(segment
		(start 68.888864 -270.122904)
		(end 68.888864 -269.888716)
		(width 0.12954)
		(layer "F.Cu")
		(net "M_A_CPU1_SB_DQS_DN<9>")
	)
	(segment
		(start 70.494652 -270.122904)
		(end 70.494652 -269.888716)
		(width 0.12954)
		(layer "F.Cu")
		(net "M_A_CPU1_SB_DQS_DN<9>")
	)
	(segment
		(start 60.561474 -276.121622)
		(end 60.226448 -276.121622)
		(width 0.12954)
		(layer "F.Cu")
		(net "M_A_CPU1_SB_DQS_DN<9>")
	)
	(segment
		(start 68.759324 -269.759176)
		(end 68.53809 -269.759176)
		(width 0.12954)
		(layer "F.Cu")
		(net "M_A_CPU1_SB_DQS_DN<9>")
	)
	(segment
		(start 65.340738 -271.342358)
		(end 65.340738 -271.880838)
		(width 0.12954)
		(layer "F.Cu")
		(net "M_A_CPU1_SB_DQS_DN<9>")
	)
	(segment
		(start 67.283076 -270.122904)
		(end 67.283076 -269.888716)
		(width 0.12954)
		(layer "F.Cu")
		(net "M_A_CPU1_SB_DQS_DN<9>")
	)
	(segment
		(start 67.601338 -270.441166)
		(end 67.283076 -270.122904)
		(width 0.12954)
		(layer "F.Cu")
		(net "M_A_CPU1_SB_DQS_DN<9>")
	)
	(arc
		(start 78.707996 -271.390364)
		(mid 78.465679 -271.220644)
		(end 78.180692 -271.14119)
		(width 0.0762)
		(layer "F.Cu")
		(net "M_A_CPU1_SB_DQS_DN<9>")
	)
	(arc
		(start 78.180692 -271.14119)
		(mid 78.063879 -271.116514)
		(end 77.954886 -271.067784)
		(width 0.0762)
		(layer "F.Cu")
		(net "M_A_CPU1_SB_DQS_DN<9>")
	)
	(arc
		(start 77.954886 -271.067784)
		(mid 77.864753 -271.030164)
		(end 77.767942 -271.017238)
		(width 0.0762)
		(layer "F.Cu")
		(net "M_A_CPU1_SB_DQS_DN<9>")
	)
	(segment
		(start 61.301376 -314.026296)
		(end 60.843668 -314.484004)
		(width 0.12954)
		(layer "F.Cu")
		(net "M_A_CPU1_SB_DQS_DN<8>")
	)
	(segment
		(start 57.86882 -314.210446)
		(end 57.550812 -314.528454)
		(width 0.101346)
		(layer "F.Cu")
		(net "M_A_CPU1_SB_DQS_DN<8>")
	)
	(segment
		(start 74.562716 -299.312838)
		(end 74.395076 -299.480478)
		(width 0.12954)
		(layer "F.Cu")
		(net "M_A_CPU1_SB_DQS_DN<8>")
	)
	(segment
		(start 76.02728 -291.320474)
		(end 75.933808 -291.320474)
		(width 0.0762)
		(layer "F.Cu")
		(net "M_A_CPU1_SB_DQS_DN<8>")
	)
	(segment
		(start 60.273946 -314.210446)
		(end 57.86882 -314.210446)
		(width 0.101346)
		(layer "F.Cu")
		(net "M_A_CPU1_SB_DQS_DN<8>")
	)
	(segment
		(start 79.647796 -290.830254)
		(end 79.748634 -291.003736)
		(width 0.0762)
		(layer "F.Cu")
		(net "M_A_CPU1_SB_DQS_DN<8>")
	)
	(segment
		(start 74.562716 -300.425358)
		(end 61.301376 -313.686698)
		(width 0.12954)
		(layer "F.Cu")
		(net "M_A_CPU1_SB_DQS_DN<8>")
	)
	(segment
		(start 74.395076 -299.869098)
		(end 74.562716 -300.036738)
		(width 0.12954)
		(layer "F.Cu")
		(net "M_A_CPU1_SB_DQS_DN<8>")
	)
	(segment
		(start 75.933808 -291.320474)
		(end 75.920346 -291.333936)
		(width 0.0762)
		(layer "F.Cu")
		(net "M_A_CPU1_SB_DQS_DN<8>")
	)
	(segment
		(start 55.860442 -313.78525)
		(end 55.328058 -313.78525)
		(width 0.101346)
		(layer "F.Cu")
		(net "M_A_CPU1_SB_DQS_DN<8>")
	)
	(segment
		(start 74.395076 -299.480478)
		(end 74.395076 -299.869098)
		(width 0.12954)
		(layer "F.Cu")
		(net "M_A_CPU1_SB_DQS_DN<8>")
	)
	(segment
		(start 74.562716 -300.036738)
		(end 74.562716 -300.425358)
		(width 0.12954)
		(layer "F.Cu")
		(net "M_A_CPU1_SB_DQS_DN<8>")
	)
	(segment
		(start 60.547504 -314.484004)
		(end 60.273946 -314.210446)
		(width 0.12954)
		(layer "F.Cu")
		(net "M_A_CPU1_SB_DQS_DN<8>")
	)
	(segment
		(start 78.89494 -291.152834)
		(end 78.886558 -291.15766)
		(width 0.0762)
		(layer "F.Cu")
		(net "M_A_CPU1_SB_DQS_DN<8>")
	)
	(segment
		(start 57.550812 -314.528454)
		(end 57.27319 -314.528454)
		(width 0.101346)
		(layer "F.Cu")
		(net "M_A_CPU1_SB_DQS_DN<8>")
	)
	(segment
		(start 79.469234 -291.15766)
		(end 79.460852 -291.152834)
		(width 0.0762)
		(layer "F.Cu")
		(net "M_A_CPU1_SB_DQS_DN<8>")
	)
	(segment
		(start 75.920346 -291.333936)
		(end 74.562716 -292.691566)
		(width 0.12954)
		(layer "F.Cu")
		(net "M_A_CPU1_SB_DQS_DN<8>")
	)
	(segment
		(start 76.144374 -291.20338)
		(end 76.02728 -291.320474)
		(width 0.0762)
		(layer "F.Cu")
		(net "M_A_CPU1_SB_DQS_DN<8>")
	)
	(segment
		(start 56.177434 -314.102242)
		(end 55.860442 -313.78525)
		(width 0.101346)
		(layer "F.Cu")
		(net "M_A_CPU1_SB_DQS_DN<8>")
	)
	(segment
		(start 77.767942 -291.20338)
		(end 76.144374 -291.20338)
		(width 0.0762)
		(layer "F.Cu")
		(net "M_A_CPU1_SB_DQS_DN<8>")
	)
	(segment
		(start 60.843668 -314.484004)
		(end 60.547504 -314.484004)
		(width 0.12954)
		(layer "F.Cu")
		(net "M_A_CPU1_SB_DQS_DN<8>")
	)
	(segment
		(start 56.846978 -314.102242)
		(end 56.177434 -314.102242)
		(width 0.101346)
		(layer "F.Cu")
		(net "M_A_CPU1_SB_DQS_DN<8>")
	)
	(segment
		(start 74.562716 -292.691566)
		(end 74.562716 -299.312838)
		(width 0.12954)
		(layer "F.Cu")
		(net "M_A_CPU1_SB_DQS_DN<8>")
	)
	(segment
		(start 61.301376 -313.686698)
		(end 61.301376 -314.026296)
		(width 0.12954)
		(layer "F.Cu")
		(net "M_A_CPU1_SB_DQS_DN<8>")
	)
	(segment
		(start 57.27319 -314.528454)
		(end 56.846978 -314.102242)
		(width 0.101346)
		(layer "F.Cu")
		(net "M_A_CPU1_SB_DQS_DN<8>")
	)
	(arc
		(start 79.748634 -291.003736)
		(mid 79.732709 -291.144428)
		(end 79.602584 -291.200332)
		(width 0.0762)
		(layer "F.Cu")
		(net "M_A_CPU1_SB_DQS_DN<8>")
	)
	(arc
		(start 78.520798 -291.152834)
		(mid 78.237842 -291.076657)
		(end 77.954886 -291.152834)
		(width 0.0762)
		(layer "F.Cu")
		(net "M_A_CPU1_SB_DQS_DN<8>")
	)
	(arc
		(start 79.460852 -291.152834)
		(mid 79.177896 -291.076657)
		(end 78.89494 -291.152834)
		(width 0.0762)
		(layer "F.Cu")
		(net "M_A_CPU1_SB_DQS_DN<8>")
	)
	(arc
		(start 77.79893 -291.20211)
		(mid 77.783449 -291.203066)
		(end 77.767942 -291.20338)
		(width 0.0762)
		(layer "F.Cu")
		(net "M_A_CPU1_SB_DQS_DN<8>")
	)
	(arc
		(start 79.602584 -291.200332)
		(mid 79.533886 -291.185316)
		(end 79.469234 -291.15766)
		(width 0.0762)
		(layer "F.Cu")
		(net "M_A_CPU1_SB_DQS_DN<8>")
	)
	(arc
		(start 77.954886 -291.152834)
		(mid 77.879646 -291.186147)
		(end 77.79893 -291.20211)
		(width 0.0762)
		(layer "F.Cu")
		(net "M_A_CPU1_SB_DQS_DN<8>")
	)
	(arc
		(start 78.886558 -291.15766)
		(mid 78.70305 -291.203154)
		(end 78.520798 -291.152834)
		(width 0.0762)
		(layer "F.Cu")
		(net "M_A_CPU1_SB_DQS_DN<8>")
	)
	(segment
		(start 57.86882 -304.860452)
		(end 57.550812 -305.17846)
		(width 0.101346)
		(layer "F.Cu")
		(net "M_A_CPU1_SB_DQS_DN<7>")
	)
	(segment
		(start 75.974956 -285.99003)
		(end 75.955906 -285.99003)
		(width 0.0762)
		(layer "F.Cu")
		(net "M_A_CPU1_SB_DQS_DN<7>")
	)
	(segment
		(start 70.141084 -296.153332)
		(end 61.159644 -305.134772)
		(width 0.12954)
		(layer "F.Cu")
		(net "M_A_CPU1_SB_DQS_DN<7>")
	)
	(segment
		(start 60.273946 -304.860452)
		(end 57.86882 -304.860452)
		(width 0.101346)
		(layer "F.Cu")
		(net "M_A_CPU1_SB_DQS_DN<7>")
	)
	(segment
		(start 56.177434 -304.752248)
		(end 55.860442 -304.435256)
		(width 0.101346)
		(layer "F.Cu")
		(net "M_A_CPU1_SB_DQS_DN<7>")
	)
	(segment
		(start 60.548266 -305.134772)
		(end 60.273946 -304.860452)
		(width 0.12954)
		(layer "F.Cu")
		(net "M_A_CPU1_SB_DQS_DN<7>")
	)
	(segment
		(start 79.647796 -285.970472)
		(end 79.748634 -286.143954)
		(width 0.0762)
		(layer "F.Cu")
		(net "M_A_CPU1_SB_DQS_DN<7>")
	)
	(segment
		(start 61.159644 -305.134772)
		(end 60.548266 -305.134772)
		(width 0.12954)
		(layer "F.Cu")
		(net "M_A_CPU1_SB_DQS_DN<7>")
	)
	(segment
		(start 57.550812 -305.17846)
		(end 57.242202 -305.17846)
		(width 0.101346)
		(layer "F.Cu")
		(net "M_A_CPU1_SB_DQS_DN<7>")
	)
	(segment
		(start 79.469234 -286.297878)
		(end 79.460852 -286.293052)
		(width 0.0762)
		(layer "F.Cu")
		(net "M_A_CPU1_SB_DQS_DN<7>")
	)
	(segment
		(start 56.81599 -304.752248)
		(end 56.177434 -304.752248)
		(width 0.101346)
		(layer "F.Cu")
		(net "M_A_CPU1_SB_DQS_DN<7>")
	)
	(segment
		(start 76.81722 -286.343598)
		(end 76.529692 -286.05607)
		(width 0.0762)
		(layer "F.Cu")
		(net "M_A_CPU1_SB_DQS_DN<7>")
	)
	(segment
		(start 76.529692 -286.05607)
		(end 76.040996 -286.05607)
		(width 0.0762)
		(layer "F.Cu")
		(net "M_A_CPU1_SB_DQS_DN<7>")
	)
	(segment
		(start 57.242202 -305.17846)
		(end 56.81599 -304.752248)
		(width 0.101346)
		(layer "F.Cu")
		(net "M_A_CPU1_SB_DQS_DN<7>")
	)
	(segment
		(start 74.57059 -285.99003)
		(end 70.141084 -290.419536)
		(width 0.12954)
		(layer "F.Cu")
		(net "M_A_CPU1_SB_DQS_DN<7>")
	)
	(segment
		(start 70.141084 -290.419536)
		(end 70.141084 -296.153332)
		(width 0.12954)
		(layer "F.Cu")
		(net "M_A_CPU1_SB_DQS_DN<7>")
	)
	(segment
		(start 78.89494 -286.293052)
		(end 78.886558 -286.297878)
		(width 0.0762)
		(layer "F.Cu")
		(net "M_A_CPU1_SB_DQS_DN<7>")
	)
	(segment
		(start 77.767942 -286.343598)
		(end 76.81722 -286.343598)
		(width 0.0762)
		(layer "F.Cu")
		(net "M_A_CPU1_SB_DQS_DN<7>")
	)
	(segment
		(start 75.955906 -285.99003)
		(end 74.57059 -285.99003)
		(width 0.12954)
		(layer "F.Cu")
		(net "M_A_CPU1_SB_DQS_DN<7>")
	)
	(segment
		(start 55.860442 -304.435256)
		(end 55.328058 -304.435256)
		(width 0.101346)
		(layer "F.Cu")
		(net "M_A_CPU1_SB_DQS_DN<7>")
	)
	(segment
		(start 76.040996 -286.05607)
		(end 75.974956 -285.99003)
		(width 0.0762)
		(layer "F.Cu")
		(net "M_A_CPU1_SB_DQS_DN<7>")
	)
	(arc
		(start 79.748634 -286.143954)
		(mid 79.732709 -286.284646)
		(end 79.602584 -286.34055)
		(width 0.0762)
		(layer "F.Cu")
		(net "M_A_CPU1_SB_DQS_DN<7>")
	)
	(arc
		(start 79.460852 -286.293052)
		(mid 79.177896 -286.216875)
		(end 78.89494 -286.293052)
		(width 0.0762)
		(layer "F.Cu")
		(net "M_A_CPU1_SB_DQS_DN<7>")
	)
	(arc
		(start 78.520798 -286.293052)
		(mid 78.237842 -286.216875)
		(end 77.954886 -286.293052)
		(width 0.0762)
		(layer "F.Cu")
		(net "M_A_CPU1_SB_DQS_DN<7>")
	)
	(arc
		(start 77.954886 -286.293052)
		(mid 77.879646 -286.326365)
		(end 77.79893 -286.342328)
		(width 0.0762)
		(layer "F.Cu")
		(net "M_A_CPU1_SB_DQS_DN<7>")
	)
	(arc
		(start 77.79893 -286.342328)
		(mid 77.783449 -286.343284)
		(end 77.767942 -286.343598)
		(width 0.0762)
		(layer "F.Cu")
		(net "M_A_CPU1_SB_DQS_DN<7>")
	)
	(arc
		(start 78.886558 -286.297878)
		(mid 78.70305 -286.343372)
		(end 78.520798 -286.293052)
		(width 0.0762)
		(layer "F.Cu")
		(net "M_A_CPU1_SB_DQS_DN<7>")
	)
	(arc
		(start 79.602584 -286.34055)
		(mid 79.533886 -286.325534)
		(end 79.469234 -286.297878)
		(width 0.0762)
		(layer "F.Cu")
		(net "M_A_CPU1_SB_DQS_DN<7>")
	)
	(segment
		(start 56.83885 -295.402254)
		(end 56.177434 -295.402254)
		(width 0.101346)
		(layer "F.Cu")
		(net "M_A_CPU1_SB_DQS_DN<6>")
	)
	(segment
		(start 60.547758 -295.78427)
		(end 60.273946 -295.510458)
		(width 0.12954)
		(layer "F.Cu")
		(net "M_A_CPU1_SB_DQS_DN<6>")
	)
	(segment
		(start 76.570586 -281.169364)
		(end 76.031598 -281.169364)
		(width 0.0762)
		(layer "F.Cu")
		(net "M_A_CPU1_SB_DQS_DN<6>")
	)
	(segment
		(start 79.647796 -281.110436)
		(end 79.748634 -281.283918)
		(width 0.0762)
		(layer "F.Cu")
		(net "M_A_CPU1_SB_DQS_DN<6>")
	)
	(segment
		(start 75.965558 -281.103324)
		(end 75.955906 -281.103324)
		(width 0.0762)
		(layer "F.Cu")
		(net "M_A_CPU1_SB_DQS_DN<6>")
	)
	(segment
		(start 56.177434 -295.402254)
		(end 55.860442 -295.085262)
		(width 0.101346)
		(layer "F.Cu")
		(net "M_A_CPU1_SB_DQS_DN<6>")
	)
	(segment
		(start 79.469234 -281.437842)
		(end 79.460852 -281.433016)
		(width 0.0762)
		(layer "F.Cu")
		(net "M_A_CPU1_SB_DQS_DN<6>")
	)
	(segment
		(start 60.273946 -295.510458)
		(end 57.86882 -295.510458)
		(width 0.101346)
		(layer "F.Cu")
		(net "M_A_CPU1_SB_DQS_DN<6>")
	)
	(segment
		(start 76.884784 -281.483562)
		(end 76.570586 -281.169364)
		(width 0.0762)
		(layer "F.Cu")
		(net "M_A_CPU1_SB_DQS_DN<6>")
	)
	(segment
		(start 57.86882 -295.510458)
		(end 57.550812 -295.828466)
		(width 0.101346)
		(layer "F.Cu")
		(net "M_A_CPU1_SB_DQS_DN<6>")
	)
	(segment
		(start 57.265062 -295.828466)
		(end 56.83885 -295.402254)
		(width 0.101346)
		(layer "F.Cu")
		(net "M_A_CPU1_SB_DQS_DN<6>")
	)
	(segment
		(start 77.767942 -281.483562)
		(end 76.884784 -281.483562)
		(width 0.0762)
		(layer "F.Cu")
		(net "M_A_CPU1_SB_DQS_DN<6>")
	)
	(segment
		(start 61.453522 -295.78427)
		(end 60.547758 -295.78427)
		(width 0.12954)
		(layer "F.Cu")
		(net "M_A_CPU1_SB_DQS_DN<6>")
	)
	(segment
		(start 73.203562 -281.103324)
		(end 65.707514 -288.599372)
		(width 0.12954)
		(layer "F.Cu")
		(net "M_A_CPU1_SB_DQS_DN<6>")
	)
	(segment
		(start 75.955906 -281.103324)
		(end 73.203562 -281.103324)
		(width 0.12954)
		(layer "F.Cu")
		(net "M_A_CPU1_SB_DQS_DN<6>")
	)
	(segment
		(start 78.89494 -281.433016)
		(end 78.886558 -281.437842)
		(width 0.0762)
		(layer "F.Cu")
		(net "M_A_CPU1_SB_DQS_DN<6>")
	)
	(segment
		(start 57.550812 -295.828466)
		(end 57.265062 -295.828466)
		(width 0.101346)
		(layer "F.Cu")
		(net "M_A_CPU1_SB_DQS_DN<6>")
	)
	(segment
		(start 65.707514 -288.599372)
		(end 65.707514 -291.530278)
		(width 0.12954)
		(layer "F.Cu")
		(net "M_A_CPU1_SB_DQS_DN<6>")
	)
	(segment
		(start 55.860442 -295.085262)
		(end 55.328058 -295.085262)
		(width 0.101346)
		(layer "F.Cu")
		(net "M_A_CPU1_SB_DQS_DN<6>")
	)
	(segment
		(start 76.031598 -281.169364)
		(end 75.965558 -281.103324)
		(width 0.0762)
		(layer "F.Cu")
		(net "M_A_CPU1_SB_DQS_DN<6>")
	)
	(segment
		(start 65.707514 -291.530278)
		(end 61.453522 -295.78427)
		(width 0.12954)
		(layer "F.Cu")
		(net "M_A_CPU1_SB_DQS_DN<6>")
	)
	(arc
		(start 77.79893 -281.482292)
		(mid 77.783449 -281.483248)
		(end 77.767942 -281.483562)
		(width 0.0762)
		(layer "F.Cu")
		(net "M_A_CPU1_SB_DQS_DN<6>")
	)
	(arc
		(start 78.886558 -281.437842)
		(mid 78.70305 -281.483336)
		(end 78.520798 -281.433016)
		(width 0.0762)
		(layer "F.Cu")
		(net "M_A_CPU1_SB_DQS_DN<6>")
	)
	(arc
		(start 78.520798 -281.433016)
		(mid 78.237842 -281.356839)
		(end 77.954886 -281.433016)
		(width 0.0762)
		(layer "F.Cu")
		(net "M_A_CPU1_SB_DQS_DN<6>")
	)
	(arc
		(start 79.748634 -281.283918)
		(mid 79.732709 -281.42461)
		(end 79.602584 -281.480514)
		(width 0.0762)
		(layer "F.Cu")
		(net "M_A_CPU1_SB_DQS_DN<6>")
	)
	(arc
		(start 77.954886 -281.433016)
		(mid 77.879646 -281.466329)
		(end 77.79893 -281.482292)
		(width 0.0762)
		(layer "F.Cu")
		(net "M_A_CPU1_SB_DQS_DN<6>")
	)
	(arc
		(start 79.602584 -281.480514)
		(mid 79.533886 -281.465498)
		(end 79.469234 -281.437842)
		(width 0.0762)
		(layer "F.Cu")
		(net "M_A_CPU1_SB_DQS_DN<6>")
	)
	(arc
		(start 79.460852 -281.433016)
		(mid 79.177896 -281.356839)
		(end 78.89494 -281.433016)
		(width 0.0762)
		(layer "F.Cu")
		(net "M_A_CPU1_SB_DQS_DN<6>")
	)
	(segment
		(start 77.767942 -276.623526)
		(end 76.900786 -276.623526)
		(width 0.0762)
		(layer "F.Cu")
		(net "M_A_CPU1_SB_DQS_DN<5>")
	)
	(segment
		(start 56.861202 -286.05226)
		(end 56.177434 -286.05226)
		(width 0.101346)
		(layer "F.Cu")
		(net "M_A_CPU1_SB_DQS_DN<5>")
	)
	(segment
		(start 57.550812 -286.478472)
		(end 57.287414 -286.478472)
		(width 0.101346)
		(layer "F.Cu")
		(net "M_A_CPU1_SB_DQS_DN<5>")
	)
	(segment
		(start 57.287414 -286.478472)
		(end 56.861202 -286.05226)
		(width 0.101346)
		(layer "F.Cu")
		(net "M_A_CPU1_SB_DQS_DN<5>")
	)
	(segment
		(start 60.273946 -286.160464)
		(end 57.86882 -286.160464)
		(width 0.101346)
		(layer "F.Cu")
		(net "M_A_CPU1_SB_DQS_DN<5>")
	)
	(segment
		(start 75.974956 -276.318218)
		(end 75.955906 -276.318218)
		(width 0.0762)
		(layer "F.Cu")
		(net "M_A_CPU1_SB_DQS_DN<5>")
	)
	(segment
		(start 55.860442 -285.735268)
		(end 55.328058 -285.735268)
		(width 0.101346)
		(layer "F.Cu")
		(net "M_A_CPU1_SB_DQS_DN<5>")
	)
	(segment
		(start 76.900786 -276.623526)
		(end 76.661518 -276.384258)
		(width 0.0762)
		(layer "F.Cu")
		(net "M_A_CPU1_SB_DQS_DN<5>")
	)
	(segment
		(start 56.177434 -286.05226)
		(end 55.860442 -285.735268)
		(width 0.101346)
		(layer "F.Cu")
		(net "M_A_CPU1_SB_DQS_DN<5>")
	)
	(segment
		(start 60.856876 -286.434022)
		(end 60.547504 -286.434022)
		(width 0.12954)
		(layer "F.Cu")
		(net "M_A_CPU1_SB_DQS_DN<5>")
	)
	(segment
		(start 61.566044 -285.724854)
		(end 60.856876 -286.434022)
		(width 0.12954)
		(layer "F.Cu")
		(net "M_A_CPU1_SB_DQS_DN<5>")
	)
	(segment
		(start 60.547504 -286.434022)
		(end 60.273946 -286.160464)
		(width 0.12954)
		(layer "F.Cu")
		(net "M_A_CPU1_SB_DQS_DN<5>")
	)
	(segment
		(start 76.040996 -276.384258)
		(end 75.974956 -276.318218)
		(width 0.0762)
		(layer "F.Cu")
		(net "M_A_CPU1_SB_DQS_DN<5>")
	)
	(segment
		(start 75.955906 -276.318218)
		(end 70.29323 -276.318218)
		(width 0.12954)
		(layer "F.Cu")
		(net "M_A_CPU1_SB_DQS_DN<5>")
	)
	(segment
		(start 61.566044 -285.045404)
		(end 61.566044 -285.724854)
		(width 0.12954)
		(layer "F.Cu")
		(net "M_A_CPU1_SB_DQS_DN<5>")
	)
	(segment
		(start 76.661518 -276.384258)
		(end 76.040996 -276.384258)
		(width 0.0762)
		(layer "F.Cu")
		(net "M_A_CPU1_SB_DQS_DN<5>")
	)
	(segment
		(start 57.86882 -286.160464)
		(end 57.550812 -286.478472)
		(width 0.101346)
		(layer "F.Cu")
		(net "M_A_CPU1_SB_DQS_DN<5>")
	)
	(segment
		(start 70.29323 -276.318218)
		(end 61.566044 -285.045404)
		(width 0.12954)
		(layer "F.Cu")
		(net "M_A_CPU1_SB_DQS_DN<5>")
	)
	(segment
		(start 79.469234 -276.577806)
		(end 79.460852 -276.57298)
		(width 0.0762)
		(layer "F.Cu")
		(net "M_A_CPU1_SB_DQS_DN<5>")
	)
	(segment
		(start 78.89494 -276.57298)
		(end 78.886558 -276.577806)
		(width 0.0762)
		(layer "F.Cu")
		(net "M_A_CPU1_SB_DQS_DN<5>")
	)
	(segment
		(start 79.647796 -276.2504)
		(end 79.748634 -276.423882)
		(width 0.0762)
		(layer "F.Cu")
		(net "M_A_CPU1_SB_DQS_DN<5>")
	)
	(arc
		(start 78.886558 -276.577806)
		(mid 78.70305 -276.6233)
		(end 78.520798 -276.57298)
		(width 0.0762)
		(layer "F.Cu")
		(net "M_A_CPU1_SB_DQS_DN<5>")
	)
	(arc
		(start 77.954886 -276.57298)
		(mid 77.879646 -276.606293)
		(end 77.79893 -276.622256)
		(width 0.0762)
		(layer "F.Cu")
		(net "M_A_CPU1_SB_DQS_DN<5>")
	)
	(arc
		(start 78.520798 -276.57298)
		(mid 78.237842 -276.496803)
		(end 77.954886 -276.57298)
		(width 0.0762)
		(layer "F.Cu")
		(net "M_A_CPU1_SB_DQS_DN<5>")
	)
	(arc
		(start 79.748634 -276.423882)
		(mid 79.732709 -276.564574)
		(end 79.602584 -276.620478)
		(width 0.0762)
		(layer "F.Cu")
		(net "M_A_CPU1_SB_DQS_DN<5>")
	)
	(arc
		(start 77.79893 -276.622256)
		(mid 77.783449 -276.623212)
		(end 77.767942 -276.623526)
		(width 0.0762)
		(layer "F.Cu")
		(net "M_A_CPU1_SB_DQS_DN<5>")
	)
	(arc
		(start 79.460852 -276.57298)
		(mid 79.177896 -276.496803)
		(end 78.89494 -276.57298)
		(width 0.0762)
		(layer "F.Cu")
		(net "M_A_CPU1_SB_DQS_DN<5>")
	)
	(arc
		(start 79.602584 -276.620478)
		(mid 79.533886 -276.605462)
		(end 79.469234 -276.577806)
		(width 0.0762)
		(layer "F.Cu")
		(net "M_A_CPU1_SB_DQS_DN<5>")
	)
	(segment
		(start 76.246482 -271.578578)
		(end 76.180442 -271.512538)
		(width 0.0762)
		(layer "F.Cu")
		(net "M_A_CPU1_SB_DQS_DN<4>")
	)
	(segment
		(start 74.765662 -271.512538)
		(end 74.11593 -270.862806)
		(width 0.12954)
		(layer "F.Cu")
		(net "M_A_CPU1_SB_DQS_DN<4>")
	)
	(segment
		(start 57.86882 -276.81047)
		(end 57.550812 -277.128478)
		(width 0.101346)
		(layer "F.Cu")
		(net "M_A_CPU1_SB_DQS_DN<4>")
	)
	(segment
		(start 79.647796 -271.390364)
		(end 79.748634 -271.563846)
		(width 0.0762)
		(layer "F.Cu")
		(net "M_A_CPU1_SB_DQS_DN<4>")
	)
	(segment
		(start 77.767942 -271.76349)
		(end 76.842112 -271.76349)
		(width 0.0762)
		(layer "F.Cu")
		(net "M_A_CPU1_SB_DQS_DN<4>")
	)
	(segment
		(start 79.469234 -271.71777)
		(end 79.460852 -271.712944)
		(width 0.0762)
		(layer "F.Cu")
		(net "M_A_CPU1_SB_DQS_DN<4>")
	)
	(segment
		(start 57.550812 -277.128478)
		(end 57.269126 -277.128478)
		(width 0.101346)
		(layer "F.Cu")
		(net "M_A_CPU1_SB_DQS_DN<4>")
	)
	(segment
		(start 60.837318 -277.078186)
		(end 60.654946 -277.078186)
		(width 0.12954)
		(layer "F.Cu")
		(net "M_A_CPU1_SB_DQS_DN<4>")
	)
	(segment
		(start 76.6572 -271.578578)
		(end 76.246482 -271.578578)
		(width 0.0762)
		(layer "F.Cu")
		(net "M_A_CPU1_SB_DQS_DN<4>")
	)
	(segment
		(start 76.842112 -271.76349)
		(end 76.6572 -271.578578)
		(width 0.0762)
		(layer "F.Cu")
		(net "M_A_CPU1_SB_DQS_DN<4>")
	)
	(segment
		(start 76.180442 -271.512538)
		(end 76.161392 -271.512538)
		(width 0.0762)
		(layer "F.Cu")
		(net "M_A_CPU1_SB_DQS_DN<4>")
	)
	(segment
		(start 56.842914 -276.702266)
		(end 56.177434 -276.702266)
		(width 0.101346)
		(layer "F.Cu")
		(net "M_A_CPU1_SB_DQS_DN<4>")
	)
	(segment
		(start 67.052698 -270.862806)
		(end 60.837318 -277.078186)
		(width 0.12954)
		(layer "F.Cu")
		(net "M_A_CPU1_SB_DQS_DN<4>")
	)
	(segment
		(start 76.161392 -271.512538)
		(end 74.765662 -271.512538)
		(width 0.12954)
		(layer "F.Cu")
		(net "M_A_CPU1_SB_DQS_DN<4>")
	)
	(segment
		(start 60.654946 -277.078186)
		(end 60.38723 -276.81047)
		(width 0.12954)
		(layer "F.Cu")
		(net "M_A_CPU1_SB_DQS_DN<4>")
	)
	(segment
		(start 78.89494 -271.712944)
		(end 78.886558 -271.71777)
		(width 0.0762)
		(layer "F.Cu")
		(net "M_A_CPU1_SB_DQS_DN<4>")
	)
	(segment
		(start 74.11593 -270.862806)
		(end 67.052698 -270.862806)
		(width 0.12954)
		(layer "F.Cu")
		(net "M_A_CPU1_SB_DQS_DN<4>")
	)
	(segment
		(start 57.269126 -277.128478)
		(end 56.842914 -276.702266)
		(width 0.101346)
		(layer "F.Cu")
		(net "M_A_CPU1_SB_DQS_DN<4>")
	)
	(segment
		(start 60.38723 -276.81047)
		(end 57.86882 -276.81047)
		(width 0.101346)
		(layer "F.Cu")
		(net "M_A_CPU1_SB_DQS_DN<4>")
	)
	(segment
		(start 56.177434 -276.702266)
		(end 55.860442 -276.385274)
		(width 0.101346)
		(layer "F.Cu")
		(net "M_A_CPU1_SB_DQS_DN<4>")
	)
	(segment
		(start 55.860442 -276.385274)
		(end 55.328058 -276.385274)
		(width 0.101346)
		(layer "F.Cu")
		(net "M_A_CPU1_SB_DQS_DN<4>")
	)
	(arc
		(start 79.748634 -271.563846)
		(mid 79.732709 -271.704538)
		(end 79.602584 -271.760442)
		(width 0.0762)
		(layer "F.Cu")
		(net "M_A_CPU1_SB_DQS_DN<4>")
	)
	(arc
		(start 79.460852 -271.712944)
		(mid 79.177896 -271.636767)
		(end 78.89494 -271.712944)
		(width 0.0762)
		(layer "F.Cu")
		(net "M_A_CPU1_SB_DQS_DN<4>")
	)
	(arc
		(start 79.602584 -271.760442)
		(mid 79.533886 -271.745426)
		(end 79.469234 -271.71777)
		(width 0.0762)
		(layer "F.Cu")
		(net "M_A_CPU1_SB_DQS_DN<4>")
	)
	(arc
		(start 78.520798 -271.712944)
		(mid 78.237842 -271.636767)
		(end 77.954886 -271.712944)
		(width 0.0762)
		(layer "F.Cu")
		(net "M_A_CPU1_SB_DQS_DN<4>")
	)
	(arc
		(start 77.954886 -271.712944)
		(mid 77.879646 -271.746257)
		(end 77.79893 -271.76222)
		(width 0.0762)
		(layer "F.Cu")
		(net "M_A_CPU1_SB_DQS_DN<4>")
	)
	(arc
		(start 78.886558 -271.71777)
		(mid 78.70305 -271.763264)
		(end 78.520798 -271.712944)
		(width 0.0762)
		(layer "F.Cu")
		(net "M_A_CPU1_SB_DQS_DN<4>")
	)
	(arc
		(start 77.79893 -271.76222)
		(mid 77.783449 -271.763176)
		(end 77.767942 -271.76349)
		(width 0.0762)
		(layer "F.Cu")
		(net "M_A_CPU1_SB_DQS_DN<4>")
	)
	(segment
		(start 69.985382 -303.176686)
		(end 70.375018 -303.566322)
		(width 0.12954)
		(layer "F.Cu")
		(net "M_A_CPU1_SB_DQS_DN<3>")
	)
	(segment
		(start 72.258682 -300.903386)
		(end 72.648318 -301.293022)
		(width 0.12954)
		(layer "F.Cu")
		(net "M_A_CPU1_SB_DQS_DN<3>")
	)
	(segment
		(start 73.438258 -300.95317)
		(end 72.98817 -300.95317)
		(width 0.12954)
		(layer "F.Cu")
		(net "M_A_CPU1_SB_DQS_DN<3>")
	)
	(segment
		(start 77.767942 -290.457128)
		(end 77.28331 -290.457128)
		(width 0.0762)
		(layer "F.Cu")
		(net "M_A_CPU1_SB_DQS_DN<3>")
	)
	(segment
		(start 75.955906 -290.48456)
		(end 75.837542 -290.48456)
		(width 0.12954)
		(layer "F.Cu")
		(net "M_A_CPU1_SB_DQS_DN<3>")
	)
	(segment
		(start 73.395332 -299.766736)
		(end 73.784968 -300.156372)
		(width 0.12954)
		(layer "F.Cu")
		(net "M_A_CPU1_SB_DQS_DN<3>")
	)
	(segment
		(start 77.28331 -290.457128)
		(end 77.244702 -290.41852)
		(width 0.0762)
		(layer "F.Cu")
		(net "M_A_CPU1_SB_DQS_DN<3>")
	)
	(segment
		(start 59.962796 -313.78525)
		(end 59.428126 -313.78525)
		(width 0.12954)
		(layer "F.Cu")
		(net "M_A_CPU1_SB_DQS_DN<3>")
	)
	(segment
		(start 71.122032 -301.856648)
		(end 71.122032 -302.040036)
		(width 0.12954)
		(layer "F.Cu")
		(net "M_A_CPU1_SB_DQS_DN<3>")
	)
	(segment
		(start 68.693538 -305.676554)
		(end 60.848494 -313.521598)
		(width 0.12954)
		(layer "F.Cu")
		(net "M_A_CPU1_SB_DQS_DN<3>")
	)
	(segment
		(start 72.258682 -300.719998)
		(end 72.258682 -300.903386)
		(width 0.12954)
		(layer "F.Cu")
		(net "M_A_CPU1_SB_DQS_DN<3>")
	)
	(segment
		(start 76.040996 -290.41852)
		(end 75.974956 -290.48456)
		(width 0.0762)
		(layer "F.Cu")
		(net "M_A_CPU1_SB_DQS_DN<3>")
	)
	(segment
		(start 72.301608 -302.08982)
		(end 71.85152 -302.08982)
		(width 0.12954)
		(layer "F.Cu")
		(net "M_A_CPU1_SB_DQS_DN<3>")
	)
	(segment
		(start 73.784968 -300.156372)
		(end 73.784968 -300.60646)
		(width 0.12954)
		(layer "F.Cu")
		(net "M_A_CPU1_SB_DQS_DN<3>")
	)
	(segment
		(start 69.985382 -302.993298)
		(end 69.985382 -303.176686)
		(width 0.12954)
		(layer "F.Cu")
		(net "M_A_CPU1_SB_DQS_DN<3>")
	)
	(segment
		(start 70.325234 -302.836834)
		(end 70.141846 -302.836834)
		(width 0.12954)
		(layer "F.Cu")
		(net "M_A_CPU1_SB_DQS_DN<3>")
	)
	(segment
		(start 72.648318 -301.293022)
		(end 72.648318 -301.74311)
		(width 0.12954)
		(layer "F.Cu")
		(net "M_A_CPU1_SB_DQS_DN<3>")
	)
	(segment
		(start 75.974956 -290.48456)
		(end 75.955906 -290.48456)
		(width 0.0762)
		(layer "F.Cu")
		(net "M_A_CPU1_SB_DQS_DN<3>")
	)
	(segment
		(start 72.415146 -300.563534)
		(end 72.258682 -300.719998)
		(width 0.12954)
		(layer "F.Cu")
		(net "M_A_CPU1_SB_DQS_DN<3>")
	)
	(segment
		(start 72.98817 -300.95317)
		(end 72.598534 -300.563534)
		(width 0.12954)
		(layer "F.Cu")
		(net "M_A_CPU1_SB_DQS_DN<3>")
	)
	(segment
		(start 71.85152 -302.08982)
		(end 71.461884 -301.700184)
		(width 0.12954)
		(layer "F.Cu")
		(net "M_A_CPU1_SB_DQS_DN<3>")
	)
	(segment
		(start 72.648318 -301.74311)
		(end 72.301608 -302.08982)
		(width 0.12954)
		(layer "F.Cu")
		(net "M_A_CPU1_SB_DQS_DN<3>")
	)
	(segment
		(start 77.244702 -290.41852)
		(end 76.040996 -290.41852)
		(width 0.0762)
		(layer "F.Cu")
		(net "M_A_CPU1_SB_DQS_DN<3>")
	)
	(segment
		(start 70.028308 -304.36312)
		(end 69.57822 -304.36312)
		(width 0.12954)
		(layer "F.Cu")
		(net "M_A_CPU1_SB_DQS_DN<3>")
	)
	(segment
		(start 71.511668 -302.429672)
		(end 71.511668 -302.87976)
		(width 0.12954)
		(layer "F.Cu")
		(net "M_A_CPU1_SB_DQS_DN<3>")
	)
	(segment
		(start 70.375018 -303.566322)
		(end 70.375018 -304.01641)
		(width 0.12954)
		(layer "F.Cu")
		(net "M_A_CPU1_SB_DQS_DN<3>")
	)
	(segment
		(start 70.71487 -303.22647)
		(end 70.325234 -302.836834)
		(width 0.12954)
		(layer "F.Cu")
		(net "M_A_CPU1_SB_DQS_DN<3>")
	)
	(segment
		(start 71.278496 -301.700184)
		(end 71.122032 -301.856648)
		(width 0.12954)
		(layer "F.Cu")
		(net "M_A_CPU1_SB_DQS_DN<3>")
	)
	(segment
		(start 69.005196 -303.973484)
		(end 68.693538 -304.285142)
		(width 0.12954)
		(layer "F.Cu")
		(net "M_A_CPU1_SB_DQS_DN<3>")
	)
	(segment
		(start 69.57822 -304.36312)
		(end 69.188584 -303.973484)
		(width 0.12954)
		(layer "F.Cu")
		(net "M_A_CPU1_SB_DQS_DN<3>")
	)
	(segment
		(start 72.598534 -300.563534)
		(end 72.415146 -300.563534)
		(width 0.12954)
		(layer "F.Cu")
		(net "M_A_CPU1_SB_DQS_DN<3>")
	)
	(segment
		(start 74.138536 -292.183566)
		(end 74.138536 -298.840144)
		(width 0.12954)
		(layer "F.Cu")
		(net "M_A_CPU1_SB_DQS_DN<3>")
	)
	(segment
		(start 71.122032 -302.040036)
		(end 71.511668 -302.429672)
		(width 0.12954)
		(layer "F.Cu")
		(net "M_A_CPU1_SB_DQS_DN<3>")
	)
	(segment
		(start 68.693538 -304.285142)
		(end 68.693538 -305.676554)
		(width 0.12954)
		(layer "F.Cu")
		(net "M_A_CPU1_SB_DQS_DN<3>")
	)
	(segment
		(start 75.837542 -290.48456)
		(end 74.138536 -292.183566)
		(width 0.12954)
		(layer "F.Cu")
		(net "M_A_CPU1_SB_DQS_DN<3>")
	)
	(segment
		(start 71.461884 -301.700184)
		(end 71.278496 -301.700184)
		(width 0.12954)
		(layer "F.Cu")
		(net "M_A_CPU1_SB_DQS_DN<3>")
	)
	(segment
		(start 60.226448 -313.521598)
		(end 59.962796 -313.78525)
		(width 0.12954)
		(layer "F.Cu")
		(net "M_A_CPU1_SB_DQS_DN<3>")
	)
	(segment
		(start 71.164958 -303.22647)
		(end 70.71487 -303.22647)
		(width 0.12954)
		(layer "F.Cu")
		(net "M_A_CPU1_SB_DQS_DN<3>")
	)
	(segment
		(start 60.848494 -313.521598)
		(end 60.226448 -313.521598)
		(width 0.12954)
		(layer "F.Cu")
		(net "M_A_CPU1_SB_DQS_DN<3>")
	)
	(segment
		(start 71.511668 -302.87976)
		(end 71.164958 -303.22647)
		(width 0.12954)
		(layer "F.Cu")
		(net "M_A_CPU1_SB_DQS_DN<3>")
	)
	(segment
		(start 69.188584 -303.973484)
		(end 69.005196 -303.973484)
		(width 0.12954)
		(layer "F.Cu")
		(net "M_A_CPU1_SB_DQS_DN<3>")
	)
	(segment
		(start 73.784968 -300.60646)
		(end 73.438258 -300.95317)
		(width 0.12954)
		(layer "F.Cu")
		(net "M_A_CPU1_SB_DQS_DN<3>")
	)
	(segment
		(start 74.138536 -298.840144)
		(end 73.395332 -299.583348)
		(width 0.12954)
		(layer "F.Cu")
		(net "M_A_CPU1_SB_DQS_DN<3>")
	)
	(segment
		(start 70.375018 -304.01641)
		(end 70.028308 -304.36312)
		(width 0.12954)
		(layer "F.Cu")
		(net "M_A_CPU1_SB_DQS_DN<3>")
	)
	(segment
		(start 73.395332 -299.583348)
		(end 73.395332 -299.766736)
		(width 0.12954)
		(layer "F.Cu")
		(net "M_A_CPU1_SB_DQS_DN<3>")
	)
	(segment
		(start 70.141846 -302.836834)
		(end 69.985382 -302.993298)
		(width 0.12954)
		(layer "F.Cu")
		(net "M_A_CPU1_SB_DQS_DN<3>")
	)
	(arc
		(start 78.707996 -290.830254)
		(mid 78.465679 -290.660534)
		(end 78.180692 -290.58108)
		(width 0.0762)
		(layer "F.Cu")
		(net "M_A_CPU1_SB_DQS_DN<3>")
	)
	(arc
		(start 77.954886 -290.507674)
		(mid 77.864753 -290.470054)
		(end 77.767942 -290.457128)
		(width 0.0762)
		(layer "F.Cu")
		(net "M_A_CPU1_SB_DQS_DN<3>")
	)
	(arc
		(start 78.180692 -290.58108)
		(mid 78.063879 -290.556404)
		(end 77.954886 -290.507674)
		(width 0.0762)
		(layer "F.Cu")
		(net "M_A_CPU1_SB_DQS_DN<3>")
	)
	(segment
		(start 63.93434 -301.763176)
		(end 63.58763 -302.109886)
		(width 0.12954)
		(layer "F.Cu")
		(net "M_A_CPU1_SB_DQS_DN<2>")
	)
	(segment
		(start 69.61759 -295.629838)
		(end 69.61759 -296.079926)
		(width 0.12954)
		(layer "F.Cu")
		(net "M_A_CPU1_SB_DQS_DN<2>")
	)
	(segment
		(start 62.000892 -303.246536)
		(end 61.798962 -303.044606)
		(width 0.12954)
		(layer "F.Cu")
		(net "M_A_CPU1_SB_DQS_DN<2>")
	)
	(segment
		(start 66.00571 -298.837858)
		(end 66.20764 -299.039788)
		(width 0.12954)
		(layer "F.Cu")
		(net "M_A_CPU1_SB_DQS_DN<2>")
	)
	(segment
		(start 63.73241 -301.111158)
		(end 63.93434 -301.313088)
		(width 0.12954)
		(layer "F.Cu")
		(net "M_A_CPU1_SB_DQS_DN<2>")
	)
	(segment
		(start 66.20764 -299.039788)
		(end 66.20764 -299.489876)
		(width 0.12954)
		(layer "F.Cu")
		(net "M_A_CPU1_SB_DQS_DN<2>")
	)
	(segment
		(start 67.14236 -297.701208)
		(end 67.34429 -297.903138)
		(width 0.12954)
		(layer "F.Cu")
		(net "M_A_CPU1_SB_DQS_DN<2>")
	)
	(segment
		(start 68.48094 -297.216576)
		(end 68.13423 -297.563286)
		(width 0.12954)
		(layer "F.Cu")
		(net "M_A_CPU1_SB_DQS_DN<2>")
	)
	(segment
		(start 67.298824 -297.361356)
		(end 67.14236 -297.51782)
		(width 0.12954)
		(layer "F.Cu")
		(net "M_A_CPU1_SB_DQS_DN<2>")
	)
	(segment
		(start 60.150248 -304.171604)
		(end 59.886596 -304.435256)
		(width 0.12954)
		(layer "F.Cu")
		(net "M_A_CPU1_SB_DQS_DN<2>")
	)
	(segment
		(start 77.28331 -285.597346)
		(end 77.186028 -285.500064)
		(width 0.0762)
		(layer "F.Cu")
		(net "M_A_CPU1_SB_DQS_DN<2>")
	)
	(segment
		(start 59.886596 -304.435256)
		(end 59.428126 -304.435256)
		(width 0.12954)
		(layer "F.Cu")
		(net "M_A_CPU1_SB_DQS_DN<2>")
	)
	(segment
		(start 67.482212 -297.361356)
		(end 67.298824 -297.361356)
		(width 0.12954)
		(layer "F.Cu")
		(net "M_A_CPU1_SB_DQS_DN<2>")
	)
	(segment
		(start 77.767942 -285.597346)
		(end 77.28331 -285.597346)
		(width 0.0762)
		(layer "F.Cu")
		(net "M_A_CPU1_SB_DQS_DN<2>")
	)
	(segment
		(start 68.618862 -296.224706)
		(end 68.435474 -296.224706)
		(width 0.12954)
		(layer "F.Cu")
		(net "M_A_CPU1_SB_DQS_DN<2>")
	)
	(segment
		(start 67.34429 -298.353226)
		(end 66.99758 -298.699936)
		(width 0.12954)
		(layer "F.Cu")
		(net "M_A_CPU1_SB_DQS_DN<2>")
	)
	(segment
		(start 63.73241 -300.92777)
		(end 63.73241 -301.111158)
		(width 0.12954)
		(layer "F.Cu")
		(net "M_A_CPU1_SB_DQS_DN<2>")
	)
	(segment
		(start 62.752224 -301.907956)
		(end 62.59576 -302.06442)
		(width 0.12954)
		(layer "F.Cu")
		(net "M_A_CPU1_SB_DQS_DN<2>")
	)
	(segment
		(start 67.14236 -297.51782)
		(end 67.14236 -297.701208)
		(width 0.12954)
		(layer "F.Cu")
		(net "M_A_CPU1_SB_DQS_DN<2>")
	)
	(segment
		(start 65.025524 -299.634656)
		(end 64.86906 -299.79112)
		(width 0.12954)
		(layer "F.Cu")
		(net "M_A_CPU1_SB_DQS_DN<2>")
	)
	(segment
		(start 77.186028 -285.500064)
		(end 76.040996 -285.500064)
		(width 0.0762)
		(layer "F.Cu")
		(net "M_A_CPU1_SB_DQS_DN<2>")
	)
	(segment
		(start 63.137542 -302.109886)
		(end 62.935612 -301.907956)
		(width 0.12954)
		(layer "F.Cu")
		(net "M_A_CPU1_SB_DQS_DN<2>")
	)
	(segment
		(start 66.00571 -298.65447)
		(end 66.00571 -298.837858)
		(width 0.12954)
		(layer "F.Cu")
		(net "M_A_CPU1_SB_DQS_DN<2>")
	)
	(segment
		(start 60.488576 -304.171604)
		(end 60.150248 -304.171604)
		(width 0.12954)
		(layer "F.Cu")
		(net "M_A_CPU1_SB_DQS_DN<2>")
	)
	(segment
		(start 74.395838 -285.566104)
		(end 69.710554 -290.251388)
		(width 0.12954)
		(layer "F.Cu")
		(net "M_A_CPU1_SB_DQS_DN<2>")
	)
	(segment
		(start 66.547492 -298.699936)
		(end 66.345562 -298.498006)
		(width 0.12954)
		(layer "F.Cu")
		(net "M_A_CPU1_SB_DQS_DN<2>")
	)
	(segment
		(start 64.274192 -300.973236)
		(end 64.072262 -300.771306)
		(width 0.12954)
		(layer "F.Cu")
		(net "M_A_CPU1_SB_DQS_DN<2>")
	)
	(segment
		(start 68.820792 -296.426636)
		(end 68.618862 -296.224706)
		(width 0.12954)
		(layer "F.Cu")
		(net "M_A_CPU1_SB_DQS_DN<2>")
	)
	(segment
		(start 61.798962 -303.044606)
		(end 61.615574 -303.044606)
		(width 0.12954)
		(layer "F.Cu")
		(net "M_A_CPU1_SB_DQS_DN<2>")
	)
	(segment
		(start 67.34429 -297.903138)
		(end 67.34429 -298.353226)
		(width 0.12954)
		(layer "F.Cu")
		(net "M_A_CPU1_SB_DQS_DN<2>")
	)
	(segment
		(start 75.974956 -285.566104)
		(end 75.955906 -285.566104)
		(width 0.0762)
		(layer "F.Cu")
		(net "M_A_CPU1_SB_DQS_DN<2>")
	)
	(segment
		(start 66.99758 -298.699936)
		(end 66.547492 -298.699936)
		(width 0.12954)
		(layer "F.Cu")
		(net "M_A_CPU1_SB_DQS_DN<2>")
	)
	(segment
		(start 63.888874 -300.771306)
		(end 63.73241 -300.92777)
		(width 0.12954)
		(layer "F.Cu")
		(net "M_A_CPU1_SB_DQS_DN<2>")
	)
	(segment
		(start 64.072262 -300.771306)
		(end 63.888874 -300.771306)
		(width 0.12954)
		(layer "F.Cu")
		(net "M_A_CPU1_SB_DQS_DN<2>")
	)
	(segment
		(start 66.345562 -298.498006)
		(end 66.162174 -298.498006)
		(width 0.12954)
		(layer "F.Cu")
		(net "M_A_CPU1_SB_DQS_DN<2>")
	)
	(segment
		(start 62.59576 -302.247808)
		(end 62.79769 -302.449738)
		(width 0.12954)
		(layer "F.Cu")
		(net "M_A_CPU1_SB_DQS_DN<2>")
	)
	(segment
		(start 69.710554 -294.949626)
		(end 69.41566 -295.24452)
		(width 0.12954)
		(layer "F.Cu")
		(net "M_A_CPU1_SB_DQS_DN<2>")
	)
	(segment
		(start 64.72428 -300.973236)
		(end 64.274192 -300.973236)
		(width 0.12954)
		(layer "F.Cu")
		(net "M_A_CPU1_SB_DQS_DN<2>")
	)
	(segment
		(start 68.13423 -297.563286)
		(end 67.684142 -297.563286)
		(width 0.12954)
		(layer "F.Cu")
		(net "M_A_CPU1_SB_DQS_DN<2>")
	)
	(segment
		(start 76.040996 -285.500064)
		(end 75.974956 -285.566104)
		(width 0.0762)
		(layer "F.Cu")
		(net "M_A_CPU1_SB_DQS_DN<2>")
	)
	(segment
		(start 69.61759 -296.079926)
		(end 69.27088 -296.426636)
		(width 0.12954)
		(layer "F.Cu")
		(net "M_A_CPU1_SB_DQS_DN<2>")
	)
	(segment
		(start 63.58763 -302.109886)
		(end 63.137542 -302.109886)
		(width 0.12954)
		(layer "F.Cu")
		(net "M_A_CPU1_SB_DQS_DN<2>")
	)
	(segment
		(start 69.41566 -295.24452)
		(end 69.41566 -295.427908)
		(width 0.12954)
		(layer "F.Cu")
		(net "M_A_CPU1_SB_DQS_DN<2>")
	)
	(segment
		(start 65.86093 -299.836586)
		(end 65.410842 -299.836586)
		(width 0.12954)
		(layer "F.Cu")
		(net "M_A_CPU1_SB_DQS_DN<2>")
	)
	(segment
		(start 62.79769 -302.449738)
		(end 62.79769 -302.899826)
		(width 0.12954)
		(layer "F.Cu")
		(net "M_A_CPU1_SB_DQS_DN<2>")
	)
	(segment
		(start 69.710554 -290.251388)
		(end 69.710554 -294.949626)
		(width 0.12954)
		(layer "F.Cu")
		(net "M_A_CPU1_SB_DQS_DN<2>")
	)
	(segment
		(start 65.07099 -300.626526)
		(end 64.72428 -300.973236)
		(width 0.12954)
		(layer "F.Cu")
		(net "M_A_CPU1_SB_DQS_DN<2>")
	)
	(segment
		(start 62.79769 -302.899826)
		(end 62.45098 -303.246536)
		(width 0.12954)
		(layer "F.Cu")
		(net "M_A_CPU1_SB_DQS_DN<2>")
	)
	(segment
		(start 65.410842 -299.836586)
		(end 65.208912 -299.634656)
		(width 0.12954)
		(layer "F.Cu")
		(net "M_A_CPU1_SB_DQS_DN<2>")
	)
	(segment
		(start 64.86906 -299.974508)
		(end 65.07099 -300.176438)
		(width 0.12954)
		(layer "F.Cu")
		(net "M_A_CPU1_SB_DQS_DN<2>")
	)
	(segment
		(start 65.208912 -299.634656)
		(end 65.025524 -299.634656)
		(width 0.12954)
		(layer "F.Cu")
		(net "M_A_CPU1_SB_DQS_DN<2>")
	)
	(segment
		(start 67.684142 -297.563286)
		(end 67.482212 -297.361356)
		(width 0.12954)
		(layer "F.Cu")
		(net "M_A_CPU1_SB_DQS_DN<2>")
	)
	(segment
		(start 62.59576 -302.06442)
		(end 62.59576 -302.247808)
		(width 0.12954)
		(layer "F.Cu")
		(net "M_A_CPU1_SB_DQS_DN<2>")
	)
	(segment
		(start 61.615574 -303.044606)
		(end 60.488576 -304.171604)
		(width 0.12954)
		(layer "F.Cu")
		(net "M_A_CPU1_SB_DQS_DN<2>")
	)
	(segment
		(start 66.162174 -298.498006)
		(end 66.00571 -298.65447)
		(width 0.12954)
		(layer "F.Cu")
		(net "M_A_CPU1_SB_DQS_DN<2>")
	)
	(segment
		(start 75.955906 -285.566104)
		(end 74.395838 -285.566104)
		(width 0.12954)
		(layer "F.Cu")
		(net "M_A_CPU1_SB_DQS_DN<2>")
	)
	(segment
		(start 66.20764 -299.489876)
		(end 65.86093 -299.836586)
		(width 0.12954)
		(layer "F.Cu")
		(net "M_A_CPU1_SB_DQS_DN<2>")
	)
	(segment
		(start 69.41566 -295.427908)
		(end 69.61759 -295.629838)
		(width 0.12954)
		(layer "F.Cu")
		(net "M_A_CPU1_SB_DQS_DN<2>")
	)
	(segment
		(start 68.27901 -296.564558)
		(end 68.48094 -296.766488)
		(width 0.12954)
		(layer "F.Cu")
		(net "M_A_CPU1_SB_DQS_DN<2>")
	)
	(segment
		(start 62.935612 -301.907956)
		(end 62.752224 -301.907956)
		(width 0.12954)
		(layer "F.Cu")
		(net "M_A_CPU1_SB_DQS_DN<2>")
	)
	(segment
		(start 68.435474 -296.224706)
		(end 68.27901 -296.38117)
		(width 0.12954)
		(layer "F.Cu")
		(net "M_A_CPU1_SB_DQS_DN<2>")
	)
	(segment
		(start 69.27088 -296.426636)
		(end 68.820792 -296.426636)
		(width 0.12954)
		(layer "F.Cu")
		(net "M_A_CPU1_SB_DQS_DN<2>")
	)
	(segment
		(start 63.93434 -301.313088)
		(end 63.93434 -301.763176)
		(width 0.12954)
		(layer "F.Cu")
		(net "M_A_CPU1_SB_DQS_DN<2>")
	)
	(segment
		(start 68.27901 -296.38117)
		(end 68.27901 -296.564558)
		(width 0.12954)
		(layer "F.Cu")
		(net "M_A_CPU1_SB_DQS_DN<2>")
	)
	(segment
		(start 62.45098 -303.246536)
		(end 62.000892 -303.246536)
		(width 0.12954)
		(layer "F.Cu")
		(net "M_A_CPU1_SB_DQS_DN<2>")
	)
	(segment
		(start 68.48094 -296.766488)
		(end 68.48094 -297.216576)
		(width 0.12954)
		(layer "F.Cu")
		(net "M_A_CPU1_SB_DQS_DN<2>")
	)
	(segment
		(start 64.86906 -299.79112)
		(end 64.86906 -299.974508)
		(width 0.12954)
		(layer "F.Cu")
		(net "M_A_CPU1_SB_DQS_DN<2>")
	)
	(segment
		(start 65.07099 -300.176438)
		(end 65.07099 -300.626526)
		(width 0.12954)
		(layer "F.Cu")
		(net "M_A_CPU1_SB_DQS_DN<2>")
	)
	(arc
		(start 78.707996 -285.970472)
		(mid 78.465679 -285.800752)
		(end 78.180692 -285.721298)
		(width 0.0762)
		(layer "F.Cu")
		(net "M_A_CPU1_SB_DQS_DN<2>")
	)
	(arc
		(start 78.180692 -285.721298)
		(mid 78.063879 -285.696622)
		(end 77.954886 -285.647892)
		(width 0.0762)
		(layer "F.Cu")
		(net "M_A_CPU1_SB_DQS_DN<2>")
	)
	(arc
		(start 77.954886 -285.647892)
		(mid 77.864753 -285.610272)
		(end 77.767942 -285.597346)
		(width 0.0762)
		(layer "F.Cu")
		(net "M_A_CPU1_SB_DQS_DN<2>")
	)
	(segment
		(start 67.668394 -286.037782)
		(end 67.280028 -286.426148)
		(width 0.12954)
		(layer "F.Cu")
		(net "M_A_CPU1_SB_DQS_DN<1>")
	)
	(segment
		(start 65.279016 -287.876996)
		(end 65.279016 -288.282888)
		(width 0.12954)
		(layer "F.Cu")
		(net "M_A_CPU1_SB_DQS_DN<1>")
	)
	(segment
		(start 67.668394 -285.487618)
		(end 67.668394 -286.037782)
		(width 0.12954)
		(layer "F.Cu")
		(net "M_A_CPU1_SB_DQS_DN<1>")
	)
	(segment
		(start 61.63945 -292.880034)
		(end 61.456824 -292.880288)
		(width 0.12954)
		(layer "F.Cu")
		(net "M_A_CPU1_SB_DQS_DN<1>")
	)
	(segment
		(start 65.279016 -288.282888)
		(end 64.90335 -288.658554)
		(width 0.12954)
		(layer "F.Cu")
		(net "M_A_CPU1_SB_DQS_DN<1>")
	)
	(segment
		(start 64.90335 -288.951924)
		(end 65.279016 -289.32759)
		(width 0.12954)
		(layer "F.Cu")
		(net "M_A_CPU1_SB_DQS_DN<1>")
	)
	(segment
		(start 66.531744 -286.624268)
		(end 66.531744 -287.174432)
		(width 0.12954)
		(layer "F.Cu")
		(net "M_A_CPU1_SB_DQS_DN<1>")
	)
	(segment
		(start 69.941694 -283.764482)
		(end 69.553328 -284.152848)
		(width 0.12954)
		(layer "F.Cu")
		(net "M_A_CPU1_SB_DQS_DN<1>")
	)
	(segment
		(start 72.517508 -280.638504)
		(end 72.214994 -280.941018)
		(width 0.12954)
		(layer "F.Cu")
		(net "M_A_CPU1_SB_DQS_DN<1>")
	)
	(segment
		(start 65.593214 -287.562798)
		(end 65.279016 -287.876996)
		(width 0.12954)
		(layer "F.Cu")
		(net "M_A_CPU1_SB_DQS_DN<1>")
	)
	(segment
		(start 61.298836 -293.038022)
		(end 61.29909 -293.22014)
		(width 0.12954)
		(layer "F.Cu")
		(net "M_A_CPU1_SB_DQS_DN<1>")
	)
	(segment
		(start 66.531744 -287.174432)
		(end 66.143378 -287.562798)
		(width 0.12954)
		(layer "F.Cu")
		(net "M_A_CPU1_SB_DQS_DN<1>")
	)
	(segment
		(start 72.214994 -281.491182)
		(end 71.826628 -281.879548)
		(width 0.12954)
		(layer "F.Cu")
		(net "M_A_CPU1_SB_DQS_DN<1>")
	)
	(segment
		(start 71.826628 -281.879548)
		(end 71.276464 -281.879548)
		(width 0.12954)
		(layer "F.Cu")
		(net "M_A_CPU1_SB_DQS_DN<1>")
	)
	(segment
		(start 68.805044 -284.350968)
		(end 68.805044 -284.901132)
		(width 0.12954)
		(layer "F.Cu")
		(net "M_A_CPU1_SB_DQS_DN<1>")
	)
	(segment
		(start 61.456824 -292.880288)
		(end 61.298836 -293.038022)
		(width 0.12954)
		(layer "F.Cu")
		(net "M_A_CPU1_SB_DQS_DN<1>")
	)
	(segment
		(start 64.90335 -288.658554)
		(end 64.90335 -288.951924)
		(width 0.12954)
		(layer "F.Cu")
		(net "M_A_CPU1_SB_DQS_DN<1>")
	)
	(segment
		(start 69.003164 -284.152848)
		(end 68.805044 -284.350968)
		(width 0.12954)
		(layer "F.Cu")
		(net "M_A_CPU1_SB_DQS_DN<1>")
	)
	(segment
		(start 60.226448 -294.82161)
		(end 59.962796 -295.085262)
		(width 0.12954)
		(layer "F.Cu")
		(net "M_A_CPU1_SB_DQS_DN<1>")
	)
	(segment
		(start 62.471554 -293.712138)
		(end 61.63945 -292.880034)
		(width 0.12954)
		(layer "F.Cu")
		(net "M_A_CPU1_SB_DQS_DN<1>")
	)
	(segment
		(start 68.805044 -284.901132)
		(end 68.416678 -285.289498)
		(width 0.12954)
		(layer "F.Cu")
		(net "M_A_CPU1_SB_DQS_DN<1>")
	)
	(segment
		(start 71.078344 -282.627832)
		(end 70.689978 -283.016198)
		(width 0.12954)
		(layer "F.Cu")
		(net "M_A_CPU1_SB_DQS_DN<1>")
	)
	(segment
		(start 75.955906 -280.638504)
		(end 72.517508 -280.638504)
		(width 0.12954)
		(layer "F.Cu")
		(net "M_A_CPU1_SB_DQS_DN<1>")
	)
	(segment
		(start 62.131448 -294.503348)
		(end 61.813186 -294.82161)
		(width 0.12954)
		(layer "F.Cu")
		(net "M_A_CPU1_SB_DQS_DN<1>")
	)
	(segment
		(start 66.729864 -286.426148)
		(end 66.531744 -286.624268)
		(width 0.12954)
		(layer "F.Cu")
		(net "M_A_CPU1_SB_DQS_DN<1>")
	)
	(segment
		(start 62.131448 -294.052498)
		(end 62.131448 -294.503348)
		(width 0.12954)
		(layer "F.Cu")
		(net "M_A_CPU1_SB_DQS_DN<1>")
	)
	(segment
		(start 76.21397 -280.591514)
		(end 76.021946 -280.572464)
		(width 0.0762)
		(layer "F.Cu")
		(net "M_A_CPU1_SB_DQS_DN<1>")
	)
	(segment
		(start 76.021946 -280.572464)
		(end 75.955906 -280.638504)
		(width 0.0762)
		(layer "F.Cu")
		(net "M_A_CPU1_SB_DQS_DN<1>")
	)
	(segment
		(start 77.767942 -280.73731)
		(end 77.28331 -280.73731)
		(width 0.0762)
		(layer "F.Cu")
		(net "M_A_CPU1_SB_DQS_DN<1>")
	)
	(segment
		(start 64.803782 -291.831014)
		(end 64.257174 -291.831014)
		(width 0.12954)
		(layer "F.Cu")
		(net "M_A_CPU1_SB_DQS_DN<1>")
	)
	(segment
		(start 70.139814 -283.016198)
		(end 69.941694 -283.214318)
		(width 0.12954)
		(layer "F.Cu")
		(net "M_A_CPU1_SB_DQS_DN<1>")
	)
	(segment
		(start 68.416678 -285.289498)
		(end 67.866514 -285.289498)
		(width 0.12954)
		(layer "F.Cu")
		(net "M_A_CPU1_SB_DQS_DN<1>")
	)
	(segment
		(start 67.280028 -286.426148)
		(end 66.729864 -286.426148)
		(width 0.12954)
		(layer "F.Cu")
		(net "M_A_CPU1_SB_DQS_DN<1>")
	)
	(segment
		(start 64.055752 -292.032436)
		(end 64.055752 -292.579044)
		(width 0.12954)
		(layer "F.Cu")
		(net "M_A_CPU1_SB_DQS_DN<1>")
	)
	(segment
		(start 64.055752 -292.579044)
		(end 62.922658 -293.712138)
		(width 0.12954)
		(layer "F.Cu")
		(net "M_A_CPU1_SB_DQS_DN<1>")
	)
	(segment
		(start 65.279016 -289.32759)
		(end 65.279016 -291.35578)
		(width 0.12954)
		(layer "F.Cu")
		(net "M_A_CPU1_SB_DQS_DN<1>")
	)
	(segment
		(start 67.866514 -285.289498)
		(end 67.668394 -285.487618)
		(width 0.12954)
		(layer "F.Cu")
		(net "M_A_CPU1_SB_DQS_DN<1>")
	)
	(segment
		(start 62.922658 -293.712138)
		(end 62.471554 -293.712138)
		(width 0.12954)
		(layer "F.Cu")
		(net "M_A_CPU1_SB_DQS_DN<1>")
	)
	(segment
		(start 65.279016 -291.35578)
		(end 64.803782 -291.831014)
		(width 0.12954)
		(layer "F.Cu")
		(net "M_A_CPU1_SB_DQS_DN<1>")
	)
	(segment
		(start 72.214994 -280.941018)
		(end 72.214994 -281.491182)
		(width 0.12954)
		(layer "F.Cu")
		(net "M_A_CPU1_SB_DQS_DN<1>")
	)
	(segment
		(start 70.689978 -283.016198)
		(end 70.139814 -283.016198)
		(width 0.12954)
		(layer "F.Cu")
		(net "M_A_CPU1_SB_DQS_DN<1>")
	)
	(segment
		(start 69.941694 -283.214318)
		(end 69.941694 -283.764482)
		(width 0.12954)
		(layer "F.Cu")
		(net "M_A_CPU1_SB_DQS_DN<1>")
	)
	(segment
		(start 64.257174 -291.831014)
		(end 64.055752 -292.032436)
		(width 0.12954)
		(layer "F.Cu")
		(net "M_A_CPU1_SB_DQS_DN<1>")
	)
	(segment
		(start 69.553328 -284.152848)
		(end 69.003164 -284.152848)
		(width 0.12954)
		(layer "F.Cu")
		(net "M_A_CPU1_SB_DQS_DN<1>")
	)
	(segment
		(start 59.962796 -295.085262)
		(end 59.428126 -295.085262)
		(width 0.12954)
		(layer "F.Cu")
		(net "M_A_CPU1_SB_DQS_DN<1>")
	)
	(segment
		(start 71.276464 -281.879548)
		(end 71.078344 -282.077668)
		(width 0.12954)
		(layer "F.Cu")
		(net "M_A_CPU1_SB_DQS_DN<1>")
	)
	(segment
		(start 71.078344 -282.077668)
		(end 71.078344 -282.627832)
		(width 0.12954)
		(layer "F.Cu")
		(net "M_A_CPU1_SB_DQS_DN<1>")
	)
	(segment
		(start 66.143378 -287.562798)
		(end 65.593214 -287.562798)
		(width 0.12954)
		(layer "F.Cu")
		(net "M_A_CPU1_SB_DQS_DN<1>")
	)
	(segment
		(start 77.137514 -280.591514)
		(end 76.21397 -280.591514)
		(width 0.0762)
		(layer "F.Cu")
		(net "M_A_CPU1_SB_DQS_DN<1>")
	)
	(segment
		(start 61.29909 -293.22014)
		(end 62.131448 -294.052498)
		(width 0.12954)
		(layer "F.Cu")
		(net "M_A_CPU1_SB_DQS_DN<1>")
	)
	(segment
		(start 61.813186 -294.82161)
		(end 60.226448 -294.82161)
		(width 0.12954)
		(layer "F.Cu")
		(net "M_A_CPU1_SB_DQS_DN<1>")
	)
	(segment
		(start 77.28331 -280.73731)
		(end 77.137514 -280.591514)
		(width 0.0762)
		(layer "F.Cu")
		(net "M_A_CPU1_SB_DQS_DN<1>")
	)
	(arc
		(start 77.954886 -280.787856)
		(mid 77.864753 -280.750236)
		(end 77.767942 -280.73731)
		(width 0.0762)
		(layer "F.Cu")
		(net "M_A_CPU1_SB_DQS_DN<1>")
	)
	(arc
		(start 78.707996 -281.110436)
		(mid 78.465679 -280.940716)
		(end 78.180692 -280.861262)
		(width 0.0762)
		(layer "F.Cu")
		(net "M_A_CPU1_SB_DQS_DN<1>")
	)
	(arc
		(start 78.180692 -280.861262)
		(mid 78.063879 -280.836586)
		(end 77.954886 -280.787856)
		(width 0.0762)
		(layer "F.Cu")
		(net "M_A_CPU1_SB_DQS_DN<1>")
	)
	(segment
		(start 67.006978 -278.174196)
		(end 67.006978 -278.357584)
		(width 0.12954)
		(layer "F.Cu")
		(net "M_A_CPU1_SB_DQS_DN<0>")
	)
	(segment
		(start 65.07353 -280.291032)
		(end 64.890142 -280.291032)
		(width 0.12954)
		(layer "F.Cu")
		(net "M_A_CPU1_SB_DQS_DN<0>")
	)
	(segment
		(start 59.962796 -285.735268)
		(end 59.428126 -285.735268)
		(width 0.12954)
		(layer "F.Cu")
		(net "M_A_CPU1_SB_DQS_DN<0>")
	)
	(segment
		(start 76.724764 -275.877274)
		(end 76.405486 -275.557996)
		(width 0.0762)
		(layer "F.Cu")
		(net "M_A_CPU1_SB_DQS_DN<0>")
	)
	(segment
		(start 64.890142 -280.291032)
		(end 64.733678 -280.447496)
		(width 0.12954)
		(layer "F.Cu")
		(net "M_A_CPU1_SB_DQS_DN<0>")
	)
	(segment
		(start 75.893168 -275.624036)
		(end 75.625198 -275.892006)
		(width 0.12954)
		(layer "F.Cu")
		(net "M_A_CPU1_SB_DQS_DN<0>")
	)
	(segment
		(start 66.21018 -279.154382)
		(end 66.026792 -279.154382)
		(width 0.12954)
		(layer "F.Cu")
		(net "M_A_CPU1_SB_DQS_DN<0>")
	)
	(segment
		(start 63.93688 -281.427682)
		(end 63.753492 -281.427682)
		(width 0.12954)
		(layer "F.Cu")
		(net "M_A_CPU1_SB_DQS_DN<0>")
	)
	(segment
		(start 69.557138 -275.624036)
		(end 69.280278 -275.900896)
		(width 0.12954)
		(layer "F.Cu")
		(net "M_A_CPU1_SB_DQS_DN<0>")
	)
	(segment
		(start 64.833754 -280.73096)
		(end 64.833754 -281.181048)
		(width 0.12954)
		(layer "F.Cu")
		(net "M_A_CPU1_SB_DQS_DN<0>")
	)
	(segment
		(start 61.480192 -283.700982)
		(end 61.138816 -284.042358)
		(width 0.12954)
		(layer "F.Cu")
		(net "M_A_CPU1_SB_DQS_DN<0>")
	)
	(segment
		(start 73.032366 -275.624036)
		(end 72.681592 -275.624036)
		(width 0.12954)
		(layer "F.Cu")
		(net "M_A_CPU1_SB_DQS_DN<0>")
	)
	(segment
		(start 74.906124 -275.892006)
		(end 74.638154 -275.624036)
		(width 0.12954)
		(layer "F.Cu")
		(net "M_A_CPU1_SB_DQS_DN<0>")
	)
	(segment
		(start 75.625198 -275.892006)
		(end 74.906124 -275.892006)
		(width 0.12954)
		(layer "F.Cu")
		(net "M_A_CPU1_SB_DQS_DN<0>")
	)
	(segment
		(start 64.036956 -281.527758)
		(end 63.93688 -281.427682)
		(width 0.12954)
		(layer "F.Cu")
		(net "M_A_CPU1_SB_DQS_DN<0>")
	)
	(segment
		(start 68.143628 -277.037546)
		(end 68.143628 -277.220934)
		(width 0.12954)
		(layer "F.Cu")
		(net "M_A_CPU1_SB_DQS_DN<0>")
	)
	(segment
		(start 67.446906 -278.117808)
		(end 67.34683 -278.017732)
		(width 0.12954)
		(layer "F.Cu")
		(net "M_A_CPU1_SB_DQS_DN<0>")
	)
	(segment
		(start 67.107054 -278.907748)
		(end 66.760344 -279.254458)
		(width 0.12954)
		(layer "F.Cu")
		(net "M_A_CPU1_SB_DQS_DN<0>")
	)
	(segment
		(start 64.733678 -280.447496)
		(end 64.733678 -280.630884)
		(width 0.12954)
		(layer "F.Cu")
		(net "M_A_CPU1_SB_DQS_DN<0>")
	)
	(segment
		(start 66.310256 -279.254458)
		(end 66.21018 -279.154382)
		(width 0.12954)
		(layer "F.Cu")
		(net "M_A_CPU1_SB_DQS_DN<0>")
	)
	(segment
		(start 71.694548 -275.892006)
		(end 71.426578 -275.624036)
		(width 0.12954)
		(layer "F.Cu")
		(net "M_A_CPU1_SB_DQS_DN<0>")
	)
	(segment
		(start 64.733678 -280.630884)
		(end 64.833754 -280.73096)
		(width 0.12954)
		(layer "F.Cu")
		(net "M_A_CPU1_SB_DQS_DN<0>")
	)
	(segment
		(start 77.767942 -275.877274)
		(end 76.724764 -275.877274)
		(width 0.0762)
		(layer "F.Cu")
		(net "M_A_CPU1_SB_DQS_DN<0>")
	)
	(segment
		(start 62.900306 -282.664408)
		(end 62.80023 -282.564332)
		(width 0.12954)
		(layer "F.Cu")
		(net "M_A_CPU1_SB_DQS_DN<0>")
	)
	(segment
		(start 62.213744 -283.801058)
		(end 61.763656 -283.801058)
		(width 0.12954)
		(layer "F.Cu")
		(net "M_A_CPU1_SB_DQS_DN<0>")
	)
	(segment
		(start 72.681592 -275.624036)
		(end 72.413622 -275.892006)
		(width 0.12954)
		(layer "F.Cu")
		(net "M_A_CPU1_SB_DQS_DN<0>")
	)
	(segment
		(start 68.243704 -277.32101)
		(end 68.243704 -277.771098)
		(width 0.12954)
		(layer "F.Cu")
		(net "M_A_CPU1_SB_DQS_DN<0>")
	)
	(segment
		(start 74.638154 -275.624036)
		(end 74.28738 -275.624036)
		(width 0.12954)
		(layer "F.Cu")
		(net "M_A_CPU1_SB_DQS_DN<0>")
	)
	(segment
		(start 70.807834 -275.892006)
		(end 70.08876 -275.892006)
		(width 0.12954)
		(layer "F.Cu")
		(net "M_A_CPU1_SB_DQS_DN<0>")
	)
	(segment
		(start 69.033644 -276.981158)
		(end 68.583556 -276.981158)
		(width 0.12954)
		(layer "F.Cu")
		(net "M_A_CPU1_SB_DQS_DN<0>")
	)
	(segment
		(start 73.300336 -275.892006)
		(end 73.032366 -275.624036)
		(width 0.12954)
		(layer "F.Cu")
		(net "M_A_CPU1_SB_DQS_DN<0>")
	)
	(segment
		(start 63.597028 -281.584146)
		(end 63.597028 -281.767534)
		(width 0.12954)
		(layer "F.Cu")
		(net "M_A_CPU1_SB_DQS_DN<0>")
	)
	(segment
		(start 64.833754 -281.181048)
		(end 64.487044 -281.527758)
		(width 0.12954)
		(layer "F.Cu")
		(net "M_A_CPU1_SB_DQS_DN<0>")
	)
	(segment
		(start 61.763656 -283.801058)
		(end 61.66358 -283.700982)
		(width 0.12954)
		(layer "F.Cu")
		(net "M_A_CPU1_SB_DQS_DN<0>")
	)
	(segment
		(start 62.560454 -283.00426)
		(end 62.560454 -283.454348)
		(width 0.12954)
		(layer "F.Cu")
		(net "M_A_CPU1_SB_DQS_DN<0>")
	)
	(segment
		(start 62.616842 -282.564332)
		(end 62.460378 -282.720796)
		(width 0.12954)
		(layer "F.Cu")
		(net "M_A_CPU1_SB_DQS_DN<0>")
	)
	(segment
		(start 61.138816 -284.042358)
		(end 61.138816 -284.957012)
		(width 0.12954)
		(layer "F.Cu")
		(net "M_A_CPU1_SB_DQS_DN<0>")
	)
	(segment
		(start 63.697104 -281.86761)
		(end 63.697104 -282.317698)
		(width 0.12954)
		(layer "F.Cu")
		(net "M_A_CPU1_SB_DQS_DN<0>")
	)
	(segment
		(start 66.026792 -279.154382)
		(end 65.870328 -279.310846)
		(width 0.12954)
		(layer "F.Cu")
		(net "M_A_CPU1_SB_DQS_DN<0>")
	)
	(segment
		(start 71.075804 -275.624036)
		(end 70.807834 -275.892006)
		(width 0.12954)
		(layer "F.Cu")
		(net "M_A_CPU1_SB_DQS_DN<0>")
	)
	(segment
		(start 67.34683 -278.017732)
		(end 67.163442 -278.017732)
		(width 0.12954)
		(layer "F.Cu")
		(net "M_A_CPU1_SB_DQS_DN<0>")
	)
	(segment
		(start 62.460378 -282.904184)
		(end 62.560454 -283.00426)
		(width 0.12954)
		(layer "F.Cu")
		(net "M_A_CPU1_SB_DQS_DN<0>")
	)
	(segment
		(start 62.460378 -282.720796)
		(end 62.460378 -282.904184)
		(width 0.12954)
		(layer "F.Cu")
		(net "M_A_CPU1_SB_DQS_DN<0>")
	)
	(segment
		(start 67.163442 -278.017732)
		(end 67.006978 -278.174196)
		(width 0.12954)
		(layer "F.Cu")
		(net "M_A_CPU1_SB_DQS_DN<0>")
	)
	(segment
		(start 69.280278 -276.084284)
		(end 69.380354 -276.18436)
		(width 0.12954)
		(layer "F.Cu")
		(net "M_A_CPU1_SB_DQS_DN<0>")
	)
	(segment
		(start 65.970404 -280.044398)
		(end 65.623694 -280.391108)
		(width 0.12954)
		(layer "F.Cu")
		(net "M_A_CPU1_SB_DQS_DN<0>")
	)
	(segment
		(start 65.623694 -280.391108)
		(end 65.173606 -280.391108)
		(width 0.12954)
		(layer "F.Cu")
		(net "M_A_CPU1_SB_DQS_DN<0>")
	)
	(segment
		(start 76.405486 -275.557996)
		(end 76.1746 -275.557996)
		(width 0.0762)
		(layer "F.Cu")
		(net "M_A_CPU1_SB_DQS_DN<0>")
	)
	(segment
		(start 63.350394 -282.664408)
		(end 62.900306 -282.664408)
		(width 0.12954)
		(layer "F.Cu")
		(net "M_A_CPU1_SB_DQS_DN<0>")
	)
	(segment
		(start 68.48348 -276.881082)
		(end 68.300092 -276.881082)
		(width 0.12954)
		(layer "F.Cu")
		(net "M_A_CPU1_SB_DQS_DN<0>")
	)
	(segment
		(start 68.300092 -276.881082)
		(end 68.143628 -277.037546)
		(width 0.12954)
		(layer "F.Cu")
		(net "M_A_CPU1_SB_DQS_DN<0>")
	)
	(segment
		(start 65.870328 -279.310846)
		(end 65.870328 -279.494234)
		(width 0.12954)
		(layer "F.Cu")
		(net "M_A_CPU1_SB_DQS_DN<0>")
	)
	(segment
		(start 63.753492 -281.427682)
		(end 63.597028 -281.584146)
		(width 0.12954)
		(layer "F.Cu")
		(net "M_A_CPU1_SB_DQS_DN<0>")
	)
	(segment
		(start 68.143628 -277.220934)
		(end 68.243704 -277.32101)
		(width 0.12954)
		(layer "F.Cu")
		(net "M_A_CPU1_SB_DQS_DN<0>")
	)
	(segment
		(start 74.01941 -275.892006)
		(end 73.300336 -275.892006)
		(width 0.12954)
		(layer "F.Cu")
		(net "M_A_CPU1_SB_DQS_DN<0>")
	)
	(segment
		(start 71.426578 -275.624036)
		(end 71.075804 -275.624036)
		(width 0.12954)
		(layer "F.Cu")
		(net "M_A_CPU1_SB_DQS_DN<0>")
	)
	(segment
		(start 63.697104 -282.317698)
		(end 63.350394 -282.664408)
		(width 0.12954)
		(layer "F.Cu")
		(net "M_A_CPU1_SB_DQS_DN<0>")
	)
	(segment
		(start 69.380354 -276.634448)
		(end 69.033644 -276.981158)
		(width 0.12954)
		(layer "F.Cu")
		(net "M_A_CPU1_SB_DQS_DN<0>")
	)
	(segment
		(start 64.487044 -281.527758)
		(end 64.036956 -281.527758)
		(width 0.12954)
		(layer "F.Cu")
		(net "M_A_CPU1_SB_DQS_DN<0>")
	)
	(segment
		(start 61.138816 -284.957012)
		(end 60.624212 -285.471616)
		(width 0.12954)
		(layer "F.Cu")
		(net "M_A_CPU1_SB_DQS_DN<0>")
	)
	(segment
		(start 66.760344 -279.254458)
		(end 66.310256 -279.254458)
		(width 0.12954)
		(layer "F.Cu")
		(net "M_A_CPU1_SB_DQS_DN<0>")
	)
	(segment
		(start 60.624212 -285.471616)
		(end 60.226448 -285.471616)
		(width 0.12954)
		(layer "F.Cu")
		(net "M_A_CPU1_SB_DQS_DN<0>")
	)
	(segment
		(start 69.280278 -275.900896)
		(end 69.280278 -276.084284)
		(width 0.12954)
		(layer "F.Cu")
		(net "M_A_CPU1_SB_DQS_DN<0>")
	)
	(segment
		(start 69.380354 -276.18436)
		(end 69.380354 -276.634448)
		(width 0.12954)
		(layer "F.Cu")
		(net "M_A_CPU1_SB_DQS_DN<0>")
	)
	(segment
		(start 76.10856 -275.624036)
		(end 76.08951 -275.624036)
		(width 0.0762)
		(layer "F.Cu")
		(net "M_A_CPU1_SB_DQS_DN<0>")
	)
	(segment
		(start 63.597028 -281.767534)
		(end 63.697104 -281.86761)
		(width 0.12954)
		(layer "F.Cu")
		(net "M_A_CPU1_SB_DQS_DN<0>")
	)
	(segment
		(start 65.870328 -279.494234)
		(end 65.970404 -279.59431)
		(width 0.12954)
		(layer "F.Cu")
		(net "M_A_CPU1_SB_DQS_DN<0>")
	)
	(segment
		(start 68.243704 -277.771098)
		(end 67.896994 -278.117808)
		(width 0.12954)
		(layer "F.Cu")
		(net "M_A_CPU1_SB_DQS_DN<0>")
	)
	(segment
		(start 74.28738 -275.624036)
		(end 74.01941 -275.892006)
		(width 0.12954)
		(layer "F.Cu")
		(net "M_A_CPU1_SB_DQS_DN<0>")
	)
	(segment
		(start 67.107054 -278.45766)
		(end 67.107054 -278.907748)
		(width 0.12954)
		(layer "F.Cu")
		(net "M_A_CPU1_SB_DQS_DN<0>")
	)
	(segment
		(start 68.583556 -276.981158)
		(end 68.48348 -276.881082)
		(width 0.12954)
		(layer "F.Cu")
		(net "M_A_CPU1_SB_DQS_DN<0>")
	)
	(segment
		(start 72.413622 -275.892006)
		(end 71.694548 -275.892006)
		(width 0.12954)
		(layer "F.Cu")
		(net "M_A_CPU1_SB_DQS_DN<0>")
	)
	(segment
		(start 65.173606 -280.391108)
		(end 65.07353 -280.291032)
		(width 0.12954)
		(layer "F.Cu")
		(net "M_A_CPU1_SB_DQS_DN<0>")
	)
	(segment
		(start 70.08876 -275.892006)
		(end 69.82079 -275.624036)
		(width 0.12954)
		(layer "F.Cu")
		(net "M_A_CPU1_SB_DQS_DN<0>")
	)
	(segment
		(start 76.08951 -275.624036)
		(end 75.893168 -275.624036)
		(width 0.12954)
		(layer "F.Cu")
		(net "M_A_CPU1_SB_DQS_DN<0>")
	)
	(segment
		(start 69.82079 -275.624036)
		(end 69.557138 -275.624036)
		(width 0.12954)
		(layer "F.Cu")
		(net "M_A_CPU1_SB_DQS_DN<0>")
	)
	(segment
		(start 61.66358 -283.700982)
		(end 61.480192 -283.700982)
		(width 0.12954)
		(layer "F.Cu")
		(net "M_A_CPU1_SB_DQS_DN<0>")
	)
	(segment
		(start 60.226448 -285.471616)
		(end 59.962796 -285.735268)
		(width 0.12954)
		(layer "F.Cu")
		(net "M_A_CPU1_SB_DQS_DN<0>")
	)
	(segment
		(start 65.970404 -279.59431)
		(end 65.970404 -280.044398)
		(width 0.12954)
		(layer "F.Cu")
		(net "M_A_CPU1_SB_DQS_DN<0>")
	)
	(segment
		(start 76.1746 -275.557996)
		(end 76.10856 -275.624036)
		(width 0.0762)
		(layer "F.Cu")
		(net "M_A_CPU1_SB_DQS_DN<0>")
	)
	(segment
		(start 62.80023 -282.564332)
		(end 62.616842 -282.564332)
		(width 0.12954)
		(layer "F.Cu")
		(net "M_A_CPU1_SB_DQS_DN<0>")
	)
	(segment
		(start 62.560454 -283.454348)
		(end 62.213744 -283.801058)
		(width 0.12954)
		(layer "F.Cu")
		(net "M_A_CPU1_SB_DQS_DN<0>")
	)
	(segment
		(start 67.006978 -278.357584)
		(end 67.107054 -278.45766)
		(width 0.12954)
		(layer "F.Cu")
		(net "M_A_CPU1_SB_DQS_DN<0>")
	)
	(segment
		(start 67.896994 -278.117808)
		(end 67.446906 -278.117808)
		(width 0.12954)
		(layer "F.Cu")
		(net "M_A_CPU1_SB_DQS_DN<0>")
	)
	(arc
		(start 77.954886 -275.92782)
		(mid 77.864753 -275.8902)
		(end 77.767942 -275.877274)
		(width 0.0762)
		(layer "F.Cu")
		(net "M_A_CPU1_SB_DQS_DN<0>")
	)
	(arc
		(start 78.180692 -276.001226)
		(mid 78.063879 -275.97655)
		(end 77.954886 -275.92782)
		(width 0.0762)
		(layer "F.Cu")
		(net "M_A_CPU1_SB_DQS_DN<0>")
	)
	(arc
		(start 78.707996 -276.2504)
		(mid 78.465679 -276.08068)
		(end 78.180692 -276.001226)
		(width 0.0762)
		(layer "F.Cu")
		(net "M_A_CPU1_SB_DQS_DN<0>")
	)
	(segment
		(start 62.346332 -292.068504)
		(end 62.215268 -291.93744)
		(width 0.10668)
		(layer "F.Cu")
		(net "M_A_CPU1_SB_DQ<9>")
	)
	(segment
		(start 76.72705 -279.86355)
		(end 76.428854 -279.565354)
		(width 0.0762)
		(layer "F.Cu")
		(net "M_A_CPU1_SB_DQ<9>")
	)
	(segment
		(start 63.276226 -290.160964)
		(end 61.63056 -291.80663)
		(width 0.10668)
		(layer "F.Cu")
		(net "M_A_CPU1_SB_DQ<9>")
	)
	(segment
		(start 77.767942 -279.86355)
		(end 76.72705 -279.86355)
		(width 0.0762)
		(layer "F.Cu")
		(net "M_A_CPU1_SB_DQ<9>")
	)
	(segment
		(start 79.647796 -279.490424)
		(end 79.748634 -279.663906)
		(width 0.0762)
		(layer "F.Cu")
		(net "M_A_CPU1_SB_DQ<9>")
	)
	(segment
		(start 78.89494 -279.813004)
		(end 78.886558 -279.81783)
		(width 0.0762)
		(layer "F.Cu")
		(net "M_A_CPU1_SB_DQ<9>")
	)
	(segment
		(start 62.215268 -291.93744)
		(end 62.215268 -291.78631)
		(width 0.10668)
		(layer "F.Cu")
		(net "M_A_CPU1_SB_DQ<9>")
	)
	(segment
		(start 63.9572 -290.126674)
		(end 63.9572 -290.608766)
		(width 0.10668)
		(layer "F.Cu")
		(net "M_A_CPU1_SB_DQ<9>")
	)
	(segment
		(start 63.9572 -290.608766)
		(end 62.497462 -292.068504)
		(width 0.10668)
		(layer "F.Cu")
		(net "M_A_CPU1_SB_DQ<9>")
	)
	(segment
		(start 62.497462 -292.068504)
		(end 62.346332 -292.068504)
		(width 0.10668)
		(layer "F.Cu")
		(net "M_A_CPU1_SB_DQ<9>")
	)
	(segment
		(start 76.428854 -279.565354)
		(end 75.960986 -279.565354)
		(width 0.0762)
		(layer "F.Cu")
		(net "M_A_CPU1_SB_DQ<9>")
	)
	(segment
		(start 63.740792 -289.910266)
		(end 63.9572 -290.126674)
		(width 0.10668)
		(layer "F.Cu")
		(net "M_A_CPU1_SB_DQ<9>")
	)
	(segment
		(start 59.949334 -292.535356)
		(end 59.428126 -292.535356)
		(width 0.10668)
		(layer "F.Cu")
		(net "M_A_CPU1_SB_DQ<9>")
	)
	(segment
		(start 72.0725 -279.565354)
		(end 63.740792 -287.897062)
		(width 0.10668)
		(layer "F.Cu")
		(net "M_A_CPU1_SB_DQ<9>")
	)
	(segment
		(start 75.960986 -279.565354)
		(end 72.0725 -279.565354)
		(width 0.10668)
		(layer "F.Cu")
		(net "M_A_CPU1_SB_DQ<9>")
	)
	(segment
		(start 62.215268 -291.78631)
		(end 63.55842 -290.443158)
		(width 0.10668)
		(layer "F.Cu")
		(net "M_A_CPU1_SB_DQ<9>")
	)
	(segment
		(start 61.63056 -291.80663)
		(end 60.67806 -291.80663)
		(width 0.10668)
		(layer "F.Cu")
		(net "M_A_CPU1_SB_DQ<9>")
	)
	(segment
		(start 60.67806 -291.80663)
		(end 59.949334 -292.535356)
		(width 0.10668)
		(layer "F.Cu")
		(net "M_A_CPU1_SB_DQ<9>")
	)
	(segment
		(start 63.740792 -287.897062)
		(end 63.740792 -289.910266)
		(width 0.10668)
		(layer "F.Cu")
		(net "M_A_CPU1_SB_DQ<9>")
	)
	(segment
		(start 63.55842 -290.292282)
		(end 63.427102 -290.160964)
		(width 0.10668)
		(layer "F.Cu")
		(net "M_A_CPU1_SB_DQ<9>")
	)
	(segment
		(start 79.469234 -279.81783)
		(end 79.460852 -279.813004)
		(width 0.0762)
		(layer "F.Cu")
		(net "M_A_CPU1_SB_DQ<9>")
	)
	(segment
		(start 63.427102 -290.160964)
		(end 63.276226 -290.160964)
		(width 0.10668)
		(layer "F.Cu")
		(net "M_A_CPU1_SB_DQ<9>")
	)
	(segment
		(start 63.55842 -290.443158)
		(end 63.55842 -290.292282)
		(width 0.10668)
		(layer "F.Cu")
		(net "M_A_CPU1_SB_DQ<9>")
	)
	(arc
		(start 79.602584 -279.860502)
		(mid 79.533886 -279.845486)
		(end 79.469234 -279.81783)
		(width 0.0762)
		(layer "F.Cu")
		(net "M_A_CPU1_SB_DQ<9>")
	)
	(arc
		(start 77.954886 -279.813004)
		(mid 77.879646 -279.846317)
		(end 77.79893 -279.86228)
		(width 0.0762)
		(layer "F.Cu")
		(net "M_A_CPU1_SB_DQ<9>")
	)
	(arc
		(start 78.520798 -279.813004)
		(mid 78.237842 -279.736827)
		(end 77.954886 -279.813004)
		(width 0.0762)
		(layer "F.Cu")
		(net "M_A_CPU1_SB_DQ<9>")
	)
	(arc
		(start 79.748634 -279.663906)
		(mid 79.732709 -279.804598)
		(end 79.602584 -279.860502)
		(width 0.0762)
		(layer "F.Cu")
		(net "M_A_CPU1_SB_DQ<9>")
	)
	(arc
		(start 78.886558 -279.81783)
		(mid 78.70305 -279.863324)
		(end 78.520798 -279.813004)
		(width 0.0762)
		(layer "F.Cu")
		(net "M_A_CPU1_SB_DQ<9>")
	)
	(arc
		(start 79.460852 -279.813004)
		(mid 79.177896 -279.736827)
		(end 78.89494 -279.813004)
		(width 0.0762)
		(layer "F.Cu")
		(net "M_A_CPU1_SB_DQ<9>")
	)
	(arc
		(start 77.79893 -279.86228)
		(mid 77.783449 -279.863236)
		(end 77.767942 -279.86355)
		(width 0.0762)
		(layer "F.Cu")
		(net "M_A_CPU1_SB_DQ<9>")
	)
	(segment
		(start 77.767942 -278.926798)
		(end 77.362304 -278.926798)
		(width 0.0762)
		(layer "F.Cu")
		(net "M_A_CPU1_SB_DQ<8>")
	)
	(segment
		(start 62.631828 -288.042858)
		(end 62.482222 -288.192464)
		(width 0.10668)
		(layer "F.Cu")
		(net "M_A_CPU1_SB_DQ<8>")
	)
	(segment
		(start 60.75934 -289.915346)
		(end 60.75934 -290.066476)
		(width 0.10668)
		(layer "F.Cu")
		(net "M_A_CPU1_SB_DQ<8>")
	)
	(segment
		(start 62.482222 -288.34334)
		(end 63.059818 -288.920936)
		(width 0.10668)
		(layer "F.Cu")
		(net "M_A_CPU1_SB_DQ<8>")
	)
	(segment
		(start 75.93838 -278.862028)
		(end 71.812658 -278.862028)
		(width 0.10668)
		(layer "F.Cu")
		(net "M_A_CPU1_SB_DQ<8>")
	)
	(segment
		(start 61.97092 -290.502848)
		(end 61.820044 -290.502848)
		(width 0.10668)
		(layer "F.Cu")
		(net "M_A_CPU1_SB_DQ<8>")
	)
	(segment
		(start 78.237842 -278.680418)
		(end 78.33614 -278.849582)
		(width 0.0762)
		(layer "F.Cu")
		(net "M_A_CPU1_SB_DQ<8>")
	)
	(segment
		(start 61.42863 -290.735766)
		(end 61.42863 -290.900866)
		(width 0.10668)
		(layer "F.Cu")
		(net "M_A_CPU1_SB_DQ<8>")
	)
	(segment
		(start 62.102492 -290.371276)
		(end 61.97092 -290.502848)
		(width 0.10668)
		(layer "F.Cu")
		(net "M_A_CPU1_SB_DQ<8>")
	)
	(segment
		(start 62.777624 -289.202876)
		(end 62.200028 -288.62528)
		(width 0.10668)
		(layer "F.Cu")
		(net "M_A_CPU1_SB_DQ<8>")
	)
	(segment
		(start 62.200028 -288.62528)
		(end 62.049152 -288.625534)
		(width 0.10668)
		(layer "F.Cu")
		(net "M_A_CPU1_SB_DQ<8>")
	)
	(segment
		(start 61.353446 -289.32124)
		(end 61.353446 -289.472116)
		(width 0.10668)
		(layer "F.Cu")
		(net "M_A_CPU1_SB_DQ<8>")
	)
	(segment
		(start 63.059818 -288.920936)
		(end 63.060072 -289.071304)
		(width 0.10668)
		(layer "F.Cu")
		(net "M_A_CPU1_SB_DQ<8>")
	)
	(segment
		(start 62.384432 -289.93846)
		(end 61.63564 -289.189668)
		(width 0.10668)
		(layer "F.Cu")
		(net "M_A_CPU1_SB_DQ<8>")
	)
	(segment
		(start 62.666626 -289.65652)
		(end 62.66688 -289.806888)
		(width 0.10668)
		(layer "F.Cu")
		(net "M_A_CPU1_SB_DQ<8>")
	)
	(segment
		(start 60.93333 -291.065966)
		(end 60.702698 -290.835334)
		(width 0.10668)
		(layer "F.Cu")
		(net "M_A_CPU1_SB_DQ<8>")
	)
	(segment
		(start 78.05928 -279.007824)
		(end 78.050898 -279.002998)
		(width 0.0762)
		(layer "F.Cu")
		(net "M_A_CPU1_SB_DQ<8>")
	)
	(segment
		(start 61.820044 -290.502848)
		(end 61.071252 -289.754056)
		(width 0.10668)
		(layer "F.Cu")
		(net "M_A_CPU1_SB_DQ<8>")
	)
	(segment
		(start 60.702698 -290.835334)
		(end 59.428126 -290.835334)
		(width 0.10668)
		(layer "F.Cu")
		(net "M_A_CPU1_SB_DQ<8>")
	)
	(segment
		(start 61.42863 -290.900866)
		(end 61.26353 -291.065966)
		(width 0.10668)
		(layer "F.Cu")
		(net "M_A_CPU1_SB_DQ<8>")
	)
	(segment
		(start 61.63564 -289.189668)
		(end 61.484764 -289.189922)
		(width 0.10668)
		(layer "F.Cu")
		(net "M_A_CPU1_SB_DQ<8>")
	)
	(segment
		(start 61.071252 -289.754056)
		(end 60.920376 -289.75431)
		(width 0.10668)
		(layer "F.Cu")
		(net "M_A_CPU1_SB_DQ<8>")
	)
	(segment
		(start 60.75934 -290.066476)
		(end 61.42863 -290.735766)
		(width 0.10668)
		(layer "F.Cu")
		(net "M_A_CPU1_SB_DQ<8>")
	)
	(segment
		(start 62.102238 -290.220908)
		(end 62.102492 -290.371276)
		(width 0.10668)
		(layer "F.Cu")
		(net "M_A_CPU1_SB_DQ<8>")
	)
	(segment
		(start 61.353446 -289.472116)
		(end 62.102238 -290.220908)
		(width 0.10668)
		(layer "F.Cu")
		(net "M_A_CPU1_SB_DQ<8>")
	)
	(segment
		(start 62.482222 -288.192464)
		(end 62.482222 -288.34334)
		(width 0.10668)
		(layer "F.Cu")
		(net "M_A_CPU1_SB_DQ<8>")
	)
	(segment
		(start 61.917834 -288.756852)
		(end 61.917834 -288.907728)
		(width 0.10668)
		(layer "F.Cu")
		(net "M_A_CPU1_SB_DQ<8>")
	)
	(segment
		(start 71.812658 -278.862028)
		(end 63.028322 -287.646364)
		(width 0.10668)
		(layer "F.Cu")
		(net "M_A_CPU1_SB_DQ<8>")
	)
	(segment
		(start 63.060072 -289.071304)
		(end 62.9285 -289.202876)
		(width 0.10668)
		(layer "F.Cu")
		(net "M_A_CPU1_SB_DQ<8>")
	)
	(segment
		(start 77.297534 -278.862028)
		(end 75.93838 -278.862028)
		(width 0.0762)
		(layer "F.Cu")
		(net "M_A_CPU1_SB_DQ<8>")
	)
	(segment
		(start 77.362304 -278.926798)
		(end 77.297534 -278.862028)
		(width 0.0762)
		(layer "F.Cu")
		(net "M_A_CPU1_SB_DQ<8>")
	)
	(segment
		(start 63.02883 -287.911286)
		(end 62.897258 -288.042858)
		(width 0.10668)
		(layer "F.Cu")
		(net "M_A_CPU1_SB_DQ<8>")
	)
	(segment
		(start 61.917834 -288.907728)
		(end 62.666626 -289.65652)
		(width 0.10668)
		(layer "F.Cu")
		(net "M_A_CPU1_SB_DQ<8>")
	)
	(segment
		(start 63.028322 -287.646364)
		(end 63.02883 -287.911286)
		(width 0.10668)
		(layer "F.Cu")
		(net "M_A_CPU1_SB_DQ<8>")
	)
	(segment
		(start 62.897258 -288.042858)
		(end 62.631828 -288.042858)
		(width 0.10668)
		(layer "F.Cu")
		(net "M_A_CPU1_SB_DQ<8>")
	)
	(segment
		(start 61.26353 -291.065966)
		(end 60.93333 -291.065966)
		(width 0.10668)
		(layer "F.Cu")
		(net "M_A_CPU1_SB_DQ<8>")
	)
	(segment
		(start 62.66688 -289.806888)
		(end 62.535308 -289.93846)
		(width 0.10668)
		(layer "F.Cu")
		(net "M_A_CPU1_SB_DQ<8>")
	)
	(segment
		(start 60.920376 -289.75431)
		(end 60.75934 -289.915346)
		(width 0.10668)
		(layer "F.Cu")
		(net "M_A_CPU1_SB_DQ<8>")
	)
	(segment
		(start 62.535308 -289.93846)
		(end 62.384432 -289.93846)
		(width 0.10668)
		(layer "F.Cu")
		(net "M_A_CPU1_SB_DQ<8>")
	)
	(segment
		(start 61.484764 -289.189922)
		(end 61.353446 -289.32124)
		(width 0.10668)
		(layer "F.Cu")
		(net "M_A_CPU1_SB_DQ<8>")
	)
	(segment
		(start 62.049152 -288.625534)
		(end 61.917834 -288.756852)
		(width 0.10668)
		(layer "F.Cu")
		(net "M_A_CPU1_SB_DQ<8>")
	)
	(segment
		(start 62.9285 -289.202876)
		(end 62.777624 -289.202876)
		(width 0.10668)
		(layer "F.Cu")
		(net "M_A_CPU1_SB_DQ<8>")
	)
	(arc
		(start 78.33614 -278.849582)
		(mid 78.327547 -278.991461)
		(end 78.198472 -279.051258)
		(width 0.0762)
		(layer "F.Cu")
		(net "M_A_CPU1_SB_DQ<8>")
	)
	(arc
		(start 78.198472 -279.051258)
		(mid 78.126734 -279.036406)
		(end 78.05928 -279.007824)
		(width 0.0762)
		(layer "F.Cu")
		(net "M_A_CPU1_SB_DQ<8>")
	)
	(arc
		(start 78.050898 -279.002998)
		(mid 77.914462 -278.946173)
		(end 77.767942 -278.926798)
		(width 0.0762)
		(layer "F.Cu")
		(net "M_A_CPU1_SB_DQ<8>")
	)
	(segment
		(start 76.672694 -278.434038)
		(end 76.643484 -278.404828)
		(width 0.0762)
		(layer "F.Cu")
		(net "M_A_CPU1_SB_DQ<7>")
	)
	(segment
		(start 60.467748 -289.560254)
		(end 58.155586 -289.560254)
		(width 0.101346)
		(layer "F.Cu")
		(net "M_A_CPU1_SB_DQ<7>")
	)
	(segment
		(start 78.05928 -278.353012)
		(end 78.050898 -278.357838)
		(width 0.0762)
		(layer "F.Cu")
		(net "M_A_CPU1_SB_DQ<7>")
	)
	(segment
		(start 77.768196 -278.434038)
		(end 76.672694 -278.434038)
		(width 0.0762)
		(layer "F.Cu")
		(net "M_A_CPU1_SB_DQ<7>")
	)
	(segment
		(start 60.635388 -289.392614)
		(end 60.467748 -289.560254)
		(width 0.101346)
		(layer "F.Cu")
		(net "M_A_CPU1_SB_DQ<7>")
	)
	(segment
		(start 76.643484 -278.404828)
		(end 75.960986 -278.404828)
		(width 0.0762)
		(layer "F.Cu")
		(net "M_A_CPU1_SB_DQ<7>")
	)
	(segment
		(start 75.960986 -278.404828)
		(end 71.623174 -278.404828)
		(width 0.10668)
		(layer "F.Cu")
		(net "M_A_CPU1_SB_DQ<7>")
	)
	(segment
		(start 58.155586 -289.560254)
		(end 57.73039 -289.98545)
		(width 0.101346)
		(layer "F.Cu")
		(net "M_A_CPU1_SB_DQ<7>")
	)
	(segment
		(start 57.73039 -289.98545)
		(end 55.328058 -289.98545)
		(width 0.101346)
		(layer "F.Cu")
		(net "M_A_CPU1_SB_DQ<7>")
	)
	(segment
		(start 71.623174 -278.404828)
		(end 60.635388 -289.392614)
		(width 0.10668)
		(layer "F.Cu")
		(net "M_A_CPU1_SB_DQ<7>")
	)
	(arc
		(start 78.42504 -278.357838)
		(mid 78.242789 -278.307488)
		(end 78.05928 -278.353012)
		(width 0.0762)
		(layer "F.Cu")
		(net "M_A_CPU1_SB_DQ<7>")
	)
	(arc
		(start 78.990952 -278.357838)
		(mid 78.707996 -278.434015)
		(end 78.42504 -278.357838)
		(width 0.0762)
		(layer "F.Cu")
		(net "M_A_CPU1_SB_DQ<7>")
	)
	(arc
		(start 79.36484 -278.357838)
		(mid 79.177896 -278.307583)
		(end 78.990952 -278.357838)
		(width 0.0762)
		(layer "F.Cu")
		(net "M_A_CPU1_SB_DQ<7>")
	)
	(arc
		(start 80.11795 -278.680418)
		(mid 79.880338 -278.50943)
		(end 79.598012 -278.432006)
		(width 0.0762)
		(layer "F.Cu")
		(net "M_A_CPU1_SB_DQ<7>")
	)
	(arc
		(start 77.815186 -278.43226)
		(mid 77.791709 -278.433636)
		(end 77.768196 -278.434038)
		(width 0.0762)
		(layer "F.Cu")
		(net "M_A_CPU1_SB_DQ<7>")
	)
	(arc
		(start 79.598012 -278.432006)
		(mid 79.477363 -278.407705)
		(end 79.36484 -278.357838)
		(width 0.0762)
		(layer "F.Cu")
		(net "M_A_CPU1_SB_DQ<7>")
	)
	(arc
		(start 78.050898 -278.357838)
		(mid 77.937174 -278.408139)
		(end 77.815186 -278.43226)
		(width 0.0762)
		(layer "F.Cu")
		(net "M_A_CPU1_SB_DQ<7>")
	)
	(segment
		(start 56.907176 -288.386774)
		(end 56.907176 -288.59226)
		(width 0.101346)
		(layer "F.Cu")
		(net "M_A_CPU1_SB_DQ<6>")
	)
	(segment
		(start 57.300876 -288.386774)
		(end 57.19953 -288.285428)
		(width 0.101346)
		(layer "F.Cu")
		(net "M_A_CPU1_SB_DQ<6>")
	)
	(segment
		(start 57.300876 -288.59226)
		(end 57.300876 -288.386774)
		(width 0.101346)
		(layer "F.Cu")
		(net "M_A_CPU1_SB_DQ<6>")
	)
	(segment
		(start 57.694576 -288.59226)
		(end 57.59323 -288.693606)
		(width 0.101346)
		(layer "F.Cu")
		(net "M_A_CPU1_SB_DQ<6>")
	)
	(segment
		(start 57.694576 -288.386774)
		(end 57.694576 -288.59226)
		(width 0.101346)
		(layer "F.Cu")
		(net "M_A_CPU1_SB_DQ<6>")
	)
	(segment
		(start 56.907176 -288.59226)
		(end 56.80583 -288.693606)
		(width 0.101346)
		(layer "F.Cu")
		(net "M_A_CPU1_SB_DQ<6>")
	)
	(segment
		(start 62.732412 -285.834074)
		(end 62.732412 -286.076898)
		(width 0.10668)
		(layer "F.Cu")
		(net "M_A_CPU1_SB_DQ<6>")
	)
	(segment
		(start 76.285598 -277.399496)
		(end 76.16444 -277.399496)
		(width 0.0762)
		(layer "F.Cu")
		(net "M_A_CPU1_SB_DQ<6>")
	)
	(segment
		(start 60.949078 -287.860232)
		(end 60.725812 -287.860232)
		(width 0.10668)
		(layer "F.Cu")
		(net "M_A_CPU1_SB_DQ<6>")
	)
	(segment
		(start 56.41213 -288.285428)
		(end 55.328058 -288.285428)
		(width 0.101346)
		(layer "F.Cu")
		(net "M_A_CPU1_SB_DQ<6>")
	)
	(segment
		(start 56.513476 -288.59226)
		(end 56.513476 -288.386774)
		(width 0.101346)
		(layer "F.Cu")
		(net "M_A_CPU1_SB_DQ<6>")
	)
	(segment
		(start 62.732412 -286.076898)
		(end 60.949078 -287.860232)
		(width 0.10668)
		(layer "F.Cu")
		(net "M_A_CPU1_SB_DQ<6>")
	)
	(segment
		(start 56.513476 -288.386774)
		(end 56.41213 -288.285428)
		(width 0.101346)
		(layer "F.Cu")
		(net "M_A_CPU1_SB_DQ<6>")
	)
	(segment
		(start 76.16444 -277.399496)
		(end 71.16699 -277.399496)
		(width 0.10668)
		(layer "F.Cu")
		(net "M_A_CPU1_SB_DQ<6>")
	)
	(segment
		(start 57.402222 -288.693606)
		(end 57.300876 -288.59226)
		(width 0.101346)
		(layer "F.Cu")
		(net "M_A_CPU1_SB_DQ<6>")
	)
	(segment
		(start 56.80583 -288.693606)
		(end 56.614822 -288.693606)
		(width 0.101346)
		(layer "F.Cu")
		(net "M_A_CPU1_SB_DQ<6>")
	)
	(segment
		(start 57.008522 -288.285428)
		(end 56.907176 -288.386774)
		(width 0.101346)
		(layer "F.Cu")
		(net "M_A_CPU1_SB_DQ<6>")
	)
	(segment
		(start 57.19953 -288.285428)
		(end 57.008522 -288.285428)
		(width 0.101346)
		(layer "F.Cu")
		(net "M_A_CPU1_SB_DQ<6>")
	)
	(segment
		(start 57.59323 -288.693606)
		(end 57.402222 -288.693606)
		(width 0.101346)
		(layer "F.Cu")
		(net "M_A_CPU1_SB_DQ<6>")
	)
	(segment
		(start 77.767942 -277.497286)
		(end 76.383388 -277.497286)
		(width 0.0762)
		(layer "F.Cu")
		(net "M_A_CPU1_SB_DQ<6>")
	)
	(segment
		(start 56.614822 -288.693606)
		(end 56.513476 -288.59226)
		(width 0.101346)
		(layer "F.Cu")
		(net "M_A_CPU1_SB_DQ<6>")
	)
	(segment
		(start 76.383388 -277.497286)
		(end 76.285598 -277.399496)
		(width 0.0762)
		(layer "F.Cu")
		(net "M_A_CPU1_SB_DQ<6>")
	)
	(segment
		(start 71.16699 -277.399496)
		(end 62.732412 -285.834074)
		(width 0.10668)
		(layer "F.Cu")
		(net "M_A_CPU1_SB_DQ<6>")
	)
	(segment
		(start 60.725812 -287.860232)
		(end 58.221118 -287.860232)
		(width 0.101346)
		(layer "F.Cu")
		(net "M_A_CPU1_SB_DQ<6>")
	)
	(segment
		(start 58.221118 -287.860232)
		(end 57.694576 -288.386774)
		(width 0.101346)
		(layer "F.Cu")
		(net "M_A_CPU1_SB_DQ<6>")
	)
	(arc
		(start 77.954886 -277.547832)
		(mid 77.864753 -277.510212)
		(end 77.767942 -277.497286)
		(width 0.0762)
		(layer "F.Cu")
		(net "M_A_CPU1_SB_DQ<6>")
	)
	(arc
		(start 78.707996 -277.870412)
		(mid 78.465679 -277.700692)
		(end 78.180692 -277.621238)
		(width 0.0762)
		(layer "F.Cu")
		(net "M_A_CPU1_SB_DQ<6>")
	)
	(arc
		(start 78.180692 -277.621238)
		(mid 78.063879 -277.596562)
		(end 77.954886 -277.547832)
		(width 0.0762)
		(layer "F.Cu")
		(net "M_A_CPU1_SB_DQ<6>")
	)
	(segment
		(start 67.216782 -281.831288)
		(end 67.216782 -282.05176)
		(width 0.10668)
		(layer "F.Cu")
		(net "M_A_CPU1_SB_DQ<5>")
	)
	(segment
		(start 63.438024 -285.610046)
		(end 63.072772 -285.975298)
		(width 0.10668)
		(layer "F.Cu")
		(net "M_A_CPU1_SB_DQ<5>")
	)
	(segment
		(start 70.038722 -279.22982)
		(end 69.866764 -279.401778)
		(width 0.10668)
		(layer "F.Cu")
		(net "M_A_CPU1_SB_DQ<5>")
	)
	(segment
		(start 65.131188 -283.916882)
		(end 64.95923 -284.08884)
		(width 0.10668)
		(layer "F.Cu")
		(net "M_A_CPU1_SB_DQ<5>")
	)
	(segment
		(start 74.557382 -278.056086)
		(end 74.450702 -277.949406)
		(width 0.10668)
		(layer "F.Cu")
		(net "M_A_CPU1_SB_DQ<5>")
	)
	(segment
		(start 75.541124 -278.056086)
		(end 75.35545 -278.056086)
		(width 0.10668)
		(layer "F.Cu")
		(net "M_A_CPU1_SB_DQ<5>")
	)
	(segment
		(start 67.044824 -282.223718)
		(end 66.824352 -282.223718)
		(width 0.10668)
		(layer "F.Cu")
		(net "M_A_CPU1_SB_DQ<5>")
	)
	(segment
		(start 68.737988 -280.530554)
		(end 68.517516 -280.530554)
		(width 0.10668)
		(layer "F.Cu")
		(net "M_A_CPU1_SB_DQ<5>")
	)
	(segment
		(start 72.562212 -277.755096)
		(end 72.455532 -277.861776)
		(width 0.10668)
		(layer "F.Cu")
		(net "M_A_CPU1_SB_DQ<5>")
	)
	(segment
		(start 72.163178 -278.056086)
		(end 72.056498 -277.949406)
		(width 0.10668)
		(layer "F.Cu")
		(net "M_A_CPU1_SB_DQ<5>")
	)
	(segment
		(start 68.517516 -280.530554)
		(end 68.345558 -280.702512)
		(width 0.10668)
		(layer "F.Cu")
		(net "M_A_CPU1_SB_DQ<5>")
	)
	(segment
		(start 66.088006 -283.180536)
		(end 65.916048 -283.352494)
		(width 0.10668)
		(layer "F.Cu")
		(net "M_A_CPU1_SB_DQ<5>")
	)
	(segment
		(start 74.344022 -277.755096)
		(end 74.158348 -277.755096)
		(width 0.10668)
		(layer "F.Cu")
		(net "M_A_CPU1_SB_DQ<5>")
	)
	(segment
		(start 63.072772 -285.975298)
		(end 63.072772 -286.218376)
		(width 0.10668)
		(layer "F.Cu")
		(net "M_A_CPU1_SB_DQ<5>")
	)
	(segment
		(start 74.158348 -277.755096)
		(end 74.051668 -277.861776)
		(width 0.10668)
		(layer "F.Cu")
		(net "M_A_CPU1_SB_DQ<5>")
	)
	(segment
		(start 64.5668 -284.48127)
		(end 64.394842 -284.653228)
		(width 0.10668)
		(layer "F.Cu")
		(net "M_A_CPU1_SB_DQ<5>")
	)
	(segment
		(start 73.652634 -277.949406)
		(end 73.652634 -277.861776)
		(width 0.10668)
		(layer "F.Cu")
		(net "M_A_CPU1_SB_DQ<5>")
	)
	(segment
		(start 69.302376 -279.966166)
		(end 69.081904 -279.966166)
		(width 0.10668)
		(layer "F.Cu")
		(net "M_A_CPU1_SB_DQ<5>")
	)
	(segment
		(start 66.259964 -282.788106)
		(end 66.088006 -282.960064)
		(width 0.10668)
		(layer "F.Cu")
		(net "M_A_CPU1_SB_DQ<5>")
	)
	(segment
		(start 75.754484 -277.755096)
		(end 75.647804 -277.861776)
		(width 0.10668)
		(layer "F.Cu")
		(net "M_A_CPU1_SB_DQ<5>")
	)
	(segment
		(start 69.081904 -279.966166)
		(end 68.909946 -280.138124)
		(width 0.10668)
		(layer "F.Cu")
		(net "M_A_CPU1_SB_DQ<5>")
	)
	(segment
		(start 68.909946 -280.138124)
		(end 68.909946 -280.358596)
		(width 0.10668)
		(layer "F.Cu")
		(net "M_A_CPU1_SB_DQ<5>")
	)
	(segment
		(start 69.474334 -279.573736)
		(end 69.474334 -279.794208)
		(width 0.10668)
		(layer "F.Cu")
		(net "M_A_CPU1_SB_DQ<5>")
	)
	(segment
		(start 74.450702 -277.949406)
		(end 74.450702 -277.861776)
		(width 0.10668)
		(layer "F.Cu")
		(net "M_A_CPU1_SB_DQ<5>")
	)
	(segment
		(start 67.953128 -281.094942)
		(end 67.78117 -281.2669)
		(width 0.10668)
		(layer "F.Cu")
		(net "M_A_CPU1_SB_DQ<5>")
	)
	(segment
		(start 64.95923 -284.309312)
		(end 64.787272 -284.48127)
		(width 0.10668)
		(layer "F.Cu")
		(net "M_A_CPU1_SB_DQ<5>")
	)
	(segment
		(start 72.348852 -278.056086)
		(end 72.163178 -278.056086)
		(width 0.10668)
		(layer "F.Cu")
		(net "M_A_CPU1_SB_DQ<5>")
	)
	(segment
		(start 74.956416 -277.755096)
		(end 74.849736 -277.861776)
		(width 0.10668)
		(layer "F.Cu")
		(net "M_A_CPU1_SB_DQ<5>")
	)
	(segment
		(start 67.78117 -281.487372)
		(end 67.609212 -281.65933)
		(width 0.10668)
		(layer "F.Cu")
		(net "M_A_CPU1_SB_DQ<5>")
	)
	(segment
		(start 66.652394 -282.616148)
		(end 66.480436 -282.788106)
		(width 0.10668)
		(layer "F.Cu")
		(net "M_A_CPU1_SB_DQ<5>")
	)
	(segment
		(start 63.072772 -286.218376)
		(end 60.953396 -288.337752)
		(width 0.10668)
		(layer "F.Cu")
		(net "M_A_CPU1_SB_DQ<5>")
	)
	(segment
		(start 75.24877 -277.861776)
		(end 75.14209 -277.755096)
		(width 0.10668)
		(layer "F.Cu")
		(net "M_A_CPU1_SB_DQ<5>")
	)
	(segment
		(start 69.646292 -279.401778)
		(end 69.474334 -279.573736)
		(width 0.10668)
		(layer "F.Cu")
		(net "M_A_CPU1_SB_DQ<5>")
	)
	(segment
		(start 72.056498 -277.949406)
		(end 72.056498 -277.861776)
		(width 0.10668)
		(layer "F.Cu")
		(net "M_A_CPU1_SB_DQ<5>")
	)
	(segment
		(start 73.652634 -277.861776)
		(end 73.545954 -277.755096)
		(width 0.10668)
		(layer "F.Cu")
		(net "M_A_CPU1_SB_DQ<5>")
	)
	(segment
		(start 68.909946 -280.358596)
		(end 68.737988 -280.530554)
		(width 0.10668)
		(layer "F.Cu")
		(net "M_A_CPU1_SB_DQ<5>")
	)
	(segment
		(start 66.480436 -282.788106)
		(end 66.259964 -282.788106)
		(width 0.10668)
		(layer "F.Cu")
		(net "M_A_CPU1_SB_DQ<5>")
	)
	(segment
		(start 70.99554 -278.273002)
		(end 70.775068 -278.273002)
		(width 0.10668)
		(layer "F.Cu")
		(net "M_A_CPU1_SB_DQ<5>")
	)
	(segment
		(start 63.830454 -285.438088)
		(end 63.658496 -285.610046)
		(width 0.10668)
		(layer "F.Cu")
		(net "M_A_CPU1_SB_DQ<5>")
	)
	(segment
		(start 70.775068 -278.273002)
		(end 70.60311 -278.44496)
		(width 0.10668)
		(layer "F.Cu")
		(net "M_A_CPU1_SB_DQ<5>")
	)
	(segment
		(start 69.474334 -279.794208)
		(end 69.302376 -279.966166)
		(width 0.10668)
		(layer "F.Cu")
		(net "M_A_CPU1_SB_DQ<5>")
	)
	(segment
		(start 65.35166 -283.916882)
		(end 65.131188 -283.916882)
		(width 0.10668)
		(layer "F.Cu")
		(net "M_A_CPU1_SB_DQ<5>")
	)
	(segment
		(start 73.759314 -278.056086)
		(end 73.652634 -277.949406)
		(width 0.10668)
		(layer "F.Cu")
		(net "M_A_CPU1_SB_DQ<5>")
	)
	(segment
		(start 72.854566 -277.949406)
		(end 72.854566 -277.861776)
		(width 0.10668)
		(layer "F.Cu")
		(net "M_A_CPU1_SB_DQ<5>")
	)
	(segment
		(start 79.469234 -278.197818)
		(end 79.460852 -278.192992)
		(width 0.0762)
		(layer "F.Cu")
		(net "M_A_CPU1_SB_DQ<5>")
	)
	(segment
		(start 73.2536 -277.949406)
		(end 73.14692 -278.056086)
		(width 0.10668)
		(layer "F.Cu")
		(net "M_A_CPU1_SB_DQ<5>")
	)
	(segment
		(start 60.62472 -288.337752)
		(end 60.50788 -288.454592)
		(width 0.10668)
		(layer "F.Cu")
		(net "M_A_CPU1_SB_DQ<5>")
	)
	(segment
		(start 70.431152 -278.83739)
		(end 70.21068 -278.83739)
		(width 0.10668)
		(layer "F.Cu")
		(net "M_A_CPU1_SB_DQ<5>")
	)
	(segment
		(start 65.695576 -283.352494)
		(end 65.523618 -283.524452)
		(width 0.10668)
		(layer "F.Cu")
		(net "M_A_CPU1_SB_DQ<5>")
	)
	(segment
		(start 70.60311 -278.44496)
		(end 70.60311 -278.665432)
		(width 0.10668)
		(layer "F.Cu")
		(net "M_A_CPU1_SB_DQ<5>")
	)
	(segment
		(start 68.345558 -280.922984)
		(end 68.1736 -281.094942)
		(width 0.10668)
		(layer "F.Cu")
		(net "M_A_CPU1_SB_DQ<5>")
	)
	(segment
		(start 60.50788 -288.454592)
		(end 60.50788 -289.018472)
		(width 0.10668)
		(layer "F.Cu")
		(net "M_A_CPU1_SB_DQ<5>")
	)
	(segment
		(start 75.14209 -277.755096)
		(end 74.956416 -277.755096)
		(width 0.10668)
		(layer "F.Cu")
		(net "M_A_CPU1_SB_DQ<5>")
	)
	(segment
		(start 72.455532 -277.949406)
		(end 72.348852 -278.056086)
		(width 0.10668)
		(layer "F.Cu")
		(net "M_A_CPU1_SB_DQ<5>")
	)
	(segment
		(start 72.961246 -278.056086)
		(end 72.854566 -277.949406)
		(width 0.10668)
		(layer "F.Cu")
		(net "M_A_CPU1_SB_DQ<5>")
	)
	(segment
		(start 73.2536 -277.861776)
		(end 73.2536 -277.949406)
		(width 0.10668)
		(layer "F.Cu")
		(net "M_A_CPU1_SB_DQ<5>")
	)
	(segment
		(start 73.944988 -278.056086)
		(end 73.759314 -278.056086)
		(width 0.10668)
		(layer "F.Cu")
		(net "M_A_CPU1_SB_DQ<5>")
	)
	(segment
		(start 71.167498 -277.880572)
		(end 71.167498 -278.101044)
		(width 0.10668)
		(layer "F.Cu")
		(net "M_A_CPU1_SB_DQ<5>")
	)
	(segment
		(start 72.056498 -277.861776)
		(end 71.949818 -277.755096)
		(width 0.10668)
		(layer "F.Cu")
		(net "M_A_CPU1_SB_DQ<5>")
	)
	(segment
		(start 66.088006 -282.960064)
		(end 66.088006 -283.180536)
		(width 0.10668)
		(layer "F.Cu")
		(net "M_A_CPU1_SB_DQ<5>")
	)
	(segment
		(start 65.523618 -283.524452)
		(end 65.523618 -283.744924)
		(width 0.10668)
		(layer "F.Cu")
		(net "M_A_CPU1_SB_DQ<5>")
	)
	(segment
		(start 70.038722 -279.009348)
		(end 70.038722 -279.22982)
		(width 0.10668)
		(layer "F.Cu")
		(net "M_A_CPU1_SB_DQ<5>")
	)
	(segment
		(start 78.89494 -278.192992)
		(end 78.886558 -278.197818)
		(width 0.0762)
		(layer "F.Cu")
		(net "M_A_CPU1_SB_DQ<5>")
	)
	(segment
		(start 69.866764 -279.401778)
		(end 69.646292 -279.401778)
		(width 0.10668)
		(layer "F.Cu")
		(net "M_A_CPU1_SB_DQ<5>")
	)
	(segment
		(start 79.647796 -277.870412)
		(end 79.748634 -278.043894)
		(width 0.0762)
		(layer "F.Cu")
		(net "M_A_CPU1_SB_DQ<5>")
	)
	(segment
		(start 71.292974 -277.755096)
		(end 71.167498 -277.880572)
		(width 0.10668)
		(layer "F.Cu")
		(net "M_A_CPU1_SB_DQ<5>")
	)
	(segment
		(start 76.89342 -278.243538)
		(end 76.404978 -277.755096)
		(width 0.0762)
		(layer "F.Cu")
		(net "M_A_CPU1_SB_DQ<5>")
	)
	(segment
		(start 72.854566 -277.861776)
		(end 72.747886 -277.755096)
		(width 0.10668)
		(layer "F.Cu")
		(net "M_A_CPU1_SB_DQ<5>")
	)
	(segment
		(start 67.78117 -281.2669)
		(end 67.78117 -281.487372)
		(width 0.10668)
		(layer "F.Cu")
		(net "M_A_CPU1_SB_DQ<5>")
	)
	(segment
		(start 68.345558 -280.702512)
		(end 68.345558 -280.922984)
		(width 0.10668)
		(layer "F.Cu")
		(net "M_A_CPU1_SB_DQ<5>")
	)
	(segment
		(start 73.545954 -277.755096)
		(end 73.36028 -277.755096)
		(width 0.10668)
		(layer "F.Cu")
		(net "M_A_CPU1_SB_DQ<5>")
	)
	(segment
		(start 77.767942 -278.243538)
		(end 76.89342 -278.243538)
		(width 0.0762)
		(layer "F.Cu")
		(net "M_A_CPU1_SB_DQ<5>")
	)
	(segment
		(start 72.455532 -277.861776)
		(end 72.455532 -277.949406)
		(width 0.10668)
		(layer "F.Cu")
		(net "M_A_CPU1_SB_DQ<5>")
	)
	(segment
		(start 71.949818 -277.755096)
		(end 71.292974 -277.755096)
		(width 0.10668)
		(layer "F.Cu")
		(net "M_A_CPU1_SB_DQ<5>")
	)
	(segment
		(start 60.953396 -288.337752)
		(end 60.62472 -288.337752)
		(width 0.10668)
		(layer "F.Cu")
		(net "M_A_CPU1_SB_DQ<5>")
	)
	(segment
		(start 64.787272 -284.48127)
		(end 64.5668 -284.48127)
		(width 0.10668)
		(layer "F.Cu")
		(net "M_A_CPU1_SB_DQ<5>")
	)
	(segment
		(start 72.747886 -277.755096)
		(end 72.562212 -277.755096)
		(width 0.10668)
		(layer "F.Cu")
		(net "M_A_CPU1_SB_DQ<5>")
	)
	(segment
		(start 63.658496 -285.610046)
		(end 63.438024 -285.610046)
		(width 0.10668)
		(layer "F.Cu")
		(net "M_A_CPU1_SB_DQ<5>")
	)
	(segment
		(start 67.216782 -282.05176)
		(end 67.044824 -282.223718)
		(width 0.10668)
		(layer "F.Cu")
		(net "M_A_CPU1_SB_DQ<5>")
	)
	(segment
		(start 63.830454 -285.217616)
		(end 63.830454 -285.438088)
		(width 0.10668)
		(layer "F.Cu")
		(net "M_A_CPU1_SB_DQ<5>")
	)
	(segment
		(start 64.394842 -284.8737)
		(end 64.222884 -285.045658)
		(width 0.10668)
		(layer "F.Cu")
		(net "M_A_CPU1_SB_DQ<5>")
	)
	(segment
		(start 74.849736 -277.949406)
		(end 74.743056 -278.056086)
		(width 0.10668)
		(layer "F.Cu")
		(net "M_A_CPU1_SB_DQ<5>")
	)
	(segment
		(start 66.824352 -282.223718)
		(end 66.652394 -282.395676)
		(width 0.10668)
		(layer "F.Cu")
		(net "M_A_CPU1_SB_DQ<5>")
	)
	(segment
		(start 67.609212 -281.65933)
		(end 67.38874 -281.65933)
		(width 0.10668)
		(layer "F.Cu")
		(net "M_A_CPU1_SB_DQ<5>")
	)
	(segment
		(start 70.60311 -278.665432)
		(end 70.431152 -278.83739)
		(width 0.10668)
		(layer "F.Cu")
		(net "M_A_CPU1_SB_DQ<5>")
	)
	(segment
		(start 65.916048 -283.352494)
		(end 65.695576 -283.352494)
		(width 0.10668)
		(layer "F.Cu")
		(net "M_A_CPU1_SB_DQ<5>")
	)
	(segment
		(start 60.50788 -289.018472)
		(end 60.39104 -289.135312)
		(width 0.10668)
		(layer "F.Cu")
		(net "M_A_CPU1_SB_DQ<5>")
	)
	(segment
		(start 66.652394 -282.395676)
		(end 66.652394 -282.616148)
		(width 0.10668)
		(layer "F.Cu")
		(net "M_A_CPU1_SB_DQ<5>")
	)
	(segment
		(start 74.051668 -277.949406)
		(end 73.944988 -278.056086)
		(width 0.10668)
		(layer "F.Cu")
		(net "M_A_CPU1_SB_DQ<5>")
	)
	(segment
		(start 75.647804 -277.949406)
		(end 75.541124 -278.056086)
		(width 0.10668)
		(layer "F.Cu")
		(net "M_A_CPU1_SB_DQ<5>")
	)
	(segment
		(start 68.1736 -281.094942)
		(end 67.953128 -281.094942)
		(width 0.10668)
		(layer "F.Cu")
		(net "M_A_CPU1_SB_DQ<5>")
	)
	(segment
		(start 74.051668 -277.861776)
		(end 74.051668 -277.949406)
		(width 0.10668)
		(layer "F.Cu")
		(net "M_A_CPU1_SB_DQ<5>")
	)
	(segment
		(start 74.849736 -277.861776)
		(end 74.849736 -277.949406)
		(width 0.10668)
		(layer "F.Cu")
		(net "M_A_CPU1_SB_DQ<5>")
	)
	(segment
		(start 65.523618 -283.744924)
		(end 65.35166 -283.916882)
		(width 0.10668)
		(layer "F.Cu")
		(net "M_A_CPU1_SB_DQ<5>")
	)
	(segment
		(start 64.95923 -284.08884)
		(end 64.95923 -284.309312)
		(width 0.10668)
		(layer "F.Cu")
		(net "M_A_CPU1_SB_DQ<5>")
	)
	(segment
		(start 64.002412 -285.045658)
		(end 63.830454 -285.217616)
		(width 0.10668)
		(layer "F.Cu")
		(net "M_A_CPU1_SB_DQ<5>")
	)
	(segment
		(start 75.24877 -277.949406)
		(end 75.24877 -277.861776)
		(width 0.10668)
		(layer "F.Cu")
		(net "M_A_CPU1_SB_DQ<5>")
	)
	(segment
		(start 74.450702 -277.861776)
		(end 74.344022 -277.755096)
		(width 0.10668)
		(layer "F.Cu")
		(net "M_A_CPU1_SB_DQ<5>")
	)
	(segment
		(start 64.222884 -285.045658)
		(end 64.002412 -285.045658)
		(width 0.10668)
		(layer "F.Cu")
		(net "M_A_CPU1_SB_DQ<5>")
	)
	(segment
		(start 73.36028 -277.755096)
		(end 73.2536 -277.861776)
		(width 0.10668)
		(layer "F.Cu")
		(net "M_A_CPU1_SB_DQ<5>")
	)
	(segment
		(start 60.39104 -289.135312)
		(end 59.428126 -289.135312)
		(width 0.10668)
		(layer "F.Cu")
		(net "M_A_CPU1_SB_DQ<5>")
	)
	(segment
		(start 73.14692 -278.056086)
		(end 72.961246 -278.056086)
		(width 0.10668)
		(layer "F.Cu")
		(net "M_A_CPU1_SB_DQ<5>")
	)
	(segment
		(start 64.394842 -284.653228)
		(end 64.394842 -284.8737)
		(width 0.10668)
		(layer "F.Cu")
		(net "M_A_CPU1_SB_DQ<5>")
	)
	(segment
		(start 75.35545 -278.056086)
		(end 75.24877 -277.949406)
		(width 0.10668)
		(layer "F.Cu")
		(net "M_A_CPU1_SB_DQ<5>")
	)
	(segment
		(start 74.743056 -278.056086)
		(end 74.557382 -278.056086)
		(width 0.10668)
		(layer "F.Cu")
		(net "M_A_CPU1_SB_DQ<5>")
	)
	(segment
		(start 71.167498 -278.101044)
		(end 70.99554 -278.273002)
		(width 0.10668)
		(layer "F.Cu")
		(net "M_A_CPU1_SB_DQ<5>")
	)
	(segment
		(start 67.38874 -281.65933)
		(end 67.216782 -281.831288)
		(width 0.10668)
		(layer "F.Cu")
		(net "M_A_CPU1_SB_DQ<5>")
	)
	(segment
		(start 70.21068 -278.83739)
		(end 70.038722 -279.009348)
		(width 0.10668)
		(layer "F.Cu")
		(net "M_A_CPU1_SB_DQ<5>")
	)
	(segment
		(start 76.001118 -277.755096)
		(end 75.754484 -277.755096)
		(width 0.10668)
		(layer "F.Cu")
		(net "M_A_CPU1_SB_DQ<5>")
	)
	(segment
		(start 76.404978 -277.755096)
		(end 76.001118 -277.755096)
		(width 0.0762)
		(layer "F.Cu")
		(net "M_A_CPU1_SB_DQ<5>")
	)
	(segment
		(start 75.647804 -277.861776)
		(end 75.647804 -277.949406)
		(width 0.10668)
		(layer "F.Cu")
		(net "M_A_CPU1_SB_DQ<5>")
	)
	(arc
		(start 78.886558 -278.197818)
		(mid 78.70305 -278.243312)
		(end 78.520798 -278.192992)
		(width 0.0762)
		(layer "F.Cu")
		(net "M_A_CPU1_SB_DQ<5>")
	)
	(arc
		(start 77.79893 -278.242268)
		(mid 77.783449 -278.243224)
		(end 77.767942 -278.243538)
		(width 0.0762)
		(layer "F.Cu")
		(net "M_A_CPU1_SB_DQ<5>")
	)
	(arc
		(start 78.520798 -278.192992)
		(mid 78.237842 -278.116815)
		(end 77.954886 -278.192992)
		(width 0.0762)
		(layer "F.Cu")
		(net "M_A_CPU1_SB_DQ<5>")
	)
	(arc
		(start 79.748634 -278.043894)
		(mid 79.732709 -278.184586)
		(end 79.602584 -278.24049)
		(width 0.0762)
		(layer "F.Cu")
		(net "M_A_CPU1_SB_DQ<5>")
	)
	(arc
		(start 77.954886 -278.192992)
		(mid 77.879646 -278.226305)
		(end 77.79893 -278.242268)
		(width 0.0762)
		(layer "F.Cu")
		(net "M_A_CPU1_SB_DQ<5>")
	)
	(arc
		(start 79.602584 -278.24049)
		(mid 79.533886 -278.225474)
		(end 79.469234 -278.197818)
		(width 0.0762)
		(layer "F.Cu")
		(net "M_A_CPU1_SB_DQ<5>")
	)
	(arc
		(start 79.460852 -278.192992)
		(mid 79.177896 -278.116815)
		(end 78.89494 -278.192992)
		(width 0.0762)
		(layer "F.Cu")
		(net "M_A_CPU1_SB_DQ<5>")
	)
	(segment
		(start 64.515492 -283.283406)
		(end 64.364616 -283.283406)
		(width 0.10668)
		(layer "F.Cu")
		(net "M_A_CPU1_SB_DQ<4>")
	)
	(segment
		(start 78.05928 -277.387812)
		(end 78.050898 -277.382986)
		(width 0.0762)
		(layer "F.Cu")
		(net "M_A_CPU1_SB_DQ<4>")
	)
	(segment
		(start 64.018668 -283.915358)
		(end 63.951104 -283.847794)
		(width 0.10668)
		(layer "F.Cu")
		(net "M_A_CPU1_SB_DQ<4>")
	)
	(segment
		(start 67.337432 -280.461466)
		(end 67.186556 -280.461466)
		(width 0.10668)
		(layer "F.Cu")
		(net "M_A_CPU1_SB_DQ<4>")
	)
	(segment
		(start 69.31279 -278.335232)
		(end 69.312536 -278.486108)
		(width 0.10668)
		(layer "F.Cu")
		(net "M_A_CPU1_SB_DQ<4>")
	)
	(segment
		(start 68.748148 -279.050496)
		(end 68.815712 -279.11806)
		(width 0.10668)
		(layer "F.Cu")
		(net "M_A_CPU1_SB_DQ<4>")
	)
	(segment
		(start 70.226936 -277.70709)
		(end 70.159372 -277.639526)
		(width 0.10668)
		(layer "F.Cu")
		(net "M_A_CPU1_SB_DQ<4>")
	)
	(segment
		(start 62.822328 -284.97657)
		(end 62.671452 -284.97657)
		(width 0.10668)
		(layer "F.Cu")
		(net "M_A_CPU1_SB_DQ<4>")
	)
	(segment
		(start 63.800228 -283.847794)
		(end 63.66891 -283.979112)
		(width 0.10668)
		(layer "F.Cu")
		(net "M_A_CPU1_SB_DQ<4>")
	)
	(segment
		(start 67.555364 -280.529284)
		(end 67.404996 -280.52903)
		(width 0.10668)
		(layer "F.Cu")
		(net "M_A_CPU1_SB_DQ<4>")
	)
	(segment
		(start 68.251324 -279.833324)
		(end 68.119752 -279.964896)
		(width 0.10668)
		(layer "F.Cu")
		(net "M_A_CPU1_SB_DQ<4>")
	)
	(segment
		(start 70.159372 -277.639526)
		(end 70.008496 -277.639526)
		(width 0.10668)
		(layer "F.Cu")
		(net "M_A_CPU1_SB_DQ<4>")
	)
	(segment
		(start 66.55816 -281.375612)
		(end 66.55816 -281.526488)
		(width 0.10668)
		(layer "F.Cu")
		(net "M_A_CPU1_SB_DQ<4>")
	)
	(segment
		(start 63.171832 -284.912816)
		(end 63.04026 -285.044388)
		(width 0.10668)
		(layer "F.Cu")
		(net "M_A_CPU1_SB_DQ<4>")
	)
	(segment
		(start 63.104268 -284.694376)
		(end 63.171832 -284.76194)
		(width 0.10668)
		(layer "F.Cu")
		(net "M_A_CPU1_SB_DQ<4>")
	)
	(segment
		(start 63.386716 -284.412182)
		(end 63.23584 -284.412182)
		(width 0.10668)
		(layer "F.Cu")
		(net "M_A_CPU1_SB_DQ<4>")
	)
	(segment
		(start 64.797686 -282.850336)
		(end 64.797432 -283.001212)
		(width 0.10668)
		(layer "F.Cu")
		(net "M_A_CPU1_SB_DQ<4>")
	)
	(segment
		(start 69.877178 -277.770844)
		(end 69.876924 -277.92172)
		(width 0.10668)
		(layer "F.Cu")
		(net "M_A_CPU1_SB_DQ<4>")
	)
	(segment
		(start 70.441312 -277.357332)
		(end 70.508876 -277.424896)
		(width 0.10668)
		(layer "F.Cu")
		(net "M_A_CPU1_SB_DQ<4>")
	)
	(segment
		(start 65.644268 -282.15463)
		(end 65.493392 -282.15463)
		(width 0.10668)
		(layer "F.Cu")
		(net "M_A_CPU1_SB_DQ<4>")
	)
	(segment
		(start 70.008496 -277.639526)
		(end 69.877178 -277.770844)
		(width 0.10668)
		(layer "F.Cu")
		(net "M_A_CPU1_SB_DQ<4>")
	)
	(segment
		(start 64.233044 -283.5656)
		(end 64.300608 -283.633164)
		(width 0.10668)
		(layer "F.Cu")
		(net "M_A_CPU1_SB_DQ<4>")
	)
	(segment
		(start 66.55816 -281.526488)
		(end 66.426588 -281.65806)
		(width 0.10668)
		(layer "F.Cu")
		(net "M_A_CPU1_SB_DQ<4>")
	)
	(segment
		(start 68.119752 -279.964896)
		(end 67.969384 -279.964642)
		(width 0.10668)
		(layer "F.Cu")
		(net "M_A_CPU1_SB_DQ<4>")
	)
	(segment
		(start 68.466208 -279.33269)
		(end 68.315332 -279.33269)
		(width 0.10668)
		(layer "F.Cu")
		(net "M_A_CPU1_SB_DQ<4>")
	)
	(segment
		(start 64.169036 -283.915612)
		(end 64.018668 -283.915358)
		(width 0.10668)
		(layer "F.Cu")
		(net "M_A_CPU1_SB_DQ<4>")
	)
	(segment
		(start 68.815712 -279.268936)
		(end 68.68414 -279.400508)
		(width 0.10668)
		(layer "F.Cu")
		(net "M_A_CPU1_SB_DQ<4>")
	)
	(segment
		(start 78.237842 -277.060406)
		(end 78.33614 -277.22957)
		(width 0.0762)
		(layer "F.Cu")
		(net "M_A_CPU1_SB_DQ<4>")
	)
	(segment
		(start 68.251324 -279.682448)
		(end 68.251324 -279.833324)
		(width 0.10668)
		(layer "F.Cu")
		(net "M_A_CPU1_SB_DQ<4>")
	)
	(segment
		(start 67.90182 -279.897078)
		(end 67.750944 -279.897078)
		(width 0.10668)
		(layer "F.Cu")
		(net "M_A_CPU1_SB_DQ<4>")
	)
	(segment
		(start 65.07988 -282.719018)
		(end 64.929004 -282.719018)
		(width 0.10668)
		(layer "F.Cu")
		(net "M_A_CPU1_SB_DQ<4>")
	)
	(segment
		(start 70.508876 -277.575772)
		(end 70.377304 -277.707344)
		(width 0.10668)
		(layer "F.Cu")
		(net "M_A_CPU1_SB_DQ<4>")
	)
	(segment
		(start 69.248528 -278.83612)
		(end 69.09816 -278.835866)
		(width 0.10668)
		(layer "F.Cu")
		(net "M_A_CPU1_SB_DQ<4>")
	)
	(segment
		(start 66.27622 -281.657806)
		(end 66.208656 -281.590242)
		(width 0.10668)
		(layer "F.Cu")
		(net "M_A_CPU1_SB_DQ<4>")
	)
	(segment
		(start 70.596252 -277.05177)
		(end 70.441566 -277.206456)
		(width 0.10668)
		(layer "F.Cu")
		(net "M_A_CPU1_SB_DQ<4>")
	)
	(segment
		(start 67.686936 -280.397712)
		(end 67.555364 -280.529284)
		(width 0.10668)
		(layer "F.Cu")
		(net "M_A_CPU1_SB_DQ<4>")
	)
	(segment
		(start 63.73622 -284.348428)
		(end 63.604648 -284.48)
		(width 0.10668)
		(layer "F.Cu")
		(net "M_A_CPU1_SB_DQ<4>")
	)
	(segment
		(start 67.404996 -280.52903)
		(end 67.337432 -280.461466)
		(width 0.10668)
		(layer "F.Cu")
		(net "M_A_CPU1_SB_DQ<4>")
	)
	(segment
		(start 68.184014 -279.464008)
		(end 68.18376 -279.614884)
		(width 0.10668)
		(layer "F.Cu")
		(net "M_A_CPU1_SB_DQ<4>")
	)
	(segment
		(start 66.773044 -281.025854)
		(end 66.622168 -281.025854)
		(width 0.10668)
		(layer "F.Cu")
		(net "M_A_CPU1_SB_DQ<4>")
	)
	(segment
		(start 67.619626 -280.028396)
		(end 67.619372 -280.179272)
		(width 0.10668)
		(layer "F.Cu")
		(net "M_A_CPU1_SB_DQ<4>")
	)
	(segment
		(start 65.926208 -281.872436)
		(end 65.993772 -281.94)
		(width 0.10668)
		(layer "F.Cu")
		(net "M_A_CPU1_SB_DQ<4>")
	)
	(segment
		(start 76.502514 -277.05177)
		(end 70.596252 -277.05177)
		(width 0.10668)
		(layer "F.Cu")
		(net "M_A_CPU1_SB_DQ<4>")
	)
	(segment
		(start 62.671452 -284.97657)
		(end 62.392052 -285.25597)
		(width 0.10668)
		(layer "F.Cu")
		(net "M_A_CPU1_SB_DQ<4>")
	)
	(segment
		(start 65.926462 -281.72156)
		(end 65.926208 -281.872436)
		(width 0.10668)
		(layer "F.Cu")
		(net "M_A_CPU1_SB_DQ<4>")
	)
	(segment
		(start 69.944488 -277.989284)
		(end 69.944488 -278.14016)
		(width 0.10668)
		(layer "F.Cu")
		(net "M_A_CPU1_SB_DQ<4>")
	)
	(segment
		(start 63.604648 -284.48)
		(end 63.45428 -284.479746)
		(width 0.10668)
		(layer "F.Cu")
		(net "M_A_CPU1_SB_DQ<4>")
	)
	(segment
		(start 65.993772 -282.090876)
		(end 65.8622 -282.222448)
		(width 0.10668)
		(layer "F.Cu")
		(net "M_A_CPU1_SB_DQ<4>")
	)
	(segment
		(start 63.23584 -284.412182)
		(end 63.104522 -284.5435)
		(width 0.10668)
		(layer "F.Cu")
		(net "M_A_CPU1_SB_DQ<4>")
	)
	(segment
		(start 69.030596 -278.768302)
		(end 68.87972 -278.768302)
		(width 0.10668)
		(layer "F.Cu")
		(net "M_A_CPU1_SB_DQ<4>")
	)
	(segment
		(start 64.864996 -283.219652)
		(end 64.733424 -283.351224)
		(width 0.10668)
		(layer "F.Cu")
		(net "M_A_CPU1_SB_DQ<4>")
	)
	(segment
		(start 69.594984 -278.203914)
		(end 69.444108 -278.203914)
		(width 0.10668)
		(layer "F.Cu")
		(net "M_A_CPU1_SB_DQ<4>")
	)
	(segment
		(start 67.186556 -280.461466)
		(end 67.055238 -280.592784)
		(width 0.10668)
		(layer "F.Cu")
		(net "M_A_CPU1_SB_DQ<4>")
	)
	(segment
		(start 66.840608 -281.093418)
		(end 66.773044 -281.025854)
		(width 0.10668)
		(layer "F.Cu")
		(net "M_A_CPU1_SB_DQ<4>")
	)
	(segment
		(start 68.533772 -279.400254)
		(end 68.466208 -279.33269)
		(width 0.10668)
		(layer "F.Cu")
		(net "M_A_CPU1_SB_DQ<4>")
	)
	(segment
		(start 64.233298 -283.414724)
		(end 64.233044 -283.5656)
		(width 0.10668)
		(layer "F.Cu")
		(net "M_A_CPU1_SB_DQ<4>")
	)
	(segment
		(start 64.733424 -283.351224)
		(end 64.583056 -283.35097)
		(width 0.10668)
		(layer "F.Cu")
		(net "M_A_CPU1_SB_DQ<4>")
	)
	(segment
		(start 64.929004 -282.719018)
		(end 64.797686 -282.850336)
		(width 0.10668)
		(layer "F.Cu")
		(net "M_A_CPU1_SB_DQ<4>")
	)
	(segment
		(start 69.3801 -278.553672)
		(end 69.3801 -278.704548)
		(width 0.10668)
		(layer "F.Cu")
		(net "M_A_CPU1_SB_DQ<4>")
	)
	(segment
		(start 63.66891 -283.979112)
		(end 63.668656 -284.129988)
		(width 0.10668)
		(layer "F.Cu")
		(net "M_A_CPU1_SB_DQ<4>")
	)
	(segment
		(start 69.812916 -278.271732)
		(end 69.662548 -278.271478)
		(width 0.10668)
		(layer "F.Cu")
		(net "M_A_CPU1_SB_DQ<4>")
	)
	(segment
		(start 69.09816 -278.835866)
		(end 69.030596 -278.768302)
		(width 0.10668)
		(layer "F.Cu")
		(net "M_A_CPU1_SB_DQ<4>")
	)
	(segment
		(start 67.054984 -280.74366)
		(end 67.122548 -280.811224)
		(width 0.10668)
		(layer "F.Cu")
		(net "M_A_CPU1_SB_DQ<4>")
	)
	(segment
		(start 64.364616 -283.283406)
		(end 64.233298 -283.414724)
		(width 0.10668)
		(layer "F.Cu")
		(net "M_A_CPU1_SB_DQ<4>")
	)
	(segment
		(start 63.45428 -284.479746)
		(end 63.386716 -284.412182)
		(width 0.10668)
		(layer "F.Cu")
		(net "M_A_CPU1_SB_DQ<4>")
	)
	(segment
		(start 70.377304 -277.707344)
		(end 70.226936 -277.70709)
		(width 0.10668)
		(layer "F.Cu")
		(net "M_A_CPU1_SB_DQ<4>")
	)
	(segment
		(start 64.864996 -283.068776)
		(end 64.864996 -283.219652)
		(width 0.10668)
		(layer "F.Cu")
		(net "M_A_CPU1_SB_DQ<4>")
	)
	(segment
		(start 66.490596 -281.308048)
		(end 66.55816 -281.375612)
		(width 0.10668)
		(layer "F.Cu")
		(net "M_A_CPU1_SB_DQ<4>")
	)
	(segment
		(start 67.686936 -280.246836)
		(end 67.686936 -280.397712)
		(width 0.10668)
		(layer "F.Cu")
		(net "M_A_CPU1_SB_DQ<4>")
	)
	(segment
		(start 63.951104 -283.847794)
		(end 63.800228 -283.847794)
		(width 0.10668)
		(layer "F.Cu")
		(net "M_A_CPU1_SB_DQ<4>")
	)
	(segment
		(start 76.863956 -277.306786)
		(end 76.60894 -277.05177)
		(width 0.0762)
		(layer "F.Cu")
		(net "M_A_CPU1_SB_DQ<4>")
	)
	(segment
		(start 66.208656 -281.590242)
		(end 66.05778 -281.590242)
		(width 0.10668)
		(layer "F.Cu")
		(net "M_A_CPU1_SB_DQ<4>")
	)
	(segment
		(start 60.892436 -287.43529)
		(end 59.428126 -287.43529)
		(width 0.10668)
		(layer "F.Cu")
		(net "M_A_CPU1_SB_DQ<4>")
	)
	(segment
		(start 68.748402 -278.89962)
		(end 68.748148 -279.050496)
		(width 0.10668)
		(layer "F.Cu")
		(net "M_A_CPU1_SB_DQ<4>")
	)
	(segment
		(start 67.750944 -279.897078)
		(end 67.619626 -280.028396)
		(width 0.10668)
		(layer "F.Cu")
		(net "M_A_CPU1_SB_DQ<4>")
	)
	(segment
		(start 67.619372 -280.179272)
		(end 67.686936 -280.246836)
		(width 0.10668)
		(layer "F.Cu")
		(net "M_A_CPU1_SB_DQ<4>")
	)
	(segment
		(start 77.767942 -277.306786)
		(end 76.863956 -277.306786)
		(width 0.0762)
		(layer "F.Cu")
		(net "M_A_CPU1_SB_DQ<4>")
	)
	(segment
		(start 66.05778 -281.590242)
		(end 65.926462 -281.72156)
		(width 0.10668)
		(layer "F.Cu")
		(net "M_A_CPU1_SB_DQ<4>")
	)
	(segment
		(start 69.444108 -278.203914)
		(end 69.31279 -278.335232)
		(width 0.10668)
		(layer "F.Cu")
		(net "M_A_CPU1_SB_DQ<4>")
	)
	(segment
		(start 63.104522 -284.5435)
		(end 63.104268 -284.694376)
		(width 0.10668)
		(layer "F.Cu")
		(net "M_A_CPU1_SB_DQ<4>")
	)
	(segment
		(start 67.122548 -280.9621)
		(end 66.990976 -281.093672)
		(width 0.10668)
		(layer "F.Cu")
		(net "M_A_CPU1_SB_DQ<4>")
	)
	(segment
		(start 66.49085 -281.157172)
		(end 66.490596 -281.308048)
		(width 0.10668)
		(layer "F.Cu")
		(net "M_A_CPU1_SB_DQ<4>")
	)
	(segment
		(start 64.300608 -283.633164)
		(end 64.300608 -283.78404)
		(width 0.10668)
		(layer "F.Cu")
		(net "M_A_CPU1_SB_DQ<4>")
	)
	(segment
		(start 69.3801 -278.704548)
		(end 69.248528 -278.83612)
		(width 0.10668)
		(layer "F.Cu")
		(net "M_A_CPU1_SB_DQ<4>")
	)
	(segment
		(start 62.889892 -285.044134)
		(end 62.822328 -284.97657)
		(width 0.10668)
		(layer "F.Cu")
		(net "M_A_CPU1_SB_DQ<4>")
	)
	(segment
		(start 70.441566 -277.206456)
		(end 70.441312 -277.357332)
		(width 0.10668)
		(layer "F.Cu")
		(net "M_A_CPU1_SB_DQ<4>")
	)
	(segment
		(start 65.36182 -282.436824)
		(end 65.429384 -282.504388)
		(width 0.10668)
		(layer "F.Cu")
		(net "M_A_CPU1_SB_DQ<4>")
	)
	(segment
		(start 63.171832 -284.76194)
		(end 63.171832 -284.912816)
		(width 0.10668)
		(layer "F.Cu")
		(net "M_A_CPU1_SB_DQ<4>")
	)
	(segment
		(start 65.362074 -282.285948)
		(end 65.36182 -282.436824)
		(width 0.10668)
		(layer "F.Cu")
		(net "M_A_CPU1_SB_DQ<4>")
	)
	(segment
		(start 67.122548 -280.811224)
		(end 67.122548 -280.9621)
		(width 0.10668)
		(layer "F.Cu")
		(net "M_A_CPU1_SB_DQ<4>")
	)
	(segment
		(start 76.60894 -277.05177)
		(end 76.502514 -277.05177)
		(width 0.0762)
		(layer "F.Cu")
		(net "M_A_CPU1_SB_DQ<4>")
	)
	(segment
		(start 67.055238 -280.592784)
		(end 67.054984 -280.74366)
		(width 0.10668)
		(layer "F.Cu")
		(net "M_A_CPU1_SB_DQ<4>")
	)
	(segment
		(start 69.944488 -278.14016)
		(end 69.812916 -278.271732)
		(width 0.10668)
		(layer "F.Cu")
		(net "M_A_CPU1_SB_DQ<4>")
	)
	(segment
		(start 64.300608 -283.78404)
		(end 64.169036 -283.915612)
		(width 0.10668)
		(layer "F.Cu")
		(net "M_A_CPU1_SB_DQ<4>")
	)
	(segment
		(start 65.429384 -282.504388)
		(end 65.429384 -282.655264)
		(width 0.10668)
		(layer "F.Cu")
		(net "M_A_CPU1_SB_DQ<4>")
	)
	(segment
		(start 69.312536 -278.486108)
		(end 69.3801 -278.553672)
		(width 0.10668)
		(layer "F.Cu")
		(net "M_A_CPU1_SB_DQ<4>")
	)
	(segment
		(start 69.876924 -277.92172)
		(end 69.944488 -277.989284)
		(width 0.10668)
		(layer "F.Cu")
		(net "M_A_CPU1_SB_DQ<4>")
	)
	(segment
		(start 68.87972 -278.768302)
		(end 68.748402 -278.89962)
		(width 0.10668)
		(layer "F.Cu")
		(net "M_A_CPU1_SB_DQ<4>")
	)
	(segment
		(start 65.711832 -282.222194)
		(end 65.644268 -282.15463)
		(width 0.10668)
		(layer "F.Cu")
		(net "M_A_CPU1_SB_DQ<4>")
	)
	(segment
		(start 64.797432 -283.001212)
		(end 64.864996 -283.068776)
		(width 0.10668)
		(layer "F.Cu")
		(net "M_A_CPU1_SB_DQ<4>")
	)
	(segment
		(start 68.18376 -279.614884)
		(end 68.251324 -279.682448)
		(width 0.10668)
		(layer "F.Cu")
		(net "M_A_CPU1_SB_DQ<4>")
	)
	(segment
		(start 68.815712 -279.11806)
		(end 68.815712 -279.268936)
		(width 0.10668)
		(layer "F.Cu")
		(net "M_A_CPU1_SB_DQ<4>")
	)
	(segment
		(start 65.8622 -282.222448)
		(end 65.711832 -282.222194)
		(width 0.10668)
		(layer "F.Cu")
		(net "M_A_CPU1_SB_DQ<4>")
	)
	(segment
		(start 68.315332 -279.33269)
		(end 68.184014 -279.464008)
		(width 0.10668)
		(layer "F.Cu")
		(net "M_A_CPU1_SB_DQ<4>")
	)
	(segment
		(start 63.73622 -284.197552)
		(end 63.73622 -284.348428)
		(width 0.10668)
		(layer "F.Cu")
		(net "M_A_CPU1_SB_DQ<4>")
	)
	(segment
		(start 65.429384 -282.655264)
		(end 65.297812 -282.786836)
		(width 0.10668)
		(layer "F.Cu")
		(net "M_A_CPU1_SB_DQ<4>")
	)
	(segment
		(start 65.993772 -281.94)
		(end 65.993772 -282.090876)
		(width 0.10668)
		(layer "F.Cu")
		(net "M_A_CPU1_SB_DQ<4>")
	)
	(segment
		(start 66.622168 -281.025854)
		(end 66.49085 -281.157172)
		(width 0.10668)
		(layer "F.Cu")
		(net "M_A_CPU1_SB_DQ<4>")
	)
	(segment
		(start 65.297812 -282.786836)
		(end 65.147444 -282.786582)
		(width 0.10668)
		(layer "F.Cu")
		(net "M_A_CPU1_SB_DQ<4>")
	)
	(segment
		(start 67.969384 -279.964642)
		(end 67.90182 -279.897078)
		(width 0.10668)
		(layer "F.Cu")
		(net "M_A_CPU1_SB_DQ<4>")
	)
	(segment
		(start 65.147444 -282.786582)
		(end 65.07988 -282.719018)
		(width 0.10668)
		(layer "F.Cu")
		(net "M_A_CPU1_SB_DQ<4>")
	)
	(segment
		(start 62.392052 -285.935674)
		(end 60.892436 -287.43529)
		(width 0.10668)
		(layer "F.Cu")
		(net "M_A_CPU1_SB_DQ<4>")
	)
	(segment
		(start 62.392052 -285.25597)
		(end 62.392052 -285.935674)
		(width 0.10668)
		(layer "F.Cu")
		(net "M_A_CPU1_SB_DQ<4>")
	)
	(segment
		(start 70.508876 -277.424896)
		(end 70.508876 -277.575772)
		(width 0.10668)
		(layer "F.Cu")
		(net "M_A_CPU1_SB_DQ<4>")
	)
	(segment
		(start 68.68414 -279.400508)
		(end 68.533772 -279.400254)
		(width 0.10668)
		(layer "F.Cu")
		(net "M_A_CPU1_SB_DQ<4>")
	)
	(segment
		(start 63.04026 -285.044388)
		(end 62.889892 -285.044134)
		(width 0.10668)
		(layer "F.Cu")
		(net "M_A_CPU1_SB_DQ<4>")
	)
	(segment
		(start 65.493392 -282.15463)
		(end 65.362074 -282.285948)
		(width 0.10668)
		(layer "F.Cu")
		(net "M_A_CPU1_SB_DQ<4>")
	)
	(segment
		(start 66.426588 -281.65806)
		(end 66.27622 -281.657806)
		(width 0.10668)
		(layer "F.Cu")
		(net "M_A_CPU1_SB_DQ<4>")
	)
	(segment
		(start 69.662548 -278.271478)
		(end 69.594984 -278.203914)
		(width 0.10668)
		(layer "F.Cu")
		(net "M_A_CPU1_SB_DQ<4>")
	)
	(segment
		(start 63.668656 -284.129988)
		(end 63.73622 -284.197552)
		(width 0.10668)
		(layer "F.Cu")
		(net "M_A_CPU1_SB_DQ<4>")
	)
	(segment
		(start 64.583056 -283.35097)
		(end 64.515492 -283.283406)
		(width 0.10668)
		(layer "F.Cu")
		(net "M_A_CPU1_SB_DQ<4>")
	)
	(segment
		(start 66.990976 -281.093672)
		(end 66.840608 -281.093418)
		(width 0.10668)
		(layer "F.Cu")
		(net "M_A_CPU1_SB_DQ<4>")
	)
	(arc
		(start 78.33614 -277.22957)
		(mid 78.327547 -277.371449)
		(end 78.198472 -277.431246)
		(width 0.0762)
		(layer "F.Cu")
		(net "M_A_CPU1_SB_DQ<4>")
	)
	(arc
		(start 78.050898 -277.382986)
		(mid 77.914462 -277.326161)
		(end 77.767942 -277.306786)
		(width 0.0762)
		(layer "F.Cu")
		(net "M_A_CPU1_SB_DQ<4>")
	)
	(arc
		(start 78.198472 -277.431246)
		(mid 78.126734 -277.416394)
		(end 78.05928 -277.387812)
		(width 0.0762)
		(layer "F.Cu")
		(net "M_A_CPU1_SB_DQ<4>")
	)
	(segment
		(start 61.244734 -282.74899)
		(end 61.104272 -282.608528)
		(width 0.10668)
		(layer "F.Cu")
		(net "M_A_CPU1_SB_DQ<3>")
	)
	(segment
		(start 60.953396 -282.608528)
		(end 60.821824 -282.7401)
		(width 0.10668)
		(layer "F.Cu")
		(net "M_A_CPU1_SB_DQ<3>")
	)
	(segment
		(start 60.96254 -283.181806)
		(end 60.714128 -283.430218)
		(width 0.10668)
		(layer "F.Cu")
		(net "M_A_CPU1_SB_DQ<3>")
	)
	(segment
		(start 77.768196 -275.194014)
		(end 76.688188 -275.194014)
		(width 0.0762)
		(layer "F.Cu")
		(net "M_A_CPU1_SB_DQ<3>")
	)
	(segment
		(start 56.556148 -283.9339)
		(end 56.454802 -284.035246)
		(width 0.101346)
		(layer "F.Cu")
		(net "M_A_CPU1_SB_DQ<3>")
	)
	(segment
		(start 57.372504 -284.035246)
		(end 57.051194 -284.035246)
		(width 0.101346)
		(layer "F.Cu")
		(net "M_A_CPU1_SB_DQ<3>")
	)
	(segment
		(start 69.253862 -274.890484)
		(end 61.39561 -282.748736)
		(width 0.10668)
		(layer "F.Cu")
		(net "M_A_CPU1_SB_DQ<3>")
	)
	(segment
		(start 56.949848 -283.811472)
		(end 56.848502 -283.710126)
		(width 0.101346)
		(layer "F.Cu")
		(net "M_A_CPU1_SB_DQ<3>")
	)
	(segment
		(start 61.39561 -282.748736)
		(end 61.244734 -282.74899)
		(width 0.10668)
		(layer "F.Cu")
		(net "M_A_CPU1_SB_DQ<3>")
	)
	(segment
		(start 78.05928 -275.112988)
		(end 78.050898 -275.117814)
		(width 0.0762)
		(layer "F.Cu")
		(net "M_A_CPU1_SB_DQ<3>")
	)
	(segment
		(start 60.96254 -283.03093)
		(end 60.96254 -283.181806)
		(width 0.10668)
		(layer "F.Cu")
		(net "M_A_CPU1_SB_DQ<3>")
	)
	(segment
		(start 57.051194 -284.035246)
		(end 56.949848 -283.9339)
		(width 0.101346)
		(layer "F.Cu")
		(net "M_A_CPU1_SB_DQ<3>")
	)
	(segment
		(start 56.657494 -283.710126)
		(end 56.556148 -283.811472)
		(width 0.101346)
		(layer "F.Cu")
		(net "M_A_CPU1_SB_DQ<3>")
	)
	(segment
		(start 60.821824 -282.7401)
		(end 60.822078 -282.890468)
		(width 0.10668)
		(layer "F.Cu")
		(net "M_A_CPU1_SB_DQ<3>")
	)
	(segment
		(start 61.104272 -282.608528)
		(end 60.953396 -282.608528)
		(width 0.10668)
		(layer "F.Cu")
		(net "M_A_CPU1_SB_DQ<3>")
	)
	(segment
		(start 76.688188 -275.194014)
		(end 76.384658 -274.890484)
		(width 0.0762)
		(layer "F.Cu")
		(net "M_A_CPU1_SB_DQ<3>")
	)
	(segment
		(start 76.384658 -274.890484)
		(end 69.253862 -274.890484)
		(width 0.10668)
		(layer "F.Cu")
		(net "M_A_CPU1_SB_DQ<3>")
	)
	(segment
		(start 60.534042 -283.610304)
		(end 57.797446 -283.610304)
		(width 0.101346)
		(layer "F.Cu")
		(net "M_A_CPU1_SB_DQ<3>")
	)
	(segment
		(start 56.454802 -284.035246)
		(end 55.328058 -284.035246)
		(width 0.101346)
		(layer "F.Cu")
		(net "M_A_CPU1_SB_DQ<3>")
	)
	(segment
		(start 60.714128 -283.430218)
		(end 60.534042 -283.610304)
		(width 0.101346)
		(layer "F.Cu")
		(net "M_A_CPU1_SB_DQ<3>")
	)
	(segment
		(start 57.797446 -283.610304)
		(end 57.372504 -284.035246)
		(width 0.101346)
		(layer "F.Cu")
		(net "M_A_CPU1_SB_DQ<3>")
	)
	(segment
		(start 60.822078 -282.890468)
		(end 60.96254 -283.03093)
		(width 0.10668)
		(layer "F.Cu")
		(net "M_A_CPU1_SB_DQ<3>")
	)
	(segment
		(start 56.556148 -283.811472)
		(end 56.556148 -283.9339)
		(width 0.101346)
		(layer "F.Cu")
		(net "M_A_CPU1_SB_DQ<3>")
	)
	(segment
		(start 56.848502 -283.710126)
		(end 56.657494 -283.710126)
		(width 0.101346)
		(layer "F.Cu")
		(net "M_A_CPU1_SB_DQ<3>")
	)
	(segment
		(start 56.949848 -283.9339)
		(end 56.949848 -283.811472)
		(width 0.101346)
		(layer "F.Cu")
		(net "M_A_CPU1_SB_DQ<3>")
	)
	(arc
		(start 80.11795 -275.440394)
		(mid 79.880338 -275.269406)
		(end 79.598012 -275.191982)
		(width 0.0762)
		(layer "F.Cu")
		(net "M_A_CPU1_SB_DQ<3>")
	)
	(arc
		(start 78.990952 -275.117814)
		(mid 78.707996 -275.193991)
		(end 78.42504 -275.117814)
		(width 0.0762)
		(layer "F.Cu")
		(net "M_A_CPU1_SB_DQ<3>")
	)
	(arc
		(start 77.815186 -275.192236)
		(mid 77.791709 -275.193612)
		(end 77.768196 -275.194014)
		(width 0.0762)
		(layer "F.Cu")
		(net "M_A_CPU1_SB_DQ<3>")
	)
	(arc
		(start 78.42504 -275.117814)
		(mid 78.242789 -275.067464)
		(end 78.05928 -275.112988)
		(width 0.0762)
		(layer "F.Cu")
		(net "M_A_CPU1_SB_DQ<3>")
	)
	(arc
		(start 79.36484 -275.117814)
		(mid 79.177896 -275.067559)
		(end 78.990952 -275.117814)
		(width 0.0762)
		(layer "F.Cu")
		(net "M_A_CPU1_SB_DQ<3>")
	)
	(arc
		(start 78.050898 -275.117814)
		(mid 77.937174 -275.168115)
		(end 77.815186 -275.192236)
		(width 0.0762)
		(layer "F.Cu")
		(net "M_A_CPU1_SB_DQ<3>")
	)
	(arc
		(start 79.598012 -275.191982)
		(mid 79.477363 -275.167681)
		(end 79.36484 -275.117814)
		(width 0.0762)
		(layer "F.Cu")
		(net "M_A_CPU1_SB_DQ<3>")
	)
	(segment
		(start 68.339462 -309.893208)
		(end 68.339462 -310.058308)
		(width 0.10668)
		(layer "F.Cu")
		(net "M_A_CPU1_SB_DQ<31>")
	)
	(segment
		(start 76.32954 -301.748952)
		(end 75.794362 -303.041304)
		(width 0.10668)
		(layer "F.Cu")
		(net "M_A_CPU1_SB_DQ<31>")
	)
	(segment
		(start 57.774078 -318.035432)
		(end 55.328058 -318.035432)
		(width 0.101346)
		(layer "F.Cu")
		(net "M_A_CPU1_SB_DQ<31>")
	)
	(segment
		(start 78.237842 -293.260272)
		(end 76.890626 -293.260272)
		(width 0.0762)
		(layer "F.Cu")
		(net "M_A_CPU1_SB_DQ<31>")
	)
	(segment
		(start 69.750432 -308.647338)
		(end 69.585332 -308.647338)
		(width 0.10668)
		(layer "F.Cu")
		(net "M_A_CPU1_SB_DQ<31>")
	)
	(segment
		(start 68.90385 -309.32882)
		(end 68.90385 -309.49392)
		(width 0.10668)
		(layer "F.Cu")
		(net "M_A_CPU1_SB_DQ<31>")
	)
	(segment
		(start 69.468238 -308.764432)
		(end 69.468238 -308.929532)
		(width 0.10668)
		(layer "F.Cu")
		(net "M_A_CPU1_SB_DQ<31>")
	)
	(segment
		(start 69.186044 -309.211726)
		(end 69.020944 -309.211726)
		(width 0.10668)
		(layer "F.Cu")
		(net "M_A_CPU1_SB_DQ<31>")
	)
	(segment
		(start 58.199274 -317.610236)
		(end 57.774078 -318.035432)
		(width 0.101346)
		(layer "F.Cu")
		(net "M_A_CPU1_SB_DQ<31>")
	)
	(segment
		(start 68.47586 -310.359806)
		(end 61.22543 -317.610236)
		(width 0.10668)
		(layer "F.Cu")
		(net "M_A_CPU1_SB_DQ<31>")
	)
	(segment
		(start 69.020944 -309.211726)
		(end 68.90385 -309.32882)
		(width 0.10668)
		(layer "F.Cu")
		(net "M_A_CPU1_SB_DQ<31>")
	)
	(segment
		(start 68.90385 -309.49392)
		(end 69.040248 -309.630318)
		(width 0.10668)
		(layer "F.Cu")
		(net "M_A_CPU1_SB_DQ<31>")
	)
	(segment
		(start 69.040248 -309.795418)
		(end 68.923154 -309.912512)
		(width 0.10668)
		(layer "F.Cu")
		(net "M_A_CPU1_SB_DQ<31>")
	)
	(segment
		(start 69.604636 -309.06593)
		(end 69.604636 -309.23103)
		(width 0.10668)
		(layer "F.Cu")
		(net "M_A_CPU1_SB_DQ<31>")
	)
	(segment
		(start 68.47586 -310.194706)
		(end 68.47586 -310.359806)
		(width 0.10668)
		(layer "F.Cu")
		(net "M_A_CPU1_SB_DQ<31>")
	)
	(segment
		(start 69.88683 -308.783736)
		(end 69.750432 -308.647338)
		(width 0.10668)
		(layer "F.Cu")
		(net "M_A_CPU1_SB_DQ<31>")
	)
	(segment
		(start 69.040248 -309.630318)
		(end 69.040248 -309.795418)
		(width 0.10668)
		(layer "F.Cu")
		(net "M_A_CPU1_SB_DQ<31>")
	)
	(segment
		(start 68.456556 -309.776114)
		(end 68.339462 -309.893208)
		(width 0.10668)
		(layer "F.Cu")
		(net "M_A_CPU1_SB_DQ<31>")
	)
	(segment
		(start 69.585332 -308.647338)
		(end 69.468238 -308.764432)
		(width 0.10668)
		(layer "F.Cu")
		(net "M_A_CPU1_SB_DQ<31>")
	)
	(segment
		(start 76.672186 -293.478712)
		(end 76.672186 -300.921928)
		(width 0.10668)
		(layer "F.Cu")
		(net "M_A_CPU1_SB_DQ<31>")
	)
	(segment
		(start 70.05193 -308.783736)
		(end 69.88683 -308.783736)
		(width 0.10668)
		(layer "F.Cu")
		(net "M_A_CPU1_SB_DQ<31>")
	)
	(segment
		(start 69.468238 -308.929532)
		(end 69.604636 -309.06593)
		(width 0.10668)
		(layer "F.Cu")
		(net "M_A_CPU1_SB_DQ<31>")
	)
	(segment
		(start 76.672186 -300.921928)
		(end 76.32954 -301.748952)
		(width 0.10668)
		(layer "F.Cu")
		(net "M_A_CPU1_SB_DQ<31>")
	)
	(segment
		(start 68.758054 -309.912512)
		(end 68.621656 -309.776114)
		(width 0.10668)
		(layer "F.Cu")
		(net "M_A_CPU1_SB_DQ<31>")
	)
	(segment
		(start 75.794362 -303.041304)
		(end 70.05193 -308.783736)
		(width 0.10668)
		(layer "F.Cu")
		(net "M_A_CPU1_SB_DQ<31>")
	)
	(segment
		(start 68.621656 -309.776114)
		(end 68.456556 -309.776114)
		(width 0.10668)
		(layer "F.Cu")
		(net "M_A_CPU1_SB_DQ<31>")
	)
	(segment
		(start 68.339462 -310.058308)
		(end 68.47586 -310.194706)
		(width 0.10668)
		(layer "F.Cu")
		(net "M_A_CPU1_SB_DQ<31>")
	)
	(segment
		(start 60.725812 -317.610236)
		(end 58.199274 -317.610236)
		(width 0.101346)
		(layer "F.Cu")
		(net "M_A_CPU1_SB_DQ<31>")
	)
	(segment
		(start 69.322442 -309.348124)
		(end 69.186044 -309.211726)
		(width 0.10668)
		(layer "F.Cu")
		(net "M_A_CPU1_SB_DQ<31>")
	)
	(segment
		(start 76.890626 -293.260272)
		(end 76.672186 -293.478712)
		(width 0.0762)
		(layer "F.Cu")
		(net "M_A_CPU1_SB_DQ<31>")
	)
	(segment
		(start 61.22543 -317.610236)
		(end 60.725812 -317.610236)
		(width 0.10668)
		(layer "F.Cu")
		(net "M_A_CPU1_SB_DQ<31>")
	)
	(segment
		(start 69.604636 -309.23103)
		(end 69.487542 -309.348124)
		(width 0.10668)
		(layer "F.Cu")
		(net "M_A_CPU1_SB_DQ<31>")
	)
	(segment
		(start 69.487542 -309.348124)
		(end 69.322442 -309.348124)
		(width 0.10668)
		(layer "F.Cu")
		(net "M_A_CPU1_SB_DQ<31>")
	)
	(segment
		(start 68.923154 -309.912512)
		(end 68.758054 -309.912512)
		(width 0.10668)
		(layer "F.Cu")
		(net "M_A_CPU1_SB_DQ<31>")
	)
	(segment
		(start 64.916558 -311.827164)
		(end 64.916558 -311.992264)
		(width 0.10668)
		(layer "F.Cu")
		(net "M_A_CPU1_SB_DQ<30>")
	)
	(segment
		(start 76.69149 -292.07714)
		(end 75.963526 -292.805104)
		(width 0.0762)
		(layer "F.Cu")
		(net "M_A_CPU1_SB_DQ<30>")
	)
	(segment
		(start 75.963526 -300.780196)
		(end 64.916558 -311.827164)
		(width 0.10668)
		(layer "F.Cu")
		(net "M_A_CPU1_SB_DQ<30>")
	)
	(segment
		(start 61.962284 -315.910214)
		(end 60.725812 -315.910214)
		(width 0.10668)
		(layer "F.Cu")
		(net "M_A_CPU1_SB_DQ<30>")
	)
	(segment
		(start 77.767942 -292.07714)
		(end 76.69149 -292.07714)
		(width 0.0762)
		(layer "F.Cu")
		(net "M_A_CPU1_SB_DQ<30>")
	)
	(segment
		(start 64.916558 -311.992264)
		(end 65.172082 -312.247788)
		(width 0.10668)
		(layer "F.Cu")
		(net "M_A_CPU1_SB_DQ<30>")
	)
	(segment
		(start 60.725812 -315.910214)
		(end 58.199274 -315.910214)
		(width 0.101346)
		(layer "F.Cu")
		(net "M_A_CPU1_SB_DQ<30>")
	)
	(segment
		(start 64.469264 -312.274458)
		(end 64.300862 -312.44286)
		(width 0.10668)
		(layer "F.Cu")
		(net "M_A_CPU1_SB_DQ<30>")
	)
	(segment
		(start 57.774078 -316.33541)
		(end 55.328058 -316.33541)
		(width 0.101346)
		(layer "F.Cu")
		(net "M_A_CPU1_SB_DQ<30>")
	)
	(segment
		(start 65.172082 -312.247788)
		(end 65.172082 -312.412888)
		(width 0.10668)
		(layer "F.Cu")
		(net "M_A_CPU1_SB_DQ<30>")
	)
	(segment
		(start 58.199274 -315.910214)
		(end 57.774078 -316.33541)
		(width 0.101346)
		(layer "F.Cu")
		(net "M_A_CPU1_SB_DQ<30>")
	)
	(segment
		(start 64.634364 -312.274458)
		(end 64.469264 -312.274458)
		(width 0.10668)
		(layer "F.Cu")
		(net "M_A_CPU1_SB_DQ<30>")
	)
	(segment
		(start 64.889888 -312.529982)
		(end 64.634364 -312.274458)
		(width 0.10668)
		(layer "F.Cu")
		(net "M_A_CPU1_SB_DQ<30>")
	)
	(segment
		(start 65.172082 -312.412888)
		(end 65.054988 -312.529982)
		(width 0.10668)
		(layer "F.Cu")
		(net "M_A_CPU1_SB_DQ<30>")
	)
	(segment
		(start 75.963526 -292.805104)
		(end 75.963526 -300.780196)
		(width 0.10668)
		(layer "F.Cu")
		(net "M_A_CPU1_SB_DQ<30>")
	)
	(segment
		(start 65.054988 -312.529982)
		(end 64.889888 -312.529982)
		(width 0.10668)
		(layer "F.Cu")
		(net "M_A_CPU1_SB_DQ<30>")
	)
	(segment
		(start 64.300862 -312.44286)
		(end 64.300862 -313.571636)
		(width 0.10668)
		(layer "F.Cu")
		(net "M_A_CPU1_SB_DQ<30>")
	)
	(segment
		(start 64.300862 -313.571636)
		(end 61.962284 -315.910214)
		(width 0.10668)
		(layer "F.Cu")
		(net "M_A_CPU1_SB_DQ<30>")
	)
	(arc
		(start 77.954886 -292.127686)
		(mid 77.864753 -292.090066)
		(end 77.767942 -292.07714)
		(width 0.0762)
		(layer "F.Cu")
		(net "M_A_CPU1_SB_DQ<30>")
	)
	(arc
		(start 78.707996 -292.450266)
		(mid 78.465679 -292.280546)
		(end 78.180692 -292.201092)
		(width 0.0762)
		(layer "F.Cu")
		(net "M_A_CPU1_SB_DQ<30>")
	)
	(arc
		(start 78.180692 -292.201092)
		(mid 78.063879 -292.176416)
		(end 77.954886 -292.127686)
		(width 0.0762)
		(layer "F.Cu")
		(net "M_A_CPU1_SB_DQ<30>")
	)
	(segment
		(start 56.980074 -282.031186)
		(end 56.863234 -282.148026)
		(width 0.101346)
		(layer "F.Cu")
		(net "M_A_CPU1_SB_DQ<2>")
	)
	(segment
		(start 60.822332 -281.910282)
		(end 60.725812 -281.910282)
		(width 0.10668)
		(layer "F.Cu")
		(net "M_A_CPU1_SB_DQ<2>")
	)
	(segment
		(start 57.544462 -282.861004)
		(end 57.379108 -282.861004)
		(width 0.101346)
		(layer "F.Cu")
		(net "M_A_CPU1_SB_DQ<2>")
	)
	(segment
		(start 56.4642 -282.452064)
		(end 56.34736 -282.335224)
		(width 0.101346)
		(layer "F.Cu")
		(net "M_A_CPU1_SB_DQ<2>")
	)
	(segment
		(start 56.58104 -283.239464)
		(end 56.4642 -283.122624)
		(width 0.101346)
		(layer "F.Cu")
		(net "M_A_CPU1_SB_DQ<2>")
	)
	(segment
		(start 56.746394 -283.239464)
		(end 56.58104 -283.239464)
		(width 0.101346)
		(layer "F.Cu")
		(net "M_A_CPU1_SB_DQ<2>")
	)
	(segment
		(start 57.661302 -282.452064)
		(end 57.661302 -282.744164)
		(width 0.101346)
		(layer "F.Cu")
		(net "M_A_CPU1_SB_DQ<2>")
	)
	(segment
		(start 60.725812 -281.910282)
		(end 58.600848 -281.910282)
		(width 0.101346)
		(layer "F.Cu")
		(net "M_A_CPU1_SB_DQ<2>")
	)
	(segment
		(start 58.600848 -281.910282)
		(end 58.175906 -282.335224)
		(width 0.101346)
		(layer "F.Cu")
		(net "M_A_CPU1_SB_DQ<2>")
	)
	(segment
		(start 58.175906 -282.335224)
		(end 57.778142 -282.335224)
		(width 0.101346)
		(layer "F.Cu")
		(net "M_A_CPU1_SB_DQ<2>")
	)
	(segment
		(start 77.767942 -274.257262)
		(end 76.281026 -274.257262)
		(width 0.0762)
		(layer "F.Cu")
		(net "M_A_CPU1_SB_DQ<2>")
	)
	(segment
		(start 57.379108 -282.861004)
		(end 57.262268 -282.744164)
		(width 0.101346)
		(layer "F.Cu")
		(net "M_A_CPU1_SB_DQ<2>")
	)
	(segment
		(start 57.661302 -282.744164)
		(end 57.544462 -282.861004)
		(width 0.101346)
		(layer "F.Cu")
		(net "M_A_CPU1_SB_DQ<2>")
	)
	(segment
		(start 57.778142 -282.335224)
		(end 57.661302 -282.452064)
		(width 0.101346)
		(layer "F.Cu")
		(net "M_A_CPU1_SB_DQ<2>")
	)
	(segment
		(start 56.863234 -283.122624)
		(end 56.746394 -283.239464)
		(width 0.101346)
		(layer "F.Cu")
		(net "M_A_CPU1_SB_DQ<2>")
	)
	(segment
		(start 76.281026 -274.257262)
		(end 76.233528 -274.209764)
		(width 0.0762)
		(layer "F.Cu")
		(net "M_A_CPU1_SB_DQ<2>")
	)
	(segment
		(start 57.262268 -282.744164)
		(end 57.262268 -282.148026)
		(width 0.101346)
		(layer "F.Cu")
		(net "M_A_CPU1_SB_DQ<2>")
	)
	(segment
		(start 56.4642 -283.122624)
		(end 56.4642 -282.452064)
		(width 0.101346)
		(layer "F.Cu")
		(net "M_A_CPU1_SB_DQ<2>")
	)
	(segment
		(start 56.34736 -282.335224)
		(end 55.328058 -282.335224)
		(width 0.101346)
		(layer "F.Cu")
		(net "M_A_CPU1_SB_DQ<2>")
	)
	(segment
		(start 57.145428 -282.031186)
		(end 56.980074 -282.031186)
		(width 0.101346)
		(layer "F.Cu")
		(net "M_A_CPU1_SB_DQ<2>")
	)
	(segment
		(start 68.52285 -274.209764)
		(end 60.822332 -281.910282)
		(width 0.10668)
		(layer "F.Cu")
		(net "M_A_CPU1_SB_DQ<2>")
	)
	(segment
		(start 57.262268 -282.148026)
		(end 57.145428 -282.031186)
		(width 0.101346)
		(layer "F.Cu")
		(net "M_A_CPU1_SB_DQ<2>")
	)
	(segment
		(start 56.863234 -282.148026)
		(end 56.863234 -283.122624)
		(width 0.101346)
		(layer "F.Cu")
		(net "M_A_CPU1_SB_DQ<2>")
	)
	(segment
		(start 75.960986 -274.209764)
		(end 68.52285 -274.209764)
		(width 0.10668)
		(layer "F.Cu")
		(net "M_A_CPU1_SB_DQ<2>")
	)
	(segment
		(start 76.233528 -274.209764)
		(end 75.960986 -274.209764)
		(width 0.0762)
		(layer "F.Cu")
		(net "M_A_CPU1_SB_DQ<2>")
	)
	(arc
		(start 78.707996 -274.630388)
		(mid 78.465679 -274.460668)
		(end 78.180692 -274.381214)
		(width 0.0762)
		(layer "F.Cu")
		(net "M_A_CPU1_SB_DQ<2>")
	)
	(arc
		(start 77.954886 -274.307808)
		(mid 77.864753 -274.270188)
		(end 77.767942 -274.257262)
		(width 0.0762)
		(layer "F.Cu")
		(net "M_A_CPU1_SB_DQ<2>")
	)
	(arc
		(start 78.180692 -274.381214)
		(mid 78.063879 -274.356538)
		(end 77.954886 -274.307808)
		(width 0.0762)
		(layer "F.Cu")
		(net "M_A_CPU1_SB_DQ<2>")
	)
	(segment
		(start 67.395598 -310.394096)
		(end 67.560698 -310.394096)
		(width 0.10668)
		(layer "F.Cu")
		(net "M_A_CPU1_SB_DQ<29>")
	)
	(segment
		(start 61.168788 -317.185294)
		(end 59.428126 -317.185294)
		(width 0.10668)
		(layer "F.Cu")
		(net "M_A_CPU1_SB_DQ<29>")
	)
	(segment
		(start 79.645256 -292.451282)
		(end 79.164942 -292.774624)
		(width 0.0762)
		(layer "F.Cu")
		(net "M_A_CPU1_SB_DQ<29>")
	)
	(segment
		(start 79.647796 -292.450266)
		(end 79.645256 -292.451282)
		(width 0.0762)
		(layer "F.Cu")
		(net "M_A_CPU1_SB_DQ<29>")
	)
	(segment
		(start 76.303886 -293.084504)
		(end 76.303886 -300.92142)
		(width 0.10668)
		(layer "F.Cu")
		(net "M_A_CPU1_SB_DQ<29>")
	)
	(segment
		(start 65.512442 -311.712864)
		(end 65.512442 -312.84164)
		(width 0.10668)
		(layer "F.Cu")
		(net "M_A_CPU1_SB_DQ<29>")
	)
	(segment
		(start 65.960752 -311.429654)
		(end 65.795652 -311.429654)
		(width 0.10668)
		(layer "F.Cu")
		(net "M_A_CPU1_SB_DQ<29>")
	)
	(segment
		(start 66.242946 -310.98236)
		(end 66.242946 -311.14746)
		(width 0.10668)
		(layer "F.Cu")
		(net "M_A_CPU1_SB_DQ<29>")
	)
	(segment
		(start 78.907132 -292.853364)
		(end 76.535026 -292.853364)
		(width 0.0762)
		(layer "F.Cu")
		(net "M_A_CPU1_SB_DQ<29>")
	)
	(segment
		(start 76.535026 -292.853364)
		(end 76.303886 -293.084504)
		(width 0.0762)
		(layer "F.Cu")
		(net "M_A_CPU1_SB_DQ<29>")
	)
	(segment
		(start 65.795652 -311.429654)
		(end 65.512442 -311.712864)
		(width 0.10668)
		(layer "F.Cu")
		(net "M_A_CPU1_SB_DQ<29>")
	)
	(segment
		(start 67.677792 -310.67629)
		(end 66.52514 -311.828942)
		(width 0.10668)
		(layer "F.Cu")
		(net "M_A_CPU1_SB_DQ<29>")
	)
	(segment
		(start 65.512442 -312.84164)
		(end 61.168788 -317.185294)
		(width 0.10668)
		(layer "F.Cu")
		(net "M_A_CPU1_SB_DQ<29>")
	)
	(segment
		(start 66.52514 -311.264554)
		(end 67.395598 -310.394096)
		(width 0.10668)
		(layer "F.Cu")
		(net "M_A_CPU1_SB_DQ<29>")
	)
	(segment
		(start 66.36004 -311.264554)
		(end 66.52514 -311.264554)
		(width 0.10668)
		(layer "F.Cu")
		(net "M_A_CPU1_SB_DQ<29>")
	)
	(segment
		(start 66.242946 -311.14746)
		(end 66.36004 -311.264554)
		(width 0.10668)
		(layer "F.Cu")
		(net "M_A_CPU1_SB_DQ<29>")
	)
	(segment
		(start 66.52514 -311.828942)
		(end 66.36004 -311.828942)
		(width 0.10668)
		(layer "F.Cu")
		(net "M_A_CPU1_SB_DQ<29>")
	)
	(segment
		(start 66.36004 -311.828942)
		(end 65.960752 -311.429654)
		(width 0.10668)
		(layer "F.Cu")
		(net "M_A_CPU1_SB_DQ<29>")
	)
	(segment
		(start 67.677792 -310.51119)
		(end 67.677792 -310.67629)
		(width 0.10668)
		(layer "F.Cu")
		(net "M_A_CPU1_SB_DQ<29>")
	)
	(segment
		(start 67.560698 -310.394096)
		(end 67.677792 -310.51119)
		(width 0.10668)
		(layer "F.Cu")
		(net "M_A_CPU1_SB_DQ<29>")
	)
	(segment
		(start 76.303886 -300.92142)
		(end 66.242946 -310.98236)
		(width 0.10668)
		(layer "F.Cu")
		(net "M_A_CPU1_SB_DQ<29>")
	)
	(arc
		(start 79.164942 -292.774624)
		(mid 79.041907 -292.833197)
		(end 78.907132 -292.853364)
		(width 0.0762)
		(layer "F.Cu")
		(net "M_A_CPU1_SB_DQ<29>")
	)
	(segment
		(start 62.027562 -314.385452)
		(end 62.15888 -314.51677)
		(width 0.10668)
		(layer "F.Cu")
		(net "M_A_CPU1_SB_DQ<28>")
	)
	(segment
		(start 62.160404 -315.23051)
		(end 61.995304 -315.23051)
		(width 0.10668)
		(layer "F.Cu")
		(net "M_A_CPU1_SB_DQ<28>")
	)
	(segment
		(start 63.843408 -313.148218)
		(end 63.960502 -313.265312)
		(width 0.10668)
		(layer "F.Cu")
		(net "M_A_CPU1_SB_DQ<28>")
	)
	(segment
		(start 78.05928 -291.967666)
		(end 78.050898 -291.96284)
		(width 0.0762)
		(layer "F.Cu")
		(net "M_A_CPU1_SB_DQ<28>")
	)
	(segment
		(start 62.309756 -314.51677)
		(end 63.678308 -313.148218)
		(width 0.10668)
		(layer "F.Cu")
		(net "M_A_CPU1_SB_DQ<28>")
	)
	(segment
		(start 62.027562 -314.234576)
		(end 62.027562 -314.385452)
		(width 0.10668)
		(layer "F.Cu")
		(net "M_A_CPU1_SB_DQ<28>")
	)
	(segment
		(start 63.960502 -313.265312)
		(end 63.960502 -313.430412)
		(width 0.10668)
		(layer "F.Cu")
		(net "M_A_CPU1_SB_DQ<28>")
	)
	(segment
		(start 62.15888 -314.51677)
		(end 62.309756 -314.51677)
		(width 0.10668)
		(layer "F.Cu")
		(net "M_A_CPU1_SB_DQ<28>")
	)
	(segment
		(start 61.545724 -314.931806)
		(end 60.992258 -315.485272)
		(width 0.10668)
		(layer "F.Cu")
		(net "M_A_CPU1_SB_DQ<28>")
	)
	(segment
		(start 78.237842 -291.64026)
		(end 78.33614 -291.809424)
		(width 0.0762)
		(layer "F.Cu")
		(net "M_A_CPU1_SB_DQ<28>")
	)
	(segment
		(start 61.995304 -315.23051)
		(end 61.6966 -314.931806)
		(width 0.10668)
		(layer "F.Cu")
		(net "M_A_CPU1_SB_DQ<28>")
	)
	(segment
		(start 75.623166 -300.638972)
		(end 62.027562 -314.234576)
		(width 0.10668)
		(layer "F.Cu")
		(net "M_A_CPU1_SB_DQ<28>")
	)
	(segment
		(start 75.623166 -292.763956)
		(end 75.623166 -300.638972)
		(width 0.10668)
		(layer "F.Cu")
		(net "M_A_CPU1_SB_DQ<28>")
	)
	(segment
		(start 76.500482 -291.88664)
		(end 76.025248 -292.361874)
		(width 0.0762)
		(layer "F.Cu")
		(net "M_A_CPU1_SB_DQ<28>")
	)
	(segment
		(start 77.767942 -291.88664)
		(end 76.500482 -291.88664)
		(width 0.0762)
		(layer "F.Cu")
		(net "M_A_CPU1_SB_DQ<28>")
	)
	(segment
		(start 76.025248 -292.361874)
		(end 75.623166 -292.763956)
		(width 0.10668)
		(layer "F.Cu")
		(net "M_A_CPU1_SB_DQ<28>")
	)
	(segment
		(start 63.960502 -313.430412)
		(end 62.160404 -315.23051)
		(width 0.10668)
		(layer "F.Cu")
		(net "M_A_CPU1_SB_DQ<28>")
	)
	(segment
		(start 61.6966 -314.931806)
		(end 61.545724 -314.931806)
		(width 0.10668)
		(layer "F.Cu")
		(net "M_A_CPU1_SB_DQ<28>")
	)
	(segment
		(start 63.678308 -313.148218)
		(end 63.843408 -313.148218)
		(width 0.10668)
		(layer "F.Cu")
		(net "M_A_CPU1_SB_DQ<28>")
	)
	(segment
		(start 60.992258 -315.485272)
		(end 59.428126 -315.485272)
		(width 0.10668)
		(layer "F.Cu")
		(net "M_A_CPU1_SB_DQ<28>")
	)
	(arc
		(start 78.198472 -292.0111)
		(mid 78.126734 -291.996248)
		(end 78.05928 -291.967666)
		(width 0.0762)
		(layer "F.Cu")
		(net "M_A_CPU1_SB_DQ<28>")
	)
	(arc
		(start 78.050898 -291.96284)
		(mid 77.914462 -291.906015)
		(end 77.767942 -291.88664)
		(width 0.0762)
		(layer "F.Cu")
		(net "M_A_CPU1_SB_DQ<28>")
	)
	(arc
		(start 78.33614 -291.809424)
		(mid 78.327547 -291.951303)
		(end 78.198472 -292.0111)
		(width 0.0762)
		(layer "F.Cu")
		(net "M_A_CPU1_SB_DQ<28>")
	)
	(segment
		(start 64.537082 -308.511956)
		(end 64.537082 -308.79288)
		(width 0.10668)
		(layer "F.Cu")
		(net "M_A_CPU1_SB_DQ<27>")
	)
	(segment
		(start 64.39535 -308.934612)
		(end 64.114426 -308.934612)
		(width 0.10668)
		(layer "F.Cu")
		(net "M_A_CPU1_SB_DQ<27>")
	)
	(segment
		(start 64.959738 -308.370224)
		(end 64.678814 -308.370224)
		(width 0.10668)
		(layer "F.Cu")
		(net "M_A_CPU1_SB_DQ<27>")
	)
	(segment
		(start 65.10147 -307.947568)
		(end 65.10147 -308.228492)
		(width 0.10668)
		(layer "F.Cu")
		(net "M_A_CPU1_SB_DQ<27>")
	)
	(segment
		(start 63.408306 -309.921656)
		(end 63.266574 -310.063388)
		(width 0.10668)
		(layer "F.Cu")
		(net "M_A_CPU1_SB_DQ<27>")
	)
	(segment
		(start 67.950588 -303.969674)
		(end 67.950588 -305.09845)
		(width 0.10668)
		(layer "F.Cu")
		(net "M_A_CPU1_SB_DQ<27>")
	)
	(segment
		(start 75.986386 -289.602164)
		(end 75.681586 -289.602164)
		(width 0.10668)
		(layer "F.Cu")
		(net "M_A_CPU1_SB_DQ<27>")
	)
	(segment
		(start 61.856874 -311.192164)
		(end 61.388752 -311.660286)
		(width 0.10668)
		(layer "F.Cu")
		(net "M_A_CPU1_SB_DQ<27>")
	)
	(segment
		(start 76.164186 -289.602164)
		(end 75.986386 -289.602164)
		(width 0.0762)
		(layer "F.Cu")
		(net "M_A_CPU1_SB_DQ<27>")
	)
	(segment
		(start 77.768196 -289.773868)
		(end 76.33589 -289.773868)
		(width 0.0762)
		(layer "F.Cu")
		(net "M_A_CPU1_SB_DQ<27>")
	)
	(segment
		(start 62.843918 -310.20512)
		(end 62.843918 -310.486044)
		(width 0.10668)
		(layer "F.Cu")
		(net "M_A_CPU1_SB_DQ<27>")
	)
	(segment
		(start 63.972694 -309.357268)
		(end 63.830962 -309.499)
		(width 0.10668)
		(layer "F.Cu")
		(net "M_A_CPU1_SB_DQ<27>")
	)
	(segment
		(start 78.05928 -289.692842)
		(end 78.050898 -289.697668)
		(width 0.0762)
		(layer "F.Cu")
		(net "M_A_CPU1_SB_DQ<27>")
	)
	(segment
		(start 67.950588 -305.09845)
		(end 65.10147 -307.947568)
		(width 0.10668)
		(layer "F.Cu")
		(net "M_A_CPU1_SB_DQ<27>")
	)
	(segment
		(start 76.33589 -289.773868)
		(end 76.164186 -289.602164)
		(width 0.0762)
		(layer "F.Cu")
		(net "M_A_CPU1_SB_DQ<27>")
	)
	(segment
		(start 60.725812 -311.660286)
		(end 57.408064 -311.660286)
		(width 0.101346)
		(layer "F.Cu")
		(net "M_A_CPU1_SB_DQ<27>")
	)
	(segment
		(start 73.377552 -291.906198)
		(end 73.377552 -298.54271)
		(width 0.10668)
		(layer "F.Cu")
		(net "M_A_CPU1_SB_DQ<27>")
	)
	(segment
		(start 75.681586 -289.602164)
		(end 73.377552 -291.906198)
		(width 0.10668)
		(layer "F.Cu")
		(net "M_A_CPU1_SB_DQ<27>")
	)
	(segment
		(start 64.114426 -308.934612)
		(end 63.972694 -309.076344)
		(width 0.10668)
		(layer "F.Cu")
		(net "M_A_CPU1_SB_DQ<27>")
	)
	(segment
		(start 63.408306 -309.640732)
		(end 63.408306 -309.921656)
		(width 0.10668)
		(layer "F.Cu")
		(net "M_A_CPU1_SB_DQ<27>")
	)
	(segment
		(start 62.27953 -311.050432)
		(end 62.137798 -311.192164)
		(width 0.10668)
		(layer "F.Cu")
		(net "M_A_CPU1_SB_DQ<27>")
	)
	(segment
		(start 62.98565 -310.063388)
		(end 62.843918 -310.20512)
		(width 0.10668)
		(layer "F.Cu")
		(net "M_A_CPU1_SB_DQ<27>")
	)
	(segment
		(start 63.830962 -309.499)
		(end 63.550038 -309.499)
		(width 0.10668)
		(layer "F.Cu")
		(net "M_A_CPU1_SB_DQ<27>")
	)
	(segment
		(start 64.678814 -308.370224)
		(end 64.537082 -308.511956)
		(width 0.10668)
		(layer "F.Cu")
		(net "M_A_CPU1_SB_DQ<27>")
	)
	(segment
		(start 64.537082 -308.79288)
		(end 64.39535 -308.934612)
		(width 0.10668)
		(layer "F.Cu")
		(net "M_A_CPU1_SB_DQ<27>")
	)
	(segment
		(start 56.983122 -312.085228)
		(end 55.328058 -312.085228)
		(width 0.101346)
		(layer "F.Cu")
		(net "M_A_CPU1_SB_DQ<27>")
	)
	(segment
		(start 57.408064 -311.660286)
		(end 56.983122 -312.085228)
		(width 0.101346)
		(layer "F.Cu")
		(net "M_A_CPU1_SB_DQ<27>")
	)
	(segment
		(start 62.27953 -310.769508)
		(end 62.27953 -311.050432)
		(width 0.10668)
		(layer "F.Cu")
		(net "M_A_CPU1_SB_DQ<27>")
	)
	(segment
		(start 63.266574 -310.063388)
		(end 62.98565 -310.063388)
		(width 0.10668)
		(layer "F.Cu")
		(net "M_A_CPU1_SB_DQ<27>")
	)
	(segment
		(start 62.421262 -310.627776)
		(end 62.27953 -310.769508)
		(width 0.10668)
		(layer "F.Cu")
		(net "M_A_CPU1_SB_DQ<27>")
	)
	(segment
		(start 62.137798 -311.192164)
		(end 61.856874 -311.192164)
		(width 0.10668)
		(layer "F.Cu")
		(net "M_A_CPU1_SB_DQ<27>")
	)
	(segment
		(start 62.843918 -310.486044)
		(end 62.702186 -310.627776)
		(width 0.10668)
		(layer "F.Cu")
		(net "M_A_CPU1_SB_DQ<27>")
	)
	(segment
		(start 63.550038 -309.499)
		(end 63.408306 -309.640732)
		(width 0.10668)
		(layer "F.Cu")
		(net "M_A_CPU1_SB_DQ<27>")
	)
	(segment
		(start 73.377552 -298.54271)
		(end 67.950588 -303.969674)
		(width 0.10668)
		(layer "F.Cu")
		(net "M_A_CPU1_SB_DQ<27>")
	)
	(segment
		(start 62.702186 -310.627776)
		(end 62.421262 -310.627776)
		(width 0.10668)
		(layer "F.Cu")
		(net "M_A_CPU1_SB_DQ<27>")
	)
	(segment
		(start 65.10147 -308.228492)
		(end 64.959738 -308.370224)
		(width 0.10668)
		(layer "F.Cu")
		(net "M_A_CPU1_SB_DQ<27>")
	)
	(segment
		(start 61.388752 -311.660286)
		(end 60.725812 -311.660286)
		(width 0.10668)
		(layer "F.Cu")
		(net "M_A_CPU1_SB_DQ<27>")
	)
	(segment
		(start 63.972694 -309.076344)
		(end 63.972694 -309.357268)
		(width 0.10668)
		(layer "F.Cu")
		(net "M_A_CPU1_SB_DQ<27>")
	)
	(arc
		(start 78.42504 -289.697668)
		(mid 78.242789 -289.647318)
		(end 78.05928 -289.692842)
		(width 0.0762)
		(layer "F.Cu")
		(net "M_A_CPU1_SB_DQ<27>")
	)
	(arc
		(start 77.815186 -289.77209)
		(mid 77.791709 -289.773466)
		(end 77.768196 -289.773868)
		(width 0.0762)
		(layer "F.Cu")
		(net "M_A_CPU1_SB_DQ<27>")
	)
	(arc
		(start 80.11795 -290.020248)
		(mid 79.880338 -289.84926)
		(end 79.598012 -289.771836)
		(width 0.0762)
		(layer "F.Cu")
		(net "M_A_CPU1_SB_DQ<27>")
	)
	(arc
		(start 78.050898 -289.697668)
		(mid 77.937174 -289.747969)
		(end 77.815186 -289.77209)
		(width 0.0762)
		(layer "F.Cu")
		(net "M_A_CPU1_SB_DQ<27>")
	)
	(arc
		(start 79.598012 -289.771836)
		(mid 79.477363 -289.747535)
		(end 79.36484 -289.697668)
		(width 0.0762)
		(layer "F.Cu")
		(net "M_A_CPU1_SB_DQ<27>")
	)
	(arc
		(start 79.36484 -289.697668)
		(mid 79.177896 -289.647413)
		(end 78.990952 -289.697668)
		(width 0.0762)
		(layer "F.Cu")
		(net "M_A_CPU1_SB_DQ<27>")
	)
	(arc
		(start 78.990952 -289.697668)
		(mid 78.707996 -289.773845)
		(end 78.42504 -289.697668)
		(width 0.0762)
		(layer "F.Cu")
		(net "M_A_CPU1_SB_DQ<27>")
	)
	(segment
		(start 76.034138 -288.837116)
		(end 75.986386 -288.789364)
		(width 0.0762)
		(layer "F.Cu")
		(net "M_A_CPU1_SB_DQ<26>")
	)
	(segment
		(start 60.725812 -309.960264)
		(end 57.816496 -309.960264)
		(width 0.101346)
		(layer "F.Cu")
		(net "M_A_CPU1_SB_DQ<26>")
	)
	(segment
		(start 58.191146 -310.758332)
		(end 57.417462 -310.758332)
		(width 0.101346)
		(layer "F.Cu")
		(net "M_A_CPU1_SB_DQ<26>")
	)
	(segment
		(start 57.300622 -310.641492)
		(end 57.300622 -310.077104)
		(width 0.101346)
		(layer "F.Cu")
		(net "M_A_CPU1_SB_DQ<26>")
	)
	(segment
		(start 57.816496 -309.960264)
		(end 57.699656 -310.077104)
		(width 0.101346)
		(layer "F.Cu")
		(net "M_A_CPU1_SB_DQ<26>")
	)
	(segment
		(start 57.699656 -310.242458)
		(end 57.816496 -310.359298)
		(width 0.101346)
		(layer "F.Cu")
		(net "M_A_CPU1_SB_DQ<26>")
	)
	(segment
		(start 64.898524 -306.05857)
		(end 64.898524 -307.187346)
		(width 0.10668)
		(layer "F.Cu")
		(net "M_A_CPU1_SB_DQ<26>")
	)
	(segment
		(start 57.816496 -310.359298)
		(end 58.191146 -310.359298)
		(width 0.101346)
		(layer "F.Cu")
		(net "M_A_CPU1_SB_DQ<26>")
	)
	(segment
		(start 58.307986 -310.641492)
		(end 58.191146 -310.758332)
		(width 0.101346)
		(layer "F.Cu")
		(net "M_A_CPU1_SB_DQ<26>")
	)
	(segment
		(start 57.300622 -310.077104)
		(end 57.183782 -309.960264)
		(width 0.101346)
		(layer "F.Cu")
		(net "M_A_CPU1_SB_DQ<26>")
	)
	(segment
		(start 72.696832 -298.260262)
		(end 64.898524 -306.05857)
		(width 0.10668)
		(layer "F.Cu")
		(net "M_A_CPU1_SB_DQ<26>")
	)
	(segment
		(start 62.125606 -309.960264)
		(end 60.725812 -309.960264)
		(width 0.10668)
		(layer "F.Cu")
		(net "M_A_CPU1_SB_DQ<26>")
	)
	(segment
		(start 75.478386 -288.789364)
		(end 72.696832 -291.570918)
		(width 0.10668)
		(layer "F.Cu")
		(net "M_A_CPU1_SB_DQ<26>")
	)
	(segment
		(start 57.699656 -310.077104)
		(end 57.699656 -310.242458)
		(width 0.101346)
		(layer "F.Cu")
		(net "M_A_CPU1_SB_DQ<26>")
	)
	(segment
		(start 58.191146 -310.359298)
		(end 58.307986 -310.476138)
		(width 0.101346)
		(layer "F.Cu")
		(net "M_A_CPU1_SB_DQ<26>")
	)
	(segment
		(start 58.307986 -310.476138)
		(end 58.307986 -310.641492)
		(width 0.101346)
		(layer "F.Cu")
		(net "M_A_CPU1_SB_DQ<26>")
	)
	(segment
		(start 56.916066 -309.960264)
		(end 56.491124 -310.385206)
		(width 0.101346)
		(layer "F.Cu")
		(net "M_A_CPU1_SB_DQ<26>")
	)
	(segment
		(start 56.491124 -310.385206)
		(end 55.328058 -310.385206)
		(width 0.101346)
		(layer "F.Cu")
		(net "M_A_CPU1_SB_DQ<26>")
	)
	(segment
		(start 77.767942 -288.837116)
		(end 76.034138 -288.837116)
		(width 0.0762)
		(layer "F.Cu")
		(net "M_A_CPU1_SB_DQ<26>")
	)
	(segment
		(start 64.898524 -307.187346)
		(end 62.125606 -309.960264)
		(width 0.10668)
		(layer "F.Cu")
		(net "M_A_CPU1_SB_DQ<26>")
	)
	(segment
		(start 57.417462 -310.758332)
		(end 57.300622 -310.641492)
		(width 0.101346)
		(layer "F.Cu")
		(net "M_A_CPU1_SB_DQ<26>")
	)
	(segment
		(start 75.986386 -288.789364)
		(end 75.478386 -288.789364)
		(width 0.10668)
		(layer "F.Cu")
		(net "M_A_CPU1_SB_DQ<26>")
	)
	(segment
		(start 57.183782 -309.960264)
		(end 56.916066 -309.960264)
		(width 0.101346)
		(layer "F.Cu")
		(net "M_A_CPU1_SB_DQ<26>")
	)
	(segment
		(start 72.696832 -291.570918)
		(end 72.696832 -298.260262)
		(width 0.10668)
		(layer "F.Cu")
		(net "M_A_CPU1_SB_DQ<26>")
	)
	(arc
		(start 77.954886 -288.887662)
		(mid 77.864753 -288.850042)
		(end 77.767942 -288.837116)
		(width 0.0762)
		(layer "F.Cu")
		(net "M_A_CPU1_SB_DQ<26>")
	)
	(arc
		(start 78.180692 -288.961068)
		(mid 78.063879 -288.936392)
		(end 77.954886 -288.887662)
		(width 0.0762)
		(layer "F.Cu")
		(net "M_A_CPU1_SB_DQ<26>")
	)
	(arc
		(start 78.707996 -289.210242)
		(mid 78.465679 -289.040522)
		(end 78.180692 -288.961068)
		(width 0.0762)
		(layer "F.Cu")
		(net "M_A_CPU1_SB_DQ<26>")
	)
	(segment
		(start 73.037192 -291.738558)
		(end 73.037192 -298.401486)
		(width 0.10668)
		(layer "F.Cu")
		(net "M_A_CPU1_SB_DQ<25>")
	)
	(segment
		(start 65.238884 -307.32857)
		(end 61.33211 -311.235344)
		(width 0.10668)
		(layer "F.Cu")
		(net "M_A_CPU1_SB_DQ<25>")
	)
	(segment
		(start 67.328034 -304.675032)
		(end 67.493134 -304.675032)
		(width 0.10668)
		(layer "F.Cu")
		(net "M_A_CPU1_SB_DQ<25>")
	)
	(segment
		(start 73.037192 -298.401486)
		(end 65.80759 -305.631088)
		(width 0.10668)
		(layer "F.Cu")
		(net "M_A_CPU1_SB_DQ<25>")
	)
	(segment
		(start 65.924684 -305.913282)
		(end 66.089784 -305.913282)
		(width 0.10668)
		(layer "F.Cu")
		(net "M_A_CPU1_SB_DQ<25>")
	)
	(segment
		(start 79.469234 -289.537648)
		(end 79.460852 -289.532822)
		(width 0.0762)
		(layer "F.Cu")
		(net "M_A_CPU1_SB_DQ<25>")
	)
	(segment
		(start 65.238884 -306.199794)
		(end 65.238884 -307.32857)
		(width 0.10668)
		(layer "F.Cu")
		(net "M_A_CPU1_SB_DQ<25>")
	)
	(segment
		(start 65.360296 -306.078382)
		(end 65.238884 -306.199794)
		(width 0.10668)
		(layer "F.Cu")
		(net "M_A_CPU1_SB_DQ<25>")
	)
	(segment
		(start 65.80759 -305.631088)
		(end 65.80759 -305.796188)
		(width 0.10668)
		(layer "F.Cu")
		(net "M_A_CPU1_SB_DQ<25>")
	)
	(segment
		(start 61.33211 -311.235344)
		(end 59.428126 -311.235344)
		(width 0.10668)
		(layer "F.Cu")
		(net "M_A_CPU1_SB_DQ<25>")
	)
	(segment
		(start 67.610228 -304.957226)
		(end 66.089784 -306.47767)
		(width 0.10668)
		(layer "F.Cu")
		(net "M_A_CPU1_SB_DQ<25>")
	)
	(segment
		(start 65.924684 -306.47767)
		(end 65.525396 -306.078382)
		(width 0.10668)
		(layer "F.Cu")
		(net "M_A_CPU1_SB_DQ<25>")
	)
	(segment
		(start 76.93279 -289.583368)
		(end 76.595986 -289.246564)
		(width 0.0762)
		(layer "F.Cu")
		(net "M_A_CPU1_SB_DQ<25>")
	)
	(segment
		(start 79.647796 -289.210242)
		(end 79.748634 -289.383724)
		(width 0.0762)
		(layer "F.Cu")
		(net "M_A_CPU1_SB_DQ<25>")
	)
	(segment
		(start 65.80759 -305.796188)
		(end 65.924684 -305.913282)
		(width 0.10668)
		(layer "F.Cu")
		(net "M_A_CPU1_SB_DQ<25>")
	)
	(segment
		(start 66.089784 -305.913282)
		(end 67.328034 -304.675032)
		(width 0.10668)
		(layer "F.Cu")
		(net "M_A_CPU1_SB_DQ<25>")
	)
	(segment
		(start 67.493134 -304.675032)
		(end 67.610228 -304.792126)
		(width 0.10668)
		(layer "F.Cu")
		(net "M_A_CPU1_SB_DQ<25>")
	)
	(segment
		(start 78.89494 -289.532822)
		(end 78.886558 -289.537648)
		(width 0.0762)
		(layer "F.Cu")
		(net "M_A_CPU1_SB_DQ<25>")
	)
	(segment
		(start 67.610228 -304.792126)
		(end 67.610228 -304.957226)
		(width 0.10668)
		(layer "F.Cu")
		(net "M_A_CPU1_SB_DQ<25>")
	)
	(segment
		(start 75.960986 -289.246564)
		(end 75.529186 -289.246564)
		(width 0.10668)
		(layer "F.Cu")
		(net "M_A_CPU1_SB_DQ<25>")
	)
	(segment
		(start 76.595986 -289.246564)
		(end 75.960986 -289.246564)
		(width 0.0762)
		(layer "F.Cu")
		(net "M_A_CPU1_SB_DQ<25>")
	)
	(segment
		(start 75.529186 -289.246564)
		(end 73.037192 -291.738558)
		(width 0.10668)
		(layer "F.Cu")
		(net "M_A_CPU1_SB_DQ<25>")
	)
	(segment
		(start 66.089784 -306.47767)
		(end 65.924684 -306.47767)
		(width 0.10668)
		(layer "F.Cu")
		(net "M_A_CPU1_SB_DQ<25>")
	)
	(segment
		(start 77.767942 -289.583368)
		(end 76.93279 -289.583368)
		(width 0.0762)
		(layer "F.Cu")
		(net "M_A_CPU1_SB_DQ<25>")
	)
	(segment
		(start 65.525396 -306.078382)
		(end 65.360296 -306.078382)
		(width 0.10668)
		(layer "F.Cu")
		(net "M_A_CPU1_SB_DQ<25>")
	)
	(arc
		(start 79.748634 -289.383724)
		(mid 79.732709 -289.524416)
		(end 79.602584 -289.58032)
		(width 0.0762)
		(layer "F.Cu")
		(net "M_A_CPU1_SB_DQ<25>")
	)
	(arc
		(start 79.460852 -289.532822)
		(mid 79.177896 -289.456645)
		(end 78.89494 -289.532822)
		(width 0.0762)
		(layer "F.Cu")
		(net "M_A_CPU1_SB_DQ<25>")
	)
	(arc
		(start 77.79893 -289.582098)
		(mid 77.783449 -289.583054)
		(end 77.767942 -289.583368)
		(width 0.0762)
		(layer "F.Cu")
		(net "M_A_CPU1_SB_DQ<25>")
	)
	(arc
		(start 78.520798 -289.532822)
		(mid 78.237842 -289.456645)
		(end 77.954886 -289.532822)
		(width 0.0762)
		(layer "F.Cu")
		(net "M_A_CPU1_SB_DQ<25>")
	)
	(arc
		(start 79.602584 -289.58032)
		(mid 79.533886 -289.565304)
		(end 79.469234 -289.537648)
		(width 0.0762)
		(layer "F.Cu")
		(net "M_A_CPU1_SB_DQ<25>")
	)
	(arc
		(start 77.954886 -289.532822)
		(mid 77.879646 -289.566135)
		(end 77.79893 -289.582098)
		(width 0.0762)
		(layer "F.Cu")
		(net "M_A_CPU1_SB_DQ<25>")
	)
	(arc
		(start 78.886558 -289.537648)
		(mid 78.70305 -289.583142)
		(end 78.520798 -289.532822)
		(width 0.0762)
		(layer "F.Cu")
		(net "M_A_CPU1_SB_DQ<25>")
	)
	(segment
		(start 62.228984 -308.810914)
		(end 64.27597 -306.763928)
		(width 0.10668)
		(layer "F.Cu")
		(net "M_A_CPU1_SB_DQ<24>")
	)
	(segment
		(start 62.063884 -308.810914)
		(end 62.228984 -308.810914)
		(width 0.10668)
		(layer "F.Cu")
		(net "M_A_CPU1_SB_DQ<24>")
	)
	(segment
		(start 62.063884 -309.375302)
		(end 61.664596 -308.976014)
		(width 0.10668)
		(layer "F.Cu")
		(net "M_A_CPU1_SB_DQ<24>")
	)
	(segment
		(start 64.558164 -307.046122)
		(end 62.228984 -309.375302)
		(width 0.10668)
		(layer "F.Cu")
		(net "M_A_CPU1_SB_DQ<24>")
	)
	(segment
		(start 61.94679 -308.52872)
		(end 61.94679 -308.69382)
		(width 0.10668)
		(layer "F.Cu")
		(net "M_A_CPU1_SB_DQ<24>")
	)
	(segment
		(start 75.986386 -288.433764)
		(end 75.275186 -288.433764)
		(width 0.10668)
		(layer "F.Cu")
		(net "M_A_CPU1_SB_DQ<24>")
	)
	(segment
		(start 62.228984 -309.375302)
		(end 62.063884 -309.375302)
		(width 0.10668)
		(layer "F.Cu")
		(net "M_A_CPU1_SB_DQ<24>")
	)
	(segment
		(start 61.94679 -308.69382)
		(end 62.063884 -308.810914)
		(width 0.10668)
		(layer "F.Cu")
		(net "M_A_CPU1_SB_DQ<24>")
	)
	(segment
		(start 61.664596 -308.976014)
		(end 61.499496 -308.976014)
		(width 0.10668)
		(layer "F.Cu")
		(net "M_A_CPU1_SB_DQ<24>")
	)
	(segment
		(start 78.05928 -288.727642)
		(end 78.050898 -288.722816)
		(width 0.0762)
		(layer "F.Cu")
		(net "M_A_CPU1_SB_DQ<24>")
	)
	(segment
		(start 72.356472 -291.352478)
		(end 72.356472 -298.119038)
		(width 0.10668)
		(layer "F.Cu")
		(net "M_A_CPU1_SB_DQ<24>")
	)
	(segment
		(start 64.44107 -306.763928)
		(end 64.558164 -306.881022)
		(width 0.10668)
		(layer "F.Cu")
		(net "M_A_CPU1_SB_DQ<24>")
	)
	(segment
		(start 64.27597 -306.763928)
		(end 64.44107 -306.763928)
		(width 0.10668)
		(layer "F.Cu")
		(net "M_A_CPU1_SB_DQ<24>")
	)
	(segment
		(start 76.199238 -288.646616)
		(end 75.986386 -288.433764)
		(width 0.0762)
		(layer "F.Cu")
		(net "M_A_CPU1_SB_DQ<24>")
	)
	(segment
		(start 72.356472 -298.119038)
		(end 61.94679 -308.52872)
		(width 0.10668)
		(layer "F.Cu")
		(net "M_A_CPU1_SB_DQ<24>")
	)
	(segment
		(start 78.237842 -288.400236)
		(end 78.33614 -288.5694)
		(width 0.0762)
		(layer "F.Cu")
		(net "M_A_CPU1_SB_DQ<24>")
	)
	(segment
		(start 64.558164 -306.881022)
		(end 64.558164 -307.046122)
		(width 0.10668)
		(layer "F.Cu")
		(net "M_A_CPU1_SB_DQ<24>")
	)
	(segment
		(start 77.767942 -288.646616)
		(end 76.199238 -288.646616)
		(width 0.0762)
		(layer "F.Cu")
		(net "M_A_CPU1_SB_DQ<24>")
	)
	(segment
		(start 60.940188 -309.535322)
		(end 59.428126 -309.535322)
		(width 0.10668)
		(layer "F.Cu")
		(net "M_A_CPU1_SB_DQ<24>")
	)
	(segment
		(start 61.499496 -308.976014)
		(end 60.940188 -309.535322)
		(width 0.10668)
		(layer "F.Cu")
		(net "M_A_CPU1_SB_DQ<24>")
	)
	(segment
		(start 75.275186 -288.433764)
		(end 72.356472 -291.352478)
		(width 0.10668)
		(layer "F.Cu")
		(net "M_A_CPU1_SB_DQ<24>")
	)
	(arc
		(start 78.050898 -288.722816)
		(mid 77.914462 -288.665991)
		(end 77.767942 -288.646616)
		(width 0.0762)
		(layer "F.Cu")
		(net "M_A_CPU1_SB_DQ<24>")
	)
	(arc
		(start 78.33614 -288.5694)
		(mid 78.327547 -288.711279)
		(end 78.198472 -288.771076)
		(width 0.0762)
		(layer "F.Cu")
		(net "M_A_CPU1_SB_DQ<24>")
	)
	(arc
		(start 78.198472 -288.771076)
		(mid 78.126734 -288.756224)
		(end 78.05928 -288.727642)
		(width 0.0762)
		(layer "F.Cu")
		(net "M_A_CPU1_SB_DQ<24>")
	)
	(segment
		(start 61.263784 -308.260242)
		(end 60.725812 -308.260242)
		(width 0.10668)
		(layer "F.Cu")
		(net "M_A_CPU1_SB_DQ<23>")
	)
	(segment
		(start 71.899272 -297.624754)
		(end 61.263784 -308.260242)
		(width 0.10668)
		(layer "F.Cu")
		(net "M_A_CPU1_SB_DQ<23>")
	)
	(segment
		(start 75.085702 -287.976564)
		(end 71.899272 -291.162994)
		(width 0.10668)
		(layer "F.Cu")
		(net "M_A_CPU1_SB_DQ<23>")
	)
	(segment
		(start 58.199274 -308.260242)
		(end 57.774078 -308.685438)
		(width 0.101346)
		(layer "F.Cu")
		(net "M_A_CPU1_SB_DQ<23>")
	)
	(segment
		(start 75.986386 -287.976564)
		(end 75.085702 -287.976564)
		(width 0.10668)
		(layer "F.Cu")
		(net "M_A_CPU1_SB_DQ<23>")
	)
	(segment
		(start 77.768196 -288.15411)
		(end 76.697332 -288.15411)
		(width 0.0762)
		(layer "F.Cu")
		(net "M_A_CPU1_SB_DQ<23>")
	)
	(segment
		(start 60.725812 -308.260242)
		(end 58.199274 -308.260242)
		(width 0.101346)
		(layer "F.Cu")
		(net "M_A_CPU1_SB_DQ<23>")
	)
	(segment
		(start 57.774078 -308.685438)
		(end 55.328058 -308.685438)
		(width 0.101346)
		(layer "F.Cu")
		(net "M_A_CPU1_SB_DQ<23>")
	)
	(segment
		(start 76.697332 -288.15411)
		(end 76.519786 -287.976564)
		(width 0.0762)
		(layer "F.Cu")
		(net "M_A_CPU1_SB_DQ<23>")
	)
	(segment
		(start 76.519786 -287.976564)
		(end 75.986386 -287.976564)
		(width 0.0762)
		(layer "F.Cu")
		(net "M_A_CPU1_SB_DQ<23>")
	)
	(segment
		(start 78.05928 -288.073084)
		(end 78.050898 -288.07791)
		(width 0.0762)
		(layer "F.Cu")
		(net "M_A_CPU1_SB_DQ<23>")
	)
	(segment
		(start 71.899272 -291.162994)
		(end 71.899272 -297.624754)
		(width 0.10668)
		(layer "F.Cu")
		(net "M_A_CPU1_SB_DQ<23>")
	)
	(arc
		(start 77.815186 -288.152332)
		(mid 77.791709 -288.153708)
		(end 77.768196 -288.15411)
		(width 0.0762)
		(layer "F.Cu")
		(net "M_A_CPU1_SB_DQ<23>")
	)
	(arc
		(start 78.990952 -288.07791)
		(mid 78.707996 -288.154087)
		(end 78.42504 -288.07791)
		(width 0.0762)
		(layer "F.Cu")
		(net "M_A_CPU1_SB_DQ<23>")
	)
	(arc
		(start 80.11795 -288.400236)
		(mid 79.880299 -288.229404)
		(end 79.598012 -288.152078)
		(width 0.0762)
		(layer "F.Cu")
		(net "M_A_CPU1_SB_DQ<23>")
	)
	(arc
		(start 79.598012 -288.152078)
		(mid 79.477363 -288.127777)
		(end 79.36484 -288.07791)
		(width 0.0762)
		(layer "F.Cu")
		(net "M_A_CPU1_SB_DQ<23>")
	)
	(arc
		(start 78.050898 -288.07791)
		(mid 77.937174 -288.128211)
		(end 77.815186 -288.152332)
		(width 0.0762)
		(layer "F.Cu")
		(net "M_A_CPU1_SB_DQ<23>")
	)
	(arc
		(start 79.36484 -288.07791)
		(mid 79.177896 -288.027655)
		(end 78.990952 -288.07791)
		(width 0.0762)
		(layer "F.Cu")
		(net "M_A_CPU1_SB_DQ<23>")
	)
	(arc
		(start 78.42504 -288.07791)
		(mid 78.242789 -288.02756)
		(end 78.05928 -288.073084)
		(width 0.0762)
		(layer "F.Cu")
		(net "M_A_CPU1_SB_DQ<23>")
	)
	(segment
		(start 62.684914 -305.5747)
		(end 62.239652 -305.573938)
		(width 0.10668)
		(layer "F.Cu")
		(net "M_A_CPU1_SB_DQ<22>")
	)
	(segment
		(start 60.670186 -306.56022)
		(end 58.199274 -306.56022)
		(width 0.101346)
		(layer "F.Cu")
		(net "M_A_CPU1_SB_DQ<22>")
	)
	(segment
		(start 60.726066 -306.56022)
		(end 60.725812 -306.560474)
		(width 0.10668)
		(layer "F.Cu")
		(net "M_A_CPU1_SB_DQ<22>")
	)
	(segment
		(start 71.218552 -290.880546)
		(end 71.218552 -297.041062)
		(width 0.10668)
		(layer "F.Cu")
		(net "M_A_CPU1_SB_DQ<22>")
	)
	(segment
		(start 56.65851 -306.985416)
		(end 55.328058 -306.985416)
		(width 0.101346)
		(layer "F.Cu")
		(net "M_A_CPU1_SB_DQ<22>")
	)
	(segment
		(start 58.199274 -306.56022)
		(end 57.561988 -307.197506)
		(width 0.101346)
		(layer "F.Cu")
		(net "M_A_CPU1_SB_DQ<22>")
	)
	(segment
		(start 61.171074 -306.849526)
		(end 61.064394 -306.742846)
		(width 0.10668)
		(layer "F.Cu")
		(net "M_A_CPU1_SB_DQ<22>")
	)
	(segment
		(start 62.076838 -306.178712)
		(end 61.925962 -306.178712)
		(width 0.10668)
		(layer "F.Cu")
		(net "M_A_CPU1_SB_DQ<22>")
	)
	(segment
		(start 61.855858 -306.108608)
		(end 61.704982 -306.108608)
		(width 0.10668)
		(layer "F.Cu")
		(net "M_A_CPU1_SB_DQ<22>")
	)
	(segment
		(start 61.925962 -306.178712)
		(end 61.855858 -306.108608)
		(width 0.10668)
		(layer "F.Cu")
		(net "M_A_CPU1_SB_DQ<22>")
	)
	(segment
		(start 62.138052 -305.826414)
		(end 62.208156 -305.896518)
		(width 0.10668)
		(layer "F.Cu")
		(net "M_A_CPU1_SB_DQ<22>")
	)
	(segment
		(start 61.463428 -306.742846)
		(end 61.356748 -306.849526)
		(width 0.10668)
		(layer "F.Cu")
		(net "M_A_CPU1_SB_DQ<22>")
	)
	(segment
		(start 71.218552 -297.041062)
		(end 62.684914 -305.5747)
		(width 0.10668)
		(layer "F.Cu")
		(net "M_A_CPU1_SB_DQ<22>")
	)
	(segment
		(start 61.064394 -306.742846)
		(end 61.064394 -306.6669)
		(width 0.10668)
		(layer "F.Cu")
		(net "M_A_CPU1_SB_DQ<22>")
	)
	(segment
		(start 62.239652 -305.573938)
		(end 62.138052 -305.675538)
		(width 0.10668)
		(layer "F.Cu")
		(net "M_A_CPU1_SB_DQ<22>")
	)
	(segment
		(start 61.356748 -306.849526)
		(end 61.171074 -306.849526)
		(width 0.10668)
		(layer "F.Cu")
		(net "M_A_CPU1_SB_DQ<22>")
	)
	(segment
		(start 74.935334 -287.163764)
		(end 71.218552 -290.880546)
		(width 0.10668)
		(layer "F.Cu")
		(net "M_A_CPU1_SB_DQ<22>")
	)
	(segment
		(start 60.67044 -306.560474)
		(end 60.670186 -306.56022)
		(width 0.101346)
		(layer "F.Cu")
		(net "M_A_CPU1_SB_DQ<22>")
	)
	(segment
		(start 62.138052 -305.675538)
		(end 62.138052 -305.826414)
		(width 0.10668)
		(layer "F.Cu")
		(net "M_A_CPU1_SB_DQ<22>")
	)
	(segment
		(start 57.561988 -307.197506)
		(end 56.8706 -307.197506)
		(width 0.101346)
		(layer "F.Cu")
		(net "M_A_CPU1_SB_DQ<22>")
	)
	(segment
		(start 56.8706 -307.197506)
		(end 56.65851 -306.985416)
		(width 0.101346)
		(layer "F.Cu")
		(net "M_A_CPU1_SB_DQ<22>")
	)
	(segment
		(start 61.064394 -306.6669)
		(end 60.957714 -306.56022)
		(width 0.10668)
		(layer "F.Cu")
		(net "M_A_CPU1_SB_DQ<22>")
	)
	(segment
		(start 61.704982 -306.108608)
		(end 61.463428 -306.350162)
		(width 0.10668)
		(layer "F.Cu")
		(net "M_A_CPU1_SB_DQ<22>")
	)
	(segment
		(start 61.463428 -306.350162)
		(end 61.463428 -306.742846)
		(width 0.10668)
		(layer "F.Cu")
		(net "M_A_CPU1_SB_DQ<22>")
	)
	(segment
		(start 75.960986 -287.163764)
		(end 74.935334 -287.163764)
		(width 0.10668)
		(layer "F.Cu")
		(net "M_A_CPU1_SB_DQ<22>")
	)
	(segment
		(start 76.01458 -287.217358)
		(end 75.960986 -287.163764)
		(width 0.0762)
		(layer "F.Cu")
		(net "M_A_CPU1_SB_DQ<22>")
	)
	(segment
		(start 60.725812 -306.560474)
		(end 60.67044 -306.560474)
		(width 0.101346)
		(layer "F.Cu")
		(net "M_A_CPU1_SB_DQ<22>")
	)
	(segment
		(start 60.957714 -306.56022)
		(end 60.726066 -306.56022)
		(width 0.10668)
		(layer "F.Cu")
		(net "M_A_CPU1_SB_DQ<22>")
	)
	(segment
		(start 62.208156 -306.047394)
		(end 62.076838 -306.178712)
		(width 0.10668)
		(layer "F.Cu")
		(net "M_A_CPU1_SB_DQ<22>")
	)
	(segment
		(start 62.208156 -305.896518)
		(end 62.208156 -306.047394)
		(width 0.10668)
		(layer "F.Cu")
		(net "M_A_CPU1_SB_DQ<22>")
	)
	(segment
		(start 77.767942 -287.217358)
		(end 76.01458 -287.217358)
		(width 0.0762)
		(layer "F.Cu")
		(net "M_A_CPU1_SB_DQ<22>")
	)
	(arc
		(start 78.707996 -287.590484)
		(mid 78.465679 -287.420764)
		(end 78.180692 -287.34131)
		(width 0.0762)
		(layer "F.Cu")
		(net "M_A_CPU1_SB_DQ<22>")
	)
	(arc
		(start 78.180692 -287.34131)
		(mid 78.063879 -287.316634)
		(end 77.954886 -287.267904)
		(width 0.0762)
		(layer "F.Cu")
		(net "M_A_CPU1_SB_DQ<22>")
	)
	(arc
		(start 77.954886 -287.267904)
		(mid 77.864753 -287.230284)
		(end 77.767942 -287.217358)
		(width 0.0762)
		(layer "F.Cu")
		(net "M_A_CPU1_SB_DQ<22>")
	)
	(segment
		(start 62.177168 -306.865274)
		(end 61.875924 -306.865274)
		(width 0.10668)
		(layer "F.Cu")
		(net "M_A_CPU1_SB_DQ<21>")
	)
	(segment
		(start 68.517008 -300.22419)
		(end 68.517008 -300.525434)
		(width 0.10668)
		(layer "F.Cu")
		(net "M_A_CPU1_SB_DQ<21>")
	)
	(segment
		(start 67.25666 -301.785782)
		(end 66.955416 -301.785782)
		(width 0.10668)
		(layer "F.Cu")
		(net "M_A_CPU1_SB_DQ<21>")
	)
	(segment
		(start 70.77456 -298.267882)
		(end 70.642988 -298.399454)
		(width 0.10668)
		(layer "F.Cu")
		(net "M_A_CPU1_SB_DQ<21>")
	)
	(segment
		(start 60.88126 -307.479192)
		(end 60.996322 -307.594254)
		(width 0.10668)
		(layer "F.Cu")
		(net "M_A_CPU1_SB_DQ<21>")
	)
	(segment
		(start 64.566292 -304.47615)
		(end 64.43472 -304.607722)
		(width 0.10668)
		(layer "F.Cu")
		(net "M_A_CPU1_SB_DQ<21>")
	)
	(segment
		(start 67.95262 -301.089822)
		(end 67.821048 -301.221394)
		(width 0.10668)
		(layer "F.Cu")
		(net "M_A_CPU1_SB_DQ<21>")
	)
	(segment
		(start 70.341744 -298.399454)
		(end 70.210172 -298.531026)
		(width 0.10668)
		(layer "F.Cu")
		(net "M_A_CPU1_SB_DQ<21>")
	)
	(segment
		(start 64.001904 -305.040538)
		(end 63.870332 -305.17211)
		(width 0.10668)
		(layer "F.Cu")
		(net "M_A_CPU1_SB_DQ<21>")
	)
	(segment
		(start 68.517008 -300.525434)
		(end 68.385436 -300.657006)
		(width 0.10668)
		(layer "F.Cu")
		(net "M_A_CPU1_SB_DQ<21>")
	)
	(segment
		(start 65.13068 -303.610518)
		(end 65.13068 -303.911762)
		(width 0.10668)
		(layer "F.Cu")
		(net "M_A_CPU1_SB_DQ<21>")
	)
	(segment
		(start 62.440312 -306.300886)
		(end 62.30874 -306.432458)
		(width 0.10668)
		(layer "F.Cu")
		(net "M_A_CPU1_SB_DQ<21>")
	)
	(segment
		(start 69.645784 -299.095414)
		(end 69.645784 -299.396658)
		(width 0.10668)
		(layer "F.Cu")
		(net "M_A_CPU1_SB_DQ<21>")
	)
	(segment
		(start 68.084192 -300.657006)
		(end 67.95262 -300.788578)
		(width 0.10668)
		(layer "F.Cu")
		(net "M_A_CPU1_SB_DQ<21>")
	)
	(segment
		(start 63.305944 -305.736498)
		(end 63.0047 -305.736498)
		(width 0.10668)
		(layer "F.Cu")
		(net "M_A_CPU1_SB_DQ<21>")
	)
	(segment
		(start 63.437516 -305.303682)
		(end 63.437516 -305.604926)
		(width 0.10668)
		(layer "F.Cu")
		(net "M_A_CPU1_SB_DQ<21>")
	)
	(segment
		(start 65.262252 -303.478946)
		(end 65.13068 -303.610518)
		(width 0.10668)
		(layer "F.Cu")
		(net "M_A_CPU1_SB_DQ<21>")
	)
	(segment
		(start 69.212968 -299.52823)
		(end 69.081396 -299.659802)
		(width 0.10668)
		(layer "F.Cu")
		(net "M_A_CPU1_SB_DQ<21>")
	)
	(segment
		(start 71.558912 -291.02177)
		(end 71.558912 -297.182286)
		(width 0.10668)
		(layer "F.Cu")
		(net "M_A_CPU1_SB_DQ<21>")
	)
	(segment
		(start 64.566292 -304.174906)
		(end 64.566292 -304.47615)
		(width 0.10668)
		(layer "F.Cu")
		(net "M_A_CPU1_SB_DQ<21>")
	)
	(segment
		(start 64.999108 -304.043334)
		(end 64.697864 -304.043334)
		(width 0.10668)
		(layer "F.Cu")
		(net "M_A_CPU1_SB_DQ<21>")
	)
	(segment
		(start 61.875924 -306.865274)
		(end 61.429392 -307.311806)
		(width 0.10668)
		(layer "F.Cu")
		(net "M_A_CPU1_SB_DQ<21>")
	)
	(segment
		(start 67.519804 -301.221394)
		(end 67.388232 -301.352966)
		(width 0.10668)
		(layer "F.Cu")
		(net "M_A_CPU1_SB_DQ<21>")
	)
	(segment
		(start 68.385436 -300.657006)
		(end 68.084192 -300.657006)
		(width 0.10668)
		(layer "F.Cu")
		(net "M_A_CPU1_SB_DQ<21>")
	)
	(segment
		(start 63.0047 -305.736498)
		(end 62.873128 -305.86807)
		(width 0.10668)
		(layer "F.Cu")
		(net "M_A_CPU1_SB_DQ<21>")
	)
	(segment
		(start 60.996322 -307.594254)
		(end 60.996576 -307.744622)
		(width 0.10668)
		(layer "F.Cu")
		(net "M_A_CPU1_SB_DQ<21>")
	)
	(segment
		(start 67.388232 -301.352966)
		(end 67.388232 -301.65421)
		(width 0.10668)
		(layer "F.Cu")
		(net "M_A_CPU1_SB_DQ<21>")
	)
	(segment
		(start 65.695068 -303.04613)
		(end 65.695068 -303.347374)
		(width 0.10668)
		(layer "F.Cu")
		(net "M_A_CPU1_SB_DQ<21>")
	)
	(segment
		(start 69.777356 -298.963842)
		(end 69.645784 -299.095414)
		(width 0.10668)
		(layer "F.Cu")
		(net "M_A_CPU1_SB_DQ<21>")
	)
	(segment
		(start 60.905898 -307.8353)
		(end 59.428126 -307.8353)
		(width 0.10668)
		(layer "F.Cu")
		(net "M_A_CPU1_SB_DQ<21>")
	)
	(segment
		(start 64.43472 -304.607722)
		(end 64.133476 -304.607722)
		(width 0.10668)
		(layer "F.Cu")
		(net "M_A_CPU1_SB_DQ<21>")
	)
	(segment
		(start 68.64858 -300.092618)
		(end 68.517008 -300.22419)
		(width 0.10668)
		(layer "F.Cu")
		(net "M_A_CPU1_SB_DQ<21>")
	)
	(segment
		(start 63.437516 -305.604926)
		(end 63.305944 -305.736498)
		(width 0.10668)
		(layer "F.Cu")
		(net "M_A_CPU1_SB_DQ<21>")
	)
	(segment
		(start 70.906132 -297.835066)
		(end 70.77456 -297.966638)
		(width 0.10668)
		(layer "F.Cu")
		(net "M_A_CPU1_SB_DQ<21>")
	)
	(segment
		(start 69.081396 -299.961046)
		(end 68.949824 -300.092618)
		(width 0.10668)
		(layer "F.Cu")
		(net "M_A_CPU1_SB_DQ<21>")
	)
	(segment
		(start 65.563496 -303.478946)
		(end 65.262252 -303.478946)
		(width 0.10668)
		(layer "F.Cu")
		(net "M_A_CPU1_SB_DQ<21>")
	)
	(segment
		(start 66.259456 -302.481742)
		(end 66.259456 -302.782986)
		(width 0.10668)
		(layer "F.Cu")
		(net "M_A_CPU1_SB_DQ<21>")
	)
	(segment
		(start 70.210172 -298.531026)
		(end 70.210172 -298.83227)
		(width 0.10668)
		(layer "F.Cu")
		(net "M_A_CPU1_SB_DQ<21>")
	)
	(segment
		(start 66.127884 -302.914558)
		(end 65.82664 -302.914558)
		(width 0.10668)
		(layer "F.Cu")
		(net "M_A_CPU1_SB_DQ<21>")
	)
	(segment
		(start 63.569088 -305.17211)
		(end 63.437516 -305.303682)
		(width 0.10668)
		(layer "F.Cu")
		(net "M_A_CPU1_SB_DQ<21>")
	)
	(segment
		(start 69.081396 -299.659802)
		(end 69.081396 -299.961046)
		(width 0.10668)
		(layer "F.Cu")
		(net "M_A_CPU1_SB_DQ<21>")
	)
	(segment
		(start 65.13068 -303.911762)
		(end 64.999108 -304.043334)
		(width 0.10668)
		(layer "F.Cu")
		(net "M_A_CPU1_SB_DQ<21>")
	)
	(segment
		(start 66.955416 -301.785782)
		(end 66.823844 -301.917354)
		(width 0.10668)
		(layer "F.Cu")
		(net "M_A_CPU1_SB_DQ<21>")
	)
	(segment
		(start 65.82664 -302.914558)
		(end 65.695068 -303.04613)
		(width 0.10668)
		(layer "F.Cu")
		(net "M_A_CPU1_SB_DQ<21>")
	)
	(segment
		(start 76.836778 -287.96361)
		(end 76.468986 -287.595818)
		(width 0.0762)
		(layer "F.Cu")
		(net "M_A_CPU1_SB_DQ<21>")
	)
	(segment
		(start 61.429392 -307.311806)
		(end 61.278516 -307.311806)
		(width 0.10668)
		(layer "F.Cu")
		(net "M_A_CPU1_SB_DQ<21>")
	)
	(segment
		(start 62.873128 -305.86807)
		(end 62.873128 -306.169314)
		(width 0.10668)
		(layer "F.Cu")
		(net "M_A_CPU1_SB_DQ<21>")
	)
	(segment
		(start 69.645784 -299.396658)
		(end 69.514212 -299.52823)
		(width 0.10668)
		(layer "F.Cu")
		(net "M_A_CPU1_SB_DQ<21>")
	)
	(segment
		(start 62.30874 -306.733702)
		(end 62.177168 -306.865274)
		(width 0.10668)
		(layer "F.Cu")
		(net "M_A_CPU1_SB_DQ<21>")
	)
	(segment
		(start 71.558912 -297.182286)
		(end 71.338948 -297.40225)
		(width 0.10668)
		(layer "F.Cu")
		(net "M_A_CPU1_SB_DQ<21>")
	)
	(segment
		(start 75.960986 -287.595818)
		(end 74.984864 -287.595818)
		(width 0.10668)
		(layer "F.Cu")
		(net "M_A_CPU1_SB_DQ<21>")
	)
	(segment
		(start 76.468986 -287.595818)
		(end 75.960986 -287.595818)
		(width 0.0762)
		(layer "F.Cu")
		(net "M_A_CPU1_SB_DQ<21>")
	)
	(segment
		(start 79.647796 -287.590484)
		(end 79.748634 -287.763966)
		(width 0.0762)
		(layer "F.Cu")
		(net "M_A_CPU1_SB_DQ<21>")
	)
	(segment
		(start 67.821048 -301.221394)
		(end 67.519804 -301.221394)
		(width 0.10668)
		(layer "F.Cu")
		(net "M_A_CPU1_SB_DQ<21>")
	)
	(segment
		(start 67.388232 -301.65421)
		(end 67.25666 -301.785782)
		(width 0.10668)
		(layer "F.Cu")
		(net "M_A_CPU1_SB_DQ<21>")
	)
	(segment
		(start 68.949824 -300.092618)
		(end 68.64858 -300.092618)
		(width 0.10668)
		(layer "F.Cu")
		(net "M_A_CPU1_SB_DQ<21>")
	)
	(segment
		(start 70.210172 -298.83227)
		(end 70.0786 -298.963842)
		(width 0.10668)
		(layer "F.Cu")
		(net "M_A_CPU1_SB_DQ<21>")
	)
	(segment
		(start 64.001904 -304.739294)
		(end 64.001904 -305.040538)
		(width 0.10668)
		(layer "F.Cu")
		(net "M_A_CPU1_SB_DQ<21>")
	)
	(segment
		(start 66.259456 -302.782986)
		(end 66.127884 -302.914558)
		(width 0.10668)
		(layer "F.Cu")
		(net "M_A_CPU1_SB_DQ<21>")
	)
	(segment
		(start 62.873128 -306.169314)
		(end 62.741556 -306.300886)
		(width 0.10668)
		(layer "F.Cu")
		(net "M_A_CPU1_SB_DQ<21>")
	)
	(segment
		(start 63.870332 -305.17211)
		(end 63.569088 -305.17211)
		(width 0.10668)
		(layer "F.Cu")
		(net "M_A_CPU1_SB_DQ<21>")
	)
	(segment
		(start 62.30874 -306.432458)
		(end 62.30874 -306.733702)
		(width 0.10668)
		(layer "F.Cu")
		(net "M_A_CPU1_SB_DQ<21>")
	)
	(segment
		(start 70.77456 -297.966638)
		(end 70.77456 -298.267882)
		(width 0.10668)
		(layer "F.Cu")
		(net "M_A_CPU1_SB_DQ<21>")
	)
	(segment
		(start 69.514212 -299.52823)
		(end 69.212968 -299.52823)
		(width 0.10668)
		(layer "F.Cu")
		(net "M_A_CPU1_SB_DQ<21>")
	)
	(segment
		(start 70.642988 -298.399454)
		(end 70.341744 -298.399454)
		(width 0.10668)
		(layer "F.Cu")
		(net "M_A_CPU1_SB_DQ<21>")
	)
	(segment
		(start 71.207376 -297.835066)
		(end 70.906132 -297.835066)
		(width 0.10668)
		(layer "F.Cu")
		(net "M_A_CPU1_SB_DQ<21>")
	)
	(segment
		(start 66.823844 -302.218598)
		(end 66.692272 -302.35017)
		(width 0.10668)
		(layer "F.Cu")
		(net "M_A_CPU1_SB_DQ<21>")
	)
	(segment
		(start 60.88126 -307.328316)
		(end 60.88126 -307.479192)
		(width 0.10668)
		(layer "F.Cu")
		(net "M_A_CPU1_SB_DQ<21>")
	)
	(segment
		(start 66.391028 -302.35017)
		(end 66.259456 -302.481742)
		(width 0.10668)
		(layer "F.Cu")
		(net "M_A_CPU1_SB_DQ<21>")
	)
	(segment
		(start 79.469234 -287.91789)
		(end 79.460852 -287.913064)
		(width 0.0762)
		(layer "F.Cu")
		(net "M_A_CPU1_SB_DQ<21>")
	)
	(segment
		(start 60.996576 -307.744622)
		(end 60.905898 -307.8353)
		(width 0.10668)
		(layer "F.Cu")
		(net "M_A_CPU1_SB_DQ<21>")
	)
	(segment
		(start 78.89494 -287.913064)
		(end 78.886558 -287.91789)
		(width 0.0762)
		(layer "F.Cu")
		(net "M_A_CPU1_SB_DQ<21>")
	)
	(segment
		(start 64.133476 -304.607722)
		(end 64.001904 -304.739294)
		(width 0.10668)
		(layer "F.Cu")
		(net "M_A_CPU1_SB_DQ<21>")
	)
	(segment
		(start 71.338948 -297.40225)
		(end 71.338948 -297.703494)
		(width 0.10668)
		(layer "F.Cu")
		(net "M_A_CPU1_SB_DQ<21>")
	)
	(segment
		(start 71.338948 -297.703494)
		(end 71.207376 -297.835066)
		(width 0.10668)
		(layer "F.Cu")
		(net "M_A_CPU1_SB_DQ<21>")
	)
	(segment
		(start 77.767942 -287.96361)
		(end 76.836778 -287.96361)
		(width 0.0762)
		(layer "F.Cu")
		(net "M_A_CPU1_SB_DQ<21>")
	)
	(segment
		(start 70.0786 -298.963842)
		(end 69.777356 -298.963842)
		(width 0.10668)
		(layer "F.Cu")
		(net "M_A_CPU1_SB_DQ<21>")
	)
	(segment
		(start 66.823844 -301.917354)
		(end 66.823844 -302.218598)
		(width 0.10668)
		(layer "F.Cu")
		(net "M_A_CPU1_SB_DQ<21>")
	)
	(segment
		(start 66.692272 -302.35017)
		(end 66.391028 -302.35017)
		(width 0.10668)
		(layer "F.Cu")
		(net "M_A_CPU1_SB_DQ<21>")
	)
	(segment
		(start 61.278516 -307.311806)
		(end 61.163454 -307.196744)
		(width 0.10668)
		(layer "F.Cu")
		(net "M_A_CPU1_SB_DQ<21>")
	)
	(segment
		(start 61.163454 -307.196744)
		(end 61.012578 -307.196998)
		(width 0.10668)
		(layer "F.Cu")
		(net "M_A_CPU1_SB_DQ<21>")
	)
	(segment
		(start 62.741556 -306.300886)
		(end 62.440312 -306.300886)
		(width 0.10668)
		(layer "F.Cu")
		(net "M_A_CPU1_SB_DQ<21>")
	)
	(segment
		(start 64.697864 -304.043334)
		(end 64.566292 -304.174906)
		(width 0.10668)
		(layer "F.Cu")
		(net "M_A_CPU1_SB_DQ<21>")
	)
	(segment
		(start 67.95262 -300.788578)
		(end 67.95262 -301.089822)
		(width 0.10668)
		(layer "F.Cu")
		(net "M_A_CPU1_SB_DQ<21>")
	)
	(segment
		(start 61.012578 -307.196998)
		(end 60.88126 -307.328316)
		(width 0.10668)
		(layer "F.Cu")
		(net "M_A_CPU1_SB_DQ<21>")
	)
	(segment
		(start 65.695068 -303.347374)
		(end 65.563496 -303.478946)
		(width 0.10668)
		(layer "F.Cu")
		(net "M_A_CPU1_SB_DQ<21>")
	)
	(segment
		(start 74.984864 -287.595818)
		(end 71.558912 -291.02177)
		(width 0.10668)
		(layer "F.Cu")
		(net "M_A_CPU1_SB_DQ<21>")
	)
	(arc
		(start 78.520798 -287.913064)
		(mid 78.237842 -287.836887)
		(end 77.954886 -287.913064)
		(width 0.0762)
		(layer "F.Cu")
		(net "M_A_CPU1_SB_DQ<21>")
	)
	(arc
		(start 79.748634 -287.763966)
		(mid 79.732709 -287.904658)
		(end 79.602584 -287.960562)
		(width 0.0762)
		(layer "F.Cu")
		(net "M_A_CPU1_SB_DQ<21>")
	)
	(arc
		(start 78.886558 -287.91789)
		(mid 78.70305 -287.963384)
		(end 78.520798 -287.913064)
		(width 0.0762)
		(layer "F.Cu")
		(net "M_A_CPU1_SB_DQ<21>")
	)
	(arc
		(start 79.602584 -287.960562)
		(mid 79.533886 -287.945546)
		(end 79.469234 -287.91789)
		(width 0.0762)
		(layer "F.Cu")
		(net "M_A_CPU1_SB_DQ<21>")
	)
	(arc
		(start 77.954886 -287.913064)
		(mid 77.879646 -287.946377)
		(end 77.79893 -287.96234)
		(width 0.0762)
		(layer "F.Cu")
		(net "M_A_CPU1_SB_DQ<21>")
	)
	(arc
		(start 77.79893 -287.96234)
		(mid 77.783449 -287.963296)
		(end 77.767942 -287.96361)
		(width 0.0762)
		(layer "F.Cu")
		(net "M_A_CPU1_SB_DQ<21>")
	)
	(arc
		(start 79.460852 -287.913064)
		(mid 79.177896 -287.836887)
		(end 78.89494 -287.913064)
		(width 0.0762)
		(layer "F.Cu")
		(net "M_A_CPU1_SB_DQ<21>")
	)
	(segment
		(start 67.754754 -299.872146)
		(end 67.754754 -300.023022)
		(width 0.10668)
		(layer "F.Cu")
		(net "M_A_CPU1_SB_DQ<20>")
	)
	(segment
		(start 65.424812 -302.057308)
		(end 65.497202 -302.129698)
		(width 0.10668)
		(layer "F.Cu")
		(net "M_A_CPU1_SB_DQ<20>")
	)
	(segment
		(start 63.23965 -304.538126)
		(end 63.108332 -304.669444)
		(width 0.10668)
		(layer "F.Cu")
		(net "M_A_CPU1_SB_DQ<20>")
	)
	(segment
		(start 69.939916 -297.391328)
		(end 69.939916 -297.542204)
		(width 0.10668)
		(layer "F.Cu")
		(net "M_A_CPU1_SB_DQ<20>")
	)
	(segment
		(start 64.237108 -303.540668)
		(end 64.086232 -303.540668)
		(width 0.10668)
		(layer "F.Cu")
		(net "M_A_CPU1_SB_DQ<20>")
	)
	(segment
		(start 69.939916 -297.542204)
		(end 70.012306 -297.614594)
		(width 0.10668)
		(layer "F.Cu")
		(net "M_A_CPU1_SB_DQ<20>")
	)
	(segment
		(start 65.424812 -301.906432)
		(end 65.424812 -302.057308)
		(width 0.10668)
		(layer "F.Cu")
		(net "M_A_CPU1_SB_DQ<20>")
	)
	(segment
		(start 64.086232 -303.540668)
		(end 64.013842 -303.468278)
		(width 0.10668)
		(layer "F.Cu")
		(net "M_A_CPU1_SB_DQ<20>")
	)
	(segment
		(start 67.190366 -300.436534)
		(end 67.190366 -300.58741)
		(width 0.10668)
		(layer "F.Cu")
		(net "M_A_CPU1_SB_DQ<20>")
	)
	(segment
		(start 70.878192 -296.453052)
		(end 70.504304 -296.82694)
		(width 0.10668)
		(layer "F.Cu")
		(net "M_A_CPU1_SB_DQ<20>")
	)
	(segment
		(start 66.835782 -300.646338)
		(end 66.684906 -300.646338)
		(width 0.10668)
		(layer "F.Cu")
		(net "M_A_CPU1_SB_DQ<20>")
	)
	(segment
		(start 67.059048 -300.718728)
		(end 66.908172 -300.718728)
		(width 0.10668)
		(layer "F.Cu")
		(net "M_A_CPU1_SB_DQ<20>")
	)
	(segment
		(start 65.215008 -302.411892)
		(end 65.142618 -302.339502)
		(width 0.10668)
		(layer "F.Cu")
		(net "M_A_CPU1_SB_DQ<20>")
	)
	(segment
		(start 68.601336 -299.025564)
		(end 68.528946 -298.953174)
		(width 0.10668)
		(layer "F.Cu")
		(net "M_A_CPU1_SB_DQ<20>")
	)
	(segment
		(start 68.319142 -299.458634)
		(end 68.187824 -299.589952)
		(width 0.10668)
		(layer "F.Cu")
		(net "M_A_CPU1_SB_DQ<20>")
	)
	(segment
		(start 63.108332 -304.669444)
		(end 62.957456 -304.669444)
		(width 0.10668)
		(layer "F.Cu")
		(net "M_A_CPU1_SB_DQ<20>")
	)
	(segment
		(start 67.964558 -299.517562)
		(end 67.813682 -299.517562)
		(width 0.10668)
		(layer "F.Cu")
		(net "M_A_CPU1_SB_DQ<20>")
	)
	(segment
		(start 68.187824 -299.589952)
		(end 68.036948 -299.589952)
		(width 0.10668)
		(layer "F.Cu")
		(net "M_A_CPU1_SB_DQ<20>")
	)
	(segment
		(start 63.16726 -304.163984)
		(end 63.16726 -304.31486)
		(width 0.10668)
		(layer "F.Cu")
		(net "M_A_CPU1_SB_DQ<20>")
	)
	(segment
		(start 67.249294 -300.08195)
		(end 67.117976 -300.213268)
		(width 0.10668)
		(layer "F.Cu")
		(net "M_A_CPU1_SB_DQ<20>")
	)
	(segment
		(start 62.73419 -304.597054)
		(end 62.602872 -304.728372)
		(width 0.10668)
		(layer "F.Cu")
		(net "M_A_CPU1_SB_DQ<20>")
	)
	(segment
		(start 70.504304 -296.82694)
		(end 70.504304 -296.977816)
		(width 0.10668)
		(layer "F.Cu")
		(net "M_A_CPU1_SB_DQ<20>")
	)
	(segment
		(start 63.731648 -303.599596)
		(end 63.731648 -303.750472)
		(width 0.10668)
		(layer "F.Cu")
		(net "M_A_CPU1_SB_DQ<20>")
	)
	(segment
		(start 66.625978 -301.151798)
		(end 66.49466 -301.283116)
		(width 0.10668)
		(layer "F.Cu")
		(net "M_A_CPU1_SB_DQ<20>")
	)
	(segment
		(start 68.81114 -298.67098)
		(end 68.88353 -298.74337)
		(width 0.10668)
		(layer "F.Cu")
		(net "M_A_CPU1_SB_DQ<20>")
	)
	(segment
		(start 63.862966 -303.468278)
		(end 63.731648 -303.599596)
		(width 0.10668)
		(layer "F.Cu")
		(net "M_A_CPU1_SB_DQ<20>")
	)
	(segment
		(start 69.093334 -298.388786)
		(end 68.942458 -298.388786)
		(width 0.10668)
		(layer "F.Cu")
		(net "M_A_CPU1_SB_DQ<20>")
	)
	(segment
		(start 68.752212 -299.025564)
		(end 68.601336 -299.025564)
		(width 0.10668)
		(layer "F.Cu")
		(net "M_A_CPU1_SB_DQ<20>")
	)
	(segment
		(start 66.553588 -300.777656)
		(end 66.553588 -300.928532)
		(width 0.10668)
		(layer "F.Cu")
		(net "M_A_CPU1_SB_DQ<20>")
	)
	(segment
		(start 70.071234 -297.26001)
		(end 69.939916 -297.391328)
		(width 0.10668)
		(layer "F.Cu")
		(net "M_A_CPU1_SB_DQ<20>")
	)
	(segment
		(start 70.878192 -290.739322)
		(end 70.878192 -296.453052)
		(width 0.10668)
		(layer "F.Cu")
		(net "M_A_CPU1_SB_DQ<20>")
	)
	(segment
		(start 70.576694 -297.050206)
		(end 70.576694 -297.201082)
		(width 0.10668)
		(layer "F.Cu")
		(net "M_A_CPU1_SB_DQ<20>")
	)
	(segment
		(start 68.319142 -299.307758)
		(end 68.319142 -299.458634)
		(width 0.10668)
		(layer "F.Cu")
		(net "M_A_CPU1_SB_DQ<20>")
	)
	(segment
		(start 62.543944 -305.233832)
		(end 62.393068 -305.233832)
		(width 0.10668)
		(layer "F.Cu")
		(net "M_A_CPU1_SB_DQ<20>")
	)
	(segment
		(start 77.767942 -287.026858)
		(end 76.34224 -287.026858)
		(width 0.0762)
		(layer "F.Cu")
		(net "M_A_CPU1_SB_DQ<20>")
	)
	(segment
		(start 65.365884 -302.411892)
		(end 65.215008 -302.411892)
		(width 0.10668)
		(layer "F.Cu")
		(net "M_A_CPU1_SB_DQ<20>")
	)
	(segment
		(start 64.296036 -303.035208)
		(end 64.296036 -303.186084)
		(width 0.10668)
		(layer "F.Cu")
		(net "M_A_CPU1_SB_DQ<20>")
	)
	(segment
		(start 69.506846 -297.824398)
		(end 69.375528 -297.955716)
		(width 0.10668)
		(layer "F.Cu")
		(net "M_A_CPU1_SB_DQ<20>")
	)
	(segment
		(start 64.368426 -303.40935)
		(end 64.237108 -303.540668)
		(width 0.10668)
		(layer "F.Cu")
		(net "M_A_CPU1_SB_DQ<20>")
	)
	(segment
		(start 66.553588 -300.928532)
		(end 66.625978 -301.000922)
		(width 0.10668)
		(layer "F.Cu")
		(net "M_A_CPU1_SB_DQ<20>")
	)
	(segment
		(start 62.602872 -304.879248)
		(end 62.675262 -304.951638)
		(width 0.10668)
		(layer "F.Cu")
		(net "M_A_CPU1_SB_DQ<20>")
	)
	(segment
		(start 70.504304 -296.977816)
		(end 70.576694 -297.050206)
		(width 0.10668)
		(layer "F.Cu")
		(net "M_A_CPU1_SB_DQ<20>")
	)
	(segment
		(start 70.445376 -297.3324)
		(end 70.2945 -297.3324)
		(width 0.10668)
		(layer "F.Cu")
		(net "M_A_CPU1_SB_DQ<20>")
	)
	(segment
		(start 63.804038 -303.973738)
		(end 63.67272 -304.105056)
		(width 0.10668)
		(layer "F.Cu")
		(net "M_A_CPU1_SB_DQ<20>")
	)
	(segment
		(start 68.528946 -298.953174)
		(end 68.37807 -298.953174)
		(width 0.10668)
		(layer "F.Cu")
		(net "M_A_CPU1_SB_DQ<20>")
	)
	(segment
		(start 61.195966 -306.135278)
		(end 59.428126 -306.135278)
		(width 0.10668)
		(layer "F.Cu")
		(net "M_A_CPU1_SB_DQ<20>")
	)
	(segment
		(start 69.447918 -298.329858)
		(end 69.3166 -298.461176)
		(width 0.10668)
		(layer "F.Cu")
		(net "M_A_CPU1_SB_DQ<20>")
	)
	(segment
		(start 63.67272 -304.105056)
		(end 63.521844 -304.105056)
		(width 0.10668)
		(layer "F.Cu")
		(net "M_A_CPU1_SB_DQ<20>")
	)
	(segment
		(start 69.165724 -298.461176)
		(end 69.093334 -298.388786)
		(width 0.10668)
		(layer "F.Cu")
		(net "M_A_CPU1_SB_DQ<20>")
	)
	(segment
		(start 70.2945 -297.3324)
		(end 70.22211 -297.26001)
		(width 0.10668)
		(layer "F.Cu")
		(net "M_A_CPU1_SB_DQ<20>")
	)
	(segment
		(start 70.22211 -297.26001)
		(end 70.071234 -297.26001)
		(width 0.10668)
		(layer "F.Cu")
		(net "M_A_CPU1_SB_DQ<20>")
	)
	(segment
		(start 70.576694 -297.201082)
		(end 70.445376 -297.3324)
		(width 0.10668)
		(layer "F.Cu")
		(net "M_A_CPU1_SB_DQ<20>")
	)
	(segment
		(start 64.860424 -302.621696)
		(end 64.932814 -302.694086)
		(width 0.10668)
		(layer "F.Cu")
		(net "M_A_CPU1_SB_DQ<20>")
	)
	(segment
		(start 67.47256 -300.15434)
		(end 67.40017 -300.08195)
		(width 0.10668)
		(layer "F.Cu")
		(net "M_A_CPU1_SB_DQ<20>")
	)
	(segment
		(start 69.375528 -298.106592)
		(end 69.447918 -298.178982)
		(width 0.10668)
		(layer "F.Cu")
		(net "M_A_CPU1_SB_DQ<20>")
	)
	(segment
		(start 63.298578 -304.032666)
		(end 63.16726 -304.163984)
		(width 0.10668)
		(layer "F.Cu")
		(net "M_A_CPU1_SB_DQ<20>")
	)
	(segment
		(start 68.81114 -298.520104)
		(end 68.81114 -298.67098)
		(width 0.10668)
		(layer "F.Cu")
		(net "M_A_CPU1_SB_DQ<20>")
	)
	(segment
		(start 64.860424 -302.47082)
		(end 64.860424 -302.621696)
		(width 0.10668)
		(layer "F.Cu")
		(net "M_A_CPU1_SB_DQ<20>")
	)
	(segment
		(start 68.942458 -298.388786)
		(end 68.81114 -298.520104)
		(width 0.10668)
		(layer "F.Cu")
		(net "M_A_CPU1_SB_DQ<20>")
	)
	(segment
		(start 67.682364 -299.799756)
		(end 67.754754 -299.872146)
		(width 0.10668)
		(layer "F.Cu")
		(net "M_A_CPU1_SB_DQ<20>")
	)
	(segment
		(start 64.013842 -303.468278)
		(end 63.862966 -303.468278)
		(width 0.10668)
		(layer "F.Cu")
		(net "M_A_CPU1_SB_DQ<20>")
	)
	(segment
		(start 63.804038 -303.822862)
		(end 63.804038 -303.973738)
		(width 0.10668)
		(layer "F.Cu")
		(net "M_A_CPU1_SB_DQ<20>")
	)
	(segment
		(start 65.55613 -301.775114)
		(end 65.424812 -301.906432)
		(width 0.10668)
		(layer "F.Cu")
		(net "M_A_CPU1_SB_DQ<20>")
	)
	(segment
		(start 66.06159 -301.716186)
		(end 65.930272 -301.847504)
		(width 0.10668)
		(layer "F.Cu")
		(net "M_A_CPU1_SB_DQ<20>")
	)
	(segment
		(start 64.427354 -302.90389)
		(end 64.296036 -303.035208)
		(width 0.10668)
		(layer "F.Cu")
		(net "M_A_CPU1_SB_DQ<20>")
	)
	(segment
		(start 66.343784 -301.283116)
		(end 66.271394 -301.210726)
		(width 0.10668)
		(layer "F.Cu")
		(net "M_A_CPU1_SB_DQ<20>")
	)
	(segment
		(start 68.246752 -299.084492)
		(end 68.246752 -299.235368)
		(width 0.10668)
		(layer "F.Cu")
		(net "M_A_CPU1_SB_DQ<20>")
	)
	(segment
		(start 62.675262 -305.102514)
		(end 62.543944 -305.233832)
		(width 0.10668)
		(layer "F.Cu")
		(net "M_A_CPU1_SB_DQ<20>")
	)
	(segment
		(start 63.23965 -304.38725)
		(end 63.23965 -304.538126)
		(width 0.10668)
		(layer "F.Cu")
		(net "M_A_CPU1_SB_DQ<20>")
	)
	(segment
		(start 63.449454 -304.032666)
		(end 63.298578 -304.032666)
		(width 0.10668)
		(layer "F.Cu")
		(net "M_A_CPU1_SB_DQ<20>")
	)
	(segment
		(start 63.16726 -304.31486)
		(end 63.23965 -304.38725)
		(width 0.10668)
		(layer "F.Cu")
		(net "M_A_CPU1_SB_DQ<20>")
	)
	(segment
		(start 64.932814 -302.844962)
		(end 64.801496 -302.97628)
		(width 0.10668)
		(layer "F.Cu")
		(net "M_A_CPU1_SB_DQ<20>")
	)
	(segment
		(start 62.320678 -305.161442)
		(end 62.169802 -305.161442)
		(width 0.10668)
		(layer "F.Cu")
		(net "M_A_CPU1_SB_DQ<20>")
	)
	(segment
		(start 66.06159 -301.56531)
		(end 66.06159 -301.716186)
		(width 0.10668)
		(layer "F.Cu")
		(net "M_A_CPU1_SB_DQ<20>")
	)
	(segment
		(start 69.730112 -297.896788)
		(end 69.657722 -297.824398)
		(width 0.10668)
		(layer "F.Cu")
		(net "M_A_CPU1_SB_DQ<20>")
	)
	(segment
		(start 69.880988 -297.896788)
		(end 69.730112 -297.896788)
		(width 0.10668)
		(layer "F.Cu")
		(net "M_A_CPU1_SB_DQ<20>")
	)
	(segment
		(start 68.036948 -299.589952)
		(end 67.964558 -299.517562)
		(width 0.10668)
		(layer "F.Cu")
		(net "M_A_CPU1_SB_DQ<20>")
	)
	(segment
		(start 67.754754 -300.023022)
		(end 67.623436 -300.15434)
		(width 0.10668)
		(layer "F.Cu")
		(net "M_A_CPU1_SB_DQ<20>")
	)
	(segment
		(start 76.098146 -286.782764)
		(end 74.83475 -286.782764)
		(width 0.10668)
		(layer "F.Cu")
		(net "M_A_CPU1_SB_DQ<20>")
	)
	(segment
		(start 69.657722 -297.824398)
		(end 69.506846 -297.824398)
		(width 0.10668)
		(layer "F.Cu")
		(net "M_A_CPU1_SB_DQ<20>")
	)
	(segment
		(start 74.83475 -286.782764)
		(end 70.878192 -290.739322)
		(width 0.10668)
		(layer "F.Cu")
		(net "M_A_CPU1_SB_DQ<20>")
	)
	(segment
		(start 65.497202 -302.280574)
		(end 65.365884 -302.411892)
		(width 0.10668)
		(layer "F.Cu")
		(net "M_A_CPU1_SB_DQ<20>")
	)
	(segment
		(start 70.012306 -297.614594)
		(end 70.012306 -297.76547)
		(width 0.10668)
		(layer "F.Cu")
		(net "M_A_CPU1_SB_DQ<20>")
	)
	(segment
		(start 67.813682 -299.517562)
		(end 67.682364 -299.64888)
		(width 0.10668)
		(layer "F.Cu")
		(net "M_A_CPU1_SB_DQ<20>")
	)
	(segment
		(start 68.37807 -298.953174)
		(end 68.246752 -299.084492)
		(width 0.10668)
		(layer "F.Cu")
		(net "M_A_CPU1_SB_DQ<20>")
	)
	(segment
		(start 62.675262 -304.951638)
		(end 62.675262 -305.102514)
		(width 0.10668)
		(layer "F.Cu")
		(net "M_A_CPU1_SB_DQ<20>")
	)
	(segment
		(start 62.885066 -304.597054)
		(end 62.73419 -304.597054)
		(width 0.10668)
		(layer "F.Cu")
		(net "M_A_CPU1_SB_DQ<20>")
	)
	(segment
		(start 64.296036 -303.186084)
		(end 64.368426 -303.258474)
		(width 0.10668)
		(layer "F.Cu")
		(net "M_A_CPU1_SB_DQ<20>")
	)
	(segment
		(start 78.237842 -286.780478)
		(end 78.33614 -286.949642)
		(width 0.0762)
		(layer "F.Cu")
		(net "M_A_CPU1_SB_DQ<20>")
	)
	(segment
		(start 65.9892 -301.342044)
		(end 65.9892 -301.49292)
		(width 0.10668)
		(layer "F.Cu")
		(net "M_A_CPU1_SB_DQ<20>")
	)
	(segment
		(start 69.447918 -298.178982)
		(end 69.447918 -298.329858)
		(width 0.10668)
		(layer "F.Cu")
		(net "M_A_CPU1_SB_DQ<20>")
	)
	(segment
		(start 68.246752 -299.235368)
		(end 68.319142 -299.307758)
		(width 0.10668)
		(layer "F.Cu")
		(net "M_A_CPU1_SB_DQ<20>")
	)
	(segment
		(start 65.930272 -301.847504)
		(end 65.779396 -301.847504)
		(width 0.10668)
		(layer "F.Cu")
		(net "M_A_CPU1_SB_DQ<20>")
	)
	(segment
		(start 62.957456 -304.669444)
		(end 62.885066 -304.597054)
		(width 0.10668)
		(layer "F.Cu")
		(net "M_A_CPU1_SB_DQ<20>")
	)
	(segment
		(start 78.05928 -287.107884)
		(end 78.050898 -287.103058)
		(width 0.0762)
		(layer "F.Cu")
		(net "M_A_CPU1_SB_DQ<20>")
	)
	(segment
		(start 62.169802 -305.161442)
		(end 61.195966 -306.135278)
		(width 0.10668)
		(layer "F.Cu")
		(net "M_A_CPU1_SB_DQ<20>")
	)
	(segment
		(start 64.57823 -302.90389)
		(end 64.427354 -302.90389)
		(width 0.10668)
		(layer "F.Cu")
		(net "M_A_CPU1_SB_DQ<20>")
	)
	(segment
		(start 64.368426 -303.258474)
		(end 64.368426 -303.40935)
		(width 0.10668)
		(layer "F.Cu")
		(net "M_A_CPU1_SB_DQ<20>")
	)
	(segment
		(start 65.142618 -302.339502)
		(end 64.991742 -302.339502)
		(width 0.10668)
		(layer "F.Cu")
		(net "M_A_CPU1_SB_DQ<20>")
	)
	(segment
		(start 66.625978 -301.000922)
		(end 66.625978 -301.151798)
		(width 0.10668)
		(layer "F.Cu")
		(net "M_A_CPU1_SB_DQ<20>")
	)
	(segment
		(start 63.731648 -303.750472)
		(end 63.804038 -303.822862)
		(width 0.10668)
		(layer "F.Cu")
		(net "M_A_CPU1_SB_DQ<20>")
	)
	(segment
		(start 65.779396 -301.847504)
		(end 65.707006 -301.775114)
		(width 0.10668)
		(layer "F.Cu")
		(net "M_A_CPU1_SB_DQ<20>")
	)
	(segment
		(start 66.120518 -301.210726)
		(end 65.9892 -301.342044)
		(width 0.10668)
		(layer "F.Cu")
		(net "M_A_CPU1_SB_DQ<20>")
	)
	(segment
		(start 64.801496 -302.97628)
		(end 64.65062 -302.97628)
		(width 0.10668)
		(layer "F.Cu")
		(net "M_A_CPU1_SB_DQ<20>")
	)
	(segment
		(start 66.49466 -301.283116)
		(end 66.343784 -301.283116)
		(width 0.10668)
		(layer "F.Cu")
		(net "M_A_CPU1_SB_DQ<20>")
	)
	(segment
		(start 67.682364 -299.64888)
		(end 67.682364 -299.799756)
		(width 0.10668)
		(layer "F.Cu")
		(net "M_A_CPU1_SB_DQ<20>")
	)
	(segment
		(start 70.012306 -297.76547)
		(end 69.880988 -297.896788)
		(width 0.10668)
		(layer "F.Cu")
		(net "M_A_CPU1_SB_DQ<20>")
	)
	(segment
		(start 67.190366 -300.58741)
		(end 67.059048 -300.718728)
		(width 0.10668)
		(layer "F.Cu")
		(net "M_A_CPU1_SB_DQ<20>")
	)
	(segment
		(start 64.65062 -302.97628)
		(end 64.57823 -302.90389)
		(width 0.10668)
		(layer "F.Cu")
		(net "M_A_CPU1_SB_DQ<20>")
	)
	(segment
		(start 68.88353 -298.894246)
		(end 68.752212 -299.025564)
		(width 0.10668)
		(layer "F.Cu")
		(net "M_A_CPU1_SB_DQ<20>")
	)
	(segment
		(start 66.684906 -300.646338)
		(end 66.553588 -300.777656)
		(width 0.10668)
		(layer "F.Cu")
		(net "M_A_CPU1_SB_DQ<20>")
	)
	(segment
		(start 67.117976 -300.364144)
		(end 67.190366 -300.436534)
		(width 0.10668)
		(layer "F.Cu")
		(net "M_A_CPU1_SB_DQ<20>")
	)
	(segment
		(start 76.34224 -287.026858)
		(end 76.098146 -286.782764)
		(width 0.0762)
		(layer "F.Cu")
		(net "M_A_CPU1_SB_DQ<20>")
	)
	(segment
		(start 67.117976 -300.213268)
		(end 67.117976 -300.364144)
		(width 0.10668)
		(layer "F.Cu")
		(net "M_A_CPU1_SB_DQ<20>")
	)
	(segment
		(start 63.521844 -304.105056)
		(end 63.449454 -304.032666)
		(width 0.10668)
		(layer "F.Cu")
		(net "M_A_CPU1_SB_DQ<20>")
	)
	(segment
		(start 67.623436 -300.15434)
		(end 67.47256 -300.15434)
		(width 0.10668)
		(layer "F.Cu")
		(net "M_A_CPU1_SB_DQ<20>")
	)
	(segment
		(start 69.375528 -297.955716)
		(end 69.375528 -298.106592)
		(width 0.10668)
		(layer "F.Cu")
		(net "M_A_CPU1_SB_DQ<20>")
	)
	(segment
		(start 68.88353 -298.74337)
		(end 68.88353 -298.894246)
		(width 0.10668)
		(layer "F.Cu")
		(net "M_A_CPU1_SB_DQ<20>")
	)
	(segment
		(start 62.602872 -304.728372)
		(end 62.602872 -304.879248)
		(width 0.10668)
		(layer "F.Cu")
		(net "M_A_CPU1_SB_DQ<20>")
	)
	(segment
		(start 66.271394 -301.210726)
		(end 66.120518 -301.210726)
		(width 0.10668)
		(layer "F.Cu")
		(net "M_A_CPU1_SB_DQ<20>")
	)
	(segment
		(start 65.707006 -301.775114)
		(end 65.55613 -301.775114)
		(width 0.10668)
		(layer "F.Cu")
		(net "M_A_CPU1_SB_DQ<20>")
	)
	(segment
		(start 64.932814 -302.694086)
		(end 64.932814 -302.844962)
		(width 0.10668)
		(layer "F.Cu")
		(net "M_A_CPU1_SB_DQ<20>")
	)
	(segment
		(start 62.393068 -305.233832)
		(end 62.320678 -305.161442)
		(width 0.10668)
		(layer "F.Cu")
		(net "M_A_CPU1_SB_DQ<20>")
	)
	(segment
		(start 65.9892 -301.49292)
		(end 66.06159 -301.56531)
		(width 0.10668)
		(layer "F.Cu")
		(net "M_A_CPU1_SB_DQ<20>")
	)
	(segment
		(start 66.908172 -300.718728)
		(end 66.835782 -300.646338)
		(width 0.10668)
		(layer "F.Cu")
		(net "M_A_CPU1_SB_DQ<20>")
	)
	(segment
		(start 64.991742 -302.339502)
		(end 64.860424 -302.47082)
		(width 0.10668)
		(layer "F.Cu")
		(net "M_A_CPU1_SB_DQ<20>")
	)
	(segment
		(start 65.497202 -302.129698)
		(end 65.497202 -302.280574)
		(width 0.10668)
		(layer "F.Cu")
		(net "M_A_CPU1_SB_DQ<20>")
	)
	(segment
		(start 69.3166 -298.461176)
		(end 69.165724 -298.461176)
		(width 0.10668)
		(layer "F.Cu")
		(net "M_A_CPU1_SB_DQ<20>")
	)
	(segment
		(start 67.40017 -300.08195)
		(end 67.249294 -300.08195)
		(width 0.10668)
		(layer "F.Cu")
		(net "M_A_CPU1_SB_DQ<20>")
	)
	(arc
		(start 78.33614 -286.949642)
		(mid 78.327547 -287.091521)
		(end 78.198472 -287.151318)
		(width 0.0762)
		(layer "F.Cu")
		(net "M_A_CPU1_SB_DQ<20>")
	)
	(arc
		(start 78.198472 -287.151318)
		(mid 78.126734 -287.136466)
		(end 78.05928 -287.107884)
		(width 0.0762)
		(layer "F.Cu")
		(net "M_A_CPU1_SB_DQ<20>")
	)
	(arc
		(start 78.050898 -287.103058)
		(mid 77.914462 -287.046233)
		(end 77.767942 -287.026858)
		(width 0.0762)
		(layer "F.Cu")
		(net "M_A_CPU1_SB_DQ<20>")
	)
	(segment
		(start 65.148206 -278.514556)
		(end 65.016888 -278.645874)
		(width 0.10668)
		(layer "F.Cu")
		(net "M_A_CPU1_SB_DQ<1>")
	)
	(segment
		(start 61.688472 -281.525726)
		(end 61.688472 -281.676602)
		(width 0.10668)
		(layer "F.Cu")
		(net "M_A_CPU1_SB_DQ<1>")
	)
	(segment
		(start 67.46367 -275.750528)
		(end 67.332352 -275.881846)
		(width 0.10668)
		(layer "F.Cu")
		(net "M_A_CPU1_SB_DQ<1>")
	)
	(segment
		(start 65.639188 -277.57501)
		(end 65.639188 -277.725886)
		(width 0.10668)
		(layer "F.Cu")
		(net "M_A_CPU1_SB_DQ<1>")
	)
	(segment
		(start 63.099442 -280.265632)
		(end 62.948566 -280.265632)
		(width 0.10668)
		(layer "F.Cu")
		(net "M_A_CPU1_SB_DQ<1>")
	)
	(segment
		(start 61.761878 -281.750008)
		(end 61.761878 -281.900884)
		(width 0.10668)
		(layer "F.Cu")
		(net "M_A_CPU1_SB_DQ<1>")
	)
	(segment
		(start 66.203576 -277.161498)
		(end 66.276982 -277.234904)
		(width 0.10668)
		(layer "F.Cu")
		(net "M_A_CPU1_SB_DQ<1>")
	)
	(segment
		(start 65.994788 -277.517098)
		(end 65.921382 -277.443692)
		(width 0.10668)
		(layer "F.Cu")
		(net "M_A_CPU1_SB_DQ<1>")
	)
	(segment
		(start 62.817248 -280.547826)
		(end 62.890654 -280.621232)
		(width 0.10668)
		(layer "F.Cu")
		(net "M_A_CPU1_SB_DQ<1>")
	)
	(segment
		(start 64.510412 -278.854662)
		(end 64.583818 -278.928068)
		(width 0.10668)
		(layer "F.Cu")
		(net "M_A_CPU1_SB_DQ<1>")
	)
	(segment
		(start 66.145664 -277.517098)
		(end 65.994788 -277.517098)
		(width 0.10668)
		(layer "F.Cu")
		(net "M_A_CPU1_SB_DQ<1>")
	)
	(segment
		(start 66.84137 -276.821392)
		(end 66.710052 -276.95271)
		(width 0.10668)
		(layer "F.Cu")
		(net "M_A_CPU1_SB_DQ<1>")
	)
	(segment
		(start 63.455042 -280.20772)
		(end 63.323724 -280.339038)
		(width 0.10668)
		(layer "F.Cu")
		(net "M_A_CPU1_SB_DQ<1>")
	)
	(segment
		(start 62.326266 -281.336496)
		(end 62.194948 -281.467814)
		(width 0.10668)
		(layer "F.Cu")
		(net "M_A_CPU1_SB_DQ<1>")
	)
	(segment
		(start 66.334894 -276.879304)
		(end 66.203576 -277.010622)
		(width 0.10668)
		(layer "F.Cu")
		(net "M_A_CPU1_SB_DQ<1>")
	)
	(segment
		(start 63.323724 -280.339038)
		(end 63.172848 -280.339038)
		(width 0.10668)
		(layer "F.Cu")
		(net "M_A_CPU1_SB_DQ<1>")
	)
	(segment
		(start 66.84137 -276.670516)
		(end 66.84137 -276.821392)
		(width 0.10668)
		(layer "F.Cu")
		(net "M_A_CPU1_SB_DQ<1>")
	)
	(segment
		(start 60.327286 -283.185362)
		(end 59.428126 -283.185362)
		(width 0.10668)
		(layer "F.Cu")
		(net "M_A_CPU1_SB_DQ<1>")
	)
	(segment
		(start 63.455042 -280.056844)
		(end 63.455042 -280.20772)
		(width 0.10668)
		(layer "F.Cu")
		(net "M_A_CPU1_SB_DQ<1>")
	)
	(segment
		(start 65.921382 -277.443692)
		(end 65.770506 -277.443692)
		(width 0.10668)
		(layer "F.Cu")
		(net "M_A_CPU1_SB_DQ<1>")
	)
	(segment
		(start 67.050158 -276.314916)
		(end 66.899282 -276.314916)
		(width 0.10668)
		(layer "F.Cu")
		(net "M_A_CPU1_SB_DQ<1>")
	)
	(segment
		(start 60.952634 -282.261564)
		(end 60.560966 -282.261564)
		(width 0.10668)
		(layer "F.Cu")
		(net "M_A_CPU1_SB_DQ<1>")
	)
	(segment
		(start 60.444126 -283.068522)
		(end 60.327286 -283.185362)
		(width 0.10668)
		(layer "F.Cu")
		(net "M_A_CPU1_SB_DQ<1>")
	)
	(segment
		(start 63.381636 -279.832562)
		(end 63.381636 -279.983438)
		(width 0.10668)
		(layer "F.Cu")
		(net "M_A_CPU1_SB_DQ<1>")
	)
	(segment
		(start 60.444126 -282.378404)
		(end 60.444126 -283.068522)
		(width 0.10668)
		(layer "F.Cu")
		(net "M_A_CPU1_SB_DQ<1>")
	)
	(segment
		(start 64.583818 -278.928068)
		(end 64.583818 -279.078944)
		(width 0.10668)
		(layer "F.Cu")
		(net "M_A_CPU1_SB_DQ<1>")
	)
	(segment
		(start 67.89674 -275.468334)
		(end 67.970146 -275.54174)
		(width 0.10668)
		(layer "F.Cu")
		(net "M_A_CPU1_SB_DQ<1>")
	)
	(segment
		(start 67.614546 -275.750528)
		(end 67.46367 -275.750528)
		(width 0.10668)
		(layer "F.Cu")
		(net "M_A_CPU1_SB_DQ<1>")
	)
	(segment
		(start 67.332352 -275.881846)
		(end 67.332352 -276.032722)
		(width 0.10668)
		(layer "F.Cu")
		(net "M_A_CPU1_SB_DQ<1>")
	)
	(segment
		(start 63.381636 -279.983438)
		(end 63.455042 -280.056844)
		(width 0.10668)
		(layer "F.Cu")
		(net "M_A_CPU1_SB_DQ<1>")
	)
	(segment
		(start 65.206118 -278.00808)
		(end 65.0748 -278.139398)
		(width 0.10668)
		(layer "F.Cu")
		(net "M_A_CPU1_SB_DQ<1>")
	)
	(segment
		(start 65.0748 -278.139398)
		(end 65.0748 -278.290274)
		(width 0.10668)
		(layer "F.Cu")
		(net "M_A_CPU1_SB_DQ<1>")
	)
	(segment
		(start 61.406278 -281.958796)
		(end 61.255402 -281.958796)
		(width 0.10668)
		(layer "F.Cu")
		(net "M_A_CPU1_SB_DQ<1>")
	)
	(segment
		(start 66.276982 -277.234904)
		(end 66.276982 -277.38578)
		(width 0.10668)
		(layer "F.Cu")
		(net "M_A_CPU1_SB_DQ<1>")
	)
	(segment
		(start 78.89494 -274.952968)
		(end 78.886558 -274.957794)
		(width 0.0762)
		(layer "F.Cu")
		(net "M_A_CPU1_SB_DQ<1>")
	)
	(segment
		(start 77.767942 -275.003514)
		(end 76.964032 -275.003514)
		(width 0.0762)
		(layer "F.Cu")
		(net "M_A_CPU1_SB_DQ<1>")
	)
	(segment
		(start 62.890654 -280.772108)
		(end 62.759336 -280.903426)
		(width 0.10668)
		(layer "F.Cu")
		(net "M_A_CPU1_SB_DQ<1>")
	)
	(segment
		(start 61.255402 -281.958796)
		(end 60.952634 -282.261564)
		(width 0.10668)
		(layer "F.Cu")
		(net "M_A_CPU1_SB_DQ<1>")
	)
	(segment
		(start 66.203576 -277.010622)
		(end 66.203576 -277.161498)
		(width 0.10668)
		(layer "F.Cu")
		(net "M_A_CPU1_SB_DQ<1>")
	)
	(segment
		(start 63.172848 -280.339038)
		(end 63.099442 -280.265632)
		(width 0.10668)
		(layer "F.Cu")
		(net "M_A_CPU1_SB_DQ<1>")
	)
	(segment
		(start 65.4304 -278.081486)
		(end 65.356994 -278.00808)
		(width 0.10668)
		(layer "F.Cu")
		(net "M_A_CPU1_SB_DQ<1>")
	)
	(segment
		(start 64.077342 -279.136856)
		(end 63.946024 -279.268174)
		(width 0.10668)
		(layer "F.Cu")
		(net "M_A_CPU1_SB_DQ<1>")
	)
	(segment
		(start 62.759336 -280.903426)
		(end 62.60846 -280.903426)
		(width 0.10668)
		(layer "F.Cu")
		(net "M_A_CPU1_SB_DQ<1>")
	)
	(segment
		(start 66.767964 -276.59711)
		(end 66.84137 -276.670516)
		(width 0.10668)
		(layer "F.Cu")
		(net "M_A_CPU1_SB_DQ<1>")
	)
	(segment
		(start 62.817248 -280.39695)
		(end 62.817248 -280.547826)
		(width 0.10668)
		(layer "F.Cu")
		(net "M_A_CPU1_SB_DQ<1>")
	)
	(segment
		(start 60.560966 -282.261564)
		(end 60.444126 -282.378404)
		(width 0.10668)
		(layer "F.Cu")
		(net "M_A_CPU1_SB_DQ<1>")
	)
	(segment
		(start 79.647796 -274.630388)
		(end 79.748634 -274.80387)
		(width 0.0762)
		(layer "F.Cu")
		(net "M_A_CPU1_SB_DQ<1>")
	)
	(segment
		(start 66.276982 -277.38578)
		(end 66.145664 -277.517098)
		(width 0.10668)
		(layer "F.Cu")
		(net "M_A_CPU1_SB_DQ<1>")
	)
	(segment
		(start 61.63056 -282.032202)
		(end 61.479684 -282.032202)
		(width 0.10668)
		(layer "F.Cu")
		(net "M_A_CPU1_SB_DQ<1>")
	)
	(segment
		(start 62.194948 -281.467814)
		(end 62.044072 -281.467814)
		(width 0.10668)
		(layer "F.Cu")
		(net "M_A_CPU1_SB_DQ<1>")
	)
	(segment
		(start 67.27444 -276.388322)
		(end 67.123564 -276.388322)
		(width 0.10668)
		(layer "F.Cu")
		(net "M_A_CPU1_SB_DQ<1>")
	)
	(segment
		(start 65.0748 -278.290274)
		(end 65.148206 -278.36368)
		(width 0.10668)
		(layer "F.Cu")
		(net "M_A_CPU1_SB_DQ<1>")
	)
	(segment
		(start 75.960986 -274.550124)
		(end 68.664074 -274.550124)
		(width 0.10668)
		(layer "F.Cu")
		(net "M_A_CPU1_SB_DQ<1>")
	)
	(segment
		(start 61.81979 -281.394408)
		(end 61.688472 -281.525726)
		(width 0.10668)
		(layer "F.Cu")
		(net "M_A_CPU1_SB_DQ<1>")
	)
	(segment
		(start 67.970146 -275.54174)
		(end 67.970146 -275.692616)
		(width 0.10668)
		(layer "F.Cu")
		(net "M_A_CPU1_SB_DQ<1>")
	)
	(segment
		(start 62.535054 -280.83002)
		(end 62.384178 -280.83002)
		(width 0.10668)
		(layer "F.Cu")
		(net "M_A_CPU1_SB_DQ<1>")
	)
	(segment
		(start 64.228218 -279.136856)
		(end 64.077342 -279.136856)
		(width 0.10668)
		(layer "F.Cu")
		(net "M_A_CPU1_SB_DQ<1>")
	)
	(segment
		(start 68.664074 -274.550124)
		(end 68.461128 -274.75307)
		(width 0.10668)
		(layer "F.Cu")
		(net "M_A_CPU1_SB_DQ<1>")
	)
	(segment
		(start 76.964032 -275.003514)
		(end 76.510642 -274.550124)
		(width 0.0762)
		(layer "F.Cu")
		(net "M_A_CPU1_SB_DQ<1>")
	)
	(segment
		(start 66.48577 -276.879304)
		(end 66.334894 -276.879304)
		(width 0.10668)
		(layer "F.Cu")
		(net "M_A_CPU1_SB_DQ<1>")
	)
	(segment
		(start 61.761878 -281.900884)
		(end 61.63056 -282.032202)
		(width 0.10668)
		(layer "F.Cu")
		(net "M_A_CPU1_SB_DQ<1>")
	)
	(segment
		(start 79.469234 -274.957794)
		(end 79.460852 -274.952968)
		(width 0.0762)
		(layer "F.Cu")
		(net "M_A_CPU1_SB_DQ<1>")
	)
	(segment
		(start 65.016888 -278.645874)
		(end 64.866012 -278.645874)
		(width 0.10668)
		(layer "F.Cu")
		(net "M_A_CPU1_SB_DQ<1>")
	)
	(segment
		(start 63.888112 -279.77465)
		(end 63.737236 -279.77465)
		(width 0.10668)
		(layer "F.Cu")
		(net "M_A_CPU1_SB_DQ<1>")
	)
	(segment
		(start 61.479684 -282.032202)
		(end 61.406278 -281.958796)
		(width 0.10668)
		(layer "F.Cu")
		(net "M_A_CPU1_SB_DQ<1>")
	)
	(segment
		(start 63.946024 -279.268174)
		(end 63.946024 -279.41905)
		(width 0.10668)
		(layer "F.Cu")
		(net "M_A_CPU1_SB_DQ<1>")
	)
	(segment
		(start 65.712594 -277.950168)
		(end 65.581276 -278.081486)
		(width 0.10668)
		(layer "F.Cu")
		(net "M_A_CPU1_SB_DQ<1>")
	)
	(segment
		(start 62.044072 -281.467814)
		(end 61.970666 -281.394408)
		(width 0.10668)
		(layer "F.Cu")
		(net "M_A_CPU1_SB_DQ<1>")
	)
	(segment
		(start 61.970666 -281.394408)
		(end 61.81979 -281.394408)
		(width 0.10668)
		(layer "F.Cu")
		(net "M_A_CPU1_SB_DQ<1>")
	)
	(segment
		(start 68.461128 -274.75307)
		(end 68.461128 -274.903946)
		(width 0.10668)
		(layer "F.Cu")
		(net "M_A_CPU1_SB_DQ<1>")
	)
	(segment
		(start 63.737236 -279.77465)
		(end 63.66383 -279.701244)
		(width 0.10668)
		(layer "F.Cu")
		(net "M_A_CPU1_SB_DQ<1>")
	)
	(segment
		(start 68.403216 -275.259546)
		(end 68.25234 -275.259546)
		(width 0.10668)
		(layer "F.Cu")
		(net "M_A_CPU1_SB_DQ<1>")
	)
	(segment
		(start 67.89674 -275.317458)
		(end 67.89674 -275.468334)
		(width 0.10668)
		(layer "F.Cu")
		(net "M_A_CPU1_SB_DQ<1>")
	)
	(segment
		(start 66.559176 -276.95271)
		(end 66.48577 -276.879304)
		(width 0.10668)
		(layer "F.Cu")
		(net "M_A_CPU1_SB_DQ<1>")
	)
	(segment
		(start 68.461128 -274.903946)
		(end 68.534534 -274.977352)
		(width 0.10668)
		(layer "F.Cu")
		(net "M_A_CPU1_SB_DQ<1>")
	)
	(segment
		(start 65.712594 -277.799292)
		(end 65.712594 -277.950168)
		(width 0.10668)
		(layer "F.Cu")
		(net "M_A_CPU1_SB_DQ<1>")
	)
	(segment
		(start 62.326266 -281.18562)
		(end 62.326266 -281.336496)
		(width 0.10668)
		(layer "F.Cu")
		(net "M_A_CPU1_SB_DQ<1>")
	)
	(segment
		(start 64.866012 -278.645874)
		(end 64.792606 -278.572468)
		(width 0.10668)
		(layer "F.Cu")
		(net "M_A_CPU1_SB_DQ<1>")
	)
	(segment
		(start 62.25286 -280.961338)
		(end 62.25286 -281.112214)
		(width 0.10668)
		(layer "F.Cu")
		(net "M_A_CPU1_SB_DQ<1>")
	)
	(segment
		(start 62.60846 -280.903426)
		(end 62.535054 -280.83002)
		(width 0.10668)
		(layer "F.Cu")
		(net "M_A_CPU1_SB_DQ<1>")
	)
	(segment
		(start 64.792606 -278.572468)
		(end 64.64173 -278.572468)
		(width 0.10668)
		(layer "F.Cu")
		(net "M_A_CPU1_SB_DQ<1>")
	)
	(segment
		(start 61.688472 -281.676602)
		(end 61.761878 -281.750008)
		(width 0.10668)
		(layer "F.Cu")
		(net "M_A_CPU1_SB_DQ<1>")
	)
	(segment
		(start 76.510642 -274.550124)
		(end 75.960986 -274.550124)
		(width 0.0762)
		(layer "F.Cu")
		(net "M_A_CPU1_SB_DQ<1>")
	)
	(segment
		(start 68.178934 -275.18614)
		(end 68.028058 -275.18614)
		(width 0.10668)
		(layer "F.Cu")
		(net "M_A_CPU1_SB_DQ<1>")
	)
	(segment
		(start 64.64173 -278.572468)
		(end 64.510412 -278.703786)
		(width 0.10668)
		(layer "F.Cu")
		(net "M_A_CPU1_SB_DQ<1>")
	)
	(segment
		(start 65.356994 -278.00808)
		(end 65.206118 -278.00808)
		(width 0.10668)
		(layer "F.Cu")
		(net "M_A_CPU1_SB_DQ<1>")
	)
	(segment
		(start 65.148206 -278.36368)
		(end 65.148206 -278.514556)
		(width 0.10668)
		(layer "F.Cu")
		(net "M_A_CPU1_SB_DQ<1>")
	)
	(segment
		(start 68.25234 -275.259546)
		(end 68.178934 -275.18614)
		(width 0.10668)
		(layer "F.Cu")
		(net "M_A_CPU1_SB_DQ<1>")
	)
	(segment
		(start 68.534534 -275.128228)
		(end 68.403216 -275.259546)
		(width 0.10668)
		(layer "F.Cu")
		(net "M_A_CPU1_SB_DQ<1>")
	)
	(segment
		(start 64.01943 -279.643332)
		(end 63.888112 -279.77465)
		(width 0.10668)
		(layer "F.Cu")
		(net "M_A_CPU1_SB_DQ<1>")
	)
	(segment
		(start 62.25286 -281.112214)
		(end 62.326266 -281.18562)
		(width 0.10668)
		(layer "F.Cu")
		(net "M_A_CPU1_SB_DQ<1>")
	)
	(segment
		(start 64.01943 -279.492456)
		(end 64.01943 -279.643332)
		(width 0.10668)
		(layer "F.Cu")
		(net "M_A_CPU1_SB_DQ<1>")
	)
	(segment
		(start 66.710052 -276.95271)
		(end 66.559176 -276.95271)
		(width 0.10668)
		(layer "F.Cu")
		(net "M_A_CPU1_SB_DQ<1>")
	)
	(segment
		(start 67.405758 -276.257004)
		(end 67.27444 -276.388322)
		(width 0.10668)
		(layer "F.Cu")
		(net "M_A_CPU1_SB_DQ<1>")
	)
	(segment
		(start 67.687952 -275.823934)
		(end 67.614546 -275.750528)
		(width 0.10668)
		(layer "F.Cu")
		(net "M_A_CPU1_SB_DQ<1>")
	)
	(segment
		(start 67.405758 -276.106128)
		(end 67.405758 -276.257004)
		(width 0.10668)
		(layer "F.Cu")
		(net "M_A_CPU1_SB_DQ<1>")
	)
	(segment
		(start 66.899282 -276.314916)
		(end 66.767964 -276.446234)
		(width 0.10668)
		(layer "F.Cu")
		(net "M_A_CPU1_SB_DQ<1>")
	)
	(segment
		(start 67.332352 -276.032722)
		(end 67.405758 -276.106128)
		(width 0.10668)
		(layer "F.Cu")
		(net "M_A_CPU1_SB_DQ<1>")
	)
	(segment
		(start 64.510412 -278.703786)
		(end 64.510412 -278.854662)
		(width 0.10668)
		(layer "F.Cu")
		(net "M_A_CPU1_SB_DQ<1>")
	)
	(segment
		(start 63.946024 -279.41905)
		(end 64.01943 -279.492456)
		(width 0.10668)
		(layer "F.Cu")
		(net "M_A_CPU1_SB_DQ<1>")
	)
	(segment
		(start 64.4525 -279.210262)
		(end 64.301624 -279.210262)
		(width 0.10668)
		(layer "F.Cu")
		(net "M_A_CPU1_SB_DQ<1>")
	)
	(segment
		(start 67.970146 -275.692616)
		(end 67.838828 -275.823934)
		(width 0.10668)
		(layer "F.Cu")
		(net "M_A_CPU1_SB_DQ<1>")
	)
	(segment
		(start 65.639188 -277.725886)
		(end 65.712594 -277.799292)
		(width 0.10668)
		(layer "F.Cu")
		(net "M_A_CPU1_SB_DQ<1>")
	)
	(segment
		(start 65.581276 -278.081486)
		(end 65.4304 -278.081486)
		(width 0.10668)
		(layer "F.Cu")
		(net "M_A_CPU1_SB_DQ<1>")
	)
	(segment
		(start 67.838828 -275.823934)
		(end 67.687952 -275.823934)
		(width 0.10668)
		(layer "F.Cu")
		(net "M_A_CPU1_SB_DQ<1>")
	)
	(segment
		(start 62.890654 -280.621232)
		(end 62.890654 -280.772108)
		(width 0.10668)
		(layer "F.Cu")
		(net "M_A_CPU1_SB_DQ<1>")
	)
	(segment
		(start 66.767964 -276.446234)
		(end 66.767964 -276.59711)
		(width 0.10668)
		(layer "F.Cu")
		(net "M_A_CPU1_SB_DQ<1>")
	)
	(segment
		(start 67.123564 -276.388322)
		(end 67.050158 -276.314916)
		(width 0.10668)
		(layer "F.Cu")
		(net "M_A_CPU1_SB_DQ<1>")
	)
	(segment
		(start 62.384178 -280.83002)
		(end 62.25286 -280.961338)
		(width 0.10668)
		(layer "F.Cu")
		(net "M_A_CPU1_SB_DQ<1>")
	)
	(segment
		(start 62.948566 -280.265632)
		(end 62.817248 -280.39695)
		(width 0.10668)
		(layer "F.Cu")
		(net "M_A_CPU1_SB_DQ<1>")
	)
	(segment
		(start 65.770506 -277.443692)
		(end 65.639188 -277.57501)
		(width 0.10668)
		(layer "F.Cu")
		(net "M_A_CPU1_SB_DQ<1>")
	)
	(segment
		(start 68.534534 -274.977352)
		(end 68.534534 -275.128228)
		(width 0.10668)
		(layer "F.Cu")
		(net "M_A_CPU1_SB_DQ<1>")
	)
	(segment
		(start 68.028058 -275.18614)
		(end 67.89674 -275.317458)
		(width 0.10668)
		(layer "F.Cu")
		(net "M_A_CPU1_SB_DQ<1>")
	)
	(segment
		(start 64.301624 -279.210262)
		(end 64.228218 -279.136856)
		(width 0.10668)
		(layer "F.Cu")
		(net "M_A_CPU1_SB_DQ<1>")
	)
	(segment
		(start 63.66383 -279.701244)
		(end 63.512954 -279.701244)
		(width 0.10668)
		(layer "F.Cu")
		(net "M_A_CPU1_SB_DQ<1>")
	)
	(segment
		(start 63.512954 -279.701244)
		(end 63.381636 -279.832562)
		(width 0.10668)
		(layer "F.Cu")
		(net "M_A_CPU1_SB_DQ<1>")
	)
	(segment
		(start 64.583818 -279.078944)
		(end 64.4525 -279.210262)
		(width 0.10668)
		(layer "F.Cu")
		(net "M_A_CPU1_SB_DQ<1>")
	)
	(arc
		(start 79.460852 -274.952968)
		(mid 79.177896 -274.876791)
		(end 78.89494 -274.952968)
		(width 0.0762)
		(layer "F.Cu")
		(net "M_A_CPU1_SB_DQ<1>")
	)
	(arc
		(start 78.520798 -274.952968)
		(mid 78.237842 -274.876791)
		(end 77.954886 -274.952968)
		(width 0.0762)
		(layer "F.Cu")
		(net "M_A_CPU1_SB_DQ<1>")
	)
	(arc
		(start 77.954886 -274.952968)
		(mid 77.879646 -274.986281)
		(end 77.79893 -275.002244)
		(width 0.0762)
		(layer "F.Cu")
		(net "M_A_CPU1_SB_DQ<1>")
	)
	(arc
		(start 77.79893 -275.002244)
		(mid 77.783449 -275.0032)
		(end 77.767942 -275.003514)
		(width 0.0762)
		(layer "F.Cu")
		(net "M_A_CPU1_SB_DQ<1>")
	)
	(arc
		(start 79.748634 -274.80387)
		(mid 79.732709 -274.944562)
		(end 79.602584 -275.000466)
		(width 0.0762)
		(layer "F.Cu")
		(net "M_A_CPU1_SB_DQ<1>")
	)
	(arc
		(start 79.602584 -275.000466)
		(mid 79.533886 -274.98545)
		(end 79.469234 -274.957794)
		(width 0.0762)
		(layer "F.Cu")
		(net "M_A_CPU1_SB_DQ<1>")
	)
	(arc
		(start 78.886558 -274.957794)
		(mid 78.70305 -275.003288)
		(end 78.520798 -274.952968)
		(width 0.0762)
		(layer "F.Cu")
		(net "M_A_CPU1_SB_DQ<1>")
	)
	(segment
		(start 61.17082 -301.57674)
		(end 61.533532 -301.939452)
		(width 0.10668)
		(layer "F.Cu")
		(net "M_A_CPU1_SB_DQ<19>")
	)
	(segment
		(start 61.45276 -301.294546)
		(end 61.302392 -301.294292)
		(width 0.10668)
		(layer "F.Cu")
		(net "M_A_CPU1_SB_DQ<19>")
	)
	(segment
		(start 77.768196 -284.914086)
		(end 76.098908 -284.914086)
		(width 0.0762)
		(layer "F.Cu")
		(net "M_A_CPU1_SB_DQ<19>")
	)
	(segment
		(start 61.533278 -302.090328)
		(end 61.313314 -302.310292)
		(width 0.10668)
		(layer "F.Cu")
		(net "M_A_CPU1_SB_DQ<19>")
	)
	(segment
		(start 78.05928 -284.83306)
		(end 78.050898 -284.837886)
		(width 0.0762)
		(layer "F.Cu")
		(net "M_A_CPU1_SB_DQ<19>")
	)
	(segment
		(start 60.725812 -302.310292)
		(end 57.715658 -302.310292)
		(width 0.101346)
		(layer "F.Cu")
		(net "M_A_CPU1_SB_DQ<19>")
	)
	(segment
		(start 68.964302 -289.9156)
		(end 68.964302 -294.659304)
		(width 0.10668)
		(layer "F.Cu")
		(net "M_A_CPU1_SB_DQ<19>")
	)
	(segment
		(start 61.17082 -301.425864)
		(end 61.17082 -301.57674)
		(width 0.10668)
		(layer "F.Cu")
		(net "M_A_CPU1_SB_DQ<19>")
	)
	(segment
		(start 61.815472 -301.657258)
		(end 61.45276 -301.294546)
		(width 0.10668)
		(layer "F.Cu")
		(net "M_A_CPU1_SB_DQ<19>")
	)
	(segment
		(start 76.018136 -284.833314)
		(end 74.046588 -284.833314)
		(width 0.10668)
		(layer "F.Cu")
		(net "M_A_CPU1_SB_DQ<19>")
	)
	(segment
		(start 57.290716 -302.735234)
		(end 55.328058 -302.735234)
		(width 0.101346)
		(layer "F.Cu")
		(net "M_A_CPU1_SB_DQ<19>")
	)
	(segment
		(start 76.098908 -284.914086)
		(end 76.018136 -284.833314)
		(width 0.0762)
		(layer "F.Cu")
		(net "M_A_CPU1_SB_DQ<19>")
	)
	(segment
		(start 61.302392 -301.294292)
		(end 61.17082 -301.425864)
		(width 0.10668)
		(layer "F.Cu")
		(net "M_A_CPU1_SB_DQ<19>")
	)
	(segment
		(start 61.313314 -302.310292)
		(end 60.725812 -302.310292)
		(width 0.10668)
		(layer "F.Cu")
		(net "M_A_CPU1_SB_DQ<19>")
	)
	(segment
		(start 61.533532 -301.939452)
		(end 61.533278 -302.090328)
		(width 0.10668)
		(layer "F.Cu")
		(net "M_A_CPU1_SB_DQ<19>")
	)
	(segment
		(start 61.966348 -301.657258)
		(end 61.815472 -301.657258)
		(width 0.10668)
		(layer "F.Cu")
		(net "M_A_CPU1_SB_DQ<19>")
	)
	(segment
		(start 74.046588 -284.833314)
		(end 68.964302 -289.9156)
		(width 0.10668)
		(layer "F.Cu")
		(net "M_A_CPU1_SB_DQ<19>")
	)
	(segment
		(start 57.715658 -302.310292)
		(end 57.290716 -302.735234)
		(width 0.101346)
		(layer "F.Cu")
		(net "M_A_CPU1_SB_DQ<19>")
	)
	(segment
		(start 68.964302 -294.659304)
		(end 61.966348 -301.657258)
		(width 0.10668)
		(layer "F.Cu")
		(net "M_A_CPU1_SB_DQ<19>")
	)
	(arc
		(start 78.42504 -284.837886)
		(mid 78.242789 -284.787536)
		(end 78.05928 -284.83306)
		(width 0.0762)
		(layer "F.Cu")
		(net "M_A_CPU1_SB_DQ<19>")
	)
	(arc
		(start 79.598012 -284.912054)
		(mid 79.477363 -284.887753)
		(end 79.36484 -284.837886)
		(width 0.0762)
		(layer "F.Cu")
		(net "M_A_CPU1_SB_DQ<19>")
	)
	(arc
		(start 79.36484 -284.837886)
		(mid 79.177896 -284.787631)
		(end 78.990952 -284.837886)
		(width 0.0762)
		(layer "F.Cu")
		(net "M_A_CPU1_SB_DQ<19>")
	)
	(arc
		(start 80.11795 -285.160466)
		(mid 79.880338 -284.989478)
		(end 79.598012 -284.912054)
		(width 0.0762)
		(layer "F.Cu")
		(net "M_A_CPU1_SB_DQ<19>")
	)
	(arc
		(start 78.990952 -284.837886)
		(mid 78.707996 -284.914063)
		(end 78.42504 -284.837886)
		(width 0.0762)
		(layer "F.Cu")
		(net "M_A_CPU1_SB_DQ<19>")
	)
	(arc
		(start 78.050898 -284.837886)
		(mid 77.937174 -284.888187)
		(end 77.815186 -284.912308)
		(width 0.0762)
		(layer "F.Cu")
		(net "M_A_CPU1_SB_DQ<19>")
	)
	(arc
		(start 77.815186 -284.912308)
		(mid 77.791709 -284.913684)
		(end 77.768196 -284.914086)
		(width 0.0762)
		(layer "F.Cu")
		(net "M_A_CPU1_SB_DQ<19>")
	)
	(segment
		(start 57.593484 -300.494192)
		(end 57.492138 -300.392846)
		(width 0.101346)
		(layer "F.Cu")
		(net "M_A_CPU1_SB_DQ<18>")
	)
	(segment
		(start 75.960986 -284.152594)
		(end 73.76414 -284.152594)
		(width 0.10668)
		(layer "F.Cu")
		(net "M_A_CPU1_SB_DQ<18>")
	)
	(segment
		(start 56.806084 -300.494192)
		(end 56.704738 -300.392846)
		(width 0.101346)
		(layer "F.Cu")
		(net "M_A_CPU1_SB_DQ<18>")
	)
	(segment
		(start 57.951624 -301.035212)
		(end 57.69483 -301.035212)
		(width 0.101346)
		(layer "F.Cu")
		(net "M_A_CPU1_SB_DQ<18>")
	)
	(segment
		(start 57.199784 -301.576232)
		(end 57.098438 -301.677578)
		(width 0.101346)
		(layer "F.Cu")
		(net "M_A_CPU1_SB_DQ<18>")
	)
	(segment
		(start 57.593484 -300.933866)
		(end 57.593484 -300.494192)
		(width 0.101346)
		(layer "F.Cu")
		(net "M_A_CPU1_SB_DQ<18>")
	)
	(segment
		(start 77.767942 -283.977334)
		(end 76.553568 -283.977334)
		(width 0.0762)
		(layer "F.Cu")
		(net "M_A_CPU1_SB_DQ<18>")
	)
	(segment
		(start 56.412384 -300.494192)
		(end 56.412384 -300.933866)
		(width 0.101346)
		(layer "F.Cu")
		(net "M_A_CPU1_SB_DQ<18>")
	)
	(segment
		(start 57.69483 -301.035212)
		(end 57.593484 -300.933866)
		(width 0.101346)
		(layer "F.Cu")
		(net "M_A_CPU1_SB_DQ<18>")
	)
	(segment
		(start 56.51373 -300.392846)
		(end 56.412384 -300.494192)
		(width 0.101346)
		(layer "F.Cu")
		(net "M_A_CPU1_SB_DQ<18>")
	)
	(segment
		(start 57.492138 -300.392846)
		(end 57.30113 -300.392846)
		(width 0.101346)
		(layer "F.Cu")
		(net "M_A_CPU1_SB_DQ<18>")
	)
	(segment
		(start 68.283582 -289.633152)
		(end 68.283582 -293.869872)
		(width 0.10668)
		(layer "F.Cu")
		(net "M_A_CPU1_SB_DQ<18>")
	)
	(segment
		(start 76.378308 -284.152594)
		(end 75.960986 -284.152594)
		(width 0.0762)
		(layer "F.Cu")
		(net "M_A_CPU1_SB_DQ<18>")
	)
	(segment
		(start 56.412384 -300.933866)
		(end 56.311038 -301.035212)
		(width 0.101346)
		(layer "F.Cu")
		(net "M_A_CPU1_SB_DQ<18>")
	)
	(segment
		(start 56.704738 -300.392846)
		(end 56.51373 -300.392846)
		(width 0.101346)
		(layer "F.Cu")
		(net "M_A_CPU1_SB_DQ<18>")
	)
	(segment
		(start 56.90743 -301.677578)
		(end 56.806084 -301.576232)
		(width 0.101346)
		(layer "F.Cu")
		(net "M_A_CPU1_SB_DQ<18>")
	)
	(segment
		(start 57.199784 -300.494192)
		(end 57.199784 -301.576232)
		(width 0.101346)
		(layer "F.Cu")
		(net "M_A_CPU1_SB_DQ<18>")
	)
	(segment
		(start 73.76414 -284.152594)
		(end 68.283582 -289.633152)
		(width 0.10668)
		(layer "F.Cu")
		(net "M_A_CPU1_SB_DQ<18>")
	)
	(segment
		(start 68.283582 -293.869872)
		(end 61.543184 -300.61027)
		(width 0.10668)
		(layer "F.Cu")
		(net "M_A_CPU1_SB_DQ<18>")
	)
	(segment
		(start 57.098438 -301.677578)
		(end 56.90743 -301.677578)
		(width 0.101346)
		(layer "F.Cu")
		(net "M_A_CPU1_SB_DQ<18>")
	)
	(segment
		(start 56.806084 -301.576232)
		(end 56.806084 -300.494192)
		(width 0.101346)
		(layer "F.Cu")
		(net "M_A_CPU1_SB_DQ<18>")
	)
	(segment
		(start 61.543184 -300.61027)
		(end 60.725812 -300.61027)
		(width 0.10668)
		(layer "F.Cu")
		(net "M_A_CPU1_SB_DQ<18>")
	)
	(segment
		(start 57.30113 -300.392846)
		(end 57.199784 -300.494192)
		(width 0.101346)
		(layer "F.Cu")
		(net "M_A_CPU1_SB_DQ<18>")
	)
	(segment
		(start 76.553568 -283.977334)
		(end 76.378308 -284.152594)
		(width 0.0762)
		(layer "F.Cu")
		(net "M_A_CPU1_SB_DQ<18>")
	)
	(segment
		(start 60.725812 -300.61027)
		(end 58.376566 -300.61027)
		(width 0.101346)
		(layer "F.Cu")
		(net "M_A_CPU1_SB_DQ<18>")
	)
	(segment
		(start 58.376566 -300.61027)
		(end 57.951624 -301.035212)
		(width 0.101346)
		(layer "F.Cu")
		(net "M_A_CPU1_SB_DQ<18>")
	)
	(segment
		(start 56.311038 -301.035212)
		(end 55.328058 -301.035212)
		(width 0.101346)
		(layer "F.Cu")
		(net "M_A_CPU1_SB_DQ<18>")
	)
	(arc
		(start 78.180692 -284.101286)
		(mid 78.063879 -284.07661)
		(end 77.954886 -284.02788)
		(width 0.0762)
		(layer "F.Cu")
		(net "M_A_CPU1_SB_DQ<18>")
	)
	(arc
		(start 78.707996 -284.35046)
		(mid 78.465679 -284.18074)
		(end 78.180692 -284.101286)
		(width 0.0762)
		(layer "F.Cu")
		(net "M_A_CPU1_SB_DQ<18>")
	)
	(arc
		(start 77.954886 -284.02788)
		(mid 77.864753 -283.99026)
		(end 77.767942 -283.977334)
		(width 0.0762)
		(layer "F.Cu")
		(net "M_A_CPU1_SB_DQ<18>")
	)
	(segment
		(start 66.264536 -296.726356)
		(end 66.264536 -296.877232)
		(width 0.10668)
		(layer "F.Cu")
		(net "M_A_CPU1_SB_DQ<17>")
	)
	(segment
		(start 62.182502 -300.959266)
		(end 62.031626 -300.95952)
		(width 0.10668)
		(layer "F.Cu")
		(net "M_A_CPU1_SB_DQ<17>")
	)
	(segment
		(start 63.33998 -299.44568)
		(end 63.442596 -299.548296)
		(width 0.10668)
		(layer "F.Cu")
		(net "M_A_CPU1_SB_DQ<17>")
	)
	(segment
		(start 62.211204 -300.574456)
		(end 62.31382 -300.677072)
		(width 0.10668)
		(layer "F.Cu")
		(net "M_A_CPU1_SB_DQ<17>")
	)
	(segment
		(start 64.571372 -298.570396)
		(end 64.440054 -298.701714)
		(width 0.10668)
		(layer "F.Cu")
		(net "M_A_CPU1_SB_DQ<17>")
	)
	(segment
		(start 65.982342 -297.008804)
		(end 65.879726 -296.906188)
		(width 0.10668)
		(layer "F.Cu")
		(net "M_A_CPU1_SB_DQ<17>")
	)
	(segment
		(start 63.622174 -299.16374)
		(end 63.471298 -299.16374)
		(width 0.10668)
		(layer "F.Cu")
		(net "M_A_CPU1_SB_DQ<17>")
	)
	(segment
		(start 63.057786 -299.728128)
		(end 62.90691 -299.728128)
		(width 0.10668)
		(layer "F.Cu")
		(net "M_A_CPU1_SB_DQ<17>")
	)
	(segment
		(start 65.56883 -297.572938)
		(end 65.417954 -297.573192)
		(width 0.10668)
		(layer "F.Cu")
		(net "M_A_CPU1_SB_DQ<17>")
	)
	(segment
		(start 67.393312 -295.59758)
		(end 67.393312 -295.748456)
		(width 0.10668)
		(layer "F.Cu")
		(net "M_A_CPU1_SB_DQ<17>")
	)
	(segment
		(start 66.726308 -296.059352)
		(end 66.828924 -296.161968)
		(width 0.10668)
		(layer "F.Cu")
		(net "M_A_CPU1_SB_DQ<17>")
	)
	(segment
		(start 68.522088 -294.61968)
		(end 68.39077 -294.750998)
		(width 0.10668)
		(layer "F.Cu")
		(net "M_A_CPU1_SB_DQ<17>")
	)
	(segment
		(start 68.522088 -294.468804)
		(end 68.522088 -294.61968)
		(width 0.10668)
		(layer "F.Cu")
		(net "M_A_CPU1_SB_DQ<17>")
	)
	(segment
		(start 67.9577 -295.184068)
		(end 67.826382 -295.315386)
		(width 0.10668)
		(layer "F.Cu")
		(net "M_A_CPU1_SB_DQ<17>")
	)
	(segment
		(start 65.700148 -297.44162)
		(end 65.56883 -297.572938)
		(width 0.10668)
		(layer "F.Cu")
		(net "M_A_CPU1_SB_DQ<17>")
	)
	(segment
		(start 65.164462 -297.470576)
		(end 65.03289 -297.602148)
		(width 0.10668)
		(layer "F.Cu")
		(net "M_A_CPU1_SB_DQ<17>")
	)
	(segment
		(start 64.006984 -299.134784)
		(end 63.875666 -299.266102)
		(width 0.10668)
		(layer "F.Cu")
		(net "M_A_CPU1_SB_DQ<17>")
	)
	(segment
		(start 67.422014 -295.213024)
		(end 67.290442 -295.344596)
		(width 0.10668)
		(layer "F.Cu")
		(net "M_A_CPU1_SB_DQ<17>")
	)
	(segment
		(start 66.161666 -296.473372)
		(end 66.16192 -296.62374)
		(width 0.10668)
		(layer "F.Cu")
		(net "M_A_CPU1_SB_DQ<17>")
	)
	(segment
		(start 68.137278 -294.648636)
		(end 67.986402 -294.648636)
		(width 0.10668)
		(layer "F.Cu")
		(net "M_A_CPU1_SB_DQ<17>")
	)
	(segment
		(start 66.726054 -295.908984)
		(end 66.726308 -296.059352)
		(width 0.10668)
		(layer "F.Cu")
		(net "M_A_CPU1_SB_DQ<17>")
	)
	(segment
		(start 66.444114 -296.3418)
		(end 66.293238 -296.3418)
		(width 0.10668)
		(layer "F.Cu")
		(net "M_A_CPU1_SB_DQ<17>")
	)
	(segment
		(start 62.31382 -300.677072)
		(end 62.31382 -300.827948)
		(width 0.10668)
		(layer "F.Cu")
		(net "M_A_CPU1_SB_DQ<17>")
	)
	(segment
		(start 66.16192 -296.62374)
		(end 66.264536 -296.726356)
		(width 0.10668)
		(layer "F.Cu")
		(net "M_A_CPU1_SB_DQ<17>")
	)
	(segment
		(start 63.875666 -299.266102)
		(end 63.72479 -299.266356)
		(width 0.10668)
		(layer "F.Cu")
		(net "M_A_CPU1_SB_DQ<17>")
	)
	(segment
		(start 63.442596 -299.699172)
		(end 63.311278 -299.83049)
		(width 0.10668)
		(layer "F.Cu")
		(net "M_A_CPU1_SB_DQ<17>")
	)
	(segment
		(start 64.571372 -298.41952)
		(end 64.571372 -298.570396)
		(width 0.10668)
		(layer "F.Cu")
		(net "M_A_CPU1_SB_DQ<17>")
	)
	(segment
		(start 67.261994 -295.879774)
		(end 67.111118 -295.880028)
		(width 0.10668)
		(layer "F.Cu")
		(net "M_A_CPU1_SB_DQ<17>")
	)
	(segment
		(start 66.133218 -297.00855)
		(end 65.982342 -297.008804)
		(width 0.10668)
		(layer "F.Cu")
		(net "M_A_CPU1_SB_DQ<17>")
	)
	(segment
		(start 64.468756 -298.316904)
		(end 64.571372 -298.41952)
		(width 0.10668)
		(layer "F.Cu")
		(net "M_A_CPU1_SB_DQ<17>")
	)
	(segment
		(start 62.775592 -300.010068)
		(end 62.878208 -300.112684)
		(width 0.10668)
		(layer "F.Cu")
		(net "M_A_CPU1_SB_DQ<17>")
	)
	(segment
		(start 63.904368 -298.881292)
		(end 64.006984 -298.983908)
		(width 0.10668)
		(layer "F.Cu")
		(net "M_A_CPU1_SB_DQ<17>")
	)
	(segment
		(start 65.417954 -297.573192)
		(end 65.315338 -297.470576)
		(width 0.10668)
		(layer "F.Cu")
		(net "M_A_CPU1_SB_DQ<17>")
	)
	(segment
		(start 61.684154 -300.95063)
		(end 60.911486 -300.95063)
		(width 0.10668)
		(layer "F.Cu")
		(net "M_A_CPU1_SB_DQ<17>")
	)
	(segment
		(start 60.76315 -301.56912)
		(end 60.44692 -301.88535)
		(width 0.10668)
		(layer "F.Cu")
		(net "M_A_CPU1_SB_DQ<17>")
	)
	(segment
		(start 65.033144 -297.752516)
		(end 65.13576 -297.855132)
		(width 0.10668)
		(layer "F.Cu")
		(net "M_A_CPU1_SB_DQ<17>")
	)
	(segment
		(start 61.92901 -300.856904)
		(end 61.77788 -300.856904)
		(width 0.10668)
		(layer "F.Cu")
		(net "M_A_CPU1_SB_DQ<17>")
	)
	(segment
		(start 60.911486 -300.95063)
		(end 60.76315 -301.098966)
		(width 0.10668)
		(layer "F.Cu")
		(net "M_A_CPU1_SB_DQ<17>")
	)
	(segment
		(start 66.828924 -296.161968)
		(end 66.828924 -296.312844)
		(width 0.10668)
		(layer "F.Cu")
		(net "M_A_CPU1_SB_DQ<17>")
	)
	(segment
		(start 68.39077 -294.750998)
		(end 68.239894 -294.751252)
		(width 0.10668)
		(layer "F.Cu")
		(net "M_A_CPU1_SB_DQ<17>")
	)
	(segment
		(start 60.76315 -301.098966)
		(end 60.76315 -301.56912)
		(width 0.10668)
		(layer "F.Cu")
		(net "M_A_CPU1_SB_DQ<17>")
	)
	(segment
		(start 66.697606 -296.444162)
		(end 66.54673 -296.444416)
		(width 0.10668)
		(layer "F.Cu")
		(net "M_A_CPU1_SB_DQ<17>")
	)
	(segment
		(start 62.775338 -299.8597)
		(end 62.775592 -300.010068)
		(width 0.10668)
		(layer "F.Cu")
		(net "M_A_CPU1_SB_DQ<17>")
	)
	(segment
		(start 64.006984 -298.983908)
		(end 64.006984 -299.134784)
		(width 0.10668)
		(layer "F.Cu")
		(net "M_A_CPU1_SB_DQ<17>")
	)
	(segment
		(start 73.905364 -284.492954)
		(end 68.623942 -289.774376)
		(width 0.10668)
		(layer "F.Cu")
		(net "M_A_CPU1_SB_DQ<17>")
	)
	(segment
		(start 67.290442 -295.344596)
		(end 67.290696 -295.494964)
		(width 0.10668)
		(layer "F.Cu")
		(net "M_A_CPU1_SB_DQ<17>")
	)
	(segment
		(start 79.469234 -284.677866)
		(end 79.460852 -284.67304)
		(width 0.0762)
		(layer "F.Cu")
		(net "M_A_CPU1_SB_DQ<17>")
	)
	(segment
		(start 77.767942 -284.723586)
		(end 76.822808 -284.723586)
		(width 0.0762)
		(layer "F.Cu")
		(net "M_A_CPU1_SB_DQ<17>")
	)
	(segment
		(start 64.853566 -298.13758)
		(end 64.75095 -298.034964)
		(width 0.10668)
		(layer "F.Cu")
		(net "M_A_CPU1_SB_DQ<17>")
	)
	(segment
		(start 63.311278 -299.83049)
		(end 63.160402 -299.830744)
		(width 0.10668)
		(layer "F.Cu")
		(net "M_A_CPU1_SB_DQ<17>")
	)
	(segment
		(start 62.74689 -300.394878)
		(end 62.596014 -300.395132)
		(width 0.10668)
		(layer "F.Cu")
		(net "M_A_CPU1_SB_DQ<17>")
	)
	(segment
		(start 62.878208 -300.26356)
		(end 62.74689 -300.394878)
		(width 0.10668)
		(layer "F.Cu")
		(net "M_A_CPU1_SB_DQ<17>")
	)
	(segment
		(start 65.597278 -297.03776)
		(end 65.597532 -297.188128)
		(width 0.10668)
		(layer "F.Cu")
		(net "M_A_CPU1_SB_DQ<17>")
	)
	(segment
		(start 62.342522 -300.292516)
		(end 62.21095 -300.424088)
		(width 0.10668)
		(layer "F.Cu")
		(net "M_A_CPU1_SB_DQ<17>")
	)
	(segment
		(start 76.592176 -284.492954)
		(end 75.960986 -284.492954)
		(width 0.0762)
		(layer "F.Cu")
		(net "M_A_CPU1_SB_DQ<17>")
	)
	(segment
		(start 65.315338 -297.470576)
		(end 65.164462 -297.470576)
		(width 0.10668)
		(layer "F.Cu")
		(net "M_A_CPU1_SB_DQ<17>")
	)
	(segment
		(start 66.857626 -295.777412)
		(end 66.726054 -295.908984)
		(width 0.10668)
		(layer "F.Cu")
		(net "M_A_CPU1_SB_DQ<17>")
	)
	(segment
		(start 67.57289 -295.213024)
		(end 67.422014 -295.213024)
		(width 0.10668)
		(layer "F.Cu")
		(net "M_A_CPU1_SB_DQ<17>")
	)
	(segment
		(start 66.293238 -296.3418)
		(end 66.161666 -296.473372)
		(width 0.10668)
		(layer "F.Cu")
		(net "M_A_CPU1_SB_DQ<17>")
	)
	(segment
		(start 67.986402 -294.648636)
		(end 67.85483 -294.780208)
		(width 0.10668)
		(layer "F.Cu")
		(net "M_A_CPU1_SB_DQ<17>")
	)
	(segment
		(start 60.44692 -301.88535)
		(end 59.428126 -301.88535)
		(width 0.10668)
		(layer "F.Cu")
		(net "M_A_CPU1_SB_DQ<17>")
	)
	(segment
		(start 63.442596 -299.548296)
		(end 63.442596 -299.699172)
		(width 0.10668)
		(layer "F.Cu")
		(net "M_A_CPU1_SB_DQ<17>")
	)
	(segment
		(start 64.186562 -298.599352)
		(end 64.035686 -298.599352)
		(width 0.10668)
		(layer "F.Cu")
		(net "M_A_CPU1_SB_DQ<17>")
	)
	(segment
		(start 63.904114 -298.730924)
		(end 63.904368 -298.881292)
		(width 0.10668)
		(layer "F.Cu")
		(net "M_A_CPU1_SB_DQ<17>")
	)
	(segment
		(start 67.393312 -295.748456)
		(end 67.261994 -295.879774)
		(width 0.10668)
		(layer "F.Cu")
		(net "M_A_CPU1_SB_DQ<17>")
	)
	(segment
		(start 62.21095 -300.424088)
		(end 62.211204 -300.574456)
		(width 0.10668)
		(layer "F.Cu")
		(net "M_A_CPU1_SB_DQ<17>")
	)
	(segment
		(start 64.440054 -298.701714)
		(end 64.289178 -298.701968)
		(width 0.10668)
		(layer "F.Cu")
		(net "M_A_CPU1_SB_DQ<17>")
	)
	(segment
		(start 67.855084 -294.930576)
		(end 67.9577 -295.033192)
		(width 0.10668)
		(layer "F.Cu")
		(net "M_A_CPU1_SB_DQ<17>")
	)
	(segment
		(start 65.72885 -296.906188)
		(end 65.597278 -297.03776)
		(width 0.10668)
		(layer "F.Cu")
		(net "M_A_CPU1_SB_DQ<17>")
	)
	(segment
		(start 63.339726 -299.295312)
		(end 63.33998 -299.44568)
		(width 0.10668)
		(layer "F.Cu")
		(net "M_A_CPU1_SB_DQ<17>")
	)
	(segment
		(start 62.90691 -299.728128)
		(end 62.775338 -299.8597)
		(width 0.10668)
		(layer "F.Cu")
		(net "M_A_CPU1_SB_DQ<17>")
	)
	(segment
		(start 66.828924 -296.312844)
		(end 66.697606 -296.444162)
		(width 0.10668)
		(layer "F.Cu")
		(net "M_A_CPU1_SB_DQ<17>")
	)
	(segment
		(start 62.31382 -300.827948)
		(end 62.182502 -300.959266)
		(width 0.10668)
		(layer "F.Cu")
		(net "M_A_CPU1_SB_DQ<17>")
	)
	(segment
		(start 65.03289 -297.602148)
		(end 65.033144 -297.752516)
		(width 0.10668)
		(layer "F.Cu")
		(net "M_A_CPU1_SB_DQ<17>")
	)
	(segment
		(start 76.822808 -284.723586)
		(end 76.592176 -284.492954)
		(width 0.0762)
		(layer "F.Cu")
		(net "M_A_CPU1_SB_DQ<17>")
	)
	(segment
		(start 64.75095 -298.034964)
		(end 64.600074 -298.034964)
		(width 0.10668)
		(layer "F.Cu")
		(net "M_A_CPU1_SB_DQ<17>")
	)
	(segment
		(start 62.596014 -300.395132)
		(end 62.493398 -300.292516)
		(width 0.10668)
		(layer "F.Cu")
		(net "M_A_CPU1_SB_DQ<17>")
	)
	(segment
		(start 61.77788 -300.856904)
		(end 61.684154 -300.95063)
		(width 0.10668)
		(layer "F.Cu")
		(net "M_A_CPU1_SB_DQ<17>")
	)
	(segment
		(start 68.419218 -294.21582)
		(end 68.419472 -294.366188)
		(width 0.10668)
		(layer "F.Cu")
		(net "M_A_CPU1_SB_DQ<17>")
	)
	(segment
		(start 68.623942 -294.011096)
		(end 68.419218 -294.21582)
		(width 0.10668)
		(layer "F.Cu")
		(net "M_A_CPU1_SB_DQ<17>")
	)
	(segment
		(start 62.031626 -300.95952)
		(end 61.92901 -300.856904)
		(width 0.10668)
		(layer "F.Cu")
		(net "M_A_CPU1_SB_DQ<17>")
	)
	(segment
		(start 65.700148 -297.290744)
		(end 65.700148 -297.44162)
		(width 0.10668)
		(layer "F.Cu")
		(net "M_A_CPU1_SB_DQ<17>")
	)
	(segment
		(start 67.826382 -295.315386)
		(end 67.675506 -295.31564)
		(width 0.10668)
		(layer "F.Cu")
		(net "M_A_CPU1_SB_DQ<17>")
	)
	(segment
		(start 63.471298 -299.16374)
		(end 63.339726 -299.295312)
		(width 0.10668)
		(layer "F.Cu")
		(net "M_A_CPU1_SB_DQ<17>")
	)
	(segment
		(start 64.600074 -298.034964)
		(end 64.468502 -298.166536)
		(width 0.10668)
		(layer "F.Cu")
		(net "M_A_CPU1_SB_DQ<17>")
	)
	(segment
		(start 63.160402 -299.830744)
		(end 63.057786 -299.728128)
		(width 0.10668)
		(layer "F.Cu")
		(net "M_A_CPU1_SB_DQ<17>")
	)
	(segment
		(start 65.13576 -298.006008)
		(end 65.004442 -298.137326)
		(width 0.10668)
		(layer "F.Cu")
		(net "M_A_CPU1_SB_DQ<17>")
	)
	(segment
		(start 78.89494 -284.67304)
		(end 78.886558 -284.677866)
		(width 0.0762)
		(layer "F.Cu")
		(net "M_A_CPU1_SB_DQ<17>")
	)
	(segment
		(start 68.239894 -294.751252)
		(end 68.137278 -294.648636)
		(width 0.10668)
		(layer "F.Cu")
		(net "M_A_CPU1_SB_DQ<17>")
	)
	(segment
		(start 62.878208 -300.112684)
		(end 62.878208 -300.26356)
		(width 0.10668)
		(layer "F.Cu")
		(net "M_A_CPU1_SB_DQ<17>")
	)
	(segment
		(start 66.54673 -296.444416)
		(end 66.444114 -296.3418)
		(width 0.10668)
		(layer "F.Cu")
		(net "M_A_CPU1_SB_DQ<17>")
	)
	(segment
		(start 75.960986 -284.492954)
		(end 73.905364 -284.492954)
		(width 0.10668)
		(layer "F.Cu")
		(net "M_A_CPU1_SB_DQ<17>")
	)
	(segment
		(start 62.493398 -300.292516)
		(end 62.342522 -300.292516)
		(width 0.10668)
		(layer "F.Cu")
		(net "M_A_CPU1_SB_DQ<17>")
	)
	(segment
		(start 79.647796 -284.35046)
		(end 79.748634 -284.523942)
		(width 0.0762)
		(layer "F.Cu")
		(net "M_A_CPU1_SB_DQ<17>")
	)
	(segment
		(start 65.13576 -297.855132)
		(end 65.13576 -298.006008)
		(width 0.10668)
		(layer "F.Cu")
		(net "M_A_CPU1_SB_DQ<17>")
	)
	(segment
		(start 67.111118 -295.880028)
		(end 67.008502 -295.777412)
		(width 0.10668)
		(layer "F.Cu")
		(net "M_A_CPU1_SB_DQ<17>")
	)
	(segment
		(start 67.85483 -294.780208)
		(end 67.855084 -294.930576)
		(width 0.10668)
		(layer "F.Cu")
		(net "M_A_CPU1_SB_DQ<17>")
	)
	(segment
		(start 66.264536 -296.877232)
		(end 66.133218 -297.00855)
		(width 0.10668)
		(layer "F.Cu")
		(net "M_A_CPU1_SB_DQ<17>")
	)
	(segment
		(start 64.289178 -298.701968)
		(end 64.186562 -298.599352)
		(width 0.10668)
		(layer "F.Cu")
		(net "M_A_CPU1_SB_DQ<17>")
	)
	(segment
		(start 68.419472 -294.366188)
		(end 68.522088 -294.468804)
		(width 0.10668)
		(layer "F.Cu")
		(net "M_A_CPU1_SB_DQ<17>")
	)
	(segment
		(start 64.035686 -298.599352)
		(end 63.904114 -298.730924)
		(width 0.10668)
		(layer "F.Cu")
		(net "M_A_CPU1_SB_DQ<17>")
	)
	(segment
		(start 63.72479 -299.266356)
		(end 63.622174 -299.16374)
		(width 0.10668)
		(layer "F.Cu")
		(net "M_A_CPU1_SB_DQ<17>")
	)
	(segment
		(start 65.597532 -297.188128)
		(end 65.700148 -297.290744)
		(width 0.10668)
		(layer "F.Cu")
		(net "M_A_CPU1_SB_DQ<17>")
	)
	(segment
		(start 68.623942 -289.774376)
		(end 68.623942 -294.011096)
		(width 0.10668)
		(layer "F.Cu")
		(net "M_A_CPU1_SB_DQ<17>")
	)
	(segment
		(start 65.004442 -298.137326)
		(end 64.853566 -298.13758)
		(width 0.10668)
		(layer "F.Cu")
		(net "M_A_CPU1_SB_DQ<17>")
	)
	(segment
		(start 65.879726 -296.906188)
		(end 65.72885 -296.906188)
		(width 0.10668)
		(layer "F.Cu")
		(net "M_A_CPU1_SB_DQ<17>")
	)
	(segment
		(start 64.468502 -298.166536)
		(end 64.468756 -298.316904)
		(width 0.10668)
		(layer "F.Cu")
		(net "M_A_CPU1_SB_DQ<17>")
	)
	(segment
		(start 67.9577 -295.033192)
		(end 67.9577 -295.184068)
		(width 0.10668)
		(layer "F.Cu")
		(net "M_A_CPU1_SB_DQ<17>")
	)
	(segment
		(start 67.675506 -295.31564)
		(end 67.57289 -295.213024)
		(width 0.10668)
		(layer "F.Cu")
		(net "M_A_CPU1_SB_DQ<17>")
	)
	(segment
		(start 67.290696 -295.494964)
		(end 67.393312 -295.59758)
		(width 0.10668)
		(layer "F.Cu")
		(net "M_A_CPU1_SB_DQ<17>")
	)
	(segment
		(start 67.008502 -295.777412)
		(end 66.857626 -295.777412)
		(width 0.10668)
		(layer "F.Cu")
		(net "M_A_CPU1_SB_DQ<17>")
	)
	(arc
		(start 79.748634 -284.523942)
		(mid 79.732709 -284.664634)
		(end 79.602584 -284.720538)
		(width 0.0762)
		(layer "F.Cu")
		(net "M_A_CPU1_SB_DQ<17>")
	)
	(arc
		(start 79.602584 -284.720538)
		(mid 79.533886 -284.705522)
		(end 79.469234 -284.677866)
		(width 0.0762)
		(layer "F.Cu")
		(net "M_A_CPU1_SB_DQ<17>")
	)
	(arc
		(start 78.520798 -284.67304)
		(mid 78.237842 -284.596863)
		(end 77.954886 -284.67304)
		(width 0.0762)
		(layer "F.Cu")
		(net "M_A_CPU1_SB_DQ<17>")
	)
	(arc
		(start 78.886558 -284.677866)
		(mid 78.70305 -284.72336)
		(end 78.520798 -284.67304)
		(width 0.0762)
		(layer "F.Cu")
		(net "M_A_CPU1_SB_DQ<17>")
	)
	(arc
		(start 79.460852 -284.67304)
		(mid 79.177896 -284.596863)
		(end 78.89494 -284.67304)
		(width 0.0762)
		(layer "F.Cu")
		(net "M_A_CPU1_SB_DQ<17>")
	)
	(arc
		(start 77.79893 -284.722316)
		(mid 77.783449 -284.723272)
		(end 77.767942 -284.723586)
		(width 0.0762)
		(layer "F.Cu")
		(net "M_A_CPU1_SB_DQ<17>")
	)
	(arc
		(start 77.954886 -284.67304)
		(mid 77.879646 -284.706353)
		(end 77.79893 -284.722316)
		(width 0.0762)
		(layer "F.Cu")
		(net "M_A_CPU1_SB_DQ<17>")
	)
	(segment
		(start 62.0141 -298.996608)
		(end 62.0141 -299.147484)
		(width 0.10668)
		(layer "F.Cu")
		(net "M_A_CPU1_SB_DQ<16>")
	)
	(segment
		(start 67.093592 -294.067992)
		(end 67.27317 -294.24757)
		(width 0.10668)
		(layer "F.Cu")
		(net "M_A_CPU1_SB_DQ<16>")
	)
	(segment
		(start 67.27317 -294.24757)
		(end 67.27317 -294.398446)
		(width 0.10668)
		(layer "F.Cu")
		(net "M_A_CPU1_SB_DQ<16>")
	)
	(segment
		(start 62.193678 -299.477938)
		(end 62.06236 -299.609256)
		(width 0.10668)
		(layer "F.Cu")
		(net "M_A_CPU1_SB_DQ<16>")
	)
	(segment
		(start 66.577464 -295.094152)
		(end 66.426588 -295.094152)
		(width 0.10668)
		(layer "F.Cu")
		(net "M_A_CPU1_SB_DQ<16>")
	)
	(segment
		(start 61.449712 -299.711872)
		(end 61.62929 -299.89145)
		(width 0.10668)
		(layer "F.Cu")
		(net "M_A_CPU1_SB_DQ<16>")
	)
	(segment
		(start 61.449712 -299.560996)
		(end 61.449712 -299.711872)
		(width 0.10668)
		(layer "F.Cu")
		(net "M_A_CPU1_SB_DQ<16>")
	)
	(segment
		(start 66.013076 -295.65854)
		(end 65.8622 -295.65854)
		(width 0.10668)
		(layer "F.Cu")
		(net "M_A_CPU1_SB_DQ<16>")
	)
	(segment
		(start 62.758066 -298.91355)
		(end 62.626748 -299.044868)
		(width 0.10668)
		(layer "F.Cu")
		(net "M_A_CPU1_SB_DQ<16>")
	)
	(segment
		(start 62.758066 -298.762674)
		(end 62.758066 -298.91355)
		(width 0.10668)
		(layer "F.Cu")
		(net "M_A_CPU1_SB_DQ<16>")
	)
	(segment
		(start 65.015618 -296.505122)
		(end 65.015618 -296.655998)
		(width 0.10668)
		(layer "F.Cu")
		(net "M_A_CPU1_SB_DQ<16>")
	)
	(segment
		(start 61.62929 -299.89145)
		(end 61.62929 -300.042326)
		(width 0.10668)
		(layer "F.Cu")
		(net "M_A_CPU1_SB_DQ<16>")
	)
	(segment
		(start 62.193678 -299.327062)
		(end 62.193678 -299.477938)
		(width 0.10668)
		(layer "F.Cu")
		(net "M_A_CPU1_SB_DQ<16>")
	)
	(segment
		(start 67.943222 -289.491928)
		(end 67.943222 -293.067486)
		(width 0.10668)
		(layer "F.Cu")
		(net "M_A_CPU1_SB_DQ<16>")
	)
	(segment
		(start 67.943222 -293.067486)
		(end 67.65798 -293.352728)
		(width 0.10668)
		(layer "F.Cu")
		(net "M_A_CPU1_SB_DQ<16>")
	)
	(segment
		(start 67.70624 -293.965376)
		(end 67.555364 -293.965376)
		(width 0.10668)
		(layer "F.Cu")
		(net "M_A_CPU1_SB_DQ<16>")
	)
	(segment
		(start 64.319912 -297.351704)
		(end 64.169036 -297.351704)
		(width 0.10668)
		(layer "F.Cu")
		(net "M_A_CPU1_SB_DQ<16>")
	)
	(segment
		(start 67.65798 -293.503604)
		(end 67.837558 -293.683182)
		(width 0.10668)
		(layer "F.Cu")
		(net "M_A_CPU1_SB_DQ<16>")
	)
	(segment
		(start 62.296294 -298.86529)
		(end 62.145418 -298.86529)
		(width 0.10668)
		(layer "F.Cu")
		(net "M_A_CPU1_SB_DQ<16>")
	)
	(segment
		(start 67.65798 -293.352728)
		(end 67.65798 -293.503604)
		(width 0.10668)
		(layer "F.Cu")
		(net "M_A_CPU1_SB_DQ<16>")
	)
	(segment
		(start 65.964816 -295.196768)
		(end 66.144394 -295.376346)
		(width 0.10668)
		(layer "F.Cu")
		(net "M_A_CPU1_SB_DQ<16>")
	)
	(segment
		(start 64.40297 -296.607738)
		(end 64.271652 -296.739056)
		(width 0.10668)
		(layer "F.Cu")
		(net "M_A_CPU1_SB_DQ<16>")
	)
	(segment
		(start 65.297812 -296.222928)
		(end 65.118234 -296.04335)
		(width 0.10668)
		(layer "F.Cu")
		(net "M_A_CPU1_SB_DQ<16>")
	)
	(segment
		(start 61.347096 -300.173644)
		(end 61.167518 -299.994066)
		(width 0.10668)
		(layer "F.Cu")
		(net "M_A_CPU1_SB_DQ<16>")
	)
	(segment
		(start 62.0141 -299.147484)
		(end 62.193678 -299.327062)
		(width 0.10668)
		(layer "F.Cu")
		(net "M_A_CPU1_SB_DQ<16>")
	)
	(segment
		(start 63.707264 -297.45432)
		(end 63.886842 -297.633898)
		(width 0.10668)
		(layer "F.Cu")
		(net "M_A_CPU1_SB_DQ<16>")
	)
	(segment
		(start 63.142876 -298.018708)
		(end 63.322454 -298.198286)
		(width 0.10668)
		(layer "F.Cu")
		(net "M_A_CPU1_SB_DQ<16>")
	)
	(segment
		(start 63.322454 -298.349162)
		(end 63.191136 -298.48048)
		(width 0.10668)
		(layer "F.Cu")
		(net "M_A_CPU1_SB_DQ<16>")
	)
	(segment
		(start 62.578488 -298.583096)
		(end 62.758066 -298.762674)
		(width 0.10668)
		(layer "F.Cu")
		(net "M_A_CPU1_SB_DQ<16>")
	)
	(segment
		(start 73.622916 -283.812234)
		(end 67.943222 -289.491928)
		(width 0.10668)
		(layer "F.Cu")
		(net "M_A_CPU1_SB_DQ<16>")
	)
	(segment
		(start 64.45123 -297.220386)
		(end 64.319912 -297.351704)
		(width 0.10668)
		(layer "F.Cu")
		(net "M_A_CPU1_SB_DQ<16>")
	)
	(segment
		(start 67.141852 -294.529764)
		(end 66.990976 -294.529764)
		(width 0.10668)
		(layer "F.Cu")
		(net "M_A_CPU1_SB_DQ<16>")
	)
	(segment
		(start 64.8843 -296.787316)
		(end 64.733424 -296.787316)
		(width 0.10668)
		(layer "F.Cu")
		(net "M_A_CPU1_SB_DQ<16>")
	)
	(segment
		(start 64.45123 -297.06951)
		(end 64.45123 -297.220386)
		(width 0.10668)
		(layer "F.Cu")
		(net "M_A_CPU1_SB_DQ<16>")
	)
	(segment
		(start 62.578488 -298.43222)
		(end 62.578488 -298.583096)
		(width 0.10668)
		(layer "F.Cu")
		(net "M_A_CPU1_SB_DQ<16>")
	)
	(segment
		(start 66.660522 -294.350186)
		(end 66.529204 -294.481504)
		(width 0.10668)
		(layer "F.Cu")
		(net "M_A_CPU1_SB_DQ<16>")
	)
	(segment
		(start 67.837558 -293.834058)
		(end 67.70624 -293.965376)
		(width 0.10668)
		(layer "F.Cu")
		(net "M_A_CPU1_SB_DQ<16>")
	)
	(segment
		(start 64.553846 -296.607738)
		(end 64.40297 -296.607738)
		(width 0.10668)
		(layer "F.Cu")
		(net "M_A_CPU1_SB_DQ<16>")
	)
	(segment
		(start 61.911484 -299.609256)
		(end 61.731906 -299.429678)
		(width 0.10668)
		(layer "F.Cu")
		(net "M_A_CPU1_SB_DQ<16>")
	)
	(segment
		(start 66.144394 -295.376346)
		(end 66.144394 -295.527222)
		(width 0.10668)
		(layer "F.Cu")
		(net "M_A_CPU1_SB_DQ<16>")
	)
	(segment
		(start 64.271652 -296.739056)
		(end 64.271652 -296.889932)
		(width 0.10668)
		(layer "F.Cu")
		(net "M_A_CPU1_SB_DQ<16>")
	)
	(segment
		(start 64.733424 -296.787316)
		(end 64.553846 -296.607738)
		(width 0.10668)
		(layer "F.Cu")
		(net "M_A_CPU1_SB_DQ<16>")
	)
	(segment
		(start 66.708782 -294.811958)
		(end 66.708782 -294.962834)
		(width 0.10668)
		(layer "F.Cu")
		(net "M_A_CPU1_SB_DQ<16>")
	)
	(segment
		(start 65.448688 -296.222928)
		(end 65.297812 -296.222928)
		(width 0.10668)
		(layer "F.Cu")
		(net "M_A_CPU1_SB_DQ<16>")
	)
	(segment
		(start 66.529204 -294.63238)
		(end 66.708782 -294.811958)
		(width 0.10668)
		(layer "F.Cu")
		(net "M_A_CPU1_SB_DQ<16>")
	)
	(segment
		(start 65.580006 -295.940734)
		(end 65.580006 -296.09161)
		(width 0.10668)
		(layer "F.Cu")
		(net "M_A_CPU1_SB_DQ<16>")
	)
	(segment
		(start 64.83604 -296.325544)
		(end 65.015618 -296.505122)
		(width 0.10668)
		(layer "F.Cu")
		(net "M_A_CPU1_SB_DQ<16>")
	)
	(segment
		(start 78.05928 -283.86786)
		(end 78.050898 -283.863034)
		(width 0.0762)
		(layer "F.Cu")
		(net "M_A_CPU1_SB_DQ<16>")
	)
	(segment
		(start 77.767942 -283.786834)
		(end 76.264516 -283.786834)
		(width 0.0762)
		(layer "F.Cu")
		(net "M_A_CPU1_SB_DQ<16>")
	)
	(segment
		(start 64.271652 -296.889932)
		(end 64.45123 -297.06951)
		(width 0.10668)
		(layer "F.Cu")
		(net "M_A_CPU1_SB_DQ<16>")
	)
	(segment
		(start 66.24701 -294.914574)
		(end 66.096134 -294.914574)
		(width 0.10668)
		(layer "F.Cu")
		(net "M_A_CPU1_SB_DQ<16>")
	)
	(segment
		(start 76.264516 -283.786834)
		(end 76.239116 -283.812234)
		(width 0.0762)
		(layer "F.Cu")
		(net "M_A_CPU1_SB_DQ<16>")
	)
	(segment
		(start 61.497972 -300.173644)
		(end 61.347096 -300.173644)
		(width 0.10668)
		(layer "F.Cu")
		(net "M_A_CPU1_SB_DQ<16>")
	)
	(segment
		(start 61.62929 -300.042326)
		(end 61.497972 -300.173644)
		(width 0.10668)
		(layer "F.Cu")
		(net "M_A_CPU1_SB_DQ<16>")
	)
	(segment
		(start 66.811398 -294.350186)
		(end 66.660522 -294.350186)
		(width 0.10668)
		(layer "F.Cu")
		(net "M_A_CPU1_SB_DQ<16>")
	)
	(segment
		(start 63.42507 -297.736514)
		(end 63.274194 -297.736514)
		(width 0.10668)
		(layer "F.Cu")
		(net "M_A_CPU1_SB_DQ<16>")
	)
	(segment
		(start 65.531746 -295.478962)
		(end 65.400428 -295.61028)
		(width 0.10668)
		(layer "F.Cu")
		(net "M_A_CPU1_SB_DQ<16>")
	)
	(segment
		(start 63.04026 -298.48048)
		(end 62.860682 -298.300902)
		(width 0.10668)
		(layer "F.Cu")
		(net "M_A_CPU1_SB_DQ<16>")
	)
	(segment
		(start 65.964816 -295.045892)
		(end 65.964816 -295.196768)
		(width 0.10668)
		(layer "F.Cu")
		(net "M_A_CPU1_SB_DQ<16>")
	)
	(segment
		(start 65.682622 -295.478962)
		(end 65.531746 -295.478962)
		(width 0.10668)
		(layer "F.Cu")
		(net "M_A_CPU1_SB_DQ<16>")
	)
	(segment
		(start 61.167518 -299.994066)
		(end 61.016642 -299.994066)
		(width 0.10668)
		(layer "F.Cu")
		(net "M_A_CPU1_SB_DQ<16>")
	)
	(segment
		(start 78.237842 -283.540454)
		(end 78.33614 -283.709618)
		(width 0.0762)
		(layer "F.Cu")
		(net "M_A_CPU1_SB_DQ<16>")
	)
	(segment
		(start 65.580006 -296.09161)
		(end 65.448688 -296.222928)
		(width 0.10668)
		(layer "F.Cu")
		(net "M_A_CPU1_SB_DQ<16>")
	)
	(segment
		(start 65.015618 -296.655998)
		(end 64.8843 -296.787316)
		(width 0.10668)
		(layer "F.Cu")
		(net "M_A_CPU1_SB_DQ<16>")
	)
	(segment
		(start 62.626748 -299.044868)
		(end 62.475872 -299.044868)
		(width 0.10668)
		(layer "F.Cu")
		(net "M_A_CPU1_SB_DQ<16>")
	)
	(segment
		(start 63.322454 -298.198286)
		(end 63.322454 -298.349162)
		(width 0.10668)
		(layer "F.Cu")
		(net "M_A_CPU1_SB_DQ<16>")
	)
	(segment
		(start 64.967358 -296.04335)
		(end 64.83604 -296.174668)
		(width 0.10668)
		(layer "F.Cu")
		(net "M_A_CPU1_SB_DQ<16>")
	)
	(segment
		(start 63.707264 -297.303444)
		(end 63.707264 -297.45432)
		(width 0.10668)
		(layer "F.Cu")
		(net "M_A_CPU1_SB_DQ<16>")
	)
	(segment
		(start 65.400428 -295.761156)
		(end 65.580006 -295.940734)
		(width 0.10668)
		(layer "F.Cu")
		(net "M_A_CPU1_SB_DQ<16>")
	)
	(segment
		(start 63.886842 -297.633898)
		(end 63.886842 -297.784774)
		(width 0.10668)
		(layer "F.Cu")
		(net "M_A_CPU1_SB_DQ<16>")
	)
	(segment
		(start 67.22491 -293.785798)
		(end 67.093592 -293.917116)
		(width 0.10668)
		(layer "F.Cu")
		(net "M_A_CPU1_SB_DQ<16>")
	)
	(segment
		(start 61.58103 -299.429678)
		(end 61.449712 -299.560996)
		(width 0.10668)
		(layer "F.Cu")
		(net "M_A_CPU1_SB_DQ<16>")
	)
	(segment
		(start 66.708782 -294.962834)
		(end 66.577464 -295.094152)
		(width 0.10668)
		(layer "F.Cu")
		(net "M_A_CPU1_SB_DQ<16>")
	)
	(segment
		(start 63.604648 -297.916092)
		(end 63.42507 -297.736514)
		(width 0.10668)
		(layer "F.Cu")
		(net "M_A_CPU1_SB_DQ<16>")
	)
	(segment
		(start 63.191136 -298.48048)
		(end 63.04026 -298.48048)
		(width 0.10668)
		(layer "F.Cu")
		(net "M_A_CPU1_SB_DQ<16>")
	)
	(segment
		(start 64.169036 -297.351704)
		(end 63.989458 -297.172126)
		(width 0.10668)
		(layer "F.Cu")
		(net "M_A_CPU1_SB_DQ<16>")
	)
	(segment
		(start 76.239116 -283.812234)
		(end 73.622916 -283.812234)
		(width 0.10668)
		(layer "F.Cu")
		(net "M_A_CPU1_SB_DQ<16>")
	)
	(segment
		(start 63.989458 -297.172126)
		(end 63.838582 -297.172126)
		(width 0.10668)
		(layer "F.Cu")
		(net "M_A_CPU1_SB_DQ<16>")
	)
	(segment
		(start 63.755524 -297.916092)
		(end 63.604648 -297.916092)
		(width 0.10668)
		(layer "F.Cu")
		(net "M_A_CPU1_SB_DQ<16>")
	)
	(segment
		(start 66.426588 -295.094152)
		(end 66.24701 -294.914574)
		(width 0.10668)
		(layer "F.Cu")
		(net "M_A_CPU1_SB_DQ<16>")
	)
	(segment
		(start 63.886842 -297.784774)
		(end 63.755524 -297.916092)
		(width 0.10668)
		(layer "F.Cu")
		(net "M_A_CPU1_SB_DQ<16>")
	)
	(segment
		(start 62.709806 -298.300902)
		(end 62.578488 -298.43222)
		(width 0.10668)
		(layer "F.Cu")
		(net "M_A_CPU1_SB_DQ<16>")
	)
	(segment
		(start 63.274194 -297.736514)
		(end 63.142876 -297.867832)
		(width 0.10668)
		(layer "F.Cu")
		(net "M_A_CPU1_SB_DQ<16>")
	)
	(segment
		(start 67.27317 -294.398446)
		(end 67.141852 -294.529764)
		(width 0.10668)
		(layer "F.Cu")
		(net "M_A_CPU1_SB_DQ<16>")
	)
	(segment
		(start 63.838582 -297.172126)
		(end 63.707264 -297.303444)
		(width 0.10668)
		(layer "F.Cu")
		(net "M_A_CPU1_SB_DQ<16>")
	)
	(segment
		(start 60.82538 -300.185328)
		(end 59.428126 -300.185328)
		(width 0.10668)
		(layer "F.Cu")
		(net "M_A_CPU1_SB_DQ<16>")
	)
	(segment
		(start 66.096134 -294.914574)
		(end 65.964816 -295.045892)
		(width 0.10668)
		(layer "F.Cu")
		(net "M_A_CPU1_SB_DQ<16>")
	)
	(segment
		(start 64.83604 -296.174668)
		(end 64.83604 -296.325544)
		(width 0.10668)
		(layer "F.Cu")
		(net "M_A_CPU1_SB_DQ<16>")
	)
	(segment
		(start 63.142876 -297.867832)
		(end 63.142876 -298.018708)
		(width 0.10668)
		(layer "F.Cu")
		(net "M_A_CPU1_SB_DQ<16>")
	)
	(segment
		(start 65.400428 -295.61028)
		(end 65.400428 -295.761156)
		(width 0.10668)
		(layer "F.Cu")
		(net "M_A_CPU1_SB_DQ<16>")
	)
	(segment
		(start 61.016642 -299.994066)
		(end 60.82538 -300.185328)
		(width 0.10668)
		(layer "F.Cu")
		(net "M_A_CPU1_SB_DQ<16>")
	)
	(segment
		(start 65.8622 -295.65854)
		(end 65.682622 -295.478962)
		(width 0.10668)
		(layer "F.Cu")
		(net "M_A_CPU1_SB_DQ<16>")
	)
	(segment
		(start 67.093592 -293.917116)
		(end 67.093592 -294.067992)
		(width 0.10668)
		(layer "F.Cu")
		(net "M_A_CPU1_SB_DQ<16>")
	)
	(segment
		(start 65.118234 -296.04335)
		(end 64.967358 -296.04335)
		(width 0.10668)
		(layer "F.Cu")
		(net "M_A_CPU1_SB_DQ<16>")
	)
	(segment
		(start 66.529204 -294.481504)
		(end 66.529204 -294.63238)
		(width 0.10668)
		(layer "F.Cu")
		(net "M_A_CPU1_SB_DQ<16>")
	)
	(segment
		(start 62.06236 -299.609256)
		(end 61.911484 -299.609256)
		(width 0.10668)
		(layer "F.Cu")
		(net "M_A_CPU1_SB_DQ<16>")
	)
	(segment
		(start 67.837558 -293.683182)
		(end 67.837558 -293.834058)
		(width 0.10668)
		(layer "F.Cu")
		(net "M_A_CPU1_SB_DQ<16>")
	)
	(segment
		(start 66.990976 -294.529764)
		(end 66.811398 -294.350186)
		(width 0.10668)
		(layer "F.Cu")
		(net "M_A_CPU1_SB_DQ<16>")
	)
	(segment
		(start 66.144394 -295.527222)
		(end 66.013076 -295.65854)
		(width 0.10668)
		(layer "F.Cu")
		(net "M_A_CPU1_SB_DQ<16>")
	)
	(segment
		(start 67.555364 -293.965376)
		(end 67.375786 -293.785798)
		(width 0.10668)
		(layer "F.Cu")
		(net "M_A_CPU1_SB_DQ<16>")
	)
	(segment
		(start 61.731906 -299.429678)
		(end 61.58103 -299.429678)
		(width 0.10668)
		(layer "F.Cu")
		(net "M_A_CPU1_SB_DQ<16>")
	)
	(segment
		(start 67.375786 -293.785798)
		(end 67.22491 -293.785798)
		(width 0.10668)
		(layer "F.Cu")
		(net "M_A_CPU1_SB_DQ<16>")
	)
	(segment
		(start 62.145418 -298.86529)
		(end 62.0141 -298.996608)
		(width 0.10668)
		(layer "F.Cu")
		(net "M_A_CPU1_SB_DQ<16>")
	)
	(segment
		(start 62.475872 -299.044868)
		(end 62.296294 -298.86529)
		(width 0.10668)
		(layer "F.Cu")
		(net "M_A_CPU1_SB_DQ<16>")
	)
	(segment
		(start 62.860682 -298.300902)
		(end 62.709806 -298.300902)
		(width 0.10668)
		(layer "F.Cu")
		(net "M_A_CPU1_SB_DQ<16>")
	)
	(arc
		(start 78.050898 -283.863034)
		(mid 77.914462 -283.806209)
		(end 77.767942 -283.786834)
		(width 0.0762)
		(layer "F.Cu")
		(net "M_A_CPU1_SB_DQ<16>")
	)
	(arc
		(start 78.198472 -283.911294)
		(mid 78.126734 -283.896442)
		(end 78.05928 -283.86786)
		(width 0.0762)
		(layer "F.Cu")
		(net "M_A_CPU1_SB_DQ<16>")
	)
	(arc
		(start 78.33614 -283.709618)
		(mid 78.327547 -283.851497)
		(end 78.198472 -283.911294)
		(width 0.0762)
		(layer "F.Cu")
		(net "M_A_CPU1_SB_DQ<16>")
	)
	(segment
		(start 60.357258 -298.910502)
		(end 58.183526 -298.910502)
		(width 0.101346)
		(layer "F.Cu")
		(net "M_A_CPU1_SB_DQ<15>")
	)
	(segment
		(start 76.472288 -283.294074)
		(end 76.420218 -283.346144)
		(width 0.0762)
		(layer "F.Cu")
		(net "M_A_CPU1_SB_DQ<15>")
	)
	(segment
		(start 62.228476 -298.135294)
		(end 60.725812 -298.757848)
		(width 0.10668)
		(layer "F.Cu")
		(net "M_A_CPU1_SB_DQ<15>")
	)
	(segment
		(start 73.442322 -283.346144)
		(end 67.478148 -289.310318)
		(width 0.10668)
		(layer "F.Cu")
		(net "M_A_CPU1_SB_DQ<15>")
	)
	(segment
		(start 67.478148 -292.885622)
		(end 62.228476 -298.135294)
		(width 0.10668)
		(layer "F.Cu")
		(net "M_A_CPU1_SB_DQ<15>")
	)
	(segment
		(start 67.478148 -289.310318)
		(end 67.478148 -292.885622)
		(width 0.10668)
		(layer "F.Cu")
		(net "M_A_CPU1_SB_DQ<15>")
	)
	(segment
		(start 75.910186 -283.346144)
		(end 73.442322 -283.346144)
		(width 0.10668)
		(layer "F.Cu")
		(net "M_A_CPU1_SB_DQ<15>")
	)
	(segment
		(start 78.05928 -283.213048)
		(end 78.050898 -283.217874)
		(width 0.0762)
		(layer "F.Cu")
		(net "M_A_CPU1_SB_DQ<15>")
	)
	(segment
		(start 77.768196 -283.294074)
		(end 76.472288 -283.294074)
		(width 0.0762)
		(layer "F.Cu")
		(net "M_A_CPU1_SB_DQ<15>")
	)
	(segment
		(start 76.420218 -283.346144)
		(end 75.910186 -283.346144)
		(width 0.0762)
		(layer "F.Cu")
		(net "M_A_CPU1_SB_DQ<15>")
	)
	(segment
		(start 60.725812 -298.757848)
		(end 60.357258 -298.910502)
		(width 0.101346)
		(layer "F.Cu")
		(net "M_A_CPU1_SB_DQ<15>")
	)
	(segment
		(start 57.15762 -299.335444)
		(end 55.328058 -299.335444)
		(width 0.101346)
		(layer "F.Cu")
		(net "M_A_CPU1_SB_DQ<15>")
	)
	(segment
		(start 58.183526 -298.910502)
		(end 57.15762 -299.335444)
		(width 0.101346)
		(layer "F.Cu")
		(net "M_A_CPU1_SB_DQ<15>")
	)
	(arc
		(start 78.050898 -283.217874)
		(mid 77.937174 -283.268175)
		(end 77.815186 -283.292296)
		(width 0.0762)
		(layer "F.Cu")
		(net "M_A_CPU1_SB_DQ<15>")
	)
	(arc
		(start 79.36484 -283.217874)
		(mid 79.177896 -283.167619)
		(end 78.990952 -283.217874)
		(width 0.0762)
		(layer "F.Cu")
		(net "M_A_CPU1_SB_DQ<15>")
	)
	(arc
		(start 78.42504 -283.217874)
		(mid 78.242789 -283.167524)
		(end 78.05928 -283.213048)
		(width 0.0762)
		(layer "F.Cu")
		(net "M_A_CPU1_SB_DQ<15>")
	)
	(arc
		(start 77.815186 -283.292296)
		(mid 77.791709 -283.293672)
		(end 77.768196 -283.294074)
		(width 0.0762)
		(layer "F.Cu")
		(net "M_A_CPU1_SB_DQ<15>")
	)
	(arc
		(start 78.990952 -283.217874)
		(mid 78.707996 -283.294051)
		(end 78.42504 -283.217874)
		(width 0.0762)
		(layer "F.Cu")
		(net "M_A_CPU1_SB_DQ<15>")
	)
	(arc
		(start 79.598012 -283.292042)
		(mid 79.477363 -283.267741)
		(end 79.36484 -283.217874)
		(width 0.0762)
		(layer "F.Cu")
		(net "M_A_CPU1_SB_DQ<15>")
	)
	(arc
		(start 80.11795 -283.540454)
		(mid 79.880338 -283.369466)
		(end 79.598012 -283.292042)
		(width 0.0762)
		(layer "F.Cu")
		(net "M_A_CPU1_SB_DQ<15>")
	)
	(segment
		(start 57.573418 -297.635422)
		(end 57.472072 -297.736768)
		(width 0.101346)
		(layer "F.Cu")
		(net "M_A_CPU1_SB_DQ<14>")
	)
	(segment
		(start 57.078372 -297.9928)
		(end 57.078372 -297.736768)
		(width 0.101346)
		(layer "F.Cu")
		(net "M_A_CPU1_SB_DQ<14>")
	)
	(segment
		(start 66.797428 -292.594538)
		(end 62.503558 -296.888408)
		(width 0.10668)
		(layer "F.Cu")
		(net "M_A_CPU1_SB_DQ<14>")
	)
	(segment
		(start 57.472072 -297.9928)
		(end 57.370726 -298.094146)
		(width 0.101346)
		(layer "F.Cu")
		(net "M_A_CPU1_SB_DQ<14>")
	)
	(segment
		(start 57.774332 -297.635422)
		(end 57.573418 -297.635422)
		(width 0.101346)
		(layer "F.Cu")
		(net "M_A_CPU1_SB_DQ<14>")
	)
	(segment
		(start 60.725812 -297.154854)
		(end 60.670186 -297.21048)
		(width 0.101346)
		(layer "F.Cu")
		(net "M_A_CPU1_SB_DQ<14>")
	)
	(segment
		(start 57.370726 -298.094146)
		(end 57.179718 -298.094146)
		(width 0.101346)
		(layer "F.Cu")
		(net "M_A_CPU1_SB_DQ<14>")
	)
	(segment
		(start 76.013056 -282.184856)
		(end 73.640442 -282.184856)
		(width 0.10668)
		(layer "F.Cu")
		(net "M_A_CPU1_SB_DQ<14>")
	)
	(segment
		(start 57.179718 -298.094146)
		(end 57.078372 -297.9928)
		(width 0.101346)
		(layer "F.Cu")
		(net "M_A_CPU1_SB_DQ<14>")
	)
	(segment
		(start 76.37145 -282.357322)
		(end 76.198984 -282.184856)
		(width 0.0762)
		(layer "F.Cu")
		(net "M_A_CPU1_SB_DQ<14>")
	)
	(segment
		(start 58.199274 -297.21048)
		(end 57.774332 -297.635422)
		(width 0.101346)
		(layer "F.Cu")
		(net "M_A_CPU1_SB_DQ<14>")
	)
	(segment
		(start 56.977026 -297.635422)
		(end 55.328058 -297.635422)
		(width 0.101346)
		(layer "F.Cu")
		(net "M_A_CPU1_SB_DQ<14>")
	)
	(segment
		(start 62.503558 -296.888408)
		(end 60.992258 -296.888408)
		(width 0.10668)
		(layer "F.Cu")
		(net "M_A_CPU1_SB_DQ<14>")
	)
	(segment
		(start 66.797428 -289.02787)
		(end 66.797428 -292.594538)
		(width 0.10668)
		(layer "F.Cu")
		(net "M_A_CPU1_SB_DQ<14>")
	)
	(segment
		(start 77.767942 -282.357322)
		(end 76.37145 -282.357322)
		(width 0.0762)
		(layer "F.Cu")
		(net "M_A_CPU1_SB_DQ<14>")
	)
	(segment
		(start 73.640442 -282.184856)
		(end 66.797428 -289.02787)
		(width 0.10668)
		(layer "F.Cu")
		(net "M_A_CPU1_SB_DQ<14>")
	)
	(segment
		(start 60.992258 -296.888408)
		(end 60.725812 -297.154854)
		(width 0.10668)
		(layer "F.Cu")
		(net "M_A_CPU1_SB_DQ<14>")
	)
	(segment
		(start 57.078372 -297.736768)
		(end 56.977026 -297.635422)
		(width 0.101346)
		(layer "F.Cu")
		(net "M_A_CPU1_SB_DQ<14>")
	)
	(segment
		(start 76.198984 -282.184856)
		(end 76.013056 -282.184856)
		(width 0.0762)
		(layer "F.Cu")
		(net "M_A_CPU1_SB_DQ<14>")
	)
	(segment
		(start 60.670186 -297.21048)
		(end 58.199274 -297.21048)
		(width 0.101346)
		(layer "F.Cu")
		(net "M_A_CPU1_SB_DQ<14>")
	)
	(segment
		(start 57.472072 -297.736768)
		(end 57.472072 -297.9928)
		(width 0.101346)
		(layer "F.Cu")
		(net "M_A_CPU1_SB_DQ<14>")
	)
	(arc
		(start 77.954886 -282.407868)
		(mid 77.864753 -282.370248)
		(end 77.767942 -282.357322)
		(width 0.0762)
		(layer "F.Cu")
		(net "M_A_CPU1_SB_DQ<14>")
	)
	(arc
		(start 78.707996 -282.730448)
		(mid 78.465679 -282.560728)
		(end 78.180692 -282.481274)
		(width 0.0762)
		(layer "F.Cu")
		(net "M_A_CPU1_SB_DQ<14>")
	)
	(arc
		(start 78.180692 -282.481274)
		(mid 78.063879 -282.456598)
		(end 77.954886 -282.407868)
		(width 0.0762)
		(layer "F.Cu")
		(net "M_A_CPU1_SB_DQ<14>")
	)
	(segment
		(start 73.301098 -283.005784)
		(end 67.137788 -289.169094)
		(width 0.10668)
		(layer "F.Cu")
		(net "M_A_CPU1_SB_DQ<13>")
	)
	(segment
		(start 75.169776 -282.899104)
		(end 75.063096 -283.005784)
		(width 0.10668)
		(layer "F.Cu")
		(net "M_A_CPU1_SB_DQ<13>")
	)
	(segment
		(start 60.583826 -297.804078)
		(end 60.583826 -298.368466)
		(width 0.10668)
		(layer "F.Cu")
		(net "M_A_CPU1_SB_DQ<13>")
	)
	(segment
		(start 74.664062 -282.529026)
		(end 74.478388 -282.529026)
		(width 0.10668)
		(layer "F.Cu")
		(net "M_A_CPU1_SB_DQ<13>")
	)
	(segment
		(start 61.31687 -297.878246)
		(end 61.31687 -297.46448)
		(width 0.10668)
		(layer "F.Cu")
		(net "M_A_CPU1_SB_DQ<13>")
	)
	(segment
		(start 77.767942 -283.103574)
		(end 76.777596 -283.103574)
		(width 0.0762)
		(layer "F.Cu")
		(net "M_A_CPU1_SB_DQ<13>")
	)
	(segment
		(start 74.770742 -282.635706)
		(end 74.664062 -282.529026)
		(width 0.10668)
		(layer "F.Cu")
		(net "M_A_CPU1_SB_DQ<13>")
	)
	(segment
		(start 74.371708 -282.635706)
		(end 74.371708 -282.899104)
		(width 0.10668)
		(layer "F.Cu")
		(net "M_A_CPU1_SB_DQ<13>")
	)
	(segment
		(start 74.079354 -283.005784)
		(end 73.972674 -282.899104)
		(width 0.10668)
		(layer "F.Cu")
		(net "M_A_CPU1_SB_DQ<13>")
	)
	(segment
		(start 61.31687 -297.46448)
		(end 61.21019 -297.3578)
		(width 0.10668)
		(layer "F.Cu")
		(net "M_A_CPU1_SB_DQ<13>")
	)
	(segment
		(start 75.56881 -282.635706)
		(end 75.46213 -282.529026)
		(width 0.10668)
		(layer "F.Cu")
		(net "M_A_CPU1_SB_DQ<13>")
	)
	(segment
		(start 75.169776 -282.635706)
		(end 75.169776 -282.899104)
		(width 0.10668)
		(layer "F.Cu")
		(net "M_A_CPU1_SB_DQ<13>")
	)
	(segment
		(start 60.583826 -298.368466)
		(end 60.466986 -298.485306)
		(width 0.10668)
		(layer "F.Cu")
		(net "M_A_CPU1_SB_DQ<13>")
	)
	(segment
		(start 75.46213 -282.529026)
		(end 75.276456 -282.529026)
		(width 0.10668)
		(layer "F.Cu")
		(net "M_A_CPU1_SB_DQ<13>")
	)
	(segment
		(start 61.609224 -297.984926)
		(end 61.42355 -297.984926)
		(width 0.10668)
		(layer "F.Cu")
		(net "M_A_CPU1_SB_DQ<13>")
	)
	(segment
		(start 79.647796 -282.730448)
		(end 79.748634 -282.90393)
		(width 0.0762)
		(layer "F.Cu")
		(net "M_A_CPU1_SB_DQ<13>")
	)
	(segment
		(start 75.56881 -282.899104)
		(end 75.56881 -282.635706)
		(width 0.10668)
		(layer "F.Cu")
		(net "M_A_CPU1_SB_DQ<13>")
	)
	(segment
		(start 73.68032 -282.626562)
		(end 73.57364 -282.733242)
		(width 0.10668)
		(layer "F.Cu")
		(net "M_A_CPU1_SB_DQ<13>")
	)
	(segment
		(start 78.89494 -283.053028)
		(end 78.886558 -283.057854)
		(width 0.0762)
		(layer "F.Cu")
		(net "M_A_CPU1_SB_DQ<13>")
	)
	(segment
		(start 75.67549 -283.005784)
		(end 75.56881 -282.899104)
		(width 0.10668)
		(layer "F.Cu")
		(net "M_A_CPU1_SB_DQ<13>")
	)
	(segment
		(start 62.524386 -297.3578)
		(end 61.822584 -297.3578)
		(width 0.10668)
		(layer "F.Cu")
		(net "M_A_CPU1_SB_DQ<13>")
	)
	(segment
		(start 75.960986 -283.005784)
		(end 75.67549 -283.005784)
		(width 0.10668)
		(layer "F.Cu")
		(net "M_A_CPU1_SB_DQ<13>")
	)
	(segment
		(start 67.137788 -292.744398)
		(end 62.524386 -297.3578)
		(width 0.10668)
		(layer "F.Cu")
		(net "M_A_CPU1_SB_DQ<13>")
	)
	(segment
		(start 61.715904 -297.46448)
		(end 61.715904 -297.878246)
		(width 0.10668)
		(layer "F.Cu")
		(net "M_A_CPU1_SB_DQ<13>")
	)
	(segment
		(start 74.371708 -282.899104)
		(end 74.265028 -283.005784)
		(width 0.10668)
		(layer "F.Cu")
		(net "M_A_CPU1_SB_DQ<13>")
	)
	(segment
		(start 61.822584 -297.3578)
		(end 61.715904 -297.46448)
		(width 0.10668)
		(layer "F.Cu")
		(net "M_A_CPU1_SB_DQ<13>")
	)
	(segment
		(start 73.57364 -282.899104)
		(end 73.46696 -283.005784)
		(width 0.10668)
		(layer "F.Cu")
		(net "M_A_CPU1_SB_DQ<13>")
	)
	(segment
		(start 74.478388 -282.529026)
		(end 74.371708 -282.635706)
		(width 0.10668)
		(layer "F.Cu")
		(net "M_A_CPU1_SB_DQ<13>")
	)
	(segment
		(start 73.972674 -282.899104)
		(end 73.972674 -282.733242)
		(width 0.10668)
		(layer "F.Cu")
		(net "M_A_CPU1_SB_DQ<13>")
	)
	(segment
		(start 61.21019 -297.3578)
		(end 61.030104 -297.3578)
		(width 0.10668)
		(layer "F.Cu")
		(net "M_A_CPU1_SB_DQ<13>")
	)
	(segment
		(start 76.679806 -283.005784)
		(end 75.960986 -283.005784)
		(width 0.0762)
		(layer "F.Cu")
		(net "M_A_CPU1_SB_DQ<13>")
	)
	(segment
		(start 61.715904 -297.878246)
		(end 61.609224 -297.984926)
		(width 0.10668)
		(layer "F.Cu")
		(net "M_A_CPU1_SB_DQ<13>")
	)
	(segment
		(start 60.466986 -298.485306)
		(end 59.428126 -298.485306)
		(width 0.10668)
		(layer "F.Cu")
		(net "M_A_CPU1_SB_DQ<13>")
	)
	(segment
		(start 75.063096 -283.005784)
		(end 74.877422 -283.005784)
		(width 0.10668)
		(layer "F.Cu")
		(net "M_A_CPU1_SB_DQ<13>")
	)
	(segment
		(start 76.777596 -283.103574)
		(end 76.679806 -283.005784)
		(width 0.0762)
		(layer "F.Cu")
		(net "M_A_CPU1_SB_DQ<13>")
	)
	(segment
		(start 74.770742 -282.899104)
		(end 74.770742 -282.635706)
		(width 0.10668)
		(layer "F.Cu")
		(net "M_A_CPU1_SB_DQ<13>")
	)
	(segment
		(start 73.57364 -282.733242)
		(end 73.57364 -282.899104)
		(width 0.10668)
		(layer "F.Cu")
		(net "M_A_CPU1_SB_DQ<13>")
	)
	(segment
		(start 61.42355 -297.984926)
		(end 61.31687 -297.878246)
		(width 0.10668)
		(layer "F.Cu")
		(net "M_A_CPU1_SB_DQ<13>")
	)
	(segment
		(start 61.030104 -297.3578)
		(end 60.583826 -297.804078)
		(width 0.10668)
		(layer "F.Cu")
		(net "M_A_CPU1_SB_DQ<13>")
	)
	(segment
		(start 67.137788 -289.169094)
		(end 67.137788 -292.744398)
		(width 0.10668)
		(layer "F.Cu")
		(net "M_A_CPU1_SB_DQ<13>")
	)
	(segment
		(start 75.276456 -282.529026)
		(end 75.169776 -282.635706)
		(width 0.10668)
		(layer "F.Cu")
		(net "M_A_CPU1_SB_DQ<13>")
	)
	(segment
		(start 79.469234 -283.057854)
		(end 79.460852 -283.053028)
		(width 0.0762)
		(layer "F.Cu")
		(net "M_A_CPU1_SB_DQ<13>")
	)
	(segment
		(start 73.972674 -282.733242)
		(end 73.865994 -282.626562)
		(width 0.10668)
		(layer "F.Cu")
		(net "M_A_CPU1_SB_DQ<13>")
	)
	(segment
		(start 74.265028 -283.005784)
		(end 74.079354 -283.005784)
		(width 0.10668)
		(layer "F.Cu")
		(net "M_A_CPU1_SB_DQ<13>")
	)
	(segment
		(start 74.877422 -283.005784)
		(end 74.770742 -282.899104)
		(width 0.10668)
		(layer "F.Cu")
		(net "M_A_CPU1_SB_DQ<13>")
	)
	(segment
		(start 73.46696 -283.005784)
		(end 73.301098 -283.005784)
		(width 0.10668)
		(layer "F.Cu")
		(net "M_A_CPU1_SB_DQ<13>")
	)
	(segment
		(start 73.865994 -282.626562)
		(end 73.68032 -282.626562)
		(width 0.10668)
		(layer "F.Cu")
		(net "M_A_CPU1_SB_DQ<13>")
	)
	(arc
		(start 77.954886 -283.053028)
		(mid 77.879646 -283.086341)
		(end 77.79893 -283.102304)
		(width 0.0762)
		(layer "F.Cu")
		(net "M_A_CPU1_SB_DQ<13>")
	)
	(arc
		(start 79.602584 -283.100526)
		(mid 79.533886 -283.08551)
		(end 79.469234 -283.057854)
		(width 0.0762)
		(layer "F.Cu")
		(net "M_A_CPU1_SB_DQ<13>")
	)
	(arc
		(start 77.79893 -283.102304)
		(mid 77.783449 -283.10326)
		(end 77.767942 -283.103574)
		(width 0.0762)
		(layer "F.Cu")
		(net "M_A_CPU1_SB_DQ<13>")
	)
	(arc
		(start 79.748634 -282.90393)
		(mid 79.732709 -283.044622)
		(end 79.602584 -283.100526)
		(width 0.0762)
		(layer "F.Cu")
		(net "M_A_CPU1_SB_DQ<13>")
	)
	(arc
		(start 78.520798 -283.053028)
		(mid 78.237842 -282.976851)
		(end 77.954886 -283.053028)
		(width 0.0762)
		(layer "F.Cu")
		(net "M_A_CPU1_SB_DQ<13>")
	)
	(arc
		(start 79.460852 -283.053028)
		(mid 79.177896 -282.976851)
		(end 78.89494 -283.053028)
		(width 0.0762)
		(layer "F.Cu")
		(net "M_A_CPU1_SB_DQ<13>")
	)
	(arc
		(start 78.886558 -283.057854)
		(mid 78.70305 -283.103348)
		(end 78.520798 -283.053028)
		(width 0.0762)
		(layer "F.Cu")
		(net "M_A_CPU1_SB_DQ<13>")
	)
	(segment
		(start 66.45021 -291.824156)
		(end 66.277236 -291.99713)
		(width 0.10668)
		(layer "F.Cu")
		(net "M_A_CPU1_SB_DQ<12>")
	)
	(segment
		(start 65.14846 -293.276782)
		(end 65.315592 -293.443914)
		(width 0.10668)
		(layer "F.Cu")
		(net "M_A_CPU1_SB_DQ<12>")
	)
	(segment
		(start 66.277236 -292.148006)
		(end 66.444368 -292.315138)
		(width 0.10668)
		(layer "F.Cu")
		(net "M_A_CPU1_SB_DQ<12>")
	)
	(segment
		(start 75.969368 -281.83713)
		(end 73.506584 -281.83713)
		(width 0.10668)
		(layer "F.Cu")
		(net "M_A_CPU1_SB_DQ<12>")
	)
	(segment
		(start 63.904622 -294.854884)
		(end 63.73749 -294.687752)
		(width 0.10668)
		(layer "F.Cu")
		(net "M_A_CPU1_SB_DQ<12>")
	)
	(segment
		(start 62.044326 -296.380916)
		(end 61.89345 -296.380916)
		(width 0.10668)
		(layer "F.Cu")
		(net "M_A_CPU1_SB_DQ<12>")
	)
	(segment
		(start 64.751204 -294.008302)
		(end 64.751204 -294.159178)
		(width 0.10668)
		(layer "F.Cu")
		(net "M_A_CPU1_SB_DQ<12>")
	)
	(segment
		(start 63.05804 -295.701466)
		(end 63.05804 -295.852342)
		(width 0.10668)
		(layer "F.Cu")
		(net "M_A_CPU1_SB_DQ<12>")
	)
	(segment
		(start 77.767942 -282.166822)
		(end 76.603606 -282.166822)
		(width 0.0762)
		(layer "F.Cu")
		(net "M_A_CPU1_SB_DQ<12>")
	)
	(segment
		(start 62.926722 -295.98366)
		(end 62.775846 -295.98366)
		(width 0.10668)
		(layer "F.Cu")
		(net "M_A_CPU1_SB_DQ<12>")
	)
	(segment
		(start 62.890908 -295.383458)
		(end 62.890908 -295.534334)
		(width 0.10668)
		(layer "F.Cu")
		(net "M_A_CPU1_SB_DQ<12>")
	)
	(segment
		(start 73.506584 -281.83713)
		(end 66.45021 -288.893504)
		(width 0.10668)
		(layer "F.Cu")
		(net "M_A_CPU1_SB_DQ<12>")
	)
	(segment
		(start 63.586614 -294.687752)
		(end 63.455296 -294.81907)
		(width 0.10668)
		(layer "F.Cu")
		(net "M_A_CPU1_SB_DQ<12>")
	)
	(segment
		(start 64.46901 -294.290496)
		(end 64.301878 -294.123364)
		(width 0.10668)
		(layer "F.Cu")
		(net "M_A_CPU1_SB_DQ<12>")
	)
	(segment
		(start 65.87998 -292.879526)
		(end 65.87998 -293.030402)
		(width 0.10668)
		(layer "F.Cu")
		(net "M_A_CPU1_SB_DQ<12>")
	)
	(segment
		(start 64.584072 -293.84117)
		(end 64.751204 -294.008302)
		(width 0.10668)
		(layer "F.Cu")
		(net "M_A_CPU1_SB_DQ<12>")
	)
	(segment
		(start 62.493652 -296.41673)
		(end 62.362334 -296.548048)
		(width 0.10668)
		(layer "F.Cu")
		(net "M_A_CPU1_SB_DQ<12>")
	)
	(segment
		(start 65.597786 -293.16172)
		(end 65.430654 -292.994588)
		(width 0.10668)
		(layer "F.Cu")
		(net "M_A_CPU1_SB_DQ<12>")
	)
	(segment
		(start 63.622428 -295.137078)
		(end 63.622428 -295.287954)
		(width 0.10668)
		(layer "F.Cu")
		(net "M_A_CPU1_SB_DQ<12>")
	)
	(segment
		(start 60.454286 -296.785284)
		(end 59.428126 -296.785284)
		(width 0.10668)
		(layer "F.Cu")
		(net "M_A_CPU1_SB_DQ<12>")
	)
	(segment
		(start 76.273914 -281.83713)
		(end 75.969368 -281.83713)
		(width 0.0762)
		(layer "F.Cu")
		(net "M_A_CPU1_SB_DQ<12>")
	)
	(segment
		(start 76.603606 -282.166822)
		(end 76.273914 -281.83713)
		(width 0.0762)
		(layer "F.Cu")
		(net "M_A_CPU1_SB_DQ<12>")
	)
	(segment
		(start 61.752988 -296.521378)
		(end 60.718192 -296.521378)
		(width 0.10668)
		(layer "F.Cu")
		(net "M_A_CPU1_SB_DQ<12>")
	)
	(segment
		(start 63.173102 -295.25214)
		(end 63.022226 -295.25214)
		(width 0.10668)
		(layer "F.Cu")
		(net "M_A_CPU1_SB_DQ<12>")
	)
	(segment
		(start 64.186816 -294.57269)
		(end 64.186816 -294.723566)
		(width 0.10668)
		(layer "F.Cu")
		(net "M_A_CPU1_SB_DQ<12>")
	)
	(segment
		(start 64.751204 -294.159178)
		(end 64.619886 -294.290496)
		(width 0.10668)
		(layer "F.Cu")
		(net "M_A_CPU1_SB_DQ<12>")
	)
	(segment
		(start 65.033398 -293.726108)
		(end 64.866266 -293.558976)
		(width 0.10668)
		(layer "F.Cu")
		(net "M_A_CPU1_SB_DQ<12>")
	)
	(segment
		(start 65.712848 -292.561518)
		(end 65.712848 -292.712394)
		(width 0.10668)
		(layer "F.Cu")
		(net "M_A_CPU1_SB_DQ<12>")
	)
	(segment
		(start 61.89345 -296.380916)
		(end 61.752988 -296.521378)
		(width 0.10668)
		(layer "F.Cu")
		(net "M_A_CPU1_SB_DQ<12>")
	)
	(segment
		(start 64.055498 -294.854884)
		(end 63.904622 -294.854884)
		(width 0.10668)
		(layer "F.Cu")
		(net "M_A_CPU1_SB_DQ<12>")
	)
	(segment
		(start 64.584072 -293.690294)
		(end 64.584072 -293.84117)
		(width 0.10668)
		(layer "F.Cu")
		(net "M_A_CPU1_SB_DQ<12>")
	)
	(segment
		(start 63.05804 -295.852342)
		(end 62.926722 -295.98366)
		(width 0.10668)
		(layer "F.Cu")
		(net "M_A_CPU1_SB_DQ<12>")
	)
	(segment
		(start 66.444368 -292.466014)
		(end 66.31305 -292.597332)
		(width 0.10668)
		(layer "F.Cu")
		(net "M_A_CPU1_SB_DQ<12>")
	)
	(segment
		(start 64.151002 -294.123364)
		(end 64.019684 -294.254682)
		(width 0.10668)
		(layer "F.Cu")
		(net "M_A_CPU1_SB_DQ<12>")
	)
	(segment
		(start 63.73749 -294.687752)
		(end 63.586614 -294.687752)
		(width 0.10668)
		(layer "F.Cu")
		(net "M_A_CPU1_SB_DQ<12>")
	)
	(segment
		(start 64.71539 -293.558976)
		(end 64.584072 -293.690294)
		(width 0.10668)
		(layer "F.Cu")
		(net "M_A_CPU1_SB_DQ<12>")
	)
	(segment
		(start 65.14846 -293.125906)
		(end 65.14846 -293.276782)
		(width 0.10668)
		(layer "F.Cu")
		(net "M_A_CPU1_SB_DQ<12>")
	)
	(segment
		(start 62.362334 -296.548048)
		(end 62.211458 -296.548048)
		(width 0.10668)
		(layer "F.Cu")
		(net "M_A_CPU1_SB_DQ<12>")
	)
	(segment
		(start 64.301878 -294.123364)
		(end 64.151002 -294.123364)
		(width 0.10668)
		(layer "F.Cu")
		(net "M_A_CPU1_SB_DQ<12>")
	)
	(segment
		(start 66.31305 -292.597332)
		(end 66.162174 -292.597332)
		(width 0.10668)
		(layer "F.Cu")
		(net "M_A_CPU1_SB_DQ<12>")
	)
	(segment
		(start 65.995042 -292.4302)
		(end 65.844166 -292.4302)
		(width 0.10668)
		(layer "F.Cu")
		(net "M_A_CPU1_SB_DQ<12>")
	)
	(segment
		(start 64.019684 -294.405558)
		(end 64.186816 -294.57269)
		(width 0.10668)
		(layer "F.Cu")
		(net "M_A_CPU1_SB_DQ<12>")
	)
	(segment
		(start 65.315592 -293.59479)
		(end 65.184274 -293.726108)
		(width 0.10668)
		(layer "F.Cu")
		(net "M_A_CPU1_SB_DQ<12>")
	)
	(segment
		(start 65.844166 -292.4302)
		(end 65.712848 -292.561518)
		(width 0.10668)
		(layer "F.Cu")
		(net "M_A_CPU1_SB_DQ<12>")
	)
	(segment
		(start 66.162174 -292.597332)
		(end 65.995042 -292.4302)
		(width 0.10668)
		(layer "F.Cu")
		(net "M_A_CPU1_SB_DQ<12>")
	)
	(segment
		(start 66.277236 -291.99713)
		(end 66.277236 -292.148006)
		(width 0.10668)
		(layer "F.Cu")
		(net "M_A_CPU1_SB_DQ<12>")
	)
	(segment
		(start 64.186816 -294.723566)
		(end 64.055498 -294.854884)
		(width 0.10668)
		(layer "F.Cu")
		(net "M_A_CPU1_SB_DQ<12>")
	)
	(segment
		(start 62.211458 -296.548048)
		(end 62.044326 -296.380916)
		(width 0.10668)
		(layer "F.Cu")
		(net "M_A_CPU1_SB_DQ<12>")
	)
	(segment
		(start 63.340234 -295.419272)
		(end 63.173102 -295.25214)
		(width 0.10668)
		(layer "F.Cu")
		(net "M_A_CPU1_SB_DQ<12>")
	)
	(segment
		(start 62.493652 -296.265854)
		(end 62.493652 -296.41673)
		(width 0.10668)
		(layer "F.Cu")
		(net "M_A_CPU1_SB_DQ<12>")
	)
	(segment
		(start 63.022226 -295.25214)
		(end 62.890908 -295.383458)
		(width 0.10668)
		(layer "F.Cu")
		(net "M_A_CPU1_SB_DQ<12>")
	)
	(segment
		(start 66.45021 -288.893504)
		(end 66.45021 -291.824156)
		(width 0.10668)
		(layer "F.Cu")
		(net "M_A_CPU1_SB_DQ<12>")
	)
	(segment
		(start 65.184274 -293.726108)
		(end 65.033398 -293.726108)
		(width 0.10668)
		(layer "F.Cu")
		(net "M_A_CPU1_SB_DQ<12>")
	)
	(segment
		(start 62.32652 -296.098722)
		(end 62.493652 -296.265854)
		(width 0.10668)
		(layer "F.Cu")
		(net "M_A_CPU1_SB_DQ<12>")
	)
	(segment
		(start 62.457838 -295.816528)
		(end 62.32652 -295.947846)
		(width 0.10668)
		(layer "F.Cu")
		(net "M_A_CPU1_SB_DQ<12>")
	)
	(segment
		(start 63.455296 -294.969946)
		(end 63.622428 -295.137078)
		(width 0.10668)
		(layer "F.Cu")
		(net "M_A_CPU1_SB_DQ<12>")
	)
	(segment
		(start 66.444368 -292.315138)
		(end 66.444368 -292.466014)
		(width 0.10668)
		(layer "F.Cu")
		(net "M_A_CPU1_SB_DQ<12>")
	)
	(segment
		(start 64.019684 -294.254682)
		(end 64.019684 -294.405558)
		(width 0.10668)
		(layer "F.Cu")
		(net "M_A_CPU1_SB_DQ<12>")
	)
	(segment
		(start 63.455296 -294.81907)
		(end 63.455296 -294.969946)
		(width 0.10668)
		(layer "F.Cu")
		(net "M_A_CPU1_SB_DQ<12>")
	)
	(segment
		(start 65.87998 -293.030402)
		(end 65.748662 -293.16172)
		(width 0.10668)
		(layer "F.Cu")
		(net "M_A_CPU1_SB_DQ<12>")
	)
	(segment
		(start 64.619886 -294.290496)
		(end 64.46901 -294.290496)
		(width 0.10668)
		(layer "F.Cu")
		(net "M_A_CPU1_SB_DQ<12>")
	)
	(segment
		(start 62.32652 -295.947846)
		(end 62.32652 -296.098722)
		(width 0.10668)
		(layer "F.Cu")
		(net "M_A_CPU1_SB_DQ<12>")
	)
	(segment
		(start 62.890908 -295.534334)
		(end 63.05804 -295.701466)
		(width 0.10668)
		(layer "F.Cu")
		(net "M_A_CPU1_SB_DQ<12>")
	)
	(segment
		(start 65.712848 -292.712394)
		(end 65.87998 -292.879526)
		(width 0.10668)
		(layer "F.Cu")
		(net "M_A_CPU1_SB_DQ<12>")
	)
	(segment
		(start 63.49111 -295.419272)
		(end 63.340234 -295.419272)
		(width 0.10668)
		(layer "F.Cu")
		(net "M_A_CPU1_SB_DQ<12>")
	)
	(segment
		(start 65.315592 -293.443914)
		(end 65.315592 -293.59479)
		(width 0.10668)
		(layer "F.Cu")
		(net "M_A_CPU1_SB_DQ<12>")
	)
	(segment
		(start 64.866266 -293.558976)
		(end 64.71539 -293.558976)
		(width 0.10668)
		(layer "F.Cu")
		(net "M_A_CPU1_SB_DQ<12>")
	)
	(segment
		(start 78.05928 -282.247848)
		(end 78.050898 -282.243022)
		(width 0.0762)
		(layer "F.Cu")
		(net "M_A_CPU1_SB_DQ<12>")
	)
	(segment
		(start 65.430654 -292.994588)
		(end 65.279778 -292.994588)
		(width 0.10668)
		(layer "F.Cu")
		(net "M_A_CPU1_SB_DQ<12>")
	)
	(segment
		(start 78.237842 -281.920442)
		(end 78.33614 -282.089606)
		(width 0.0762)
		(layer "F.Cu")
		(net "M_A_CPU1_SB_DQ<12>")
	)
	(segment
		(start 62.775846 -295.98366)
		(end 62.608714 -295.816528)
		(width 0.10668)
		(layer "F.Cu")
		(net "M_A_CPU1_SB_DQ<12>")
	)
	(segment
		(start 65.279778 -292.994588)
		(end 65.14846 -293.125906)
		(width 0.10668)
		(layer "F.Cu")
		(net "M_A_CPU1_SB_DQ<12>")
	)
	(segment
		(start 60.718192 -296.521378)
		(end 60.454286 -296.785284)
		(width 0.10668)
		(layer "F.Cu")
		(net "M_A_CPU1_SB_DQ<12>")
	)
	(segment
		(start 63.622428 -295.287954)
		(end 63.49111 -295.419272)
		(width 0.10668)
		(layer "F.Cu")
		(net "M_A_CPU1_SB_DQ<12>")
	)
	(segment
		(start 65.748662 -293.16172)
		(end 65.597786 -293.16172)
		(width 0.10668)
		(layer "F.Cu")
		(net "M_A_CPU1_SB_DQ<12>")
	)
	(segment
		(start 62.608714 -295.816528)
		(end 62.457838 -295.816528)
		(width 0.10668)
		(layer "F.Cu")
		(net "M_A_CPU1_SB_DQ<12>")
	)
	(arc
		(start 78.33614 -282.089606)
		(mid 78.327547 -282.231485)
		(end 78.198472 -282.291282)
		(width 0.0762)
		(layer "F.Cu")
		(net "M_A_CPU1_SB_DQ<12>")
	)
	(arc
		(start 78.050898 -282.243022)
		(mid 77.914462 -282.186197)
		(end 77.767942 -282.166822)
		(width 0.0762)
		(layer "F.Cu")
		(net "M_A_CPU1_SB_DQ<12>")
	)
	(arc
		(start 78.198472 -282.291282)
		(mid 78.126734 -282.27643)
		(end 78.05928 -282.247848)
		(width 0.0762)
		(layer "F.Cu")
		(net "M_A_CPU1_SB_DQ<12>")
	)
	(segment
		(start 57.057036 -293.130732)
		(end 56.95569 -293.029386)
		(width 0.101346)
		(layer "F.Cu")
		(net "M_A_CPU1_SB_DQ<11>")
	)
	(segment
		(start 62.638686 -292.408864)
		(end 62.205108 -292.408864)
		(width 0.10668)
		(layer "F.Cu")
		(net "M_A_CPU1_SB_DQ<11>")
	)
	(segment
		(start 61.153294 -292.14699)
		(end 60.560712 -292.739572)
		(width 0.10668)
		(layer "F.Cu")
		(net "M_A_CPU1_SB_DQ<11>")
	)
	(segment
		(start 64.081152 -289.769042)
		(end 64.31026 -289.99815)
		(width 0.10668)
		(layer "F.Cu")
		(net "M_A_CPU1_SB_DQ<11>")
	)
	(segment
		(start 76.2508 -279.905714)
		(end 72.213724 -279.905714)
		(width 0.10668)
		(layer "F.Cu")
		(net "M_A_CPU1_SB_DQ<11>")
	)
	(segment
		(start 64.31026 -290.73729)
		(end 62.638686 -292.408864)
		(width 0.10668)
		(layer "F.Cu")
		(net "M_A_CPU1_SB_DQ<11>")
	)
	(segment
		(start 57.39511 -293.38524)
		(end 57.158382 -293.38524)
		(width 0.101346)
		(layer "F.Cu")
		(net "M_A_CPU1_SB_DQ<11>")
	)
	(segment
		(start 56.95569 -293.029386)
		(end 56.764682 -293.029386)
		(width 0.101346)
		(layer "F.Cu")
		(net "M_A_CPU1_SB_DQ<11>")
	)
	(segment
		(start 60.339986 -292.960298)
		(end 57.820052 -292.960298)
		(width 0.101346)
		(layer "F.Cu")
		(net "M_A_CPU1_SB_DQ<11>")
	)
	(segment
		(start 60.560712 -292.739572)
		(end 60.339986 -292.960298)
		(width 0.101346)
		(layer "F.Cu")
		(net "M_A_CPU1_SB_DQ<11>")
	)
	(segment
		(start 72.213724 -279.905714)
		(end 64.081152 -288.038286)
		(width 0.10668)
		(layer "F.Cu")
		(net "M_A_CPU1_SB_DQ<11>")
	)
	(segment
		(start 56.56199 -293.38524)
		(end 55.328058 -293.38524)
		(width 0.101346)
		(layer "F.Cu")
		(net "M_A_CPU1_SB_DQ<11>")
	)
	(segment
		(start 56.764682 -293.029386)
		(end 56.663336 -293.130732)
		(width 0.101346)
		(layer "F.Cu")
		(net "M_A_CPU1_SB_DQ<11>")
	)
	(segment
		(start 61.943234 -292.14699)
		(end 61.153294 -292.14699)
		(width 0.10668)
		(layer "F.Cu")
		(net "M_A_CPU1_SB_DQ<11>")
	)
	(segment
		(start 56.663336 -293.130732)
		(end 56.663336 -293.283894)
		(width 0.101346)
		(layer "F.Cu")
		(net "M_A_CPU1_SB_DQ<11>")
	)
	(segment
		(start 62.205108 -292.408864)
		(end 61.943234 -292.14699)
		(width 0.10668)
		(layer "F.Cu")
		(net "M_A_CPU1_SB_DQ<11>")
	)
	(segment
		(start 64.31026 -289.99815)
		(end 64.31026 -290.73729)
		(width 0.10668)
		(layer "F.Cu")
		(net "M_A_CPU1_SB_DQ<11>")
	)
	(segment
		(start 57.820052 -292.960298)
		(end 57.39511 -293.38524)
		(width 0.101346)
		(layer "F.Cu")
		(net "M_A_CPU1_SB_DQ<11>")
	)
	(segment
		(start 76.399136 -280.05405)
		(end 76.2508 -279.905714)
		(width 0.0762)
		(layer "F.Cu")
		(net "M_A_CPU1_SB_DQ<11>")
	)
	(segment
		(start 57.158382 -293.38524)
		(end 57.057036 -293.283894)
		(width 0.101346)
		(layer "F.Cu")
		(net "M_A_CPU1_SB_DQ<11>")
	)
	(segment
		(start 56.663336 -293.283894)
		(end 56.56199 -293.38524)
		(width 0.101346)
		(layer "F.Cu")
		(net "M_A_CPU1_SB_DQ<11>")
	)
	(segment
		(start 77.768196 -280.05405)
		(end 76.399136 -280.05405)
		(width 0.0762)
		(layer "F.Cu")
		(net "M_A_CPU1_SB_DQ<11>")
	)
	(segment
		(start 57.057036 -293.283894)
		(end 57.057036 -293.130732)
		(width 0.101346)
		(layer "F.Cu")
		(net "M_A_CPU1_SB_DQ<11>")
	)
	(segment
		(start 64.081152 -288.038286)
		(end 64.081152 -289.769042)
		(width 0.10668)
		(layer "F.Cu")
		(net "M_A_CPU1_SB_DQ<11>")
	)
	(segment
		(start 78.05928 -279.973024)
		(end 78.050898 -279.97785)
		(width 0.0762)
		(layer "F.Cu")
		(net "M_A_CPU1_SB_DQ<11>")
	)
	(arc
		(start 79.36484 -279.97785)
		(mid 79.177896 -279.927595)
		(end 78.990952 -279.97785)
		(width 0.0762)
		(layer "F.Cu")
		(net "M_A_CPU1_SB_DQ<11>")
	)
	(arc
		(start 79.598012 -280.052018)
		(mid 79.477363 -280.027717)
		(end 79.36484 -279.97785)
		(width 0.0762)
		(layer "F.Cu")
		(net "M_A_CPU1_SB_DQ<11>")
	)
	(arc
		(start 77.815186 -280.052272)
		(mid 77.791709 -280.053648)
		(end 77.768196 -280.05405)
		(width 0.0762)
		(layer "F.Cu")
		(net "M_A_CPU1_SB_DQ<11>")
	)
	(arc
		(start 80.11795 -280.30043)
		(mid 79.880338 -280.129442)
		(end 79.598012 -280.052018)
		(width 0.0762)
		(layer "F.Cu")
		(net "M_A_CPU1_SB_DQ<11>")
	)
	(arc
		(start 78.990952 -279.97785)
		(mid 78.707996 -280.054027)
		(end 78.42504 -279.97785)
		(width 0.0762)
		(layer "F.Cu")
		(net "M_A_CPU1_SB_DQ<11>")
	)
	(arc
		(start 78.42504 -279.97785)
		(mid 78.242789 -279.9275)
		(end 78.05928 -279.973024)
		(width 0.0762)
		(layer "F.Cu")
		(net "M_A_CPU1_SB_DQ<11>")
	)
	(arc
		(start 78.050898 -279.97785)
		(mid 77.937174 -280.028151)
		(end 77.815186 -280.052272)
		(width 0.0762)
		(layer "F.Cu")
		(net "M_A_CPU1_SB_DQ<11>")
	)
	(segment
		(start 57.597548 -291.260276)
		(end 57.496202 -291.361622)
		(width 0.101346)
		(layer "F.Cu")
		(net "M_A_CPU1_SB_DQ<10>")
	)
	(segment
		(start 75.966066 -279.224994)
		(end 71.931276 -279.224994)
		(width 0.10668)
		(layer "F.Cu")
		(net "M_A_CPU1_SB_DQ<10>")
	)
	(segment
		(start 57.001156 -291.260276)
		(end 56.804814 -291.260276)
		(width 0.101346)
		(layer "F.Cu")
		(net "M_A_CPU1_SB_DQ<10>")
	)
	(segment
		(start 76.45908 -279.224994)
		(end 75.966066 -279.224994)
		(width 0.0762)
		(layer "F.Cu")
		(net "M_A_CPU1_SB_DQ<10>")
	)
	(segment
		(start 57.496202 -292.1254)
		(end 57.394856 -292.226746)
		(width 0.101346)
		(layer "F.Cu")
		(net "M_A_CPU1_SB_DQ<10>")
	)
	(segment
		(start 57.788556 -291.260276)
		(end 57.597548 -291.260276)
		(width 0.101346)
		(layer "F.Cu")
		(net "M_A_CPU1_SB_DQ<10>")
	)
	(segment
		(start 77.767942 -279.117298)
		(end 76.566776 -279.117298)
		(width 0.0762)
		(layer "F.Cu")
		(net "M_A_CPU1_SB_DQ<10>")
	)
	(segment
		(start 61.489336 -291.46627)
		(end 60.85586 -291.46627)
		(width 0.10668)
		(layer "F.Cu")
		(net "M_A_CPU1_SB_DQ<10>")
	)
	(segment
		(start 76.566776 -279.117298)
		(end 76.45908 -279.224994)
		(width 0.0762)
		(layer "F.Cu")
		(net "M_A_CPU1_SB_DQ<10>")
	)
	(segment
		(start 57.203848 -292.226746)
		(end 57.102502 -292.1254)
		(width 0.101346)
		(layer "F.Cu")
		(net "M_A_CPU1_SB_DQ<10>")
	)
	(segment
		(start 56.379872 -291.685218)
		(end 55.328058 -291.685218)
		(width 0.101346)
		(layer "F.Cu")
		(net "M_A_CPU1_SB_DQ<10>")
	)
	(segment
		(start 58.182256 -292.226746)
		(end 57.991248 -292.226746)
		(width 0.101346)
		(layer "F.Cu")
		(net "M_A_CPU1_SB_DQ<10>")
	)
	(segment
		(start 58.283602 -291.361622)
		(end 58.283602 -292.1254)
		(width 0.101346)
		(layer "F.Cu")
		(net "M_A_CPU1_SB_DQ<10>")
	)
	(segment
		(start 57.991248 -292.226746)
		(end 57.889902 -292.1254)
		(width 0.101346)
		(layer "F.Cu")
		(net "M_A_CPU1_SB_DQ<10>")
	)
	(segment
		(start 60.85586 -291.46627)
		(end 60.649866 -291.260276)
		(width 0.101346)
		(layer "F.Cu")
		(net "M_A_CPU1_SB_DQ<10>")
	)
	(segment
		(start 58.384948 -291.260276)
		(end 58.283602 -291.361622)
		(width 0.101346)
		(layer "F.Cu")
		(net "M_A_CPU1_SB_DQ<10>")
	)
	(segment
		(start 71.931276 -279.224994)
		(end 63.400432 -287.755838)
		(width 0.10668)
		(layer "F.Cu")
		(net "M_A_CPU1_SB_DQ<10>")
	)
	(segment
		(start 63.400432 -287.755838)
		(end 63.400432 -289.555174)
		(width 0.10668)
		(layer "F.Cu")
		(net "M_A_CPU1_SB_DQ<10>")
	)
	(segment
		(start 57.889902 -291.361622)
		(end 57.788556 -291.260276)
		(width 0.101346)
		(layer "F.Cu")
		(net "M_A_CPU1_SB_DQ<10>")
	)
	(segment
		(start 58.283602 -292.1254)
		(end 58.182256 -292.226746)
		(width 0.101346)
		(layer "F.Cu")
		(net "M_A_CPU1_SB_DQ<10>")
	)
	(segment
		(start 57.102502 -292.1254)
		(end 57.102502 -291.361622)
		(width 0.101346)
		(layer "F.Cu")
		(net "M_A_CPU1_SB_DQ<10>")
	)
	(segment
		(start 57.394856 -292.226746)
		(end 57.203848 -292.226746)
		(width 0.101346)
		(layer "F.Cu")
		(net "M_A_CPU1_SB_DQ<10>")
	)
	(segment
		(start 57.889902 -292.1254)
		(end 57.889902 -291.361622)
		(width 0.101346)
		(layer "F.Cu")
		(net "M_A_CPU1_SB_DQ<10>")
	)
	(segment
		(start 60.649866 -291.260276)
		(end 58.384948 -291.260276)
		(width 0.101346)
		(layer "F.Cu")
		(net "M_A_CPU1_SB_DQ<10>")
	)
	(segment
		(start 57.102502 -291.361622)
		(end 57.001156 -291.260276)
		(width 0.101346)
		(layer "F.Cu")
		(net "M_A_CPU1_SB_DQ<10>")
	)
	(segment
		(start 57.496202 -291.361622)
		(end 57.496202 -292.1254)
		(width 0.101346)
		(layer "F.Cu")
		(net "M_A_CPU1_SB_DQ<10>")
	)
	(segment
		(start 63.400432 -289.555174)
		(end 61.489336 -291.46627)
		(width 0.10668)
		(layer "F.Cu")
		(net "M_A_CPU1_SB_DQ<10>")
	)
	(segment
		(start 56.804814 -291.260276)
		(end 56.379872 -291.685218)
		(width 0.101346)
		(layer "F.Cu")
		(net "M_A_CPU1_SB_DQ<10>")
	)
	(arc
		(start 78.180692 -279.24125)
		(mid 78.063879 -279.216574)
		(end 77.954886 -279.167844)
		(width 0.0762)
		(layer "F.Cu")
		(net "M_A_CPU1_SB_DQ<10>")
	)
	(arc
		(start 77.954886 -279.167844)
		(mid 77.864753 -279.130224)
		(end 77.767942 -279.117298)
		(width 0.0762)
		(layer "F.Cu")
		(net "M_A_CPU1_SB_DQ<10>")
	)
	(arc
		(start 78.707996 -279.490424)
		(mid 78.465679 -279.320704)
		(end 78.180692 -279.24125)
		(width 0.0762)
		(layer "F.Cu")
		(net "M_A_CPU1_SB_DQ<10>")
	)
	(segment
		(start 78.237842 -273.820382)
		(end 78.33614 -273.989546)
		(width 0.0762)
		(layer "F.Cu")
		(net "M_A_CPU1_SB_DQ<0>")
	)
	(segment
		(start 61.565536 -280.098754)
		(end 61.434218 -280.230072)
		(width 0.10668)
		(layer "F.Cu")
		(net "M_A_CPU1_SB_DQ<0>")
	)
	(segment
		(start 67.078098 -274.586192)
		(end 67.078098 -274.737068)
		(width 0.10668)
		(layer "F.Cu")
		(net "M_A_CPU1_SB_DQ<0>")
	)
	(segment
		(start 65.527428 -276.723602)
		(end 65.39611 -276.85492)
		(width 0.10668)
		(layer "F.Cu")
		(net "M_A_CPU1_SB_DQ<0>")
	)
	(segment
		(start 65.949322 -275.865844)
		(end 66.091816 -276.008338)
		(width 0.10668)
		(layer "F.Cu")
		(net "M_A_CPU1_SB_DQ<0>")
	)
	(segment
		(start 66.091816 -276.008338)
		(end 66.091816 -276.159214)
		(width 0.10668)
		(layer "F.Cu")
		(net "M_A_CPU1_SB_DQ<0>")
	)
	(segment
		(start 63.138558 -279.112472)
		(end 62.987682 -279.112472)
		(width 0.10668)
		(layer "F.Cu")
		(net "M_A_CPU1_SB_DQ<0>")
	)
	(segment
		(start 67.209416 -274.454874)
		(end 67.078098 -274.586192)
		(width 0.10668)
		(layer "F.Cu")
		(net "M_A_CPU1_SB_DQ<0>")
	)
	(segment
		(start 64.831722 -277.419308)
		(end 64.680846 -277.419308)
		(width 0.10668)
		(layer "F.Cu")
		(net "M_A_CPU1_SB_DQ<0>")
	)
	(segment
		(start 62.009782 -280.241248)
		(end 61.858906 -280.241248)
		(width 0.10668)
		(layer "F.Cu")
		(net "M_A_CPU1_SB_DQ<0>")
	)
	(segment
		(start 61.998606 -279.665684)
		(end 61.998606 -279.81656)
		(width 0.10668)
		(layer "F.Cu")
		(net "M_A_CPU1_SB_DQ<0>")
	)
	(segment
		(start 63.823088 -277.841202)
		(end 63.69177 -277.97252)
		(width 0.10668)
		(layer "F.Cu")
		(net "M_A_CPU1_SB_DQ<0>")
	)
	(segment
		(start 65.960498 -276.290532)
		(end 65.809622 -276.290532)
		(width 0.10668)
		(layer "F.Cu")
		(net "M_A_CPU1_SB_DQ<0>")
	)
	(segment
		(start 63.69177 -277.97252)
		(end 63.69177 -278.123396)
		(width 0.10668)
		(layer "F.Cu")
		(net "M_A_CPU1_SB_DQ<0>")
	)
	(segment
		(start 66.51371 -275.15058)
		(end 66.51371 -275.301456)
		(width 0.10668)
		(layer "F.Cu")
		(net "M_A_CPU1_SB_DQ<0>")
	)
	(segment
		(start 64.680846 -277.419308)
		(end 64.538352 -277.276814)
		(width 0.10668)
		(layer "F.Cu")
		(net "M_A_CPU1_SB_DQ<0>")
	)
	(segment
		(start 65.384934 -276.279356)
		(end 65.384934 -276.430232)
		(width 0.10668)
		(layer "F.Cu")
		(net "M_A_CPU1_SB_DQ<0>")
	)
	(segment
		(start 66.37401 -275.726144)
		(end 66.231516 -275.58365)
		(width 0.10668)
		(layer "F.Cu")
		(net "M_A_CPU1_SB_DQ<0>")
	)
	(segment
		(start 66.231516 -275.58365)
		(end 66.08064 -275.58365)
		(width 0.10668)
		(layer "F.Cu")
		(net "M_A_CPU1_SB_DQ<0>")
	)
	(segment
		(start 64.820546 -276.99462)
		(end 64.96304 -277.137114)
		(width 0.10668)
		(layer "F.Cu")
		(net "M_A_CPU1_SB_DQ<0>")
	)
	(segment
		(start 61.434218 -280.380948)
		(end 61.576712 -280.523442)
		(width 0.10668)
		(layer "F.Cu")
		(net "M_A_CPU1_SB_DQ<0>")
	)
	(segment
		(start 64.398652 -277.701502)
		(end 64.398652 -277.852378)
		(width 0.10668)
		(layer "F.Cu")
		(net "M_A_CPU1_SB_DQ<0>")
	)
	(segment
		(start 65.527428 -276.572726)
		(end 65.527428 -276.723602)
		(width 0.10668)
		(layer "F.Cu")
		(net "M_A_CPU1_SB_DQ<0>")
	)
	(segment
		(start 67.78498 -274.315174)
		(end 67.78498 -274.46605)
		(width 0.10668)
		(layer "F.Cu")
		(net "M_A_CPU1_SB_DQ<0>")
	)
	(segment
		(start 62.705488 -279.394666)
		(end 62.705488 -279.545542)
		(width 0.10668)
		(layer "F.Cu")
		(net "M_A_CPU1_SB_DQ<0>")
	)
	(segment
		(start 67.360292 -274.454874)
		(end 67.209416 -274.454874)
		(width 0.10668)
		(layer "F.Cu")
		(net "M_A_CPU1_SB_DQ<0>")
	)
	(segment
		(start 63.834264 -278.416766)
		(end 63.702946 -278.548084)
		(width 0.10668)
		(layer "F.Cu")
		(net "M_A_CPU1_SB_DQ<0>")
	)
	(segment
		(start 66.938398 -275.161756)
		(end 66.795904 -275.019262)
		(width 0.10668)
		(layer "F.Cu")
		(net "M_A_CPU1_SB_DQ<0>")
	)
	(segment
		(start 65.516252 -276.148038)
		(end 65.384934 -276.279356)
		(width 0.10668)
		(layer "F.Cu")
		(net "M_A_CPU1_SB_DQ<0>")
	)
	(segment
		(start 62.562994 -279.101296)
		(end 62.562994 -279.252172)
		(width 0.10668)
		(layer "F.Cu")
		(net "M_A_CPU1_SB_DQ<0>")
	)
	(segment
		(start 66.08064 -275.58365)
		(end 65.949322 -275.714968)
		(width 0.10668)
		(layer "F.Cu")
		(net "M_A_CPU1_SB_DQ<0>")
	)
	(segment
		(start 64.256158 -277.408132)
		(end 64.256158 -277.559008)
		(width 0.10668)
		(layer "F.Cu")
		(net "M_A_CPU1_SB_DQ<0>")
	)
	(segment
		(start 61.998606 -279.81656)
		(end 62.1411 -279.959054)
		(width 0.10668)
		(layer "F.Cu")
		(net "M_A_CPU1_SB_DQ<0>")
	)
	(segment
		(start 64.256158 -277.559008)
		(end 64.398652 -277.701502)
		(width 0.10668)
		(layer "F.Cu")
		(net "M_A_CPU1_SB_DQ<0>")
	)
	(segment
		(start 66.091816 -276.159214)
		(end 65.960498 -276.290532)
		(width 0.10668)
		(layer "F.Cu")
		(net "M_A_CPU1_SB_DQ<0>")
	)
	(segment
		(start 61.576712 -280.523442)
		(end 61.576712 -280.674318)
		(width 0.10668)
		(layer "F.Cu")
		(net "M_A_CPU1_SB_DQ<0>")
	)
	(segment
		(start 67.502786 -274.597368)
		(end 67.360292 -274.454874)
		(width 0.10668)
		(layer "F.Cu")
		(net "M_A_CPU1_SB_DQ<0>")
	)
	(segment
		(start 66.795904 -275.019262)
		(end 66.645028 -275.019262)
		(width 0.10668)
		(layer "F.Cu")
		(net "M_A_CPU1_SB_DQ<0>")
	)
	(segment
		(start 61.19368 -280.704798)
		(end 60.67806 -280.704798)
		(width 0.10668)
		(layer "F.Cu")
		(net "M_A_CPU1_SB_DQ<0>")
	)
	(segment
		(start 63.269876 -278.830278)
		(end 63.269876 -278.981154)
		(width 0.10668)
		(layer "F.Cu")
		(net "M_A_CPU1_SB_DQ<0>")
	)
	(segment
		(start 64.538352 -277.276814)
		(end 64.387476 -277.276814)
		(width 0.10668)
		(layer "F.Cu")
		(net "M_A_CPU1_SB_DQ<0>")
	)
	(segment
		(start 67.642486 -274.17268)
		(end 67.78498 -274.315174)
		(width 0.10668)
		(layer "F.Cu")
		(net "M_A_CPU1_SB_DQ<0>")
	)
	(segment
		(start 60.57138 -280.811478)
		(end 60.57138 -281.3685)
		(width 0.10668)
		(layer "F.Cu")
		(net "M_A_CPU1_SB_DQ<0>")
	)
	(segment
		(start 63.55207 -278.548084)
		(end 63.409576 -278.40559)
		(width 0.10668)
		(layer "F.Cu")
		(net "M_A_CPU1_SB_DQ<0>")
	)
	(segment
		(start 62.57417 -279.67686)
		(end 62.423294 -279.67686)
		(width 0.10668)
		(layer "F.Cu")
		(net "M_A_CPU1_SB_DQ<0>")
	)
	(segment
		(start 64.96304 -277.137114)
		(end 64.96304 -277.28799)
		(width 0.10668)
		(layer "F.Cu")
		(net "M_A_CPU1_SB_DQ<0>")
	)
	(segment
		(start 64.820546 -276.843744)
		(end 64.820546 -276.99462)
		(width 0.10668)
		(layer "F.Cu")
		(net "M_A_CPU1_SB_DQ<0>")
	)
	(segment
		(start 64.951864 -276.712426)
		(end 64.820546 -276.843744)
		(width 0.10668)
		(layer "F.Cu")
		(net "M_A_CPU1_SB_DQ<0>")
	)
	(segment
		(start 63.973964 -277.841202)
		(end 63.823088 -277.841202)
		(width 0.10668)
		(layer "F.Cu")
		(net "M_A_CPU1_SB_DQ<0>")
	)
	(segment
		(start 65.667128 -276.148038)
		(end 65.516252 -276.148038)
		(width 0.10668)
		(layer "F.Cu")
		(net "M_A_CPU1_SB_DQ<0>")
	)
	(segment
		(start 64.398652 -277.852378)
		(end 64.267334 -277.983696)
		(width 0.10668)
		(layer "F.Cu")
		(net "M_A_CPU1_SB_DQ<0>")
	)
	(segment
		(start 62.694312 -278.969978)
		(end 62.562994 -279.101296)
		(width 0.10668)
		(layer "F.Cu")
		(net "M_A_CPU1_SB_DQ<0>")
	)
	(segment
		(start 67.078098 -274.737068)
		(end 67.220592 -274.879562)
		(width 0.10668)
		(layer "F.Cu")
		(net "M_A_CPU1_SB_DQ<0>")
	)
	(segment
		(start 62.1411 -280.10993)
		(end 62.009782 -280.241248)
		(width 0.10668)
		(layer "F.Cu")
		(net "M_A_CPU1_SB_DQ<0>")
	)
	(segment
		(start 61.576712 -280.674318)
		(end 61.445394 -280.805636)
		(width 0.10668)
		(layer "F.Cu")
		(net "M_A_CPU1_SB_DQ<0>")
	)
	(segment
		(start 67.220592 -275.030438)
		(end 67.089274 -275.161756)
		(width 0.10668)
		(layer "F.Cu")
		(net "M_A_CPU1_SB_DQ<0>")
	)
	(segment
		(start 62.562994 -279.252172)
		(end 62.705488 -279.394666)
		(width 0.10668)
		(layer "F.Cu")
		(net "M_A_CPU1_SB_DQ<0>")
	)
	(segment
		(start 63.269876 -278.981154)
		(end 63.138558 -279.112472)
		(width 0.10668)
		(layer "F.Cu")
		(net "M_A_CPU1_SB_DQ<0>")
	)
	(segment
		(start 63.702946 -278.548084)
		(end 63.55207 -278.548084)
		(width 0.10668)
		(layer "F.Cu")
		(net "M_A_CPU1_SB_DQ<0>")
	)
	(segment
		(start 64.387476 -277.276814)
		(end 64.256158 -277.408132)
		(width 0.10668)
		(layer "F.Cu")
		(net "M_A_CPU1_SB_DQ<0>")
	)
	(segment
		(start 66.51371 -275.301456)
		(end 66.656204 -275.44395)
		(width 0.10668)
		(layer "F.Cu")
		(net "M_A_CPU1_SB_DQ<0>")
	)
	(segment
		(start 65.949322 -275.714968)
		(end 65.949322 -275.865844)
		(width 0.10668)
		(layer "F.Cu")
		(net "M_A_CPU1_SB_DQ<0>")
	)
	(segment
		(start 67.78498 -274.46605)
		(end 67.653662 -274.597368)
		(width 0.10668)
		(layer "F.Cu")
		(net "M_A_CPU1_SB_DQ<0>")
	)
	(segment
		(start 64.116458 -277.983696)
		(end 63.973964 -277.841202)
		(width 0.10668)
		(layer "F.Cu")
		(net "M_A_CPU1_SB_DQ<0>")
	)
	(segment
		(start 76.384404 -274.066762)
		(end 76.146406 -273.828764)
		(width 0.0762)
		(layer "F.Cu")
		(net "M_A_CPU1_SB_DQ<0>")
	)
	(segment
		(start 63.69177 -278.123396)
		(end 63.834264 -278.26589)
		(width 0.10668)
		(layer "F.Cu")
		(net "M_A_CPU1_SB_DQ<0>")
	)
	(segment
		(start 64.267334 -277.983696)
		(end 64.116458 -277.983696)
		(width 0.10668)
		(layer "F.Cu")
		(net "M_A_CPU1_SB_DQ<0>")
	)
	(segment
		(start 63.409576 -278.40559)
		(end 63.2587 -278.40559)
		(width 0.10668)
		(layer "F.Cu")
		(net "M_A_CPU1_SB_DQ<0>")
	)
	(segment
		(start 63.127382 -278.536908)
		(end 63.127382 -278.687784)
		(width 0.10668)
		(layer "F.Cu")
		(net "M_A_CPU1_SB_DQ<0>")
	)
	(segment
		(start 67.220592 -274.879562)
		(end 67.220592 -275.030438)
		(width 0.10668)
		(layer "F.Cu")
		(net "M_A_CPU1_SB_DQ<0>")
	)
	(segment
		(start 66.645028 -275.019262)
		(end 66.51371 -275.15058)
		(width 0.10668)
		(layer "F.Cu")
		(net "M_A_CPU1_SB_DQ<0>")
	)
	(segment
		(start 66.656204 -275.44395)
		(end 66.656204 -275.594826)
		(width 0.10668)
		(layer "F.Cu")
		(net "M_A_CPU1_SB_DQ<0>")
	)
	(segment
		(start 64.96304 -277.28799)
		(end 64.831722 -277.419308)
		(width 0.10668)
		(layer "F.Cu")
		(net "M_A_CPU1_SB_DQ<0>")
	)
	(segment
		(start 67.653662 -274.597368)
		(end 67.502786 -274.597368)
		(width 0.10668)
		(layer "F.Cu")
		(net "M_A_CPU1_SB_DQ<0>")
	)
	(segment
		(start 62.129924 -279.534366)
		(end 61.998606 -279.665684)
		(width 0.10668)
		(layer "F.Cu")
		(net "M_A_CPU1_SB_DQ<0>")
	)
	(segment
		(start 76.146406 -273.828764)
		(end 67.835526 -273.828764)
		(width 0.10668)
		(layer "F.Cu")
		(net "M_A_CPU1_SB_DQ<0>")
	)
	(segment
		(start 61.716412 -280.098754)
		(end 61.565536 -280.098754)
		(width 0.10668)
		(layer "F.Cu")
		(net "M_A_CPU1_SB_DQ<0>")
	)
	(segment
		(start 60.57138 -281.3685)
		(end 60.45454 -281.48534)
		(width 0.10668)
		(layer "F.Cu")
		(net "M_A_CPU1_SB_DQ<0>")
	)
	(segment
		(start 67.642486 -274.021804)
		(end 67.642486 -274.17268)
		(width 0.10668)
		(layer "F.Cu")
		(net "M_A_CPU1_SB_DQ<0>")
	)
	(segment
		(start 62.845188 -278.969978)
		(end 62.694312 -278.969978)
		(width 0.10668)
		(layer "F.Cu")
		(net "M_A_CPU1_SB_DQ<0>")
	)
	(segment
		(start 63.2587 -278.40559)
		(end 63.127382 -278.536908)
		(width 0.10668)
		(layer "F.Cu")
		(net "M_A_CPU1_SB_DQ<0>")
	)
	(segment
		(start 65.384934 -276.430232)
		(end 65.527428 -276.572726)
		(width 0.10668)
		(layer "F.Cu")
		(net "M_A_CPU1_SB_DQ<0>")
	)
	(segment
		(start 78.05928 -274.147788)
		(end 78.050898 -274.142962)
		(width 0.0762)
		(layer "F.Cu")
		(net "M_A_CPU1_SB_DQ<0>")
	)
	(segment
		(start 60.67806 -280.704798)
		(end 60.57138 -280.811478)
		(width 0.10668)
		(layer "F.Cu")
		(net "M_A_CPU1_SB_DQ<0>")
	)
	(segment
		(start 62.1411 -279.959054)
		(end 62.1411 -280.10993)
		(width 0.10668)
		(layer "F.Cu")
		(net "M_A_CPU1_SB_DQ<0>")
	)
	(segment
		(start 66.524886 -275.726144)
		(end 66.37401 -275.726144)
		(width 0.10668)
		(layer "F.Cu")
		(net "M_A_CPU1_SB_DQ<0>")
	)
	(segment
		(start 65.245234 -276.85492)
		(end 65.10274 -276.712426)
		(width 0.10668)
		(layer "F.Cu")
		(net "M_A_CPU1_SB_DQ<0>")
	)
	(segment
		(start 61.445394 -280.805636)
		(end 61.294518 -280.805636)
		(width 0.10668)
		(layer "F.Cu")
		(net "M_A_CPU1_SB_DQ<0>")
	)
	(segment
		(start 62.705488 -279.545542)
		(end 62.57417 -279.67686)
		(width 0.10668)
		(layer "F.Cu")
		(net "M_A_CPU1_SB_DQ<0>")
	)
	(segment
		(start 67.089274 -275.161756)
		(end 66.938398 -275.161756)
		(width 0.10668)
		(layer "F.Cu")
		(net "M_A_CPU1_SB_DQ<0>")
	)
	(segment
		(start 65.10274 -276.712426)
		(end 64.951864 -276.712426)
		(width 0.10668)
		(layer "F.Cu")
		(net "M_A_CPU1_SB_DQ<0>")
	)
	(segment
		(start 67.835526 -273.828764)
		(end 67.642486 -274.021804)
		(width 0.10668)
		(layer "F.Cu")
		(net "M_A_CPU1_SB_DQ<0>")
	)
	(segment
		(start 63.834264 -278.26589)
		(end 63.834264 -278.416766)
		(width 0.10668)
		(layer "F.Cu")
		(net "M_A_CPU1_SB_DQ<0>")
	)
	(segment
		(start 61.434218 -280.230072)
		(end 61.434218 -280.380948)
		(width 0.10668)
		(layer "F.Cu")
		(net "M_A_CPU1_SB_DQ<0>")
	)
	(segment
		(start 61.294518 -280.805636)
		(end 61.19368 -280.704798)
		(width 0.10668)
		(layer "F.Cu")
		(net "M_A_CPU1_SB_DQ<0>")
	)
	(segment
		(start 62.2808 -279.534366)
		(end 62.129924 -279.534366)
		(width 0.10668)
		(layer "F.Cu")
		(net "M_A_CPU1_SB_DQ<0>")
	)
	(segment
		(start 62.987682 -279.112472)
		(end 62.845188 -278.969978)
		(width 0.10668)
		(layer "F.Cu")
		(net "M_A_CPU1_SB_DQ<0>")
	)
	(segment
		(start 62.423294 -279.67686)
		(end 62.2808 -279.534366)
		(width 0.10668)
		(layer "F.Cu")
		(net "M_A_CPU1_SB_DQ<0>")
	)
	(segment
		(start 63.127382 -278.687784)
		(end 63.269876 -278.830278)
		(width 0.10668)
		(layer "F.Cu")
		(net "M_A_CPU1_SB_DQ<0>")
	)
	(segment
		(start 61.858906 -280.241248)
		(end 61.716412 -280.098754)
		(width 0.10668)
		(layer "F.Cu")
		(net "M_A_CPU1_SB_DQ<0>")
	)
	(segment
		(start 60.45454 -281.48534)
		(end 59.428126 -281.48534)
		(width 0.10668)
		(layer "F.Cu")
		(net "M_A_CPU1_SB_DQ<0>")
	)
	(segment
		(start 77.767942 -274.066762)
		(end 76.384404 -274.066762)
		(width 0.0762)
		(layer "F.Cu")
		(net "M_A_CPU1_SB_DQ<0>")
	)
	(segment
		(start 65.809622 -276.290532)
		(end 65.667128 -276.148038)
		(width 0.10668)
		(layer "F.Cu")
		(net "M_A_CPU1_SB_DQ<0>")
	)
	(segment
		(start 66.656204 -275.594826)
		(end 66.524886 -275.726144)
		(width 0.10668)
		(layer "F.Cu")
		(net "M_A_CPU1_SB_DQ<0>")
	)
	(segment
		(start 65.39611 -276.85492)
		(end 65.245234 -276.85492)
		(width 0.10668)
		(layer "F.Cu")
		(net "M_A_CPU1_SB_DQ<0>")
	)
	(arc
		(start 78.33614 -273.989546)
		(mid 78.327547 -274.131425)
		(end 78.198472 -274.191222)
		(width 0.0762)
		(layer "F.Cu")
		(net "M_A_CPU1_SB_DQ<0>")
	)
	(arc
		(start 78.050898 -274.142962)
		(mid 77.914462 -274.086137)
		(end 77.767942 -274.066762)
		(width 0.0762)
		(layer "F.Cu")
		(net "M_A_CPU1_SB_DQ<0>")
	)
	(arc
		(start 78.198472 -274.191222)
		(mid 78.126734 -274.17637)
		(end 78.05928 -274.147788)
		(width 0.0762)
		(layer "F.Cu")
		(net "M_A_CPU1_SB_DQ<0>")
	)
	(segment
		(start 60.670186 -269.160498)
		(end 58.13044 -269.160498)
		(width 0.101346)
		(layer "F.Cu")
		(net "M_A_CPU1_SB_CS_N<1>")
	)
	(segment
		(start 60.85713 -267.993622)
		(end 60.85713 -268.973554)
		(width 0.10668)
		(layer "F.Cu")
		(net "M_A_CPU1_SB_CS_N<1>")
	)
	(segment
		(start 60.85713 -268.973554)
		(end 60.67044 -269.160244)
		(width 0.10668)
		(layer "F.Cu")
		(net "M_A_CPU1_SB_CS_N<1>")
	)
	(segment
		(start 57.705244 -268.735302)
		(end 55.328058 -268.735302)
		(width 0.101346)
		(layer "F.Cu")
		(net "M_A_CPU1_SB_CS_N<1>")
	)
	(segment
		(start 76.904088 -266.157202)
		(end 76.700126 -266.361164)
		(width 0.0762)
		(layer "F.Cu")
		(net "M_A_CPU1_SB_CS_N<1>")
	)
	(segment
		(start 61.213746 -267.637006)
		(end 60.85713 -267.993622)
		(width 0.10668)
		(layer "F.Cu")
		(net "M_A_CPU1_SB_CS_N<1>")
	)
	(segment
		(start 58.13044 -269.160498)
		(end 57.705244 -268.735302)
		(width 0.101346)
		(layer "F.Cu")
		(net "M_A_CPU1_SB_CS_N<1>")
	)
	(segment
		(start 75.581256 -265.839702)
		(end 65.320672 -265.839702)
		(width 0.10668)
		(layer "F.Cu")
		(net "M_A_CPU1_SB_CS_N<1>")
	)
	(segment
		(start 76.700126 -266.361164)
		(end 76.102718 -266.361164)
		(width 0.10668)
		(layer "F.Cu")
		(net "M_A_CPU1_SB_CS_N<1>")
	)
	(segment
		(start 77.767942 -266.157202)
		(end 76.904088 -266.157202)
		(width 0.0762)
		(layer "F.Cu")
		(net "M_A_CPU1_SB_CS_N<1>")
	)
	(segment
		(start 60.67044 -269.160244)
		(end 60.670186 -269.160498)
		(width 0.101346)
		(layer "F.Cu")
		(net "M_A_CPU1_SB_CS_N<1>")
	)
	(segment
		(start 65.320672 -265.839702)
		(end 63.523368 -267.637006)
		(width 0.10668)
		(layer "F.Cu")
		(net "M_A_CPU1_SB_CS_N<1>")
	)
	(segment
		(start 63.523368 -267.637006)
		(end 61.213746 -267.637006)
		(width 0.10668)
		(layer "F.Cu")
		(net "M_A_CPU1_SB_CS_N<1>")
	)
	(segment
		(start 76.102718 -266.361164)
		(end 75.581256 -265.839702)
		(width 0.10668)
		(layer "F.Cu")
		(net "M_A_CPU1_SB_CS_N<1>")
	)
	(arc
		(start 78.707996 -266.530328)
		(mid 78.517709 -266.344902)
		(end 78.259178 -266.283694)
		(width 0.0762)
		(layer "F.Cu")
		(net "M_A_CPU1_SB_CS_N<1>")
	)
	(arc
		(start 78.259178 -266.283694)
		(mid 78.101642 -266.267318)
		(end 77.954886 -266.207748)
		(width 0.0762)
		(layer "F.Cu")
		(net "M_A_CPU1_SB_CS_N<1>")
	)
	(arc
		(start 77.954886 -266.207748)
		(mid 77.864753 -266.170128)
		(end 77.767942 -266.157202)
		(width 0.0762)
		(layer "F.Cu")
		(net "M_A_CPU1_SB_CS_N<1>")
	)
	(segment
		(start 63.147956 -267.189966)
		(end 63.041276 -267.296646)
		(width 0.10668)
		(layer "F.Cu")
		(net "M_A_CPU1_SB_CS_N<0>")
	)
	(segment
		(start 61.631576 -266.737592)
		(end 61.291978 -267.07719)
		(width 0.10668)
		(layer "F.Cu")
		(net "M_A_CPU1_SB_CS_N<0>")
	)
	(segment
		(start 63.041276 -267.296646)
		(end 62.855602 -267.296646)
		(width 0.10668)
		(layer "F.Cu")
		(net "M_A_CPU1_SB_CS_N<0>")
	)
	(segment
		(start 60.830206 -266.91717)
		(end 60.698888 -267.048488)
		(width 0.10668)
		(layer "F.Cu")
		(net "M_A_CPU1_SB_CS_N<0>")
	)
	(segment
		(start 60.698888 -267.048488)
		(end 60.698888 -267.199364)
		(width 0.10668)
		(layer "F.Cu")
		(net "M_A_CPU1_SB_CS_N<0>")
	)
	(segment
		(start 63.147956 -266.844272)
		(end 63.147956 -267.189966)
		(width 0.10668)
		(layer "F.Cu")
		(net "M_A_CPU1_SB_CS_N<0>")
	)
	(segment
		(start 60.698888 -267.199364)
		(end 60.858908 -267.359384)
		(width 0.10668)
		(layer "F.Cu")
		(net "M_A_CPU1_SB_CS_N<0>")
	)
	(segment
		(start 77.13218 -265.499342)
		(end 76.581508 -265.499342)
		(width 0.0762)
		(layer "F.Cu")
		(net "M_A_CPU1_SB_CS_N<0>")
	)
	(segment
		(start 62.057534 -267.296646)
		(end 61.950854 -267.189966)
		(width 0.10668)
		(layer "F.Cu")
		(net "M_A_CPU1_SB_CS_N<0>")
	)
	(segment
		(start 60.858908 -267.51026)
		(end 60.48375 -267.885418)
		(width 0.10668)
		(layer "F.Cu")
		(net "M_A_CPU1_SB_CS_N<0>")
	)
	(segment
		(start 62.243208 -267.296646)
		(end 62.057534 -267.296646)
		(width 0.10668)
		(layer "F.Cu")
		(net "M_A_CPU1_SB_CS_N<0>")
	)
	(segment
		(start 60.858908 -267.359384)
		(end 60.858908 -267.51026)
		(width 0.10668)
		(layer "F.Cu")
		(net "M_A_CPU1_SB_CS_N<0>")
	)
	(segment
		(start 61.844174 -266.737592)
		(end 61.631576 -266.737592)
		(width 0.10668)
		(layer "F.Cu")
		(net "M_A_CPU1_SB_CS_N<0>")
	)
	(segment
		(start 64.804544 -265.87323)
		(end 63.940182 -266.737592)
		(width 0.10668)
		(layer "F.Cu")
		(net "M_A_CPU1_SB_CS_N<0>")
	)
	(segment
		(start 63.254636 -266.737592)
		(end 63.147956 -266.844272)
		(width 0.10668)
		(layer "F.Cu")
		(net "M_A_CPU1_SB_CS_N<0>")
	)
	(segment
		(start 63.940182 -266.737592)
		(end 63.254636 -266.737592)
		(width 0.10668)
		(layer "F.Cu")
		(net "M_A_CPU1_SB_CS_N<0>")
	)
	(segment
		(start 62.349888 -266.844272)
		(end 62.349888 -267.189966)
		(width 0.10668)
		(layer "F.Cu")
		(net "M_A_CPU1_SB_CS_N<0>")
	)
	(segment
		(start 61.950854 -266.844272)
		(end 61.844174 -266.737592)
		(width 0.10668)
		(layer "F.Cu")
		(net "M_A_CPU1_SB_CS_N<0>")
	)
	(segment
		(start 78.05928 -265.392916)
		(end 78.050898 -265.397742)
		(width 0.0762)
		(layer "F.Cu")
		(net "M_A_CPU1_SB_CS_N<0>")
	)
	(segment
		(start 60.981082 -266.91717)
		(end 60.830206 -266.91717)
		(width 0.10668)
		(layer "F.Cu")
		(net "M_A_CPU1_SB_CS_N<0>")
	)
	(segment
		(start 62.642242 -266.737592)
		(end 62.456568 -266.737592)
		(width 0.10668)
		(layer "F.Cu")
		(net "M_A_CPU1_SB_CS_N<0>")
	)
	(segment
		(start 62.855602 -267.296646)
		(end 62.748922 -267.189966)
		(width 0.10668)
		(layer "F.Cu")
		(net "M_A_CPU1_SB_CS_N<0>")
	)
	(segment
		(start 76.581508 -265.499342)
		(end 65.178686 -265.499342)
		(width 0.10668)
		(layer "F.Cu")
		(net "M_A_CPU1_SB_CS_N<0>")
	)
	(segment
		(start 62.349888 -267.189966)
		(end 62.243208 -267.296646)
		(width 0.10668)
		(layer "F.Cu")
		(net "M_A_CPU1_SB_CS_N<0>")
	)
	(segment
		(start 62.748922 -266.844272)
		(end 62.642242 -266.737592)
		(width 0.10668)
		(layer "F.Cu")
		(net "M_A_CPU1_SB_CS_N<0>")
	)
	(segment
		(start 61.291978 -267.07719)
		(end 61.141102 -267.07719)
		(width 0.10668)
		(layer "F.Cu")
		(net "M_A_CPU1_SB_CS_N<0>")
	)
	(segment
		(start 62.456568 -266.737592)
		(end 62.349888 -266.844272)
		(width 0.10668)
		(layer "F.Cu")
		(net "M_A_CPU1_SB_CS_N<0>")
	)
	(segment
		(start 64.804544 -265.873484)
		(end 64.804544 -265.87323)
		(width 0.10668)
		(layer "F.Cu")
		(net "M_A_CPU1_SB_CS_N<0>")
	)
	(segment
		(start 60.48375 -267.885418)
		(end 59.428126 -267.885418)
		(width 0.10668)
		(layer "F.Cu")
		(net "M_A_CPU1_SB_CS_N<0>")
	)
	(segment
		(start 61.141102 -267.07719)
		(end 60.981082 -266.91717)
		(width 0.10668)
		(layer "F.Cu")
		(net "M_A_CPU1_SB_CS_N<0>")
	)
	(segment
		(start 65.178686 -265.499342)
		(end 64.804544 -265.873484)
		(width 0.10668)
		(layer "F.Cu")
		(net "M_A_CPU1_SB_CS_N<0>")
	)
	(segment
		(start 61.950854 -267.189966)
		(end 61.950854 -266.844272)
		(width 0.10668)
		(layer "F.Cu")
		(net "M_A_CPU1_SB_CS_N<0>")
	)
	(segment
		(start 62.748922 -267.189966)
		(end 62.748922 -266.844272)
		(width 0.10668)
		(layer "F.Cu")
		(net "M_A_CPU1_SB_CS_N<0>")
	)
	(arc
		(start 78.42504 -265.397742)
		(mid 78.242789 -265.347392)
		(end 78.05928 -265.392916)
		(width 0.0762)
		(layer "F.Cu")
		(net "M_A_CPU1_SB_CS_N<0>")
	)
	(arc
		(start 79.36484 -265.397742)
		(mid 79.177896 -265.347487)
		(end 78.990952 -265.397742)
		(width 0.0762)
		(layer "F.Cu")
		(net "M_A_CPU1_SB_CS_N<0>")
	)
	(arc
		(start 78.050898 -265.397742)
		(mid 77.937174 -265.448043)
		(end 77.815186 -265.472164)
		(width 0.0762)
		(layer "F.Cu")
		(net "M_A_CPU1_SB_CS_N<0>")
	)
	(arc
		(start 78.990952 -265.397742)
		(mid 78.707996 -265.473919)
		(end 78.42504 -265.397742)
		(width 0.0762)
		(layer "F.Cu")
		(net "M_A_CPU1_SB_CS_N<0>")
	)
	(arc
		(start 79.661766 -265.473942)
		(mid 79.508017 -265.456433)
		(end 79.36484 -265.397742)
		(width 0.0762)
		(layer "F.Cu")
		(net "M_A_CPU1_SB_CS_N<0>")
	)
	(arc
		(start 77.815186 -265.472164)
		(mid 77.473953 -265.492547)
		(end 77.13218 -265.499342)
		(width 0.0762)
		(layer "F.Cu")
		(net "M_A_CPU1_SB_CS_N<0>")
	)
	(arc
		(start 80.11795 -265.720322)
		(mid 79.922601 -265.536503)
		(end 79.661766 -265.473942)
		(width 0.0762)
		(layer "F.Cu")
		(net "M_A_CPU1_SB_CS_N<0>")
	)
	(segment
		(start 60.67044 -274.260564)
		(end 60.670186 -274.26031)
		(width 0.101346)
		(layer "F.Cu")
		(net "M_A_CPU1_SB_CB<7>")
	)
	(segment
		(start 60.670186 -274.26031)
		(end 56.8325 -274.26031)
		(width 0.101346)
		(layer "F.Cu")
		(net "M_A_CPU1_SB_CB<7>")
	)
	(segment
		(start 56.8325 -274.26031)
		(end 56.407558 -274.685252)
		(width 0.101346)
		(layer "F.Cu")
		(net "M_A_CPU1_SB_CB<7>")
	)
	(segment
		(start 73.917302 -269.026386)
		(end 66.3956 -269.026386)
		(width 0.10668)
		(layer "F.Cu")
		(net "M_A_CPU1_SB_CB<7>")
	)
	(segment
		(start 56.407558 -274.685252)
		(end 55.328058 -274.685252)
		(width 0.101346)
		(layer "F.Cu")
		(net "M_A_CPU1_SB_CB<7>")
	)
	(segment
		(start 78.05928 -270.252952)
		(end 78.050898 -270.257778)
		(width 0.0762)
		(layer "F.Cu")
		(net "M_A_CPU1_SB_CB<7>")
	)
	(segment
		(start 76.507086 -270.285464)
		(end 75.887072 -270.285464)
		(width 0.0762)
		(layer "F.Cu")
		(net "M_A_CPU1_SB_CB<7>")
	)
	(segment
		(start 66.3956 -269.026386)
		(end 61.161422 -274.260564)
		(width 0.10668)
		(layer "F.Cu")
		(net "M_A_CPU1_SB_CB<7>")
	)
	(segment
		(start 77.768196 -270.333978)
		(end 76.5556 -270.333978)
		(width 0.0762)
		(layer "F.Cu")
		(net "M_A_CPU1_SB_CB<7>")
	)
	(segment
		(start 61.161422 -274.260564)
		(end 60.725812 -274.260564)
		(width 0.10668)
		(layer "F.Cu")
		(net "M_A_CPU1_SB_CB<7>")
	)
	(segment
		(start 75.17638 -270.285464)
		(end 73.917302 -269.026386)
		(width 0.10668)
		(layer "F.Cu")
		(net "M_A_CPU1_SB_CB<7>")
	)
	(segment
		(start 60.725812 -274.260564)
		(end 60.67044 -274.260564)
		(width 0.101346)
		(layer "F.Cu")
		(net "M_A_CPU1_SB_CB<7>")
	)
	(segment
		(start 75.887072 -270.285464)
		(end 75.17638 -270.285464)
		(width 0.10668)
		(layer "F.Cu")
		(net "M_A_CPU1_SB_CB<7>")
	)
	(segment
		(start 76.5556 -270.333978)
		(end 76.507086 -270.285464)
		(width 0.0762)
		(layer "F.Cu")
		(net "M_A_CPU1_SB_CB<7>")
	)
	(arc
		(start 78.42504 -270.257778)
		(mid 78.242789 -270.207428)
		(end 78.05928 -270.252952)
		(width 0.0762)
		(layer "F.Cu")
		(net "M_A_CPU1_SB_CB<7>")
	)
	(arc
		(start 77.815186 -270.3322)
		(mid 77.791709 -270.333576)
		(end 77.768196 -270.333978)
		(width 0.0762)
		(layer "F.Cu")
		(net "M_A_CPU1_SB_CB<7>")
	)
	(arc
		(start 79.36484 -270.257778)
		(mid 79.177896 -270.207523)
		(end 78.990952 -270.257778)
		(width 0.0762)
		(layer "F.Cu")
		(net "M_A_CPU1_SB_CB<7>")
	)
	(arc
		(start 79.598012 -270.331946)
		(mid 79.477363 -270.307645)
		(end 79.36484 -270.257778)
		(width 0.0762)
		(layer "F.Cu")
		(net "M_A_CPU1_SB_CB<7>")
	)
	(arc
		(start 80.11795 -270.580358)
		(mid 79.880338 -270.40937)
		(end 79.598012 -270.331946)
		(width 0.0762)
		(layer "F.Cu")
		(net "M_A_CPU1_SB_CB<7>")
	)
	(arc
		(start 78.050898 -270.257778)
		(mid 77.937174 -270.308079)
		(end 77.815186 -270.3322)
		(width 0.0762)
		(layer "F.Cu")
		(net "M_A_CPU1_SB_CB<7>")
	)
	(arc
		(start 78.990952 -270.257778)
		(mid 78.707996 -270.333955)
		(end 78.42504 -270.257778)
		(width 0.0762)
		(layer "F.Cu")
		(net "M_A_CPU1_SB_CB<7>")
	)
	(segment
		(start 77.767942 -269.397226)
		(end 76.293218 -269.397226)
		(width 0.0762)
		(layer "F.Cu")
		(net "M_A_CPU1_SB_CB<6>")
	)
	(segment
		(start 63.952374 -269.645384)
		(end 61.816234 -271.781524)
		(width 0.10668)
		(layer "F.Cu")
		(net "M_A_CPU1_SB_CB<6>")
	)
	(segment
		(start 61.18987 -272.53311)
		(end 61.00699 -272.35023)
		(width 0.10668)
		(layer "F.Cu")
		(net "M_A_CPU1_SB_CB<6>")
	)
	(segment
		(start 76.0857 -269.604744)
		(end 75.458828 -269.604744)
		(width 0.10668)
		(layer "F.Cu")
		(net "M_A_CPU1_SB_CB<6>")
	)
	(segment
		(start 61.42482 -271.781524)
		(end 61.289184 -271.91716)
		(width 0.10668)
		(layer "F.Cu")
		(net "M_A_CPU1_SB_CB<6>")
	)
	(segment
		(start 64.504316 -269.482316)
		(end 64.504316 -269.633192)
		(width 0.10668)
		(layer "F.Cu")
		(net "M_A_CPU1_SB_CB<6>")
	)
	(segment
		(start 64.222376 -269.76451)
		(end 64.10325 -269.645384)
		(width 0.10668)
		(layer "F.Cu")
		(net "M_A_CPU1_SB_CB<6>")
	)
	(segment
		(start 64.937132 -269.200376)
		(end 64.786764 -269.200122)
		(width 0.10668)
		(layer "F.Cu")
		(net "M_A_CPU1_SB_CB<6>")
	)
	(segment
		(start 60.646056 -272.560288)
		(end 56.802782 -272.560288)
		(width 0.101346)
		(layer "F.Cu")
		(net "M_A_CPU1_SB_CB<6>")
	)
	(segment
		(start 64.38519 -269.36319)
		(end 64.504316 -269.482316)
		(width 0.10668)
		(layer "F.Cu")
		(net "M_A_CPU1_SB_CB<6>")
	)
	(segment
		(start 64.372744 -269.764764)
		(end 64.222376 -269.76451)
		(width 0.10668)
		(layer "F.Cu")
		(net "M_A_CPU1_SB_CB<6>")
	)
	(segment
		(start 64.385444 -269.212314)
		(end 64.38519 -269.36319)
		(width 0.10668)
		(layer "F.Cu")
		(net "M_A_CPU1_SB_CB<6>")
	)
	(segment
		(start 61.00699 -272.35023)
		(end 60.856114 -272.35023)
		(width 0.10668)
		(layer "F.Cu")
		(net "M_A_CPU1_SB_CB<6>")
	)
	(segment
		(start 65.068704 -269.068804)
		(end 64.937132 -269.200376)
		(width 0.10668)
		(layer "F.Cu")
		(net "M_A_CPU1_SB_CB<6>")
	)
	(segment
		(start 64.786764 -269.200122)
		(end 64.667638 -269.080996)
		(width 0.10668)
		(layer "F.Cu")
		(net "M_A_CPU1_SB_CB<6>")
	)
	(segment
		(start 61.816234 -271.781524)
		(end 61.42482 -271.781524)
		(width 0.10668)
		(layer "F.Cu")
		(net "M_A_CPU1_SB_CB<6>")
	)
	(segment
		(start 64.949578 -268.798802)
		(end 65.068704 -268.917928)
		(width 0.10668)
		(layer "F.Cu")
		(net "M_A_CPU1_SB_CB<6>")
	)
	(segment
		(start 64.10325 -269.645384)
		(end 63.952374 -269.645384)
		(width 0.10668)
		(layer "F.Cu")
		(net "M_A_CPU1_SB_CB<6>")
	)
	(segment
		(start 65.068704 -268.917928)
		(end 65.068704 -269.068804)
		(width 0.10668)
		(layer "F.Cu")
		(net "M_A_CPU1_SB_CB<6>")
	)
	(segment
		(start 56.37784 -272.98523)
		(end 55.328058 -272.98523)
		(width 0.101346)
		(layer "F.Cu")
		(net "M_A_CPU1_SB_CB<6>")
	)
	(segment
		(start 60.856114 -272.35023)
		(end 60.646056 -272.560288)
		(width 0.10668)
		(layer "F.Cu")
		(net "M_A_CPU1_SB_CB<6>")
	)
	(segment
		(start 64.667638 -269.080996)
		(end 64.516762 -269.080996)
		(width 0.10668)
		(layer "F.Cu")
		(net "M_A_CPU1_SB_CB<6>")
	)
	(segment
		(start 61.289184 -272.068036)
		(end 61.472064 -272.250916)
		(width 0.10668)
		(layer "F.Cu")
		(net "M_A_CPU1_SB_CB<6>")
	)
	(segment
		(start 61.289184 -271.91716)
		(end 61.289184 -272.068036)
		(width 0.10668)
		(layer "F.Cu")
		(net "M_A_CPU1_SB_CB<6>")
	)
	(segment
		(start 56.802782 -272.560288)
		(end 56.37784 -272.98523)
		(width 0.101346)
		(layer "F.Cu")
		(net "M_A_CPU1_SB_CB<6>")
	)
	(segment
		(start 61.472064 -272.250916)
		(end 61.472064 -272.401792)
		(width 0.10668)
		(layer "F.Cu")
		(net "M_A_CPU1_SB_CB<6>")
	)
	(segment
		(start 64.504316 -269.633192)
		(end 64.372744 -269.764764)
		(width 0.10668)
		(layer "F.Cu")
		(net "M_A_CPU1_SB_CB<6>")
	)
	(segment
		(start 65.252092 -268.345666)
		(end 64.949832 -268.647926)
		(width 0.10668)
		(layer "F.Cu")
		(net "M_A_CPU1_SB_CB<6>")
	)
	(segment
		(start 64.516762 -269.080996)
		(end 64.385444 -269.212314)
		(width 0.10668)
		(layer "F.Cu")
		(net "M_A_CPU1_SB_CB<6>")
	)
	(segment
		(start 75.458828 -269.604744)
		(end 74.19975 -268.345666)
		(width 0.10668)
		(layer "F.Cu")
		(net "M_A_CPU1_SB_CB<6>")
	)
	(segment
		(start 64.949832 -268.647926)
		(end 64.949578 -268.798802)
		(width 0.10668)
		(layer "F.Cu")
		(net "M_A_CPU1_SB_CB<6>")
	)
	(segment
		(start 76.293218 -269.397226)
		(end 76.0857 -269.604744)
		(width 0.0762)
		(layer "F.Cu")
		(net "M_A_CPU1_SB_CB<6>")
	)
	(segment
		(start 74.19975 -268.345666)
		(end 65.252092 -268.345666)
		(width 0.10668)
		(layer "F.Cu")
		(net "M_A_CPU1_SB_CB<6>")
	)
	(segment
		(start 61.472064 -272.401792)
		(end 61.340746 -272.53311)
		(width 0.10668)
		(layer "F.Cu")
		(net "M_A_CPU1_SB_CB<6>")
	)
	(segment
		(start 61.340746 -272.53311)
		(end 61.18987 -272.53311)
		(width 0.10668)
		(layer "F.Cu")
		(net "M_A_CPU1_SB_CB<6>")
	)
	(arc
		(start 78.180692 -269.521178)
		(mid 78.063879 -269.496502)
		(end 77.954886 -269.447772)
		(width 0.0762)
		(layer "F.Cu")
		(net "M_A_CPU1_SB_CB<6>")
	)
	(arc
		(start 77.954886 -269.447772)
		(mid 77.864753 -269.410152)
		(end 77.767942 -269.397226)
		(width 0.0762)
		(layer "F.Cu")
		(net "M_A_CPU1_SB_CB<6>")
	)
	(arc
		(start 78.707996 -269.770352)
		(mid 78.465679 -269.600632)
		(end 78.180692 -269.521178)
		(width 0.0762)
		(layer "F.Cu")
		(net "M_A_CPU1_SB_CB<6>")
	)
	(segment
		(start 62.342014 -272.167096)
		(end 62.482222 -272.307304)
		(width 0.10668)
		(layer "F.Cu")
		(net "M_A_CPU1_SB_CB<5>")
	)
	(segment
		(start 63.611252 -271.328896)
		(end 63.47968 -271.460468)
		(width 0.10668)
		(layer "F.Cu")
		(net "M_A_CPU1_SB_CB<5>")
	)
	(segment
		(start 79.647796 -269.770352)
		(end 79.748634 -269.943834)
		(width 0.0762)
		(layer "F.Cu")
		(net "M_A_CPU1_SB_CB<5>")
	)
	(segment
		(start 61.63564 -273.153632)
		(end 61.377576 -272.895568)
		(width 0.10668)
		(layer "F.Cu")
		(net "M_A_CPU1_SB_CB<5>")
	)
	(segment
		(start 62.482476 -272.457672)
		(end 62.350904 -272.589244)
		(width 0.10668)
		(layer "F.Cu")
		(net "M_A_CPU1_SB_CB<5>")
	)
	(segment
		(start 63.893192 -270.89608)
		(end 63.752984 -270.755872)
		(width 0.10668)
		(layer "F.Cu")
		(net "M_A_CPU1_SB_CB<5>")
	)
	(segment
		(start 79.469234 -270.097758)
		(end 79.460852 -270.092932)
		(width 0.0762)
		(layer "F.Cu")
		(net "M_A_CPU1_SB_CB<5>")
	)
	(segment
		(start 61.071252 -273.71802)
		(end 60.931044 -273.577812)
		(width 0.10668)
		(layer "F.Cu")
		(net "M_A_CPU1_SB_CB<5>")
	)
	(segment
		(start 61.353446 -273.43608)
		(end 61.3537 -273.586448)
		(width 0.10668)
		(layer "F.Cu")
		(net "M_A_CPU1_SB_CB<5>")
	)
	(segment
		(start 78.89494 -270.092932)
		(end 78.886558 -270.097758)
		(width 0.0762)
		(layer "F.Cu")
		(net "M_A_CPU1_SB_CB<5>")
	)
	(segment
		(start 62.906402 -271.451832)
		(end 62.906402 -271.602708)
		(width 0.10668)
		(layer "F.Cu")
		(net "M_A_CPU1_SB_CB<5>")
	)
	(segment
		(start 63.47079 -271.03832)
		(end 63.610998 -271.178528)
		(width 0.10668)
		(layer "F.Cu")
		(net "M_A_CPU1_SB_CB<5>")
	)
	(segment
		(start 63.752984 -270.755872)
		(end 63.602108 -270.756126)
		(width 0.10668)
		(layer "F.Cu")
		(net "M_A_CPU1_SB_CB<5>")
	)
	(segment
		(start 63.47968 -271.460468)
		(end 63.328804 -271.460468)
		(width 0.10668)
		(layer "F.Cu")
		(net "M_A_CPU1_SB_CB<5>")
	)
	(segment
		(start 63.328804 -271.460468)
		(end 63.188596 -271.32026)
		(width 0.10668)
		(layer "F.Cu")
		(net "M_A_CPU1_SB_CB<5>")
	)
	(segment
		(start 61.3537 -273.586448)
		(end 61.222128 -273.71802)
		(width 0.10668)
		(layer "F.Cu")
		(net "M_A_CPU1_SB_CB<5>")
	)
	(segment
		(start 62.350904 -272.589244)
		(end 62.200028 -272.589244)
		(width 0.10668)
		(layer "F.Cu")
		(net "M_A_CPU1_SB_CB<5>")
	)
	(segment
		(start 62.915292 -272.024856)
		(end 62.764416 -272.024856)
		(width 0.10668)
		(layer "F.Cu")
		(net "M_A_CPU1_SB_CB<5>")
	)
	(segment
		(start 61.095382 -273.178016)
		(end 61.353446 -273.43608)
		(width 0.10668)
		(layer "F.Cu")
		(net "M_A_CPU1_SB_CB<5>")
	)
	(segment
		(start 61.2267 -272.895822)
		(end 61.095382 -273.02714)
		(width 0.10668)
		(layer "F.Cu")
		(net "M_A_CPU1_SB_CB<5>")
	)
	(segment
		(start 75.938126 -269.945104)
		(end 75.317604 -269.945104)
		(width 0.10668)
		(layer "F.Cu")
		(net "M_A_CPU1_SB_CB<5>")
	)
	(segment
		(start 64.035178 -270.323056)
		(end 64.035178 -270.473932)
		(width 0.10668)
		(layer "F.Cu")
		(net "M_A_CPU1_SB_CB<5>")
	)
	(segment
		(start 61.918088 -273.02206)
		(end 61.786516 -273.153632)
		(width 0.10668)
		(layer "F.Cu")
		(net "M_A_CPU1_SB_CB<5>")
	)
	(segment
		(start 60.780168 -273.578066)
		(end 60.522866 -273.835368)
		(width 0.10668)
		(layer "F.Cu")
		(net "M_A_CPU1_SB_CB<5>")
	)
	(segment
		(start 63.03772 -271.320514)
		(end 62.906402 -271.451832)
		(width 0.10668)
		(layer "F.Cu")
		(net "M_A_CPU1_SB_CB<5>")
	)
	(segment
		(start 61.917834 -272.871692)
		(end 61.918088 -273.02206)
		(width 0.10668)
		(layer "F.Cu")
		(net "M_A_CPU1_SB_CB<5>")
	)
	(segment
		(start 66.254122 -268.686026)
		(end 64.608456 -270.331692)
		(width 0.10668)
		(layer "F.Cu")
		(net "M_A_CPU1_SB_CB<5>")
	)
	(segment
		(start 63.47079 -270.887444)
		(end 63.47079 -271.03832)
		(width 0.10668)
		(layer "F.Cu")
		(net "M_A_CPU1_SB_CB<5>")
	)
	(segment
		(start 77.767942 -270.143478)
		(end 76.6445 -270.143478)
		(width 0.0762)
		(layer "F.Cu")
		(net "M_A_CPU1_SB_CB<5>")
	)
	(segment
		(start 64.166496 -270.191738)
		(end 64.035178 -270.323056)
		(width 0.10668)
		(layer "F.Cu")
		(net "M_A_CPU1_SB_CB<5>")
	)
	(segment
		(start 76.6445 -270.143478)
		(end 76.446126 -269.945104)
		(width 0.0762)
		(layer "F.Cu")
		(net "M_A_CPU1_SB_CB<5>")
	)
	(segment
		(start 64.044068 -270.89608)
		(end 63.893192 -270.89608)
		(width 0.10668)
		(layer "F.Cu")
		(net "M_A_CPU1_SB_CB<5>")
	)
	(segment
		(start 62.200028 -272.589244)
		(end 62.05982 -272.449036)
		(width 0.10668)
		(layer "F.Cu")
		(net "M_A_CPU1_SB_CB<5>")
	)
	(segment
		(start 62.764416 -272.024856)
		(end 62.624208 -271.884648)
		(width 0.10668)
		(layer "F.Cu")
		(net "M_A_CPU1_SB_CB<5>")
	)
	(segment
		(start 63.04661 -271.742916)
		(end 63.046864 -271.893284)
		(width 0.10668)
		(layer "F.Cu")
		(net "M_A_CPU1_SB_CB<5>")
	)
	(segment
		(start 62.624208 -271.884648)
		(end 62.473332 -271.884902)
		(width 0.10668)
		(layer "F.Cu")
		(net "M_A_CPU1_SB_CB<5>")
	)
	(segment
		(start 64.317372 -270.191484)
		(end 64.166496 -270.191738)
		(width 0.10668)
		(layer "F.Cu")
		(net "M_A_CPU1_SB_CB<5>")
	)
	(segment
		(start 61.786516 -273.153632)
		(end 61.63564 -273.153632)
		(width 0.10668)
		(layer "F.Cu")
		(net "M_A_CPU1_SB_CB<5>")
	)
	(segment
		(start 62.482222 -272.307304)
		(end 62.482476 -272.457672)
		(width 0.10668)
		(layer "F.Cu")
		(net "M_A_CPU1_SB_CB<5>")
	)
	(segment
		(start 64.035178 -270.473932)
		(end 64.175386 -270.61414)
		(width 0.10668)
		(layer "F.Cu")
		(net "M_A_CPU1_SB_CB<5>")
	)
	(segment
		(start 63.188596 -271.32026)
		(end 63.03772 -271.320514)
		(width 0.10668)
		(layer "F.Cu")
		(net "M_A_CPU1_SB_CB<5>")
	)
	(segment
		(start 75.317604 -269.945104)
		(end 74.058526 -268.686026)
		(width 0.10668)
		(layer "F.Cu")
		(net "M_A_CPU1_SB_CB<5>")
	)
	(segment
		(start 63.046864 -271.893284)
		(end 62.915292 -272.024856)
		(width 0.10668)
		(layer "F.Cu")
		(net "M_A_CPU1_SB_CB<5>")
	)
	(segment
		(start 62.342014 -272.01622)
		(end 62.342014 -272.167096)
		(width 0.10668)
		(layer "F.Cu")
		(net "M_A_CPU1_SB_CB<5>")
	)
	(segment
		(start 61.095382 -273.02714)
		(end 61.095382 -273.178016)
		(width 0.10668)
		(layer "F.Cu")
		(net "M_A_CPU1_SB_CB<5>")
	)
	(segment
		(start 63.602108 -270.756126)
		(end 63.47079 -270.887444)
		(width 0.10668)
		(layer "F.Cu")
		(net "M_A_CPU1_SB_CB<5>")
	)
	(segment
		(start 61.777626 -272.580608)
		(end 61.777626 -272.731484)
		(width 0.10668)
		(layer "F.Cu")
		(net "M_A_CPU1_SB_CB<5>")
	)
	(segment
		(start 62.473332 -271.884902)
		(end 62.342014 -272.01622)
		(width 0.10668)
		(layer "F.Cu")
		(net "M_A_CPU1_SB_CB<5>")
	)
	(segment
		(start 61.222128 -273.71802)
		(end 61.071252 -273.71802)
		(width 0.10668)
		(layer "F.Cu")
		(net "M_A_CPU1_SB_CB<5>")
	)
	(segment
		(start 64.175386 -270.61414)
		(end 64.17564 -270.764508)
		(width 0.10668)
		(layer "F.Cu")
		(net "M_A_CPU1_SB_CB<5>")
	)
	(segment
		(start 61.777626 -272.731484)
		(end 61.917834 -272.871692)
		(width 0.10668)
		(layer "F.Cu")
		(net "M_A_CPU1_SB_CB<5>")
	)
	(segment
		(start 76.446126 -269.945104)
		(end 75.938126 -269.945104)
		(width 0.0762)
		(layer "F.Cu")
		(net "M_A_CPU1_SB_CB<5>")
	)
	(segment
		(start 60.522866 -273.835368)
		(end 59.428126 -273.835368)
		(width 0.10668)
		(layer "F.Cu")
		(net "M_A_CPU1_SB_CB<5>")
	)
	(segment
		(start 63.610998 -271.178528)
		(end 63.611252 -271.328896)
		(width 0.10668)
		(layer "F.Cu")
		(net "M_A_CPU1_SB_CB<5>")
	)
	(segment
		(start 74.058526 -268.686026)
		(end 66.254122 -268.686026)
		(width 0.10668)
		(layer "F.Cu")
		(net "M_A_CPU1_SB_CB<5>")
	)
	(segment
		(start 64.17564 -270.764508)
		(end 64.044068 -270.89608)
		(width 0.10668)
		(layer "F.Cu")
		(net "M_A_CPU1_SB_CB<5>")
	)
	(segment
		(start 64.608456 -270.331692)
		(end 64.45758 -270.331692)
		(width 0.10668)
		(layer "F.Cu")
		(net "M_A_CPU1_SB_CB<5>")
	)
	(segment
		(start 62.906402 -271.602708)
		(end 63.04661 -271.742916)
		(width 0.10668)
		(layer "F.Cu")
		(net "M_A_CPU1_SB_CB<5>")
	)
	(segment
		(start 61.377576 -272.895568)
		(end 61.2267 -272.895822)
		(width 0.10668)
		(layer "F.Cu")
		(net "M_A_CPU1_SB_CB<5>")
	)
	(segment
		(start 64.45758 -270.331692)
		(end 64.317372 -270.191484)
		(width 0.10668)
		(layer "F.Cu")
		(net "M_A_CPU1_SB_CB<5>")
	)
	(segment
		(start 62.05982 -272.449036)
		(end 61.908944 -272.44929)
		(width 0.10668)
		(layer "F.Cu")
		(net "M_A_CPU1_SB_CB<5>")
	)
	(segment
		(start 60.931044 -273.577812)
		(end 60.780168 -273.578066)
		(width 0.10668)
		(layer "F.Cu")
		(net "M_A_CPU1_SB_CB<5>")
	)
	(segment
		(start 61.908944 -272.44929)
		(end 61.777626 -272.580608)
		(width 0.10668)
		(layer "F.Cu")
		(net "M_A_CPU1_SB_CB<5>")
	)
	(arc
		(start 78.520798 -270.092932)
		(mid 78.237842 -270.016755)
		(end 77.954886 -270.092932)
		(width 0.0762)
		(layer "F.Cu")
		(net "M_A_CPU1_SB_CB<5>")
	)
	(arc
		(start 77.79893 -270.142208)
		(mid 77.783449 -270.143164)
		(end 77.767942 -270.143478)
		(width 0.0762)
		(layer "F.Cu")
		(net "M_A_CPU1_SB_CB<5>")
	)
	(arc
		(start 79.602584 -270.14043)
		(mid 79.533886 -270.125414)
		(end 79.469234 -270.097758)
		(width 0.0762)
		(layer "F.Cu")
		(net "M_A_CPU1_SB_CB<5>")
	)
	(arc
		(start 79.460852 -270.092932)
		(mid 79.177896 -270.016755)
		(end 78.89494 -270.092932)
		(width 0.0762)
		(layer "F.Cu")
		(net "M_A_CPU1_SB_CB<5>")
	)
	(arc
		(start 79.748634 -269.943834)
		(mid 79.732709 -270.084526)
		(end 79.602584 -270.14043)
		(width 0.0762)
		(layer "F.Cu")
		(net "M_A_CPU1_SB_CB<5>")
	)
	(arc
		(start 77.954886 -270.092932)
		(mid 77.879646 -270.126245)
		(end 77.79893 -270.142208)
		(width 0.0762)
		(layer "F.Cu")
		(net "M_A_CPU1_SB_CB<5>")
	)
	(arc
		(start 78.886558 -270.097758)
		(mid 78.70305 -270.143252)
		(end 78.520798 -270.092932)
		(width 0.0762)
		(layer "F.Cu")
		(net "M_A_CPU1_SB_CB<5>")
	)
	(segment
		(start 69.06768 -267.898626)
		(end 69.06768 -267.736066)
		(width 0.10668)
		(layer "F.Cu")
		(net "M_A_CPU1_SB_CB<4>")
	)
	(segment
		(start 66.96583 -268.005306)
		(end 66.780156 -268.005306)
		(width 0.10668)
		(layer "F.Cu")
		(net "M_A_CPU1_SB_CB<4>")
	)
	(segment
		(start 78.05928 -269.287752)
		(end 78.050898 -269.282926)
		(width 0.0762)
		(layer "F.Cu")
		(net "M_A_CPU1_SB_CB<4>")
	)
	(segment
		(start 72.658986 -267.736066)
		(end 72.658986 -267.898626)
		(width 0.10668)
		(layer "F.Cu")
		(net "M_A_CPU1_SB_CB<4>")
	)
	(segment
		(start 70.264782 -267.736066)
		(end 70.264782 -267.898626)
		(width 0.10668)
		(layer "F.Cu")
		(net "M_A_CPU1_SB_CB<4>")
	)
	(segment
		(start 68.561966 -268.005306)
		(end 68.376292 -268.005306)
		(width 0.10668)
		(layer "F.Cu")
		(net "M_A_CPU1_SB_CB<4>")
	)
	(segment
		(start 74.88301 -268.396466)
		(end 74.732134 -268.396466)
		(width 0.10668)
		(layer "F.Cu")
		(net "M_A_CPU1_SB_CB<4>")
	)
	(segment
		(start 72.658986 -267.898626)
		(end 72.552306 -268.005306)
		(width 0.10668)
		(layer "F.Cu")
		(net "M_A_CPU1_SB_CB<4>")
	)
	(segment
		(start 73.1647 -268.005306)
		(end 73.05802 -267.898626)
		(width 0.10668)
		(layer "F.Cu")
		(net "M_A_CPU1_SB_CB<4>")
	)
	(segment
		(start 75.600052 -269.264384)
		(end 75.165204 -268.829536)
		(width 0.10668)
		(layer "F.Cu")
		(net "M_A_CPU1_SB_CB<4>")
	)
	(segment
		(start 69.972428 -268.005306)
		(end 69.865748 -267.898626)
		(width 0.10668)
		(layer "F.Cu")
		(net "M_A_CPU1_SB_CB<4>")
	)
	(segment
		(start 65.875408 -267.736066)
		(end 65.768728 -267.629386)
		(width 0.10668)
		(layer "F.Cu")
		(net "M_A_CPU1_SB_CB<4>")
	)
	(segment
		(start 60.376562 -272.135346)
		(end 59.428126 -272.135346)
		(width 0.10668)
		(layer "F.Cu")
		(net "M_A_CPU1_SB_CB<4>")
	)
	(segment
		(start 69.466714 -267.898626)
		(end 69.360034 -268.005306)
		(width 0.10668)
		(layer "F.Cu")
		(net "M_A_CPU1_SB_CB<4>")
	)
	(segment
		(start 74.418444 -267.732256)
		(end 74.318622 -267.832078)
		(width 0.10668)
		(layer "F.Cu")
		(net "M_A_CPU1_SB_CB<4>")
	)
	(segment
		(start 67.471544 -267.898626)
		(end 67.471544 -267.736066)
		(width 0.10668)
		(layer "F.Cu")
		(net "M_A_CPU1_SB_CB<4>")
	)
	(segment
		(start 66.780156 -268.005306)
		(end 66.673476 -267.898626)
		(width 0.10668)
		(layer "F.Cu")
		(net "M_A_CPU1_SB_CB<4>")
	)
	(segment
		(start 72.765666 -267.629386)
		(end 72.658986 -267.736066)
		(width 0.10668)
		(layer "F.Cu")
		(net "M_A_CPU1_SB_CB<4>")
	)
	(segment
		(start 74.700638 -267.863574)
		(end 74.56932 -267.732256)
		(width 0.10668)
		(layer "F.Cu")
		(net "M_A_CPU1_SB_CB<4>")
	)
	(segment
		(start 74.167746 -267.832078)
		(end 73.965054 -267.629386)
		(width 0.10668)
		(layer "F.Cu")
		(net "M_A_CPU1_SB_CB<4>")
	)
	(segment
		(start 66.673476 -267.898626)
		(end 66.673476 -267.736066)
		(width 0.10668)
		(layer "F.Cu")
		(net "M_A_CPU1_SB_CB<4>")
	)
	(segment
		(start 66.274442 -267.898626)
		(end 66.167762 -268.005306)
		(width 0.10668)
		(layer "F.Cu")
		(net "M_A_CPU1_SB_CB<4>")
	)
	(segment
		(start 67.471544 -267.736066)
		(end 67.364864 -267.629386)
		(width 0.10668)
		(layer "F.Cu")
		(net "M_A_CPU1_SB_CB<4>")
	)
	(segment
		(start 67.07251 -267.898626)
		(end 66.96583 -268.005306)
		(width 0.10668)
		(layer "F.Cu")
		(net "M_A_CPU1_SB_CB<4>")
	)
	(segment
		(start 74.700638 -268.01445)
		(end 74.700638 -267.863574)
		(width 0.10668)
		(layer "F.Cu")
		(net "M_A_CPU1_SB_CB<4>")
	)
	(segment
		(start 73.457054 -267.736066)
		(end 73.457054 -267.898626)
		(width 0.10668)
		(layer "F.Cu")
		(net "M_A_CPU1_SB_CB<4>")
	)
	(segment
		(start 70.158102 -268.005306)
		(end 69.972428 -268.005306)
		(width 0.10668)
		(layer "F.Cu")
		(net "M_A_CPU1_SB_CB<4>")
	)
	(segment
		(start 67.870578 -267.898626)
		(end 67.763898 -268.005306)
		(width 0.10668)
		(layer "F.Cu")
		(net "M_A_CPU1_SB_CB<4>")
	)
	(segment
		(start 75.165204 -268.829536)
		(end 75.165204 -268.67866)
		(width 0.10668)
		(layer "F.Cu")
		(net "M_A_CPU1_SB_CB<4>")
	)
	(segment
		(start 74.600816 -268.114272)
		(end 74.700638 -268.01445)
		(width 0.10668)
		(layer "F.Cu")
		(net "M_A_CPU1_SB_CB<4>")
	)
	(segment
		(start 66.673476 -267.736066)
		(end 66.566796 -267.629386)
		(width 0.10668)
		(layer "F.Cu")
		(net "M_A_CPU1_SB_CB<4>")
	)
	(segment
		(start 68.269612 -267.898626)
		(end 68.269612 -267.736066)
		(width 0.10668)
		(layer "F.Cu")
		(net "M_A_CPU1_SB_CB<4>")
	)
	(segment
		(start 75.265026 -268.427962)
		(end 75.133708 -268.296644)
		(width 0.10668)
		(layer "F.Cu")
		(net "M_A_CPU1_SB_CB<4>")
	)
	(segment
		(start 71.461884 -267.736066)
		(end 71.355204 -267.629386)
		(width 0.10668)
		(layer "F.Cu")
		(net "M_A_CPU1_SB_CB<4>")
	)
	(segment
		(start 71.06285 -267.736066)
		(end 71.06285 -267.898626)
		(width 0.10668)
		(layer "F.Cu")
		(net "M_A_CPU1_SB_CB<4>")
	)
	(segment
		(start 70.770496 -268.005306)
		(end 70.663816 -267.898626)
		(width 0.10668)
		(layer "F.Cu")
		(net "M_A_CPU1_SB_CB<4>")
	)
	(segment
		(start 78.237842 -268.960346)
		(end 78.33614 -269.12951)
		(width 0.0762)
		(layer "F.Cu")
		(net "M_A_CPU1_SB_CB<4>")
	)
	(segment
		(start 67.763898 -268.005306)
		(end 67.578224 -268.005306)
		(width 0.10668)
		(layer "F.Cu")
		(net "M_A_CPU1_SB_CB<4>")
	)
	(segment
		(start 65.768728 -267.629386)
		(end 65.486788 -267.629386)
		(width 0.10668)
		(layer "F.Cu")
		(net "M_A_CPU1_SB_CB<4>")
	)
	(segment
		(start 72.153272 -267.629386)
		(end 71.967598 -267.629386)
		(width 0.10668)
		(layer "F.Cu")
		(net "M_A_CPU1_SB_CB<4>")
	)
	(segment
		(start 70.663816 -267.898626)
		(end 70.663816 -267.736066)
		(width 0.10668)
		(layer "F.Cu")
		(net "M_A_CPU1_SB_CB<4>")
	)
	(segment
		(start 68.376292 -268.005306)
		(end 68.269612 -267.898626)
		(width 0.10668)
		(layer "F.Cu")
		(net "M_A_CPU1_SB_CB<4>")
	)
	(segment
		(start 70.663816 -267.736066)
		(end 70.557136 -267.629386)
		(width 0.10668)
		(layer "F.Cu")
		(net "M_A_CPU1_SB_CB<4>")
	)
	(segment
		(start 75.985624 -269.206726)
		(end 75.927966 -269.264384)
		(width 0.0762)
		(layer "F.Cu")
		(net "M_A_CPU1_SB_CB<4>")
	)
	(segment
		(start 69.865748 -267.898626)
		(end 69.865748 -267.736066)
		(width 0.10668)
		(layer "F.Cu")
		(net "M_A_CPU1_SB_CB<4>")
	)
	(segment
		(start 68.668646 -267.736066)
		(end 68.668646 -267.898626)
		(width 0.10668)
		(layer "F.Cu")
		(net "M_A_CPU1_SB_CB<4>")
	)
	(segment
		(start 67.977258 -267.629386)
		(end 67.870578 -267.736066)
		(width 0.10668)
		(layer "F.Cu")
		(net "M_A_CPU1_SB_CB<4>")
	)
	(segment
		(start 68.162932 -267.629386)
		(end 67.977258 -267.629386)
		(width 0.10668)
		(layer "F.Cu")
		(net "M_A_CPU1_SB_CB<4>")
	)
	(segment
		(start 68.668646 -267.898626)
		(end 68.561966 -268.005306)
		(width 0.10668)
		(layer "F.Cu")
		(net "M_A_CPU1_SB_CB<4>")
	)
	(segment
		(start 74.318622 -267.832078)
		(end 74.167746 -267.832078)
		(width 0.10668)
		(layer "F.Cu")
		(net "M_A_CPU1_SB_CB<4>")
	)
	(segment
		(start 72.552306 -268.005306)
		(end 72.366632 -268.005306)
		(width 0.10668)
		(layer "F.Cu")
		(net "M_A_CPU1_SB_CB<4>")
	)
	(segment
		(start 67.07251 -267.736066)
		(end 67.07251 -267.898626)
		(width 0.10668)
		(layer "F.Cu")
		(net "M_A_CPU1_SB_CB<4>")
	)
	(segment
		(start 70.371462 -267.629386)
		(end 70.264782 -267.736066)
		(width 0.10668)
		(layer "F.Cu")
		(net "M_A_CPU1_SB_CB<4>")
	)
	(segment
		(start 71.16953 -267.629386)
		(end 71.06285 -267.736066)
		(width 0.10668)
		(layer "F.Cu")
		(net "M_A_CPU1_SB_CB<4>")
	)
	(segment
		(start 65.875408 -267.898626)
		(end 65.875408 -267.736066)
		(width 0.10668)
		(layer "F.Cu")
		(net "M_A_CPU1_SB_CB<4>")
	)
	(segment
		(start 73.563734 -267.629386)
		(end 73.457054 -267.736066)
		(width 0.10668)
		(layer "F.Cu")
		(net "M_A_CPU1_SB_CB<4>")
	)
	(segment
		(start 71.860918 -267.898626)
		(end 71.754238 -268.005306)
		(width 0.10668)
		(layer "F.Cu")
		(net "M_A_CPU1_SB_CB<4>")
	)
	(segment
		(start 73.457054 -267.898626)
		(end 73.350374 -268.005306)
		(width 0.10668)
		(layer "F.Cu")
		(net "M_A_CPU1_SB_CB<4>")
	)
	(segment
		(start 72.95134 -267.629386)
		(end 72.765666 -267.629386)
		(width 0.10668)
		(layer "F.Cu")
		(net "M_A_CPU1_SB_CB<4>")
	)
	(segment
		(start 71.754238 -268.005306)
		(end 71.568564 -268.005306)
		(width 0.10668)
		(layer "F.Cu")
		(net "M_A_CPU1_SB_CB<4>")
	)
	(segment
		(start 67.578224 -268.005306)
		(end 67.471544 -267.898626)
		(width 0.10668)
		(layer "F.Cu")
		(net "M_A_CPU1_SB_CB<4>")
	)
	(segment
		(start 68.269612 -267.736066)
		(end 68.162932 -267.629386)
		(width 0.10668)
		(layer "F.Cu")
		(net "M_A_CPU1_SB_CB<4>")
	)
	(segment
		(start 69.466714 -267.736066)
		(end 69.466714 -267.898626)
		(width 0.10668)
		(layer "F.Cu")
		(net "M_A_CPU1_SB_CB<4>")
	)
	(segment
		(start 69.759068 -267.629386)
		(end 69.573394 -267.629386)
		(width 0.10668)
		(layer "F.Cu")
		(net "M_A_CPU1_SB_CB<4>")
	)
	(segment
		(start 65.982088 -268.005306)
		(end 65.875408 -267.898626)
		(width 0.10668)
		(layer "F.Cu")
		(net "M_A_CPU1_SB_CB<4>")
	)
	(segment
		(start 73.965054 -267.629386)
		(end 73.563734 -267.629386)
		(width 0.10668)
		(layer "F.Cu")
		(net "M_A_CPU1_SB_CB<4>")
	)
	(segment
		(start 72.259952 -267.898626)
		(end 72.259952 -267.736066)
		(width 0.10668)
		(layer "F.Cu")
		(net "M_A_CPU1_SB_CB<4>")
	)
	(segment
		(start 70.557136 -267.629386)
		(end 70.371462 -267.629386)
		(width 0.10668)
		(layer "F.Cu")
		(net "M_A_CPU1_SB_CB<4>")
	)
	(segment
		(start 67.870578 -267.736066)
		(end 67.870578 -267.898626)
		(width 0.10668)
		(layer "F.Cu")
		(net "M_A_CPU1_SB_CB<4>")
	)
	(segment
		(start 75.165204 -268.67866)
		(end 75.265026 -268.578838)
		(width 0.10668)
		(layer "F.Cu")
		(net "M_A_CPU1_SB_CB<4>")
	)
	(segment
		(start 67.364864 -267.629386)
		(end 67.17919 -267.629386)
		(width 0.10668)
		(layer "F.Cu")
		(net "M_A_CPU1_SB_CB<4>")
	)
	(segment
		(start 71.568564 -268.005306)
		(end 71.461884 -267.898626)
		(width 0.10668)
		(layer "F.Cu")
		(net "M_A_CPU1_SB_CB<4>")
	)
	(segment
		(start 73.350374 -268.005306)
		(end 73.1647 -268.005306)
		(width 0.10668)
		(layer "F.Cu")
		(net "M_A_CPU1_SB_CB<4>")
	)
	(segment
		(start 69.360034 -268.005306)
		(end 69.17436 -268.005306)
		(width 0.10668)
		(layer "F.Cu")
		(net "M_A_CPU1_SB_CB<4>")
	)
	(segment
		(start 75.133708 -268.296644)
		(end 74.982832 -268.296644)
		(width 0.10668)
		(layer "F.Cu")
		(net "M_A_CPU1_SB_CB<4>")
	)
	(segment
		(start 66.566796 -267.629386)
		(end 66.381122 -267.629386)
		(width 0.10668)
		(layer "F.Cu")
		(net "M_A_CPU1_SB_CB<4>")
	)
	(segment
		(start 74.982832 -268.296644)
		(end 74.88301 -268.396466)
		(width 0.10668)
		(layer "F.Cu")
		(net "M_A_CPU1_SB_CB<4>")
	)
	(segment
		(start 73.05802 -267.736066)
		(end 72.95134 -267.629386)
		(width 0.10668)
		(layer "F.Cu")
		(net "M_A_CPU1_SB_CB<4>")
	)
	(segment
		(start 69.17436 -268.005306)
		(end 69.06768 -267.898626)
		(width 0.10668)
		(layer "F.Cu")
		(net "M_A_CPU1_SB_CB<4>")
	)
	(segment
		(start 72.259952 -267.736066)
		(end 72.153272 -267.629386)
		(width 0.10668)
		(layer "F.Cu")
		(net "M_A_CPU1_SB_CB<4>")
	)
	(segment
		(start 71.06285 -267.898626)
		(end 70.95617 -268.005306)
		(width 0.10668)
		(layer "F.Cu")
		(net "M_A_CPU1_SB_CB<4>")
	)
	(segment
		(start 73.05802 -267.898626)
		(end 73.05802 -267.736066)
		(width 0.10668)
		(layer "F.Cu")
		(net "M_A_CPU1_SB_CB<4>")
	)
	(segment
		(start 69.865748 -267.736066)
		(end 69.759068 -267.629386)
		(width 0.10668)
		(layer "F.Cu")
		(net "M_A_CPU1_SB_CB<4>")
	)
	(segment
		(start 71.355204 -267.629386)
		(end 71.16953 -267.629386)
		(width 0.10668)
		(layer "F.Cu")
		(net "M_A_CPU1_SB_CB<4>")
	)
	(segment
		(start 77.767942 -269.206726)
		(end 75.985624 -269.206726)
		(width 0.0762)
		(layer "F.Cu")
		(net "M_A_CPU1_SB_CB<4>")
	)
	(segment
		(start 61.070744 -271.441164)
		(end 60.376562 -272.135346)
		(width 0.10668)
		(layer "F.Cu")
		(net "M_A_CPU1_SB_CB<4>")
	)
	(segment
		(start 61.67501 -271.441164)
		(end 61.070744 -271.441164)
		(width 0.10668)
		(layer "F.Cu")
		(net "M_A_CPU1_SB_CB<4>")
	)
	(segment
		(start 74.600816 -268.265148)
		(end 74.600816 -268.114272)
		(width 0.10668)
		(layer "F.Cu")
		(net "M_A_CPU1_SB_CB<4>")
	)
	(segment
		(start 71.967598 -267.629386)
		(end 71.860918 -267.736066)
		(width 0.10668)
		(layer "F.Cu")
		(net "M_A_CPU1_SB_CB<4>")
	)
	(segment
		(start 71.461884 -267.898626)
		(end 71.461884 -267.736066)
		(width 0.10668)
		(layer "F.Cu")
		(net "M_A_CPU1_SB_CB<4>")
	)
	(segment
		(start 69.573394 -267.629386)
		(end 69.466714 -267.736066)
		(width 0.10668)
		(layer "F.Cu")
		(net "M_A_CPU1_SB_CB<4>")
	)
	(segment
		(start 68.775326 -267.629386)
		(end 68.668646 -267.736066)
		(width 0.10668)
		(layer "F.Cu")
		(net "M_A_CPU1_SB_CB<4>")
	)
	(segment
		(start 70.95617 -268.005306)
		(end 70.770496 -268.005306)
		(width 0.10668)
		(layer "F.Cu")
		(net "M_A_CPU1_SB_CB<4>")
	)
	(segment
		(start 69.06768 -267.736066)
		(end 68.961 -267.629386)
		(width 0.10668)
		(layer "F.Cu")
		(net "M_A_CPU1_SB_CB<4>")
	)
	(segment
		(start 72.366632 -268.005306)
		(end 72.259952 -267.898626)
		(width 0.10668)
		(layer "F.Cu")
		(net "M_A_CPU1_SB_CB<4>")
	)
	(segment
		(start 71.860918 -267.736066)
		(end 71.860918 -267.898626)
		(width 0.10668)
		(layer "F.Cu")
		(net "M_A_CPU1_SB_CB<4>")
	)
	(segment
		(start 66.274442 -267.736066)
		(end 66.274442 -267.898626)
		(width 0.10668)
		(layer "F.Cu")
		(net "M_A_CPU1_SB_CB<4>")
	)
	(segment
		(start 75.927966 -269.264384)
		(end 75.600052 -269.264384)
		(width 0.10668)
		(layer "F.Cu")
		(net "M_A_CPU1_SB_CB<4>")
	)
	(segment
		(start 65.486788 -267.629386)
		(end 61.67501 -271.441164)
		(width 0.10668)
		(layer "F.Cu")
		(net "M_A_CPU1_SB_CB<4>")
	)
	(segment
		(start 74.732134 -268.396466)
		(end 74.600816 -268.265148)
		(width 0.10668)
		(layer "F.Cu")
		(net "M_A_CPU1_SB_CB<4>")
	)
	(segment
		(start 74.56932 -267.732256)
		(end 74.418444 -267.732256)
		(width 0.10668)
		(layer "F.Cu")
		(net "M_A_CPU1_SB_CB<4>")
	)
	(segment
		(start 66.381122 -267.629386)
		(end 66.274442 -267.736066)
		(width 0.10668)
		(layer "F.Cu")
		(net "M_A_CPU1_SB_CB<4>")
	)
	(segment
		(start 75.265026 -268.578838)
		(end 75.265026 -268.427962)
		(width 0.10668)
		(layer "F.Cu")
		(net "M_A_CPU1_SB_CB<4>")
	)
	(segment
		(start 67.17919 -267.629386)
		(end 67.07251 -267.736066)
		(width 0.10668)
		(layer "F.Cu")
		(net "M_A_CPU1_SB_CB<4>")
	)
	(segment
		(start 70.264782 -267.898626)
		(end 70.158102 -268.005306)
		(width 0.10668)
		(layer "F.Cu")
		(net "M_A_CPU1_SB_CB<4>")
	)
	(segment
		(start 68.961 -267.629386)
		(end 68.775326 -267.629386)
		(width 0.10668)
		(layer "F.Cu")
		(net "M_A_CPU1_SB_CB<4>")
	)
	(segment
		(start 66.167762 -268.005306)
		(end 65.982088 -268.005306)
		(width 0.10668)
		(layer "F.Cu")
		(net "M_A_CPU1_SB_CB<4>")
	)
	(arc
		(start 78.33614 -269.12951)
		(mid 78.327547 -269.271389)
		(end 78.198472 -269.331186)
		(width 0.0762)
		(layer "F.Cu")
		(net "M_A_CPU1_SB_CB<4>")
	)
	(arc
		(start 78.198472 -269.331186)
		(mid 78.126734 -269.316334)
		(end 78.05928 -269.287752)
		(width 0.0762)
		(layer "F.Cu")
		(net "M_A_CPU1_SB_CB<4>")
	)
	(arc
		(start 78.050898 -269.282926)
		(mid 77.914462 -269.226101)
		(end 77.767942 -269.206726)
		(width 0.0762)
		(layer "F.Cu")
		(net "M_A_CPU1_SB_CB<4>")
	)
	(segment
		(start 57.148984 -280.635202)
		(end 55.328058 -280.635202)
		(width 0.101346)
		(layer "F.Cu")
		(net "M_A_CPU1_SB_CB<3>")
	)
	(segment
		(start 76.522072 -273.363944)
		(end 75.968606 -273.363944)
		(width 0.0762)
		(layer "F.Cu")
		(net "M_A_CPU1_SB_CB<3>")
	)
	(segment
		(start 75.968606 -273.363944)
		(end 67.653662 -273.363944)
		(width 0.10668)
		(layer "F.Cu")
		(net "M_A_CPU1_SB_CB<3>")
	)
	(segment
		(start 58.17489 -280.21026)
		(end 57.148984 -280.635202)
		(width 0.101346)
		(layer "F.Cu")
		(net "M_A_CPU1_SB_CB<3>")
	)
	(segment
		(start 60.807346 -280.21026)
		(end 60.725812 -280.21026)
		(width 0.10668)
		(layer "F.Cu")
		(net "M_A_CPU1_SB_CB<3>")
	)
	(segment
		(start 67.653662 -273.363944)
		(end 60.807346 -280.21026)
		(width 0.10668)
		(layer "F.Cu")
		(net "M_A_CPU1_SB_CB<3>")
	)
	(segment
		(start 76.73213 -273.574002)
		(end 76.522072 -273.363944)
		(width 0.0762)
		(layer "F.Cu")
		(net "M_A_CPU1_SB_CB<3>")
	)
	(segment
		(start 78.05928 -273.492976)
		(end 78.050898 -273.497802)
		(width 0.0762)
		(layer "F.Cu")
		(net "M_A_CPU1_SB_CB<3>")
	)
	(segment
		(start 77.768196 -273.574002)
		(end 76.73213 -273.574002)
		(width 0.0762)
		(layer "F.Cu")
		(net "M_A_CPU1_SB_CB<3>")
	)
	(segment
		(start 60.725812 -280.21026)
		(end 58.17489 -280.21026)
		(width 0.101346)
		(layer "F.Cu")
		(net "M_A_CPU1_SB_CB<3>")
	)
	(arc
		(start 80.11795 -273.820382)
		(mid 79.880338 -273.649394)
		(end 79.598012 -273.57197)
		(width 0.0762)
		(layer "F.Cu")
		(net "M_A_CPU1_SB_CB<3>")
	)
	(arc
		(start 77.815186 -273.572224)
		(mid 77.791709 -273.5736)
		(end 77.768196 -273.574002)
		(width 0.0762)
		(layer "F.Cu")
		(net "M_A_CPU1_SB_CB<3>")
	)
	(arc
		(start 78.990952 -273.497802)
		(mid 78.707996 -273.573979)
		(end 78.42504 -273.497802)
		(width 0.0762)
		(layer "F.Cu")
		(net "M_A_CPU1_SB_CB<3>")
	)
	(arc
		(start 78.050898 -273.497802)
		(mid 77.937174 -273.548103)
		(end 77.815186 -273.572224)
		(width 0.0762)
		(layer "F.Cu")
		(net "M_A_CPU1_SB_CB<3>")
	)
	(arc
		(start 79.598012 -273.57197)
		(mid 79.477363 -273.547669)
		(end 79.36484 -273.497802)
		(width 0.0762)
		(layer "F.Cu")
		(net "M_A_CPU1_SB_CB<3>")
	)
	(arc
		(start 79.36484 -273.497802)
		(mid 79.177896 -273.447547)
		(end 78.990952 -273.497802)
		(width 0.0762)
		(layer "F.Cu")
		(net "M_A_CPU1_SB_CB<3>")
	)
	(arc
		(start 78.42504 -273.497802)
		(mid 78.242789 -273.447452)
		(end 78.05928 -273.492976)
		(width 0.0762)
		(layer "F.Cu")
		(net "M_A_CPU1_SB_CB<3>")
	)
	(segment
		(start 76.893674 -272.63725)
		(end 76.845668 -272.589244)
		(width 0.0762)
		(layer "F.Cu")
		(net "M_A_CPU1_SB_CB<2>")
	)
	(segment
		(start 69.222874 -272.069306)
		(end 69.0372 -272.069306)
		(width 0.10668)
		(layer "F.Cu")
		(net "M_A_CPU1_SB_CB<2>")
	)
	(segment
		(start 68.424806 -272.069306)
		(end 68.239132 -272.069306)
		(width 0.10668)
		(layer "F.Cu")
		(net "M_A_CPU1_SB_CB<2>")
	)
	(segment
		(start 68.132452 -272.175986)
		(end 68.132452 -272.482564)
		(width 0.10668)
		(layer "F.Cu")
		(net "M_A_CPU1_SB_CB<2>")
	)
	(segment
		(start 68.025772 -272.589244)
		(end 67.03441 -272.589244)
		(width 0.10668)
		(layer "F.Cu")
		(net "M_A_CPU1_SB_CB<2>")
	)
	(segment
		(start 61.113416 -278.510238)
		(end 60.725812 -278.510238)
		(width 0.10668)
		(layer "F.Cu")
		(net "M_A_CPU1_SB_CB<2>")
	)
	(segment
		(start 69.0372 -272.069306)
		(end 68.93052 -272.175986)
		(width 0.10668)
		(layer "F.Cu")
		(net "M_A_CPU1_SB_CB<2>")
	)
	(segment
		(start 68.132452 -272.482564)
		(end 68.025772 -272.589244)
		(width 0.10668)
		(layer "F.Cu")
		(net "M_A_CPU1_SB_CB<2>")
	)
	(segment
		(start 68.93052 -272.175986)
		(end 68.93052 -272.482564)
		(width 0.10668)
		(layer "F.Cu")
		(net "M_A_CPU1_SB_CB<2>")
	)
	(segment
		(start 68.638166 -272.589244)
		(end 68.531486 -272.482564)
		(width 0.10668)
		(layer "F.Cu")
		(net "M_A_CPU1_SB_CB<2>")
	)
	(segment
		(start 68.82384 -272.589244)
		(end 68.638166 -272.589244)
		(width 0.10668)
		(layer "F.Cu")
		(net "M_A_CPU1_SB_CB<2>")
	)
	(segment
		(start 69.329554 -272.175986)
		(end 69.222874 -272.069306)
		(width 0.10668)
		(layer "F.Cu")
		(net "M_A_CPU1_SB_CB<2>")
	)
	(segment
		(start 68.93052 -272.482564)
		(end 68.82384 -272.589244)
		(width 0.10668)
		(layer "F.Cu")
		(net "M_A_CPU1_SB_CB<2>")
	)
	(segment
		(start 68.531486 -272.175986)
		(end 68.424806 -272.069306)
		(width 0.10668)
		(layer "F.Cu")
		(net "M_A_CPU1_SB_CB<2>")
	)
	(segment
		(start 60.725812 -278.510238)
		(end 58.180986 -278.510238)
		(width 0.101346)
		(layer "F.Cu")
		(net "M_A_CPU1_SB_CB<2>")
	)
	(segment
		(start 77.767942 -272.63725)
		(end 76.893674 -272.63725)
		(width 0.0762)
		(layer "F.Cu")
		(net "M_A_CPU1_SB_CB<2>")
	)
	(segment
		(start 69.329554 -272.482564)
		(end 69.329554 -272.175986)
		(width 0.10668)
		(layer "F.Cu")
		(net "M_A_CPU1_SB_CB<2>")
	)
	(segment
		(start 68.239132 -272.069306)
		(end 68.132452 -272.175986)
		(width 0.10668)
		(layer "F.Cu")
		(net "M_A_CPU1_SB_CB<2>")
	)
	(segment
		(start 68.531486 -272.482564)
		(end 68.531486 -272.175986)
		(width 0.10668)
		(layer "F.Cu")
		(net "M_A_CPU1_SB_CB<2>")
	)
	(segment
		(start 75.955652 -272.589244)
		(end 69.436234 -272.589244)
		(width 0.10668)
		(layer "F.Cu")
		(net "M_A_CPU1_SB_CB<2>")
	)
	(segment
		(start 67.03441 -272.589244)
		(end 61.113416 -278.510238)
		(width 0.10668)
		(layer "F.Cu")
		(net "M_A_CPU1_SB_CB<2>")
	)
	(segment
		(start 69.436234 -272.589244)
		(end 69.329554 -272.482564)
		(width 0.10668)
		(layer "F.Cu")
		(net "M_A_CPU1_SB_CB<2>")
	)
	(segment
		(start 76.845668 -272.589244)
		(end 75.955652 -272.589244)
		(width 0.0762)
		(layer "F.Cu")
		(net "M_A_CPU1_SB_CB<2>")
	)
	(segment
		(start 57.75579 -278.935434)
		(end 55.328058 -278.935434)
		(width 0.101346)
		(layer "F.Cu")
		(net "M_A_CPU1_SB_CB<2>")
	)
	(segment
		(start 58.180986 -278.510238)
		(end 57.75579 -278.935434)
		(width 0.101346)
		(layer "F.Cu")
		(net "M_A_CPU1_SB_CB<2>")
	)
	(arc
		(start 78.180692 -272.761202)
		(mid 78.063879 -272.736526)
		(end 77.954886 -272.687796)
		(width 0.0762)
		(layer "F.Cu")
		(net "M_A_CPU1_SB_CB<2>")
	)
	(arc
		(start 78.707996 -273.010376)
		(mid 78.465679 -272.840656)
		(end 78.180692 -272.761202)
		(width 0.0762)
		(layer "F.Cu")
		(net "M_A_CPU1_SB_CB<2>")
	)
	(arc
		(start 77.954886 -272.687796)
		(mid 77.864753 -272.650176)
		(end 77.767942 -272.63725)
		(width 0.0762)
		(layer "F.Cu")
		(net "M_A_CPU1_SB_CB<2>")
	)
	(segment
		(start 63.135002 -276.970236)
		(end 63.00343 -277.101808)
		(width 0.10668)
		(layer "F.Cu")
		(net "M_A_CPU1_SB_CB<1>")
	)
	(segment
		(start 62.157102 -278.099012)
		(end 62.006226 -278.099012)
		(width 0.10668)
		(layer "F.Cu")
		(net "M_A_CPU1_SB_CB<1>")
	)
	(segment
		(start 61.808106 -278.727662)
		(end 61.65723 -278.727916)
		(width 0.10668)
		(layer "F.Cu")
		(net "M_A_CPU1_SB_CB<1>")
	)
	(segment
		(start 64.47917 -275.905976)
		(end 64.414654 -275.84146)
		(width 0.10668)
		(layer "F.Cu")
		(net "M_A_CPU1_SB_CB<1>")
	)
	(segment
		(start 61.939424 -278.445468)
		(end 61.939424 -278.596344)
		(width 0.10668)
		(layer "F.Cu")
		(net "M_A_CPU1_SB_CB<1>")
	)
	(segment
		(start 64.761364 -275.774404)
		(end 64.630046 -275.905722)
		(width 0.10668)
		(layer "F.Cu")
		(net "M_A_CPU1_SB_CB<1>")
	)
	(segment
		(start 65.260982 -274.844256)
		(end 65.261236 -274.994624)
		(width 0.10668)
		(layer "F.Cu")
		(net "M_A_CPU1_SB_CB<1>")
	)
	(segment
		(start 66.32321 -274.212558)
		(end 66.172334 -274.212812)
		(width 0.10668)
		(layer "F.Cu")
		(net "M_A_CPU1_SB_CB<1>")
	)
	(segment
		(start 64.828166 -275.277072)
		(end 64.696594 -275.408644)
		(width 0.10668)
		(layer "F.Cu")
		(net "M_A_CPU1_SB_CB<1>")
	)
	(segment
		(start 65.89014 -274.645628)
		(end 65.758822 -274.776946)
		(width 0.10668)
		(layer "F.Cu")
		(net "M_A_CPU1_SB_CB<1>")
	)
	(segment
		(start 61.243718 -279.29205)
		(end 61.092842 -279.292304)
		(width 0.10668)
		(layer "F.Cu")
		(net "M_A_CPU1_SB_CB<1>")
	)
	(segment
		(start 65.607946 -274.7772)
		(end 65.54343 -274.712684)
		(width 0.10668)
		(layer "F.Cu")
		(net "M_A_CPU1_SB_CB<1>")
	)
	(segment
		(start 63.0682 -277.467568)
		(end 62.936882 -277.598886)
		(width 0.10668)
		(layer "F.Cu")
		(net "M_A_CPU1_SB_CB<1>")
	)
	(segment
		(start 61.375036 -279.009856)
		(end 61.375036 -279.160732)
		(width 0.10668)
		(layer "F.Cu")
		(net "M_A_CPU1_SB_CB<1>")
	)
	(segment
		(start 66.954146 -273.151092)
		(end 66.9544 -273.30146)
		(width 0.10668)
		(layer "F.Cu")
		(net "M_A_CPU1_SB_CB<1>")
	)
	(segment
		(start 66.736722 -273.648424)
		(end 66.672206 -273.583908)
		(width 0.10668)
		(layer "F.Cu")
		(net "M_A_CPU1_SB_CB<1>")
	)
	(segment
		(start 66.52133 -273.583908)
		(end 66.389758 -273.71548)
		(width 0.10668)
		(layer "F.Cu")
		(net "M_A_CPU1_SB_CB<1>")
	)
	(segment
		(start 61.310266 -278.794972)
		(end 61.31052 -278.94534)
		(width 0.10668)
		(layer "F.Cu")
		(net "M_A_CPU1_SB_CB<1>")
	)
	(segment
		(start 63.003684 -277.252176)
		(end 63.0682 -277.316692)
		(width 0.10668)
		(layer "F.Cu")
		(net "M_A_CPU1_SB_CB<1>")
	)
	(segment
		(start 61.092842 -279.292304)
		(end 61.028326 -279.227788)
		(width 0.10668)
		(layer "F.Cu")
		(net "M_A_CPU1_SB_CB<1>")
	)
	(segment
		(start 65.82537 -274.279868)
		(end 65.825624 -274.430236)
		(width 0.10668)
		(layer "F.Cu")
		(net "M_A_CPU1_SB_CB<1>")
	)
	(segment
		(start 64.132206 -275.973032)
		(end 64.13246 -276.1234)
		(width 0.10668)
		(layer "F.Cu")
		(net "M_A_CPU1_SB_CB<1>")
	)
	(segment
		(start 64.414654 -275.84146)
		(end 64.263778 -275.84146)
		(width 0.10668)
		(layer "F.Cu")
		(net "M_A_CPU1_SB_CB<1>")
	)
	(segment
		(start 65.89014 -274.494752)
		(end 65.89014 -274.645628)
		(width 0.10668)
		(layer "F.Cu")
		(net "M_A_CPU1_SB_CB<1>")
	)
	(segment
		(start 62.786006 -277.59914)
		(end 62.72149 -277.534624)
		(width 0.10668)
		(layer "F.Cu")
		(net "M_A_CPU1_SB_CB<1>")
	)
	(segment
		(start 65.758822 -274.776946)
		(end 65.607946 -274.7772)
		(width 0.10668)
		(layer "F.Cu")
		(net "M_A_CPU1_SB_CB<1>")
	)
	(segment
		(start 63.0682 -277.316692)
		(end 63.0682 -277.467568)
		(width 0.10668)
		(layer "F.Cu")
		(net "M_A_CPU1_SB_CB<1>")
	)
	(segment
		(start 62.221618 -278.163528)
		(end 62.157102 -278.099012)
		(width 0.10668)
		(layer "F.Cu")
		(net "M_A_CPU1_SB_CB<1>")
	)
	(segment
		(start 66.672206 -273.583908)
		(end 66.52133 -273.583908)
		(width 0.10668)
		(layer "F.Cu")
		(net "M_A_CPU1_SB_CB<1>")
	)
	(segment
		(start 76.357226 -272.929604)
		(end 75.960986 -272.929604)
		(width 0.0762)
		(layer "F.Cu")
		(net "M_A_CPU1_SB_CB<1>")
	)
	(segment
		(start 65.261236 -274.994624)
		(end 65.325752 -275.05914)
		(width 0.10668)
		(layer "F.Cu")
		(net "M_A_CPU1_SB_CB<1>")
	)
	(segment
		(start 66.107818 -274.148296)
		(end 65.956942 -274.148296)
		(width 0.10668)
		(layer "F.Cu")
		(net "M_A_CPU1_SB_CB<1>")
	)
	(segment
		(start 62.503812 -277.88108)
		(end 62.503812 -278.031956)
		(width 0.10668)
		(layer "F.Cu")
		(net "M_A_CPU1_SB_CB<1>")
	)
	(segment
		(start 65.956942 -274.148296)
		(end 65.82537 -274.279868)
		(width 0.10668)
		(layer "F.Cu")
		(net "M_A_CPU1_SB_CB<1>")
	)
	(segment
		(start 63.69939 -276.405848)
		(end 63.567818 -276.53742)
		(width 0.10668)
		(layer "F.Cu")
		(net "M_A_CPU1_SB_CB<1>")
	)
	(segment
		(start 62.439042 -277.666196)
		(end 62.439296 -277.816564)
		(width 0.10668)
		(layer "F.Cu")
		(net "M_A_CPU1_SB_CB<1>")
	)
	(segment
		(start 64.196976 -276.187916)
		(end 64.196976 -276.338792)
		(width 0.10668)
		(layer "F.Cu")
		(net "M_A_CPU1_SB_CB<1>")
	)
	(segment
		(start 65.54343 -274.712684)
		(end 65.392554 -274.712684)
		(width 0.10668)
		(layer "F.Cu")
		(net "M_A_CPU1_SB_CB<1>")
	)
	(segment
		(start 61.441838 -278.6634)
		(end 61.310266 -278.794972)
		(width 0.10668)
		(layer "F.Cu")
		(net "M_A_CPU1_SB_CB<1>")
	)
	(segment
		(start 63.850266 -276.405848)
		(end 63.69939 -276.405848)
		(width 0.10668)
		(layer "F.Cu")
		(net "M_A_CPU1_SB_CB<1>")
	)
	(segment
		(start 64.065658 -276.47011)
		(end 63.914782 -276.470364)
		(width 0.10668)
		(layer "F.Cu")
		(net "M_A_CPU1_SB_CB<1>")
	)
	(segment
		(start 78.89494 -273.332956)
		(end 78.886558 -273.337782)
		(width 0.0762)
		(layer "F.Cu")
		(net "M_A_CPU1_SB_CB<1>")
	)
	(segment
		(start 63.568072 -276.687788)
		(end 63.632588 -276.752304)
		(width 0.10668)
		(layer "F.Cu")
		(net "M_A_CPU1_SB_CB<1>")
	)
	(segment
		(start 65.325752 -275.210016)
		(end 65.194434 -275.341334)
		(width 0.10668)
		(layer "F.Cu")
		(net "M_A_CPU1_SB_CB<1>")
	)
	(segment
		(start 63.285878 -276.970236)
		(end 63.135002 -276.970236)
		(width 0.10668)
		(layer "F.Cu")
		(net "M_A_CPU1_SB_CB<1>")
	)
	(segment
		(start 66.389758 -273.71548)
		(end 66.390012 -273.865848)
		(width 0.10668)
		(layer "F.Cu")
		(net "M_A_CPU1_SB_CB<1>")
	)
	(segment
		(start 61.028326 -279.227788)
		(end 60.87745 -279.227788)
		(width 0.10668)
		(layer "F.Cu")
		(net "M_A_CPU1_SB_CB<1>")
	)
	(segment
		(start 60.31992 -279.785318)
		(end 59.428126 -279.785318)
		(width 0.10668)
		(layer "F.Cu")
		(net "M_A_CPU1_SB_CB<1>")
	)
	(segment
		(start 62.936882 -277.598886)
		(end 62.786006 -277.59914)
		(width 0.10668)
		(layer "F.Cu")
		(net "M_A_CPU1_SB_CB<1>")
	)
	(segment
		(start 64.696594 -275.408644)
		(end 64.696848 -275.559012)
		(width 0.10668)
		(layer "F.Cu")
		(net "M_A_CPU1_SB_CB<1>")
	)
	(segment
		(start 75.960986 -272.929604)
		(end 67.175634 -272.929604)
		(width 0.10668)
		(layer "F.Cu")
		(net "M_A_CPU1_SB_CB<1>")
	)
	(segment
		(start 65.194434 -275.341334)
		(end 65.043558 -275.341588)
		(width 0.10668)
		(layer "F.Cu")
		(net "M_A_CPU1_SB_CB<1>")
	)
	(segment
		(start 63.632588 -276.752304)
		(end 63.632588 -276.90318)
		(width 0.10668)
		(layer "F.Cu")
		(net "M_A_CPU1_SB_CB<1>")
	)
	(segment
		(start 64.696848 -275.559012)
		(end 64.761364 -275.623528)
		(width 0.10668)
		(layer "F.Cu")
		(net "M_A_CPU1_SB_CB<1>")
	)
	(segment
		(start 61.375036 -279.160732)
		(end 61.243718 -279.29205)
		(width 0.10668)
		(layer "F.Cu")
		(net "M_A_CPU1_SB_CB<1>")
	)
	(segment
		(start 66.390012 -273.865848)
		(end 66.454528 -273.930364)
		(width 0.10668)
		(layer "F.Cu")
		(net "M_A_CPU1_SB_CB<1>")
	)
	(segment
		(start 65.043558 -275.341588)
		(end 64.979042 -275.277072)
		(width 0.10668)
		(layer "F.Cu")
		(net "M_A_CPU1_SB_CB<1>")
	)
	(segment
		(start 60.87745 -279.227788)
		(end 60.31992 -279.785318)
		(width 0.10668)
		(layer "F.Cu")
		(net "M_A_CPU1_SB_CB<1>")
	)
	(segment
		(start 61.939424 -278.596344)
		(end 61.808106 -278.727662)
		(width 0.10668)
		(layer "F.Cu")
		(net "M_A_CPU1_SB_CB<1>")
	)
	(segment
		(start 61.592714 -278.6634)
		(end 61.441838 -278.6634)
		(width 0.10668)
		(layer "F.Cu")
		(net "M_A_CPU1_SB_CB<1>")
	)
	(segment
		(start 62.570614 -277.534624)
		(end 62.439042 -277.666196)
		(width 0.10668)
		(layer "F.Cu")
		(net "M_A_CPU1_SB_CB<1>")
	)
	(segment
		(start 66.172334 -274.212812)
		(end 66.107818 -274.148296)
		(width 0.10668)
		(layer "F.Cu")
		(net "M_A_CPU1_SB_CB<1>")
	)
	(segment
		(start 63.350394 -277.034752)
		(end 63.285878 -276.970236)
		(width 0.10668)
		(layer "F.Cu")
		(net "M_A_CPU1_SB_CB<1>")
	)
	(segment
		(start 61.874908 -278.380952)
		(end 61.939424 -278.445468)
		(width 0.10668)
		(layer "F.Cu")
		(net "M_A_CPU1_SB_CB<1>")
	)
	(segment
		(start 65.392554 -274.712684)
		(end 65.260982 -274.844256)
		(width 0.10668)
		(layer "F.Cu")
		(net "M_A_CPU1_SB_CB<1>")
	)
	(segment
		(start 61.31052 -278.94534)
		(end 61.375036 -279.009856)
		(width 0.10668)
		(layer "F.Cu")
		(net "M_A_CPU1_SB_CB<1>")
	)
	(segment
		(start 62.006226 -278.099012)
		(end 61.874654 -278.230584)
		(width 0.10668)
		(layer "F.Cu")
		(net "M_A_CPU1_SB_CB<1>")
	)
	(segment
		(start 66.454528 -274.08124)
		(end 66.32321 -274.212558)
		(width 0.10668)
		(layer "F.Cu")
		(net "M_A_CPU1_SB_CB<1>")
	)
	(segment
		(start 63.50127 -277.034498)
		(end 63.350394 -277.034752)
		(width 0.10668)
		(layer "F.Cu")
		(net "M_A_CPU1_SB_CB<1>")
	)
	(segment
		(start 66.887598 -273.64817)
		(end 66.736722 -273.648424)
		(width 0.10668)
		(layer "F.Cu")
		(net "M_A_CPU1_SB_CB<1>")
	)
	(segment
		(start 64.630046 -275.905722)
		(end 64.47917 -275.905976)
		(width 0.10668)
		(layer "F.Cu")
		(net "M_A_CPU1_SB_CB<1>")
	)
	(segment
		(start 64.196976 -276.338792)
		(end 64.065658 -276.47011)
		(width 0.10668)
		(layer "F.Cu")
		(net "M_A_CPU1_SB_CB<1>")
	)
	(segment
		(start 63.914782 -276.470364)
		(end 63.850266 -276.405848)
		(width 0.10668)
		(layer "F.Cu")
		(net "M_A_CPU1_SB_CB<1>")
	)
	(segment
		(start 64.761364 -275.623528)
		(end 64.761364 -275.774404)
		(width 0.10668)
		(layer "F.Cu")
		(net "M_A_CPU1_SB_CB<1>")
	)
	(segment
		(start 79.647796 -273.010376)
		(end 79.748634 -273.183858)
		(width 0.0762)
		(layer "F.Cu")
		(net "M_A_CPU1_SB_CB<1>")
	)
	(segment
		(start 66.454528 -273.930364)
		(end 66.454528 -274.08124)
		(width 0.10668)
		(layer "F.Cu")
		(net "M_A_CPU1_SB_CB<1>")
	)
	(segment
		(start 61.874654 -278.230584)
		(end 61.874908 -278.380952)
		(width 0.10668)
		(layer "F.Cu")
		(net "M_A_CPU1_SB_CB<1>")
	)
	(segment
		(start 62.72149 -277.534624)
		(end 62.570614 -277.534624)
		(width 0.10668)
		(layer "F.Cu")
		(net "M_A_CPU1_SB_CB<1>")
	)
	(segment
		(start 67.018916 -273.365976)
		(end 67.018916 -273.516852)
		(width 0.10668)
		(layer "F.Cu")
		(net "M_A_CPU1_SB_CB<1>")
	)
	(segment
		(start 79.469234 -273.337782)
		(end 79.460852 -273.332956)
		(width 0.0762)
		(layer "F.Cu")
		(net "M_A_CPU1_SB_CB<1>")
	)
	(segment
		(start 63.632588 -276.90318)
		(end 63.50127 -277.034498)
		(width 0.10668)
		(layer "F.Cu")
		(net "M_A_CPU1_SB_CB<1>")
	)
	(segment
		(start 64.13246 -276.1234)
		(end 64.196976 -276.187916)
		(width 0.10668)
		(layer "F.Cu")
		(net "M_A_CPU1_SB_CB<1>")
	)
	(segment
		(start 64.979042 -275.277072)
		(end 64.828166 -275.277072)
		(width 0.10668)
		(layer "F.Cu")
		(net "M_A_CPU1_SB_CB<1>")
	)
	(segment
		(start 62.439296 -277.816564)
		(end 62.503812 -277.88108)
		(width 0.10668)
		(layer "F.Cu")
		(net "M_A_CPU1_SB_CB<1>")
	)
	(segment
		(start 65.325752 -275.05914)
		(end 65.325752 -275.210016)
		(width 0.10668)
		(layer "F.Cu")
		(net "M_A_CPU1_SB_CB<1>")
	)
	(segment
		(start 62.503812 -278.031956)
		(end 62.372494 -278.163274)
		(width 0.10668)
		(layer "F.Cu")
		(net "M_A_CPU1_SB_CB<1>")
	)
	(segment
		(start 62.372494 -278.163274)
		(end 62.221618 -278.163528)
		(width 0.10668)
		(layer "F.Cu")
		(net "M_A_CPU1_SB_CB<1>")
	)
	(segment
		(start 77.767942 -273.383502)
		(end 76.811124 -273.383502)
		(width 0.0762)
		(layer "F.Cu")
		(net "M_A_CPU1_SB_CB<1>")
	)
	(segment
		(start 67.018916 -273.516852)
		(end 66.887598 -273.64817)
		(width 0.10668)
		(layer "F.Cu")
		(net "M_A_CPU1_SB_CB<1>")
	)
	(segment
		(start 64.263778 -275.84146)
		(end 64.132206 -275.973032)
		(width 0.10668)
		(layer "F.Cu")
		(net "M_A_CPU1_SB_CB<1>")
	)
	(segment
		(start 63.567818 -276.53742)
		(end 63.568072 -276.687788)
		(width 0.10668)
		(layer "F.Cu")
		(net "M_A_CPU1_SB_CB<1>")
	)
	(segment
		(start 63.00343 -277.101808)
		(end 63.003684 -277.252176)
		(width 0.10668)
		(layer "F.Cu")
		(net "M_A_CPU1_SB_CB<1>")
	)
	(segment
		(start 76.811124 -273.383502)
		(end 76.357226 -272.929604)
		(width 0.0762)
		(layer "F.Cu")
		(net "M_A_CPU1_SB_CB<1>")
	)
	(segment
		(start 67.175634 -272.929604)
		(end 66.954146 -273.151092)
		(width 0.10668)
		(layer "F.Cu")
		(net "M_A_CPU1_SB_CB<1>")
	)
	(segment
		(start 65.825624 -274.430236)
		(end 65.89014 -274.494752)
		(width 0.10668)
		(layer "F.Cu")
		(net "M_A_CPU1_SB_CB<1>")
	)
	(segment
		(start 66.9544 -273.30146)
		(end 67.018916 -273.365976)
		(width 0.10668)
		(layer "F.Cu")
		(net "M_A_CPU1_SB_CB<1>")
	)
	(segment
		(start 61.65723 -278.727916)
		(end 61.592714 -278.6634)
		(width 0.10668)
		(layer "F.Cu")
		(net "M_A_CPU1_SB_CB<1>")
	)
	(arc
		(start 78.886558 -273.337782)
		(mid 78.70305 -273.383276)
		(end 78.520798 -273.332956)
		(width 0.0762)
		(layer "F.Cu")
		(net "M_A_CPU1_SB_CB<1>")
	)
	(arc
		(start 78.520798 -273.332956)
		(mid 78.237842 -273.256779)
		(end 77.954886 -273.332956)
		(width 0.0762)
		(layer "F.Cu")
		(net "M_A_CPU1_SB_CB<1>")
	)
	(arc
		(start 79.748634 -273.183858)
		(mid 79.732709 -273.32455)
		(end 79.602584 -273.380454)
		(width 0.0762)
		(layer "F.Cu")
		(net "M_A_CPU1_SB_CB<1>")
	)
	(arc
		(start 77.954886 -273.332956)
		(mid 77.879646 -273.366269)
		(end 77.79893 -273.382232)
		(width 0.0762)
		(layer "F.Cu")
		(net "M_A_CPU1_SB_CB<1>")
	)
	(arc
		(start 79.602584 -273.380454)
		(mid 79.533886 -273.365438)
		(end 79.469234 -273.337782)
		(width 0.0762)
		(layer "F.Cu")
		(net "M_A_CPU1_SB_CB<1>")
	)
	(arc
		(start 79.460852 -273.332956)
		(mid 79.177896 -273.256779)
		(end 78.89494 -273.332956)
		(width 0.0762)
		(layer "F.Cu")
		(net "M_A_CPU1_SB_CB<1>")
	)
	(arc
		(start 77.79893 -273.382232)
		(mid 77.783449 -273.383188)
		(end 77.767942 -273.383502)
		(width 0.0762)
		(layer "F.Cu")
		(net "M_A_CPU1_SB_CB<1>")
	)
	(segment
		(start 72.256142 -272.115026)
		(end 72.256142 -271.702276)
		(width 0.10668)
		(layer "F.Cu")
		(net "M_A_CPU1_SB_CB<0>")
	)
	(segment
		(start 71.05904 -271.702276)
		(end 71.05904 -272.115026)
		(width 0.10668)
		(layer "F.Cu")
		(net "M_A_CPU1_SB_CB<0>")
	)
	(segment
		(start 72.655176 -271.702276)
		(end 72.655176 -272.115026)
		(width 0.10668)
		(layer "F.Cu")
		(net "M_A_CPU1_SB_CB<0>")
	)
	(segment
		(start 70.553326 -271.595596)
		(end 70.367652 -271.595596)
		(width 0.10668)
		(layer "F.Cu")
		(net "M_A_CPU1_SB_CB<0>")
	)
	(segment
		(start 77.767942 -272.44675)
		(end 77.244194 -272.44675)
		(width 0.0762)
		(layer "F.Cu")
		(net "M_A_CPU1_SB_CB<0>")
	)
	(segment
		(start 72.548496 -272.221706)
		(end 72.362822 -272.221706)
		(width 0.10668)
		(layer "F.Cu")
		(net "M_A_CPU1_SB_CB<0>")
	)
	(segment
		(start 71.564754 -272.221706)
		(end 71.458074 -272.115026)
		(width 0.10668)
		(layer "F.Cu")
		(net "M_A_CPU1_SB_CB<0>")
	)
	(segment
		(start 72.761856 -271.595596)
		(end 72.655176 -271.702276)
		(width 0.10668)
		(layer "F.Cu")
		(net "M_A_CPU1_SB_CB<0>")
	)
	(segment
		(start 73.05421 -272.115026)
		(end 73.05421 -271.702276)
		(width 0.10668)
		(layer "F.Cu")
		(net "M_A_CPU1_SB_CB<0>")
	)
	(segment
		(start 61.056774 -278.085296)
		(end 59.428126 -278.085296)
		(width 0.10668)
		(layer "F.Cu")
		(net "M_A_CPU1_SB_CB<0>")
	)
	(segment
		(start 74.465434 -272.248884)
		(end 73.812146 -271.595596)
		(width 0.10668)
		(layer "F.Cu")
		(net "M_A_CPU1_SB_CB<0>")
	)
	(segment
		(start 73.812146 -271.595596)
		(end 73.559924 -271.595596)
		(width 0.10668)
		(layer "F.Cu")
		(net "M_A_CPU1_SB_CB<0>")
	)
	(segment
		(start 78.05928 -272.527776)
		(end 78.050898 -272.52295)
		(width 0.0762)
		(layer "F.Cu")
		(net "M_A_CPU1_SB_CB<0>")
	)
	(segment
		(start 73.16089 -272.221706)
		(end 73.05421 -272.115026)
		(width 0.10668)
		(layer "F.Cu")
		(net "M_A_CPU1_SB_CB<0>")
	)
	(segment
		(start 78.237842 -272.20037)
		(end 78.33614 -272.369534)
		(width 0.0762)
		(layer "F.Cu")
		(net "M_A_CPU1_SB_CB<0>")
	)
	(segment
		(start 70.766686 -272.221706)
		(end 70.660006 -272.115026)
		(width 0.10668)
		(layer "F.Cu")
		(net "M_A_CPU1_SB_CB<0>")
	)
	(segment
		(start 71.857108 -272.115026)
		(end 71.750428 -272.221706)
		(width 0.10668)
		(layer "F.Cu")
		(net "M_A_CPU1_SB_CB<0>")
	)
	(segment
		(start 70.95236 -272.221706)
		(end 70.766686 -272.221706)
		(width 0.10668)
		(layer "F.Cu")
		(net "M_A_CPU1_SB_CB<0>")
	)
	(segment
		(start 73.346564 -272.221706)
		(end 73.16089 -272.221706)
		(width 0.10668)
		(layer "F.Cu")
		(net "M_A_CPU1_SB_CB<0>")
	)
	(segment
		(start 71.16572 -271.595596)
		(end 71.05904 -271.702276)
		(width 0.10668)
		(layer "F.Cu")
		(net "M_A_CPU1_SB_CB<0>")
	)
	(segment
		(start 69.968618 -272.221706)
		(end 69.861938 -272.115026)
		(width 0.10668)
		(layer "F.Cu")
		(net "M_A_CPU1_SB_CB<0>")
	)
	(segment
		(start 71.963788 -271.595596)
		(end 71.857108 -271.702276)
		(width 0.10668)
		(layer "F.Cu")
		(net "M_A_CPU1_SB_CB<0>")
	)
	(segment
		(start 70.660006 -271.702276)
		(end 70.553326 -271.595596)
		(width 0.10668)
		(layer "F.Cu")
		(net "M_A_CPU1_SB_CB<0>")
	)
	(segment
		(start 71.458074 -271.702276)
		(end 71.351394 -271.595596)
		(width 0.10668)
		(layer "F.Cu")
		(net "M_A_CPU1_SB_CB<0>")
	)
	(segment
		(start 77.046328 -272.248884)
		(end 75.981052 -272.248884)
		(width 0.0762)
		(layer "F.Cu")
		(net "M_A_CPU1_SB_CB<0>")
	)
	(segment
		(start 75.981052 -272.248884)
		(end 74.465434 -272.248884)
		(width 0.10668)
		(layer "F.Cu")
		(net "M_A_CPU1_SB_CB<0>")
	)
	(segment
		(start 71.351394 -271.595596)
		(end 71.16572 -271.595596)
		(width 0.10668)
		(layer "F.Cu")
		(net "M_A_CPU1_SB_CB<0>")
	)
	(segment
		(start 71.857108 -271.702276)
		(end 71.857108 -272.115026)
		(width 0.10668)
		(layer "F.Cu")
		(net "M_A_CPU1_SB_CB<0>")
	)
	(segment
		(start 70.260972 -272.115026)
		(end 70.154292 -272.221706)
		(width 0.10668)
		(layer "F.Cu")
		(net "M_A_CPU1_SB_CB<0>")
	)
	(segment
		(start 70.260972 -271.702276)
		(end 70.260972 -272.115026)
		(width 0.10668)
		(layer "F.Cu")
		(net "M_A_CPU1_SB_CB<0>")
	)
	(segment
		(start 73.559924 -271.595596)
		(end 73.453244 -271.702276)
		(width 0.10668)
		(layer "F.Cu")
		(net "M_A_CPU1_SB_CB<0>")
	)
	(segment
		(start 72.256142 -271.702276)
		(end 72.149462 -271.595596)
		(width 0.10668)
		(layer "F.Cu")
		(net "M_A_CPU1_SB_CB<0>")
	)
	(segment
		(start 72.362822 -272.221706)
		(end 72.256142 -272.115026)
		(width 0.10668)
		(layer "F.Cu")
		(net "M_A_CPU1_SB_CB<0>")
	)
	(segment
		(start 72.94753 -271.595596)
		(end 72.761856 -271.595596)
		(width 0.10668)
		(layer "F.Cu")
		(net "M_A_CPU1_SB_CB<0>")
	)
	(segment
		(start 69.861938 -271.702276)
		(end 69.755258 -271.595596)
		(width 0.10668)
		(layer "F.Cu")
		(net "M_A_CPU1_SB_CB<0>")
	)
	(segment
		(start 71.750428 -272.221706)
		(end 71.564754 -272.221706)
		(width 0.10668)
		(layer "F.Cu")
		(net "M_A_CPU1_SB_CB<0>")
	)
	(segment
		(start 69.755258 -271.595596)
		(end 67.546474 -271.595596)
		(width 0.10668)
		(layer "F.Cu")
		(net "M_A_CPU1_SB_CB<0>")
	)
	(segment
		(start 69.861938 -272.115026)
		(end 69.861938 -271.702276)
		(width 0.10668)
		(layer "F.Cu")
		(net "M_A_CPU1_SB_CB<0>")
	)
	(segment
		(start 70.154292 -272.221706)
		(end 69.968618 -272.221706)
		(width 0.10668)
		(layer "F.Cu")
		(net "M_A_CPU1_SB_CB<0>")
	)
	(segment
		(start 77.244194 -272.44675)
		(end 77.046328 -272.248884)
		(width 0.0762)
		(layer "F.Cu")
		(net "M_A_CPU1_SB_CB<0>")
	)
	(segment
		(start 70.660006 -272.115026)
		(end 70.660006 -271.702276)
		(width 0.10668)
		(layer "F.Cu")
		(net "M_A_CPU1_SB_CB<0>")
	)
	(segment
		(start 67.546474 -271.595596)
		(end 61.056774 -278.085296)
		(width 0.10668)
		(layer "F.Cu")
		(net "M_A_CPU1_SB_CB<0>")
	)
	(segment
		(start 73.453244 -272.115026)
		(end 73.346564 -272.221706)
		(width 0.10668)
		(layer "F.Cu")
		(net "M_A_CPU1_SB_CB<0>")
	)
	(segment
		(start 72.149462 -271.595596)
		(end 71.963788 -271.595596)
		(width 0.10668)
		(layer "F.Cu")
		(net "M_A_CPU1_SB_CB<0>")
	)
	(segment
		(start 73.453244 -271.702276)
		(end 73.453244 -272.115026)
		(width 0.10668)
		(layer "F.Cu")
		(net "M_A_CPU1_SB_CB<0>")
	)
	(segment
		(start 70.367652 -271.595596)
		(end 70.260972 -271.702276)
		(width 0.10668)
		(layer "F.Cu")
		(net "M_A_CPU1_SB_CB<0>")
	)
	(segment
		(start 71.05904 -272.115026)
		(end 70.95236 -272.221706)
		(width 0.10668)
		(layer "F.Cu")
		(net "M_A_CPU1_SB_CB<0>")
	)
	(segment
		(start 72.655176 -272.115026)
		(end 72.548496 -272.221706)
		(width 0.10668)
		(layer "F.Cu")
		(net "M_A_CPU1_SB_CB<0>")
	)
	(segment
		(start 71.458074 -272.115026)
		(end 71.458074 -271.702276)
		(width 0.10668)
		(layer "F.Cu")
		(net "M_A_CPU1_SB_CB<0>")
	)
	(segment
		(start 73.05421 -271.702276)
		(end 72.94753 -271.595596)
		(width 0.10668)
		(layer "F.Cu")
		(net "M_A_CPU1_SB_CB<0>")
	)
	(arc
		(start 78.33614 -272.369534)
		(mid 78.327547 -272.511413)
		(end 78.198472 -272.57121)
		(width 0.0762)
		(layer "F.Cu")
		(net "M_A_CPU1_SB_CB<0>")
	)
	(arc
		(start 78.198472 -272.57121)
		(mid 78.126734 -272.556358)
		(end 78.05928 -272.527776)
		(width 0.0762)
		(layer "F.Cu")
		(net "M_A_CPU1_SB_CB<0>")
	)
	(arc
		(start 78.050898 -272.52295)
		(mid 77.914462 -272.466125)
		(end 77.767942 -272.44675)
		(width 0.0762)
		(layer "F.Cu")
		(net "M_A_CPU1_SB_CB<0>")
	)
	(segment
		(start 61.819282 -265.540998)
		(end 61.936122 -265.657838)
		(width 0.10668)
		(layer "F.Cu")
		(net "M_A_CPU1_SB_CA<6>")
	)
	(segment
		(start 63.611506 -266.056872)
		(end 61.537088 -266.056872)
		(width 0.10668)
		(layer "F.Cu")
		(net "M_A_CPU1_SB_CA<6>")
	)
	(segment
		(start 78.05928 -264.427716)
		(end 78.050898 -264.42289)
		(width 0.0762)
		(layer "F.Cu")
		(net "M_A_CPU1_SB_CA<6>")
	)
	(segment
		(start 73.399142 -264.105136)
		(end 72.742806 -264.761472)
		(width 0.10668)
		(layer "F.Cu")
		(net "M_A_CPU1_SB_CA<6>")
	)
	(segment
		(start 76.745592 -264.34669)
		(end 76.504038 -264.105136)
		(width 0.0762)
		(layer "F.Cu")
		(net "M_A_CPU1_SB_CA<6>")
	)
	(segment
		(start 61.537088 -266.056872)
		(end 61.420248 -265.940032)
		(width 0.10668)
		(layer "F.Cu")
		(net "M_A_CPU1_SB_CA<6>")
	)
	(segment
		(start 59.824366 -266.185396)
		(end 59.428126 -266.185396)
		(width 0.10668)
		(layer "F.Cu")
		(net "M_A_CPU1_SB_CA<6>")
	)
	(segment
		(start 76.156566 -264.105136)
		(end 73.399142 -264.105136)
		(width 0.10668)
		(layer "F.Cu")
		(net "M_A_CPU1_SB_CA<6>")
	)
	(segment
		(start 61.936122 -265.258804)
		(end 61.819282 -265.375644)
		(width 0.10668)
		(layer "F.Cu")
		(net "M_A_CPU1_SB_CA<6>")
	)
	(segment
		(start 61.303408 -265.258804)
		(end 60.750958 -265.258804)
		(width 0.10668)
		(layer "F.Cu")
		(net "M_A_CPU1_SB_CA<6>")
	)
	(segment
		(start 63.979552 -265.258804)
		(end 61.936122 -265.258804)
		(width 0.10668)
		(layer "F.Cu")
		(net "M_A_CPU1_SB_CA<6>")
	)
	(segment
		(start 61.420248 -265.940032)
		(end 61.420248 -265.375644)
		(width 0.10668)
		(layer "F.Cu")
		(net "M_A_CPU1_SB_CA<6>")
	)
	(segment
		(start 61.936122 -265.657838)
		(end 63.611506 -265.657838)
		(width 0.10668)
		(layer "F.Cu")
		(net "M_A_CPU1_SB_CA<6>")
	)
	(segment
		(start 61.819282 -265.375644)
		(end 61.819282 -265.540998)
		(width 0.10668)
		(layer "F.Cu")
		(net "M_A_CPU1_SB_CA<6>")
	)
	(segment
		(start 76.504038 -264.105136)
		(end 76.156566 -264.105136)
		(width 0.0762)
		(layer "F.Cu")
		(net "M_A_CPU1_SB_CA<6>")
	)
	(segment
		(start 78.237842 -264.10031)
		(end 78.33614 -264.269474)
		(width 0.0762)
		(layer "F.Cu")
		(net "M_A_CPU1_SB_CA<6>")
	)
	(segment
		(start 64.476884 -264.761472)
		(end 63.979552 -265.258804)
		(width 0.10668)
		(layer "F.Cu")
		(net "M_A_CPU1_SB_CA<6>")
	)
	(segment
		(start 61.420248 -265.375644)
		(end 61.303408 -265.258804)
		(width 0.10668)
		(layer "F.Cu")
		(net "M_A_CPU1_SB_CA<6>")
	)
	(segment
		(start 77.767942 -264.34669)
		(end 76.745592 -264.34669)
		(width 0.0762)
		(layer "F.Cu")
		(net "M_A_CPU1_SB_CA<6>")
	)
	(segment
		(start 60.750958 -265.258804)
		(end 59.824366 -266.185396)
		(width 0.10668)
		(layer "F.Cu")
		(net "M_A_CPU1_SB_CA<6>")
	)
	(segment
		(start 63.728346 -265.774678)
		(end 63.728346 -265.940032)
		(width 0.10668)
		(layer "F.Cu")
		(net "M_A_CPU1_SB_CA<6>")
	)
	(segment
		(start 63.611506 -265.657838)
		(end 63.728346 -265.774678)
		(width 0.10668)
		(layer "F.Cu")
		(net "M_A_CPU1_SB_CA<6>")
	)
	(segment
		(start 72.742806 -264.761472)
		(end 64.476884 -264.761472)
		(width 0.10668)
		(layer "F.Cu")
		(net "M_A_CPU1_SB_CA<6>")
	)
	(segment
		(start 63.728346 -265.940032)
		(end 63.611506 -266.056872)
		(width 0.10668)
		(layer "F.Cu")
		(net "M_A_CPU1_SB_CA<6>")
	)
	(arc
		(start 78.050898 -264.42289)
		(mid 77.914462 -264.366065)
		(end 77.767942 -264.34669)
		(width 0.0762)
		(layer "F.Cu")
		(net "M_A_CPU1_SB_CA<6>")
	)
	(arc
		(start 78.198472 -264.47115)
		(mid 78.126734 -264.456298)
		(end 78.05928 -264.427716)
		(width 0.0762)
		(layer "F.Cu")
		(net "M_A_CPU1_SB_CA<6>")
	)
	(arc
		(start 78.33614 -264.269474)
		(mid 78.327547 -264.411353)
		(end 78.198472 -264.47115)
		(width 0.0762)
		(layer "F.Cu")
		(net "M_A_CPU1_SB_CA<6>")
	)
	(segment
		(start 57.705498 -265.335258)
		(end 55.328058 -265.335258)
		(width 0.101346)
		(layer "F.Cu")
		(net "M_A_CPU1_SB_CA<5>")
	)
	(segment
		(start 60.67044 -264.910316)
		(end 58.13044 -264.910316)
		(width 0.101346)
		(layer "F.Cu")
		(net "M_A_CPU1_SB_CA<5>")
	)
	(segment
		(start 77.768196 -263.85393)
		(end 77.6732 -263.85393)
		(width 0.0762)
		(layer "F.Cu")
		(net "M_A_CPU1_SB_CA<5>")
	)
	(segment
		(start 76.758546 -263.927844)
		(end 76.595478 -263.764776)
		(width 0.0762)
		(layer "F.Cu")
		(net "M_A_CPU1_SB_CA<5>")
	)
	(segment
		(start 58.13044 -264.910316)
		(end 57.705498 -265.335258)
		(width 0.101346)
		(layer "F.Cu")
		(net "M_A_CPU1_SB_CA<5>")
	)
	(segment
		(start 78.05928 -263.772904)
		(end 78.050898 -263.77773)
		(width 0.0762)
		(layer "F.Cu")
		(net "M_A_CPU1_SB_CA<5>")
	)
	(segment
		(start 76.595478 -263.764776)
		(end 76.098146 -263.764776)
		(width 0.0762)
		(layer "F.Cu")
		(net "M_A_CPU1_SB_CA<5>")
	)
	(segment
		(start 73.257918 -263.764776)
		(end 72.601582 -264.421112)
		(width 0.10668)
		(layer "F.Cu")
		(net "M_A_CPU1_SB_CA<5>")
	)
	(segment
		(start 64.33566 -264.421112)
		(end 63.846456 -264.910316)
		(width 0.10668)
		(layer "F.Cu")
		(net "M_A_CPU1_SB_CA<5>")
	)
	(segment
		(start 77.599286 -263.927844)
		(end 76.758546 -263.927844)
		(width 0.0762)
		(layer "F.Cu")
		(net "M_A_CPU1_SB_CA<5>")
	)
	(segment
		(start 72.601582 -264.421112)
		(end 64.33566 -264.421112)
		(width 0.10668)
		(layer "F.Cu")
		(net "M_A_CPU1_SB_CA<5>")
	)
	(segment
		(start 76.098146 -263.764776)
		(end 73.257918 -263.764776)
		(width 0.10668)
		(layer "F.Cu")
		(net "M_A_CPU1_SB_CA<5>")
	)
	(segment
		(start 77.6732 -263.85393)
		(end 77.599286 -263.927844)
		(width 0.0762)
		(layer "F.Cu")
		(net "M_A_CPU1_SB_CA<5>")
	)
	(segment
		(start 63.846456 -264.910316)
		(end 60.67044 -264.910316)
		(width 0.10668)
		(layer "F.Cu")
		(net "M_A_CPU1_SB_CA<5>")
	)
	(arc
		(start 78.42504 -263.77773)
		(mid 78.242789 -263.72738)
		(end 78.05928 -263.772904)
		(width 0.0762)
		(layer "F.Cu")
		(net "M_A_CPU1_SB_CA<5>")
	)
	(arc
		(start 77.815186 -263.852152)
		(mid 77.791709 -263.853528)
		(end 77.768196 -263.85393)
		(width 0.0762)
		(layer "F.Cu")
		(net "M_A_CPU1_SB_CA<5>")
	)
	(arc
		(start 78.050898 -263.77773)
		(mid 77.937174 -263.828031)
		(end 77.815186 -263.852152)
		(width 0.0762)
		(layer "F.Cu")
		(net "M_A_CPU1_SB_CA<5>")
	)
	(arc
		(start 78.990952 -263.77773)
		(mid 78.707996 -263.853907)
		(end 78.42504 -263.77773)
		(width 0.0762)
		(layer "F.Cu")
		(net "M_A_CPU1_SB_CA<5>")
	)
	(arc
		(start 80.11795 -264.10031)
		(mid 79.922601 -263.916491)
		(end 79.661766 -263.85393)
		(width 0.0762)
		(layer "F.Cu")
		(net "M_A_CPU1_SB_CA<5>")
	)
	(arc
		(start 79.661766 -263.85393)
		(mid 79.508017 -263.836421)
		(end 79.36484 -263.77773)
		(width 0.0762)
		(layer "F.Cu")
		(net "M_A_CPU1_SB_CA<5>")
	)
	(arc
		(start 79.36484 -263.77773)
		(mid 79.177896 -263.727475)
		(end 78.990952 -263.77773)
		(width 0.0762)
		(layer "F.Cu")
		(net "M_A_CPU1_SB_CA<5>")
	)
	(segment
		(start 76.098146 -263.424416)
		(end 73.116694 -263.424416)
		(width 0.10668)
		(layer "F.Cu")
		(net "M_A_CPU1_SB_CA<4>")
	)
	(segment
		(start 76.676758 -263.424416)
		(end 76.098146 -263.424416)
		(width 0.0762)
		(layer "F.Cu")
		(net "M_A_CPU1_SB_CA<4>")
	)
	(segment
		(start 59.921902 -264.485374)
		(end 59.428126 -264.485374)
		(width 0.10668)
		(layer "F.Cu")
		(net "M_A_CPU1_SB_CA<4>")
	)
	(segment
		(start 76.915772 -263.66343)
		(end 76.676758 -263.424416)
		(width 0.0762)
		(layer "F.Cu")
		(net "M_A_CPU1_SB_CA<4>")
	)
	(segment
		(start 61.964824 -263.961118)
		(end 63.471806 -263.961118)
		(width 0.10668)
		(layer "F.Cu")
		(net "M_A_CPU1_SB_CA<4>")
	)
	(segment
		(start 73.116694 -263.424416)
		(end 72.460358 -264.080752)
		(width 0.10668)
		(layer "F.Cu")
		(net "M_A_CPU1_SB_CA<4>")
	)
	(segment
		(start 61.44895 -263.678924)
		(end 61.33211 -263.562084)
		(width 0.10668)
		(layer "F.Cu")
		(net "M_A_CPU1_SB_CA<4>")
	)
	(segment
		(start 60.845192 -263.562084)
		(end 59.921902 -264.485374)
		(width 0.10668)
		(layer "F.Cu")
		(net "M_A_CPU1_SB_CA<4>")
	)
	(segment
		(start 61.964824 -263.562084)
		(end 61.847984 -263.678924)
		(width 0.10668)
		(layer "F.Cu")
		(net "M_A_CPU1_SB_CA<4>")
	)
	(segment
		(start 61.847984 -263.844278)
		(end 61.964824 -263.961118)
		(width 0.10668)
		(layer "F.Cu")
		(net "M_A_CPU1_SB_CA<4>")
	)
	(segment
		(start 61.44895 -264.243312)
		(end 61.44895 -263.678924)
		(width 0.10668)
		(layer "F.Cu")
		(net "M_A_CPU1_SB_CA<4>")
	)
	(segment
		(start 77.767942 -263.66343)
		(end 76.915772 -263.66343)
		(width 0.0762)
		(layer "F.Cu")
		(net "M_A_CPU1_SB_CA<4>")
	)
	(segment
		(start 63.588646 -264.243312)
		(end 63.471806 -264.360152)
		(width 0.10668)
		(layer "F.Cu")
		(net "M_A_CPU1_SB_CA<4>")
	)
	(segment
		(start 63.471806 -264.360152)
		(end 61.56579 -264.360152)
		(width 0.10668)
		(layer "F.Cu")
		(net "M_A_CPU1_SB_CA<4>")
	)
	(segment
		(start 79.469234 -263.61771)
		(end 79.460852 -263.612884)
		(width 0.0762)
		(layer "F.Cu")
		(net "M_A_CPU1_SB_CA<4>")
	)
	(segment
		(start 78.89494 -263.612884)
		(end 78.886558 -263.61771)
		(width 0.0762)
		(layer "F.Cu")
		(net "M_A_CPU1_SB_CA<4>")
	)
	(segment
		(start 79.647796 -263.290304)
		(end 79.756254 -263.476994)
		(width 0.0762)
		(layer "F.Cu")
		(net "M_A_CPU1_SB_CA<4>")
	)
	(segment
		(start 61.847984 -263.678924)
		(end 61.847984 -263.844278)
		(width 0.10668)
		(layer "F.Cu")
		(net "M_A_CPU1_SB_CA<4>")
	)
	(segment
		(start 67.369182 -264.080752)
		(end 66.850514 -263.562084)
		(width 0.10668)
		(layer "F.Cu")
		(net "M_A_CPU1_SB_CA<4>")
	)
	(segment
		(start 63.588646 -264.077958)
		(end 63.588646 -264.243312)
		(width 0.10668)
		(layer "F.Cu")
		(net "M_A_CPU1_SB_CA<4>")
	)
	(segment
		(start 63.471806 -263.961118)
		(end 63.588646 -264.077958)
		(width 0.10668)
		(layer "F.Cu")
		(net "M_A_CPU1_SB_CA<4>")
	)
	(segment
		(start 61.56579 -264.360152)
		(end 61.44895 -264.243312)
		(width 0.10668)
		(layer "F.Cu")
		(net "M_A_CPU1_SB_CA<4>")
	)
	(segment
		(start 61.33211 -263.562084)
		(end 60.845192 -263.562084)
		(width 0.10668)
		(layer "F.Cu")
		(net "M_A_CPU1_SB_CA<4>")
	)
	(segment
		(start 66.850514 -263.562084)
		(end 61.964824 -263.562084)
		(width 0.10668)
		(layer "F.Cu")
		(net "M_A_CPU1_SB_CA<4>")
	)
	(segment
		(start 72.460358 -264.080752)
		(end 67.369182 -264.080752)
		(width 0.10668)
		(layer "F.Cu")
		(net "M_A_CPU1_SB_CA<4>")
	)
	(arc
		(start 79.460852 -263.612884)
		(mid 79.177896 -263.536707)
		(end 78.89494 -263.612884)
		(width 0.0762)
		(layer "F.Cu")
		(net "M_A_CPU1_SB_CA<4>")
	)
	(arc
		(start 78.520798 -263.612884)
		(mid 78.237842 -263.536707)
		(end 77.954886 -263.612884)
		(width 0.0762)
		(layer "F.Cu")
		(net "M_A_CPU1_SB_CA<4>")
	)
	(arc
		(start 78.886558 -263.61771)
		(mid 78.70305 -263.663204)
		(end 78.520798 -263.612884)
		(width 0.0762)
		(layer "F.Cu")
		(net "M_A_CPU1_SB_CA<4>")
	)
	(arc
		(start 77.954886 -263.612884)
		(mid 77.864753 -263.650504)
		(end 77.767942 -263.66343)
		(width 0.0762)
		(layer "F.Cu")
		(net "M_A_CPU1_SB_CA<4>")
	)
	(arc
		(start 79.604616 -263.660636)
		(mid 79.534862 -263.645679)
		(end 79.469234 -263.61771)
		(width 0.0762)
		(layer "F.Cu")
		(net "M_A_CPU1_SB_CA<4>")
	)
	(arc
		(start 79.756254 -263.476994)
		(mid 79.730337 -263.610036)
		(end 79.604616 -263.660636)
		(width 0.0762)
		(layer "F.Cu")
		(net "M_A_CPU1_SB_CA<4>")
	)
	(segment
		(start 60.67044 -263.210294)
		(end 58.13044 -263.210294)
		(width 0.101346)
		(layer "F.Cu")
		(net "M_A_CPU1_SB_CA<3>")
	)
	(segment
		(start 76.783692 -262.917178)
		(end 76.616814 -263.084056)
		(width 0.0762)
		(layer "F.Cu")
		(net "M_A_CPU1_SB_CA<3>")
	)
	(segment
		(start 77.767942 -262.917178)
		(end 76.783692 -262.917178)
		(width 0.0762)
		(layer "F.Cu")
		(net "M_A_CPU1_SB_CA<3>")
	)
	(segment
		(start 76.616814 -263.084056)
		(end 76.098146 -263.084056)
		(width 0.0762)
		(layer "F.Cu")
		(net "M_A_CPU1_SB_CA<3>")
	)
	(segment
		(start 58.13044 -263.210294)
		(end 57.705498 -263.635236)
		(width 0.101346)
		(layer "F.Cu")
		(net "M_A_CPU1_SB_CA<3>")
	)
	(segment
		(start 76.098146 -263.084056)
		(end 72.97547 -263.084056)
		(width 0.10668)
		(layer "F.Cu")
		(net "M_A_CPU1_SB_CA<3>")
	)
	(segment
		(start 72.319134 -263.740392)
		(end 67.510406 -263.740392)
		(width 0.10668)
		(layer "F.Cu")
		(net "M_A_CPU1_SB_CA<3>")
	)
	(segment
		(start 72.97547 -263.084056)
		(end 72.319134 -263.740392)
		(width 0.10668)
		(layer "F.Cu")
		(net "M_A_CPU1_SB_CA<3>")
	)
	(segment
		(start 57.705498 -263.635236)
		(end 55.328058 -263.635236)
		(width 0.101346)
		(layer "F.Cu")
		(net "M_A_CPU1_SB_CA<3>")
	)
	(segment
		(start 67.510406 -263.740392)
		(end 66.980308 -263.210294)
		(width 0.10668)
		(layer "F.Cu")
		(net "M_A_CPU1_SB_CA<3>")
	)
	(segment
		(start 66.980308 -263.210294)
		(end 60.67044 -263.210294)
		(width 0.10668)
		(layer "F.Cu")
		(net "M_A_CPU1_SB_CA<3>")
	)
	(arc
		(start 78.180692 -263.04113)
		(mid 78.063879 -263.016454)
		(end 77.954886 -262.967724)
		(width 0.0762)
		(layer "F.Cu")
		(net "M_A_CPU1_SB_CA<3>")
	)
	(arc
		(start 77.954886 -262.967724)
		(mid 77.864753 -262.930104)
		(end 77.767942 -262.917178)
		(width 0.0762)
		(layer "F.Cu")
		(net "M_A_CPU1_SB_CA<3>")
	)
	(arc
		(start 78.707996 -263.290304)
		(mid 78.465679 -263.120584)
		(end 78.180692 -263.04113)
		(width 0.0762)
		(layer "F.Cu")
		(net "M_A_CPU1_SB_CA<3>")
	)
	(segment
		(start 72.853804 -262.724138)
		(end 72.17791 -263.400032)
		(width 0.10668)
		(layer "F.Cu")
		(net "M_A_CPU1_SB_CA<2>")
	)
	(segment
		(start 78.237842 -262.480298)
		(end 78.33614 -262.649462)
		(width 0.0762)
		(layer "F.Cu")
		(net "M_A_CPU1_SB_CA<2>")
	)
	(segment
		(start 61.084206 -262.150098)
		(end 60.954412 -262.020304)
		(width 0.10668)
		(layer "F.Cu")
		(net "M_A_CPU1_SB_CA<2>")
	)
	(segment
		(start 60.670186 -262.020304)
		(end 59.905138 -262.785352)
		(width 0.10668)
		(layer "F.Cu")
		(net "M_A_CPU1_SB_CA<2>")
	)
	(segment
		(start 60.954412 -262.020304)
		(end 60.670186 -262.020304)
		(width 0.10668)
		(layer "F.Cu")
		(net "M_A_CPU1_SB_CA<2>")
	)
	(segment
		(start 67.65163 -263.400032)
		(end 66.127122 -261.875524)
		(width 0.10668)
		(layer "F.Cu")
		(net "M_A_CPU1_SB_CA<2>")
	)
	(segment
		(start 61.25337 -262.673592)
		(end 61.084206 -262.504428)
		(width 0.10668)
		(layer "F.Cu")
		(net "M_A_CPU1_SB_CA<2>")
	)
	(segment
		(start 78.05928 -262.807704)
		(end 78.050898 -262.802878)
		(width 0.0762)
		(layer "F.Cu")
		(net "M_A_CPU1_SB_CA<2>")
	)
	(segment
		(start 59.905138 -262.785352)
		(end 59.428126 -262.785352)
		(width 0.10668)
		(layer "F.Cu")
		(net "M_A_CPU1_SB_CA<2>")
	)
	(segment
		(start 77.362304 -262.726678)
		(end 77.359764 -262.724138)
		(width 0.0762)
		(layer "F.Cu")
		(net "M_A_CPU1_SB_CA<2>")
	)
	(segment
		(start 63.354966 -262.274558)
		(end 63.471806 -262.391398)
		(width 0.10668)
		(layer "F.Cu")
		(net "M_A_CPU1_SB_CA<2>")
	)
	(segment
		(start 77.359764 -262.724138)
		(end 76.098146 -262.724138)
		(width 0.0762)
		(layer "F.Cu")
		(net "M_A_CPU1_SB_CA<2>")
	)
	(segment
		(start 63.471806 -262.556752)
		(end 63.354966 -262.673592)
		(width 0.10668)
		(layer "F.Cu")
		(net "M_A_CPU1_SB_CA<2>")
	)
	(segment
		(start 63.471806 -262.391398)
		(end 63.471806 -262.556752)
		(width 0.10668)
		(layer "F.Cu")
		(net "M_A_CPU1_SB_CA<2>")
	)
	(segment
		(start 66.127122 -261.875524)
		(end 61.652404 -261.875524)
		(width 0.10668)
		(layer "F.Cu")
		(net "M_A_CPU1_SB_CA<2>")
	)
	(segment
		(start 76.098146 -262.724138)
		(end 72.853804 -262.724138)
		(width 0.10668)
		(layer "F.Cu")
		(net "M_A_CPU1_SB_CA<2>")
	)
	(segment
		(start 61.652404 -262.274558)
		(end 63.354966 -262.274558)
		(width 0.10668)
		(layer "F.Cu")
		(net "M_A_CPU1_SB_CA<2>")
	)
	(segment
		(start 61.652404 -261.875524)
		(end 61.535564 -261.992364)
		(width 0.10668)
		(layer "F.Cu")
		(net "M_A_CPU1_SB_CA<2>")
	)
	(segment
		(start 63.354966 -262.673592)
		(end 61.25337 -262.673592)
		(width 0.10668)
		(layer "F.Cu")
		(net "M_A_CPU1_SB_CA<2>")
	)
	(segment
		(start 61.084206 -262.504428)
		(end 61.084206 -262.150098)
		(width 0.10668)
		(layer "F.Cu")
		(net "M_A_CPU1_SB_CA<2>")
	)
	(segment
		(start 61.535564 -261.992364)
		(end 61.535564 -262.157718)
		(width 0.10668)
		(layer "F.Cu")
		(net "M_A_CPU1_SB_CA<2>")
	)
	(segment
		(start 61.535564 -262.157718)
		(end 61.652404 -262.274558)
		(width 0.10668)
		(layer "F.Cu")
		(net "M_A_CPU1_SB_CA<2>")
	)
	(segment
		(start 72.17791 -263.400032)
		(end 67.65163 -263.400032)
		(width 0.10668)
		(layer "F.Cu")
		(net "M_A_CPU1_SB_CA<2>")
	)
	(segment
		(start 77.767942 -262.726678)
		(end 77.362304 -262.726678)
		(width 0.0762)
		(layer "F.Cu")
		(net "M_A_CPU1_SB_CA<2>")
	)
	(arc
		(start 78.33614 -262.649462)
		(mid 78.327547 -262.791341)
		(end 78.198472 -262.851138)
		(width 0.0762)
		(layer "F.Cu")
		(net "M_A_CPU1_SB_CA<2>")
	)
	(arc
		(start 78.198472 -262.851138)
		(mid 78.126734 -262.836286)
		(end 78.05928 -262.807704)
		(width 0.0762)
		(layer "F.Cu")
		(net "M_A_CPU1_SB_CA<2>")
	)
	(arc
		(start 78.050898 -262.802878)
		(mid 77.914462 -262.746053)
		(end 77.767942 -262.726678)
		(width 0.0762)
		(layer "F.Cu")
		(net "M_A_CPU1_SB_CA<2>")
	)
	(segment
		(start 72.71258 -262.383778)
		(end 72.036686 -263.059672)
		(width 0.10668)
		(layer "F.Cu")
		(net "M_A_CPU1_SB_CA<1>")
	)
	(segment
		(start 77.770482 -262.233918)
		(end 76.547472 -262.233918)
		(width 0.0762)
		(layer "F.Cu")
		(net "M_A_CPU1_SB_CA<1>")
	)
	(segment
		(start 66.253106 -261.510272)
		(end 60.67044 -261.510272)
		(width 0.10668)
		(layer "F.Cu")
		(net "M_A_CPU1_SB_CA<1>")
	)
	(segment
		(start 78.05928 -262.152892)
		(end 78.050898 -262.157718)
		(width 0.0762)
		(layer "F.Cu")
		(net "M_A_CPU1_SB_CA<1>")
	)
	(segment
		(start 76.397612 -262.383778)
		(end 76.098146 -262.383778)
		(width 0.0762)
		(layer "F.Cu")
		(net "M_A_CPU1_SB_CA<1>")
	)
	(segment
		(start 58.13044 -261.510272)
		(end 57.705498 -261.935214)
		(width 0.101346)
		(layer "F.Cu")
		(net "M_A_CPU1_SB_CA<1>")
	)
	(segment
		(start 57.705498 -261.935214)
		(end 55.328058 -261.935214)
		(width 0.101346)
		(layer "F.Cu")
		(net "M_A_CPU1_SB_CA<1>")
	)
	(segment
		(start 76.098146 -262.383778)
		(end 72.71258 -262.383778)
		(width 0.10668)
		(layer "F.Cu")
		(net "M_A_CPU1_SB_CA<1>")
	)
	(segment
		(start 60.67044 -261.510272)
		(end 58.13044 -261.510272)
		(width 0.101346)
		(layer "F.Cu")
		(net "M_A_CPU1_SB_CA<1>")
	)
	(segment
		(start 72.036686 -263.059672)
		(end 67.802506 -263.059672)
		(width 0.10668)
		(layer "F.Cu")
		(net "M_A_CPU1_SB_CA<1>")
	)
	(segment
		(start 67.802506 -263.059672)
		(end 66.253106 -261.510272)
		(width 0.10668)
		(layer "F.Cu")
		(net "M_A_CPU1_SB_CA<1>")
	)
	(segment
		(start 76.547472 -262.233918)
		(end 76.397612 -262.383778)
		(width 0.0762)
		(layer "F.Cu")
		(net "M_A_CPU1_SB_CA<1>")
	)
	(arc
		(start 78.990952 -262.157718)
		(mid 78.707996 -262.233895)
		(end 78.42504 -262.157718)
		(width 0.0762)
		(layer "F.Cu")
		(net "M_A_CPU1_SB_CA<1>")
	)
	(arc
		(start 78.050898 -262.157718)
		(mid 77.937174 -262.208019)
		(end 77.815186 -262.23214)
		(width 0.0762)
		(layer "F.Cu")
		(net "M_A_CPU1_SB_CA<1>")
	)
	(arc
		(start 80.11795 -262.480298)
		(mid 79.922601 -262.296479)
		(end 79.661766 -262.233918)
		(width 0.0762)
		(layer "F.Cu")
		(net "M_A_CPU1_SB_CA<1>")
	)
	(arc
		(start 79.36484 -262.157718)
		(mid 79.177896 -262.107463)
		(end 78.990952 -262.157718)
		(width 0.0762)
		(layer "F.Cu")
		(net "M_A_CPU1_SB_CA<1>")
	)
	(arc
		(start 79.661766 -262.233918)
		(mid 79.508017 -262.216409)
		(end 79.36484 -262.157718)
		(width 0.0762)
		(layer "F.Cu")
		(net "M_A_CPU1_SB_CA<1>")
	)
	(arc
		(start 77.815186 -262.23214)
		(mid 77.792852 -262.233475)
		(end 77.770482 -262.233918)
		(width 0.0762)
		(layer "F.Cu")
		(net "M_A_CPU1_SB_CA<1>")
	)
	(arc
		(start 78.42504 -262.157718)
		(mid 78.242789 -262.107368)
		(end 78.05928 -262.152892)
		(width 0.0762)
		(layer "F.Cu")
		(net "M_A_CPU1_SB_CA<1>")
	)
	(segment
		(start 77.767942 -262.043418)
		(end 76.098146 -262.043418)
		(width 0.0762)
		(layer "F.Cu")
		(net "M_A_CPU1_SB_CA<0>")
	)
	(segment
		(start 79.469234 -261.997698)
		(end 79.460852 -261.992872)
		(width 0.0762)
		(layer "F.Cu")
		(net "M_A_CPU1_SB_CA<0>")
	)
	(segment
		(start 76.098146 -262.043418)
		(end 72.571356 -262.043418)
		(width 0.10668)
		(layer "F.Cu")
		(net "M_A_CPU1_SB_CA<0>")
	)
	(segment
		(start 63.947548 -261.08533)
		(end 63.761874 -261.08533)
		(width 0.10668)
		(layer "F.Cu")
		(net "M_A_CPU1_SB_CA<0>")
	)
	(segment
		(start 64.958976 -260.646926)
		(end 64.852296 -260.753606)
		(width 0.10668)
		(layer "F.Cu")
		(net "M_A_CPU1_SB_CA<0>")
	)
	(segment
		(start 64.054228 -260.97865)
		(end 63.947548 -261.08533)
		(width 0.10668)
		(layer "F.Cu")
		(net "M_A_CPU1_SB_CA<0>")
	)
	(segment
		(start 79.647796 -261.670292)
		(end 79.756254 -261.856982)
		(width 0.0762)
		(layer "F.Cu")
		(net "M_A_CPU1_SB_CA<0>")
	)
	(segment
		(start 65.14465 -260.646926)
		(end 64.958976 -260.646926)
		(width 0.10668)
		(layer "F.Cu")
		(net "M_A_CPU1_SB_CA<0>")
	)
	(segment
		(start 63.548514 -260.646926)
		(end 63.36284 -260.646926)
		(width 0.10668)
		(layer "F.Cu")
		(net "M_A_CPU1_SB_CA<0>")
	)
	(segment
		(start 63.761874 -261.08533)
		(end 63.655194 -260.97865)
		(width 0.10668)
		(layer "F.Cu")
		(net "M_A_CPU1_SB_CA<0>")
	)
	(segment
		(start 64.054228 -260.753606)
		(end 64.054228 -260.97865)
		(width 0.10668)
		(layer "F.Cu")
		(net "M_A_CPU1_SB_CA<0>")
	)
	(segment
		(start 65.25133 -260.97865)
		(end 65.25133 -260.753606)
		(width 0.10668)
		(layer "F.Cu")
		(net "M_A_CPU1_SB_CA<0>")
	)
	(segment
		(start 63.655194 -260.97865)
		(end 63.655194 -260.753606)
		(width 0.10668)
		(layer "F.Cu")
		(net "M_A_CPU1_SB_CA<0>")
	)
	(segment
		(start 62.750446 -260.646926)
		(end 62.564772 -260.646926)
		(width 0.10668)
		(layer "F.Cu")
		(net "M_A_CPU1_SB_CA<0>")
	)
	(segment
		(start 64.160908 -260.646926)
		(end 64.054228 -260.753606)
		(width 0.10668)
		(layer "F.Cu")
		(net "M_A_CPU1_SB_CA<0>")
	)
	(segment
		(start 71.895462 -262.719312)
		(end 67.94373 -262.719312)
		(width 0.10668)
		(layer "F.Cu")
		(net "M_A_CPU1_SB_CA<0>")
	)
	(segment
		(start 72.571356 -262.043418)
		(end 71.895462 -262.719312)
		(width 0.10668)
		(layer "F.Cu")
		(net "M_A_CPU1_SB_CA<0>")
	)
	(segment
		(start 64.852296 -260.753606)
		(end 64.852296 -260.97865)
		(width 0.10668)
		(layer "F.Cu")
		(net "M_A_CPU1_SB_CA<0>")
	)
	(segment
		(start 62.857126 -260.97865)
		(end 62.857126 -260.753606)
		(width 0.10668)
		(layer "F.Cu")
		(net "M_A_CPU1_SB_CA<0>")
	)
	(segment
		(start 63.655194 -260.753606)
		(end 63.548514 -260.646926)
		(width 0.10668)
		(layer "F.Cu")
		(net "M_A_CPU1_SB_CA<0>")
	)
	(segment
		(start 62.963806 -261.08533)
		(end 62.857126 -260.97865)
		(width 0.10668)
		(layer "F.Cu")
		(net "M_A_CPU1_SB_CA<0>")
	)
	(segment
		(start 62.857126 -260.753606)
		(end 62.750446 -260.646926)
		(width 0.10668)
		(layer "F.Cu")
		(net "M_A_CPU1_SB_CA<0>")
	)
	(segment
		(start 67.94373 -262.719312)
		(end 66.309748 -261.08533)
		(width 0.10668)
		(layer "F.Cu")
		(net "M_A_CPU1_SB_CA<0>")
	)
	(segment
		(start 66.309748 -261.08533)
		(end 65.35801 -261.08533)
		(width 0.10668)
		(layer "F.Cu")
		(net "M_A_CPU1_SB_CA<0>")
	)
	(segment
		(start 64.745616 -261.08533)
		(end 64.559942 -261.08533)
		(width 0.10668)
		(layer "F.Cu")
		(net "M_A_CPU1_SB_CA<0>")
	)
	(segment
		(start 62.564772 -260.646926)
		(end 62.458092 -260.753606)
		(width 0.10668)
		(layer "F.Cu")
		(net "M_A_CPU1_SB_CA<0>")
	)
	(segment
		(start 65.35801 -261.08533)
		(end 65.25133 -260.97865)
		(width 0.10668)
		(layer "F.Cu")
		(net "M_A_CPU1_SB_CA<0>")
	)
	(segment
		(start 64.852296 -260.97865)
		(end 64.745616 -261.08533)
		(width 0.10668)
		(layer "F.Cu")
		(net "M_A_CPU1_SB_CA<0>")
	)
	(segment
		(start 64.346582 -260.646926)
		(end 64.160908 -260.646926)
		(width 0.10668)
		(layer "F.Cu")
		(net "M_A_CPU1_SB_CA<0>")
	)
	(segment
		(start 62.458092 -260.97865)
		(end 62.351412 -261.08533)
		(width 0.10668)
		(layer "F.Cu")
		(net "M_A_CPU1_SB_CA<0>")
	)
	(segment
		(start 63.25616 -260.97865)
		(end 63.14948 -261.08533)
		(width 0.10668)
		(layer "F.Cu")
		(net "M_A_CPU1_SB_CA<0>")
	)
	(segment
		(start 63.14948 -261.08533)
		(end 62.963806 -261.08533)
		(width 0.10668)
		(layer "F.Cu")
		(net "M_A_CPU1_SB_CA<0>")
	)
	(segment
		(start 64.453262 -260.753606)
		(end 64.346582 -260.646926)
		(width 0.10668)
		(layer "F.Cu")
		(net "M_A_CPU1_SB_CA<0>")
	)
	(segment
		(start 63.36284 -260.646926)
		(end 63.25616 -260.753606)
		(width 0.10668)
		(layer "F.Cu")
		(net "M_A_CPU1_SB_CA<0>")
	)
	(segment
		(start 64.453262 -260.97865)
		(end 64.453262 -260.753606)
		(width 0.10668)
		(layer "F.Cu")
		(net "M_A_CPU1_SB_CA<0>")
	)
	(segment
		(start 78.89494 -261.992872)
		(end 78.886558 -261.997698)
		(width 0.0762)
		(layer "F.Cu")
		(net "M_A_CPU1_SB_CA<0>")
	)
	(segment
		(start 63.25616 -260.753606)
		(end 63.25616 -260.97865)
		(width 0.10668)
		(layer "F.Cu")
		(net "M_A_CPU1_SB_CA<0>")
	)
	(segment
		(start 62.458092 -260.753606)
		(end 62.458092 -260.97865)
		(width 0.10668)
		(layer "F.Cu")
		(net "M_A_CPU1_SB_CA<0>")
	)
	(segment
		(start 65.25133 -260.753606)
		(end 65.14465 -260.646926)
		(width 0.10668)
		(layer "F.Cu")
		(net "M_A_CPU1_SB_CA<0>")
	)
	(segment
		(start 64.559942 -261.08533)
		(end 64.453262 -260.97865)
		(width 0.10668)
		(layer "F.Cu")
		(net "M_A_CPU1_SB_CA<0>")
	)
	(segment
		(start 62.351412 -261.08533)
		(end 59.428126 -261.08533)
		(width 0.10668)
		(layer "F.Cu")
		(net "M_A_CPU1_SB_CA<0>")
	)
	(arc
		(start 79.756254 -261.856982)
		(mid 79.730337 -261.990024)
		(end 79.604616 -262.040624)
		(width 0.0762)
		(layer "F.Cu")
		(net "M_A_CPU1_SB_CA<0>")
	)
	(arc
		(start 77.954886 -261.992872)
		(mid 77.864753 -262.030492)
		(end 77.767942 -262.043418)
		(width 0.0762)
		(layer "F.Cu")
		(net "M_A_CPU1_SB_CA<0>")
	)
	(arc
		(start 79.604616 -262.040624)
		(mid 79.534862 -262.025667)
		(end 79.469234 -261.997698)
		(width 0.0762)
		(layer "F.Cu")
		(net "M_A_CPU1_SB_CA<0>")
	)
	(arc
		(start 79.460852 -261.992872)
		(mid 79.177896 -261.916695)
		(end 78.89494 -261.992872)
		(width 0.0762)
		(layer "F.Cu")
		(net "M_A_CPU1_SB_CA<0>")
	)
	(arc
		(start 78.520798 -261.992872)
		(mid 78.237842 -261.916695)
		(end 77.954886 -261.992872)
		(width 0.0762)
		(layer "F.Cu")
		(net "M_A_CPU1_SB_CA<0>")
	)
	(arc
		(start 78.886558 -261.997698)
		(mid 78.70305 -262.043192)
		(end 78.520798 -261.992872)
		(width 0.0762)
		(layer "F.Cu")
		(net "M_A_CPU1_SB_CA<0>")
	)
	(segment
		(start 61.330332 -268.066012)
		(end 61.19876 -268.197584)
		(width 0.10668)
		(layer "F.Cu")
		(net "M_A_CPU1_SA_RSP<0>")
	)
	(segment
		(start 63.664592 -267.977366)
		(end 63.15329 -267.977366)
		(width 0.10668)
		(layer "F.Cu")
		(net "M_A_CPU1_SA_RSP<0>")
	)
	(segment
		(start 63.04661 -268.084046)
		(end 63.04661 -268.305026)
		(width 0.10668)
		(layer "F.Cu")
		(net "M_A_CPU1_SA_RSP<0>")
	)
	(segment
		(start 79.469234 -266.857734)
		(end 79.460852 -266.852908)
		(width 0.0762)
		(layer "F.Cu")
		(net "M_A_CPU1_SA_RSP<0>")
	)
	(segment
		(start 77.767942 -266.903454)
		(end 76.933806 -266.903454)
		(width 0.0762)
		(layer "F.Cu")
		(net "M_A_CPU1_SA_RSP<0>")
	)
	(segment
		(start 76.933806 -266.903454)
		(end 76.731876 -266.701524)
		(width 0.0762)
		(layer "F.Cu")
		(net "M_A_CPU1_SA_RSP<0>")
	)
	(segment
		(start 61.19876 -268.197584)
		(end 61.199014 -268.347952)
		(width 0.10668)
		(layer "F.Cu")
		(net "M_A_CPU1_SA_RSP<0>")
	)
	(segment
		(start 62.540896 -267.977366)
		(end 62.335156 -267.977366)
		(width 0.10668)
		(layer "F.Cu")
		(net "M_A_CPU1_SA_RSP<0>")
	)
	(segment
		(start 61.481208 -268.066012)
		(end 61.330332 -268.066012)
		(width 0.10668)
		(layer "F.Cu")
		(net "M_A_CPU1_SA_RSP<0>")
	)
	(segment
		(start 63.15329 -267.977366)
		(end 63.04661 -268.084046)
		(width 0.10668)
		(layer "F.Cu")
		(net "M_A_CPU1_SA_RSP<0>")
	)
	(segment
		(start 75.961494 -266.701524)
		(end 75.440032 -266.180062)
		(width 0.10668)
		(layer "F.Cu")
		(net "M_A_CPU1_SA_RSP<0>")
	)
	(segment
		(start 60.727082 -269.58544)
		(end 59.428126 -269.58544)
		(width 0.10668)
		(layer "F.Cu")
		(net "M_A_CPU1_SA_RSP<0>")
	)
	(segment
		(start 62.647576 -268.305026)
		(end 62.647576 -268.084046)
		(width 0.10668)
		(layer "F.Cu")
		(net "M_A_CPU1_SA_RSP<0>")
	)
	(segment
		(start 65.461896 -266.180062)
		(end 63.664592 -267.977366)
		(width 0.10668)
		(layer "F.Cu")
		(net "M_A_CPU1_SA_RSP<0>")
	)
	(segment
		(start 79.647796 -266.530328)
		(end 79.756254 -266.717018)
		(width 0.0762)
		(layer "F.Cu")
		(net "M_A_CPU1_SA_RSP<0>")
	)
	(segment
		(start 61.939424 -268.373098)
		(end 61.788548 -268.373352)
		(width 0.10668)
		(layer "F.Cu")
		(net "M_A_CPU1_SA_RSP<0>")
	)
	(segment
		(start 62.754256 -268.411706)
		(end 62.647576 -268.305026)
		(width 0.10668)
		(layer "F.Cu")
		(net "M_A_CPU1_SA_RSP<0>")
	)
	(segment
		(start 61.199014 -268.347952)
		(end 61.506354 -268.655292)
		(width 0.10668)
		(layer "F.Cu")
		(net "M_A_CPU1_SA_RSP<0>")
	)
	(segment
		(start 61.788548 -268.373352)
		(end 61.481208 -268.066012)
		(width 0.10668)
		(layer "F.Cu")
		(net "M_A_CPU1_SA_RSP<0>")
	)
	(segment
		(start 61.506354 -268.806168)
		(end 60.727082 -269.58544)
		(width 0.10668)
		(layer "F.Cu")
		(net "M_A_CPU1_SA_RSP<0>")
	)
	(segment
		(start 62.647576 -268.084046)
		(end 62.540896 -267.977366)
		(width 0.10668)
		(layer "F.Cu")
		(net "M_A_CPU1_SA_RSP<0>")
	)
	(segment
		(start 63.04661 -268.305026)
		(end 62.93993 -268.411706)
		(width 0.10668)
		(layer "F.Cu")
		(net "M_A_CPU1_SA_RSP<0>")
	)
	(segment
		(start 61.506354 -268.655292)
		(end 61.506354 -268.806168)
		(width 0.10668)
		(layer "F.Cu")
		(net "M_A_CPU1_SA_RSP<0>")
	)
	(segment
		(start 76.731876 -266.701524)
		(end 75.961494 -266.701524)
		(width 0.10668)
		(layer "F.Cu")
		(net "M_A_CPU1_SA_RSP<0>")
	)
	(segment
		(start 78.89494 -266.852908)
		(end 78.886558 -266.857734)
		(width 0.0762)
		(layer "F.Cu")
		(net "M_A_CPU1_SA_RSP<0>")
	)
	(segment
		(start 75.440032 -266.180062)
		(end 65.461896 -266.180062)
		(width 0.10668)
		(layer "F.Cu")
		(net "M_A_CPU1_SA_RSP<0>")
	)
	(segment
		(start 62.335156 -267.977366)
		(end 61.939424 -268.373098)
		(width 0.10668)
		(layer "F.Cu")
		(net "M_A_CPU1_SA_RSP<0>")
	)
	(segment
		(start 62.93993 -268.411706)
		(end 62.754256 -268.411706)
		(width 0.10668)
		(layer "F.Cu")
		(net "M_A_CPU1_SA_RSP<0>")
	)
	(arc
		(start 78.520798 -266.852908)
		(mid 78.237842 -266.776731)
		(end 77.954886 -266.852908)
		(width 0.0762)
		(layer "F.Cu")
		(net "M_A_CPU1_SA_RSP<0>")
	)
	(arc
		(start 79.604616 -266.90066)
		(mid 79.534862 -266.885703)
		(end 79.469234 -266.857734)
		(width 0.0762)
		(layer "F.Cu")
		(net "M_A_CPU1_SA_RSP<0>")
	)
	(arc
		(start 77.954886 -266.852908)
		(mid 77.864753 -266.890528)
		(end 77.767942 -266.903454)
		(width 0.0762)
		(layer "F.Cu")
		(net "M_A_CPU1_SA_RSP<0>")
	)
	(arc
		(start 79.756254 -266.717018)
		(mid 79.730337 -266.85006)
		(end 79.604616 -266.90066)
		(width 0.0762)
		(layer "F.Cu")
		(net "M_A_CPU1_SA_RSP<0>")
	)
	(arc
		(start 78.886558 -266.857734)
		(mid 78.70305 -266.903228)
		(end 78.520798 -266.852908)
		(width 0.0762)
		(layer "F.Cu")
		(net "M_A_CPU1_SA_RSP<0>")
	)
	(arc
		(start 79.460852 -266.852908)
		(mid 79.177896 -266.776731)
		(end 78.89494 -266.852908)
		(width 0.0762)
		(layer "F.Cu")
		(net "M_A_CPU1_SA_RSP<0>")
	)
	(segment
		(start 76.457302 -256.228088)
		(end 75.939142 -256.746248)
		(width 0.10668)
		(layer "F.Cu")
		(net "M_A_CPU1_SA_PAR")
	)
	(segment
		(start 66.657982 -255.456944)
		(end 62.665102 -255.456944)
		(width 0.10668)
		(layer "F.Cu")
		(net "M_A_CPU1_SA_PAR")
	)
	(segment
		(start 79.347822 -256.090166)
		(end 79.452978 -255.909318)
		(width 0.0762)
		(layer "F.Cu")
		(net "M_A_CPU1_SA_PAR")
	)
	(segment
		(start 75.832462 -257.040126)
		(end 75.646788 -257.040126)
		(width 0.10668)
		(layer "F.Cu")
		(net "M_A_CPU1_SA_PAR")
	)
	(segment
		(start 61.4934 -254.285242)
		(end 59.428126 -254.285242)
		(width 0.10668)
		(layer "F.Cu")
		(net "M_A_CPU1_SA_PAR")
	)
	(segment
		(start 75.141074 -256.746248)
		(end 75.141074 -256.933446)
		(width 0.10668)
		(layer "F.Cu")
		(net "M_A_CPU1_SA_PAR")
	)
	(segment
		(start 67.8942 -254.220726)
		(end 66.657982 -255.456944)
		(width 0.10668)
		(layer "F.Cu")
		(net "M_A_CPU1_SA_PAR")
	)
	(segment
		(start 74.74204 -256.746248)
		(end 74.63536 -256.639568)
		(width 0.10668)
		(layer "F.Cu")
		(net "M_A_CPU1_SA_PAR")
	)
	(segment
		(start 75.540108 -256.746248)
		(end 75.433428 -256.639568)
		(width 0.10668)
		(layer "F.Cu")
		(net "M_A_CPU1_SA_PAR")
	)
	(segment
		(start 79.168244 -255.763522)
		(end 79.160878 -255.76784)
		(width 0.0762)
		(layer "F.Cu")
		(net "M_A_CPU1_SA_PAR")
	)
	(segment
		(start 79.347822 -256.09042)
		(end 79.347822 -256.090166)
		(width 0.0762)
		(layer "F.Cu")
		(net "M_A_CPU1_SA_PAR")
	)
	(segment
		(start 75.034394 -257.040126)
		(end 74.84872 -257.040126)
		(width 0.10668)
		(layer "F.Cu")
		(net "M_A_CPU1_SA_PAR")
	)
	(segment
		(start 75.247754 -256.639568)
		(end 75.141074 -256.746248)
		(width 0.10668)
		(layer "F.Cu")
		(net "M_A_CPU1_SA_PAR")
	)
	(segment
		(start 77.443838 -255.710944)
		(end 76.684886 -255.710944)
		(width 0.0762)
		(layer "F.Cu")
		(net "M_A_CPU1_SA_PAR")
	)
	(segment
		(start 75.939142 -256.933446)
		(end 75.832462 -257.040126)
		(width 0.10668)
		(layer "F.Cu")
		(net "M_A_CPU1_SA_PAR")
	)
	(segment
		(start 75.540108 -256.933446)
		(end 75.540108 -256.746248)
		(width 0.10668)
		(layer "F.Cu")
		(net "M_A_CPU1_SA_PAR")
	)
	(segment
		(start 75.939142 -256.746248)
		(end 75.939142 -256.933446)
		(width 0.10668)
		(layer "F.Cu")
		(net "M_A_CPU1_SA_PAR")
	)
	(segment
		(start 76.684886 -255.710944)
		(end 76.457302 -255.938528)
		(width 0.0762)
		(layer "F.Cu")
		(net "M_A_CPU1_SA_PAR")
	)
	(segment
		(start 78.594966 -255.76784)
		(end 78.586584 -255.763014)
		(width 0.0762)
		(layer "F.Cu")
		(net "M_A_CPU1_SA_PAR")
	)
	(segment
		(start 75.433428 -256.639568)
		(end 75.247754 -256.639568)
		(width 0.10668)
		(layer "F.Cu")
		(net "M_A_CPU1_SA_PAR")
	)
	(segment
		(start 76.457302 -255.938528)
		(end 76.457302 -256.228088)
		(width 0.0762)
		(layer "F.Cu")
		(net "M_A_CPU1_SA_PAR")
	)
	(segment
		(start 75.646788 -257.040126)
		(end 75.540108 -256.933446)
		(width 0.10668)
		(layer "F.Cu")
		(net "M_A_CPU1_SA_PAR")
	)
	(segment
		(start 74.74204 -256.933446)
		(end 74.74204 -256.746248)
		(width 0.10668)
		(layer "F.Cu")
		(net "M_A_CPU1_SA_PAR")
	)
	(segment
		(start 74.84872 -257.040126)
		(end 74.74204 -256.933446)
		(width 0.10668)
		(layer "F.Cu")
		(net "M_A_CPU1_SA_PAR")
	)
	(segment
		(start 62.665102 -255.456944)
		(end 61.4934 -254.285242)
		(width 0.10668)
		(layer "F.Cu")
		(net "M_A_CPU1_SA_PAR")
	)
	(segment
		(start 74.63536 -256.639568)
		(end 74.158094 -256.639568)
		(width 0.10668)
		(layer "F.Cu")
		(net "M_A_CPU1_SA_PAR")
	)
	(segment
		(start 75.141074 -256.933446)
		(end 75.034394 -257.040126)
		(width 0.10668)
		(layer "F.Cu")
		(net "M_A_CPU1_SA_PAR")
	)
	(segment
		(start 71.739252 -254.220726)
		(end 67.8942 -254.220726)
		(width 0.10668)
		(layer "F.Cu")
		(net "M_A_CPU1_SA_PAR")
	)
	(segment
		(start 79.16926 -255.763014)
		(end 79.168244 -255.763522)
		(width 0.0762)
		(layer "F.Cu")
		(net "M_A_CPU1_SA_PAR")
	)
	(segment
		(start 74.158094 -256.639568)
		(end 71.739252 -254.220726)
		(width 0.10668)
		(layer "F.Cu")
		(net "M_A_CPU1_SA_PAR")
	)
	(arc
		(start 77.654912 -255.76784)
		(mid 77.553144 -255.725406)
		(end 77.443838 -255.710944)
		(width 0.0762)
		(layer "F.Cu")
		(net "M_A_CPU1_SA_PAR")
	)
	(arc
		(start 79.160878 -255.76784)
		(mid 78.877922 -255.844017)
		(end 78.594966 -255.76784)
		(width 0.0762)
		(layer "F.Cu")
		(net "M_A_CPU1_SA_PAR")
	)
	(arc
		(start 79.452978 -255.909318)
		(mid 79.444041 -255.790294)
		(end 79.349346 -255.717548)
		(width 0.0762)
		(layer "F.Cu")
		(net "M_A_CPU1_SA_PAR")
	)
	(arc
		(start 79.349346 -255.717548)
		(mid 79.256422 -255.728871)
		(end 79.16926 -255.763014)
		(width 0.0762)
		(layer "F.Cu")
		(net "M_A_CPU1_SA_PAR")
	)
	(arc
		(start 78.586584 -255.763014)
		(mid 78.403076 -255.71752)
		(end 78.220824 -255.76784)
		(width 0.0762)
		(layer "F.Cu")
		(net "M_A_CPU1_SA_PAR")
	)
	(arc
		(start 78.220824 -255.76784)
		(mid 77.937868 -255.844017)
		(end 77.654912 -255.76784)
		(width 0.0762)
		(layer "F.Cu")
		(net "M_A_CPU1_SA_PAR")
	)
	(segment
		(start 61.01461 -241.025426)
		(end 61.01461 -240.225326)
		(width 0.12954)
		(layer "F.Cu")
		(net "M_A_CPU1_SA_DQS_DP<9>")
	)
	(segment
		(start 78.594966 -247.66778)
		(end 78.586584 -247.662954)
		(width 0.0762)
		(layer "F.Cu")
		(net "M_A_CPU1_SA_DQS_DP<9>")
	)
	(segment
		(start 56.750458 -239.517936)
		(end 56.183784 -239.517936)
		(width 0.101346)
		(layer "F.Cu")
		(net "M_A_CPU1_SA_DQS_DP<9>")
	)
	(segment
		(start 76.43749 -247.774206)
		(end 76.040996 -247.774206)
		(width 0.0762)
		(layer "F.Cu")
		(net "M_A_CPU1_SA_DQS_DP<9>")
	)
	(segment
		(start 62.45352 -242.464336)
		(end 61.01461 -241.025426)
		(width 0.12954)
		(layer "F.Cu")
		(net "M_A_CPU1_SA_DQS_DP<9>")
	)
	(segment
		(start 79.347822 -247.99036)
		(end 79.44866 -247.816878)
		(width 0.0762)
		(layer "F.Cu")
		(net "M_A_CPU1_SA_DQS_DP<9>")
	)
	(segment
		(start 76.594462 -247.617234)
		(end 76.43749 -247.774206)
		(width 0.0762)
		(layer "F.Cu")
		(net "M_A_CPU1_SA_DQS_DP<9>")
	)
	(segment
		(start 55.866284 -239.835436)
		(end 55.328058 -239.835436)
		(width 0.101346)
		(layer "F.Cu")
		(net "M_A_CPU1_SA_DQS_DP<9>")
	)
	(segment
		(start 66.801746 -247.840246)
		(end 62.45352 -243.49202)
		(width 0.12954)
		(layer "F.Cu")
		(net "M_A_CPU1_SA_DQS_DP<9>")
	)
	(segment
		(start 57.17667 -239.944148)
		(end 56.750458 -239.517936)
		(width 0.101346)
		(layer "F.Cu")
		(net "M_A_CPU1_SA_DQS_DP<9>")
	)
	(segment
		(start 77.467968 -247.617234)
		(end 76.594462 -247.617234)
		(width 0.0762)
		(layer "F.Cu")
		(net "M_A_CPU1_SA_DQS_DP<9>")
	)
	(segment
		(start 60.28944 -240.260378)
		(end 57.859168 -240.260378)
		(width 0.101346)
		(layer "F.Cu")
		(net "M_A_CPU1_SA_DQS_DP<9>")
	)
	(segment
		(start 62.45352 -243.49202)
		(end 62.45352 -242.464336)
		(width 0.12954)
		(layer "F.Cu")
		(net "M_A_CPU1_SA_DQS_DP<9>")
	)
	(segment
		(start 75.955906 -247.840246)
		(end 66.801746 -247.840246)
		(width 0.12954)
		(layer "F.Cu")
		(net "M_A_CPU1_SA_DQS_DP<9>")
	)
	(segment
		(start 56.183784 -239.517936)
		(end 55.866284 -239.835436)
		(width 0.101346)
		(layer "F.Cu")
		(net "M_A_CPU1_SA_DQS_DP<9>")
	)
	(segment
		(start 61.01461 -240.225326)
		(end 60.76569 -239.976406)
		(width 0.12954)
		(layer "F.Cu")
		(net "M_A_CPU1_SA_DQS_DP<9>")
	)
	(segment
		(start 57.542938 -239.944148)
		(end 57.17667 -239.944148)
		(width 0.101346)
		(layer "F.Cu")
		(net "M_A_CPU1_SA_DQS_DP<9>")
	)
	(segment
		(start 79.16926 -247.662954)
		(end 79.160878 -247.66778)
		(width 0.0762)
		(layer "F.Cu")
		(net "M_A_CPU1_SA_DQS_DP<9>")
	)
	(segment
		(start 60.573412 -239.976406)
		(end 60.28944 -240.260378)
		(width 0.12954)
		(layer "F.Cu")
		(net "M_A_CPU1_SA_DQS_DP<9>")
	)
	(segment
		(start 57.859168 -240.260378)
		(end 57.542938 -239.944148)
		(width 0.101346)
		(layer "F.Cu")
		(net "M_A_CPU1_SA_DQS_DP<9>")
	)
	(segment
		(start 75.974956 -247.840246)
		(end 75.955906 -247.840246)
		(width 0.0762)
		(layer "F.Cu")
		(net "M_A_CPU1_SA_DQS_DP<9>")
	)
	(segment
		(start 60.76569 -239.976406)
		(end 60.573412 -239.976406)
		(width 0.12954)
		(layer "F.Cu")
		(net "M_A_CPU1_SA_DQS_DP<9>")
	)
	(segment
		(start 76.040996 -247.774206)
		(end 75.974956 -247.840246)
		(width 0.0762)
		(layer "F.Cu")
		(net "M_A_CPU1_SA_DQS_DP<9>")
	)
	(arc
		(start 79.160878 -247.66778)
		(mid 78.877922 -247.743957)
		(end 78.594966 -247.66778)
		(width 0.0762)
		(layer "F.Cu")
		(net "M_A_CPU1_SA_DQS_DP<9>")
	)
	(arc
		(start 78.220824 -247.66778)
		(mid 77.937868 -247.743957)
		(end 77.654912 -247.66778)
		(width 0.0762)
		(layer "F.Cu")
		(net "M_A_CPU1_SA_DQS_DP<9>")
	)
	(arc
		(start 77.498956 -247.618504)
		(mid 77.483475 -247.617548)
		(end 77.467968 -247.617234)
		(width 0.0762)
		(layer "F.Cu")
		(net "M_A_CPU1_SA_DQS_DP<9>")
	)
	(arc
		(start 79.30261 -247.620282)
		(mid 79.233912 -247.635298)
		(end 79.16926 -247.662954)
		(width 0.0762)
		(layer "F.Cu")
		(net "M_A_CPU1_SA_DQS_DP<9>")
	)
	(arc
		(start 77.654912 -247.66778)
		(mid 77.579672 -247.634467)
		(end 77.498956 -247.618504)
		(width 0.0762)
		(layer "F.Cu")
		(net "M_A_CPU1_SA_DQS_DP<9>")
	)
	(arc
		(start 79.44866 -247.816878)
		(mid 79.432735 -247.676186)
		(end 79.30261 -247.620282)
		(width 0.0762)
		(layer "F.Cu")
		(net "M_A_CPU1_SA_DQS_DP<9>")
	)
	(arc
		(start 78.586584 -247.662954)
		(mid 78.403076 -247.61746)
		(end 78.220824 -247.66778)
		(width 0.0762)
		(layer "F.Cu")
		(net "M_A_CPU1_SA_DQS_DP<9>")
	)
	(segment
		(start 75.954382 -243.026184)
		(end 71.477124 -243.026184)
		(width 0.12954)
		(layer "F.Cu")
		(net "M_A_CPU1_SA_DQS_DP<8>")
	)
	(segment
		(start 76.039472 -242.960144)
		(end 75.973432 -243.026184)
		(width 0.0762)
		(layer "F.Cu")
		(net "M_A_CPU1_SA_DQS_DP<8>")
	)
	(segment
		(start 76.548996 -242.859306)
		(end 76.452476 -242.960144)
		(width 0.0762)
		(layer "F.Cu")
		(net "M_A_CPU1_SA_DQS_DP<8>")
	)
	(segment
		(start 60.741306 -230.641906)
		(end 60.557918 -230.641906)
		(width 0.12954)
		(layer "F.Cu")
		(net "M_A_CPU1_SA_DQS_DP<8>")
	)
	(segment
		(start 60.870846 -230.771446)
		(end 60.741306 -230.641906)
		(width 0.12954)
		(layer "F.Cu")
		(net "M_A_CPU1_SA_DQS_DP<8>")
	)
	(segment
		(start 75.973432 -243.026184)
		(end 75.954382 -243.026184)
		(width 0.0762)
		(layer "F.Cu")
		(net "M_A_CPU1_SA_DQS_DP<8>")
	)
	(segment
		(start 56.73217 -230.167942)
		(end 56.183784 -230.167942)
		(width 0.101346)
		(layer "F.Cu")
		(net "M_A_CPU1_SA_DQS_DP<8>")
	)
	(segment
		(start 71.477124 -243.026184)
		(end 62.027816 -233.576876)
		(width 0.12954)
		(layer "F.Cu")
		(net "M_A_CPU1_SA_DQS_DP<8>")
	)
	(segment
		(start 55.866284 -230.485442)
		(end 55.328058 -230.485442)
		(width 0.101346)
		(layer "F.Cu")
		(net "M_A_CPU1_SA_DQS_DP<8>")
	)
	(segment
		(start 76.651104 -242.757198)
		(end 76.548996 -242.859306)
		(width 0.0762)
		(layer "F.Cu")
		(net "M_A_CPU1_SA_DQS_DP<8>")
	)
	(segment
		(start 76.452476 -242.960144)
		(end 76.039472 -242.960144)
		(width 0.0762)
		(layer "F.Cu")
		(net "M_A_CPU1_SA_DQS_DP<8>")
	)
	(segment
		(start 79.347822 -243.130324)
		(end 79.44866 -242.956842)
		(width 0.0762)
		(layer "F.Cu")
		(net "M_A_CPU1_SA_DQS_DP<8>")
	)
	(segment
		(start 57.859168 -230.910384)
		(end 57.542938 -230.594154)
		(width 0.101346)
		(layer "F.Cu")
		(net "M_A_CPU1_SA_DQS_DP<8>")
	)
	(segment
		(start 79.16926 -242.802918)
		(end 79.160878 -242.807744)
		(width 0.0762)
		(layer "F.Cu")
		(net "M_A_CPU1_SA_DQS_DP<8>")
	)
	(segment
		(start 60.870846 -231.521762)
		(end 60.870846 -230.771446)
		(width 0.12954)
		(layer "F.Cu")
		(net "M_A_CPU1_SA_DQS_DP<8>")
	)
	(segment
		(start 57.542938 -230.594154)
		(end 57.158382 -230.594154)
		(width 0.101346)
		(layer "F.Cu")
		(net "M_A_CPU1_SA_DQS_DP<8>")
	)
	(segment
		(start 56.183784 -230.167942)
		(end 55.866284 -230.485442)
		(width 0.101346)
		(layer "F.Cu")
		(net "M_A_CPU1_SA_DQS_DP<8>")
	)
	(segment
		(start 60.557918 -230.641906)
		(end 60.28944 -230.910384)
		(width 0.12954)
		(layer "F.Cu")
		(net "M_A_CPU1_SA_DQS_DP<8>")
	)
	(segment
		(start 62.027816 -233.576876)
		(end 62.027816 -232.678732)
		(width 0.12954)
		(layer "F.Cu")
		(net "M_A_CPU1_SA_DQS_DP<8>")
	)
	(segment
		(start 57.158382 -230.594154)
		(end 56.73217 -230.167942)
		(width 0.101346)
		(layer "F.Cu")
		(net "M_A_CPU1_SA_DQS_DP<8>")
	)
	(segment
		(start 78.594966 -242.807744)
		(end 78.586584 -242.802918)
		(width 0.0762)
		(layer "F.Cu")
		(net "M_A_CPU1_SA_DQS_DP<8>")
	)
	(segment
		(start 60.28944 -230.910384)
		(end 57.859168 -230.910384)
		(width 0.101346)
		(layer "F.Cu")
		(net "M_A_CPU1_SA_DQS_DP<8>")
	)
	(segment
		(start 77.467968 -242.757198)
		(end 76.651104 -242.757198)
		(width 0.0762)
		(layer "F.Cu")
		(net "M_A_CPU1_SA_DQS_DP<8>")
	)
	(segment
		(start 62.027816 -232.678732)
		(end 60.870846 -231.521762)
		(width 0.12954)
		(layer "F.Cu")
		(net "M_A_CPU1_SA_DQS_DP<8>")
	)
	(arc
		(start 79.160878 -242.807744)
		(mid 78.877922 -242.883921)
		(end 78.594966 -242.807744)
		(width 0.0762)
		(layer "F.Cu")
		(net "M_A_CPU1_SA_DQS_DP<8>")
	)
	(arc
		(start 79.30261 -242.760246)
		(mid 79.233912 -242.775262)
		(end 79.16926 -242.802918)
		(width 0.0762)
		(layer "F.Cu")
		(net "M_A_CPU1_SA_DQS_DP<8>")
	)
	(arc
		(start 77.654912 -242.807744)
		(mid 77.579672 -242.774431)
		(end 77.498956 -242.758468)
		(width 0.0762)
		(layer "F.Cu")
		(net "M_A_CPU1_SA_DQS_DP<8>")
	)
	(arc
		(start 77.498956 -242.758468)
		(mid 77.483475 -242.757512)
		(end 77.467968 -242.757198)
		(width 0.0762)
		(layer "F.Cu")
		(net "M_A_CPU1_SA_DQS_DP<8>")
	)
	(arc
		(start 79.44866 -242.956842)
		(mid 79.432735 -242.81615)
		(end 79.30261 -242.760246)
		(width 0.0762)
		(layer "F.Cu")
		(net "M_A_CPU1_SA_DQS_DP<8>")
	)
	(arc
		(start 78.586584 -242.802918)
		(mid 78.403076 -242.757424)
		(end 78.220824 -242.807744)
		(width 0.0762)
		(layer "F.Cu")
		(net "M_A_CPU1_SA_DQS_DP<8>")
	)
	(arc
		(start 78.220824 -242.807744)
		(mid 77.937868 -242.883921)
		(end 77.654912 -242.807744)
		(width 0.0762)
		(layer "F.Cu")
		(net "M_A_CPU1_SA_DQS_DP<8>")
	)
	(segment
		(start 56.177688 -220.817694)
		(end 55.860188 -221.135194)
		(width 0.101346)
		(layer "F.Cu")
		(net "M_A_CPU1_SA_DQS_DP<7>")
	)
	(segment
		(start 60.553092 -221.296484)
		(end 60.28944 -221.560136)
		(width 0.12954)
		(layer "F.Cu")
		(net "M_A_CPU1_SA_DQS_DP<7>")
	)
	(segment
		(start 65.34404 -224.739708)
		(end 61.900816 -221.296484)
		(width 0.12954)
		(layer "F.Cu")
		(net "M_A_CPU1_SA_DQS_DP<7>")
	)
	(segment
		(start 76.497688 -238.024924)
		(end 76.408534 -238.134144)
		(width 0.0762)
		(layer "F.Cu")
		(net "M_A_CPU1_SA_DQS_DP<7>")
	)
	(segment
		(start 57.74944 -221.560136)
		(end 57.43194 -221.242636)
		(width 0.101346)
		(layer "F.Cu")
		(net "M_A_CPU1_SA_DQS_DP<7>")
	)
	(segment
		(start 56.513222 -220.817694)
		(end 56.177688 -220.817694)
		(width 0.101346)
		(layer "F.Cu")
		(net "M_A_CPU1_SA_DQS_DP<7>")
	)
	(segment
		(start 77.467968 -237.897162)
		(end 76.62545 -237.897162)
		(width 0.0762)
		(layer "F.Cu")
		(net "M_A_CPU1_SA_DQS_DP<7>")
	)
	(segment
		(start 60.28944 -221.560136)
		(end 57.74944 -221.560136)
		(width 0.101346)
		(layer "F.Cu")
		(net "M_A_CPU1_SA_DQS_DP<7>")
	)
	(segment
		(start 57.43194 -221.242636)
		(end 56.938164 -221.242636)
		(width 0.101346)
		(layer "F.Cu")
		(net "M_A_CPU1_SA_DQS_DP<7>")
	)
	(segment
		(start 76.408534 -238.134144)
		(end 76.071984 -238.134144)
		(width 0.0762)
		(layer "F.Cu")
		(net "M_A_CPU1_SA_DQS_DP<7>")
	)
	(segment
		(start 56.938164 -221.242636)
		(end 56.513222 -220.817694)
		(width 0.101346)
		(layer "F.Cu")
		(net "M_A_CPU1_SA_DQS_DP<7>")
	)
	(segment
		(start 76.005944 -238.200184)
		(end 75.986894 -238.200184)
		(width 0.0762)
		(layer "F.Cu")
		(net "M_A_CPU1_SA_DQS_DP<7>")
	)
	(segment
		(start 61.900816 -221.296484)
		(end 60.553092 -221.296484)
		(width 0.12954)
		(layer "F.Cu")
		(net "M_A_CPU1_SA_DQS_DP<7>")
	)
	(segment
		(start 65.34404 -229.619556)
		(end 65.34404 -224.739708)
		(width 0.12954)
		(layer "F.Cu")
		(net "M_A_CPU1_SA_DQS_DP<7>")
	)
	(segment
		(start 78.594966 -237.947708)
		(end 78.586584 -237.942882)
		(width 0.0762)
		(layer "F.Cu")
		(net "M_A_CPU1_SA_DQS_DP<7>")
	)
	(segment
		(start 79.16926 -237.942882)
		(end 79.160878 -237.947708)
		(width 0.0762)
		(layer "F.Cu")
		(net "M_A_CPU1_SA_DQS_DP<7>")
	)
	(segment
		(start 75.986894 -238.200184)
		(end 73.924668 -238.200184)
		(width 0.12954)
		(layer "F.Cu")
		(net "M_A_CPU1_SA_DQS_DP<7>")
	)
	(segment
		(start 76.62545 -237.897162)
		(end 76.497688 -238.024924)
		(width 0.0762)
		(layer "F.Cu")
		(net "M_A_CPU1_SA_DQS_DP<7>")
	)
	(segment
		(start 79.347822 -238.270288)
		(end 79.44866 -238.096806)
		(width 0.0762)
		(layer "F.Cu")
		(net "M_A_CPU1_SA_DQS_DP<7>")
	)
	(segment
		(start 55.860188 -221.135194)
		(end 55.328058 -221.135194)
		(width 0.101346)
		(layer "F.Cu")
		(net "M_A_CPU1_SA_DQS_DP<7>")
	)
	(segment
		(start 73.924668 -238.200184)
		(end 65.34404 -229.619556)
		(width 0.12954)
		(layer "F.Cu")
		(net "M_A_CPU1_SA_DQS_DP<7>")
	)
	(segment
		(start 76.071984 -238.134144)
		(end 76.005944 -238.200184)
		(width 0.0762)
		(layer "F.Cu")
		(net "M_A_CPU1_SA_DQS_DP<7>")
	)
	(arc
		(start 78.586584 -237.942882)
		(mid 78.403076 -237.897388)
		(end 78.220824 -237.947708)
		(width 0.0762)
		(layer "F.Cu")
		(net "M_A_CPU1_SA_DQS_DP<7>")
	)
	(arc
		(start 79.160878 -237.947708)
		(mid 78.877922 -238.023885)
		(end 78.594966 -237.947708)
		(width 0.0762)
		(layer "F.Cu")
		(net "M_A_CPU1_SA_DQS_DP<7>")
	)
	(arc
		(start 78.220824 -237.947708)
		(mid 77.937868 -238.023885)
		(end 77.654912 -237.947708)
		(width 0.0762)
		(layer "F.Cu")
		(net "M_A_CPU1_SA_DQS_DP<7>")
	)
	(arc
		(start 79.30261 -237.90021)
		(mid 79.233912 -237.915226)
		(end 79.16926 -237.942882)
		(width 0.0762)
		(layer "F.Cu")
		(net "M_A_CPU1_SA_DQS_DP<7>")
	)
	(arc
		(start 77.498956 -237.898432)
		(mid 77.483475 -237.897476)
		(end 77.467968 -237.897162)
		(width 0.0762)
		(layer "F.Cu")
		(net "M_A_CPU1_SA_DQS_DP<7>")
	)
	(arc
		(start 77.654912 -237.947708)
		(mid 77.579672 -237.914395)
		(end 77.498956 -237.898432)
		(width 0.0762)
		(layer "F.Cu")
		(net "M_A_CPU1_SA_DQS_DP<7>")
	)
	(arc
		(start 79.44866 -238.096806)
		(mid 79.432735 -237.956114)
		(end 79.30261 -237.90021)
		(width 0.0762)
		(layer "F.Cu")
		(net "M_A_CPU1_SA_DQS_DP<7>")
	)
	(segment
		(start 69.73062 -219.685362)
		(end 62.270132 -212.225128)
		(width 0.12954)
		(layer "F.Cu")
		(net "M_A_CPU1_SA_DQS_DP<6>")
	)
	(segment
		(start 76.54417 -233.037126)
		(end 76.43749 -233.143806)
		(width 0.0762)
		(layer "F.Cu")
		(net "M_A_CPU1_SA_DQS_DP<6>")
	)
	(segment
		(start 56.965596 -211.892642)
		(end 56.540654 -211.4677)
		(width 0.101346)
		(layer "F.Cu")
		(net "M_A_CPU1_SA_DQS_DP<6>")
	)
	(segment
		(start 79.347822 -233.410252)
		(end 79.44866 -233.23677)
		(width 0.0762)
		(layer "F.Cu")
		(net "M_A_CPU1_SA_DQS_DP<6>")
	)
	(segment
		(start 76.040996 -233.143806)
		(end 75.974956 -233.209846)
		(width 0.0762)
		(layer "F.Cu")
		(net "M_A_CPU1_SA_DQS_DP<6>")
	)
	(segment
		(start 76.43749 -233.143806)
		(end 76.040996 -233.143806)
		(width 0.0762)
		(layer "F.Cu")
		(net "M_A_CPU1_SA_DQS_DP<6>")
	)
	(segment
		(start 69.73062 -227.757736)
		(end 69.73062 -219.685362)
		(width 0.12954)
		(layer "F.Cu")
		(net "M_A_CPU1_SA_DQS_DP<6>")
	)
	(segment
		(start 56.540654 -211.4677)
		(end 56.177688 -211.4677)
		(width 0.101346)
		(layer "F.Cu")
		(net "M_A_CPU1_SA_DQS_DP<6>")
	)
	(segment
		(start 57.43194 -211.892642)
		(end 56.965596 -211.892642)
		(width 0.101346)
		(layer "F.Cu")
		(net "M_A_CPU1_SA_DQS_DP<6>")
	)
	(segment
		(start 60.855098 -211.945982)
		(end 60.5536 -211.945982)
		(width 0.12954)
		(layer "F.Cu")
		(net "M_A_CPU1_SA_DQS_DP<6>")
	)
	(segment
		(start 75.974956 -233.209846)
		(end 75.955906 -233.209846)
		(width 0.0762)
		(layer "F.Cu")
		(net "M_A_CPU1_SA_DQS_DP<6>")
	)
	(segment
		(start 55.860188 -211.7852)
		(end 55.328058 -211.7852)
		(width 0.101346)
		(layer "F.Cu")
		(net "M_A_CPU1_SA_DQS_DP<6>")
	)
	(segment
		(start 62.270132 -212.225128)
		(end 61.134244 -212.225128)
		(width 0.12954)
		(layer "F.Cu")
		(net "M_A_CPU1_SA_DQS_DP<6>")
	)
	(segment
		(start 77.467968 -233.037126)
		(end 76.54417 -233.037126)
		(width 0.0762)
		(layer "F.Cu")
		(net "M_A_CPU1_SA_DQS_DP<6>")
	)
	(segment
		(start 75.18273 -233.209846)
		(end 69.73062 -227.757736)
		(width 0.12954)
		(layer "F.Cu")
		(net "M_A_CPU1_SA_DQS_DP<6>")
	)
	(segment
		(start 56.177688 -211.4677)
		(end 55.860188 -211.7852)
		(width 0.101346)
		(layer "F.Cu")
		(net "M_A_CPU1_SA_DQS_DP<6>")
	)
	(segment
		(start 60.28944 -212.210142)
		(end 57.74944 -212.210142)
		(width 0.101346)
		(layer "F.Cu")
		(net "M_A_CPU1_SA_DQS_DP<6>")
	)
	(segment
		(start 75.955906 -233.209846)
		(end 75.18273 -233.209846)
		(width 0.12954)
		(layer "F.Cu")
		(net "M_A_CPU1_SA_DQS_DP<6>")
	)
	(segment
		(start 79.16926 -233.082846)
		(end 79.160878 -233.087672)
		(width 0.0762)
		(layer "F.Cu")
		(net "M_A_CPU1_SA_DQS_DP<6>")
	)
	(segment
		(start 57.74944 -212.210142)
		(end 57.43194 -211.892642)
		(width 0.101346)
		(layer "F.Cu")
		(net "M_A_CPU1_SA_DQS_DP<6>")
	)
	(segment
		(start 61.134244 -212.225128)
		(end 60.855098 -211.945982)
		(width 0.12954)
		(layer "F.Cu")
		(net "M_A_CPU1_SA_DQS_DP<6>")
	)
	(segment
		(start 78.594966 -233.087672)
		(end 78.586584 -233.082846)
		(width 0.0762)
		(layer "F.Cu")
		(net "M_A_CPU1_SA_DQS_DP<6>")
	)
	(segment
		(start 60.5536 -211.945982)
		(end 60.28944 -212.210142)
		(width 0.12954)
		(layer "F.Cu")
		(net "M_A_CPU1_SA_DQS_DP<6>")
	)
	(arc
		(start 78.220824 -233.087672)
		(mid 77.937868 -233.163849)
		(end 77.654912 -233.087672)
		(width 0.0762)
		(layer "F.Cu")
		(net "M_A_CPU1_SA_DQS_DP<6>")
	)
	(arc
		(start 79.44866 -233.23677)
		(mid 79.432735 -233.096078)
		(end 79.30261 -233.040174)
		(width 0.0762)
		(layer "F.Cu")
		(net "M_A_CPU1_SA_DQS_DP<6>")
	)
	(arc
		(start 79.30261 -233.040174)
		(mid 79.233912 -233.05519)
		(end 79.16926 -233.082846)
		(width 0.0762)
		(layer "F.Cu")
		(net "M_A_CPU1_SA_DQS_DP<6>")
	)
	(arc
		(start 77.654912 -233.087672)
		(mid 77.579672 -233.054359)
		(end 77.498956 -233.038396)
		(width 0.0762)
		(layer "F.Cu")
		(net "M_A_CPU1_SA_DQS_DP<6>")
	)
	(arc
		(start 79.160878 -233.087672)
		(mid 78.877922 -233.163849)
		(end 78.594966 -233.087672)
		(width 0.0762)
		(layer "F.Cu")
		(net "M_A_CPU1_SA_DQS_DP<6>")
	)
	(arc
		(start 78.586584 -233.082846)
		(mid 78.403076 -233.037352)
		(end 78.220824 -233.087672)
		(width 0.0762)
		(layer "F.Cu")
		(net "M_A_CPU1_SA_DQS_DP<6>")
	)
	(arc
		(start 77.498956 -233.038396)
		(mid 77.483475 -233.03744)
		(end 77.467968 -233.037126)
		(width 0.0762)
		(layer "F.Cu")
		(net "M_A_CPU1_SA_DQS_DP<6>")
	)
	(segment
		(start 57.74944 -202.860148)
		(end 57.43194 -202.542648)
		(width 0.101346)
		(layer "F.Cu")
		(net "M_A_CPU1_SA_DQS_DP<5>")
	)
	(segment
		(start 79.347822 -228.55047)
		(end 79.44866 -228.376988)
		(width 0.0762)
		(layer "F.Cu")
		(net "M_A_CPU1_SA_DQS_DP<5>")
	)
	(segment
		(start 71.938896 -213.948518)
		(end 71.663814 -213.673436)
		(width 0.12954)
		(layer "F.Cu")
		(net "M_A_CPU1_SA_DQS_DP<5>")
	)
	(segment
		(start 76.27239 -227.924106)
		(end 76.06284 -227.714556)
		(width 0.0762)
		(layer "F.Cu")
		(net "M_A_CPU1_SA_DQS_DP<5>")
	)
	(segment
		(start 60.28944 -202.860148)
		(end 57.74944 -202.860148)
		(width 0.101346)
		(layer "F.Cu")
		(net "M_A_CPU1_SA_DQS_DP<5>")
	)
	(segment
		(start 60.561982 -202.587606)
		(end 60.28944 -202.860148)
		(width 0.12954)
		(layer "F.Cu")
		(net "M_A_CPU1_SA_DQS_DP<5>")
	)
	(segment
		(start 75.969368 -227.714556)
		(end 75.955906 -227.701094)
		(width 0.0762)
		(layer "F.Cu")
		(net "M_A_CPU1_SA_DQS_DP<5>")
	)
	(segment
		(start 74.1172 -216.712292)
		(end 72.450706 -215.045798)
		(width 0.12954)
		(layer "F.Cu")
		(net "M_A_CPU1_SA_DQS_DP<5>")
	)
	(segment
		(start 76.06284 -227.714556)
		(end 75.969368 -227.714556)
		(width 0.0762)
		(layer "F.Cu")
		(net "M_A_CPU1_SA_DQS_DP<5>")
	)
	(segment
		(start 71.663814 -213.4362)
		(end 60.815728 -202.587606)
		(width 0.12954)
		(layer "F.Cu")
		(net "M_A_CPU1_SA_DQS_DP<5>")
	)
	(segment
		(start 57.43194 -202.542648)
		(end 56.950356 -202.542648)
		(width 0.101346)
		(layer "F.Cu")
		(net "M_A_CPU1_SA_DQS_DP<5>")
	)
	(segment
		(start 56.525414 -202.117706)
		(end 56.177688 -202.117706)
		(width 0.101346)
		(layer "F.Cu")
		(net "M_A_CPU1_SA_DQS_DP<5>")
	)
	(segment
		(start 78.594966 -228.22789)
		(end 78.586584 -228.223064)
		(width 0.0762)
		(layer "F.Cu")
		(net "M_A_CPU1_SA_DQS_DP<5>")
	)
	(segment
		(start 71.663814 -213.673436)
		(end 71.663814 -213.4362)
		(width 0.12954)
		(layer "F.Cu")
		(net "M_A_CPU1_SA_DQS_DP<5>")
	)
	(segment
		(start 60.815728 -202.587606)
		(end 60.561982 -202.587606)
		(width 0.12954)
		(layer "F.Cu")
		(net "M_A_CPU1_SA_DQS_DP<5>")
	)
	(segment
		(start 55.860188 -202.435206)
		(end 55.328058 -202.435206)
		(width 0.101346)
		(layer "F.Cu")
		(net "M_A_CPU1_SA_DQS_DP<5>")
	)
	(segment
		(start 74.1172 -225.862134)
		(end 74.1172 -216.712292)
		(width 0.12954)
		(layer "F.Cu")
		(net "M_A_CPU1_SA_DQS_DP<5>")
	)
	(segment
		(start 72.176132 -213.948518)
		(end 71.938896 -213.948518)
		(width 0.12954)
		(layer "F.Cu")
		(net "M_A_CPU1_SA_DQS_DP<5>")
	)
	(segment
		(start 77.324458 -227.924106)
		(end 76.27239 -227.924106)
		(width 0.0762)
		(layer "F.Cu")
		(net "M_A_CPU1_SA_DQS_DP<5>")
	)
	(segment
		(start 56.177688 -202.117706)
		(end 55.860188 -202.435206)
		(width 0.101346)
		(layer "F.Cu")
		(net "M_A_CPU1_SA_DQS_DP<5>")
	)
	(segment
		(start 72.450706 -214.223092)
		(end 72.176132 -213.948518)
		(width 0.12954)
		(layer "F.Cu")
		(net "M_A_CPU1_SA_DQS_DP<5>")
	)
	(segment
		(start 56.950356 -202.542648)
		(end 56.525414 -202.117706)
		(width 0.101346)
		(layer "F.Cu")
		(net "M_A_CPU1_SA_DQS_DP<5>")
	)
	(segment
		(start 77.539342 -228.13899)
		(end 77.324458 -227.924106)
		(width 0.0762)
		(layer "F.Cu")
		(net "M_A_CPU1_SA_DQS_DP<5>")
	)
	(segment
		(start 75.955906 -227.701094)
		(end 75.95616 -227.701094)
		(width 0.12954)
		(layer "F.Cu")
		(net "M_A_CPU1_SA_DQS_DP<5>")
	)
	(segment
		(start 72.450706 -215.045798)
		(end 72.450706 -214.223092)
		(width 0.12954)
		(layer "F.Cu")
		(net "M_A_CPU1_SA_DQS_DP<5>")
	)
	(segment
		(start 79.16926 -228.223064)
		(end 79.160878 -228.22789)
		(width 0.0762)
		(layer "F.Cu")
		(net "M_A_CPU1_SA_DQS_DP<5>")
	)
	(segment
		(start 75.95616 -227.701094)
		(end 74.1172 -225.862134)
		(width 0.12954)
		(layer "F.Cu")
		(net "M_A_CPU1_SA_DQS_DP<5>")
	)
	(arc
		(start 78.220824 -228.22789)
		(mid 77.864964 -228.299332)
		(end 77.539342 -228.13899)
		(width 0.0762)
		(layer "F.Cu")
		(net "M_A_CPU1_SA_DQS_DP<5>")
	)
	(arc
		(start 79.44866 -228.376988)
		(mid 79.432735 -228.236296)
		(end 79.30261 -228.180392)
		(width 0.0762)
		(layer "F.Cu")
		(net "M_A_CPU1_SA_DQS_DP<5>")
	)
	(arc
		(start 78.586584 -228.223064)
		(mid 78.403076 -228.17757)
		(end 78.220824 -228.22789)
		(width 0.0762)
		(layer "F.Cu")
		(net "M_A_CPU1_SA_DQS_DP<5>")
	)
	(arc
		(start 79.160878 -228.22789)
		(mid 78.877922 -228.304067)
		(end 78.594966 -228.22789)
		(width 0.0762)
		(layer "F.Cu")
		(net "M_A_CPU1_SA_DQS_DP<5>")
	)
	(arc
		(start 79.30261 -228.180392)
		(mid 79.233912 -228.195408)
		(end 79.16926 -228.223064)
		(width 0.0762)
		(layer "F.Cu")
		(net "M_A_CPU1_SA_DQS_DP<5>")
	)
	(segment
		(start 64.82207 -244.351048)
		(end 64.665352 -244.19433)
		(width 0.12954)
		(layer "F.Cu")
		(net "M_A_CPU1_SA_DQS_DP<4>")
	)
	(segment
		(start 66.938652 -246.46763)
		(end 66.938652 -246.284242)
		(width 0.12954)
		(layer "F.Cu")
		(net "M_A_CPU1_SA_DQS_DP<4>")
	)
	(segment
		(start 66.244978 -244.704616)
		(end 66.245232 -244.255036)
		(width 0.12954)
		(layer "F.Cu")
		(net "M_A_CPU1_SA_DQS_DP<4>")
	)
	(segment
		(start 76.448666 -246.677434)
		(end 76.429616 -246.677434)
		(width 0.0762)
		(layer "F.Cu")
		(net "M_A_CPU1_SA_DQS_DP<4>")
	)
	(segment
		(start 62.08141 -239.768888)
		(end 60.696348 -238.383826)
		(width 0.12954)
		(layer "F.Cu")
		(net "M_A_CPU1_SA_DQS_DP<4>")
	)
	(segment
		(start 76.429616 -246.677434)
		(end 67.148456 -246.677434)
		(width 0.12954)
		(layer "F.Cu")
		(net "M_A_CPU1_SA_DQS_DP<4>")
	)
	(segment
		(start 66.245232 -244.255036)
		(end 65.898268 -243.908072)
		(width 0.12954)
		(layer "F.Cu")
		(net "M_A_CPU1_SA_DQS_DP<4>")
	)
	(segment
		(start 64.665352 -244.19433)
		(end 64.665352 -244.010942)
		(width 0.12954)
		(layer "F.Cu")
		(net "M_A_CPU1_SA_DQS_DP<4>")
	)
	(segment
		(start 76.514706 -246.743474)
		(end 76.448666 -246.677434)
		(width 0.0762)
		(layer "F.Cu")
		(net "M_A_CPU1_SA_DQS_DP<4>")
	)
	(segment
		(start 60.211208 -238.383826)
		(end 59.962796 -238.135414)
		(width 0.12954)
		(layer "F.Cu")
		(net "M_A_CPU1_SA_DQS_DP<4>")
	)
	(segment
		(start 63.8683 -243.214398)
		(end 63.68542 -243.214398)
		(width 0.12954)
		(layer "F.Cu")
		(net "M_A_CPU1_SA_DQS_DP<4>")
	)
	(segment
		(start 64.761618 -242.771422)
		(end 64.31153 -242.771168)
		(width 0.12954)
		(layer "F.Cu")
		(net "M_A_CPU1_SA_DQS_DP<4>")
	)
	(segment
		(start 60.696348 -238.383826)
		(end 60.211208 -238.383826)
		(width 0.12954)
		(layer "F.Cu")
		(net "M_A_CPU1_SA_DQS_DP<4>")
	)
	(segment
		(start 65.898268 -243.908072)
		(end 65.44818 -243.907818)
		(width 0.12954)
		(layer "F.Cu")
		(net "M_A_CPU1_SA_DQS_DP<4>")
	)
	(segment
		(start 62.08141 -240.582704)
		(end 62.08141 -239.768888)
		(width 0.12954)
		(layer "F.Cu")
		(net "M_A_CPU1_SA_DQS_DP<4>")
	)
	(segment
		(start 67.034918 -245.044722)
		(end 66.58483 -245.044468)
		(width 0.12954)
		(layer "F.Cu")
		(net "M_A_CPU1_SA_DQS_DP<4>")
	)
	(segment
		(start 65.802002 -245.147592)
		(end 66.244978 -244.704616)
		(width 0.12954)
		(layer "F.Cu")
		(net "M_A_CPU1_SA_DQS_DP<4>")
	)
	(segment
		(start 67.381628 -245.841266)
		(end 67.381882 -245.391686)
		(width 0.12954)
		(layer "F.Cu")
		(net "M_A_CPU1_SA_DQS_DP<4>")
	)
	(segment
		(start 77.467968 -246.743474)
		(end 76.514706 -246.743474)
		(width 0.0762)
		(layer "F.Cu")
		(net "M_A_CPU1_SA_DQS_DP<4>")
	)
	(segment
		(start 59.962796 -238.135414)
		(end 59.428126 -238.135414)
		(width 0.12954)
		(layer "F.Cu")
		(net "M_A_CPU1_SA_DQS_DP<4>")
	)
	(segment
		(start 65.00495 -244.351048)
		(end 64.82207 -244.351048)
		(width 0.12954)
		(layer "F.Cu")
		(net "M_A_CPU1_SA_DQS_DP<4>")
	)
	(segment
		(start 66.58483 -245.044468)
		(end 66.1416 -245.487698)
		(width 0.12954)
		(layer "F.Cu")
		(net "M_A_CPU1_SA_DQS_DP<4>")
	)
	(segment
		(start 66.938652 -246.284242)
		(end 67.381628 -245.841266)
		(width 0.12954)
		(layer "F.Cu")
		(net "M_A_CPU1_SA_DQS_DP<4>")
	)
	(segment
		(start 67.381882 -245.391686)
		(end 67.034918 -245.044722)
		(width 0.12954)
		(layer "F.Cu")
		(net "M_A_CPU1_SA_DQS_DP<4>")
	)
	(segment
		(start 65.802002 -245.33098)
		(end 65.802002 -245.147592)
		(width 0.12954)
		(layer "F.Cu")
		(net "M_A_CPU1_SA_DQS_DP<4>")
	)
	(segment
		(start 65.108328 -243.567966)
		(end 65.108582 -243.118386)
		(width 0.12954)
		(layer "F.Cu")
		(net "M_A_CPU1_SA_DQS_DP<4>")
	)
	(segment
		(start 67.148456 -246.677434)
		(end 66.938652 -246.46763)
		(width 0.12954)
		(layer "F.Cu")
		(net "M_A_CPU1_SA_DQS_DP<4>")
	)
	(segment
		(start 65.95872 -245.487698)
		(end 65.802002 -245.33098)
		(width 0.12954)
		(layer "F.Cu")
		(net "M_A_CPU1_SA_DQS_DP<4>")
	)
	(segment
		(start 63.52032 -242.021614)
		(end 62.08141 -240.582704)
		(width 0.12954)
		(layer "F.Cu")
		(net "M_A_CPU1_SA_DQS_DP<4>")
	)
	(segment
		(start 64.31153 -242.771168)
		(end 63.8683 -243.214398)
		(width 0.12954)
		(layer "F.Cu")
		(net "M_A_CPU1_SA_DQS_DP<4>")
	)
	(segment
		(start 63.68542 -243.214398)
		(end 63.52032 -243.049298)
		(width 0.12954)
		(layer "F.Cu")
		(net "M_A_CPU1_SA_DQS_DP<4>")
	)
	(segment
		(start 66.1416 -245.487698)
		(end 65.95872 -245.487698)
		(width 0.12954)
		(layer "F.Cu")
		(net "M_A_CPU1_SA_DQS_DP<4>")
	)
	(segment
		(start 64.665352 -244.010942)
		(end 65.108328 -243.567966)
		(width 0.12954)
		(layer "F.Cu")
		(net "M_A_CPU1_SA_DQS_DP<4>")
	)
	(segment
		(start 65.44818 -243.907818)
		(end 65.00495 -244.351048)
		(width 0.12954)
		(layer "F.Cu")
		(net "M_A_CPU1_SA_DQS_DP<4>")
	)
	(segment
		(start 65.108582 -243.118386)
		(end 64.761618 -242.771422)
		(width 0.12954)
		(layer "F.Cu")
		(net "M_A_CPU1_SA_DQS_DP<4>")
	)
	(segment
		(start 63.52032 -243.049298)
		(end 63.52032 -242.021614)
		(width 0.12954)
		(layer "F.Cu")
		(net "M_A_CPU1_SA_DQS_DP<4>")
	)
	(arc
		(start 77.880718 -246.619522)
		(mid 77.763905 -246.644198)
		(end 77.654912 -246.692928)
		(width 0.0762)
		(layer "F.Cu")
		(net "M_A_CPU1_SA_DQS_DP<4>")
	)
	(arc
		(start 77.654912 -246.692928)
		(mid 77.564779 -246.730548)
		(end 77.467968 -246.743474)
		(width 0.0762)
		(layer "F.Cu")
		(net "M_A_CPU1_SA_DQS_DP<4>")
	)
	(arc
		(start 78.408022 -246.370348)
		(mid 78.165705 -246.540068)
		(end 77.880718 -246.619522)
		(width 0.0762)
		(layer "F.Cu")
		(net "M_A_CPU1_SA_DQS_DP<4>")
	)
	(segment
		(start 68.15709 -237.259368)
		(end 67.705986 -237.259368)
		(width 0.12954)
		(layer "F.Cu")
		(net "M_A_CPU1_SA_DQS_DP<3>")
	)
	(segment
		(start 76.501752 -242.010438)
		(end 76.040996 -242.010438)
		(width 0.0762)
		(layer "F.Cu")
		(net "M_A_CPU1_SA_DQS_DP<3>")
	)
	(segment
		(start 61.948822 -231.0511)
		(end 61.948822 -230.2637)
		(width 0.12954)
		(layer "F.Cu")
		(net "M_A_CPU1_SA_DQS_DP<3>")
	)
	(segment
		(start 65.098422 -235.13796)
		(end 64.940434 -234.979972)
		(width 0.12954)
		(layer "F.Cu")
		(net "M_A_CPU1_SA_DQS_DP<3>")
	)
	(segment
		(start 77.467968 -241.883438)
		(end 76.628752 -241.883438)
		(width 0.0762)
		(layer "F.Cu")
		(net "M_A_CPU1_SA_DQS_DP<3>")
	)
	(segment
		(start 68.350384 -238.20755)
		(end 68.502276 -238.055658)
		(width 0.12954)
		(layer "F.Cu")
		(net "M_A_CPU1_SA_DQS_DP<3>")
	)
	(segment
		(start 68.502276 -238.055658)
		(end 68.502276 -237.604554)
		(width 0.12954)
		(layer "F.Cu")
		(net "M_A_CPU1_SA_DQS_DP<3>")
	)
	(segment
		(start 67.213734 -237.253272)
		(end 67.213734 -237.0709)
		(width 0.12954)
		(layer "F.Cu")
		(net "M_A_CPU1_SA_DQS_DP<3>")
	)
	(segment
		(start 66.235072 -236.27461)
		(end 66.077084 -236.116622)
		(width 0.12954)
		(layer "F.Cu")
		(net "M_A_CPU1_SA_DQS_DP<3>")
	)
	(segment
		(start 76.040996 -242.010438)
		(end 75.974956 -241.944398)
		(width 0.0762)
		(layer "F.Cu")
		(net "M_A_CPU1_SA_DQS_DP<3>")
	)
	(segment
		(start 66.569336 -236.122718)
		(end 66.417444 -236.27461)
		(width 0.12954)
		(layer "F.Cu")
		(net "M_A_CPU1_SA_DQS_DP<3>")
	)
	(segment
		(start 65.88379 -234.986068)
		(end 65.432686 -234.986068)
		(width 0.12954)
		(layer "F.Cu")
		(net "M_A_CPU1_SA_DQS_DP<3>")
	)
	(segment
		(start 67.365626 -236.919008)
		(end 67.365626 -236.467904)
		(width 0.12954)
		(layer "F.Cu")
		(net "M_A_CPU1_SA_DQS_DP<3>")
	)
	(segment
		(start 65.092326 -234.194604)
		(end 64.74714 -233.849418)
		(width 0.12954)
		(layer "F.Cu")
		(net "M_A_CPU1_SA_DQS_DP<3>")
	)
	(segment
		(start 63.955676 -233.509058)
		(end 63.955676 -233.057954)
		(width 0.12954)
		(layer "F.Cu")
		(net "M_A_CPU1_SA_DQS_DP<3>")
	)
	(segment
		(start 60.734194 -229.049072)
		(end 60.226448 -229.049072)
		(width 0.12954)
		(layer "F.Cu")
		(net "M_A_CPU1_SA_DQS_DP<3>")
	)
	(segment
		(start 67.213734 -237.0709)
		(end 67.365626 -236.919008)
		(width 0.12954)
		(layer "F.Cu")
		(net "M_A_CPU1_SA_DQS_DP<3>")
	)
	(segment
		(start 68.842636 -238.396018)
		(end 68.690744 -238.54791)
		(width 0.12954)
		(layer "F.Cu")
		(net "M_A_CPU1_SA_DQS_DP<3>")
	)
	(segment
		(start 67.365626 -236.467904)
		(end 67.02044 -236.122718)
		(width 0.12954)
		(layer "F.Cu")
		(net "M_A_CPU1_SA_DQS_DP<3>")
	)
	(segment
		(start 70.623684 -240.48085)
		(end 70.775576 -240.328958)
		(width 0.12954)
		(layer "F.Cu")
		(net "M_A_CPU1_SA_DQS_DP<3>")
	)
	(segment
		(start 69.827394 -239.68456)
		(end 69.645022 -239.68456)
		(width 0.12954)
		(layer "F.Cu")
		(net "M_A_CPU1_SA_DQS_DP<3>")
	)
	(segment
		(start 68.350384 -238.389922)
		(end 68.350384 -238.20755)
		(width 0.12954)
		(layer "F.Cu")
		(net "M_A_CPU1_SA_DQS_DP<3>")
	)
	(segment
		(start 69.487034 -239.3442)
		(end 69.638926 -239.192308)
		(width 0.12954)
		(layer "F.Cu")
		(net "M_A_CPU1_SA_DQS_DP<3>")
	)
	(segment
		(start 75.974956 -241.944398)
		(end 75.955906 -241.944398)
		(width 0.0762)
		(layer "F.Cu")
		(net "M_A_CPU1_SA_DQS_DP<3>")
	)
	(segment
		(start 68.502276 -237.604554)
		(end 68.15709 -237.259368)
		(width 0.12954)
		(layer "F.Cu")
		(net "M_A_CPU1_SA_DQS_DP<3>")
	)
	(segment
		(start 66.077084 -235.93425)
		(end 66.228976 -235.782358)
		(width 0.12954)
		(layer "F.Cu")
		(net "M_A_CPU1_SA_DQS_DP<3>")
	)
	(segment
		(start 65.432686 -234.986068)
		(end 65.280794 -235.13796)
		(width 0.12954)
		(layer "F.Cu")
		(net "M_A_CPU1_SA_DQS_DP<3>")
	)
	(segment
		(start 65.280794 -235.13796)
		(end 65.098422 -235.13796)
		(width 0.12954)
		(layer "F.Cu")
		(net "M_A_CPU1_SA_DQS_DP<3>")
	)
	(segment
		(start 67.554094 -237.41126)
		(end 67.371722 -237.41126)
		(width 0.12954)
		(layer "F.Cu")
		(net "M_A_CPU1_SA_DQS_DP<3>")
	)
	(segment
		(start 69.638926 -238.741204)
		(end 69.29374 -238.396018)
		(width 0.12954)
		(layer "F.Cu")
		(net "M_A_CPU1_SA_DQS_DP<3>")
	)
	(segment
		(start 69.638926 -239.192308)
		(end 69.638926 -238.741204)
		(width 0.12954)
		(layer "F.Cu")
		(net "M_A_CPU1_SA_DQS_DP<3>")
	)
	(segment
		(start 64.940434 -234.979972)
		(end 64.940434 -234.7976)
		(width 0.12954)
		(layer "F.Cu")
		(net "M_A_CPU1_SA_DQS_DP<3>")
	)
	(segment
		(start 66.228976 -235.331254)
		(end 65.88379 -234.986068)
		(width 0.12954)
		(layer "F.Cu")
		(net "M_A_CPU1_SA_DQS_DP<3>")
	)
	(segment
		(start 67.705986 -237.259368)
		(end 67.554094 -237.41126)
		(width 0.12954)
		(layer "F.Cu")
		(net "M_A_CPU1_SA_DQS_DP<3>")
	)
	(segment
		(start 64.144144 -234.00131)
		(end 63.961772 -234.00131)
		(width 0.12954)
		(layer "F.Cu")
		(net "M_A_CPU1_SA_DQS_DP<3>")
	)
	(segment
		(start 75.955906 -241.944398)
		(end 72.84212 -241.944398)
		(width 0.12954)
		(layer "F.Cu")
		(net "M_A_CPU1_SA_DQS_DP<3>")
	)
	(segment
		(start 63.961772 -234.00131)
		(end 63.803784 -233.843322)
		(width 0.12954)
		(layer "F.Cu")
		(net "M_A_CPU1_SA_DQS_DP<3>")
	)
	(segment
		(start 65.092326 -234.645708)
		(end 65.092326 -234.194604)
		(width 0.12954)
		(layer "F.Cu")
		(net "M_A_CPU1_SA_DQS_DP<3>")
	)
	(segment
		(start 69.979286 -239.532668)
		(end 69.827394 -239.68456)
		(width 0.12954)
		(layer "F.Cu")
		(net "M_A_CPU1_SA_DQS_DP<3>")
	)
	(segment
		(start 63.803784 -233.66095)
		(end 63.955676 -233.509058)
		(width 0.12954)
		(layer "F.Cu")
		(net "M_A_CPU1_SA_DQS_DP<3>")
	)
	(segment
		(start 70.623684 -240.663222)
		(end 70.623684 -240.48085)
		(width 0.12954)
		(layer "F.Cu")
		(net "M_A_CPU1_SA_DQS_DP<3>")
	)
	(segment
		(start 66.228976 -235.782358)
		(end 66.228976 -235.331254)
		(width 0.12954)
		(layer "F.Cu")
		(net "M_A_CPU1_SA_DQS_DP<3>")
	)
	(segment
		(start 59.962796 -228.78542)
		(end 59.428126 -228.78542)
		(width 0.12954)
		(layer "F.Cu")
		(net "M_A_CPU1_SA_DQS_DP<3>")
	)
	(segment
		(start 70.43039 -239.532668)
		(end 69.979286 -239.532668)
		(width 0.12954)
		(layer "F.Cu")
		(net "M_A_CPU1_SA_DQS_DP<3>")
	)
	(segment
		(start 64.940434 -234.7976)
		(end 65.092326 -234.645708)
		(width 0.12954)
		(layer "F.Cu")
		(net "M_A_CPU1_SA_DQS_DP<3>")
	)
	(segment
		(start 61.948822 -230.2637)
		(end 60.734194 -229.049072)
		(width 0.12954)
		(layer "F.Cu")
		(net "M_A_CPU1_SA_DQS_DP<3>")
	)
	(segment
		(start 69.645022 -239.68456)
		(end 69.487034 -239.526572)
		(width 0.12954)
		(layer "F.Cu")
		(net "M_A_CPU1_SA_DQS_DP<3>")
	)
	(segment
		(start 66.417444 -236.27461)
		(end 66.235072 -236.27461)
		(width 0.12954)
		(layer "F.Cu")
		(net "M_A_CPU1_SA_DQS_DP<3>")
	)
	(segment
		(start 64.296036 -233.849418)
		(end 64.144144 -234.00131)
		(width 0.12954)
		(layer "F.Cu")
		(net "M_A_CPU1_SA_DQS_DP<3>")
	)
	(segment
		(start 63.955676 -233.057954)
		(end 61.948822 -231.0511)
		(width 0.12954)
		(layer "F.Cu")
		(net "M_A_CPU1_SA_DQS_DP<3>")
	)
	(segment
		(start 66.077084 -236.116622)
		(end 66.077084 -235.93425)
		(width 0.12954)
		(layer "F.Cu")
		(net "M_A_CPU1_SA_DQS_DP<3>")
	)
	(segment
		(start 70.781672 -240.82121)
		(end 70.623684 -240.663222)
		(width 0.12954)
		(layer "F.Cu")
		(net "M_A_CPU1_SA_DQS_DP<3>")
	)
	(segment
		(start 70.775576 -240.328958)
		(end 70.775576 -239.877854)
		(width 0.12954)
		(layer "F.Cu")
		(net "M_A_CPU1_SA_DQS_DP<3>")
	)
	(segment
		(start 67.02044 -236.122718)
		(end 66.569336 -236.122718)
		(width 0.12954)
		(layer "F.Cu")
		(net "M_A_CPU1_SA_DQS_DP<3>")
	)
	(segment
		(start 68.508372 -238.54791)
		(end 68.350384 -238.389922)
		(width 0.12954)
		(layer "F.Cu")
		(net "M_A_CPU1_SA_DQS_DP<3>")
	)
	(segment
		(start 64.74714 -233.849418)
		(end 64.296036 -233.849418)
		(width 0.12954)
		(layer "F.Cu")
		(net "M_A_CPU1_SA_DQS_DP<3>")
	)
	(segment
		(start 71.56704 -240.669318)
		(end 71.115936 -240.669318)
		(width 0.12954)
		(layer "F.Cu")
		(net "M_A_CPU1_SA_DQS_DP<3>")
	)
	(segment
		(start 70.775576 -239.877854)
		(end 70.43039 -239.532668)
		(width 0.12954)
		(layer "F.Cu")
		(net "M_A_CPU1_SA_DQS_DP<3>")
	)
	(segment
		(start 76.628752 -241.883438)
		(end 76.501752 -242.010438)
		(width 0.0762)
		(layer "F.Cu")
		(net "M_A_CPU1_SA_DQS_DP<3>")
	)
	(segment
		(start 69.29374 -238.396018)
		(end 68.842636 -238.396018)
		(width 0.12954)
		(layer "F.Cu")
		(net "M_A_CPU1_SA_DQS_DP<3>")
	)
	(segment
		(start 71.115936 -240.669318)
		(end 70.964044 -240.82121)
		(width 0.12954)
		(layer "F.Cu")
		(net "M_A_CPU1_SA_DQS_DP<3>")
	)
	(segment
		(start 69.487034 -239.526572)
		(end 69.487034 -239.3442)
		(width 0.12954)
		(layer "F.Cu")
		(net "M_A_CPU1_SA_DQS_DP<3>")
	)
	(segment
		(start 68.690744 -238.54791)
		(end 68.508372 -238.54791)
		(width 0.12954)
		(layer "F.Cu")
		(net "M_A_CPU1_SA_DQS_DP<3>")
	)
	(segment
		(start 60.226448 -229.049072)
		(end 59.962796 -228.78542)
		(width 0.12954)
		(layer "F.Cu")
		(net "M_A_CPU1_SA_DQS_DP<3>")
	)
	(segment
		(start 67.371722 -237.41126)
		(end 67.213734 -237.253272)
		(width 0.12954)
		(layer "F.Cu")
		(net "M_A_CPU1_SA_DQS_DP<3>")
	)
	(segment
		(start 72.84212 -241.944398)
		(end 71.56704 -240.669318)
		(width 0.12954)
		(layer "F.Cu")
		(net "M_A_CPU1_SA_DQS_DP<3>")
	)
	(segment
		(start 63.803784 -233.843322)
		(end 63.803784 -233.66095)
		(width 0.12954)
		(layer "F.Cu")
		(net "M_A_CPU1_SA_DQS_DP<3>")
	)
	(segment
		(start 70.964044 -240.82121)
		(end 70.781672 -240.82121)
		(width 0.12954)
		(layer "F.Cu")
		(net "M_A_CPU1_SA_DQS_DP<3>")
	)
	(arc
		(start 78.408022 -241.510312)
		(mid 78.165705 -241.680032)
		(end 77.880718 -241.759486)
		(width 0.0762)
		(layer "F.Cu")
		(net "M_A_CPU1_SA_DQS_DP<3>")
	)
	(arc
		(start 77.654912 -241.832892)
		(mid 77.564779 -241.870512)
		(end 77.467968 -241.883438)
		(width 0.0762)
		(layer "F.Cu")
		(net "M_A_CPU1_SA_DQS_DP<3>")
	)
	(arc
		(start 77.880718 -241.759486)
		(mid 77.763905 -241.784162)
		(end 77.654912 -241.832892)
		(width 0.0762)
		(layer "F.Cu")
		(net "M_A_CPU1_SA_DQS_DP<3>")
	)
	(segment
		(start 63.774828 -220.034104)
		(end 63.32474 -220.034104)
		(width 0.12954)
		(layer "F.Cu")
		(net "M_A_CPU1_SA_DQS_DP<2>")
	)
	(segment
		(start 65.906396 -223.592644)
		(end 66.394838 -223.104202)
		(width 0.12954)
		(layer "F.Cu")
		(net "M_A_CPU1_SA_DQS_DP<2>")
	)
	(segment
		(start 76.167996 -237.102904)
		(end 76.148946 -237.102904)
		(width 0.0762)
		(layer "F.Cu")
		(net "M_A_CPU1_SA_DQS_DP<2>")
	)
	(segment
		(start 63.78956 -221.659196)
		(end 63.633096 -221.502732)
		(width 0.12954)
		(layer "F.Cu")
		(net "M_A_CPU1_SA_DQS_DP<2>")
	)
	(segment
		(start 74.350626 -237.102904)
		(end 66.41084 -229.163118)
		(width 0.12954)
		(layer "F.Cu")
		(net "M_A_CPU1_SA_DQS_DP<2>")
	)
	(segment
		(start 66.41084 -229.163118)
		(end 66.41084 -224.280476)
		(width 0.12954)
		(layer "F.Cu")
		(net "M_A_CPU1_SA_DQS_DP<2>")
	)
	(segment
		(start 64.121538 -220.380814)
		(end 63.774828 -220.034104)
		(width 0.12954)
		(layer "F.Cu")
		(net "M_A_CPU1_SA_DQS_DP<2>")
	)
	(segment
		(start 66.41084 -224.280476)
		(end 65.906396 -223.776032)
		(width 0.12954)
		(layer "F.Cu")
		(net "M_A_CPU1_SA_DQS_DP<2>")
	)
	(segment
		(start 63.633096 -221.502732)
		(end 63.633096 -221.319344)
		(width 0.12954)
		(layer "F.Cu")
		(net "M_A_CPU1_SA_DQS_DP<2>")
	)
	(segment
		(start 62.65291 -220.522546)
		(end 61.829442 -219.699078)
		(width 0.12954)
		(layer "F.Cu")
		(net "M_A_CPU1_SA_DQS_DP<2>")
	)
	(segment
		(start 66.048128 -222.307404)
		(end 65.59804 -222.307404)
		(width 0.12954)
		(layer "F.Cu")
		(net "M_A_CPU1_SA_DQS_DP<2>")
	)
	(segment
		(start 65.109598 -222.795846)
		(end 64.92621 -222.795846)
		(width 0.12954)
		(layer "F.Cu")
		(net "M_A_CPU1_SA_DQS_DP<2>")
	)
	(segment
		(start 76.234036 -237.168944)
		(end 76.167996 -237.102904)
		(width 0.0762)
		(layer "F.Cu")
		(net "M_A_CPU1_SA_DQS_DP<2>")
	)
	(segment
		(start 63.972948 -221.659196)
		(end 63.78956 -221.659196)
		(width 0.12954)
		(layer "F.Cu")
		(net "M_A_CPU1_SA_DQS_DP<2>")
	)
	(segment
		(start 65.906396 -223.776032)
		(end 65.906396 -223.592644)
		(width 0.12954)
		(layer "F.Cu")
		(net "M_A_CPU1_SA_DQS_DP<2>")
	)
	(segment
		(start 66.394838 -222.654114)
		(end 66.048128 -222.307404)
		(width 0.12954)
		(layer "F.Cu")
		(net "M_A_CPU1_SA_DQS_DP<2>")
	)
	(segment
		(start 76.354178 -237.168944)
		(end 76.234036 -237.168944)
		(width 0.0762)
		(layer "F.Cu")
		(net "M_A_CPU1_SA_DQS_DP<2>")
	)
	(segment
		(start 76.148946 -237.102904)
		(end 74.350626 -237.102904)
		(width 0.12954)
		(layer "F.Cu")
		(net "M_A_CPU1_SA_DQS_DP<2>")
	)
	(segment
		(start 63.32474 -220.034104)
		(end 62.836298 -220.522546)
		(width 0.12954)
		(layer "F.Cu")
		(net "M_A_CPU1_SA_DQS_DP<2>")
	)
	(segment
		(start 65.59804 -222.307404)
		(end 65.109598 -222.795846)
		(width 0.12954)
		(layer "F.Cu")
		(net "M_A_CPU1_SA_DQS_DP<2>")
	)
	(segment
		(start 64.62776 -221.004384)
		(end 63.972948 -221.659196)
		(width 0.12954)
		(layer "F.Cu")
		(net "M_A_CPU1_SA_DQS_DP<2>")
	)
	(segment
		(start 77.467968 -237.023402)
		(end 76.49972 -237.023402)
		(width 0.0762)
		(layer "F.Cu")
		(net "M_A_CPU1_SA_DQS_DP<2>")
	)
	(segment
		(start 60.226448 -219.699078)
		(end 59.962796 -219.435426)
		(width 0.12954)
		(layer "F.Cu")
		(net "M_A_CPU1_SA_DQS_DP<2>")
	)
	(segment
		(start 65.077848 -221.004384)
		(end 64.62776 -221.004384)
		(width 0.12954)
		(layer "F.Cu")
		(net "M_A_CPU1_SA_DQS_DP<2>")
	)
	(segment
		(start 59.962796 -219.435426)
		(end 59.428126 -219.435426)
		(width 0.12954)
		(layer "F.Cu")
		(net "M_A_CPU1_SA_DQS_DP<2>")
	)
	(segment
		(start 62.836298 -220.522546)
		(end 62.65291 -220.522546)
		(width 0.12954)
		(layer "F.Cu")
		(net "M_A_CPU1_SA_DQS_DP<2>")
	)
	(segment
		(start 65.424558 -221.801182)
		(end 65.424558 -221.351094)
		(width 0.12954)
		(layer "F.Cu")
		(net "M_A_CPU1_SA_DQS_DP<2>")
	)
	(segment
		(start 64.92621 -222.795846)
		(end 64.769746 -222.639382)
		(width 0.12954)
		(layer "F.Cu")
		(net "M_A_CPU1_SA_DQS_DP<2>")
	)
	(segment
		(start 63.633096 -221.319344)
		(end 64.121538 -220.830902)
		(width 0.12954)
		(layer "F.Cu")
		(net "M_A_CPU1_SA_DQS_DP<2>")
	)
	(segment
		(start 76.49972 -237.023402)
		(end 76.354178 -237.168944)
		(width 0.0762)
		(layer "F.Cu")
		(net "M_A_CPU1_SA_DQS_DP<2>")
	)
	(segment
		(start 66.394838 -223.104202)
		(end 66.394838 -222.654114)
		(width 0.12954)
		(layer "F.Cu")
		(net "M_A_CPU1_SA_DQS_DP<2>")
	)
	(segment
		(start 65.424558 -221.351094)
		(end 65.077848 -221.004384)
		(width 0.12954)
		(layer "F.Cu")
		(net "M_A_CPU1_SA_DQS_DP<2>")
	)
	(segment
		(start 64.769746 -222.455994)
		(end 65.424558 -221.801182)
		(width 0.12954)
		(layer "F.Cu")
		(net "M_A_CPU1_SA_DQS_DP<2>")
	)
	(segment
		(start 61.829442 -219.699078)
		(end 60.226448 -219.699078)
		(width 0.12954)
		(layer "F.Cu")
		(net "M_A_CPU1_SA_DQS_DP<2>")
	)
	(segment
		(start 64.769746 -222.639382)
		(end 64.769746 -222.455994)
		(width 0.12954)
		(layer "F.Cu")
		(net "M_A_CPU1_SA_DQS_DP<2>")
	)
	(segment
		(start 64.121538 -220.830902)
		(end 64.121538 -220.380814)
		(width 0.12954)
		(layer "F.Cu")
		(net "M_A_CPU1_SA_DQS_DP<2>")
	)
	(arc
		(start 77.654912 -236.972856)
		(mid 77.564779 -237.010476)
		(end 77.467968 -237.023402)
		(width 0.0762)
		(layer "F.Cu")
		(net "M_A_CPU1_SA_DQS_DP<2>")
	)
	(arc
		(start 77.880718 -236.89945)
		(mid 77.763905 -236.924126)
		(end 77.654912 -236.972856)
		(width 0.0762)
		(layer "F.Cu")
		(net "M_A_CPU1_SA_DQS_DP<2>")
	)
	(arc
		(start 78.408022 -236.650276)
		(mid 78.165705 -236.819996)
		(end 77.880718 -236.89945)
		(width 0.0762)
		(layer "F.Cu")
		(net "M_A_CPU1_SA_DQS_DP<2>")
	)
	(segment
		(start 68.459604 -216.72169)
		(end 68.676012 -216.505282)
		(width 0.12954)
		(layer "F.Cu")
		(net "M_A_CPU1_SA_DQS_DP<1>")
	)
	(segment
		(start 63.913004 -212.17509)
		(end 64.030606 -212.057488)
		(width 0.12954)
		(layer "F.Cu")
		(net "M_A_CPU1_SA_DQS_DP<1>")
	)
	(segment
		(start 69.596254 -218.041728)
		(end 69.596254 -217.85834)
		(width 0.12954)
		(layer "F.Cu")
		(net "M_A_CPU1_SA_DQS_DP<1>")
	)
	(segment
		(start 68.616068 -217.061542)
		(end 68.459604 -216.905078)
		(width 0.12954)
		(layer "F.Cu")
		(net "M_A_CPU1_SA_DQS_DP<1>")
	)
	(segment
		(start 66.526156 -214.788242)
		(end 66.342768 -214.788242)
		(width 0.12954)
		(layer "F.Cu")
		(net "M_A_CPU1_SA_DQS_DP<1>")
	)
	(segment
		(start 68.676012 -216.505282)
		(end 68.676012 -216.055194)
		(width 0.12954)
		(layer "F.Cu")
		(net "M_A_CPU1_SA_DQS_DP<1>")
	)
	(segment
		(start 63.913004 -212.358478)
		(end 63.913004 -212.17509)
		(width 0.12954)
		(layer "F.Cu")
		(net "M_A_CPU1_SA_DQS_DP<1>")
	)
	(segment
		(start 63.116206 -211.378292)
		(end 62.932818 -211.378292)
		(width 0.12954)
		(layer "F.Cu")
		(net "M_A_CPU1_SA_DQS_DP<1>")
	)
	(segment
		(start 64.030606 -211.6074)
		(end 63.683896 -211.26069)
		(width 0.12954)
		(layer "F.Cu")
		(net "M_A_CPU1_SA_DQS_DP<1>")
	)
	(segment
		(start 64.919352 -212.298534)
		(end 64.469264 -212.298534)
		(width 0.12954)
		(layer "F.Cu")
		(net "M_A_CPU1_SA_DQS_DP<1>")
	)
	(segment
		(start 68.329302 -215.708484)
		(end 67.879214 -215.708484)
		(width 0.12954)
		(layer "F.Cu")
		(net "M_A_CPU1_SA_DQS_DP<1>")
	)
	(segment
		(start 67.662806 -215.924892)
		(end 67.479418 -215.924892)
		(width 0.12954)
		(layer "F.Cu")
		(net "M_A_CPU1_SA_DQS_DP<1>")
	)
	(segment
		(start 64.469264 -212.298534)
		(end 64.252856 -212.514942)
		(width 0.12954)
		(layer "F.Cu")
		(net "M_A_CPU1_SA_DQS_DP<1>")
	)
	(segment
		(start 65.266062 -212.645244)
		(end 64.919352 -212.298534)
		(width 0.12954)
		(layer "F.Cu")
		(net "M_A_CPU1_SA_DQS_DP<1>")
	)
	(segment
		(start 59.962796 -210.085432)
		(end 59.428126 -210.085432)
		(width 0.12954)
		(layer "F.Cu")
		(net "M_A_CPU1_SA_DQS_DP<1>")
	)
	(segment
		(start 67.539362 -215.368632)
		(end 67.539362 -214.918544)
		(width 0.12954)
		(layer "F.Cu")
		(net "M_A_CPU1_SA_DQS_DP<1>")
	)
	(segment
		(start 64.030606 -212.057488)
		(end 64.030606 -211.6074)
		(width 0.12954)
		(layer "F.Cu")
		(net "M_A_CPU1_SA_DQS_DP<1>")
	)
	(segment
		(start 63.683896 -211.26069)
		(end 63.233808 -211.26069)
		(width 0.12954)
		(layer "F.Cu")
		(net "M_A_CPU1_SA_DQS_DP<1>")
	)
	(segment
		(start 68.676012 -216.055194)
		(end 68.329302 -215.708484)
		(width 0.12954)
		(layer "F.Cu")
		(net "M_A_CPU1_SA_DQS_DP<1>")
	)
	(segment
		(start 77.467968 -232.163366)
		(end 76.263246 -232.163366)
		(width 0.0762)
		(layer "F.Cu")
		(net "M_A_CPU1_SA_DQS_DP<1>")
	)
	(segment
		(start 65.266062 -213.095332)
		(end 65.266062 -212.645244)
		(width 0.12954)
		(layer "F.Cu")
		(net "M_A_CPU1_SA_DQS_DP<1>")
	)
	(segment
		(start 60.789058 -210.349084)
		(end 60.226448 -210.349084)
		(width 0.12954)
		(layer "F.Cu")
		(net "M_A_CPU1_SA_DQS_DP<1>")
	)
	(segment
		(start 70.79742 -219.242894)
		(end 69.596254 -218.041728)
		(width 0.12954)
		(layer "F.Cu")
		(net "M_A_CPU1_SA_DQS_DP<1>")
	)
	(segment
		(start 62.711076 -211.15655)
		(end 61.596524 -211.15655)
		(width 0.12954)
		(layer "F.Cu")
		(net "M_A_CPU1_SA_DQS_DP<1>")
	)
	(segment
		(start 60.226448 -210.349084)
		(end 59.962796 -210.085432)
		(width 0.12954)
		(layer "F.Cu")
		(net "M_A_CPU1_SA_DQS_DP<1>")
	)
	(segment
		(start 66.186304 -214.631778)
		(end 66.186304 -214.44839)
		(width 0.12954)
		(layer "F.Cu")
		(net "M_A_CPU1_SA_DQS_DP<1>")
	)
	(segment
		(start 65.389506 -213.651592)
		(end 65.206118 -213.651592)
		(width 0.12954)
		(layer "F.Cu")
		(net "M_A_CPU1_SA_DQS_DP<1>")
	)
	(segment
		(start 64.069468 -212.514942)
		(end 63.913004 -212.358478)
		(width 0.12954)
		(layer "F.Cu")
		(net "M_A_CPU1_SA_DQS_DP<1>")
	)
	(segment
		(start 61.596524 -211.15655)
		(end 60.789058 -210.349084)
		(width 0.12954)
		(layer "F.Cu")
		(net "M_A_CPU1_SA_DQS_DP<1>")
	)
	(segment
		(start 67.322954 -215.768428)
		(end 67.322954 -215.58504)
		(width 0.12954)
		(layer "F.Cu")
		(net "M_A_CPU1_SA_DQS_DP<1>")
	)
	(segment
		(start 63.233808 -211.26069)
		(end 63.116206 -211.378292)
		(width 0.12954)
		(layer "F.Cu")
		(net "M_A_CPU1_SA_DQS_DP<1>")
	)
	(segment
		(start 69.596254 -217.85834)
		(end 69.812662 -217.641932)
		(width 0.12954)
		(layer "F.Cu")
		(net "M_A_CPU1_SA_DQS_DP<1>")
	)
	(segment
		(start 67.879214 -215.708484)
		(end 67.662806 -215.924892)
		(width 0.12954)
		(layer "F.Cu")
		(net "M_A_CPU1_SA_DQS_DP<1>")
	)
	(segment
		(start 64.252856 -212.514942)
		(end 64.069468 -212.514942)
		(width 0.12954)
		(layer "F.Cu")
		(net "M_A_CPU1_SA_DQS_DP<1>")
	)
	(segment
		(start 67.192652 -214.571834)
		(end 66.742564 -214.571834)
		(width 0.12954)
		(layer "F.Cu")
		(net "M_A_CPU1_SA_DQS_DP<1>")
	)
	(segment
		(start 66.742564 -214.571834)
		(end 66.526156 -214.788242)
		(width 0.12954)
		(layer "F.Cu")
		(net "M_A_CPU1_SA_DQS_DP<1>")
	)
	(segment
		(start 67.539362 -214.918544)
		(end 67.192652 -214.571834)
		(width 0.12954)
		(layer "F.Cu")
		(net "M_A_CPU1_SA_DQS_DP<1>")
	)
	(segment
		(start 70.79742 -227.301298)
		(end 70.79742 -219.242894)
		(width 0.12954)
		(layer "F.Cu")
		(net "M_A_CPU1_SA_DQS_DP<1>")
	)
	(segment
		(start 76.263246 -232.163366)
		(end 76.197206 -232.097326)
		(width 0.0762)
		(layer "F.Cu")
		(net "M_A_CPU1_SA_DQS_DP<1>")
	)
	(segment
		(start 65.605914 -213.435184)
		(end 65.389506 -213.651592)
		(width 0.12954)
		(layer "F.Cu")
		(net "M_A_CPU1_SA_DQS_DP<1>")
	)
	(segment
		(start 65.049654 -213.31174)
		(end 65.266062 -213.095332)
		(width 0.12954)
		(layer "F.Cu")
		(net "M_A_CPU1_SA_DQS_DP<1>")
	)
	(segment
		(start 69.812662 -217.191844)
		(end 69.465952 -216.845134)
		(width 0.12954)
		(layer "F.Cu")
		(net "M_A_CPU1_SA_DQS_DP<1>")
	)
	(segment
		(start 68.459604 -216.905078)
		(end 68.459604 -216.72169)
		(width 0.12954)
		(layer "F.Cu")
		(net "M_A_CPU1_SA_DQS_DP<1>")
	)
	(segment
		(start 76.178156 -232.097326)
		(end 75.593448 -232.097326)
		(width 0.12954)
		(layer "F.Cu")
		(net "M_A_CPU1_SA_DQS_DP<1>")
	)
	(segment
		(start 62.932818 -211.378292)
		(end 62.711076 -211.15655)
		(width 0.12954)
		(layer "F.Cu")
		(net "M_A_CPU1_SA_DQS_DP<1>")
	)
	(segment
		(start 68.799456 -217.061542)
		(end 68.616068 -217.061542)
		(width 0.12954)
		(layer "F.Cu")
		(net "M_A_CPU1_SA_DQS_DP<1>")
	)
	(segment
		(start 66.056002 -213.435184)
		(end 65.605914 -213.435184)
		(width 0.12954)
		(layer "F.Cu")
		(net "M_A_CPU1_SA_DQS_DP<1>")
	)
	(segment
		(start 69.465952 -216.845134)
		(end 69.015864 -216.845134)
		(width 0.12954)
		(layer "F.Cu")
		(net "M_A_CPU1_SA_DQS_DP<1>")
	)
	(segment
		(start 65.049654 -213.495128)
		(end 65.049654 -213.31174)
		(width 0.12954)
		(layer "F.Cu")
		(net "M_A_CPU1_SA_DQS_DP<1>")
	)
	(segment
		(start 69.812662 -217.641932)
		(end 69.812662 -217.191844)
		(width 0.12954)
		(layer "F.Cu")
		(net "M_A_CPU1_SA_DQS_DP<1>")
	)
	(segment
		(start 76.197206 -232.097326)
		(end 76.178156 -232.097326)
		(width 0.0762)
		(layer "F.Cu")
		(net "M_A_CPU1_SA_DQS_DP<1>")
	)
	(segment
		(start 67.322954 -215.58504)
		(end 67.539362 -215.368632)
		(width 0.12954)
		(layer "F.Cu")
		(net "M_A_CPU1_SA_DQS_DP<1>")
	)
	(segment
		(start 66.186304 -214.44839)
		(end 66.402712 -214.231982)
		(width 0.12954)
		(layer "F.Cu")
		(net "M_A_CPU1_SA_DQS_DP<1>")
	)
	(segment
		(start 67.479418 -215.924892)
		(end 67.322954 -215.768428)
		(width 0.12954)
		(layer "F.Cu")
		(net "M_A_CPU1_SA_DQS_DP<1>")
	)
	(segment
		(start 66.402712 -214.231982)
		(end 66.402712 -213.781894)
		(width 0.12954)
		(layer "F.Cu")
		(net "M_A_CPU1_SA_DQS_DP<1>")
	)
	(segment
		(start 65.206118 -213.651592)
		(end 65.049654 -213.495128)
		(width 0.12954)
		(layer "F.Cu")
		(net "M_A_CPU1_SA_DQS_DP<1>")
	)
	(segment
		(start 75.593448 -232.097326)
		(end 70.79742 -227.301298)
		(width 0.12954)
		(layer "F.Cu")
		(net "M_A_CPU1_SA_DQS_DP<1>")
	)
	(segment
		(start 66.402712 -213.781894)
		(end 66.056002 -213.435184)
		(width 0.12954)
		(layer "F.Cu")
		(net "M_A_CPU1_SA_DQS_DP<1>")
	)
	(segment
		(start 66.342768 -214.788242)
		(end 66.186304 -214.631778)
		(width 0.12954)
		(layer "F.Cu")
		(net "M_A_CPU1_SA_DQS_DP<1>")
	)
	(segment
		(start 69.015864 -216.845134)
		(end 68.799456 -217.061542)
		(width 0.12954)
		(layer "F.Cu")
		(net "M_A_CPU1_SA_DQS_DP<1>")
	)
	(arc
		(start 78.408022 -231.79024)
		(mid 78.165705 -231.95996)
		(end 77.880718 -232.039414)
		(width 0.0762)
		(layer "F.Cu")
		(net "M_A_CPU1_SA_DQS_DP<1>")
	)
	(arc
		(start 77.880718 -232.039414)
		(mid 77.763905 -232.06409)
		(end 77.654912 -232.11282)
		(width 0.0762)
		(layer "F.Cu")
		(net "M_A_CPU1_SA_DQS_DP<1>")
	)
	(arc
		(start 77.654912 -232.11282)
		(mid 77.564779 -232.15044)
		(end 77.467968 -232.163366)
		(width 0.0762)
		(layer "F.Cu")
		(net "M_A_CPU1_SA_DQS_DP<1>")
	)
	(segment
		(start 66.014092 -205.648814)
		(end 65.418716 -205.648814)
		(width 0.12954)
		(layer "F.Cu")
		(net "M_A_CPU1_SA_DQS_DP<0>")
	)
	(segment
		(start 69.788278 -210.018376)
		(end 69.788278 -209.423)
		(width 0.12954)
		(layer "F.Cu")
		(net "M_A_CPU1_SA_DQS_DP<0>")
	)
	(segment
		(start 64.105028 -204.335126)
		(end 64.105028 -203.73975)
		(width 0.12954)
		(layer "F.Cu")
		(net "M_A_CPU1_SA_DQS_DP<0>")
	)
	(segment
		(start 73.517506 -214.418672)
		(end 73.925176 -214.011002)
		(width 0.12954)
		(layer "F.Cu")
		(net "M_A_CPU1_SA_DQS_DP<0>")
	)
	(segment
		(start 64.282066 -204.512164)
		(end 64.105028 -204.335126)
		(width 0.12954)
		(layer "F.Cu")
		(net "M_A_CPU1_SA_DQS_DP<0>")
	)
	(segment
		(start 66.378328 -206.01305)
		(end 66.014092 -205.648814)
		(width 0.12954)
		(layer "F.Cu")
		(net "M_A_CPU1_SA_DQS_DP<0>")
	)
	(segment
		(start 69.788278 -209.423)
		(end 69.424042 -209.058764)
		(width 0.12954)
		(layer "F.Cu")
		(net "M_A_CPU1_SA_DQS_DP<0>")
	)
	(segment
		(start 73.675494 -214.759032)
		(end 73.517506 -214.601044)
		(width 0.12954)
		(layer "F.Cu")
		(net "M_A_CPU1_SA_DQS_DP<0>")
	)
	(segment
		(start 76.480924 -226.673156)
		(end 76.480924 -226.67341)
		(width 0.12954)
		(layer "F.Cu")
		(net "M_A_CPU1_SA_DQS_DP<0>")
	)
	(segment
		(start 65.241678 -204.8764)
		(end 64.877442 -204.512164)
		(width 0.12954)
		(layer "F.Cu")
		(net "M_A_CPU1_SA_DQS_DP<0>")
	)
	(segment
		(start 68.651628 -208.881726)
		(end 68.651628 -208.28635)
		(width 0.12954)
		(layer "F.Cu")
		(net "M_A_CPU1_SA_DQS_DP<0>")
	)
	(segment
		(start 67.514978 -207.745076)
		(end 67.514978 -207.1497)
		(width 0.12954)
		(layer "F.Cu")
		(net "M_A_CPU1_SA_DQS_DP<0>")
	)
	(segment
		(start 68.828666 -209.058764)
		(end 68.651628 -208.881726)
		(width 0.12954)
		(layer "F.Cu")
		(net "M_A_CPU1_SA_DQS_DP<0>")
	)
	(segment
		(start 68.287392 -207.922114)
		(end 67.692016 -207.922114)
		(width 0.12954)
		(layer "F.Cu")
		(net "M_A_CPU1_SA_DQS_DP<0>")
	)
	(segment
		(start 72.061578 -212.291676)
		(end 72.061578 -211.6963)
		(width 0.12954)
		(layer "F.Cu")
		(net "M_A_CPU1_SA_DQS_DP<0>")
	)
	(segment
		(start 64.877442 -204.512164)
		(end 64.282066 -204.512164)
		(width 0.12954)
		(layer "F.Cu")
		(net "M_A_CPU1_SA_DQS_DP<0>")
	)
	(segment
		(start 67.150742 -206.785464)
		(end 66.555366 -206.785464)
		(width 0.12954)
		(layer "F.Cu")
		(net "M_A_CPU1_SA_DQS_DP<0>")
	)
	(segment
		(start 65.241678 -205.471776)
		(end 65.241678 -204.8764)
		(width 0.12954)
		(layer "F.Cu")
		(net "M_A_CPU1_SA_DQS_DP<0>")
	)
	(segment
		(start 62.968378 -203.198476)
		(end 62.968378 -202.6031)
		(width 0.12954)
		(layer "F.Cu")
		(net "M_A_CPU1_SA_DQS_DP<0>")
	)
	(segment
		(start 75.184 -214.818722)
		(end 74.71664 -214.351362)
		(width 0.12954)
		(layer "F.Cu")
		(net "M_A_CPU1_SA_DQS_DP<0>")
	)
	(segment
		(start 77.467968 -227.303584)
		(end 77.017626 -227.303584)
		(width 0.0762)
		(layer "F.Cu")
		(net "M_A_CPU1_SA_DQS_DP<0>")
	)
	(segment
		(start 72.061578 -211.6963)
		(end 71.697342 -211.332064)
		(width 0.12954)
		(layer "F.Cu")
		(net "M_A_CPU1_SA_DQS_DP<0>")
	)
	(segment
		(start 72.238616 -212.468714)
		(end 72.061578 -212.291676)
		(width 0.12954)
		(layer "F.Cu")
		(net "M_A_CPU1_SA_DQS_DP<0>")
	)
	(segment
		(start 69.424042 -209.058764)
		(end 68.828666 -209.058764)
		(width 0.12954)
		(layer "F.Cu")
		(net "M_A_CPU1_SA_DQS_DP<0>")
	)
	(segment
		(start 70.924928 -211.155026)
		(end 70.924928 -210.55965)
		(width 0.12954)
		(layer "F.Cu")
		(net "M_A_CPU1_SA_DQS_DP<0>")
	)
	(segment
		(start 76.494386 -226.780344)
		(end 76.494386 -226.686618)
		(width 0.0762)
		(layer "F.Cu")
		(net "M_A_CPU1_SA_DQS_DP<0>")
	)
	(segment
		(start 72.833992 -212.468714)
		(end 72.238616 -212.468714)
		(width 0.12954)
		(layer "F.Cu")
		(net "M_A_CPU1_SA_DQS_DP<0>")
	)
	(segment
		(start 73.857866 -214.759032)
		(end 73.675494 -214.759032)
		(width 0.12954)
		(layer "F.Cu")
		(net "M_A_CPU1_SA_DQS_DP<0>")
	)
	(segment
		(start 73.925176 -214.011002)
		(end 73.925176 -213.559898)
		(width 0.12954)
		(layer "F.Cu")
		(net "M_A_CPU1_SA_DQS_DP<0>")
	)
	(segment
		(start 59.962796 -200.735438)
		(end 59.428126 -200.735438)
		(width 0.12954)
		(layer "F.Cu")
		(net "M_A_CPU1_SA_DQS_DP<0>")
	)
	(segment
		(start 71.101966 -211.332064)
		(end 70.924928 -211.155026)
		(width 0.12954)
		(layer "F.Cu")
		(net "M_A_CPU1_SA_DQS_DP<0>")
	)
	(segment
		(start 61.364368 -200.99909)
		(end 60.226448 -200.99909)
		(width 0.12954)
		(layer "F.Cu")
		(net "M_A_CPU1_SA_DQS_DP<0>")
	)
	(segment
		(start 77.017626 -227.303584)
		(end 76.494386 -226.780344)
		(width 0.0762)
		(layer "F.Cu")
		(net "M_A_CPU1_SA_DQS_DP<0>")
	)
	(segment
		(start 76.480924 -226.67341)
		(end 75.184 -225.376486)
		(width 0.12954)
		(layer "F.Cu")
		(net "M_A_CPU1_SA_DQS_DP<0>")
	)
	(segment
		(start 62.604142 -202.238864)
		(end 62.008766 -202.238864)
		(width 0.12954)
		(layer "F.Cu")
		(net "M_A_CPU1_SA_DQS_DP<0>")
	)
	(segment
		(start 74.71664 -214.351362)
		(end 74.265536 -214.351362)
		(width 0.12954)
		(layer "F.Cu")
		(net "M_A_CPU1_SA_DQS_DP<0>")
	)
	(segment
		(start 66.378328 -206.608426)
		(end 66.378328 -206.01305)
		(width 0.12954)
		(layer "F.Cu")
		(net "M_A_CPU1_SA_DQS_DP<0>")
	)
	(segment
		(start 67.514978 -207.1497)
		(end 67.150742 -206.785464)
		(width 0.12954)
		(layer "F.Cu")
		(net "M_A_CPU1_SA_DQS_DP<0>")
	)
	(segment
		(start 63.740792 -203.375514)
		(end 63.145416 -203.375514)
		(width 0.12954)
		(layer "F.Cu")
		(net "M_A_CPU1_SA_DQS_DP<0>")
	)
	(segment
		(start 67.692016 -207.922114)
		(end 67.514978 -207.745076)
		(width 0.12954)
		(layer "F.Cu")
		(net "M_A_CPU1_SA_DQS_DP<0>")
	)
	(segment
		(start 62.968378 -202.6031)
		(end 62.604142 -202.238864)
		(width 0.12954)
		(layer "F.Cu")
		(net "M_A_CPU1_SA_DQS_DP<0>")
	)
	(segment
		(start 70.560692 -210.195414)
		(end 69.965316 -210.195414)
		(width 0.12954)
		(layer "F.Cu")
		(net "M_A_CPU1_SA_DQS_DP<0>")
	)
	(segment
		(start 64.105028 -203.73975)
		(end 63.740792 -203.375514)
		(width 0.12954)
		(layer "F.Cu")
		(net "M_A_CPU1_SA_DQS_DP<0>")
	)
	(segment
		(start 65.418716 -205.648814)
		(end 65.241678 -205.471776)
		(width 0.12954)
		(layer "F.Cu")
		(net "M_A_CPU1_SA_DQS_DP<0>")
	)
	(segment
		(start 68.651628 -208.28635)
		(end 68.287392 -207.922114)
		(width 0.12954)
		(layer "F.Cu")
		(net "M_A_CPU1_SA_DQS_DP<0>")
	)
	(segment
		(start 61.831728 -201.46645)
		(end 61.364368 -200.99909)
		(width 0.12954)
		(layer "F.Cu")
		(net "M_A_CPU1_SA_DQS_DP<0>")
	)
	(segment
		(start 73.925176 -213.559898)
		(end 72.833992 -212.468714)
		(width 0.12954)
		(layer "F.Cu")
		(net "M_A_CPU1_SA_DQS_DP<0>")
	)
	(segment
		(start 74.265536 -214.351362)
		(end 73.857866 -214.759032)
		(width 0.12954)
		(layer "F.Cu")
		(net "M_A_CPU1_SA_DQS_DP<0>")
	)
	(segment
		(start 71.697342 -211.332064)
		(end 71.101966 -211.332064)
		(width 0.12954)
		(layer "F.Cu")
		(net "M_A_CPU1_SA_DQS_DP<0>")
	)
	(segment
		(start 61.831728 -202.061826)
		(end 61.831728 -201.46645)
		(width 0.12954)
		(layer "F.Cu")
		(net "M_A_CPU1_SA_DQS_DP<0>")
	)
	(segment
		(start 62.008766 -202.238864)
		(end 61.831728 -202.061826)
		(width 0.12954)
		(layer "F.Cu")
		(net "M_A_CPU1_SA_DQS_DP<0>")
	)
	(segment
		(start 76.494386 -226.686618)
		(end 76.480924 -226.673156)
		(width 0.0762)
		(layer "F.Cu")
		(net "M_A_CPU1_SA_DQS_DP<0>")
	)
	(segment
		(start 66.555366 -206.785464)
		(end 66.378328 -206.608426)
		(width 0.12954)
		(layer "F.Cu")
		(net "M_A_CPU1_SA_DQS_DP<0>")
	)
	(segment
		(start 63.145416 -203.375514)
		(end 62.968378 -203.198476)
		(width 0.12954)
		(layer "F.Cu")
		(net "M_A_CPU1_SA_DQS_DP<0>")
	)
	(segment
		(start 73.517506 -214.601044)
		(end 73.517506 -214.418672)
		(width 0.12954)
		(layer "F.Cu")
		(net "M_A_CPU1_SA_DQS_DP<0>")
	)
	(segment
		(start 60.226448 -200.99909)
		(end 59.962796 -200.735438)
		(width 0.12954)
		(layer "F.Cu")
		(net "M_A_CPU1_SA_DQS_DP<0>")
	)
	(segment
		(start 69.965316 -210.195414)
		(end 69.788278 -210.018376)
		(width 0.12954)
		(layer "F.Cu")
		(net "M_A_CPU1_SA_DQS_DP<0>")
	)
	(segment
		(start 75.184 -225.376486)
		(end 75.184 -214.818722)
		(width 0.12954)
		(layer "F.Cu")
		(net "M_A_CPU1_SA_DQS_DP<0>")
	)
	(segment
		(start 70.924928 -210.55965)
		(end 70.560692 -210.195414)
		(width 0.12954)
		(layer "F.Cu")
		(net "M_A_CPU1_SA_DQS_DP<0>")
	)
	(arc
		(start 77.880718 -227.179632)
		(mid 77.763905 -227.204308)
		(end 77.654912 -227.253038)
		(width 0.0762)
		(layer "F.Cu")
		(net "M_A_CPU1_SA_DQS_DP<0>")
	)
	(arc
		(start 78.408022 -226.930458)
		(mid 78.165705 -227.100178)
		(end 77.880718 -227.179632)
		(width 0.0762)
		(layer "F.Cu")
		(net "M_A_CPU1_SA_DQS_DP<0>")
	)
	(arc
		(start 77.654912 -227.253038)
		(mid 77.564779 -227.290658)
		(end 77.467968 -227.303584)
		(width 0.0762)
		(layer "F.Cu")
		(net "M_A_CPU1_SA_DQS_DP<0>")
	)
	(segment
		(start 57.550812 -239.728502)
		(end 57.266078 -239.728502)
		(width 0.101346)
		(layer "F.Cu")
		(net "M_A_CPU1_SA_DQS_DN<9>")
	)
	(segment
		(start 61.33719 -240.091468)
		(end 60.899548 -239.653826)
		(width 0.12954)
		(layer "F.Cu")
		(net "M_A_CPU1_SA_DQS_DN<9>")
	)
	(segment
		(start 60.532772 -239.653826)
		(end 60.28944 -239.410494)
		(width 0.12954)
		(layer "F.Cu")
		(net "M_A_CPU1_SA_DQS_DN<9>")
	)
	(segment
		(start 56.839866 -239.30229)
		(end 56.177434 -239.30229)
		(width 0.101346)
		(layer "F.Cu")
		(net "M_A_CPU1_SA_DQS_DN<9>")
	)
	(segment
		(start 76.358496 -247.583706)
		(end 76.040996 -247.583706)
		(width 0.0762)
		(layer "F.Cu")
		(net "M_A_CPU1_SA_DQS_DN<9>")
	)
	(segment
		(start 60.899548 -239.653826)
		(end 60.532772 -239.653826)
		(width 0.12954)
		(layer "F.Cu")
		(net "M_A_CPU1_SA_DQS_DN<9>")
	)
	(segment
		(start 75.974956 -247.517666)
		(end 75.955906 -247.517666)
		(width 0.0762)
		(layer "F.Cu")
		(net "M_A_CPU1_SA_DQS_DN<9>")
	)
	(segment
		(start 57.266078 -239.728502)
		(end 56.839866 -239.30229)
		(width 0.101346)
		(layer "F.Cu")
		(net "M_A_CPU1_SA_DQS_DN<9>")
	)
	(segment
		(start 75.955906 -247.517666)
		(end 66.935604 -247.517666)
		(width 0.12954)
		(layer "F.Cu")
		(net "M_A_CPU1_SA_DQS_DN<9>")
	)
	(segment
		(start 55.860442 -238.985298)
		(end 55.328058 -238.985298)
		(width 0.101346)
		(layer "F.Cu")
		(net "M_A_CPU1_SA_DQS_DN<9>")
	)
	(segment
		(start 77.759306 -247.50776)
		(end 77.750924 -247.502934)
		(width 0.0762)
		(layer "F.Cu")
		(net "M_A_CPU1_SA_DQS_DN<9>")
	)
	(segment
		(start 57.86882 -239.410494)
		(end 57.550812 -239.728502)
		(width 0.101346)
		(layer "F.Cu")
		(net "M_A_CPU1_SA_DQS_DN<9>")
	)
	(segment
		(start 76.515468 -247.426734)
		(end 76.358496 -247.583706)
		(width 0.0762)
		(layer "F.Cu")
		(net "M_A_CPU1_SA_DQS_DN<9>")
	)
	(segment
		(start 66.935604 -247.517666)
		(end 62.7761 -243.358162)
		(width 0.12954)
		(layer "F.Cu")
		(net "M_A_CPU1_SA_DQS_DN<9>")
	)
	(segment
		(start 77.468222 -247.426734)
		(end 76.515468 -247.426734)
		(width 0.0762)
		(layer "F.Cu")
		(net "M_A_CPU1_SA_DQS_DN<9>")
	)
	(segment
		(start 60.28944 -239.410494)
		(end 57.86882 -239.410494)
		(width 0.101346)
		(layer "F.Cu")
		(net "M_A_CPU1_SA_DQS_DN<9>")
	)
	(segment
		(start 62.7761 -243.358162)
		(end 62.7761 -242.330478)
		(width 0.12954)
		(layer "F.Cu")
		(net "M_A_CPU1_SA_DQS_DN<9>")
	)
	(segment
		(start 56.177434 -239.30229)
		(end 55.860442 -238.985298)
		(width 0.101346)
		(layer "F.Cu")
		(net "M_A_CPU1_SA_DQS_DN<9>")
	)
	(segment
		(start 61.33719 -240.891568)
		(end 61.33719 -240.091468)
		(width 0.12954)
		(layer "F.Cu")
		(net "M_A_CPU1_SA_DQS_DN<9>")
	)
	(segment
		(start 76.040996 -247.583706)
		(end 75.974956 -247.517666)
		(width 0.0762)
		(layer "F.Cu")
		(net "M_A_CPU1_SA_DQS_DN<9>")
	)
	(segment
		(start 62.7761 -242.330478)
		(end 61.33719 -240.891568)
		(width 0.12954)
		(layer "F.Cu")
		(net "M_A_CPU1_SA_DQS_DN<9>")
	)
	(arc
		(start 77.515212 -247.428512)
		(mid 77.491735 -247.427136)
		(end 77.468222 -247.426734)
		(width 0.0762)
		(layer "F.Cu")
		(net "M_A_CPU1_SA_DQS_DN<9>")
	)
	(arc
		(start 79.064866 -247.502934)
		(mid 78.877922 -247.553189)
		(end 78.690978 -247.502934)
		(width 0.0762)
		(layer "F.Cu")
		(net "M_A_CPU1_SA_DQS_DN<9>")
	)
	(arc
		(start 78.125066 -247.502934)
		(mid 77.942815 -247.553284)
		(end 77.759306 -247.50776)
		(width 0.0762)
		(layer "F.Cu")
		(net "M_A_CPU1_SA_DQS_DN<9>")
	)
	(arc
		(start 79.298038 -247.428766)
		(mid 79.177389 -247.453067)
		(end 79.064866 -247.502934)
		(width 0.0762)
		(layer "F.Cu")
		(net "M_A_CPU1_SA_DQS_DN<9>")
	)
	(arc
		(start 79.817976 -247.180354)
		(mid 79.580364 -247.351342)
		(end 79.298038 -247.428766)
		(width 0.0762)
		(layer "F.Cu")
		(net "M_A_CPU1_SA_DQS_DN<9>")
	)
	(arc
		(start 78.690978 -247.502934)
		(mid 78.408022 -247.426757)
		(end 78.125066 -247.502934)
		(width 0.0762)
		(layer "F.Cu")
		(net "M_A_CPU1_SA_DQS_DN<9>")
	)
	(arc
		(start 77.750924 -247.502934)
		(mid 77.6372 -247.452633)
		(end 77.515212 -247.428512)
		(width 0.0762)
		(layer "F.Cu")
		(net "M_A_CPU1_SA_DQS_DN<9>")
	)
	(segment
		(start 60.28944 -230.0605)
		(end 57.86882 -230.0605)
		(width 0.101346)
		(layer "F.Cu")
		(net "M_A_CPU1_SA_DQS_DN<8>")
	)
	(segment
		(start 75.954382 -242.703604)
		(end 71.610982 -242.703604)
		(width 0.12954)
		(layer "F.Cu")
		(net "M_A_CPU1_SA_DQS_DN<8>")
	)
	(segment
		(start 56.177434 -229.952296)
		(end 55.860442 -229.635304)
		(width 0.101346)
		(layer "F.Cu")
		(net "M_A_CPU1_SA_DQS_DN<8>")
	)
	(segment
		(start 75.973432 -242.703604)
		(end 75.954382 -242.703604)
		(width 0.0762)
		(layer "F.Cu")
		(net "M_A_CPU1_SA_DQS_DN<8>")
	)
	(segment
		(start 57.550812 -230.378508)
		(end 57.24779 -230.378508)
		(width 0.101346)
		(layer "F.Cu")
		(net "M_A_CPU1_SA_DQS_DN<8>")
	)
	(segment
		(start 55.860442 -229.635304)
		(end 55.328058 -229.635304)
		(width 0.101346)
		(layer "F.Cu")
		(net "M_A_CPU1_SA_DQS_DN<8>")
	)
	(segment
		(start 61.193426 -230.637588)
		(end 60.875164 -230.319326)
		(width 0.12954)
		(layer "F.Cu")
		(net "M_A_CPU1_SA_DQS_DN<8>")
	)
	(segment
		(start 56.821578 -229.952296)
		(end 56.177434 -229.952296)
		(width 0.101346)
		(layer "F.Cu")
		(net "M_A_CPU1_SA_DQS_DN<8>")
	)
	(segment
		(start 76.412852 -242.725956)
		(end 76.370942 -242.769644)
		(width 0.0762)
		(layer "F.Cu")
		(net "M_A_CPU1_SA_DQS_DN<8>")
	)
	(segment
		(start 77.759306 -242.647724)
		(end 77.750924 -242.642898)
		(width 0.0762)
		(layer "F.Cu")
		(net "M_A_CPU1_SA_DQS_DN<8>")
	)
	(segment
		(start 77.468222 -242.566698)
		(end 76.57211 -242.566698)
		(width 0.0762)
		(layer "F.Cu")
		(net "M_A_CPU1_SA_DQS_DN<8>")
	)
	(segment
		(start 76.57211 -242.566698)
		(end 76.412852 -242.725956)
		(width 0.0762)
		(layer "F.Cu")
		(net "M_A_CPU1_SA_DQS_DN<8>")
	)
	(segment
		(start 57.24779 -230.378508)
		(end 56.821578 -229.952296)
		(width 0.101346)
		(layer "F.Cu")
		(net "M_A_CPU1_SA_DQS_DN<8>")
	)
	(segment
		(start 71.610982 -242.703604)
		(end 62.350396 -233.443018)
		(width 0.12954)
		(layer "F.Cu")
		(net "M_A_CPU1_SA_DQS_DN<8>")
	)
	(segment
		(start 62.350396 -232.544874)
		(end 61.193426 -231.387904)
		(width 0.12954)
		(layer "F.Cu")
		(net "M_A_CPU1_SA_DQS_DN<8>")
	)
	(segment
		(start 60.548266 -230.319326)
		(end 60.28944 -230.0605)
		(width 0.12954)
		(layer "F.Cu")
		(net "M_A_CPU1_SA_DQS_DN<8>")
	)
	(segment
		(start 57.86882 -230.0605)
		(end 57.550812 -230.378508)
		(width 0.101346)
		(layer "F.Cu")
		(net "M_A_CPU1_SA_DQS_DN<8>")
	)
	(segment
		(start 60.875164 -230.319326)
		(end 60.548266 -230.319326)
		(width 0.12954)
		(layer "F.Cu")
		(net "M_A_CPU1_SA_DQS_DN<8>")
	)
	(segment
		(start 76.370942 -242.769644)
		(end 76.039472 -242.769644)
		(width 0.0762)
		(layer "F.Cu")
		(net "M_A_CPU1_SA_DQS_DN<8>")
	)
	(segment
		(start 76.039472 -242.769644)
		(end 75.973432 -242.703604)
		(width 0.0762)
		(layer "F.Cu")
		(net "M_A_CPU1_SA_DQS_DN<8>")
	)
	(segment
		(start 62.350396 -233.443018)
		(end 62.350396 -232.544874)
		(width 0.12954)
		(layer "F.Cu")
		(net "M_A_CPU1_SA_DQS_DN<8>")
	)
	(segment
		(start 61.193426 -231.387904)
		(end 61.193426 -230.637588)
		(width 0.12954)
		(layer "F.Cu")
		(net "M_A_CPU1_SA_DQS_DN<8>")
	)
	(arc
		(start 77.750924 -242.642898)
		(mid 77.6372 -242.592597)
		(end 77.515212 -242.568476)
		(width 0.0762)
		(layer "F.Cu")
		(net "M_A_CPU1_SA_DQS_DN<8>")
	)
	(arc
		(start 78.690978 -242.642898)
		(mid 78.408022 -242.566721)
		(end 78.125066 -242.642898)
		(width 0.0762)
		(layer "F.Cu")
		(net "M_A_CPU1_SA_DQS_DN<8>")
	)
	(arc
		(start 79.298038 -242.56873)
		(mid 79.177389 -242.593031)
		(end 79.064866 -242.642898)
		(width 0.0762)
		(layer "F.Cu")
		(net "M_A_CPU1_SA_DQS_DN<8>")
	)
	(arc
		(start 77.515212 -242.568476)
		(mid 77.491735 -242.5671)
		(end 77.468222 -242.566698)
		(width 0.0762)
		(layer "F.Cu")
		(net "M_A_CPU1_SA_DQS_DN<8>")
	)
	(arc
		(start 78.125066 -242.642898)
		(mid 77.942815 -242.693248)
		(end 77.759306 -242.647724)
		(width 0.0762)
		(layer "F.Cu")
		(net "M_A_CPU1_SA_DQS_DN<8>")
	)
	(arc
		(start 79.817976 -242.320318)
		(mid 79.580364 -242.491306)
		(end 79.298038 -242.56873)
		(width 0.0762)
		(layer "F.Cu")
		(net "M_A_CPU1_SA_DQS_DN<8>")
	)
	(arc
		(start 79.064866 -242.642898)
		(mid 78.877922 -242.693153)
		(end 78.690978 -242.642898)
		(width 0.0762)
		(layer "F.Cu")
		(net "M_A_CPU1_SA_DQS_DN<8>")
	)
	(segment
		(start 65.66662 -224.60585)
		(end 62.034674 -220.973904)
		(width 0.12954)
		(layer "F.Cu")
		(net "M_A_CPU1_SA_DQS_DN<7>")
	)
	(segment
		(start 56.60263 -220.602048)
		(end 56.176926 -220.602048)
		(width 0.101346)
		(layer "F.Cu")
		(net "M_A_CPU1_SA_DQS_DN<7>")
	)
	(segment
		(start 76.35621 -237.896908)
		(end 76.31811 -237.943644)
		(width 0.0762)
		(layer "F.Cu")
		(net "M_A_CPU1_SA_DQS_DN<7>")
	)
	(segment
		(start 56.176926 -220.602048)
		(end 55.860188 -220.28531)
		(width 0.101346)
		(layer "F.Cu")
		(net "M_A_CPU1_SA_DQS_DN<7>")
	)
	(segment
		(start 76.546456 -237.706662)
		(end 76.35621 -237.896908)
		(width 0.0762)
		(layer "F.Cu")
		(net "M_A_CPU1_SA_DQS_DN<7>")
	)
	(segment
		(start 60.553092 -220.973904)
		(end 60.28944 -220.710252)
		(width 0.12954)
		(layer "F.Cu")
		(net "M_A_CPU1_SA_DQS_DN<7>")
	)
	(segment
		(start 60.28944 -220.710252)
		(end 57.74944 -220.710252)
		(width 0.101346)
		(layer "F.Cu")
		(net "M_A_CPU1_SA_DQS_DN<7>")
	)
	(segment
		(start 57.74944 -220.710252)
		(end 57.432702 -221.02699)
		(width 0.101346)
		(layer "F.Cu")
		(net "M_A_CPU1_SA_DQS_DN<7>")
	)
	(segment
		(start 74.058526 -237.877604)
		(end 65.66662 -229.485698)
		(width 0.12954)
		(layer "F.Cu")
		(net "M_A_CPU1_SA_DQS_DN<7>")
	)
	(segment
		(start 57.027572 -221.02699)
		(end 56.60263 -220.602048)
		(width 0.101346)
		(layer "F.Cu")
		(net "M_A_CPU1_SA_DQS_DN<7>")
	)
	(segment
		(start 77.468222 -237.706662)
		(end 76.546456 -237.706662)
		(width 0.0762)
		(layer "F.Cu")
		(net "M_A_CPU1_SA_DQS_DN<7>")
	)
	(segment
		(start 57.432702 -221.02699)
		(end 57.027572 -221.02699)
		(width 0.101346)
		(layer "F.Cu")
		(net "M_A_CPU1_SA_DQS_DN<7>")
	)
	(segment
		(start 62.034674 -220.973904)
		(end 60.553092 -220.973904)
		(width 0.12954)
		(layer "F.Cu")
		(net "M_A_CPU1_SA_DQS_DN<7>")
	)
	(segment
		(start 55.860188 -220.28531)
		(end 55.328058 -220.28531)
		(width 0.101346)
		(layer "F.Cu")
		(net "M_A_CPU1_SA_DQS_DN<7>")
	)
	(segment
		(start 75.986894 -237.877604)
		(end 74.058526 -237.877604)
		(width 0.12954)
		(layer "F.Cu")
		(net "M_A_CPU1_SA_DQS_DN<7>")
	)
	(segment
		(start 76.005944 -237.877604)
		(end 75.986894 -237.877604)
		(width 0.0762)
		(layer "F.Cu")
		(net "M_A_CPU1_SA_DQS_DN<7>")
	)
	(segment
		(start 76.31811 -237.943644)
		(end 76.071984 -237.943644)
		(width 0.0762)
		(layer "F.Cu")
		(net "M_A_CPU1_SA_DQS_DN<7>")
	)
	(segment
		(start 77.759306 -237.787688)
		(end 77.750924 -237.782862)
		(width 0.0762)
		(layer "F.Cu")
		(net "M_A_CPU1_SA_DQS_DN<7>")
	)
	(segment
		(start 65.66662 -229.485698)
		(end 65.66662 -224.60585)
		(width 0.12954)
		(layer "F.Cu")
		(net "M_A_CPU1_SA_DQS_DN<7>")
	)
	(segment
		(start 76.071984 -237.943644)
		(end 76.005944 -237.877604)
		(width 0.0762)
		(layer "F.Cu")
		(net "M_A_CPU1_SA_DQS_DN<7>")
	)
	(arc
		(start 78.690978 -237.782862)
		(mid 78.408022 -237.706685)
		(end 78.125066 -237.782862)
		(width 0.0762)
		(layer "F.Cu")
		(net "M_A_CPU1_SA_DQS_DN<7>")
	)
	(arc
		(start 79.298038 -237.708694)
		(mid 79.177389 -237.732995)
		(end 79.064866 -237.782862)
		(width 0.0762)
		(layer "F.Cu")
		(net "M_A_CPU1_SA_DQS_DN<7>")
	)
	(arc
		(start 77.515212 -237.70844)
		(mid 77.491735 -237.707064)
		(end 77.468222 -237.706662)
		(width 0.0762)
		(layer "F.Cu")
		(net "M_A_CPU1_SA_DQS_DN<7>")
	)
	(arc
		(start 77.750924 -237.782862)
		(mid 77.6372 -237.732561)
		(end 77.515212 -237.70844)
		(width 0.0762)
		(layer "F.Cu")
		(net "M_A_CPU1_SA_DQS_DN<7>")
	)
	(arc
		(start 79.817976 -237.460282)
		(mid 79.580364 -237.63127)
		(end 79.298038 -237.708694)
		(width 0.0762)
		(layer "F.Cu")
		(net "M_A_CPU1_SA_DQS_DN<7>")
	)
	(arc
		(start 78.125066 -237.782862)
		(mid 77.942815 -237.833212)
		(end 77.759306 -237.787688)
		(width 0.0762)
		(layer "F.Cu")
		(net "M_A_CPU1_SA_DQS_DN<7>")
	)
	(arc
		(start 79.064866 -237.782862)
		(mid 78.877922 -237.833117)
		(end 78.690978 -237.782862)
		(width 0.0762)
		(layer "F.Cu")
		(net "M_A_CPU1_SA_DQS_DN<7>")
	)
	(segment
		(start 55.860188 -210.935316)
		(end 55.328058 -210.935316)
		(width 0.101346)
		(layer "F.Cu")
		(net "M_A_CPU1_SA_DQS_DN<6>")
	)
	(segment
		(start 60.988956 -211.623402)
		(end 60.552584 -211.623402)
		(width 0.12954)
		(layer "F.Cu")
		(net "M_A_CPU1_SA_DQS_DN<6>")
	)
	(segment
		(start 75.955906 -232.887266)
		(end 75.316588 -232.887266)
		(width 0.12954)
		(layer "F.Cu")
		(net "M_A_CPU1_SA_DQS_DN<6>")
	)
	(segment
		(start 57.432702 -211.676996)
		(end 57.055004 -211.676996)
		(width 0.101346)
		(layer "F.Cu")
		(net "M_A_CPU1_SA_DQS_DN<6>")
	)
	(segment
		(start 75.974956 -232.887266)
		(end 75.955906 -232.887266)
		(width 0.0762)
		(layer "F.Cu")
		(net "M_A_CPU1_SA_DQS_DN<6>")
	)
	(segment
		(start 76.358496 -232.953306)
		(end 76.040996 -232.953306)
		(width 0.0762)
		(layer "F.Cu")
		(net "M_A_CPU1_SA_DQS_DN<6>")
	)
	(segment
		(start 56.176926 -211.252054)
		(end 55.860188 -210.935316)
		(width 0.101346)
		(layer "F.Cu")
		(net "M_A_CPU1_SA_DQS_DN<6>")
	)
	(segment
		(start 60.552584 -211.623402)
		(end 60.28944 -211.360258)
		(width 0.12954)
		(layer "F.Cu")
		(net "M_A_CPU1_SA_DQS_DN<6>")
	)
	(segment
		(start 77.468222 -232.846626)
		(end 76.465176 -232.846626)
		(width 0.0762)
		(layer "F.Cu")
		(net "M_A_CPU1_SA_DQS_DN<6>")
	)
	(segment
		(start 76.465176 -232.846626)
		(end 76.358496 -232.953306)
		(width 0.0762)
		(layer "F.Cu")
		(net "M_A_CPU1_SA_DQS_DN<6>")
	)
	(segment
		(start 70.0532 -219.551504)
		(end 62.40399 -211.902548)
		(width 0.12954)
		(layer "F.Cu")
		(net "M_A_CPU1_SA_DQS_DN<6>")
	)
	(segment
		(start 57.74944 -211.360258)
		(end 57.432702 -211.676996)
		(width 0.101346)
		(layer "F.Cu")
		(net "M_A_CPU1_SA_DQS_DN<6>")
	)
	(segment
		(start 56.630062 -211.252054)
		(end 56.176926 -211.252054)
		(width 0.101346)
		(layer "F.Cu")
		(net "M_A_CPU1_SA_DQS_DN<6>")
	)
	(segment
		(start 57.055004 -211.676996)
		(end 56.630062 -211.252054)
		(width 0.101346)
		(layer "F.Cu")
		(net "M_A_CPU1_SA_DQS_DN<6>")
	)
	(segment
		(start 62.40399 -211.902548)
		(end 61.268102 -211.902548)
		(width 0.12954)
		(layer "F.Cu")
		(net "M_A_CPU1_SA_DQS_DN<6>")
	)
	(segment
		(start 70.0532 -227.623878)
		(end 70.0532 -219.551504)
		(width 0.12954)
		(layer "F.Cu")
		(net "M_A_CPU1_SA_DQS_DN<6>")
	)
	(segment
		(start 61.268102 -211.902548)
		(end 60.988956 -211.623402)
		(width 0.12954)
		(layer "F.Cu")
		(net "M_A_CPU1_SA_DQS_DN<6>")
	)
	(segment
		(start 75.316588 -232.887266)
		(end 70.0532 -227.623878)
		(width 0.12954)
		(layer "F.Cu")
		(net "M_A_CPU1_SA_DQS_DN<6>")
	)
	(segment
		(start 77.759306 -232.927652)
		(end 77.750924 -232.922826)
		(width 0.0762)
		(layer "F.Cu")
		(net "M_A_CPU1_SA_DQS_DN<6>")
	)
	(segment
		(start 76.040996 -232.953306)
		(end 75.974956 -232.887266)
		(width 0.0762)
		(layer "F.Cu")
		(net "M_A_CPU1_SA_DQS_DN<6>")
	)
	(segment
		(start 60.28944 -211.360258)
		(end 57.74944 -211.360258)
		(width 0.101346)
		(layer "F.Cu")
		(net "M_A_CPU1_SA_DQS_DN<6>")
	)
	(arc
		(start 79.817976 -232.600246)
		(mid 79.580364 -232.771234)
		(end 79.298038 -232.848658)
		(width 0.0762)
		(layer "F.Cu")
		(net "M_A_CPU1_SA_DQS_DN<6>")
	)
	(arc
		(start 78.125066 -232.922826)
		(mid 77.942815 -232.973176)
		(end 77.759306 -232.927652)
		(width 0.0762)
		(layer "F.Cu")
		(net "M_A_CPU1_SA_DQS_DN<6>")
	)
	(arc
		(start 78.690978 -232.922826)
		(mid 78.408022 -232.846649)
		(end 78.125066 -232.922826)
		(width 0.0762)
		(layer "F.Cu")
		(net "M_A_CPU1_SA_DQS_DN<6>")
	)
	(arc
		(start 77.515212 -232.848404)
		(mid 77.491735 -232.847028)
		(end 77.468222 -232.846626)
		(width 0.0762)
		(layer "F.Cu")
		(net "M_A_CPU1_SA_DQS_DN<6>")
	)
	(arc
		(start 79.064866 -232.922826)
		(mid 78.877922 -232.973081)
		(end 78.690978 -232.922826)
		(width 0.0762)
		(layer "F.Cu")
		(net "M_A_CPU1_SA_DQS_DN<6>")
	)
	(arc
		(start 77.750924 -232.922826)
		(mid 77.6372 -232.872525)
		(end 77.515212 -232.848404)
		(width 0.0762)
		(layer "F.Cu")
		(net "M_A_CPU1_SA_DQS_DN<6>")
	)
	(arc
		(start 79.298038 -232.848658)
		(mid 79.177389 -232.872959)
		(end 79.064866 -232.922826)
		(width 0.0762)
		(layer "F.Cu")
		(net "M_A_CPU1_SA_DQS_DN<6>")
	)
	(segment
		(start 76.184506 -227.473002)
		(end 74.43978 -225.728276)
		(width 0.12954)
		(layer "F.Cu")
		(net "M_A_CPU1_SA_DQS_DN<5>")
	)
	(segment
		(start 56.176926 -201.90206)
		(end 55.860188 -201.585322)
		(width 0.101346)
		(layer "F.Cu")
		(net "M_A_CPU1_SA_DQS_DN<5>")
	)
	(segment
		(start 72.773286 -214.91194)
		(end 72.773286 -214.089234)
		(width 0.12954)
		(layer "F.Cu")
		(net "M_A_CPU1_SA_DQS_DN<5>")
	)
	(segment
		(start 77.674216 -228.004116)
		(end 77.403452 -227.733606)
		(width 0.0762)
		(layer "F.Cu")
		(net "M_A_CPU1_SA_DQS_DN<5>")
	)
	(segment
		(start 55.860188 -201.585322)
		(end 55.328058 -201.585322)
		(width 0.101346)
		(layer "F.Cu")
		(net "M_A_CPU1_SA_DQS_DN<5>")
	)
	(segment
		(start 60.544202 -202.265026)
		(end 60.28944 -202.010264)
		(width 0.12954)
		(layer "F.Cu")
		(net "M_A_CPU1_SA_DQS_DN<5>")
	)
	(segment
		(start 57.039764 -202.327002)
		(end 56.614822 -201.90206)
		(width 0.101346)
		(layer "F.Cu")
		(net "M_A_CPU1_SA_DQS_DN<5>")
	)
	(segment
		(start 60.949586 -202.265026)
		(end 60.544202 -202.265026)
		(width 0.12954)
		(layer "F.Cu")
		(net "M_A_CPU1_SA_DQS_DN<5>")
	)
	(segment
		(start 72.773286 -214.089234)
		(end 60.949586 -202.265026)
		(width 0.12954)
		(layer "F.Cu")
		(net "M_A_CPU1_SA_DQS_DN<5>")
	)
	(segment
		(start 77.403452 -227.733606)
		(end 76.351384 -227.733606)
		(width 0.0762)
		(layer "F.Cu")
		(net "M_A_CPU1_SA_DQS_DN<5>")
	)
	(segment
		(start 57.432702 -202.327002)
		(end 57.039764 -202.327002)
		(width 0.101346)
		(layer "F.Cu")
		(net "M_A_CPU1_SA_DQS_DN<5>")
	)
	(segment
		(start 76.197968 -227.486464)
		(end 76.184506 -227.473002)
		(width 0.0762)
		(layer "F.Cu")
		(net "M_A_CPU1_SA_DQS_DN<5>")
	)
	(segment
		(start 74.43978 -216.578434)
		(end 72.773286 -214.91194)
		(width 0.12954)
		(layer "F.Cu")
		(net "M_A_CPU1_SA_DQS_DN<5>")
	)
	(segment
		(start 76.351384 -227.733606)
		(end 76.197714 -227.579936)
		(width 0.0762)
		(layer "F.Cu")
		(net "M_A_CPU1_SA_DQS_DN<5>")
	)
	(segment
		(start 76.197714 -227.579936)
		(end 76.197968 -227.486464)
		(width 0.0762)
		(layer "F.Cu")
		(net "M_A_CPU1_SA_DQS_DN<5>")
	)
	(segment
		(start 60.28944 -202.010264)
		(end 57.74944 -202.010264)
		(width 0.101346)
		(layer "F.Cu")
		(net "M_A_CPU1_SA_DQS_DN<5>")
	)
	(segment
		(start 56.614822 -201.90206)
		(end 56.176926 -201.90206)
		(width 0.101346)
		(layer "F.Cu")
		(net "M_A_CPU1_SA_DQS_DN<5>")
	)
	(segment
		(start 74.43978 -225.728276)
		(end 74.43978 -216.578434)
		(width 0.12954)
		(layer "F.Cu")
		(net "M_A_CPU1_SA_DQS_DN<5>")
	)
	(segment
		(start 57.74944 -202.010264)
		(end 57.432702 -202.327002)
		(width 0.101346)
		(layer "F.Cu")
		(net "M_A_CPU1_SA_DQS_DN<5>")
	)
	(arc
		(start 78.690978 -228.063044)
		(mid 78.408022 -227.986867)
		(end 78.125066 -228.063044)
		(width 0.0762)
		(layer "F.Cu")
		(net "M_A_CPU1_SA_DQS_DN<5>")
	)
	(arc
		(start 79.298038 -227.988876)
		(mid 79.177389 -228.013177)
		(end 79.064866 -228.063044)
		(width 0.0762)
		(layer "F.Cu")
		(net "M_A_CPU1_SA_DQS_DN<5>")
	)
	(arc
		(start 78.125066 -228.063044)
		(mid 77.937868 -228.113426)
		(end 77.75067 -228.063044)
		(width 0.0762)
		(layer "F.Cu")
		(net "M_A_CPU1_SA_DQS_DN<5>")
	)
	(arc
		(start 79.064866 -228.063044)
		(mid 78.877922 -228.113299)
		(end 78.690978 -228.063044)
		(width 0.0762)
		(layer "F.Cu")
		(net "M_A_CPU1_SA_DQS_DN<5>")
	)
	(arc
		(start 77.75067 -228.063044)
		(mid 77.710525 -228.036068)
		(end 77.674216 -228.004116)
		(width 0.0762)
		(layer "F.Cu")
		(net "M_A_CPU1_SA_DQS_DN<5>")
	)
	(arc
		(start 79.817976 -227.740464)
		(mid 79.580364 -227.911452)
		(end 79.298038 -227.988876)
		(width 0.0762)
		(layer "F.Cu")
		(net "M_A_CPU1_SA_DQS_DN<5>")
	)
	(segment
		(start 76.429616 -247.000014)
		(end 67.014598 -247.000014)
		(width 0.12954)
		(layer "F.Cu")
		(net "M_A_CPU1_SA_DQS_DN<4>")
	)
	(segment
		(start 77.467968 -246.933974)
		(end 76.514706 -246.933974)
		(width 0.0762)
		(layer "F.Cu")
		(net "M_A_CPU1_SA_DQS_DN<4>")
	)
	(segment
		(start 64.688212 -244.673628)
		(end 64.342772 -244.328188)
		(width 0.12954)
		(layer "F.Cu")
		(net "M_A_CPU1_SA_DQS_DN<4>")
	)
	(segment
		(start 65.479422 -245.013734)
		(end 65.922144 -244.570758)
		(width 0.12954)
		(layer "F.Cu")
		(net "M_A_CPU1_SA_DQS_DN<4>")
	)
	(segment
		(start 65.138808 -244.673628)
		(end 64.688212 -244.673628)
		(width 0.12954)
		(layer "F.Cu")
		(net "M_A_CPU1_SA_DQS_DN<4>")
	)
	(segment
		(start 65.581784 -244.230652)
		(end 65.138808 -244.673628)
		(width 0.12954)
		(layer "F.Cu")
		(net "M_A_CPU1_SA_DQS_DN<4>")
	)
	(segment
		(start 66.90106 -245.367556)
		(end 66.718434 -245.367302)
		(width 0.12954)
		(layer "F.Cu")
		(net "M_A_CPU1_SA_DQS_DN<4>")
	)
	(segment
		(start 63.551562 -243.536978)
		(end 63.19774 -243.183156)
		(width 0.12954)
		(layer "F.Cu")
		(net "M_A_CPU1_SA_DQS_DN<4>")
	)
	(segment
		(start 65.479422 -245.464838)
		(end 65.479422 -245.013734)
		(width 0.12954)
		(layer "F.Cu")
		(net "M_A_CPU1_SA_DQS_DN<4>")
	)
	(segment
		(start 60.56249 -238.706406)
		(end 60.241688 -238.706406)
		(width 0.12954)
		(layer "F.Cu")
		(net "M_A_CPU1_SA_DQS_DN<4>")
	)
	(segment
		(start 64.342772 -243.877084)
		(end 64.785494 -243.434108)
		(width 0.12954)
		(layer "F.Cu")
		(net "M_A_CPU1_SA_DQS_DN<4>")
	)
	(segment
		(start 65.922398 -244.38864)
		(end 65.76441 -244.230906)
		(width 0.12954)
		(layer "F.Cu")
		(net "M_A_CPU1_SA_DQS_DN<4>")
	)
	(segment
		(start 66.718434 -245.367302)
		(end 66.275458 -245.810278)
		(width 0.12954)
		(layer "F.Cu")
		(net "M_A_CPU1_SA_DQS_DN<4>")
	)
	(segment
		(start 76.514706 -246.933974)
		(end 76.448666 -247.000014)
		(width 0.0762)
		(layer "F.Cu")
		(net "M_A_CPU1_SA_DQS_DN<4>")
	)
	(segment
		(start 60.241688 -238.706406)
		(end 59.962796 -238.985298)
		(width 0.12954)
		(layer "F.Cu")
		(net "M_A_CPU1_SA_DQS_DN<4>")
	)
	(segment
		(start 66.275458 -245.810278)
		(end 65.824862 -245.810278)
		(width 0.12954)
		(layer "F.Cu")
		(net "M_A_CPU1_SA_DQS_DN<4>")
	)
	(segment
		(start 61.75883 -239.902746)
		(end 60.56249 -238.706406)
		(width 0.12954)
		(layer "F.Cu")
		(net "M_A_CPU1_SA_DQS_DN<4>")
	)
	(segment
		(start 61.75883 -240.716562)
		(end 61.75883 -239.902746)
		(width 0.12954)
		(layer "F.Cu")
		(net "M_A_CPU1_SA_DQS_DN<4>")
	)
	(segment
		(start 67.059048 -245.52529)
		(end 66.90106 -245.367556)
		(width 0.12954)
		(layer "F.Cu")
		(net "M_A_CPU1_SA_DQS_DN<4>")
	)
	(segment
		(start 66.616072 -246.601488)
		(end 66.616072 -246.150384)
		(width 0.12954)
		(layer "F.Cu")
		(net "M_A_CPU1_SA_DQS_DN<4>")
	)
	(segment
		(start 67.014598 -247.000014)
		(end 66.616072 -246.601488)
		(width 0.12954)
		(layer "F.Cu")
		(net "M_A_CPU1_SA_DQS_DN<4>")
	)
	(segment
		(start 65.922144 -244.570758)
		(end 65.922398 -244.38864)
		(width 0.12954)
		(layer "F.Cu")
		(net "M_A_CPU1_SA_DQS_DN<4>")
	)
	(segment
		(start 64.785494 -243.434108)
		(end 64.785748 -243.25199)
		(width 0.12954)
		(layer "F.Cu")
		(net "M_A_CPU1_SA_DQS_DN<4>")
	)
	(segment
		(start 66.616072 -246.150384)
		(end 67.058794 -245.707408)
		(width 0.12954)
		(layer "F.Cu")
		(net "M_A_CPU1_SA_DQS_DN<4>")
	)
	(segment
		(start 64.002158 -243.536978)
		(end 63.551562 -243.536978)
		(width 0.12954)
		(layer "F.Cu")
		(net "M_A_CPU1_SA_DQS_DN<4>")
	)
	(segment
		(start 67.058794 -245.707408)
		(end 67.059048 -245.52529)
		(width 0.12954)
		(layer "F.Cu")
		(net "M_A_CPU1_SA_DQS_DN<4>")
	)
	(segment
		(start 77.937868 -247.180354)
		(end 78.036166 -247.01119)
		(width 0.0762)
		(layer "F.Cu")
		(net "M_A_CPU1_SA_DQS_DN<4>")
	)
	(segment
		(start 77.759306 -246.852948)
		(end 77.750924 -246.857774)
		(width 0.0762)
		(layer "F.Cu")
		(net "M_A_CPU1_SA_DQS_DN<4>")
	)
	(segment
		(start 64.62776 -243.094256)
		(end 64.445134 -243.094002)
		(width 0.12954)
		(layer "F.Cu")
		(net "M_A_CPU1_SA_DQS_DN<4>")
	)
	(segment
		(start 64.785748 -243.25199)
		(end 64.62776 -243.094256)
		(width 0.12954)
		(layer "F.Cu")
		(net "M_A_CPU1_SA_DQS_DN<4>")
	)
	(segment
		(start 64.445134 -243.094002)
		(end 64.002158 -243.536978)
		(width 0.12954)
		(layer "F.Cu")
		(net "M_A_CPU1_SA_DQS_DN<4>")
	)
	(segment
		(start 64.342772 -244.328188)
		(end 64.342772 -243.877084)
		(width 0.12954)
		(layer "F.Cu")
		(net "M_A_CPU1_SA_DQS_DN<4>")
	)
	(segment
		(start 65.76441 -244.230906)
		(end 65.581784 -244.230652)
		(width 0.12954)
		(layer "F.Cu")
		(net "M_A_CPU1_SA_DQS_DN<4>")
	)
	(segment
		(start 59.962796 -238.985298)
		(end 59.428126 -238.985298)
		(width 0.12954)
		(layer "F.Cu")
		(net "M_A_CPU1_SA_DQS_DN<4>")
	)
	(segment
		(start 63.19774 -242.155472)
		(end 61.75883 -240.716562)
		(width 0.12954)
		(layer "F.Cu")
		(net "M_A_CPU1_SA_DQS_DN<4>")
	)
	(segment
		(start 63.19774 -243.183156)
		(end 63.19774 -242.155472)
		(width 0.12954)
		(layer "F.Cu")
		(net "M_A_CPU1_SA_DQS_DN<4>")
	)
	(segment
		(start 65.824862 -245.810278)
		(end 65.479422 -245.464838)
		(width 0.12954)
		(layer "F.Cu")
		(net "M_A_CPU1_SA_DQS_DN<4>")
	)
	(segment
		(start 76.448666 -247.000014)
		(end 76.429616 -247.000014)
		(width 0.0762)
		(layer "F.Cu")
		(net "M_A_CPU1_SA_DQS_DN<4>")
	)
	(arc
		(start 77.898498 -246.809514)
		(mid 77.82676 -246.824366)
		(end 77.759306 -246.852948)
		(width 0.0762)
		(layer "F.Cu")
		(net "M_A_CPU1_SA_DQS_DN<4>")
	)
	(arc
		(start 78.036166 -247.01119)
		(mid 78.027573 -246.869311)
		(end 77.898498 -246.809514)
		(width 0.0762)
		(layer "F.Cu")
		(net "M_A_CPU1_SA_DQS_DN<4>")
	)
	(arc
		(start 77.750924 -246.857774)
		(mid 77.614488 -246.914599)
		(end 77.467968 -246.933974)
		(width 0.0762)
		(layer "F.Cu")
		(net "M_A_CPU1_SA_DQS_DN<4>")
	)
	(segment
		(start 66.886582 -236.445298)
		(end 66.703194 -236.445298)
		(width 0.12954)
		(layer "F.Cu")
		(net "M_A_CPU1_SA_DQS_DN<3>")
	)
	(segment
		(start 70.452996 -240.011712)
		(end 70.296532 -239.855248)
		(width 0.12954)
		(layer "F.Cu")
		(net "M_A_CPU1_SA_DQS_DN<3>")
	)
	(segment
		(start 65.906396 -235.465112)
		(end 65.749932 -235.308648)
		(width 0.12954)
		(layer "F.Cu")
		(net "M_A_CPU1_SA_DQS_DN<3>")
	)
	(segment
		(start 65.754504 -236.25048)
		(end 65.754504 -235.800392)
		(width 0.12954)
		(layer "F.Cu")
		(net "M_A_CPU1_SA_DQS_DN<3>")
	)
	(segment
		(start 76.707746 -242.073938)
		(end 76.580746 -242.200938)
		(width 0.0762)
		(layer "F.Cu")
		(net "M_A_CPU1_SA_DQS_DN<3>")
	)
	(segment
		(start 70.296532 -239.855248)
		(end 70.113144 -239.855248)
		(width 0.12954)
		(layer "F.Cu")
		(net "M_A_CPU1_SA_DQS_DN<3>")
	)
	(segment
		(start 63.481204 -233.527092)
		(end 63.633096 -233.3752)
		(width 0.12954)
		(layer "F.Cu")
		(net "M_A_CPU1_SA_DQS_DN<3>")
	)
	(segment
		(start 64.613282 -234.171998)
		(end 64.429894 -234.171998)
		(width 0.12954)
		(layer "F.Cu")
		(net "M_A_CPU1_SA_DQS_DN<3>")
	)
	(segment
		(start 64.769746 -234.328462)
		(end 64.613282 -234.171998)
		(width 0.12954)
		(layer "F.Cu")
		(net "M_A_CPU1_SA_DQS_DN<3>")
	)
	(segment
		(start 67.237864 -237.73384)
		(end 66.891154 -237.38713)
		(width 0.12954)
		(layer "F.Cu")
		(net "M_A_CPU1_SA_DQS_DN<3>")
	)
	(segment
		(start 66.101214 -236.59719)
		(end 65.754504 -236.25048)
		(width 0.12954)
		(layer "F.Cu")
		(net "M_A_CPU1_SA_DQS_DN<3>")
	)
	(segment
		(start 76.580746 -242.200938)
		(end 76.040996 -242.200938)
		(width 0.0762)
		(layer "F.Cu")
		(net "M_A_CPU1_SA_DQS_DN<3>")
	)
	(segment
		(start 68.179696 -237.738412)
		(end 68.023232 -237.581948)
		(width 0.12954)
		(layer "F.Cu")
		(net "M_A_CPU1_SA_DQS_DN<3>")
	)
	(segment
		(start 63.633096 -233.191812)
		(end 61.626242 -231.184958)
		(width 0.12954)
		(layer "F.Cu")
		(net "M_A_CPU1_SA_DQS_DN<3>")
	)
	(segment
		(start 69.961252 -240.00714)
		(end 69.511164 -240.00714)
		(width 0.12954)
		(layer "F.Cu")
		(net "M_A_CPU1_SA_DQS_DN<3>")
	)
	(segment
		(start 68.023232 -237.581948)
		(end 67.839844 -237.581948)
		(width 0.12954)
		(layer "F.Cu")
		(net "M_A_CPU1_SA_DQS_DN<3>")
	)
	(segment
		(start 63.827914 -234.32389)
		(end 63.481204 -233.97718)
		(width 0.12954)
		(layer "F.Cu")
		(net "M_A_CPU1_SA_DQS_DN<3>")
	)
	(segment
		(start 77.467968 -242.073938)
		(end 76.707746 -242.073938)
		(width 0.0762)
		(layer "F.Cu")
		(net "M_A_CPU1_SA_DQS_DN<3>")
	)
	(segment
		(start 70.113144 -239.855248)
		(end 69.961252 -240.00714)
		(width 0.12954)
		(layer "F.Cu")
		(net "M_A_CPU1_SA_DQS_DN<3>")
	)
	(segment
		(start 77.759306 -241.992912)
		(end 77.750924 -241.997738)
		(width 0.0762)
		(layer "F.Cu")
		(net "M_A_CPU1_SA_DQS_DN<3>")
	)
	(segment
		(start 68.976494 -238.718598)
		(end 68.824602 -238.87049)
		(width 0.12954)
		(layer "F.Cu")
		(net "M_A_CPU1_SA_DQS_DN<3>")
	)
	(segment
		(start 68.027804 -238.073692)
		(end 68.179696 -237.9218)
		(width 0.12954)
		(layer "F.Cu")
		(net "M_A_CPU1_SA_DQS_DN<3>")
	)
	(segment
		(start 65.754504 -235.800392)
		(end 65.906396 -235.6485)
		(width 0.12954)
		(layer "F.Cu")
		(net "M_A_CPU1_SA_DQS_DN<3>")
	)
	(segment
		(start 75.955906 -242.266978)
		(end 72.708262 -242.266978)
		(width 0.12954)
		(layer "F.Cu")
		(net "M_A_CPU1_SA_DQS_DN<3>")
	)
	(segment
		(start 67.687952 -237.73384)
		(end 67.237864 -237.73384)
		(width 0.12954)
		(layer "F.Cu")
		(net "M_A_CPU1_SA_DQS_DN<3>")
	)
	(segment
		(start 65.749932 -235.308648)
		(end 65.566544 -235.308648)
		(width 0.12954)
		(layer "F.Cu")
		(net "M_A_CPU1_SA_DQS_DN<3>")
	)
	(segment
		(start 61.626242 -230.397558)
		(end 60.600336 -229.371652)
		(width 0.12954)
		(layer "F.Cu")
		(net "M_A_CPU1_SA_DQS_DN<3>")
	)
	(segment
		(start 71.249794 -240.991898)
		(end 71.097902 -241.14379)
		(width 0.12954)
		(layer "F.Cu")
		(net "M_A_CPU1_SA_DQS_DN<3>")
	)
	(segment
		(start 77.937868 -242.320318)
		(end 78.036166 -242.151154)
		(width 0.0762)
		(layer "F.Cu")
		(net "M_A_CPU1_SA_DQS_DN<3>")
	)
	(segment
		(start 64.617854 -234.663742)
		(end 64.769746 -234.51185)
		(width 0.12954)
		(layer "F.Cu")
		(net "M_A_CPU1_SA_DQS_DN<3>")
	)
	(segment
		(start 76.040996 -242.200938)
		(end 75.974956 -242.266978)
		(width 0.0762)
		(layer "F.Cu")
		(net "M_A_CPU1_SA_DQS_DN<3>")
	)
	(segment
		(start 63.633096 -233.3752)
		(end 63.633096 -233.191812)
		(width 0.12954)
		(layer "F.Cu")
		(net "M_A_CPU1_SA_DQS_DN<3>")
	)
	(segment
		(start 69.164454 -239.66043)
		(end 69.164454 -239.210342)
		(width 0.12954)
		(layer "F.Cu")
		(net "M_A_CPU1_SA_DQS_DN<3>")
	)
	(segment
		(start 61.626242 -231.184958)
		(end 61.626242 -230.397558)
		(width 0.12954)
		(layer "F.Cu")
		(net "M_A_CPU1_SA_DQS_DN<3>")
	)
	(segment
		(start 70.647814 -241.14379)
		(end 70.301104 -240.79708)
		(width 0.12954)
		(layer "F.Cu")
		(net "M_A_CPU1_SA_DQS_DN<3>")
	)
	(segment
		(start 72.708262 -242.266978)
		(end 71.433182 -240.991898)
		(width 0.12954)
		(layer "F.Cu")
		(net "M_A_CPU1_SA_DQS_DN<3>")
	)
	(segment
		(start 70.452996 -240.1951)
		(end 70.452996 -240.011712)
		(width 0.12954)
		(layer "F.Cu")
		(net "M_A_CPU1_SA_DQS_DN<3>")
	)
	(segment
		(start 64.278002 -234.32389)
		(end 63.827914 -234.32389)
		(width 0.12954)
		(layer "F.Cu")
		(net "M_A_CPU1_SA_DQS_DN<3>")
	)
	(segment
		(start 68.824602 -238.87049)
		(end 68.374514 -238.87049)
		(width 0.12954)
		(layer "F.Cu")
		(net "M_A_CPU1_SA_DQS_DN<3>")
	)
	(segment
		(start 59.962796 -229.635304)
		(end 59.428126 -229.635304)
		(width 0.12954)
		(layer "F.Cu")
		(net "M_A_CPU1_SA_DQS_DN<3>")
	)
	(segment
		(start 64.964564 -235.46054)
		(end 64.617854 -235.11383)
		(width 0.12954)
		(layer "F.Cu")
		(net "M_A_CPU1_SA_DQS_DN<3>")
	)
	(segment
		(start 68.027804 -238.52378)
		(end 68.027804 -238.073692)
		(width 0.12954)
		(layer "F.Cu")
		(net "M_A_CPU1_SA_DQS_DN<3>")
	)
	(segment
		(start 68.179696 -237.9218)
		(end 68.179696 -237.738412)
		(width 0.12954)
		(layer "F.Cu")
		(net "M_A_CPU1_SA_DQS_DN<3>")
	)
	(segment
		(start 64.429894 -234.171998)
		(end 64.278002 -234.32389)
		(width 0.12954)
		(layer "F.Cu")
		(net "M_A_CPU1_SA_DQS_DN<3>")
	)
	(segment
		(start 69.511164 -240.00714)
		(end 69.164454 -239.66043)
		(width 0.12954)
		(layer "F.Cu")
		(net "M_A_CPU1_SA_DQS_DN<3>")
	)
	(segment
		(start 69.316346 -238.875062)
		(end 69.159882 -238.718598)
		(width 0.12954)
		(layer "F.Cu")
		(net "M_A_CPU1_SA_DQS_DN<3>")
	)
	(segment
		(start 66.551302 -236.59719)
		(end 66.101214 -236.59719)
		(width 0.12954)
		(layer "F.Cu")
		(net "M_A_CPU1_SA_DQS_DN<3>")
	)
	(segment
		(start 71.433182 -240.991898)
		(end 71.249794 -240.991898)
		(width 0.12954)
		(layer "F.Cu")
		(net "M_A_CPU1_SA_DQS_DN<3>")
	)
	(segment
		(start 75.974956 -242.266978)
		(end 75.955906 -242.266978)
		(width 0.0762)
		(layer "F.Cu")
		(net "M_A_CPU1_SA_DQS_DN<3>")
	)
	(segment
		(start 70.301104 -240.79708)
		(end 70.301104 -240.346992)
		(width 0.12954)
		(layer "F.Cu")
		(net "M_A_CPU1_SA_DQS_DN<3>")
	)
	(segment
		(start 71.097902 -241.14379)
		(end 70.647814 -241.14379)
		(width 0.12954)
		(layer "F.Cu")
		(net "M_A_CPU1_SA_DQS_DN<3>")
	)
	(segment
		(start 68.374514 -238.87049)
		(end 68.027804 -238.52378)
		(width 0.12954)
		(layer "F.Cu")
		(net "M_A_CPU1_SA_DQS_DN<3>")
	)
	(segment
		(start 66.891154 -236.937042)
		(end 67.043046 -236.78515)
		(width 0.12954)
		(layer "F.Cu")
		(net "M_A_CPU1_SA_DQS_DN<3>")
	)
	(segment
		(start 65.414652 -235.46054)
		(end 64.964564 -235.46054)
		(width 0.12954)
		(layer "F.Cu")
		(net "M_A_CPU1_SA_DQS_DN<3>")
	)
	(segment
		(start 67.839844 -237.581948)
		(end 67.687952 -237.73384)
		(width 0.12954)
		(layer "F.Cu")
		(net "M_A_CPU1_SA_DQS_DN<3>")
	)
	(segment
		(start 64.617854 -235.11383)
		(end 64.617854 -234.663742)
		(width 0.12954)
		(layer "F.Cu")
		(net "M_A_CPU1_SA_DQS_DN<3>")
	)
	(segment
		(start 60.600336 -229.371652)
		(end 60.226448 -229.371652)
		(width 0.12954)
		(layer "F.Cu")
		(net "M_A_CPU1_SA_DQS_DN<3>")
	)
	(segment
		(start 66.703194 -236.445298)
		(end 66.551302 -236.59719)
		(width 0.12954)
		(layer "F.Cu")
		(net "M_A_CPU1_SA_DQS_DN<3>")
	)
	(segment
		(start 67.043046 -236.78515)
		(end 67.043046 -236.601762)
		(width 0.12954)
		(layer "F.Cu")
		(net "M_A_CPU1_SA_DQS_DN<3>")
	)
	(segment
		(start 67.043046 -236.601762)
		(end 66.886582 -236.445298)
		(width 0.12954)
		(layer "F.Cu")
		(net "M_A_CPU1_SA_DQS_DN<3>")
	)
	(segment
		(start 63.481204 -233.97718)
		(end 63.481204 -233.527092)
		(width 0.12954)
		(layer "F.Cu")
		(net "M_A_CPU1_SA_DQS_DN<3>")
	)
	(segment
		(start 69.159882 -238.718598)
		(end 68.976494 -238.718598)
		(width 0.12954)
		(layer "F.Cu")
		(net "M_A_CPU1_SA_DQS_DN<3>")
	)
	(segment
		(start 70.301104 -240.346992)
		(end 70.452996 -240.1951)
		(width 0.12954)
		(layer "F.Cu")
		(net "M_A_CPU1_SA_DQS_DN<3>")
	)
	(segment
		(start 64.769746 -234.51185)
		(end 64.769746 -234.328462)
		(width 0.12954)
		(layer "F.Cu")
		(net "M_A_CPU1_SA_DQS_DN<3>")
	)
	(segment
		(start 69.164454 -239.210342)
		(end 69.316346 -239.05845)
		(width 0.12954)
		(layer "F.Cu")
		(net "M_A_CPU1_SA_DQS_DN<3>")
	)
	(segment
		(start 60.226448 -229.371652)
		(end 59.962796 -229.635304)
		(width 0.12954)
		(layer "F.Cu")
		(net "M_A_CPU1_SA_DQS_DN<3>")
	)
	(segment
		(start 65.566544 -235.308648)
		(end 65.414652 -235.46054)
		(width 0.12954)
		(layer "F.Cu")
		(net "M_A_CPU1_SA_DQS_DN<3>")
	)
	(segment
		(start 66.891154 -237.38713)
		(end 66.891154 -236.937042)
		(width 0.12954)
		(layer "F.Cu")
		(net "M_A_CPU1_SA_DQS_DN<3>")
	)
	(segment
		(start 69.316346 -239.05845)
		(end 69.316346 -238.875062)
		(width 0.12954)
		(layer "F.Cu")
		(net "M_A_CPU1_SA_DQS_DN<3>")
	)
	(segment
		(start 65.906396 -235.6485)
		(end 65.906396 -235.465112)
		(width 0.12954)
		(layer "F.Cu")
		(net "M_A_CPU1_SA_DQS_DN<3>")
	)
	(arc
		(start 78.036166 -242.151154)
		(mid 78.027573 -242.009275)
		(end 77.898498 -241.949478)
		(width 0.0762)
		(layer "F.Cu")
		(net "M_A_CPU1_SA_DQS_DN<3>")
	)
	(arc
		(start 77.750924 -241.997738)
		(mid 77.614488 -242.054563)
		(end 77.467968 -242.073938)
		(width 0.0762)
		(layer "F.Cu")
		(net "M_A_CPU1_SA_DQS_DN<3>")
	)
	(arc
		(start 77.898498 -241.949478)
		(mid 77.82676 -241.96433)
		(end 77.759306 -241.992912)
		(width 0.0762)
		(layer "F.Cu")
		(net "M_A_CPU1_SA_DQS_DN<3>")
	)
	(segment
		(start 64.106806 -221.981776)
		(end 63.655702 -221.981776)
		(width 0.12954)
		(layer "F.Cu")
		(net "M_A_CPU1_SA_DQS_DN<2>")
	)
	(segment
		(start 60.226448 -220.021658)
		(end 59.962796 -220.28531)
		(width 0.12954)
		(layer "F.Cu")
		(net "M_A_CPU1_SA_DQS_DN<2>")
	)
	(segment
		(start 65.91427 -222.629984)
		(end 65.731898 -222.629984)
		(width 0.12954)
		(layer "F.Cu")
		(net "M_A_CPU1_SA_DQS_DN<2>")
	)
	(segment
		(start 65.731898 -222.629984)
		(end 65.243456 -223.118426)
		(width 0.12954)
		(layer "F.Cu")
		(net "M_A_CPU1_SA_DQS_DN<2>")
	)
	(segment
		(start 77.937868 -237.460282)
		(end 78.036166 -237.291118)
		(width 0.0762)
		(layer "F.Cu")
		(net "M_A_CPU1_SA_DQS_DN<2>")
	)
	(segment
		(start 63.655702 -221.981776)
		(end 63.310516 -221.63659)
		(width 0.12954)
		(layer "F.Cu")
		(net "M_A_CPU1_SA_DQS_DN<2>")
	)
	(segment
		(start 76.148946 -237.425484)
		(end 74.216768 -237.425484)
		(width 0.12954)
		(layer "F.Cu")
		(net "M_A_CPU1_SA_DQS_DN<2>")
	)
	(segment
		(start 77.759306 -237.132876)
		(end 77.750924 -237.137702)
		(width 0.0762)
		(layer "F.Cu")
		(net "M_A_CPU1_SA_DQS_DN<2>")
	)
	(segment
		(start 65.101978 -221.667324)
		(end 65.101978 -221.484952)
		(width 0.12954)
		(layer "F.Cu")
		(net "M_A_CPU1_SA_DQS_DN<2>")
	)
	(segment
		(start 76.433172 -237.359444)
		(end 76.234036 -237.359444)
		(width 0.0762)
		(layer "F.Cu")
		(net "M_A_CPU1_SA_DQS_DN<2>")
	)
	(segment
		(start 77.467968 -237.213902)
		(end 76.578714 -237.213902)
		(width 0.0762)
		(layer "F.Cu")
		(net "M_A_CPU1_SA_DQS_DN<2>")
	)
	(segment
		(start 65.243456 -223.118426)
		(end 64.792352 -223.118426)
		(width 0.12954)
		(layer "F.Cu")
		(net "M_A_CPU1_SA_DQS_DN<2>")
	)
	(segment
		(start 62.970156 -220.845126)
		(end 62.519052 -220.845126)
		(width 0.12954)
		(layer "F.Cu")
		(net "M_A_CPU1_SA_DQS_DN<2>")
	)
	(segment
		(start 63.798958 -220.514672)
		(end 63.64097 -220.356684)
		(width 0.12954)
		(layer "F.Cu")
		(net "M_A_CPU1_SA_DQS_DN<2>")
	)
	(segment
		(start 76.167996 -237.425484)
		(end 76.148946 -237.425484)
		(width 0.0762)
		(layer "F.Cu")
		(net "M_A_CPU1_SA_DQS_DN<2>")
	)
	(segment
		(start 64.761618 -221.326964)
		(end 64.106806 -221.981776)
		(width 0.12954)
		(layer "F.Cu")
		(net "M_A_CPU1_SA_DQS_DN<2>")
	)
	(segment
		(start 74.216768 -237.425484)
		(end 66.08826 -229.296976)
		(width 0.12954)
		(layer "F.Cu")
		(net "M_A_CPU1_SA_DQS_DN<2>")
	)
	(segment
		(start 64.447166 -222.77324)
		(end 64.447166 -222.322136)
		(width 0.12954)
		(layer "F.Cu")
		(net "M_A_CPU1_SA_DQS_DN<2>")
	)
	(segment
		(start 64.447166 -222.322136)
		(end 65.101978 -221.667324)
		(width 0.12954)
		(layer "F.Cu")
		(net "M_A_CPU1_SA_DQS_DN<2>")
	)
	(segment
		(start 61.695584 -220.021658)
		(end 60.226448 -220.021658)
		(width 0.12954)
		(layer "F.Cu")
		(net "M_A_CPU1_SA_DQS_DN<2>")
	)
	(segment
		(start 63.458598 -220.356684)
		(end 62.970156 -220.845126)
		(width 0.12954)
		(layer "F.Cu")
		(net "M_A_CPU1_SA_DQS_DN<2>")
	)
	(segment
		(start 66.072258 -222.787972)
		(end 65.91427 -222.629984)
		(width 0.12954)
		(layer "F.Cu")
		(net "M_A_CPU1_SA_DQS_DN<2>")
	)
	(segment
		(start 64.792352 -223.118426)
		(end 64.447166 -222.77324)
		(width 0.12954)
		(layer "F.Cu")
		(net "M_A_CPU1_SA_DQS_DN<2>")
	)
	(segment
		(start 59.962796 -220.28531)
		(end 59.428126 -220.28531)
		(width 0.12954)
		(layer "F.Cu")
		(net "M_A_CPU1_SA_DQS_DN<2>")
	)
	(segment
		(start 76.234036 -237.359444)
		(end 76.167996 -237.425484)
		(width 0.0762)
		(layer "F.Cu")
		(net "M_A_CPU1_SA_DQS_DN<2>")
	)
	(segment
		(start 63.310516 -221.185486)
		(end 63.798958 -220.697044)
		(width 0.12954)
		(layer "F.Cu")
		(net "M_A_CPU1_SA_DQS_DN<2>")
	)
	(segment
		(start 63.64097 -220.356684)
		(end 63.458598 -220.356684)
		(width 0.12954)
		(layer "F.Cu")
		(net "M_A_CPU1_SA_DQS_DN<2>")
	)
	(segment
		(start 63.798958 -220.697044)
		(end 63.798958 -220.514672)
		(width 0.12954)
		(layer "F.Cu")
		(net "M_A_CPU1_SA_DQS_DN<2>")
	)
	(segment
		(start 65.583816 -223.90989)
		(end 65.583816 -223.458786)
		(width 0.12954)
		(layer "F.Cu")
		(net "M_A_CPU1_SA_DQS_DN<2>")
	)
	(segment
		(start 62.519052 -220.845126)
		(end 61.695584 -220.021658)
		(width 0.12954)
		(layer "F.Cu")
		(net "M_A_CPU1_SA_DQS_DN<2>")
	)
	(segment
		(start 66.08826 -224.414334)
		(end 65.583816 -223.90989)
		(width 0.12954)
		(layer "F.Cu")
		(net "M_A_CPU1_SA_DQS_DN<2>")
	)
	(segment
		(start 66.072258 -222.970344)
		(end 66.072258 -222.787972)
		(width 0.12954)
		(layer "F.Cu")
		(net "M_A_CPU1_SA_DQS_DN<2>")
	)
	(segment
		(start 76.578714 -237.213902)
		(end 76.433172 -237.359444)
		(width 0.0762)
		(layer "F.Cu")
		(net "M_A_CPU1_SA_DQS_DN<2>")
	)
	(segment
		(start 65.101978 -221.484952)
		(end 64.94399 -221.326964)
		(width 0.12954)
		(layer "F.Cu")
		(net "M_A_CPU1_SA_DQS_DN<2>")
	)
	(segment
		(start 63.310516 -221.63659)
		(end 63.310516 -221.185486)
		(width 0.12954)
		(layer "F.Cu")
		(net "M_A_CPU1_SA_DQS_DN<2>")
	)
	(segment
		(start 65.583816 -223.458786)
		(end 66.072258 -222.970344)
		(width 0.12954)
		(layer "F.Cu")
		(net "M_A_CPU1_SA_DQS_DN<2>")
	)
	(segment
		(start 66.08826 -229.296976)
		(end 66.08826 -224.414334)
		(width 0.12954)
		(layer "F.Cu")
		(net "M_A_CPU1_SA_DQS_DN<2>")
	)
	(segment
		(start 64.94399 -221.326964)
		(end 64.761618 -221.326964)
		(width 0.12954)
		(layer "F.Cu")
		(net "M_A_CPU1_SA_DQS_DN<2>")
	)
	(arc
		(start 77.750924 -237.137702)
		(mid 77.614488 -237.194527)
		(end 77.467968 -237.213902)
		(width 0.0762)
		(layer "F.Cu")
		(net "M_A_CPU1_SA_DQS_DN<2>")
	)
	(arc
		(start 77.898498 -237.089442)
		(mid 77.82676 -237.104294)
		(end 77.759306 -237.132876)
		(width 0.0762)
		(layer "F.Cu")
		(net "M_A_CPU1_SA_DQS_DN<2>")
	)
	(arc
		(start 78.036166 -237.291118)
		(mid 78.027573 -237.149239)
		(end 77.898498 -237.089442)
		(width 0.0762)
		(layer "F.Cu")
		(net "M_A_CPU1_SA_DQS_DN<2>")
	)
	(segment
		(start 67.000374 -215.451182)
		(end 67.216782 -215.234774)
		(width 0.12954)
		(layer "F.Cu")
		(net "M_A_CPU1_SA_DQS_DN<1>")
	)
	(segment
		(start 64.943482 -212.961474)
		(end 64.943482 -212.779102)
		(width 0.12954)
		(layer "F.Cu")
		(net "M_A_CPU1_SA_DQS_DN<1>")
	)
	(segment
		(start 66.080132 -213.915752)
		(end 65.922144 -213.757764)
		(width 0.12954)
		(layer "F.Cu")
		(net "M_A_CPU1_SA_DQS_DN<1>")
	)
	(segment
		(start 67.216782 -215.234774)
		(end 67.216782 -215.052402)
		(width 0.12954)
		(layer "F.Cu")
		(net "M_A_CPU1_SA_DQS_DN<1>")
	)
	(segment
		(start 63.708026 -211.741258)
		(end 63.550038 -211.58327)
		(width 0.12954)
		(layer "F.Cu")
		(net "M_A_CPU1_SA_DQS_DN<1>")
	)
	(segment
		(start 67.000374 -215.902286)
		(end 67.000374 -215.451182)
		(width 0.12954)
		(layer "F.Cu")
		(net "M_A_CPU1_SA_DQS_DN<1>")
	)
	(segment
		(start 64.603122 -212.621114)
		(end 64.386714 -212.837522)
		(width 0.12954)
		(layer "F.Cu")
		(net "M_A_CPU1_SA_DQS_DN<1>")
	)
	(segment
		(start 76.178156 -232.419906)
		(end 75.45959 -232.419906)
		(width 0.12954)
		(layer "F.Cu")
		(net "M_A_CPU1_SA_DQS_DN<1>")
	)
	(segment
		(start 76.197206 -232.419906)
		(end 76.178156 -232.419906)
		(width 0.0762)
		(layer "F.Cu")
		(net "M_A_CPU1_SA_DQS_DN<1>")
	)
	(segment
		(start 68.137024 -216.587832)
		(end 68.353432 -216.371424)
		(width 0.12954)
		(layer "F.Cu")
		(net "M_A_CPU1_SA_DQS_DN<1>")
	)
	(segment
		(start 77.937868 -232.600246)
		(end 78.036166 -232.431082)
		(width 0.0762)
		(layer "F.Cu")
		(net "M_A_CPU1_SA_DQS_DN<1>")
	)
	(segment
		(start 66.080132 -214.098124)
		(end 66.080132 -213.915752)
		(width 0.12954)
		(layer "F.Cu")
		(net "M_A_CPU1_SA_DQS_DN<1>")
	)
	(segment
		(start 69.332094 -217.167714)
		(end 69.149722 -217.167714)
		(width 0.12954)
		(layer "F.Cu")
		(net "M_A_CPU1_SA_DQS_DN<1>")
	)
	(segment
		(start 69.490082 -217.325702)
		(end 69.332094 -217.167714)
		(width 0.12954)
		(layer "F.Cu")
		(net "M_A_CPU1_SA_DQS_DN<1>")
	)
	(segment
		(start 69.149722 -217.167714)
		(end 68.933314 -217.384122)
		(width 0.12954)
		(layer "F.Cu")
		(net "M_A_CPU1_SA_DQS_DN<1>")
	)
	(segment
		(start 67.058794 -214.894414)
		(end 66.876422 -214.894414)
		(width 0.12954)
		(layer "F.Cu")
		(net "M_A_CPU1_SA_DQS_DN<1>")
	)
	(segment
		(start 63.590424 -212.041232)
		(end 63.708026 -211.92363)
		(width 0.12954)
		(layer "F.Cu")
		(net "M_A_CPU1_SA_DQS_DN<1>")
	)
	(segment
		(start 68.353432 -216.189052)
		(end 68.195444 -216.031064)
		(width 0.12954)
		(layer "F.Cu")
		(net "M_A_CPU1_SA_DQS_DN<1>")
	)
	(segment
		(start 63.550038 -211.58327)
		(end 63.367666 -211.58327)
		(width 0.12954)
		(layer "F.Cu")
		(net "M_A_CPU1_SA_DQS_DN<1>")
	)
	(segment
		(start 64.785494 -212.621114)
		(end 64.603122 -212.621114)
		(width 0.12954)
		(layer "F.Cu")
		(net "M_A_CPU1_SA_DQS_DN<1>")
	)
	(segment
		(start 65.07226 -213.974172)
		(end 64.727074 -213.628986)
		(width 0.12954)
		(layer "F.Cu")
		(net "M_A_CPU1_SA_DQS_DN<1>")
	)
	(segment
		(start 59.962796 -210.935316)
		(end 59.428126 -210.935316)
		(width 0.12954)
		(layer "F.Cu")
		(net "M_A_CPU1_SA_DQS_DN<1>")
	)
	(segment
		(start 67.34556 -216.247472)
		(end 67.000374 -215.902286)
		(width 0.12954)
		(layer "F.Cu")
		(net "M_A_CPU1_SA_DQS_DN<1>")
	)
	(segment
		(start 77.467968 -232.353866)
		(end 76.263246 -232.353866)
		(width 0.0762)
		(layer "F.Cu")
		(net "M_A_CPU1_SA_DQS_DN<1>")
	)
	(segment
		(start 68.48221 -217.384122)
		(end 68.137024 -217.038936)
		(width 0.12954)
		(layer "F.Cu")
		(net "M_A_CPU1_SA_DQS_DN<1>")
	)
	(segment
		(start 64.727074 -213.628986)
		(end 64.727074 -213.177882)
		(width 0.12954)
		(layer "F.Cu")
		(net "M_A_CPU1_SA_DQS_DN<1>")
	)
	(segment
		(start 75.45959 -232.419906)
		(end 70.47484 -227.435156)
		(width 0.12954)
		(layer "F.Cu")
		(net "M_A_CPU1_SA_DQS_DN<1>")
	)
	(segment
		(start 65.863724 -214.314532)
		(end 66.080132 -214.098124)
		(width 0.12954)
		(layer "F.Cu")
		(net "M_A_CPU1_SA_DQS_DN<1>")
	)
	(segment
		(start 63.708026 -211.92363)
		(end 63.708026 -211.741258)
		(width 0.12954)
		(layer "F.Cu")
		(net "M_A_CPU1_SA_DQS_DN<1>")
	)
	(segment
		(start 63.590424 -212.492336)
		(end 63.590424 -212.041232)
		(width 0.12954)
		(layer "F.Cu")
		(net "M_A_CPU1_SA_DQS_DN<1>")
	)
	(segment
		(start 63.367666 -211.58327)
		(end 63.250064 -211.700872)
		(width 0.12954)
		(layer "F.Cu")
		(net "M_A_CPU1_SA_DQS_DN<1>")
	)
	(segment
		(start 66.20891 -215.110822)
		(end 65.863724 -214.765636)
		(width 0.12954)
		(layer "F.Cu")
		(net "M_A_CPU1_SA_DQS_DN<1>")
	)
	(segment
		(start 61.462666 -211.47913)
		(end 60.6552 -210.671664)
		(width 0.12954)
		(layer "F.Cu")
		(net "M_A_CPU1_SA_DQS_DN<1>")
	)
	(segment
		(start 65.863724 -214.765636)
		(end 65.863724 -214.314532)
		(width 0.12954)
		(layer "F.Cu")
		(net "M_A_CPU1_SA_DQS_DN<1>")
	)
	(segment
		(start 67.796664 -216.247472)
		(end 67.34556 -216.247472)
		(width 0.12954)
		(layer "F.Cu")
		(net "M_A_CPU1_SA_DQS_DN<1>")
	)
	(segment
		(start 68.933314 -217.384122)
		(end 68.48221 -217.384122)
		(width 0.12954)
		(layer "F.Cu")
		(net "M_A_CPU1_SA_DQS_DN<1>")
	)
	(segment
		(start 68.137024 -217.038936)
		(end 68.137024 -216.587832)
		(width 0.12954)
		(layer "F.Cu")
		(net "M_A_CPU1_SA_DQS_DN<1>")
	)
	(segment
		(start 69.490082 -217.508074)
		(end 69.490082 -217.325702)
		(width 0.12954)
		(layer "F.Cu")
		(net "M_A_CPU1_SA_DQS_DN<1>")
	)
	(segment
		(start 62.79896 -211.700872)
		(end 62.577218 -211.47913)
		(width 0.12954)
		(layer "F.Cu")
		(net "M_A_CPU1_SA_DQS_DN<1>")
	)
	(segment
		(start 65.922144 -213.757764)
		(end 65.739772 -213.757764)
		(width 0.12954)
		(layer "F.Cu")
		(net "M_A_CPU1_SA_DQS_DN<1>")
	)
	(segment
		(start 64.386714 -212.837522)
		(end 63.93561 -212.837522)
		(width 0.12954)
		(layer "F.Cu")
		(net "M_A_CPU1_SA_DQS_DN<1>")
	)
	(segment
		(start 68.195444 -216.031064)
		(end 68.013072 -216.031064)
		(width 0.12954)
		(layer "F.Cu")
		(net "M_A_CPU1_SA_DQS_DN<1>")
	)
	(segment
		(start 69.273674 -217.724482)
		(end 69.490082 -217.508074)
		(width 0.12954)
		(layer "F.Cu")
		(net "M_A_CPU1_SA_DQS_DN<1>")
	)
	(segment
		(start 60.226448 -210.671664)
		(end 59.962796 -210.935316)
		(width 0.12954)
		(layer "F.Cu")
		(net "M_A_CPU1_SA_DQS_DN<1>")
	)
	(segment
		(start 62.577218 -211.47913)
		(end 61.462666 -211.47913)
		(width 0.12954)
		(layer "F.Cu")
		(net "M_A_CPU1_SA_DQS_DN<1>")
	)
	(segment
		(start 70.47484 -219.376752)
		(end 69.273674 -218.175586)
		(width 0.12954)
		(layer "F.Cu")
		(net "M_A_CPU1_SA_DQS_DN<1>")
	)
	(segment
		(start 65.739772 -213.757764)
		(end 65.523364 -213.974172)
		(width 0.12954)
		(layer "F.Cu")
		(net "M_A_CPU1_SA_DQS_DN<1>")
	)
	(segment
		(start 66.660014 -215.110822)
		(end 66.20891 -215.110822)
		(width 0.12954)
		(layer "F.Cu")
		(net "M_A_CPU1_SA_DQS_DN<1>")
	)
	(segment
		(start 63.250064 -211.700872)
		(end 62.79896 -211.700872)
		(width 0.12954)
		(layer "F.Cu")
		(net "M_A_CPU1_SA_DQS_DN<1>")
	)
	(segment
		(start 66.876422 -214.894414)
		(end 66.660014 -215.110822)
		(width 0.12954)
		(layer "F.Cu")
		(net "M_A_CPU1_SA_DQS_DN<1>")
	)
	(segment
		(start 65.523364 -213.974172)
		(end 65.07226 -213.974172)
		(width 0.12954)
		(layer "F.Cu")
		(net "M_A_CPU1_SA_DQS_DN<1>")
	)
	(segment
		(start 64.943482 -212.779102)
		(end 64.785494 -212.621114)
		(width 0.12954)
		(layer "F.Cu")
		(net "M_A_CPU1_SA_DQS_DN<1>")
	)
	(segment
		(start 67.216782 -215.052402)
		(end 67.058794 -214.894414)
		(width 0.12954)
		(layer "F.Cu")
		(net "M_A_CPU1_SA_DQS_DN<1>")
	)
	(segment
		(start 68.013072 -216.031064)
		(end 67.796664 -216.247472)
		(width 0.12954)
		(layer "F.Cu")
		(net "M_A_CPU1_SA_DQS_DN<1>")
	)
	(segment
		(start 60.6552 -210.671664)
		(end 60.226448 -210.671664)
		(width 0.12954)
		(layer "F.Cu")
		(net "M_A_CPU1_SA_DQS_DN<1>")
	)
	(segment
		(start 68.353432 -216.371424)
		(end 68.353432 -216.189052)
		(width 0.12954)
		(layer "F.Cu")
		(net "M_A_CPU1_SA_DQS_DN<1>")
	)
	(segment
		(start 70.47484 -227.435156)
		(end 70.47484 -219.376752)
		(width 0.12954)
		(layer "F.Cu")
		(net "M_A_CPU1_SA_DQS_DN<1>")
	)
	(segment
		(start 64.727074 -213.177882)
		(end 64.943482 -212.961474)
		(width 0.12954)
		(layer "F.Cu")
		(net "M_A_CPU1_SA_DQS_DN<1>")
	)
	(segment
		(start 77.759306 -232.27284)
		(end 77.750924 -232.277666)
		(width 0.0762)
		(layer "F.Cu")
		(net "M_A_CPU1_SA_DQS_DN<1>")
	)
	(segment
		(start 63.93561 -212.837522)
		(end 63.590424 -212.492336)
		(width 0.12954)
		(layer "F.Cu")
		(net "M_A_CPU1_SA_DQS_DN<1>")
	)
	(segment
		(start 69.273674 -218.175586)
		(end 69.273674 -217.724482)
		(width 0.12954)
		(layer "F.Cu")
		(net "M_A_CPU1_SA_DQS_DN<1>")
	)
	(segment
		(start 76.263246 -232.353866)
		(end 76.197206 -232.419906)
		(width 0.0762)
		(layer "F.Cu")
		(net "M_A_CPU1_SA_DQS_DN<1>")
	)
	(arc
		(start 77.750924 -232.277666)
		(mid 77.614488 -232.334491)
		(end 77.467968 -232.353866)
		(width 0.0762)
		(layer "F.Cu")
		(net "M_A_CPU1_SA_DQS_DN<1>")
	)
	(arc
		(start 78.036166 -232.431082)
		(mid 78.027573 -232.289203)
		(end 77.898498 -232.229406)
		(width 0.0762)
		(layer "F.Cu")
		(net "M_A_CPU1_SA_DQS_DN<1>")
	)
	(arc
		(start 77.898498 -232.229406)
		(mid 77.82676 -232.244258)
		(end 77.759306 -232.27284)
		(width 0.0762)
		(layer "F.Cu")
		(net "M_A_CPU1_SA_DQS_DN<1>")
	)
	(segment
		(start 62.645798 -202.736958)
		(end 62.470284 -202.561444)
		(width 0.12954)
		(layer "F.Cu")
		(net "M_A_CPU1_SA_DQS_DN<0>")
	)
	(segment
		(start 67.192398 -207.878934)
		(end 67.192398 -207.283558)
		(width 0.12954)
		(layer "F.Cu")
		(net "M_A_CPU1_SA_DQS_DN<0>")
	)
	(segment
		(start 76.252832 -226.901756)
		(end 74.86142 -225.510344)
		(width 0.12954)
		(layer "F.Cu")
		(net "M_A_CPU1_SA_DQS_DN<0>")
	)
	(segment
		(start 69.290184 -209.381344)
		(end 68.694808 -209.381344)
		(width 0.12954)
		(layer "F.Cu")
		(net "M_A_CPU1_SA_DQS_DN<0>")
	)
	(segment
		(start 72.700134 -212.791294)
		(end 72.104758 -212.791294)
		(width 0.12954)
		(layer "F.Cu")
		(net "M_A_CPU1_SA_DQS_DN<0>")
	)
	(segment
		(start 64.743584 -204.834744)
		(end 64.148208 -204.834744)
		(width 0.12954)
		(layer "F.Cu")
		(net "M_A_CPU1_SA_DQS_DN<0>")
	)
	(segment
		(start 68.153534 -208.244694)
		(end 67.558158 -208.244694)
		(width 0.12954)
		(layer "F.Cu")
		(net "M_A_CPU1_SA_DQS_DN<0>")
	)
	(segment
		(start 65.880234 -205.971394)
		(end 65.284858 -205.971394)
		(width 0.12954)
		(layer "F.Cu")
		(net "M_A_CPU1_SA_DQS_DN<0>")
	)
	(segment
		(start 73.541636 -215.081612)
		(end 73.194926 -214.734902)
		(width 0.12954)
		(layer "F.Cu")
		(net "M_A_CPU1_SA_DQS_DN<0>")
	)
	(segment
		(start 74.86142 -225.510344)
		(end 74.86142 -216.109296)
		(width 0.12954)
		(layer "F.Cu")
		(net "M_A_CPU1_SA_DQS_DN<0>")
	)
	(segment
		(start 66.421508 -207.108044)
		(end 66.055748 -206.742284)
		(width 0.12954)
		(layer "F.Cu")
		(net "M_A_CPU1_SA_DQS_DN<0>")
	)
	(segment
		(start 73.194926 -214.284814)
		(end 73.602596 -213.877144)
		(width 0.12954)
		(layer "F.Cu")
		(net "M_A_CPU1_SA_DQS_DN<0>")
	)
	(segment
		(start 71.738998 -212.425534)
		(end 71.738998 -211.830158)
		(width 0.12954)
		(layer "F.Cu")
		(net "M_A_CPU1_SA_DQS_DN<0>")
	)
	(segment
		(start 69.465698 -209.556858)
		(end 69.290184 -209.381344)
		(width 0.12954)
		(layer "F.Cu")
		(net "M_A_CPU1_SA_DQS_DN<0>")
	)
	(segment
		(start 74.582782 -214.673942)
		(end 74.399394 -214.673942)
		(width 0.12954)
		(layer "F.Cu")
		(net "M_A_CPU1_SA_DQS_DN<0>")
	)
	(segment
		(start 74.86142 -215.385396)
		(end 74.86142 -214.95258)
		(width 0.12954)
		(layer "F.Cu")
		(net "M_A_CPU1_SA_DQS_DN<0>")
	)
	(segment
		(start 68.329048 -209.015584)
		(end 68.329048 -208.420208)
		(width 0.12954)
		(layer "F.Cu")
		(net "M_A_CPU1_SA_DQS_DN<0>")
	)
	(segment
		(start 63.606934 -203.698094)
		(end 63.011558 -203.698094)
		(width 0.12954)
		(layer "F.Cu")
		(net "M_A_CPU1_SA_DQS_DN<0>")
	)
	(segment
		(start 63.011558 -203.698094)
		(end 62.645798 -203.332334)
		(width 0.12954)
		(layer "F.Cu")
		(net "M_A_CPU1_SA_DQS_DN<0>")
	)
	(segment
		(start 76.359766 -226.915218)
		(end 76.266294 -226.915218)
		(width 0.0762)
		(layer "F.Cu")
		(net "M_A_CPU1_SA_DQS_DN<0>")
	)
	(segment
		(start 73.602596 -213.877144)
		(end 73.602596 -213.693756)
		(width 0.12954)
		(layer "F.Cu")
		(net "M_A_CPU1_SA_DQS_DN<0>")
	)
	(segment
		(start 66.055748 -206.146908)
		(end 65.880234 -205.971394)
		(width 0.12954)
		(layer "F.Cu")
		(net "M_A_CPU1_SA_DQS_DN<0>")
	)
	(segment
		(start 73.194926 -214.734902)
		(end 73.194926 -214.284814)
		(width 0.12954)
		(layer "F.Cu")
		(net "M_A_CPU1_SA_DQS_DN<0>")
	)
	(segment
		(start 61.509148 -201.600308)
		(end 61.23051 -201.32167)
		(width 0.12954)
		(layer "F.Cu")
		(net "M_A_CPU1_SA_DQS_DN<0>")
	)
	(segment
		(start 62.645798 -203.332334)
		(end 62.645798 -202.736958)
		(width 0.12954)
		(layer "F.Cu")
		(net "M_A_CPU1_SA_DQS_DN<0>")
	)
	(segment
		(start 61.874908 -202.561444)
		(end 61.509148 -202.195684)
		(width 0.12954)
		(layer "F.Cu")
		(net "M_A_CPU1_SA_DQS_DN<0>")
	)
	(segment
		(start 77.759306 -227.413058)
		(end 77.750924 -227.417884)
		(width 0.0762)
		(layer "F.Cu")
		(net "M_A_CPU1_SA_DQS_DN<0>")
	)
	(segment
		(start 69.465698 -210.152234)
		(end 69.465698 -209.556858)
		(width 0.12954)
		(layer "F.Cu")
		(net "M_A_CPU1_SA_DQS_DN<0>")
	)
	(segment
		(start 61.23051 -201.32167)
		(end 60.226448 -201.32167)
		(width 0.12954)
		(layer "F.Cu")
		(net "M_A_CPU1_SA_DQS_DN<0>")
	)
	(segment
		(start 64.919098 -205.010258)
		(end 64.743584 -204.834744)
		(width 0.12954)
		(layer "F.Cu")
		(net "M_A_CPU1_SA_DQS_DN<0>")
	)
	(segment
		(start 70.602348 -210.693508)
		(end 70.426834 -210.517994)
		(width 0.12954)
		(layer "F.Cu")
		(net "M_A_CPU1_SA_DQS_DN<0>")
	)
	(segment
		(start 64.148208 -204.834744)
		(end 63.782448 -204.468984)
		(width 0.12954)
		(layer "F.Cu")
		(net "M_A_CPU1_SA_DQS_DN<0>")
	)
	(segment
		(start 73.602596 -213.693756)
		(end 72.700134 -212.791294)
		(width 0.12954)
		(layer "F.Cu")
		(net "M_A_CPU1_SA_DQS_DN<0>")
	)
	(segment
		(start 68.694808 -209.381344)
		(end 68.329048 -209.015584)
		(width 0.12954)
		(layer "F.Cu")
		(net "M_A_CPU1_SA_DQS_DN<0>")
	)
	(segment
		(start 76.266294 -226.915218)
		(end 76.252832 -226.901756)
		(width 0.0762)
		(layer "F.Cu")
		(net "M_A_CPU1_SA_DQS_DN<0>")
	)
	(segment
		(start 76.938632 -227.494084)
		(end 76.359766 -226.915218)
		(width 0.0762)
		(layer "F.Cu")
		(net "M_A_CPU1_SA_DQS_DN<0>")
	)
	(segment
		(start 64.919098 -205.605634)
		(end 64.919098 -205.010258)
		(width 0.12954)
		(layer "F.Cu")
		(net "M_A_CPU1_SA_DQS_DN<0>")
	)
	(segment
		(start 77.467968 -227.494084)
		(end 76.938632 -227.494084)
		(width 0.0762)
		(layer "F.Cu")
		(net "M_A_CPU1_SA_DQS_DN<0>")
	)
	(segment
		(start 66.055748 -206.742284)
		(end 66.055748 -206.146908)
		(width 0.12954)
		(layer "F.Cu")
		(net "M_A_CPU1_SA_DQS_DN<0>")
	)
	(segment
		(start 61.509148 -202.195684)
		(end 61.509148 -201.600308)
		(width 0.12954)
		(layer "F.Cu")
		(net "M_A_CPU1_SA_DQS_DN<0>")
	)
	(segment
		(start 60.226448 -201.32167)
		(end 59.962796 -201.585322)
		(width 0.12954)
		(layer "F.Cu")
		(net "M_A_CPU1_SA_DQS_DN<0>")
	)
	(segment
		(start 70.602348 -211.288884)
		(end 70.602348 -210.693508)
		(width 0.12954)
		(layer "F.Cu")
		(net "M_A_CPU1_SA_DQS_DN<0>")
	)
	(segment
		(start 74.86142 -214.95258)
		(end 74.582782 -214.673942)
		(width 0.12954)
		(layer "F.Cu")
		(net "M_A_CPU1_SA_DQS_DN<0>")
	)
	(segment
		(start 67.192398 -207.283558)
		(end 67.016884 -207.108044)
		(width 0.12954)
		(layer "F.Cu")
		(net "M_A_CPU1_SA_DQS_DN<0>")
	)
	(segment
		(start 65.284858 -205.971394)
		(end 64.919098 -205.605634)
		(width 0.12954)
		(layer "F.Cu")
		(net "M_A_CPU1_SA_DQS_DN<0>")
	)
	(segment
		(start 70.968108 -211.654644)
		(end 70.602348 -211.288884)
		(width 0.12954)
		(layer "F.Cu")
		(net "M_A_CPU1_SA_DQS_DN<0>")
	)
	(segment
		(start 59.962796 -201.585322)
		(end 59.428126 -201.585322)
		(width 0.12954)
		(layer "F.Cu")
		(net "M_A_CPU1_SA_DQS_DN<0>")
	)
	(segment
		(start 74.69378 -215.553036)
		(end 74.86142 -215.385396)
		(width 0.12954)
		(layer "F.Cu")
		(net "M_A_CPU1_SA_DQS_DN<0>")
	)
	(segment
		(start 70.426834 -210.517994)
		(end 69.831458 -210.517994)
		(width 0.12954)
		(layer "F.Cu")
		(net "M_A_CPU1_SA_DQS_DN<0>")
	)
	(segment
		(start 74.399394 -214.673942)
		(end 73.991724 -215.081612)
		(width 0.12954)
		(layer "F.Cu")
		(net "M_A_CPU1_SA_DQS_DN<0>")
	)
	(segment
		(start 73.991724 -215.081612)
		(end 73.541636 -215.081612)
		(width 0.12954)
		(layer "F.Cu")
		(net "M_A_CPU1_SA_DQS_DN<0>")
	)
	(segment
		(start 68.329048 -208.420208)
		(end 68.153534 -208.244694)
		(width 0.12954)
		(layer "F.Cu")
		(net "M_A_CPU1_SA_DQS_DN<0>")
	)
	(segment
		(start 71.738998 -211.830158)
		(end 71.563484 -211.654644)
		(width 0.12954)
		(layer "F.Cu")
		(net "M_A_CPU1_SA_DQS_DN<0>")
	)
	(segment
		(start 69.831458 -210.517994)
		(end 69.465698 -210.152234)
		(width 0.12954)
		(layer "F.Cu")
		(net "M_A_CPU1_SA_DQS_DN<0>")
	)
	(segment
		(start 67.558158 -208.244694)
		(end 67.192398 -207.878934)
		(width 0.12954)
		(layer "F.Cu")
		(net "M_A_CPU1_SA_DQS_DN<0>")
	)
	(segment
		(start 67.016884 -207.108044)
		(end 66.421508 -207.108044)
		(width 0.12954)
		(layer "F.Cu")
		(net "M_A_CPU1_SA_DQS_DN<0>")
	)
	(segment
		(start 72.104758 -212.791294)
		(end 71.738998 -212.425534)
		(width 0.12954)
		(layer "F.Cu")
		(net "M_A_CPU1_SA_DQS_DN<0>")
	)
	(segment
		(start 74.86142 -216.109296)
		(end 74.69378 -215.941656)
		(width 0.12954)
		(layer "F.Cu")
		(net "M_A_CPU1_SA_DQS_DN<0>")
	)
	(segment
		(start 63.782448 -203.873608)
		(end 63.606934 -203.698094)
		(width 0.12954)
		(layer "F.Cu")
		(net "M_A_CPU1_SA_DQS_DN<0>")
	)
	(segment
		(start 63.782448 -204.468984)
		(end 63.782448 -203.873608)
		(width 0.12954)
		(layer "F.Cu")
		(net "M_A_CPU1_SA_DQS_DN<0>")
	)
	(segment
		(start 62.470284 -202.561444)
		(end 61.874908 -202.561444)
		(width 0.12954)
		(layer "F.Cu")
		(net "M_A_CPU1_SA_DQS_DN<0>")
	)
	(segment
		(start 71.563484 -211.654644)
		(end 70.968108 -211.654644)
		(width 0.12954)
		(layer "F.Cu")
		(net "M_A_CPU1_SA_DQS_DN<0>")
	)
	(segment
		(start 74.69378 -215.941656)
		(end 74.69378 -215.553036)
		(width 0.12954)
		(layer "F.Cu")
		(net "M_A_CPU1_SA_DQS_DN<0>")
	)
	(segment
		(start 77.937868 -227.740464)
		(end 78.036166 -227.5713)
		(width 0.0762)
		(layer "F.Cu")
		(net "M_A_CPU1_SA_DQS_DN<0>")
	)
	(arc
		(start 77.898498 -227.369624)
		(mid 77.82676 -227.384476)
		(end 77.759306 -227.413058)
		(width 0.0762)
		(layer "F.Cu")
		(net "M_A_CPU1_SA_DQS_DN<0>")
	)
	(arc
		(start 78.036166 -227.5713)
		(mid 78.027573 -227.429421)
		(end 77.898498 -227.369624)
		(width 0.0762)
		(layer "F.Cu")
		(net "M_A_CPU1_SA_DQS_DN<0>")
	)
	(arc
		(start 77.750924 -227.417884)
		(mid 77.614488 -227.474709)
		(end 77.467968 -227.494084)
		(width 0.0762)
		(layer "F.Cu")
		(net "M_A_CPU1_SA_DQS_DN<0>")
	)
	(segment
		(start 62.727078 -209.022696)
		(end 62.576202 -209.022696)
		(width 0.10668)
		(layer "F.Cu")
		(net "M_A_CPU1_SA_DQ<9>")
	)
	(segment
		(start 77.759306 -231.30764)
		(end 77.750924 -231.302814)
		(width 0.0762)
		(layer "F.Cu")
		(net "M_A_CPU1_SA_DQ<9>")
	)
	(segment
		(start 62.01537 -209.432398)
		(end 61.884052 -209.30108)
		(width 0.10668)
		(layer "F.Cu")
		(net "M_A_CPU1_SA_DQ<9>")
	)
	(segment
		(start 62.166246 -209.432652)
		(end 62.01537 -209.432398)
		(width 0.10668)
		(layer "F.Cu")
		(net "M_A_CPU1_SA_DQ<9>")
	)
	(segment
		(start 76.206096 -231.226614)
		(end 75.80376 -231.226614)
		(width 0.10668)
		(layer "F.Cu")
		(net "M_A_CPU1_SA_DQ<9>")
	)
	(segment
		(start 62.294008 -208.740248)
		(end 62.294262 -208.58988)
		(width 0.10668)
		(layer "F.Cu")
		(net "M_A_CPU1_SA_DQ<9>")
	)
	(segment
		(start 62.453012 -209.860896)
		(end 62.453012 -209.71002)
		(width 0.10668)
		(layer "F.Cu")
		(net "M_A_CPU1_SA_DQ<9>")
	)
	(segment
		(start 77.467968 -231.226614)
		(end 76.206096 -231.226614)
		(width 0.0762)
		(layer "F.Cu")
		(net "M_A_CPU1_SA_DQ<9>")
	)
	(segment
		(start 62.453012 -209.71002)
		(end 62.858396 -209.304636)
		(width 0.10668)
		(layer "F.Cu")
		(net "M_A_CPU1_SA_DQ<9>")
	)
	(segment
		(start 61.884052 -209.150204)
		(end 62.294008 -208.740248)
		(width 0.10668)
		(layer "F.Cu")
		(net "M_A_CPU1_SA_DQ<9>")
	)
	(segment
		(start 62.735206 -209.992468)
		(end 62.58433 -209.992214)
		(width 0.10668)
		(layer "F.Cu")
		(net "M_A_CPU1_SA_DQ<9>")
	)
	(segment
		(start 62.58433 -209.992214)
		(end 62.453012 -209.860896)
		(width 0.10668)
		(layer "F.Cu")
		(net "M_A_CPU1_SA_DQ<9>")
	)
	(segment
		(start 63.291466 -209.587084)
		(end 63.14059 -209.587084)
		(width 0.10668)
		(layer "F.Cu")
		(net "M_A_CPU1_SA_DQ<9>")
	)
	(segment
		(start 63.14059 -209.587084)
		(end 62.735206 -209.992468)
		(width 0.10668)
		(layer "F.Cu")
		(net "M_A_CPU1_SA_DQ<9>")
	)
	(segment
		(start 71.54799 -226.970844)
		(end 71.54799 -217.843608)
		(width 0.10668)
		(layer "F.Cu")
		(net "M_A_CPU1_SA_DQ<9>")
	)
	(segment
		(start 62.858396 -209.304636)
		(end 62.85865 -209.154268)
		(width 0.10668)
		(layer "F.Cu")
		(net "M_A_CPU1_SA_DQ<9>")
	)
	(segment
		(start 62.85865 -209.154268)
		(end 62.727078 -209.022696)
		(width 0.10668)
		(layer "F.Cu")
		(net "M_A_CPU1_SA_DQ<9>")
	)
	(segment
		(start 62.089792 -208.38541)
		(end 59.428126 -208.38541)
		(width 0.10668)
		(layer "F.Cu")
		(net "M_A_CPU1_SA_DQ<9>")
	)
	(segment
		(start 61.884052 -209.30108)
		(end 61.884052 -209.150204)
		(width 0.10668)
		(layer "F.Cu")
		(net "M_A_CPU1_SA_DQ<9>")
	)
	(segment
		(start 62.294262 -208.58988)
		(end 62.089792 -208.38541)
		(width 0.10668)
		(layer "F.Cu")
		(net "M_A_CPU1_SA_DQ<9>")
	)
	(segment
		(start 62.576202 -209.022696)
		(end 62.166246 -209.432652)
		(width 0.10668)
		(layer "F.Cu")
		(net "M_A_CPU1_SA_DQ<9>")
	)
	(segment
		(start 71.54799 -217.843608)
		(end 63.291466 -209.587084)
		(width 0.10668)
		(layer "F.Cu")
		(net "M_A_CPU1_SA_DQ<9>")
	)
	(segment
		(start 75.80376 -231.226614)
		(end 71.54799 -226.970844)
		(width 0.10668)
		(layer "F.Cu")
		(net "M_A_CPU1_SA_DQ<9>")
	)
	(arc
		(start 77.750924 -231.302814)
		(mid 77.614488 -231.245989)
		(end 77.467968 -231.226614)
		(width 0.0762)
		(layer "F.Cu")
		(net "M_A_CPU1_SA_DQ<9>")
	)
	(arc
		(start 78.690978 -231.302814)
		(mid 78.408022 -231.226637)
		(end 78.125066 -231.302814)
		(width 0.0762)
		(layer "F.Cu")
		(net "M_A_CPU1_SA_DQ<9>")
	)
	(arc
		(start 78.125066 -231.302814)
		(mid 77.942815 -231.353198)
		(end 77.759306 -231.30764)
		(width 0.0762)
		(layer "F.Cu")
		(net "M_A_CPU1_SA_DQ<9>")
	)
	(arc
		(start 79.349346 -231.22636)
		(mid 79.202025 -231.245679)
		(end 79.064866 -231.302814)
		(width 0.0762)
		(layer "F.Cu")
		(net "M_A_CPU1_SA_DQ<9>")
	)
	(arc
		(start 79.064866 -231.302814)
		(mid 78.877922 -231.353103)
		(end 78.690978 -231.302814)
		(width 0.0762)
		(layer "F.Cu")
		(net "M_A_CPU1_SA_DQ<9>")
	)
	(arc
		(start 79.817976 -230.980234)
		(mid 79.614011 -231.161083)
		(end 79.349346 -231.22636)
		(width 0.0762)
		(layer "F.Cu")
		(net "M_A_CPU1_SA_DQ<9>")
	)
	(segment
		(start 62.980316 -208.096358)
		(end 63.236094 -207.84058)
		(width 0.10668)
		(layer "F.Cu")
		(net "M_A_CPU1_SA_DQ<8>")
	)
	(segment
		(start 77.444092 -230.549704)
		(end 76.486766 -230.549704)
		(width 0.0762)
		(layer "F.Cu")
		(net "M_A_CPU1_SA_DQ<8>")
	)
	(segment
		(start 61.569092 -206.685642)
		(end 61.41847 -206.685388)
		(width 0.10668)
		(layer "F.Cu")
		(net "M_A_CPU1_SA_DQ<8>")
	)
	(segment
		(start 61.481208 -207.337914)
		(end 61.985652 -206.83347)
		(width 0.10668)
		(layer "F.Cu")
		(net "M_A_CPU1_SA_DQ<8>")
	)
	(segment
		(start 61.985906 -206.683102)
		(end 61.854334 -206.55153)
		(width 0.10668)
		(layer "F.Cu")
		(net "M_A_CPU1_SA_DQ<8>")
	)
	(segment
		(start 62.671706 -207.276192)
		(end 62.67196 -207.125824)
		(width 0.10668)
		(layer "F.Cu")
		(net "M_A_CPU1_SA_DQ<8>")
	)
	(segment
		(start 72.22871 -226.688396)
		(end 72.22871 -217.495628)
		(width 0.10668)
		(layer "F.Cu")
		(net "M_A_CPU1_SA_DQ<8>")
	)
	(segment
		(start 76.354686 -230.417624)
		(end 75.957938 -230.417624)
		(width 0.10668)
		(layer "F.Cu")
		(net "M_A_CPU1_SA_DQ<8>")
	)
	(segment
		(start 62.41415 -207.533748)
		(end 62.671706 -207.276192)
		(width 0.10668)
		(layer "F.Cu")
		(net "M_A_CPU1_SA_DQ<8>")
	)
	(segment
		(start 62.980316 -208.247234)
		(end 62.980316 -208.096358)
		(width 0.10668)
		(layer "F.Cu")
		(net "M_A_CPU1_SA_DQ<8>")
	)
	(segment
		(start 62.545468 -207.815688)
		(end 62.413896 -207.684116)
		(width 0.10668)
		(layer "F.Cu")
		(net "M_A_CPU1_SA_DQ<8>")
	)
	(segment
		(start 61.41847 -206.685388)
		(end 59.428126 -206.685388)
		(width 0.10668)
		(layer "F.Cu")
		(net "M_A_CPU1_SA_DQ<8>")
	)
	(segment
		(start 75.957938 -230.417624)
		(end 72.22871 -226.688396)
		(width 0.10668)
		(layer "F.Cu")
		(net "M_A_CPU1_SA_DQ<8>")
	)
	(segment
		(start 61.985652 -206.83347)
		(end 61.985906 -206.683102)
		(width 0.10668)
		(layer "F.Cu")
		(net "M_A_CPU1_SA_DQ<8>")
	)
	(segment
		(start 61.480954 -207.488282)
		(end 61.481208 -207.337914)
		(width 0.10668)
		(layer "F.Cu")
		(net "M_A_CPU1_SA_DQ<8>")
	)
	(segment
		(start 63.236348 -207.690212)
		(end 63.104776 -207.55864)
		(width 0.10668)
		(layer "F.Cu")
		(net "M_A_CPU1_SA_DQ<8>")
	)
	(segment
		(start 72.22871 -217.495628)
		(end 62.980316 -208.247234)
		(width 0.10668)
		(layer "F.Cu")
		(net "M_A_CPU1_SA_DQ<8>")
	)
	(segment
		(start 61.763402 -207.620108)
		(end 61.612526 -207.619854)
		(width 0.10668)
		(layer "F.Cu")
		(net "M_A_CPU1_SA_DQ<8>")
	)
	(segment
		(start 61.703458 -206.551276)
		(end 61.569092 -206.685642)
		(width 0.10668)
		(layer "F.Cu")
		(net "M_A_CPU1_SA_DQ<8>")
	)
	(segment
		(start 61.612526 -207.619854)
		(end 61.480954 -207.488282)
		(width 0.10668)
		(layer "F.Cu")
		(net "M_A_CPU1_SA_DQ<8>")
	)
	(segment
		(start 76.486766 -230.549704)
		(end 76.354686 -230.417624)
		(width 0.0762)
		(layer "F.Cu")
		(net "M_A_CPU1_SA_DQ<8>")
	)
	(segment
		(start 63.236094 -207.84058)
		(end 63.236348 -207.690212)
		(width 0.10668)
		(layer "F.Cu")
		(net "M_A_CPU1_SA_DQ<8>")
	)
	(segment
		(start 62.389512 -206.993998)
		(end 61.763402 -207.620108)
		(width 0.10668)
		(layer "F.Cu")
		(net "M_A_CPU1_SA_DQ<8>")
	)
	(segment
		(start 62.9539 -207.558386)
		(end 62.696344 -207.815942)
		(width 0.10668)
		(layer "F.Cu")
		(net "M_A_CPU1_SA_DQ<8>")
	)
	(segment
		(start 62.540388 -206.994252)
		(end 62.389512 -206.993998)
		(width 0.10668)
		(layer "F.Cu")
		(net "M_A_CPU1_SA_DQ<8>")
	)
	(segment
		(start 62.67196 -207.125824)
		(end 62.540388 -206.994252)
		(width 0.10668)
		(layer "F.Cu")
		(net "M_A_CPU1_SA_DQ<8>")
	)
	(segment
		(start 62.413896 -207.684116)
		(end 62.41415 -207.533748)
		(width 0.10668)
		(layer "F.Cu")
		(net "M_A_CPU1_SA_DQ<8>")
	)
	(segment
		(start 63.104776 -207.55864)
		(end 62.9539 -207.558386)
		(width 0.10668)
		(layer "F.Cu")
		(net "M_A_CPU1_SA_DQ<8>")
	)
	(segment
		(start 61.854334 -206.55153)
		(end 61.703458 -206.551276)
		(width 0.10668)
		(layer "F.Cu")
		(net "M_A_CPU1_SA_DQ<8>")
	)
	(segment
		(start 62.696344 -207.815942)
		(end 62.545468 -207.815688)
		(width 0.10668)
		(layer "F.Cu")
		(net "M_A_CPU1_SA_DQ<8>")
	)
	(arc
		(start 77.89037 -230.418386)
		(mid 77.768514 -230.442542)
		(end 77.654912 -230.492808)
		(width 0.0762)
		(layer "F.Cu")
		(net "M_A_CPU1_SA_DQ<8>")
	)
	(arc
		(start 77.654912 -230.492808)
		(mid 77.553272 -230.535223)
		(end 77.444092 -230.549704)
		(width 0.0762)
		(layer "F.Cu")
		(net "M_A_CPU1_SA_DQ<8>")
	)
	(arc
		(start 78.408022 -230.170228)
		(mid 78.171894 -230.341663)
		(end 77.89037 -230.418386)
		(width 0.0762)
		(layer "F.Cu")
		(net "M_A_CPU1_SA_DQ<8>")
	)
	(segment
		(start 60.67044 -205.410308)
		(end 58.13044 -205.410308)
		(width 0.101346)
		(layer "F.Cu")
		(net "M_A_CPU1_SA_DQ<7>")
	)
	(segment
		(start 62.205108 -206.008224)
		(end 62.054232 -206.008224)
		(width 0.10668)
		(layer "F.Cu")
		(net "M_A_CPU1_SA_DQ<7>")
	)
	(segment
		(start 76.058522 -229.797356)
		(end 76.05649 -229.795324)
		(width 0.0762)
		(layer "F.Cu")
		(net "M_A_CPU1_SA_DQ<7>")
	)
	(segment
		(start 57.705498 -205.83525)
		(end 55.328058 -205.83525)
		(width 0.101346)
		(layer "F.Cu")
		(net "M_A_CPU1_SA_DQ<7>")
	)
	(segment
		(start 63.693548 -208.313782)
		(end 63.693548 -207.496664)
		(width 0.10668)
		(layer "F.Cu")
		(net "M_A_CPU1_SA_DQ<7>")
	)
	(segment
		(start 77.467968 -229.797356)
		(end 76.058522 -229.797356)
		(width 0.0762)
		(layer "F.Cu")
		(net "M_A_CPU1_SA_DQ<7>")
	)
	(segment
		(start 62.054232 -206.008224)
		(end 61.971428 -206.091028)
		(width 0.10668)
		(layer "F.Cu")
		(net "M_A_CPU1_SA_DQ<7>")
	)
	(segment
		(start 78.594966 -229.847902)
		(end 78.586584 -229.843076)
		(width 0.0762)
		(layer "F.Cu")
		(net "M_A_CPU1_SA_DQ<7>")
	)
	(segment
		(start 61.772038 -205.72603)
		(end 61.772038 -205.575154)
		(width 0.10668)
		(layer "F.Cu")
		(net "M_A_CPU1_SA_DQ<7>")
	)
	(segment
		(start 79.347822 -230.170228)
		(end 79.44866 -229.997)
		(width 0.0762)
		(layer "F.Cu")
		(net "M_A_CPU1_SA_DQ<7>")
	)
	(segment
		(start 58.13044 -205.410308)
		(end 57.705498 -205.83525)
		(width 0.101346)
		(layer "F.Cu")
		(net "M_A_CPU1_SA_DQ<7>")
	)
	(segment
		(start 63.693548 -207.496664)
		(end 62.205108 -206.008224)
		(width 0.10668)
		(layer "F.Cu")
		(net "M_A_CPU1_SA_DQ<7>")
	)
	(segment
		(start 61.772038 -205.575154)
		(end 61.607192 -205.410308)
		(width 0.10668)
		(layer "F.Cu")
		(net "M_A_CPU1_SA_DQ<7>")
	)
	(segment
		(start 61.689234 -205.808834)
		(end 61.772038 -205.72603)
		(width 0.10668)
		(layer "F.Cu")
		(net "M_A_CPU1_SA_DQ<7>")
	)
	(segment
		(start 61.971428 -206.091028)
		(end 61.820552 -206.091028)
		(width 0.10668)
		(layer "F.Cu")
		(net "M_A_CPU1_SA_DQ<7>")
	)
	(segment
		(start 72.68591 -226.49688)
		(end 72.68591 -217.306144)
		(width 0.10668)
		(layer "F.Cu")
		(net "M_A_CPU1_SA_DQ<7>")
	)
	(segment
		(start 76.05649 -229.795324)
		(end 75.984354 -229.795324)
		(width 0.10668)
		(layer "F.Cu")
		(net "M_A_CPU1_SA_DQ<7>")
	)
	(segment
		(start 61.689234 -205.95971)
		(end 61.689234 -205.808834)
		(width 0.10668)
		(layer "F.Cu")
		(net "M_A_CPU1_SA_DQ<7>")
	)
	(segment
		(start 79.16926 -229.843076)
		(end 79.160878 -229.847902)
		(width 0.0762)
		(layer "F.Cu")
		(net "M_A_CPU1_SA_DQ<7>")
	)
	(segment
		(start 61.607192 -205.410308)
		(end 60.67044 -205.410308)
		(width 0.10668)
		(layer "F.Cu")
		(net "M_A_CPU1_SA_DQ<7>")
	)
	(segment
		(start 72.68591 -217.306144)
		(end 63.693548 -208.313782)
		(width 0.10668)
		(layer "F.Cu")
		(net "M_A_CPU1_SA_DQ<7>")
	)
	(segment
		(start 61.820552 -206.091028)
		(end 61.689234 -205.95971)
		(width 0.10668)
		(layer "F.Cu")
		(net "M_A_CPU1_SA_DQ<7>")
	)
	(segment
		(start 75.984354 -229.795324)
		(end 72.68591 -226.49688)
		(width 0.10668)
		(layer "F.Cu")
		(net "M_A_CPU1_SA_DQ<7>")
	)
	(arc
		(start 77.498956 -229.798626)
		(mid 77.483475 -229.79767)
		(end 77.467968 -229.797356)
		(width 0.0762)
		(layer "F.Cu")
		(net "M_A_CPU1_SA_DQ<7>")
	)
	(arc
		(start 79.30261 -229.800404)
		(mid 79.233912 -229.81542)
		(end 79.16926 -229.843076)
		(width 0.0762)
		(layer "F.Cu")
		(net "M_A_CPU1_SA_DQ<7>")
	)
	(arc
		(start 78.586584 -229.843076)
		(mid 78.403076 -229.797582)
		(end 78.220824 -229.847902)
		(width 0.0762)
		(layer "F.Cu")
		(net "M_A_CPU1_SA_DQ<7>")
	)
	(arc
		(start 79.160878 -229.847902)
		(mid 78.877922 -229.924079)
		(end 78.594966 -229.847902)
		(width 0.0762)
		(layer "F.Cu")
		(net "M_A_CPU1_SA_DQ<7>")
	)
	(arc
		(start 79.44866 -229.997)
		(mid 79.432735 -229.856308)
		(end 79.30261 -229.800404)
		(width 0.0762)
		(layer "F.Cu")
		(net "M_A_CPU1_SA_DQ<7>")
	)
	(arc
		(start 78.220824 -229.847902)
		(mid 77.937868 -229.924079)
		(end 77.654912 -229.847902)
		(width 0.0762)
		(layer "F.Cu")
		(net "M_A_CPU1_SA_DQ<7>")
	)
	(arc
		(start 77.654912 -229.847902)
		(mid 77.579672 -229.814589)
		(end 77.498956 -229.798626)
		(width 0.0762)
		(layer "F.Cu")
		(net "M_A_CPU1_SA_DQ<7>")
	)
	(segment
		(start 57.369202 -204.236574)
		(end 57.369202 -204.89418)
		(width 0.101346)
		(layer "F.Cu")
		(net "M_A_CPU1_SA_DQ<6>")
	)
	(segment
		(start 76.111354 -228.957124)
		(end 73.36663 -226.2124)
		(width 0.10668)
		(layer "F.Cu")
		(net "M_A_CPU1_SA_DQ<6>")
	)
	(segment
		(start 57.470548 -204.135228)
		(end 57.369202 -204.236574)
		(width 0.101346)
		(layer "F.Cu")
		(net "M_A_CPU1_SA_DQ<6>")
	)
	(segment
		(start 77.937868 -229.360476)
		(end 78.033626 -229.19563)
		(width 0.0762)
		(layer "F.Cu")
		(net "M_A_CPU1_SA_DQ<6>")
	)
	(segment
		(start 73.36663 -217.023696)
		(end 68.522596 -212.179662)
		(width 0.10668)
		(layer "F.Cu")
		(net "M_A_CPU1_SA_DQ<6>")
	)
	(segment
		(start 58.13044 -204.560424)
		(end 57.705244 -204.135228)
		(width 0.101346)
		(layer "F.Cu")
		(net "M_A_CPU1_SA_DQ<6>")
	)
	(segment
		(start 77.322426 -229.162864)
		(end 76.520294 -229.162864)
		(width 0.0762)
		(layer "F.Cu")
		(net "M_A_CPU1_SA_DQ<6>")
	)
	(segment
		(start 56.874156 -204.135228)
		(end 55.328058 -204.135228)
		(width 0.101346)
		(layer "F.Cu")
		(net "M_A_CPU1_SA_DQ<6>")
	)
	(segment
		(start 57.076848 -204.995526)
		(end 56.975502 -204.89418)
		(width 0.101346)
		(layer "F.Cu")
		(net "M_A_CPU1_SA_DQ<6>")
	)
	(segment
		(start 57.267856 -204.995526)
		(end 57.076848 -204.995526)
		(width 0.101346)
		(layer "F.Cu")
		(net "M_A_CPU1_SA_DQ<6>")
	)
	(segment
		(start 76.314554 -228.957124)
		(end 76.111354 -228.957124)
		(width 0.10668)
		(layer "F.Cu")
		(net "M_A_CPU1_SA_DQ<6>")
	)
	(segment
		(start 57.705244 -204.135228)
		(end 57.470548 -204.135228)
		(width 0.101346)
		(layer "F.Cu")
		(net "M_A_CPU1_SA_DQ<6>")
	)
	(segment
		(start 76.520294 -229.162864)
		(end 76.314554 -228.957124)
		(width 0.0762)
		(layer "F.Cu")
		(net "M_A_CPU1_SA_DQ<6>")
	)
	(segment
		(start 56.975502 -204.89418)
		(end 56.975502 -204.236574)
		(width 0.101346)
		(layer "F.Cu")
		(net "M_A_CPU1_SA_DQ<6>")
	)
	(segment
		(start 57.369202 -204.89418)
		(end 57.267856 -204.995526)
		(width 0.101346)
		(layer "F.Cu")
		(net "M_A_CPU1_SA_DQ<6>")
	)
	(segment
		(start 61.720476 -204.560424)
		(end 60.67044 -204.560424)
		(width 0.10668)
		(layer "F.Cu")
		(net "M_A_CPU1_SA_DQ<6>")
	)
	(segment
		(start 73.36663 -226.2124)
		(end 73.36663 -217.023696)
		(width 0.10668)
		(layer "F.Cu")
		(net "M_A_CPU1_SA_DQ<6>")
	)
	(segment
		(start 60.67044 -204.560424)
		(end 58.13044 -204.560424)
		(width 0.101346)
		(layer "F.Cu")
		(net "M_A_CPU1_SA_DQ<6>")
	)
	(segment
		(start 68.522596 -211.362544)
		(end 61.720476 -204.560424)
		(width 0.10668)
		(layer "F.Cu")
		(net "M_A_CPU1_SA_DQ<6>")
	)
	(segment
		(start 56.975502 -204.236574)
		(end 56.874156 -204.135228)
		(width 0.101346)
		(layer "F.Cu")
		(net "M_A_CPU1_SA_DQ<6>")
	)
	(segment
		(start 68.522596 -212.179662)
		(end 68.522596 -211.362544)
		(width 0.10668)
		(layer "F.Cu")
		(net "M_A_CPU1_SA_DQ<6>")
	)
	(segment
		(start 77.759306 -229.03307)
		(end 77.750924 -229.037896)
		(width 0.0762)
		(layer "F.Cu")
		(net "M_A_CPU1_SA_DQ<6>")
	)
	(arc
		(start 77.887576 -228.990906)
		(mid 77.821508 -229.006115)
		(end 77.759306 -229.03307)
		(width 0.0762)
		(layer "F.Cu")
		(net "M_A_CPU1_SA_DQ<6>")
	)
	(arc
		(start 78.033626 -229.19563)
		(mid 78.022436 -229.049074)
		(end 77.887576 -228.990906)
		(width 0.0762)
		(layer "F.Cu")
		(net "M_A_CPU1_SA_DQ<6>")
	)
	(arc
		(start 77.750924 -229.037896)
		(mid 77.545602 -229.130992)
		(end 77.322426 -229.162864)
		(width 0.0762)
		(layer "F.Cu")
		(net "M_A_CPU1_SA_DQ<6>")
	)
	(segment
		(start 65.92443 -209.609436)
		(end 65.924684 -209.459068)
		(width 0.10668)
		(layer "F.Cu")
		(net "M_A_CPU1_SA_DQ<5>")
	)
	(segment
		(start 66.337434 -210.476084)
		(end 66.337434 -210.325208)
		(width 0.10668)
		(layer "F.Cu")
		(net "M_A_CPU1_SA_DQ<5>")
	)
	(segment
		(start 64.795908 -208.330292)
		(end 64.664336 -208.19872)
		(width 0.10668)
		(layer "F.Cu")
		(net "M_A_CPU1_SA_DQ<5>")
	)
	(segment
		(start 64.033908 -207.35544)
		(end 61.663834 -204.985366)
		(width 0.10668)
		(layer "F.Cu")
		(net "M_A_CPU1_SA_DQ<5>")
	)
	(segment
		(start 66.489072 -210.023456)
		(end 66.3575 -209.891884)
		(width 0.10668)
		(layer "F.Cu")
		(net "M_A_CPU1_SA_DQ<5>")
	)
	(segment
		(start 64.775588 -208.914238)
		(end 64.64427 -208.78292)
		(width 0.10668)
		(layer "F.Cu")
		(net "M_A_CPU1_SA_DQ<5>")
	)
	(segment
		(start 65.077848 -208.763108)
		(end 64.926464 -208.914492)
		(width 0.10668)
		(layer "F.Cu")
		(net "M_A_CPU1_SA_DQ<5>")
	)
	(segment
		(start 67.46621 -211.453984)
		(end 67.617594 -211.3026)
		(width 0.10668)
		(layer "F.Cu")
		(net "M_A_CPU1_SA_DQ<5>")
	)
	(segment
		(start 73.02627 -217.16492)
		(end 68.030598 -212.169248)
		(width 0.10668)
		(layer "F.Cu")
		(net "M_A_CPU1_SA_DQ<5>")
	)
	(segment
		(start 65.642236 -209.327496)
		(end 65.490852 -209.47888)
		(width 0.10668)
		(layer "F.Cu")
		(net "M_A_CPU1_SA_DQ<5>")
	)
	(segment
		(start 67.184016 -211.172044)
		(end 67.03314 -211.17179)
		(width 0.10668)
		(layer "F.Cu")
		(net "M_A_CPU1_SA_DQ<5>")
	)
	(segment
		(start 67.486276 -211.02066)
		(end 67.3354 -211.02066)
		(width 0.10668)
		(layer "F.Cu")
		(net "M_A_CPU1_SA_DQ<5>")
	)
	(segment
		(start 67.748404 -211.736432)
		(end 67.597528 -211.736178)
		(width 0.10668)
		(layer "F.Cu")
		(net "M_A_CPU1_SA_DQ<5>")
	)
	(segment
		(start 77.759306 -229.687882)
		(end 77.750924 -229.683056)
		(width 0.0762)
		(layer "F.Cu")
		(net "M_A_CPU1_SA_DQ<5>")
	)
	(segment
		(start 65.924684 -209.459068)
		(end 65.793112 -209.327496)
		(width 0.10668)
		(layer "F.Cu")
		(net "M_A_CPU1_SA_DQ<5>")
	)
	(segment
		(start 65.490852 -209.47888)
		(end 65.339976 -209.478626)
		(width 0.10668)
		(layer "F.Cu")
		(net "M_A_CPU1_SA_DQ<5>")
	)
	(segment
		(start 65.208658 -209.347308)
		(end 65.208658 -209.196432)
		(width 0.10668)
		(layer "F.Cu")
		(net "M_A_CPU1_SA_DQ<5>")
	)
	(segment
		(start 67.03314 -211.17179)
		(end 66.901822 -211.040472)
		(width 0.10668)
		(layer "F.Cu")
		(net "M_A_CPU1_SA_DQ<5>")
	)
	(segment
		(start 66.206624 -209.891884)
		(end 66.05524 -210.043268)
		(width 0.10668)
		(layer "F.Cu")
		(net "M_A_CPU1_SA_DQ<5>")
	)
	(segment
		(start 64.795654 -208.48066)
		(end 64.795908 -208.330292)
		(width 0.10668)
		(layer "F.Cu")
		(net "M_A_CPU1_SA_DQ<5>")
	)
	(segment
		(start 64.64427 -208.632044)
		(end 64.795654 -208.48066)
		(width 0.10668)
		(layer "F.Cu")
		(net "M_A_CPU1_SA_DQ<5>")
	)
	(segment
		(start 66.619628 -210.607656)
		(end 66.468752 -210.607402)
		(width 0.10668)
		(layer "F.Cu")
		(net "M_A_CPU1_SA_DQ<5>")
	)
	(segment
		(start 67.053206 -210.738212)
		(end 67.05346 -210.587844)
		(width 0.10668)
		(layer "F.Cu")
		(net "M_A_CPU1_SA_DQ<5>")
	)
	(segment
		(start 67.617848 -211.152232)
		(end 67.486276 -211.02066)
		(width 0.10668)
		(layer "F.Cu")
		(net "M_A_CPU1_SA_DQ<5>")
	)
	(segment
		(start 67.05346 -210.587844)
		(end 66.921888 -210.456272)
		(width 0.10668)
		(layer "F.Cu")
		(net "M_A_CPU1_SA_DQ<5>")
	)
	(segment
		(start 64.664336 -208.19872)
		(end 64.51346 -208.19872)
		(width 0.10668)
		(layer "F.Cu")
		(net "M_A_CPU1_SA_DQ<5>")
	)
	(segment
		(start 66.901822 -210.889596)
		(end 67.053206 -210.738212)
		(width 0.10668)
		(layer "F.Cu")
		(net "M_A_CPU1_SA_DQ<5>")
	)
	(segment
		(start 66.921888 -210.456272)
		(end 66.771012 -210.456272)
		(width 0.10668)
		(layer "F.Cu")
		(net "M_A_CPU1_SA_DQ<5>")
	)
	(segment
		(start 65.360042 -209.045048)
		(end 65.360296 -208.89468)
		(width 0.10668)
		(layer "F.Cu")
		(net "M_A_CPU1_SA_DQ<5>")
	)
	(segment
		(start 76.45654 -229.606856)
		(end 76.208382 -229.358698)
		(width 0.0762)
		(layer "F.Cu")
		(net "M_A_CPU1_SA_DQ<5>")
	)
	(segment
		(start 66.901822 -211.040472)
		(end 66.901822 -210.889596)
		(width 0.10668)
		(layer "F.Cu")
		(net "M_A_CPU1_SA_DQ<5>")
	)
	(segment
		(start 65.208658 -209.196432)
		(end 65.360042 -209.045048)
		(width 0.10668)
		(layer "F.Cu")
		(net "M_A_CPU1_SA_DQ<5>")
	)
	(segment
		(start 64.51346 -208.19872)
		(end 64.362076 -208.350104)
		(width 0.10668)
		(layer "F.Cu")
		(net "M_A_CPU1_SA_DQ<5>")
	)
	(segment
		(start 65.773046 -209.76082)
		(end 65.92443 -209.609436)
		(width 0.10668)
		(layer "F.Cu")
		(net "M_A_CPU1_SA_DQ<5>")
	)
	(segment
		(start 68.182236 -211.71662)
		(end 68.050664 -211.585048)
		(width 0.10668)
		(layer "F.Cu")
		(net "M_A_CPU1_SA_DQ<5>")
	)
	(segment
		(start 68.050664 -211.585048)
		(end 67.899788 -211.585048)
		(width 0.10668)
		(layer "F.Cu")
		(net "M_A_CPU1_SA_DQ<5>")
	)
	(segment
		(start 67.617594 -211.3026)
		(end 67.617848 -211.152232)
		(width 0.10668)
		(layer "F.Cu")
		(net "M_A_CPU1_SA_DQ<5>")
	)
	(segment
		(start 76.208382 -229.358698)
		(end 76.030328 -229.358698)
		(width 0.10668)
		(layer "F.Cu")
		(net "M_A_CPU1_SA_DQ<5>")
	)
	(segment
		(start 64.926464 -208.914492)
		(end 64.775588 -208.914238)
		(width 0.10668)
		(layer "F.Cu")
		(net "M_A_CPU1_SA_DQ<5>")
	)
	(segment
		(start 65.228724 -208.763108)
		(end 65.077848 -208.763108)
		(width 0.10668)
		(layer "F.Cu")
		(net "M_A_CPU1_SA_DQ<5>")
	)
	(segment
		(start 67.46621 -211.60486)
		(end 67.46621 -211.453984)
		(width 0.10668)
		(layer "F.Cu")
		(net "M_A_CPU1_SA_DQ<5>")
	)
	(segment
		(start 67.3354 -211.02066)
		(end 67.184016 -211.172044)
		(width 0.10668)
		(layer "F.Cu")
		(net "M_A_CPU1_SA_DQ<5>")
	)
	(segment
		(start 64.033908 -208.172558)
		(end 64.033908 -207.35544)
		(width 0.10668)
		(layer "F.Cu")
		(net "M_A_CPU1_SA_DQ<5>")
	)
	(segment
		(start 65.904364 -210.043014)
		(end 65.773046 -209.911696)
		(width 0.10668)
		(layer "F.Cu")
		(net "M_A_CPU1_SA_DQ<5>")
	)
	(segment
		(start 68.030598 -212.018372)
		(end 68.181982 -211.866988)
		(width 0.10668)
		(layer "F.Cu")
		(net "M_A_CPU1_SA_DQ<5>")
	)
	(segment
		(start 66.771012 -210.456272)
		(end 66.619628 -210.607656)
		(width 0.10668)
		(layer "F.Cu")
		(net "M_A_CPU1_SA_DQ<5>")
	)
	(segment
		(start 68.181982 -211.866988)
		(end 68.182236 -211.71662)
		(width 0.10668)
		(layer "F.Cu")
		(net "M_A_CPU1_SA_DQ<5>")
	)
	(segment
		(start 66.468752 -210.607402)
		(end 66.337434 -210.476084)
		(width 0.10668)
		(layer "F.Cu")
		(net "M_A_CPU1_SA_DQ<5>")
	)
	(segment
		(start 68.030598 -212.169248)
		(end 68.030598 -212.018372)
		(width 0.10668)
		(layer "F.Cu")
		(net "M_A_CPU1_SA_DQ<5>")
	)
	(segment
		(start 66.488818 -210.173824)
		(end 66.489072 -210.023456)
		(width 0.10668)
		(layer "F.Cu")
		(net "M_A_CPU1_SA_DQ<5>")
	)
	(segment
		(start 65.360296 -208.89468)
		(end 65.228724 -208.763108)
		(width 0.10668)
		(layer "F.Cu")
		(net "M_A_CPU1_SA_DQ<5>")
	)
	(segment
		(start 67.597528 -211.736178)
		(end 67.46621 -211.60486)
		(width 0.10668)
		(layer "F.Cu")
		(net "M_A_CPU1_SA_DQ<5>")
	)
	(segment
		(start 64.64427 -208.78292)
		(end 64.64427 -208.632044)
		(width 0.10668)
		(layer "F.Cu")
		(net "M_A_CPU1_SA_DQ<5>")
	)
	(segment
		(start 77.468222 -229.606856)
		(end 76.45654 -229.606856)
		(width 0.0762)
		(layer "F.Cu")
		(net "M_A_CPU1_SA_DQ<5>")
	)
	(segment
		(start 65.773046 -209.911696)
		(end 65.773046 -209.76082)
		(width 0.10668)
		(layer "F.Cu")
		(net "M_A_CPU1_SA_DQ<5>")
	)
	(segment
		(start 64.362076 -208.350104)
		(end 64.2112 -208.34985)
		(width 0.10668)
		(layer "F.Cu")
		(net "M_A_CPU1_SA_DQ<5>")
	)
	(segment
		(start 61.663834 -204.985366)
		(end 59.428126 -204.985366)
		(width 0.10668)
		(layer "F.Cu")
		(net "M_A_CPU1_SA_DQ<5>")
	)
	(segment
		(start 73.02627 -226.35464)
		(end 73.02627 -217.16492)
		(width 0.10668)
		(layer "F.Cu")
		(net "M_A_CPU1_SA_DQ<5>")
	)
	(segment
		(start 66.337434 -210.325208)
		(end 66.488818 -210.173824)
		(width 0.10668)
		(layer "F.Cu")
		(net "M_A_CPU1_SA_DQ<5>")
	)
	(segment
		(start 65.339976 -209.478626)
		(end 65.208658 -209.347308)
		(width 0.10668)
		(layer "F.Cu")
		(net "M_A_CPU1_SA_DQ<5>")
	)
	(segment
		(start 66.05524 -210.043268)
		(end 65.904364 -210.043014)
		(width 0.10668)
		(layer "F.Cu")
		(net "M_A_CPU1_SA_DQ<5>")
	)
	(segment
		(start 67.899788 -211.585048)
		(end 67.748404 -211.736432)
		(width 0.10668)
		(layer "F.Cu")
		(net "M_A_CPU1_SA_DQ<5>")
	)
	(segment
		(start 64.2112 -208.34985)
		(end 64.033908 -208.172558)
		(width 0.10668)
		(layer "F.Cu")
		(net "M_A_CPU1_SA_DQ<5>")
	)
	(segment
		(start 65.793112 -209.327496)
		(end 65.642236 -209.327496)
		(width 0.10668)
		(layer "F.Cu")
		(net "M_A_CPU1_SA_DQ<5>")
	)
	(segment
		(start 66.3575 -209.891884)
		(end 66.206624 -209.891884)
		(width 0.10668)
		(layer "F.Cu")
		(net "M_A_CPU1_SA_DQ<5>")
	)
	(segment
		(start 76.030328 -229.358698)
		(end 73.02627 -226.35464)
		(width 0.10668)
		(layer "F.Cu")
		(net "M_A_CPU1_SA_DQ<5>")
	)
	(arc
		(start 79.064866 -229.683056)
		(mid 78.877922 -229.733311)
		(end 78.690978 -229.683056)
		(width 0.0762)
		(layer "F.Cu")
		(net "M_A_CPU1_SA_DQ<5>")
	)
	(arc
		(start 77.515212 -229.608634)
		(mid 77.491735 -229.607258)
		(end 77.468222 -229.606856)
		(width 0.0762)
		(layer "F.Cu")
		(net "M_A_CPU1_SA_DQ<5>")
	)
	(arc
		(start 79.298038 -229.608888)
		(mid 79.177389 -229.633189)
		(end 79.064866 -229.683056)
		(width 0.0762)
		(layer "F.Cu")
		(net "M_A_CPU1_SA_DQ<5>")
	)
	(arc
		(start 78.690978 -229.683056)
		(mid 78.408022 -229.606879)
		(end 78.125066 -229.683056)
		(width 0.0762)
		(layer "F.Cu")
		(net "M_A_CPU1_SA_DQ<5>")
	)
	(arc
		(start 79.817976 -229.360476)
		(mid 79.580364 -229.531464)
		(end 79.298038 -229.608888)
		(width 0.0762)
		(layer "F.Cu")
		(net "M_A_CPU1_SA_DQ<5>")
	)
	(arc
		(start 77.750924 -229.683056)
		(mid 77.6372 -229.632755)
		(end 77.515212 -229.608634)
		(width 0.0762)
		(layer "F.Cu")
		(net "M_A_CPU1_SA_DQ<5>")
	)
	(arc
		(start 78.125066 -229.683056)
		(mid 77.942815 -229.733406)
		(end 77.759306 -229.687882)
		(width 0.0762)
		(layer "F.Cu")
		(net "M_A_CPU1_SA_DQ<5>")
	)
	(segment
		(start 76.750926 -228.946964)
		(end 76.532486 -228.728524)
		(width 0.0762)
		(layer "F.Cu")
		(net "M_A_CPU1_SA_DQ<4>")
	)
	(segment
		(start 61.145928 -203.498704)
		(end 60.932568 -203.285344)
		(width 0.10668)
		(layer "F.Cu")
		(net "M_A_CPU1_SA_DQ<4>")
	)
	(segment
		(start 71.708772 -214.290148)
		(end 71.557896 -214.290148)
		(width 0.10668)
		(layer "F.Cu")
		(net "M_A_CPU1_SA_DQ<4>")
	)
	(segment
		(start 68.872354 -211.896452)
		(end 69.13245 -211.636356)
		(width 0.10668)
		(layer "F.Cu")
		(net "M_A_CPU1_SA_DQ<4>")
	)
	(segment
		(start 60.860178 -203.93533)
		(end 61.145928 -203.64958)
		(width 0.10668)
		(layer "F.Cu")
		(net "M_A_CPU1_SA_DQ<4>")
	)
	(segment
		(start 70.847458 -213.87181)
		(end 70.696582 -213.87181)
		(width 0.10668)
		(layer "F.Cu")
		(net "M_A_CPU1_SA_DQ<4>")
	)
	(segment
		(start 70.000876 -213.025228)
		(end 70.258686 -212.767418)
		(width 0.10668)
		(layer "F.Cu")
		(net "M_A_CPU1_SA_DQ<4>")
	)
	(segment
		(start 69.567806 -212.743034)
		(end 69.436488 -212.611716)
		(width 0.10668)
		(layer "F.Cu")
		(net "M_A_CPU1_SA_DQ<4>")
	)
	(segment
		(start 69.154294 -212.178646)
		(end 69.003418 -212.178646)
		(width 0.10668)
		(layer "F.Cu")
		(net "M_A_CPU1_SA_DQ<4>")
	)
	(segment
		(start 61.142372 -204.217524)
		(end 60.991496 -204.217524)
		(width 0.10668)
		(layer "F.Cu")
		(net "M_A_CPU1_SA_DQ<4>")
	)
	(segment
		(start 71.007478 -213.71179)
		(end 70.847458 -213.87181)
		(width 0.10668)
		(layer "F.Cu")
		(net "M_A_CPU1_SA_DQ<4>")
	)
	(segment
		(start 61.578998 -203.931774)
		(end 61.428122 -203.931774)
		(width 0.10668)
		(layer "F.Cu")
		(net "M_A_CPU1_SA_DQ<4>")
	)
	(segment
		(start 69.13245 -211.636356)
		(end 69.13245 -211.485226)
		(width 0.10668)
		(layer "F.Cu")
		(net "M_A_CPU1_SA_DQ<4>")
	)
	(segment
		(start 73.70699 -216.882218)
		(end 71.69404 -214.869268)
		(width 0.10668)
		(layer "F.Cu")
		(net "M_A_CPU1_SA_DQ<4>")
	)
	(segment
		(start 69.718682 -212.743034)
		(end 69.567806 -212.743034)
		(width 0.10668)
		(layer "F.Cu")
		(net "M_A_CPU1_SA_DQ<4>")
	)
	(segment
		(start 70.000876 -213.176104)
		(end 70.000876 -213.025228)
		(width 0.10668)
		(layer "F.Cu")
		(net "M_A_CPU1_SA_DQ<4>")
	)
	(segment
		(start 76.426568 -228.622606)
		(end 76.285344 -228.622606)
		(width 0.10668)
		(layer "F.Cu")
		(net "M_A_CPU1_SA_DQ<4>")
	)
	(segment
		(start 71.69404 -214.718392)
		(end 71.84009 -214.572342)
		(width 0.10668)
		(layer "F.Cu")
		(net "M_A_CPU1_SA_DQ<4>")
	)
	(segment
		(start 69.13245 -211.485226)
		(end 61.578998 -203.931774)
		(width 0.10668)
		(layer "F.Cu")
		(net "M_A_CPU1_SA_DQ<4>")
	)
	(segment
		(start 69.694298 -212.20303)
		(end 69.694298 -212.052154)
		(width 0.10668)
		(layer "F.Cu")
		(net "M_A_CPU1_SA_DQ<4>")
	)
	(segment
		(start 77.373226 -228.946964)
		(end 76.750926 -228.946964)
		(width 0.0762)
		(layer "F.Cu")
		(net "M_A_CPU1_SA_DQ<4>")
	)
	(segment
		(start 71.26097 -214.436198)
		(end 71.129652 -214.30488)
		(width 0.10668)
		(layer "F.Cu")
		(net "M_A_CPU1_SA_DQ<4>")
	)
	(segment
		(start 73.70699 -226.044252)
		(end 73.70699 -216.882218)
		(width 0.10668)
		(layer "F.Cu")
		(net "M_A_CPU1_SA_DQ<4>")
	)
	(segment
		(start 71.69404 -214.869268)
		(end 71.69404 -214.718392)
		(width 0.10668)
		(layer "F.Cu")
		(net "M_A_CPU1_SA_DQ<4>")
	)
	(segment
		(start 70.565264 -213.740492)
		(end 70.565264 -213.589616)
		(width 0.10668)
		(layer "F.Cu")
		(net "M_A_CPU1_SA_DQ<4>")
	)
	(segment
		(start 70.54088 -213.049612)
		(end 70.28307 -213.307422)
		(width 0.10668)
		(layer "F.Cu")
		(net "M_A_CPU1_SA_DQ<4>")
	)
	(segment
		(start 60.932568 -203.285344)
		(end 59.428126 -203.285344)
		(width 0.10668)
		(layer "F.Cu")
		(net "M_A_CPU1_SA_DQ<4>")
	)
	(segment
		(start 70.823074 -213.18093)
		(end 70.691756 -213.049612)
		(width 0.10668)
		(layer "F.Cu")
		(net "M_A_CPU1_SA_DQ<4>")
	)
	(segment
		(start 71.557896 -214.290148)
		(end 71.411846 -214.436198)
		(width 0.10668)
		(layer "F.Cu")
		(net "M_A_CPU1_SA_DQ<4>")
	)
	(segment
		(start 70.127368 -212.485224)
		(end 69.976492 -212.485224)
		(width 0.10668)
		(layer "F.Cu")
		(net "M_A_CPU1_SA_DQ<4>")
	)
	(segment
		(start 70.823074 -213.331806)
		(end 70.823074 -213.18093)
		(width 0.10668)
		(layer "F.Cu")
		(net "M_A_CPU1_SA_DQ<4>")
	)
	(segment
		(start 71.84009 -214.421466)
		(end 71.708772 -214.290148)
		(width 0.10668)
		(layer "F.Cu")
		(net "M_A_CPU1_SA_DQ<4>")
	)
	(segment
		(start 71.411846 -214.436198)
		(end 71.26097 -214.436198)
		(width 0.10668)
		(layer "F.Cu")
		(net "M_A_CPU1_SA_DQ<4>")
	)
	(segment
		(start 71.289672 -213.843108)
		(end 71.158354 -213.71179)
		(width 0.10668)
		(layer "F.Cu")
		(net "M_A_CPU1_SA_DQ<4>")
	)
	(segment
		(start 71.129652 -214.30488)
		(end 71.129652 -214.154004)
		(width 0.10668)
		(layer "F.Cu")
		(net "M_A_CPU1_SA_DQ<4>")
	)
	(segment
		(start 76.532486 -228.728524)
		(end 76.426568 -228.622606)
		(width 0.10668)
		(layer "F.Cu")
		(net "M_A_CPU1_SA_DQ<4>")
	)
	(segment
		(start 76.285344 -228.622606)
		(end 73.70699 -226.044252)
		(width 0.10668)
		(layer "F.Cu")
		(net "M_A_CPU1_SA_DQ<4>")
	)
	(segment
		(start 71.158354 -213.71179)
		(end 71.007478 -213.71179)
		(width 0.10668)
		(layer "F.Cu")
		(net "M_A_CPU1_SA_DQ<4>")
	)
	(segment
		(start 70.258686 -212.767418)
		(end 70.258686 -212.616542)
		(width 0.10668)
		(layer "F.Cu")
		(net "M_A_CPU1_SA_DQ<4>")
	)
	(segment
		(start 69.412104 -211.920836)
		(end 69.154294 -212.178646)
		(width 0.10668)
		(layer "F.Cu")
		(net "M_A_CPU1_SA_DQ<4>")
	)
	(segment
		(start 61.428122 -203.931774)
		(end 61.142372 -204.217524)
		(width 0.10668)
		(layer "F.Cu")
		(net "M_A_CPU1_SA_DQ<4>")
	)
	(segment
		(start 69.976492 -212.485224)
		(end 69.718682 -212.743034)
		(width 0.10668)
		(layer "F.Cu")
		(net "M_A_CPU1_SA_DQ<4>")
	)
	(segment
		(start 61.145928 -203.64958)
		(end 61.145928 -203.498704)
		(width 0.10668)
		(layer "F.Cu")
		(net "M_A_CPU1_SA_DQ<4>")
	)
	(segment
		(start 70.258686 -212.616542)
		(end 70.127368 -212.485224)
		(width 0.10668)
		(layer "F.Cu")
		(net "M_A_CPU1_SA_DQ<4>")
	)
	(segment
		(start 70.132194 -213.307422)
		(end 70.000876 -213.176104)
		(width 0.10668)
		(layer "F.Cu")
		(net "M_A_CPU1_SA_DQ<4>")
	)
	(segment
		(start 71.289672 -213.993984)
		(end 71.289672 -213.843108)
		(width 0.10668)
		(layer "F.Cu")
		(net "M_A_CPU1_SA_DQ<4>")
	)
	(segment
		(start 70.691756 -213.049612)
		(end 70.54088 -213.049612)
		(width 0.10668)
		(layer "F.Cu")
		(net "M_A_CPU1_SA_DQ<4>")
	)
	(segment
		(start 69.56298 -211.920836)
		(end 69.412104 -211.920836)
		(width 0.10668)
		(layer "F.Cu")
		(net "M_A_CPU1_SA_DQ<4>")
	)
	(segment
		(start 71.129652 -214.154004)
		(end 71.289672 -213.993984)
		(width 0.10668)
		(layer "F.Cu")
		(net "M_A_CPU1_SA_DQ<4>")
	)
	(segment
		(start 70.696582 -213.87181)
		(end 70.565264 -213.740492)
		(width 0.10668)
		(layer "F.Cu")
		(net "M_A_CPU1_SA_DQ<4>")
	)
	(segment
		(start 69.436488 -212.46084)
		(end 69.694298 -212.20303)
		(width 0.10668)
		(layer "F.Cu")
		(net "M_A_CPU1_SA_DQ<4>")
	)
	(segment
		(start 60.860178 -204.086206)
		(end 60.860178 -203.93533)
		(width 0.10668)
		(layer "F.Cu")
		(net "M_A_CPU1_SA_DQ<4>")
	)
	(segment
		(start 68.872354 -212.047582)
		(end 68.872354 -211.896452)
		(width 0.10668)
		(layer "F.Cu")
		(net "M_A_CPU1_SA_DQ<4>")
	)
	(segment
		(start 69.694298 -212.052154)
		(end 69.56298 -211.920836)
		(width 0.10668)
		(layer "F.Cu")
		(net "M_A_CPU1_SA_DQ<4>")
	)
	(segment
		(start 70.28307 -213.307422)
		(end 70.132194 -213.307422)
		(width 0.10668)
		(layer "F.Cu")
		(net "M_A_CPU1_SA_DQ<4>")
	)
	(segment
		(start 71.84009 -214.572342)
		(end 71.84009 -214.421466)
		(width 0.10668)
		(layer "F.Cu")
		(net "M_A_CPU1_SA_DQ<4>")
	)
	(segment
		(start 69.003418 -212.178646)
		(end 68.872354 -212.047582)
		(width 0.10668)
		(layer "F.Cu")
		(net "M_A_CPU1_SA_DQ<4>")
	)
	(segment
		(start 69.436488 -212.611716)
		(end 69.436488 -212.46084)
		(width 0.10668)
		(layer "F.Cu")
		(net "M_A_CPU1_SA_DQ<4>")
	)
	(segment
		(start 70.565264 -213.589616)
		(end 70.823074 -213.331806)
		(width 0.10668)
		(layer "F.Cu")
		(net "M_A_CPU1_SA_DQ<4>")
	)
	(segment
		(start 60.991496 -204.217524)
		(end 60.860178 -204.086206)
		(width 0.10668)
		(layer "F.Cu")
		(net "M_A_CPU1_SA_DQ<4>")
	)
	(arc
		(start 77.889862 -228.798882)
		(mid 77.768277 -228.822953)
		(end 77.654912 -228.87305)
		(width 0.0762)
		(layer "F.Cu")
		(net "M_A_CPU1_SA_DQ<4>")
	)
	(arc
		(start 77.654912 -228.87305)
		(mid 77.518836 -228.928171)
		(end 77.373226 -228.946964)
		(width 0.0762)
		(layer "F.Cu")
		(net "M_A_CPU1_SA_DQ<4>")
	)
	(arc
		(start 78.408022 -228.55047)
		(mid 78.17166 -228.722063)
		(end 77.889862 -228.798882)
		(width 0.0762)
		(layer "F.Cu")
		(net "M_A_CPU1_SA_DQ<4>")
	)
	(segment
		(start 75.59421 -225.185986)
		(end 75.59421 -214.648542)
		(width 0.10668)
		(layer "F.Cu")
		(net "M_A_CPU1_SA_DQ<3>")
	)
	(segment
		(start 79.347822 -226.930458)
		(end 79.443072 -226.766374)
		(width 0.0762)
		(layer "F.Cu")
		(net "M_A_CPU1_SA_DQ<3>")
	)
	(segment
		(start 77.539342 -226.518978)
		(end 77.315822 -226.295204)
		(width 0.0762)
		(layer "F.Cu")
		(net "M_A_CPU1_SA_DQ<3>")
	)
	(segment
		(start 61.256164 -200.310496)
		(end 60.344812 -200.310496)
		(width 0.10668)
		(layer "F.Cu")
		(net "M_A_CPU1_SA_DQ<3>")
	)
	(segment
		(start 57.000648 -199.8853)
		(end 55.328058 -199.8853)
		(width 0.101346)
		(layer "F.Cu")
		(net "M_A_CPU1_SA_DQ<3>")
	)
	(segment
		(start 57.647586 -200.15327)
		(end 57.000648 -199.8853)
		(width 0.101346)
		(layer "F.Cu")
		(net "M_A_CPU1_SA_DQ<3>")
	)
	(segment
		(start 76.703428 -226.295204)
		(end 76.36383 -225.955606)
		(width 0.0762)
		(layer "F.Cu")
		(net "M_A_CPU1_SA_DQ<3>")
	)
	(segment
		(start 57.804812 -200.310496)
		(end 57.647586 -200.15327)
		(width 0.101346)
		(layer "F.Cu")
		(net "M_A_CPU1_SA_DQ<3>")
	)
	(segment
		(start 78.594966 -226.607878)
		(end 78.586584 -226.603052)
		(width 0.0762)
		(layer "F.Cu")
		(net "M_A_CPU1_SA_DQ<3>")
	)
	(segment
		(start 75.59421 -214.648542)
		(end 61.256164 -200.310496)
		(width 0.10668)
		(layer "F.Cu")
		(net "M_A_CPU1_SA_DQ<3>")
	)
	(segment
		(start 77.315822 -226.295204)
		(end 76.703428 -226.295204)
		(width 0.0762)
		(layer "F.Cu")
		(net "M_A_CPU1_SA_DQ<3>")
	)
	(segment
		(start 79.16926 -226.603052)
		(end 79.160878 -226.607878)
		(width 0.0762)
		(layer "F.Cu")
		(net "M_A_CPU1_SA_DQ<3>")
	)
	(segment
		(start 79.443072 -226.766374)
		(end 79.443072 -226.67341)
		(width 0.0762)
		(layer "F.Cu")
		(net "M_A_CPU1_SA_DQ<3>")
	)
	(segment
		(start 60.344812 -200.310496)
		(end 57.804812 -200.310496)
		(width 0.101346)
		(layer "F.Cu")
		(net "M_A_CPU1_SA_DQ<3>")
	)
	(segment
		(start 76.36383 -225.955606)
		(end 75.59421 -225.185986)
		(width 0.10668)
		(layer "F.Cu")
		(net "M_A_CPU1_SA_DQ<3>")
	)
	(arc
		(start 78.220824 -226.607878)
		(mid 77.864964 -226.67932)
		(end 77.539342 -226.518978)
		(width 0.0762)
		(layer "F.Cu")
		(net "M_A_CPU1_SA_DQ<3>")
	)
	(arc
		(start 79.328772 -226.558094)
		(mid 79.246481 -226.571585)
		(end 79.16926 -226.603052)
		(width 0.0762)
		(layer "F.Cu")
		(net "M_A_CPU1_SA_DQ<3>")
	)
	(arc
		(start 79.443072 -226.67341)
		(mid 79.409655 -226.592229)
		(end 79.328772 -226.558094)
		(width 0.0762)
		(layer "F.Cu")
		(net "M_A_CPU1_SA_DQ<3>")
	)
	(arc
		(start 79.160878 -226.607878)
		(mid 78.877922 -226.684055)
		(end 78.594966 -226.607878)
		(width 0.0762)
		(layer "F.Cu")
		(net "M_A_CPU1_SA_DQ<3>")
	)
	(arc
		(start 78.586584 -226.603052)
		(mid 78.403076 -226.557558)
		(end 78.220824 -226.607878)
		(width 0.0762)
		(layer "F.Cu")
		(net "M_A_CPU1_SA_DQ<3>")
	)
	(segment
		(start 60.2996 -233.46029)
		(end 58.58256 -233.46029)
		(width 0.101346)
		(layer "F.Cu")
		(net "M_A_CPU1_SA_DQ<31>")
	)
	(segment
		(start 65.475866 -239.687608)
		(end 64.774318 -239.687608)
		(width 0.10668)
		(layer "F.Cu")
		(net "M_A_CPU1_SA_DQ<31>")
	)
	(segment
		(start 78.594966 -244.427756)
		(end 78.586584 -244.42293)
		(width 0.0762)
		(layer "F.Cu")
		(net "M_A_CPU1_SA_DQ<31>")
	)
	(segment
		(start 76.504546 -244.372384)
		(end 76.402946 -244.473984)
		(width 0.0762)
		(layer "F.Cu")
		(net "M_A_CPU1_SA_DQ<31>")
	)
	(segment
		(start 58.157618 -233.885232)
		(end 55.328058 -233.885232)
		(width 0.101346)
		(layer "F.Cu")
		(net "M_A_CPU1_SA_DQ<31>")
	)
	(segment
		(start 79.347822 -244.750082)
		(end 79.452978 -244.569234)
		(width 0.0762)
		(layer "F.Cu")
		(net "M_A_CPU1_SA_DQ<31>")
	)
	(segment
		(start 61.693806 -236.607096)
		(end 61.693806 -235.905548)
		(width 0.10668)
		(layer "F.Cu")
		(net "M_A_CPU1_SA_DQ<31>")
	)
	(segment
		(start 60.46724 -233.62793)
		(end 60.2996 -233.46029)
		(width 0.101346)
		(layer "F.Cu")
		(net "M_A_CPU1_SA_DQ<31>")
	)
	(segment
		(start 77.449426 -244.372384)
		(end 76.504546 -244.372384)
		(width 0.0762)
		(layer "F.Cu")
		(net "M_A_CPU1_SA_DQ<31>")
	)
	(segment
		(start 61.693806 -235.905548)
		(end 60.596526 -234.808268)
		(width 0.10668)
		(layer "F.Cu")
		(net "M_A_CPU1_SA_DQ<31>")
	)
	(segment
		(start 79.168244 -244.423438)
		(end 79.160878 -244.427756)
		(width 0.0762)
		(layer "F.Cu")
		(net "M_A_CPU1_SA_DQ<31>")
	)
	(segment
		(start 60.596526 -234.808268)
		(end 60.596526 -233.757216)
		(width 0.10668)
		(layer "F.Cu")
		(net "M_A_CPU1_SA_DQ<31>")
	)
	(segment
		(start 60.596526 -233.757216)
		(end 60.46724 -233.62793)
		(width 0.10668)
		(layer "F.Cu")
		(net "M_A_CPU1_SA_DQ<31>")
	)
	(segment
		(start 70.262242 -244.473984)
		(end 65.475866 -239.687608)
		(width 0.10668)
		(layer "F.Cu")
		(net "M_A_CPU1_SA_DQ<31>")
	)
	(segment
		(start 76.402946 -244.473984)
		(end 70.262242 -244.473984)
		(width 0.10668)
		(layer "F.Cu")
		(net "M_A_CPU1_SA_DQ<31>")
	)
	(segment
		(start 64.774318 -239.687608)
		(end 61.693806 -236.607096)
		(width 0.10668)
		(layer "F.Cu")
		(net "M_A_CPU1_SA_DQ<31>")
	)
	(segment
		(start 79.347822 -244.750336)
		(end 79.347822 -244.750082)
		(width 0.0762)
		(layer "F.Cu")
		(net "M_A_CPU1_SA_DQ<31>")
	)
	(segment
		(start 79.16926 -244.42293)
		(end 79.168244 -244.423438)
		(width 0.0762)
		(layer "F.Cu")
		(net "M_A_CPU1_SA_DQ<31>")
	)
	(segment
		(start 58.58256 -233.46029)
		(end 58.157618 -233.885232)
		(width 0.101346)
		(layer "F.Cu")
		(net "M_A_CPU1_SA_DQ<31>")
	)
	(arc
		(start 78.586584 -244.42293)
		(mid 78.403076 -244.377436)
		(end 78.220824 -244.427756)
		(width 0.0762)
		(layer "F.Cu")
		(net "M_A_CPU1_SA_DQ<31>")
	)
	(arc
		(start 79.349346 -244.377464)
		(mid 79.256422 -244.388787)
		(end 79.16926 -244.42293)
		(width 0.0762)
		(layer "F.Cu")
		(net "M_A_CPU1_SA_DQ<31>")
	)
	(arc
		(start 79.452978 -244.569234)
		(mid 79.444041 -244.45021)
		(end 79.349346 -244.377464)
		(width 0.0762)
		(layer "F.Cu")
		(net "M_A_CPU1_SA_DQ<31>")
	)
	(arc
		(start 78.220824 -244.427756)
		(mid 77.937868 -244.503933)
		(end 77.654912 -244.427756)
		(width 0.0762)
		(layer "F.Cu")
		(net "M_A_CPU1_SA_DQ<31>")
	)
	(arc
		(start 77.654912 -244.427756)
		(mid 77.555839 -244.386442)
		(end 77.449426 -244.372384)
		(width 0.0762)
		(layer "F.Cu")
		(net "M_A_CPU1_SA_DQ<31>")
	)
	(arc
		(start 79.160878 -244.427756)
		(mid 78.877922 -244.503933)
		(end 78.594966 -244.427756)
		(width 0.0762)
		(layer "F.Cu")
		(net "M_A_CPU1_SA_DQ<31>")
	)
	(segment
		(start 77.108558 -243.793264)
		(end 75.986386 -243.793264)
		(width 0.0762)
		(layer "F.Cu")
		(net "M_A_CPU1_SA_DQ<30>")
	)
	(segment
		(start 58.13044 -232.610406)
		(end 58.128662 -232.612184)
		(width 0.101346)
		(layer "F.Cu")
		(net "M_A_CPU1_SA_DQ<30>")
	)
	(segment
		(start 60.67044 -232.610406)
		(end 58.13044 -232.610406)
		(width 0.101346)
		(layer "F.Cu")
		(net "M_A_CPU1_SA_DQ<30>")
	)
	(segment
		(start 62.37605 -235.473494)
		(end 62.225174 -235.473494)
		(width 0.10668)
		(layer "F.Cu")
		(net "M_A_CPU1_SA_DQ<30>")
	)
	(segment
		(start 63.904876 -236.615732)
		(end 63.773558 -236.484414)
		(width 0.10668)
		(layer "F.Cu")
		(net "M_A_CPU1_SA_DQ<30>")
	)
	(segment
		(start 61.277246 -233.051604)
		(end 60.836048 -232.610406)
		(width 0.10668)
		(layer "F.Cu")
		(net "M_A_CPU1_SA_DQ<30>")
	)
	(segment
		(start 63.78702 -236.884464)
		(end 63.904876 -236.766608)
		(width 0.10668)
		(layer "F.Cu")
		(net "M_A_CPU1_SA_DQ<30>")
	)
	(segment
		(start 63.773558 -236.484414)
		(end 63.622682 -236.484414)
		(width 0.10668)
		(layer "F.Cu")
		(net "M_A_CPU1_SA_DQ<30>")
	)
	(segment
		(start 56.225186 -232.612184)
		(end 55.798212 -232.18521)
		(width 0.101346)
		(layer "F.Cu")
		(net "M_A_CPU1_SA_DQ<30>")
	)
	(segment
		(start 63.20917 -235.920026)
		(end 63.058294 -235.920026)
		(width 0.10668)
		(layer "F.Cu")
		(net "M_A_CPU1_SA_DQ<30>")
	)
	(segment
		(start 63.35395 -236.60227)
		(end 63.222632 -236.470952)
		(width 0.10668)
		(layer "F.Cu")
		(net "M_A_CPU1_SA_DQ<30>")
	)
	(segment
		(start 62.940438 -236.037882)
		(end 62.789562 -236.037882)
		(width 0.10668)
		(layer "F.Cu")
		(net "M_A_CPU1_SA_DQ<30>")
	)
	(segment
		(start 60.836048 -232.610406)
		(end 60.67044 -232.610406)
		(width 0.10668)
		(layer "F.Cu")
		(net "M_A_CPU1_SA_DQ<30>")
	)
	(segment
		(start 62.658244 -235.755688)
		(end 62.7761 -235.637832)
		(width 0.10668)
		(layer "F.Cu")
		(net "M_A_CPU1_SA_DQ<30>")
	)
	(segment
		(start 55.798212 -232.18521)
		(end 55.328058 -232.18521)
		(width 0.101346)
		(layer "F.Cu")
		(net "M_A_CPU1_SA_DQ<30>")
	)
	(segment
		(start 75.983846 -243.790724)
		(end 70.542404 -243.790724)
		(width 0.10668)
		(layer "F.Cu")
		(net "M_A_CPU1_SA_DQ<30>")
	)
	(segment
		(start 63.340488 -236.20222)
		(end 63.340488 -236.051344)
		(width 0.10668)
		(layer "F.Cu")
		(net "M_A_CPU1_SA_DQ<30>")
	)
	(segment
		(start 62.644782 -235.355638)
		(end 62.493906 -235.355638)
		(width 0.10668)
		(layer "F.Cu")
		(net "M_A_CPU1_SA_DQ<30>")
	)
	(segment
		(start 63.058294 -235.920026)
		(end 62.940438 -236.037882)
		(width 0.10668)
		(layer "F.Cu")
		(net "M_A_CPU1_SA_DQ<30>")
	)
	(segment
		(start 75.986386 -243.793264)
		(end 75.983846 -243.790724)
		(width 0.0762)
		(layer "F.Cu")
		(net "M_A_CPU1_SA_DQ<30>")
	)
	(segment
		(start 62.7761 -235.486956)
		(end 62.644782 -235.355638)
		(width 0.10668)
		(layer "F.Cu")
		(net "M_A_CPU1_SA_DQ<30>")
	)
	(segment
		(start 62.493906 -235.355638)
		(end 62.37605 -235.473494)
		(width 0.10668)
		(layer "F.Cu")
		(net "M_A_CPU1_SA_DQ<30>")
	)
	(segment
		(start 77.759306 -243.612924)
		(end 77.750924 -243.61775)
		(width 0.0762)
		(layer "F.Cu")
		(net "M_A_CPU1_SA_DQ<30>")
	)
	(segment
		(start 63.78702 -237.03534)
		(end 63.78702 -236.884464)
		(width 0.10668)
		(layer "F.Cu")
		(net "M_A_CPU1_SA_DQ<30>")
	)
	(segment
		(start 58.128662 -232.612184)
		(end 56.225186 -232.612184)
		(width 0.101346)
		(layer "F.Cu")
		(net "M_A_CPU1_SA_DQ<30>")
	)
	(segment
		(start 62.7761 -235.637832)
		(end 62.7761 -235.486956)
		(width 0.10668)
		(layer "F.Cu")
		(net "M_A_CPU1_SA_DQ<30>")
	)
	(segment
		(start 63.904876 -236.766608)
		(end 63.904876 -236.615732)
		(width 0.10668)
		(layer "F.Cu")
		(net "M_A_CPU1_SA_DQ<30>")
	)
	(segment
		(start 70.542404 -243.790724)
		(end 63.78702 -237.03534)
		(width 0.10668)
		(layer "F.Cu")
		(net "M_A_CPU1_SA_DQ<30>")
	)
	(segment
		(start 62.225174 -235.473494)
		(end 62.05093 -235.29925)
		(width 0.10668)
		(layer "F.Cu")
		(net "M_A_CPU1_SA_DQ<30>")
	)
	(segment
		(start 63.222632 -236.320076)
		(end 63.340488 -236.20222)
		(width 0.10668)
		(layer "F.Cu")
		(net "M_A_CPU1_SA_DQ<30>")
	)
	(segment
		(start 62.05093 -234.755436)
		(end 61.277246 -233.981752)
		(width 0.10668)
		(layer "F.Cu")
		(net "M_A_CPU1_SA_DQ<30>")
	)
	(segment
		(start 63.504826 -236.60227)
		(end 63.35395 -236.60227)
		(width 0.10668)
		(layer "F.Cu")
		(net "M_A_CPU1_SA_DQ<30>")
	)
	(segment
		(start 63.222632 -236.470952)
		(end 63.222632 -236.320076)
		(width 0.10668)
		(layer "F.Cu")
		(net "M_A_CPU1_SA_DQ<30>")
	)
	(segment
		(start 62.789562 -236.037882)
		(end 62.658244 -235.906564)
		(width 0.10668)
		(layer "F.Cu")
		(net "M_A_CPU1_SA_DQ<30>")
	)
	(segment
		(start 61.277246 -233.981752)
		(end 61.277246 -233.051604)
		(width 0.10668)
		(layer "F.Cu")
		(net "M_A_CPU1_SA_DQ<30>")
	)
	(segment
		(start 62.658244 -235.906564)
		(end 62.658244 -235.755688)
		(width 0.10668)
		(layer "F.Cu")
		(net "M_A_CPU1_SA_DQ<30>")
	)
	(segment
		(start 77.937868 -243.94033)
		(end 78.030832 -243.78031)
		(width 0.0762)
		(layer "F.Cu")
		(net "M_A_CPU1_SA_DQ<30>")
	)
	(segment
		(start 62.05093 -235.29925)
		(end 62.05093 -234.755436)
		(width 0.10668)
		(layer "F.Cu")
		(net "M_A_CPU1_SA_DQ<30>")
	)
	(segment
		(start 63.622682 -236.484414)
		(end 63.504826 -236.60227)
		(width 0.10668)
		(layer "F.Cu")
		(net "M_A_CPU1_SA_DQ<30>")
	)
	(segment
		(start 63.340488 -236.051344)
		(end 63.20917 -235.920026)
		(width 0.10668)
		(layer "F.Cu")
		(net "M_A_CPU1_SA_DQ<30>")
	)
	(arc
		(start 77.184758 -243.787168)
		(mid 77.146781 -243.791754)
		(end 77.108558 -243.793264)
		(width 0.0762)
		(layer "F.Cu")
		(net "M_A_CPU1_SA_DQ<30>")
	)
	(arc
		(start 77.899006 -243.56949)
		(mid 77.826998 -243.584272)
		(end 77.759306 -243.612924)
		(width 0.0762)
		(layer "F.Cu")
		(net "M_A_CPU1_SA_DQ<30>")
	)
	(arc
		(start 78.030832 -243.78031)
		(mid 78.030672 -243.633749)
		(end 77.899006 -243.56949)
		(width 0.0762)
		(layer "F.Cu")
		(net "M_A_CPU1_SA_DQ<30>")
	)
	(arc
		(start 77.66812 -243.65712)
		(mid 77.429764 -243.734502)
		(end 77.184758 -243.787168)
		(width 0.0762)
		(layer "F.Cu")
		(net "M_A_CPU1_SA_DQ<30>")
	)
	(arc
		(start 77.750924 -243.61775)
		(mid 77.710326 -243.639126)
		(end 77.66812 -243.65712)
		(width 0.0762)
		(layer "F.Cu")
		(net "M_A_CPU1_SA_DQ<30>")
	)
	(segment
		(start 77.160374 -225.716084)
		(end 76.27493 -224.83064)
		(width 0.0762)
		(layer "F.Cu")
		(net "M_A_CPU1_SA_DQ<2>")
	)
	(segment
		(start 76.27493 -214.347298)
		(end 64.347344 -202.419712)
		(width 0.10668)
		(layer "F.Cu")
		(net "M_A_CPU1_SA_DQ<2>")
	)
	(segment
		(start 64.347344 -202.419712)
		(end 64.347344 -201.935334)
		(width 0.10668)
		(layer "F.Cu")
		(net "M_A_CPU1_SA_DQ<2>")
	)
	(segment
		(start 64.347344 -201.935334)
		(end 61.022484 -198.610474)
		(width 0.10668)
		(layer "F.Cu")
		(net "M_A_CPU1_SA_DQ<2>")
	)
	(segment
		(start 58.13044 -198.610474)
		(end 57.705244 -198.185278)
		(width 0.101346)
		(layer "F.Cu")
		(net "M_A_CPU1_SA_DQ<2>")
	)
	(segment
		(start 76.27493 -224.83064)
		(end 76.27493 -214.347298)
		(width 0.10668)
		(layer "F.Cu")
		(net "M_A_CPU1_SA_DQ<2>")
	)
	(segment
		(start 61.022484 -198.610474)
		(end 58.13044 -198.610474)
		(width 0.101346)
		(layer "F.Cu")
		(net "M_A_CPU1_SA_DQ<2>")
	)
	(segment
		(start 57.705244 -198.185278)
		(end 55.328058 -198.185278)
		(width 0.101346)
		(layer "F.Cu")
		(net "M_A_CPU1_SA_DQ<2>")
	)
	(segment
		(start 77.5335 -225.716084)
		(end 77.160374 -225.716084)
		(width 0.0762)
		(layer "F.Cu")
		(net "M_A_CPU1_SA_DQ<2>")
	)
	(arc
		(start 77.937868 -226.120452)
		(mid 77.819431 -225.834521)
		(end 77.5335 -225.716084)
		(width 0.0762)
		(layer "F.Cu")
		(net "M_A_CPU1_SA_DQ<2>")
	)
	(segment
		(start 63.112396 -236.99343)
		(end 62.9158 -237.190026)
		(width 0.10668)
		(layer "F.Cu")
		(net "M_A_CPU1_SA_DQ<29>")
	)
	(segment
		(start 62.069472 -236.343444)
		(end 62.266068 -236.146848)
		(width 0.10668)
		(layer "F.Cu")
		(net "M_A_CPU1_SA_DQ<29>")
	)
	(segment
		(start 61.488066 -235.067348)
		(end 61.567314 -234.9881)
		(width 0.10668)
		(layer "F.Cu")
		(net "M_A_CPU1_SA_DQ<29>")
	)
	(segment
		(start 63.894208 -238.319056)
		(end 63.762636 -238.187484)
		(width 0.10668)
		(layer "F.Cu")
		(net "M_A_CPU1_SA_DQ<29>")
	)
	(segment
		(start 61.205872 -234.785408)
		(end 61.054996 -234.785154)
		(width 0.10668)
		(layer "F.Cu")
		(net "M_A_CPU1_SA_DQ<29>")
	)
	(segment
		(start 65.087754 -238.817912)
		(end 64.956436 -238.686594)
		(width 0.10668)
		(layer "F.Cu")
		(net "M_A_CPU1_SA_DQ<29>")
	)
	(segment
		(start 65.088008 -238.968788)
		(end 65.087754 -238.817912)
		(width 0.10668)
		(layer "F.Cu")
		(net "M_A_CPU1_SA_DQ<29>")
	)
	(segment
		(start 62.201044 -236.625892)
		(end 62.069472 -236.49432)
		(width 0.10668)
		(layer "F.Cu")
		(net "M_A_CPU1_SA_DQ<29>")
	)
	(segment
		(start 65.273936 -239.346994)
		(end 65.123568 -239.347248)
		(width 0.10668)
		(layer "F.Cu")
		(net "M_A_CPU1_SA_DQ<29>")
	)
	(segment
		(start 64.458596 -238.883444)
		(end 64.327024 -238.751872)
		(width 0.10668)
		(layer "F.Cu")
		(net "M_A_CPU1_SA_DQ<29>")
	)
	(segment
		(start 64.991996 -239.215676)
		(end 64.991996 -239.0648)
		(width 0.10668)
		(layer "F.Cu")
		(net "M_A_CPU1_SA_DQ<29>")
	)
	(segment
		(start 79.064866 -244.262656)
		(end 79.064866 -244.26291)
		(width 0.0762)
		(layer "F.Cu")
		(net "M_A_CPU1_SA_DQ<29>")
	)
	(segment
		(start 63.82766 -237.557818)
		(end 63.676784 -237.557818)
		(width 0.10668)
		(layer "F.Cu")
		(net "M_A_CPU1_SA_DQ<29>")
	)
	(segment
		(start 65.520824 -239.250982)
		(end 65.369948 -239.250982)
		(width 0.10668)
		(layer "F.Cu")
		(net "M_A_CPU1_SA_DQ<29>")
	)
	(segment
		(start 62.069472 -236.49432)
		(end 62.069472 -236.343444)
		(width 0.10668)
		(layer "F.Cu")
		(net "M_A_CPU1_SA_DQ<29>")
	)
	(segment
		(start 63.39459 -237.124748)
		(end 63.263272 -236.99343)
		(width 0.10668)
		(layer "F.Cu")
		(net "M_A_CPU1_SA_DQ<29>")
	)
	(segment
		(start 65.369948 -239.250982)
		(end 65.273936 -239.346994)
		(width 0.10668)
		(layer "F.Cu")
		(net "M_A_CPU1_SA_DQ<29>")
	)
	(segment
		(start 77.148182 -244.100604)
		(end 76.423266 -244.100604)
		(width 0.0762)
		(layer "F.Cu")
		(net "M_A_CPU1_SA_DQ<29>")
	)
	(segment
		(start 64.80556 -238.686594)
		(end 64.608964 -238.88319)
		(width 0.10668)
		(layer "F.Cu")
		(net "M_A_CPU1_SA_DQ<29>")
	)
	(segment
		(start 76.423266 -244.100604)
		(end 76.392786 -244.131084)
		(width 0.0762)
		(layer "F.Cu")
		(net "M_A_CPU1_SA_DQ<29>")
	)
	(segment
		(start 64.523366 -238.253524)
		(end 64.392048 -238.122206)
		(width 0.10668)
		(layer "F.Cu")
		(net "M_A_CPU1_SA_DQ<29>")
	)
	(segment
		(start 63.958978 -237.689136)
		(end 63.82766 -237.557818)
		(width 0.10668)
		(layer "F.Cu")
		(net "M_A_CPU1_SA_DQ<29>")
	)
	(segment
		(start 63.762636 -238.187484)
		(end 63.762636 -238.036608)
		(width 0.10668)
		(layer "F.Cu")
		(net "M_A_CPU1_SA_DQ<29>")
	)
	(segment
		(start 64.608964 -238.88319)
		(end 64.458596 -238.883444)
		(width 0.10668)
		(layer "F.Cu")
		(net "M_A_CPU1_SA_DQ<29>")
	)
	(segment
		(start 75.971146 -244.131084)
		(end 70.400926 -244.131084)
		(width 0.10668)
		(layer "F.Cu")
		(net "M_A_CPU1_SA_DQ<29>")
	)
	(segment
		(start 63.959232 -237.840012)
		(end 63.958978 -237.689136)
		(width 0.10668)
		(layer "F.Cu")
		(net "M_A_CPU1_SA_DQ<29>")
	)
	(segment
		(start 64.956436 -238.686594)
		(end 64.80556 -238.686594)
		(width 0.10668)
		(layer "F.Cu")
		(net "M_A_CPU1_SA_DQ<29>")
	)
	(segment
		(start 62.266068 -236.146848)
		(end 62.265814 -235.995972)
		(width 0.10668)
		(layer "F.Cu")
		(net "M_A_CPU1_SA_DQ<29>")
	)
	(segment
		(start 63.198248 -237.623096)
		(end 63.198248 -237.47222)
		(width 0.10668)
		(layer "F.Cu")
		(net "M_A_CPU1_SA_DQ<29>")
	)
	(segment
		(start 63.762636 -238.036608)
		(end 63.959232 -237.840012)
		(width 0.10668)
		(layer "F.Cu")
		(net "M_A_CPU1_SA_DQ<29>")
	)
	(segment
		(start 62.63386 -236.907832)
		(end 62.830456 -236.711236)
		(width 0.10668)
		(layer "F.Cu")
		(net "M_A_CPU1_SA_DQ<29>")
	)
	(segment
		(start 61.435996 -234.70616)
		(end 61.28512 -234.70616)
		(width 0.10668)
		(layer "F.Cu")
		(net "M_A_CPU1_SA_DQ<29>")
	)
	(segment
		(start 62.765432 -237.19028)
		(end 62.63386 -237.058708)
		(width 0.10668)
		(layer "F.Cu")
		(net "M_A_CPU1_SA_DQ<29>")
	)
	(segment
		(start 77.759306 -244.267736)
		(end 77.750924 -244.26291)
		(width 0.0762)
		(layer "F.Cu")
		(net "M_A_CPU1_SA_DQ<29>")
	)
	(segment
		(start 63.198248 -237.47222)
		(end 63.394844 -237.275624)
		(width 0.10668)
		(layer "F.Cu")
		(net "M_A_CPU1_SA_DQ<29>")
	)
	(segment
		(start 63.394844 -237.275624)
		(end 63.39459 -237.124748)
		(width 0.10668)
		(layer "F.Cu")
		(net "M_A_CPU1_SA_DQ<29>")
	)
	(segment
		(start 62.830456 -236.711236)
		(end 62.830202 -236.56036)
		(width 0.10668)
		(layer "F.Cu")
		(net "M_A_CPU1_SA_DQ<29>")
	)
	(segment
		(start 76.392786 -244.131084)
		(end 75.971146 -244.131084)
		(width 0.0762)
		(layer "F.Cu")
		(net "M_A_CPU1_SA_DQ<29>")
	)
	(segment
		(start 60.779152 -233.035348)
		(end 59.428126 -233.035348)
		(width 0.10668)
		(layer "F.Cu")
		(net "M_A_CPU1_SA_DQ<29>")
	)
	(segment
		(start 65.123568 -239.347248)
		(end 64.991996 -239.215676)
		(width 0.10668)
		(layer "F.Cu")
		(net "M_A_CPU1_SA_DQ<29>")
	)
	(segment
		(start 61.488066 -235.218224)
		(end 61.488066 -235.067348)
		(width 0.10668)
		(layer "F.Cu")
		(net "M_A_CPU1_SA_DQ<29>")
	)
	(segment
		(start 64.044576 -238.318802)
		(end 63.894208 -238.319056)
		(width 0.10668)
		(layer "F.Cu")
		(net "M_A_CPU1_SA_DQ<29>")
	)
	(segment
		(start 61.567568 -234.837732)
		(end 61.435996 -234.70616)
		(width 0.10668)
		(layer "F.Cu")
		(net "M_A_CPU1_SA_DQ<29>")
	)
	(segment
		(start 62.63386 -237.058708)
		(end 62.63386 -236.907832)
		(width 0.10668)
		(layer "F.Cu")
		(net "M_A_CPU1_SA_DQ<29>")
	)
	(segment
		(start 63.676784 -237.557818)
		(end 63.480188 -237.754414)
		(width 0.10668)
		(layer "F.Cu")
		(net "M_A_CPU1_SA_DQ<29>")
	)
	(segment
		(start 62.351412 -236.625638)
		(end 62.201044 -236.625892)
		(width 0.10668)
		(layer "F.Cu")
		(net "M_A_CPU1_SA_DQ<29>")
	)
	(segment
		(start 62.548008 -236.429042)
		(end 62.351412 -236.625638)
		(width 0.10668)
		(layer "F.Cu")
		(net "M_A_CPU1_SA_DQ<29>")
	)
	(segment
		(start 62.265814 -235.995972)
		(end 61.488066 -235.218224)
		(width 0.10668)
		(layer "F.Cu")
		(net "M_A_CPU1_SA_DQ<29>")
	)
	(segment
		(start 60.936886 -233.193082)
		(end 60.779152 -233.035348)
		(width 0.10668)
		(layer "F.Cu")
		(net "M_A_CPU1_SA_DQ<29>")
	)
	(segment
		(start 61.28512 -234.70616)
		(end 61.205872 -234.785408)
		(width 0.10668)
		(layer "F.Cu")
		(net "M_A_CPU1_SA_DQ<29>")
	)
	(segment
		(start 63.480188 -237.754414)
		(end 63.32982 -237.754668)
		(width 0.10668)
		(layer "F.Cu")
		(net "M_A_CPU1_SA_DQ<29>")
	)
	(segment
		(start 62.9158 -237.190026)
		(end 62.765432 -237.19028)
		(width 0.10668)
		(layer "F.Cu")
		(net "M_A_CPU1_SA_DQ<29>")
	)
	(segment
		(start 64.392048 -238.122206)
		(end 64.241172 -238.122206)
		(width 0.10668)
		(layer "F.Cu")
		(net "M_A_CPU1_SA_DQ<29>")
	)
	(segment
		(start 61.054996 -234.785154)
		(end 60.936886 -234.667044)
		(width 0.10668)
		(layer "F.Cu")
		(net "M_A_CPU1_SA_DQ<29>")
	)
	(segment
		(start 64.327024 -238.600996)
		(end 64.52362 -238.4044)
		(width 0.10668)
		(layer "F.Cu")
		(net "M_A_CPU1_SA_DQ<29>")
	)
	(segment
		(start 64.991996 -239.0648)
		(end 65.088008 -238.968788)
		(width 0.10668)
		(layer "F.Cu")
		(net "M_A_CPU1_SA_DQ<29>")
	)
	(segment
		(start 63.263272 -236.99343)
		(end 63.112396 -236.99343)
		(width 0.10668)
		(layer "F.Cu")
		(net "M_A_CPU1_SA_DQ<29>")
	)
	(segment
		(start 62.698884 -236.429042)
		(end 62.548008 -236.429042)
		(width 0.10668)
		(layer "F.Cu")
		(net "M_A_CPU1_SA_DQ<29>")
	)
	(segment
		(start 63.32982 -237.754668)
		(end 63.198248 -237.623096)
		(width 0.10668)
		(layer "F.Cu")
		(net "M_A_CPU1_SA_DQ<29>")
	)
	(segment
		(start 64.241172 -238.122206)
		(end 64.044576 -238.318802)
		(width 0.10668)
		(layer "F.Cu")
		(net "M_A_CPU1_SA_DQ<29>")
	)
	(segment
		(start 64.327024 -238.751872)
		(end 64.327024 -238.600996)
		(width 0.10668)
		(layer "F.Cu")
		(net "M_A_CPU1_SA_DQ<29>")
	)
	(segment
		(start 60.936886 -234.667044)
		(end 60.936886 -233.193082)
		(width 0.10668)
		(layer "F.Cu")
		(net "M_A_CPU1_SA_DQ<29>")
	)
	(segment
		(start 64.52362 -238.4044)
		(end 64.523366 -238.253524)
		(width 0.10668)
		(layer "F.Cu")
		(net "M_A_CPU1_SA_DQ<29>")
	)
	(segment
		(start 70.400926 -244.131084)
		(end 65.520824 -239.250982)
		(width 0.10668)
		(layer "F.Cu")
		(net "M_A_CPU1_SA_DQ<29>")
	)
	(segment
		(start 61.567314 -234.9881)
		(end 61.567568 -234.837732)
		(width 0.10668)
		(layer "F.Cu")
		(net "M_A_CPU1_SA_DQ<29>")
	)
	(segment
		(start 62.830202 -236.56036)
		(end 62.698884 -236.429042)
		(width 0.10668)
		(layer "F.Cu")
		(net "M_A_CPU1_SA_DQ<29>")
	)
	(arc
		(start 78.690978 -244.26291)
		(mid 78.408022 -244.186733)
		(end 78.125066 -244.26291)
		(width 0.0762)
		(layer "F.Cu")
		(net "M_A_CPU1_SA_DQ<29>")
	)
	(arc
		(start 78.125066 -244.26291)
		(mid 77.942815 -244.31326)
		(end 77.759306 -244.267736)
		(width 0.0762)
		(layer "F.Cu")
		(net "M_A_CPU1_SA_DQ<29>")
	)
	(arc
		(start 79.817976 -243.94033)
		(mid 79.61396 -244.121024)
		(end 79.349346 -244.186202)
		(width 0.0762)
		(layer "F.Cu")
		(net "M_A_CPU1_SA_DQ<29>")
	)
	(arc
		(start 79.064866 -244.26291)
		(mid 78.877922 -244.313165)
		(end 78.690978 -244.26291)
		(width 0.0762)
		(layer "F.Cu")
		(net "M_A_CPU1_SA_DQ<29>")
	)
	(arc
		(start 77.750924 -244.26291)
		(mid 77.460291 -244.141873)
		(end 77.148182 -244.100604)
		(width 0.0762)
		(layer "F.Cu")
		(net "M_A_CPU1_SA_DQ<29>")
	)
	(arc
		(start 79.349346 -244.186202)
		(mid 79.202025 -244.205521)
		(end 79.064866 -244.262656)
		(width 0.0762)
		(layer "F.Cu")
		(net "M_A_CPU1_SA_DQ<29>")
	)
	(segment
		(start 65.125854 -237.348776)
		(end 64.974978 -237.348522)
		(width 0.10668)
		(layer "F.Cu")
		(net "M_A_CPU1_SA_DQ<28>")
	)
	(segment
		(start 69.088254 -241.70132)
		(end 69.207888 -241.581686)
		(width 0.10668)
		(layer "F.Cu")
		(net "M_A_CPU1_SA_DQ<28>")
	)
	(segment
		(start 70.618858 -242.992402)
		(end 70.499224 -243.112036)
		(width 0.10668)
		(layer "F.Cu")
		(net "M_A_CPU1_SA_DQ<28>")
	)
	(segment
		(start 67.514724 -239.737646)
		(end 67.383406 -239.606328)
		(width 0.10668)
		(layer "F.Cu")
		(net "M_A_CPU1_SA_DQ<28>")
	)
	(segment
		(start 67.23253 -239.606074)
		(end 67.112896 -239.725708)
		(width 0.10668)
		(layer "F.Cu")
		(net "M_A_CPU1_SA_DQ<28>")
	)
	(segment
		(start 65.690242 -237.913164)
		(end 65.539366 -237.91291)
		(width 0.10668)
		(layer "F.Cu")
		(net "M_A_CPU1_SA_DQ<28>")
	)
	(segment
		(start 65.137284 -237.900972)
		(end 65.137538 -237.750604)
		(width 0.10668)
		(layer "F.Cu")
		(net "M_A_CPU1_SA_DQ<28>")
	)
	(segment
		(start 69.370448 -241.98326)
		(end 69.219572 -241.98326)
		(width 0.10668)
		(layer "F.Cu")
		(net "M_A_CPU1_SA_DQ<28>")
	)
	(segment
		(start 69.640958 -241.86388)
		(end 69.490082 -241.863626)
		(width 0.10668)
		(layer "F.Cu")
		(net "M_A_CPU1_SA_DQ<28>")
	)
	(segment
		(start 67.959224 -240.722912)
		(end 67.959478 -240.572544)
		(width 0.10668)
		(layer "F.Cu")
		(net "M_A_CPU1_SA_DQ<28>")
	)
	(segment
		(start 66.668142 -239.041686)
		(end 66.548508 -239.16132)
		(width 0.10668)
		(layer "F.Cu")
		(net "M_A_CPU1_SA_DQ<28>")
	)
	(segment
		(start 69.652388 -242.416076)
		(end 69.652642 -242.265708)
		(width 0.10668)
		(layer "F.Cu")
		(net "M_A_CPU1_SA_DQ<28>")
	)
	(segment
		(start 66.830448 -239.594136)
		(end 66.830702 -239.443768)
		(width 0.10668)
		(layer "F.Cu")
		(net "M_A_CPU1_SA_DQ<28>")
	)
	(segment
		(start 70.336664 -242.710462)
		(end 70.336664 -242.559586)
		(width 0.10668)
		(layer "F.Cu")
		(net "M_A_CPU1_SA_DQ<28>")
	)
	(segment
		(start 65.98412 -238.596932)
		(end 65.833244 -238.596932)
		(width 0.10668)
		(layer "F.Cu")
		(net "M_A_CPU1_SA_DQ<28>")
	)
	(segment
		(start 66.266314 -238.87938)
		(end 66.385948 -238.759746)
		(width 0.10668)
		(layer "F.Cu")
		(net "M_A_CPU1_SA_DQ<28>")
	)
	(segment
		(start 64.692784 -236.915706)
		(end 61.617606 -233.840528)
		(width 0.10668)
		(layer "F.Cu")
		(net "M_A_CPU1_SA_DQ<28>")
	)
	(segment
		(start 67.526408 -240.290096)
		(end 67.394836 -240.158524)
		(width 0.10668)
		(layer "F.Cu")
		(net "M_A_CPU1_SA_DQ<28>")
	)
	(segment
		(start 68.80606 -241.418872)
		(end 68.655184 -241.418872)
		(width 0.10668)
		(layer "F.Cu")
		(net "M_A_CPU1_SA_DQ<28>")
	)
	(segment
		(start 66.830702 -239.443768)
		(end 66.950336 -239.324134)
		(width 0.10668)
		(layer "F.Cu")
		(net "M_A_CPU1_SA_DQ<28>")
	)
	(segment
		(start 68.079112 -240.302034)
		(end 67.947794 -240.170716)
		(width 0.10668)
		(layer "F.Cu")
		(net "M_A_CPU1_SA_DQ<28>")
	)
	(segment
		(start 66.819018 -239.04194)
		(end 66.668142 -239.041686)
		(width 0.10668)
		(layer "F.Cu")
		(net "M_A_CPU1_SA_DQ<28>")
	)
	(segment
		(start 69.772276 -241.995198)
		(end 69.640958 -241.86388)
		(width 0.10668)
		(layer "F.Cu")
		(net "M_A_CPU1_SA_DQ<28>")
	)
	(segment
		(start 69.088 -241.851688)
		(end 69.088254 -241.70132)
		(width 0.10668)
		(layer "F.Cu")
		(net "M_A_CPU1_SA_DQ<28>")
	)
	(segment
		(start 66.950336 -239.173258)
		(end 66.819018 -239.04194)
		(width 0.10668)
		(layer "F.Cu")
		(net "M_A_CPU1_SA_DQ<28>")
	)
	(segment
		(start 67.796918 -240.170462)
		(end 67.677284 -240.290096)
		(width 0.10668)
		(layer "F.Cu")
		(net "M_A_CPU1_SA_DQ<28>")
	)
	(segment
		(start 70.216776 -242.980464)
		(end 70.21703 -242.830096)
		(width 0.10668)
		(layer "F.Cu")
		(net "M_A_CPU1_SA_DQ<28>")
	)
	(segment
		(start 66.950336 -239.324134)
		(end 66.950336 -239.173258)
		(width 0.10668)
		(layer "F.Cu")
		(net "M_A_CPU1_SA_DQ<28>")
	)
	(segment
		(start 70.205346 -242.428268)
		(end 70.05447 -242.428014)
		(width 0.10668)
		(layer "F.Cu")
		(net "M_A_CPU1_SA_DQ<28>")
	)
	(segment
		(start 65.82156 -238.195358)
		(end 65.82156 -238.044482)
		(width 0.10668)
		(layer "F.Cu")
		(net "M_A_CPU1_SA_DQ<28>")
	)
	(segment
		(start 70.769734 -242.992656)
		(end 70.618858 -242.992402)
		(width 0.10668)
		(layer "F.Cu")
		(net "M_A_CPU1_SA_DQ<28>")
	)
	(segment
		(start 64.855344 -237.468156)
		(end 64.704468 -237.468156)
		(width 0.10668)
		(layer "F.Cu")
		(net "M_A_CPU1_SA_DQ<28>")
	)
	(segment
		(start 69.207888 -241.581686)
		(end 69.207888 -241.43081)
		(width 0.10668)
		(layer "F.Cu")
		(net "M_A_CPU1_SA_DQ<28>")
	)
	(segment
		(start 68.523866 -241.136932)
		(end 68.6435 -241.017298)
		(width 0.10668)
		(layer "F.Cu")
		(net "M_A_CPU1_SA_DQ<28>")
	)
	(segment
		(start 67.959478 -240.572544)
		(end 68.079112 -240.45291)
		(width 0.10668)
		(layer "F.Cu")
		(net "M_A_CPU1_SA_DQ<28>")
	)
	(segment
		(start 66.385948 -238.759746)
		(end 66.385948 -238.60887)
		(width 0.10668)
		(layer "F.Cu")
		(net "M_A_CPU1_SA_DQ<28>")
	)
	(segment
		(start 65.833244 -238.596932)
		(end 65.701672 -238.46536)
		(width 0.10668)
		(layer "F.Cu")
		(net "M_A_CPU1_SA_DQ<28>")
	)
	(segment
		(start 64.704468 -237.468156)
		(end 64.572896 -237.336584)
		(width 0.10668)
		(layer "F.Cu")
		(net "M_A_CPU1_SA_DQ<28>")
	)
	(segment
		(start 65.268856 -238.032544)
		(end 65.137284 -237.900972)
		(width 0.10668)
		(layer "F.Cu")
		(net "M_A_CPU1_SA_DQ<28>")
	)
	(segment
		(start 69.934836 -242.547648)
		(end 69.78396 -242.547648)
		(width 0.10668)
		(layer "F.Cu")
		(net "M_A_CPU1_SA_DQ<28>")
	)
	(segment
		(start 70.499224 -243.112036)
		(end 70.348348 -243.112036)
		(width 0.10668)
		(layer "F.Cu")
		(net "M_A_CPU1_SA_DQ<28>")
	)
	(segment
		(start 65.257172 -237.480094)
		(end 65.125854 -237.348776)
		(width 0.10668)
		(layer "F.Cu")
		(net "M_A_CPU1_SA_DQ<28>")
	)
	(segment
		(start 68.241672 -240.854484)
		(end 68.090796 -240.854484)
		(width 0.10668)
		(layer "F.Cu")
		(net "M_A_CPU1_SA_DQ<28>")
	)
	(segment
		(start 64.974978 -237.348522)
		(end 64.855344 -237.468156)
		(width 0.10668)
		(layer "F.Cu")
		(net "M_A_CPU1_SA_DQ<28>")
	)
	(segment
		(start 69.490082 -241.863626)
		(end 69.370448 -241.98326)
		(width 0.10668)
		(layer "F.Cu")
		(net "M_A_CPU1_SA_DQ<28>")
	)
	(segment
		(start 67.514724 -239.888522)
		(end 67.514724 -239.737646)
		(width 0.10668)
		(layer "F.Cu")
		(net "M_A_CPU1_SA_DQ<28>")
	)
	(segment
		(start 64.692784 -237.066582)
		(end 64.692784 -236.915706)
		(width 0.10668)
		(layer "F.Cu")
		(net "M_A_CPU1_SA_DQ<28>")
	)
	(segment
		(start 65.257172 -237.63097)
		(end 65.257172 -237.480094)
		(width 0.10668)
		(layer "F.Cu")
		(net "M_A_CPU1_SA_DQ<28>")
	)
	(segment
		(start 69.07657 -241.299492)
		(end 68.925694 -241.299238)
		(width 0.10668)
		(layer "F.Cu")
		(net "M_A_CPU1_SA_DQ<28>")
	)
	(segment
		(start 64.572896 -237.336584)
		(end 64.57315 -237.186216)
		(width 0.10668)
		(layer "F.Cu")
		(net "M_A_CPU1_SA_DQ<28>")
	)
	(segment
		(start 66.397632 -239.16132)
		(end 66.26606 -239.029748)
		(width 0.10668)
		(layer "F.Cu")
		(net "M_A_CPU1_SA_DQ<28>")
	)
	(segment
		(start 60.051188 -231.335326)
		(end 59.428126 -231.335326)
		(width 0.10668)
		(layer "F.Cu")
		(net "M_A_CPU1_SA_DQ<28>")
	)
	(segment
		(start 61.617606 -233.840528)
		(end 61.617606 -232.901744)
		(width 0.10668)
		(layer "F.Cu")
		(net "M_A_CPU1_SA_DQ<28>")
	)
	(segment
		(start 67.383406 -239.606328)
		(end 67.23253 -239.606074)
		(width 0.10668)
		(layer "F.Cu")
		(net "M_A_CPU1_SA_DQ<28>")
	)
	(segment
		(start 68.090796 -240.854484)
		(end 67.959224 -240.722912)
		(width 0.10668)
		(layer "F.Cu")
		(net "M_A_CPU1_SA_DQ<28>")
	)
	(segment
		(start 65.701926 -238.314992)
		(end 65.82156 -238.195358)
		(width 0.10668)
		(layer "F.Cu")
		(net "M_A_CPU1_SA_DQ<28>")
	)
	(segment
		(start 68.523612 -241.2873)
		(end 68.523866 -241.136932)
		(width 0.10668)
		(layer "F.Cu")
		(net "M_A_CPU1_SA_DQ<28>")
	)
	(segment
		(start 71.227442 -243.450364)
		(end 70.769734 -242.992656)
		(width 0.10668)
		(layer "F.Cu")
		(net "M_A_CPU1_SA_DQ<28>")
	)
	(segment
		(start 65.137538 -237.750604)
		(end 65.257172 -237.63097)
		(width 0.10668)
		(layer "F.Cu")
		(net "M_A_CPU1_SA_DQ<28>")
	)
	(segment
		(start 76.214986 -243.506244)
		(end 76.159106 -243.450364)
		(width 0.0762)
		(layer "F.Cu")
		(net "M_A_CPU1_SA_DQ<28>")
	)
	(segment
		(start 65.701672 -238.46536)
		(end 65.701926 -238.314992)
		(width 0.10668)
		(layer "F.Cu")
		(net "M_A_CPU1_SA_DQ<28>")
	)
	(segment
		(start 68.655184 -241.418872)
		(end 68.523612 -241.2873)
		(width 0.10668)
		(layer "F.Cu")
		(net "M_A_CPU1_SA_DQ<28>")
	)
	(segment
		(start 66.26606 -239.029748)
		(end 66.266314 -238.87938)
		(width 0.10668)
		(layer "F.Cu")
		(net "M_A_CPU1_SA_DQ<28>")
	)
	(segment
		(start 68.6435 -241.017298)
		(end 68.6435 -240.866422)
		(width 0.10668)
		(layer "F.Cu")
		(net "M_A_CPU1_SA_DQ<28>")
	)
	(segment
		(start 66.103754 -238.477298)
		(end 65.98412 -238.596932)
		(width 0.10668)
		(layer "F.Cu")
		(net "M_A_CPU1_SA_DQ<28>")
	)
	(segment
		(start 67.677284 -240.290096)
		(end 67.526408 -240.290096)
		(width 0.10668)
		(layer "F.Cu")
		(net "M_A_CPU1_SA_DQ<28>")
	)
	(segment
		(start 70.348348 -243.112036)
		(end 70.216776 -242.980464)
		(width 0.10668)
		(layer "F.Cu")
		(net "M_A_CPU1_SA_DQ<28>")
	)
	(segment
		(start 70.21703 -242.830096)
		(end 70.336664 -242.710462)
		(width 0.10668)
		(layer "F.Cu")
		(net "M_A_CPU1_SA_DQ<28>")
	)
	(segment
		(start 65.539366 -237.91291)
		(end 65.419732 -238.032544)
		(width 0.10668)
		(layer "F.Cu")
		(net "M_A_CPU1_SA_DQ<28>")
	)
	(segment
		(start 67.39509 -240.008156)
		(end 67.514724 -239.888522)
		(width 0.10668)
		(layer "F.Cu")
		(net "M_A_CPU1_SA_DQ<28>")
	)
	(segment
		(start 69.207888 -241.43081)
		(end 69.07657 -241.299492)
		(width 0.10668)
		(layer "F.Cu")
		(net "M_A_CPU1_SA_DQ<28>")
	)
	(segment
		(start 70.336664 -242.559586)
		(end 70.205346 -242.428268)
		(width 0.10668)
		(layer "F.Cu")
		(net "M_A_CPU1_SA_DQ<28>")
	)
	(segment
		(start 76.159106 -243.450364)
		(end 71.227442 -243.450364)
		(width 0.10668)
		(layer "F.Cu")
		(net "M_A_CPU1_SA_DQ<28>")
	)
	(segment
		(start 69.772276 -242.146074)
		(end 69.772276 -241.995198)
		(width 0.10668)
		(layer "F.Cu")
		(net "M_A_CPU1_SA_DQ<28>")
	)
	(segment
		(start 67.394836 -240.158524)
		(end 67.39509 -240.008156)
		(width 0.10668)
		(layer "F.Cu")
		(net "M_A_CPU1_SA_DQ<28>")
	)
	(segment
		(start 64.57315 -237.186216)
		(end 64.692784 -237.066582)
		(width 0.10668)
		(layer "F.Cu")
		(net "M_A_CPU1_SA_DQ<28>")
	)
	(segment
		(start 66.385948 -238.60887)
		(end 66.25463 -238.477552)
		(width 0.10668)
		(layer "F.Cu")
		(net "M_A_CPU1_SA_DQ<28>")
	)
	(segment
		(start 67.112896 -239.725708)
		(end 66.96202 -239.725708)
		(width 0.10668)
		(layer "F.Cu")
		(net "M_A_CPU1_SA_DQ<28>")
	)
	(segment
		(start 70.05447 -242.428014)
		(end 69.934836 -242.547648)
		(width 0.10668)
		(layer "F.Cu")
		(net "M_A_CPU1_SA_DQ<28>")
	)
	(segment
		(start 66.25463 -238.477552)
		(end 66.103754 -238.477298)
		(width 0.10668)
		(layer "F.Cu")
		(net "M_A_CPU1_SA_DQ<28>")
	)
	(segment
		(start 61.617606 -232.901744)
		(end 60.051188 -231.335326)
		(width 0.10668)
		(layer "F.Cu")
		(net "M_A_CPU1_SA_DQ<28>")
	)
	(segment
		(start 69.78396 -242.547648)
		(end 69.652388 -242.416076)
		(width 0.10668)
		(layer "F.Cu")
		(net "M_A_CPU1_SA_DQ<28>")
	)
	(segment
		(start 68.925694 -241.299238)
		(end 68.80606 -241.418872)
		(width 0.10668)
		(layer "F.Cu")
		(net "M_A_CPU1_SA_DQ<28>")
	)
	(segment
		(start 68.361306 -240.73485)
		(end 68.241672 -240.854484)
		(width 0.10668)
		(layer "F.Cu")
		(net "M_A_CPU1_SA_DQ<28>")
	)
	(segment
		(start 66.548508 -239.16132)
		(end 66.397632 -239.16132)
		(width 0.10668)
		(layer "F.Cu")
		(net "M_A_CPU1_SA_DQ<28>")
	)
	(segment
		(start 66.96202 -239.725708)
		(end 66.830448 -239.594136)
		(width 0.10668)
		(layer "F.Cu")
		(net "M_A_CPU1_SA_DQ<28>")
	)
	(segment
		(start 77.400658 -243.506244)
		(end 76.214986 -243.506244)
		(width 0.0762)
		(layer "F.Cu")
		(net "M_A_CPU1_SA_DQ<28>")
	)
	(segment
		(start 69.652642 -242.265708)
		(end 69.772276 -242.146074)
		(width 0.10668)
		(layer "F.Cu")
		(net "M_A_CPU1_SA_DQ<28>")
	)
	(segment
		(start 68.512182 -240.735104)
		(end 68.361306 -240.73485)
		(width 0.10668)
		(layer "F.Cu")
		(net "M_A_CPU1_SA_DQ<28>")
	)
	(segment
		(start 68.079112 -240.45291)
		(end 68.079112 -240.302034)
		(width 0.10668)
		(layer "F.Cu")
		(net "M_A_CPU1_SA_DQ<28>")
	)
	(segment
		(start 67.947794 -240.170716)
		(end 67.796918 -240.170462)
		(width 0.10668)
		(layer "F.Cu")
		(net "M_A_CPU1_SA_DQ<28>")
	)
	(segment
		(start 65.419732 -238.032544)
		(end 65.268856 -238.032544)
		(width 0.10668)
		(layer "F.Cu")
		(net "M_A_CPU1_SA_DQ<28>")
	)
	(segment
		(start 65.82156 -238.044482)
		(end 65.690242 -237.913164)
		(width 0.10668)
		(layer "F.Cu")
		(net "M_A_CPU1_SA_DQ<28>")
	)
	(segment
		(start 68.6435 -240.866422)
		(end 68.512182 -240.735104)
		(width 0.10668)
		(layer "F.Cu")
		(net "M_A_CPU1_SA_DQ<28>")
	)
	(segment
		(start 69.219572 -241.98326)
		(end 69.088 -241.851688)
		(width 0.10668)
		(layer "F.Cu")
		(net "M_A_CPU1_SA_DQ<28>")
	)
	(arc
		(start 77.654912 -243.452904)
		(mid 77.579672 -243.486217)
		(end 77.498956 -243.50218)
		(width 0.0762)
		(layer "F.Cu")
		(net "M_A_CPU1_SA_DQ<28>")
	)
	(arc
		(start 77.89037 -243.378482)
		(mid 77.768514 -243.402638)
		(end 77.654912 -243.452904)
		(width 0.0762)
		(layer "F.Cu")
		(net "M_A_CPU1_SA_DQ<28>")
	)
	(arc
		(start 78.408022 -243.130324)
		(mid 78.171894 -243.301759)
		(end 77.89037 -243.378482)
		(width 0.0762)
		(layer "F.Cu")
		(net "M_A_CPU1_SA_DQ<28>")
	)
	(arc
		(start 77.498956 -243.50218)
		(mid 77.449849 -243.505221)
		(end 77.400658 -243.506244)
		(width 0.0762)
		(layer "F.Cu")
		(net "M_A_CPU1_SA_DQ<28>")
	)
	(segment
		(start 79.16926 -241.182906)
		(end 79.168244 -241.183414)
		(width 0.0762)
		(layer "F.Cu")
		(net "M_A_CPU1_SA_DQ<27>")
	)
	(segment
		(start 77.44587 -241.131344)
		(end 76.644246 -241.131344)
		(width 0.0762)
		(layer "F.Cu")
		(net "M_A_CPU1_SA_DQ<27>")
	)
	(segment
		(start 76.644246 -241.131344)
		(end 76.275184 -241.500406)
		(width 0.0762)
		(layer "F.Cu")
		(net "M_A_CPU1_SA_DQ<27>")
	)
	(segment
		(start 78.594966 -241.187732)
		(end 78.586584 -241.182906)
		(width 0.0762)
		(layer "F.Cu")
		(net "M_A_CPU1_SA_DQ<27>")
	)
	(segment
		(start 60.344812 -228.360478)
		(end 57.804812 -228.360478)
		(width 0.101346)
		(layer "F.Cu")
		(net "M_A_CPU1_SA_DQ<27>")
	)
	(segment
		(start 62.43447 -230.159052)
		(end 60.635896 -228.360478)
		(width 0.10668)
		(layer "F.Cu")
		(net "M_A_CPU1_SA_DQ<27>")
	)
	(segment
		(start 79.347822 -241.510058)
		(end 79.452978 -241.32921)
		(width 0.0762)
		(layer "F.Cu")
		(net "M_A_CPU1_SA_DQ<27>")
	)
	(segment
		(start 62.43447 -230.956612)
		(end 62.43447 -230.159052)
		(width 0.10668)
		(layer "F.Cu")
		(net "M_A_CPU1_SA_DQ<27>")
	)
	(segment
		(start 57.379616 -227.935282)
		(end 55.328058 -227.935282)
		(width 0.101346)
		(layer "F.Cu")
		(net "M_A_CPU1_SA_DQ<27>")
	)
	(segment
		(start 79.347822 -241.510312)
		(end 79.347822 -241.510058)
		(width 0.0762)
		(layer "F.Cu")
		(net "M_A_CPU1_SA_DQ<27>")
	)
	(segment
		(start 76.275184 -241.500406)
		(end 72.978264 -241.500406)
		(width 0.10668)
		(layer "F.Cu")
		(net "M_A_CPU1_SA_DQ<27>")
	)
	(segment
		(start 79.168244 -241.183414)
		(end 79.160878 -241.187732)
		(width 0.0762)
		(layer "F.Cu")
		(net "M_A_CPU1_SA_DQ<27>")
	)
	(segment
		(start 57.804812 -228.360478)
		(end 57.379616 -227.935282)
		(width 0.101346)
		(layer "F.Cu")
		(net "M_A_CPU1_SA_DQ<27>")
	)
	(segment
		(start 60.635896 -228.360478)
		(end 60.344812 -228.360478)
		(width 0.10668)
		(layer "F.Cu")
		(net "M_A_CPU1_SA_DQ<27>")
	)
	(segment
		(start 72.978264 -241.500406)
		(end 62.43447 -230.956612)
		(width 0.10668)
		(layer "F.Cu")
		(net "M_A_CPU1_SA_DQ<27>")
	)
	(arc
		(start 79.160878 -241.187732)
		(mid 78.877922 -241.263909)
		(end 78.594966 -241.187732)
		(width 0.0762)
		(layer "F.Cu")
		(net "M_A_CPU1_SA_DQ<27>")
	)
	(arc
		(start 78.586584 -241.182906)
		(mid 78.403076 -241.137412)
		(end 78.220824 -241.187732)
		(width 0.0762)
		(layer "F.Cu")
		(net "M_A_CPU1_SA_DQ<27>")
	)
	(arc
		(start 77.654912 -241.187732)
		(mid 77.55412 -241.145726)
		(end 77.44587 -241.131344)
		(width 0.0762)
		(layer "F.Cu")
		(net "M_A_CPU1_SA_DQ<27>")
	)
	(arc
		(start 79.452978 -241.32921)
		(mid 79.444041 -241.210186)
		(end 79.349346 -241.13744)
		(width 0.0762)
		(layer "F.Cu")
		(net "M_A_CPU1_SA_DQ<27>")
	)
	(arc
		(start 78.220824 -241.187732)
		(mid 77.937868 -241.263909)
		(end 77.654912 -241.187732)
		(width 0.0762)
		(layer "F.Cu")
		(net "M_A_CPU1_SA_DQ<27>")
	)
	(arc
		(start 79.349346 -241.13744)
		(mid 79.256422 -241.148763)
		(end 79.16926 -241.182906)
		(width 0.0762)
		(layer "F.Cu")
		(net "M_A_CPU1_SA_DQ<27>")
	)
	(segment
		(start 76.822808 -240.633504)
		(end 76.433426 -240.633504)
		(width 0.0762)
		(layer "F.Cu")
		(net "M_A_CPU1_SA_DQ<26>")
	)
	(segment
		(start 63.11519 -228.882448)
		(end 61.410596 -227.177854)
		(width 0.10668)
		(layer "F.Cu")
		(net "M_A_CPU1_SA_DQ<26>")
	)
	(segment
		(start 76.433426 -240.633504)
		(end 76.258166 -240.808764)
		(width 0.0762)
		(layer "F.Cu")
		(net "M_A_CPU1_SA_DQ<26>")
	)
	(segment
		(start 75.971146 -240.808764)
		(end 73.364598 -240.808764)
		(width 0.10668)
		(layer "F.Cu")
		(net "M_A_CPU1_SA_DQ<26>")
	)
	(segment
		(start 76.258166 -240.808764)
		(end 75.971146 -240.808764)
		(width 0.0762)
		(layer "F.Cu")
		(net "M_A_CPU1_SA_DQ<26>")
	)
	(segment
		(start 61.410596 -226.745292)
		(end 61.32576 -226.660456)
		(width 0.10668)
		(layer "F.Cu")
		(net "M_A_CPU1_SA_DQ<26>")
	)
	(segment
		(start 73.364598 -240.808764)
		(end 63.11519 -230.559356)
		(width 0.10668)
		(layer "F.Cu")
		(net "M_A_CPU1_SA_DQ<26>")
	)
	(segment
		(start 57.705244 -226.23526)
		(end 55.328058 -226.23526)
		(width 0.101346)
		(layer "F.Cu")
		(net "M_A_CPU1_SA_DQ<26>")
	)
	(segment
		(start 58.13044 -226.660456)
		(end 57.705244 -226.23526)
		(width 0.101346)
		(layer "F.Cu")
		(net "M_A_CPU1_SA_DQ<26>")
	)
	(segment
		(start 61.32576 -226.660456)
		(end 60.67044 -226.660456)
		(width 0.10668)
		(layer "F.Cu")
		(net "M_A_CPU1_SA_DQ<26>")
	)
	(segment
		(start 61.410596 -227.177854)
		(end 61.410596 -226.745292)
		(width 0.10668)
		(layer "F.Cu")
		(net "M_A_CPU1_SA_DQ<26>")
	)
	(segment
		(start 60.67044 -226.660456)
		(end 58.13044 -226.660456)
		(width 0.101346)
		(layer "F.Cu")
		(net "M_A_CPU1_SA_DQ<26>")
	)
	(segment
		(start 63.11519 -230.559356)
		(end 63.11519 -228.882448)
		(width 0.10668)
		(layer "F.Cu")
		(net "M_A_CPU1_SA_DQ<26>")
	)
	(segment
		(start 77.937868 -240.700306)
		(end 78.030832 -240.540286)
		(width 0.0762)
		(layer "F.Cu")
		(net "M_A_CPU1_SA_DQ<26>")
	)
	(arc
		(start 77.759306 -240.3729)
		(mid 77.308848 -240.567131)
		(end 76.822808 -240.633504)
		(width 0.0762)
		(layer "F.Cu")
		(net "M_A_CPU1_SA_DQ<26>")
	)
	(arc
		(start 78.030832 -240.540286)
		(mid 78.030672 -240.393725)
		(end 77.899006 -240.329466)
		(width 0.0762)
		(layer "F.Cu")
		(net "M_A_CPU1_SA_DQ<26>")
	)
	(arc
		(start 77.899006 -240.329466)
		(mid 77.826998 -240.344248)
		(end 77.759306 -240.3729)
		(width 0.0762)
		(layer "F.Cu")
		(net "M_A_CPU1_SA_DQ<26>")
	)
	(segment
		(start 61.564012 -227.81895)
		(end 61.312298 -227.567236)
		(width 0.10668)
		(layer "F.Cu")
		(net "M_A_CPU1_SA_DQ<25>")
	)
	(segment
		(start 75.966066 -241.159284)
		(end 73.118726 -241.159284)
		(width 0.10668)
		(layer "F.Cu")
		(net "M_A_CPU1_SA_DQ<25>")
	)
	(segment
		(start 62.1284 -228.534214)
		(end 62.1284 -228.383338)
		(width 0.10668)
		(layer "F.Cu")
		(net "M_A_CPU1_SA_DQ<25>")
	)
	(segment
		(start 79.064866 -241.022632)
		(end 79.064866 -241.022886)
		(width 0.0762)
		(layer "F.Cu")
		(net "M_A_CPU1_SA_DQ<25>")
	)
	(segment
		(start 61.922152 -229.15372)
		(end 61.79058 -229.022148)
		(width 0.10668)
		(layer "F.Cu")
		(net "M_A_CPU1_SA_DQ<25>")
	)
	(segment
		(start 62.410594 -228.816154)
		(end 62.073028 -229.15372)
		(width 0.10668)
		(layer "F.Cu")
		(net "M_A_CPU1_SA_DQ<25>")
	)
	(segment
		(start 61.846206 -228.251766)
		(end 61.50864 -228.589332)
		(width 0.10668)
		(layer "F.Cu")
		(net "M_A_CPU1_SA_DQ<25>")
	)
	(segment
		(start 62.77483 -229.80142)
		(end 62.59449 -229.62108)
		(width 0.10668)
		(layer "F.Cu")
		(net "M_A_CPU1_SA_DQ<25>")
	)
	(segment
		(start 60.373006 -227.529644)
		(end 59.92876 -227.085398)
		(width 0.10668)
		(layer "F.Cu")
		(net "M_A_CPU1_SA_DQ<25>")
	)
	(segment
		(start 60.709302 -227.91928)
		(end 60.544202 -227.91928)
		(width 0.10668)
		(layer "F.Cu")
		(net "M_A_CPU1_SA_DQ<25>")
	)
	(segment
		(start 60.544202 -227.91928)
		(end 60.373006 -227.748084)
		(width 0.10668)
		(layer "F.Cu")
		(net "M_A_CPU1_SA_DQ<25>")
	)
	(segment
		(start 62.77483 -229.029768)
		(end 62.56147 -228.816408)
		(width 0.10668)
		(layer "F.Cu")
		(net "M_A_CPU1_SA_DQ<25>")
	)
	(segment
		(start 73.118726 -241.159284)
		(end 62.77483 -230.815388)
		(width 0.10668)
		(layer "F.Cu")
		(net "M_A_CPU1_SA_DQ<25>")
	)
	(segment
		(start 61.79058 -229.022148)
		(end 61.790834 -228.87178)
		(width 0.10668)
		(layer "F.Cu")
		(net "M_A_CPU1_SA_DQ<25>")
	)
	(segment
		(start 62.77483 -230.815388)
		(end 62.77483 -229.80142)
		(width 0.10668)
		(layer "F.Cu")
		(net "M_A_CPU1_SA_DQ<25>")
	)
	(segment
		(start 61.226192 -228.45776)
		(end 61.226446 -228.307392)
		(width 0.10668)
		(layer "F.Cu")
		(net "M_A_CPU1_SA_DQ<25>")
	)
	(segment
		(start 61.312298 -227.567236)
		(end 61.061346 -227.567236)
		(width 0.10668)
		(layer "F.Cu")
		(net "M_A_CPU1_SA_DQ<25>")
	)
	(segment
		(start 62.56147 -228.816408)
		(end 62.410594 -228.816154)
		(width 0.10668)
		(layer "F.Cu")
		(net "M_A_CPU1_SA_DQ<25>")
	)
	(segment
		(start 59.92876 -227.085398)
		(end 59.428126 -227.085398)
		(width 0.10668)
		(layer "F.Cu")
		(net "M_A_CPU1_SA_DQ<25>")
	)
	(segment
		(start 61.997082 -228.25202)
		(end 61.846206 -228.251766)
		(width 0.10668)
		(layer "F.Cu")
		(net "M_A_CPU1_SA_DQ<25>")
	)
	(segment
		(start 77.759306 -241.027712)
		(end 77.750924 -241.022886)
		(width 0.0762)
		(layer "F.Cu")
		(net "M_A_CPU1_SA_DQ<25>")
	)
	(segment
		(start 76.479146 -240.938304)
		(end 76.258166 -241.159284)
		(width 0.0762)
		(layer "F.Cu")
		(net "M_A_CPU1_SA_DQ<25>")
	)
	(segment
		(start 61.226446 -228.307392)
		(end 61.564012 -227.969826)
		(width 0.10668)
		(layer "F.Cu")
		(net "M_A_CPU1_SA_DQ<25>")
	)
	(segment
		(start 61.564012 -227.969826)
		(end 61.564012 -227.81895)
		(width 0.10668)
		(layer "F.Cu")
		(net "M_A_CPU1_SA_DQ<25>")
	)
	(segment
		(start 77.436726 -240.938304)
		(end 76.479146 -240.938304)
		(width 0.0762)
		(layer "F.Cu")
		(net "M_A_CPU1_SA_DQ<25>")
	)
	(segment
		(start 61.50864 -228.589332)
		(end 61.357764 -228.589332)
		(width 0.10668)
		(layer "F.Cu")
		(net "M_A_CPU1_SA_DQ<25>")
	)
	(segment
		(start 61.061346 -227.567236)
		(end 60.709302 -227.91928)
		(width 0.10668)
		(layer "F.Cu")
		(net "M_A_CPU1_SA_DQ<25>")
	)
	(segment
		(start 61.790834 -228.87178)
		(end 62.1284 -228.534214)
		(width 0.10668)
		(layer "F.Cu")
		(net "M_A_CPU1_SA_DQ<25>")
	)
	(segment
		(start 61.357764 -228.589332)
		(end 61.226192 -228.45776)
		(width 0.10668)
		(layer "F.Cu")
		(net "M_A_CPU1_SA_DQ<25>")
	)
	(segment
		(start 62.59449 -229.62108)
		(end 62.59449 -229.402386)
		(width 0.10668)
		(layer "F.Cu")
		(net "M_A_CPU1_SA_DQ<25>")
	)
	(segment
		(start 62.073028 -229.15372)
		(end 61.922152 -229.15372)
		(width 0.10668)
		(layer "F.Cu")
		(net "M_A_CPU1_SA_DQ<25>")
	)
	(segment
		(start 62.1284 -228.383338)
		(end 61.997082 -228.25202)
		(width 0.10668)
		(layer "F.Cu")
		(net "M_A_CPU1_SA_DQ<25>")
	)
	(segment
		(start 62.77483 -229.222046)
		(end 62.77483 -229.029768)
		(width 0.10668)
		(layer "F.Cu")
		(net "M_A_CPU1_SA_DQ<25>")
	)
	(segment
		(start 60.373006 -227.748084)
		(end 60.373006 -227.529644)
		(width 0.10668)
		(layer "F.Cu")
		(net "M_A_CPU1_SA_DQ<25>")
	)
	(segment
		(start 76.258166 -241.159284)
		(end 75.966066 -241.159284)
		(width 0.0762)
		(layer "F.Cu")
		(net "M_A_CPU1_SA_DQ<25>")
	)
	(segment
		(start 62.59449 -229.402386)
		(end 62.77483 -229.222046)
		(width 0.10668)
		(layer "F.Cu")
		(net "M_A_CPU1_SA_DQ<25>")
	)
	(arc
		(start 79.064866 -241.022886)
		(mid 78.877922 -241.073141)
		(end 78.690978 -241.022886)
		(width 0.0762)
		(layer "F.Cu")
		(net "M_A_CPU1_SA_DQ<25>")
	)
	(arc
		(start 79.349346 -240.946178)
		(mid 79.202025 -240.965497)
		(end 79.064866 -241.022632)
		(width 0.0762)
		(layer "F.Cu")
		(net "M_A_CPU1_SA_DQ<25>")
	)
	(arc
		(start 79.817976 -240.700306)
		(mid 79.61396 -240.881)
		(end 79.349346 -240.946178)
		(width 0.0762)
		(layer "F.Cu")
		(net "M_A_CPU1_SA_DQ<25>")
	)
	(arc
		(start 77.750924 -241.022886)
		(mid 77.599427 -240.959767)
		(end 77.436726 -240.938304)
		(width 0.0762)
		(layer "F.Cu")
		(net "M_A_CPU1_SA_DQ<25>")
	)
	(arc
		(start 78.690978 -241.022886)
		(mid 78.408022 -240.946709)
		(end 78.125066 -241.022886)
		(width 0.0762)
		(layer "F.Cu")
		(net "M_A_CPU1_SA_DQ<25>")
	)
	(arc
		(start 78.125066 -241.022886)
		(mid 77.942815 -241.073236)
		(end 77.759306 -241.027712)
		(width 0.0762)
		(layer "F.Cu")
		(net "M_A_CPU1_SA_DQ<25>")
	)
	(segment
		(start 62.177168 -226.451668)
		(end 62.177168 -226.300792)
		(width 0.10668)
		(layer "F.Cu")
		(net "M_A_CPU1_SA_DQ<24>")
	)
	(segment
		(start 62.597792 -227.723954)
		(end 62.446916 -227.723954)
		(width 0.10668)
		(layer "F.Cu")
		(net "M_A_CPU1_SA_DQ<24>")
	)
	(segment
		(start 62.741556 -226.86518)
		(end 62.610238 -226.733862)
		(width 0.10668)
		(layer "F.Cu")
		(net "M_A_CPU1_SA_DQ<24>")
	)
	(segment
		(start 73.503282 -240.465864)
		(end 63.45555 -230.418132)
		(width 0.10668)
		(layer "F.Cu")
		(net "M_A_CPU1_SA_DQ<24>")
	)
	(segment
		(start 62.177168 -226.300792)
		(end 62.04585 -226.169474)
		(width 0.10668)
		(layer "F.Cu")
		(net "M_A_CPU1_SA_DQ<24>")
	)
	(segment
		(start 62.459362 -226.733608)
		(end 62.033404 -227.159566)
		(width 0.10668)
		(layer "F.Cu")
		(net "M_A_CPU1_SA_DQ<24>")
	)
	(segment
		(start 61.750956 -227.027994)
		(end 61.75121 -226.877626)
		(width 0.10668)
		(layer "F.Cu")
		(net "M_A_CPU1_SA_DQ<24>")
	)
	(segment
		(start 63.45555 -230.418132)
		(end 63.45555 -228.447346)
		(width 0.10668)
		(layer "F.Cu")
		(net "M_A_CPU1_SA_DQ<24>")
	)
	(segment
		(start 63.305944 -227.580444)
		(end 63.305944 -227.429568)
		(width 0.10668)
		(layer "F.Cu")
		(net "M_A_CPU1_SA_DQ<24>")
	)
	(segment
		(start 62.879732 -228.15677)
		(end 62.879986 -228.006402)
		(width 0.10668)
		(layer "F.Cu")
		(net "M_A_CPU1_SA_DQ<24>")
	)
	(segment
		(start 62.446916 -227.723954)
		(end 62.315344 -227.592382)
		(width 0.10668)
		(layer "F.Cu")
		(net "M_A_CPU1_SA_DQ<24>")
	)
	(segment
		(start 62.610238 -226.733862)
		(end 62.459362 -226.733608)
		(width 0.10668)
		(layer "F.Cu")
		(net "M_A_CPU1_SA_DQ<24>")
	)
	(segment
		(start 63.305944 -227.429568)
		(end 63.174626 -227.29825)
		(width 0.10668)
		(layer "F.Cu")
		(net "M_A_CPU1_SA_DQ<24>")
	)
	(segment
		(start 62.315598 -227.442014)
		(end 62.741556 -227.016056)
		(width 0.10668)
		(layer "F.Cu")
		(net "M_A_CPU1_SA_DQ<24>")
	)
	(segment
		(start 61.882528 -227.159566)
		(end 61.750956 -227.027994)
		(width 0.10668)
		(layer "F.Cu")
		(net "M_A_CPU1_SA_DQ<24>")
	)
	(segment
		(start 76.250546 -240.465864)
		(end 75.971146 -240.465864)
		(width 0.0762)
		(layer "F.Cu")
		(net "M_A_CPU1_SA_DQ<24>")
	)
	(segment
		(start 77.262228 -240.318544)
		(end 76.397866 -240.318544)
		(width 0.0762)
		(layer "F.Cu")
		(net "M_A_CPU1_SA_DQ<24>")
	)
	(segment
		(start 62.741556 -227.016056)
		(end 62.741556 -226.86518)
		(width 0.10668)
		(layer "F.Cu")
		(net "M_A_CPU1_SA_DQ<24>")
	)
	(segment
		(start 63.174626 -227.29825)
		(end 63.02375 -227.297996)
		(width 0.10668)
		(layer "F.Cu")
		(net "M_A_CPU1_SA_DQ<24>")
	)
	(segment
		(start 63.015368 -228.292406)
		(end 62.879732 -228.15677)
		(width 0.10668)
		(layer "F.Cu")
		(net "M_A_CPU1_SA_DQ<24>")
	)
	(segment
		(start 63.30061 -228.292406)
		(end 63.015368 -228.292406)
		(width 0.10668)
		(layer "F.Cu")
		(net "M_A_CPU1_SA_DQ<24>")
	)
	(segment
		(start 75.971146 -240.465864)
		(end 73.503282 -240.465864)
		(width 0.10668)
		(layer "F.Cu")
		(net "M_A_CPU1_SA_DQ<24>")
	)
	(segment
		(start 76.397866 -240.318544)
		(end 76.250546 -240.465864)
		(width 0.0762)
		(layer "F.Cu")
		(net "M_A_CPU1_SA_DQ<24>")
	)
	(segment
		(start 61.894974 -226.16922)
		(end 60.892182 -226.16922)
		(width 0.10668)
		(layer "F.Cu")
		(net "M_A_CPU1_SA_DQ<24>")
	)
	(segment
		(start 62.033404 -227.159566)
		(end 61.882528 -227.159566)
		(width 0.10668)
		(layer "F.Cu")
		(net "M_A_CPU1_SA_DQ<24>")
	)
	(segment
		(start 61.75121 -226.877626)
		(end 62.177168 -226.451668)
		(width 0.10668)
		(layer "F.Cu")
		(net "M_A_CPU1_SA_DQ<24>")
	)
	(segment
		(start 63.02375 -227.297996)
		(end 62.597792 -227.723954)
		(width 0.10668)
		(layer "F.Cu")
		(net "M_A_CPU1_SA_DQ<24>")
	)
	(segment
		(start 60.892182 -226.16922)
		(end 60.108338 -225.385376)
		(width 0.10668)
		(layer "F.Cu")
		(net "M_A_CPU1_SA_DQ<24>")
	)
	(segment
		(start 62.879986 -228.006402)
		(end 63.305944 -227.580444)
		(width 0.10668)
		(layer "F.Cu")
		(net "M_A_CPU1_SA_DQ<24>")
	)
	(segment
		(start 60.108338 -225.385376)
		(end 59.428126 -225.385376)
		(width 0.10668)
		(layer "F.Cu")
		(net "M_A_CPU1_SA_DQ<24>")
	)
	(segment
		(start 62.315344 -227.592382)
		(end 62.315598 -227.442014)
		(width 0.10668)
		(layer "F.Cu")
		(net "M_A_CPU1_SA_DQ<24>")
	)
	(segment
		(start 63.45555 -228.447346)
		(end 63.30061 -228.292406)
		(width 0.10668)
		(layer "F.Cu")
		(net "M_A_CPU1_SA_DQ<24>")
	)
	(segment
		(start 62.04585 -226.169474)
		(end 61.894974 -226.16922)
		(width 0.10668)
		(layer "F.Cu")
		(net "M_A_CPU1_SA_DQ<24>")
	)
	(arc
		(start 77.89037 -240.138458)
		(mid 77.768514 -240.162614)
		(end 77.654912 -240.21288)
		(width 0.0762)
		(layer "F.Cu")
		(net "M_A_CPU1_SA_DQ<24>")
	)
	(arc
		(start 78.408022 -239.8903)
		(mid 78.171894 -240.061735)
		(end 77.89037 -240.138458)
		(width 0.0762)
		(layer "F.Cu")
		(net "M_A_CPU1_SA_DQ<24>")
	)
	(arc
		(start 77.654912 -240.21288)
		(mid 77.465548 -240.291634)
		(end 77.262228 -240.318544)
		(width 0.0762)
		(layer "F.Cu")
		(net "M_A_CPU1_SA_DQ<24>")
	)
	(segment
		(start 61.340238 -224.780094)
		(end 61.189362 -224.780094)
		(width 0.10668)
		(layer "F.Cu")
		(net "M_A_CPU1_SA_DQ<23>")
	)
	(segment
		(start 61.157612 -225.376232)
		(end 61.471556 -225.062288)
		(width 0.10668)
		(layer "F.Cu")
		(net "M_A_CPU1_SA_DQ<23>")
	)
	(segment
		(start 60.593224 -224.811844)
		(end 60.907168 -224.4979)
		(width 0.10668)
		(layer "F.Cu")
		(net "M_A_CPU1_SA_DQ<23>")
	)
	(segment
		(start 60.593224 -224.96272)
		(end 60.593224 -224.811844)
		(width 0.10668)
		(layer "F.Cu")
		(net "M_A_CPU1_SA_DQ<23>")
	)
	(segment
		(start 61.439806 -225.658426)
		(end 61.28893 -225.658426)
		(width 0.10668)
		(layer "F.Cu")
		(net "M_A_CPU1_SA_DQ<23>")
	)
	(segment
		(start 73.692766 -240.008664)
		(end 63.91275 -230.228648)
		(width 0.10668)
		(layer "F.Cu")
		(net "M_A_CPU1_SA_DQ<23>")
	)
	(segment
		(start 61.28893 -225.658426)
		(end 61.157612 -225.527108)
		(width 0.10668)
		(layer "F.Cu")
		(net "M_A_CPU1_SA_DQ<23>")
	)
	(segment
		(start 60.875418 -225.094038)
		(end 60.724542 -225.094038)
		(width 0.10668)
		(layer "F.Cu")
		(net "M_A_CPU1_SA_DQ<23>")
	)
	(segment
		(start 61.471556 -225.062288)
		(end 61.471556 -224.911412)
		(width 0.10668)
		(layer "F.Cu")
		(net "M_A_CPU1_SA_DQ<23>")
	)
	(segment
		(start 61.189362 -224.780094)
		(end 60.875418 -225.094038)
		(width 0.10668)
		(layer "F.Cu")
		(net "M_A_CPU1_SA_DQ<23>")
	)
	(segment
		(start 75.966066 -240.008664)
		(end 73.692766 -240.008664)
		(width 0.10668)
		(layer "F.Cu")
		(net "M_A_CPU1_SA_DQ<23>")
	)
	(segment
		(start 63.91275 -227.352606)
		(end 61.904626 -225.344482)
		(width 0.10668)
		(layer "F.Cu")
		(net "M_A_CPU1_SA_DQ<23>")
	)
	(segment
		(start 61.904626 -225.344482)
		(end 61.75375 -225.344482)
		(width 0.10668)
		(layer "F.Cu")
		(net "M_A_CPU1_SA_DQ<23>")
	)
	(segment
		(start 76.191364 -240.008664)
		(end 75.966066 -240.008664)
		(width 0.0762)
		(layer "F.Cu")
		(net "M_A_CPU1_SA_DQ<23>")
	)
	(segment
		(start 60.907168 -224.347024)
		(end 60.67044 -224.110296)
		(width 0.10668)
		(layer "F.Cu")
		(net "M_A_CPU1_SA_DQ<23>")
	)
	(segment
		(start 61.157612 -225.527108)
		(end 61.157612 -225.376232)
		(width 0.10668)
		(layer "F.Cu")
		(net "M_A_CPU1_SA_DQ<23>")
	)
	(segment
		(start 61.471556 -224.911412)
		(end 61.340238 -224.780094)
		(width 0.10668)
		(layer "F.Cu")
		(net "M_A_CPU1_SA_DQ<23>")
	)
	(segment
		(start 79.347822 -239.8903)
		(end 79.347822 -239.890046)
		(width 0.0762)
		(layer "F.Cu")
		(net "M_A_CPU1_SA_DQ<23>")
	)
	(segment
		(start 77.443838 -239.510824)
		(end 76.689204 -239.510824)
		(width 0.0762)
		(layer "F.Cu")
		(net "M_A_CPU1_SA_DQ<23>")
	)
	(segment
		(start 60.724542 -225.094038)
		(end 60.593224 -224.96272)
		(width 0.10668)
		(layer "F.Cu")
		(net "M_A_CPU1_SA_DQ<23>")
	)
	(segment
		(start 58.13044 -224.110296)
		(end 57.705498 -224.535238)
		(width 0.101346)
		(layer "F.Cu")
		(net "M_A_CPU1_SA_DQ<23>")
	)
	(segment
		(start 63.91275 -230.228648)
		(end 63.91275 -227.352606)
		(width 0.10668)
		(layer "F.Cu")
		(net "M_A_CPU1_SA_DQ<23>")
	)
	(segment
		(start 79.168244 -239.563402)
		(end 79.160878 -239.56772)
		(width 0.0762)
		(layer "F.Cu")
		(net "M_A_CPU1_SA_DQ<23>")
	)
	(segment
		(start 79.16926 -239.562894)
		(end 79.168244 -239.563402)
		(width 0.0762)
		(layer "F.Cu")
		(net "M_A_CPU1_SA_DQ<23>")
	)
	(segment
		(start 78.594966 -239.56772)
		(end 78.586584 -239.562894)
		(width 0.0762)
		(layer "F.Cu")
		(net "M_A_CPU1_SA_DQ<23>")
	)
	(segment
		(start 76.689204 -239.510824)
		(end 76.191364 -240.008664)
		(width 0.0762)
		(layer "F.Cu")
		(net "M_A_CPU1_SA_DQ<23>")
	)
	(segment
		(start 57.705498 -224.535238)
		(end 55.328058 -224.535238)
		(width 0.101346)
		(layer "F.Cu")
		(net "M_A_CPU1_SA_DQ<23>")
	)
	(segment
		(start 61.75375 -225.344482)
		(end 61.439806 -225.658426)
		(width 0.10668)
		(layer "F.Cu")
		(net "M_A_CPU1_SA_DQ<23>")
	)
	(segment
		(start 79.347822 -239.890046)
		(end 79.452978 -239.709198)
		(width 0.0762)
		(layer "F.Cu")
		(net "M_A_CPU1_SA_DQ<23>")
	)
	(segment
		(start 60.67044 -224.110296)
		(end 58.13044 -224.110296)
		(width 0.101346)
		(layer "F.Cu")
		(net "M_A_CPU1_SA_DQ<23>")
	)
	(segment
		(start 60.907168 -224.4979)
		(end 60.907168 -224.347024)
		(width 0.10668)
		(layer "F.Cu")
		(net "M_A_CPU1_SA_DQ<23>")
	)
	(arc
		(start 79.160878 -239.56772)
		(mid 78.877922 -239.643897)
		(end 78.594966 -239.56772)
		(width 0.0762)
		(layer "F.Cu")
		(net "M_A_CPU1_SA_DQ<23>")
	)
	(arc
		(start 78.220824 -239.56772)
		(mid 77.937868 -239.643897)
		(end 77.654912 -239.56772)
		(width 0.0762)
		(layer "F.Cu")
		(net "M_A_CPU1_SA_DQ<23>")
	)
	(arc
		(start 79.349346 -239.517428)
		(mid 79.256422 -239.528751)
		(end 79.16926 -239.562894)
		(width 0.0762)
		(layer "F.Cu")
		(net "M_A_CPU1_SA_DQ<23>")
	)
	(arc
		(start 79.452978 -239.709198)
		(mid 79.444041 -239.590174)
		(end 79.349346 -239.517428)
		(width 0.0762)
		(layer "F.Cu")
		(net "M_A_CPU1_SA_DQ<23>")
	)
	(arc
		(start 78.586584 -239.562894)
		(mid 78.403076 -239.5174)
		(end 78.220824 -239.56772)
		(width 0.0762)
		(layer "F.Cu")
		(net "M_A_CPU1_SA_DQ<23>")
	)
	(arc
		(start 77.654912 -239.56772)
		(mid 77.553144 -239.525286)
		(end 77.443838 -239.510824)
		(width 0.0762)
		(layer "F.Cu")
		(net "M_A_CPU1_SA_DQ<23>")
	)
	(segment
		(start 56.774334 -223.435926)
		(end 56.583326 -223.435926)
		(width 0.101346)
		(layer "F.Cu")
		(net "M_A_CPU1_SA_DQ<22>")
	)
	(segment
		(start 58.053732 -222.835216)
		(end 57.764426 -222.835216)
		(width 0.101346)
		(layer "F.Cu")
		(net "M_A_CPU1_SA_DQ<22>")
	)
	(segment
		(start 56.48198 -222.936562)
		(end 56.380634 -222.835216)
		(width 0.101346)
		(layer "F.Cu")
		(net "M_A_CPU1_SA_DQ<22>")
	)
	(segment
		(start 61.019944 -223.143572)
		(end 60.903104 -223.260412)
		(width 0.10668)
		(layer "F.Cu")
		(net "M_A_CPU1_SA_DQ<22>")
	)
	(segment
		(start 58.478928 -223.260412)
		(end 58.053732 -222.835216)
		(width 0.101346)
		(layer "F.Cu")
		(net "M_A_CPU1_SA_DQ<22>")
	)
	(segment
		(start 57.561734 -223.435926)
		(end 57.370726 -223.435926)
		(width 0.101346)
		(layer "F.Cu")
		(net "M_A_CPU1_SA_DQ<22>")
	)
	(segment
		(start 60.67044 -223.260412)
		(end 58.478928 -223.260412)
		(width 0.101346)
		(layer "F.Cu")
		(net "M_A_CPU1_SA_DQ<22>")
	)
	(segment
		(start 61.418978 -223.143572)
		(end 61.418978 -222.914464)
		(width 0.10668)
		(layer "F.Cu")
		(net "M_A_CPU1_SA_DQ<22>")
	)
	(segment
		(start 56.87568 -223.33458)
		(end 56.774334 -223.435926)
		(width 0.101346)
		(layer "F.Cu")
		(net "M_A_CPU1_SA_DQ<22>")
	)
	(segment
		(start 76.471526 -238.936784)
		(end 76.082906 -239.325404)
		(width 0.0762)
		(layer "F.Cu")
		(net "M_A_CPU1_SA_DQ<22>")
	)
	(segment
		(start 75.968606 -239.325404)
		(end 73.972674 -239.325404)
		(width 0.10668)
		(layer "F.Cu")
		(net "M_A_CPU1_SA_DQ<22>")
	)
	(segment
		(start 57.370726 -223.435926)
		(end 57.26938 -223.33458)
		(width 0.101346)
		(layer "F.Cu")
		(net "M_A_CPU1_SA_DQ<22>")
	)
	(segment
		(start 61.833252 -223.260412)
		(end 61.535818 -223.260412)
		(width 0.10668)
		(layer "F.Cu")
		(net "M_A_CPU1_SA_DQ<22>")
	)
	(segment
		(start 57.764426 -222.835216)
		(end 57.66308 -222.936562)
		(width 0.101346)
		(layer "F.Cu")
		(net "M_A_CPU1_SA_DQ<22>")
	)
	(segment
		(start 77.098398 -238.936784)
		(end 76.471526 -238.936784)
		(width 0.0762)
		(layer "F.Cu")
		(net "M_A_CPU1_SA_DQ<22>")
	)
	(segment
		(start 61.302138 -222.797624)
		(end 61.136784 -222.797624)
		(width 0.10668)
		(layer "F.Cu")
		(net "M_A_CPU1_SA_DQ<22>")
	)
	(segment
		(start 61.136784 -222.797624)
		(end 61.019944 -222.914464)
		(width 0.10668)
		(layer "F.Cu")
		(net "M_A_CPU1_SA_DQ<22>")
	)
	(segment
		(start 73.972674 -239.325404)
		(end 64.59347 -229.9462)
		(width 0.10668)
		(layer "F.Cu")
		(net "M_A_CPU1_SA_DQ<22>")
	)
	(segment
		(start 61.418978 -222.914464)
		(end 61.302138 -222.797624)
		(width 0.10668)
		(layer "F.Cu")
		(net "M_A_CPU1_SA_DQ<22>")
	)
	(segment
		(start 56.583326 -223.435926)
		(end 56.48198 -223.33458)
		(width 0.101346)
		(layer "F.Cu")
		(net "M_A_CPU1_SA_DQ<22>")
	)
	(segment
		(start 57.26938 -223.33458)
		(end 57.26938 -222.936562)
		(width 0.101346)
		(layer "F.Cu")
		(net "M_A_CPU1_SA_DQ<22>")
	)
	(segment
		(start 57.168034 -222.835216)
		(end 56.977026 -222.835216)
		(width 0.101346)
		(layer "F.Cu")
		(net "M_A_CPU1_SA_DQ<22>")
	)
	(segment
		(start 60.903104 -223.260412)
		(end 60.67044 -223.260412)
		(width 0.10668)
		(layer "F.Cu")
		(net "M_A_CPU1_SA_DQ<22>")
	)
	(segment
		(start 56.380634 -222.835216)
		(end 55.328058 -222.835216)
		(width 0.101346)
		(layer "F.Cu")
		(net "M_A_CPU1_SA_DQ<22>")
	)
	(segment
		(start 64.59347 -226.02063)
		(end 61.833252 -223.260412)
		(width 0.10668)
		(layer "F.Cu")
		(net "M_A_CPU1_SA_DQ<22>")
	)
	(segment
		(start 56.977026 -222.835216)
		(end 56.87568 -222.936562)
		(width 0.101346)
		(layer "F.Cu")
		(net "M_A_CPU1_SA_DQ<22>")
	)
	(segment
		(start 64.59347 -229.9462)
		(end 64.59347 -226.02063)
		(width 0.10668)
		(layer "F.Cu")
		(net "M_A_CPU1_SA_DQ<22>")
	)
	(segment
		(start 61.535818 -223.260412)
		(end 61.418978 -223.143572)
		(width 0.10668)
		(layer "F.Cu")
		(net "M_A_CPU1_SA_DQ<22>")
	)
	(segment
		(start 56.87568 -222.936562)
		(end 56.87568 -223.33458)
		(width 0.101346)
		(layer "F.Cu")
		(net "M_A_CPU1_SA_DQ<22>")
	)
	(segment
		(start 76.082906 -239.325404)
		(end 75.968606 -239.325404)
		(width 0.0762)
		(layer "F.Cu")
		(net "M_A_CPU1_SA_DQ<22>")
	)
	(segment
		(start 61.019944 -222.914464)
		(end 61.019944 -223.143572)
		(width 0.10668)
		(layer "F.Cu")
		(net "M_A_CPU1_SA_DQ<22>")
	)
	(segment
		(start 57.66308 -223.33458)
		(end 57.561734 -223.435926)
		(width 0.101346)
		(layer "F.Cu")
		(net "M_A_CPU1_SA_DQ<22>")
	)
	(segment
		(start 57.26938 -222.936562)
		(end 57.168034 -222.835216)
		(width 0.101346)
		(layer "F.Cu")
		(net "M_A_CPU1_SA_DQ<22>")
	)
	(segment
		(start 77.937868 -239.080294)
		(end 78.030832 -238.920274)
		(width 0.0762)
		(layer "F.Cu")
		(net "M_A_CPU1_SA_DQ<22>")
	)
	(segment
		(start 57.66308 -222.936562)
		(end 57.66308 -223.33458)
		(width 0.101346)
		(layer "F.Cu")
		(net "M_A_CPU1_SA_DQ<22>")
	)
	(segment
		(start 56.48198 -223.33458)
		(end 56.48198 -222.936562)
		(width 0.101346)
		(layer "F.Cu")
		(net "M_A_CPU1_SA_DQ<22>")
	)
	(arc
		(start 77.759306 -238.752888)
		(mid 77.441409 -238.889972)
		(end 77.098398 -238.936784)
		(width 0.0762)
		(layer "F.Cu")
		(net "M_A_CPU1_SA_DQ<22>")
	)
	(arc
		(start 77.899006 -238.709454)
		(mid 77.826998 -238.724236)
		(end 77.759306 -238.752888)
		(width 0.0762)
		(layer "F.Cu")
		(net "M_A_CPU1_SA_DQ<22>")
	)
	(arc
		(start 78.030832 -238.920274)
		(mid 78.030672 -238.773713)
		(end 77.899006 -238.709454)
		(width 0.0762)
		(layer "F.Cu")
		(net "M_A_CPU1_SA_DQ<22>")
	)
	(segment
		(start 61.80836 -223.717104)
		(end 61.657484 -223.717104)
		(width 0.10668)
		(layer "F.Cu")
		(net "M_A_CPU1_SA_DQ<21>")
	)
	(segment
		(start 61.657484 -223.717104)
		(end 61.289946 -224.084642)
		(width 0.10668)
		(layer "F.Cu")
		(net "M_A_CPU1_SA_DQ<21>")
	)
	(segment
		(start 62.937136 -224.84588)
		(end 62.78626 -224.84588)
		(width 0.10668)
		(layer "F.Cu")
		(net "M_A_CPU1_SA_DQ<21>")
	)
	(segment
		(start 60.740036 -223.685354)
		(end 59.428126 -223.685354)
		(width 0.10668)
		(layer "F.Cu")
		(net "M_A_CPU1_SA_DQ<21>")
	)
	(segment
		(start 63.547498 -226.342194)
		(end 63.39713 -226.342448)
		(width 0.10668)
		(layer "F.Cu")
		(net "M_A_CPU1_SA_DQ<21>")
	)
	(segment
		(start 63.632842 -225.541586)
		(end 63.501524 -225.410268)
		(width 0.10668)
		(layer "F.Cu")
		(net "M_A_CPU1_SA_DQ<21>")
	)
	(segment
		(start 64.25311 -227.198428)
		(end 63.829946 -226.775264)
		(width 0.10668)
		(layer "F.Cu")
		(net "M_A_CPU1_SA_DQ<21>")
	)
	(segment
		(start 62.221872 -224.281492)
		(end 61.854334 -224.64903)
		(width 0.10668)
		(layer "F.Cu")
		(net "M_A_CPU1_SA_DQ<21>")
	)
	(segment
		(start 61.572394 -224.517712)
		(end 61.572394 -224.366836)
		(width 0.10668)
		(layer "F.Cu")
		(net "M_A_CPU1_SA_DQ<21>")
	)
	(segment
		(start 62.50432 -224.563686)
		(end 62.504066 -224.41281)
		(width 0.10668)
		(layer "F.Cu")
		(net "M_A_CPU1_SA_DQ<21>")
	)
	(segment
		(start 62.136782 -225.0821)
		(end 62.136782 -224.931224)
		(width 0.10668)
		(layer "F.Cu")
		(net "M_A_CPU1_SA_DQ<21>")
	)
	(segment
		(start 77.759306 -239.4077)
		(end 77.750924 -239.402874)
		(width 0.0762)
		(layer "F.Cu")
		(net "M_A_CPU1_SA_DQ<21>")
	)
	(segment
		(start 63.265558 -226.06)
		(end 63.633096 -225.692462)
		(width 0.10668)
		(layer "F.Cu")
		(net "M_A_CPU1_SA_DQ<21>")
	)
	(segment
		(start 62.70117 -225.495612)
		(end 63.068708 -225.128074)
		(width 0.10668)
		(layer "F.Cu")
		(net "M_A_CPU1_SA_DQ<21>")
	)
	(segment
		(start 76.616306 -239.228884)
		(end 76.179426 -239.665764)
		(width 0.0762)
		(layer "F.Cu")
		(net "M_A_CPU1_SA_DQ<21>")
	)
	(segment
		(start 61.572394 -224.366836)
		(end 61.939932 -223.999298)
		(width 0.10668)
		(layer "F.Cu")
		(net "M_A_CPU1_SA_DQ<21>")
	)
	(segment
		(start 62.98311 -225.777806)
		(end 62.832742 -225.77806)
		(width 0.10668)
		(layer "F.Cu")
		(net "M_A_CPU1_SA_DQ<21>")
	)
	(segment
		(start 63.265558 -226.210876)
		(end 63.265558 -226.06)
		(width 0.10668)
		(layer "F.Cu")
		(net "M_A_CPU1_SA_DQ<21>")
	)
	(segment
		(start 63.915036 -225.974656)
		(end 63.547498 -226.342194)
		(width 0.10668)
		(layer "F.Cu")
		(net "M_A_CPU1_SA_DQ<21>")
	)
	(segment
		(start 63.350648 -225.410268)
		(end 62.98311 -225.777806)
		(width 0.10668)
		(layer "F.Cu")
		(net "M_A_CPU1_SA_DQ<21>")
	)
	(segment
		(start 61.289946 -224.084642)
		(end 61.139578 -224.084896)
		(width 0.10668)
		(layer "F.Cu")
		(net "M_A_CPU1_SA_DQ<21>")
	)
	(segment
		(start 62.70117 -225.646488)
		(end 62.70117 -225.495612)
		(width 0.10668)
		(layer "F.Cu")
		(net "M_A_CPU1_SA_DQ<21>")
	)
	(segment
		(start 63.068708 -225.128074)
		(end 63.068454 -224.977198)
		(width 0.10668)
		(layer "F.Cu")
		(net "M_A_CPU1_SA_DQ<21>")
	)
	(segment
		(start 62.418722 -225.213418)
		(end 62.268354 -225.213672)
		(width 0.10668)
		(layer "F.Cu")
		(net "M_A_CPU1_SA_DQ<21>")
	)
	(segment
		(start 64.065912 -225.974656)
		(end 63.915036 -225.974656)
		(width 0.10668)
		(layer "F.Cu")
		(net "M_A_CPU1_SA_DQ<21>")
	)
	(segment
		(start 61.939678 -223.848422)
		(end 61.80836 -223.717104)
		(width 0.10668)
		(layer "F.Cu")
		(net "M_A_CPU1_SA_DQ<21>")
	)
	(segment
		(start 62.268354 -225.213672)
		(end 62.136782 -225.0821)
		(width 0.10668)
		(layer "F.Cu")
		(net "M_A_CPU1_SA_DQ<21>")
	)
	(segment
		(start 61.854334 -224.64903)
		(end 61.703966 -224.649284)
		(width 0.10668)
		(layer "F.Cu")
		(net "M_A_CPU1_SA_DQ<21>")
	)
	(segment
		(start 64.19723 -226.105974)
		(end 64.065912 -225.974656)
		(width 0.10668)
		(layer "F.Cu")
		(net "M_A_CPU1_SA_DQ<21>")
	)
	(segment
		(start 61.139578 -224.084896)
		(end 60.740036 -223.685354)
		(width 0.10668)
		(layer "F.Cu")
		(net "M_A_CPU1_SA_DQ<21>")
	)
	(segment
		(start 63.068454 -224.977198)
		(end 62.937136 -224.84588)
		(width 0.10668)
		(layer "F.Cu")
		(net "M_A_CPU1_SA_DQ<21>")
	)
	(segment
		(start 63.39713 -226.342448)
		(end 63.265558 -226.210876)
		(width 0.10668)
		(layer "F.Cu")
		(net "M_A_CPU1_SA_DQ<21>")
	)
	(segment
		(start 73.83145 -239.665764)
		(end 64.25311 -230.087424)
		(width 0.10668)
		(layer "F.Cu")
		(net "M_A_CPU1_SA_DQ<21>")
	)
	(segment
		(start 62.504066 -224.41281)
		(end 62.372748 -224.281492)
		(width 0.10668)
		(layer "F.Cu")
		(net "M_A_CPU1_SA_DQ<21>")
	)
	(segment
		(start 63.829946 -226.624388)
		(end 64.197484 -226.25685)
		(width 0.10668)
		(layer "F.Cu")
		(net "M_A_CPU1_SA_DQ<21>")
	)
	(segment
		(start 61.703966 -224.649284)
		(end 61.572394 -224.517712)
		(width 0.10668)
		(layer "F.Cu")
		(net "M_A_CPU1_SA_DQ<21>")
	)
	(segment
		(start 63.829946 -226.775264)
		(end 63.829946 -226.624388)
		(width 0.10668)
		(layer "F.Cu")
		(net "M_A_CPU1_SA_DQ<21>")
	)
	(segment
		(start 63.633096 -225.692462)
		(end 63.632842 -225.541586)
		(width 0.10668)
		(layer "F.Cu")
		(net "M_A_CPU1_SA_DQ<21>")
	)
	(segment
		(start 62.136782 -224.931224)
		(end 62.50432 -224.563686)
		(width 0.10668)
		(layer "F.Cu")
		(net "M_A_CPU1_SA_DQ<21>")
	)
	(segment
		(start 64.25311 -230.087424)
		(end 64.25311 -227.198428)
		(width 0.10668)
		(layer "F.Cu")
		(net "M_A_CPU1_SA_DQ<21>")
	)
	(segment
		(start 62.372748 -224.281492)
		(end 62.221872 -224.281492)
		(width 0.10668)
		(layer "F.Cu")
		(net "M_A_CPU1_SA_DQ<21>")
	)
	(segment
		(start 79.064866 -239.40262)
		(end 79.064866 -239.402874)
		(width 0.0762)
		(layer "F.Cu")
		(net "M_A_CPU1_SA_DQ<21>")
	)
	(segment
		(start 64.197484 -226.25685)
		(end 64.19723 -226.105974)
		(width 0.10668)
		(layer "F.Cu")
		(net "M_A_CPU1_SA_DQ<21>")
	)
	(segment
		(start 62.832742 -225.77806)
		(end 62.70117 -225.646488)
		(width 0.10668)
		(layer "F.Cu")
		(net "M_A_CPU1_SA_DQ<21>")
	)
	(segment
		(start 61.939932 -223.999298)
		(end 61.939678 -223.848422)
		(width 0.10668)
		(layer "F.Cu")
		(net "M_A_CPU1_SA_DQ<21>")
	)
	(segment
		(start 75.976226 -239.665764)
		(end 73.83145 -239.665764)
		(width 0.10668)
		(layer "F.Cu")
		(net "M_A_CPU1_SA_DQ<21>")
	)
	(segment
		(start 76.179426 -239.665764)
		(end 75.976226 -239.665764)
		(width 0.0762)
		(layer "F.Cu")
		(net "M_A_CPU1_SA_DQ<21>")
	)
	(segment
		(start 63.501524 -225.410268)
		(end 63.350648 -225.410268)
		(width 0.10668)
		(layer "F.Cu")
		(net "M_A_CPU1_SA_DQ<21>")
	)
	(segment
		(start 77.104748 -239.228884)
		(end 76.616306 -239.228884)
		(width 0.0762)
		(layer "F.Cu")
		(net "M_A_CPU1_SA_DQ<21>")
	)
	(segment
		(start 62.78626 -224.84588)
		(end 62.418722 -225.213418)
		(width 0.10668)
		(layer "F.Cu")
		(net "M_A_CPU1_SA_DQ<21>")
	)
	(arc
		(start 78.125066 -239.402874)
		(mid 77.942815 -239.453224)
		(end 77.759306 -239.4077)
		(width 0.0762)
		(layer "F.Cu")
		(net "M_A_CPU1_SA_DQ<21>")
	)
	(arc
		(start 79.064866 -239.402874)
		(mid 78.877922 -239.453129)
		(end 78.690978 -239.402874)
		(width 0.0762)
		(layer "F.Cu")
		(net "M_A_CPU1_SA_DQ<21>")
	)
	(arc
		(start 79.817976 -239.080294)
		(mid 79.61396 -239.260988)
		(end 79.349346 -239.326166)
		(width 0.0762)
		(layer "F.Cu")
		(net "M_A_CPU1_SA_DQ<21>")
	)
	(arc
		(start 78.690978 -239.402874)
		(mid 78.408022 -239.326697)
		(end 78.125066 -239.402874)
		(width 0.0762)
		(layer "F.Cu")
		(net "M_A_CPU1_SA_DQ<21>")
	)
	(arc
		(start 79.349346 -239.326166)
		(mid 79.202025 -239.345485)
		(end 79.064866 -239.40262)
		(width 0.0762)
		(layer "F.Cu")
		(net "M_A_CPU1_SA_DQ<21>")
	)
	(arc
		(start 77.750924 -239.402874)
		(mid 77.43935 -239.273104)
		(end 77.104748 -239.228884)
		(width 0.0762)
		(layer "F.Cu")
		(net "M_A_CPU1_SA_DQ<21>")
	)
	(segment
		(start 62.2681 -223.0628)
		(end 62.599824 -222.731076)
		(width 0.10668)
		(layer "F.Cu")
		(net "M_A_CPU1_SA_DQ<20>")
	)
	(segment
		(start 63.961264 -224.755964)
		(end 64.292988 -224.42424)
		(width 0.10668)
		(layer "F.Cu")
		(net "M_A_CPU1_SA_DQ<20>")
	)
	(segment
		(start 63.032894 -223.01327)
		(end 62.882018 -223.01327)
		(width 0.10668)
		(layer "F.Cu")
		(net "M_A_CPU1_SA_DQ<20>")
	)
	(segment
		(start 62.599824 -222.5802)
		(end 62.468506 -222.448882)
		(width 0.10668)
		(layer "F.Cu")
		(net "M_A_CPU1_SA_DQ<20>")
	)
	(segment
		(start 64.857376 -224.837752)
		(end 64.726058 -224.706434)
		(width 0.10668)
		(layer "F.Cu")
		(net "M_A_CPU1_SA_DQ<20>")
	)
	(segment
		(start 62.2681 -223.213676)
		(end 62.2681 -223.0628)
		(width 0.10668)
		(layer "F.Cu")
		(net "M_A_CPU1_SA_DQ<20>")
	)
	(segment
		(start 64.575182 -224.706434)
		(end 64.243458 -225.038158)
		(width 0.10668)
		(layer "F.Cu")
		(net "M_A_CPU1_SA_DQ<20>")
	)
	(segment
		(start 61.270642 -222.216218)
		(end 61.039756 -221.985332)
		(width 0.10668)
		(layer "F.Cu")
		(net "M_A_CPU1_SA_DQ<20>")
	)
	(segment
		(start 62.832488 -223.778064)
		(end 62.832488 -223.627188)
		(width 0.10668)
		(layer "F.Cu")
		(net "M_A_CPU1_SA_DQ<20>")
	)
	(segment
		(start 63.597282 -223.577658)
		(end 63.446406 -223.577658)
		(width 0.10668)
		(layer "F.Cu")
		(net "M_A_CPU1_SA_DQ<20>")
	)
	(segment
		(start 63.67907 -224.47377)
		(end 63.528194 -224.47377)
		(width 0.10668)
		(layer "F.Cu")
		(net "M_A_CPU1_SA_DQ<20>")
	)
	(segment
		(start 62.035436 -222.015812)
		(end 61.904118 -221.884494)
		(width 0.10668)
		(layer "F.Cu")
		(net "M_A_CPU1_SA_DQ<20>")
	)
	(segment
		(start 64.857376 -224.988628)
		(end 64.857376 -224.837752)
		(width 0.10668)
		(layer "F.Cu")
		(net "M_A_CPU1_SA_DQ<20>")
	)
	(segment
		(start 64.93383 -229.804976)
		(end 64.93383 -225.879406)
		(width 0.10668)
		(layer "F.Cu")
		(net "M_A_CPU1_SA_DQ<20>")
	)
	(segment
		(start 64.525652 -225.320352)
		(end 64.857376 -224.988628)
		(width 0.10668)
		(layer "F.Cu")
		(net "M_A_CPU1_SA_DQ<20>")
	)
	(segment
		(start 61.83503 -222.780606)
		(end 61.703712 -222.649288)
		(width 0.10668)
		(layer "F.Cu")
		(net "M_A_CPU1_SA_DQ<20>")
	)
	(segment
		(start 62.832488 -223.627188)
		(end 63.164212 -223.295464)
		(width 0.10668)
		(layer "F.Cu")
		(net "M_A_CPU1_SA_DQ<20>")
	)
	(segment
		(start 63.961264 -224.90684)
		(end 63.961264 -224.755964)
		(width 0.10668)
		(layer "F.Cu")
		(net "M_A_CPU1_SA_DQ<20>")
	)
	(segment
		(start 62.550294 -223.344994)
		(end 62.399418 -223.344994)
		(width 0.10668)
		(layer "F.Cu")
		(net "M_A_CPU1_SA_DQ<20>")
	)
	(segment
		(start 61.421518 -222.216218)
		(end 61.270642 -222.216218)
		(width 0.10668)
		(layer "F.Cu")
		(net "M_A_CPU1_SA_DQ<20>")
	)
	(segment
		(start 64.16167 -224.142046)
		(end 64.010794 -224.142046)
		(width 0.10668)
		(layer "F.Cu")
		(net "M_A_CPU1_SA_DQ<20>")
	)
	(segment
		(start 64.243458 -225.038158)
		(end 64.092582 -225.038158)
		(width 0.10668)
		(layer "F.Cu")
		(net "M_A_CPU1_SA_DQ<20>")
	)
	(segment
		(start 62.468506 -222.448882)
		(end 62.31763 -222.448882)
		(width 0.10668)
		(layer "F.Cu")
		(net "M_A_CPU1_SA_DQ<20>")
	)
	(segment
		(start 63.114682 -223.909382)
		(end 62.963806 -223.909382)
		(width 0.10668)
		(layer "F.Cu")
		(net "M_A_CPU1_SA_DQ<20>")
	)
	(segment
		(start 61.753242 -221.884494)
		(end 61.421518 -222.216218)
		(width 0.10668)
		(layer "F.Cu")
		(net "M_A_CPU1_SA_DQ<20>")
	)
	(segment
		(start 62.035436 -222.166688)
		(end 62.035436 -222.015812)
		(width 0.10668)
		(layer "F.Cu")
		(net "M_A_CPU1_SA_DQ<20>")
	)
	(segment
		(start 62.599824 -222.731076)
		(end 62.599824 -222.5802)
		(width 0.10668)
		(layer "F.Cu")
		(net "M_A_CPU1_SA_DQ<20>")
	)
	(segment
		(start 75.930506 -238.964724)
		(end 74.093578 -238.964724)
		(width 0.10668)
		(layer "F.Cu")
		(net "M_A_CPU1_SA_DQ<20>")
	)
	(segment
		(start 61.703712 -222.498412)
		(end 62.035436 -222.166688)
		(width 0.10668)
		(layer "F.Cu")
		(net "M_A_CPU1_SA_DQ<20>")
	)
	(segment
		(start 63.528194 -224.47377)
		(end 63.396876 -224.342452)
		(width 0.10668)
		(layer "F.Cu")
		(net "M_A_CPU1_SA_DQ<20>")
	)
	(segment
		(start 61.039756 -221.985332)
		(end 59.428126 -221.985332)
		(width 0.10668)
		(layer "F.Cu")
		(net "M_A_CPU1_SA_DQ<20>")
	)
	(segment
		(start 61.904118 -221.884494)
		(end 61.753242 -221.884494)
		(width 0.10668)
		(layer "F.Cu")
		(net "M_A_CPU1_SA_DQ<20>")
	)
	(segment
		(start 64.292988 -224.273364)
		(end 64.16167 -224.142046)
		(width 0.10668)
		(layer "F.Cu")
		(net "M_A_CPU1_SA_DQ<20>")
	)
	(segment
		(start 64.092582 -225.038158)
		(end 63.961264 -224.90684)
		(width 0.10668)
		(layer "F.Cu")
		(net "M_A_CPU1_SA_DQ<20>")
	)
	(segment
		(start 61.985906 -222.780606)
		(end 61.83503 -222.780606)
		(width 0.10668)
		(layer "F.Cu")
		(net "M_A_CPU1_SA_DQ<20>")
	)
	(segment
		(start 62.399418 -223.344994)
		(end 62.2681 -223.213676)
		(width 0.10668)
		(layer "F.Cu")
		(net "M_A_CPU1_SA_DQ<20>")
	)
	(segment
		(start 64.292988 -224.42424)
		(end 64.292988 -224.273364)
		(width 0.10668)
		(layer "F.Cu")
		(net "M_A_CPU1_SA_DQ<20>")
	)
	(segment
		(start 63.446406 -223.577658)
		(end 63.114682 -223.909382)
		(width 0.10668)
		(layer "F.Cu")
		(net "M_A_CPU1_SA_DQ<20>")
	)
	(segment
		(start 62.882018 -223.01327)
		(end 62.550294 -223.344994)
		(width 0.10668)
		(layer "F.Cu")
		(net "M_A_CPU1_SA_DQ<20>")
	)
	(segment
		(start 63.7286 -223.708976)
		(end 63.597282 -223.577658)
		(width 0.10668)
		(layer "F.Cu")
		(net "M_A_CPU1_SA_DQ<20>")
	)
	(segment
		(start 76.242926 -238.652304)
		(end 75.930506 -238.964724)
		(width 0.0762)
		(layer "F.Cu")
		(net "M_A_CPU1_SA_DQ<20>")
	)
	(segment
		(start 63.396876 -224.342452)
		(end 63.396876 -224.191576)
		(width 0.10668)
		(layer "F.Cu")
		(net "M_A_CPU1_SA_DQ<20>")
	)
	(segment
		(start 64.93383 -225.879406)
		(end 64.525652 -225.471228)
		(width 0.10668)
		(layer "F.Cu")
		(net "M_A_CPU1_SA_DQ<20>")
	)
	(segment
		(start 63.164212 -223.144588)
		(end 63.032894 -223.01327)
		(width 0.10668)
		(layer "F.Cu")
		(net "M_A_CPU1_SA_DQ<20>")
	)
	(segment
		(start 64.010794 -224.142046)
		(end 63.67907 -224.47377)
		(width 0.10668)
		(layer "F.Cu")
		(net "M_A_CPU1_SA_DQ<20>")
	)
	(segment
		(start 61.703712 -222.649288)
		(end 61.703712 -222.498412)
		(width 0.10668)
		(layer "F.Cu")
		(net "M_A_CPU1_SA_DQ<20>")
	)
	(segment
		(start 74.093578 -238.964724)
		(end 64.93383 -229.804976)
		(width 0.10668)
		(layer "F.Cu")
		(net "M_A_CPU1_SA_DQ<20>")
	)
	(segment
		(start 63.7286 -223.859852)
		(end 63.7286 -223.708976)
		(width 0.10668)
		(layer "F.Cu")
		(net "M_A_CPU1_SA_DQ<20>")
	)
	(segment
		(start 63.164212 -223.295464)
		(end 63.164212 -223.144588)
		(width 0.10668)
		(layer "F.Cu")
		(net "M_A_CPU1_SA_DQ<20>")
	)
	(segment
		(start 64.525652 -225.471228)
		(end 64.525652 -225.320352)
		(width 0.10668)
		(layer "F.Cu")
		(net "M_A_CPU1_SA_DQ<20>")
	)
	(segment
		(start 77.433932 -238.652304)
		(end 76.242926 -238.652304)
		(width 0.0762)
		(layer "F.Cu")
		(net "M_A_CPU1_SA_DQ<20>")
	)
	(segment
		(start 63.396876 -224.191576)
		(end 63.7286 -223.859852)
		(width 0.10668)
		(layer "F.Cu")
		(net "M_A_CPU1_SA_DQ<20>")
	)
	(segment
		(start 64.726058 -224.706434)
		(end 64.575182 -224.706434)
		(width 0.10668)
		(layer "F.Cu")
		(net "M_A_CPU1_SA_DQ<20>")
	)
	(segment
		(start 62.31763 -222.448882)
		(end 61.985906 -222.780606)
		(width 0.10668)
		(layer "F.Cu")
		(net "M_A_CPU1_SA_DQ<20>")
	)
	(segment
		(start 62.963806 -223.909382)
		(end 62.832488 -223.778064)
		(width 0.10668)
		(layer "F.Cu")
		(net "M_A_CPU1_SA_DQ<20>")
	)
	(arc
		(start 78.408022 -238.270288)
		(mid 78.171894 -238.441723)
		(end 77.89037 -238.518446)
		(width 0.0762)
		(layer "F.Cu")
		(net "M_A_CPU1_SA_DQ<20>")
	)
	(arc
		(start 77.654912 -238.592868)
		(mid 77.54835 -238.637193)
		(end 77.433932 -238.652304)
		(width 0.0762)
		(layer "F.Cu")
		(net "M_A_CPU1_SA_DQ<20>")
	)
	(arc
		(start 77.89037 -238.518446)
		(mid 77.768514 -238.542602)
		(end 77.654912 -238.592868)
		(width 0.0762)
		(layer "F.Cu")
		(net "M_A_CPU1_SA_DQ<20>")
	)
	(segment
		(start 64.006984 -202.076812)
		(end 63.875666 -201.945494)
		(width 0.10668)
		(layer "F.Cu")
		(net "M_A_CPU1_SA_DQ<1>")
	)
	(segment
		(start 61.653674 -200.065894)
		(end 61.749432 -199.970136)
		(width 0.10668)
		(layer "F.Cu")
		(net "M_A_CPU1_SA_DQ<1>")
	)
	(segment
		(start 63.875666 -201.945494)
		(end 63.72479 -201.945494)
		(width 0.10668)
		(layer "F.Cu")
		(net "M_A_CPU1_SA_DQ<1>")
	)
	(segment
		(start 62.913768 -201.476864)
		(end 62.78245 -201.345546)
		(width 0.10668)
		(layer "F.Cu")
		(net "M_A_CPU1_SA_DQ<1>")
	)
	(segment
		(start 61.089286 -199.652382)
		(end 61.089286 -199.501506)
		(width 0.10668)
		(layer "F.Cu")
		(net "M_A_CPU1_SA_DQ<1>")
	)
	(segment
		(start 63.442596 -201.6633)
		(end 63.442596 -201.512424)
		(width 0.10668)
		(layer "F.Cu")
		(net "M_A_CPU1_SA_DQ<1>")
	)
	(segment
		(start 62.31382 -200.383648)
		(end 62.182502 -200.25233)
		(width 0.10668)
		(layer "F.Cu")
		(net "M_A_CPU1_SA_DQ<1>")
	)
	(segment
		(start 60.965588 -199.035416)
		(end 59.428126 -199.035416)
		(width 0.10668)
		(layer "F.Cu")
		(net "M_A_CPU1_SA_DQ<1>")
	)
	(segment
		(start 62.182502 -200.25233)
		(end 62.031626 -200.25233)
		(width 0.10668)
		(layer "F.Cu")
		(net "M_A_CPU1_SA_DQ<1>")
	)
	(segment
		(start 62.74689 -200.816718)
		(end 62.596014 -200.816718)
		(width 0.10668)
		(layer "F.Cu")
		(net "M_A_CPU1_SA_DQ<1>")
	)
	(segment
		(start 62.78245 -201.345546)
		(end 62.78245 -201.19467)
		(width 0.10668)
		(layer "F.Cu")
		(net "M_A_CPU1_SA_DQ<1>")
	)
	(segment
		(start 62.031626 -200.25233)
		(end 61.935868 -200.348088)
		(width 0.10668)
		(layer "F.Cu")
		(net "M_A_CPU1_SA_DQ<1>")
	)
	(segment
		(start 62.31382 -200.534524)
		(end 62.31382 -200.383648)
		(width 0.10668)
		(layer "F.Cu")
		(net "M_A_CPU1_SA_DQ<1>")
	)
	(segment
		(start 63.911226 -202.323446)
		(end 64.006984 -202.227688)
		(width 0.10668)
		(layer "F.Cu")
		(net "M_A_CPU1_SA_DQ<1>")
	)
	(segment
		(start 62.218062 -200.630282)
		(end 62.31382 -200.534524)
		(width 0.10668)
		(layer "F.Cu")
		(net "M_A_CPU1_SA_DQ<1>")
	)
	(segment
		(start 63.478156 -202.041252)
		(end 63.346838 -201.909934)
		(width 0.10668)
		(layer "F.Cu")
		(net "M_A_CPU1_SA_DQ<1>")
	)
	(segment
		(start 61.185044 -199.254872)
		(end 60.965588 -199.035416)
		(width 0.10668)
		(layer "F.Cu")
		(net "M_A_CPU1_SA_DQ<1>")
	)
	(segment
		(start 63.311278 -201.381106)
		(end 63.160402 -201.381106)
		(width 0.10668)
		(layer "F.Cu")
		(net "M_A_CPU1_SA_DQ<1>")
	)
	(segment
		(start 75.93457 -214.507318)
		(end 63.911226 -202.483974)
		(width 0.10668)
		(layer "F.Cu")
		(net "M_A_CPU1_SA_DQ<1>")
	)
	(segment
		(start 77.323696 -226.033584)
		(end 76.943966 -226.033584)
		(width 0.0762)
		(layer "F.Cu")
		(net "M_A_CPU1_SA_DQ<1>")
	)
	(segment
		(start 62.878208 -201.098912)
		(end 62.878208 -200.948036)
		(width 0.10668)
		(layer "F.Cu")
		(net "M_A_CPU1_SA_DQ<1>")
	)
	(segment
		(start 62.500256 -200.912476)
		(end 62.34938 -200.912476)
		(width 0.10668)
		(layer "F.Cu")
		(net "M_A_CPU1_SA_DQ<1>")
	)
	(segment
		(start 63.160402 -201.381106)
		(end 63.064644 -201.476864)
		(width 0.10668)
		(layer "F.Cu")
		(net "M_A_CPU1_SA_DQ<1>")
	)
	(segment
		(start 75.93457 -225.024188)
		(end 75.93457 -214.507318)
		(width 0.10668)
		(layer "F.Cu")
		(net "M_A_CPU1_SA_DQ<1>")
	)
	(segment
		(start 62.218062 -200.781158)
		(end 62.218062 -200.630282)
		(width 0.10668)
		(layer "F.Cu")
		(net "M_A_CPU1_SA_DQ<1>")
	)
	(segment
		(start 63.442596 -201.512424)
		(end 63.311278 -201.381106)
		(width 0.10668)
		(layer "F.Cu")
		(net "M_A_CPU1_SA_DQ<1>")
	)
	(segment
		(start 61.653674 -200.21677)
		(end 61.653674 -200.065894)
		(width 0.10668)
		(layer "F.Cu")
		(net "M_A_CPU1_SA_DQ<1>")
	)
	(segment
		(start 62.78245 -201.19467)
		(end 62.878208 -201.098912)
		(width 0.10668)
		(layer "F.Cu")
		(net "M_A_CPU1_SA_DQ<1>")
	)
	(segment
		(start 64.006984 -202.227688)
		(end 64.006984 -202.076812)
		(width 0.10668)
		(layer "F.Cu")
		(net "M_A_CPU1_SA_DQ<1>")
	)
	(segment
		(start 61.935868 -200.348088)
		(end 61.784992 -200.348088)
		(width 0.10668)
		(layer "F.Cu")
		(net "M_A_CPU1_SA_DQ<1>")
	)
	(segment
		(start 63.72479 -201.945494)
		(end 63.629032 -202.041252)
		(width 0.10668)
		(layer "F.Cu")
		(net "M_A_CPU1_SA_DQ<1>")
	)
	(segment
		(start 61.618114 -199.687942)
		(end 61.467238 -199.687942)
		(width 0.10668)
		(layer "F.Cu")
		(net "M_A_CPU1_SA_DQ<1>")
	)
	(segment
		(start 61.185044 -199.405748)
		(end 61.185044 -199.254872)
		(width 0.10668)
		(layer "F.Cu")
		(net "M_A_CPU1_SA_DQ<1>")
	)
	(segment
		(start 63.629032 -202.041252)
		(end 63.478156 -202.041252)
		(width 0.10668)
		(layer "F.Cu")
		(net "M_A_CPU1_SA_DQ<1>")
	)
	(segment
		(start 61.749432 -199.81926)
		(end 61.618114 -199.687942)
		(width 0.10668)
		(layer "F.Cu")
		(net "M_A_CPU1_SA_DQ<1>")
	)
	(segment
		(start 61.467238 -199.687942)
		(end 61.37148 -199.7837)
		(width 0.10668)
		(layer "F.Cu")
		(net "M_A_CPU1_SA_DQ<1>")
	)
	(segment
		(start 62.878208 -200.948036)
		(end 62.74689 -200.816718)
		(width 0.10668)
		(layer "F.Cu")
		(net "M_A_CPU1_SA_DQ<1>")
	)
	(segment
		(start 61.089286 -199.501506)
		(end 61.185044 -199.405748)
		(width 0.10668)
		(layer "F.Cu")
		(net "M_A_CPU1_SA_DQ<1>")
	)
	(segment
		(start 63.064644 -201.476864)
		(end 62.913768 -201.476864)
		(width 0.10668)
		(layer "F.Cu")
		(net "M_A_CPU1_SA_DQ<1>")
	)
	(segment
		(start 61.749432 -199.970136)
		(end 61.749432 -199.81926)
		(width 0.10668)
		(layer "F.Cu")
		(net "M_A_CPU1_SA_DQ<1>")
	)
	(segment
		(start 61.220604 -199.7837)
		(end 61.089286 -199.652382)
		(width 0.10668)
		(layer "F.Cu")
		(net "M_A_CPU1_SA_DQ<1>")
	)
	(segment
		(start 63.346838 -201.909934)
		(end 63.346838 -201.759058)
		(width 0.10668)
		(layer "F.Cu")
		(net "M_A_CPU1_SA_DQ<1>")
	)
	(segment
		(start 61.784992 -200.348088)
		(end 61.653674 -200.21677)
		(width 0.10668)
		(layer "F.Cu")
		(net "M_A_CPU1_SA_DQ<1>")
	)
	(segment
		(start 77.674216 -226.384104)
		(end 77.323696 -226.033584)
		(width 0.0762)
		(layer "F.Cu")
		(net "M_A_CPU1_SA_DQ<1>")
	)
	(segment
		(start 62.34938 -200.912476)
		(end 62.218062 -200.781158)
		(width 0.10668)
		(layer "F.Cu")
		(net "M_A_CPU1_SA_DQ<1>")
	)
	(segment
		(start 63.346838 -201.759058)
		(end 63.442596 -201.6633)
		(width 0.10668)
		(layer "F.Cu")
		(net "M_A_CPU1_SA_DQ<1>")
	)
	(segment
		(start 76.632308 -225.721926)
		(end 75.93457 -225.024188)
		(width 0.10668)
		(layer "F.Cu")
		(net "M_A_CPU1_SA_DQ<1>")
	)
	(segment
		(start 62.596014 -200.816718)
		(end 62.500256 -200.912476)
		(width 0.10668)
		(layer "F.Cu")
		(net "M_A_CPU1_SA_DQ<1>")
	)
	(segment
		(start 63.911226 -202.483974)
		(end 63.911226 -202.323446)
		(width 0.10668)
		(layer "F.Cu")
		(net "M_A_CPU1_SA_DQ<1>")
	)
	(segment
		(start 61.37148 -199.7837)
		(end 61.220604 -199.7837)
		(width 0.10668)
		(layer "F.Cu")
		(net "M_A_CPU1_SA_DQ<1>")
	)
	(segment
		(start 76.943966 -226.033584)
		(end 76.632308 -225.721926)
		(width 0.0762)
		(layer "F.Cu")
		(net "M_A_CPU1_SA_DQ<1>")
	)
	(arc
		(start 79.064866 -226.443032)
		(mid 78.877922 -226.493287)
		(end 78.690978 -226.443032)
		(width 0.0762)
		(layer "F.Cu")
		(net "M_A_CPU1_SA_DQ<1>")
	)
	(arc
		(start 78.690978 -226.443032)
		(mid 78.408022 -226.366855)
		(end 78.125066 -226.443032)
		(width 0.0762)
		(layer "F.Cu")
		(net "M_A_CPU1_SA_DQ<1>")
	)
	(arc
		(start 79.338932 -226.366832)
		(mid 79.197019 -226.387374)
		(end 79.064866 -226.443032)
		(width 0.0762)
		(layer "F.Cu")
		(net "M_A_CPU1_SA_DQ<1>")
	)
	(arc
		(start 79.817976 -226.120452)
		(mid 79.608265 -226.30159)
		(end 79.338932 -226.366832)
		(width 0.0762)
		(layer "F.Cu")
		(net "M_A_CPU1_SA_DQ<1>")
	)
	(arc
		(start 78.125066 -226.443032)
		(mid 77.889597 -226.490277)
		(end 77.674216 -226.384104)
		(width 0.0762)
		(layer "F.Cu")
		(net "M_A_CPU1_SA_DQ<1>")
	)
	(segment
		(start 76.616306 -236.272324)
		(end 76.202286 -236.686344)
		(width 0.0762)
		(layer "F.Cu")
		(net "M_A_CPU1_SA_DQ<19>")
	)
	(segment
		(start 75.935586 -236.686344)
		(end 74.530458 -236.686344)
		(width 0.10668)
		(layer "F.Cu")
		(net "M_A_CPU1_SA_DQ<19>")
	)
	(segment
		(start 79.347822 -236.650276)
		(end 79.347822 -236.650022)
		(width 0.0762)
		(layer "F.Cu")
		(net "M_A_CPU1_SA_DQ<19>")
	)
	(segment
		(start 66.82105 -222.16745)
		(end 64.552576 -219.898976)
		(width 0.10668)
		(layer "F.Cu")
		(net "M_A_CPU1_SA_DQ<19>")
	)
	(segment
		(start 57.000648 -218.585288)
		(end 55.328058 -218.585288)
		(width 0.101346)
		(layer "F.Cu")
		(net "M_A_CPU1_SA_DQ<19>")
	)
	(segment
		(start 79.16926 -236.32287)
		(end 79.168244 -236.323378)
		(width 0.0762)
		(layer "F.Cu")
		(net "M_A_CPU1_SA_DQ<19>")
	)
	(segment
		(start 57.804812 -219.010484)
		(end 57.647586 -218.853258)
		(width 0.101346)
		(layer "F.Cu")
		(net "M_A_CPU1_SA_DQ<19>")
	)
	(segment
		(start 57.647586 -218.853258)
		(end 57.000648 -218.585288)
		(width 0.101346)
		(layer "F.Cu")
		(net "M_A_CPU1_SA_DQ<19>")
	)
	(segment
		(start 77.449426 -236.272324)
		(end 76.616306 -236.272324)
		(width 0.0762)
		(layer "F.Cu")
		(net "M_A_CPU1_SA_DQ<19>")
	)
	(segment
		(start 79.168244 -236.323378)
		(end 79.160878 -236.327696)
		(width 0.0762)
		(layer "F.Cu")
		(net "M_A_CPU1_SA_DQ<19>")
	)
	(segment
		(start 66.82105 -228.976936)
		(end 66.82105 -222.16745)
		(width 0.10668)
		(layer "F.Cu")
		(net "M_A_CPU1_SA_DQ<19>")
	)
	(segment
		(start 78.594966 -236.327696)
		(end 78.586584 -236.32287)
		(width 0.0762)
		(layer "F.Cu")
		(net "M_A_CPU1_SA_DQ<19>")
	)
	(segment
		(start 74.530458 -236.686344)
		(end 66.82105 -228.976936)
		(width 0.10668)
		(layer "F.Cu")
		(net "M_A_CPU1_SA_DQ<19>")
	)
	(segment
		(start 76.202286 -236.686344)
		(end 75.935586 -236.686344)
		(width 0.0762)
		(layer "F.Cu")
		(net "M_A_CPU1_SA_DQ<19>")
	)
	(segment
		(start 62.406784 -219.010484)
		(end 60.344812 -219.010484)
		(width 0.10668)
		(layer "F.Cu")
		(net "M_A_CPU1_SA_DQ<19>")
	)
	(segment
		(start 79.347822 -236.650022)
		(end 79.452978 -236.469174)
		(width 0.0762)
		(layer "F.Cu")
		(net "M_A_CPU1_SA_DQ<19>")
	)
	(segment
		(start 64.552576 -219.898976)
		(end 62.406784 -219.010484)
		(width 0.10668)
		(layer "F.Cu")
		(net "M_A_CPU1_SA_DQ<19>")
	)
	(segment
		(start 60.344812 -219.010484)
		(end 57.804812 -219.010484)
		(width 0.101346)
		(layer "F.Cu")
		(net "M_A_CPU1_SA_DQ<19>")
	)
	(arc
		(start 79.349346 -236.277404)
		(mid 79.256422 -236.288727)
		(end 79.16926 -236.32287)
		(width 0.0762)
		(layer "F.Cu")
		(net "M_A_CPU1_SA_DQ<19>")
	)
	(arc
		(start 78.220824 -236.327696)
		(mid 77.937868 -236.403873)
		(end 77.654912 -236.327696)
		(width 0.0762)
		(layer "F.Cu")
		(net "M_A_CPU1_SA_DQ<19>")
	)
	(arc
		(start 77.654912 -236.327696)
		(mid 77.555839 -236.286382)
		(end 77.449426 -236.272324)
		(width 0.0762)
		(layer "F.Cu")
		(net "M_A_CPU1_SA_DQ<19>")
	)
	(arc
		(start 79.160878 -236.327696)
		(mid 78.877922 -236.403873)
		(end 78.594966 -236.327696)
		(width 0.0762)
		(layer "F.Cu")
		(net "M_A_CPU1_SA_DQ<19>")
	)
	(arc
		(start 79.452978 -236.469174)
		(mid 79.444041 -236.35015)
		(end 79.349346 -236.277404)
		(width 0.0762)
		(layer "F.Cu")
		(net "M_A_CPU1_SA_DQ<19>")
	)
	(arc
		(start 78.586584 -236.32287)
		(mid 78.403076 -236.277376)
		(end 78.220824 -236.327696)
		(width 0.0762)
		(layer "F.Cu")
		(net "M_A_CPU1_SA_DQ<19>")
	)
	(segment
		(start 75.945746 -235.970064)
		(end 74.777346 -235.970064)
		(width 0.10668)
		(layer "F.Cu")
		(net "M_A_CPU1_SA_DQ<18>")
	)
	(segment
		(start 77.937868 -235.84027)
		(end 78.030832 -235.68025)
		(width 0.0762)
		(layer "F.Cu")
		(net "M_A_CPU1_SA_DQ<18>")
	)
	(segment
		(start 74.777346 -235.970064)
		(end 67.50177 -228.694488)
		(width 0.10668)
		(layer "F.Cu")
		(net "M_A_CPU1_SA_DQ<18>")
	)
	(segment
		(start 58.13044 -217.310462)
		(end 57.705244 -216.885266)
		(width 0.101346)
		(layer "F.Cu")
		(net "M_A_CPU1_SA_DQ<18>")
	)
	(segment
		(start 76.463906 -235.655104)
		(end 76.148946 -235.970064)
		(width 0.0762)
		(layer "F.Cu")
		(net "M_A_CPU1_SA_DQ<18>")
	)
	(segment
		(start 60.67044 -217.310462)
		(end 58.13044 -217.310462)
		(width 0.101346)
		(layer "F.Cu")
		(net "M_A_CPU1_SA_DQ<18>")
	)
	(segment
		(start 63.263018 -217.310462)
		(end 60.67044 -217.310462)
		(width 0.10668)
		(layer "F.Cu")
		(net "M_A_CPU1_SA_DQ<18>")
	)
	(segment
		(start 77.240638 -235.655104)
		(end 76.463906 -235.655104)
		(width 0.0762)
		(layer "F.Cu")
		(net "M_A_CPU1_SA_DQ<18>")
	)
	(segment
		(start 67.50177 -221.549214)
		(end 63.263018 -217.310462)
		(width 0.10668)
		(layer "F.Cu")
		(net "M_A_CPU1_SA_DQ<18>")
	)
	(segment
		(start 67.50177 -228.694488)
		(end 67.50177 -221.549214)
		(width 0.10668)
		(layer "F.Cu")
		(net "M_A_CPU1_SA_DQ<18>")
	)
	(segment
		(start 57.705244 -216.885266)
		(end 55.328058 -216.885266)
		(width 0.101346)
		(layer "F.Cu")
		(net "M_A_CPU1_SA_DQ<18>")
	)
	(segment
		(start 77.759306 -235.512864)
		(end 77.750924 -235.51769)
		(width 0.0762)
		(layer "F.Cu")
		(net "M_A_CPU1_SA_DQ<18>")
	)
	(segment
		(start 76.148946 -235.970064)
		(end 75.945746 -235.970064)
		(width 0.0762)
		(layer "F.Cu")
		(net "M_A_CPU1_SA_DQ<18>")
	)
	(arc
		(start 77.899006 -235.46943)
		(mid 77.826998 -235.484212)
		(end 77.759306 -235.512864)
		(width 0.0762)
		(layer "F.Cu")
		(net "M_A_CPU1_SA_DQ<18>")
	)
	(arc
		(start 78.030832 -235.68025)
		(mid 78.030672 -235.533689)
		(end 77.899006 -235.46943)
		(width 0.0762)
		(layer "F.Cu")
		(net "M_A_CPU1_SA_DQ<18>")
	)
	(arc
		(start 77.750924 -235.51769)
		(mid 77.504878 -235.620192)
		(end 77.240638 -235.655104)
		(width 0.0762)
		(layer "F.Cu")
		(net "M_A_CPU1_SA_DQ<18>")
	)
	(segment
		(start 62.326266 -217.842084)
		(end 62.326266 -218.470226)
		(width 0.10668)
		(layer "F.Cu")
		(net "M_A_CPU1_SA_DQ<17>")
	)
	(segment
		(start 62.870588 -217.735404)
		(end 62.432946 -217.735404)
		(width 0.10668)
		(layer "F.Cu")
		(net "M_A_CPU1_SA_DQ<17>")
	)
	(segment
		(start 75.938126 -236.343444)
		(end 74.669142 -236.343444)
		(width 0.10668)
		(layer "F.Cu")
		(net "M_A_CPU1_SA_DQ<17>")
	)
	(segment
		(start 61.528198 -218.470226)
		(end 61.421518 -218.576906)
		(width 0.10668)
		(layer "F.Cu")
		(net "M_A_CPU1_SA_DQ<17>")
	)
	(segment
		(start 67.16141 -228.835712)
		(end 67.16141 -222.026226)
		(width 0.10668)
		(layer "F.Cu")
		(net "M_A_CPU1_SA_DQ<17>")
	)
	(segment
		(start 61.022484 -217.735404)
		(end 59.428126 -217.735404)
		(width 0.10668)
		(layer "F.Cu")
		(net "M_A_CPU1_SA_DQ<17>")
	)
	(segment
		(start 61.421518 -218.576906)
		(end 61.235844 -218.576906)
		(width 0.10668)
		(layer "F.Cu")
		(net "M_A_CPU1_SA_DQ<17>")
	)
	(segment
		(start 76.184506 -236.343444)
		(end 75.938126 -236.343444)
		(width 0.0762)
		(layer "F.Cu")
		(net "M_A_CPU1_SA_DQ<17>")
	)
	(segment
		(start 61.634878 -217.735404)
		(end 61.528198 -217.842084)
		(width 0.10668)
		(layer "F.Cu")
		(net "M_A_CPU1_SA_DQ<17>")
	)
	(segment
		(start 62.219586 -218.576906)
		(end 62.033912 -218.576906)
		(width 0.10668)
		(layer "F.Cu")
		(net "M_A_CPU1_SA_DQ<17>")
	)
	(segment
		(start 61.927232 -217.842084)
		(end 61.820552 -217.735404)
		(width 0.10668)
		(layer "F.Cu")
		(net "M_A_CPU1_SA_DQ<17>")
	)
	(segment
		(start 79.064866 -236.162596)
		(end 79.064866 -236.16285)
		(width 0.0762)
		(layer "F.Cu")
		(net "M_A_CPU1_SA_DQ<17>")
	)
	(segment
		(start 61.820552 -217.735404)
		(end 61.634878 -217.735404)
		(width 0.10668)
		(layer "F.Cu")
		(net "M_A_CPU1_SA_DQ<17>")
	)
	(segment
		(start 76.547726 -235.980224)
		(end 76.184506 -236.343444)
		(width 0.0762)
		(layer "F.Cu")
		(net "M_A_CPU1_SA_DQ<17>")
	)
	(segment
		(start 67.16141 -222.026226)
		(end 62.870588 -217.735404)
		(width 0.10668)
		(layer "F.Cu")
		(net "M_A_CPU1_SA_DQ<17>")
	)
	(segment
		(start 61.235844 -218.576906)
		(end 61.129164 -218.470226)
		(width 0.10668)
		(layer "F.Cu")
		(net "M_A_CPU1_SA_DQ<17>")
	)
	(segment
		(start 61.129164 -217.842084)
		(end 61.022484 -217.735404)
		(width 0.10668)
		(layer "F.Cu")
		(net "M_A_CPU1_SA_DQ<17>")
	)
	(segment
		(start 61.528198 -217.842084)
		(end 61.528198 -218.470226)
		(width 0.10668)
		(layer "F.Cu")
		(net "M_A_CPU1_SA_DQ<17>")
	)
	(segment
		(start 62.033912 -218.576906)
		(end 61.927232 -218.470226)
		(width 0.10668)
		(layer "F.Cu")
		(net "M_A_CPU1_SA_DQ<17>")
	)
	(segment
		(start 77.072744 -235.980224)
		(end 76.547726 -235.980224)
		(width 0.0762)
		(layer "F.Cu")
		(net "M_A_CPU1_SA_DQ<17>")
	)
	(segment
		(start 62.432946 -217.735404)
		(end 62.326266 -217.842084)
		(width 0.10668)
		(layer "F.Cu")
		(net "M_A_CPU1_SA_DQ<17>")
	)
	(segment
		(start 61.927232 -218.470226)
		(end 61.927232 -217.842084)
		(width 0.10668)
		(layer "F.Cu")
		(net "M_A_CPU1_SA_DQ<17>")
	)
	(segment
		(start 77.759306 -236.167676)
		(end 77.750924 -236.16285)
		(width 0.0762)
		(layer "F.Cu")
		(net "M_A_CPU1_SA_DQ<17>")
	)
	(segment
		(start 61.129164 -218.470226)
		(end 61.129164 -217.842084)
		(width 0.10668)
		(layer "F.Cu")
		(net "M_A_CPU1_SA_DQ<17>")
	)
	(segment
		(start 74.669142 -236.343444)
		(end 67.16141 -228.835712)
		(width 0.10668)
		(layer "F.Cu")
		(net "M_A_CPU1_SA_DQ<17>")
	)
	(segment
		(start 62.326266 -218.470226)
		(end 62.219586 -218.576906)
		(width 0.10668)
		(layer "F.Cu")
		(net "M_A_CPU1_SA_DQ<17>")
	)
	(arc
		(start 79.817976 -235.84027)
		(mid 79.61396 -236.020964)
		(end 79.349346 -236.086142)
		(width 0.0762)
		(layer "F.Cu")
		(net "M_A_CPU1_SA_DQ<17>")
	)
	(arc
		(start 79.064866 -236.16285)
		(mid 78.877922 -236.213105)
		(end 78.690978 -236.16285)
		(width 0.0762)
		(layer "F.Cu")
		(net "M_A_CPU1_SA_DQ<17>")
	)
	(arc
		(start 78.690978 -236.16285)
		(mid 78.408022 -236.086673)
		(end 78.125066 -236.16285)
		(width 0.0762)
		(layer "F.Cu")
		(net "M_A_CPU1_SA_DQ<17>")
	)
	(arc
		(start 78.125066 -236.16285)
		(mid 77.942815 -236.2132)
		(end 77.759306 -236.167676)
		(width 0.0762)
		(layer "F.Cu")
		(net "M_A_CPU1_SA_DQ<17>")
	)
	(arc
		(start 79.349346 -236.086142)
		(mid 79.202025 -236.105461)
		(end 79.064866 -236.162596)
		(width 0.0762)
		(layer "F.Cu")
		(net "M_A_CPU1_SA_DQ<17>")
	)
	(arc
		(start 77.750924 -236.16285)
		(mid 77.423914 -236.026679)
		(end 77.072744 -235.980224)
		(width 0.0762)
		(layer "F.Cu")
		(net "M_A_CPU1_SA_DQ<17>")
	)
	(segment
		(start 62.044072 -216.142062)
		(end 62.044072 -216.857326)
		(width 0.10668)
		(layer "F.Cu")
		(net "M_A_CPU1_SA_DQ<16>")
	)
	(segment
		(start 61.937392 -216.964006)
		(end 61.751718 -216.964006)
		(width 0.10668)
		(layer "F.Cu")
		(net "M_A_CPU1_SA_DQ<16>")
	)
	(segment
		(start 60.95365 -216.964006)
		(end 60.84697 -216.857326)
		(width 0.10668)
		(layer "F.Cu")
		(net "M_A_CPU1_SA_DQ<16>")
	)
	(segment
		(start 67.84213 -221.391734)
		(end 62.485778 -216.035382)
		(width 0.10668)
		(layer "F.Cu")
		(net "M_A_CPU1_SA_DQ<16>")
	)
	(segment
		(start 61.246004 -216.014046)
		(end 61.246004 -216.857326)
		(width 0.10668)
		(layer "F.Cu")
		(net "M_A_CPU1_SA_DQ<16>")
	)
	(segment
		(start 76.214986 -235.583984)
		(end 75.976226 -235.583984)
		(width 0.0762)
		(layer "F.Cu")
		(net "M_A_CPU1_SA_DQ<16>")
	)
	(segment
		(start 61.139324 -216.964006)
		(end 60.95365 -216.964006)
		(width 0.10668)
		(layer "F.Cu")
		(net "M_A_CPU1_SA_DQ<16>")
	)
	(segment
		(start 61.751718 -216.964006)
		(end 61.645038 -216.857326)
		(width 0.10668)
		(layer "F.Cu")
		(net "M_A_CPU1_SA_DQ<16>")
	)
	(segment
		(start 61.645038 -216.014046)
		(end 61.538358 -215.907366)
		(width 0.10668)
		(layer "F.Cu")
		(net "M_A_CPU1_SA_DQ<16>")
	)
	(segment
		(start 62.485778 -216.035382)
		(end 62.150752 -216.035382)
		(width 0.10668)
		(layer "F.Cu")
		(net "M_A_CPU1_SA_DQ<16>")
	)
	(segment
		(start 60.84697 -216.857326)
		(end 60.84697 -216.142062)
		(width 0.10668)
		(layer "F.Cu")
		(net "M_A_CPU1_SA_DQ<16>")
	)
	(segment
		(start 61.538358 -215.907366)
		(end 61.352684 -215.907366)
		(width 0.10668)
		(layer "F.Cu")
		(net "M_A_CPU1_SA_DQ<16>")
	)
	(segment
		(start 61.246004 -216.857326)
		(end 61.139324 -216.964006)
		(width 0.10668)
		(layer "F.Cu")
		(net "M_A_CPU1_SA_DQ<16>")
	)
	(segment
		(start 67.84213 -228.553264)
		(end 67.84213 -221.391734)
		(width 0.10668)
		(layer "F.Cu")
		(net "M_A_CPU1_SA_DQ<16>")
	)
	(segment
		(start 76.390246 -235.408724)
		(end 76.214986 -235.583984)
		(width 0.0762)
		(layer "F.Cu")
		(net "M_A_CPU1_SA_DQ<16>")
	)
	(segment
		(start 74.87285 -235.583984)
		(end 67.84213 -228.553264)
		(width 0.10668)
		(layer "F.Cu")
		(net "M_A_CPU1_SA_DQ<16>")
	)
	(segment
		(start 60.84697 -216.142062)
		(end 60.74029 -216.035382)
		(width 0.10668)
		(layer "F.Cu")
		(net "M_A_CPU1_SA_DQ<16>")
	)
	(segment
		(start 75.976226 -235.583984)
		(end 74.87285 -235.583984)
		(width 0.10668)
		(layer "F.Cu")
		(net "M_A_CPU1_SA_DQ<16>")
	)
	(segment
		(start 62.150752 -216.035382)
		(end 62.044072 -216.142062)
		(width 0.10668)
		(layer "F.Cu")
		(net "M_A_CPU1_SA_DQ<16>")
	)
	(segment
		(start 77.447902 -235.408724)
		(end 76.390246 -235.408724)
		(width 0.0762)
		(layer "F.Cu")
		(net "M_A_CPU1_SA_DQ<16>")
	)
	(segment
		(start 61.645038 -216.857326)
		(end 61.645038 -216.014046)
		(width 0.10668)
		(layer "F.Cu")
		(net "M_A_CPU1_SA_DQ<16>")
	)
	(segment
		(start 62.044072 -216.857326)
		(end 61.937392 -216.964006)
		(width 0.10668)
		(layer "F.Cu")
		(net "M_A_CPU1_SA_DQ<16>")
	)
	(segment
		(start 60.74029 -216.035382)
		(end 59.428126 -216.035382)
		(width 0.10668)
		(layer "F.Cu")
		(net "M_A_CPU1_SA_DQ<16>")
	)
	(segment
		(start 61.352684 -215.907366)
		(end 61.246004 -216.014046)
		(width 0.10668)
		(layer "F.Cu")
		(net "M_A_CPU1_SA_DQ<16>")
	)
	(arc
		(start 78.408022 -235.030264)
		(mid 78.171894 -235.201699)
		(end 77.89037 -235.278422)
		(width 0.0762)
		(layer "F.Cu")
		(net "M_A_CPU1_SA_DQ<16>")
	)
	(arc
		(start 77.89037 -235.278422)
		(mid 77.768514 -235.302578)
		(end 77.654912 -235.352844)
		(width 0.0762)
		(layer "F.Cu")
		(net "M_A_CPU1_SA_DQ<16>")
	)
	(arc
		(start 77.654912 -235.352844)
		(mid 77.555105 -235.394473)
		(end 77.447902 -235.408724)
		(width 0.0762)
		(layer "F.Cu")
		(net "M_A_CPU1_SA_DQ<16>")
	)
	(segment
		(start 75.019154 -235.083604)
		(end 68.29933 -228.36378)
		(width 0.10668)
		(layer "F.Cu")
		(net "M_A_CPU1_SA_DQ<15>")
	)
	(segment
		(start 62.441328 -215.343994)
		(end 62.290452 -215.343994)
		(width 0.10668)
		(layer "F.Cu")
		(net "M_A_CPU1_SA_DQ<15>")
	)
	(segment
		(start 60.67044 -214.760302)
		(end 58.13044 -214.760302)
		(width 0.101346)
		(layer "F.Cu")
		(net "M_A_CPU1_SA_DQ<15>")
	)
	(segment
		(start 76.550012 -234.657138)
		(end 76.123546 -235.083604)
		(width 0.0762)
		(layer "F.Cu")
		(net "M_A_CPU1_SA_DQ<15>")
	)
	(segment
		(start 62.1919 -215.442546)
		(end 62.041024 -215.442546)
		(width 0.10668)
		(layer "F.Cu")
		(net "M_A_CPU1_SA_DQ<15>")
	)
	(segment
		(start 68.29933 -228.36378)
		(end 68.29933 -221.201996)
		(width 0.10668)
		(layer "F.Cu")
		(net "M_A_CPU1_SA_DQ<15>")
	)
	(segment
		(start 79.347822 -235.03001)
		(end 79.452978 -234.849162)
		(width 0.0762)
		(layer "F.Cu")
		(net "M_A_CPU1_SA_DQ<15>")
	)
	(segment
		(start 58.13044 -214.760302)
		(end 57.705498 -215.185244)
		(width 0.101346)
		(layer "F.Cu")
		(net "M_A_CPU1_SA_DQ<15>")
	)
	(segment
		(start 61.909706 -215.311228)
		(end 61.909706 -215.160352)
		(width 0.10668)
		(layer "F.Cu")
		(net "M_A_CPU1_SA_DQ<15>")
	)
	(segment
		(start 76.062586 -235.083604)
		(end 75.019154 -235.083604)
		(width 0.10668)
		(layer "F.Cu")
		(net "M_A_CPU1_SA_DQ<15>")
	)
	(segment
		(start 62.041024 -215.442546)
		(end 61.909706 -215.311228)
		(width 0.10668)
		(layer "F.Cu")
		(net "M_A_CPU1_SA_DQ<15>")
	)
	(segment
		(start 77.467968 -234.657138)
		(end 76.550012 -234.657138)
		(width 0.0762)
		(layer "F.Cu")
		(net "M_A_CPU1_SA_DQ<15>")
	)
	(segment
		(start 78.594966 -234.707684)
		(end 78.586584 -234.702858)
		(width 0.0762)
		(layer "F.Cu")
		(net "M_A_CPU1_SA_DQ<15>")
	)
	(segment
		(start 62.008258 -214.910924)
		(end 61.857636 -214.760302)
		(width 0.10668)
		(layer "F.Cu")
		(net "M_A_CPU1_SA_DQ<15>")
	)
	(segment
		(start 62.008258 -215.0618)
		(end 62.008258 -214.910924)
		(width 0.10668)
		(layer "F.Cu")
		(net "M_A_CPU1_SA_DQ<15>")
	)
	(segment
		(start 62.290452 -215.343994)
		(end 62.1919 -215.442546)
		(width 0.10668)
		(layer "F.Cu")
		(net "M_A_CPU1_SA_DQ<15>")
	)
	(segment
		(start 57.705498 -215.185244)
		(end 55.328058 -215.185244)
		(width 0.101346)
		(layer "F.Cu")
		(net "M_A_CPU1_SA_DQ<15>")
	)
	(segment
		(start 61.909706 -215.160352)
		(end 62.008258 -215.0618)
		(width 0.10668)
		(layer "F.Cu")
		(net "M_A_CPU1_SA_DQ<15>")
	)
	(segment
		(start 79.16926 -234.702858)
		(end 79.168244 -234.703366)
		(width 0.0762)
		(layer "F.Cu")
		(net "M_A_CPU1_SA_DQ<15>")
	)
	(segment
		(start 68.29933 -221.201996)
		(end 62.441328 -215.343994)
		(width 0.10668)
		(layer "F.Cu")
		(net "M_A_CPU1_SA_DQ<15>")
	)
	(segment
		(start 79.168244 -234.703366)
		(end 79.160878 -234.707684)
		(width 0.0762)
		(layer "F.Cu")
		(net "M_A_CPU1_SA_DQ<15>")
	)
	(segment
		(start 76.123546 -235.083604)
		(end 76.062586 -235.083604)
		(width 0.0762)
		(layer "F.Cu")
		(net "M_A_CPU1_SA_DQ<15>")
	)
	(segment
		(start 61.857636 -214.760302)
		(end 60.67044 -214.760302)
		(width 0.10668)
		(layer "F.Cu")
		(net "M_A_CPU1_SA_DQ<15>")
	)
	(segment
		(start 79.347822 -235.030264)
		(end 79.347822 -235.03001)
		(width 0.0762)
		(layer "F.Cu")
		(net "M_A_CPU1_SA_DQ<15>")
	)
	(arc
		(start 78.220824 -234.707684)
		(mid 77.937868 -234.783861)
		(end 77.654912 -234.707684)
		(width 0.0762)
		(layer "F.Cu")
		(net "M_A_CPU1_SA_DQ<15>")
	)
	(arc
		(start 77.654912 -234.707684)
		(mid 77.564779 -234.670064)
		(end 77.467968 -234.657138)
		(width 0.0762)
		(layer "F.Cu")
		(net "M_A_CPU1_SA_DQ<15>")
	)
	(arc
		(start 79.349346 -234.657392)
		(mid 79.256422 -234.668715)
		(end 79.16926 -234.702858)
		(width 0.0762)
		(layer "F.Cu")
		(net "M_A_CPU1_SA_DQ<15>")
	)
	(arc
		(start 78.586584 -234.702858)
		(mid 78.403076 -234.657364)
		(end 78.220824 -234.707684)
		(width 0.0762)
		(layer "F.Cu")
		(net "M_A_CPU1_SA_DQ<15>")
	)
	(arc
		(start 79.452978 -234.849162)
		(mid 79.444041 -234.730138)
		(end 79.349346 -234.657392)
		(width 0.0762)
		(layer "F.Cu")
		(net "M_A_CPU1_SA_DQ<15>")
	)
	(arc
		(start 79.160878 -234.707684)
		(mid 78.877922 -234.783861)
		(end 78.594966 -234.707684)
		(width 0.0762)
		(layer "F.Cu")
		(net "M_A_CPU1_SA_DQ<15>")
	)
	(segment
		(start 65.064132 -216.14003)
		(end 64.200786 -216.14003)
		(width 0.10668)
		(layer "F.Cu")
		(net "M_A_CPU1_SA_DQ<14>")
	)
	(segment
		(start 61.437774 -213.131146)
		(end 61.2521 -213.131146)
		(width 0.10668)
		(layer "F.Cu")
		(net "M_A_CPU1_SA_DQ<14>")
	)
	(segment
		(start 64.200786 -216.14003)
		(end 61.971174 -213.910418)
		(width 0.10668)
		(layer "F.Cu")
		(net "M_A_CPU1_SA_DQ<14>")
	)
	(segment
		(start 61.544454 -213.237826)
		(end 61.437774 -213.131146)
		(width 0.10668)
		(layer "F.Cu")
		(net "M_A_CPU1_SA_DQ<14>")
	)
	(segment
		(start 60.67044 -213.910418)
		(end 58.13044 -213.910418)
		(width 0.101346)
		(layer "F.Cu")
		(net "M_A_CPU1_SA_DQ<14>")
	)
	(segment
		(start 77.937868 -234.220258)
		(end 78.030832 -234.060238)
		(width 0.0762)
		(layer "F.Cu")
		(net "M_A_CPU1_SA_DQ<14>")
	)
	(segment
		(start 58.126376 -213.914482)
		(end 56.265318 -213.914482)
		(width 0.101346)
		(layer "F.Cu")
		(net "M_A_CPU1_SA_DQ<14>")
	)
	(segment
		(start 61.03874 -213.910418)
		(end 60.67044 -213.910418)
		(width 0.10668)
		(layer "F.Cu")
		(net "M_A_CPU1_SA_DQ<14>")
	)
	(segment
		(start 61.651134 -213.910418)
		(end 61.544454 -213.803738)
		(width 0.10668)
		(layer "F.Cu")
		(net "M_A_CPU1_SA_DQ<14>")
	)
	(segment
		(start 61.14542 -213.237826)
		(end 61.14542 -213.803738)
		(width 0.10668)
		(layer "F.Cu")
		(net "M_A_CPU1_SA_DQ<14>")
	)
	(segment
		(start 56.265318 -213.914482)
		(end 55.836058 -213.485222)
		(width 0.101346)
		(layer "F.Cu")
		(net "M_A_CPU1_SA_DQ<14>")
	)
	(segment
		(start 55.836058 -213.485222)
		(end 55.328058 -213.485222)
		(width 0.101346)
		(layer "F.Cu")
		(net "M_A_CPU1_SA_DQ<14>")
	)
	(segment
		(start 58.13044 -213.910418)
		(end 58.126376 -213.914482)
		(width 0.101346)
		(layer "F.Cu")
		(net "M_A_CPU1_SA_DQ<14>")
	)
	(segment
		(start 76.115926 -234.118404)
		(end 76.029566 -234.204764)
		(width 0.0762)
		(layer "F.Cu")
		(net "M_A_CPU1_SA_DQ<14>")
	)
	(segment
		(start 76.029566 -234.204764)
		(end 75.103482 -234.204764)
		(width 0.10668)
		(layer "F.Cu")
		(net "M_A_CPU1_SA_DQ<14>")
	)
	(segment
		(start 61.971174 -213.910418)
		(end 61.651134 -213.910418)
		(width 0.10668)
		(layer "F.Cu")
		(net "M_A_CPU1_SA_DQ<14>")
	)
	(segment
		(start 68.98005 -220.055948)
		(end 65.064132 -216.14003)
		(width 0.10668)
		(layer "F.Cu")
		(net "M_A_CPU1_SA_DQ<14>")
	)
	(segment
		(start 75.103482 -234.204764)
		(end 68.98005 -228.081332)
		(width 0.10668)
		(layer "F.Cu")
		(net "M_A_CPU1_SA_DQ<14>")
	)
	(segment
		(start 68.98005 -228.081332)
		(end 68.98005 -220.055948)
		(width 0.10668)
		(layer "F.Cu")
		(net "M_A_CPU1_SA_DQ<14>")
	)
	(segment
		(start 77.759306 -233.892852)
		(end 77.750924 -233.897678)
		(width 0.0762)
		(layer "F.Cu")
		(net "M_A_CPU1_SA_DQ<14>")
	)
	(segment
		(start 61.14542 -213.803738)
		(end 61.03874 -213.910418)
		(width 0.10668)
		(layer "F.Cu")
		(net "M_A_CPU1_SA_DQ<14>")
	)
	(segment
		(start 61.544454 -213.803738)
		(end 61.544454 -213.237826)
		(width 0.10668)
		(layer "F.Cu")
		(net "M_A_CPU1_SA_DQ<14>")
	)
	(segment
		(start 76.93152 -234.118404)
		(end 76.115926 -234.118404)
		(width 0.0762)
		(layer "F.Cu")
		(net "M_A_CPU1_SA_DQ<14>")
	)
	(segment
		(start 61.2521 -213.131146)
		(end 61.14542 -213.237826)
		(width 0.10668)
		(layer "F.Cu")
		(net "M_A_CPU1_SA_DQ<14>")
	)
	(arc
		(start 77.899006 -233.849418)
		(mid 77.826998 -233.8642)
		(end 77.759306 -233.892852)
		(width 0.0762)
		(layer "F.Cu")
		(net "M_A_CPU1_SA_DQ<14>")
	)
	(arc
		(start 78.030832 -234.060238)
		(mid 78.030672 -233.913677)
		(end 77.899006 -233.849418)
		(width 0.0762)
		(layer "F.Cu")
		(net "M_A_CPU1_SA_DQ<14>")
	)
	(arc
		(start 77.750924 -233.897678)
		(mid 77.355819 -234.062217)
		(end 76.93152 -234.118404)
		(width 0.0762)
		(layer "F.Cu")
		(net "M_A_CPU1_SA_DQ<14>")
	)
	(segment
		(start 67.061842 -218.718892)
		(end 66.944748 -218.601798)
		(width 0.10668)
		(layer "F.Cu")
		(net "M_A_CPU1_SA_DQ<13>")
	)
	(segment
		(start 77.467968 -234.466638)
		(end 76.316332 -234.466638)
		(width 0.0762)
		(layer "F.Cu")
		(net "M_A_CPU1_SA_DQ<13>")
	)
	(segment
		(start 75.953366 -234.654344)
		(end 75.071478 -234.654344)
		(width 0.10668)
		(layer "F.Cu")
		(net "M_A_CPU1_SA_DQ<13>")
	)
	(segment
		(start 79.064866 -234.542584)
		(end 79.064866 -234.542838)
		(width 0.0762)
		(layer "F.Cu")
		(net "M_A_CPU1_SA_DQ<13>")
	)
	(segment
		(start 65.815972 -217.473022)
		(end 65.650872 -217.473022)
		(width 0.10668)
		(layer "F.Cu")
		(net "M_A_CPU1_SA_DQ<13>")
	)
	(segment
		(start 65.03416 -216.960958)
		(end 64.869568 -217.12555)
		(width 0.10668)
		(layer "F.Cu")
		(net "M_A_CPU1_SA_DQ<13>")
	)
	(segment
		(start 66.96202 -219.383102)
		(end 66.844926 -219.266008)
		(width 0.10668)
		(layer "F.Cu")
		(net "M_A_CPU1_SA_DQ<13>")
	)
	(segment
		(start 66.280538 -218.53652)
		(end 66.497454 -218.319604)
		(width 0.10668)
		(layer "F.Cu")
		(net "M_A_CPU1_SA_DQ<13>")
	)
	(segment
		(start 64.385952 -216.48039)
		(end 64.30518 -216.561162)
		(width 0.10668)
		(layer "F.Cu")
		(net "M_A_CPU1_SA_DQ<13>")
	)
	(segment
		(start 66.497454 -218.319604)
		(end 66.497454 -218.154504)
		(width 0.10668)
		(layer "F.Cu")
		(net "M_A_CPU1_SA_DQ<13>")
	)
	(segment
		(start 67.526408 -219.94749)
		(end 67.409314 -219.830396)
		(width 0.10668)
		(layer "F.Cu")
		(net "M_A_CPU1_SA_DQ<13>")
	)
	(segment
		(start 64.551052 -216.48039)
		(end 64.385952 -216.48039)
		(width 0.10668)
		(layer "F.Cu")
		(net "M_A_CPU1_SA_DQ<13>")
	)
	(segment
		(start 66.779648 -218.601798)
		(end 66.562732 -218.818714)
		(width 0.10668)
		(layer "F.Cu")
		(net "M_A_CPU1_SA_DQ<13>")
	)
	(segment
		(start 64.14008 -216.561162)
		(end 61.914278 -214.33536)
		(width 0.10668)
		(layer "F.Cu")
		(net "M_A_CPU1_SA_DQ<13>")
	)
	(segment
		(start 65.933066 -217.590116)
		(end 65.815972 -217.473022)
		(width 0.10668)
		(layer "F.Cu")
		(net "M_A_CPU1_SA_DQ<13>")
	)
	(segment
		(start 65.833244 -218.254326)
		(end 65.71615 -218.137232)
		(width 0.10668)
		(layer "F.Cu")
		(net "M_A_CPU1_SA_DQ<13>")
	)
	(segment
		(start 68.63969 -228.222556)
		(end 68.63969 -221.060772)
		(width 0.10668)
		(layer "F.Cu")
		(net "M_A_CPU1_SA_DQ<13>")
	)
	(segment
		(start 65.933066 -217.755216)
		(end 65.933066 -217.590116)
		(width 0.10668)
		(layer "F.Cu")
		(net "M_A_CPU1_SA_DQ<13>")
	)
	(segment
		(start 61.914278 -214.33536)
		(end 59.428126 -214.33536)
		(width 0.10668)
		(layer "F.Cu")
		(net "M_A_CPU1_SA_DQ<13>")
	)
	(segment
		(start 66.944748 -218.601798)
		(end 66.779648 -218.601798)
		(width 0.10668)
		(layer "F.Cu")
		(net "M_A_CPU1_SA_DQ<13>")
	)
	(segment
		(start 66.397632 -218.818714)
		(end 66.280538 -218.70162)
		(width 0.10668)
		(layer "F.Cu")
		(net "M_A_CPU1_SA_DQ<13>")
	)
	(segment
		(start 67.908424 -219.730574)
		(end 67.691508 -219.94749)
		(width 0.10668)
		(layer "F.Cu")
		(net "M_A_CPU1_SA_DQ<13>")
	)
	(segment
		(start 65.316354 -217.078052)
		(end 65.19926 -216.960958)
		(width 0.10668)
		(layer "F.Cu")
		(net "M_A_CPU1_SA_DQ<13>")
	)
	(segment
		(start 75.071478 -234.654344)
		(end 68.63969 -228.222556)
		(width 0.10668)
		(layer "F.Cu")
		(net "M_A_CPU1_SA_DQ<13>")
	)
	(segment
		(start 76.128626 -234.654344)
		(end 75.953366 -234.654344)
		(width 0.0762)
		(layer "F.Cu")
		(net "M_A_CPU1_SA_DQ<13>")
	)
	(segment
		(start 66.844926 -219.100908)
		(end 67.061842 -218.883992)
		(width 0.10668)
		(layer "F.Cu")
		(net "M_A_CPU1_SA_DQ<13>")
	)
	(segment
		(start 64.587374 -217.008456)
		(end 64.587374 -216.843356)
		(width 0.10668)
		(layer "F.Cu")
		(net "M_A_CPU1_SA_DQ<13>")
	)
	(segment
		(start 67.12712 -219.383102)
		(end 66.96202 -219.383102)
		(width 0.10668)
		(layer "F.Cu")
		(net "M_A_CPU1_SA_DQ<13>")
	)
	(segment
		(start 67.344036 -219.166186)
		(end 67.12712 -219.383102)
		(width 0.10668)
		(layer "F.Cu")
		(net "M_A_CPU1_SA_DQ<13>")
	)
	(segment
		(start 67.691508 -219.94749)
		(end 67.526408 -219.94749)
		(width 0.10668)
		(layer "F.Cu")
		(net "M_A_CPU1_SA_DQ<13>")
	)
	(segment
		(start 65.998344 -218.254326)
		(end 65.833244 -218.254326)
		(width 0.10668)
		(layer "F.Cu")
		(net "M_A_CPU1_SA_DQ<13>")
	)
	(segment
		(start 65.71615 -217.972132)
		(end 65.933066 -217.755216)
		(width 0.10668)
		(layer "F.Cu")
		(net "M_A_CPU1_SA_DQ<13>")
	)
	(segment
		(start 64.587374 -216.843356)
		(end 64.668146 -216.762584)
		(width 0.10668)
		(layer "F.Cu")
		(net "M_A_CPU1_SA_DQ<13>")
	)
	(segment
		(start 66.497454 -218.154504)
		(end 66.38036 -218.03741)
		(width 0.10668)
		(layer "F.Cu")
		(net "M_A_CPU1_SA_DQ<13>")
	)
	(segment
		(start 68.190618 -219.847668)
		(end 68.073524 -219.730574)
		(width 0.10668)
		(layer "F.Cu")
		(net "M_A_CPU1_SA_DQ<13>")
	)
	(segment
		(start 67.973702 -220.229684)
		(end 68.190618 -220.012768)
		(width 0.10668)
		(layer "F.Cu")
		(net "M_A_CPU1_SA_DQ<13>")
	)
	(segment
		(start 64.668146 -216.762584)
		(end 64.668146 -216.597484)
		(width 0.10668)
		(layer "F.Cu")
		(net "M_A_CPU1_SA_DQ<13>")
	)
	(segment
		(start 65.650872 -217.473022)
		(end 65.433956 -217.689938)
		(width 0.10668)
		(layer "F.Cu")
		(net "M_A_CPU1_SA_DQ<13>")
	)
	(segment
		(start 65.71615 -218.137232)
		(end 65.71615 -217.972132)
		(width 0.10668)
		(layer "F.Cu")
		(net "M_A_CPU1_SA_DQ<13>")
	)
	(segment
		(start 67.061842 -218.883992)
		(end 67.061842 -218.718892)
		(width 0.10668)
		(layer "F.Cu")
		(net "M_A_CPU1_SA_DQ<13>")
	)
	(segment
		(start 65.151762 -217.407744)
		(end 65.316354 -217.243152)
		(width 0.10668)
		(layer "F.Cu")
		(net "M_A_CPU1_SA_DQ<13>")
	)
	(segment
		(start 66.844926 -219.266008)
		(end 66.844926 -219.100908)
		(width 0.10668)
		(layer "F.Cu")
		(net "M_A_CPU1_SA_DQ<13>")
	)
	(segment
		(start 68.073524 -219.730574)
		(end 67.908424 -219.730574)
		(width 0.10668)
		(layer "F.Cu")
		(net "M_A_CPU1_SA_DQ<13>")
	)
	(segment
		(start 68.190618 -220.012768)
		(end 68.190618 -219.847668)
		(width 0.10668)
		(layer "F.Cu")
		(net "M_A_CPU1_SA_DQ<13>")
	)
	(segment
		(start 68.63969 -221.060772)
		(end 67.973702 -220.394784)
		(width 0.10668)
		(layer "F.Cu")
		(net "M_A_CPU1_SA_DQ<13>")
	)
	(segment
		(start 67.62623 -219.28328)
		(end 67.509136 -219.166186)
		(width 0.10668)
		(layer "F.Cu")
		(net "M_A_CPU1_SA_DQ<13>")
	)
	(segment
		(start 67.62623 -219.44838)
		(end 67.62623 -219.28328)
		(width 0.10668)
		(layer "F.Cu")
		(net "M_A_CPU1_SA_DQ<13>")
	)
	(segment
		(start 67.409314 -219.830396)
		(end 67.409314 -219.665296)
		(width 0.10668)
		(layer "F.Cu")
		(net "M_A_CPU1_SA_DQ<13>")
	)
	(segment
		(start 65.268856 -217.689938)
		(end 65.151762 -217.572844)
		(width 0.10668)
		(layer "F.Cu")
		(net "M_A_CPU1_SA_DQ<13>")
	)
	(segment
		(start 65.433956 -217.689938)
		(end 65.268856 -217.689938)
		(width 0.10668)
		(layer "F.Cu")
		(net "M_A_CPU1_SA_DQ<13>")
	)
	(segment
		(start 76.316332 -234.466638)
		(end 76.128626 -234.654344)
		(width 0.0762)
		(layer "F.Cu")
		(net "M_A_CPU1_SA_DQ<13>")
	)
	(segment
		(start 66.562732 -218.818714)
		(end 66.397632 -218.818714)
		(width 0.10668)
		(layer "F.Cu")
		(net "M_A_CPU1_SA_DQ<13>")
	)
	(segment
		(start 65.151762 -217.572844)
		(end 65.151762 -217.407744)
		(width 0.10668)
		(layer "F.Cu")
		(net "M_A_CPU1_SA_DQ<13>")
	)
	(segment
		(start 66.38036 -218.03741)
		(end 66.21526 -218.03741)
		(width 0.10668)
		(layer "F.Cu")
		(net "M_A_CPU1_SA_DQ<13>")
	)
	(segment
		(start 66.21526 -218.03741)
		(end 65.998344 -218.254326)
		(width 0.10668)
		(layer "F.Cu")
		(net "M_A_CPU1_SA_DQ<13>")
	)
	(segment
		(start 67.409314 -219.665296)
		(end 67.62623 -219.44838)
		(width 0.10668)
		(layer "F.Cu")
		(net "M_A_CPU1_SA_DQ<13>")
	)
	(segment
		(start 65.19926 -216.960958)
		(end 65.03416 -216.960958)
		(width 0.10668)
		(layer "F.Cu")
		(net "M_A_CPU1_SA_DQ<13>")
	)
	(segment
		(start 65.316354 -217.243152)
		(end 65.316354 -217.078052)
		(width 0.10668)
		(layer "F.Cu")
		(net "M_A_CPU1_SA_DQ<13>")
	)
	(segment
		(start 64.704468 -217.12555)
		(end 64.587374 -217.008456)
		(width 0.10668)
		(layer "F.Cu")
		(net "M_A_CPU1_SA_DQ<13>")
	)
	(segment
		(start 64.668146 -216.597484)
		(end 64.551052 -216.48039)
		(width 0.10668)
		(layer "F.Cu")
		(net "M_A_CPU1_SA_DQ<13>")
	)
	(segment
		(start 64.869568 -217.12555)
		(end 64.704468 -217.12555)
		(width 0.10668)
		(layer "F.Cu")
		(net "M_A_CPU1_SA_DQ<13>")
	)
	(segment
		(start 77.759306 -234.547664)
		(end 77.750924 -234.542838)
		(width 0.0762)
		(layer "F.Cu")
		(net "M_A_CPU1_SA_DQ<13>")
	)
	(segment
		(start 64.30518 -216.561162)
		(end 64.14008 -216.561162)
		(width 0.10668)
		(layer "F.Cu")
		(net "M_A_CPU1_SA_DQ<13>")
	)
	(segment
		(start 67.973702 -220.394784)
		(end 67.973702 -220.229684)
		(width 0.10668)
		(layer "F.Cu")
		(net "M_A_CPU1_SA_DQ<13>")
	)
	(segment
		(start 67.509136 -219.166186)
		(end 67.344036 -219.166186)
		(width 0.10668)
		(layer "F.Cu")
		(net "M_A_CPU1_SA_DQ<13>")
	)
	(segment
		(start 66.280538 -218.70162)
		(end 66.280538 -218.53652)
		(width 0.10668)
		(layer "F.Cu")
		(net "M_A_CPU1_SA_DQ<13>")
	)
	(arc
		(start 78.125066 -234.542838)
		(mid 77.942815 -234.593188)
		(end 77.759306 -234.547664)
		(width 0.0762)
		(layer "F.Cu")
		(net "M_A_CPU1_SA_DQ<13>")
	)
	(arc
		(start 79.349346 -234.46613)
		(mid 79.202025 -234.485449)
		(end 79.064866 -234.542584)
		(width 0.0762)
		(layer "F.Cu")
		(net "M_A_CPU1_SA_DQ<13>")
	)
	(arc
		(start 78.690978 -234.542838)
		(mid 78.408022 -234.466661)
		(end 78.125066 -234.542838)
		(width 0.0762)
		(layer "F.Cu")
		(net "M_A_CPU1_SA_DQ<13>")
	)
	(arc
		(start 77.750924 -234.542838)
		(mid 77.614488 -234.486013)
		(end 77.467968 -234.466638)
		(width 0.0762)
		(layer "F.Cu")
		(net "M_A_CPU1_SA_DQ<13>")
	)
	(arc
		(start 79.817976 -234.220258)
		(mid 79.61396 -234.400952)
		(end 79.349346 -234.46613)
		(width 0.0762)
		(layer "F.Cu")
		(net "M_A_CPU1_SA_DQ<13>")
	)
	(arc
		(start 79.064866 -234.542838)
		(mid 78.877922 -234.593093)
		(end 78.690978 -234.542838)
		(width 0.0762)
		(layer "F.Cu")
		(net "M_A_CPU1_SA_DQ<13>")
	)
	(segment
		(start 61.93409 -213.22157)
		(end 62.234826 -212.920834)
		(width 0.10668)
		(layer "F.Cu")
		(net "M_A_CPU1_SA_DQ<12>")
	)
	(segment
		(start 63.909448 -215.196928)
		(end 63.758572 -215.196928)
		(width 0.10668)
		(layer "F.Cu")
		(net "M_A_CPU1_SA_DQ<12>")
	)
	(segment
		(start 62.799214 -213.485222)
		(end 62.799214 -213.334346)
		(width 0.10668)
		(layer "F.Cu")
		(net "M_A_CPU1_SA_DQ<12>")
	)
	(segment
		(start 63.796672 -214.331804)
		(end 63.645796 -214.331804)
		(width 0.10668)
		(layer "F.Cu")
		(net "M_A_CPU1_SA_DQ<12>")
	)
	(segment
		(start 64.492378 -215.178386)
		(end 64.492378 -215.02751)
		(width 0.10668)
		(layer "F.Cu")
		(net "M_A_CPU1_SA_DQ<12>")
	)
	(segment
		(start 62.065408 -213.503764)
		(end 61.93409 -213.372446)
		(width 0.10668)
		(layer "F.Cu")
		(net "M_A_CPU1_SA_DQ<12>")
	)
	(segment
		(start 62.100206 -212.635338)
		(end 59.428126 -212.635338)
		(width 0.10668)
		(layer "F.Cu")
		(net "M_A_CPU1_SA_DQ<12>")
	)
	(segment
		(start 63.232284 -213.767416)
		(end 63.081408 -213.767416)
		(width 0.10668)
		(layer "F.Cu")
		(net "M_A_CPU1_SA_DQ<12>")
	)
	(segment
		(start 62.667896 -213.203028)
		(end 62.51702 -213.203028)
		(width 0.10668)
		(layer "F.Cu")
		(net "M_A_CPU1_SA_DQ<12>")
	)
	(segment
		(start 62.780672 -214.068152)
		(end 62.629796 -214.068152)
		(width 0.10668)
		(layer "F.Cu")
		(net "M_A_CPU1_SA_DQ<12>")
	)
	(segment
		(start 69.32041 -227.940108)
		(end 69.32041 -219.855542)
		(width 0.10668)
		(layer "F.Cu")
		(net "M_A_CPU1_SA_DQ<12>")
	)
	(segment
		(start 64.191642 -215.629998)
		(end 64.191642 -215.479122)
		(width 0.10668)
		(layer "F.Cu")
		(net "M_A_CPU1_SA_DQ<12>")
	)
	(segment
		(start 64.36106 -214.896192)
		(end 64.210184 -214.896192)
		(width 0.10668)
		(layer "F.Cu")
		(net "M_A_CPU1_SA_DQ<12>")
	)
	(segment
		(start 63.34506 -214.63254)
		(end 63.194184 -214.63254)
		(width 0.10668)
		(layer "F.Cu")
		(net "M_A_CPU1_SA_DQ<12>")
	)
	(segment
		(start 62.498478 -213.936834)
		(end 62.498478 -213.785958)
		(width 0.10668)
		(layer "F.Cu")
		(net "M_A_CPU1_SA_DQ<12>")
	)
	(segment
		(start 64.473836 -215.761316)
		(end 64.32296 -215.761316)
		(width 0.10668)
		(layer "F.Cu")
		(net "M_A_CPU1_SA_DQ<12>")
	)
	(segment
		(start 64.492378 -215.02751)
		(end 64.36106 -214.896192)
		(width 0.10668)
		(layer "F.Cu")
		(net "M_A_CPU1_SA_DQ<12>")
	)
	(segment
		(start 69.32041 -219.855542)
		(end 64.925448 -215.46058)
		(width 0.10668)
		(layer "F.Cu")
		(net "M_A_CPU1_SA_DQ<12>")
	)
	(segment
		(start 63.062866 -214.350346)
		(end 63.363602 -214.04961)
		(width 0.10668)
		(layer "F.Cu")
		(net "M_A_CPU1_SA_DQ<12>")
	)
	(segment
		(start 75.171046 -233.790744)
		(end 69.32041 -227.940108)
		(width 0.10668)
		(layer "F.Cu")
		(net "M_A_CPU1_SA_DQ<12>")
	)
	(segment
		(start 63.645796 -214.331804)
		(end 63.34506 -214.63254)
		(width 0.10668)
		(layer "F.Cu")
		(net "M_A_CPU1_SA_DQ<12>")
	)
	(segment
		(start 62.234826 -212.920834)
		(end 62.234826 -212.769958)
		(width 0.10668)
		(layer "F.Cu")
		(net "M_A_CPU1_SA_DQ<12>")
	)
	(segment
		(start 62.629796 -214.068152)
		(end 62.498478 -213.936834)
		(width 0.10668)
		(layer "F.Cu")
		(net "M_A_CPU1_SA_DQ<12>")
	)
	(segment
		(start 62.51702 -213.203028)
		(end 62.216284 -213.503764)
		(width 0.10668)
		(layer "F.Cu")
		(net "M_A_CPU1_SA_DQ<12>")
	)
	(segment
		(start 64.774572 -215.46058)
		(end 64.473836 -215.761316)
		(width 0.10668)
		(layer "F.Cu")
		(net "M_A_CPU1_SA_DQ<12>")
	)
	(segment
		(start 75.963526 -233.790744)
		(end 75.171046 -233.790744)
		(width 0.10668)
		(layer "F.Cu")
		(net "M_A_CPU1_SA_DQ<12>")
	)
	(segment
		(start 61.93409 -213.372446)
		(end 61.93409 -213.22157)
		(width 0.10668)
		(layer "F.Cu")
		(net "M_A_CPU1_SA_DQ<12>")
	)
	(segment
		(start 64.925448 -215.46058)
		(end 64.774572 -215.46058)
		(width 0.10668)
		(layer "F.Cu")
		(net "M_A_CPU1_SA_DQ<12>")
	)
	(segment
		(start 64.32296 -215.761316)
		(end 64.191642 -215.629998)
		(width 0.10668)
		(layer "F.Cu")
		(net "M_A_CPU1_SA_DQ<12>")
	)
	(segment
		(start 63.758572 -215.196928)
		(end 63.627254 -215.06561)
		(width 0.10668)
		(layer "F.Cu")
		(net "M_A_CPU1_SA_DQ<12>")
	)
	(segment
		(start 63.081408 -213.767416)
		(end 62.780672 -214.068152)
		(width 0.10668)
		(layer "F.Cu")
		(net "M_A_CPU1_SA_DQ<12>")
	)
	(segment
		(start 63.627254 -215.06561)
		(end 63.627254 -214.914734)
		(width 0.10668)
		(layer "F.Cu")
		(net "M_A_CPU1_SA_DQ<12>")
	)
	(segment
		(start 77.440282 -233.790744)
		(end 75.963526 -233.790744)
		(width 0.0762)
		(layer "F.Cu")
		(net "M_A_CPU1_SA_DQ<12>")
	)
	(segment
		(start 63.92799 -214.613998)
		(end 63.92799 -214.463122)
		(width 0.10668)
		(layer "F.Cu")
		(net "M_A_CPU1_SA_DQ<12>")
	)
	(segment
		(start 63.627254 -214.914734)
		(end 63.92799 -214.613998)
		(width 0.10668)
		(layer "F.Cu")
		(net "M_A_CPU1_SA_DQ<12>")
	)
	(segment
		(start 62.234826 -212.769958)
		(end 62.100206 -212.635338)
		(width 0.10668)
		(layer "F.Cu")
		(net "M_A_CPU1_SA_DQ<12>")
	)
	(segment
		(start 63.363602 -213.898734)
		(end 63.232284 -213.767416)
		(width 0.10668)
		(layer "F.Cu")
		(net "M_A_CPU1_SA_DQ<12>")
	)
	(segment
		(start 64.191642 -215.479122)
		(end 64.492378 -215.178386)
		(width 0.10668)
		(layer "F.Cu")
		(net "M_A_CPU1_SA_DQ<12>")
	)
	(segment
		(start 63.062866 -214.501222)
		(end 63.062866 -214.350346)
		(width 0.10668)
		(layer "F.Cu")
		(net "M_A_CPU1_SA_DQ<12>")
	)
	(segment
		(start 62.216284 -213.503764)
		(end 62.065408 -213.503764)
		(width 0.10668)
		(layer "F.Cu")
		(net "M_A_CPU1_SA_DQ<12>")
	)
	(segment
		(start 63.194184 -214.63254)
		(end 63.062866 -214.501222)
		(width 0.10668)
		(layer "F.Cu")
		(net "M_A_CPU1_SA_DQ<12>")
	)
	(segment
		(start 63.92799 -214.463122)
		(end 63.796672 -214.331804)
		(width 0.10668)
		(layer "F.Cu")
		(net "M_A_CPU1_SA_DQ<12>")
	)
	(segment
		(start 62.498478 -213.785958)
		(end 62.799214 -213.485222)
		(width 0.10668)
		(layer "F.Cu")
		(net "M_A_CPU1_SA_DQ<12>")
	)
	(segment
		(start 62.799214 -213.334346)
		(end 62.667896 -213.203028)
		(width 0.10668)
		(layer "F.Cu")
		(net "M_A_CPU1_SA_DQ<12>")
	)
	(segment
		(start 63.363602 -214.04961)
		(end 63.363602 -213.898734)
		(width 0.10668)
		(layer "F.Cu")
		(net "M_A_CPU1_SA_DQ<12>")
	)
	(segment
		(start 64.210184 -214.896192)
		(end 63.909448 -215.196928)
		(width 0.10668)
		(layer "F.Cu")
		(net "M_A_CPU1_SA_DQ<12>")
	)
	(arc
		(start 77.654912 -233.732832)
		(mid 77.551434 -233.776008)
		(end 77.440282 -233.790744)
		(width 0.0762)
		(layer "F.Cu")
		(net "M_A_CPU1_SA_DQ<12>")
	)
	(arc
		(start 77.89037 -233.65841)
		(mid 77.768514 -233.682566)
		(end 77.654912 -233.732832)
		(width 0.0762)
		(layer "F.Cu")
		(net "M_A_CPU1_SA_DQ<12>")
	)
	(arc
		(start 78.408022 -233.410252)
		(mid 78.171894 -233.581687)
		(end 77.89037 -233.65841)
		(width 0.0762)
		(layer "F.Cu")
		(net "M_A_CPU1_SA_DQ<12>")
	)
	(segment
		(start 75.694286 -231.598724)
		(end 71.20763 -227.112068)
		(width 0.10668)
		(layer "F.Cu")
		(net "M_A_CPU1_SA_DQ<11>")
	)
	(segment
		(start 78.594966 -231.467914)
		(end 78.586584 -231.463088)
		(width 0.0762)
		(layer "F.Cu")
		(net "M_A_CPU1_SA_DQ<11>")
	)
	(segment
		(start 76.602336 -231.417114)
		(end 76.420726 -231.598724)
		(width 0.0762)
		(layer "F.Cu")
		(net "M_A_CPU1_SA_DQ<11>")
	)
	(segment
		(start 64.556386 -211.349844)
		(end 63.878968 -210.897216)
		(width 0.10668)
		(layer "F.Cu")
		(net "M_A_CPU1_SA_DQ<11>")
	)
	(segment
		(start 57.804812 -209.66049)
		(end 57.379616 -209.235294)
		(width 0.101346)
		(layer "F.Cu")
		(net "M_A_CPU1_SA_DQ<11>")
	)
	(segment
		(start 63.878968 -210.897216)
		(end 60.893198 -209.66049)
		(width 0.10668)
		(layer "F.Cu")
		(net "M_A_CPU1_SA_DQ<11>")
	)
	(segment
		(start 70.387464 -217.180922)
		(end 64.556386 -211.349844)
		(width 0.10668)
		(layer "F.Cu")
		(net "M_A_CPU1_SA_DQ<11>")
	)
	(segment
		(start 79.168244 -231.463596)
		(end 79.160878 -231.467914)
		(width 0.0762)
		(layer "F.Cu")
		(net "M_A_CPU1_SA_DQ<11>")
	)
	(segment
		(start 76.420726 -231.598724)
		(end 75.694286 -231.598724)
		(width 0.10668)
		(layer "F.Cu")
		(net "M_A_CPU1_SA_DQ<11>")
	)
	(segment
		(start 60.893198 -209.66049)
		(end 60.344812 -209.66049)
		(width 0.10668)
		(layer "F.Cu")
		(net "M_A_CPU1_SA_DQ<11>")
	)
	(segment
		(start 71.20763 -227.112068)
		(end 71.20763 -219.160344)
		(width 0.10668)
		(layer "F.Cu")
		(net "M_A_CPU1_SA_DQ<11>")
	)
	(segment
		(start 79.16926 -231.463088)
		(end 79.168244 -231.463596)
		(width 0.0762)
		(layer "F.Cu")
		(net "M_A_CPU1_SA_DQ<11>")
	)
	(segment
		(start 57.379616 -209.235294)
		(end 55.328058 -209.235294)
		(width 0.101346)
		(layer "F.Cu")
		(net "M_A_CPU1_SA_DQ<11>")
	)
	(segment
		(start 77.467968 -231.417114)
		(end 76.602336 -231.417114)
		(width 0.0762)
		(layer "F.Cu")
		(net "M_A_CPU1_SA_DQ<11>")
	)
	(segment
		(start 79.347822 -231.79024)
		(end 79.452978 -231.609392)
		(width 0.0762)
		(layer "F.Cu")
		(net "M_A_CPU1_SA_DQ<11>")
	)
	(segment
		(start 71.20763 -219.160344)
		(end 70.387464 -217.180922)
		(width 0.10668)
		(layer "F.Cu")
		(net "M_A_CPU1_SA_DQ<11>")
	)
	(segment
		(start 60.344812 -209.66049)
		(end 57.804812 -209.66049)
		(width 0.101346)
		(layer "F.Cu")
		(net "M_A_CPU1_SA_DQ<11>")
	)
	(arc
		(start 77.654912 -231.467914)
		(mid 77.564799 -231.430145)
		(end 77.467968 -231.417114)
		(width 0.0762)
		(layer "F.Cu")
		(net "M_A_CPU1_SA_DQ<11>")
	)
	(arc
		(start 79.349346 -231.417622)
		(mid 79.256422 -231.428945)
		(end 79.16926 -231.463088)
		(width 0.0762)
		(layer "F.Cu")
		(net "M_A_CPU1_SA_DQ<11>")
	)
	(arc
		(start 78.586584 -231.463088)
		(mid 78.403076 -231.417563)
		(end 78.220824 -231.467914)
		(width 0.0762)
		(layer "F.Cu")
		(net "M_A_CPU1_SA_DQ<11>")
	)
	(arc
		(start 78.220824 -231.467914)
		(mid 77.937868 -231.544091)
		(end 77.654912 -231.467914)
		(width 0.0762)
		(layer "F.Cu")
		(net "M_A_CPU1_SA_DQ<11>")
	)
	(arc
		(start 79.160878 -231.467914)
		(mid 78.877922 -231.544091)
		(end 78.594966 -231.467914)
		(width 0.0762)
		(layer "F.Cu")
		(net "M_A_CPU1_SA_DQ<11>")
	)
	(arc
		(start 79.452978 -231.609392)
		(mid 79.444041 -231.490368)
		(end 79.349346 -231.417622)
		(width 0.0762)
		(layer "F.Cu")
		(net "M_A_CPU1_SA_DQ<11>")
	)
	(segment
		(start 77.937868 -230.980234)
		(end 78.030832 -230.820214)
		(width 0.0762)
		(layer "F.Cu")
		(net "M_A_CPU1_SA_DQ<10>")
	)
	(segment
		(start 75.928474 -230.869744)
		(end 71.88835 -226.82962)
		(width 0.10668)
		(layer "F.Cu")
		(net "M_A_CPU1_SA_DQ<10>")
	)
	(segment
		(start 60.67044 -207.960468)
		(end 58.13044 -207.960468)
		(width 0.101346)
		(layer "F.Cu")
		(net "M_A_CPU1_SA_DQ<10>")
	)
	(segment
		(start 77.759306 -230.652828)
		(end 77.750924 -230.657654)
		(width 0.0762)
		(layer "F.Cu")
		(net "M_A_CPU1_SA_DQ<10>")
	)
	(segment
		(start 76.298806 -230.869744)
		(end 75.928474 -230.869744)
		(width 0.10668)
		(layer "F.Cu")
		(net "M_A_CPU1_SA_DQ<10>")
	)
	(segment
		(start 71.88835 -226.82962)
		(end 71.88835 -217.640408)
		(width 0.10668)
		(layer "F.Cu")
		(net "M_A_CPU1_SA_DQ<10>")
	)
	(segment
		(start 76.963524 -230.869744)
		(end 76.298806 -230.869744)
		(width 0.0762)
		(layer "F.Cu")
		(net "M_A_CPU1_SA_DQ<10>")
	)
	(segment
		(start 71.88835 -217.640408)
		(end 62.20841 -207.960468)
		(width 0.10668)
		(layer "F.Cu")
		(net "M_A_CPU1_SA_DQ<10>")
	)
	(segment
		(start 62.20841 -207.960468)
		(end 60.67044 -207.960468)
		(width 0.10668)
		(layer "F.Cu")
		(net "M_A_CPU1_SA_DQ<10>")
	)
	(segment
		(start 57.705244 -207.535272)
		(end 55.328058 -207.535272)
		(width 0.101346)
		(layer "F.Cu")
		(net "M_A_CPU1_SA_DQ<10>")
	)
	(segment
		(start 58.13044 -207.960468)
		(end 57.705244 -207.535272)
		(width 0.101346)
		(layer "F.Cu")
		(net "M_A_CPU1_SA_DQ<10>")
	)
	(arc
		(start 77.750924 -230.657654)
		(mid 77.371256 -230.815793)
		(end 76.963524 -230.869744)
		(width 0.0762)
		(layer "F.Cu")
		(net "M_A_CPU1_SA_DQ<10>")
	)
	(arc
		(start 78.030832 -230.820214)
		(mid 78.030672 -230.673653)
		(end 77.899006 -230.609394)
		(width 0.0762)
		(layer "F.Cu")
		(net "M_A_CPU1_SA_DQ<10>")
	)
	(arc
		(start 77.899006 -230.609394)
		(mid 77.826998 -230.624176)
		(end 77.759306 -230.652828)
		(width 0.0762)
		(layer "F.Cu")
		(net "M_A_CPU1_SA_DQ<10>")
	)
	(segment
		(start 68.318888 -205.415388)
		(end 68.318888 -205.264512)
		(width 0.10668)
		(layer "F.Cu")
		(net "M_A_CPU1_SA_DQ<0>")
	)
	(segment
		(start 76.61529 -214.206074)
		(end 68.147184 -205.737968)
		(width 0.10668)
		(layer "F.Cu")
		(net "M_A_CPU1_SA_DQ<0>")
	)
	(segment
		(start 76.61529 -224.150428)
		(end 76.61529 -214.206074)
		(width 0.10668)
		(layer "F.Cu")
		(net "M_A_CPU1_SA_DQ<0>")
	)
	(segment
		(start 66.061336 -203.157836)
		(end 66.061336 -203.00696)
		(width 0.10668)
		(layer "F.Cu")
		(net "M_A_CPU1_SA_DQ<0>")
	)
	(segment
		(start 66.494406 -203.44003)
		(end 66.34353 -203.44003)
		(width 0.10668)
		(layer "F.Cu")
		(net "M_A_CPU1_SA_DQ<0>")
	)
	(segment
		(start 68.147184 -205.737968)
		(end 68.147184 -205.587092)
		(width 0.10668)
		(layer "F.Cu")
		(net "M_A_CPU1_SA_DQ<0>")
	)
	(segment
		(start 67.018408 -204.458316)
		(end 67.190112 -204.286612)
		(width 0.10668)
		(layer "F.Cu")
		(net "M_A_CPU1_SA_DQ<0>")
	)
	(segment
		(start 67.86499 -205.304898)
		(end 67.714114 -205.304898)
		(width 0.10668)
		(layer "F.Cu")
		(net "M_A_CPU1_SA_DQ<0>")
	)
	(segment
		(start 68.318888 -205.264512)
		(end 68.18757 -205.133194)
		(width 0.10668)
		(layer "F.Cu")
		(net "M_A_CPU1_SA_DQ<0>")
	)
	(segment
		(start 66.34353 -203.44003)
		(end 66.171826 -203.611734)
		(width 0.10668)
		(layer "F.Cu")
		(net "M_A_CPU1_SA_DQ<0>")
	)
	(segment
		(start 67.7545 -204.700124)
		(end 67.623182 -204.568806)
		(width 0.10668)
		(layer "F.Cu")
		(net "M_A_CPU1_SA_DQ<0>")
	)
	(segment
		(start 65.325244 -202.765152)
		(end 65.496948 -202.593448)
		(width 0.10668)
		(layer "F.Cu")
		(net "M_A_CPU1_SA_DQ<0>")
	)
	(segment
		(start 67.018408 -204.609192)
		(end 67.018408 -204.458316)
		(width 0.10668)
		(layer "F.Cu")
		(net "M_A_CPU1_SA_DQ<0>")
	)
	(segment
		(start 67.300602 -204.74051)
		(end 67.149726 -204.74051)
		(width 0.10668)
		(layer "F.Cu")
		(net "M_A_CPU1_SA_DQ<0>")
	)
	(segment
		(start 65.889632 -203.480416)
		(end 65.889632 -203.32954)
		(width 0.10668)
		(layer "F.Cu")
		(net "M_A_CPU1_SA_DQ<0>")
	)
	(segment
		(start 68.036694 -205.133194)
		(end 67.86499 -205.304898)
		(width 0.10668)
		(layer "F.Cu")
		(net "M_A_CPU1_SA_DQ<0>")
	)
	(segment
		(start 67.190112 -204.135736)
		(end 67.058794 -204.004418)
		(width 0.10668)
		(layer "F.Cu")
		(net "M_A_CPU1_SA_DQ<0>")
	)
	(segment
		(start 66.625724 -203.571348)
		(end 66.494406 -203.44003)
		(width 0.10668)
		(layer "F.Cu")
		(net "M_A_CPU1_SA_DQ<0>")
	)
	(segment
		(start 65.607438 -203.047346)
		(end 65.456562 -203.047346)
		(width 0.10668)
		(layer "F.Cu")
		(net "M_A_CPU1_SA_DQ<0>")
	)
	(segment
		(start 64.892174 -202.482958)
		(end 64.687704 -202.278488)
		(width 0.10668)
		(layer "F.Cu")
		(net "M_A_CPU1_SA_DQ<0>")
	)
	(segment
		(start 64.687704 -201.566526)
		(end 60.456572 -197.335394)
		(width 0.10668)
		(layer "F.Cu")
		(net "M_A_CPU1_SA_DQ<0>")
	)
	(segment
		(start 65.214754 -202.311254)
		(end 65.04305 -202.482958)
		(width 0.10668)
		(layer "F.Cu")
		(net "M_A_CPU1_SA_DQ<0>")
	)
	(segment
		(start 66.625724 -203.722224)
		(end 66.625724 -203.571348)
		(width 0.10668)
		(layer "F.Cu")
		(net "M_A_CPU1_SA_DQ<0>")
	)
	(segment
		(start 60.456572 -197.335394)
		(end 59.428126 -197.335394)
		(width 0.10668)
		(layer "F.Cu")
		(net "M_A_CPU1_SA_DQ<0>")
	)
	(segment
		(start 67.582796 -205.022704)
		(end 67.7545 -204.851)
		(width 0.10668)
		(layer "F.Cu")
		(net "M_A_CPU1_SA_DQ<0>")
	)
	(segment
		(start 67.7545 -204.851)
		(end 67.7545 -204.700124)
		(width 0.10668)
		(layer "F.Cu")
		(net "M_A_CPU1_SA_DQ<0>")
	)
	(segment
		(start 66.907918 -204.004418)
		(end 66.736214 -204.176122)
		(width 0.10668)
		(layer "F.Cu")
		(net "M_A_CPU1_SA_DQ<0>")
	)
	(segment
		(start 67.149726 -204.74051)
		(end 67.018408 -204.609192)
		(width 0.10668)
		(layer "F.Cu")
		(net "M_A_CPU1_SA_DQ<0>")
	)
	(segment
		(start 65.779142 -202.875642)
		(end 65.607438 -203.047346)
		(width 0.10668)
		(layer "F.Cu")
		(net "M_A_CPU1_SA_DQ<0>")
	)
	(segment
		(start 66.585338 -204.176122)
		(end 66.45402 -204.044804)
		(width 0.10668)
		(layer "F.Cu")
		(net "M_A_CPU1_SA_DQ<0>")
	)
	(segment
		(start 77.952092 -225.014282)
		(end 77.771244 -225.014282)
		(width 0.0762)
		(layer "F.Cu")
		(net "M_A_CPU1_SA_DQ<0>")
	)
	(segment
		(start 67.623182 -204.568806)
		(end 67.472306 -204.568806)
		(width 0.10668)
		(layer "F.Cu")
		(net "M_A_CPU1_SA_DQ<0>")
	)
	(segment
		(start 66.45402 -204.044804)
		(end 66.45402 -203.893928)
		(width 0.10668)
		(layer "F.Cu")
		(net "M_A_CPU1_SA_DQ<0>")
	)
	(segment
		(start 66.171826 -203.611734)
		(end 66.02095 -203.611734)
		(width 0.10668)
		(layer "F.Cu")
		(net "M_A_CPU1_SA_DQ<0>")
	)
	(segment
		(start 76.862686 -224.397824)
		(end 76.61529 -224.150428)
		(width 0.0762)
		(layer "F.Cu")
		(net "M_A_CPU1_SA_DQ<0>")
	)
	(segment
		(start 68.147184 -205.587092)
		(end 68.318888 -205.415388)
		(width 0.10668)
		(layer "F.Cu")
		(net "M_A_CPU1_SA_DQ<0>")
	)
	(segment
		(start 67.190112 -204.286612)
		(end 67.190112 -204.135736)
		(width 0.10668)
		(layer "F.Cu")
		(net "M_A_CPU1_SA_DQ<0>")
	)
	(segment
		(start 65.36563 -202.311254)
		(end 65.214754 -202.311254)
		(width 0.10668)
		(layer "F.Cu")
		(net "M_A_CPU1_SA_DQ<0>")
	)
	(segment
		(start 67.582796 -205.17358)
		(end 67.582796 -205.022704)
		(width 0.10668)
		(layer "F.Cu")
		(net "M_A_CPU1_SA_DQ<0>")
	)
	(segment
		(start 65.496948 -202.593448)
		(end 65.496948 -202.442572)
		(width 0.10668)
		(layer "F.Cu")
		(net "M_A_CPU1_SA_DQ<0>")
	)
	(segment
		(start 66.02095 -203.611734)
		(end 65.889632 -203.480416)
		(width 0.10668)
		(layer "F.Cu")
		(net "M_A_CPU1_SA_DQ<0>")
	)
	(segment
		(start 66.736214 -204.176122)
		(end 66.585338 -204.176122)
		(width 0.10668)
		(layer "F.Cu")
		(net "M_A_CPU1_SA_DQ<0>")
	)
	(segment
		(start 77.490066 -224.733104)
		(end 77.391006 -224.733104)
		(width 0.0762)
		(layer "F.Cu")
		(net "M_A_CPU1_SA_DQ<0>")
	)
	(segment
		(start 67.058794 -204.004418)
		(end 66.907918 -204.004418)
		(width 0.10668)
		(layer "F.Cu")
		(net "M_A_CPU1_SA_DQ<0>")
	)
	(segment
		(start 65.456562 -203.047346)
		(end 65.325244 -202.916028)
		(width 0.10668)
		(layer "F.Cu")
		(net "M_A_CPU1_SA_DQ<0>")
	)
	(segment
		(start 65.04305 -202.482958)
		(end 64.892174 -202.482958)
		(width 0.10668)
		(layer "F.Cu")
		(net "M_A_CPU1_SA_DQ<0>")
	)
	(segment
		(start 66.061336 -203.00696)
		(end 65.930018 -202.875642)
		(width 0.10668)
		(layer "F.Cu")
		(net "M_A_CPU1_SA_DQ<0>")
	)
	(segment
		(start 66.45402 -203.893928)
		(end 66.625724 -203.722224)
		(width 0.10668)
		(layer "F.Cu")
		(net "M_A_CPU1_SA_DQ<0>")
	)
	(segment
		(start 65.325244 -202.916028)
		(end 65.325244 -202.765152)
		(width 0.10668)
		(layer "F.Cu")
		(net "M_A_CPU1_SA_DQ<0>")
	)
	(segment
		(start 65.496948 -202.442572)
		(end 65.36563 -202.311254)
		(width 0.10668)
		(layer "F.Cu")
		(net "M_A_CPU1_SA_DQ<0>")
	)
	(segment
		(start 64.687704 -202.278488)
		(end 64.687704 -201.566526)
		(width 0.10668)
		(layer "F.Cu")
		(net "M_A_CPU1_SA_DQ<0>")
	)
	(segment
		(start 67.472306 -204.568806)
		(end 67.300602 -204.74051)
		(width 0.10668)
		(layer "F.Cu")
		(net "M_A_CPU1_SA_DQ<0>")
	)
	(segment
		(start 65.930018 -202.875642)
		(end 65.779142 -202.875642)
		(width 0.10668)
		(layer "F.Cu")
		(net "M_A_CPU1_SA_DQ<0>")
	)
	(segment
		(start 65.889632 -203.32954)
		(end 66.061336 -203.157836)
		(width 0.10668)
		(layer "F.Cu")
		(net "M_A_CPU1_SA_DQ<0>")
	)
	(segment
		(start 77.055726 -224.397824)
		(end 76.862686 -224.397824)
		(width 0.0762)
		(layer "F.Cu")
		(net "M_A_CPU1_SA_DQ<0>")
	)
	(segment
		(start 77.391006 -224.733104)
		(end 77.055726 -224.397824)
		(width 0.0762)
		(layer "F.Cu")
		(net "M_A_CPU1_SA_DQ<0>")
	)
	(segment
		(start 67.714114 -205.304898)
		(end 67.582796 -205.17358)
		(width 0.10668)
		(layer "F.Cu")
		(net "M_A_CPU1_SA_DQ<0>")
	)
	(segment
		(start 68.18757 -205.133194)
		(end 68.036694 -205.133194)
		(width 0.10668)
		(layer "F.Cu")
		(net "M_A_CPU1_SA_DQ<0>")
	)
	(segment
		(start 77.771244 -225.014282)
		(end 77.490066 -224.733104)
		(width 0.0762)
		(layer "F.Cu")
		(net "M_A_CPU1_SA_DQ<0>")
	)
	(arc
		(start 78.408022 -225.310446)
		(mid 78.195938 -225.137914)
		(end 77.952092 -225.014282)
		(width 0.0762)
		(layer "F.Cu")
		(net "M_A_CPU1_SA_DQ<0>")
	)
	(segment
		(start 63.35522 -251.429266)
		(end 61.44895 -249.522996)
		(width 0.10668)
		(layer "F.Cu")
		(net "M_A_CPU1_SA_CS_N<1>")
	)
	(segment
		(start 57.705498 -246.63527)
		(end 55.328058 -246.63527)
		(width 0.101346)
		(layer "F.Cu")
		(net "M_A_CPU1_SA_CS_N<1>")
	)
	(segment
		(start 79.347822 -252.850142)
		(end 79.452978 -252.669294)
		(width 0.0762)
		(layer "F.Cu")
		(net "M_A_CPU1_SA_CS_N<1>")
	)
	(segment
		(start 79.168244 -252.523498)
		(end 79.160878 -252.527816)
		(width 0.0762)
		(layer "F.Cu")
		(net "M_A_CPU1_SA_CS_N<1>")
	)
	(segment
		(start 79.347822 -252.850396)
		(end 79.347822 -252.850142)
		(width 0.0762)
		(layer "F.Cu")
		(net "M_A_CPU1_SA_CS_N<1>")
	)
	(segment
		(start 60.432696 -247.060212)
		(end 58.13044 -247.060212)
		(width 0.101346)
		(layer "F.Cu")
		(net "M_A_CPU1_SA_CS_N<1>")
	)
	(segment
		(start 77.440028 -252.469904)
		(end 76.687426 -252.469904)
		(width 0.0762)
		(layer "F.Cu")
		(net "M_A_CPU1_SA_CS_N<1>")
	)
	(segment
		(start 58.13044 -247.060212)
		(end 57.705498 -246.63527)
		(width 0.101346)
		(layer "F.Cu")
		(net "M_A_CPU1_SA_CS_N<1>")
	)
	(segment
		(start 76.687426 -252.469904)
		(end 76.425806 -252.208284)
		(width 0.10668)
		(layer "F.Cu")
		(net "M_A_CPU1_SA_CS_N<1>")
	)
	(segment
		(start 61.44895 -249.522996)
		(end 61.44895 -248.923302)
		(width 0.10668)
		(layer "F.Cu")
		(net "M_A_CPU1_SA_CS_N<1>")
	)
	(segment
		(start 79.16926 -252.52299)
		(end 79.168244 -252.523498)
		(width 0.0762)
		(layer "F.Cu")
		(net "M_A_CPU1_SA_CS_N<1>")
	)
	(segment
		(start 61.44895 -248.923302)
		(end 60.74537 -248.219722)
		(width 0.10668)
		(layer "F.Cu")
		(net "M_A_CPU1_SA_CS_N<1>")
	)
	(segment
		(start 76.425806 -252.208284)
		(end 73.579482 -252.208284)
		(width 0.10668)
		(layer "F.Cu")
		(net "M_A_CPU1_SA_CS_N<1>")
	)
	(segment
		(start 60.74537 -247.372886)
		(end 60.432696 -247.060212)
		(width 0.101346)
		(layer "F.Cu")
		(net "M_A_CPU1_SA_CS_N<1>")
	)
	(segment
		(start 72.800464 -251.429266)
		(end 63.35522 -251.429266)
		(width 0.10668)
		(layer "F.Cu")
		(net "M_A_CPU1_SA_CS_N<1>")
	)
	(segment
		(start 60.74537 -248.219722)
		(end 60.74537 -247.372886)
		(width 0.10668)
		(layer "F.Cu")
		(net "M_A_CPU1_SA_CS_N<1>")
	)
	(segment
		(start 73.579482 -252.208284)
		(end 72.800464 -251.429266)
		(width 0.10668)
		(layer "F.Cu")
		(net "M_A_CPU1_SA_CS_N<1>")
	)
	(segment
		(start 78.594966 -252.527816)
		(end 78.586584 -252.52299)
		(width 0.0762)
		(layer "F.Cu")
		(net "M_A_CPU1_SA_CS_N<1>")
	)
	(arc
		(start 79.349346 -252.477524)
		(mid 79.256422 -252.488847)
		(end 79.16926 -252.52299)
		(width 0.0762)
		(layer "F.Cu")
		(net "M_A_CPU1_SA_CS_N<1>")
	)
	(arc
		(start 78.586584 -252.52299)
		(mid 78.403076 -252.477496)
		(end 78.220824 -252.527816)
		(width 0.0762)
		(layer "F.Cu")
		(net "M_A_CPU1_SA_CS_N<1>")
	)
	(arc
		(start 77.654912 -252.527816)
		(mid 77.55131 -252.484596)
		(end 77.440028 -252.469904)
		(width 0.0762)
		(layer "F.Cu")
		(net "M_A_CPU1_SA_CS_N<1>")
	)
	(arc
		(start 79.160878 -252.527816)
		(mid 78.877922 -252.603993)
		(end 78.594966 -252.527816)
		(width 0.0762)
		(layer "F.Cu")
		(net "M_A_CPU1_SA_CS_N<1>")
	)
	(arc
		(start 78.220824 -252.527816)
		(mid 77.937868 -252.603993)
		(end 77.654912 -252.527816)
		(width 0.0762)
		(layer "F.Cu")
		(net "M_A_CPU1_SA_CS_N<1>")
	)
	(arc
		(start 79.452978 -252.669294)
		(mid 79.444041 -252.55027)
		(end 79.349346 -252.477524)
		(width 0.0762)
		(layer "F.Cu")
		(net "M_A_CPU1_SA_CS_N<1>")
	)
	(segment
		(start 76.308966 -251.867924)
		(end 75.629516 -251.867924)
		(width 0.10668)
		(layer "F.Cu")
		(net "M_A_CPU1_SA_CS_N<0>")
	)
	(segment
		(start 74.618088 -251.370846)
		(end 74.432414 -251.370846)
		(width 0.10668)
		(layer "F.Cu")
		(net "M_A_CPU1_SA_CS_N<0>")
	)
	(segment
		(start 59.577986 -245.935246)
		(end 59.428126 -245.785386)
		(width 0.10668)
		(layer "F.Cu")
		(net "M_A_CPU1_SA_CS_N<0>")
	)
	(segment
		(start 75.230482 -251.370846)
		(end 75.123802 -251.477526)
		(width 0.10668)
		(layer "F.Cu")
		(net "M_A_CPU1_SA_CS_N<0>")
	)
	(segment
		(start 74.325734 -251.477526)
		(end 74.325734 -251.761244)
		(width 0.10668)
		(layer "F.Cu")
		(net "M_A_CPU1_SA_CS_N<0>")
	)
	(segment
		(start 72.941688 -251.088906)
		(end 63.496444 -251.088906)
		(width 0.10668)
		(layer "F.Cu")
		(net "M_A_CPU1_SA_CS_N<0>")
	)
	(segment
		(start 77.759306 -251.712984)
		(end 77.750924 -251.71781)
		(width 0.0762)
		(layer "F.Cu")
		(net "M_A_CPU1_SA_CS_N<0>")
	)
	(segment
		(start 61.08573 -246.923306)
		(end 60.210192 -246.047768)
		(width 0.101346)
		(layer "F.Cu")
		(net "M_A_CPU1_SA_CS_N<0>")
	)
	(segment
		(start 75.629516 -251.867924)
		(end 75.522836 -251.761244)
		(width 0.10668)
		(layer "F.Cu")
		(net "M_A_CPU1_SA_CS_N<0>")
	)
	(segment
		(start 75.017122 -251.867924)
		(end 74.831448 -251.867924)
		(width 0.10668)
		(layer "F.Cu")
		(net "M_A_CPU1_SA_CS_N<0>")
	)
	(segment
		(start 60.09767 -245.935246)
		(end 59.577986 -245.935246)
		(width 0.10668)
		(layer "F.Cu")
		(net "M_A_CPU1_SA_CS_N<0>")
	)
	(segment
		(start 74.219054 -251.867924)
		(end 73.720706 -251.867924)
		(width 0.10668)
		(layer "F.Cu")
		(net "M_A_CPU1_SA_CS_N<0>")
	)
	(segment
		(start 77.19441 -251.867924)
		(end 76.308966 -251.867924)
		(width 0.0762)
		(layer "F.Cu")
		(net "M_A_CPU1_SA_CS_N<0>")
	)
	(segment
		(start 60.210192 -246.047768)
		(end 60.09767 -245.935246)
		(width 0.10668)
		(layer "F.Cu")
		(net "M_A_CPU1_SA_CS_N<0>")
	)
	(segment
		(start 61.78931 -248.781824)
		(end 61.08573 -248.078244)
		(width 0.10668)
		(layer "F.Cu")
		(net "M_A_CPU1_SA_CS_N<0>")
	)
	(segment
		(start 61.78931 -249.381772)
		(end 61.78931 -248.781824)
		(width 0.10668)
		(layer "F.Cu")
		(net "M_A_CPU1_SA_CS_N<0>")
	)
	(segment
		(start 74.724768 -251.477526)
		(end 74.618088 -251.370846)
		(width 0.10668)
		(layer "F.Cu")
		(net "M_A_CPU1_SA_CS_N<0>")
	)
	(segment
		(start 73.720706 -251.867924)
		(end 72.941688 -251.088906)
		(width 0.10668)
		(layer "F.Cu")
		(net "M_A_CPU1_SA_CS_N<0>")
	)
	(segment
		(start 77.937868 -252.04039)
		(end 78.030832 -251.88037)
		(width 0.0762)
		(layer "F.Cu")
		(net "M_A_CPU1_SA_CS_N<0>")
	)
	(segment
		(start 75.123802 -251.761244)
		(end 75.017122 -251.867924)
		(width 0.10668)
		(layer "F.Cu")
		(net "M_A_CPU1_SA_CS_N<0>")
	)
	(segment
		(start 75.522836 -251.477526)
		(end 75.416156 -251.370846)
		(width 0.10668)
		(layer "F.Cu")
		(net "M_A_CPU1_SA_CS_N<0>")
	)
	(segment
		(start 75.123802 -251.477526)
		(end 75.123802 -251.761244)
		(width 0.10668)
		(layer "F.Cu")
		(net "M_A_CPU1_SA_CS_N<0>")
	)
	(segment
		(start 74.325734 -251.761244)
		(end 74.219054 -251.867924)
		(width 0.10668)
		(layer "F.Cu")
		(net "M_A_CPU1_SA_CS_N<0>")
	)
	(segment
		(start 74.724768 -251.761244)
		(end 74.724768 -251.477526)
		(width 0.10668)
		(layer "F.Cu")
		(net "M_A_CPU1_SA_CS_N<0>")
	)
	(segment
		(start 75.522836 -251.761244)
		(end 75.522836 -251.477526)
		(width 0.10668)
		(layer "F.Cu")
		(net "M_A_CPU1_SA_CS_N<0>")
	)
	(segment
		(start 74.432414 -251.370846)
		(end 74.325734 -251.477526)
		(width 0.10668)
		(layer "F.Cu")
		(net "M_A_CPU1_SA_CS_N<0>")
	)
	(segment
		(start 63.496444 -251.088906)
		(end 61.78931 -249.381772)
		(width 0.10668)
		(layer "F.Cu")
		(net "M_A_CPU1_SA_CS_N<0>")
	)
	(segment
		(start 75.416156 -251.370846)
		(end 75.230482 -251.370846)
		(width 0.10668)
		(layer "F.Cu")
		(net "M_A_CPU1_SA_CS_N<0>")
	)
	(segment
		(start 61.08573 -248.078244)
		(end 61.08573 -246.923306)
		(width 0.10668)
		(layer "F.Cu")
		(net "M_A_CPU1_SA_CS_N<0>")
	)
	(segment
		(start 74.831448 -251.867924)
		(end 74.724768 -251.761244)
		(width 0.10668)
		(layer "F.Cu")
		(net "M_A_CPU1_SA_CS_N<0>")
	)
	(arc
		(start 77.899006 -251.66955)
		(mid 77.826998 -251.684332)
		(end 77.759306 -251.712984)
		(width 0.0762)
		(layer "F.Cu")
		(net "M_A_CPU1_SA_CS_N<0>")
	)
	(arc
		(start 78.030832 -251.88037)
		(mid 78.030672 -251.733809)
		(end 77.899006 -251.66955)
		(width 0.0762)
		(layer "F.Cu")
		(net "M_A_CPU1_SA_CS_N<0>")
	)
	(arc
		(start 77.750924 -251.71781)
		(mid 77.482607 -251.829707)
		(end 77.19441 -251.867924)
		(width 0.0762)
		(layer "F.Cu")
		(net "M_A_CPU1_SA_CS_N<0>")
	)
	(segment
		(start 62.57417 -247.461024)
		(end 62.57417 -246.266462)
		(width 0.10668)
		(layer "F.Cu")
		(net "M_A_CPU1_SA_CB<7>")
	)
	(segment
		(start 79.168244 -249.283474)
		(end 79.160878 -249.287792)
		(width 0.0762)
		(layer "F.Cu")
		(net "M_A_CPU1_SA_CB<7>")
	)
	(segment
		(start 60.583572 -242.985544)
		(end 60.408312 -242.810284)
		(width 0.101346)
		(layer "F.Cu")
		(net "M_A_CPU1_SA_CB<7>")
	)
	(segment
		(start 74.481182 -249.559064)
		(end 74.211942 -249.289824)
		(width 0.10668)
		(layer "F.Cu")
		(net "M_A_CPU1_SA_CB<7>")
	)
	(segment
		(start 79.16926 -249.282966)
		(end 79.168244 -249.283474)
		(width 0.0762)
		(layer "F.Cu")
		(net "M_A_CPU1_SA_CB<7>")
	)
	(segment
		(start 76.308966 -249.559064)
		(end 74.481182 -249.559064)
		(width 0.10668)
		(layer "F.Cu")
		(net "M_A_CPU1_SA_CB<7>")
	)
	(segment
		(start 61.02223 -243.424202)
		(end 60.583572 -242.985544)
		(width 0.10668)
		(layer "F.Cu")
		(net "M_A_CPU1_SA_CB<7>")
	)
	(segment
		(start 63.27775 -248.164604)
		(end 62.57417 -247.461024)
		(width 0.10668)
		(layer "F.Cu")
		(net "M_A_CPU1_SA_CB<7>")
	)
	(segment
		(start 61.02223 -244.714522)
		(end 61.02223 -243.424202)
		(width 0.10668)
		(layer "F.Cu")
		(net "M_A_CPU1_SA_CB<7>")
	)
	(segment
		(start 77.44587 -249.231404)
		(end 76.636626 -249.231404)
		(width 0.0762)
		(layer "F.Cu")
		(net "M_A_CPU1_SA_CB<7>")
	)
	(segment
		(start 60.408312 -242.810284)
		(end 58.13044 -242.810284)
		(width 0.101346)
		(layer "F.Cu")
		(net "M_A_CPU1_SA_CB<7>")
	)
	(segment
		(start 63.27775 -248.757694)
		(end 63.27775 -248.164604)
		(width 0.10668)
		(layer "F.Cu")
		(net "M_A_CPU1_SA_CB<7>")
	)
	(segment
		(start 66.48831 -249.600466)
		(end 64.120522 -249.600466)
		(width 0.10668)
		(layer "F.Cu")
		(net "M_A_CPU1_SA_CB<7>")
	)
	(segment
		(start 64.120522 -249.600466)
		(end 63.27775 -248.757694)
		(width 0.10668)
		(layer "F.Cu")
		(net "M_A_CPU1_SA_CB<7>")
	)
	(segment
		(start 78.594966 -249.287792)
		(end 78.586584 -249.282966)
		(width 0.0762)
		(layer "F.Cu")
		(net "M_A_CPU1_SA_CB<7>")
	)
	(segment
		(start 74.211942 -249.289824)
		(end 67.238372 -249.289824)
		(width 0.10668)
		(layer "F.Cu")
		(net "M_A_CPU1_SA_CB<7>")
	)
	(segment
		(start 62.57417 -246.266462)
		(end 61.02223 -244.714522)
		(width 0.10668)
		(layer "F.Cu")
		(net "M_A_CPU1_SA_CB<7>")
	)
	(segment
		(start 57.104534 -243.235226)
		(end 55.328058 -243.235226)
		(width 0.101346)
		(layer "F.Cu")
		(net "M_A_CPU1_SA_CB<7>")
	)
	(segment
		(start 58.13044 -242.810284)
		(end 57.104534 -243.235226)
		(width 0.101346)
		(layer "F.Cu")
		(net "M_A_CPU1_SA_CB<7>")
	)
	(segment
		(start 79.347822 -249.610372)
		(end 79.347822 -249.610118)
		(width 0.0762)
		(layer "F.Cu")
		(net "M_A_CPU1_SA_CB<7>")
	)
	(segment
		(start 79.347822 -249.610118)
		(end 79.452978 -249.42927)
		(width 0.0762)
		(layer "F.Cu")
		(net "M_A_CPU1_SA_CB<7>")
	)
	(segment
		(start 76.636626 -249.231404)
		(end 76.308966 -249.559064)
		(width 0.0762)
		(layer "F.Cu")
		(net "M_A_CPU1_SA_CB<7>")
	)
	(segment
		(start 67.238372 -249.289824)
		(end 66.48831 -249.600466)
		(width 0.10668)
		(layer "F.Cu")
		(net "M_A_CPU1_SA_CB<7>")
	)
	(arc
		(start 79.452978 -249.42927)
		(mid 79.444041 -249.310246)
		(end 79.349346 -249.2375)
		(width 0.0762)
		(layer "F.Cu")
		(net "M_A_CPU1_SA_CB<7>")
	)
	(arc
		(start 77.654912 -249.287792)
		(mid 77.55412 -249.245786)
		(end 77.44587 -249.231404)
		(width 0.0762)
		(layer "F.Cu")
		(net "M_A_CPU1_SA_CB<7>")
	)
	(arc
		(start 78.586584 -249.282966)
		(mid 78.403076 -249.237472)
		(end 78.220824 -249.287792)
		(width 0.0762)
		(layer "F.Cu")
		(net "M_A_CPU1_SA_CB<7>")
	)
	(arc
		(start 79.349346 -249.2375)
		(mid 79.256422 -249.248823)
		(end 79.16926 -249.282966)
		(width 0.0762)
		(layer "F.Cu")
		(net "M_A_CPU1_SA_CB<7>")
	)
	(arc
		(start 79.160878 -249.287792)
		(mid 78.877922 -249.363969)
		(end 78.594966 -249.287792)
		(width 0.0762)
		(layer "F.Cu")
		(net "M_A_CPU1_SA_CB<7>")
	)
	(arc
		(start 78.220824 -249.287792)
		(mid 77.937868 -249.363969)
		(end 77.654912 -249.287792)
		(width 0.0762)
		(layer "F.Cu")
		(net "M_A_CPU1_SA_CB<7>")
	)
	(segment
		(start 64.405002 -247.830594)
		(end 64.405002 -247.134126)
		(width 0.10668)
		(layer "F.Cu")
		(net "M_A_CPU1_SA_CB<6>")
	)
	(segment
		(start 74.74077 -248.855484)
		(end 74.49439 -248.609104)
		(width 0.10668)
		(layer "F.Cu")
		(net "M_A_CPU1_SA_CB<6>")
	)
	(segment
		(start 57.169558 -241.782346)
		(end 57.052718 -241.899186)
		(width 0.101346)
		(layer "F.Cu")
		(net "M_A_CPU1_SA_CB<6>")
	)
	(segment
		(start 63.540132 -246.859552)
		(end 63.389256 -246.859552)
		(width 0.10668)
		(layer "F.Cu")
		(net "M_A_CPU1_SA_CB<6>")
	)
	(segment
		(start 63.257938 -246.577358)
		(end 63.477648 -246.357648)
		(width 0.10668)
		(layer "F.Cu")
		(net "M_A_CPU1_SA_CB<6>")
	)
	(segment
		(start 63.910718 -246.639842)
		(end 63.759842 -246.639842)
		(width 0.10668)
		(layer "F.Cu")
		(net "M_A_CPU1_SA_CB<6>")
	)
	(segment
		(start 63.257938 -246.728234)
		(end 63.257938 -246.577358)
		(width 0.10668)
		(layer "F.Cu")
		(net "M_A_CPU1_SA_CB<6>")
	)
	(segment
		(start 58.13044 -241.9604)
		(end 57.705244 -241.535204)
		(width 0.101346)
		(layer "F.Cu")
		(net "M_A_CPU1_SA_CB<6>")
	)
	(segment
		(start 74.49439 -248.609104)
		(end 65.183512 -248.609104)
		(width 0.10668)
		(layer "F.Cu")
		(net "M_A_CPU1_SA_CB<6>")
	)
	(segment
		(start 56.770524 -241.652044)
		(end 56.653684 -241.535204)
		(width 0.101346)
		(layer "F.Cu")
		(net "M_A_CPU1_SA_CB<6>")
	)
	(segment
		(start 63.477648 -246.357648)
		(end 63.477648 -246.206772)
		(width 0.10668)
		(layer "F.Cu")
		(net "M_A_CPU1_SA_CB<6>")
	)
	(segment
		(start 57.169558 -241.652044)
		(end 57.169558 -241.782346)
		(width 0.101346)
		(layer "F.Cu")
		(net "M_A_CPU1_SA_CB<6>")
	)
	(segment
		(start 61.70295 -244.432074)
		(end 61.70295 -242.99291)
		(width 0.10668)
		(layer "F.Cu")
		(net "M_A_CPU1_SA_CB<6>")
	)
	(segment
		(start 63.389256 -246.859552)
		(end 63.257938 -246.728234)
		(width 0.10668)
		(layer "F.Cu")
		(net "M_A_CPU1_SA_CB<6>")
	)
	(segment
		(start 76.098146 -248.855484)
		(end 75.981306 -248.855484)
		(width 0.0762)
		(layer "F.Cu")
		(net "M_A_CPU1_SA_CB<6>")
	)
	(segment
		(start 56.653684 -241.535204)
		(end 55.328058 -241.535204)
		(width 0.101346)
		(layer "F.Cu")
		(net "M_A_CPU1_SA_CB<6>")
	)
	(segment
		(start 57.052718 -241.899186)
		(end 56.887364 -241.899186)
		(width 0.101346)
		(layer "F.Cu")
		(net "M_A_CPU1_SA_CB<6>")
	)
	(segment
		(start 56.770524 -241.782346)
		(end 56.770524 -241.652044)
		(width 0.101346)
		(layer "F.Cu")
		(net "M_A_CPU1_SA_CB<6>")
	)
	(segment
		(start 61.70295 -242.99291)
		(end 60.67044 -241.9604)
		(width 0.10668)
		(layer "F.Cu")
		(net "M_A_CPU1_SA_CB<6>")
	)
	(segment
		(start 57.286398 -241.535204)
		(end 57.169558 -241.652044)
		(width 0.101346)
		(layer "F.Cu")
		(net "M_A_CPU1_SA_CB<6>")
	)
	(segment
		(start 64.405002 -247.134126)
		(end 63.910718 -246.639842)
		(width 0.10668)
		(layer "F.Cu")
		(net "M_A_CPU1_SA_CB<6>")
	)
	(segment
		(start 77.467968 -248.553986)
		(end 76.399644 -248.553986)
		(width 0.0762)
		(layer "F.Cu")
		(net "M_A_CPU1_SA_CB<6>")
	)
	(segment
		(start 56.887364 -241.899186)
		(end 56.770524 -241.782346)
		(width 0.101346)
		(layer "F.Cu")
		(net "M_A_CPU1_SA_CB<6>")
	)
	(segment
		(start 75.981306 -248.855484)
		(end 74.74077 -248.855484)
		(width 0.10668)
		(layer "F.Cu")
		(net "M_A_CPU1_SA_CB<6>")
	)
	(segment
		(start 76.399644 -248.553986)
		(end 76.098146 -248.855484)
		(width 0.0762)
		(layer "F.Cu")
		(net "M_A_CPU1_SA_CB<6>")
	)
	(segment
		(start 65.183512 -248.609104)
		(end 64.405002 -247.830594)
		(width 0.10668)
		(layer "F.Cu")
		(net "M_A_CPU1_SA_CB<6>")
	)
	(segment
		(start 77.937868 -248.800366)
		(end 78.036166 -248.631202)
		(width 0.0762)
		(layer "F.Cu")
		(net "M_A_CPU1_SA_CB<6>")
	)
	(segment
		(start 63.759842 -246.639842)
		(end 63.540132 -246.859552)
		(width 0.10668)
		(layer "F.Cu")
		(net "M_A_CPU1_SA_CB<6>")
	)
	(segment
		(start 60.67044 -241.9604)
		(end 58.13044 -241.9604)
		(width 0.101346)
		(layer "F.Cu")
		(net "M_A_CPU1_SA_CB<6>")
	)
	(segment
		(start 63.477648 -246.206772)
		(end 61.70295 -244.432074)
		(width 0.10668)
		(layer "F.Cu")
		(net "M_A_CPU1_SA_CB<6>")
	)
	(segment
		(start 57.705244 -241.535204)
		(end 57.286398 -241.535204)
		(width 0.101346)
		(layer "F.Cu")
		(net "M_A_CPU1_SA_CB<6>")
	)
	(segment
		(start 77.759306 -248.47296)
		(end 77.750924 -248.477786)
		(width 0.0762)
		(layer "F.Cu")
		(net "M_A_CPU1_SA_CB<6>")
	)
	(arc
		(start 78.036166 -248.631202)
		(mid 78.027573 -248.489323)
		(end 77.898498 -248.429526)
		(width 0.0762)
		(layer "F.Cu")
		(net "M_A_CPU1_SA_CB<6>")
	)
	(arc
		(start 77.750924 -248.477786)
		(mid 77.614488 -248.534611)
		(end 77.467968 -248.553986)
		(width 0.0762)
		(layer "F.Cu")
		(net "M_A_CPU1_SA_CB<6>")
	)
	(arc
		(start 77.898498 -248.429526)
		(mid 77.82676 -248.444378)
		(end 77.759306 -248.47296)
		(width 0.0762)
		(layer "F.Cu")
		(net "M_A_CPU1_SA_CB<6>")
	)
	(segment
		(start 62.91453 -246.125238)
		(end 61.36259 -244.573298)
		(width 0.10668)
		(layer "F.Cu")
		(net "M_A_CPU1_SA_CB<5>")
	)
	(segment
		(start 64.64808 -249.260106)
		(end 64.261746 -249.260106)
		(width 0.10668)
		(layer "F.Cu")
		(net "M_A_CPU1_SA_CB<5>")
	)
	(segment
		(start 66.420492 -249.260106)
		(end 66.030602 -249.260106)
		(width 0.10668)
		(layer "F.Cu")
		(net "M_A_CPU1_SA_CB<5>")
	)
	(segment
		(start 77.759306 -249.127772)
		(end 77.750924 -249.122946)
		(width 0.0762)
		(layer "F.Cu")
		(net "M_A_CPU1_SA_CB<5>")
	)
	(segment
		(start 62.91453 -247.3198)
		(end 62.91453 -246.125238)
		(width 0.10668)
		(layer "F.Cu")
		(net "M_A_CPU1_SA_CB<5>")
	)
	(segment
		(start 66.030602 -249.260106)
		(end 65.845182 -249.074686)
		(width 0.10668)
		(layer "F.Cu")
		(net "M_A_CPU1_SA_CB<5>")
	)
	(segment
		(start 64.164718 -249.163078)
		(end 64.164718 -249.012202)
		(width 0.10668)
		(layer "F.Cu")
		(net "M_A_CPU1_SA_CB<5>")
	)
	(segment
		(start 65.446148 -249.260106)
		(end 65.232534 -249.260106)
		(width 0.10668)
		(layer "F.Cu")
		(net "M_A_CPU1_SA_CB<5>")
	)
	(segment
		(start 76.448666 -248.934224)
		(end 76.179426 -249.203464)
		(width 0.0762)
		(layer "F.Cu")
		(net "M_A_CPU1_SA_CB<5>")
	)
	(segment
		(start 63.335916 -247.59031)
		(end 63.18504 -247.59031)
		(width 0.10668)
		(layer "F.Cu")
		(net "M_A_CPU1_SA_CB<5>")
	)
	(segment
		(start 76.179426 -249.203464)
		(end 74.607166 -249.203464)
		(width 0.10668)
		(layer "F.Cu")
		(net "M_A_CPU1_SA_CB<5>")
	)
	(segment
		(start 64.064642 -247.27535)
		(end 63.933324 -247.144032)
		(width 0.10668)
		(layer "F.Cu")
		(net "M_A_CPU1_SA_CB<5>")
	)
	(segment
		(start 65.845182 -249.074686)
		(end 65.631568 -249.074686)
		(width 0.10668)
		(layer "F.Cu")
		(net "M_A_CPU1_SA_CB<5>")
	)
	(segment
		(start 65.232534 -249.260106)
		(end 65.047114 -249.074686)
		(width 0.10668)
		(layer "F.Cu")
		(net "M_A_CPU1_SA_CB<5>")
	)
	(segment
		(start 63.882524 -248.730008)
		(end 63.731648 -248.730008)
		(width 0.10668)
		(layer "F.Cu")
		(net "M_A_CPU1_SA_CB<5>")
	)
	(segment
		(start 65.047114 -249.074686)
		(end 64.8335 -249.074686)
		(width 0.10668)
		(layer "F.Cu")
		(net "M_A_CPU1_SA_CB<5>")
	)
	(segment
		(start 60.471304 -242.385342)
		(end 59.428126 -242.385342)
		(width 0.10668)
		(layer "F.Cu")
		(net "M_A_CPU1_SA_CB<5>")
	)
	(segment
		(start 63.18504 -247.59031)
		(end 62.91453 -247.3198)
		(width 0.10668)
		(layer "F.Cu")
		(net "M_A_CPU1_SA_CB<5>")
	)
	(segment
		(start 67.170554 -248.949464)
		(end 66.420492 -249.260106)
		(width 0.10668)
		(layer "F.Cu")
		(net "M_A_CPU1_SA_CB<5>")
	)
	(segment
		(start 64.164718 -249.012202)
		(end 64.559434 -248.617486)
		(width 0.10668)
		(layer "F.Cu")
		(net "M_A_CPU1_SA_CB<5>")
	)
	(segment
		(start 61.36259 -243.276628)
		(end 60.471304 -242.385342)
		(width 0.10668)
		(layer "F.Cu")
		(net "M_A_CPU1_SA_CB<5>")
	)
	(segment
		(start 63.933324 -247.144032)
		(end 63.782448 -247.143778)
		(width 0.10668)
		(layer "F.Cu")
		(net "M_A_CPU1_SA_CB<5>")
	)
	(segment
		(start 63.61811 -248.61647)
		(end 63.61811 -247.872758)
		(width 0.10668)
		(layer "F.Cu")
		(net "M_A_CPU1_SA_CB<5>")
	)
	(segment
		(start 77.050138 -248.934224)
		(end 76.448666 -248.934224)
		(width 0.0762)
		(layer "F.Cu")
		(net "M_A_CPU1_SA_CB<5>")
	)
	(segment
		(start 64.559434 -248.46661)
		(end 64.428116 -248.335292)
		(width 0.10668)
		(layer "F.Cu")
		(net "M_A_CPU1_SA_CB<5>")
	)
	(segment
		(start 74.353166 -248.949464)
		(end 67.170554 -248.949464)
		(width 0.10668)
		(layer "F.Cu")
		(net "M_A_CPU1_SA_CB<5>")
	)
	(segment
		(start 64.064642 -247.426226)
		(end 64.064642 -247.27535)
		(width 0.10668)
		(layer "F.Cu")
		(net "M_A_CPU1_SA_CB<5>")
	)
	(segment
		(start 74.607166 -249.203464)
		(end 74.353166 -248.949464)
		(width 0.10668)
		(layer "F.Cu")
		(net "M_A_CPU1_SA_CB<5>")
	)
	(segment
		(start 79.064866 -249.122692)
		(end 79.064866 -249.122946)
		(width 0.0762)
		(layer "F.Cu")
		(net "M_A_CPU1_SA_CB<5>")
	)
	(segment
		(start 63.731648 -248.730008)
		(end 63.61811 -248.61647)
		(width 0.10668)
		(layer "F.Cu")
		(net "M_A_CPU1_SA_CB<5>")
	)
	(segment
		(start 63.782448 -247.143778)
		(end 63.335916 -247.59031)
		(width 0.10668)
		(layer "F.Cu")
		(net "M_A_CPU1_SA_CB<5>")
	)
	(segment
		(start 64.261746 -249.260106)
		(end 64.164718 -249.163078)
		(width 0.10668)
		(layer "F.Cu")
		(net "M_A_CPU1_SA_CB<5>")
	)
	(segment
		(start 64.27724 -248.335292)
		(end 63.882524 -248.730008)
		(width 0.10668)
		(layer "F.Cu")
		(net "M_A_CPU1_SA_CB<5>")
	)
	(segment
		(start 64.559434 -248.617486)
		(end 64.559434 -248.46661)
		(width 0.10668)
		(layer "F.Cu")
		(net "M_A_CPU1_SA_CB<5>")
	)
	(segment
		(start 63.61811 -247.872758)
		(end 64.064642 -247.426226)
		(width 0.10668)
		(layer "F.Cu")
		(net "M_A_CPU1_SA_CB<5>")
	)
	(segment
		(start 64.428116 -248.335292)
		(end 64.27724 -248.335292)
		(width 0.10668)
		(layer "F.Cu")
		(net "M_A_CPU1_SA_CB<5>")
	)
	(segment
		(start 64.8335 -249.074686)
		(end 64.64808 -249.260106)
		(width 0.10668)
		(layer "F.Cu")
		(net "M_A_CPU1_SA_CB<5>")
	)
	(segment
		(start 65.631568 -249.074686)
		(end 65.446148 -249.260106)
		(width 0.10668)
		(layer "F.Cu")
		(net "M_A_CPU1_SA_CB<5>")
	)
	(segment
		(start 61.36259 -244.573298)
		(end 61.36259 -243.276628)
		(width 0.10668)
		(layer "F.Cu")
		(net "M_A_CPU1_SA_CB<5>")
	)
	(arc
		(start 78.125066 -249.122946)
		(mid 77.942815 -249.173296)
		(end 77.759306 -249.127772)
		(width 0.0762)
		(layer "F.Cu")
		(net "M_A_CPU1_SA_CB<5>")
	)
	(arc
		(start 79.817976 -248.800366)
		(mid 79.61396 -248.98106)
		(end 79.349346 -249.046238)
		(width 0.0762)
		(layer "F.Cu")
		(net "M_A_CPU1_SA_CB<5>")
	)
	(arc
		(start 78.690978 -249.122946)
		(mid 78.408022 -249.046769)
		(end 78.125066 -249.122946)
		(width 0.0762)
		(layer "F.Cu")
		(net "M_A_CPU1_SA_CB<5>")
	)
	(arc
		(start 79.349346 -249.046238)
		(mid 79.202025 -249.065557)
		(end 79.064866 -249.122692)
		(width 0.0762)
		(layer "F.Cu")
		(net "M_A_CPU1_SA_CB<5>")
	)
	(arc
		(start 79.064866 -249.122946)
		(mid 78.877922 -249.173201)
		(end 78.690978 -249.122946)
		(width 0.0762)
		(layer "F.Cu")
		(net "M_A_CPU1_SA_CB<5>")
	)
	(arc
		(start 77.750924 -249.122946)
		(mid 77.413014 -248.982229)
		(end 77.050138 -248.934224)
		(width 0.0762)
		(layer "F.Cu")
		(net "M_A_CPU1_SA_CB<5>")
	)
	(segment
		(start 63.773812 -246.021352)
		(end 63.773812 -245.870476)
		(width 0.10668)
		(layer "F.Cu")
		(net "M_A_CPU1_SA_CB<4>")
	)
	(segment
		(start 65.066164 -246.835676)
		(end 65.066164 -246.6848)
		(width 0.10668)
		(layer "F.Cu")
		(net "M_A_CPU1_SA_CB<4>")
	)
	(segment
		(start 65.354454 -247.977914)
		(end 65.781428 -247.55094)
		(width 0.10668)
		(layer "F.Cu")
		(net "M_A_CPU1_SA_CB<4>")
	)
	(segment
		(start 62.211966 -244.459506)
		(end 62.04331 -244.29085)
		(width 0.10668)
		(layer "F.Cu")
		(net "M_A_CPU1_SA_CB<4>")
	)
	(segment
		(start 75.931522 -248.447306)
		(end 75.71105 -248.447306)
		(width 0.10668)
		(layer "F.Cu")
		(net "M_A_CPU1_SA_CB<4>")
	)
	(segment
		(start 63.209424 -245.456964)
		(end 63.209424 -245.306088)
		(width 0.10668)
		(layer "F.Cu")
		(net "M_A_CPU1_SA_CB<4>")
	)
	(segment
		(start 76.320396 -248.363486)
		(end 76.225654 -248.268744)
		(width 0.0762)
		(layer "F.Cu")
		(net "M_A_CPU1_SA_CB<4>")
	)
	(segment
		(start 77.467968 -248.363486)
		(end 76.320396 -248.363486)
		(width 0.0762)
		(layer "F.Cu")
		(net "M_A_CPU1_SA_CB<4>")
	)
	(segment
		(start 63.090806 -244.860318)
		(end 62.92723 -245.023894)
		(width 0.10668)
		(layer "F.Cu")
		(net "M_A_CPU1_SA_CB<4>")
	)
	(segment
		(start 76.225654 -248.268744)
		(end 76.110084 -248.268744)
		(width 0.10668)
		(layer "F.Cu")
		(net "M_A_CPU1_SA_CB<4>")
	)
	(segment
		(start 65.781428 -247.55094)
		(end 65.781428 -247.400064)
		(width 0.10668)
		(layer "F.Cu")
		(net "M_A_CPU1_SA_CB<4>")
	)
	(segment
		(start 74.73442 -248.268744)
		(end 65.494408 -248.268744)
		(width 0.10668)
		(layer "F.Cu")
		(net "M_A_CPU1_SA_CB<4>")
	)
	(segment
		(start 64.78397 -246.553482)
		(end 64.620394 -246.717058)
		(width 0.10668)
		(layer "F.Cu")
		(net "M_A_CPU1_SA_CB<4>")
	)
	(segment
		(start 65.65011 -247.268746)
		(end 65.499234 -247.268746)
		(width 0.10668)
		(layer "F.Cu")
		(net "M_A_CPU1_SA_CB<4>")
	)
	(segment
		(start 62.526418 -244.29593)
		(end 62.362842 -244.459506)
		(width 0.10668)
		(layer "F.Cu")
		(net "M_A_CPU1_SA_CB<4>")
	)
	(segment
		(start 63.937388 -245.556024)
		(end 63.80607 -245.424706)
		(width 0.10668)
		(layer "F.Cu")
		(net "M_A_CPU1_SA_CB<4>")
	)
	(segment
		(start 62.776354 -245.023894)
		(end 62.645036 -244.892576)
		(width 0.10668)
		(layer "F.Cu")
		(net "M_A_CPU1_SA_CB<4>")
	)
	(segment
		(start 64.902588 -246.999252)
		(end 65.066164 -246.835676)
		(width 0.10668)
		(layer "F.Cu")
		(net "M_A_CPU1_SA_CB<4>")
	)
	(segment
		(start 62.04331 -244.29085)
		(end 62.04331 -242.771422)
		(width 0.10668)
		(layer "F.Cu")
		(net "M_A_CPU1_SA_CB<4>")
	)
	(segment
		(start 64.934846 -246.553482)
		(end 64.78397 -246.553482)
		(width 0.10668)
		(layer "F.Cu")
		(net "M_A_CPU1_SA_CB<4>")
	)
	(segment
		(start 63.90513 -246.15267)
		(end 63.773812 -246.021352)
		(width 0.10668)
		(layer "F.Cu")
		(net "M_A_CPU1_SA_CB<4>")
	)
	(segment
		(start 65.027556 -247.740424)
		(end 64.87668 -247.740424)
		(width 0.10668)
		(layer "F.Cu")
		(net "M_A_CPU1_SA_CB<4>")
	)
	(segment
		(start 64.469518 -246.717058)
		(end 64.3382 -246.58574)
		(width 0.10668)
		(layer "F.Cu")
		(net "M_A_CPU1_SA_CB<4>")
	)
	(segment
		(start 63.373 -245.142512)
		(end 63.373 -244.991636)
		(width 0.10668)
		(layer "F.Cu")
		(net "M_A_CPU1_SA_CB<4>")
	)
	(segment
		(start 59.957462 -240.68532)
		(end 59.428126 -240.68532)
		(width 0.10668)
		(layer "F.Cu")
		(net "M_A_CPU1_SA_CB<4>")
	)
	(segment
		(start 63.340742 -245.588282)
		(end 63.209424 -245.456964)
		(width 0.10668)
		(layer "F.Cu")
		(net "M_A_CPU1_SA_CB<4>")
	)
	(segment
		(start 63.80607 -245.424706)
		(end 63.655194 -245.424706)
		(width 0.10668)
		(layer "F.Cu")
		(net "M_A_CPU1_SA_CB<4>")
	)
	(segment
		(start 64.620394 -246.717058)
		(end 64.469518 -246.717058)
		(width 0.10668)
		(layer "F.Cu")
		(net "M_A_CPU1_SA_CB<4>")
	)
	(segment
		(start 63.655194 -245.424706)
		(end 63.491618 -245.588282)
		(width 0.10668)
		(layer "F.Cu")
		(net "M_A_CPU1_SA_CB<4>")
	)
	(segment
		(start 64.3382 -246.58574)
		(end 64.3382 -246.434864)
		(width 0.10668)
		(layer "F.Cu")
		(net "M_A_CPU1_SA_CB<4>")
	)
	(segment
		(start 65.354454 -248.12879)
		(end 65.354454 -247.977914)
		(width 0.10668)
		(layer "F.Cu")
		(net "M_A_CPU1_SA_CB<4>")
	)
	(segment
		(start 65.781428 -247.400064)
		(end 65.65011 -247.268746)
		(width 0.10668)
		(layer "F.Cu")
		(net "M_A_CPU1_SA_CB<4>")
	)
	(segment
		(start 64.056006 -246.15267)
		(end 63.90513 -246.15267)
		(width 0.10668)
		(layer "F.Cu")
		(net "M_A_CPU1_SA_CB<4>")
	)
	(segment
		(start 75.71105 -248.447306)
		(end 75.532488 -248.268744)
		(width 0.10668)
		(layer "F.Cu")
		(net "M_A_CPU1_SA_CB<4>")
	)
	(segment
		(start 62.645036 -244.892576)
		(end 62.645036 -244.7417)
		(width 0.10668)
		(layer "F.Cu")
		(net "M_A_CPU1_SA_CB<4>")
	)
	(segment
		(start 62.645036 -244.7417)
		(end 62.808612 -244.578124)
		(width 0.10668)
		(layer "F.Cu")
		(net "M_A_CPU1_SA_CB<4>")
	)
	(segment
		(start 65.066164 -246.6848)
		(end 64.934846 -246.553482)
		(width 0.10668)
		(layer "F.Cu")
		(net "M_A_CPU1_SA_CB<4>")
	)
	(segment
		(start 63.937388 -245.7069)
		(end 63.937388 -245.556024)
		(width 0.10668)
		(layer "F.Cu")
		(net "M_A_CPU1_SA_CB<4>")
	)
	(segment
		(start 75.532488 -248.268744)
		(end 75.312016 -248.268744)
		(width 0.10668)
		(layer "F.Cu")
		(net "M_A_CPU1_SA_CB<4>")
	)
	(segment
		(start 62.92723 -245.023894)
		(end 62.776354 -245.023894)
		(width 0.10668)
		(layer "F.Cu")
		(net "M_A_CPU1_SA_CB<4>")
	)
	(segment
		(start 76.110084 -248.268744)
		(end 75.931522 -248.447306)
		(width 0.10668)
		(layer "F.Cu")
		(net "M_A_CPU1_SA_CB<4>")
	)
	(segment
		(start 64.902588 -247.301004)
		(end 64.902588 -246.999252)
		(width 0.10668)
		(layer "F.Cu")
		(net "M_A_CPU1_SA_CB<4>")
	)
	(segment
		(start 65.494408 -248.268744)
		(end 65.354454 -248.12879)
		(width 0.10668)
		(layer "F.Cu")
		(net "M_A_CPU1_SA_CB<4>")
	)
	(segment
		(start 64.501776 -246.271288)
		(end 64.501776 -246.120412)
		(width 0.10668)
		(layer "F.Cu")
		(net "M_A_CPU1_SA_CB<4>")
	)
	(segment
		(start 63.373 -244.991636)
		(end 63.241682 -244.860318)
		(width 0.10668)
		(layer "F.Cu")
		(net "M_A_CPU1_SA_CB<4>")
	)
	(segment
		(start 63.491618 -245.588282)
		(end 63.340742 -245.588282)
		(width 0.10668)
		(layer "F.Cu")
		(net "M_A_CPU1_SA_CB<4>")
	)
	(segment
		(start 62.808612 -244.578124)
		(end 62.808612 -244.427248)
		(width 0.10668)
		(layer "F.Cu")
		(net "M_A_CPU1_SA_CB<4>")
	)
	(segment
		(start 63.773812 -245.870476)
		(end 63.937388 -245.7069)
		(width 0.10668)
		(layer "F.Cu")
		(net "M_A_CPU1_SA_CB<4>")
	)
	(segment
		(start 75.133454 -248.447306)
		(end 74.912982 -248.447306)
		(width 0.10668)
		(layer "F.Cu")
		(net "M_A_CPU1_SA_CB<4>")
	)
	(segment
		(start 64.745362 -247.609106)
		(end 64.745362 -247.45823)
		(width 0.10668)
		(layer "F.Cu")
		(net "M_A_CPU1_SA_CB<4>")
	)
	(segment
		(start 64.219582 -245.989094)
		(end 64.056006 -246.15267)
		(width 0.10668)
		(layer "F.Cu")
		(net "M_A_CPU1_SA_CB<4>")
	)
	(segment
		(start 62.04331 -242.771422)
		(end 59.957462 -240.68532)
		(width 0.10668)
		(layer "F.Cu")
		(net "M_A_CPU1_SA_CB<4>")
	)
	(segment
		(start 62.808612 -244.427248)
		(end 62.677294 -244.29593)
		(width 0.10668)
		(layer "F.Cu")
		(net "M_A_CPU1_SA_CB<4>")
	)
	(segment
		(start 75.312016 -248.268744)
		(end 75.133454 -248.447306)
		(width 0.10668)
		(layer "F.Cu")
		(net "M_A_CPU1_SA_CB<4>")
	)
	(segment
		(start 64.745362 -247.45823)
		(end 64.902588 -247.301004)
		(width 0.10668)
		(layer "F.Cu")
		(net "M_A_CPU1_SA_CB<4>")
	)
	(segment
		(start 63.209424 -245.306088)
		(end 63.373 -245.142512)
		(width 0.10668)
		(layer "F.Cu")
		(net "M_A_CPU1_SA_CB<4>")
	)
	(segment
		(start 74.912982 -248.447306)
		(end 74.73442 -248.268744)
		(width 0.10668)
		(layer "F.Cu")
		(net "M_A_CPU1_SA_CB<4>")
	)
	(segment
		(start 64.87668 -247.740424)
		(end 64.745362 -247.609106)
		(width 0.10668)
		(layer "F.Cu")
		(net "M_A_CPU1_SA_CB<4>")
	)
	(segment
		(start 62.362842 -244.459506)
		(end 62.211966 -244.459506)
		(width 0.10668)
		(layer "F.Cu")
		(net "M_A_CPU1_SA_CB<4>")
	)
	(segment
		(start 65.499234 -247.268746)
		(end 65.027556 -247.740424)
		(width 0.10668)
		(layer "F.Cu")
		(net "M_A_CPU1_SA_CB<4>")
	)
	(segment
		(start 64.370458 -245.989094)
		(end 64.219582 -245.989094)
		(width 0.10668)
		(layer "F.Cu")
		(net "M_A_CPU1_SA_CB<4>")
	)
	(segment
		(start 64.3382 -246.434864)
		(end 64.501776 -246.271288)
		(width 0.10668)
		(layer "F.Cu")
		(net "M_A_CPU1_SA_CB<4>")
	)
	(segment
		(start 62.677294 -244.29593)
		(end 62.526418 -244.29593)
		(width 0.10668)
		(layer "F.Cu")
		(net "M_A_CPU1_SA_CB<4>")
	)
	(segment
		(start 64.501776 -246.120412)
		(end 64.370458 -245.989094)
		(width 0.10668)
		(layer "F.Cu")
		(net "M_A_CPU1_SA_CB<4>")
	)
	(segment
		(start 63.241682 -244.860318)
		(end 63.090806 -244.860318)
		(width 0.10668)
		(layer "F.Cu")
		(net "M_A_CPU1_SA_CB<4>")
	)
	(arc
		(start 77.880718 -248.239534)
		(mid 77.763905 -248.26421)
		(end 77.654912 -248.31294)
		(width 0.0762)
		(layer "F.Cu")
		(net "M_A_CPU1_SA_CB<4>")
	)
	(arc
		(start 78.408022 -247.99036)
		(mid 78.165705 -248.16008)
		(end 77.880718 -248.239534)
		(width 0.0762)
		(layer "F.Cu")
		(net "M_A_CPU1_SA_CB<4>")
	)
	(arc
		(start 77.654912 -248.31294)
		(mid 77.564779 -248.35056)
		(end 77.467968 -248.363486)
		(width 0.0762)
		(layer "F.Cu")
		(net "M_A_CPU1_SA_CB<4>")
	)
	(segment
		(start 68.66001 -246.089424)
		(end 64.931544 -242.360958)
		(width 0.10668)
		(layer "F.Cu")
		(net "M_A_CPU1_SA_CB<3>")
	)
	(segment
		(start 79.347822 -246.370094)
		(end 79.452978 -246.189246)
		(width 0.0762)
		(layer "F.Cu")
		(net "M_A_CPU1_SA_CB<3>")
	)
	(segment
		(start 78.594966 -246.047768)
		(end 78.586584 -246.042942)
		(width 0.0762)
		(layer "F.Cu")
		(net "M_A_CPU1_SA_CB<3>")
	)
	(segment
		(start 64.484504 -242.360958)
		(end 62.49162 -240.368074)
		(width 0.10668)
		(layer "F.Cu")
		(net "M_A_CPU1_SA_CB<3>")
	)
	(segment
		(start 62.49162 -240.368074)
		(end 62.49162 -239.564926)
		(width 0.10668)
		(layer "F.Cu")
		(net "M_A_CPU1_SA_CB<3>")
	)
	(segment
		(start 57.379616 -237.285276)
		(end 55.328058 -237.285276)
		(width 0.101346)
		(layer "F.Cu")
		(net "M_A_CPU1_SA_CB<3>")
	)
	(segment
		(start 62.49162 -239.564926)
		(end 60.637166 -237.710472)
		(width 0.10668)
		(layer "F.Cu")
		(net "M_A_CPU1_SA_CB<3>")
	)
	(segment
		(start 79.16926 -246.042942)
		(end 79.168244 -246.04345)
		(width 0.0762)
		(layer "F.Cu")
		(net "M_A_CPU1_SA_CB<3>")
	)
	(segment
		(start 60.637166 -237.710472)
		(end 60.344812 -237.710472)
		(width 0.10668)
		(layer "F.Cu")
		(net "M_A_CPU1_SA_CB<3>")
	)
	(segment
		(start 79.347822 -246.370348)
		(end 79.347822 -246.370094)
		(width 0.0762)
		(layer "F.Cu")
		(net "M_A_CPU1_SA_CB<3>")
	)
	(segment
		(start 77.451458 -245.992904)
		(end 76.542646 -245.992904)
		(width 0.0762)
		(layer "F.Cu")
		(net "M_A_CPU1_SA_CB<3>")
	)
	(segment
		(start 64.931544 -242.360958)
		(end 64.484504 -242.360958)
		(width 0.10668)
		(layer "F.Cu")
		(net "M_A_CPU1_SA_CB<3>")
	)
	(segment
		(start 76.542646 -245.992904)
		(end 76.446126 -246.089424)
		(width 0.0762)
		(layer "F.Cu")
		(net "M_A_CPU1_SA_CB<3>")
	)
	(segment
		(start 60.344812 -237.710472)
		(end 57.804812 -237.710472)
		(width 0.101346)
		(layer "F.Cu")
		(net "M_A_CPU1_SA_CB<3>")
	)
	(segment
		(start 57.804812 -237.710472)
		(end 57.379616 -237.285276)
		(width 0.101346)
		(layer "F.Cu")
		(net "M_A_CPU1_SA_CB<3>")
	)
	(segment
		(start 76.446126 -246.089424)
		(end 68.66001 -246.089424)
		(width 0.10668)
		(layer "F.Cu")
		(net "M_A_CPU1_SA_CB<3>")
	)
	(segment
		(start 79.168244 -246.04345)
		(end 79.160878 -246.047768)
		(width 0.0762)
		(layer "F.Cu")
		(net "M_A_CPU1_SA_CB<3>")
	)
	(arc
		(start 79.349346 -245.997476)
		(mid 79.256422 -246.008799)
		(end 79.16926 -246.042942)
		(width 0.0762)
		(layer "F.Cu")
		(net "M_A_CPU1_SA_CB<3>")
	)
	(arc
		(start 78.220824 -246.047768)
		(mid 77.937868 -246.123945)
		(end 77.654912 -246.047768)
		(width 0.0762)
		(layer "F.Cu")
		(net "M_A_CPU1_SA_CB<3>")
	)
	(arc
		(start 78.586584 -246.042942)
		(mid 78.403076 -245.997448)
		(end 78.220824 -246.047768)
		(width 0.0762)
		(layer "F.Cu")
		(net "M_A_CPU1_SA_CB<3>")
	)
	(arc
		(start 79.160878 -246.047768)
		(mid 78.877922 -246.123945)
		(end 78.594966 -246.047768)
		(width 0.0762)
		(layer "F.Cu")
		(net "M_A_CPU1_SA_CB<3>")
	)
	(arc
		(start 79.452978 -246.189246)
		(mid 79.444041 -246.070222)
		(end 79.349346 -245.997476)
		(width 0.0762)
		(layer "F.Cu")
		(net "M_A_CPU1_SA_CB<3>")
	)
	(arc
		(start 77.654912 -246.047768)
		(mid 77.556815 -246.006881)
		(end 77.451458 -245.992904)
		(width 0.0762)
		(layer "F.Cu")
		(net "M_A_CPU1_SA_CB<3>")
	)
	(segment
		(start 65.451736 -241.64417)
		(end 65.38595 -241.709956)
		(width 0.10668)
		(layer "F.Cu")
		(net "M_A_CPU1_SA_CB<2>")
	)
	(segment
		(start 56.891936 -236.09554)
		(end 56.891936 -235.6866)
		(width 0.101346)
		(layer "F.Cu")
		(net "M_A_CPU1_SA_CB<2>")
	)
	(segment
		(start 56.993282 -236.196886)
		(end 56.891936 -236.09554)
		(width 0.101346)
		(layer "F.Cu")
		(net "M_A_CPU1_SA_CB<2>")
	)
	(segment
		(start 65.38595 -241.709956)
		(end 65.235074 -241.709702)
		(width 0.10668)
		(layer "F.Cu")
		(net "M_A_CPU1_SA_CB<2>")
	)
	(segment
		(start 65.169542 -241.361722)
		(end 65.169796 -241.211354)
		(width 0.10668)
		(layer "F.Cu")
		(net "M_A_CPU1_SA_CB<2>")
	)
	(segment
		(start 57.285636 -235.6866)
		(end 57.285636 -236.09554)
		(width 0.101346)
		(layer "F.Cu")
		(net "M_A_CPU1_SA_CB<2>")
	)
	(segment
		(start 77.104748 -245.375684)
		(end 76.288646 -245.375684)
		(width 0.0762)
		(layer "F.Cu")
		(net "M_A_CPU1_SA_CB<2>")
	)
	(segment
		(start 65.169796 -241.211354)
		(end 60.896246 -236.937804)
		(width 0.10668)
		(layer "F.Cu")
		(net "M_A_CPU1_SA_CB<2>")
	)
	(segment
		(start 69.247766 -245.289324)
		(end 65.602612 -241.64417)
		(width 0.10668)
		(layer "F.Cu")
		(net "M_A_CPU1_SA_CB<2>")
	)
	(segment
		(start 65.235074 -241.709702)
		(end 65.103756 -241.578384)
		(width 0.10668)
		(layer "F.Cu")
		(net "M_A_CPU1_SA_CB<2>")
	)
	(segment
		(start 77.759306 -245.232936)
		(end 77.750924 -245.237762)
		(width 0.0762)
		(layer "F.Cu")
		(net "M_A_CPU1_SA_CB<2>")
	)
	(segment
		(start 57.705244 -235.585254)
		(end 57.386982 -235.585254)
		(width 0.101346)
		(layer "F.Cu")
		(net "M_A_CPU1_SA_CB<2>")
	)
	(segment
		(start 65.602612 -241.64417)
		(end 65.451736 -241.64417)
		(width 0.10668)
		(layer "F.Cu")
		(net "M_A_CPU1_SA_CB<2>")
	)
	(segment
		(start 57.285636 -236.09554)
		(end 57.18429 -236.196886)
		(width 0.101346)
		(layer "F.Cu")
		(net "M_A_CPU1_SA_CB<2>")
	)
	(segment
		(start 60.896246 -236.236256)
		(end 60.67044 -236.01045)
		(width 0.10668)
		(layer "F.Cu")
		(net "M_A_CPU1_SA_CB<2>")
	)
	(segment
		(start 76.288646 -245.375684)
		(end 76.202286 -245.289324)
		(width 0.0762)
		(layer "F.Cu")
		(net "M_A_CPU1_SA_CB<2>")
	)
	(segment
		(start 60.896246 -236.937804)
		(end 60.896246 -236.236256)
		(width 0.10668)
		(layer "F.Cu")
		(net "M_A_CPU1_SA_CB<2>")
	)
	(segment
		(start 77.937868 -245.560342)
		(end 78.030832 -245.400322)
		(width 0.0762)
		(layer "F.Cu")
		(net "M_A_CPU1_SA_CB<2>")
	)
	(segment
		(start 56.79059 -235.585254)
		(end 55.328058 -235.585254)
		(width 0.101346)
		(layer "F.Cu")
		(net "M_A_CPU1_SA_CB<2>")
	)
	(segment
		(start 56.891936 -235.6866)
		(end 56.79059 -235.585254)
		(width 0.101346)
		(layer "F.Cu")
		(net "M_A_CPU1_SA_CB<2>")
	)
	(segment
		(start 57.386982 -235.585254)
		(end 57.285636 -235.6866)
		(width 0.101346)
		(layer "F.Cu")
		(net "M_A_CPU1_SA_CB<2>")
	)
	(segment
		(start 58.13044 -236.01045)
		(end 57.705244 -235.585254)
		(width 0.101346)
		(layer "F.Cu")
		(net "M_A_CPU1_SA_CB<2>")
	)
	(segment
		(start 65.103756 -241.427508)
		(end 65.169542 -241.361722)
		(width 0.10668)
		(layer "F.Cu")
		(net "M_A_CPU1_SA_CB<2>")
	)
	(segment
		(start 76.202286 -245.289324)
		(end 69.247766 -245.289324)
		(width 0.10668)
		(layer "F.Cu")
		(net "M_A_CPU1_SA_CB<2>")
	)
	(segment
		(start 65.103756 -241.578384)
		(end 65.103756 -241.427508)
		(width 0.10668)
		(layer "F.Cu")
		(net "M_A_CPU1_SA_CB<2>")
	)
	(segment
		(start 60.67044 -236.01045)
		(end 58.13044 -236.01045)
		(width 0.101346)
		(layer "F.Cu")
		(net "M_A_CPU1_SA_CB<2>")
	)
	(segment
		(start 57.18429 -236.196886)
		(end 56.993282 -236.196886)
		(width 0.101346)
		(layer "F.Cu")
		(net "M_A_CPU1_SA_CB<2>")
	)
	(arc
		(start 77.899006 -245.189502)
		(mid 77.826998 -245.204284)
		(end 77.759306 -245.232936)
		(width 0.0762)
		(layer "F.Cu")
		(net "M_A_CPU1_SA_CB<2>")
	)
	(arc
		(start 77.750924 -245.237762)
		(mid 77.70323 -245.262572)
		(end 77.653388 -245.28272)
		(width 0.0762)
		(layer "F.Cu")
		(net "M_A_CPU1_SA_CB<2>")
	)
	(arc
		(start 77.653388 -245.28272)
		(mid 77.382981 -245.352308)
		(end 77.104748 -245.375684)
		(width 0.0762)
		(layer "F.Cu")
		(net "M_A_CPU1_SA_CB<2>")
	)
	(arc
		(start 78.030832 -245.400322)
		(mid 78.030672 -245.253761)
		(end 77.899006 -245.189502)
		(width 0.0762)
		(layer "F.Cu")
		(net "M_A_CPU1_SA_CB<2>")
	)
	(segment
		(start 77.16901 -245.726204)
		(end 76.027026 -245.726204)
		(width 0.0762)
		(layer "F.Cu")
		(net "M_A_CPU1_SA_CB<1>")
	)
	(segment
		(start 63.873888 -240.596166)
		(end 63.61303 -240.857024)
		(width 0.10668)
		(layer "F.Cu")
		(net "M_A_CPU1_SA_CB<1>")
	)
	(segment
		(start 67.479418 -244.427248)
		(end 67.479418 -244.14734)
		(width 0.10668)
		(layer "F.Cu")
		(net "M_A_CPU1_SA_CB<1>")
	)
	(segment
		(start 67.621658 -244.569488)
		(end 67.479418 -244.427248)
		(width 0.10668)
		(layer "F.Cu")
		(net "M_A_CPU1_SA_CB<1>")
	)
	(segment
		(start 68.608194 -245.556024)
		(end 68.608194 -245.276116)
		(width 0.10668)
		(layer "F.Cu")
		(net "M_A_CPU1_SA_CB<1>")
	)
	(segment
		(start 63.61303 -240.857024)
		(end 63.462154 -240.857024)
		(width 0.10668)
		(layer "F.Cu")
		(net "M_A_CPU1_SA_CB<1>")
	)
	(segment
		(start 64.156082 -240.87836)
		(end 64.156082 -240.727484)
		(width 0.10668)
		(layer "F.Cu")
		(net "M_A_CPU1_SA_CB<1>")
	)
	(segment
		(start 67.901566 -244.569488)
		(end 67.621658 -244.569488)
		(width 0.10668)
		(layer "F.Cu")
		(net "M_A_CPU1_SA_CB<1>")
	)
	(segment
		(start 64.177418 -241.421412)
		(end 64.026542 -241.421412)
		(width 0.10668)
		(layer "F.Cu")
		(net "M_A_CPU1_SA_CB<1>")
	)
	(segment
		(start 66.91503 -243.86286)
		(end 66.91503 -243.582952)
		(width 0.10668)
		(layer "F.Cu")
		(net "M_A_CPU1_SA_CB<1>")
	)
	(segment
		(start 68.747894 -245.695724)
		(end 68.608194 -245.556024)
		(width 0.10668)
		(layer "F.Cu")
		(net "M_A_CPU1_SA_CB<1>")
	)
	(segment
		(start 66.492882 -243.440712)
		(end 66.350642 -243.298472)
		(width 0.10668)
		(layer "F.Cu")
		(net "M_A_CPU1_SA_CB<1>")
	)
	(segment
		(start 65.928494 -242.876324)
		(end 65.786254 -242.734084)
		(width 0.10668)
		(layer "F.Cu")
		(net "M_A_CPU1_SA_CB<1>")
	)
	(segment
		(start 65.364106 -242.311936)
		(end 65.072768 -242.020598)
		(width 0.10668)
		(layer "F.Cu")
		(net "M_A_CPU1_SA_CB<1>")
	)
	(segment
		(start 64.459612 -241.854482)
		(end 64.459612 -241.703606)
		(width 0.10668)
		(layer "F.Cu")
		(net "M_A_CPU1_SA_CB<1>")
	)
	(segment
		(start 75.996546 -245.695724)
		(end 68.747894 -245.695724)
		(width 0.10668)
		(layer "F.Cu")
		(net "M_A_CPU1_SA_CB<1>")
	)
	(segment
		(start 66.77279 -243.440712)
		(end 66.492882 -243.440712)
		(width 0.10668)
		(layer "F.Cu")
		(net "M_A_CPU1_SA_CB<1>")
	)
	(segment
		(start 62.83198 -240.22685)
		(end 62.83198 -239.366298)
		(width 0.10668)
		(layer "F.Cu")
		(net "M_A_CPU1_SA_CB<1>")
	)
	(segment
		(start 63.330836 -240.57483)
		(end 63.591694 -240.313972)
		(width 0.10668)
		(layer "F.Cu")
		(net "M_A_CPU1_SA_CB<1>")
	)
	(segment
		(start 64.024764 -240.596166)
		(end 63.873888 -240.596166)
		(width 0.10668)
		(layer "F.Cu")
		(net "M_A_CPU1_SA_CB<1>")
	)
	(segment
		(start 65.072768 -242.020598)
		(end 64.625728 -242.020598)
		(width 0.10668)
		(layer "F.Cu")
		(net "M_A_CPU1_SA_CB<1>")
	)
	(segment
		(start 64.72047 -241.291872)
		(end 64.589152 -241.160554)
		(width 0.10668)
		(layer "F.Cu")
		(net "M_A_CPU1_SA_CB<1>")
	)
	(segment
		(start 63.462154 -240.857024)
		(end 63.330836 -240.725706)
		(width 0.10668)
		(layer "F.Cu")
		(net "M_A_CPU1_SA_CB<1>")
	)
	(segment
		(start 62.83198 -239.366298)
		(end 59.901074 -236.435392)
		(width 0.10668)
		(layer "F.Cu")
		(net "M_A_CPU1_SA_CB<1>")
	)
	(segment
		(start 66.350642 -243.018564)
		(end 66.208402 -242.876324)
		(width 0.10668)
		(layer "F.Cu")
		(net "M_A_CPU1_SA_CB<1>")
	)
	(segment
		(start 63.895224 -241.290094)
		(end 63.895224 -241.139218)
		(width 0.10668)
		(layer "F.Cu")
		(net "M_A_CPU1_SA_CB<1>")
	)
	(segment
		(start 63.3095 -240.031778)
		(end 63.048642 -240.292636)
		(width 0.10668)
		(layer "F.Cu")
		(net "M_A_CPU1_SA_CB<1>")
	)
	(segment
		(start 67.337178 -244.0051)
		(end 67.05727 -244.0051)
		(width 0.10668)
		(layer "F.Cu")
		(net "M_A_CPU1_SA_CB<1>")
	)
	(segment
		(start 68.043806 -244.711728)
		(end 67.901566 -244.569488)
		(width 0.10668)
		(layer "F.Cu")
		(net "M_A_CPU1_SA_CB<1>")
	)
	(segment
		(start 68.465954 -245.133876)
		(end 68.186046 -245.133876)
		(width 0.10668)
		(layer "F.Cu")
		(net "M_A_CPU1_SA_CB<1>")
	)
	(segment
		(start 64.026542 -241.421412)
		(end 63.895224 -241.290094)
		(width 0.10668)
		(layer "F.Cu")
		(net "M_A_CPU1_SA_CB<1>")
	)
	(segment
		(start 65.644014 -242.311936)
		(end 65.364106 -242.311936)
		(width 0.10668)
		(layer "F.Cu")
		(net "M_A_CPU1_SA_CB<1>")
	)
	(segment
		(start 62.897766 -240.292636)
		(end 62.83198 -240.22685)
		(width 0.10668)
		(layer "F.Cu")
		(net "M_A_CPU1_SA_CB<1>")
	)
	(segment
		(start 64.72047 -241.442748)
		(end 64.72047 -241.291872)
		(width 0.10668)
		(layer "F.Cu")
		(net "M_A_CPU1_SA_CB<1>")
	)
	(segment
		(start 67.479418 -244.14734)
		(end 67.337178 -244.0051)
		(width 0.10668)
		(layer "F.Cu")
		(net "M_A_CPU1_SA_CB<1>")
	)
	(segment
		(start 66.208402 -242.876324)
		(end 65.928494 -242.876324)
		(width 0.10668)
		(layer "F.Cu")
		(net "M_A_CPU1_SA_CB<1>")
	)
	(segment
		(start 64.156082 -240.727484)
		(end 64.024764 -240.596166)
		(width 0.10668)
		(layer "F.Cu")
		(net "M_A_CPU1_SA_CB<1>")
	)
	(segment
		(start 77.759306 -245.887748)
		(end 77.750924 -245.882922)
		(width 0.0762)
		(layer "F.Cu")
		(net "M_A_CPU1_SA_CB<1>")
	)
	(segment
		(start 76.027026 -245.726204)
		(end 75.996546 -245.695724)
		(width 0.0762)
		(layer "F.Cu")
		(net "M_A_CPU1_SA_CB<1>")
	)
	(segment
		(start 65.786254 -242.734084)
		(end 65.786254 -242.454176)
		(width 0.10668)
		(layer "F.Cu")
		(net "M_A_CPU1_SA_CB<1>")
	)
	(segment
		(start 64.438276 -241.160554)
		(end 64.177418 -241.421412)
		(width 0.10668)
		(layer "F.Cu")
		(net "M_A_CPU1_SA_CB<1>")
	)
	(segment
		(start 63.895224 -241.139218)
		(end 64.156082 -240.87836)
		(width 0.10668)
		(layer "F.Cu")
		(net "M_A_CPU1_SA_CB<1>")
	)
	(segment
		(start 64.589152 -241.160554)
		(end 64.438276 -241.160554)
		(width 0.10668)
		(layer "F.Cu")
		(net "M_A_CPU1_SA_CB<1>")
	)
	(segment
		(start 63.330836 -240.725706)
		(end 63.330836 -240.57483)
		(width 0.10668)
		(layer "F.Cu")
		(net "M_A_CPU1_SA_CB<1>")
	)
	(segment
		(start 59.901074 -236.435392)
		(end 59.428126 -236.435392)
		(width 0.10668)
		(layer "F.Cu")
		(net "M_A_CPU1_SA_CB<1>")
	)
	(segment
		(start 66.91503 -243.582952)
		(end 66.77279 -243.440712)
		(width 0.10668)
		(layer "F.Cu")
		(net "M_A_CPU1_SA_CB<1>")
	)
	(segment
		(start 64.459612 -241.703606)
		(end 64.72047 -241.442748)
		(width 0.10668)
		(layer "F.Cu")
		(net "M_A_CPU1_SA_CB<1>")
	)
	(segment
		(start 68.043806 -244.991636)
		(end 68.043806 -244.711728)
		(width 0.10668)
		(layer "F.Cu")
		(net "M_A_CPU1_SA_CB<1>")
	)
	(segment
		(start 68.608194 -245.276116)
		(end 68.465954 -245.133876)
		(width 0.10668)
		(layer "F.Cu")
		(net "M_A_CPU1_SA_CB<1>")
	)
	(segment
		(start 66.350642 -243.298472)
		(end 66.350642 -243.018564)
		(width 0.10668)
		(layer "F.Cu")
		(net "M_A_CPU1_SA_CB<1>")
	)
	(segment
		(start 63.591694 -240.313972)
		(end 63.591694 -240.163096)
		(width 0.10668)
		(layer "F.Cu")
		(net "M_A_CPU1_SA_CB<1>")
	)
	(segment
		(start 65.786254 -242.454176)
		(end 65.644014 -242.311936)
		(width 0.10668)
		(layer "F.Cu")
		(net "M_A_CPU1_SA_CB<1>")
	)
	(segment
		(start 64.625728 -242.020598)
		(end 64.459612 -241.854482)
		(width 0.10668)
		(layer "F.Cu")
		(net "M_A_CPU1_SA_CB<1>")
	)
	(segment
		(start 63.591694 -240.163096)
		(end 63.460376 -240.031778)
		(width 0.10668)
		(layer "F.Cu")
		(net "M_A_CPU1_SA_CB<1>")
	)
	(segment
		(start 68.186046 -245.133876)
		(end 68.043806 -244.991636)
		(width 0.10668)
		(layer "F.Cu")
		(net "M_A_CPU1_SA_CB<1>")
	)
	(segment
		(start 63.460376 -240.031778)
		(end 63.3095 -240.031778)
		(width 0.10668)
		(layer "F.Cu")
		(net "M_A_CPU1_SA_CB<1>")
	)
	(segment
		(start 63.048642 -240.292636)
		(end 62.897766 -240.292636)
		(width 0.10668)
		(layer "F.Cu")
		(net "M_A_CPU1_SA_CB<1>")
	)
	(segment
		(start 67.05727 -244.0051)
		(end 66.91503 -243.86286)
		(width 0.10668)
		(layer "F.Cu")
		(net "M_A_CPU1_SA_CB<1>")
	)
	(segment
		(start 79.064866 -245.882668)
		(end 79.064866 -245.882922)
		(width 0.0762)
		(layer "F.Cu")
		(net "M_A_CPU1_SA_CB<1>")
	)
	(arc
		(start 79.064866 -245.882922)
		(mid 78.877922 -245.933177)
		(end 78.690978 -245.882922)
		(width 0.0762)
		(layer "F.Cu")
		(net "M_A_CPU1_SA_CB<1>")
	)
	(arc
		(start 77.750924 -245.882922)
		(mid 77.470333 -245.766072)
		(end 77.16901 -245.726204)
		(width 0.0762)
		(layer "F.Cu")
		(net "M_A_CPU1_SA_CB<1>")
	)
	(arc
		(start 79.817976 -245.560342)
		(mid 79.61396 -245.741036)
		(end 79.349346 -245.806214)
		(width 0.0762)
		(layer "F.Cu")
		(net "M_A_CPU1_SA_CB<1>")
	)
	(arc
		(start 78.690978 -245.882922)
		(mid 78.408022 -245.806745)
		(end 78.125066 -245.882922)
		(width 0.0762)
		(layer "F.Cu")
		(net "M_A_CPU1_SA_CB<1>")
	)
	(arc
		(start 79.349346 -245.806214)
		(mid 79.202025 -245.825533)
		(end 79.064866 -245.882668)
		(width 0.0762)
		(layer "F.Cu")
		(net "M_A_CPU1_SA_CB<1>")
	)
	(arc
		(start 78.125066 -245.882922)
		(mid 77.942815 -245.933272)
		(end 77.759306 -245.887748)
		(width 0.0762)
		(layer "F.Cu")
		(net "M_A_CPU1_SA_CB<1>")
	)
	(segment
		(start 61.236606 -236.79658)
		(end 61.236606 -236.095032)
		(width 0.10668)
		(layer "F.Cu")
		(net "M_A_CPU1_SA_CB<0>")
	)
	(segment
		(start 68.017644 -242.966748)
		(end 67.867276 -242.967002)
		(width 0.10668)
		(layer "F.Cu")
		(net "M_A_CPU1_SA_CB<0>")
	)
	(segment
		(start 66.174112 -241.273838)
		(end 66.019426 -241.428524)
		(width 0.10668)
		(layer "F.Cu")
		(net "M_A_CPU1_SA_CB<0>")
	)
	(segment
		(start 67.453256 -242.40236)
		(end 67.302888 -242.402614)
		(width 0.10668)
		(layer "F.Cu")
		(net "M_A_CPU1_SA_CB<0>")
	)
	(segment
		(start 66.301366 -241.710718)
		(end 66.456052 -241.556032)
		(width 0.10668)
		(layer "F.Cu")
		(net "M_A_CPU1_SA_CB<0>")
	)
	(segment
		(start 66.583814 -241.992912)
		(end 66.432938 -241.992912)
		(width 0.10668)
		(layer "F.Cu")
		(net "M_A_CPU1_SA_CB<0>")
	)
	(segment
		(start 65.195704 -240.144808)
		(end 65.045336 -240.145062)
		(width 0.10668)
		(layer "F.Cu")
		(net "M_A_CPU1_SA_CB<0>")
	)
	(segment
		(start 69.14642 -244.095524)
		(end 68.996052 -244.095778)
		(width 0.10668)
		(layer "F.Cu")
		(net "M_A_CPU1_SA_CB<0>")
	)
	(segment
		(start 65.17259 -240.581942)
		(end 65.327276 -240.427256)
		(width 0.10668)
		(layer "F.Cu")
		(net "M_A_CPU1_SA_CB<0>")
	)
	(segment
		(start 67.02044 -241.969544)
		(end 66.888868 -241.837972)
		(width 0.10668)
		(layer "F.Cu")
		(net "M_A_CPU1_SA_CB<0>")
	)
	(segment
		(start 65.891664 -240.840768)
		(end 65.760092 -240.709196)
		(width 0.10668)
		(layer "F.Cu")
		(net "M_A_CPU1_SA_CB<0>")
	)
	(segment
		(start 66.32448 -241.273584)
		(end 66.174112 -241.273838)
		(width 0.10668)
		(layer "F.Cu")
		(net "M_A_CPU1_SA_CB<0>")
	)
	(segment
		(start 65.86855 -241.428524)
		(end 65.737232 -241.297206)
		(width 0.10668)
		(layer "F.Cu")
		(net "M_A_CPU1_SA_CB<0>")
	)
	(segment
		(start 69.277992 -244.377972)
		(end 69.277992 -244.227096)
		(width 0.10668)
		(layer "F.Cu")
		(net "M_A_CPU1_SA_CB<0>")
	)
	(segment
		(start 65.045336 -240.145062)
		(end 64.89065 -240.299748)
		(width 0.10668)
		(layer "F.Cu")
		(net "M_A_CPU1_SA_CB<0>")
	)
	(segment
		(start 65.737232 -241.297206)
		(end 65.736978 -241.14633)
		(width 0.10668)
		(layer "F.Cu")
		(net "M_A_CPU1_SA_CB<0>")
	)
	(segment
		(start 76.575666 -245.126764)
		(end 76.397866 -244.948964)
		(width 0.0762)
		(layer "F.Cu")
		(net "M_A_CPU1_SA_CB<0>")
	)
	(segment
		(start 66.019426 -241.428524)
		(end 65.86855 -241.428524)
		(width 0.10668)
		(layer "F.Cu")
		(net "M_A_CPU1_SA_CB<0>")
	)
	(segment
		(start 68.559172 -244.119146)
		(end 68.558918 -243.96827)
		(width 0.10668)
		(layer "F.Cu")
		(net "M_A_CPU1_SA_CB<0>")
	)
	(segment
		(start 67.148202 -242.5573)
		(end 66.997326 -242.5573)
		(width 0.10668)
		(layer "F.Cu")
		(net "M_A_CPU1_SA_CB<0>")
	)
	(segment
		(start 68.126102 -243.686076)
		(end 67.994784 -243.554758)
		(width 0.10668)
		(layer "F.Cu")
		(net "M_A_CPU1_SA_CB<0>")
	)
	(segment
		(start 67.867276 -242.967002)
		(end 67.71259 -243.121688)
		(width 0.10668)
		(layer "F.Cu")
		(net "M_A_CPU1_SA_CB<0>")
	)
	(segment
		(start 77.388212 -245.126764)
		(end 76.575666 -245.126764)
		(width 0.0762)
		(layer "F.Cu")
		(net "M_A_CPU1_SA_CB<0>")
	)
	(segment
		(start 61.236606 -236.095032)
		(end 59.876944 -234.73537)
		(width 0.10668)
		(layer "F.Cu")
		(net "M_A_CPU1_SA_CB<0>")
	)
	(segment
		(start 65.327276 -240.427256)
		(end 65.327276 -240.27638)
		(width 0.10668)
		(layer "F.Cu")
		(net "M_A_CPU1_SA_CB<0>")
	)
	(segment
		(start 65.736978 -241.14633)
		(end 65.891664 -240.991644)
		(width 0.10668)
		(layer "F.Cu")
		(net "M_A_CPU1_SA_CB<0>")
	)
	(segment
		(start 67.994784 -243.554758)
		(end 67.99453 -243.403882)
		(width 0.10668)
		(layer "F.Cu")
		(net "M_A_CPU1_SA_CB<0>")
	)
	(segment
		(start 68.558918 -243.96827)
		(end 68.713604 -243.813584)
		(width 0.10668)
		(layer "F.Cu")
		(net "M_A_CPU1_SA_CB<0>")
	)
	(segment
		(start 66.30162 -241.861594)
		(end 66.301366 -241.710718)
		(width 0.10668)
		(layer "F.Cu")
		(net "M_A_CPU1_SA_CB<0>")
	)
	(segment
		(start 65.327276 -240.27638)
		(end 65.195704 -240.144808)
		(width 0.10668)
		(layer "F.Cu")
		(net "M_A_CPU1_SA_CB<0>")
	)
	(segment
		(start 68.713604 -243.662708)
		(end 68.582032 -243.531136)
		(width 0.10668)
		(layer "F.Cu")
		(net "M_A_CPU1_SA_CB<0>")
	)
	(segment
		(start 65.455038 -240.864136)
		(end 65.304162 -240.864136)
		(width 0.10668)
		(layer "F.Cu")
		(net "M_A_CPU1_SA_CB<0>")
	)
	(segment
		(start 68.149216 -243.09832)
		(end 68.017644 -242.966748)
		(width 0.10668)
		(layer "F.Cu")
		(net "M_A_CPU1_SA_CB<0>")
	)
	(segment
		(start 65.609724 -240.70945)
		(end 65.455038 -240.864136)
		(width 0.10668)
		(layer "F.Cu")
		(net "M_A_CPU1_SA_CB<0>")
	)
	(segment
		(start 68.841366 -244.250464)
		(end 68.69049 -244.250464)
		(width 0.10668)
		(layer "F.Cu")
		(net "M_A_CPU1_SA_CB<0>")
	)
	(segment
		(start 67.430396 -242.99037)
		(end 67.430142 -242.839494)
		(width 0.10668)
		(layer "F.Cu")
		(net "M_A_CPU1_SA_CB<0>")
	)
	(segment
		(start 66.866008 -242.425982)
		(end 66.865754 -242.275106)
		(width 0.10668)
		(layer "F.Cu")
		(net "M_A_CPU1_SA_CB<0>")
	)
	(segment
		(start 66.456052 -241.556032)
		(end 66.456052 -241.405156)
		(width 0.10668)
		(layer "F.Cu")
		(net "M_A_CPU1_SA_CB<0>")
	)
	(segment
		(start 67.71259 -243.121688)
		(end 67.561714 -243.121688)
		(width 0.10668)
		(layer "F.Cu")
		(net "M_A_CPU1_SA_CB<0>")
	)
	(segment
		(start 64.739774 -240.299748)
		(end 61.236606 -236.79658)
		(width 0.10668)
		(layer "F.Cu")
		(net "M_A_CPU1_SA_CB<0>")
	)
	(segment
		(start 68.276978 -243.686076)
		(end 68.126102 -243.686076)
		(width 0.10668)
		(layer "F.Cu")
		(net "M_A_CPU1_SA_CB<0>")
	)
	(segment
		(start 68.713604 -243.813584)
		(end 68.713604 -243.662708)
		(width 0.10668)
		(layer "F.Cu")
		(net "M_A_CPU1_SA_CB<0>")
	)
	(segment
		(start 67.584828 -242.533932)
		(end 67.453256 -242.40236)
		(width 0.10668)
		(layer "F.Cu")
		(net "M_A_CPU1_SA_CB<0>")
	)
	(segment
		(start 66.997326 -242.5573)
		(end 66.866008 -242.425982)
		(width 0.10668)
		(layer "F.Cu")
		(net "M_A_CPU1_SA_CB<0>")
	)
	(segment
		(start 66.432938 -241.992912)
		(end 66.30162 -241.861594)
		(width 0.10668)
		(layer "F.Cu")
		(net "M_A_CPU1_SA_CB<0>")
	)
	(segment
		(start 69.277992 -244.227096)
		(end 69.14642 -244.095524)
		(width 0.10668)
		(layer "F.Cu")
		(net "M_A_CPU1_SA_CB<0>")
	)
	(segment
		(start 66.865754 -242.275106)
		(end 67.02044 -242.12042)
		(width 0.10668)
		(layer "F.Cu")
		(net "M_A_CPU1_SA_CB<0>")
	)
	(segment
		(start 66.7385 -241.838226)
		(end 66.583814 -241.992912)
		(width 0.10668)
		(layer "F.Cu")
		(net "M_A_CPU1_SA_CB<0>")
	)
	(segment
		(start 69.12356 -244.683534)
		(end 69.123306 -244.532658)
		(width 0.10668)
		(layer "F.Cu")
		(net "M_A_CPU1_SA_CB<0>")
	)
	(segment
		(start 67.430142 -242.839494)
		(end 67.584828 -242.684808)
		(width 0.10668)
		(layer "F.Cu")
		(net "M_A_CPU1_SA_CB<0>")
	)
	(segment
		(start 69.38899 -244.948964)
		(end 69.12356 -244.683534)
		(width 0.10668)
		(layer "F.Cu")
		(net "M_A_CPU1_SA_CB<0>")
	)
	(segment
		(start 67.561714 -243.121688)
		(end 67.430396 -242.99037)
		(width 0.10668)
		(layer "F.Cu")
		(net "M_A_CPU1_SA_CB<0>")
	)
	(segment
		(start 67.584828 -242.684808)
		(end 67.584828 -242.533932)
		(width 0.10668)
		(layer "F.Cu")
		(net "M_A_CPU1_SA_CB<0>")
	)
	(segment
		(start 67.02044 -242.12042)
		(end 67.02044 -241.969544)
		(width 0.10668)
		(layer "F.Cu")
		(net "M_A_CPU1_SA_CB<0>")
	)
	(segment
		(start 67.302888 -242.402614)
		(end 67.148202 -242.5573)
		(width 0.10668)
		(layer "F.Cu")
		(net "M_A_CPU1_SA_CB<0>")
	)
	(segment
		(start 68.149216 -243.249196)
		(end 68.149216 -243.09832)
		(width 0.10668)
		(layer "F.Cu")
		(net "M_A_CPU1_SA_CB<0>")
	)
	(segment
		(start 59.876944 -234.73537)
		(end 59.428126 -234.73537)
		(width 0.10668)
		(layer "F.Cu")
		(net "M_A_CPU1_SA_CB<0>")
	)
	(segment
		(start 68.582032 -243.531136)
		(end 68.431664 -243.53139)
		(width 0.10668)
		(layer "F.Cu")
		(net "M_A_CPU1_SA_CB<0>")
	)
	(segment
		(start 68.996052 -244.095778)
		(end 68.841366 -244.250464)
		(width 0.10668)
		(layer "F.Cu")
		(net "M_A_CPU1_SA_CB<0>")
	)
	(segment
		(start 64.89065 -240.299748)
		(end 64.739774 -240.299748)
		(width 0.10668)
		(layer "F.Cu")
		(net "M_A_CPU1_SA_CB<0>")
	)
	(segment
		(start 69.123306 -244.532658)
		(end 69.277992 -244.377972)
		(width 0.10668)
		(layer "F.Cu")
		(net "M_A_CPU1_SA_CB<0>")
	)
	(segment
		(start 67.99453 -243.403882)
		(end 68.149216 -243.249196)
		(width 0.10668)
		(layer "F.Cu")
		(net "M_A_CPU1_SA_CB<0>")
	)
	(segment
		(start 66.888868 -241.837972)
		(end 66.7385 -241.838226)
		(width 0.10668)
		(layer "F.Cu")
		(net "M_A_CPU1_SA_CB<0>")
	)
	(segment
		(start 76.397866 -244.948964)
		(end 69.38899 -244.948964)
		(width 0.10668)
		(layer "F.Cu")
		(net "M_A_CPU1_SA_CB<0>")
	)
	(segment
		(start 65.304162 -240.864136)
		(end 65.172844 -240.732818)
		(width 0.10668)
		(layer "F.Cu")
		(net "M_A_CPU1_SA_CB<0>")
	)
	(segment
		(start 65.172844 -240.732818)
		(end 65.17259 -240.581942)
		(width 0.10668)
		(layer "F.Cu")
		(net "M_A_CPU1_SA_CB<0>")
	)
	(segment
		(start 66.456052 -241.405156)
		(end 66.32448 -241.273584)
		(width 0.10668)
		(layer "F.Cu")
		(net "M_A_CPU1_SA_CB<0>")
	)
	(segment
		(start 68.431664 -243.53139)
		(end 68.276978 -243.686076)
		(width 0.10668)
		(layer "F.Cu")
		(net "M_A_CPU1_SA_CB<0>")
	)
	(segment
		(start 65.760092 -240.709196)
		(end 65.609724 -240.70945)
		(width 0.10668)
		(layer "F.Cu")
		(net "M_A_CPU1_SA_CB<0>")
	)
	(segment
		(start 65.891664 -240.991644)
		(end 65.891664 -240.840768)
		(width 0.10668)
		(layer "F.Cu")
		(net "M_A_CPU1_SA_CB<0>")
	)
	(segment
		(start 68.69049 -244.250464)
		(end 68.559172 -244.119146)
		(width 0.10668)
		(layer "F.Cu")
		(net "M_A_CPU1_SA_CB<0>")
	)
	(arc
		(start 77.498956 -245.122192)
		(mid 77.443631 -245.125623)
		(end 77.388212 -245.126764)
		(width 0.0762)
		(layer "F.Cu")
		(net "M_A_CPU1_SA_CB<0>")
	)
	(arc
		(start 77.89037 -244.998494)
		(mid 77.768514 -245.02265)
		(end 77.654912 -245.072916)
		(width 0.0762)
		(layer "F.Cu")
		(net "M_A_CPU1_SA_CB<0>")
	)
	(arc
		(start 78.408022 -244.750336)
		(mid 78.171894 -244.921771)
		(end 77.89037 -244.998494)
		(width 0.0762)
		(layer "F.Cu")
		(net "M_A_CPU1_SA_CB<0>")
	)
	(arc
		(start 77.654912 -245.072916)
		(mid 77.579672 -245.106229)
		(end 77.498956 -245.122192)
		(width 0.0762)
		(layer "F.Cu")
		(net "M_A_CPU1_SA_CB<0>")
	)
	(segment
		(start 63.848488 -254.644906)
		(end 63.741808 -254.751586)
		(width 0.10668)
		(layer "F.Cu")
		(net "M_A_CPU1_SA_CA<6>")
	)
	(segment
		(start 60.310014 -252.58522)
		(end 59.428126 -252.58522)
		(width 0.10668)
		(layer "F.Cu")
		(net "M_A_CPU1_SA_CA<6>")
	)
	(segment
		(start 65.337944 -255.009904)
		(end 65.231264 -255.116584)
		(width 0.10668)
		(layer "F.Cu")
		(net "M_A_CPU1_SA_CA<6>")
	)
	(segment
		(start 62.841378 -255.116584)
		(end 60.310014 -252.58522)
		(width 0.10668)
		(layer "F.Cu")
		(net "M_A_CPU1_SA_CA<6>")
	)
	(segment
		(start 65.736978 -254.751586)
		(end 65.630298 -254.644906)
		(width 0.10668)
		(layer "F.Cu")
		(net "M_A_CPU1_SA_CA<6>")
	)
	(segment
		(start 76.080366 -255.982724)
		(end 75.763882 -256.299208)
		(width 0.10668)
		(layer "F.Cu")
		(net "M_A_CPU1_SA_CA<6>")
	)
	(segment
		(start 64.93891 -254.751586)
		(end 64.83223 -254.644906)
		(width 0.10668)
		(layer "F.Cu")
		(net "M_A_CPU1_SA_CA<6>")
	)
	(segment
		(start 64.034162 -254.644906)
		(end 63.848488 -254.644906)
		(width 0.10668)
		(layer "F.Cu")
		(net "M_A_CPU1_SA_CA<6>")
	)
	(segment
		(start 65.843658 -255.116584)
		(end 65.736978 -255.009904)
		(width 0.10668)
		(layer "F.Cu")
		(net "M_A_CPU1_SA_CA<6>")
	)
	(segment
		(start 64.83223 -254.644906)
		(end 64.646556 -254.644906)
		(width 0.10668)
		(layer "F.Cu")
		(net "M_A_CPU1_SA_CA<6>")
	)
	(segment
		(start 75.763882 -256.299208)
		(end 74.299318 -256.299208)
		(width 0.10668)
		(layer "F.Cu")
		(net "M_A_CPU1_SA_CA<6>")
	)
	(segment
		(start 66.516758 -255.116584)
		(end 65.843658 -255.116584)
		(width 0.10668)
		(layer "F.Cu")
		(net "M_A_CPU1_SA_CA<6>")
	)
	(segment
		(start 74.299318 -256.299208)
		(end 71.880476 -253.880366)
		(width 0.10668)
		(layer "F.Cu")
		(net "M_A_CPU1_SA_CA<6>")
	)
	(segment
		(start 64.539876 -254.751586)
		(end 64.539876 -255.009904)
		(width 0.10668)
		(layer "F.Cu")
		(net "M_A_CPU1_SA_CA<6>")
	)
	(segment
		(start 79.064866 -255.60274)
		(end 79.064866 -255.602994)
		(width 0.0762)
		(layer "F.Cu")
		(net "M_A_CPU1_SA_CA<6>")
	)
	(segment
		(start 65.337944 -254.751586)
		(end 65.337944 -255.009904)
		(width 0.10668)
		(layer "F.Cu")
		(net "M_A_CPU1_SA_CA<6>")
	)
	(segment
		(start 67.752976 -253.880366)
		(end 66.516758 -255.116584)
		(width 0.10668)
		(layer "F.Cu")
		(net "M_A_CPU1_SA_CA<6>")
	)
	(segment
		(start 64.140842 -255.009904)
		(end 64.140842 -254.751586)
		(width 0.10668)
		(layer "F.Cu")
		(net "M_A_CPU1_SA_CA<6>")
	)
	(segment
		(start 64.93891 -255.009904)
		(end 64.93891 -254.751586)
		(width 0.10668)
		(layer "F.Cu")
		(net "M_A_CPU1_SA_CA<6>")
	)
	(segment
		(start 64.646556 -254.644906)
		(end 64.539876 -254.751586)
		(width 0.10668)
		(layer "F.Cu")
		(net "M_A_CPU1_SA_CA<6>")
	)
	(segment
		(start 64.140842 -254.751586)
		(end 64.034162 -254.644906)
		(width 0.10668)
		(layer "F.Cu")
		(net "M_A_CPU1_SA_CA<6>")
	)
	(segment
		(start 64.247522 -255.116584)
		(end 64.140842 -255.009904)
		(width 0.10668)
		(layer "F.Cu")
		(net "M_A_CPU1_SA_CA<6>")
	)
	(segment
		(start 63.741808 -255.009904)
		(end 63.635128 -255.116584)
		(width 0.10668)
		(layer "F.Cu")
		(net "M_A_CPU1_SA_CA<6>")
	)
	(segment
		(start 65.231264 -255.116584)
		(end 65.04559 -255.116584)
		(width 0.10668)
		(layer "F.Cu")
		(net "M_A_CPU1_SA_CA<6>")
	)
	(segment
		(start 63.635128 -255.116584)
		(end 62.841378 -255.116584)
		(width 0.10668)
		(layer "F.Cu")
		(net "M_A_CPU1_SA_CA<6>")
	)
	(segment
		(start 65.736978 -255.009904)
		(end 65.736978 -254.751586)
		(width 0.10668)
		(layer "F.Cu")
		(net "M_A_CPU1_SA_CA<6>")
	)
	(segment
		(start 76.611226 -255.451864)
		(end 76.080366 -255.982724)
		(width 0.0762)
		(layer "F.Cu")
		(net "M_A_CPU1_SA_CA<6>")
	)
	(segment
		(start 77.759306 -255.60782)
		(end 77.750924 -255.602994)
		(width 0.0762)
		(layer "F.Cu")
		(net "M_A_CPU1_SA_CA<6>")
	)
	(segment
		(start 77.273658 -255.451864)
		(end 76.611226 -255.451864)
		(width 0.0762)
		(layer "F.Cu")
		(net "M_A_CPU1_SA_CA<6>")
	)
	(segment
		(start 71.880476 -253.880366)
		(end 67.752976 -253.880366)
		(width 0.10668)
		(layer "F.Cu")
		(net "M_A_CPU1_SA_CA<6>")
	)
	(segment
		(start 65.630298 -254.644906)
		(end 65.444624 -254.644906)
		(width 0.10668)
		(layer "F.Cu")
		(net "M_A_CPU1_SA_CA<6>")
	)
	(segment
		(start 64.539876 -255.009904)
		(end 64.433196 -255.116584)
		(width 0.10668)
		(layer "F.Cu")
		(net "M_A_CPU1_SA_CA<6>")
	)
	(segment
		(start 63.741808 -254.751586)
		(end 63.741808 -255.009904)
		(width 0.10668)
		(layer "F.Cu")
		(net "M_A_CPU1_SA_CA<6>")
	)
	(segment
		(start 64.433196 -255.116584)
		(end 64.247522 -255.116584)
		(width 0.10668)
		(layer "F.Cu")
		(net "M_A_CPU1_SA_CA<6>")
	)
	(segment
		(start 65.444624 -254.644906)
		(end 65.337944 -254.751586)
		(width 0.10668)
		(layer "F.Cu")
		(net "M_A_CPU1_SA_CA<6>")
	)
	(segment
		(start 65.04559 -255.116584)
		(end 64.93891 -255.009904)
		(width 0.10668)
		(layer "F.Cu")
		(net "M_A_CPU1_SA_CA<6>")
	)
	(arc
		(start 77.750924 -255.602994)
		(mid 77.556931 -255.512387)
		(end 77.349858 -255.45796)
		(width 0.0762)
		(layer "F.Cu")
		(net "M_A_CPU1_SA_CA<6>")
	)
	(arc
		(start 79.349346 -255.526286)
		(mid 79.202025 -255.545605)
		(end 79.064866 -255.60274)
		(width 0.0762)
		(layer "F.Cu")
		(net "M_A_CPU1_SA_CA<6>")
	)
	(arc
		(start 79.064866 -255.602994)
		(mid 78.877922 -255.653249)
		(end 78.690978 -255.602994)
		(width 0.0762)
		(layer "F.Cu")
		(net "M_A_CPU1_SA_CA<6>")
	)
	(arc
		(start 77.349858 -255.45796)
		(mid 77.311885 -255.453328)
		(end 77.273658 -255.451864)
		(width 0.0762)
		(layer "F.Cu")
		(net "M_A_CPU1_SA_CA<6>")
	)
	(arc
		(start 78.125066 -255.602994)
		(mid 77.942815 -255.653344)
		(end 77.759306 -255.60782)
		(width 0.0762)
		(layer "F.Cu")
		(net "M_A_CPU1_SA_CA<6>")
	)
	(arc
		(start 78.690978 -255.602994)
		(mid 78.408022 -255.526817)
		(end 78.125066 -255.602994)
		(width 0.0762)
		(layer "F.Cu")
		(net "M_A_CPU1_SA_CA<6>")
	)
	(arc
		(start 79.817976 -255.280414)
		(mid 79.61396 -255.461108)
		(end 79.349346 -255.526286)
		(width 0.0762)
		(layer "F.Cu")
		(net "M_A_CPU1_SA_CA<6>")
	)
	(segment
		(start 58.13044 -252.160278)
		(end 57.705498 -251.735336)
		(width 0.101346)
		(layer "F.Cu")
		(net "M_A_CPU1_SA_CA<5>")
	)
	(segment
		(start 57.705498 -251.735336)
		(end 55.328058 -251.735336)
		(width 0.101346)
		(layer "F.Cu")
		(net "M_A_CPU1_SA_CA<5>")
	)
	(segment
		(start 60.534296 -252.327918)
		(end 60.366656 -252.160278)
		(width 0.101346)
		(layer "F.Cu")
		(net "M_A_CPU1_SA_CA<5>")
	)
	(segment
		(start 77.467968 -255.034034)
		(end 76.528676 -255.034034)
		(width 0.0762)
		(layer "F.Cu")
		(net "M_A_CPU1_SA_CA<5>")
	)
	(segment
		(start 66.910458 -254.241046)
		(end 62.447424 -254.241046)
		(width 0.10668)
		(layer "F.Cu")
		(net "M_A_CPU1_SA_CA<5>")
	)
	(segment
		(start 75.603862 -255.958848)
		(end 74.440542 -255.958848)
		(width 0.10668)
		(layer "F.Cu")
		(net "M_A_CPU1_SA_CA<5>")
	)
	(segment
		(start 60.366656 -252.160278)
		(end 58.13044 -252.160278)
		(width 0.101346)
		(layer "F.Cu")
		(net "M_A_CPU1_SA_CA<5>")
	)
	(segment
		(start 77.937868 -255.280414)
		(end 78.036166 -255.11125)
		(width 0.0762)
		(layer "F.Cu")
		(net "M_A_CPU1_SA_CA<5>")
	)
	(segment
		(start 77.759306 -254.953008)
		(end 77.750924 -254.957834)
		(width 0.0762)
		(layer "F.Cu")
		(net "M_A_CPU1_SA_CA<5>")
	)
	(segment
		(start 72.0217 -253.540006)
		(end 67.611498 -253.540006)
		(width 0.10668)
		(layer "F.Cu")
		(net "M_A_CPU1_SA_CA<5>")
	)
	(segment
		(start 62.447424 -254.241046)
		(end 60.534296 -252.327918)
		(width 0.10668)
		(layer "F.Cu")
		(net "M_A_CPU1_SA_CA<5>")
	)
	(segment
		(start 67.611498 -253.540006)
		(end 66.910458 -254.241046)
		(width 0.10668)
		(layer "F.Cu")
		(net "M_A_CPU1_SA_CA<5>")
	)
	(segment
		(start 74.440542 -255.958848)
		(end 72.0217 -253.540006)
		(width 0.10668)
		(layer "F.Cu")
		(net "M_A_CPU1_SA_CA<5>")
	)
	(segment
		(start 76.528676 -255.034034)
		(end 75.603862 -255.958848)
		(width 0.0762)
		(layer "F.Cu")
		(net "M_A_CPU1_SA_CA<5>")
	)
	(arc
		(start 77.750924 -254.957834)
		(mid 77.614488 -255.014659)
		(end 77.467968 -255.034034)
		(width 0.0762)
		(layer "F.Cu")
		(net "M_A_CPU1_SA_CA<5>")
	)
	(arc
		(start 78.036166 -255.11125)
		(mid 78.027573 -254.969371)
		(end 77.898498 -254.909574)
		(width 0.0762)
		(layer "F.Cu")
		(net "M_A_CPU1_SA_CA<5>")
	)
	(arc
		(start 77.898498 -254.909574)
		(mid 77.82676 -254.924426)
		(end 77.759306 -254.953008)
		(width 0.0762)
		(layer "F.Cu")
		(net "M_A_CPU1_SA_CA<5>")
	)
	(segment
		(start 64.23152 -253.306326)
		(end 64.23152 -253.689866)
		(width 0.10668)
		(layer "F.Cu")
		(net "M_A_CPU1_SA_CA<4>")
	)
	(segment
		(start 64.23152 -253.689866)
		(end 64.12484 -253.796546)
		(width 0.10668)
		(layer "F.Cu")
		(net "M_A_CPU1_SA_CA<4>")
	)
	(segment
		(start 64.630554 -253.689866)
		(end 64.630554 -253.306326)
		(width 0.10668)
		(layer "F.Cu")
		(net "M_A_CPU1_SA_CA<4>")
	)
	(segment
		(start 75.59421 -254.893064)
		(end 75.48753 -254.999744)
		(width 0.10668)
		(layer "F.Cu")
		(net "M_A_CPU1_SA_CA<4>")
	)
	(segment
		(start 63.725806 -253.199646)
		(end 61.985398 -253.199646)
		(width 0.10668)
		(layer "F.Cu")
		(net "M_A_CPU1_SA_CA<4>")
	)
	(segment
		(start 65.535302 -253.796546)
		(end 65.428622 -253.689866)
		(width 0.10668)
		(layer "F.Cu")
		(net "M_A_CPU1_SA_CA<4>")
	)
	(segment
		(start 75.38085 -255.401826)
		(end 75.195176 -255.401826)
		(width 0.10668)
		(layer "F.Cu")
		(net "M_A_CPU1_SA_CA<4>")
	)
	(segment
		(start 65.136268 -253.199646)
		(end 65.029588 -253.306326)
		(width 0.10668)
		(layer "F.Cu")
		(net "M_A_CPU1_SA_CA<4>")
	)
	(segment
		(start 65.827656 -253.689866)
		(end 65.720976 -253.796546)
		(width 0.10668)
		(layer "F.Cu")
		(net "M_A_CPU1_SA_CA<4>")
	)
	(segment
		(start 75.48753 -254.999744)
		(end 75.48753 -255.295146)
		(width 0.10668)
		(layer "F.Cu")
		(net "M_A_CPU1_SA_CA<4>")
	)
	(segment
		(start 74.689462 -255.295146)
		(end 74.582782 -255.401826)
		(width 0.10668)
		(layer "F.Cu")
		(net "M_A_CPU1_SA_CA<4>")
	)
	(segment
		(start 59.9694 -250.885198)
		(end 59.428126 -250.885198)
		(width 0.10668)
		(layer "F.Cu")
		(net "M_A_CPU1_SA_CA<4>")
	)
	(segment
		(start 77.467968 -254.843534)
		(end 76.216256 -254.843534)
		(width 0.0762)
		(layer "F.Cu")
		(net "M_A_CPU1_SA_CA<4>")
	)
	(segment
		(start 60.430156 -251.345954)
		(end 59.9694 -250.885198)
		(width 0.10668)
		(layer "F.Cu")
		(net "M_A_CPU1_SA_CA<4>")
	)
	(segment
		(start 75.088496 -255.295146)
		(end 75.088496 -254.999744)
		(width 0.10668)
		(layer "F.Cu")
		(net "M_A_CPU1_SA_CA<4>")
	)
	(segment
		(start 76.202794 -254.856996)
		(end 76.166726 -254.893064)
		(width 0.10668)
		(layer "F.Cu")
		(net "M_A_CPU1_SA_CA<4>")
	)
	(segment
		(start 75.195176 -255.401826)
		(end 75.088496 -255.295146)
		(width 0.10668)
		(layer "F.Cu")
		(net "M_A_CPU1_SA_CA<4>")
	)
	(segment
		(start 74.290428 -254.999744)
		(end 74.183748 -254.893064)
		(width 0.10668)
		(layer "F.Cu")
		(net "M_A_CPU1_SA_CA<4>")
	)
	(segment
		(start 63.939166 -253.796546)
		(end 63.832486 -253.689866)
		(width 0.10668)
		(layer "F.Cu")
		(net "M_A_CPU1_SA_CA<4>")
	)
	(segment
		(start 76.216256 -254.843534)
		(end 76.202794 -254.856996)
		(width 0.0762)
		(layer "F.Cu")
		(net "M_A_CPU1_SA_CA<4>")
	)
	(segment
		(start 64.922908 -253.796546)
		(end 64.737234 -253.796546)
		(width 0.10668)
		(layer "F.Cu")
		(net "M_A_CPU1_SA_CA<4>")
	)
	(segment
		(start 64.737234 -253.796546)
		(end 64.630554 -253.689866)
		(width 0.10668)
		(layer "F.Cu")
		(net "M_A_CPU1_SA_CA<4>")
	)
	(segment
		(start 65.934336 -253.199646)
		(end 65.827656 -253.306326)
		(width 0.10668)
		(layer "F.Cu")
		(net "M_A_CPU1_SA_CA<4>")
	)
	(segment
		(start 65.029588 -253.689866)
		(end 64.922908 -253.796546)
		(width 0.10668)
		(layer "F.Cu")
		(net "M_A_CPU1_SA_CA<4>")
	)
	(segment
		(start 74.689462 -254.999744)
		(end 74.689462 -255.295146)
		(width 0.10668)
		(layer "F.Cu")
		(net "M_A_CPU1_SA_CA<4>")
	)
	(segment
		(start 63.832486 -253.689866)
		(end 63.832486 -253.306326)
		(width 0.10668)
		(layer "F.Cu")
		(net "M_A_CPU1_SA_CA<4>")
	)
	(segment
		(start 74.183748 -254.893064)
		(end 73.856342 -254.893064)
		(width 0.10668)
		(layer "F.Cu")
		(net "M_A_CPU1_SA_CA<4>")
	)
	(segment
		(start 75.088496 -254.999744)
		(end 74.981816 -254.893064)
		(width 0.10668)
		(layer "F.Cu")
		(net "M_A_CPU1_SA_CA<4>")
	)
	(segment
		(start 65.827656 -253.306326)
		(end 65.827656 -253.689866)
		(width 0.10668)
		(layer "F.Cu")
		(net "M_A_CPU1_SA_CA<4>")
	)
	(segment
		(start 65.428622 -253.689866)
		(end 65.428622 -253.306326)
		(width 0.10668)
		(layer "F.Cu")
		(net "M_A_CPU1_SA_CA<4>")
	)
	(segment
		(start 75.48753 -255.295146)
		(end 75.38085 -255.401826)
		(width 0.10668)
		(layer "F.Cu")
		(net "M_A_CPU1_SA_CA<4>")
	)
	(segment
		(start 65.321942 -253.199646)
		(end 65.136268 -253.199646)
		(width 0.10668)
		(layer "F.Cu")
		(net "M_A_CPU1_SA_CA<4>")
	)
	(segment
		(start 63.832486 -253.306326)
		(end 63.725806 -253.199646)
		(width 0.10668)
		(layer "F.Cu")
		(net "M_A_CPU1_SA_CA<4>")
	)
	(segment
		(start 65.428622 -253.306326)
		(end 65.321942 -253.199646)
		(width 0.10668)
		(layer "F.Cu")
		(net "M_A_CPU1_SA_CA<4>")
	)
	(segment
		(start 74.290428 -255.295146)
		(end 74.290428 -254.999744)
		(width 0.10668)
		(layer "F.Cu")
		(net "M_A_CPU1_SA_CA<4>")
	)
	(segment
		(start 72.162924 -253.199646)
		(end 65.934336 -253.199646)
		(width 0.10668)
		(layer "F.Cu")
		(net "M_A_CPU1_SA_CA<4>")
	)
	(segment
		(start 61.985398 -253.199646)
		(end 60.430156 -251.644404)
		(width 0.10668)
		(layer "F.Cu")
		(net "M_A_CPU1_SA_CA<4>")
	)
	(segment
		(start 74.397108 -255.401826)
		(end 74.290428 -255.295146)
		(width 0.10668)
		(layer "F.Cu")
		(net "M_A_CPU1_SA_CA<4>")
	)
	(segment
		(start 65.029588 -253.306326)
		(end 65.029588 -253.689866)
		(width 0.10668)
		(layer "F.Cu")
		(net "M_A_CPU1_SA_CA<4>")
	)
	(segment
		(start 64.523874 -253.199646)
		(end 64.3382 -253.199646)
		(width 0.10668)
		(layer "F.Cu")
		(net "M_A_CPU1_SA_CA<4>")
	)
	(segment
		(start 64.12484 -253.796546)
		(end 63.939166 -253.796546)
		(width 0.10668)
		(layer "F.Cu")
		(net "M_A_CPU1_SA_CA<4>")
	)
	(segment
		(start 64.3382 -253.199646)
		(end 64.23152 -253.306326)
		(width 0.10668)
		(layer "F.Cu")
		(net "M_A_CPU1_SA_CA<4>")
	)
	(segment
		(start 74.796142 -254.893064)
		(end 74.689462 -254.999744)
		(width 0.10668)
		(layer "F.Cu")
		(net "M_A_CPU1_SA_CA<4>")
	)
	(segment
		(start 74.981816 -254.893064)
		(end 74.796142 -254.893064)
		(width 0.10668)
		(layer "F.Cu")
		(net "M_A_CPU1_SA_CA<4>")
	)
	(segment
		(start 65.720976 -253.796546)
		(end 65.535302 -253.796546)
		(width 0.10668)
		(layer "F.Cu")
		(net "M_A_CPU1_SA_CA<4>")
	)
	(segment
		(start 74.582782 -255.401826)
		(end 74.397108 -255.401826)
		(width 0.10668)
		(layer "F.Cu")
		(net "M_A_CPU1_SA_CA<4>")
	)
	(segment
		(start 73.856342 -254.893064)
		(end 72.162924 -253.199646)
		(width 0.10668)
		(layer "F.Cu")
		(net "M_A_CPU1_SA_CA<4>")
	)
	(segment
		(start 64.630554 -253.306326)
		(end 64.523874 -253.199646)
		(width 0.10668)
		(layer "F.Cu")
		(net "M_A_CPU1_SA_CA<4>")
	)
	(segment
		(start 76.166726 -254.893064)
		(end 75.59421 -254.893064)
		(width 0.10668)
		(layer "F.Cu")
		(net "M_A_CPU1_SA_CA<4>")
	)
	(segment
		(start 60.430156 -251.644404)
		(end 60.430156 -251.345954)
		(width 0.10668)
		(layer "F.Cu")
		(net "M_A_CPU1_SA_CA<4>")
	)
	(arc
		(start 77.654912 -254.792988)
		(mid 77.564779 -254.830608)
		(end 77.467968 -254.843534)
		(width 0.0762)
		(layer "F.Cu")
		(net "M_A_CPU1_SA_CA<4>")
	)
	(arc
		(start 77.880718 -254.719582)
		(mid 77.763905 -254.744258)
		(end 77.654912 -254.792988)
		(width 0.0762)
		(layer "F.Cu")
		(net "M_A_CPU1_SA_CA<4>")
	)
	(arc
		(start 78.408022 -254.470408)
		(mid 78.165705 -254.640128)
		(end 77.880718 -254.719582)
		(width 0.0762)
		(layer "F.Cu")
		(net "M_A_CPU1_SA_CA<4>")
	)
	(segment
		(start 60.770516 -251.502672)
		(end 60.770516 -250.893326)
		(width 0.10668)
		(layer "F.Cu")
		(net "M_A_CPU1_SA_CA<3>")
	)
	(segment
		(start 73.997566 -254.552704)
		(end 72.304148 -252.859286)
		(width 0.10668)
		(layer "F.Cu")
		(net "M_A_CPU1_SA_CA<3>")
	)
	(segment
		(start 58.13044 -250.460256)
		(end 57.705498 -250.035314)
		(width 0.101346)
		(layer "F.Cu")
		(net "M_A_CPU1_SA_CA<3>")
	)
	(segment
		(start 76.481686 -254.092964)
		(end 76.256896 -254.317754)
		(width 0.0762)
		(layer "F.Cu")
		(net "M_A_CPU1_SA_CA<3>")
	)
	(segment
		(start 78.594966 -254.147828)
		(end 78.586584 -254.143002)
		(width 0.0762)
		(layer "F.Cu")
		(net "M_A_CPU1_SA_CA<3>")
	)
	(segment
		(start 77.451458 -254.092964)
		(end 76.481686 -254.092964)
		(width 0.0762)
		(layer "F.Cu")
		(net "M_A_CPU1_SA_CA<3>")
	)
	(segment
		(start 79.168244 -254.14351)
		(end 79.160878 -254.147828)
		(width 0.0762)
		(layer "F.Cu")
		(net "M_A_CPU1_SA_CA<3>")
	)
	(segment
		(start 79.16926 -254.143002)
		(end 79.168244 -254.14351)
		(width 0.0762)
		(layer "F.Cu")
		(net "M_A_CPU1_SA_CA<3>")
	)
	(segment
		(start 76.021946 -254.552704)
		(end 73.997566 -254.552704)
		(width 0.10668)
		(layer "F.Cu")
		(net "M_A_CPU1_SA_CA<3>")
	)
	(segment
		(start 76.256896 -254.317754)
		(end 76.021946 -254.552704)
		(width 0.10668)
		(layer "F.Cu")
		(net "M_A_CPU1_SA_CA<3>")
	)
	(segment
		(start 79.347822 -254.470154)
		(end 79.452978 -254.289306)
		(width 0.0762)
		(layer "F.Cu")
		(net "M_A_CPU1_SA_CA<3>")
	)
	(segment
		(start 57.705498 -250.035314)
		(end 55.328058 -250.035314)
		(width 0.101346)
		(layer "F.Cu")
		(net "M_A_CPU1_SA_CA<3>")
	)
	(segment
		(start 60.505086 -250.627896)
		(end 60.337446 -250.460256)
		(width 0.101346)
		(layer "F.Cu")
		(net "M_A_CPU1_SA_CA<3>")
	)
	(segment
		(start 72.304148 -252.859286)
		(end 62.12713 -252.859286)
		(width 0.10668)
		(layer "F.Cu")
		(net "M_A_CPU1_SA_CA<3>")
	)
	(segment
		(start 60.770516 -250.893326)
		(end 60.505086 -250.627896)
		(width 0.10668)
		(layer "F.Cu")
		(net "M_A_CPU1_SA_CA<3>")
	)
	(segment
		(start 62.12713 -252.859286)
		(end 60.770516 -251.502672)
		(width 0.10668)
		(layer "F.Cu")
		(net "M_A_CPU1_SA_CA<3>")
	)
	(segment
		(start 60.337446 -250.460256)
		(end 58.13044 -250.460256)
		(width 0.101346)
		(layer "F.Cu")
		(net "M_A_CPU1_SA_CA<3>")
	)
	(segment
		(start 79.347822 -254.470408)
		(end 79.347822 -254.470154)
		(width 0.0762)
		(layer "F.Cu")
		(net "M_A_CPU1_SA_CA<3>")
	)
	(arc
		(start 79.160878 -254.147828)
		(mid 78.877922 -254.224005)
		(end 78.594966 -254.147828)
		(width 0.0762)
		(layer "F.Cu")
		(net "M_A_CPU1_SA_CA<3>")
	)
	(arc
		(start 78.586584 -254.143002)
		(mid 78.403076 -254.097508)
		(end 78.220824 -254.147828)
		(width 0.0762)
		(layer "F.Cu")
		(net "M_A_CPU1_SA_CA<3>")
	)
	(arc
		(start 79.349346 -254.097536)
		(mid 79.256422 -254.108859)
		(end 79.16926 -254.143002)
		(width 0.0762)
		(layer "F.Cu")
		(net "M_A_CPU1_SA_CA<3>")
	)
	(arc
		(start 77.654912 -254.147828)
		(mid 77.556815 -254.106941)
		(end 77.451458 -254.092964)
		(width 0.0762)
		(layer "F.Cu")
		(net "M_A_CPU1_SA_CA<3>")
	)
	(arc
		(start 78.220824 -254.147828)
		(mid 77.937868 -254.224005)
		(end 77.654912 -254.147828)
		(width 0.0762)
		(layer "F.Cu")
		(net "M_A_CPU1_SA_CA<3>")
	)
	(arc
		(start 79.452978 -254.289306)
		(mid 79.444041 -254.170282)
		(end 79.349346 -254.097536)
		(width 0.0762)
		(layer "F.Cu")
		(net "M_A_CPU1_SA_CA<3>")
	)
	(segment
		(start 72.445372 -252.518926)
		(end 62.999874 -252.518926)
		(width 0.10668)
		(layer "F.Cu")
		(net "M_A_CPU1_SA_CA<2>")
	)
	(segment
		(start 75.879706 -254.212344)
		(end 74.13879 -254.212344)
		(width 0.10668)
		(layer "F.Cu")
		(net "M_A_CPU1_SA_CA<2>")
	)
	(segment
		(start 61.743082 -251.737622)
		(end 61.592206 -251.737622)
		(width 0.10668)
		(layer "F.Cu")
		(net "M_A_CPU1_SA_CA<2>")
	)
	(segment
		(start 77.16901 -253.826264)
		(end 76.265786 -253.826264)
		(width 0.0762)
		(layer "F.Cu")
		(net "M_A_CPU1_SA_CA<2>")
	)
	(segment
		(start 62.025276 -252.019816)
		(end 62.187582 -251.85751)
		(width 0.10668)
		(layer "F.Cu")
		(net "M_A_CPU1_SA_CA<2>")
	)
	(segment
		(start 60.42787 -249.946922)
		(end 60.42787 -249.35053)
		(width 0.10668)
		(layer "F.Cu")
		(net "M_A_CPU1_SA_CA<2>")
	)
	(segment
		(start 74.13879 -254.212344)
		(end 72.445372 -252.518926)
		(width 0.10668)
		(layer "F.Cu")
		(net "M_A_CPU1_SA_CA<2>")
	)
	(segment
		(start 61.460888 -251.606304)
		(end 61.460888 -251.455428)
		(width 0.10668)
		(layer "F.Cu")
		(net "M_A_CPU1_SA_CA<2>")
	)
	(segment
		(start 60.26277 -249.18543)
		(end 59.428126 -249.18543)
		(width 0.10668)
		(layer "F.Cu")
		(net "M_A_CPU1_SA_CA<2>")
	)
	(segment
		(start 62.999874 -252.518926)
		(end 62.620652 -252.139704)
		(width 0.10668)
		(layer "F.Cu")
		(net "M_A_CPU1_SA_CA<2>")
	)
	(segment
		(start 77.759306 -253.987808)
		(end 77.750924 -253.982982)
		(width 0.0762)
		(layer "F.Cu")
		(net "M_A_CPU1_SA_CA<2>")
	)
	(segment
		(start 62.156594 -252.30201)
		(end 62.025276 -252.170692)
		(width 0.10668)
		(layer "F.Cu")
		(net "M_A_CPU1_SA_CA<2>")
	)
	(segment
		(start 62.187582 -251.706634)
		(end 62.056264 -251.575316)
		(width 0.10668)
		(layer "F.Cu")
		(net "M_A_CPU1_SA_CA<2>")
	)
	(segment
		(start 62.187582 -251.85751)
		(end 62.187582 -251.706634)
		(width 0.10668)
		(layer "F.Cu")
		(net "M_A_CPU1_SA_CA<2>")
	)
	(segment
		(start 61.623194 -251.293122)
		(end 61.623194 -251.142246)
		(width 0.10668)
		(layer "F.Cu")
		(net "M_A_CPU1_SA_CA<2>")
	)
	(segment
		(start 62.620652 -252.139704)
		(end 62.469776 -252.139704)
		(width 0.10668)
		(layer "F.Cu")
		(net "M_A_CPU1_SA_CA<2>")
	)
	(segment
		(start 62.469776 -252.139704)
		(end 62.30747 -252.30201)
		(width 0.10668)
		(layer "F.Cu")
		(net "M_A_CPU1_SA_CA<2>")
	)
	(segment
		(start 61.460888 -251.455428)
		(end 61.623194 -251.293122)
		(width 0.10668)
		(layer "F.Cu")
		(net "M_A_CPU1_SA_CA<2>")
	)
	(segment
		(start 62.056264 -251.575316)
		(end 61.905388 -251.575316)
		(width 0.10668)
		(layer "F.Cu")
		(net "M_A_CPU1_SA_CA<2>")
	)
	(segment
		(start 61.592206 -251.737622)
		(end 61.460888 -251.606304)
		(width 0.10668)
		(layer "F.Cu")
		(net "M_A_CPU1_SA_CA<2>")
	)
	(segment
		(start 76.265786 -253.826264)
		(end 76.023216 -254.068834)
		(width 0.0762)
		(layer "F.Cu")
		(net "M_A_CPU1_SA_CA<2>")
	)
	(segment
		(start 62.30747 -252.30201)
		(end 62.156594 -252.30201)
		(width 0.10668)
		(layer "F.Cu")
		(net "M_A_CPU1_SA_CA<2>")
	)
	(segment
		(start 61.623194 -251.142246)
		(end 60.42787 -249.946922)
		(width 0.10668)
		(layer "F.Cu")
		(net "M_A_CPU1_SA_CA<2>")
	)
	(segment
		(start 60.42787 -249.35053)
		(end 60.26277 -249.18543)
		(width 0.10668)
		(layer "F.Cu")
		(net "M_A_CPU1_SA_CA<2>")
	)
	(segment
		(start 61.905388 -251.575316)
		(end 61.743082 -251.737622)
		(width 0.10668)
		(layer "F.Cu")
		(net "M_A_CPU1_SA_CA<2>")
	)
	(segment
		(start 79.064866 -253.982728)
		(end 79.064866 -253.982982)
		(width 0.0762)
		(layer "F.Cu")
		(net "M_A_CPU1_SA_CA<2>")
	)
	(segment
		(start 76.023216 -254.068834)
		(end 75.879706 -254.212344)
		(width 0.10668)
		(layer "F.Cu")
		(net "M_A_CPU1_SA_CA<2>")
	)
	(segment
		(start 62.025276 -252.170692)
		(end 62.025276 -252.019816)
		(width 0.10668)
		(layer "F.Cu")
		(net "M_A_CPU1_SA_CA<2>")
	)
	(arc
		(start 79.064866 -253.982982)
		(mid 78.877922 -254.033237)
		(end 78.690978 -253.982982)
		(width 0.0762)
		(layer "F.Cu")
		(net "M_A_CPU1_SA_CA<2>")
	)
	(arc
		(start 77.750924 -253.982982)
		(mid 77.470333 -253.866132)
		(end 77.16901 -253.826264)
		(width 0.0762)
		(layer "F.Cu")
		(net "M_A_CPU1_SA_CA<2>")
	)
	(arc
		(start 79.817976 -253.660402)
		(mid 79.61396 -253.841096)
		(end 79.349346 -253.906274)
		(width 0.0762)
		(layer "F.Cu")
		(net "M_A_CPU1_SA_CA<2>")
	)
	(arc
		(start 78.125066 -253.982982)
		(mid 77.942815 -254.033332)
		(end 77.759306 -253.987808)
		(width 0.0762)
		(layer "F.Cu")
		(net "M_A_CPU1_SA_CA<2>")
	)
	(arc
		(start 79.349346 -253.906274)
		(mid 79.202025 -253.925593)
		(end 79.064866 -253.982728)
		(width 0.0762)
		(layer "F.Cu")
		(net "M_A_CPU1_SA_CA<2>")
	)
	(arc
		(start 78.690978 -253.982982)
		(mid 78.408022 -253.906805)
		(end 78.125066 -253.982982)
		(width 0.0762)
		(layer "F.Cu")
		(net "M_A_CPU1_SA_CA<2>")
	)
	(segment
		(start 58.13044 -248.760234)
		(end 57.705498 -248.335292)
		(width 0.101346)
		(layer "F.Cu")
		(net "M_A_CPU1_SA_CA<1>")
	)
	(segment
		(start 77.051154 -253.526544)
		(end 76.082906 -253.526544)
		(width 0.0762)
		(layer "F.Cu")
		(net "M_A_CPU1_SA_CA<1>")
	)
	(segment
		(start 60.76823 -249.209306)
		(end 60.513468 -248.954544)
		(width 0.10668)
		(layer "F.Cu")
		(net "M_A_CPU1_SA_CA<1>")
	)
	(segment
		(start 77.759306 -253.332996)
		(end 77.750924 -253.337822)
		(width 0.0762)
		(layer "F.Cu")
		(net "M_A_CPU1_SA_CA<1>")
	)
	(segment
		(start 75.990196 -253.619254)
		(end 75.737466 -253.871984)
		(width 0.10668)
		(layer "F.Cu")
		(net "M_A_CPU1_SA_CA<1>")
	)
	(segment
		(start 57.705498 -248.335292)
		(end 55.328058 -248.335292)
		(width 0.101346)
		(layer "F.Cu")
		(net "M_A_CPU1_SA_CA<1>")
	)
	(segment
		(start 60.513468 -248.954544)
		(end 60.319158 -248.760234)
		(width 0.101346)
		(layer "F.Cu")
		(net "M_A_CPU1_SA_CA<1>")
	)
	(segment
		(start 74.280014 -253.871984)
		(end 72.586596 -252.178566)
		(width 0.10668)
		(layer "F.Cu")
		(net "M_A_CPU1_SA_CA<1>")
	)
	(segment
		(start 75.737466 -253.871984)
		(end 74.280014 -253.871984)
		(width 0.10668)
		(layer "F.Cu")
		(net "M_A_CPU1_SA_CA<1>")
	)
	(segment
		(start 60.319158 -248.760234)
		(end 58.13044 -248.760234)
		(width 0.101346)
		(layer "F.Cu")
		(net "M_A_CPU1_SA_CA<1>")
	)
	(segment
		(start 60.76823 -249.805698)
		(end 60.76823 -249.209306)
		(width 0.10668)
		(layer "F.Cu")
		(net "M_A_CPU1_SA_CA<1>")
	)
	(segment
		(start 63.141098 -252.178566)
		(end 60.76823 -249.805698)
		(width 0.10668)
		(layer "F.Cu")
		(net "M_A_CPU1_SA_CA<1>")
	)
	(segment
		(start 77.937868 -253.660402)
		(end 78.030832 -253.500382)
		(width 0.0762)
		(layer "F.Cu")
		(net "M_A_CPU1_SA_CA<1>")
	)
	(segment
		(start 72.586596 -252.178566)
		(end 63.141098 -252.178566)
		(width 0.10668)
		(layer "F.Cu")
		(net "M_A_CPU1_SA_CA<1>")
	)
	(segment
		(start 76.082906 -253.526544)
		(end 75.990196 -253.619254)
		(width 0.0762)
		(layer "F.Cu")
		(net "M_A_CPU1_SA_CA<1>")
	)
	(arc
		(start 78.030832 -253.500382)
		(mid 78.030672 -253.353821)
		(end 77.899006 -253.289562)
		(width 0.0762)
		(layer "F.Cu")
		(net "M_A_CPU1_SA_CA<1>")
	)
	(arc
		(start 77.750924 -253.337822)
		(mid 77.413541 -253.47854)
		(end 77.051154 -253.526544)
		(width 0.0762)
		(layer "F.Cu")
		(net "M_A_CPU1_SA_CA<1>")
	)
	(arc
		(start 77.899006 -253.289562)
		(mid 77.826998 -253.304344)
		(end 77.759306 -253.332996)
		(width 0.0762)
		(layer "F.Cu")
		(net "M_A_CPU1_SA_CA<1>")
	)
	(segment
		(start 72.72782 -251.838206)
		(end 63.282576 -251.838206)
		(width 0.10668)
		(layer "F.Cu")
		(net "M_A_CPU1_SA_CA<0>")
	)
	(segment
		(start 60.40501 -247.985788)
		(end 59.90463 -247.485408)
		(width 0.10668)
		(layer "F.Cu")
		(net "M_A_CPU1_SA_CA<0>")
	)
	(segment
		(start 75.410568 -252.696726)
		(end 75.303888 -252.590046)
		(width 0.10668)
		(layer "F.Cu")
		(net "M_A_CPU1_SA_CA<0>")
	)
	(segment
		(start 61.10859 -249.66422)
		(end 61.10859 -249.064526)
		(width 0.10668)
		(layer "F.Cu")
		(net "M_A_CPU1_SA_CA<0>")
	)
	(segment
		(start 74.012298 -252.571504)
		(end 73.812146 -252.771656)
		(width 0.10668)
		(layer "F.Cu")
		(net "M_A_CPU1_SA_CA<0>")
	)
	(segment
		(start 75.861926 -253.229364)
		(end 75.742546 -253.348744)
		(width 0.10668)
		(layer "F.Cu")
		(net "M_A_CPU1_SA_CA<0>")
	)
	(segment
		(start 73.812146 -252.771656)
		(end 73.66127 -252.771656)
		(width 0.10668)
		(layer "F.Cu")
		(net "M_A_CPU1_SA_CA<0>")
	)
	(segment
		(start 75.303888 -252.590046)
		(end 75.118214 -252.590046)
		(width 0.10668)
		(layer "F.Cu")
		(net "M_A_CPU1_SA_CA<0>")
	)
	(segment
		(start 75.517248 -253.348744)
		(end 75.410568 -253.242064)
		(width 0.10668)
		(layer "F.Cu")
		(net "M_A_CPU1_SA_CA<0>")
	)
	(segment
		(start 74.294492 -252.853952)
		(end 74.294492 -252.703076)
		(width 0.10668)
		(layer "F.Cu")
		(net "M_A_CPU1_SA_CA<0>")
	)
	(segment
		(start 74.294492 -252.703076)
		(end 74.163174 -252.571758)
		(width 0.10668)
		(layer "F.Cu")
		(net "M_A_CPU1_SA_CA<0>")
	)
	(segment
		(start 60.641738 -248.597674)
		(end 60.40501 -248.360946)
		(width 0.10668)
		(layer "F.Cu")
		(net "M_A_CPU1_SA_CA<0>")
	)
	(segment
		(start 75.011534 -252.696726)
		(end 75.011534 -253.242064)
		(width 0.10668)
		(layer "F.Cu")
		(net "M_A_CPU1_SA_CA<0>")
	)
	(segment
		(start 75.011534 -253.242064)
		(end 74.904854 -253.348744)
		(width 0.10668)
		(layer "F.Cu")
		(net "M_A_CPU1_SA_CA<0>")
	)
	(segment
		(start 61.10859 -249.064526)
		(end 60.67044 -248.626376)
		(width 0.10668)
		(layer "F.Cu")
		(net "M_A_CPU1_SA_CA<0>")
	)
	(segment
		(start 60.67044 -248.626376)
		(end 60.641738 -248.597674)
		(width 0.101346)
		(layer "F.Cu")
		(net "M_A_CPU1_SA_CA<0>")
	)
	(segment
		(start 74.09434 -253.054104)
		(end 74.294492 -252.853952)
		(width 0.10668)
		(layer "F.Cu")
		(net "M_A_CPU1_SA_CA<0>")
	)
	(segment
		(start 75.410568 -253.242064)
		(end 75.410568 -252.696726)
		(width 0.10668)
		(layer "F.Cu")
		(net "M_A_CPU1_SA_CA<0>")
	)
	(segment
		(start 75.118214 -252.590046)
		(end 75.011534 -252.696726)
		(width 0.10668)
		(layer "F.Cu")
		(net "M_A_CPU1_SA_CA<0>")
	)
	(segment
		(start 74.904854 -253.348744)
		(end 74.238358 -253.348744)
		(width 0.10668)
		(layer "F.Cu")
		(net "M_A_CPU1_SA_CA<0>")
	)
	(segment
		(start 74.163174 -252.571758)
		(end 74.012298 -252.571504)
		(width 0.10668)
		(layer "F.Cu")
		(net "M_A_CPU1_SA_CA<0>")
	)
	(segment
		(start 73.66127 -252.771656)
		(end 72.72782 -251.838206)
		(width 0.10668)
		(layer "F.Cu")
		(net "M_A_CPU1_SA_CA<0>")
	)
	(segment
		(start 74.094086 -253.204472)
		(end 74.09434 -253.054104)
		(width 0.10668)
		(layer "F.Cu")
		(net "M_A_CPU1_SA_CA<0>")
	)
	(segment
		(start 59.90463 -247.485408)
		(end 59.428126 -247.485408)
		(width 0.10668)
		(layer "F.Cu")
		(net "M_A_CPU1_SA_CA<0>")
	)
	(segment
		(start 63.282576 -251.838206)
		(end 61.10859 -249.66422)
		(width 0.10668)
		(layer "F.Cu")
		(net "M_A_CPU1_SA_CA<0>")
	)
	(segment
		(start 60.40501 -248.360946)
		(end 60.40501 -247.985788)
		(width 0.10668)
		(layer "F.Cu")
		(net "M_A_CPU1_SA_CA<0>")
	)
	(segment
		(start 77.44587 -253.229364)
		(end 75.861926 -253.229364)
		(width 0.0762)
		(layer "F.Cu")
		(net "M_A_CPU1_SA_CA<0>")
	)
	(segment
		(start 75.742546 -253.348744)
		(end 75.517248 -253.348744)
		(width 0.10668)
		(layer "F.Cu")
		(net "M_A_CPU1_SA_CA<0>")
	)
	(segment
		(start 74.238358 -253.348744)
		(end 74.094086 -253.204472)
		(width 0.10668)
		(layer "F.Cu")
		(net "M_A_CPU1_SA_CA<0>")
	)
	(arc
		(start 78.408022 -252.850396)
		(mid 78.171894 -253.021831)
		(end 77.89037 -253.098554)
		(width 0.0762)
		(layer "F.Cu")
		(net "M_A_CPU1_SA_CA<0>")
	)
	(arc
		(start 77.654912 -253.172976)
		(mid 77.554129 -253.215033)
		(end 77.44587 -253.229364)
		(width 0.0762)
		(layer "F.Cu")
		(net "M_A_CPU1_SA_CA<0>")
	)
	(arc
		(start 77.89037 -253.098554)
		(mid 77.768514 -253.12271)
		(end 77.654912 -253.172976)
		(width 0.0762)
		(layer "F.Cu")
		(net "M_A_CPU1_SA_CA<0>")
	)
	(segment
		(start 61.65977 -246.685054)
		(end 60.67044 -245.695724)
		(width 0.10668)
		(layer "F.Cu")
		(net "M_A_CPU1_RESET_N")
	)
	(segment
		(start 60.334906 -245.36019)
		(end 57.115964 -245.36019)
		(width 0.101346)
		(layer "F.Cu")
		(net "M_A_CPU1_RESET_N")
	)
	(segment
		(start 74.120502 -250.770644)
		(end 73.864724 -250.514866)
		(width 0.10668)
		(layer "F.Cu")
		(net "M_A_CPU1_RESET_N")
	)
	(segment
		(start 77.587602 -250.770644)
		(end 74.120502 -250.770644)
		(width 0.10668)
		(layer "F.Cu")
		(net "M_A_CPU1_RESET_N")
	)
	(segment
		(start 60.67044 -245.695724)
		(end 60.334906 -245.36019)
		(width 0.101346)
		(layer "F.Cu")
		(net "M_A_CPU1_RESET_N")
	)
	(segment
		(start 62.36335 -249.136916)
		(end 62.36335 -248.543826)
		(width 0.10668)
		(layer "F.Cu")
		(net "M_A_CPU1_RESET_N")
	)
	(segment
		(start 62.36335 -248.543826)
		(end 61.65977 -247.840246)
		(width 0.10668)
		(layer "F.Cu")
		(net "M_A_CPU1_RESET_N")
	)
	(segment
		(start 77.937868 -250.420378)
		(end 77.587602 -250.770644)
		(width 0.10668)
		(layer "F.Cu")
		(net "M_A_CPU1_RESET_N")
	)
	(segment
		(start 63.7413 -250.514866)
		(end 62.36335 -249.136916)
		(width 0.10668)
		(layer "F.Cu")
		(net "M_A_CPU1_RESET_N")
	)
	(segment
		(start 56.691022 -244.935248)
		(end 55.328058 -244.935248)
		(width 0.101346)
		(layer "F.Cu")
		(net "M_A_CPU1_RESET_N")
	)
	(segment
		(start 61.65977 -247.840246)
		(end 61.65977 -246.685054)
		(width 0.10668)
		(layer "F.Cu")
		(net "M_A_CPU1_RESET_N")
	)
	(segment
		(start 57.115964 -245.36019)
		(end 56.691022 -244.935248)
		(width 0.101346)
		(layer "F.Cu")
		(net "M_A_CPU1_RESET_N")
	)
	(segment
		(start 73.864724 -250.514866)
		(end 63.7413 -250.514866)
		(width 0.10668)
		(layer "F.Cu")
		(net "M_A_CPU1_RESET_N")
	)
	(segment
		(start 71.541132 -254.698246)
		(end 68.092066 -254.698246)
		(width 0.14732)
		(layer "F.Cu")
		(net "M_A_CPU1_CLK_DP<0>")
	)
	(segment
		(start 76.03998 -257.517646)
		(end 74.360532 -257.517646)
		(width 0.14732)
		(layer "F.Cu")
		(net "M_A_CPU1_CLK_DP<0>")
	)
	(segment
		(start 76.705714 -256.958084)
		(end 76.599542 -256.958084)
		(width 0.0762)
		(layer "F.Cu")
		(net "M_A_CPU1_CLK_DP<0>")
	)
	(segment
		(start 57.683146 -255.0287)
		(end 57.683146 -254.35306)
		(width 0.14732)
		(layer "F.Cu")
		(net "M_A_CPU1_CLK_DP<0>")
	)
	(segment
		(start 77.196442 -256.467356)
		(end 76.705714 -256.958084)
		(width 0.0762)
		(layer "F.Cu")
		(net "M_A_CPU1_CLK_DP<0>")
	)
	(segment
		(start 56.083962 -253.69012)
		(end 55.8292 -253.435358)
		(width 0.14732)
		(layer "F.Cu")
		(net "M_A_CPU1_CLK_DP<0>")
	)
	(segment
		(start 57.683146 -254.35306)
		(end 57.020206 -253.69012)
		(width 0.14732)
		(layer "F.Cu")
		(net "M_A_CPU1_CLK_DP<0>")
	)
	(segment
		(start 58.58891 -255.934464)
		(end 57.683146 -255.0287)
		(width 0.14732)
		(layer "F.Cu")
		(net "M_A_CPU1_CLK_DP<0>")
	)
	(segment
		(start 76.58608 -256.971546)
		(end 76.03998 -257.517646)
		(width 0.14732)
		(layer "F.Cu")
		(net "M_A_CPU1_CLK_DP<0>")
	)
	(segment
		(start 76.599542 -256.958084)
		(end 76.58608 -256.971546)
		(width 0.0762)
		(layer "F.Cu")
		(net "M_A_CPU1_CLK_DP<0>")
	)
	(segment
		(start 68.092066 -254.698246)
		(end 66.855848 -255.934464)
		(width 0.14732)
		(layer "F.Cu")
		(net "M_A_CPU1_CLK_DP<0>")
	)
	(segment
		(start 55.8292 -253.435358)
		(end 55.328058 -253.435358)
		(width 0.14732)
		(layer "F.Cu")
		(net "M_A_CPU1_CLK_DP<0>")
	)
	(segment
		(start 77.37602 -256.467356)
		(end 77.196442 -256.467356)
		(width 0.0762)
		(layer "F.Cu")
		(net "M_A_CPU1_CLK_DP<0>")
	)
	(segment
		(start 74.360532 -257.517646)
		(end 71.541132 -254.698246)
		(width 0.14732)
		(layer "F.Cu")
		(net "M_A_CPU1_CLK_DP<0>")
	)
	(segment
		(start 66.855848 -255.934464)
		(end 58.58891 -255.934464)
		(width 0.14732)
		(layer "F.Cu")
		(net "M_A_CPU1_CLK_DP<0>")
	)
	(segment
		(start 57.020206 -253.69012)
		(end 56.083962 -253.69012)
		(width 0.14732)
		(layer "F.Cu")
		(net "M_A_CPU1_CLK_DP<0>")
	)
	(arc
		(start 77.89037 -256.338578)
		(mid 77.768514 -256.362734)
		(end 77.654912 -256.413)
		(width 0.0762)
		(layer "F.Cu")
		(net "M_A_CPU1_CLK_DP<0>")
	)
	(arc
		(start 77.654912 -256.413)
		(mid 77.579672 -256.446313)
		(end 77.498956 -256.462276)
		(width 0.0762)
		(layer "F.Cu")
		(net "M_A_CPU1_CLK_DP<0>")
	)
	(arc
		(start 77.498956 -256.462276)
		(mid 77.43754 -256.466081)
		(end 77.37602 -256.467356)
		(width 0.0762)
		(layer "F.Cu")
		(net "M_A_CPU1_CLK_DP<0>")
	)
	(arc
		(start 78.408022 -256.09042)
		(mid 78.171894 -256.261855)
		(end 77.89037 -256.338578)
		(width 0.0762)
		(layer "F.Cu")
		(net "M_A_CPU1_CLK_DP<0>")
	)
	(segment
		(start 74.219308 -257.858006)
		(end 71.399908 -255.038606)
		(width 0.14732)
		(layer "F.Cu")
		(net "M_A_CPU1_CLK_DN<0>")
	)
	(segment
		(start 76.181204 -257.858006)
		(end 74.219308 -257.858006)
		(width 0.14732)
		(layer "F.Cu")
		(net "M_A_CPU1_CLK_DN<0>")
	)
	(segment
		(start 57.342786 -254.494284)
		(end 56.878982 -254.03048)
		(width 0.14732)
		(layer "F.Cu")
		(net "M_A_CPU1_CLK_DN<0>")
	)
	(segment
		(start 55.829708 -254.285242)
		(end 55.328058 -254.285242)
		(width 0.14732)
		(layer "F.Cu")
		(net "M_A_CPU1_CLK_DN<0>")
	)
	(segment
		(start 76.840334 -257.092958)
		(end 76.840334 -257.198876)
		(width 0.0762)
		(layer "F.Cu")
		(net "M_A_CPU1_CLK_DN<0>")
	)
	(segment
		(start 77.937868 -256.900426)
		(end 78.030832 -256.740406)
		(width 0.0762)
		(layer "F.Cu")
		(net "M_A_CPU1_CLK_DN<0>")
	)
	(segment
		(start 76.840334 -257.198876)
		(end 76.826872 -257.212338)
		(width 0.0762)
		(layer "F.Cu")
		(net "M_A_CPU1_CLK_DN<0>")
	)
	(segment
		(start 56.878982 -254.03048)
		(end 56.08447 -254.03048)
		(width 0.14732)
		(layer "F.Cu")
		(net "M_A_CPU1_CLK_DN<0>")
	)
	(segment
		(start 77.373988 -256.658872)
		(end 77.276452 -256.658872)
		(width 0.0762)
		(layer "F.Cu")
		(net "M_A_CPU1_CLK_DN<0>")
	)
	(segment
		(start 77.515212 -256.652268)
		(end 77.51445 -256.653284)
		(width 0.0762)
		(layer "F.Cu")
		(net "M_A_CPU1_CLK_DN<0>")
	)
	(segment
		(start 66.997072 -256.274824)
		(end 58.447686 -256.274824)
		(width 0.14732)
		(layer "F.Cu")
		(net "M_A_CPU1_CLK_DN<0>")
	)
	(segment
		(start 77.759306 -256.57302)
		(end 77.750924 -256.577846)
		(width 0.0762)
		(layer "F.Cu")
		(net "M_A_CPU1_CLK_DN<0>")
	)
	(segment
		(start 68.23329 -255.038606)
		(end 66.997072 -256.274824)
		(width 0.14732)
		(layer "F.Cu")
		(net "M_A_CPU1_CLK_DN<0>")
	)
	(segment
		(start 58.447686 -256.274824)
		(end 57.342786 -255.169924)
		(width 0.14732)
		(layer "F.Cu")
		(net "M_A_CPU1_CLK_DN<0>")
	)
	(segment
		(start 76.826872 -257.212338)
		(end 76.181204 -257.858006)
		(width 0.14732)
		(layer "F.Cu")
		(net "M_A_CPU1_CLK_DN<0>")
	)
	(segment
		(start 57.342786 -255.169924)
		(end 57.342786 -254.494284)
		(width 0.14732)
		(layer "F.Cu")
		(net "M_A_CPU1_CLK_DN<0>")
	)
	(segment
		(start 77.275436 -256.657856)
		(end 76.840334 -257.092958)
		(width 0.0762)
		(layer "F.Cu")
		(net "M_A_CPU1_CLK_DN<0>")
	)
	(segment
		(start 71.399908 -255.038606)
		(end 68.23329 -255.038606)
		(width 0.14732)
		(layer "F.Cu")
		(net "M_A_CPU1_CLK_DN<0>")
	)
	(segment
		(start 77.276452 -256.658872)
		(end 77.275436 -256.657856)
		(width 0.0762)
		(layer "F.Cu")
		(net "M_A_CPU1_CLK_DN<0>")
	)
	(segment
		(start 56.08447 -254.03048)
		(end 55.829708 -254.285242)
		(width 0.14732)
		(layer "F.Cu")
		(net "M_A_CPU1_CLK_DN<0>")
	)
	(arc
		(start 78.030832 -256.740406)
		(mid 78.030672 -256.593845)
		(end 77.899006 -256.529586)
		(width 0.0762)
		(layer "F.Cu")
		(net "M_A_CPU1_CLK_DN<0>")
	)
	(arc
		(start 77.750924 -256.577846)
		(mid 77.6372 -256.628147)
		(end 77.515212 -256.652268)
		(width 0.0762)
		(layer "F.Cu")
		(net "M_A_CPU1_CLK_DN<0>")
	)
	(arc
		(start 77.899006 -256.529586)
		(mid 77.826998 -256.544368)
		(end 77.759306 -256.57302)
		(width 0.0762)
		(layer "F.Cu")
		(net "M_A_CPU1_CLK_DN<0>")
	)
	(arc
		(start 77.51445 -256.653284)
		(mid 77.444275 -256.657478)
		(end 77.373988 -256.658872)
		(width 0.0762)
		(layer "F.Cu")
		(net "M_A_CPU1_CLK_DN<0>")
	)
	(segment
		(start 62.70371 -248.402602)
		(end 62.00013 -247.699022)
		(width 0.10668)
		(layer "F.Cu")
		(net "M_A_CPU1_ALERT_R_N")
	)
	(segment
		(start 62.00013 -247.699022)
		(end 62.00013 -246.50446)
		(width 0.10668)
		(layer "F.Cu")
		(net "M_A_CPU1_ALERT_R_N")
	)
	(segment
		(start 60.44819 -244.616986)
		(end 60.34151 -244.510306)
		(width 0.101346)
		(layer "F.Cu")
		(net "M_A_CPU1_ALERT_R_N")
	)
	(segment
		(start 60.44819 -244.95252)
		(end 60.44819 -244.677946)
		(width 0.10668)
		(layer "F.Cu")
		(net "M_A_CPU1_ALERT_R_N")
	)
	(segment
		(start 62.70371 -248.995692)
		(end 62.70371 -248.402602)
		(width 0.10668)
		(layer "F.Cu")
		(net "M_A_CPU1_ALERT_R_N")
	)
	(segment
		(start 60.34151 -244.510306)
		(end 58.220102 -244.510306)
		(width 0.101346)
		(layer "F.Cu")
		(net "M_A_CPU1_ALERT_R_N")
	)
	(segment
		(start 77.706982 -249.910346)
		(end 77.45857 -250.054364)
		(width 0.0762)
		(layer "F.Cu")
		(net "M_A_CPU1_ALERT_R_N")
	)
	(segment
		(start 74.13371 -250.174506)
		(end 63.882524 -250.174506)
		(width 0.10668)
		(layer "F.Cu")
		(net "M_A_CPU1_ALERT_R_N")
	)
	(segment
		(start 58.220102 -244.510306)
		(end 58.13044 -244.420644)
		(width 0.101346)
		(layer "F.Cu")
		(net "M_A_CPU1_ALERT_R_N")
	)
	(segment
		(start 63.882524 -250.174506)
		(end 62.70371 -248.995692)
		(width 0.10668)
		(layer "F.Cu")
		(net "M_A_CPU1_ALERT_R_N")
	)
	(segment
		(start 60.44819 -244.677946)
		(end 60.44819 -244.616986)
		(width 0.101346)
		(layer "F.Cu")
		(net "M_A_CPU1_ALERT_R_N")
	)
	(segment
		(start 76.036424 -250.359926)
		(end 74.31913 -250.359926)
		(width 0.10668)
		(layer "F.Cu")
		(net "M_A_CPU1_ALERT_R_N")
	)
	(segment
		(start 76.16444 -250.23191)
		(end 76.036424 -250.359926)
		(width 0.10668)
		(layer "F.Cu")
		(net "M_A_CPU1_ALERT_R_N")
	)
	(segment
		(start 58.13044 -244.420644)
		(end 57.79516 -244.085364)
		(width 0.10668)
		(layer "F.Cu")
		(net "M_A_CPU1_ALERT_R_N")
	)
	(segment
		(start 76.796646 -250.232164)
		(end 76.16444 -250.23191)
		(width 0.10668)
		(layer "F.Cu")
		(net "M_A_CPU1_ALERT_R_N")
	)
	(segment
		(start 74.31913 -250.359926)
		(end 74.13371 -250.174506)
		(width 0.10668)
		(layer "F.Cu")
		(net "M_A_CPU1_ALERT_R_N")
	)
	(segment
		(start 62.00013 -246.50446)
		(end 60.44819 -244.95252)
		(width 0.10668)
		(layer "F.Cu")
		(net "M_A_CPU1_ALERT_R_N")
	)
	(via
		(at 57.79516 -244.085364)
		(size 0.4826)
		(drill 0.254)
		(layers "F.Cu" "B.Cu")
		(net "M_A_CPU1_ALERT_R_N")
	)
	(arc
		(start 77.777086 -249.879866)
		(mid 77.741133 -249.893033)
		(end 77.706982 -249.910346)
		(width 0.0762)
		(layer "F.Cu")
		(net "M_A_CPU1_ALERT_R_N")
	)
	(arc
		(start 78.408022 -249.610372)
		(mid 78.171894 -249.781807)
		(end 77.89037 -249.85853)
		(width 0.0762)
		(layer "F.Cu")
		(net "M_A_CPU1_ALERT_R_N")
	)
	(arc
		(start 77.45857 -250.054364)
		(mid 77.139345 -250.186951)
		(end 76.796646 -250.232164)
		(width 0.0762)
		(layer "F.Cu")
		(net "M_A_CPU1_ALERT_R_N")
	)
	(arc
		(start 77.89037 -249.85853)
		(mid 77.833184 -249.866306)
		(end 77.777086 -249.879866)
		(width 0.0762)
		(layer "F.Cu")
		(net "M_A_CPU1_ALERT_R_N")
	)
	(via
		(at 59.428126 -244.085364)
		(size 0.4826)
		(drill 0.254)
		(layers "F.Cu" "B.Cu")
		(net "M_A_CPU1_ALERT_N")
	)
	(segment
		(start 58.59526 -244.085364)
		(end 59.428126 -244.085364)
		(width 0.10668)
		(layer "B.Cu")
		(net "M_A_CPU1_ALERT_N")
	)
	(segment
		(start 311.204864 -268.858492)
		(end 311.204864 -269.038832)
		(width 0.10668)
		(layer "F.Cu")
		(net "M_A_CPU0_SB_RSP<0>")
	)
	(segment
		(start 309.75681 -270.280892)
		(end 309.605934 -270.281146)
		(width 0.10668)
		(layer "F.Cu")
		(net "M_A_CPU0_SB_RSP<0>")
	)
	(segment
		(start 309.542434 -269.50289)
		(end 309.542688 -269.653258)
		(width 0.10668)
		(layer "F.Cu")
		(net "M_A_CPU0_SB_RSP<0>")
	)
	(segment
		(start 310.293512 -268.751812)
		(end 310.106822 -268.938502)
		(width 0.10668)
		(layer "F.Cu")
		(net "M_A_CPU0_SB_RSP<0>")
	)
	(segment
		(start 310.452516 -269.43431)
		(end 310.452516 -269.585186)
		(width 0.10668)
		(layer "F.Cu")
		(net "M_A_CPU0_SB_RSP<0>")
	)
	(segment
		(start 325.999348 -267.667486)
		(end 325.990966 -267.66266)
		(width 0.0762)
		(layer "F.Cu")
		(net "M_A_CPU0_SB_RSP<0>")
	)
	(segment
		(start 309.888128 -270.149574)
		(end 309.75681 -270.280892)
		(width 0.10668)
		(layer "F.Cu")
		(net "M_A_CPU0_SB_RSP<0>")
	)
	(segment
		(start 324.240398 -267.52169)
		(end 323.384164 -266.665456)
		(width 0.10668)
		(layer "F.Cu")
		(net "M_A_CPU0_SB_RSP<0>")
	)
	(segment
		(start 310.321198 -269.716504)
		(end 310.170322 -269.716758)
		(width 0.10668)
		(layer "F.Cu")
		(net "M_A_CPU0_SB_RSP<0>")
	)
	(segment
		(start 311.204864 -269.038832)
		(end 311.098184 -269.145512)
		(width 0.10668)
		(layer "F.Cu")
		(net "M_A_CPU0_SB_RSP<0>")
	)
	(segment
		(start 313.3979 -266.665456)
		(end 311.204864 -268.858492)
		(width 0.10668)
		(layer "F.Cu")
		(net "M_A_CPU0_SB_RSP<0>")
	)
	(segment
		(start 309.824882 -269.371318)
		(end 309.674006 -269.371318)
		(width 0.10668)
		(layer "F.Cu")
		(net "M_A_CPU0_SB_RSP<0>")
	)
	(segment
		(start 311.098184 -269.145512)
		(end 310.91251 -269.145512)
		(width 0.10668)
		(layer "F.Cu")
		(net "M_A_CPU0_SB_RSP<0>")
	)
	(segment
		(start 310.91251 -269.145512)
		(end 310.80583 -269.038832)
		(width 0.10668)
		(layer "F.Cu")
		(net "M_A_CPU0_SB_RSP<0>")
	)
	(segment
		(start 325.70801 -267.58646)
		(end 324.491604 -267.58646)
		(width 0.0762)
		(layer "F.Cu")
		(net "M_A_CPU0_SB_RSP<0>")
	)
	(segment
		(start 309.109618 -269.935706)
		(end 308.610254 -270.43507)
		(width 0.10668)
		(layer "F.Cu")
		(net "M_A_CPU0_SB_RSP<0>")
	)
	(segment
		(start 324.426834 -267.52169)
		(end 324.240398 -267.52169)
		(width 0.10668)
		(layer "F.Cu")
		(net "M_A_CPU0_SB_RSP<0>")
	)
	(segment
		(start 310.452516 -269.585186)
		(end 310.321198 -269.716504)
		(width 0.10668)
		(layer "F.Cu")
		(net "M_A_CPU0_SB_RSP<0>")
	)
	(segment
		(start 326.17791 -267.34008)
		(end 326.276208 -267.509244)
		(width 0.0762)
		(layer "F.Cu")
		(net "M_A_CPU0_SB_RSP<0>")
	)
	(segment
		(start 309.605934 -270.281146)
		(end 309.260494 -269.935706)
		(width 0.10668)
		(layer "F.Cu")
		(net "M_A_CPU0_SB_RSP<0>")
	)
	(segment
		(start 324.491604 -267.58646)
		(end 324.426834 -267.52169)
		(width 0.0762)
		(layer "F.Cu")
		(net "M_A_CPU0_SB_RSP<0>")
	)
	(segment
		(start 310.170322 -269.716758)
		(end 309.824882 -269.371318)
		(width 0.10668)
		(layer "F.Cu")
		(net "M_A_CPU0_SB_RSP<0>")
	)
	(segment
		(start 310.80583 -268.858492)
		(end 310.69915 -268.751812)
		(width 0.10668)
		(layer "F.Cu")
		(net "M_A_CPU0_SB_RSP<0>")
	)
	(segment
		(start 323.384164 -266.665456)
		(end 313.3979 -266.665456)
		(width 0.10668)
		(layer "F.Cu")
		(net "M_A_CPU0_SB_RSP<0>")
	)
	(segment
		(start 309.260494 -269.935706)
		(end 309.109618 -269.935706)
		(width 0.10668)
		(layer "F.Cu")
		(net "M_A_CPU0_SB_RSP<0>")
	)
	(segment
		(start 310.80583 -269.038832)
		(end 310.80583 -268.858492)
		(width 0.10668)
		(layer "F.Cu")
		(net "M_A_CPU0_SB_RSP<0>")
	)
	(segment
		(start 309.888128 -269.998698)
		(end 309.888128 -270.149574)
		(width 0.10668)
		(layer "F.Cu")
		(net "M_A_CPU0_SB_RSP<0>")
	)
	(segment
		(start 310.69915 -268.751812)
		(end 310.293512 -268.751812)
		(width 0.10668)
		(layer "F.Cu")
		(net "M_A_CPU0_SB_RSP<0>")
	)
	(segment
		(start 310.107076 -269.08887)
		(end 310.452516 -269.43431)
		(width 0.10668)
		(layer "F.Cu")
		(net "M_A_CPU0_SB_RSP<0>")
	)
	(segment
		(start 309.542688 -269.653258)
		(end 309.888128 -269.998698)
		(width 0.10668)
		(layer "F.Cu")
		(net "M_A_CPU0_SB_RSP<0>")
	)
	(segment
		(start 309.674006 -269.371318)
		(end 309.542434 -269.50289)
		(width 0.10668)
		(layer "F.Cu")
		(net "M_A_CPU0_SB_RSP<0>")
	)
	(segment
		(start 308.610254 -270.43507)
		(end 307.368194 -270.43507)
		(width 0.10668)
		(layer "F.Cu")
		(net "M_A_CPU0_SB_RSP<0>")
	)
	(segment
		(start 310.106822 -268.938502)
		(end 310.107076 -269.08887)
		(width 0.10668)
		(layer "F.Cu")
		(net "M_A_CPU0_SB_RSP<0>")
	)
	(arc
		(start 326.13854 -267.71092)
		(mid 326.066802 -267.696068)
		(end 325.999348 -267.667486)
		(width 0.0762)
		(layer "F.Cu")
		(net "M_A_CPU0_SB_RSP<0>")
	)
	(arc
		(start 326.276208 -267.509244)
		(mid 326.267615 -267.651123)
		(end 326.13854 -267.71092)
		(width 0.0762)
		(layer "F.Cu")
		(net "M_A_CPU0_SB_RSP<0>")
	)
	(arc
		(start 325.990966 -267.66266)
		(mid 325.85453 -267.605835)
		(end 325.70801 -267.58646)
		(width 0.0762)
		(layer "F.Cu")
		(net "M_A_CPU0_SB_RSP<0>")
	)
	(segment
		(start 304.553366 -266.918186)
		(end 304.436526 -267.035026)
		(width 0.101346)
		(layer "F.Cu")
		(net "M_A_CPU0_SB_PAR")
	)
	(segment
		(start 304.553366 -266.716764)
		(end 304.553366 -266.918186)
		(width 0.101346)
		(layer "F.Cu")
		(net "M_A_CPU0_SB_PAR")
	)
	(segment
		(start 304.436526 -267.035026)
		(end 303.268126 -267.035026)
		(width 0.101346)
		(layer "F.Cu")
		(net "M_A_CPU0_SB_PAR")
	)
	(segment
		(start 313.034426 -265.101578)
		(end 311.739026 -266.396978)
		(width 0.10668)
		(layer "F.Cu")
		(net "M_A_CPU0_SB_PAR")
	)
	(segment
		(start 311.739026 -266.396978)
		(end 308.82336 -266.396978)
		(width 0.10668)
		(layer "F.Cu")
		(net "M_A_CPU0_SB_PAR")
	)
	(segment
		(start 320.824098 -265.101578)
		(end 313.034426 -265.101578)
		(width 0.10668)
		(layer "F.Cu")
		(net "M_A_CPU0_SB_PAR")
	)
	(segment
		(start 324.411594 -264.53719)
		(end 321.388486 -264.53719)
		(width 0.10668)
		(layer "F.Cu")
		(net "M_A_CPU0_SB_PAR")
	)
	(segment
		(start 325.70801 -264.536936)
		(end 324.411848 -264.536936)
		(width 0.0762)
		(layer "F.Cu")
		(net "M_A_CPU0_SB_PAR")
	)
	(segment
		(start 304.660046 -266.610084)
		(end 304.553366 -266.716764)
		(width 0.101346)
		(layer "F.Cu")
		(net "M_A_CPU0_SB_PAR")
	)
	(segment
		(start 324.411848 -264.536936)
		(end 324.411594 -264.53719)
		(width 0.0762)
		(layer "F.Cu")
		(net "M_A_CPU0_SB_PAR")
	)
	(segment
		(start 321.388486 -264.53719)
		(end 320.824098 -265.101578)
		(width 0.10668)
		(layer "F.Cu")
		(net "M_A_CPU0_SB_PAR")
	)
	(segment
		(start 308.82336 -266.396978)
		(end 308.610508 -266.60983)
		(width 0.10668)
		(layer "F.Cu")
		(net "M_A_CPU0_SB_PAR")
	)
	(segment
		(start 308.610508 -266.60983)
		(end 308.610254 -266.610084)
		(width 0.101346)
		(layer "F.Cu")
		(net "M_A_CPU0_SB_PAR")
	)
	(segment
		(start 308.610254 -266.610084)
		(end 304.660046 -266.610084)
		(width 0.101346)
		(layer "F.Cu")
		(net "M_A_CPU0_SB_PAR")
	)
	(arc
		(start 326.648064 -264.910062)
		(mid 326.405747 -264.740342)
		(end 326.12076 -264.660888)
		(width 0.0762)
		(layer "F.Cu")
		(net "M_A_CPU0_SB_PAR")
	)
	(arc
		(start 325.894954 -264.587482)
		(mid 325.804821 -264.549862)
		(end 325.70801 -264.536936)
		(width 0.0762)
		(layer "F.Cu")
		(net "M_A_CPU0_SB_PAR")
	)
	(arc
		(start 326.12076 -264.660888)
		(mid 326.003947 -264.636212)
		(end 325.894954 -264.587482)
		(width 0.0762)
		(layer "F.Cu")
		(net "M_A_CPU0_SB_PAR")
	)
	(segment
		(start 309.548276 -275.156676)
		(end 309.34279 -275.362162)
		(width 0.12954)
		(layer "F.Cu")
		(net "M_A_CPU0_SB_DQS_DP<9>")
	)
	(segment
		(start 315.227462 -269.436342)
		(end 314.73013 -269.436342)
		(width 0.12954)
		(layer "F.Cu")
		(net "M_A_CPU0_SB_DQS_DP<9>")
	)
	(segment
		(start 310.47944 -274.225512)
		(end 309.94096 -274.225512)
		(width 0.12954)
		(layer "F.Cu")
		(net "M_A_CPU0_SB_DQS_DP<9>")
	)
	(segment
		(start 324.404736 -270.826484)
		(end 324.338696 -270.760444)
		(width 0.0762)
		(layer "F.Cu")
		(net "M_A_CPU0_SB_DQS_DP<9>")
	)
	(segment
		(start 312.958226 -271.208246)
		(end 312.958226 -271.746726)
		(width 0.12954)
		(layer "F.Cu")
		(net "M_A_CPU0_SB_DQS_DP<9>")
	)
	(segment
		(start 320.363088 -269.988792)
		(end 320.363088 -269.754604)
		(width 0.12954)
		(layer "F.Cu")
		(net "M_A_CPU0_SB_DQS_DP<9>")
	)
	(segment
		(start 317.631826 -269.754604)
		(end 317.631826 -269.988792)
		(width 0.12954)
		(layer "F.Cu")
		(net "M_A_CPU0_SB_DQS_DP<9>")
	)
	(segment
		(start 315.896498 -270.118332)
		(end 315.675264 -270.118332)
		(width 0.12954)
		(layer "F.Cu")
		(net "M_A_CPU0_SB_DQS_DP<9>")
	)
	(segment
		(start 308.80431 -275.362162)
		(end 308.367684 -275.798788)
		(width 0.12954)
		(layer "F.Cu")
		(net "M_A_CPU0_SB_DQS_DP<9>")
	)
	(segment
		(start 319.237614 -269.988792)
		(end 319.108074 -270.118332)
		(width 0.12954)
		(layer "F.Cu")
		(net "M_A_CPU0_SB_DQS_DP<9>")
	)
	(segment
		(start 321.68465 -269.436342)
		(end 321.161664 -269.436342)
		(width 0.12954)
		(layer "F.Cu")
		(net "M_A_CPU0_SB_DQS_DP<9>")
	)
	(segment
		(start 313.88939 -270.815562)
		(end 313.35091 -270.815562)
		(width 0.12954)
		(layer "F.Cu")
		(net "M_A_CPU0_SB_DQS_DP<9>")
	)
	(segment
		(start 311.821576 -272.883376)
		(end 311.61609 -273.088862)
		(width 0.12954)
		(layer "F.Cu")
		(net "M_A_CPU0_SB_DQS_DP<9>")
	)
	(segment
		(start 320.044826 -269.436342)
		(end 319.555876 -269.436342)
		(width 0.12954)
		(layer "F.Cu")
		(net "M_A_CPU0_SB_DQS_DP<9>")
	)
	(segment
		(start 315.545724 -269.988792)
		(end 315.545724 -269.754604)
		(width 0.12954)
		(layer "F.Cu")
		(net "M_A_CPU0_SB_DQS_DP<9>")
	)
	(segment
		(start 326.17791 -270.580104)
		(end 326.276208 -270.749268)
		(width 0.0762)
		(layer "F.Cu")
		(net "M_A_CPU0_SB_DQS_DP<9>")
	)
	(segment
		(start 324.319646 -270.760444)
		(end 323.008752 -270.760444)
		(width 0.12954)
		(layer "F.Cu")
		(net "M_A_CPU0_SB_DQS_DP<9>")
	)
	(segment
		(start 318.7573 -269.988792)
		(end 318.7573 -269.754604)
		(width 0.12954)
		(layer "F.Cu")
		(net "M_A_CPU0_SB_DQS_DP<9>")
	)
	(segment
		(start 316.026038 -269.988792)
		(end 315.896498 -270.118332)
		(width 0.12954)
		(layer "F.Cu")
		(net "M_A_CPU0_SB_DQS_DP<9>")
	)
	(segment
		(start 315.675264 -270.118332)
		(end 315.545724 -269.988792)
		(width 0.12954)
		(layer "F.Cu")
		(net "M_A_CPU0_SB_DQS_DP<9>")
	)
	(segment
		(start 317.151512 -269.754604)
		(end 316.83325 -269.436342)
		(width 0.12954)
		(layer "F.Cu")
		(net "M_A_CPU0_SB_DQS_DP<9>")
	)
	(segment
		(start 309.94096 -274.225512)
		(end 309.548276 -274.618196)
		(width 0.12954)
		(layer "F.Cu")
		(net "M_A_CPU0_SB_DQS_DP<9>")
	)
	(segment
		(start 314.094876 -270.071596)
		(end 314.094876 -270.610076)
		(width 0.12954)
		(layer "F.Cu")
		(net "M_A_CPU0_SB_DQS_DP<9>")
	)
	(segment
		(start 311.821576 -272.344896)
		(end 311.821576 -272.883376)
		(width 0.12954)
		(layer "F.Cu")
		(net "M_A_CPU0_SB_DQS_DP<9>")
	)
	(segment
		(start 316.026038 -269.754604)
		(end 316.026038 -269.988792)
		(width 0.12954)
		(layer "F.Cu")
		(net "M_A_CPU0_SB_DQS_DP<9>")
	)
	(segment
		(start 316.83325 -269.436342)
		(end 316.3443 -269.436342)
		(width 0.12954)
		(layer "F.Cu")
		(net "M_A_CPU0_SB_DQS_DP<9>")
	)
	(segment
		(start 314.094876 -270.610076)
		(end 313.88939 -270.815562)
		(width 0.12954)
		(layer "F.Cu")
		(net "M_A_CPU0_SB_DQS_DP<9>")
	)
	(segment
		(start 323.008752 -270.760444)
		(end 321.68465 -269.436342)
		(width 0.12954)
		(layer "F.Cu")
		(net "M_A_CPU0_SB_DQS_DP<9>")
	)
	(segment
		(start 310.684926 -274.020026)
		(end 310.47944 -274.225512)
		(width 0.12954)
		(layer "F.Cu")
		(net "M_A_CPU0_SB_DQS_DP<9>")
	)
	(segment
		(start 308.166516 -275.798788)
		(end 307.902864 -275.535136)
		(width 0.12954)
		(layer "F.Cu")
		(net "M_A_CPU0_SB_DQS_DP<9>")
	)
	(segment
		(start 317.502286 -270.118332)
		(end 317.281052 -270.118332)
		(width 0.12954)
		(layer "F.Cu")
		(net "M_A_CPU0_SB_DQS_DP<9>")
	)
	(segment
		(start 309.548276 -274.618196)
		(end 309.548276 -275.156676)
		(width 0.12954)
		(layer "F.Cu")
		(net "M_A_CPU0_SB_DQS_DP<9>")
	)
	(segment
		(start 320.713862 -270.118332)
		(end 320.492628 -270.118332)
		(width 0.12954)
		(layer "F.Cu")
		(net "M_A_CPU0_SB_DQS_DP<9>")
	)
	(segment
		(start 318.88684 -270.118332)
		(end 318.7573 -269.988792)
		(width 0.12954)
		(layer "F.Cu")
		(net "M_A_CPU0_SB_DQS_DP<9>")
	)
	(segment
		(start 325.70801 -270.826484)
		(end 324.404736 -270.826484)
		(width 0.0762)
		(layer "F.Cu")
		(net "M_A_CPU0_SB_DQS_DP<9>")
	)
	(segment
		(start 311.07761 -273.088862)
		(end 310.684926 -273.481546)
		(width 0.12954)
		(layer "F.Cu")
		(net "M_A_CPU0_SB_DQS_DP<9>")
	)
	(segment
		(start 319.237614 -269.754604)
		(end 319.237614 -269.988792)
		(width 0.12954)
		(layer "F.Cu")
		(net "M_A_CPU0_SB_DQS_DP<9>")
	)
	(segment
		(start 308.367684 -275.798788)
		(end 308.166516 -275.798788)
		(width 0.12954)
		(layer "F.Cu")
		(net "M_A_CPU0_SB_DQS_DP<9>")
	)
	(segment
		(start 311.61609 -273.088862)
		(end 311.07761 -273.088862)
		(width 0.12954)
		(layer "F.Cu")
		(net "M_A_CPU0_SB_DQS_DP<9>")
	)
	(segment
		(start 319.555876 -269.436342)
		(end 319.237614 -269.754604)
		(width 0.12954)
		(layer "F.Cu")
		(net "M_A_CPU0_SB_DQS_DP<9>")
	)
	(segment
		(start 312.958226 -271.746726)
		(end 312.75274 -271.952212)
		(width 0.12954)
		(layer "F.Cu")
		(net "M_A_CPU0_SB_DQS_DP<9>")
	)
	(segment
		(start 317.151512 -269.988792)
		(end 317.151512 -269.754604)
		(width 0.12954)
		(layer "F.Cu")
		(net "M_A_CPU0_SB_DQS_DP<9>")
	)
	(segment
		(start 312.21426 -271.952212)
		(end 311.821576 -272.344896)
		(width 0.12954)
		(layer "F.Cu")
		(net "M_A_CPU0_SB_DQS_DP<9>")
	)
	(segment
		(start 320.843402 -269.754604)
		(end 320.843402 -269.988792)
		(width 0.12954)
		(layer "F.Cu")
		(net "M_A_CPU0_SB_DQS_DP<9>")
	)
	(segment
		(start 309.34279 -275.362162)
		(end 308.80431 -275.362162)
		(width 0.12954)
		(layer "F.Cu")
		(net "M_A_CPU0_SB_DQS_DP<9>")
	)
	(segment
		(start 318.439038 -269.436342)
		(end 317.950088 -269.436342)
		(width 0.12954)
		(layer "F.Cu")
		(net "M_A_CPU0_SB_DQS_DP<9>")
	)
	(segment
		(start 317.281052 -270.118332)
		(end 317.151512 -269.988792)
		(width 0.12954)
		(layer "F.Cu")
		(net "M_A_CPU0_SB_DQS_DP<9>")
	)
	(segment
		(start 310.684926 -273.481546)
		(end 310.684926 -274.020026)
		(width 0.12954)
		(layer "F.Cu")
		(net "M_A_CPU0_SB_DQS_DP<9>")
	)
	(segment
		(start 318.7573 -269.754604)
		(end 318.439038 -269.436342)
		(width 0.12954)
		(layer "F.Cu")
		(net "M_A_CPU0_SB_DQS_DP<9>")
	)
	(segment
		(start 316.3443 -269.436342)
		(end 316.026038 -269.754604)
		(width 0.12954)
		(layer "F.Cu")
		(net "M_A_CPU0_SB_DQS_DP<9>")
	)
	(segment
		(start 321.161664 -269.436342)
		(end 320.843402 -269.754604)
		(width 0.12954)
		(layer "F.Cu")
		(net "M_A_CPU0_SB_DQS_DP<9>")
	)
	(segment
		(start 307.902864 -275.535136)
		(end 307.368194 -275.535136)
		(width 0.12954)
		(layer "F.Cu")
		(net "M_A_CPU0_SB_DQS_DP<9>")
	)
	(segment
		(start 325.999348 -270.90751)
		(end 325.990966 -270.902684)
		(width 0.0762)
		(layer "F.Cu")
		(net "M_A_CPU0_SB_DQS_DP<9>")
	)
	(segment
		(start 317.950088 -269.436342)
		(end 317.631826 -269.754604)
		(width 0.12954)
		(layer "F.Cu")
		(net "M_A_CPU0_SB_DQS_DP<9>")
	)
	(segment
		(start 314.73013 -269.436342)
		(end 314.094876 -270.071596)
		(width 0.12954)
		(layer "F.Cu")
		(net "M_A_CPU0_SB_DQS_DP<9>")
	)
	(segment
		(start 312.75274 -271.952212)
		(end 312.21426 -271.952212)
		(width 0.12954)
		(layer "F.Cu")
		(net "M_A_CPU0_SB_DQS_DP<9>")
	)
	(segment
		(start 320.492628 -270.118332)
		(end 320.363088 -269.988792)
		(width 0.12954)
		(layer "F.Cu")
		(net "M_A_CPU0_SB_DQS_DP<9>")
	)
	(segment
		(start 320.363088 -269.754604)
		(end 320.044826 -269.436342)
		(width 0.12954)
		(layer "F.Cu")
		(net "M_A_CPU0_SB_DQS_DP<9>")
	)
	(segment
		(start 319.108074 -270.118332)
		(end 318.88684 -270.118332)
		(width 0.12954)
		(layer "F.Cu")
		(net "M_A_CPU0_SB_DQS_DP<9>")
	)
	(segment
		(start 317.631826 -269.988792)
		(end 317.502286 -270.118332)
		(width 0.12954)
		(layer "F.Cu")
		(net "M_A_CPU0_SB_DQS_DP<9>")
	)
	(segment
		(start 320.843402 -269.988792)
		(end 320.713862 -270.118332)
		(width 0.12954)
		(layer "F.Cu")
		(net "M_A_CPU0_SB_DQS_DP<9>")
	)
	(segment
		(start 324.338696 -270.760444)
		(end 324.319646 -270.760444)
		(width 0.0762)
		(layer "F.Cu")
		(net "M_A_CPU0_SB_DQS_DP<9>")
	)
	(segment
		(start 313.35091 -270.815562)
		(end 312.958226 -271.208246)
		(width 0.12954)
		(layer "F.Cu")
		(net "M_A_CPU0_SB_DQS_DP<9>")
	)
	(segment
		(start 315.545724 -269.754604)
		(end 315.227462 -269.436342)
		(width 0.12954)
		(layer "F.Cu")
		(net "M_A_CPU0_SB_DQS_DP<9>")
	)
	(arc
		(start 326.13854 -270.950944)
		(mid 326.066802 -270.936092)
		(end 325.999348 -270.90751)
		(width 0.0762)
		(layer "F.Cu")
		(net "M_A_CPU0_SB_DQS_DP<9>")
	)
	(arc
		(start 325.990966 -270.902684)
		(mid 325.85453 -270.845859)
		(end 325.70801 -270.826484)
		(width 0.0762)
		(layer "F.Cu")
		(net "M_A_CPU0_SB_DQS_DP<9>")
	)
	(arc
		(start 326.276208 -270.749268)
		(mid 326.267615 -270.891147)
		(end 326.13854 -270.950944)
		(width 0.0762)
		(layer "F.Cu")
		(net "M_A_CPU0_SB_DQS_DP<9>")
	)
	(segment
		(start 322.825364 -300.558962)
		(end 309.564024 -313.820302)
		(width 0.12954)
		(layer "F.Cu")
		(net "M_A_CPU0_SB_DQS_DP<8>")
	)
	(segment
		(start 303.806352 -314.635134)
		(end 303.268126 -314.635134)
		(width 0.101346)
		(layer "F.Cu")
		(net "M_A_CPU0_SB_DQS_DP<8>")
	)
	(segment
		(start 308.917594 -314.80633)
		(end 308.487064 -314.80633)
		(width 0.12954)
		(layer "F.Cu")
		(net "M_A_CPU0_SB_DQS_DP<8>")
	)
	(segment
		(start 325.999348 -291.3126)
		(end 325.990966 -291.317426)
		(width 0.0762)
		(layer "F.Cu")
		(net "M_A_CPU0_SB_DQS_DP<8>")
	)
	(segment
		(start 305.799236 -315.060076)
		(end 305.483006 -314.743846)
		(width 0.101346)
		(layer "F.Cu")
		(net "M_A_CPU0_SB_DQS_DP<8>")
	)
	(segment
		(start 304.123852 -314.317634)
		(end 303.806352 -314.635134)
		(width 0.101346)
		(layer "F.Cu")
		(net "M_A_CPU0_SB_DQS_DP<8>")
	)
	(segment
		(start 324.102476 -291.454586)
		(end 324.102476 -291.548566)
		(width 0.0762)
		(layer "F.Cu")
		(net "M_A_CPU0_SB_DQS_DP<8>")
	)
	(segment
		(start 309.564024 -314.1599)
		(end 308.917594 -314.80633)
		(width 0.12954)
		(layer "F.Cu")
		(net "M_A_CPU0_SB_DQS_DP<8>")
	)
	(segment
		(start 322.825364 -292.82517)
		(end 322.825364 -300.558962)
		(width 0.12954)
		(layer "F.Cu")
		(net "M_A_CPU0_SB_DQS_DP<8>")
	)
	(segment
		(start 305.483006 -314.743846)
		(end 305.12385 -314.743846)
		(width 0.101346)
		(layer "F.Cu")
		(net "M_A_CPU0_SB_DQS_DP<8>")
	)
	(segment
		(start 324.163436 -291.393626)
		(end 324.102476 -291.454586)
		(width 0.0762)
		(layer "F.Cu")
		(net "M_A_CPU0_SB_DQS_DP<8>")
	)
	(segment
		(start 304.697638 -314.317634)
		(end 304.123852 -314.317634)
		(width 0.101346)
		(layer "F.Cu")
		(net "M_A_CPU0_SB_DQS_DP<8>")
	)
	(segment
		(start 324.102476 -291.548566)
		(end 324.089014 -291.562028)
		(width 0.0762)
		(layer "F.Cu")
		(net "M_A_CPU0_SB_DQS_DP<8>")
	)
	(segment
		(start 305.12385 -314.743846)
		(end 304.697638 -314.317634)
		(width 0.101346)
		(layer "F.Cu")
		(net "M_A_CPU0_SB_DQS_DP<8>")
	)
	(segment
		(start 309.564024 -313.820302)
		(end 309.564024 -314.1599)
		(width 0.12954)
		(layer "F.Cu")
		(net "M_A_CPU0_SB_DQS_DP<8>")
	)
	(segment
		(start 308.233318 -315.060076)
		(end 305.799236 -315.060076)
		(width 0.101346)
		(layer "F.Cu")
		(net "M_A_CPU0_SB_DQS_DP<8>")
	)
	(segment
		(start 308.487064 -314.80633)
		(end 308.233318 -315.060076)
		(width 0.12954)
		(layer "F.Cu")
		(net "M_A_CPU0_SB_DQS_DP<8>")
	)
	(segment
		(start 325.708264 -291.393626)
		(end 324.163436 -291.393626)
		(width 0.0762)
		(layer "F.Cu")
		(net "M_A_CPU0_SB_DQS_DP<8>")
	)
	(segment
		(start 324.089014 -291.562028)
		(end 322.825364 -292.82517)
		(width 0.12954)
		(layer "F.Cu")
		(net "M_A_CPU0_SB_DQS_DP<8>")
	)
	(arc
		(start 328.058018 -291.640006)
		(mid 327.820406 -291.469018)
		(end 327.53808 -291.391594)
		(width 0.0762)
		(layer "F.Cu")
		(net "M_A_CPU0_SB_DQS_DP<8>")
	)
	(arc
		(start 325.990966 -291.317426)
		(mid 325.877242 -291.367727)
		(end 325.755254 -291.391848)
		(width 0.0762)
		(layer "F.Cu")
		(net "M_A_CPU0_SB_DQS_DP<8>")
	)
	(arc
		(start 325.755254 -291.391848)
		(mid 325.731777 -291.393224)
		(end 325.708264 -291.393626)
		(width 0.0762)
		(layer "F.Cu")
		(net "M_A_CPU0_SB_DQS_DP<8>")
	)
	(arc
		(start 327.53808 -291.391594)
		(mid 327.417431 -291.367293)
		(end 327.304908 -291.317426)
		(width 0.0762)
		(layer "F.Cu")
		(net "M_A_CPU0_SB_DQS_DP<8>")
	)
	(arc
		(start 326.365108 -291.317426)
		(mid 326.182857 -291.267076)
		(end 325.999348 -291.3126)
		(width 0.0762)
		(layer "F.Cu")
		(net "M_A_CPU0_SB_DQS_DP<8>")
	)
	(arc
		(start 326.93102 -291.317426)
		(mid 326.648064 -291.393603)
		(end 326.365108 -291.317426)
		(width 0.0762)
		(layer "F.Cu")
		(net "M_A_CPU0_SB_DQS_DP<8>")
	)
	(arc
		(start 327.304908 -291.317426)
		(mid 327.117964 -291.267171)
		(end 326.93102 -291.317426)
		(width 0.0762)
		(layer "F.Cu")
		(net "M_A_CPU0_SB_DQS_DP<8>")
	)
	(segment
		(start 309.23357 -305.457098)
		(end 308.486302 -305.457098)
		(width 0.12954)
		(layer "F.Cu")
		(net "M_A_CPU0_SB_DQS_DP<7>")
	)
	(segment
		(start 305.799236 -305.710082)
		(end 305.483006 -305.393852)
		(width 0.101346)
		(layer "F.Cu")
		(net "M_A_CPU0_SB_DQS_DP<7>")
	)
	(segment
		(start 325.708264 -286.533844)
		(end 324.678294 -286.533844)
		(width 0.0762)
		(layer "F.Cu")
		(net "M_A_CPU0_SB_DQS_DP<7>")
	)
	(segment
		(start 323.895974 -286.312356)
		(end 322.644516 -286.312356)
		(width 0.12954)
		(layer "F.Cu")
		(net "M_A_CPU0_SB_DQS_DP<7>")
	)
	(segment
		(start 318.403732 -290.55314)
		(end 318.403732 -296.286936)
		(width 0.12954)
		(layer "F.Cu")
		(net "M_A_CPU0_SB_DQS_DP<7>")
	)
	(segment
		(start 305.092862 -305.393852)
		(end 304.66665 -304.96764)
		(width 0.101346)
		(layer "F.Cu")
		(net "M_A_CPU0_SB_DQS_DP<7>")
	)
	(segment
		(start 308.233318 -305.710082)
		(end 305.799236 -305.710082)
		(width 0.101346)
		(layer "F.Cu")
		(net "M_A_CPU0_SB_DQS_DP<7>")
	)
	(segment
		(start 323.915024 -286.312356)
		(end 323.895974 -286.312356)
		(width 0.0762)
		(layer "F.Cu")
		(net "M_A_CPU0_SB_DQS_DP<7>")
	)
	(segment
		(start 308.486302 -305.457098)
		(end 308.233318 -305.710082)
		(width 0.12954)
		(layer "F.Cu")
		(net "M_A_CPU0_SB_DQS_DP<7>")
	)
	(segment
		(start 325.999348 -286.452818)
		(end 325.990966 -286.457644)
		(width 0.0762)
		(layer "F.Cu")
		(net "M_A_CPU0_SB_DQS_DP<7>")
	)
	(segment
		(start 323.981064 -286.246316)
		(end 323.915024 -286.312356)
		(width 0.0762)
		(layer "F.Cu")
		(net "M_A_CPU0_SB_DQS_DP<7>")
	)
	(segment
		(start 324.678294 -286.533844)
		(end 324.390766 -286.246316)
		(width 0.0762)
		(layer "F.Cu")
		(net "M_A_CPU0_SB_DQS_DP<7>")
	)
	(segment
		(start 304.123852 -304.96764)
		(end 303.806352 -305.28514)
		(width 0.101346)
		(layer "F.Cu")
		(net "M_A_CPU0_SB_DQS_DP<7>")
	)
	(segment
		(start 322.644516 -286.312356)
		(end 318.403732 -290.55314)
		(width 0.12954)
		(layer "F.Cu")
		(net "M_A_CPU0_SB_DQS_DP<7>")
	)
	(segment
		(start 303.806352 -305.28514)
		(end 303.268126 -305.28514)
		(width 0.101346)
		(layer "F.Cu")
		(net "M_A_CPU0_SB_DQS_DP<7>")
	)
	(segment
		(start 318.403732 -296.286936)
		(end 309.23357 -305.457098)
		(width 0.12954)
		(layer "F.Cu")
		(net "M_A_CPU0_SB_DQS_DP<7>")
	)
	(segment
		(start 324.390766 -286.246316)
		(end 323.981064 -286.246316)
		(width 0.0762)
		(layer "F.Cu")
		(net "M_A_CPU0_SB_DQS_DP<7>")
	)
	(segment
		(start 304.66665 -304.96764)
		(end 304.123852 -304.96764)
		(width 0.101346)
		(layer "F.Cu")
		(net "M_A_CPU0_SB_DQS_DP<7>")
	)
	(segment
		(start 305.483006 -305.393852)
		(end 305.092862 -305.393852)
		(width 0.101346)
		(layer "F.Cu")
		(net "M_A_CPU0_SB_DQS_DP<7>")
	)
	(arc
		(start 328.058018 -286.780224)
		(mid 327.820406 -286.609236)
		(end 327.53808 -286.531812)
		(width 0.0762)
		(layer "F.Cu")
		(net "M_A_CPU0_SB_DQS_DP<7>")
	)
	(arc
		(start 327.53808 -286.531812)
		(mid 327.417431 -286.507511)
		(end 327.304908 -286.457644)
		(width 0.0762)
		(layer "F.Cu")
		(net "M_A_CPU0_SB_DQS_DP<7>")
	)
	(arc
		(start 326.365108 -286.457644)
		(mid 326.182857 -286.407294)
		(end 325.999348 -286.452818)
		(width 0.0762)
		(layer "F.Cu")
		(net "M_A_CPU0_SB_DQS_DP<7>")
	)
	(arc
		(start 327.304908 -286.457644)
		(mid 327.117964 -286.407389)
		(end 326.93102 -286.457644)
		(width 0.0762)
		(layer "F.Cu")
		(net "M_A_CPU0_SB_DQS_DP<7>")
	)
	(arc
		(start 325.755254 -286.532066)
		(mid 325.731777 -286.533442)
		(end 325.708264 -286.533844)
		(width 0.0762)
		(layer "F.Cu")
		(net "M_A_CPU0_SB_DQS_DP<7>")
	)
	(arc
		(start 325.990966 -286.457644)
		(mid 325.877242 -286.507945)
		(end 325.755254 -286.532066)
		(width 0.0762)
		(layer "F.Cu")
		(net "M_A_CPU0_SB_DQS_DP<7>")
	)
	(arc
		(start 326.93102 -286.457644)
		(mid 326.648064 -286.533821)
		(end 326.365108 -286.457644)
		(width 0.0762)
		(layer "F.Cu")
		(net "M_A_CPU0_SB_DQS_DP<7>")
	)
	(segment
		(start 323.962014 -281.35961)
		(end 323.895974 -281.42565)
		(width 0.0762)
		(layer "F.Cu")
		(net "M_A_CPU0_SB_DQS_DP<6>")
	)
	(segment
		(start 308.48681 -296.106596)
		(end 308.233318 -296.360088)
		(width 0.12954)
		(layer "F.Cu")
		(net "M_A_CPU0_SB_DQS_DP<6>")
	)
	(segment
		(start 305.115722 -296.043858)
		(end 304.68951 -295.617646)
		(width 0.101346)
		(layer "F.Cu")
		(net "M_A_CPU0_SB_DQS_DP<6>")
	)
	(segment
		(start 323.895974 -281.42565)
		(end 321.277488 -281.42565)
		(width 0.12954)
		(layer "F.Cu")
		(net "M_A_CPU0_SB_DQS_DP<6>")
	)
	(segment
		(start 305.799236 -296.360088)
		(end 305.483006 -296.043858)
		(width 0.101346)
		(layer "F.Cu")
		(net "M_A_CPU0_SB_DQS_DP<6>")
	)
	(segment
		(start 313.970162 -291.663882)
		(end 309.527448 -296.106596)
		(width 0.12954)
		(layer "F.Cu")
		(net "M_A_CPU0_SB_DQS_DP<6>")
	)
	(segment
		(start 313.970162 -288.732976)
		(end 313.970162 -291.663882)
		(width 0.12954)
		(layer "F.Cu")
		(net "M_A_CPU0_SB_DQS_DP<6>")
	)
	(segment
		(start 325.999348 -281.592782)
		(end 325.990966 -281.597608)
		(width 0.0762)
		(layer "F.Cu")
		(net "M_A_CPU0_SB_DQS_DP<6>")
	)
	(segment
		(start 308.233318 -296.360088)
		(end 305.799236 -296.360088)
		(width 0.101346)
		(layer "F.Cu")
		(net "M_A_CPU0_SB_DQS_DP<6>")
	)
	(segment
		(start 303.806352 -295.935146)
		(end 303.268126 -295.935146)
		(width 0.101346)
		(layer "F.Cu")
		(net "M_A_CPU0_SB_DQS_DP<6>")
	)
	(segment
		(start 321.277488 -281.42565)
		(end 313.970162 -288.732976)
		(width 0.12954)
		(layer "F.Cu")
		(net "M_A_CPU0_SB_DQS_DP<6>")
	)
	(segment
		(start 324.43166 -281.35961)
		(end 323.962014 -281.35961)
		(width 0.0762)
		(layer "F.Cu")
		(net "M_A_CPU0_SB_DQS_DP<6>")
	)
	(segment
		(start 304.68951 -295.617646)
		(end 304.123852 -295.617646)
		(width 0.101346)
		(layer "F.Cu")
		(net "M_A_CPU0_SB_DQS_DP<6>")
	)
	(segment
		(start 309.527448 -296.106596)
		(end 308.48681 -296.106596)
		(width 0.12954)
		(layer "F.Cu")
		(net "M_A_CPU0_SB_DQS_DP<6>")
	)
	(segment
		(start 324.745858 -281.673808)
		(end 324.43166 -281.35961)
		(width 0.0762)
		(layer "F.Cu")
		(net "M_A_CPU0_SB_DQS_DP<6>")
	)
	(segment
		(start 305.483006 -296.043858)
		(end 305.115722 -296.043858)
		(width 0.101346)
		(layer "F.Cu")
		(net "M_A_CPU0_SB_DQS_DP<6>")
	)
	(segment
		(start 304.123852 -295.617646)
		(end 303.806352 -295.935146)
		(width 0.101346)
		(layer "F.Cu")
		(net "M_A_CPU0_SB_DQS_DP<6>")
	)
	(segment
		(start 325.708264 -281.673808)
		(end 324.745858 -281.673808)
		(width 0.0762)
		(layer "F.Cu")
		(net "M_A_CPU0_SB_DQS_DP<6>")
	)
	(arc
		(start 325.755254 -281.67203)
		(mid 325.731777 -281.673406)
		(end 325.708264 -281.673808)
		(width 0.0762)
		(layer "F.Cu")
		(net "M_A_CPU0_SB_DQS_DP<6>")
	)
	(arc
		(start 327.304908 -281.597608)
		(mid 327.117964 -281.547353)
		(end 326.93102 -281.597608)
		(width 0.0762)
		(layer "F.Cu")
		(net "M_A_CPU0_SB_DQS_DP<6>")
	)
	(arc
		(start 328.058018 -281.920188)
		(mid 327.820406 -281.7492)
		(end 327.53808 -281.671776)
		(width 0.0762)
		(layer "F.Cu")
		(net "M_A_CPU0_SB_DQS_DP<6>")
	)
	(arc
		(start 326.93102 -281.597608)
		(mid 326.648064 -281.673785)
		(end 326.365108 -281.597608)
		(width 0.0762)
		(layer "F.Cu")
		(net "M_A_CPU0_SB_DQS_DP<6>")
	)
	(arc
		(start 327.53808 -281.671776)
		(mid 327.417431 -281.647475)
		(end 327.304908 -281.597608)
		(width 0.0762)
		(layer "F.Cu")
		(net "M_A_CPU0_SB_DQS_DP<6>")
	)
	(arc
		(start 326.365108 -281.597608)
		(mid 326.182857 -281.547258)
		(end 325.999348 -281.592782)
		(width 0.0762)
		(layer "F.Cu")
		(net "M_A_CPU0_SB_DQS_DP<6>")
	)
	(arc
		(start 325.990966 -281.597608)
		(mid 325.877242 -281.647909)
		(end 325.755254 -281.67203)
		(width 0.0762)
		(layer "F.Cu")
		(net "M_A_CPU0_SB_DQS_DP<6>")
	)
	(segment
		(start 318.367156 -276.640544)
		(end 309.828692 -285.179008)
		(width 0.12954)
		(layer "F.Cu")
		(net "M_A_CPU0_SB_DQS_DP<5>")
	)
	(segment
		(start 305.799236 -287.010094)
		(end 305.483006 -286.693864)
		(width 0.101346)
		(layer "F.Cu")
		(net "M_A_CPU0_SB_DQS_DP<5>")
	)
	(segment
		(start 305.483006 -286.693864)
		(end 305.138074 -286.693864)
		(width 0.101346)
		(layer "F.Cu")
		(net "M_A_CPU0_SB_DQS_DP<5>")
	)
	(segment
		(start 304.711862 -286.267652)
		(end 304.123852 -286.267652)
		(width 0.101346)
		(layer "F.Cu")
		(net "M_A_CPU0_SB_DQS_DP<5>")
	)
	(segment
		(start 325.708264 -276.813772)
		(end 324.76186 -276.813772)
		(width 0.0762)
		(layer "F.Cu")
		(net "M_A_CPU0_SB_DQS_DP<5>")
	)
	(segment
		(start 308.487064 -286.756348)
		(end 308.233318 -287.010094)
		(width 0.12954)
		(layer "F.Cu")
		(net "M_A_CPU0_SB_DQS_DP<5>")
	)
	(segment
		(start 309.828692 -285.179008)
		(end 309.828692 -285.858458)
		(width 0.12954)
		(layer "F.Cu")
		(net "M_A_CPU0_SB_DQS_DP<5>")
	)
	(segment
		(start 324.522592 -276.574504)
		(end 323.962014 -276.574504)
		(width 0.0762)
		(layer "F.Cu")
		(net "M_A_CPU0_SB_DQS_DP<5>")
	)
	(segment
		(start 308.233318 -287.010094)
		(end 305.799236 -287.010094)
		(width 0.101346)
		(layer "F.Cu")
		(net "M_A_CPU0_SB_DQS_DP<5>")
	)
	(segment
		(start 325.999348 -276.732746)
		(end 325.990966 -276.737572)
		(width 0.0762)
		(layer "F.Cu")
		(net "M_A_CPU0_SB_DQS_DP<5>")
	)
	(segment
		(start 304.123852 -286.267652)
		(end 303.806352 -286.585152)
		(width 0.101346)
		(layer "F.Cu")
		(net "M_A_CPU0_SB_DQS_DP<5>")
	)
	(segment
		(start 308.930802 -286.756348)
		(end 308.487064 -286.756348)
		(width 0.12954)
		(layer "F.Cu")
		(net "M_A_CPU0_SB_DQS_DP<5>")
	)
	(segment
		(start 305.138074 -286.693864)
		(end 304.711862 -286.267652)
		(width 0.101346)
		(layer "F.Cu")
		(net "M_A_CPU0_SB_DQS_DP<5>")
	)
	(segment
		(start 309.828692 -285.858458)
		(end 308.930802 -286.756348)
		(width 0.12954)
		(layer "F.Cu")
		(net "M_A_CPU0_SB_DQS_DP<5>")
	)
	(segment
		(start 324.76186 -276.813772)
		(end 324.522592 -276.574504)
		(width 0.0762)
		(layer "F.Cu")
		(net "M_A_CPU0_SB_DQS_DP<5>")
	)
	(segment
		(start 323.962014 -276.574504)
		(end 323.895974 -276.640544)
		(width 0.0762)
		(layer "F.Cu")
		(net "M_A_CPU0_SB_DQS_DP<5>")
	)
	(segment
		(start 303.806352 -286.585152)
		(end 303.268126 -286.585152)
		(width 0.101346)
		(layer "F.Cu")
		(net "M_A_CPU0_SB_DQS_DP<5>")
	)
	(segment
		(start 323.895974 -276.640544)
		(end 318.367156 -276.640544)
		(width 0.12954)
		(layer "F.Cu")
		(net "M_A_CPU0_SB_DQS_DP<5>")
	)
	(arc
		(start 327.53808 -276.81174)
		(mid 327.417431 -276.787439)
		(end 327.304908 -276.737572)
		(width 0.0762)
		(layer "F.Cu")
		(net "M_A_CPU0_SB_DQS_DP<5>")
	)
	(arc
		(start 325.755254 -276.811994)
		(mid 325.731777 -276.81337)
		(end 325.708264 -276.813772)
		(width 0.0762)
		(layer "F.Cu")
		(net "M_A_CPU0_SB_DQS_DP<5>")
	)
	(arc
		(start 326.365108 -276.737572)
		(mid 326.182857 -276.687222)
		(end 325.999348 -276.732746)
		(width 0.0762)
		(layer "F.Cu")
		(net "M_A_CPU0_SB_DQS_DP<5>")
	)
	(arc
		(start 327.304908 -276.737572)
		(mid 327.117964 -276.687317)
		(end 326.93102 -276.737572)
		(width 0.0762)
		(layer "F.Cu")
		(net "M_A_CPU0_SB_DQS_DP<5>")
	)
	(arc
		(start 325.990966 -276.737572)
		(mid 325.877242 -276.787873)
		(end 325.755254 -276.811994)
		(width 0.0762)
		(layer "F.Cu")
		(net "M_A_CPU0_SB_DQS_DP<5>")
	)
	(arc
		(start 328.058018 -277.060152)
		(mid 327.820406 -276.889164)
		(end 327.53808 -276.81174)
		(width 0.0762)
		(layer "F.Cu")
		(net "M_A_CPU0_SB_DQS_DP<5>")
	)
	(arc
		(start 326.93102 -276.737572)
		(mid 326.648064 -276.813749)
		(end 326.365108 -276.737572)
		(width 0.0762)
		(layer "F.Cu")
		(net "M_A_CPU0_SB_DQS_DP<5>")
	)
	(segment
		(start 324.518274 -271.768824)
		(end 324.18655 -271.768824)
		(width 0.0762)
		(layer "F.Cu")
		(net "M_A_CPU0_SB_DQS_DP<4>")
	)
	(segment
		(start 315.126624 -271.185132)
		(end 308.911244 -277.400512)
		(width 0.12954)
		(layer "F.Cu")
		(net "M_A_CPU0_SB_DQS_DP<4>")
	)
	(segment
		(start 303.806352 -277.235158)
		(end 303.268126 -277.235158)
		(width 0.101346)
		(layer "F.Cu")
		(net "M_A_CPU0_SB_DQS_DP<4>")
	)
	(segment
		(start 304.123852 -276.917658)
		(end 303.806352 -277.235158)
		(width 0.101346)
		(layer "F.Cu")
		(net "M_A_CPU0_SB_DQS_DP<4>")
	)
	(segment
		(start 308.596538 -277.400512)
		(end 308.33695 -277.6601)
		(width 0.12954)
		(layer "F.Cu")
		(net "M_A_CPU0_SB_DQS_DP<4>")
	)
	(segment
		(start 308.33695 -277.6601)
		(end 305.799236 -277.6601)
		(width 0.101346)
		(layer "F.Cu")
		(net "M_A_CPU0_SB_DQS_DP<4>")
	)
	(segment
		(start 305.799236 -277.6601)
		(end 305.483006 -277.34387)
		(width 0.101346)
		(layer "F.Cu")
		(net "M_A_CPU0_SB_DQS_DP<4>")
	)
	(segment
		(start 305.119786 -277.34387)
		(end 304.693574 -276.917658)
		(width 0.101346)
		(layer "F.Cu")
		(net "M_A_CPU0_SB_DQS_DP<4>")
	)
	(segment
		(start 308.911244 -277.400512)
		(end 308.596538 -277.400512)
		(width 0.12954)
		(layer "F.Cu")
		(net "M_A_CPU0_SB_DQS_DP<4>")
	)
	(segment
		(start 324.703186 -271.953736)
		(end 324.518274 -271.768824)
		(width 0.0762)
		(layer "F.Cu")
		(net "M_A_CPU0_SB_DQS_DP<4>")
	)
	(segment
		(start 324.18655 -271.768824)
		(end 324.12051 -271.834864)
		(width 0.0762)
		(layer "F.Cu")
		(net "M_A_CPU0_SB_DQS_DP<4>")
	)
	(segment
		(start 305.483006 -277.34387)
		(end 305.119786 -277.34387)
		(width 0.101346)
		(layer "F.Cu")
		(net "M_A_CPU0_SB_DQS_DP<4>")
	)
	(segment
		(start 325.708264 -271.953736)
		(end 324.703186 -271.953736)
		(width 0.0762)
		(layer "F.Cu")
		(net "M_A_CPU0_SB_DQS_DP<4>")
	)
	(segment
		(start 321.92214 -271.185132)
		(end 315.126624 -271.185132)
		(width 0.12954)
		(layer "F.Cu")
		(net "M_A_CPU0_SB_DQS_DP<4>")
	)
	(segment
		(start 304.693574 -276.917658)
		(end 304.123852 -276.917658)
		(width 0.101346)
		(layer "F.Cu")
		(net "M_A_CPU0_SB_DQS_DP<4>")
	)
	(segment
		(start 324.12051 -271.834864)
		(end 324.10146 -271.834864)
		(width 0.0762)
		(layer "F.Cu")
		(net "M_A_CPU0_SB_DQS_DP<4>")
	)
	(segment
		(start 325.999348 -271.87271)
		(end 325.990966 -271.877536)
		(width 0.0762)
		(layer "F.Cu")
		(net "M_A_CPU0_SB_DQS_DP<4>")
	)
	(segment
		(start 324.10146 -271.834864)
		(end 322.571872 -271.834864)
		(width 0.12954)
		(layer "F.Cu")
		(net "M_A_CPU0_SB_DQS_DP<4>")
	)
	(segment
		(start 322.571872 -271.834864)
		(end 321.92214 -271.185132)
		(width 0.12954)
		(layer "F.Cu")
		(net "M_A_CPU0_SB_DQS_DP<4>")
	)
	(arc
		(start 325.755254 -271.951958)
		(mid 325.731777 -271.953334)
		(end 325.708264 -271.953736)
		(width 0.0762)
		(layer "F.Cu")
		(net "M_A_CPU0_SB_DQS_DP<4>")
	)
	(arc
		(start 327.53808 -271.951704)
		(mid 327.417431 -271.927403)
		(end 327.304908 -271.877536)
		(width 0.0762)
		(layer "F.Cu")
		(net "M_A_CPU0_SB_DQS_DP<4>")
	)
	(arc
		(start 326.365108 -271.877536)
		(mid 326.182857 -271.827186)
		(end 325.999348 -271.87271)
		(width 0.0762)
		(layer "F.Cu")
		(net "M_A_CPU0_SB_DQS_DP<4>")
	)
	(arc
		(start 325.990966 -271.877536)
		(mid 325.877242 -271.927837)
		(end 325.755254 -271.951958)
		(width 0.0762)
		(layer "F.Cu")
		(net "M_A_CPU0_SB_DQS_DP<4>")
	)
	(arc
		(start 327.304908 -271.877536)
		(mid 327.117964 -271.827281)
		(end 326.93102 -271.877536)
		(width 0.0762)
		(layer "F.Cu")
		(net "M_A_CPU0_SB_DQS_DP<4>")
	)
	(arc
		(start 328.058018 -272.200116)
		(mid 327.820406 -272.029128)
		(end 327.53808 -271.951704)
		(width 0.0762)
		(layer "F.Cu")
		(net "M_A_CPU0_SB_DQS_DP<4>")
	)
	(arc
		(start 326.93102 -271.877536)
		(mid 326.648064 -271.953713)
		(end 326.365108 -271.877536)
		(width 0.0762)
		(layer "F.Cu")
		(net "M_A_CPU0_SB_DQS_DP<4>")
	)
	(segment
		(start 321.756024 -292.049454)
		(end 321.756024 -298.706032)
		(width 0.12954)
		(layer "F.Cu")
		(net "M_A_CPU0_SB_DQS_DP<3>")
	)
	(segment
		(start 321.402456 -300.289976)
		(end 321.402456 -300.472348)
		(width 0.12954)
		(layer "F.Cu")
		(net "M_A_CPU0_SB_DQS_DP<3>")
	)
	(segment
		(start 317.834518 -304.040286)
		(end 317.652146 -304.040286)
		(width 0.12954)
		(layer "F.Cu")
		(net "M_A_CPU0_SB_DQS_DP<3>")
	)
	(segment
		(start 317.992506 -303.882298)
		(end 317.834518 -304.040286)
		(width 0.12954)
		(layer "F.Cu")
		(net "M_A_CPU0_SB_DQS_DP<3>")
	)
	(segment
		(start 318.39916 -302.514)
		(end 317.948056 -302.514)
		(width 0.12954)
		(layer "F.Cu")
		(net "M_A_CPU0_SB_DQS_DP<3>")
	)
	(segment
		(start 321.01282 -299.449236)
		(end 321.01282 -299.90034)
		(width 0.12954)
		(layer "F.Cu")
		(net "M_A_CPU0_SB_DQS_DP<3>")
	)
	(segment
		(start 323.915024 -290.161726)
		(end 323.895974 -290.161726)
		(width 0.0762)
		(layer "F.Cu")
		(net "M_A_CPU0_SB_DQS_DP<3>")
	)
	(segment
		(start 320.221356 -300.2407)
		(end 319.87617 -300.585886)
		(width 0.12954)
		(layer "F.Cu")
		(net "M_A_CPU0_SB_DQS_DP<3>")
	)
	(segment
		(start 321.402456 -300.472348)
		(end 321.244468 -300.630336)
		(width 0.12954)
		(layer "F.Cu")
		(net "M_A_CPU0_SB_DQS_DP<3>")
	)
	(segment
		(start 325.70801 -290.266374)
		(end 325.302372 -290.266374)
		(width 0.0762)
		(layer "F.Cu")
		(net "M_A_CPU0_SB_DQS_DP<3>")
	)
	(segment
		(start 319.129156 -302.563276)
		(end 319.129156 -302.745648)
		(width 0.12954)
		(layer "F.Cu")
		(net "M_A_CPU0_SB_DQS_DP<3>")
	)
	(segment
		(start 319.084706 -301.37735)
		(end 318.73952 -301.722536)
		(width 0.12954)
		(layer "F.Cu")
		(net "M_A_CPU0_SB_DQS_DP<3>")
	)
	(segment
		(start 319.87617 -300.585886)
		(end 319.87617 -301.03699)
		(width 0.12954)
		(layer "F.Cu")
		(net "M_A_CPU0_SB_DQS_DP<3>")
	)
	(segment
		(start 320.67246 -300.2407)
		(end 320.221356 -300.2407)
		(width 0.12954)
		(layer "F.Cu")
		(net "M_A_CPU0_SB_DQS_DP<3>")
	)
	(segment
		(start 308.654704 -313.198764)
		(end 308.166516 -313.198764)
		(width 0.12954)
		(layer "F.Cu")
		(net "M_A_CPU0_SB_DQS_DP<3>")
	)
	(segment
		(start 319.87617 -301.03699)
		(end 320.265806 -301.426626)
		(width 0.12954)
		(layer "F.Cu")
		(net "M_A_CPU0_SB_DQS_DP<3>")
	)
	(segment
		(start 318.73952 -301.722536)
		(end 318.73952 -302.17364)
		(width 0.12954)
		(layer "F.Cu")
		(net "M_A_CPU0_SB_DQS_DP<3>")
	)
	(segment
		(start 317.652146 -304.040286)
		(end 317.26251 -303.65065)
		(width 0.12954)
		(layer "F.Cu")
		(net "M_A_CPU0_SB_DQS_DP<3>")
	)
	(segment
		(start 317.60287 -303.31029)
		(end 317.992506 -303.699926)
		(width 0.12954)
		(layer "F.Cu")
		(net "M_A_CPU0_SB_DQS_DP<3>")
	)
	(segment
		(start 316.311026 -304.15103)
		(end 316.311026 -305.542442)
		(width 0.12954)
		(layer "F.Cu")
		(net "M_A_CPU0_SB_DQS_DP<3>")
	)
	(segment
		(start 321.062096 -300.630336)
		(end 320.67246 -300.2407)
		(width 0.12954)
		(layer "F.Cu")
		(net "M_A_CPU0_SB_DQS_DP<3>")
	)
	(segment
		(start 326.17791 -290.019994)
		(end 326.276208 -290.189158)
		(width 0.0762)
		(layer "F.Cu")
		(net "M_A_CPU0_SB_DQS_DP<3>")
	)
	(segment
		(start 323.895974 -290.161726)
		(end 323.643752 -290.161726)
		(width 0.12954)
		(layer "F.Cu")
		(net "M_A_CPU0_SB_DQS_DP<3>")
	)
	(segment
		(start 307.902864 -312.935112)
		(end 307.368194 -312.935112)
		(width 0.12954)
		(layer "F.Cu")
		(net "M_A_CPU0_SB_DQS_DP<3>")
	)
	(segment
		(start 321.01282 -299.90034)
		(end 321.402456 -300.289976)
		(width 0.12954)
		(layer "F.Cu")
		(net "M_A_CPU0_SB_DQS_DP<3>")
	)
	(segment
		(start 325.999348 -290.3474)
		(end 325.990966 -290.342574)
		(width 0.0762)
		(layer "F.Cu")
		(net "M_A_CPU0_SB_DQS_DP<3>")
	)
	(segment
		(start 318.73952 -302.17364)
		(end 319.129156 -302.563276)
		(width 0.12954)
		(layer "F.Cu")
		(net "M_A_CPU0_SB_DQS_DP<3>")
	)
	(segment
		(start 321.756024 -298.706032)
		(end 321.01282 -299.449236)
		(width 0.12954)
		(layer "F.Cu")
		(net "M_A_CPU0_SB_DQS_DP<3>")
	)
	(segment
		(start 318.971168 -302.903636)
		(end 318.788796 -302.903636)
		(width 0.12954)
		(layer "F.Cu")
		(net "M_A_CPU0_SB_DQS_DP<3>")
	)
	(segment
		(start 320.265806 -301.608998)
		(end 320.107818 -301.766986)
		(width 0.12954)
		(layer "F.Cu")
		(net "M_A_CPU0_SB_DQS_DP<3>")
	)
	(segment
		(start 321.244468 -300.630336)
		(end 321.062096 -300.630336)
		(width 0.12954)
		(layer "F.Cu")
		(net "M_A_CPU0_SB_DQS_DP<3>")
	)
	(segment
		(start 317.60287 -302.859186)
		(end 317.60287 -303.31029)
		(width 0.12954)
		(layer "F.Cu")
		(net "M_A_CPU0_SB_DQS_DP<3>")
	)
	(segment
		(start 318.788796 -302.903636)
		(end 318.39916 -302.514)
		(width 0.12954)
		(layer "F.Cu")
		(net "M_A_CPU0_SB_DQS_DP<3>")
	)
	(segment
		(start 320.107818 -301.766986)
		(end 319.925446 -301.766986)
		(width 0.12954)
		(layer "F.Cu")
		(net "M_A_CPU0_SB_DQS_DP<3>")
	)
	(segment
		(start 319.53581 -301.37735)
		(end 319.084706 -301.37735)
		(width 0.12954)
		(layer "F.Cu")
		(net "M_A_CPU0_SB_DQS_DP<3>")
	)
	(segment
		(start 319.925446 -301.766986)
		(end 319.53581 -301.37735)
		(width 0.12954)
		(layer "F.Cu")
		(net "M_A_CPU0_SB_DQS_DP<3>")
	)
	(segment
		(start 309.441596 -312.411872)
		(end 309.20436 -312.411872)
		(width 0.12954)
		(layer "F.Cu")
		(net "M_A_CPU0_SB_DQS_DP<3>")
	)
	(segment
		(start 317.992506 -303.699926)
		(end 317.992506 -303.882298)
		(width 0.12954)
		(layer "F.Cu")
		(net "M_A_CPU0_SB_DQS_DP<3>")
	)
	(segment
		(start 323.981064 -290.227766)
		(end 323.915024 -290.161726)
		(width 0.0762)
		(layer "F.Cu")
		(net "M_A_CPU0_SB_DQS_DP<3>")
	)
	(segment
		(start 317.26251 -303.65065)
		(end 316.811406 -303.65065)
		(width 0.12954)
		(layer "F.Cu")
		(net "M_A_CPU0_SB_DQS_DP<3>")
	)
	(segment
		(start 323.643752 -290.161726)
		(end 321.756024 -292.049454)
		(width 0.12954)
		(layer "F.Cu")
		(net "M_A_CPU0_SB_DQS_DP<3>")
	)
	(segment
		(start 316.811406 -303.65065)
		(end 316.311026 -304.15103)
		(width 0.12954)
		(layer "F.Cu")
		(net "M_A_CPU0_SB_DQS_DP<3>")
	)
	(segment
		(start 308.166516 -313.198764)
		(end 307.902864 -312.935112)
		(width 0.12954)
		(layer "F.Cu")
		(net "M_A_CPU0_SB_DQS_DP<3>")
	)
	(segment
		(start 319.129156 -302.745648)
		(end 318.971168 -302.903636)
		(width 0.12954)
		(layer "F.Cu")
		(net "M_A_CPU0_SB_DQS_DP<3>")
	)
	(segment
		(start 308.929278 -312.92419)
		(end 308.654704 -313.198764)
		(width 0.12954)
		(layer "F.Cu")
		(net "M_A_CPU0_SB_DQS_DP<3>")
	)
	(segment
		(start 320.265806 -301.426626)
		(end 320.265806 -301.608998)
		(width 0.12954)
		(layer "F.Cu")
		(net "M_A_CPU0_SB_DQS_DP<3>")
	)
	(segment
		(start 325.263764 -290.227766)
		(end 323.981064 -290.227766)
		(width 0.0762)
		(layer "F.Cu")
		(net "M_A_CPU0_SB_DQS_DP<3>")
	)
	(segment
		(start 308.929278 -312.686954)
		(end 308.929278 -312.92419)
		(width 0.12954)
		(layer "F.Cu")
		(net "M_A_CPU0_SB_DQS_DP<3>")
	)
	(segment
		(start 316.311026 -305.542442)
		(end 309.441596 -312.411872)
		(width 0.12954)
		(layer "F.Cu")
		(net "M_A_CPU0_SB_DQS_DP<3>")
	)
	(segment
		(start 309.20436 -312.411872)
		(end 308.929278 -312.686954)
		(width 0.12954)
		(layer "F.Cu")
		(net "M_A_CPU0_SB_DQS_DP<3>")
	)
	(segment
		(start 325.302372 -290.266374)
		(end 325.263764 -290.227766)
		(width 0.0762)
		(layer "F.Cu")
		(net "M_A_CPU0_SB_DQS_DP<3>")
	)
	(segment
		(start 317.948056 -302.514)
		(end 317.60287 -302.859186)
		(width 0.12954)
		(layer "F.Cu")
		(net "M_A_CPU0_SB_DQS_DP<3>")
	)
	(arc
		(start 326.276208 -290.189158)
		(mid 326.267615 -290.331037)
		(end 326.13854 -290.390834)
		(width 0.0762)
		(layer "F.Cu")
		(net "M_A_CPU0_SB_DQS_DP<3>")
	)
	(arc
		(start 326.13854 -290.390834)
		(mid 326.066802 -290.375982)
		(end 325.999348 -290.3474)
		(width 0.0762)
		(layer "F.Cu")
		(net "M_A_CPU0_SB_DQS_DP<3>")
	)
	(arc
		(start 325.990966 -290.342574)
		(mid 325.85453 -290.285749)
		(end 325.70801 -290.266374)
		(width 0.0762)
		(layer "F.Cu")
		(net "M_A_CPU0_SB_DQS_DP<3>")
	)
	(segment
		(start 313.66714 -299.513752)
		(end 313.484768 -299.513752)
		(width 0.12954)
		(layer "F.Cu")
		(net "M_A_CPU0_SB_DQS_DP<2>")
	)
	(segment
		(start 314.759848 -297.383708)
		(end 314.759848 -297.834812)
		(width 0.12954)
		(layer "F.Cu")
		(net "M_A_CPU0_SB_DQS_DP<2>")
	)
	(segment
		(start 311.551828 -301.629064)
		(end 311.39384 -301.787052)
		(width 0.12954)
		(layer "F.Cu")
		(net "M_A_CPU0_SB_DQS_DP<2>")
	)
	(segment
		(start 323.895974 -285.24327)
		(end 322.202048 -285.24327)
		(width 0.12954)
		(layer "F.Cu")
		(net "M_A_CPU0_SB_DQS_DP<2>")
	)
	(segment
		(start 307.826664 -303.585118)
		(end 307.368194 -303.585118)
		(width 0.12954)
		(layer "F.Cu")
		(net "M_A_CPU0_SB_DQS_DP<2>")
	)
	(segment
		(start 325.302372 -285.406592)
		(end 325.20509 -285.30931)
		(width 0.0762)
		(layer "F.Cu")
		(net "M_A_CPU0_SB_DQS_DP<2>")
	)
	(segment
		(start 309.872888 -302.721772)
		(end 309.421784 -302.721772)
		(width 0.12954)
		(layer "F.Cu")
		(net "M_A_CPU0_SB_DQS_DP<2>")
	)
	(segment
		(start 312.831734 -299.311822)
		(end 312.486548 -299.657008)
		(width 0.12954)
		(layer "F.Cu")
		(net "M_A_CPU0_SB_DQS_DP<2>")
	)
	(segment
		(start 315.896498 -296.698162)
		(end 316.098428 -296.900092)
		(width 0.12954)
		(layer "F.Cu")
		(net "M_A_CPU0_SB_DQS_DP<2>")
	)
	(segment
		(start 314.419488 -298.175172)
		(end 313.968384 -298.175172)
		(width 0.12954)
		(layer "F.Cu")
		(net "M_A_CPU0_SB_DQS_DP<2>")
	)
	(segment
		(start 314.759848 -297.834812)
		(end 314.961778 -298.036742)
		(width 0.12954)
		(layer "F.Cu")
		(net "M_A_CPU0_SB_DQS_DP<2>")
	)
	(segment
		(start 322.202048 -285.24327)
		(end 317.328042 -290.117276)
		(width 0.12954)
		(layer "F.Cu")
		(net "M_A_CPU0_SB_DQS_DP<2>")
	)
	(segment
		(start 314.621418 -298.377102)
		(end 314.419488 -298.175172)
		(width 0.12954)
		(layer "F.Cu")
		(net "M_A_CPU0_SB_DQS_DP<2>")
	)
	(segment
		(start 317.235078 -295.763442)
		(end 317.235078 -295.945814)
		(width 0.12954)
		(layer "F.Cu")
		(net "M_A_CPU0_SB_DQS_DP<2>")
	)
	(segment
		(start 313.282838 -299.311822)
		(end 312.831734 -299.311822)
		(width 0.12954)
		(layer "F.Cu")
		(net "M_A_CPU0_SB_DQS_DP<2>")
	)
	(segment
		(start 315.896498 -296.247058)
		(end 315.896498 -296.698162)
		(width 0.12954)
		(layer "F.Cu")
		(net "M_A_CPU0_SB_DQS_DP<2>")
	)
	(segment
		(start 315.94044 -297.240452)
		(end 315.758068 -297.240452)
		(width 0.12954)
		(layer "F.Cu")
		(net "M_A_CPU0_SB_DQS_DP<2>")
	)
	(segment
		(start 325.999348 -285.487618)
		(end 325.990966 -285.482792)
		(width 0.0762)
		(layer "F.Cu")
		(net "M_A_CPU0_SB_DQS_DP<2>")
	)
	(segment
		(start 313.968384 -298.175172)
		(end 313.623198 -298.520358)
		(width 0.12954)
		(layer "F.Cu")
		(net "M_A_CPU0_SB_DQS_DP<2>")
	)
	(segment
		(start 312.486548 -299.657008)
		(end 312.486548 -300.108112)
		(width 0.12954)
		(layer "F.Cu")
		(net "M_A_CPU0_SB_DQS_DP<2>")
	)
	(segment
		(start 310.213248 -302.381412)
		(end 310.415178 -302.583342)
		(width 0.12954)
		(layer "F.Cu")
		(net "M_A_CPU0_SB_DQS_DP<2>")
	)
	(segment
		(start 313.484768 -299.513752)
		(end 313.282838 -299.311822)
		(width 0.12954)
		(layer "F.Cu")
		(net "M_A_CPU0_SB_DQS_DP<2>")
	)
	(segment
		(start 312.688478 -300.310042)
		(end 312.688478 -300.492414)
		(width 0.12954)
		(layer "F.Cu")
		(net "M_A_CPU0_SB_DQS_DP<2>")
	)
	(segment
		(start 317.033148 -295.561512)
		(end 317.235078 -295.763442)
		(width 0.12954)
		(layer "F.Cu")
		(net "M_A_CPU0_SB_DQS_DP<2>")
	)
	(segment
		(start 314.961778 -298.219114)
		(end 314.80379 -298.377102)
		(width 0.12954)
		(layer "F.Cu")
		(net "M_A_CPU0_SB_DQS_DP<2>")
	)
	(segment
		(start 309.421784 -302.721772)
		(end 308.294786 -303.84877)
		(width 0.12954)
		(layer "F.Cu")
		(net "M_A_CPU0_SB_DQS_DP<2>")
	)
	(segment
		(start 315.758068 -297.240452)
		(end 315.556138 -297.038522)
		(width 0.12954)
		(layer "F.Cu")
		(net "M_A_CPU0_SB_DQS_DP<2>")
	)
	(segment
		(start 317.07709 -296.103802)
		(end 316.894718 -296.103802)
		(width 0.12954)
		(layer "F.Cu")
		(net "M_A_CPU0_SB_DQS_DP<2>")
	)
	(segment
		(start 316.098428 -297.082464)
		(end 315.94044 -297.240452)
		(width 0.12954)
		(layer "F.Cu")
		(net "M_A_CPU0_SB_DQS_DP<2>")
	)
	(segment
		(start 311.349898 -300.793658)
		(end 311.349898 -301.244762)
		(width 0.12954)
		(layer "F.Cu")
		(net "M_A_CPU0_SB_DQS_DP<2>")
	)
	(segment
		(start 323.915024 -285.24327)
		(end 323.895974 -285.24327)
		(width 0.0762)
		(layer "F.Cu")
		(net "M_A_CPU0_SB_DQS_DP<2>")
	)
	(segment
		(start 316.894718 -296.103802)
		(end 316.692788 -295.901872)
		(width 0.12954)
		(layer "F.Cu")
		(net "M_A_CPU0_SB_DQS_DP<2>")
	)
	(segment
		(start 315.105034 -297.038522)
		(end 314.759848 -297.383708)
		(width 0.12954)
		(layer "F.Cu")
		(net "M_A_CPU0_SB_DQS_DP<2>")
	)
	(segment
		(start 314.961778 -298.036742)
		(end 314.961778 -298.219114)
		(width 0.12954)
		(layer "F.Cu")
		(net "M_A_CPU0_SB_DQS_DP<2>")
	)
	(segment
		(start 326.17791 -285.160212)
		(end 326.276208 -285.329376)
		(width 0.0762)
		(layer "F.Cu")
		(net "M_A_CPU0_SB_DQS_DP<2>")
	)
	(segment
		(start 311.551828 -301.446692)
		(end 311.551828 -301.629064)
		(width 0.12954)
		(layer "F.Cu")
		(net "M_A_CPU0_SB_DQS_DP<2>")
	)
	(segment
		(start 316.692788 -295.901872)
		(end 316.241684 -295.901872)
		(width 0.12954)
		(layer "F.Cu")
		(net "M_A_CPU0_SB_DQS_DP<2>")
	)
	(segment
		(start 313.825128 -299.173392)
		(end 313.825128 -299.355764)
		(width 0.12954)
		(layer "F.Cu")
		(net "M_A_CPU0_SB_DQS_DP<2>")
	)
	(segment
		(start 312.53049 -300.650402)
		(end 312.348118 -300.650402)
		(width 0.12954)
		(layer "F.Cu")
		(net "M_A_CPU0_SB_DQS_DP<2>")
	)
	(segment
		(start 310.213248 -301.930308)
		(end 310.213248 -302.381412)
		(width 0.12954)
		(layer "F.Cu")
		(net "M_A_CPU0_SB_DQS_DP<2>")
	)
	(segment
		(start 312.348118 -300.650402)
		(end 312.146188 -300.448472)
		(width 0.12954)
		(layer "F.Cu")
		(net "M_A_CPU0_SB_DQS_DP<2>")
	)
	(segment
		(start 317.033148 -295.110408)
		(end 317.033148 -295.561512)
		(width 0.12954)
		(layer "F.Cu")
		(net "M_A_CPU0_SB_DQS_DP<2>")
	)
	(segment
		(start 308.090316 -303.84877)
		(end 307.826664 -303.585118)
		(width 0.12954)
		(layer "F.Cu")
		(net "M_A_CPU0_SB_DQS_DP<2>")
	)
	(segment
		(start 310.415178 -302.583342)
		(end 310.415178 -302.765714)
		(width 0.12954)
		(layer "F.Cu")
		(net "M_A_CPU0_SB_DQS_DP<2>")
	)
	(segment
		(start 323.981064 -285.30931)
		(end 323.915024 -285.24327)
		(width 0.0762)
		(layer "F.Cu")
		(net "M_A_CPU0_SB_DQS_DP<2>")
	)
	(segment
		(start 314.80379 -298.377102)
		(end 314.621418 -298.377102)
		(width 0.12954)
		(layer "F.Cu")
		(net "M_A_CPU0_SB_DQS_DP<2>")
	)
	(segment
		(start 310.074818 -302.923702)
		(end 309.872888 -302.721772)
		(width 0.12954)
		(layer "F.Cu")
		(net "M_A_CPU0_SB_DQS_DP<2>")
	)
	(segment
		(start 317.235078 -295.945814)
		(end 317.07709 -296.103802)
		(width 0.12954)
		(layer "F.Cu")
		(net "M_A_CPU0_SB_DQS_DP<2>")
	)
	(segment
		(start 325.20509 -285.30931)
		(end 323.981064 -285.30931)
		(width 0.0762)
		(layer "F.Cu")
		(net "M_A_CPU0_SB_DQS_DP<2>")
	)
	(segment
		(start 311.695084 -300.448472)
		(end 311.349898 -300.793658)
		(width 0.12954)
		(layer "F.Cu")
		(net "M_A_CPU0_SB_DQS_DP<2>")
	)
	(segment
		(start 308.294786 -303.84877)
		(end 308.090316 -303.84877)
		(width 0.12954)
		(layer "F.Cu")
		(net "M_A_CPU0_SB_DQS_DP<2>")
	)
	(segment
		(start 313.623198 -298.971462)
		(end 313.825128 -299.173392)
		(width 0.12954)
		(layer "F.Cu")
		(net "M_A_CPU0_SB_DQS_DP<2>")
	)
	(segment
		(start 310.558434 -301.585122)
		(end 310.213248 -301.930308)
		(width 0.12954)
		(layer "F.Cu")
		(net "M_A_CPU0_SB_DQS_DP<2>")
	)
	(segment
		(start 311.211468 -301.787052)
		(end 311.009538 -301.585122)
		(width 0.12954)
		(layer "F.Cu")
		(net "M_A_CPU0_SB_DQS_DP<2>")
	)
	(segment
		(start 311.349898 -301.244762)
		(end 311.551828 -301.446692)
		(width 0.12954)
		(layer "F.Cu")
		(net "M_A_CPU0_SB_DQS_DP<2>")
	)
	(segment
		(start 316.098428 -296.900092)
		(end 316.098428 -297.082464)
		(width 0.12954)
		(layer "F.Cu")
		(net "M_A_CPU0_SB_DQS_DP<2>")
	)
	(segment
		(start 312.688478 -300.492414)
		(end 312.53049 -300.650402)
		(width 0.12954)
		(layer "F.Cu")
		(net "M_A_CPU0_SB_DQS_DP<2>")
	)
	(segment
		(start 315.556138 -297.038522)
		(end 315.105034 -297.038522)
		(width 0.12954)
		(layer "F.Cu")
		(net "M_A_CPU0_SB_DQS_DP<2>")
	)
	(segment
		(start 311.009538 -301.585122)
		(end 310.558434 -301.585122)
		(width 0.12954)
		(layer "F.Cu")
		(net "M_A_CPU0_SB_DQS_DP<2>")
	)
	(segment
		(start 316.241684 -295.901872)
		(end 315.896498 -296.247058)
		(width 0.12954)
		(layer "F.Cu")
		(net "M_A_CPU0_SB_DQS_DP<2>")
	)
	(segment
		(start 310.25719 -302.923702)
		(end 310.074818 -302.923702)
		(width 0.12954)
		(layer "F.Cu")
		(net "M_A_CPU0_SB_DQS_DP<2>")
	)
	(segment
		(start 313.825128 -299.355764)
		(end 313.66714 -299.513752)
		(width 0.12954)
		(layer "F.Cu")
		(net "M_A_CPU0_SB_DQS_DP<2>")
	)
	(segment
		(start 312.146188 -300.448472)
		(end 311.695084 -300.448472)
		(width 0.12954)
		(layer "F.Cu")
		(net "M_A_CPU0_SB_DQS_DP<2>")
	)
	(segment
		(start 312.486548 -300.108112)
		(end 312.688478 -300.310042)
		(width 0.12954)
		(layer "F.Cu")
		(net "M_A_CPU0_SB_DQS_DP<2>")
	)
	(segment
		(start 325.70801 -285.406592)
		(end 325.302372 -285.406592)
		(width 0.0762)
		(layer "F.Cu")
		(net "M_A_CPU0_SB_DQS_DP<2>")
	)
	(segment
		(start 313.623198 -298.520358)
		(end 313.623198 -298.971462)
		(width 0.12954)
		(layer "F.Cu")
		(net "M_A_CPU0_SB_DQS_DP<2>")
	)
	(segment
		(start 311.39384 -301.787052)
		(end 311.211468 -301.787052)
		(width 0.12954)
		(layer "F.Cu")
		(net "M_A_CPU0_SB_DQS_DP<2>")
	)
	(segment
		(start 310.415178 -302.765714)
		(end 310.25719 -302.923702)
		(width 0.12954)
		(layer "F.Cu")
		(net "M_A_CPU0_SB_DQS_DP<2>")
	)
	(segment
		(start 317.328042 -290.117276)
		(end 317.328042 -294.815514)
		(width 0.12954)
		(layer "F.Cu")
		(net "M_A_CPU0_SB_DQS_DP<2>")
	)
	(segment
		(start 317.328042 -294.815514)
		(end 317.033148 -295.110408)
		(width 0.12954)
		(layer "F.Cu")
		(net "M_A_CPU0_SB_DQS_DP<2>")
	)
	(arc
		(start 325.990966 -285.482792)
		(mid 325.85453 -285.425967)
		(end 325.70801 -285.406592)
		(width 0.0762)
		(layer "F.Cu")
		(net "M_A_CPU0_SB_DQS_DP<2>")
	)
	(arc
		(start 326.276208 -285.329376)
		(mid 326.267615 -285.471255)
		(end 326.13854 -285.531052)
		(width 0.0762)
		(layer "F.Cu")
		(net "M_A_CPU0_SB_DQS_DP<2>")
	)
	(arc
		(start 326.13854 -285.531052)
		(mid 326.066802 -285.5162)
		(end 325.999348 -285.487618)
		(width 0.0762)
		(layer "F.Cu")
		(net "M_A_CPU0_SB_DQS_DP<2>")
	)
	(segment
		(start 310.728868 -293.389304)
		(end 310.54548 -293.389304)
		(width 0.12954)
		(layer "F.Cu")
		(net "M_A_CPU0_SB_DQS_DP<1>")
	)
	(segment
		(start 317.559182 -283.080206)
		(end 317.559182 -283.63037)
		(width 0.12954)
		(layer "F.Cu")
		(net "M_A_CPU0_SB_DQS_DP<1>")
	)
	(segment
		(start 318.695832 -282.49372)
		(end 318.496188 -282.693364)
		(width 0.12954)
		(layer "F.Cu")
		(net "M_A_CPU0_SB_DQS_DP<1>")
	)
	(segment
		(start 323.981064 -280.38171)
		(end 323.915024 -280.31567)
		(width 0.0762)
		(layer "F.Cu")
		(net "M_A_CPU0_SB_DQS_DP<1>")
	)
	(segment
		(start 312.520838 -289.085528)
		(end 312.896504 -289.461194)
		(width 0.12954)
		(layer "F.Cu")
		(net "M_A_CPU0_SB_DQS_DP<1>")
	)
	(segment
		(start 312.896504 -291.221668)
		(end 312.609992 -291.50818)
		(width 0.12954)
		(layer "F.Cu")
		(net "M_A_CPU0_SB_DQS_DP<1>")
	)
	(segment
		(start 310.54548 -293.389304)
		(end 309.713122 -292.556946)
		(width 0.12954)
		(layer "F.Cu")
		(net "M_A_CPU0_SB_DQS_DP<1>")
	)
	(segment
		(start 318.695832 -281.943556)
		(end 318.695832 -282.49372)
		(width 0.12954)
		(layer "F.Cu")
		(net "M_A_CPU0_SB_DQS_DP<1>")
	)
	(segment
		(start 309.619396 -294.498776)
		(end 308.166516 -294.498776)
		(width 0.12954)
		(layer "F.Cu")
		(net "M_A_CPU0_SB_DQS_DP<1>")
	)
	(segment
		(start 317.559182 -283.63037)
		(end 317.359538 -283.830014)
		(width 0.12954)
		(layer "F.Cu")
		(net "M_A_CPU0_SB_DQS_DP<1>")
	)
	(segment
		(start 325.156576 -280.40076)
		(end 324.163944 -280.40076)
		(width 0.0762)
		(layer "F.Cu")
		(net "M_A_CPU0_SB_DQS_DP<1>")
	)
	(segment
		(start 325.302372 -280.546556)
		(end 325.156576 -280.40076)
		(width 0.0762)
		(layer "F.Cu")
		(net "M_A_CPU0_SB_DQS_DP<1>")
	)
	(segment
		(start 315.285882 -285.353506)
		(end 315.285882 -285.90367)
		(width 0.12954)
		(layer "F.Cu")
		(net "M_A_CPU0_SB_DQS_DP<1>")
	)
	(segment
		(start 319.832482 -281.35707)
		(end 319.632838 -281.556714)
		(width 0.12954)
		(layer "F.Cu")
		(net "M_A_CPU0_SB_DQS_DP<1>")
	)
	(segment
		(start 309.713122 -292.556946)
		(end 309.263034 -292.5572)
		(width 0.12954)
		(layer "F.Cu")
		(net "M_A_CPU0_SB_DQS_DP<1>")
	)
	(segment
		(start 314.536074 -286.103314)
		(end 314.149232 -286.490156)
		(width 0.12954)
		(layer "F.Cu")
		(net "M_A_CPU0_SB_DQS_DP<1>")
	)
	(segment
		(start 312.896504 -289.461194)
		(end 312.896504 -291.221668)
		(width 0.12954)
		(layer "F.Cu")
		(net "M_A_CPU0_SB_DQS_DP<1>")
	)
	(segment
		(start 308.166516 -294.498776)
		(end 307.902864 -294.235124)
		(width 0.12954)
		(layer "F.Cu")
		(net "M_A_CPU0_SB_DQS_DP<1>")
	)
	(segment
		(start 314.149232 -287.04032)
		(end 313.949588 -287.239964)
		(width 0.12954)
		(layer "F.Cu")
		(net "M_A_CPU0_SB_DQS_DP<1>")
	)
	(segment
		(start 309.263034 -292.5572)
		(end 308.91607 -292.904164)
		(width 0.12954)
		(layer "F.Cu")
		(net "M_A_CPU0_SB_DQS_DP<1>")
	)
	(segment
		(start 324.163944 -280.40076)
		(end 323.981064 -280.38171)
		(width 0.0762)
		(layer "F.Cu")
		(net "M_A_CPU0_SB_DQS_DP<1>")
	)
	(segment
		(start 313.399424 -287.239964)
		(end 312.896504 -287.742884)
		(width 0.12954)
		(layer "F.Cu")
		(net "M_A_CPU0_SB_DQS_DP<1>")
	)
	(segment
		(start 312.520838 -288.524442)
		(end 312.520838 -289.085528)
		(width 0.12954)
		(layer "F.Cu")
		(net "M_A_CPU0_SB_DQS_DP<1>")
	)
	(segment
		(start 307.902864 -294.235124)
		(end 307.368194 -294.235124)
		(width 0.12954)
		(layer "F.Cu")
		(net "M_A_CPU0_SB_DQS_DP<1>")
	)
	(segment
		(start 316.422532 -284.216856)
		(end 316.422532 -284.76702)
		(width 0.12954)
		(layer "F.Cu")
		(net "M_A_CPU0_SB_DQS_DP<1>")
	)
	(segment
		(start 317.359538 -283.830014)
		(end 316.809374 -283.830014)
		(width 0.12954)
		(layer "F.Cu")
		(net "M_A_CPU0_SB_DQS_DP<1>")
	)
	(segment
		(start 325.999348 -280.627582)
		(end 325.990966 -280.622756)
		(width 0.0762)
		(layer "F.Cu")
		(net "M_A_CPU0_SB_DQS_DP<1>")
	)
	(segment
		(start 319.082674 -281.556714)
		(end 318.695832 -281.943556)
		(width 0.12954)
		(layer "F.Cu")
		(net "M_A_CPU0_SB_DQS_DP<1>")
	)
	(segment
		(start 316.222888 -284.966664)
		(end 315.672724 -284.966664)
		(width 0.12954)
		(layer "F.Cu")
		(net "M_A_CPU0_SB_DQS_DP<1>")
	)
	(segment
		(start 323.895974 -280.31567)
		(end 320.323718 -280.31567)
		(width 0.12954)
		(layer "F.Cu")
		(net "M_A_CPU0_SB_DQS_DP<1>")
	)
	(segment
		(start 325.70801 -280.546556)
		(end 325.302372 -280.546556)
		(width 0.0762)
		(layer "F.Cu")
		(net "M_A_CPU0_SB_DQS_DP<1>")
	)
	(segment
		(start 312.896504 -287.742884)
		(end 312.896504 -288.148776)
		(width 0.12954)
		(layer "F.Cu")
		(net "M_A_CPU0_SB_DQS_DP<1>")
	)
	(segment
		(start 317.946024 -282.693364)
		(end 317.559182 -283.080206)
		(width 0.12954)
		(layer "F.Cu")
		(net "M_A_CPU0_SB_DQS_DP<1>")
	)
	(segment
		(start 320.323718 -280.31567)
		(end 319.832482 -280.806906)
		(width 0.12954)
		(layer "F.Cu")
		(net "M_A_CPU0_SB_DQS_DP<1>")
	)
	(segment
		(start 315.672724 -284.966664)
		(end 315.285882 -285.353506)
		(width 0.12954)
		(layer "F.Cu")
		(net "M_A_CPU0_SB_DQS_DP<1>")
	)
	(segment
		(start 313.949588 -287.239964)
		(end 313.399424 -287.239964)
		(width 0.12954)
		(layer "F.Cu")
		(net "M_A_CPU0_SB_DQS_DP<1>")
	)
	(segment
		(start 323.915024 -280.31567)
		(end 323.895974 -280.31567)
		(width 0.0762)
		(layer "F.Cu")
		(net "M_A_CPU0_SB_DQS_DP<1>")
	)
	(segment
		(start 316.809374 -283.830014)
		(end 316.422532 -284.216856)
		(width 0.12954)
		(layer "F.Cu")
		(net "M_A_CPU0_SB_DQS_DP<1>")
	)
	(segment
		(start 309.748936 -294.369236)
		(end 309.619396 -294.498776)
		(width 0.12954)
		(layer "F.Cu")
		(net "M_A_CPU0_SB_DQS_DP<1>")
	)
	(segment
		(start 326.17791 -280.300176)
		(end 326.276208 -280.46934)
		(width 0.0762)
		(layer "F.Cu")
		(net "M_A_CPU0_SB_DQS_DP<1>")
	)
	(segment
		(start 309.748936 -294.186356)
		(end 309.748936 -294.369236)
		(width 0.12954)
		(layer "F.Cu")
		(net "M_A_CPU0_SB_DQS_DP<1>")
	)
	(segment
		(start 318.496188 -282.693364)
		(end 317.946024 -282.693364)
		(width 0.12954)
		(layer "F.Cu")
		(net "M_A_CPU0_SB_DQS_DP<1>")
	)
	(segment
		(start 315.086238 -286.103314)
		(end 314.536074 -286.103314)
		(width 0.12954)
		(layer "F.Cu")
		(net "M_A_CPU0_SB_DQS_DP<1>")
	)
	(segment
		(start 319.632838 -281.556714)
		(end 319.082674 -281.556714)
		(width 0.12954)
		(layer "F.Cu")
		(net "M_A_CPU0_SB_DQS_DP<1>")
	)
	(segment
		(start 315.285882 -285.90367)
		(end 315.086238 -286.103314)
		(width 0.12954)
		(layer "F.Cu")
		(net "M_A_CPU0_SB_DQS_DP<1>")
	)
	(segment
		(start 312.609992 -291.50818)
		(end 312.063384 -291.50818)
		(width 0.12954)
		(layer "F.Cu")
		(net "M_A_CPU0_SB_DQS_DP<1>")
	)
	(segment
		(start 308.916324 -293.353744)
		(end 309.748936 -294.186356)
		(width 0.12954)
		(layer "F.Cu")
		(net "M_A_CPU0_SB_DQS_DP<1>")
	)
	(segment
		(start 312.896504 -288.148776)
		(end 312.520838 -288.524442)
		(width 0.12954)
		(layer "F.Cu")
		(net "M_A_CPU0_SB_DQS_DP<1>")
	)
	(segment
		(start 311.67324 -292.444932)
		(end 310.728868 -293.389304)
		(width 0.12954)
		(layer "F.Cu")
		(net "M_A_CPU0_SB_DQS_DP<1>")
	)
	(segment
		(start 311.67324 -291.898324)
		(end 311.67324 -292.444932)
		(width 0.12954)
		(layer "F.Cu")
		(net "M_A_CPU0_SB_DQS_DP<1>")
	)
	(segment
		(start 314.149232 -286.490156)
		(end 314.149232 -287.04032)
		(width 0.12954)
		(layer "F.Cu")
		(net "M_A_CPU0_SB_DQS_DP<1>")
	)
	(segment
		(start 319.832482 -280.806906)
		(end 319.832482 -281.35707)
		(width 0.12954)
		(layer "F.Cu")
		(net "M_A_CPU0_SB_DQS_DP<1>")
	)
	(segment
		(start 312.063384 -291.50818)
		(end 311.67324 -291.898324)
		(width 0.12954)
		(layer "F.Cu")
		(net "M_A_CPU0_SB_DQS_DP<1>")
	)
	(segment
		(start 308.91607 -292.904164)
		(end 308.916324 -293.353744)
		(width 0.12954)
		(layer "F.Cu")
		(net "M_A_CPU0_SB_DQS_DP<1>")
	)
	(segment
		(start 316.422532 -284.76702)
		(end 316.222888 -284.966664)
		(width 0.12954)
		(layer "F.Cu")
		(net "M_A_CPU0_SB_DQS_DP<1>")
	)
	(arc
		(start 326.276208 -280.46934)
		(mid 326.267615 -280.611219)
		(end 326.13854 -280.671016)
		(width 0.0762)
		(layer "F.Cu")
		(net "M_A_CPU0_SB_DQS_DP<1>")
	)
	(arc
		(start 326.13854 -280.671016)
		(mid 326.066802 -280.656164)
		(end 325.999348 -280.627582)
		(width 0.0762)
		(layer "F.Cu")
		(net "M_A_CPU0_SB_DQS_DP<1>")
	)
	(arc
		(start 325.990966 -280.622756)
		(mid 325.85453 -280.565931)
		(end 325.70801 -280.546556)
		(width 0.0762)
		(layer "F.Cu")
		(net "M_A_CPU0_SB_DQS_DP<1>")
	)
	(segment
		(start 315.861192 -277.636986)
		(end 315.703204 -277.794974)
		(width 0.12954)
		(layer "F.Cu")
		(net "M_A_CPU0_SB_DQS_DP<0>")
	)
	(segment
		(start 324.424548 -275.367242)
		(end 324.114668 -275.367242)
		(width 0.0762)
		(layer "F.Cu")
		(net "M_A_CPU0_SB_DQS_DP<0>")
	)
	(segment
		(start 313.147456 -279.968198)
		(end 312.696352 -279.968198)
		(width 0.12954)
		(layer "F.Cu")
		(net "M_A_CPU0_SB_DQS_DP<0>")
	)
	(segment
		(start 316.997842 -276.500336)
		(end 316.839854 -276.658324)
		(width 0.12954)
		(layer "F.Cu")
		(net "M_A_CPU0_SB_DQS_DP<0>")
	)
	(segment
		(start 316.897766 -276.217888)
		(end 316.997842 -276.317964)
		(width 0.12954)
		(layer "F.Cu")
		(net "M_A_CPU0_SB_DQS_DP<0>")
	)
	(segment
		(start 322.98005 -275.569172)
		(end 322.71208 -275.301202)
		(width 0.12954)
		(layer "F.Cu")
		(net "M_A_CPU0_SB_DQS_DP<0>")
	)
	(segment
		(start 319.768474 -275.569172)
		(end 319.500504 -275.301202)
		(width 0.12954)
		(layer "F.Cu")
		(net "M_A_CPU0_SB_DQS_DP<0>")
	)
	(segment
		(start 325.70801 -275.68652)
		(end 324.743826 -275.68652)
		(width 0.0762)
		(layer "F.Cu")
		(net "M_A_CPU0_SB_DQS_DP<0>")
	)
	(segment
		(start 323.699378 -275.301202)
		(end 323.431408 -275.569172)
		(width 0.12954)
		(layer "F.Cu")
		(net "M_A_CPU0_SB_DQS_DP<0>")
	)
	(segment
		(start 322.71208 -275.301202)
		(end 322.09359 -275.301202)
		(width 0.12954)
		(layer "F.Cu")
		(net "M_A_CPU0_SB_DQS_DP<0>")
	)
	(segment
		(start 324.029578 -275.301202)
		(end 323.699378 -275.301202)
		(width 0.12954)
		(layer "F.Cu")
		(net "M_A_CPU0_SB_DQS_DP<0>")
	)
	(segment
		(start 316.897766 -275.766784)
		(end 316.897766 -276.217888)
		(width 0.12954)
		(layer "F.Cu")
		(net "M_A_CPU0_SB_DQS_DP<0>")
	)
	(segment
		(start 313.833002 -278.831548)
		(end 313.487816 -279.176734)
		(width 0.12954)
		(layer "F.Cu")
		(net "M_A_CPU0_SB_DQS_DP<0>")
	)
	(segment
		(start 308.756304 -284.8229)
		(end 308.430422 -285.148782)
		(width 0.12954)
		(layer "F.Cu")
		(net "M_A_CPU0_SB_DQS_DP<0>")
	)
	(segment
		(start 312.351166 -280.313384)
		(end 312.351166 -280.764488)
		(width 0.12954)
		(layer "F.Cu")
		(net "M_A_CPU0_SB_DQS_DP<0>")
	)
	(segment
		(start 312.293254 -281.204924)
		(end 312.110882 -281.204924)
		(width 0.12954)
		(layer "F.Cu")
		(net "M_A_CPU0_SB_DQS_DP<0>")
	)
	(segment
		(start 311.314592 -282.001214)
		(end 311.314592 -282.183586)
		(width 0.12954)
		(layer "F.Cu")
		(net "M_A_CPU0_SB_DQS_DP<0>")
	)
	(segment
		(start 309.737506 -283.378148)
		(end 309.286402 -283.378148)
		(width 0.12954)
		(layer "F.Cu")
		(net "M_A_CPU0_SB_DQS_DP<0>")
	)
	(segment
		(start 315.761116 -277.354538)
		(end 315.861192 -277.454614)
		(width 0.12954)
		(layer "F.Cu")
		(net "M_A_CPU0_SB_DQS_DP<0>")
	)
	(segment
		(start 310.974232 -282.341574)
		(end 310.874156 -282.241498)
		(width 0.12954)
		(layer "F.Cu")
		(net "M_A_CPU0_SB_DQS_DP<0>")
	)
	(segment
		(start 312.451242 -281.046936)
		(end 312.293254 -281.204924)
		(width 0.12954)
		(layer "F.Cu")
		(net "M_A_CPU0_SB_DQS_DP<0>")
	)
	(segment
		(start 315.420756 -277.694898)
		(end 314.969652 -277.694898)
		(width 0.12954)
		(layer "F.Cu")
		(net "M_A_CPU0_SB_DQS_DP<0>")
	)
	(segment
		(start 311.214516 -281.901138)
		(end 311.314592 -282.001214)
		(width 0.12954)
		(layer "F.Cu")
		(net "M_A_CPU0_SB_DQS_DP<0>")
	)
	(segment
		(start 311.214516 -281.450034)
		(end 311.214516 -281.901138)
		(width 0.12954)
		(layer "F.Cu")
		(net "M_A_CPU0_SB_DQS_DP<0>")
	)
	(segment
		(start 308.430422 -285.148782)
		(end 308.166516 -285.148782)
		(width 0.12954)
		(layer "F.Cu")
		(net "M_A_CPU0_SB_DQS_DP<0>")
	)
	(segment
		(start 326.17791 -275.44014)
		(end 326.276208 -275.609304)
		(width 0.0762)
		(layer "F.Cu")
		(net "M_A_CPU0_SB_DQS_DP<0>")
	)
	(segment
		(start 310.423052 -282.241498)
		(end 310.077866 -282.586684)
		(width 0.12954)
		(layer "F.Cu")
		(net "M_A_CPU0_SB_DQS_DP<0>")
	)
	(segment
		(start 312.451242 -280.864564)
		(end 312.451242 -281.046936)
		(width 0.12954)
		(layer "F.Cu")
		(net "M_A_CPU0_SB_DQS_DP<0>")
	)
	(segment
		(start 309.837582 -283.478224)
		(end 309.737506 -283.378148)
		(width 0.12954)
		(layer "F.Cu")
		(net "M_A_CPU0_SB_DQS_DP<0>")
	)
	(segment
		(start 321.106292 -275.301202)
		(end 320.487802 -275.301202)
		(width 0.12954)
		(layer "F.Cu")
		(net "M_A_CPU0_SB_DQS_DP<0>")
	)
	(segment
		(start 310.077866 -282.586684)
		(end 310.077866 -283.037788)
		(width 0.12954)
		(layer "F.Cu")
		(net "M_A_CPU0_SB_DQS_DP<0>")
	)
	(segment
		(start 314.624466 -278.040084)
		(end 314.624466 -278.491188)
		(width 0.12954)
		(layer "F.Cu")
		(net "M_A_CPU0_SB_DQS_DP<0>")
	)
	(segment
		(start 324.048628 -275.301202)
		(end 324.029578 -275.301202)
		(width 0.0762)
		(layer "F.Cu")
		(net "M_A_CPU0_SB_DQS_DP<0>")
	)
	(segment
		(start 325.999348 -275.767546)
		(end 325.990966 -275.76272)
		(width 0.0762)
		(layer "F.Cu")
		(net "M_A_CPU0_SB_DQS_DP<0>")
	)
	(segment
		(start 309.286402 -283.378148)
		(end 308.756304 -283.908246)
		(width 0.12954)
		(layer "F.Cu")
		(net "M_A_CPU0_SB_DQS_DP<0>")
	)
	(segment
		(start 318.162686 -275.569172)
		(end 317.894716 -275.301202)
		(width 0.12954)
		(layer "F.Cu")
		(net "M_A_CPU0_SB_DQS_DP<0>")
	)
	(segment
		(start 316.106302 -276.558248)
		(end 315.761116 -276.903434)
		(width 0.12954)
		(layer "F.Cu")
		(net "M_A_CPU0_SB_DQS_DP<0>")
	)
	(segment
		(start 313.429904 -280.068274)
		(end 313.247532 -280.068274)
		(width 0.12954)
		(layer "F.Cu")
		(net "M_A_CPU0_SB_DQS_DP<0>")
	)
	(segment
		(start 316.657482 -276.658324)
		(end 316.557406 -276.558248)
		(width 0.12954)
		(layer "F.Cu")
		(net "M_A_CPU0_SB_DQS_DP<0>")
	)
	(segment
		(start 310.874156 -282.241498)
		(end 310.423052 -282.241498)
		(width 0.12954)
		(layer "F.Cu")
		(net "M_A_CPU0_SB_DQS_DP<0>")
	)
	(segment
		(start 321.82562 -275.569172)
		(end 321.374262 -275.569172)
		(width 0.12954)
		(layer "F.Cu")
		(net "M_A_CPU0_SB_DQS_DP<0>")
	)
	(segment
		(start 316.997842 -276.317964)
		(end 316.997842 -276.500336)
		(width 0.12954)
		(layer "F.Cu")
		(net "M_A_CPU0_SB_DQS_DP<0>")
	)
	(segment
		(start 324.743826 -275.68652)
		(end 324.424548 -275.367242)
		(width 0.0762)
		(layer "F.Cu")
		(net "M_A_CPU0_SB_DQS_DP<0>")
	)
	(segment
		(start 315.703204 -277.794974)
		(end 315.520832 -277.794974)
		(width 0.12954)
		(layer "F.Cu")
		(net "M_A_CPU0_SB_DQS_DP<0>")
	)
	(segment
		(start 324.114668 -275.367242)
		(end 324.048628 -275.301202)
		(width 0.0762)
		(layer "F.Cu")
		(net "M_A_CPU0_SB_DQS_DP<0>")
	)
	(segment
		(start 315.520832 -277.794974)
		(end 315.420756 -277.694898)
		(width 0.12954)
		(layer "F.Cu")
		(net "M_A_CPU0_SB_DQS_DP<0>")
	)
	(segment
		(start 308.756304 -283.908246)
		(end 308.756304 -284.8229)
		(width 0.12954)
		(layer "F.Cu")
		(net "M_A_CPU0_SB_DQS_DP<0>")
	)
	(segment
		(start 313.587892 -279.910286)
		(end 313.429904 -280.068274)
		(width 0.12954)
		(layer "F.Cu")
		(net "M_A_CPU0_SB_DQS_DP<0>")
	)
	(segment
		(start 319.500504 -275.301202)
		(end 318.882014 -275.301202)
		(width 0.12954)
		(layer "F.Cu")
		(net "M_A_CPU0_SB_DQS_DP<0>")
	)
	(segment
		(start 313.587892 -279.727914)
		(end 313.587892 -279.910286)
		(width 0.12954)
		(layer "F.Cu")
		(net "M_A_CPU0_SB_DQS_DP<0>")
	)
	(segment
		(start 323.431408 -275.569172)
		(end 322.98005 -275.569172)
		(width 0.12954)
		(layer "F.Cu")
		(net "M_A_CPU0_SB_DQS_DP<0>")
	)
	(segment
		(start 314.384182 -278.931624)
		(end 314.284106 -278.831548)
		(width 0.12954)
		(layer "F.Cu")
		(net "M_A_CPU0_SB_DQS_DP<0>")
	)
	(segment
		(start 317.894716 -275.301202)
		(end 317.363348 -275.301202)
		(width 0.12954)
		(layer "F.Cu")
		(net "M_A_CPU0_SB_DQS_DP<0>")
	)
	(segment
		(start 318.614044 -275.569172)
		(end 318.162686 -275.569172)
		(width 0.12954)
		(layer "F.Cu")
		(net "M_A_CPU0_SB_DQS_DP<0>")
	)
	(segment
		(start 316.557406 -276.558248)
		(end 316.106302 -276.558248)
		(width 0.12954)
		(layer "F.Cu")
		(net "M_A_CPU0_SB_DQS_DP<0>")
	)
	(segment
		(start 322.09359 -275.301202)
		(end 321.82562 -275.569172)
		(width 0.12954)
		(layer "F.Cu")
		(net "M_A_CPU0_SB_DQS_DP<0>")
	)
	(segment
		(start 311.314592 -282.183586)
		(end 311.156604 -282.341574)
		(width 0.12954)
		(layer "F.Cu")
		(net "M_A_CPU0_SB_DQS_DP<0>")
	)
	(segment
		(start 310.019954 -283.478224)
		(end 309.837582 -283.478224)
		(width 0.12954)
		(layer "F.Cu")
		(net "M_A_CPU0_SB_DQS_DP<0>")
	)
	(segment
		(start 313.247532 -280.068274)
		(end 313.147456 -279.968198)
		(width 0.12954)
		(layer "F.Cu")
		(net "M_A_CPU0_SB_DQS_DP<0>")
	)
	(segment
		(start 308.166516 -285.148782)
		(end 307.902864 -284.88513)
		(width 0.12954)
		(layer "F.Cu")
		(net "M_A_CPU0_SB_DQS_DP<0>")
	)
	(segment
		(start 312.351166 -280.764488)
		(end 312.451242 -280.864564)
		(width 0.12954)
		(layer "F.Cu")
		(net "M_A_CPU0_SB_DQS_DP<0>")
	)
	(segment
		(start 312.110882 -281.204924)
		(end 312.010806 -281.104848)
		(width 0.12954)
		(layer "F.Cu")
		(net "M_A_CPU0_SB_DQS_DP<0>")
	)
	(segment
		(start 321.374262 -275.569172)
		(end 321.106292 -275.301202)
		(width 0.12954)
		(layer "F.Cu")
		(net "M_A_CPU0_SB_DQS_DP<0>")
	)
	(segment
		(start 315.861192 -277.454614)
		(end 315.861192 -277.636986)
		(width 0.12954)
		(layer "F.Cu")
		(net "M_A_CPU0_SB_DQS_DP<0>")
	)
	(segment
		(start 311.559702 -281.104848)
		(end 311.214516 -281.450034)
		(width 0.12954)
		(layer "F.Cu")
		(net "M_A_CPU0_SB_DQS_DP<0>")
	)
	(segment
		(start 314.724542 -278.773636)
		(end 314.566554 -278.931624)
		(width 0.12954)
		(layer "F.Cu")
		(net "M_A_CPU0_SB_DQS_DP<0>")
	)
	(segment
		(start 317.363348 -275.301202)
		(end 316.897766 -275.766784)
		(width 0.12954)
		(layer "F.Cu")
		(net "M_A_CPU0_SB_DQS_DP<0>")
	)
	(segment
		(start 311.156604 -282.341574)
		(end 310.974232 -282.341574)
		(width 0.12954)
		(layer "F.Cu")
		(net "M_A_CPU0_SB_DQS_DP<0>")
	)
	(segment
		(start 320.487802 -275.301202)
		(end 320.219832 -275.569172)
		(width 0.12954)
		(layer "F.Cu")
		(net "M_A_CPU0_SB_DQS_DP<0>")
	)
	(segment
		(start 310.077866 -283.037788)
		(end 310.177942 -283.137864)
		(width 0.12954)
		(layer "F.Cu")
		(net "M_A_CPU0_SB_DQS_DP<0>")
	)
	(segment
		(start 314.724542 -278.591264)
		(end 314.724542 -278.773636)
		(width 0.12954)
		(layer "F.Cu")
		(net "M_A_CPU0_SB_DQS_DP<0>")
	)
	(segment
		(start 307.902864 -284.88513)
		(end 307.368194 -284.88513)
		(width 0.12954)
		(layer "F.Cu")
		(net "M_A_CPU0_SB_DQS_DP<0>")
	)
	(segment
		(start 314.969652 -277.694898)
		(end 314.624466 -278.040084)
		(width 0.12954)
		(layer "F.Cu")
		(net "M_A_CPU0_SB_DQS_DP<0>")
	)
	(segment
		(start 313.487816 -279.627838)
		(end 313.587892 -279.727914)
		(width 0.12954)
		(layer "F.Cu")
		(net "M_A_CPU0_SB_DQS_DP<0>")
	)
	(segment
		(start 312.010806 -281.104848)
		(end 311.559702 -281.104848)
		(width 0.12954)
		(layer "F.Cu")
		(net "M_A_CPU0_SB_DQS_DP<0>")
	)
	(segment
		(start 318.882014 -275.301202)
		(end 318.614044 -275.569172)
		(width 0.12954)
		(layer "F.Cu")
		(net "M_A_CPU0_SB_DQS_DP<0>")
	)
	(segment
		(start 310.177942 -283.320236)
		(end 310.019954 -283.478224)
		(width 0.12954)
		(layer "F.Cu")
		(net "M_A_CPU0_SB_DQS_DP<0>")
	)
	(segment
		(start 313.487816 -279.176734)
		(end 313.487816 -279.627838)
		(width 0.12954)
		(layer "F.Cu")
		(net "M_A_CPU0_SB_DQS_DP<0>")
	)
	(segment
		(start 310.177942 -283.137864)
		(end 310.177942 -283.320236)
		(width 0.12954)
		(layer "F.Cu")
		(net "M_A_CPU0_SB_DQS_DP<0>")
	)
	(segment
		(start 316.839854 -276.658324)
		(end 316.657482 -276.658324)
		(width 0.12954)
		(layer "F.Cu")
		(net "M_A_CPU0_SB_DQS_DP<0>")
	)
	(segment
		(start 314.284106 -278.831548)
		(end 313.833002 -278.831548)
		(width 0.12954)
		(layer "F.Cu")
		(net "M_A_CPU0_SB_DQS_DP<0>")
	)
	(segment
		(start 312.696352 -279.968198)
		(end 312.351166 -280.313384)
		(width 0.12954)
		(layer "F.Cu")
		(net "M_A_CPU0_SB_DQS_DP<0>")
	)
	(segment
		(start 314.566554 -278.931624)
		(end 314.384182 -278.931624)
		(width 0.12954)
		(layer "F.Cu")
		(net "M_A_CPU0_SB_DQS_DP<0>")
	)
	(segment
		(start 320.219832 -275.569172)
		(end 319.768474 -275.569172)
		(width 0.12954)
		(layer "F.Cu")
		(net "M_A_CPU0_SB_DQS_DP<0>")
	)
	(segment
		(start 315.761116 -276.903434)
		(end 315.761116 -277.354538)
		(width 0.12954)
		(layer "F.Cu")
		(net "M_A_CPU0_SB_DQS_DP<0>")
	)
	(segment
		(start 314.624466 -278.491188)
		(end 314.724542 -278.591264)
		(width 0.12954)
		(layer "F.Cu")
		(net "M_A_CPU0_SB_DQS_DP<0>")
	)
	(arc
		(start 326.13854 -275.81098)
		(mid 326.066802 -275.796128)
		(end 325.999348 -275.767546)
		(width 0.0762)
		(layer "F.Cu")
		(net "M_A_CPU0_SB_DQS_DP<0>")
	)
	(arc
		(start 325.990966 -275.76272)
		(mid 325.85453 -275.705895)
		(end 325.70801 -275.68652)
		(width 0.0762)
		(layer "F.Cu")
		(net "M_A_CPU0_SB_DQS_DP<0>")
	)
	(arc
		(start 326.276208 -275.609304)
		(mid 326.267615 -275.751183)
		(end 326.13854 -275.81098)
		(width 0.0762)
		(layer "F.Cu")
		(net "M_A_CPU0_SB_DQS_DP<0>")
	)
	(segment
		(start 312.886598 -272.274792)
		(end 312.348118 -272.274792)
		(width 0.12954)
		(layer "F.Cu")
		(net "M_A_CPU0_SB_DQS_DN<9>")
	)
	(segment
		(start 309.870856 -275.290534)
		(end 309.476648 -275.684742)
		(width 0.12954)
		(layer "F.Cu")
		(net "M_A_CPU0_SB_DQS_DN<9>")
	)
	(segment
		(start 313.484768 -271.138142)
		(end 313.280806 -271.342104)
		(width 0.12954)
		(layer "F.Cu")
		(net "M_A_CPU0_SB_DQS_DN<9>")
	)
	(segment
		(start 320.84772 -270.440912)
		(end 320.35877 -270.440912)
		(width 0.12954)
		(layer "F.Cu")
		(net "M_A_CPU0_SB_DQS_DN<9>")
	)
	(segment
		(start 321.295522 -269.758922)
		(end 321.165982 -269.888462)
		(width 0.12954)
		(layer "F.Cu")
		(net "M_A_CPU0_SB_DQS_DN<9>")
	)
	(segment
		(start 311.007506 -274.153884)
		(end 310.613298 -274.548092)
		(width 0.12954)
		(layer "F.Cu")
		(net "M_A_CPU0_SB_DQS_DN<9>")
	)
	(segment
		(start 311.211468 -273.411442)
		(end 311.007506 -273.615404)
		(width 0.12954)
		(layer "F.Cu")
		(net "M_A_CPU0_SB_DQS_DN<9>")
	)
	(segment
		(start 317.954406 -269.888462)
		(end 317.954406 -270.12265)
		(width 0.12954)
		(layer "F.Cu")
		(net "M_A_CPU0_SB_DQS_DN<9>")
	)
	(segment
		(start 307.902864 -276.38502)
		(end 307.368194 -276.38502)
		(width 0.12954)
		(layer "F.Cu")
		(net "M_A_CPU0_SB_DQS_DN<9>")
	)
	(segment
		(start 321.165982 -269.888462)
		(end 321.165982 -270.12265)
		(width 0.12954)
		(layer "F.Cu")
		(net "M_A_CPU0_SB_DQS_DN<9>")
	)
	(segment
		(start 316.478158 -269.758922)
		(end 316.348618 -269.888462)
		(width 0.12954)
		(layer "F.Cu")
		(net "M_A_CPU0_SB_DQS_DN<9>")
	)
	(segment
		(start 320.040508 -269.888462)
		(end 319.910968 -269.758922)
		(width 0.12954)
		(layer "F.Cu")
		(net "M_A_CPU0_SB_DQS_DN<9>")
	)
	(segment
		(start 314.417456 -270.205454)
		(end 314.417456 -270.743934)
		(width 0.12954)
		(layer "F.Cu")
		(net "M_A_CPU0_SB_DQS_DN<9>")
	)
	(segment
		(start 314.863988 -269.758922)
		(end 314.417456 -270.205454)
		(width 0.12954)
		(layer "F.Cu")
		(net "M_A_CPU0_SB_DQS_DN<9>")
	)
	(segment
		(start 324.319646 -271.083024)
		(end 322.874894 -271.083024)
		(width 0.12954)
		(layer "F.Cu")
		(net "M_A_CPU0_SB_DQS_DN<9>")
	)
	(segment
		(start 315.093604 -269.758922)
		(end 314.863988 -269.758922)
		(width 0.12954)
		(layer "F.Cu")
		(net "M_A_CPU0_SB_DQS_DN<9>")
	)
	(segment
		(start 318.30518 -269.758922)
		(end 318.083946 -269.758922)
		(width 0.12954)
		(layer "F.Cu")
		(net "M_A_CPU0_SB_DQS_DN<9>")
	)
	(segment
		(start 318.083946 -269.758922)
		(end 317.954406 -269.888462)
		(width 0.12954)
		(layer "F.Cu")
		(net "M_A_CPU0_SB_DQS_DN<9>")
	)
	(segment
		(start 312.144156 -273.017234)
		(end 311.749948 -273.411442)
		(width 0.12954)
		(layer "F.Cu")
		(net "M_A_CPU0_SB_DQS_DN<9>")
	)
	(segment
		(start 317.636144 -270.440912)
		(end 317.147194 -270.440912)
		(width 0.12954)
		(layer "F.Cu")
		(net "M_A_CPU0_SB_DQS_DN<9>")
	)
	(segment
		(start 319.241932 -270.440912)
		(end 318.752982 -270.440912)
		(width 0.12954)
		(layer "F.Cu")
		(net "M_A_CPU0_SB_DQS_DN<9>")
	)
	(segment
		(start 316.699392 -269.758922)
		(end 316.478158 -269.758922)
		(width 0.12954)
		(layer "F.Cu")
		(net "M_A_CPU0_SB_DQS_DN<9>")
	)
	(segment
		(start 319.560194 -269.888462)
		(end 319.560194 -270.12265)
		(width 0.12954)
		(layer "F.Cu")
		(net "M_A_CPU0_SB_DQS_DN<9>")
	)
	(segment
		(start 325.70801 -271.016984)
		(end 324.404736 -271.016984)
		(width 0.0762)
		(layer "F.Cu")
		(net "M_A_CPU0_SB_DQS_DN<9>")
	)
	(segment
		(start 310.074818 -274.548092)
		(end 309.870856 -274.752054)
		(width 0.12954)
		(layer "F.Cu")
		(net "M_A_CPU0_SB_DQS_DN<9>")
	)
	(segment
		(start 310.613298 -274.548092)
		(end 310.074818 -274.548092)
		(width 0.12954)
		(layer "F.Cu")
		(net "M_A_CPU0_SB_DQS_DN<9>")
	)
	(segment
		(start 318.43472 -269.888462)
		(end 318.30518 -269.758922)
		(width 0.12954)
		(layer "F.Cu")
		(net "M_A_CPU0_SB_DQS_DN<9>")
	)
	(segment
		(start 319.910968 -269.758922)
		(end 319.689734 -269.758922)
		(width 0.12954)
		(layer "F.Cu")
		(net "M_A_CPU0_SB_DQS_DN<9>")
	)
	(segment
		(start 316.348618 -269.888462)
		(end 316.348618 -270.12265)
		(width 0.12954)
		(layer "F.Cu")
		(net "M_A_CPU0_SB_DQS_DN<9>")
	)
	(segment
		(start 315.541406 -270.440912)
		(end 315.223144 -270.12265)
		(width 0.12954)
		(layer "F.Cu")
		(net "M_A_CPU0_SB_DQS_DN<9>")
	)
	(segment
		(start 316.030356 -270.440912)
		(end 315.541406 -270.440912)
		(width 0.12954)
		(layer "F.Cu")
		(net "M_A_CPU0_SB_DQS_DN<9>")
	)
	(segment
		(start 314.417456 -270.743934)
		(end 314.023248 -271.138142)
		(width 0.12954)
		(layer "F.Cu")
		(net "M_A_CPU0_SB_DQS_DN<9>")
	)
	(segment
		(start 316.828932 -269.888462)
		(end 316.699392 -269.758922)
		(width 0.12954)
		(layer "F.Cu")
		(net "M_A_CPU0_SB_DQS_DN<9>")
	)
	(segment
		(start 321.165982 -270.12265)
		(end 320.84772 -270.440912)
		(width 0.12954)
		(layer "F.Cu")
		(net "M_A_CPU0_SB_DQS_DN<9>")
	)
	(segment
		(start 324.338696 -271.083024)
		(end 324.319646 -271.083024)
		(width 0.0762)
		(layer "F.Cu")
		(net "M_A_CPU0_SB_DQS_DN<9>")
	)
	(segment
		(start 317.147194 -270.440912)
		(end 316.828932 -270.12265)
		(width 0.12954)
		(layer "F.Cu")
		(net "M_A_CPU0_SB_DQS_DN<9>")
	)
	(segment
		(start 316.828932 -270.12265)
		(end 316.828932 -269.888462)
		(width 0.12954)
		(layer "F.Cu")
		(net "M_A_CPU0_SB_DQS_DN<9>")
	)
	(segment
		(start 316.348618 -270.12265)
		(end 316.030356 -270.440912)
		(width 0.12954)
		(layer "F.Cu")
		(net "M_A_CPU0_SB_DQS_DN<9>")
	)
	(segment
		(start 313.280806 -271.880584)
		(end 312.886598 -272.274792)
		(width 0.12954)
		(layer "F.Cu")
		(net "M_A_CPU0_SB_DQS_DN<9>")
	)
	(segment
		(start 317.954406 -270.12265)
		(end 317.636144 -270.440912)
		(width 0.12954)
		(layer "F.Cu")
		(net "M_A_CPU0_SB_DQS_DN<9>")
	)
	(segment
		(start 308.501542 -276.121368)
		(end 308.166516 -276.121368)
		(width 0.12954)
		(layer "F.Cu")
		(net "M_A_CPU0_SB_DQS_DN<9>")
	)
	(segment
		(start 315.223144 -269.888462)
		(end 315.093604 -269.758922)
		(width 0.12954)
		(layer "F.Cu")
		(net "M_A_CPU0_SB_DQS_DN<9>")
	)
	(segment
		(start 313.280806 -271.342104)
		(end 313.280806 -271.880584)
		(width 0.12954)
		(layer "F.Cu")
		(net "M_A_CPU0_SB_DQS_DN<9>")
	)
	(segment
		(start 308.938168 -275.684742)
		(end 308.501542 -276.121368)
		(width 0.12954)
		(layer "F.Cu")
		(net "M_A_CPU0_SB_DQS_DN<9>")
	)
	(segment
		(start 308.166516 -276.121368)
		(end 307.902864 -276.38502)
		(width 0.12954)
		(layer "F.Cu")
		(net "M_A_CPU0_SB_DQS_DN<9>")
	)
	(segment
		(start 315.223144 -270.12265)
		(end 315.223144 -269.888462)
		(width 0.12954)
		(layer "F.Cu")
		(net "M_A_CPU0_SB_DQS_DN<9>")
	)
	(segment
		(start 314.023248 -271.138142)
		(end 313.484768 -271.138142)
		(width 0.12954)
		(layer "F.Cu")
		(net "M_A_CPU0_SB_DQS_DN<9>")
	)
	(segment
		(start 309.870856 -274.752054)
		(end 309.870856 -275.290534)
		(width 0.12954)
		(layer "F.Cu")
		(net "M_A_CPU0_SB_DQS_DN<9>")
	)
	(segment
		(start 312.144156 -272.478754)
		(end 312.144156 -273.017234)
		(width 0.12954)
		(layer "F.Cu")
		(net "M_A_CPU0_SB_DQS_DN<9>")
	)
	(segment
		(start 320.040508 -270.12265)
		(end 320.040508 -269.888462)
		(width 0.12954)
		(layer "F.Cu")
		(net "M_A_CPU0_SB_DQS_DN<9>")
	)
	(segment
		(start 319.560194 -270.12265)
		(end 319.241932 -270.440912)
		(width 0.12954)
		(layer "F.Cu")
		(net "M_A_CPU0_SB_DQS_DN<9>")
	)
	(segment
		(start 312.348118 -272.274792)
		(end 312.144156 -272.478754)
		(width 0.12954)
		(layer "F.Cu")
		(net "M_A_CPU0_SB_DQS_DN<9>")
	)
	(segment
		(start 324.404736 -271.016984)
		(end 324.338696 -271.083024)
		(width 0.0762)
		(layer "F.Cu")
		(net "M_A_CPU0_SB_DQS_DN<9>")
	)
	(segment
		(start 322.874894 -271.083024)
		(end 321.550792 -269.758922)
		(width 0.12954)
		(layer "F.Cu")
		(net "M_A_CPU0_SB_DQS_DN<9>")
	)
	(segment
		(start 311.749948 -273.411442)
		(end 311.211468 -273.411442)
		(width 0.12954)
		(layer "F.Cu")
		(net "M_A_CPU0_SB_DQS_DN<9>")
	)
	(segment
		(start 320.35877 -270.440912)
		(end 320.040508 -270.12265)
		(width 0.12954)
		(layer "F.Cu")
		(net "M_A_CPU0_SB_DQS_DN<9>")
	)
	(segment
		(start 311.007506 -273.615404)
		(end 311.007506 -274.153884)
		(width 0.12954)
		(layer "F.Cu")
		(net "M_A_CPU0_SB_DQS_DN<9>")
	)
	(segment
		(start 319.689734 -269.758922)
		(end 319.560194 -269.888462)
		(width 0.12954)
		(layer "F.Cu")
		(net "M_A_CPU0_SB_DQS_DN<9>")
	)
	(segment
		(start 309.476648 -275.684742)
		(end 308.938168 -275.684742)
		(width 0.12954)
		(layer "F.Cu")
		(net "M_A_CPU0_SB_DQS_DN<9>")
	)
	(segment
		(start 318.752982 -270.440912)
		(end 318.43472 -270.12265)
		(width 0.12954)
		(layer "F.Cu")
		(net "M_A_CPU0_SB_DQS_DN<9>")
	)
	(segment
		(start 321.550792 -269.758922)
		(end 321.295522 -269.758922)
		(width 0.12954)
		(layer "F.Cu")
		(net "M_A_CPU0_SB_DQS_DN<9>")
	)
	(segment
		(start 318.43472 -270.12265)
		(end 318.43472 -269.888462)
		(width 0.12954)
		(layer "F.Cu")
		(net "M_A_CPU0_SB_DQS_DN<9>")
	)
	(arc
		(start 326.648064 -271.39011)
		(mid 326.405747 -271.22039)
		(end 326.12076 -271.140936)
		(width 0.0762)
		(layer "F.Cu")
		(net "M_A_CPU0_SB_DQS_DN<9>")
	)
	(arc
		(start 326.12076 -271.140936)
		(mid 326.003947 -271.11626)
		(end 325.894954 -271.06753)
		(width 0.0762)
		(layer "F.Cu")
		(net "M_A_CPU0_SB_DQS_DN<9>")
	)
	(arc
		(start 325.894954 -271.06753)
		(mid 325.804821 -271.02991)
		(end 325.70801 -271.016984)
		(width 0.0762)
		(layer "F.Cu")
		(net "M_A_CPU0_SB_DQS_DN<9>")
	)
	(segment
		(start 322.502784 -300.036484)
		(end 322.502784 -300.425104)
		(width 0.12954)
		(layer "F.Cu")
		(net "M_A_CPU0_SB_DQS_DN<8>")
	)
	(segment
		(start 327.587864 -290.83)
		(end 327.688702 -291.003482)
		(width 0.0762)
		(layer "F.Cu")
		(net "M_A_CPU0_SB_DQS_DN<8>")
	)
	(segment
		(start 308.214014 -314.210192)
		(end 305.808888 -314.210192)
		(width 0.101346)
		(layer "F.Cu")
		(net "M_A_CPU0_SB_DQS_DN<8>")
	)
	(segment
		(start 323.967348 -291.32022)
		(end 323.873876 -291.32022)
		(width 0.0762)
		(layer "F.Cu")
		(net "M_A_CPU0_SB_DQS_DN<8>")
	)
	(segment
		(start 323.860414 -291.333682)
		(end 322.502784 -292.691312)
		(width 0.12954)
		(layer "F.Cu")
		(net "M_A_CPU0_SB_DQS_DN<8>")
	)
	(segment
		(start 308.783736 -314.48375)
		(end 308.487572 -314.48375)
		(width 0.12954)
		(layer "F.Cu")
		(net "M_A_CPU0_SB_DQS_DN<8>")
	)
	(segment
		(start 308.487572 -314.48375)
		(end 308.214014 -314.210192)
		(width 0.12954)
		(layer "F.Cu")
		(net "M_A_CPU0_SB_DQS_DN<8>")
	)
	(segment
		(start 305.49088 -314.5282)
		(end 305.213258 -314.5282)
		(width 0.101346)
		(layer "F.Cu")
		(net "M_A_CPU0_SB_DQS_DN<8>")
	)
	(segment
		(start 327.409302 -291.157406)
		(end 327.40092 -291.15258)
		(width 0.0762)
		(layer "F.Cu")
		(net "M_A_CPU0_SB_DQS_DN<8>")
	)
	(segment
		(start 309.241444 -313.686444)
		(end 309.241444 -314.026042)
		(width 0.12954)
		(layer "F.Cu")
		(net "M_A_CPU0_SB_DQS_DN<8>")
	)
	(segment
		(start 325.70801 -291.203126)
		(end 324.084442 -291.203126)
		(width 0.0762)
		(layer "F.Cu")
		(net "M_A_CPU0_SB_DQS_DN<8>")
	)
	(segment
		(start 326.835008 -291.15258)
		(end 326.826626 -291.157406)
		(width 0.0762)
		(layer "F.Cu")
		(net "M_A_CPU0_SB_DQS_DN<8>")
	)
	(segment
		(start 322.502784 -300.425104)
		(end 309.241444 -313.686444)
		(width 0.12954)
		(layer "F.Cu")
		(net "M_A_CPU0_SB_DQS_DN<8>")
	)
	(segment
		(start 304.117502 -314.101988)
		(end 303.80051 -313.784996)
		(width 0.101346)
		(layer "F.Cu")
		(net "M_A_CPU0_SB_DQS_DN<8>")
	)
	(segment
		(start 322.335144 -299.868844)
		(end 322.502784 -300.036484)
		(width 0.12954)
		(layer "F.Cu")
		(net "M_A_CPU0_SB_DQS_DN<8>")
	)
	(segment
		(start 322.502784 -292.691312)
		(end 322.502784 -299.312584)
		(width 0.12954)
		(layer "F.Cu")
		(net "M_A_CPU0_SB_DQS_DN<8>")
	)
	(segment
		(start 303.80051 -313.784996)
		(end 303.268126 -313.784996)
		(width 0.101346)
		(layer "F.Cu")
		(net "M_A_CPU0_SB_DQS_DN<8>")
	)
	(segment
		(start 309.241444 -314.026042)
		(end 308.783736 -314.48375)
		(width 0.12954)
		(layer "F.Cu")
		(net "M_A_CPU0_SB_DQS_DN<8>")
	)
	(segment
		(start 304.787046 -314.101988)
		(end 304.117502 -314.101988)
		(width 0.101346)
		(layer "F.Cu")
		(net "M_A_CPU0_SB_DQS_DN<8>")
	)
	(segment
		(start 305.808888 -314.210192)
		(end 305.49088 -314.5282)
		(width 0.101346)
		(layer "F.Cu")
		(net "M_A_CPU0_SB_DQS_DN<8>")
	)
	(segment
		(start 322.502784 -299.312584)
		(end 322.335144 -299.480224)
		(width 0.12954)
		(layer "F.Cu")
		(net "M_A_CPU0_SB_DQS_DN<8>")
	)
	(segment
		(start 324.084442 -291.203126)
		(end 323.967348 -291.32022)
		(width 0.0762)
		(layer "F.Cu")
		(net "M_A_CPU0_SB_DQS_DN<8>")
	)
	(segment
		(start 305.213258 -314.5282)
		(end 304.787046 -314.101988)
		(width 0.101346)
		(layer "F.Cu")
		(net "M_A_CPU0_SB_DQS_DN<8>")
	)
	(segment
		(start 323.873876 -291.32022)
		(end 323.860414 -291.333682)
		(width 0.0762)
		(layer "F.Cu")
		(net "M_A_CPU0_SB_DQS_DN<8>")
	)
	(segment
		(start 322.335144 -299.480224)
		(end 322.335144 -299.868844)
		(width 0.12954)
		(layer "F.Cu")
		(net "M_A_CPU0_SB_DQS_DN<8>")
	)
	(arc
		(start 327.542652 -291.200078)
		(mid 327.473954 -291.185062)
		(end 327.409302 -291.157406)
		(width 0.0762)
		(layer "F.Cu")
		(net "M_A_CPU0_SB_DQS_DN<8>")
	)
	(arc
		(start 325.738998 -291.201856)
		(mid 325.723517 -291.202812)
		(end 325.70801 -291.203126)
		(width 0.0762)
		(layer "F.Cu")
		(net "M_A_CPU0_SB_DQS_DN<8>")
	)
	(arc
		(start 327.40092 -291.15258)
		(mid 327.117964 -291.076403)
		(end 326.835008 -291.15258)
		(width 0.0762)
		(layer "F.Cu")
		(net "M_A_CPU0_SB_DQS_DN<8>")
	)
	(arc
		(start 326.460866 -291.15258)
		(mid 326.17791 -291.076403)
		(end 325.894954 -291.15258)
		(width 0.0762)
		(layer "F.Cu")
		(net "M_A_CPU0_SB_DQS_DN<8>")
	)
	(arc
		(start 325.894954 -291.15258)
		(mid 325.819714 -291.185893)
		(end 325.738998 -291.201856)
		(width 0.0762)
		(layer "F.Cu")
		(net "M_A_CPU0_SB_DQS_DN<8>")
	)
	(arc
		(start 326.826626 -291.157406)
		(mid 326.643118 -291.2029)
		(end 326.460866 -291.15258)
		(width 0.0762)
		(layer "F.Cu")
		(net "M_A_CPU0_SB_DQS_DN<8>")
	)
	(arc
		(start 327.688702 -291.003482)
		(mid 327.672777 -291.144174)
		(end 327.542652 -291.200078)
		(width 0.0762)
		(layer "F.Cu")
		(net "M_A_CPU0_SB_DQS_DN<8>")
	)
	(segment
		(start 324.46976 -286.055816)
		(end 323.981064 -286.055816)
		(width 0.0762)
		(layer "F.Cu")
		(net "M_A_CPU0_SB_DQS_DN<7>")
	)
	(segment
		(start 327.587864 -285.970218)
		(end 327.688702 -286.1437)
		(width 0.0762)
		(layer "F.Cu")
		(net "M_A_CPU0_SB_DQS_DN<7>")
	)
	(segment
		(start 309.099712 -305.134518)
		(end 308.488334 -305.134518)
		(width 0.12954)
		(layer "F.Cu")
		(net "M_A_CPU0_SB_DQS_DN<7>")
	)
	(segment
		(start 305.49088 -305.178206)
		(end 305.18227 -305.178206)
		(width 0.101346)
		(layer "F.Cu")
		(net "M_A_CPU0_SB_DQS_DN<7>")
	)
	(segment
		(start 305.808888 -304.860198)
		(end 305.49088 -305.178206)
		(width 0.101346)
		(layer "F.Cu")
		(net "M_A_CPU0_SB_DQS_DN<7>")
	)
	(segment
		(start 318.081152 -290.419282)
		(end 318.081152 -296.153078)
		(width 0.12954)
		(layer "F.Cu")
		(net "M_A_CPU0_SB_DQS_DN<7>")
	)
	(segment
		(start 308.488334 -305.134518)
		(end 308.214014 -304.860198)
		(width 0.12954)
		(layer "F.Cu")
		(net "M_A_CPU0_SB_DQS_DN<7>")
	)
	(segment
		(start 324.757288 -286.343344)
		(end 324.46976 -286.055816)
		(width 0.0762)
		(layer "F.Cu")
		(net "M_A_CPU0_SB_DQS_DN<7>")
	)
	(segment
		(start 326.835008 -286.292798)
		(end 326.826626 -286.297624)
		(width 0.0762)
		(layer "F.Cu")
		(net "M_A_CPU0_SB_DQS_DN<7>")
	)
	(segment
		(start 318.081152 -296.153078)
		(end 309.099712 -305.134518)
		(width 0.12954)
		(layer "F.Cu")
		(net "M_A_CPU0_SB_DQS_DN<7>")
	)
	(segment
		(start 327.409302 -286.297624)
		(end 327.40092 -286.292798)
		(width 0.0762)
		(layer "F.Cu")
		(net "M_A_CPU0_SB_DQS_DN<7>")
	)
	(segment
		(start 322.510658 -285.989776)
		(end 318.081152 -290.419282)
		(width 0.12954)
		(layer "F.Cu")
		(net "M_A_CPU0_SB_DQS_DN<7>")
	)
	(segment
		(start 323.895974 -285.989776)
		(end 322.510658 -285.989776)
		(width 0.12954)
		(layer "F.Cu")
		(net "M_A_CPU0_SB_DQS_DN<7>")
	)
	(segment
		(start 305.18227 -305.178206)
		(end 304.756058 -304.751994)
		(width 0.101346)
		(layer "F.Cu")
		(net "M_A_CPU0_SB_DQS_DN<7>")
	)
	(segment
		(start 304.756058 -304.751994)
		(end 304.117502 -304.751994)
		(width 0.101346)
		(layer "F.Cu")
		(net "M_A_CPU0_SB_DQS_DN<7>")
	)
	(segment
		(start 303.80051 -304.435002)
		(end 303.268126 -304.435002)
		(width 0.101346)
		(layer "F.Cu")
		(net "M_A_CPU0_SB_DQS_DN<7>")
	)
	(segment
		(start 323.981064 -286.055816)
		(end 323.915024 -285.989776)
		(width 0.0762)
		(layer "F.Cu")
		(net "M_A_CPU0_SB_DQS_DN<7>")
	)
	(segment
		(start 304.117502 -304.751994)
		(end 303.80051 -304.435002)
		(width 0.101346)
		(layer "F.Cu")
		(net "M_A_CPU0_SB_DQS_DN<7>")
	)
	(segment
		(start 308.214014 -304.860198)
		(end 305.808888 -304.860198)
		(width 0.101346)
		(layer "F.Cu")
		(net "M_A_CPU0_SB_DQS_DN<7>")
	)
	(segment
		(start 325.70801 -286.343344)
		(end 324.757288 -286.343344)
		(width 0.0762)
		(layer "F.Cu")
		(net "M_A_CPU0_SB_DQS_DN<7>")
	)
	(segment
		(start 323.915024 -285.989776)
		(end 323.895974 -285.989776)
		(width 0.0762)
		(layer "F.Cu")
		(net "M_A_CPU0_SB_DQS_DN<7>")
	)
	(arc
		(start 327.40092 -286.292798)
		(mid 327.117964 -286.216621)
		(end 326.835008 -286.292798)
		(width 0.0762)
		(layer "F.Cu")
		(net "M_A_CPU0_SB_DQS_DN<7>")
	)
	(arc
		(start 326.826626 -286.297624)
		(mid 326.643118 -286.343118)
		(end 326.460866 -286.292798)
		(width 0.0762)
		(layer "F.Cu")
		(net "M_A_CPU0_SB_DQS_DN<7>")
	)
	(arc
		(start 327.688702 -286.1437)
		(mid 327.672777 -286.284392)
		(end 327.542652 -286.340296)
		(width 0.0762)
		(layer "F.Cu")
		(net "M_A_CPU0_SB_DQS_DN<7>")
	)
	(arc
		(start 326.460866 -286.292798)
		(mid 326.17791 -286.216621)
		(end 325.894954 -286.292798)
		(width 0.0762)
		(layer "F.Cu")
		(net "M_A_CPU0_SB_DQS_DN<7>")
	)
	(arc
		(start 325.894954 -286.292798)
		(mid 325.819714 -286.326111)
		(end 325.738998 -286.342074)
		(width 0.0762)
		(layer "F.Cu")
		(net "M_A_CPU0_SB_DQS_DN<7>")
	)
	(arc
		(start 327.542652 -286.340296)
		(mid 327.473954 -286.32528)
		(end 327.409302 -286.297624)
		(width 0.0762)
		(layer "F.Cu")
		(net "M_A_CPU0_SB_DQS_DN<7>")
	)
	(arc
		(start 325.738998 -286.342074)
		(mid 325.723517 -286.34303)
		(end 325.70801 -286.343344)
		(width 0.0762)
		(layer "F.Cu")
		(net "M_A_CPU0_SB_DQS_DN<7>")
	)
	(segment
		(start 325.70801 -281.483308)
		(end 324.824852 -281.483308)
		(width 0.0762)
		(layer "F.Cu")
		(net "M_A_CPU0_SB_DQS_DN<6>")
	)
	(segment
		(start 321.14363 -281.10307)
		(end 313.647582 -288.599118)
		(width 0.12954)
		(layer "F.Cu")
		(net "M_A_CPU0_SB_DQS_DN<6>")
	)
	(segment
		(start 324.824852 -281.483308)
		(end 324.510654 -281.16911)
		(width 0.0762)
		(layer "F.Cu")
		(net "M_A_CPU0_SB_DQS_DN<6>")
	)
	(segment
		(start 313.647582 -291.530024)
		(end 309.39359 -295.784016)
		(width 0.12954)
		(layer "F.Cu")
		(net "M_A_CPU0_SB_DQS_DN<6>")
	)
	(segment
		(start 305.49088 -295.828212)
		(end 305.20513 -295.828212)
		(width 0.101346)
		(layer "F.Cu")
		(net "M_A_CPU0_SB_DQS_DN<6>")
	)
	(segment
		(start 327.409302 -281.437588)
		(end 327.40092 -281.432762)
		(width 0.0762)
		(layer "F.Cu")
		(net "M_A_CPU0_SB_DQS_DN<6>")
	)
	(segment
		(start 305.808888 -295.510204)
		(end 305.49088 -295.828212)
		(width 0.101346)
		(layer "F.Cu")
		(net "M_A_CPU0_SB_DQS_DN<6>")
	)
	(segment
		(start 309.39359 -295.784016)
		(end 308.487826 -295.784016)
		(width 0.12954)
		(layer "F.Cu")
		(net "M_A_CPU0_SB_DQS_DN<6>")
	)
	(segment
		(start 323.895974 -281.10307)
		(end 321.14363 -281.10307)
		(width 0.12954)
		(layer "F.Cu")
		(net "M_A_CPU0_SB_DQS_DN<6>")
	)
	(segment
		(start 326.835008 -281.432762)
		(end 326.826626 -281.437588)
		(width 0.0762)
		(layer "F.Cu")
		(net "M_A_CPU0_SB_DQS_DN<6>")
	)
	(segment
		(start 305.20513 -295.828212)
		(end 304.778918 -295.402)
		(width 0.101346)
		(layer "F.Cu")
		(net "M_A_CPU0_SB_DQS_DN<6>")
	)
	(segment
		(start 323.971666 -281.16911)
		(end 323.905626 -281.10307)
		(width 0.0762)
		(layer "F.Cu")
		(net "M_A_CPU0_SB_DQS_DN<6>")
	)
	(segment
		(start 327.587864 -281.110182)
		(end 327.688702 -281.283664)
		(width 0.0762)
		(layer "F.Cu")
		(net "M_A_CPU0_SB_DQS_DN<6>")
	)
	(segment
		(start 308.487826 -295.784016)
		(end 308.214014 -295.510204)
		(width 0.12954)
		(layer "F.Cu")
		(net "M_A_CPU0_SB_DQS_DN<6>")
	)
	(segment
		(start 324.510654 -281.16911)
		(end 323.971666 -281.16911)
		(width 0.0762)
		(layer "F.Cu")
		(net "M_A_CPU0_SB_DQS_DN<6>")
	)
	(segment
		(start 304.778918 -295.402)
		(end 304.117502 -295.402)
		(width 0.101346)
		(layer "F.Cu")
		(net "M_A_CPU0_SB_DQS_DN<6>")
	)
	(segment
		(start 304.117502 -295.402)
		(end 303.80051 -295.085008)
		(width 0.101346)
		(layer "F.Cu")
		(net "M_A_CPU0_SB_DQS_DN<6>")
	)
	(segment
		(start 303.80051 -295.085008)
		(end 303.268126 -295.085008)
		(width 0.101346)
		(layer "F.Cu")
		(net "M_A_CPU0_SB_DQS_DN<6>")
	)
	(segment
		(start 308.214014 -295.510204)
		(end 305.808888 -295.510204)
		(width 0.101346)
		(layer "F.Cu")
		(net "M_A_CPU0_SB_DQS_DN<6>")
	)
	(segment
		(start 313.647582 -288.599118)
		(end 313.647582 -291.530024)
		(width 0.12954)
		(layer "F.Cu")
		(net "M_A_CPU0_SB_DQS_DN<6>")
	)
	(segment
		(start 323.905626 -281.10307)
		(end 323.895974 -281.10307)
		(width 0.0762)
		(layer "F.Cu")
		(net "M_A_CPU0_SB_DQS_DN<6>")
	)
	(arc
		(start 325.894954 -281.432762)
		(mid 325.819714 -281.466075)
		(end 325.738998 -281.482038)
		(width 0.0762)
		(layer "F.Cu")
		(net "M_A_CPU0_SB_DQS_DN<6>")
	)
	(arc
		(start 325.738998 -281.482038)
		(mid 325.723517 -281.482994)
		(end 325.70801 -281.483308)
		(width 0.0762)
		(layer "F.Cu")
		(net "M_A_CPU0_SB_DQS_DN<6>")
	)
	(arc
		(start 327.542652 -281.48026)
		(mid 327.473954 -281.465244)
		(end 327.409302 -281.437588)
		(width 0.0762)
		(layer "F.Cu")
		(net "M_A_CPU0_SB_DQS_DN<6>")
	)
	(arc
		(start 327.688702 -281.283664)
		(mid 327.672777 -281.424356)
		(end 327.542652 -281.48026)
		(width 0.0762)
		(layer "F.Cu")
		(net "M_A_CPU0_SB_DQS_DN<6>")
	)
	(arc
		(start 327.40092 -281.432762)
		(mid 327.117964 -281.356585)
		(end 326.835008 -281.432762)
		(width 0.0762)
		(layer "F.Cu")
		(net "M_A_CPU0_SB_DQS_DN<6>")
	)
	(arc
		(start 326.826626 -281.437588)
		(mid 326.643118 -281.483082)
		(end 326.460866 -281.432762)
		(width 0.0762)
		(layer "F.Cu")
		(net "M_A_CPU0_SB_DQS_DN<6>")
	)
	(arc
		(start 326.460866 -281.432762)
		(mid 326.17791 -281.356585)
		(end 325.894954 -281.432762)
		(width 0.0762)
		(layer "F.Cu")
		(net "M_A_CPU0_SB_DQS_DN<6>")
	)
	(segment
		(start 327.587864 -276.250146)
		(end 327.688702 -276.423628)
		(width 0.0762)
		(layer "F.Cu")
		(net "M_A_CPU0_SB_DQS_DN<5>")
	)
	(segment
		(start 324.840854 -276.623272)
		(end 324.601586 -276.384004)
		(width 0.0762)
		(layer "F.Cu")
		(net "M_A_CPU0_SB_DQS_DN<5>")
	)
	(segment
		(start 324.601586 -276.384004)
		(end 323.981064 -276.384004)
		(width 0.0762)
		(layer "F.Cu")
		(net "M_A_CPU0_SB_DQS_DN<5>")
	)
	(segment
		(start 304.117502 -286.052006)
		(end 303.80051 -285.735014)
		(width 0.101346)
		(layer "F.Cu")
		(net "M_A_CPU0_SB_DQS_DN<5>")
	)
	(segment
		(start 323.895974 -276.317964)
		(end 318.233298 -276.317964)
		(width 0.12954)
		(layer "F.Cu")
		(net "M_A_CPU0_SB_DQS_DN<5>")
	)
	(segment
		(start 323.915024 -276.317964)
		(end 323.895974 -276.317964)
		(width 0.0762)
		(layer "F.Cu")
		(net "M_A_CPU0_SB_DQS_DN<5>")
	)
	(segment
		(start 305.49088 -286.478218)
		(end 305.227482 -286.478218)
		(width 0.101346)
		(layer "F.Cu")
		(net "M_A_CPU0_SB_DQS_DN<5>")
	)
	(segment
		(start 327.409302 -276.577552)
		(end 327.40092 -276.572726)
		(width 0.0762)
		(layer "F.Cu")
		(net "M_A_CPU0_SB_DQS_DN<5>")
	)
	(segment
		(start 304.80127 -286.052006)
		(end 304.117502 -286.052006)
		(width 0.101346)
		(layer "F.Cu")
		(net "M_A_CPU0_SB_DQS_DN<5>")
	)
	(segment
		(start 308.796944 -286.433768)
		(end 308.487572 -286.433768)
		(width 0.12954)
		(layer "F.Cu")
		(net "M_A_CPU0_SB_DQS_DN<5>")
	)
	(segment
		(start 303.80051 -285.735014)
		(end 303.268126 -285.735014)
		(width 0.101346)
		(layer "F.Cu")
		(net "M_A_CPU0_SB_DQS_DN<5>")
	)
	(segment
		(start 309.506112 -285.7246)
		(end 308.796944 -286.433768)
		(width 0.12954)
		(layer "F.Cu")
		(net "M_A_CPU0_SB_DQS_DN<5>")
	)
	(segment
		(start 305.808888 -286.16021)
		(end 305.49088 -286.478218)
		(width 0.101346)
		(layer "F.Cu")
		(net "M_A_CPU0_SB_DQS_DN<5>")
	)
	(segment
		(start 308.214014 -286.16021)
		(end 305.808888 -286.16021)
		(width 0.101346)
		(layer "F.Cu")
		(net "M_A_CPU0_SB_DQS_DN<5>")
	)
	(segment
		(start 323.981064 -276.384004)
		(end 323.915024 -276.317964)
		(width 0.0762)
		(layer "F.Cu")
		(net "M_A_CPU0_SB_DQS_DN<5>")
	)
	(segment
		(start 318.233298 -276.317964)
		(end 309.506112 -285.04515)
		(width 0.12954)
		(layer "F.Cu")
		(net "M_A_CPU0_SB_DQS_DN<5>")
	)
	(segment
		(start 305.227482 -286.478218)
		(end 304.80127 -286.052006)
		(width 0.101346)
		(layer "F.Cu")
		(net "M_A_CPU0_SB_DQS_DN<5>")
	)
	(segment
		(start 325.70801 -276.623272)
		(end 324.840854 -276.623272)
		(width 0.0762)
		(layer "F.Cu")
		(net "M_A_CPU0_SB_DQS_DN<5>")
	)
	(segment
		(start 326.835008 -276.572726)
		(end 326.826626 -276.577552)
		(width 0.0762)
		(layer "F.Cu")
		(net "M_A_CPU0_SB_DQS_DN<5>")
	)
	(segment
		(start 308.487572 -286.433768)
		(end 308.214014 -286.16021)
		(width 0.12954)
		(layer "F.Cu")
		(net "M_A_CPU0_SB_DQS_DN<5>")
	)
	(segment
		(start 309.506112 -285.04515)
		(end 309.506112 -285.7246)
		(width 0.12954)
		(layer "F.Cu")
		(net "M_A_CPU0_SB_DQS_DN<5>")
	)
	(arc
		(start 327.40092 -276.572726)
		(mid 327.117964 -276.496549)
		(end 326.835008 -276.572726)
		(width 0.0762)
		(layer "F.Cu")
		(net "M_A_CPU0_SB_DQS_DN<5>")
	)
	(arc
		(start 325.738998 -276.622002)
		(mid 325.723517 -276.622958)
		(end 325.70801 -276.623272)
		(width 0.0762)
		(layer "F.Cu")
		(net "M_A_CPU0_SB_DQS_DN<5>")
	)
	(arc
		(start 327.688702 -276.423628)
		(mid 327.672777 -276.56432)
		(end 327.542652 -276.620224)
		(width 0.0762)
		(layer "F.Cu")
		(net "M_A_CPU0_SB_DQS_DN<5>")
	)
	(arc
		(start 325.894954 -276.572726)
		(mid 325.819714 -276.606039)
		(end 325.738998 -276.622002)
		(width 0.0762)
		(layer "F.Cu")
		(net "M_A_CPU0_SB_DQS_DN<5>")
	)
	(arc
		(start 326.460866 -276.572726)
		(mid 326.17791 -276.496549)
		(end 325.894954 -276.572726)
		(width 0.0762)
		(layer "F.Cu")
		(net "M_A_CPU0_SB_DQS_DN<5>")
	)
	(arc
		(start 327.542652 -276.620224)
		(mid 327.473954 -276.605208)
		(end 327.409302 -276.577552)
		(width 0.0762)
		(layer "F.Cu")
		(net "M_A_CPU0_SB_DQS_DN<5>")
	)
	(arc
		(start 326.826626 -276.577552)
		(mid 326.643118 -276.623046)
		(end 326.460866 -276.572726)
		(width 0.0762)
		(layer "F.Cu")
		(net "M_A_CPU0_SB_DQS_DN<5>")
	)
	(segment
		(start 305.808888 -276.810216)
		(end 305.49088 -277.128224)
		(width 0.101346)
		(layer "F.Cu")
		(net "M_A_CPU0_SB_DQS_DN<4>")
	)
	(segment
		(start 305.49088 -277.128224)
		(end 305.209194 -277.128224)
		(width 0.101346)
		(layer "F.Cu")
		(net "M_A_CPU0_SB_DQS_DN<4>")
	)
	(segment
		(start 322.70573 -271.512284)
		(end 322.055998 -270.862552)
		(width 0.12954)
		(layer "F.Cu")
		(net "M_A_CPU0_SB_DQS_DN<4>")
	)
	(segment
		(start 304.782982 -276.702012)
		(end 304.117502 -276.702012)
		(width 0.101346)
		(layer "F.Cu")
		(net "M_A_CPU0_SB_DQS_DN<4>")
	)
	(segment
		(start 308.327298 -276.810216)
		(end 305.808888 -276.810216)
		(width 0.101346)
		(layer "F.Cu")
		(net "M_A_CPU0_SB_DQS_DN<4>")
	)
	(segment
		(start 324.18655 -271.578324)
		(end 324.12051 -271.512284)
		(width 0.0762)
		(layer "F.Cu")
		(net "M_A_CPU0_SB_DQS_DN<4>")
	)
	(segment
		(start 327.587864 -271.39011)
		(end 327.688702 -271.563592)
		(width 0.0762)
		(layer "F.Cu")
		(net "M_A_CPU0_SB_DQS_DN<4>")
	)
	(segment
		(start 324.12051 -271.512284)
		(end 324.10146 -271.512284)
		(width 0.0762)
		(layer "F.Cu")
		(net "M_A_CPU0_SB_DQS_DN<4>")
	)
	(segment
		(start 324.78218 -271.763236)
		(end 324.597268 -271.578324)
		(width 0.0762)
		(layer "F.Cu")
		(net "M_A_CPU0_SB_DQS_DN<4>")
	)
	(segment
		(start 324.10146 -271.512284)
		(end 322.70573 -271.512284)
		(width 0.12954)
		(layer "F.Cu")
		(net "M_A_CPU0_SB_DQS_DN<4>")
	)
	(segment
		(start 327.409302 -271.717516)
		(end 327.40092 -271.71269)
		(width 0.0762)
		(layer "F.Cu")
		(net "M_A_CPU0_SB_DQS_DN<4>")
	)
	(segment
		(start 324.597268 -271.578324)
		(end 324.18655 -271.578324)
		(width 0.0762)
		(layer "F.Cu")
		(net "M_A_CPU0_SB_DQS_DN<4>")
	)
	(segment
		(start 303.80051 -276.38502)
		(end 303.268126 -276.38502)
		(width 0.101346)
		(layer "F.Cu")
		(net "M_A_CPU0_SB_DQS_DN<4>")
	)
	(segment
		(start 305.209194 -277.128224)
		(end 304.782982 -276.702012)
		(width 0.101346)
		(layer "F.Cu")
		(net "M_A_CPU0_SB_DQS_DN<4>")
	)
	(segment
		(start 325.70801 -271.763236)
		(end 324.78218 -271.763236)
		(width 0.0762)
		(layer "F.Cu")
		(net "M_A_CPU0_SB_DQS_DN<4>")
	)
	(segment
		(start 326.835008 -271.71269)
		(end 326.826626 -271.717516)
		(width 0.0762)
		(layer "F.Cu")
		(net "M_A_CPU0_SB_DQS_DN<4>")
	)
	(segment
		(start 308.777386 -277.077932)
		(end 308.595014 -277.077932)
		(width 0.12954)
		(layer "F.Cu")
		(net "M_A_CPU0_SB_DQS_DN<4>")
	)
	(segment
		(start 304.117502 -276.702012)
		(end 303.80051 -276.38502)
		(width 0.101346)
		(layer "F.Cu")
		(net "M_A_CPU0_SB_DQS_DN<4>")
	)
	(segment
		(start 308.595014 -277.077932)
		(end 308.327298 -276.810216)
		(width 0.12954)
		(layer "F.Cu")
		(net "M_A_CPU0_SB_DQS_DN<4>")
	)
	(segment
		(start 314.992766 -270.862552)
		(end 308.777386 -277.077932)
		(width 0.12954)
		(layer "F.Cu")
		(net "M_A_CPU0_SB_DQS_DN<4>")
	)
	(segment
		(start 322.055998 -270.862552)
		(end 314.992766 -270.862552)
		(width 0.12954)
		(layer "F.Cu")
		(net "M_A_CPU0_SB_DQS_DN<4>")
	)
	(arc
		(start 326.460866 -271.71269)
		(mid 326.17791 -271.636513)
		(end 325.894954 -271.71269)
		(width 0.0762)
		(layer "F.Cu")
		(net "M_A_CPU0_SB_DQS_DN<4>")
	)
	(arc
		(start 325.894954 -271.71269)
		(mid 325.819714 -271.746003)
		(end 325.738998 -271.761966)
		(width 0.0762)
		(layer "F.Cu")
		(net "M_A_CPU0_SB_DQS_DN<4>")
	)
	(arc
		(start 327.542652 -271.760188)
		(mid 327.473954 -271.745172)
		(end 327.409302 -271.717516)
		(width 0.0762)
		(layer "F.Cu")
		(net "M_A_CPU0_SB_DQS_DN<4>")
	)
	(arc
		(start 327.40092 -271.71269)
		(mid 327.117964 -271.636513)
		(end 326.835008 -271.71269)
		(width 0.0762)
		(layer "F.Cu")
		(net "M_A_CPU0_SB_DQS_DN<4>")
	)
	(arc
		(start 326.826626 -271.717516)
		(mid 326.643118 -271.76301)
		(end 326.460866 -271.71269)
		(width 0.0762)
		(layer "F.Cu")
		(net "M_A_CPU0_SB_DQS_DN<4>")
	)
	(arc
		(start 327.688702 -271.563592)
		(mid 327.672777 -271.704284)
		(end 327.542652 -271.760188)
		(width 0.0762)
		(layer "F.Cu")
		(net "M_A_CPU0_SB_DQS_DN<4>")
	)
	(arc
		(start 325.738998 -271.761966)
		(mid 325.723517 -271.762922)
		(end 325.70801 -271.763236)
		(width 0.0762)
		(layer "F.Cu")
		(net "M_A_CPU0_SB_DQS_DN<4>")
	)
	(segment
		(start 307.902864 -313.784996)
		(end 307.368194 -313.784996)
		(width 0.12954)
		(layer "F.Cu")
		(net "M_A_CPU0_SB_DQS_DN<3>")
	)
	(segment
		(start 325.18477 -290.418266)
		(end 323.981064 -290.418266)
		(width 0.0762)
		(layer "F.Cu")
		(net "M_A_CPU0_SB_DQS_DN<3>")
	)
	(segment
		(start 319.791588 -302.089566)
		(end 319.401952 -301.69993)
		(width 0.12954)
		(layer "F.Cu")
		(net "M_A_CPU0_SB_DQS_DN<3>")
	)
	(segment
		(start 319.218564 -301.69993)
		(end 319.0621 -301.856394)
		(width 0.12954)
		(layer "F.Cu")
		(net "M_A_CPU0_SB_DQS_DN<3>")
	)
	(segment
		(start 317.518288 -304.362866)
		(end 317.128652 -303.97323)
		(width 0.12954)
		(layer "F.Cu")
		(net "M_A_CPU0_SB_DQS_DN<3>")
	)
	(segment
		(start 320.355214 -300.56328)
		(end 320.19875 -300.719744)
		(width 0.12954)
		(layer "F.Cu")
		(net "M_A_CPU0_SB_DQS_DN<3>")
	)
	(segment
		(start 325.70801 -290.456874)
		(end 325.223378 -290.456874)
		(width 0.0762)
		(layer "F.Cu")
		(net "M_A_CPU0_SB_DQS_DN<3>")
	)
	(segment
		(start 316.633606 -304.284888)
		(end 316.633606 -305.6763)
		(width 0.12954)
		(layer "F.Cu")
		(net "M_A_CPU0_SB_DQS_DN<3>")
	)
	(segment
		(start 319.105026 -303.226216)
		(end 318.654938 -303.226216)
		(width 0.12954)
		(layer "F.Cu")
		(net "M_A_CPU0_SB_DQS_DN<3>")
	)
	(segment
		(start 308.166516 -313.521344)
		(end 307.902864 -313.784996)
		(width 0.12954)
		(layer "F.Cu")
		(net "M_A_CPU0_SB_DQS_DN<3>")
	)
	(segment
		(start 323.915024 -290.484306)
		(end 323.895974 -290.484306)
		(width 0.0762)
		(layer "F.Cu")
		(net "M_A_CPU0_SB_DQS_DN<3>")
	)
	(segment
		(start 318.315086 -303.566068)
		(end 318.315086 -304.016156)
		(width 0.12954)
		(layer "F.Cu")
		(net "M_A_CPU0_SB_DQS_DN<3>")
	)
	(segment
		(start 325.223378 -290.456874)
		(end 325.18477 -290.418266)
		(width 0.0762)
		(layer "F.Cu")
		(net "M_A_CPU0_SB_DQS_DN<3>")
	)
	(segment
		(start 323.895974 -290.484306)
		(end 323.77761 -290.484306)
		(width 0.12954)
		(layer "F.Cu")
		(net "M_A_CPU0_SB_DQS_DN<3>")
	)
	(segment
		(start 322.078604 -292.183312)
		(end 322.078604 -298.83989)
		(width 0.12954)
		(layer "F.Cu")
		(net "M_A_CPU0_SB_DQS_DN<3>")
	)
	(segment
		(start 321.378326 -300.952916)
		(end 320.928238 -300.952916)
		(width 0.12954)
		(layer "F.Cu")
		(net "M_A_CPU0_SB_DQS_DN<3>")
	)
	(segment
		(start 319.451736 -302.879506)
		(end 319.105026 -303.226216)
		(width 0.12954)
		(layer "F.Cu")
		(net "M_A_CPU0_SB_DQS_DN<3>")
	)
	(segment
		(start 320.588386 -301.292768)
		(end 320.588386 -301.742856)
		(width 0.12954)
		(layer "F.Cu")
		(net "M_A_CPU0_SB_DQS_DN<3>")
	)
	(segment
		(start 323.981064 -290.418266)
		(end 323.915024 -290.484306)
		(width 0.0762)
		(layer "F.Cu")
		(net "M_A_CPU0_SB_DQS_DN<3>")
	)
	(segment
		(start 319.0621 -302.039782)
		(end 319.451736 -302.429418)
		(width 0.12954)
		(layer "F.Cu")
		(net "M_A_CPU0_SB_DQS_DN<3>")
	)
	(segment
		(start 318.081914 -302.83658)
		(end 317.92545 -302.993044)
		(width 0.12954)
		(layer "F.Cu")
		(net "M_A_CPU0_SB_DQS_DN<3>")
	)
	(segment
		(start 308.788562 -313.521344)
		(end 308.166516 -313.521344)
		(width 0.12954)
		(layer "F.Cu")
		(net "M_A_CPU0_SB_DQS_DN<3>")
	)
	(segment
		(start 317.92545 -302.993044)
		(end 317.92545 -303.176432)
		(width 0.12954)
		(layer "F.Cu")
		(net "M_A_CPU0_SB_DQS_DN<3>")
	)
	(segment
		(start 317.92545 -303.176432)
		(end 318.315086 -303.566068)
		(width 0.12954)
		(layer "F.Cu")
		(net "M_A_CPU0_SB_DQS_DN<3>")
	)
	(segment
		(start 318.265302 -302.83658)
		(end 318.081914 -302.83658)
		(width 0.12954)
		(layer "F.Cu")
		(net "M_A_CPU0_SB_DQS_DN<3>")
	)
	(segment
		(start 321.3354 -299.766482)
		(end 321.725036 -300.156118)
		(width 0.12954)
		(layer "F.Cu")
		(net "M_A_CPU0_SB_DQS_DN<3>")
	)
	(segment
		(start 317.128652 -303.97323)
		(end 316.945264 -303.97323)
		(width 0.12954)
		(layer "F.Cu")
		(net "M_A_CPU0_SB_DQS_DN<3>")
	)
	(segment
		(start 320.928238 -300.952916)
		(end 320.538602 -300.56328)
		(width 0.12954)
		(layer "F.Cu")
		(net "M_A_CPU0_SB_DQS_DN<3>")
	)
	(segment
		(start 318.654938 -303.226216)
		(end 318.265302 -302.83658)
		(width 0.12954)
		(layer "F.Cu")
		(net "M_A_CPU0_SB_DQS_DN<3>")
	)
	(segment
		(start 320.538602 -300.56328)
		(end 320.355214 -300.56328)
		(width 0.12954)
		(layer "F.Cu")
		(net "M_A_CPU0_SB_DQS_DN<3>")
	)
	(segment
		(start 319.451736 -302.429418)
		(end 319.451736 -302.879506)
		(width 0.12954)
		(layer "F.Cu")
		(net "M_A_CPU0_SB_DQS_DN<3>")
	)
	(segment
		(start 321.3354 -299.583094)
		(end 321.3354 -299.766482)
		(width 0.12954)
		(layer "F.Cu")
		(net "M_A_CPU0_SB_DQS_DN<3>")
	)
	(segment
		(start 320.19875 -300.903132)
		(end 320.588386 -301.292768)
		(width 0.12954)
		(layer "F.Cu")
		(net "M_A_CPU0_SB_DQS_DN<3>")
	)
	(segment
		(start 323.77761 -290.484306)
		(end 322.078604 -292.183312)
		(width 0.12954)
		(layer "F.Cu")
		(net "M_A_CPU0_SB_DQS_DN<3>")
	)
	(segment
		(start 320.588386 -301.742856)
		(end 320.241676 -302.089566)
		(width 0.12954)
		(layer "F.Cu")
		(net "M_A_CPU0_SB_DQS_DN<3>")
	)
	(segment
		(start 320.241676 -302.089566)
		(end 319.791588 -302.089566)
		(width 0.12954)
		(layer "F.Cu")
		(net "M_A_CPU0_SB_DQS_DN<3>")
	)
	(segment
		(start 317.968376 -304.362866)
		(end 317.518288 -304.362866)
		(width 0.12954)
		(layer "F.Cu")
		(net "M_A_CPU0_SB_DQS_DN<3>")
	)
	(segment
		(start 321.725036 -300.606206)
		(end 321.378326 -300.952916)
		(width 0.12954)
		(layer "F.Cu")
		(net "M_A_CPU0_SB_DQS_DN<3>")
	)
	(segment
		(start 319.0621 -301.856394)
		(end 319.0621 -302.039782)
		(width 0.12954)
		(layer "F.Cu")
		(net "M_A_CPU0_SB_DQS_DN<3>")
	)
	(segment
		(start 322.078604 -298.83989)
		(end 321.3354 -299.583094)
		(width 0.12954)
		(layer "F.Cu")
		(net "M_A_CPU0_SB_DQS_DN<3>")
	)
	(segment
		(start 320.19875 -300.719744)
		(end 320.19875 -300.903132)
		(width 0.12954)
		(layer "F.Cu")
		(net "M_A_CPU0_SB_DQS_DN<3>")
	)
	(segment
		(start 321.725036 -300.156118)
		(end 321.725036 -300.606206)
		(width 0.12954)
		(layer "F.Cu")
		(net "M_A_CPU0_SB_DQS_DN<3>")
	)
	(segment
		(start 316.633606 -305.6763)
		(end 308.788562 -313.521344)
		(width 0.12954)
		(layer "F.Cu")
		(net "M_A_CPU0_SB_DQS_DN<3>")
	)
	(segment
		(start 316.945264 -303.97323)
		(end 316.633606 -304.284888)
		(width 0.12954)
		(layer "F.Cu")
		(net "M_A_CPU0_SB_DQS_DN<3>")
	)
	(segment
		(start 319.401952 -301.69993)
		(end 319.218564 -301.69993)
		(width 0.12954)
		(layer "F.Cu")
		(net "M_A_CPU0_SB_DQS_DN<3>")
	)
	(segment
		(start 318.315086 -304.016156)
		(end 317.968376 -304.362866)
		(width 0.12954)
		(layer "F.Cu")
		(net "M_A_CPU0_SB_DQS_DN<3>")
	)
	(arc
		(start 326.648064 -290.83)
		(mid 326.405747 -290.66028)
		(end 326.12076 -290.580826)
		(width 0.0762)
		(layer "F.Cu")
		(net "M_A_CPU0_SB_DQS_DN<3>")
	)
	(arc
		(start 326.12076 -290.580826)
		(mid 326.003947 -290.55615)
		(end 325.894954 -290.50742)
		(width 0.0762)
		(layer "F.Cu")
		(net "M_A_CPU0_SB_DQS_DN<3>")
	)
	(arc
		(start 325.894954 -290.50742)
		(mid 325.804821 -290.4698)
		(end 325.70801 -290.456874)
		(width 0.0762)
		(layer "F.Cu")
		(net "M_A_CPU0_SB_DQS_DN<3>")
	)
	(segment
		(start 310.87568 -301.907702)
		(end 310.692292 -301.907702)
		(width 0.12954)
		(layer "F.Cu")
		(net "M_A_CPU0_SB_DQS_DN<2>")
	)
	(segment
		(start 313.945778 -298.654216)
		(end 313.945778 -298.837604)
		(width 0.12954)
		(layer "F.Cu")
		(net "M_A_CPU0_SB_DQS_DN<2>")
	)
	(segment
		(start 314.28563 -298.497752)
		(end 314.102242 -298.497752)
		(width 0.12954)
		(layer "F.Cu")
		(net "M_A_CPU0_SB_DQS_DN<2>")
	)
	(segment
		(start 316.375542 -296.224452)
		(end 316.219078 -296.380916)
		(width 0.12954)
		(layer "F.Cu")
		(net "M_A_CPU0_SB_DQS_DN<2>")
	)
	(segment
		(start 315.62421 -297.563032)
		(end 315.42228 -297.361102)
		(width 0.12954)
		(layer "F.Cu")
		(net "M_A_CPU0_SB_DQS_DN<2>")
	)
	(segment
		(start 312.809128 -299.974254)
		(end 313.011058 -300.176184)
		(width 0.12954)
		(layer "F.Cu")
		(net "M_A_CPU0_SB_DQS_DN<2>")
	)
	(segment
		(start 311.874408 -301.762922)
		(end 311.527698 -302.109632)
		(width 0.12954)
		(layer "F.Cu")
		(net "M_A_CPU0_SB_DQS_DN<2>")
	)
	(segment
		(start 317.650622 -290.251134)
		(end 317.650622 -294.949372)
		(width 0.12954)
		(layer "F.Cu")
		(net "M_A_CPU0_SB_DQS_DN<2>")
	)
	(segment
		(start 317.557658 -295.629584)
		(end 317.557658 -296.079672)
		(width 0.12954)
		(layer "F.Cu")
		(net "M_A_CPU0_SB_DQS_DN<2>")
	)
	(segment
		(start 314.147708 -299.039534)
		(end 314.147708 -299.489622)
		(width 0.12954)
		(layer "F.Cu")
		(net "M_A_CPU0_SB_DQS_DN<2>")
	)
	(segment
		(start 310.535828 -302.064166)
		(end 310.535828 -302.247554)
		(width 0.12954)
		(layer "F.Cu")
		(net "M_A_CPU0_SB_DQS_DN<2>")
	)
	(segment
		(start 311.527698 -302.109632)
		(end 311.07761 -302.109632)
		(width 0.12954)
		(layer "F.Cu")
		(net "M_A_CPU0_SB_DQS_DN<2>")
	)
	(segment
		(start 312.809128 -299.790866)
		(end 312.809128 -299.974254)
		(width 0.12954)
		(layer "F.Cu")
		(net "M_A_CPU0_SB_DQS_DN<2>")
	)
	(segment
		(start 316.219078 -296.564304)
		(end 316.421008 -296.766234)
		(width 0.12954)
		(layer "F.Cu")
		(net "M_A_CPU0_SB_DQS_DN<2>")
	)
	(segment
		(start 317.355728 -295.427654)
		(end 317.557658 -295.629584)
		(width 0.12954)
		(layer "F.Cu")
		(net "M_A_CPU0_SB_DQS_DN<2>")
	)
	(segment
		(start 323.915024 -285.56585)
		(end 323.895974 -285.56585)
		(width 0.0762)
		(layer "F.Cu")
		(net "M_A_CPU0_SB_DQS_DN<2>")
	)
	(segment
		(start 323.895974 -285.56585)
		(end 322.335906 -285.56585)
		(width 0.12954)
		(layer "F.Cu")
		(net "M_A_CPU0_SB_DQS_DN<2>")
	)
	(segment
		(start 313.945778 -298.837604)
		(end 314.147708 -299.039534)
		(width 0.12954)
		(layer "F.Cu")
		(net "M_A_CPU0_SB_DQS_DN<2>")
	)
	(segment
		(start 310.391048 -303.246282)
		(end 309.94096 -303.246282)
		(width 0.12954)
		(layer "F.Cu")
		(net "M_A_CPU0_SB_DQS_DN<2>")
	)
	(segment
		(start 310.535828 -302.247554)
		(end 310.737758 -302.449484)
		(width 0.12954)
		(layer "F.Cu")
		(net "M_A_CPU0_SB_DQS_DN<2>")
	)
	(segment
		(start 311.672478 -301.110904)
		(end 311.874408 -301.312834)
		(width 0.12954)
		(layer "F.Cu")
		(net "M_A_CPU0_SB_DQS_DN<2>")
	)
	(segment
		(start 310.737758 -302.899572)
		(end 310.391048 -303.246282)
		(width 0.12954)
		(layer "F.Cu")
		(net "M_A_CPU0_SB_DQS_DN<2>")
	)
	(segment
		(start 316.074298 -297.563032)
		(end 315.62421 -297.563032)
		(width 0.12954)
		(layer "F.Cu")
		(net "M_A_CPU0_SB_DQS_DN<2>")
	)
	(segment
		(start 309.73903 -303.044352)
		(end 309.555642 -303.044352)
		(width 0.12954)
		(layer "F.Cu")
		(net "M_A_CPU0_SB_DQS_DN<2>")
	)
	(segment
		(start 315.284358 -297.902884)
		(end 315.284358 -298.352972)
		(width 0.12954)
		(layer "F.Cu")
		(net "M_A_CPU0_SB_DQS_DN<2>")
	)
	(segment
		(start 316.219078 -296.380916)
		(end 316.219078 -296.564304)
		(width 0.12954)
		(layer "F.Cu")
		(net "M_A_CPU0_SB_DQS_DN<2>")
	)
	(segment
		(start 308.090316 -304.17135)
		(end 307.826664 -304.435002)
		(width 0.12954)
		(layer "F.Cu")
		(net "M_A_CPU0_SB_DQS_DN<2>")
	)
	(segment
		(start 311.874408 -301.312834)
		(end 311.874408 -301.762922)
		(width 0.12954)
		(layer "F.Cu")
		(net "M_A_CPU0_SB_DQS_DN<2>")
	)
	(segment
		(start 315.284358 -298.352972)
		(end 314.937648 -298.699682)
		(width 0.12954)
		(layer "F.Cu")
		(net "M_A_CPU0_SB_DQS_DN<2>")
	)
	(segment
		(start 317.210948 -296.426382)
		(end 316.76086 -296.426382)
		(width 0.12954)
		(layer "F.Cu")
		(net "M_A_CPU0_SB_DQS_DN<2>")
	)
	(segment
		(start 311.672478 -300.927516)
		(end 311.672478 -301.110904)
		(width 0.12954)
		(layer "F.Cu")
		(net "M_A_CPU0_SB_DQS_DN<2>")
	)
	(segment
		(start 315.082428 -297.517566)
		(end 315.082428 -297.700954)
		(width 0.12954)
		(layer "F.Cu")
		(net "M_A_CPU0_SB_DQS_DN<2>")
	)
	(segment
		(start 325.126096 -285.49981)
		(end 323.981064 -285.49981)
		(width 0.0762)
		(layer "F.Cu")
		(net "M_A_CPU0_SB_DQS_DN<2>")
	)
	(segment
		(start 314.147708 -299.489622)
		(end 313.800998 -299.836332)
		(width 0.12954)
		(layer "F.Cu")
		(net "M_A_CPU0_SB_DQS_DN<2>")
	)
	(segment
		(start 317.355728 -295.244266)
		(end 317.355728 -295.427654)
		(width 0.12954)
		(layer "F.Cu")
		(net "M_A_CPU0_SB_DQS_DN<2>")
	)
	(segment
		(start 314.102242 -298.497752)
		(end 313.945778 -298.654216)
		(width 0.12954)
		(layer "F.Cu")
		(net "M_A_CPU0_SB_DQS_DN<2>")
	)
	(segment
		(start 312.21426 -300.972982)
		(end 312.01233 -300.771052)
		(width 0.12954)
		(layer "F.Cu")
		(net "M_A_CPU0_SB_DQS_DN<2>")
	)
	(segment
		(start 312.965592 -299.634402)
		(end 312.809128 -299.790866)
		(width 0.12954)
		(layer "F.Cu")
		(net "M_A_CPU0_SB_DQS_DN<2>")
	)
	(segment
		(start 325.223378 -285.597092)
		(end 325.126096 -285.49981)
		(width 0.0762)
		(layer "F.Cu")
		(net "M_A_CPU0_SB_DQS_DN<2>")
	)
	(segment
		(start 313.14898 -299.634402)
		(end 312.965592 -299.634402)
		(width 0.12954)
		(layer "F.Cu")
		(net "M_A_CPU0_SB_DQS_DN<2>")
	)
	(segment
		(start 323.981064 -285.49981)
		(end 323.915024 -285.56585)
		(width 0.0762)
		(layer "F.Cu")
		(net "M_A_CPU0_SB_DQS_DN<2>")
	)
	(segment
		(start 316.421008 -296.766234)
		(end 316.421008 -297.216322)
		(width 0.12954)
		(layer "F.Cu")
		(net "M_A_CPU0_SB_DQS_DN<2>")
	)
	(segment
		(start 325.70801 -285.597092)
		(end 325.223378 -285.597092)
		(width 0.0762)
		(layer "F.Cu")
		(net "M_A_CPU0_SB_DQS_DN<2>")
	)
	(segment
		(start 313.011058 -300.176184)
		(end 313.011058 -300.626272)
		(width 0.12954)
		(layer "F.Cu")
		(net "M_A_CPU0_SB_DQS_DN<2>")
	)
	(segment
		(start 322.335906 -285.56585)
		(end 317.650622 -290.251134)
		(width 0.12954)
		(layer "F.Cu")
		(net "M_A_CPU0_SB_DQS_DN<2>")
	)
	(segment
		(start 314.937648 -298.699682)
		(end 314.48756 -298.699682)
		(width 0.12954)
		(layer "F.Cu")
		(net "M_A_CPU0_SB_DQS_DN<2>")
	)
	(segment
		(start 311.07761 -302.109632)
		(end 310.87568 -301.907702)
		(width 0.12954)
		(layer "F.Cu")
		(net "M_A_CPU0_SB_DQS_DN<2>")
	)
	(segment
		(start 315.238892 -297.361102)
		(end 315.082428 -297.517566)
		(width 0.12954)
		(layer "F.Cu")
		(net "M_A_CPU0_SB_DQS_DN<2>")
	)
	(segment
		(start 316.76086 -296.426382)
		(end 316.55893 -296.224452)
		(width 0.12954)
		(layer "F.Cu")
		(net "M_A_CPU0_SB_DQS_DN<2>")
	)
	(segment
		(start 309.555642 -303.044352)
		(end 308.428644 -304.17135)
		(width 0.12954)
		(layer "F.Cu")
		(net "M_A_CPU0_SB_DQS_DN<2>")
	)
	(segment
		(start 317.650622 -294.949372)
		(end 317.355728 -295.244266)
		(width 0.12954)
		(layer "F.Cu")
		(net "M_A_CPU0_SB_DQS_DN<2>")
	)
	(segment
		(start 310.692292 -301.907702)
		(end 310.535828 -302.064166)
		(width 0.12954)
		(layer "F.Cu")
		(net "M_A_CPU0_SB_DQS_DN<2>")
	)
	(segment
		(start 313.011058 -300.626272)
		(end 312.664348 -300.972982)
		(width 0.12954)
		(layer "F.Cu")
		(net "M_A_CPU0_SB_DQS_DN<2>")
	)
	(segment
		(start 308.428644 -304.17135)
		(end 308.090316 -304.17135)
		(width 0.12954)
		(layer "F.Cu")
		(net "M_A_CPU0_SB_DQS_DN<2>")
	)
	(segment
		(start 312.01233 -300.771052)
		(end 311.828942 -300.771052)
		(width 0.12954)
		(layer "F.Cu")
		(net "M_A_CPU0_SB_DQS_DN<2>")
	)
	(segment
		(start 311.828942 -300.771052)
		(end 311.672478 -300.927516)
		(width 0.12954)
		(layer "F.Cu")
		(net "M_A_CPU0_SB_DQS_DN<2>")
	)
	(segment
		(start 316.421008 -297.216322)
		(end 316.074298 -297.563032)
		(width 0.12954)
		(layer "F.Cu")
		(net "M_A_CPU0_SB_DQS_DN<2>")
	)
	(segment
		(start 309.94096 -303.246282)
		(end 309.73903 -303.044352)
		(width 0.12954)
		(layer "F.Cu")
		(net "M_A_CPU0_SB_DQS_DN<2>")
	)
	(segment
		(start 313.35091 -299.836332)
		(end 313.14898 -299.634402)
		(width 0.12954)
		(layer "F.Cu")
		(net "M_A_CPU0_SB_DQS_DN<2>")
	)
	(segment
		(start 316.55893 -296.224452)
		(end 316.375542 -296.224452)
		(width 0.12954)
		(layer "F.Cu")
		(net "M_A_CPU0_SB_DQS_DN<2>")
	)
	(segment
		(start 310.737758 -302.449484)
		(end 310.737758 -302.899572)
		(width 0.12954)
		(layer "F.Cu")
		(net "M_A_CPU0_SB_DQS_DN<2>")
	)
	(segment
		(start 314.48756 -298.699682)
		(end 314.28563 -298.497752)
		(width 0.12954)
		(layer "F.Cu")
		(net "M_A_CPU0_SB_DQS_DN<2>")
	)
	(segment
		(start 313.800998 -299.836332)
		(end 313.35091 -299.836332)
		(width 0.12954)
		(layer "F.Cu")
		(net "M_A_CPU0_SB_DQS_DN<2>")
	)
	(segment
		(start 315.082428 -297.700954)
		(end 315.284358 -297.902884)
		(width 0.12954)
		(layer "F.Cu")
		(net "M_A_CPU0_SB_DQS_DN<2>")
	)
	(segment
		(start 317.557658 -296.079672)
		(end 317.210948 -296.426382)
		(width 0.12954)
		(layer "F.Cu")
		(net "M_A_CPU0_SB_DQS_DN<2>")
	)
	(segment
		(start 312.664348 -300.972982)
		(end 312.21426 -300.972982)
		(width 0.12954)
		(layer "F.Cu")
		(net "M_A_CPU0_SB_DQS_DN<2>")
	)
	(segment
		(start 307.826664 -304.435002)
		(end 307.368194 -304.435002)
		(width 0.12954)
		(layer "F.Cu")
		(net "M_A_CPU0_SB_DQS_DN<2>")
	)
	(segment
		(start 315.42228 -297.361102)
		(end 315.238892 -297.361102)
		(width 0.12954)
		(layer "F.Cu")
		(net "M_A_CPU0_SB_DQS_DN<2>")
	)
	(arc
		(start 326.648064 -285.970218)
		(mid 326.405747 -285.800498)
		(end 326.12076 -285.721044)
		(width 0.0762)
		(layer "F.Cu")
		(net "M_A_CPU0_SB_DQS_DN<2>")
	)
	(arc
		(start 325.894954 -285.647638)
		(mid 325.804821 -285.610018)
		(end 325.70801 -285.597092)
		(width 0.0762)
		(layer "F.Cu")
		(net "M_A_CPU0_SB_DQS_DN<2>")
	)
	(arc
		(start 326.12076 -285.721044)
		(mid 326.003947 -285.696368)
		(end 325.894954 -285.647638)
		(width 0.0762)
		(layer "F.Cu")
		(net "M_A_CPU0_SB_DQS_DN<2>")
	)
	(segment
		(start 314.669932 -286.425894)
		(end 314.471812 -286.624014)
		(width 0.12954)
		(layer "F.Cu")
		(net "M_A_CPU0_SB_DQS_DN<1>")
	)
	(segment
		(start 309.579518 -292.87978)
		(end 309.396892 -292.880034)
		(width 0.12954)
		(layer "F.Cu")
		(net "M_A_CPU0_SB_DQS_DN<1>")
	)
	(segment
		(start 316.745112 -284.900878)
		(end 316.356746 -285.289244)
		(width 0.12954)
		(layer "F.Cu")
		(net "M_A_CPU0_SB_DQS_DN<1>")
	)
	(segment
		(start 315.608462 -286.037528)
		(end 315.220096 -286.425894)
		(width 0.12954)
		(layer "F.Cu")
		(net "M_A_CPU0_SB_DQS_DN<1>")
	)
	(segment
		(start 312.197242 -291.83076)
		(end 311.99582 -292.032182)
		(width 0.12954)
		(layer "F.Cu")
		(net "M_A_CPU0_SB_DQS_DN<1>")
	)
	(segment
		(start 310.071516 -294.052244)
		(end 310.071516 -294.503094)
		(width 0.12954)
		(layer "F.Cu")
		(net "M_A_CPU0_SB_DQS_DN<1>")
	)
	(segment
		(start 315.806582 -285.289244)
		(end 315.608462 -285.487364)
		(width 0.12954)
		(layer "F.Cu")
		(net "M_A_CPU0_SB_DQS_DN<1>")
	)
	(segment
		(start 311.99582 -292.032182)
		(end 311.99582 -292.57879)
		(width 0.12954)
		(layer "F.Cu")
		(net "M_A_CPU0_SB_DQS_DN<1>")
	)
	(segment
		(start 319.018412 -282.077414)
		(end 319.018412 -282.627578)
		(width 0.12954)
		(layer "F.Cu")
		(net "M_A_CPU0_SB_DQS_DN<1>")
	)
	(segment
		(start 325.077582 -280.59126)
		(end 324.154038 -280.59126)
		(width 0.0762)
		(layer "F.Cu")
		(net "M_A_CPU0_SB_DQS_DN<1>")
	)
	(segment
		(start 317.493396 -284.152594)
		(end 316.943232 -284.152594)
		(width 0.12954)
		(layer "F.Cu")
		(net "M_A_CPU0_SB_DQS_DN<1>")
	)
	(segment
		(start 316.356746 -285.289244)
		(end 315.806582 -285.289244)
		(width 0.12954)
		(layer "F.Cu")
		(net "M_A_CPU0_SB_DQS_DN<1>")
	)
	(segment
		(start 314.083446 -287.562544)
		(end 313.533282 -287.562544)
		(width 0.12954)
		(layer "F.Cu")
		(net "M_A_CPU0_SB_DQS_DN<1>")
	)
	(segment
		(start 309.396892 -292.880034)
		(end 309.238904 -293.037768)
		(width 0.12954)
		(layer "F.Cu")
		(net "M_A_CPU0_SB_DQS_DN<1>")
	)
	(segment
		(start 314.471812 -287.174178)
		(end 314.083446 -287.562544)
		(width 0.12954)
		(layer "F.Cu")
		(net "M_A_CPU0_SB_DQS_DN<1>")
	)
	(segment
		(start 312.74385 -291.83076)
		(end 312.197242 -291.83076)
		(width 0.12954)
		(layer "F.Cu")
		(net "M_A_CPU0_SB_DQS_DN<1>")
	)
	(segment
		(start 325.70801 -280.737056)
		(end 325.223378 -280.737056)
		(width 0.0762)
		(layer "F.Cu")
		(net "M_A_CPU0_SB_DQS_DN<1>")
	)
	(segment
		(start 316.943232 -284.152594)
		(end 316.745112 -284.350714)
		(width 0.12954)
		(layer "F.Cu")
		(net "M_A_CPU0_SB_DQS_DN<1>")
	)
	(segment
		(start 323.962014 -280.57221)
		(end 323.895974 -280.63825)
		(width 0.0762)
		(layer "F.Cu")
		(net "M_A_CPU0_SB_DQS_DN<1>")
	)
	(segment
		(start 320.457576 -280.63825)
		(end 320.155062 -280.940764)
		(width 0.12954)
		(layer "F.Cu")
		(net "M_A_CPU0_SB_DQS_DN<1>")
	)
	(segment
		(start 319.018412 -282.627578)
		(end 318.630046 -283.015944)
		(width 0.12954)
		(layer "F.Cu")
		(net "M_A_CPU0_SB_DQS_DN<1>")
	)
	(segment
		(start 310.862726 -293.711884)
		(end 310.411622 -293.711884)
		(width 0.12954)
		(layer "F.Cu")
		(net "M_A_CPU0_SB_DQS_DN<1>")
	)
	(segment
		(start 309.239158 -293.219886)
		(end 310.071516 -294.052244)
		(width 0.12954)
		(layer "F.Cu")
		(net "M_A_CPU0_SB_DQS_DN<1>")
	)
	(segment
		(start 319.216532 -281.879294)
		(end 319.018412 -282.077414)
		(width 0.12954)
		(layer "F.Cu")
		(net "M_A_CPU0_SB_DQS_DN<1>")
	)
	(segment
		(start 310.411622 -293.711884)
		(end 309.579518 -292.87978)
		(width 0.12954)
		(layer "F.Cu")
		(net "M_A_CPU0_SB_DQS_DN<1>")
	)
	(segment
		(start 311.99582 -292.57879)
		(end 310.862726 -293.711884)
		(width 0.12954)
		(layer "F.Cu")
		(net "M_A_CPU0_SB_DQS_DN<1>")
	)
	(segment
		(start 317.881762 -283.764228)
		(end 317.493396 -284.152594)
		(width 0.12954)
		(layer "F.Cu")
		(net "M_A_CPU0_SB_DQS_DN<1>")
	)
	(segment
		(start 307.902864 -295.085008)
		(end 307.368194 -295.085008)
		(width 0.12954)
		(layer "F.Cu")
		(net "M_A_CPU0_SB_DQS_DN<1>")
	)
	(segment
		(start 318.079882 -283.015944)
		(end 317.881762 -283.214064)
		(width 0.12954)
		(layer "F.Cu")
		(net "M_A_CPU0_SB_DQS_DN<1>")
	)
	(segment
		(start 325.223378 -280.737056)
		(end 325.077582 -280.59126)
		(width 0.0762)
		(layer "F.Cu")
		(net "M_A_CPU0_SB_DQS_DN<1>")
	)
	(segment
		(start 309.238904 -293.037768)
		(end 309.239158 -293.219886)
		(width 0.12954)
		(layer "F.Cu")
		(net "M_A_CPU0_SB_DQS_DN<1>")
	)
	(segment
		(start 315.608462 -285.487364)
		(end 315.608462 -286.037528)
		(width 0.12954)
		(layer "F.Cu")
		(net "M_A_CPU0_SB_DQS_DN<1>")
	)
	(segment
		(start 313.219084 -287.876742)
		(end 313.219084 -288.282634)
		(width 0.12954)
		(layer "F.Cu")
		(net "M_A_CPU0_SB_DQS_DN<1>")
	)
	(segment
		(start 313.219084 -288.282634)
		(end 312.843418 -288.6583)
		(width 0.12954)
		(layer "F.Cu")
		(net "M_A_CPU0_SB_DQS_DN<1>")
	)
	(segment
		(start 317.881762 -283.214064)
		(end 317.881762 -283.764228)
		(width 0.12954)
		(layer "F.Cu")
		(net "M_A_CPU0_SB_DQS_DN<1>")
	)
	(segment
		(start 310.071516 -294.503094)
		(end 309.753254 -294.821356)
		(width 0.12954)
		(layer "F.Cu")
		(net "M_A_CPU0_SB_DQS_DN<1>")
	)
	(segment
		(start 308.166516 -294.821356)
		(end 307.902864 -295.085008)
		(width 0.12954)
		(layer "F.Cu")
		(net "M_A_CPU0_SB_DQS_DN<1>")
	)
	(segment
		(start 313.533282 -287.562544)
		(end 313.219084 -287.876742)
		(width 0.12954)
		(layer "F.Cu")
		(net "M_A_CPU0_SB_DQS_DN<1>")
	)
	(segment
		(start 313.219084 -291.355526)
		(end 312.74385 -291.83076)
		(width 0.12954)
		(layer "F.Cu")
		(net "M_A_CPU0_SB_DQS_DN<1>")
	)
	(segment
		(start 309.753254 -294.821356)
		(end 308.166516 -294.821356)
		(width 0.12954)
		(layer "F.Cu")
		(net "M_A_CPU0_SB_DQS_DN<1>")
	)
	(segment
		(start 313.219084 -289.327336)
		(end 313.219084 -291.355526)
		(width 0.12954)
		(layer "F.Cu")
		(net "M_A_CPU0_SB_DQS_DN<1>")
	)
	(segment
		(start 312.843418 -288.95167)
		(end 313.219084 -289.327336)
		(width 0.12954)
		(layer "F.Cu")
		(net "M_A_CPU0_SB_DQS_DN<1>")
	)
	(segment
		(start 316.745112 -284.350714)
		(end 316.745112 -284.900878)
		(width 0.12954)
		(layer "F.Cu")
		(net "M_A_CPU0_SB_DQS_DN<1>")
	)
	(segment
		(start 320.155062 -280.940764)
		(end 320.155062 -281.490928)
		(width 0.12954)
		(layer "F.Cu")
		(net "M_A_CPU0_SB_DQS_DN<1>")
	)
	(segment
		(start 323.895974 -280.63825)
		(end 320.457576 -280.63825)
		(width 0.12954)
		(layer "F.Cu")
		(net "M_A_CPU0_SB_DQS_DN<1>")
	)
	(segment
		(start 318.630046 -283.015944)
		(end 318.079882 -283.015944)
		(width 0.12954)
		(layer "F.Cu")
		(net "M_A_CPU0_SB_DQS_DN<1>")
	)
	(segment
		(start 312.843418 -288.6583)
		(end 312.843418 -288.95167)
		(width 0.12954)
		(layer "F.Cu")
		(net "M_A_CPU0_SB_DQS_DN<1>")
	)
	(segment
		(start 314.471812 -286.624014)
		(end 314.471812 -287.174178)
		(width 0.12954)
		(layer "F.Cu")
		(net "M_A_CPU0_SB_DQS_DN<1>")
	)
	(segment
		(start 324.154038 -280.59126)
		(end 323.962014 -280.57221)
		(width 0.0762)
		(layer "F.Cu")
		(net "M_A_CPU0_SB_DQS_DN<1>")
	)
	(segment
		(start 315.220096 -286.425894)
		(end 314.669932 -286.425894)
		(width 0.12954)
		(layer "F.Cu")
		(net "M_A_CPU0_SB_DQS_DN<1>")
	)
	(segment
		(start 319.766696 -281.879294)
		(end 319.216532 -281.879294)
		(width 0.12954)
		(layer "F.Cu")
		(net "M_A_CPU0_SB_DQS_DN<1>")
	)
	(segment
		(start 320.155062 -281.490928)
		(end 319.766696 -281.879294)
		(width 0.12954)
		(layer "F.Cu")
		(net "M_A_CPU0_SB_DQS_DN<1>")
	)
	(arc
		(start 326.12076 -280.861008)
		(mid 326.003947 -280.836332)
		(end 325.894954 -280.787602)
		(width 0.0762)
		(layer "F.Cu")
		(net "M_A_CPU0_SB_DQS_DN<1>")
	)
	(arc
		(start 325.894954 -280.787602)
		(mid 325.804821 -280.749982)
		(end 325.70801 -280.737056)
		(width 0.0762)
		(layer "F.Cu")
		(net "M_A_CPU0_SB_DQS_DN<1>")
	)
	(arc
		(start 326.648064 -281.110182)
		(mid 326.405747 -280.940462)
		(end 326.12076 -280.861008)
		(width 0.0762)
		(layer "F.Cu")
		(net "M_A_CPU0_SB_DQS_DN<1>")
	)
	(segment
		(start 310.740298 -282.564078)
		(end 310.55691 -282.564078)
		(width 0.12954)
		(layer "F.Cu")
		(net "M_A_CPU0_SB_DQS_DN<0>")
	)
	(segment
		(start 312.427112 -281.527504)
		(end 311.977024 -281.527504)
		(width 0.12954)
		(layer "F.Cu")
		(net "M_A_CPU0_SB_DQS_DN<0>")
	)
	(segment
		(start 313.563762 -280.390854)
		(end 313.113674 -280.390854)
		(width 0.12954)
		(layer "F.Cu")
		(net "M_A_CPU0_SB_DQS_DN<0>")
	)
	(segment
		(start 317.220346 -276.08403)
		(end 317.320422 -276.184106)
		(width 0.12954)
		(layer "F.Cu")
		(net "M_A_CPU0_SB_DQS_DN<0>")
	)
	(segment
		(start 319.366646 -275.623782)
		(end 319.015872 -275.623782)
		(width 0.12954)
		(layer "F.Cu")
		(net "M_A_CPU0_SB_DQS_DN<0>")
	)
	(segment
		(start 319.015872 -275.623782)
		(end 318.747902 -275.891752)
		(width 0.12954)
		(layer "F.Cu")
		(net "M_A_CPU0_SB_DQS_DN<0>")
	)
	(segment
		(start 316.24016 -276.880828)
		(end 316.083696 -277.037292)
		(width 0.12954)
		(layer "F.Cu")
		(net "M_A_CPU0_SB_DQS_DN<0>")
	)
	(segment
		(start 318.028828 -275.891752)
		(end 317.760858 -275.623782)
		(width 0.12954)
		(layer "F.Cu")
		(net "M_A_CPU0_SB_DQS_DN<0>")
	)
	(segment
		(start 311.637172 -281.867356)
		(end 311.637172 -282.317444)
		(width 0.12954)
		(layer "F.Cu")
		(net "M_A_CPU0_SB_DQS_DN<0>")
	)
	(segment
		(start 324.029578 -275.623782)
		(end 323.833236 -275.623782)
		(width 0.12954)
		(layer "F.Cu")
		(net "M_A_CPU0_SB_DQS_DN<0>")
	)
	(segment
		(start 317.320422 -276.634194)
		(end 316.973712 -276.980904)
		(width 0.12954)
		(layer "F.Cu")
		(net "M_A_CPU0_SB_DQS_DN<0>")
	)
	(segment
		(start 311.637172 -282.317444)
		(end 311.290462 -282.664154)
		(width 0.12954)
		(layer "F.Cu")
		(net "M_A_CPU0_SB_DQS_DN<0>")
	)
	(segment
		(start 310.55691 -282.564078)
		(end 310.400446 -282.720542)
		(width 0.12954)
		(layer "F.Cu")
		(net "M_A_CPU0_SB_DQS_DN<0>")
	)
	(segment
		(start 313.810396 -279.49398)
		(end 313.910472 -279.594056)
		(width 0.12954)
		(layer "F.Cu")
		(net "M_A_CPU0_SB_DQS_DN<0>")
	)
	(segment
		(start 315.10351 -278.017478)
		(end 314.947046 -278.173942)
		(width 0.12954)
		(layer "F.Cu")
		(net "M_A_CPU0_SB_DQS_DN<0>")
	)
	(segment
		(start 315.286898 -278.017478)
		(end 315.10351 -278.017478)
		(width 0.12954)
		(layer "F.Cu")
		(net "M_A_CPU0_SB_DQS_DN<0>")
	)
	(segment
		(start 315.386974 -278.117554)
		(end 315.286898 -278.017478)
		(width 0.12954)
		(layer "F.Cu")
		(net "M_A_CPU0_SB_DQS_DN<0>")
	)
	(segment
		(start 309.078884 -284.956758)
		(end 308.56428 -285.471362)
		(width 0.12954)
		(layer "F.Cu")
		(net "M_A_CPU0_SB_DQS_DN<0>")
	)
	(segment
		(start 324.345554 -275.557742)
		(end 324.114668 -275.557742)
		(width 0.0762)
		(layer "F.Cu")
		(net "M_A_CPU0_SB_DQS_DN<0>")
	)
	(segment
		(start 314.250324 -279.254204)
		(end 314.150248 -279.154128)
		(width 0.12954)
		(layer "F.Cu")
		(net "M_A_CPU0_SB_DQS_DN<0>")
	)
	(segment
		(start 313.810396 -279.310592)
		(end 313.810396 -279.49398)
		(width 0.12954)
		(layer "F.Cu")
		(net "M_A_CPU0_SB_DQS_DN<0>")
	)
	(segment
		(start 318.747902 -275.891752)
		(end 318.028828 -275.891752)
		(width 0.12954)
		(layer "F.Cu")
		(net "M_A_CPU0_SB_DQS_DN<0>")
	)
	(segment
		(start 322.846192 -275.891752)
		(end 322.578222 -275.623782)
		(width 0.12954)
		(layer "F.Cu")
		(net "M_A_CPU0_SB_DQS_DN<0>")
	)
	(segment
		(start 309.703724 -283.800804)
		(end 309.603648 -283.700728)
		(width 0.12954)
		(layer "F.Cu")
		(net "M_A_CPU0_SB_DQS_DN<0>")
	)
	(segment
		(start 313.113674 -280.390854)
		(end 313.013598 -280.290778)
		(width 0.12954)
		(layer "F.Cu")
		(net "M_A_CPU0_SB_DQS_DN<0>")
	)
	(segment
		(start 309.603648 -283.700728)
		(end 309.42026 -283.700728)
		(width 0.12954)
		(layer "F.Cu")
		(net "M_A_CPU0_SB_DQS_DN<0>")
	)
	(segment
		(start 316.083696 -277.22068)
		(end 316.183772 -277.320756)
		(width 0.12954)
		(layer "F.Cu")
		(net "M_A_CPU0_SB_DQS_DN<0>")
	)
	(segment
		(start 321.240404 -275.891752)
		(end 320.972434 -275.623782)
		(width 0.12954)
		(layer "F.Cu")
		(net "M_A_CPU0_SB_DQS_DN<0>")
	)
	(segment
		(start 316.083696 -277.037292)
		(end 316.083696 -277.22068)
		(width 0.12954)
		(layer "F.Cu")
		(net "M_A_CPU0_SB_DQS_DN<0>")
	)
	(segment
		(start 316.523624 -276.980904)
		(end 316.423548 -276.880828)
		(width 0.12954)
		(layer "F.Cu")
		(net "M_A_CPU0_SB_DQS_DN<0>")
	)
	(segment
		(start 325.70801 -275.87702)
		(end 324.664832 -275.87702)
		(width 0.0762)
		(layer "F.Cu")
		(net "M_A_CPU0_SB_DQS_DN<0>")
	)
	(segment
		(start 311.977024 -281.527504)
		(end 311.876948 -281.427428)
		(width 0.12954)
		(layer "F.Cu")
		(net "M_A_CPU0_SB_DQS_DN<0>")
	)
	(segment
		(start 324.664832 -275.87702)
		(end 324.345554 -275.557742)
		(width 0.0762)
		(layer "F.Cu")
		(net "M_A_CPU0_SB_DQS_DN<0>")
	)
	(segment
		(start 309.42026 -283.700728)
		(end 309.078884 -284.042104)
		(width 0.12954)
		(layer "F.Cu")
		(net "M_A_CPU0_SB_DQS_DN<0>")
	)
	(segment
		(start 314.700412 -279.254204)
		(end 314.250324 -279.254204)
		(width 0.12954)
		(layer "F.Cu")
		(net "M_A_CPU0_SB_DQS_DN<0>")
	)
	(segment
		(start 308.56428 -285.471362)
		(end 308.166516 -285.471362)
		(width 0.12954)
		(layer "F.Cu")
		(net "M_A_CPU0_SB_DQS_DN<0>")
	)
	(segment
		(start 308.166516 -285.471362)
		(end 307.902864 -285.735014)
		(width 0.12954)
		(layer "F.Cu")
		(net "M_A_CPU0_SB_DQS_DN<0>")
	)
	(segment
		(start 310.500522 -283.454094)
		(end 310.153812 -283.800804)
		(width 0.12954)
		(layer "F.Cu")
		(net "M_A_CPU0_SB_DQS_DN<0>")
	)
	(segment
		(start 322.578222 -275.623782)
		(end 322.227448 -275.623782)
		(width 0.12954)
		(layer "F.Cu")
		(net "M_A_CPU0_SB_DQS_DN<0>")
	)
	(segment
		(start 310.500522 -283.004006)
		(end 310.500522 -283.454094)
		(width 0.12954)
		(layer "F.Cu")
		(net "M_A_CPU0_SB_DQS_DN<0>")
	)
	(segment
		(start 312.773822 -281.180794)
		(end 312.427112 -281.527504)
		(width 0.12954)
		(layer "F.Cu")
		(net "M_A_CPU0_SB_DQS_DN<0>")
	)
	(segment
		(start 312.773822 -280.730706)
		(end 312.773822 -281.180794)
		(width 0.12954)
		(layer "F.Cu")
		(net "M_A_CPU0_SB_DQS_DN<0>")
	)
	(segment
		(start 316.183772 -277.320756)
		(end 316.183772 -277.770844)
		(width 0.12954)
		(layer "F.Cu")
		(net "M_A_CPU0_SB_DQS_DN<0>")
	)
	(segment
		(start 310.840374 -282.664154)
		(end 310.740298 -282.564078)
		(width 0.12954)
		(layer "F.Cu")
		(net "M_A_CPU0_SB_DQS_DN<0>")
	)
	(segment
		(start 312.83021 -280.290778)
		(end 312.673746 -280.447242)
		(width 0.12954)
		(layer "F.Cu")
		(net "M_A_CPU0_SB_DQS_DN<0>")
	)
	(segment
		(start 316.973712 -276.980904)
		(end 316.523624 -276.980904)
		(width 0.12954)
		(layer "F.Cu")
		(net "M_A_CPU0_SB_DQS_DN<0>")
	)
	(segment
		(start 315.047122 -278.907494)
		(end 314.700412 -279.254204)
		(width 0.12954)
		(layer "F.Cu")
		(net "M_A_CPU0_SB_DQS_DN<0>")
	)
	(segment
		(start 317.760858 -275.623782)
		(end 317.497206 -275.623782)
		(width 0.12954)
		(layer "F.Cu")
		(net "M_A_CPU0_SB_DQS_DN<0>")
	)
	(segment
		(start 307.902864 -285.735014)
		(end 307.368194 -285.735014)
		(width 0.12954)
		(layer "F.Cu")
		(net "M_A_CPU0_SB_DQS_DN<0>")
	)
	(segment
		(start 314.947046 -278.173942)
		(end 314.947046 -278.35733)
		(width 0.12954)
		(layer "F.Cu")
		(net "M_A_CPU0_SB_DQS_DN<0>")
	)
	(segment
		(start 310.400446 -282.720542)
		(end 310.400446 -282.90393)
		(width 0.12954)
		(layer "F.Cu")
		(net "M_A_CPU0_SB_DQS_DN<0>")
	)
	(segment
		(start 320.972434 -275.623782)
		(end 320.62166 -275.623782)
		(width 0.12954)
		(layer "F.Cu")
		(net "M_A_CPU0_SB_DQS_DN<0>")
	)
	(segment
		(start 316.423548 -276.880828)
		(end 316.24016 -276.880828)
		(width 0.12954)
		(layer "F.Cu")
		(net "M_A_CPU0_SB_DQS_DN<0>")
	)
	(segment
		(start 323.565266 -275.891752)
		(end 322.846192 -275.891752)
		(width 0.12954)
		(layer "F.Cu")
		(net "M_A_CPU0_SB_DQS_DN<0>")
	)
	(segment
		(start 323.833236 -275.623782)
		(end 323.565266 -275.891752)
		(width 0.12954)
		(layer "F.Cu")
		(net "M_A_CPU0_SB_DQS_DN<0>")
	)
	(segment
		(start 322.227448 -275.623782)
		(end 321.959478 -275.891752)
		(width 0.12954)
		(layer "F.Cu")
		(net "M_A_CPU0_SB_DQS_DN<0>")
	)
	(segment
		(start 319.634616 -275.891752)
		(end 319.366646 -275.623782)
		(width 0.12954)
		(layer "F.Cu")
		(net "M_A_CPU0_SB_DQS_DN<0>")
	)
	(segment
		(start 311.876948 -281.427428)
		(end 311.69356 -281.427428)
		(width 0.12954)
		(layer "F.Cu")
		(net "M_A_CPU0_SB_DQS_DN<0>")
	)
	(segment
		(start 317.220346 -275.900642)
		(end 317.220346 -276.08403)
		(width 0.12954)
		(layer "F.Cu")
		(net "M_A_CPU0_SB_DQS_DN<0>")
	)
	(segment
		(start 313.910472 -279.594056)
		(end 313.910472 -280.044144)
		(width 0.12954)
		(layer "F.Cu")
		(net "M_A_CPU0_SB_DQS_DN<0>")
	)
	(segment
		(start 311.537096 -281.76728)
		(end 311.637172 -281.867356)
		(width 0.12954)
		(layer "F.Cu")
		(net "M_A_CPU0_SB_DQS_DN<0>")
	)
	(segment
		(start 324.114668 -275.557742)
		(end 324.048628 -275.623782)
		(width 0.0762)
		(layer "F.Cu")
		(net "M_A_CPU0_SB_DQS_DN<0>")
	)
	(segment
		(start 313.96686 -279.154128)
		(end 313.810396 -279.310592)
		(width 0.12954)
		(layer "F.Cu")
		(net "M_A_CPU0_SB_DQS_DN<0>")
	)
	(segment
		(start 321.959478 -275.891752)
		(end 321.240404 -275.891752)
		(width 0.12954)
		(layer "F.Cu")
		(net "M_A_CPU0_SB_DQS_DN<0>")
	)
	(segment
		(start 310.400446 -282.90393)
		(end 310.500522 -283.004006)
		(width 0.12954)
		(layer "F.Cu")
		(net "M_A_CPU0_SB_DQS_DN<0>")
	)
	(segment
		(start 309.078884 -284.042104)
		(end 309.078884 -284.956758)
		(width 0.12954)
		(layer "F.Cu")
		(net "M_A_CPU0_SB_DQS_DN<0>")
	)
	(segment
		(start 315.047122 -278.457406)
		(end 315.047122 -278.907494)
		(width 0.12954)
		(layer "F.Cu")
		(net "M_A_CPU0_SB_DQS_DN<0>")
	)
	(segment
		(start 316.183772 -277.770844)
		(end 315.837062 -278.117554)
		(width 0.12954)
		(layer "F.Cu")
		(net "M_A_CPU0_SB_DQS_DN<0>")
	)
	(segment
		(start 317.320422 -276.184106)
		(end 317.320422 -276.634194)
		(width 0.12954)
		(layer "F.Cu")
		(net "M_A_CPU0_SB_DQS_DN<0>")
	)
	(segment
		(start 320.62166 -275.623782)
		(end 320.35369 -275.891752)
		(width 0.12954)
		(layer "F.Cu")
		(net "M_A_CPU0_SB_DQS_DN<0>")
	)
	(segment
		(start 313.910472 -280.044144)
		(end 313.563762 -280.390854)
		(width 0.12954)
		(layer "F.Cu")
		(net "M_A_CPU0_SB_DQS_DN<0>")
	)
	(segment
		(start 313.013598 -280.290778)
		(end 312.83021 -280.290778)
		(width 0.12954)
		(layer "F.Cu")
		(net "M_A_CPU0_SB_DQS_DN<0>")
	)
	(segment
		(start 314.150248 -279.154128)
		(end 313.96686 -279.154128)
		(width 0.12954)
		(layer "F.Cu")
		(net "M_A_CPU0_SB_DQS_DN<0>")
	)
	(segment
		(start 324.048628 -275.623782)
		(end 324.029578 -275.623782)
		(width 0.0762)
		(layer "F.Cu")
		(net "M_A_CPU0_SB_DQS_DN<0>")
	)
	(segment
		(start 315.837062 -278.117554)
		(end 315.386974 -278.117554)
		(width 0.12954)
		(layer "F.Cu")
		(net "M_A_CPU0_SB_DQS_DN<0>")
	)
	(segment
		(start 317.497206 -275.623782)
		(end 317.220346 -275.900642)
		(width 0.12954)
		(layer "F.Cu")
		(net "M_A_CPU0_SB_DQS_DN<0>")
	)
	(segment
		(start 311.537096 -281.583892)
		(end 311.537096 -281.76728)
		(width 0.12954)
		(layer "F.Cu")
		(net "M_A_CPU0_SB_DQS_DN<0>")
	)
	(segment
		(start 314.947046 -278.35733)
		(end 315.047122 -278.457406)
		(width 0.12954)
		(layer "F.Cu")
		(net "M_A_CPU0_SB_DQS_DN<0>")
	)
	(segment
		(start 312.673746 -280.447242)
		(end 312.673746 -280.63063)
		(width 0.12954)
		(layer "F.Cu")
		(net "M_A_CPU0_SB_DQS_DN<0>")
	)
	(segment
		(start 311.69356 -281.427428)
		(end 311.537096 -281.583892)
		(width 0.12954)
		(layer "F.Cu")
		(net "M_A_CPU0_SB_DQS_DN<0>")
	)
	(segment
		(start 310.153812 -283.800804)
		(end 309.703724 -283.800804)
		(width 0.12954)
		(layer "F.Cu")
		(net "M_A_CPU0_SB_DQS_DN<0>")
	)
	(segment
		(start 312.673746 -280.63063)
		(end 312.773822 -280.730706)
		(width 0.12954)
		(layer "F.Cu")
		(net "M_A_CPU0_SB_DQS_DN<0>")
	)
	(segment
		(start 311.290462 -282.664154)
		(end 310.840374 -282.664154)
		(width 0.12954)
		(layer "F.Cu")
		(net "M_A_CPU0_SB_DQS_DN<0>")
	)
	(segment
		(start 320.35369 -275.891752)
		(end 319.634616 -275.891752)
		(width 0.12954)
		(layer "F.Cu")
		(net "M_A_CPU0_SB_DQS_DN<0>")
	)
	(arc
		(start 326.12076 -276.000972)
		(mid 326.003947 -275.976296)
		(end 325.894954 -275.927566)
		(width 0.0762)
		(layer "F.Cu")
		(net "M_A_CPU0_SB_DQS_DN<0>")
	)
	(arc
		(start 325.894954 -275.927566)
		(mid 325.804821 -275.889946)
		(end 325.70801 -275.87702)
		(width 0.0762)
		(layer "F.Cu")
		(net "M_A_CPU0_SB_DQS_DN<0>")
	)
	(arc
		(start 326.648064 -276.250146)
		(mid 326.405747 -276.080426)
		(end 326.12076 -276.000972)
		(width 0.0762)
		(layer "F.Cu")
		(net "M_A_CPU0_SB_DQS_DN<0>")
	)
	(segment
		(start 308.618128 -291.806376)
		(end 307.889402 -292.535102)
		(width 0.10668)
		(layer "F.Cu")
		(net "M_A_CPU0_SB_DQ<9>")
	)
	(segment
		(start 320.012568 -279.5651)
		(end 311.68086 -287.896808)
		(width 0.10668)
		(layer "F.Cu")
		(net "M_A_CPU0_SB_DQ<9>")
	)
	(segment
		(start 311.216294 -290.16071)
		(end 309.570628 -291.806376)
		(width 0.10668)
		(layer "F.Cu")
		(net "M_A_CPU0_SB_DQ<9>")
	)
	(segment
		(start 324.368922 -279.5651)
		(end 323.901054 -279.5651)
		(width 0.0762)
		(layer "F.Cu")
		(net "M_A_CPU0_SB_DQ<9>")
	)
	(segment
		(start 310.155336 -291.786056)
		(end 311.498488 -290.442904)
		(width 0.10668)
		(layer "F.Cu")
		(net "M_A_CPU0_SB_DQ<9>")
	)
	(segment
		(start 310.155336 -291.937186)
		(end 310.155336 -291.786056)
		(width 0.10668)
		(layer "F.Cu")
		(net "M_A_CPU0_SB_DQ<9>")
	)
	(segment
		(start 309.570628 -291.806376)
		(end 308.618128 -291.806376)
		(width 0.10668)
		(layer "F.Cu")
		(net "M_A_CPU0_SB_DQ<9>")
	)
	(segment
		(start 310.43753 -292.06825)
		(end 310.2864 -292.06825)
		(width 0.10668)
		(layer "F.Cu")
		(net "M_A_CPU0_SB_DQ<9>")
	)
	(segment
		(start 310.2864 -292.06825)
		(end 310.155336 -291.937186)
		(width 0.10668)
		(layer "F.Cu")
		(net "M_A_CPU0_SB_DQ<9>")
	)
	(segment
		(start 311.498488 -290.442904)
		(end 311.498488 -290.292028)
		(width 0.10668)
		(layer "F.Cu")
		(net "M_A_CPU0_SB_DQ<9>")
	)
	(segment
		(start 327.587864 -279.49017)
		(end 327.688702 -279.663652)
		(width 0.0762)
		(layer "F.Cu")
		(net "M_A_CPU0_SB_DQ<9>")
	)
	(segment
		(start 326.835008 -279.81275)
		(end 326.826626 -279.817576)
		(width 0.0762)
		(layer "F.Cu")
		(net "M_A_CPU0_SB_DQ<9>")
	)
	(segment
		(start 311.68086 -289.910012)
		(end 311.897268 -290.12642)
		(width 0.10668)
		(layer "F.Cu")
		(net "M_A_CPU0_SB_DQ<9>")
	)
	(segment
		(start 311.897268 -290.608512)
		(end 310.43753 -292.06825)
		(width 0.10668)
		(layer "F.Cu")
		(net "M_A_CPU0_SB_DQ<9>")
	)
	(segment
		(start 311.897268 -290.12642)
		(end 311.897268 -290.608512)
		(width 0.10668)
		(layer "F.Cu")
		(net "M_A_CPU0_SB_DQ<9>")
	)
	(segment
		(start 325.70801 -279.863296)
		(end 324.667118 -279.863296)
		(width 0.0762)
		(layer "F.Cu")
		(net "M_A_CPU0_SB_DQ<9>")
	)
	(segment
		(start 324.667118 -279.863296)
		(end 324.368922 -279.5651)
		(width 0.0762)
		(layer "F.Cu")
		(net "M_A_CPU0_SB_DQ<9>")
	)
	(segment
		(start 311.68086 -287.896808)
		(end 311.68086 -289.910012)
		(width 0.10668)
		(layer "F.Cu")
		(net "M_A_CPU0_SB_DQ<9>")
	)
	(segment
		(start 327.409302 -279.817576)
		(end 327.40092 -279.81275)
		(width 0.0762)
		(layer "F.Cu")
		(net "M_A_CPU0_SB_DQ<9>")
	)
	(segment
		(start 311.36717 -290.16071)
		(end 311.216294 -290.16071)
		(width 0.10668)
		(layer "F.Cu")
		(net "M_A_CPU0_SB_DQ<9>")
	)
	(segment
		(start 311.498488 -290.292028)
		(end 311.36717 -290.16071)
		(width 0.10668)
		(layer "F.Cu")
		(net "M_A_CPU0_SB_DQ<9>")
	)
	(segment
		(start 323.901054 -279.5651)
		(end 320.012568 -279.5651)
		(width 0.10668)
		(layer "F.Cu")
		(net "M_A_CPU0_SB_DQ<9>")
	)
	(segment
		(start 307.889402 -292.535102)
		(end 307.368194 -292.535102)
		(width 0.10668)
		(layer "F.Cu")
		(net "M_A_CPU0_SB_DQ<9>")
	)
	(arc
		(start 325.894954 -279.81275)
		(mid 325.819714 -279.846063)
		(end 325.738998 -279.862026)
		(width 0.0762)
		(layer "F.Cu")
		(net "M_A_CPU0_SB_DQ<9>")
	)
	(arc
		(start 327.688702 -279.663652)
		(mid 327.672777 -279.804344)
		(end 327.542652 -279.860248)
		(width 0.0762)
		(layer "F.Cu")
		(net "M_A_CPU0_SB_DQ<9>")
	)
	(arc
		(start 326.460866 -279.81275)
		(mid 326.17791 -279.736573)
		(end 325.894954 -279.81275)
		(width 0.0762)
		(layer "F.Cu")
		(net "M_A_CPU0_SB_DQ<9>")
	)
	(arc
		(start 327.40092 -279.81275)
		(mid 327.117964 -279.736573)
		(end 326.835008 -279.81275)
		(width 0.0762)
		(layer "F.Cu")
		(net "M_A_CPU0_SB_DQ<9>")
	)
	(arc
		(start 325.738998 -279.862026)
		(mid 325.723517 -279.862982)
		(end 325.70801 -279.863296)
		(width 0.0762)
		(layer "F.Cu")
		(net "M_A_CPU0_SB_DQ<9>")
	)
	(arc
		(start 326.826626 -279.817576)
		(mid 326.643118 -279.86307)
		(end 326.460866 -279.81275)
		(width 0.0762)
		(layer "F.Cu")
		(net "M_A_CPU0_SB_DQ<9>")
	)
	(arc
		(start 327.542652 -279.860248)
		(mid 327.473954 -279.845232)
		(end 327.409302 -279.817576)
		(width 0.0762)
		(layer "F.Cu")
		(net "M_A_CPU0_SB_DQ<9>")
	)
	(segment
		(start 325.999348 -279.00757)
		(end 325.990966 -279.002744)
		(width 0.0762)
		(layer "F.Cu")
		(net "M_A_CPU0_SB_DQ<8>")
	)
	(segment
		(start 325.70801 -278.926544)
		(end 325.302372 -278.926544)
		(width 0.0762)
		(layer "F.Cu")
		(net "M_A_CPU0_SB_DQ<8>")
	)
	(segment
		(start 309.293514 -289.320986)
		(end 309.293514 -289.471862)
		(width 0.10668)
		(layer "F.Cu")
		(net "M_A_CPU0_SB_DQ<8>")
	)
	(segment
		(start 310.96839 -287.64611)
		(end 310.968898 -287.911032)
		(width 0.10668)
		(layer "F.Cu")
		(net "M_A_CPU0_SB_DQ<8>")
	)
	(segment
		(start 308.860444 -289.754056)
		(end 308.699408 -289.915092)
		(width 0.10668)
		(layer "F.Cu")
		(net "M_A_CPU0_SB_DQ<8>")
	)
	(segment
		(start 309.203598 -291.065712)
		(end 308.873398 -291.065712)
		(width 0.10668)
		(layer "F.Cu")
		(net "M_A_CPU0_SB_DQ<8>")
	)
	(segment
		(start 319.752726 -278.861774)
		(end 310.96839 -287.64611)
		(width 0.10668)
		(layer "F.Cu")
		(net "M_A_CPU0_SB_DQ<8>")
	)
	(segment
		(start 310.717692 -289.202622)
		(end 310.140096 -288.625026)
		(width 0.10668)
		(layer "F.Cu")
		(net "M_A_CPU0_SB_DQ<8>")
	)
	(segment
		(start 309.857902 -288.907474)
		(end 310.606694 -289.656266)
		(width 0.10668)
		(layer "F.Cu")
		(net "M_A_CPU0_SB_DQ<8>")
	)
	(segment
		(start 310.042306 -290.220654)
		(end 310.04256 -290.371022)
		(width 0.10668)
		(layer "F.Cu")
		(net "M_A_CPU0_SB_DQ<8>")
	)
	(segment
		(start 310.3245 -289.938206)
		(end 309.575708 -289.189414)
		(width 0.10668)
		(layer "F.Cu")
		(net "M_A_CPU0_SB_DQ<8>")
	)
	(segment
		(start 309.575708 -289.189414)
		(end 309.424832 -289.189668)
		(width 0.10668)
		(layer "F.Cu")
		(net "M_A_CPU0_SB_DQ<8>")
	)
	(segment
		(start 310.968898 -287.911032)
		(end 310.837326 -288.042604)
		(width 0.10668)
		(layer "F.Cu")
		(net "M_A_CPU0_SB_DQ<8>")
	)
	(segment
		(start 309.01132 -289.753802)
		(end 308.860444 -289.754056)
		(width 0.10668)
		(layer "F.Cu")
		(net "M_A_CPU0_SB_DQ<8>")
	)
	(segment
		(start 310.868568 -289.202622)
		(end 310.717692 -289.202622)
		(width 0.10668)
		(layer "F.Cu")
		(net "M_A_CPU0_SB_DQ<8>")
	)
	(segment
		(start 308.699408 -290.066222)
		(end 309.368698 -290.735512)
		(width 0.10668)
		(layer "F.Cu")
		(net "M_A_CPU0_SB_DQ<8>")
	)
	(segment
		(start 310.571896 -288.042604)
		(end 310.42229 -288.19221)
		(width 0.10668)
		(layer "F.Cu")
		(net "M_A_CPU0_SB_DQ<8>")
	)
	(segment
		(start 309.368698 -290.900612)
		(end 309.203598 -291.065712)
		(width 0.10668)
		(layer "F.Cu")
		(net "M_A_CPU0_SB_DQ<8>")
	)
	(segment
		(start 309.910988 -290.502594)
		(end 309.760112 -290.502594)
		(width 0.10668)
		(layer "F.Cu")
		(net "M_A_CPU0_SB_DQ<8>")
	)
	(segment
		(start 308.873398 -291.065712)
		(end 308.642766 -290.83508)
		(width 0.10668)
		(layer "F.Cu")
		(net "M_A_CPU0_SB_DQ<8>")
	)
	(segment
		(start 325.302372 -278.926544)
		(end 325.237602 -278.861774)
		(width 0.0762)
		(layer "F.Cu")
		(net "M_A_CPU0_SB_DQ<8>")
	)
	(segment
		(start 309.98922 -288.62528)
		(end 309.857902 -288.756598)
		(width 0.10668)
		(layer "F.Cu")
		(net "M_A_CPU0_SB_DQ<8>")
	)
	(segment
		(start 323.878448 -278.861774)
		(end 319.752726 -278.861774)
		(width 0.10668)
		(layer "F.Cu")
		(net "M_A_CPU0_SB_DQ<8>")
	)
	(segment
		(start 309.857902 -288.756598)
		(end 309.857902 -288.907474)
		(width 0.10668)
		(layer "F.Cu")
		(net "M_A_CPU0_SB_DQ<8>")
	)
	(segment
		(start 311.00014 -289.07105)
		(end 310.868568 -289.202622)
		(width 0.10668)
		(layer "F.Cu")
		(net "M_A_CPU0_SB_DQ<8>")
	)
	(segment
		(start 325.237602 -278.861774)
		(end 323.878448 -278.861774)
		(width 0.0762)
		(layer "F.Cu")
		(net "M_A_CPU0_SB_DQ<8>")
	)
	(segment
		(start 308.699408 -289.915092)
		(end 308.699408 -290.066222)
		(width 0.10668)
		(layer "F.Cu")
		(net "M_A_CPU0_SB_DQ<8>")
	)
	(segment
		(start 310.140096 -288.625026)
		(end 309.98922 -288.62528)
		(width 0.10668)
		(layer "F.Cu")
		(net "M_A_CPU0_SB_DQ<8>")
	)
	(segment
		(start 310.42229 -288.19221)
		(end 310.42229 -288.343086)
		(width 0.10668)
		(layer "F.Cu")
		(net "M_A_CPU0_SB_DQ<8>")
	)
	(segment
		(start 309.760112 -290.502594)
		(end 309.01132 -289.753802)
		(width 0.10668)
		(layer "F.Cu")
		(net "M_A_CPU0_SB_DQ<8>")
	)
	(segment
		(start 309.424832 -289.189668)
		(end 309.293514 -289.320986)
		(width 0.10668)
		(layer "F.Cu")
		(net "M_A_CPU0_SB_DQ<8>")
	)
	(segment
		(start 310.999886 -288.920682)
		(end 311.00014 -289.07105)
		(width 0.10668)
		(layer "F.Cu")
		(net "M_A_CPU0_SB_DQ<8>")
	)
	(segment
		(start 310.04256 -290.371022)
		(end 309.910988 -290.502594)
		(width 0.10668)
		(layer "F.Cu")
		(net "M_A_CPU0_SB_DQ<8>")
	)
	(segment
		(start 310.606694 -289.656266)
		(end 310.606948 -289.806634)
		(width 0.10668)
		(layer "F.Cu")
		(net "M_A_CPU0_SB_DQ<8>")
	)
	(segment
		(start 309.293514 -289.471862)
		(end 310.042306 -290.220654)
		(width 0.10668)
		(layer "F.Cu")
		(net "M_A_CPU0_SB_DQ<8>")
	)
	(segment
		(start 310.606948 -289.806634)
		(end 310.475376 -289.938206)
		(width 0.10668)
		(layer "F.Cu")
		(net "M_A_CPU0_SB_DQ<8>")
	)
	(segment
		(start 310.42229 -288.343086)
		(end 310.999886 -288.920682)
		(width 0.10668)
		(layer "F.Cu")
		(net "M_A_CPU0_SB_DQ<8>")
	)
	(segment
		(start 326.17791 -278.680164)
		(end 326.276208 -278.849328)
		(width 0.0762)
		(layer "F.Cu")
		(net "M_A_CPU0_SB_DQ<8>")
	)
	(segment
		(start 310.475376 -289.938206)
		(end 310.3245 -289.938206)
		(width 0.10668)
		(layer "F.Cu")
		(net "M_A_CPU0_SB_DQ<8>")
	)
	(segment
		(start 309.368698 -290.735512)
		(end 309.368698 -290.900612)
		(width 0.10668)
		(layer "F.Cu")
		(net "M_A_CPU0_SB_DQ<8>")
	)
	(segment
		(start 308.642766 -290.83508)
		(end 307.368194 -290.83508)
		(width 0.10668)
		(layer "F.Cu")
		(net "M_A_CPU0_SB_DQ<8>")
	)
	(segment
		(start 310.837326 -288.042604)
		(end 310.571896 -288.042604)
		(width 0.10668)
		(layer "F.Cu")
		(net "M_A_CPU0_SB_DQ<8>")
	)
	(arc
		(start 326.276208 -278.849328)
		(mid 326.267615 -278.991207)
		(end 326.13854 -279.051004)
		(width 0.0762)
		(layer "F.Cu")
		(net "M_A_CPU0_SB_DQ<8>")
	)
	(arc
		(start 326.13854 -279.051004)
		(mid 326.066802 -279.036152)
		(end 325.999348 -279.00757)
		(width 0.0762)
		(layer "F.Cu")
		(net "M_A_CPU0_SB_DQ<8>")
	)
	(arc
		(start 325.990966 -279.002744)
		(mid 325.85453 -278.945919)
		(end 325.70801 -278.926544)
		(width 0.0762)
		(layer "F.Cu")
		(net "M_A_CPU0_SB_DQ<8>")
	)
	(segment
		(start 323.901054 -278.404574)
		(end 319.563242 -278.404574)
		(width 0.10668)
		(layer "F.Cu")
		(net "M_A_CPU0_SB_DQ<7>")
	)
	(segment
		(start 324.583552 -278.404574)
		(end 323.901054 -278.404574)
		(width 0.0762)
		(layer "F.Cu")
		(net "M_A_CPU0_SB_DQ<7>")
	)
	(segment
		(start 306.095654 -289.56)
		(end 305.670458 -289.985196)
		(width 0.101346)
		(layer "F.Cu")
		(net "M_A_CPU0_SB_DQ<7>")
	)
	(segment
		(start 308.407816 -289.56)
		(end 306.095654 -289.56)
		(width 0.101346)
		(layer "F.Cu")
		(net "M_A_CPU0_SB_DQ<7>")
	)
	(segment
		(start 325.999348 -278.352758)
		(end 325.990966 -278.357584)
		(width 0.0762)
		(layer "F.Cu")
		(net "M_A_CPU0_SB_DQ<7>")
	)
	(segment
		(start 319.563242 -278.404574)
		(end 308.575456 -289.39236)
		(width 0.10668)
		(layer "F.Cu")
		(net "M_A_CPU0_SB_DQ<7>")
	)
	(segment
		(start 308.575456 -289.39236)
		(end 308.407816 -289.56)
		(width 0.101346)
		(layer "F.Cu")
		(net "M_A_CPU0_SB_DQ<7>")
	)
	(segment
		(start 324.612762 -278.433784)
		(end 324.583552 -278.404574)
		(width 0.0762)
		(layer "F.Cu")
		(net "M_A_CPU0_SB_DQ<7>")
	)
	(segment
		(start 305.670458 -289.985196)
		(end 303.268126 -289.985196)
		(width 0.101346)
		(layer "F.Cu")
		(net "M_A_CPU0_SB_DQ<7>")
	)
	(segment
		(start 325.708264 -278.433784)
		(end 324.612762 -278.433784)
		(width 0.0762)
		(layer "F.Cu")
		(net "M_A_CPU0_SB_DQ<7>")
	)
	(arc
		(start 327.53808 -278.431752)
		(mid 327.417431 -278.407451)
		(end 327.304908 -278.357584)
		(width 0.0762)
		(layer "F.Cu")
		(net "M_A_CPU0_SB_DQ<7>")
	)
	(arc
		(start 326.365108 -278.357584)
		(mid 326.182857 -278.307234)
		(end 325.999348 -278.352758)
		(width 0.0762)
		(layer "F.Cu")
		(net "M_A_CPU0_SB_DQ<7>")
	)
	(arc
		(start 325.755254 -278.432006)
		(mid 325.731777 -278.433382)
		(end 325.708264 -278.433784)
		(width 0.0762)
		(layer "F.Cu")
		(net "M_A_CPU0_SB_DQ<7>")
	)
	(arc
		(start 325.990966 -278.357584)
		(mid 325.877242 -278.407885)
		(end 325.755254 -278.432006)
		(width 0.0762)
		(layer "F.Cu")
		(net "M_A_CPU0_SB_DQ<7>")
	)
	(arc
		(start 328.058018 -278.680164)
		(mid 327.820406 -278.509176)
		(end 327.53808 -278.431752)
		(width 0.0762)
		(layer "F.Cu")
		(net "M_A_CPU0_SB_DQ<7>")
	)
	(arc
		(start 327.304908 -278.357584)
		(mid 327.117964 -278.307329)
		(end 326.93102 -278.357584)
		(width 0.0762)
		(layer "F.Cu")
		(net "M_A_CPU0_SB_DQ<7>")
	)
	(arc
		(start 326.93102 -278.357584)
		(mid 326.648064 -278.433761)
		(end 326.365108 -278.357584)
		(width 0.0762)
		(layer "F.Cu")
		(net "M_A_CPU0_SB_DQ<7>")
	)
	(segment
		(start 305.34229 -288.693352)
		(end 305.240944 -288.592006)
		(width 0.101346)
		(layer "F.Cu")
		(net "M_A_CPU0_SB_DQ<6>")
	)
	(segment
		(start 304.847244 -288.592006)
		(end 304.745898 -288.693352)
		(width 0.101346)
		(layer "F.Cu")
		(net "M_A_CPU0_SB_DQ<6>")
	)
	(segment
		(start 324.104508 -277.399242)
		(end 319.107058 -277.399242)
		(width 0.10668)
		(layer "F.Cu")
		(net "M_A_CPU0_SB_DQ<6>")
	)
	(segment
		(start 304.453544 -288.592006)
		(end 304.453544 -288.38652)
		(width 0.101346)
		(layer "F.Cu")
		(net "M_A_CPU0_SB_DQ<6>")
	)
	(segment
		(start 304.847244 -288.38652)
		(end 304.847244 -288.592006)
		(width 0.101346)
		(layer "F.Cu")
		(net "M_A_CPU0_SB_DQ<6>")
	)
	(segment
		(start 324.323456 -277.497032)
		(end 324.225666 -277.399242)
		(width 0.0762)
		(layer "F.Cu")
		(net "M_A_CPU0_SB_DQ<6>")
	)
	(segment
		(start 310.67248 -286.076644)
		(end 308.889146 -287.859978)
		(width 0.10668)
		(layer "F.Cu")
		(net "M_A_CPU0_SB_DQ<6>")
	)
	(segment
		(start 310.67248 -285.83382)
		(end 310.67248 -286.076644)
		(width 0.10668)
		(layer "F.Cu")
		(net "M_A_CPU0_SB_DQ<6>")
	)
	(segment
		(start 304.94859 -288.285174)
		(end 304.847244 -288.38652)
		(width 0.101346)
		(layer "F.Cu")
		(net "M_A_CPU0_SB_DQ<6>")
	)
	(segment
		(start 325.70801 -277.497032)
		(end 324.323456 -277.497032)
		(width 0.0762)
		(layer "F.Cu")
		(net "M_A_CPU0_SB_DQ<6>")
	)
	(segment
		(start 304.55489 -288.693352)
		(end 304.453544 -288.592006)
		(width 0.101346)
		(layer "F.Cu")
		(net "M_A_CPU0_SB_DQ<6>")
	)
	(segment
		(start 306.161186 -287.859978)
		(end 305.634644 -288.38652)
		(width 0.101346)
		(layer "F.Cu")
		(net "M_A_CPU0_SB_DQ<6>")
	)
	(segment
		(start 308.889146 -287.859978)
		(end 308.66588 -287.859978)
		(width 0.10668)
		(layer "F.Cu")
		(net "M_A_CPU0_SB_DQ<6>")
	)
	(segment
		(start 319.107058 -277.399242)
		(end 310.67248 -285.83382)
		(width 0.10668)
		(layer "F.Cu")
		(net "M_A_CPU0_SB_DQ<6>")
	)
	(segment
		(start 305.139598 -288.285174)
		(end 304.94859 -288.285174)
		(width 0.101346)
		(layer "F.Cu")
		(net "M_A_CPU0_SB_DQ<6>")
	)
	(segment
		(start 305.634644 -288.38652)
		(end 305.634644 -288.592006)
		(width 0.101346)
		(layer "F.Cu")
		(net "M_A_CPU0_SB_DQ<6>")
	)
	(segment
		(start 304.352198 -288.285174)
		(end 303.268126 -288.285174)
		(width 0.101346)
		(layer "F.Cu")
		(net "M_A_CPU0_SB_DQ<6>")
	)
	(segment
		(start 304.745898 -288.693352)
		(end 304.55489 -288.693352)
		(width 0.101346)
		(layer "F.Cu")
		(net "M_A_CPU0_SB_DQ<6>")
	)
	(segment
		(start 305.240944 -288.592006)
		(end 305.240944 -288.38652)
		(width 0.101346)
		(layer "F.Cu")
		(net "M_A_CPU0_SB_DQ<6>")
	)
	(segment
		(start 305.533298 -288.693352)
		(end 305.34229 -288.693352)
		(width 0.101346)
		(layer "F.Cu")
		(net "M_A_CPU0_SB_DQ<6>")
	)
	(segment
		(start 324.225666 -277.399242)
		(end 324.104508 -277.399242)
		(width 0.0762)
		(layer "F.Cu")
		(net "M_A_CPU0_SB_DQ<6>")
	)
	(segment
		(start 304.453544 -288.38652)
		(end 304.352198 -288.285174)
		(width 0.101346)
		(layer "F.Cu")
		(net "M_A_CPU0_SB_DQ<6>")
	)
	(segment
		(start 308.66588 -287.859978)
		(end 306.161186 -287.859978)
		(width 0.101346)
		(layer "F.Cu")
		(net "M_A_CPU0_SB_DQ<6>")
	)
	(segment
		(start 305.240944 -288.38652)
		(end 305.139598 -288.285174)
		(width 0.101346)
		(layer "F.Cu")
		(net "M_A_CPU0_SB_DQ<6>")
	)
	(segment
		(start 305.634644 -288.592006)
		(end 305.533298 -288.693352)
		(width 0.101346)
		(layer "F.Cu")
		(net "M_A_CPU0_SB_DQ<6>")
	)
	(arc
		(start 325.894954 -277.547578)
		(mid 325.804821 -277.509958)
		(end 325.70801 -277.497032)
		(width 0.0762)
		(layer "F.Cu")
		(net "M_A_CPU0_SB_DQ<6>")
	)
	(arc
		(start 326.12076 -277.620984)
		(mid 326.003947 -277.596308)
		(end 325.894954 -277.547578)
		(width 0.0762)
		(layer "F.Cu")
		(net "M_A_CPU0_SB_DQ<6>")
	)
	(arc
		(start 326.648064 -277.870158)
		(mid 326.405747 -277.700438)
		(end 326.12076 -277.620984)
		(width 0.0762)
		(layer "F.Cu")
		(net "M_A_CPU0_SB_DQ<6>")
	)
	(segment
		(start 320.28892 -278.055832)
		(end 320.103246 -278.055832)
		(width 0.10668)
		(layer "F.Cu")
		(net "M_A_CPU0_SB_DQ<5>")
	)
	(segment
		(start 315.15685 -281.831034)
		(end 315.15685 -282.051506)
		(width 0.10668)
		(layer "F.Cu")
		(net "M_A_CPU0_SB_DQ<5>")
	)
	(segment
		(start 321.086988 -278.055832)
		(end 320.901314 -278.055832)
		(width 0.10668)
		(layer "F.Cu")
		(net "M_A_CPU0_SB_DQ<5>")
	)
	(segment
		(start 322.098416 -277.754842)
		(end 321.991736 -277.861522)
		(width 0.10668)
		(layer "F.Cu")
		(net "M_A_CPU0_SB_DQ<5>")
	)
	(segment
		(start 323.941186 -277.754842)
		(end 323.694552 -277.754842)
		(width 0.10668)
		(layer "F.Cu")
		(net "M_A_CPU0_SB_DQ<5>")
	)
	(segment
		(start 308.447948 -289.018218)
		(end 308.331108 -289.135058)
		(width 0.10668)
		(layer "F.Cu")
		(net "M_A_CPU0_SB_DQ<5>")
	)
	(segment
		(start 324.833488 -278.243284)
		(end 324.345046 -277.754842)
		(width 0.0762)
		(layer "F.Cu")
		(net "M_A_CPU0_SB_DQ<5>")
	)
	(segment
		(start 313.856116 -283.35224)
		(end 313.635644 -283.35224)
		(width 0.10668)
		(layer "F.Cu")
		(net "M_A_CPU0_SB_DQ<5>")
	)
	(segment
		(start 318.37122 -278.837136)
		(end 318.150748 -278.837136)
		(width 0.10668)
		(layer "F.Cu")
		(net "M_A_CPU0_SB_DQ<5>")
	)
	(segment
		(start 314.200032 -282.787852)
		(end 314.028074 -282.95981)
		(width 0.10668)
		(layer "F.Cu")
		(net "M_A_CPU0_SB_DQ<5>")
	)
	(segment
		(start 315.721238 -281.487118)
		(end 315.54928 -281.659076)
		(width 0.10668)
		(layer "F.Cu")
		(net "M_A_CPU0_SB_DQ<5>")
	)
	(segment
		(start 319.889886 -277.754842)
		(end 319.233042 -277.754842)
		(width 0.10668)
		(layer "F.Cu")
		(net "M_A_CPU0_SB_DQ<5>")
	)
	(segment
		(start 315.54928 -281.659076)
		(end 315.328808 -281.659076)
		(width 0.10668)
		(layer "F.Cu")
		(net "M_A_CPU0_SB_DQ<5>")
	)
	(segment
		(start 314.420504 -282.787852)
		(end 314.200032 -282.787852)
		(width 0.10668)
		(layer "F.Cu")
		(net "M_A_CPU0_SB_DQ<5>")
	)
	(segment
		(start 320.50228 -277.754842)
		(end 320.3956 -277.861522)
		(width 0.10668)
		(layer "F.Cu")
		(net "M_A_CPU0_SB_DQ<5>")
	)
	(segment
		(start 314.76442 -282.223464)
		(end 314.592462 -282.395422)
		(width 0.10668)
		(layer "F.Cu")
		(net "M_A_CPU0_SB_DQ<5>")
	)
	(segment
		(start 323.082158 -277.754842)
		(end 322.896484 -277.754842)
		(width 0.10668)
		(layer "F.Cu")
		(net "M_A_CPU0_SB_DQ<5>")
	)
	(segment
		(start 321.885056 -278.055832)
		(end 321.699382 -278.055832)
		(width 0.10668)
		(layer "F.Cu")
		(net "M_A_CPU0_SB_DQ<5>")
	)
	(segment
		(start 317.242444 -279.965912)
		(end 317.021972 -279.965912)
		(width 0.10668)
		(layer "F.Cu")
		(net "M_A_CPU0_SB_DQ<5>")
	)
	(segment
		(start 314.592462 -282.395422)
		(end 314.592462 -282.615894)
		(width 0.10668)
		(layer "F.Cu")
		(net "M_A_CPU0_SB_DQ<5>")
	)
	(segment
		(start 311.01284 -286.218122)
		(end 308.893464 -288.337498)
		(width 0.10668)
		(layer "F.Cu")
		(net "M_A_CPU0_SB_DQ<5>")
	)
	(segment
		(start 327.587864 -277.870158)
		(end 327.688702 -278.04364)
		(width 0.0762)
		(layer "F.Cu")
		(net "M_A_CPU0_SB_DQ<5>")
	)
	(segment
		(start 318.150748 -278.837136)
		(end 317.97879 -279.009094)
		(width 0.10668)
		(layer "F.Cu")
		(net "M_A_CPU0_SB_DQ<5>")
	)
	(segment
		(start 320.3956 -277.861522)
		(end 320.3956 -277.949152)
		(width 0.10668)
		(layer "F.Cu")
		(net "M_A_CPU0_SB_DQ<5>")
	)
	(segment
		(start 318.543178 -278.444706)
		(end 318.543178 -278.665178)
		(width 0.10668)
		(layer "F.Cu")
		(net "M_A_CPU0_SB_DQ<5>")
	)
	(segment
		(start 315.721238 -281.266646)
		(end 315.721238 -281.487118)
		(width 0.10668)
		(layer "F.Cu")
		(net "M_A_CPU0_SB_DQ<5>")
	)
	(segment
		(start 325.70801 -278.243284)
		(end 324.833488 -278.243284)
		(width 0.0762)
		(layer "F.Cu")
		(net "M_A_CPU0_SB_DQ<5>")
	)
	(segment
		(start 308.447948 -288.454338)
		(end 308.447948 -289.018218)
		(width 0.10668)
		(layer "F.Cu")
		(net "M_A_CPU0_SB_DQ<5>")
	)
	(segment
		(start 322.28409 -277.754842)
		(end 322.098416 -277.754842)
		(width 0.10668)
		(layer "F.Cu")
		(net "M_A_CPU0_SB_DQ<5>")
	)
	(segment
		(start 311.770522 -285.217362)
		(end 311.770522 -285.437834)
		(width 0.10668)
		(layer "F.Cu")
		(net "M_A_CPU0_SB_DQ<5>")
	)
	(segment
		(start 316.285626 -280.92273)
		(end 316.113668 -281.094688)
		(width 0.10668)
		(layer "F.Cu")
		(net "M_A_CPU0_SB_DQ<5>")
	)
	(segment
		(start 316.457584 -280.5303)
		(end 316.285626 -280.702258)
		(width 0.10668)
		(layer "F.Cu")
		(net "M_A_CPU0_SB_DQ<5>")
	)
	(segment
		(start 321.592702 -277.949152)
		(end 321.592702 -277.861522)
		(width 0.10668)
		(layer "F.Cu")
		(net "M_A_CPU0_SB_DQ<5>")
	)
	(segment
		(start 312.899298 -284.088586)
		(end 312.899298 -284.309058)
		(width 0.10668)
		(layer "F.Cu")
		(net "M_A_CPU0_SB_DQ<5>")
	)
	(segment
		(start 311.378092 -285.609792)
		(end 311.01284 -285.975044)
		(width 0.10668)
		(layer "F.Cu")
		(net "M_A_CPU0_SB_DQ<5>")
	)
	(segment
		(start 322.39077 -277.861522)
		(end 322.28409 -277.754842)
		(width 0.10668)
		(layer "F.Cu")
		(net "M_A_CPU0_SB_DQ<5>")
	)
	(segment
		(start 315.15685 -282.051506)
		(end 314.984892 -282.223464)
		(width 0.10668)
		(layer "F.Cu")
		(net "M_A_CPU0_SB_DQ<5>")
	)
	(segment
		(start 322.789804 -277.949152)
		(end 322.683124 -278.055832)
		(width 0.10668)
		(layer "F.Cu")
		(net "M_A_CPU0_SB_DQ<5>")
	)
	(segment
		(start 317.414402 -279.793954)
		(end 317.242444 -279.965912)
		(width 0.10668)
		(layer "F.Cu")
		(net "M_A_CPU0_SB_DQ<5>")
	)
	(segment
		(start 313.463686 -283.524198)
		(end 313.463686 -283.74467)
		(width 0.10668)
		(layer "F.Cu")
		(net "M_A_CPU0_SB_DQ<5>")
	)
	(segment
		(start 311.770522 -285.437834)
		(end 311.598564 -285.609792)
		(width 0.10668)
		(layer "F.Cu")
		(net "M_A_CPU0_SB_DQ<5>")
	)
	(segment
		(start 314.028074 -282.95981)
		(end 314.028074 -283.180282)
		(width 0.10668)
		(layer "F.Cu")
		(net "M_A_CPU0_SB_DQ<5>")
	)
	(segment
		(start 311.598564 -285.609792)
		(end 311.378092 -285.609792)
		(width 0.10668)
		(layer "F.Cu")
		(net "M_A_CPU0_SB_DQ<5>")
	)
	(segment
		(start 320.901314 -278.055832)
		(end 320.794634 -277.949152)
		(width 0.10668)
		(layer "F.Cu")
		(net "M_A_CPU0_SB_DQ<5>")
	)
	(segment
		(start 312.33491 -284.652974)
		(end 312.33491 -284.873446)
		(width 0.10668)
		(layer "F.Cu")
		(net "M_A_CPU0_SB_DQ<5>")
	)
	(segment
		(start 315.328808 -281.659076)
		(end 315.15685 -281.831034)
		(width 0.10668)
		(layer "F.Cu")
		(net "M_A_CPU0_SB_DQ<5>")
	)
	(segment
		(start 319.233042 -277.754842)
		(end 319.107566 -277.880318)
		(width 0.10668)
		(layer "F.Cu")
		(net "M_A_CPU0_SB_DQ<5>")
	)
	(segment
		(start 314.028074 -283.180282)
		(end 313.856116 -283.35224)
		(width 0.10668)
		(layer "F.Cu")
		(net "M_A_CPU0_SB_DQ<5>")
	)
	(segment
		(start 322.49745 -278.055832)
		(end 322.39077 -277.949152)
		(width 0.10668)
		(layer "F.Cu")
		(net "M_A_CPU0_SB_DQ<5>")
	)
	(segment
		(start 321.699382 -278.055832)
		(end 321.592702 -277.949152)
		(width 0.10668)
		(layer "F.Cu")
		(net "M_A_CPU0_SB_DQ<5>")
	)
	(segment
		(start 323.481192 -278.055832)
		(end 323.295518 -278.055832)
		(width 0.10668)
		(layer "F.Cu")
		(net "M_A_CPU0_SB_DQ<5>")
	)
	(segment
		(start 321.486022 -277.754842)
		(end 321.300348 -277.754842)
		(width 0.10668)
		(layer "F.Cu")
		(net "M_A_CPU0_SB_DQ<5>")
	)
	(segment
		(start 316.850014 -280.13787)
		(end 316.850014 -280.358342)
		(width 0.10668)
		(layer "F.Cu")
		(net "M_A_CPU0_SB_DQ<5>")
	)
	(segment
		(start 308.564788 -288.337498)
		(end 308.447948 -288.454338)
		(width 0.10668)
		(layer "F.Cu")
		(net "M_A_CPU0_SB_DQ<5>")
	)
	(segment
		(start 327.409302 -278.197564)
		(end 327.40092 -278.192738)
		(width 0.0762)
		(layer "F.Cu")
		(net "M_A_CPU0_SB_DQ<5>")
	)
	(segment
		(start 321.300348 -277.754842)
		(end 321.193668 -277.861522)
		(width 0.10668)
		(layer "F.Cu")
		(net "M_A_CPU0_SB_DQ<5>")
	)
	(segment
		(start 316.285626 -280.702258)
		(end 316.285626 -280.92273)
		(width 0.10668)
		(layer "F.Cu")
		(net "M_A_CPU0_SB_DQ<5>")
	)
	(segment
		(start 323.587872 -277.949152)
		(end 323.481192 -278.055832)
		(width 0.10668)
		(layer "F.Cu")
		(net "M_A_CPU0_SB_DQ<5>")
	)
	(segment
		(start 317.58636 -279.401524)
		(end 317.414402 -279.573482)
		(width 0.10668)
		(layer "F.Cu")
		(net "M_A_CPU0_SB_DQ<5>")
	)
	(segment
		(start 308.893464 -288.337498)
		(end 308.564788 -288.337498)
		(width 0.10668)
		(layer "F.Cu")
		(net "M_A_CPU0_SB_DQ<5>")
	)
	(segment
		(start 326.835008 -278.192738)
		(end 326.826626 -278.197564)
		(width 0.0762)
		(layer "F.Cu")
		(net "M_A_CPU0_SB_DQ<5>")
	)
	(segment
		(start 313.291728 -283.916628)
		(end 313.071256 -283.916628)
		(width 0.10668)
		(layer "F.Cu")
		(net "M_A_CPU0_SB_DQ<5>")
	)
	(segment
		(start 314.984892 -282.223464)
		(end 314.76442 -282.223464)
		(width 0.10668)
		(layer "F.Cu")
		(net "M_A_CPU0_SB_DQ<5>")
	)
	(segment
		(start 323.188838 -277.861522)
		(end 323.082158 -277.754842)
		(width 0.10668)
		(layer "F.Cu")
		(net "M_A_CPU0_SB_DQ<5>")
	)
	(segment
		(start 316.850014 -280.358342)
		(end 316.678056 -280.5303)
		(width 0.10668)
		(layer "F.Cu")
		(net "M_A_CPU0_SB_DQ<5>")
	)
	(segment
		(start 316.678056 -280.5303)
		(end 316.457584 -280.5303)
		(width 0.10668)
		(layer "F.Cu")
		(net "M_A_CPU0_SB_DQ<5>")
	)
	(segment
		(start 320.103246 -278.055832)
		(end 319.996566 -277.949152)
		(width 0.10668)
		(layer "F.Cu")
		(net "M_A_CPU0_SB_DQ<5>")
	)
	(segment
		(start 311.94248 -285.045404)
		(end 311.770522 -285.217362)
		(width 0.10668)
		(layer "F.Cu")
		(net "M_A_CPU0_SB_DQ<5>")
	)
	(segment
		(start 322.683124 -278.055832)
		(end 322.49745 -278.055832)
		(width 0.10668)
		(layer "F.Cu")
		(net "M_A_CPU0_SB_DQ<5>")
	)
	(segment
		(start 320.794634 -277.949152)
		(end 320.794634 -277.861522)
		(width 0.10668)
		(layer "F.Cu")
		(net "M_A_CPU0_SB_DQ<5>")
	)
	(segment
		(start 321.991736 -277.949152)
		(end 321.885056 -278.055832)
		(width 0.10668)
		(layer "F.Cu")
		(net "M_A_CPU0_SB_DQ<5>")
	)
	(segment
		(start 312.33491 -284.873446)
		(end 312.162952 -285.045404)
		(width 0.10668)
		(layer "F.Cu")
		(net "M_A_CPU0_SB_DQ<5>")
	)
	(segment
		(start 317.97879 -279.229566)
		(end 317.806832 -279.401524)
		(width 0.10668)
		(layer "F.Cu")
		(net "M_A_CPU0_SB_DQ<5>")
	)
	(segment
		(start 322.39077 -277.949152)
		(end 322.39077 -277.861522)
		(width 0.10668)
		(layer "F.Cu")
		(net "M_A_CPU0_SB_DQ<5>")
	)
	(segment
		(start 312.162952 -285.045404)
		(end 311.94248 -285.045404)
		(width 0.10668)
		(layer "F.Cu")
		(net "M_A_CPU0_SB_DQ<5>")
	)
	(segment
		(start 315.893196 -281.094688)
		(end 315.721238 -281.266646)
		(width 0.10668)
		(layer "F.Cu")
		(net "M_A_CPU0_SB_DQ<5>")
	)
	(segment
		(start 312.506868 -284.481016)
		(end 312.33491 -284.652974)
		(width 0.10668)
		(layer "F.Cu")
		(net "M_A_CPU0_SB_DQ<5>")
	)
	(segment
		(start 322.896484 -277.754842)
		(end 322.789804 -277.861522)
		(width 0.10668)
		(layer "F.Cu")
		(net "M_A_CPU0_SB_DQ<5>")
	)
	(segment
		(start 323.188838 -277.949152)
		(end 323.188838 -277.861522)
		(width 0.10668)
		(layer "F.Cu")
		(net "M_A_CPU0_SB_DQ<5>")
	)
	(segment
		(start 323.587872 -277.861522)
		(end 323.587872 -277.949152)
		(width 0.10668)
		(layer "F.Cu")
		(net "M_A_CPU0_SB_DQ<5>")
	)
	(segment
		(start 308.331108 -289.135058)
		(end 307.368194 -289.135058)
		(width 0.10668)
		(layer "F.Cu")
		(net "M_A_CPU0_SB_DQ<5>")
	)
	(segment
		(start 322.789804 -277.861522)
		(end 322.789804 -277.949152)
		(width 0.10668)
		(layer "F.Cu")
		(net "M_A_CPU0_SB_DQ<5>")
	)
	(segment
		(start 320.3956 -277.949152)
		(end 320.28892 -278.055832)
		(width 0.10668)
		(layer "F.Cu")
		(net "M_A_CPU0_SB_DQ<5>")
	)
	(segment
		(start 313.635644 -283.35224)
		(end 313.463686 -283.524198)
		(width 0.10668)
		(layer "F.Cu")
		(net "M_A_CPU0_SB_DQ<5>")
	)
	(segment
		(start 319.996566 -277.949152)
		(end 319.996566 -277.861522)
		(width 0.10668)
		(layer "F.Cu")
		(net "M_A_CPU0_SB_DQ<5>")
	)
	(segment
		(start 323.295518 -278.055832)
		(end 323.188838 -277.949152)
		(width 0.10668)
		(layer "F.Cu")
		(net "M_A_CPU0_SB_DQ<5>")
	)
	(segment
		(start 319.107566 -277.880318)
		(end 319.107566 -278.10079)
		(width 0.10668)
		(layer "F.Cu")
		(net "M_A_CPU0_SB_DQ<5>")
	)
	(segment
		(start 318.715136 -278.272748)
		(end 318.543178 -278.444706)
		(width 0.10668)
		(layer "F.Cu")
		(net "M_A_CPU0_SB_DQ<5>")
	)
	(segment
		(start 321.193668 -277.861522)
		(end 321.193668 -277.949152)
		(width 0.10668)
		(layer "F.Cu")
		(net "M_A_CPU0_SB_DQ<5>")
	)
	(segment
		(start 320.794634 -277.861522)
		(end 320.687954 -277.754842)
		(width 0.10668)
		(layer "F.Cu")
		(net "M_A_CPU0_SB_DQ<5>")
	)
	(segment
		(start 317.021972 -279.965912)
		(end 316.850014 -280.13787)
		(width 0.10668)
		(layer "F.Cu")
		(net "M_A_CPU0_SB_DQ<5>")
	)
	(segment
		(start 321.592702 -277.861522)
		(end 321.486022 -277.754842)
		(width 0.10668)
		(layer "F.Cu")
		(net "M_A_CPU0_SB_DQ<5>")
	)
	(segment
		(start 313.071256 -283.916628)
		(end 312.899298 -284.088586)
		(width 0.10668)
		(layer "F.Cu")
		(net "M_A_CPU0_SB_DQ<5>")
	)
	(segment
		(start 317.414402 -279.573482)
		(end 317.414402 -279.793954)
		(width 0.10668)
		(layer "F.Cu")
		(net "M_A_CPU0_SB_DQ<5>")
	)
	(segment
		(start 320.687954 -277.754842)
		(end 320.50228 -277.754842)
		(width 0.10668)
		(layer "F.Cu")
		(net "M_A_CPU0_SB_DQ<5>")
	)
	(segment
		(start 324.345046 -277.754842)
		(end 323.941186 -277.754842)
		(width 0.0762)
		(layer "F.Cu")
		(net "M_A_CPU0_SB_DQ<5>")
	)
	(segment
		(start 321.991736 -277.861522)
		(end 321.991736 -277.949152)
		(width 0.10668)
		(layer "F.Cu")
		(net "M_A_CPU0_SB_DQ<5>")
	)
	(segment
		(start 312.899298 -284.309058)
		(end 312.72734 -284.481016)
		(width 0.10668)
		(layer "F.Cu")
		(net "M_A_CPU0_SB_DQ<5>")
	)
	(segment
		(start 316.113668 -281.094688)
		(end 315.893196 -281.094688)
		(width 0.10668)
		(layer "F.Cu")
		(net "M_A_CPU0_SB_DQ<5>")
	)
	(segment
		(start 318.935608 -278.272748)
		(end 318.715136 -278.272748)
		(width 0.10668)
		(layer "F.Cu")
		(net "M_A_CPU0_SB_DQ<5>")
	)
	(segment
		(start 323.694552 -277.754842)
		(end 323.587872 -277.861522)
		(width 0.10668)
		(layer "F.Cu")
		(net "M_A_CPU0_SB_DQ<5>")
	)
	(segment
		(start 317.97879 -279.009094)
		(end 317.97879 -279.229566)
		(width 0.10668)
		(layer "F.Cu")
		(net "M_A_CPU0_SB_DQ<5>")
	)
	(segment
		(start 319.107566 -278.10079)
		(end 318.935608 -278.272748)
		(width 0.10668)
		(layer "F.Cu")
		(net "M_A_CPU0_SB_DQ<5>")
	)
	(segment
		(start 319.996566 -277.861522)
		(end 319.889886 -277.754842)
		(width 0.10668)
		(layer "F.Cu")
		(net "M_A_CPU0_SB_DQ<5>")
	)
	(segment
		(start 318.543178 -278.665178)
		(end 318.37122 -278.837136)
		(width 0.10668)
		(layer "F.Cu")
		(net "M_A_CPU0_SB_DQ<5>")
	)
	(segment
		(start 312.72734 -284.481016)
		(end 312.506868 -284.481016)
		(width 0.10668)
		(layer "F.Cu")
		(net "M_A_CPU0_SB_DQ<5>")
	)
	(segment
		(start 314.592462 -282.615894)
		(end 314.420504 -282.787852)
		(width 0.10668)
		(layer "F.Cu")
		(net "M_A_CPU0_SB_DQ<5>")
	)
	(segment
		(start 321.193668 -277.949152)
		(end 321.086988 -278.055832)
		(width 0.10668)
		(layer "F.Cu")
		(net "M_A_CPU0_SB_DQ<5>")
	)
	(segment
		(start 311.01284 -285.975044)
		(end 311.01284 -286.218122)
		(width 0.10668)
		(layer "F.Cu")
		(net "M_A_CPU0_SB_DQ<5>")
	)
	(segment
		(start 313.463686 -283.74467)
		(end 313.291728 -283.916628)
		(width 0.10668)
		(layer "F.Cu")
		(net "M_A_CPU0_SB_DQ<5>")
	)
	(segment
		(start 317.806832 -279.401524)
		(end 317.58636 -279.401524)
		(width 0.10668)
		(layer "F.Cu")
		(net "M_A_CPU0_SB_DQ<5>")
	)
	(arc
		(start 327.40092 -278.192738)
		(mid 327.117964 -278.116561)
		(end 326.835008 -278.192738)
		(width 0.0762)
		(layer "F.Cu")
		(net "M_A_CPU0_SB_DQ<5>")
	)
	(arc
		(start 327.542652 -278.240236)
		(mid 327.473954 -278.22522)
		(end 327.409302 -278.197564)
		(width 0.0762)
		(layer "F.Cu")
		(net "M_A_CPU0_SB_DQ<5>")
	)
	(arc
		(start 326.460866 -278.192738)
		(mid 326.17791 -278.116561)
		(end 325.894954 -278.192738)
		(width 0.0762)
		(layer "F.Cu")
		(net "M_A_CPU0_SB_DQ<5>")
	)
	(arc
		(start 325.894954 -278.192738)
		(mid 325.819714 -278.226051)
		(end 325.738998 -278.242014)
		(width 0.0762)
		(layer "F.Cu")
		(net "M_A_CPU0_SB_DQ<5>")
	)
	(arc
		(start 326.826626 -278.197564)
		(mid 326.643118 -278.243058)
		(end 326.460866 -278.192738)
		(width 0.0762)
		(layer "F.Cu")
		(net "M_A_CPU0_SB_DQ<5>")
	)
	(arc
		(start 325.738998 -278.242014)
		(mid 325.723517 -278.24297)
		(end 325.70801 -278.243284)
		(width 0.0762)
		(layer "F.Cu")
		(net "M_A_CPU0_SB_DQ<5>")
	)
	(arc
		(start 327.688702 -278.04364)
		(mid 327.672777 -278.184332)
		(end 327.542652 -278.240236)
		(width 0.0762)
		(layer "F.Cu")
		(net "M_A_CPU0_SB_DQ<5>")
	)
	(segment
		(start 317.535052 -278.20366)
		(end 317.384176 -278.20366)
		(width 0.10668)
		(layer "F.Cu")
		(net "M_A_CPU0_SB_DQ<4>")
	)
	(segment
		(start 314.430918 -281.156918)
		(end 314.430664 -281.307794)
		(width 0.10668)
		(layer "F.Cu")
		(net "M_A_CPU0_SB_DQ<4>")
	)
	(segment
		(start 313.23788 -282.786582)
		(end 313.087512 -282.786328)
		(width 0.10668)
		(layer "F.Cu")
		(net "M_A_CPU0_SB_DQ<4>")
	)
	(segment
		(start 310.82996 -285.04388)
		(end 310.762396 -284.976316)
		(width 0.10668)
		(layer "F.Cu")
		(net "M_A_CPU0_SB_DQ<4>")
	)
	(segment
		(start 314.498228 -281.375358)
		(end 314.498228 -281.526234)
		(width 0.10668)
		(layer "F.Cu")
		(net "M_A_CPU0_SB_DQ<4>")
	)
	(segment
		(start 316.406276 -279.332436)
		(end 316.2554 -279.332436)
		(width 0.10668)
		(layer "F.Cu")
		(net "M_A_CPU0_SB_DQ<4>")
	)
	(segment
		(start 311.326784 -284.411928)
		(end 311.175908 -284.411928)
		(width 0.10668)
		(layer "F.Cu")
		(net "M_A_CPU0_SB_DQ<4>")
	)
	(segment
		(start 318.09944 -277.639272)
		(end 317.948564 -277.639272)
		(width 0.10668)
		(layer "F.Cu")
		(net "M_A_CPU0_SB_DQ<4>")
	)
	(segment
		(start 317.752984 -278.271478)
		(end 317.602616 -278.271224)
		(width 0.10668)
		(layer "F.Cu")
		(net "M_A_CPU0_SB_DQ<4>")
	)
	(segment
		(start 311.676288 -284.197298)
		(end 311.676288 -284.348174)
		(width 0.10668)
		(layer "F.Cu")
		(net "M_A_CPU0_SB_DQ<4>")
	)
	(segment
		(start 316.819788 -278.768048)
		(end 316.68847 -278.899366)
		(width 0.10668)
		(layer "F.Cu")
		(net "M_A_CPU0_SB_DQ<4>")
	)
	(segment
		(start 310.61152 -284.976316)
		(end 310.33212 -285.255716)
		(width 0.10668)
		(layer "F.Cu")
		(net "M_A_CPU0_SB_DQ<4>")
	)
	(segment
		(start 317.884556 -278.139906)
		(end 317.752984 -278.271478)
		(width 0.10668)
		(layer "F.Cu")
		(net "M_A_CPU0_SB_DQ<4>")
	)
	(segment
		(start 312.869072 -282.718764)
		(end 312.737754 -282.850082)
		(width 0.10668)
		(layer "F.Cu")
		(net "M_A_CPU0_SB_DQ<4>")
	)
	(segment
		(start 315.062616 -280.81097)
		(end 315.062616 -280.961846)
		(width 0.10668)
		(layer "F.Cu")
		(net "M_A_CPU0_SB_DQ<4>")
	)
	(segment
		(start 313.369452 -282.504134)
		(end 313.369452 -282.65501)
		(width 0.10668)
		(layer "F.Cu")
		(net "M_A_CPU0_SB_DQ<4>")
	)
	(segment
		(start 324.442582 -277.051516)
		(end 318.53632 -277.051516)
		(width 0.10668)
		(layer "F.Cu")
		(net "M_A_CPU0_SB_DQ<4>")
	)
	(segment
		(start 314.995306 -280.59253)
		(end 314.995052 -280.743406)
		(width 0.10668)
		(layer "F.Cu")
		(net "M_A_CPU0_SB_DQ<4>")
	)
	(segment
		(start 312.523124 -283.350716)
		(end 312.45556 -283.283152)
		(width 0.10668)
		(layer "F.Cu")
		(net "M_A_CPU0_SB_DQ<4>")
	)
	(segment
		(start 311.1119 -284.761686)
		(end 311.1119 -284.912562)
		(width 0.10668)
		(layer "F.Cu")
		(net "M_A_CPU0_SB_DQ<4>")
	)
	(segment
		(start 315.55944 -280.179018)
		(end 315.627004 -280.246582)
		(width 0.10668)
		(layer "F.Cu")
		(net "M_A_CPU0_SB_DQ<4>")
	)
	(segment
		(start 316.75578 -279.268682)
		(end 316.624208 -279.400254)
		(width 0.10668)
		(layer "F.Cu")
		(net "M_A_CPU0_SB_DQ<4>")
	)
	(segment
		(start 314.148724 -281.589988)
		(end 313.997848 -281.589988)
		(width 0.10668)
		(layer "F.Cu")
		(net "M_A_CPU0_SB_DQ<4>")
	)
	(segment
		(start 318.53632 -277.051516)
		(end 318.381634 -277.206202)
		(width 0.10668)
		(layer "F.Cu")
		(net "M_A_CPU0_SB_DQ<4>")
	)
	(segment
		(start 314.780676 -281.093164)
		(end 314.713112 -281.0256)
		(width 0.10668)
		(layer "F.Cu")
		(net "M_A_CPU0_SB_DQ<4>")
	)
	(segment
		(start 315.2775 -280.461212)
		(end 315.126624 -280.461212)
		(width 0.10668)
		(layer "F.Cu")
		(net "M_A_CPU0_SB_DQ<4>")
	)
	(segment
		(start 313.301888 -282.43657)
		(end 313.369452 -282.504134)
		(width 0.10668)
		(layer "F.Cu")
		(net "M_A_CPU0_SB_DQ<4>")
	)
	(segment
		(start 316.970664 -278.768048)
		(end 316.819788 -278.768048)
		(width 0.10668)
		(layer "F.Cu")
		(net "M_A_CPU0_SB_DQ<4>")
	)
	(segment
		(start 317.816992 -277.921466)
		(end 317.884556 -277.98903)
		(width 0.10668)
		(layer "F.Cu")
		(net "M_A_CPU0_SB_DQ<4>")
	)
	(segment
		(start 313.802268 -282.222194)
		(end 313.6519 -282.22194)
		(width 0.10668)
		(layer "F.Cu")
		(net "M_A_CPU0_SB_DQ<4>")
	)
	(segment
		(start 315.345064 -280.528776)
		(end 315.2775 -280.461212)
		(width 0.10668)
		(layer "F.Cu")
		(net "M_A_CPU0_SB_DQ<4>")
	)
	(segment
		(start 313.369452 -282.65501)
		(end 313.23788 -282.786582)
		(width 0.10668)
		(layer "F.Cu")
		(net "M_A_CPU0_SB_DQ<4>")
	)
	(segment
		(start 314.931044 -281.093418)
		(end 314.780676 -281.093164)
		(width 0.10668)
		(layer "F.Cu")
		(net "M_A_CPU0_SB_DQ<4>")
	)
	(segment
		(start 318.38138 -277.357078)
		(end 318.448944 -277.424642)
		(width 0.10668)
		(layer "F.Cu")
		(net "M_A_CPU0_SB_DQ<4>")
	)
	(segment
		(start 311.175908 -284.411928)
		(end 311.04459 -284.543246)
		(width 0.10668)
		(layer "F.Cu")
		(net "M_A_CPU0_SB_DQ<4>")
	)
	(segment
		(start 315.909452 -279.964388)
		(end 315.841888 -279.896824)
		(width 0.10668)
		(layer "F.Cu")
		(net "M_A_CPU0_SB_DQ<4>")
	)
	(segment
		(start 318.448944 -277.424642)
		(end 318.448944 -277.575518)
		(width 0.10668)
		(layer "F.Cu")
		(net "M_A_CPU0_SB_DQ<4>")
	)
	(segment
		(start 314.562236 -281.0256)
		(end 314.430918 -281.156918)
		(width 0.10668)
		(layer "F.Cu")
		(net "M_A_CPU0_SB_DQ<4>")
	)
	(segment
		(start 316.68847 -278.899366)
		(end 316.688216 -279.050242)
		(width 0.10668)
		(layer "F.Cu")
		(net "M_A_CPU0_SB_DQ<4>")
	)
	(segment
		(start 312.173366 -283.41447)
		(end 312.173112 -283.565346)
		(width 0.10668)
		(layer "F.Cu")
		(net "M_A_CPU0_SB_DQ<4>")
	)
	(segment
		(start 313.087512 -282.786328)
		(end 313.019948 -282.718764)
		(width 0.10668)
		(layer "F.Cu")
		(net "M_A_CPU0_SB_DQ<4>")
	)
	(segment
		(start 313.43346 -282.154376)
		(end 313.302142 -282.285694)
		(width 0.10668)
		(layer "F.Cu")
		(net "M_A_CPU0_SB_DQ<4>")
	)
	(segment
		(start 326.17791 -277.060152)
		(end 326.276208 -277.229316)
		(width 0.0762)
		(layer "F.Cu")
		(net "M_A_CPU0_SB_DQ<4>")
	)
	(segment
		(start 317.038228 -278.835612)
		(end 316.970664 -278.768048)
		(width 0.10668)
		(layer "F.Cu")
		(net "M_A_CPU0_SB_DQ<4>")
	)
	(segment
		(start 312.173112 -283.565346)
		(end 312.240676 -283.63291)
		(width 0.10668)
		(layer "F.Cu")
		(net "M_A_CPU0_SB_DQ<4>")
	)
	(segment
		(start 313.6519 -282.22194)
		(end 313.584336 -282.154376)
		(width 0.10668)
		(layer "F.Cu")
		(net "M_A_CPU0_SB_DQ<4>")
	)
	(segment
		(start 315.691012 -279.896824)
		(end 315.559694 -280.028142)
		(width 0.10668)
		(layer "F.Cu")
		(net "M_A_CPU0_SB_DQ<4>")
	)
	(segment
		(start 317.252604 -278.485854)
		(end 317.320168 -278.553418)
		(width 0.10668)
		(layer "F.Cu")
		(net "M_A_CPU0_SB_DQ<4>")
	)
	(segment
		(start 318.448944 -277.575518)
		(end 318.317372 -277.70709)
		(width 0.10668)
		(layer "F.Cu")
		(net "M_A_CPU0_SB_DQ<4>")
	)
	(segment
		(start 325.999348 -277.387558)
		(end 325.990966 -277.382732)
		(width 0.0762)
		(layer "F.Cu")
		(net "M_A_CPU0_SB_DQ<4>")
	)
	(segment
		(start 324.549008 -277.051516)
		(end 324.442582 -277.051516)
		(width 0.0762)
		(layer "F.Cu")
		(net "M_A_CPU0_SB_DQ<4>")
	)
	(segment
		(start 311.891172 -283.84754)
		(end 311.740296 -283.84754)
		(width 0.10668)
		(layer "F.Cu")
		(net "M_A_CPU0_SB_DQ<4>")
	)
	(segment
		(start 312.109104 -283.915358)
		(end 311.958736 -283.915104)
		(width 0.10668)
		(layer "F.Cu")
		(net "M_A_CPU0_SB_DQ<4>")
	)
	(segment
		(start 325.70801 -277.306532)
		(end 324.804024 -277.306532)
		(width 0.0762)
		(layer "F.Cu")
		(net "M_A_CPU0_SB_DQ<4>")
	)
	(segment
		(start 311.544716 -284.479746)
		(end 311.394348 -284.479492)
		(width 0.10668)
		(layer "F.Cu")
		(net "M_A_CPU0_SB_DQ<4>")
	)
	(segment
		(start 316.47384 -279.4)
		(end 316.406276 -279.332436)
		(width 0.10668)
		(layer "F.Cu")
		(net "M_A_CPU0_SB_DQ<4>")
	)
	(segment
		(start 318.381634 -277.206202)
		(end 318.38138 -277.357078)
		(width 0.10668)
		(layer "F.Cu")
		(net "M_A_CPU0_SB_DQ<4>")
	)
	(segment
		(start 312.304684 -283.283152)
		(end 312.173366 -283.41447)
		(width 0.10668)
		(layer "F.Cu")
		(net "M_A_CPU0_SB_DQ<4>")
	)
	(segment
		(start 314.216288 -281.657552)
		(end 314.148724 -281.589988)
		(width 0.10668)
		(layer "F.Cu")
		(net "M_A_CPU0_SB_DQ<4>")
	)
	(segment
		(start 315.841888 -279.896824)
		(end 315.691012 -279.896824)
		(width 0.10668)
		(layer "F.Cu")
		(net "M_A_CPU0_SB_DQ<4>")
	)
	(segment
		(start 313.93384 -281.939746)
		(end 313.93384 -282.090622)
		(width 0.10668)
		(layer "F.Cu")
		(net "M_A_CPU0_SB_DQ<4>")
	)
	(segment
		(start 311.044336 -284.694122)
		(end 311.1119 -284.761686)
		(width 0.10668)
		(layer "F.Cu")
		(net "M_A_CPU0_SB_DQ<4>")
	)
	(segment
		(start 312.673492 -283.35097)
		(end 312.523124 -283.350716)
		(width 0.10668)
		(layer "F.Cu")
		(net "M_A_CPU0_SB_DQ<4>")
	)
	(segment
		(start 312.240676 -283.63291)
		(end 312.240676 -283.783786)
		(width 0.10668)
		(layer "F.Cu")
		(net "M_A_CPU0_SB_DQ<4>")
	)
	(segment
		(start 315.495432 -280.52903)
		(end 315.345064 -280.528776)
		(width 0.10668)
		(layer "F.Cu")
		(net "M_A_CPU0_SB_DQ<4>")
	)
	(segment
		(start 315.627004 -280.246582)
		(end 315.627004 -280.397458)
		(width 0.10668)
		(layer "F.Cu")
		(net "M_A_CPU0_SB_DQ<4>")
	)
	(segment
		(start 317.188596 -278.835866)
		(end 317.038228 -278.835612)
		(width 0.10668)
		(layer "F.Cu")
		(net "M_A_CPU0_SB_DQ<4>")
	)
	(segment
		(start 317.384176 -278.20366)
		(end 317.252858 -278.334978)
		(width 0.10668)
		(layer "F.Cu")
		(net "M_A_CPU0_SB_DQ<4>")
	)
	(segment
		(start 312.45556 -283.283152)
		(end 312.304684 -283.283152)
		(width 0.10668)
		(layer "F.Cu")
		(net "M_A_CPU0_SB_DQ<4>")
	)
	(segment
		(start 311.394348 -284.479492)
		(end 311.326784 -284.411928)
		(width 0.10668)
		(layer "F.Cu")
		(net "M_A_CPU0_SB_DQ<4>")
	)
	(segment
		(start 313.93384 -282.090622)
		(end 313.802268 -282.222194)
		(width 0.10668)
		(layer "F.Cu")
		(net "M_A_CPU0_SB_DQ<4>")
	)
	(segment
		(start 313.302142 -282.285694)
		(end 313.301888 -282.43657)
		(width 0.10668)
		(layer "F.Cu")
		(net "M_A_CPU0_SB_DQ<4>")
	)
	(segment
		(start 311.04459 -284.543246)
		(end 311.044336 -284.694122)
		(width 0.10668)
		(layer "F.Cu")
		(net "M_A_CPU0_SB_DQ<4>")
	)
	(segment
		(start 317.948564 -277.639272)
		(end 317.817246 -277.77059)
		(width 0.10668)
		(layer "F.Cu")
		(net "M_A_CPU0_SB_DQ<4>")
	)
	(segment
		(start 316.191392 -279.83307)
		(end 316.05982 -279.964642)
		(width 0.10668)
		(layer "F.Cu")
		(net "M_A_CPU0_SB_DQ<4>")
	)
	(segment
		(start 316.124082 -279.463754)
		(end 316.123828 -279.61463)
		(width 0.10668)
		(layer "F.Cu")
		(net "M_A_CPU0_SB_DQ<4>")
	)
	(segment
		(start 312.737754 -282.850082)
		(end 312.7375 -283.000958)
		(width 0.10668)
		(layer "F.Cu")
		(net "M_A_CPU0_SB_DQ<4>")
	)
	(segment
		(start 316.624208 -279.400254)
		(end 316.47384 -279.4)
		(width 0.10668)
		(layer "F.Cu")
		(net "M_A_CPU0_SB_DQ<4>")
	)
	(segment
		(start 316.191392 -279.682194)
		(end 316.191392 -279.83307)
		(width 0.10668)
		(layer "F.Cu")
		(net "M_A_CPU0_SB_DQ<4>")
	)
	(segment
		(start 317.252858 -278.334978)
		(end 317.252604 -278.485854)
		(width 0.10668)
		(layer "F.Cu")
		(net "M_A_CPU0_SB_DQ<4>")
	)
	(segment
		(start 317.320168 -278.704294)
		(end 317.188596 -278.835866)
		(width 0.10668)
		(layer "F.Cu")
		(net "M_A_CPU0_SB_DQ<4>")
	)
	(segment
		(start 311.740296 -283.84754)
		(end 311.608978 -283.978858)
		(width 0.10668)
		(layer "F.Cu")
		(net "M_A_CPU0_SB_DQ<4>")
	)
	(segment
		(start 314.713112 -281.0256)
		(end 314.562236 -281.0256)
		(width 0.10668)
		(layer "F.Cu")
		(net "M_A_CPU0_SB_DQ<4>")
	)
	(segment
		(start 311.608724 -284.129734)
		(end 311.676288 -284.197298)
		(width 0.10668)
		(layer "F.Cu")
		(net "M_A_CPU0_SB_DQ<4>")
	)
	(segment
		(start 313.86653 -281.721306)
		(end 313.866276 -281.872182)
		(width 0.10668)
		(layer "F.Cu")
		(net "M_A_CPU0_SB_DQ<4>")
	)
	(segment
		(start 316.75578 -279.117806)
		(end 316.75578 -279.268682)
		(width 0.10668)
		(layer "F.Cu")
		(net "M_A_CPU0_SB_DQ<4>")
	)
	(segment
		(start 315.627004 -280.397458)
		(end 315.495432 -280.52903)
		(width 0.10668)
		(layer "F.Cu")
		(net "M_A_CPU0_SB_DQ<4>")
	)
	(segment
		(start 317.817246 -277.77059)
		(end 317.816992 -277.921466)
		(width 0.10668)
		(layer "F.Cu")
		(net "M_A_CPU0_SB_DQ<4>")
	)
	(segment
		(start 316.2554 -279.332436)
		(end 316.124082 -279.463754)
		(width 0.10668)
		(layer "F.Cu")
		(net "M_A_CPU0_SB_DQ<4>")
	)
	(segment
		(start 312.805064 -283.219398)
		(end 312.673492 -283.35097)
		(width 0.10668)
		(layer "F.Cu")
		(net "M_A_CPU0_SB_DQ<4>")
	)
	(segment
		(start 314.995052 -280.743406)
		(end 315.062616 -280.81097)
		(width 0.10668)
		(layer "F.Cu")
		(net "M_A_CPU0_SB_DQ<4>")
	)
	(segment
		(start 311.1119 -284.912562)
		(end 310.980328 -285.044134)
		(width 0.10668)
		(layer "F.Cu")
		(net "M_A_CPU0_SB_DQ<4>")
	)
	(segment
		(start 312.7375 -283.000958)
		(end 312.805064 -283.068522)
		(width 0.10668)
		(layer "F.Cu")
		(net "M_A_CPU0_SB_DQ<4>")
	)
	(segment
		(start 311.676288 -284.348174)
		(end 311.544716 -284.479746)
		(width 0.10668)
		(layer "F.Cu")
		(net "M_A_CPU0_SB_DQ<4>")
	)
	(segment
		(start 316.123828 -279.61463)
		(end 316.191392 -279.682194)
		(width 0.10668)
		(layer "F.Cu")
		(net "M_A_CPU0_SB_DQ<4>")
	)
	(segment
		(start 313.866276 -281.872182)
		(end 313.93384 -281.939746)
		(width 0.10668)
		(layer "F.Cu")
		(net "M_A_CPU0_SB_DQ<4>")
	)
	(segment
		(start 318.167004 -277.706836)
		(end 318.09944 -277.639272)
		(width 0.10668)
		(layer "F.Cu")
		(net "M_A_CPU0_SB_DQ<4>")
	)
	(segment
		(start 310.33212 -285.255716)
		(end 310.33212 -285.93542)
		(width 0.10668)
		(layer "F.Cu")
		(net "M_A_CPU0_SB_DQ<4>")
	)
	(segment
		(start 314.430664 -281.307794)
		(end 314.498228 -281.375358)
		(width 0.10668)
		(layer "F.Cu")
		(net "M_A_CPU0_SB_DQ<4>")
	)
	(segment
		(start 315.559694 -280.028142)
		(end 315.55944 -280.179018)
		(width 0.10668)
		(layer "F.Cu")
		(net "M_A_CPU0_SB_DQ<4>")
	)
	(segment
		(start 317.602616 -278.271224)
		(end 317.535052 -278.20366)
		(width 0.10668)
		(layer "F.Cu")
		(net "M_A_CPU0_SB_DQ<4>")
	)
	(segment
		(start 313.997848 -281.589988)
		(end 313.86653 -281.721306)
		(width 0.10668)
		(layer "F.Cu")
		(net "M_A_CPU0_SB_DQ<4>")
	)
	(segment
		(start 318.317372 -277.70709)
		(end 318.167004 -277.706836)
		(width 0.10668)
		(layer "F.Cu")
		(net "M_A_CPU0_SB_DQ<4>")
	)
	(segment
		(start 311.958736 -283.915104)
		(end 311.891172 -283.84754)
		(width 0.10668)
		(layer "F.Cu")
		(net "M_A_CPU0_SB_DQ<4>")
	)
	(segment
		(start 310.980328 -285.044134)
		(end 310.82996 -285.04388)
		(width 0.10668)
		(layer "F.Cu")
		(net "M_A_CPU0_SB_DQ<4>")
	)
	(segment
		(start 314.498228 -281.526234)
		(end 314.366656 -281.657806)
		(width 0.10668)
		(layer "F.Cu")
		(net "M_A_CPU0_SB_DQ<4>")
	)
	(segment
		(start 315.062616 -280.961846)
		(end 314.931044 -281.093418)
		(width 0.10668)
		(layer "F.Cu")
		(net "M_A_CPU0_SB_DQ<4>")
	)
	(segment
		(start 314.366656 -281.657806)
		(end 314.216288 -281.657552)
		(width 0.10668)
		(layer "F.Cu")
		(net "M_A_CPU0_SB_DQ<4>")
	)
	(segment
		(start 313.019948 -282.718764)
		(end 312.869072 -282.718764)
		(width 0.10668)
		(layer "F.Cu")
		(net "M_A_CPU0_SB_DQ<4>")
	)
	(segment
		(start 316.05982 -279.964642)
		(end 315.909452 -279.964388)
		(width 0.10668)
		(layer "F.Cu")
		(net "M_A_CPU0_SB_DQ<4>")
	)
	(segment
		(start 308.832504 -287.435036)
		(end 307.368194 -287.435036)
		(width 0.10668)
		(layer "F.Cu")
		(net "M_A_CPU0_SB_DQ<4>")
	)
	(segment
		(start 310.762396 -284.976316)
		(end 310.61152 -284.976316)
		(width 0.10668)
		(layer "F.Cu")
		(net "M_A_CPU0_SB_DQ<4>")
	)
	(segment
		(start 316.688216 -279.050242)
		(end 316.75578 -279.117806)
		(width 0.10668)
		(layer "F.Cu")
		(net "M_A_CPU0_SB_DQ<4>")
	)
	(segment
		(start 312.240676 -283.783786)
		(end 312.109104 -283.915358)
		(width 0.10668)
		(layer "F.Cu")
		(net "M_A_CPU0_SB_DQ<4>")
	)
	(segment
		(start 317.320168 -278.553418)
		(end 317.320168 -278.704294)
		(width 0.10668)
		(layer "F.Cu")
		(net "M_A_CPU0_SB_DQ<4>")
	)
	(segment
		(start 313.584336 -282.154376)
		(end 313.43346 -282.154376)
		(width 0.10668)
		(layer "F.Cu")
		(net "M_A_CPU0_SB_DQ<4>")
	)
	(segment
		(start 324.804024 -277.306532)
		(end 324.549008 -277.051516)
		(width 0.0762)
		(layer "F.Cu")
		(net "M_A_CPU0_SB_DQ<4>")
	)
	(segment
		(start 311.608978 -283.978858)
		(end 311.608724 -284.129734)
		(width 0.10668)
		(layer "F.Cu")
		(net "M_A_CPU0_SB_DQ<4>")
	)
	(segment
		(start 317.884556 -277.98903)
		(end 317.884556 -278.139906)
		(width 0.10668)
		(layer "F.Cu")
		(net "M_A_CPU0_SB_DQ<4>")
	)
	(segment
		(start 312.805064 -283.068522)
		(end 312.805064 -283.219398)
		(width 0.10668)
		(layer "F.Cu")
		(net "M_A_CPU0_SB_DQ<4>")
	)
	(segment
		(start 310.33212 -285.93542)
		(end 308.832504 -287.435036)
		(width 0.10668)
		(layer "F.Cu")
		(net "M_A_CPU0_SB_DQ<4>")
	)
	(segment
		(start 315.126624 -280.461212)
		(end 314.995306 -280.59253)
		(width 0.10668)
		(layer "F.Cu")
		(net "M_A_CPU0_SB_DQ<4>")
	)
	(arc
		(start 326.276208 -277.229316)
		(mid 326.267615 -277.371195)
		(end 326.13854 -277.430992)
		(width 0.0762)
		(layer "F.Cu")
		(net "M_A_CPU0_SB_DQ<4>")
	)
	(arc
		(start 326.13854 -277.430992)
		(mid 326.066802 -277.41614)
		(end 325.999348 -277.387558)
		(width 0.0762)
		(layer "F.Cu")
		(net "M_A_CPU0_SB_DQ<4>")
	)
	(arc
		(start 325.990966 -277.382732)
		(mid 325.85453 -277.325907)
		(end 325.70801 -277.306532)
		(width 0.0762)
		(layer "F.Cu")
		(net "M_A_CPU0_SB_DQ<4>")
	)
	(segment
		(start 308.761892 -282.739846)
		(end 308.762146 -282.890214)
		(width 0.10668)
		(layer "F.Cu")
		(net "M_A_CPU0_SB_DQ<3>")
	)
	(segment
		(start 309.184802 -282.748736)
		(end 309.04434 -282.608274)
		(width 0.10668)
		(layer "F.Cu")
		(net "M_A_CPU0_SB_DQ<3>")
	)
	(segment
		(start 304.889916 -283.811218)
		(end 304.78857 -283.709872)
		(width 0.101346)
		(layer "F.Cu")
		(net "M_A_CPU0_SB_DQ<3>")
	)
	(segment
		(start 304.39487 -284.034992)
		(end 303.268126 -284.034992)
		(width 0.101346)
		(layer "F.Cu")
		(net "M_A_CPU0_SB_DQ<3>")
	)
	(segment
		(start 317.19393 -274.89023)
		(end 309.335678 -282.748482)
		(width 0.10668)
		(layer "F.Cu")
		(net "M_A_CPU0_SB_DQ<3>")
	)
	(segment
		(start 308.654196 -283.429964)
		(end 308.47411 -283.61005)
		(width 0.101346)
		(layer "F.Cu")
		(net "M_A_CPU0_SB_DQ<3>")
	)
	(segment
		(start 305.312572 -284.034992)
		(end 304.991262 -284.034992)
		(width 0.101346)
		(layer "F.Cu")
		(net "M_A_CPU0_SB_DQ<3>")
	)
	(segment
		(start 304.496216 -283.933646)
		(end 304.39487 -284.034992)
		(width 0.101346)
		(layer "F.Cu")
		(net "M_A_CPU0_SB_DQ<3>")
	)
	(segment
		(start 308.47411 -283.61005)
		(end 305.737514 -283.61005)
		(width 0.101346)
		(layer "F.Cu")
		(net "M_A_CPU0_SB_DQ<3>")
	)
	(segment
		(start 304.597562 -283.709872)
		(end 304.496216 -283.811218)
		(width 0.101346)
		(layer "F.Cu")
		(net "M_A_CPU0_SB_DQ<3>")
	)
	(segment
		(start 305.737514 -283.61005)
		(end 305.312572 -284.034992)
		(width 0.101346)
		(layer "F.Cu")
		(net "M_A_CPU0_SB_DQ<3>")
	)
	(segment
		(start 324.628256 -275.19376)
		(end 324.324726 -274.89023)
		(width 0.0762)
		(layer "F.Cu")
		(net "M_A_CPU0_SB_DQ<3>")
	)
	(segment
		(start 308.762146 -282.890214)
		(end 308.902608 -283.030676)
		(width 0.10668)
		(layer "F.Cu")
		(net "M_A_CPU0_SB_DQ<3>")
	)
	(segment
		(start 309.04434 -282.608274)
		(end 308.893464 -282.608274)
		(width 0.10668)
		(layer "F.Cu")
		(net "M_A_CPU0_SB_DQ<3>")
	)
	(segment
		(start 304.496216 -283.811218)
		(end 304.496216 -283.933646)
		(width 0.101346)
		(layer "F.Cu")
		(net "M_A_CPU0_SB_DQ<3>")
	)
	(segment
		(start 308.893464 -282.608274)
		(end 308.761892 -282.739846)
		(width 0.10668)
		(layer "F.Cu")
		(net "M_A_CPU0_SB_DQ<3>")
	)
	(segment
		(start 325.999348 -275.112734)
		(end 325.990966 -275.11756)
		(width 0.0762)
		(layer "F.Cu")
		(net "M_A_CPU0_SB_DQ<3>")
	)
	(segment
		(start 304.889916 -283.933646)
		(end 304.889916 -283.811218)
		(width 0.101346)
		(layer "F.Cu")
		(net "M_A_CPU0_SB_DQ<3>")
	)
	(segment
		(start 304.78857 -283.709872)
		(end 304.597562 -283.709872)
		(width 0.101346)
		(layer "F.Cu")
		(net "M_A_CPU0_SB_DQ<3>")
	)
	(segment
		(start 308.902608 -283.030676)
		(end 308.902608 -283.181552)
		(width 0.10668)
		(layer "F.Cu")
		(net "M_A_CPU0_SB_DQ<3>")
	)
	(segment
		(start 304.991262 -284.034992)
		(end 304.889916 -283.933646)
		(width 0.101346)
		(layer "F.Cu")
		(net "M_A_CPU0_SB_DQ<3>")
	)
	(segment
		(start 325.708264 -275.19376)
		(end 324.628256 -275.19376)
		(width 0.0762)
		(layer "F.Cu")
		(net "M_A_CPU0_SB_DQ<3>")
	)
	(segment
		(start 309.335678 -282.748482)
		(end 309.184802 -282.748736)
		(width 0.10668)
		(layer "F.Cu")
		(net "M_A_CPU0_SB_DQ<3>")
	)
	(segment
		(start 308.902608 -283.181552)
		(end 308.654196 -283.429964)
		(width 0.10668)
		(layer "F.Cu")
		(net "M_A_CPU0_SB_DQ<3>")
	)
	(segment
		(start 324.324726 -274.89023)
		(end 317.19393 -274.89023)
		(width 0.10668)
		(layer "F.Cu")
		(net "M_A_CPU0_SB_DQ<3>")
	)
	(arc
		(start 326.93102 -275.11756)
		(mid 326.648064 -275.193737)
		(end 326.365108 -275.11756)
		(width 0.0762)
		(layer "F.Cu")
		(net "M_A_CPU0_SB_DQ<3>")
	)
	(arc
		(start 327.304908 -275.11756)
		(mid 327.117964 -275.067305)
		(end 326.93102 -275.11756)
		(width 0.0762)
		(layer "F.Cu")
		(net "M_A_CPU0_SB_DQ<3>")
	)
	(arc
		(start 325.990966 -275.11756)
		(mid 325.877242 -275.167861)
		(end 325.755254 -275.191982)
		(width 0.0762)
		(layer "F.Cu")
		(net "M_A_CPU0_SB_DQ<3>")
	)
	(arc
		(start 327.53808 -275.191728)
		(mid 327.417431 -275.167427)
		(end 327.304908 -275.11756)
		(width 0.0762)
		(layer "F.Cu")
		(net "M_A_CPU0_SB_DQ<3>")
	)
	(arc
		(start 328.058018 -275.44014)
		(mid 327.820406 -275.269152)
		(end 327.53808 -275.191728)
		(width 0.0762)
		(layer "F.Cu")
		(net "M_A_CPU0_SB_DQ<3>")
	)
	(arc
		(start 325.755254 -275.191982)
		(mid 325.731777 -275.193358)
		(end 325.708264 -275.19376)
		(width 0.0762)
		(layer "F.Cu")
		(net "M_A_CPU0_SB_DQ<3>")
	)
	(arc
		(start 326.365108 -275.11756)
		(mid 326.182857 -275.06721)
		(end 325.999348 -275.112734)
		(width 0.0762)
		(layer "F.Cu")
		(net "M_A_CPU0_SB_DQ<3>")
	)
	(segment
		(start 317.6905 -308.647084)
		(end 317.5254 -308.647084)
		(width 0.10668)
		(layer "F.Cu")
		(net "M_A_CPU0_SB_DQ<31>")
	)
	(segment
		(start 317.544704 -309.230776)
		(end 317.42761 -309.34787)
		(width 0.10668)
		(layer "F.Cu")
		(net "M_A_CPU0_SB_DQ<31>")
	)
	(segment
		(start 317.408306 -308.929278)
		(end 317.544704 -309.065676)
		(width 0.10668)
		(layer "F.Cu")
		(net "M_A_CPU0_SB_DQ<31>")
	)
	(segment
		(start 316.863222 -309.912258)
		(end 316.698122 -309.912258)
		(width 0.10668)
		(layer "F.Cu")
		(net "M_A_CPU0_SB_DQ<31>")
	)
	(segment
		(start 316.415928 -310.359552)
		(end 309.165498 -317.609982)
		(width 0.10668)
		(layer "F.Cu")
		(net "M_A_CPU0_SB_DQ<31>")
	)
	(segment
		(start 317.991998 -308.783482)
		(end 317.826898 -308.783482)
		(width 0.10668)
		(layer "F.Cu")
		(net "M_A_CPU0_SB_DQ<31>")
	)
	(segment
		(start 306.139342 -317.609982)
		(end 305.714146 -318.035178)
		(width 0.101346)
		(layer "F.Cu")
		(net "M_A_CPU0_SB_DQ<31>")
	)
	(segment
		(start 317.42761 -309.34787)
		(end 317.26251 -309.34787)
		(width 0.10668)
		(layer "F.Cu")
		(net "M_A_CPU0_SB_DQ<31>")
	)
	(segment
		(start 317.826898 -308.783482)
		(end 317.6905 -308.647084)
		(width 0.10668)
		(layer "F.Cu")
		(net "M_A_CPU0_SB_DQ<31>")
	)
	(segment
		(start 309.165498 -317.609982)
		(end 308.66588 -317.609982)
		(width 0.10668)
		(layer "F.Cu")
		(net "M_A_CPU0_SB_DQ<31>")
	)
	(segment
		(start 324.612254 -300.921674)
		(end 323.73443 -303.04105)
		(width 0.10668)
		(layer "F.Cu")
		(net "M_A_CPU0_SB_DQ<31>")
	)
	(segment
		(start 324.612254 -293.478458)
		(end 324.612254 -300.921674)
		(width 0.10668)
		(layer "F.Cu")
		(net "M_A_CPU0_SB_DQ<31>")
	)
	(segment
		(start 324.830694 -293.260018)
		(end 324.612254 -293.478458)
		(width 0.0762)
		(layer "F.Cu")
		(net "M_A_CPU0_SB_DQ<31>")
	)
	(segment
		(start 305.714146 -318.035178)
		(end 303.268126 -318.035178)
		(width 0.101346)
		(layer "F.Cu")
		(net "M_A_CPU0_SB_DQ<31>")
	)
	(segment
		(start 317.5254 -308.647084)
		(end 317.408306 -308.764178)
		(width 0.10668)
		(layer "F.Cu")
		(net "M_A_CPU0_SB_DQ<31>")
	)
	(segment
		(start 308.66588 -317.609982)
		(end 306.139342 -317.609982)
		(width 0.101346)
		(layer "F.Cu")
		(net "M_A_CPU0_SB_DQ<31>")
	)
	(segment
		(start 326.17791 -293.260018)
		(end 324.830694 -293.260018)
		(width 0.0762)
		(layer "F.Cu")
		(net "M_A_CPU0_SB_DQ<31>")
	)
	(segment
		(start 316.415928 -310.194452)
		(end 316.415928 -310.359552)
		(width 0.10668)
		(layer "F.Cu")
		(net "M_A_CPU0_SB_DQ<31>")
	)
	(segment
		(start 317.544704 -309.065676)
		(end 317.544704 -309.230776)
		(width 0.10668)
		(layer "F.Cu")
		(net "M_A_CPU0_SB_DQ<31>")
	)
	(segment
		(start 316.396624 -309.77586)
		(end 316.27953 -309.892954)
		(width 0.10668)
		(layer "F.Cu")
		(net "M_A_CPU0_SB_DQ<31>")
	)
	(segment
		(start 316.698122 -309.912258)
		(end 316.561724 -309.77586)
		(width 0.10668)
		(layer "F.Cu")
		(net "M_A_CPU0_SB_DQ<31>")
	)
	(segment
		(start 317.26251 -309.34787)
		(end 317.126112 -309.211472)
		(width 0.10668)
		(layer "F.Cu")
		(net "M_A_CPU0_SB_DQ<31>")
	)
	(segment
		(start 317.408306 -308.764178)
		(end 317.408306 -308.929278)
		(width 0.10668)
		(layer "F.Cu")
		(net "M_A_CPU0_SB_DQ<31>")
	)
	(segment
		(start 323.73443 -303.04105)
		(end 317.991998 -308.783482)
		(width 0.10668)
		(layer "F.Cu")
		(net "M_A_CPU0_SB_DQ<31>")
	)
	(segment
		(start 316.561724 -309.77586)
		(end 316.396624 -309.77586)
		(width 0.10668)
		(layer "F.Cu")
		(net "M_A_CPU0_SB_DQ<31>")
	)
	(segment
		(start 317.126112 -309.211472)
		(end 316.961012 -309.211472)
		(width 0.10668)
		(layer "F.Cu")
		(net "M_A_CPU0_SB_DQ<31>")
	)
	(segment
		(start 316.843918 -309.328566)
		(end 316.843918 -309.493666)
		(width 0.10668)
		(layer "F.Cu")
		(net "M_A_CPU0_SB_DQ<31>")
	)
	(segment
		(start 316.27953 -310.058054)
		(end 316.415928 -310.194452)
		(width 0.10668)
		(layer "F.Cu")
		(net "M_A_CPU0_SB_DQ<31>")
	)
	(segment
		(start 316.843918 -309.493666)
		(end 316.980316 -309.630064)
		(width 0.10668)
		(layer "F.Cu")
		(net "M_A_CPU0_SB_DQ<31>")
	)
	(segment
		(start 316.980316 -309.795164)
		(end 316.863222 -309.912258)
		(width 0.10668)
		(layer "F.Cu")
		(net "M_A_CPU0_SB_DQ<31>")
	)
	(segment
		(start 316.961012 -309.211472)
		(end 316.843918 -309.328566)
		(width 0.10668)
		(layer "F.Cu")
		(net "M_A_CPU0_SB_DQ<31>")
	)
	(segment
		(start 316.980316 -309.630064)
		(end 316.980316 -309.795164)
		(width 0.10668)
		(layer "F.Cu")
		(net "M_A_CPU0_SB_DQ<31>")
	)
	(segment
		(start 316.27953 -309.892954)
		(end 316.27953 -310.058054)
		(width 0.10668)
		(layer "F.Cu")
		(net "M_A_CPU0_SB_DQ<31>")
	)
	(segment
		(start 324.631558 -292.076886)
		(end 323.903594 -292.80485)
		(width 0.0762)
		(layer "F.Cu")
		(net "M_A_CPU0_SB_DQ<30>")
	)
	(segment
		(start 313.11215 -312.412634)
		(end 312.995056 -312.529728)
		(width 0.10668)
		(layer "F.Cu")
		(net "M_A_CPU0_SB_DQ<30>")
	)
	(segment
		(start 312.856626 -311.82691)
		(end 312.856626 -311.99201)
		(width 0.10668)
		(layer "F.Cu")
		(net "M_A_CPU0_SB_DQ<30>")
	)
	(segment
		(start 325.70801 -292.076886)
		(end 324.631558 -292.076886)
		(width 0.0762)
		(layer "F.Cu")
		(net "M_A_CPU0_SB_DQ<30>")
	)
	(segment
		(start 312.24093 -312.442606)
		(end 312.24093 -313.571382)
		(width 0.10668)
		(layer "F.Cu")
		(net "M_A_CPU0_SB_DQ<30>")
	)
	(segment
		(start 305.714146 -316.335156)
		(end 303.268126 -316.335156)
		(width 0.101346)
		(layer "F.Cu")
		(net "M_A_CPU0_SB_DQ<30>")
	)
	(segment
		(start 312.995056 -312.529728)
		(end 312.829956 -312.529728)
		(width 0.10668)
		(layer "F.Cu")
		(net "M_A_CPU0_SB_DQ<30>")
	)
	(segment
		(start 312.24093 -313.571382)
		(end 309.902352 -315.90996)
		(width 0.10668)
		(layer "F.Cu")
		(net "M_A_CPU0_SB_DQ<30>")
	)
	(segment
		(start 312.409332 -312.274204)
		(end 312.24093 -312.442606)
		(width 0.10668)
		(layer "F.Cu")
		(net "M_A_CPU0_SB_DQ<30>")
	)
	(segment
		(start 312.856626 -311.99201)
		(end 313.11215 -312.247534)
		(width 0.10668)
		(layer "F.Cu")
		(net "M_A_CPU0_SB_DQ<30>")
	)
	(segment
		(start 306.139342 -315.90996)
		(end 305.714146 -316.335156)
		(width 0.101346)
		(layer "F.Cu")
		(net "M_A_CPU0_SB_DQ<30>")
	)
	(segment
		(start 309.902352 -315.90996)
		(end 308.66588 -315.90996)
		(width 0.10668)
		(layer "F.Cu")
		(net "M_A_CPU0_SB_DQ<30>")
	)
	(segment
		(start 323.903594 -292.80485)
		(end 323.903594 -300.779942)
		(width 0.10668)
		(layer "F.Cu")
		(net "M_A_CPU0_SB_DQ<30>")
	)
	(segment
		(start 313.11215 -312.247534)
		(end 313.11215 -312.412634)
		(width 0.10668)
		(layer "F.Cu")
		(net "M_A_CPU0_SB_DQ<30>")
	)
	(segment
		(start 312.829956 -312.529728)
		(end 312.574432 -312.274204)
		(width 0.10668)
		(layer "F.Cu")
		(net "M_A_CPU0_SB_DQ<30>")
	)
	(segment
		(start 308.66588 -315.90996)
		(end 306.139342 -315.90996)
		(width 0.101346)
		(layer "F.Cu")
		(net "M_A_CPU0_SB_DQ<30>")
	)
	(segment
		(start 312.574432 -312.274204)
		(end 312.409332 -312.274204)
		(width 0.10668)
		(layer "F.Cu")
		(net "M_A_CPU0_SB_DQ<30>")
	)
	(segment
		(start 323.903594 -300.779942)
		(end 312.856626 -311.82691)
		(width 0.10668)
		(layer "F.Cu")
		(net "M_A_CPU0_SB_DQ<30>")
	)
	(arc
		(start 326.648064 -292.450012)
		(mid 326.405747 -292.280292)
		(end 326.12076 -292.200838)
		(width 0.0762)
		(layer "F.Cu")
		(net "M_A_CPU0_SB_DQ<30>")
	)
	(arc
		(start 326.12076 -292.200838)
		(mid 326.003947 -292.176162)
		(end 325.894954 -292.127432)
		(width 0.0762)
		(layer "F.Cu")
		(net "M_A_CPU0_SB_DQ<30>")
	)
	(arc
		(start 325.894954 -292.127432)
		(mid 325.804821 -292.089812)
		(end 325.70801 -292.076886)
		(width 0.0762)
		(layer "F.Cu")
		(net "M_A_CPU0_SB_DQ<30>")
	)
	(segment
		(start 325.70801 -274.257008)
		(end 324.221094 -274.257008)
		(width 0.0762)
		(layer "F.Cu")
		(net "M_A_CPU0_SB_DQ<2>")
	)
	(segment
		(start 304.803302 -283.12237)
		(end 304.686462 -283.23921)
		(width 0.101346)
		(layer "F.Cu")
		(net "M_A_CPU0_SB_DQ<2>")
	)
	(segment
		(start 304.803302 -282.147772)
		(end 304.803302 -283.12237)
		(width 0.101346)
		(layer "F.Cu")
		(net "M_A_CPU0_SB_DQ<2>")
	)
	(segment
		(start 304.920142 -282.030932)
		(end 304.803302 -282.147772)
		(width 0.101346)
		(layer "F.Cu")
		(net "M_A_CPU0_SB_DQ<2>")
	)
	(segment
		(start 323.901054 -274.20951)
		(end 316.462918 -274.20951)
		(width 0.10668)
		(layer "F.Cu")
		(net "M_A_CPU0_SB_DQ<2>")
	)
	(segment
		(start 304.404268 -282.45181)
		(end 304.287428 -282.33497)
		(width 0.101346)
		(layer "F.Cu")
		(net "M_A_CPU0_SB_DQ<2>")
	)
	(segment
		(start 304.521108 -283.23921)
		(end 304.404268 -283.12237)
		(width 0.101346)
		(layer "F.Cu")
		(net "M_A_CPU0_SB_DQ<2>")
	)
	(segment
		(start 305.71821 -282.33497)
		(end 305.60137 -282.45181)
		(width 0.101346)
		(layer "F.Cu")
		(net "M_A_CPU0_SB_DQ<2>")
	)
	(segment
		(start 324.173596 -274.20951)
		(end 323.901054 -274.20951)
		(width 0.0762)
		(layer "F.Cu")
		(net "M_A_CPU0_SB_DQ<2>")
	)
	(segment
		(start 304.686462 -283.23921)
		(end 304.521108 -283.23921)
		(width 0.101346)
		(layer "F.Cu")
		(net "M_A_CPU0_SB_DQ<2>")
	)
	(segment
		(start 304.404268 -283.12237)
		(end 304.404268 -282.45181)
		(width 0.101346)
		(layer "F.Cu")
		(net "M_A_CPU0_SB_DQ<2>")
	)
	(segment
		(start 305.60137 -282.74391)
		(end 305.48453 -282.86075)
		(width 0.101346)
		(layer "F.Cu")
		(net "M_A_CPU0_SB_DQ<2>")
	)
	(segment
		(start 306.540916 -281.910028)
		(end 306.115974 -282.33497)
		(width 0.101346)
		(layer "F.Cu")
		(net "M_A_CPU0_SB_DQ<2>")
	)
	(segment
		(start 305.085496 -282.030932)
		(end 304.920142 -282.030932)
		(width 0.101346)
		(layer "F.Cu")
		(net "M_A_CPU0_SB_DQ<2>")
	)
	(segment
		(start 308.66588 -281.910028)
		(end 306.540916 -281.910028)
		(width 0.101346)
		(layer "F.Cu")
		(net "M_A_CPU0_SB_DQ<2>")
	)
	(segment
		(start 305.48453 -282.86075)
		(end 305.319176 -282.86075)
		(width 0.101346)
		(layer "F.Cu")
		(net "M_A_CPU0_SB_DQ<2>")
	)
	(segment
		(start 305.202336 -282.147772)
		(end 305.085496 -282.030932)
		(width 0.101346)
		(layer "F.Cu")
		(net "M_A_CPU0_SB_DQ<2>")
	)
	(segment
		(start 324.221094 -274.257008)
		(end 324.173596 -274.20951)
		(width 0.0762)
		(layer "F.Cu")
		(net "M_A_CPU0_SB_DQ<2>")
	)
	(segment
		(start 308.7624 -281.910028)
		(end 308.66588 -281.910028)
		(width 0.10668)
		(layer "F.Cu")
		(net "M_A_CPU0_SB_DQ<2>")
	)
	(segment
		(start 306.115974 -282.33497)
		(end 305.71821 -282.33497)
		(width 0.101346)
		(layer "F.Cu")
		(net "M_A_CPU0_SB_DQ<2>")
	)
	(segment
		(start 316.462918 -274.20951)
		(end 308.7624 -281.910028)
		(width 0.10668)
		(layer "F.Cu")
		(net "M_A_CPU0_SB_DQ<2>")
	)
	(segment
		(start 304.287428 -282.33497)
		(end 303.268126 -282.33497)
		(width 0.101346)
		(layer "F.Cu")
		(net "M_A_CPU0_SB_DQ<2>")
	)
	(segment
		(start 305.202336 -282.74391)
		(end 305.202336 -282.147772)
		(width 0.101346)
		(layer "F.Cu")
		(net "M_A_CPU0_SB_DQ<2>")
	)
	(segment
		(start 305.60137 -282.45181)
		(end 305.60137 -282.74391)
		(width 0.101346)
		(layer "F.Cu")
		(net "M_A_CPU0_SB_DQ<2>")
	)
	(segment
		(start 305.319176 -282.86075)
		(end 305.202336 -282.74391)
		(width 0.101346)
		(layer "F.Cu")
		(net "M_A_CPU0_SB_DQ<2>")
	)
	(arc
		(start 326.648064 -274.630134)
		(mid 326.405747 -274.460414)
		(end 326.12076 -274.38096)
		(width 0.0762)
		(layer "F.Cu")
		(net "M_A_CPU0_SB_DQ<2>")
	)
	(arc
		(start 326.12076 -274.38096)
		(mid 326.003947 -274.356284)
		(end 325.894954 -274.307554)
		(width 0.0762)
		(layer "F.Cu")
		(net "M_A_CPU0_SB_DQ<2>")
	)
	(arc
		(start 325.894954 -274.307554)
		(mid 325.804821 -274.269934)
		(end 325.70801 -274.257008)
		(width 0.0762)
		(layer "F.Cu")
		(net "M_A_CPU0_SB_DQ<2>")
	)
	(segment
		(start 324.475094 -292.85311)
		(end 324.243954 -293.08425)
		(width 0.0762)
		(layer "F.Cu")
		(net "M_A_CPU0_SB_DQ<29>")
	)
	(segment
		(start 315.61786 -310.510936)
		(end 315.61786 -310.676036)
		(width 0.10668)
		(layer "F.Cu")
		(net "M_A_CPU0_SB_DQ<29>")
	)
	(segment
		(start 313.90082 -311.4294)
		(end 313.73572 -311.4294)
		(width 0.10668)
		(layer "F.Cu")
		(net "M_A_CPU0_SB_DQ<29>")
	)
	(segment
		(start 314.465208 -311.2643)
		(end 315.335666 -310.393842)
		(width 0.10668)
		(layer "F.Cu")
		(net "M_A_CPU0_SB_DQ<29>")
	)
	(segment
		(start 315.500766 -310.393842)
		(end 315.61786 -310.510936)
		(width 0.10668)
		(layer "F.Cu")
		(net "M_A_CPU0_SB_DQ<29>")
	)
	(segment
		(start 327.585324 -292.451028)
		(end 327.10501 -292.77437)
		(width 0.0762)
		(layer "F.Cu")
		(net "M_A_CPU0_SB_DQ<29>")
	)
	(segment
		(start 324.243954 -293.08425)
		(end 324.243954 -300.921166)
		(width 0.10668)
		(layer "F.Cu")
		(net "M_A_CPU0_SB_DQ<29>")
	)
	(segment
		(start 314.465208 -311.828688)
		(end 314.300108 -311.828688)
		(width 0.10668)
		(layer "F.Cu")
		(net "M_A_CPU0_SB_DQ<29>")
	)
	(segment
		(start 313.45251 -312.841386)
		(end 309.108856 -317.18504)
		(width 0.10668)
		(layer "F.Cu")
		(net "M_A_CPU0_SB_DQ<29>")
	)
	(segment
		(start 324.243954 -300.921166)
		(end 314.183014 -310.982106)
		(width 0.10668)
		(layer "F.Cu")
		(net "M_A_CPU0_SB_DQ<29>")
	)
	(segment
		(start 327.587864 -292.450012)
		(end 327.585324 -292.451028)
		(width 0.0762)
		(layer "F.Cu")
		(net "M_A_CPU0_SB_DQ<29>")
	)
	(segment
		(start 314.183014 -310.982106)
		(end 314.183014 -311.147206)
		(width 0.10668)
		(layer "F.Cu")
		(net "M_A_CPU0_SB_DQ<29>")
	)
	(segment
		(start 315.61786 -310.676036)
		(end 314.465208 -311.828688)
		(width 0.10668)
		(layer "F.Cu")
		(net "M_A_CPU0_SB_DQ<29>")
	)
	(segment
		(start 313.73572 -311.4294)
		(end 313.45251 -311.71261)
		(width 0.10668)
		(layer "F.Cu")
		(net "M_A_CPU0_SB_DQ<29>")
	)
	(segment
		(start 326.8472 -292.85311)
		(end 324.475094 -292.85311)
		(width 0.0762)
		(layer "F.Cu")
		(net "M_A_CPU0_SB_DQ<29>")
	)
	(segment
		(start 314.300108 -311.2643)
		(end 314.465208 -311.2643)
		(width 0.10668)
		(layer "F.Cu")
		(net "M_A_CPU0_SB_DQ<29>")
	)
	(segment
		(start 315.335666 -310.393842)
		(end 315.500766 -310.393842)
		(width 0.10668)
		(layer "F.Cu")
		(net "M_A_CPU0_SB_DQ<29>")
	)
	(segment
		(start 313.45251 -311.71261)
		(end 313.45251 -312.841386)
		(width 0.10668)
		(layer "F.Cu")
		(net "M_A_CPU0_SB_DQ<29>")
	)
	(segment
		(start 309.108856 -317.18504)
		(end 307.368194 -317.18504)
		(width 0.10668)
		(layer "F.Cu")
		(net "M_A_CPU0_SB_DQ<29>")
	)
	(segment
		(start 314.300108 -311.828688)
		(end 313.90082 -311.4294)
		(width 0.10668)
		(layer "F.Cu")
		(net "M_A_CPU0_SB_DQ<29>")
	)
	(segment
		(start 314.183014 -311.147206)
		(end 314.300108 -311.2643)
		(width 0.10668)
		(layer "F.Cu")
		(net "M_A_CPU0_SB_DQ<29>")
	)
	(arc
		(start 327.10501 -292.77437)
		(mid 326.981975 -292.832943)
		(end 326.8472 -292.85311)
		(width 0.0762)
		(layer "F.Cu")
		(net "M_A_CPU0_SB_DQ<29>")
	)
	(segment
		(start 310.249824 -314.516516)
		(end 311.618376 -313.147964)
		(width 0.10668)
		(layer "F.Cu")
		(net "M_A_CPU0_SB_DQ<28>")
	)
	(segment
		(start 311.90057 -313.430158)
		(end 310.100472 -315.230256)
		(width 0.10668)
		(layer "F.Cu")
		(net "M_A_CPU0_SB_DQ<28>")
	)
	(segment
		(start 309.636668 -314.931552)
		(end 309.485792 -314.931552)
		(width 0.10668)
		(layer "F.Cu")
		(net "M_A_CPU0_SB_DQ<28>")
	)
	(segment
		(start 311.90057 -313.265058)
		(end 311.90057 -313.430158)
		(width 0.10668)
		(layer "F.Cu")
		(net "M_A_CPU0_SB_DQ<28>")
	)
	(segment
		(start 325.70801 -291.886386)
		(end 324.44055 -291.886386)
		(width 0.0762)
		(layer "F.Cu")
		(net "M_A_CPU0_SB_DQ<28>")
	)
	(segment
		(start 309.935372 -315.230256)
		(end 309.636668 -314.931552)
		(width 0.10668)
		(layer "F.Cu")
		(net "M_A_CPU0_SB_DQ<28>")
	)
	(segment
		(start 310.098948 -314.516516)
		(end 310.249824 -314.516516)
		(width 0.10668)
		(layer "F.Cu")
		(net "M_A_CPU0_SB_DQ<28>")
	)
	(segment
		(start 325.999348 -291.967412)
		(end 325.990966 -291.962586)
		(width 0.0762)
		(layer "F.Cu")
		(net "M_A_CPU0_SB_DQ<28>")
	)
	(segment
		(start 323.965316 -292.36162)
		(end 323.563234 -292.763702)
		(width 0.10668)
		(layer "F.Cu")
		(net "M_A_CPU0_SB_DQ<28>")
	)
	(segment
		(start 308.932326 -315.485018)
		(end 307.368194 -315.485018)
		(width 0.10668)
		(layer "F.Cu")
		(net "M_A_CPU0_SB_DQ<28>")
	)
	(segment
		(start 326.17791 -291.640006)
		(end 326.276208 -291.80917)
		(width 0.0762)
		(layer "F.Cu")
		(net "M_A_CPU0_SB_DQ<28>")
	)
	(segment
		(start 323.563234 -292.763702)
		(end 323.563234 -300.638718)
		(width 0.10668)
		(layer "F.Cu")
		(net "M_A_CPU0_SB_DQ<28>")
	)
	(segment
		(start 309.96763 -314.234322)
		(end 309.96763 -314.385198)
		(width 0.10668)
		(layer "F.Cu")
		(net "M_A_CPU0_SB_DQ<28>")
	)
	(segment
		(start 311.783476 -313.147964)
		(end 311.90057 -313.265058)
		(width 0.10668)
		(layer "F.Cu")
		(net "M_A_CPU0_SB_DQ<28>")
	)
	(segment
		(start 311.618376 -313.147964)
		(end 311.783476 -313.147964)
		(width 0.10668)
		(layer "F.Cu")
		(net "M_A_CPU0_SB_DQ<28>")
	)
	(segment
		(start 323.563234 -300.638718)
		(end 309.96763 -314.234322)
		(width 0.10668)
		(layer "F.Cu")
		(net "M_A_CPU0_SB_DQ<28>")
	)
	(segment
		(start 309.96763 -314.385198)
		(end 310.098948 -314.516516)
		(width 0.10668)
		(layer "F.Cu")
		(net "M_A_CPU0_SB_DQ<28>")
	)
	(segment
		(start 324.44055 -291.886386)
		(end 323.965316 -292.36162)
		(width 0.0762)
		(layer "F.Cu")
		(net "M_A_CPU0_SB_DQ<28>")
	)
	(segment
		(start 309.485792 -314.931552)
		(end 308.932326 -315.485018)
		(width 0.10668)
		(layer "F.Cu")
		(net "M_A_CPU0_SB_DQ<28>")
	)
	(segment
		(start 310.100472 -315.230256)
		(end 309.935372 -315.230256)
		(width 0.10668)
		(layer "F.Cu")
		(net "M_A_CPU0_SB_DQ<28>")
	)
	(arc
		(start 325.990966 -291.962586)
		(mid 325.85453 -291.905761)
		(end 325.70801 -291.886386)
		(width 0.0762)
		(layer "F.Cu")
		(net "M_A_CPU0_SB_DQ<28>")
	)
	(arc
		(start 326.13854 -292.010846)
		(mid 326.066802 -291.995994)
		(end 325.999348 -291.967412)
		(width 0.0762)
		(layer "F.Cu")
		(net "M_A_CPU0_SB_DQ<28>")
	)
	(arc
		(start 326.276208 -291.80917)
		(mid 326.267615 -291.951049)
		(end 326.13854 -292.010846)
		(width 0.0762)
		(layer "F.Cu")
		(net "M_A_CPU0_SB_DQ<28>")
	)
	(segment
		(start 310.783986 -310.204866)
		(end 310.783986 -310.48579)
		(width 0.10668)
		(layer "F.Cu")
		(net "M_A_CPU0_SB_DQ<27>")
	)
	(segment
		(start 311.348374 -309.640478)
		(end 311.348374 -309.921402)
		(width 0.10668)
		(layer "F.Cu")
		(net "M_A_CPU0_SB_DQ<27>")
	)
	(segment
		(start 310.925718 -310.063134)
		(end 310.783986 -310.204866)
		(width 0.10668)
		(layer "F.Cu")
		(net "M_A_CPU0_SB_DQ<27>")
	)
	(segment
		(start 311.77103 -309.498746)
		(end 311.490106 -309.498746)
		(width 0.10668)
		(layer "F.Cu")
		(net "M_A_CPU0_SB_DQ<27>")
	)
	(segment
		(start 310.642254 -310.627522)
		(end 310.36133 -310.627522)
		(width 0.10668)
		(layer "F.Cu")
		(net "M_A_CPU0_SB_DQ<27>")
	)
	(segment
		(start 313.041538 -307.947314)
		(end 313.041538 -308.228238)
		(width 0.10668)
		(layer "F.Cu")
		(net "M_A_CPU0_SB_DQ<27>")
	)
	(segment
		(start 310.077866 -311.19191)
		(end 309.796942 -311.19191)
		(width 0.10668)
		(layer "F.Cu")
		(net "M_A_CPU0_SB_DQ<27>")
	)
	(segment
		(start 309.796942 -311.19191)
		(end 309.32882 -311.660032)
		(width 0.10668)
		(layer "F.Cu")
		(net "M_A_CPU0_SB_DQ<27>")
	)
	(segment
		(start 311.206642 -310.063134)
		(end 310.925718 -310.063134)
		(width 0.10668)
		(layer "F.Cu")
		(net "M_A_CPU0_SB_DQ<27>")
	)
	(segment
		(start 323.926454 -289.60191)
		(end 323.621654 -289.60191)
		(width 0.10668)
		(layer "F.Cu")
		(net "M_A_CPU0_SB_DQ<27>")
	)
	(segment
		(start 312.47715 -308.511702)
		(end 312.47715 -308.792626)
		(width 0.10668)
		(layer "F.Cu")
		(net "M_A_CPU0_SB_DQ<27>")
	)
	(segment
		(start 311.912762 -309.07609)
		(end 311.912762 -309.357014)
		(width 0.10668)
		(layer "F.Cu")
		(net "M_A_CPU0_SB_DQ<27>")
	)
	(segment
		(start 312.899806 -308.36997)
		(end 312.618882 -308.36997)
		(width 0.10668)
		(layer "F.Cu")
		(net "M_A_CPU0_SB_DQ<27>")
	)
	(segment
		(start 324.104254 -289.60191)
		(end 323.926454 -289.60191)
		(width 0.0762)
		(layer "F.Cu")
		(net "M_A_CPU0_SB_DQ<27>")
	)
	(segment
		(start 311.490106 -309.498746)
		(end 311.348374 -309.640478)
		(width 0.10668)
		(layer "F.Cu")
		(net "M_A_CPU0_SB_DQ<27>")
	)
	(segment
		(start 313.041538 -308.228238)
		(end 312.899806 -308.36997)
		(width 0.10668)
		(layer "F.Cu")
		(net "M_A_CPU0_SB_DQ<27>")
	)
	(segment
		(start 312.054494 -308.934358)
		(end 311.912762 -309.07609)
		(width 0.10668)
		(layer "F.Cu")
		(net "M_A_CPU0_SB_DQ<27>")
	)
	(segment
		(start 309.32882 -311.660032)
		(end 308.66588 -311.660032)
		(width 0.10668)
		(layer "F.Cu")
		(net "M_A_CPU0_SB_DQ<27>")
	)
	(segment
		(start 321.31762 -291.905944)
		(end 321.31762 -298.542456)
		(width 0.10668)
		(layer "F.Cu")
		(net "M_A_CPU0_SB_DQ<27>")
	)
	(segment
		(start 310.219598 -310.769254)
		(end 310.219598 -311.050178)
		(width 0.10668)
		(layer "F.Cu")
		(net "M_A_CPU0_SB_DQ<27>")
	)
	(segment
		(start 310.219598 -311.050178)
		(end 310.077866 -311.19191)
		(width 0.10668)
		(layer "F.Cu")
		(net "M_A_CPU0_SB_DQ<27>")
	)
	(segment
		(start 311.912762 -309.357014)
		(end 311.77103 -309.498746)
		(width 0.10668)
		(layer "F.Cu")
		(net "M_A_CPU0_SB_DQ<27>")
	)
	(segment
		(start 312.335418 -308.934358)
		(end 312.054494 -308.934358)
		(width 0.10668)
		(layer "F.Cu")
		(net "M_A_CPU0_SB_DQ<27>")
	)
	(segment
		(start 321.31762 -298.542456)
		(end 315.890656 -303.96942)
		(width 0.10668)
		(layer "F.Cu")
		(net "M_A_CPU0_SB_DQ<27>")
	)
	(segment
		(start 310.36133 -310.627522)
		(end 310.219598 -310.769254)
		(width 0.10668)
		(layer "F.Cu")
		(net "M_A_CPU0_SB_DQ<27>")
	)
	(segment
		(start 312.618882 -308.36997)
		(end 312.47715 -308.511702)
		(width 0.10668)
		(layer "F.Cu")
		(net "M_A_CPU0_SB_DQ<27>")
	)
	(segment
		(start 310.783986 -310.48579)
		(end 310.642254 -310.627522)
		(width 0.10668)
		(layer "F.Cu")
		(net "M_A_CPU0_SB_DQ<27>")
	)
	(segment
		(start 324.275958 -289.773614)
		(end 324.104254 -289.60191)
		(width 0.0762)
		(layer "F.Cu")
		(net "M_A_CPU0_SB_DQ<27>")
	)
	(segment
		(start 323.621654 -289.60191)
		(end 321.31762 -291.905944)
		(width 0.10668)
		(layer "F.Cu")
		(net "M_A_CPU0_SB_DQ<27>")
	)
	(segment
		(start 325.708264 -289.773614)
		(end 324.275958 -289.773614)
		(width 0.0762)
		(layer "F.Cu")
		(net "M_A_CPU0_SB_DQ<27>")
	)
	(segment
		(start 305.348132 -311.660032)
		(end 304.92319 -312.084974)
		(width 0.101346)
		(layer "F.Cu")
		(net "M_A_CPU0_SB_DQ<27>")
	)
	(segment
		(start 315.890656 -303.96942)
		(end 315.890656 -305.098196)
		(width 0.10668)
		(layer "F.Cu")
		(net "M_A_CPU0_SB_DQ<27>")
	)
	(segment
		(start 325.999348 -289.692588)
		(end 325.990966 -289.697414)
		(width 0.0762)
		(layer "F.Cu")
		(net "M_A_CPU0_SB_DQ<27>")
	)
	(segment
		(start 311.348374 -309.921402)
		(end 311.206642 -310.063134)
		(width 0.10668)
		(layer "F.Cu")
		(net "M_A_CPU0_SB_DQ<27>")
	)
	(segment
		(start 304.92319 -312.084974)
		(end 303.268126 -312.084974)
		(width 0.101346)
		(layer "F.Cu")
		(net "M_A_CPU0_SB_DQ<27>")
	)
	(segment
		(start 315.890656 -305.098196)
		(end 313.041538 -307.947314)
		(width 0.10668)
		(layer "F.Cu")
		(net "M_A_CPU0_SB_DQ<27>")
	)
	(segment
		(start 312.47715 -308.792626)
		(end 312.335418 -308.934358)
		(width 0.10668)
		(layer "F.Cu")
		(net "M_A_CPU0_SB_DQ<27>")
	)
	(segment
		(start 308.66588 -311.660032)
		(end 305.348132 -311.660032)
		(width 0.101346)
		(layer "F.Cu")
		(net "M_A_CPU0_SB_DQ<27>")
	)
	(arc
		(start 327.304908 -289.697414)
		(mid 327.117964 -289.647159)
		(end 326.93102 -289.697414)
		(width 0.0762)
		(layer "F.Cu")
		(net "M_A_CPU0_SB_DQ<27>")
	)
	(arc
		(start 328.058018 -290.019994)
		(mid 327.820406 -289.849006)
		(end 327.53808 -289.771582)
		(width 0.0762)
		(layer "F.Cu")
		(net "M_A_CPU0_SB_DQ<27>")
	)
	(arc
		(start 325.755254 -289.771836)
		(mid 325.731777 -289.773212)
		(end 325.708264 -289.773614)
		(width 0.0762)
		(layer "F.Cu")
		(net "M_A_CPU0_SB_DQ<27>")
	)
	(arc
		(start 326.93102 -289.697414)
		(mid 326.648064 -289.773591)
		(end 326.365108 -289.697414)
		(width 0.0762)
		(layer "F.Cu")
		(net "M_A_CPU0_SB_DQ<27>")
	)
	(arc
		(start 326.365108 -289.697414)
		(mid 326.182857 -289.647064)
		(end 325.999348 -289.692588)
		(width 0.0762)
		(layer "F.Cu")
		(net "M_A_CPU0_SB_DQ<27>")
	)
	(arc
		(start 327.53808 -289.771582)
		(mid 327.417431 -289.747281)
		(end 327.304908 -289.697414)
		(width 0.0762)
		(layer "F.Cu")
		(net "M_A_CPU0_SB_DQ<27>")
	)
	(arc
		(start 325.990966 -289.697414)
		(mid 325.877242 -289.747715)
		(end 325.755254 -289.771836)
		(width 0.0762)
		(layer "F.Cu")
		(net "M_A_CPU0_SB_DQ<27>")
	)
	(segment
		(start 312.838592 -306.058316)
		(end 312.838592 -307.187092)
		(width 0.10668)
		(layer "F.Cu")
		(net "M_A_CPU0_SB_DQ<26>")
	)
	(segment
		(start 304.856134 -309.96001)
		(end 304.431192 -310.384952)
		(width 0.101346)
		(layer "F.Cu")
		(net "M_A_CPU0_SB_DQ<26>")
	)
	(segment
		(start 305.35753 -310.758078)
		(end 305.24069 -310.641238)
		(width 0.101346)
		(layer "F.Cu")
		(net "M_A_CPU0_SB_DQ<26>")
	)
	(segment
		(start 323.418454 -288.78911)
		(end 320.6369 -291.570664)
		(width 0.10668)
		(layer "F.Cu")
		(net "M_A_CPU0_SB_DQ<26>")
	)
	(segment
		(start 320.6369 -291.570664)
		(end 320.6369 -298.260008)
		(width 0.10668)
		(layer "F.Cu")
		(net "M_A_CPU0_SB_DQ<26>")
	)
	(segment
		(start 323.926454 -288.78911)
		(end 323.418454 -288.78911)
		(width 0.10668)
		(layer "F.Cu")
		(net "M_A_CPU0_SB_DQ<26>")
	)
	(segment
		(start 305.756564 -310.359044)
		(end 306.131214 -310.359044)
		(width 0.101346)
		(layer "F.Cu")
		(net "M_A_CPU0_SB_DQ<26>")
	)
	(segment
		(start 320.6369 -298.260008)
		(end 312.838592 -306.058316)
		(width 0.10668)
		(layer "F.Cu")
		(net "M_A_CPU0_SB_DQ<26>")
	)
	(segment
		(start 325.70801 -288.836862)
		(end 323.974206 -288.836862)
		(width 0.0762)
		(layer "F.Cu")
		(net "M_A_CPU0_SB_DQ<26>")
	)
	(segment
		(start 305.12385 -309.96001)
		(end 304.856134 -309.96001)
		(width 0.101346)
		(layer "F.Cu")
		(net "M_A_CPU0_SB_DQ<26>")
	)
	(segment
		(start 304.431192 -310.384952)
		(end 303.268126 -310.384952)
		(width 0.101346)
		(layer "F.Cu")
		(net "M_A_CPU0_SB_DQ<26>")
	)
	(segment
		(start 305.756564 -309.96001)
		(end 305.639724 -310.07685)
		(width 0.101346)
		(layer "F.Cu")
		(net "M_A_CPU0_SB_DQ<26>")
	)
	(segment
		(start 305.639724 -310.242204)
		(end 305.756564 -310.359044)
		(width 0.101346)
		(layer "F.Cu")
		(net "M_A_CPU0_SB_DQ<26>")
	)
	(segment
		(start 306.131214 -310.359044)
		(end 306.248054 -310.475884)
		(width 0.101346)
		(layer "F.Cu")
		(net "M_A_CPU0_SB_DQ<26>")
	)
	(segment
		(start 305.639724 -310.07685)
		(end 305.639724 -310.242204)
		(width 0.101346)
		(layer "F.Cu")
		(net "M_A_CPU0_SB_DQ<26>")
	)
	(segment
		(start 310.065674 -309.96001)
		(end 308.66588 -309.96001)
		(width 0.10668)
		(layer "F.Cu")
		(net "M_A_CPU0_SB_DQ<26>")
	)
	(segment
		(start 308.66588 -309.96001)
		(end 305.756564 -309.96001)
		(width 0.101346)
		(layer "F.Cu")
		(net "M_A_CPU0_SB_DQ<26>")
	)
	(segment
		(start 306.248054 -310.641238)
		(end 306.131214 -310.758078)
		(width 0.101346)
		(layer "F.Cu")
		(net "M_A_CPU0_SB_DQ<26>")
	)
	(segment
		(start 312.838592 -307.187092)
		(end 310.065674 -309.96001)
		(width 0.10668)
		(layer "F.Cu")
		(net "M_A_CPU0_SB_DQ<26>")
	)
	(segment
		(start 305.24069 -310.07685)
		(end 305.12385 -309.96001)
		(width 0.101346)
		(layer "F.Cu")
		(net "M_A_CPU0_SB_DQ<26>")
	)
	(segment
		(start 306.131214 -310.758078)
		(end 305.35753 -310.758078)
		(width 0.101346)
		(layer "F.Cu")
		(net "M_A_CPU0_SB_DQ<26>")
	)
	(segment
		(start 305.24069 -310.641238)
		(end 305.24069 -310.07685)
		(width 0.101346)
		(layer "F.Cu")
		(net "M_A_CPU0_SB_DQ<26>")
	)
	(segment
		(start 323.974206 -288.836862)
		(end 323.926454 -288.78911)
		(width 0.0762)
		(layer "F.Cu")
		(net "M_A_CPU0_SB_DQ<26>")
	)
	(segment
		(start 306.248054 -310.475884)
		(end 306.248054 -310.641238)
		(width 0.101346)
		(layer "F.Cu")
		(net "M_A_CPU0_SB_DQ<26>")
	)
	(arc
		(start 326.648064 -289.209988)
		(mid 326.405747 -289.040268)
		(end 326.12076 -288.960814)
		(width 0.0762)
		(layer "F.Cu")
		(net "M_A_CPU0_SB_DQ<26>")
	)
	(arc
		(start 326.12076 -288.960814)
		(mid 326.003947 -288.936138)
		(end 325.894954 -288.887408)
		(width 0.0762)
		(layer "F.Cu")
		(net "M_A_CPU0_SB_DQ<26>")
	)
	(arc
		(start 325.894954 -288.887408)
		(mid 325.804821 -288.849788)
		(end 325.70801 -288.836862)
		(width 0.0762)
		(layer "F.Cu")
		(net "M_A_CPU0_SB_DQ<26>")
	)
	(segment
		(start 326.835008 -289.532568)
		(end 326.826626 -289.537394)
		(width 0.0762)
		(layer "F.Cu")
		(net "M_A_CPU0_SB_DQ<25>")
	)
	(segment
		(start 313.747658 -305.795934)
		(end 313.864752 -305.913028)
		(width 0.10668)
		(layer "F.Cu")
		(net "M_A_CPU0_SB_DQ<25>")
	)
	(segment
		(start 325.70801 -289.583114)
		(end 324.872858 -289.583114)
		(width 0.0762)
		(layer "F.Cu")
		(net "M_A_CPU0_SB_DQ<25>")
	)
	(segment
		(start 313.465464 -306.078128)
		(end 313.300364 -306.078128)
		(width 0.10668)
		(layer "F.Cu")
		(net "M_A_CPU0_SB_DQ<25>")
	)
	(segment
		(start 315.550296 -304.791872)
		(end 315.550296 -304.956972)
		(width 0.10668)
		(layer "F.Cu")
		(net "M_A_CPU0_SB_DQ<25>")
	)
	(segment
		(start 315.550296 -304.956972)
		(end 314.029852 -306.477416)
		(width 0.10668)
		(layer "F.Cu")
		(net "M_A_CPU0_SB_DQ<25>")
	)
	(segment
		(start 314.029852 -306.477416)
		(end 313.864752 -306.477416)
		(width 0.10668)
		(layer "F.Cu")
		(net "M_A_CPU0_SB_DQ<25>")
	)
	(segment
		(start 320.97726 -298.401232)
		(end 313.747658 -305.630834)
		(width 0.10668)
		(layer "F.Cu")
		(net "M_A_CPU0_SB_DQ<25>")
	)
	(segment
		(start 323.469254 -289.24631)
		(end 320.97726 -291.738304)
		(width 0.10668)
		(layer "F.Cu")
		(net "M_A_CPU0_SB_DQ<25>")
	)
	(segment
		(start 327.587864 -289.209988)
		(end 327.688702 -289.38347)
		(width 0.0762)
		(layer "F.Cu")
		(net "M_A_CPU0_SB_DQ<25>")
	)
	(segment
		(start 313.747658 -305.630834)
		(end 313.747658 -305.795934)
		(width 0.10668)
		(layer "F.Cu")
		(net "M_A_CPU0_SB_DQ<25>")
	)
	(segment
		(start 327.409302 -289.537394)
		(end 327.40092 -289.532568)
		(width 0.0762)
		(layer "F.Cu")
		(net "M_A_CPU0_SB_DQ<25>")
	)
	(segment
		(start 313.178952 -306.19954)
		(end 313.178952 -307.328316)
		(width 0.10668)
		(layer "F.Cu")
		(net "M_A_CPU0_SB_DQ<25>")
	)
	(segment
		(start 315.268102 -304.674778)
		(end 315.433202 -304.674778)
		(width 0.10668)
		(layer "F.Cu")
		(net "M_A_CPU0_SB_DQ<25>")
	)
	(segment
		(start 313.178952 -307.328316)
		(end 309.272178 -311.23509)
		(width 0.10668)
		(layer "F.Cu")
		(net "M_A_CPU0_SB_DQ<25>")
	)
	(segment
		(start 314.029852 -305.913028)
		(end 315.268102 -304.674778)
		(width 0.10668)
		(layer "F.Cu")
		(net "M_A_CPU0_SB_DQ<25>")
	)
	(segment
		(start 323.901054 -289.24631)
		(end 323.469254 -289.24631)
		(width 0.10668)
		(layer "F.Cu")
		(net "M_A_CPU0_SB_DQ<25>")
	)
	(segment
		(start 309.272178 -311.23509)
		(end 307.368194 -311.23509)
		(width 0.10668)
		(layer "F.Cu")
		(net "M_A_CPU0_SB_DQ<25>")
	)
	(segment
		(start 313.300364 -306.078128)
		(end 313.178952 -306.19954)
		(width 0.10668)
		(layer "F.Cu")
		(net "M_A_CPU0_SB_DQ<25>")
	)
	(segment
		(start 320.97726 -291.738304)
		(end 320.97726 -298.401232)
		(width 0.10668)
		(layer "F.Cu")
		(net "M_A_CPU0_SB_DQ<25>")
	)
	(segment
		(start 313.864752 -305.913028)
		(end 314.029852 -305.913028)
		(width 0.10668)
		(layer "F.Cu")
		(net "M_A_CPU0_SB_DQ<25>")
	)
	(segment
		(start 315.433202 -304.674778)
		(end 315.550296 -304.791872)
		(width 0.10668)
		(layer "F.Cu")
		(net "M_A_CPU0_SB_DQ<25>")
	)
	(segment
		(start 324.872858 -289.583114)
		(end 324.536054 -289.24631)
		(width 0.0762)
		(layer "F.Cu")
		(net "M_A_CPU0_SB_DQ<25>")
	)
	(segment
		(start 324.536054 -289.24631)
		(end 323.901054 -289.24631)
		(width 0.0762)
		(layer "F.Cu")
		(net "M_A_CPU0_SB_DQ<25>")
	)
	(segment
		(start 313.864752 -306.477416)
		(end 313.465464 -306.078128)
		(width 0.10668)
		(layer "F.Cu")
		(net "M_A_CPU0_SB_DQ<25>")
	)
	(arc
		(start 327.688702 -289.38347)
		(mid 327.672777 -289.524162)
		(end 327.542652 -289.580066)
		(width 0.0762)
		(layer "F.Cu")
		(net "M_A_CPU0_SB_DQ<25>")
	)
	(arc
		(start 325.894954 -289.532568)
		(mid 325.819714 -289.565881)
		(end 325.738998 -289.581844)
		(width 0.0762)
		(layer "F.Cu")
		(net "M_A_CPU0_SB_DQ<25>")
	)
	(arc
		(start 326.460866 -289.532568)
		(mid 326.17791 -289.456391)
		(end 325.894954 -289.532568)
		(width 0.0762)
		(layer "F.Cu")
		(net "M_A_CPU0_SB_DQ<25>")
	)
	(arc
		(start 326.826626 -289.537394)
		(mid 326.643118 -289.582888)
		(end 326.460866 -289.532568)
		(width 0.0762)
		(layer "F.Cu")
		(net "M_A_CPU0_SB_DQ<25>")
	)
	(arc
		(start 327.542652 -289.580066)
		(mid 327.473954 -289.56505)
		(end 327.409302 -289.537394)
		(width 0.0762)
		(layer "F.Cu")
		(net "M_A_CPU0_SB_DQ<25>")
	)
	(arc
		(start 327.40092 -289.532568)
		(mid 327.117964 -289.456391)
		(end 326.835008 -289.532568)
		(width 0.0762)
		(layer "F.Cu")
		(net "M_A_CPU0_SB_DQ<25>")
	)
	(arc
		(start 325.738998 -289.581844)
		(mid 325.723517 -289.5828)
		(end 325.70801 -289.583114)
		(width 0.0762)
		(layer "F.Cu")
		(net "M_A_CPU0_SB_DQ<25>")
	)
	(segment
		(start 320.29654 -298.118784)
		(end 309.886858 -308.528466)
		(width 0.10668)
		(layer "F.Cu")
		(net "M_A_CPU0_SB_DQ<24>")
	)
	(segment
		(start 309.886858 -308.528466)
		(end 309.886858 -308.693566)
		(width 0.10668)
		(layer "F.Cu")
		(net "M_A_CPU0_SB_DQ<24>")
	)
	(segment
		(start 310.169052 -309.375048)
		(end 310.003952 -309.375048)
		(width 0.10668)
		(layer "F.Cu")
		(net "M_A_CPU0_SB_DQ<24>")
	)
	(segment
		(start 323.926454 -288.43351)
		(end 323.215254 -288.43351)
		(width 0.10668)
		(layer "F.Cu")
		(net "M_A_CPU0_SB_DQ<24>")
	)
	(segment
		(start 325.70801 -288.646362)
		(end 324.139306 -288.646362)
		(width 0.0762)
		(layer "F.Cu")
		(net "M_A_CPU0_SB_DQ<24>")
	)
	(segment
		(start 312.498232 -307.045868)
		(end 310.169052 -309.375048)
		(width 0.10668)
		(layer "F.Cu")
		(net "M_A_CPU0_SB_DQ<24>")
	)
	(segment
		(start 312.498232 -306.880768)
		(end 312.498232 -307.045868)
		(width 0.10668)
		(layer "F.Cu")
		(net "M_A_CPU0_SB_DQ<24>")
	)
	(segment
		(start 312.216038 -306.763674)
		(end 312.381138 -306.763674)
		(width 0.10668)
		(layer "F.Cu")
		(net "M_A_CPU0_SB_DQ<24>")
	)
	(segment
		(start 312.381138 -306.763674)
		(end 312.498232 -306.880768)
		(width 0.10668)
		(layer "F.Cu")
		(net "M_A_CPU0_SB_DQ<24>")
	)
	(segment
		(start 325.999348 -288.727388)
		(end 325.990966 -288.722562)
		(width 0.0762)
		(layer "F.Cu")
		(net "M_A_CPU0_SB_DQ<24>")
	)
	(segment
		(start 320.29654 -291.352224)
		(end 320.29654 -298.118784)
		(width 0.10668)
		(layer "F.Cu")
		(net "M_A_CPU0_SB_DQ<24>")
	)
	(segment
		(start 308.880256 -309.535068)
		(end 307.368194 -309.535068)
		(width 0.10668)
		(layer "F.Cu")
		(net "M_A_CPU0_SB_DQ<24>")
	)
	(segment
		(start 310.003952 -309.375048)
		(end 309.604664 -308.97576)
		(width 0.10668)
		(layer "F.Cu")
		(net "M_A_CPU0_SB_DQ<24>")
	)
	(segment
		(start 309.439564 -308.97576)
		(end 308.880256 -309.535068)
		(width 0.10668)
		(layer "F.Cu")
		(net "M_A_CPU0_SB_DQ<24>")
	)
	(segment
		(start 309.886858 -308.693566)
		(end 310.003952 -308.81066)
		(width 0.10668)
		(layer "F.Cu")
		(net "M_A_CPU0_SB_DQ<24>")
	)
	(segment
		(start 310.003952 -308.81066)
		(end 310.169052 -308.81066)
		(width 0.10668)
		(layer "F.Cu")
		(net "M_A_CPU0_SB_DQ<24>")
	)
	(segment
		(start 324.139306 -288.646362)
		(end 323.926454 -288.43351)
		(width 0.0762)
		(layer "F.Cu")
		(net "M_A_CPU0_SB_DQ<24>")
	)
	(segment
		(start 323.215254 -288.43351)
		(end 320.29654 -291.352224)
		(width 0.10668)
		(layer "F.Cu")
		(net "M_A_CPU0_SB_DQ<24>")
	)
	(segment
		(start 310.169052 -308.81066)
		(end 312.216038 -306.763674)
		(width 0.10668)
		(layer "F.Cu")
		(net "M_A_CPU0_SB_DQ<24>")
	)
	(segment
		(start 326.17791 -288.399982)
		(end 326.276208 -288.569146)
		(width 0.0762)
		(layer "F.Cu")
		(net "M_A_CPU0_SB_DQ<24>")
	)
	(segment
		(start 309.604664 -308.97576)
		(end 309.439564 -308.97576)
		(width 0.10668)
		(layer "F.Cu")
		(net "M_A_CPU0_SB_DQ<24>")
	)
	(arc
		(start 326.13854 -288.770822)
		(mid 326.066802 -288.75597)
		(end 325.999348 -288.727388)
		(width 0.0762)
		(layer "F.Cu")
		(net "M_A_CPU0_SB_DQ<24>")
	)
	(arc
		(start 325.990966 -288.722562)
		(mid 325.85453 -288.665737)
		(end 325.70801 -288.646362)
		(width 0.0762)
		(layer "F.Cu")
		(net "M_A_CPU0_SB_DQ<24>")
	)
	(arc
		(start 326.276208 -288.569146)
		(mid 326.267615 -288.711025)
		(end 326.13854 -288.770822)
		(width 0.0762)
		(layer "F.Cu")
		(net "M_A_CPU0_SB_DQ<24>")
	)
	(segment
		(start 324.459854 -287.97631)
		(end 323.926454 -287.97631)
		(width 0.0762)
		(layer "F.Cu")
		(net "M_A_CPU0_SB_DQ<23>")
	)
	(segment
		(start 325.999348 -288.07283)
		(end 325.990966 -288.077656)
		(width 0.0762)
		(layer "F.Cu")
		(net "M_A_CPU0_SB_DQ<23>")
	)
	(segment
		(start 306.139342 -308.259988)
		(end 305.714146 -308.685184)
		(width 0.101346)
		(layer "F.Cu")
		(net "M_A_CPU0_SB_DQ<23>")
	)
	(segment
		(start 309.203852 -308.259988)
		(end 308.66588 -308.259988)
		(width 0.10668)
		(layer "F.Cu")
		(net "M_A_CPU0_SB_DQ<23>")
	)
	(segment
		(start 305.714146 -308.685184)
		(end 303.268126 -308.685184)
		(width 0.101346)
		(layer "F.Cu")
		(net "M_A_CPU0_SB_DQ<23>")
	)
	(segment
		(start 323.926454 -287.97631)
		(end 323.02577 -287.97631)
		(width 0.10668)
		(layer "F.Cu")
		(net "M_A_CPU0_SB_DQ<23>")
	)
	(segment
		(start 319.83934 -297.6245)
		(end 309.203852 -308.259988)
		(width 0.10668)
		(layer "F.Cu")
		(net "M_A_CPU0_SB_DQ<23>")
	)
	(segment
		(start 319.83934 -291.16274)
		(end 319.83934 -297.6245)
		(width 0.10668)
		(layer "F.Cu")
		(net "M_A_CPU0_SB_DQ<23>")
	)
	(segment
		(start 323.02577 -287.97631)
		(end 319.83934 -291.16274)
		(width 0.10668)
		(layer "F.Cu")
		(net "M_A_CPU0_SB_DQ<23>")
	)
	(segment
		(start 325.708264 -288.153856)
		(end 324.6374 -288.153856)
		(width 0.0762)
		(layer "F.Cu")
		(net "M_A_CPU0_SB_DQ<23>")
	)
	(segment
		(start 308.66588 -308.259988)
		(end 306.139342 -308.259988)
		(width 0.101346)
		(layer "F.Cu")
		(net "M_A_CPU0_SB_DQ<23>")
	)
	(segment
		(start 324.6374 -288.153856)
		(end 324.459854 -287.97631)
		(width 0.0762)
		(layer "F.Cu")
		(net "M_A_CPU0_SB_DQ<23>")
	)
	(arc
		(start 327.304908 -288.077656)
		(mid 327.117964 -288.027401)
		(end 326.93102 -288.077656)
		(width 0.0762)
		(layer "F.Cu")
		(net "M_A_CPU0_SB_DQ<23>")
	)
	(arc
		(start 326.365108 -288.077656)
		(mid 326.182857 -288.027306)
		(end 325.999348 -288.07283)
		(width 0.0762)
		(layer "F.Cu")
		(net "M_A_CPU0_SB_DQ<23>")
	)
	(arc
		(start 328.058018 -288.399982)
		(mid 327.820367 -288.22915)
		(end 327.53808 -288.151824)
		(width 0.0762)
		(layer "F.Cu")
		(net "M_A_CPU0_SB_DQ<23>")
	)
	(arc
		(start 325.755254 -288.152078)
		(mid 325.731777 -288.153454)
		(end 325.708264 -288.153856)
		(width 0.0762)
		(layer "F.Cu")
		(net "M_A_CPU0_SB_DQ<23>")
	)
	(arc
		(start 325.990966 -288.077656)
		(mid 325.877242 -288.127957)
		(end 325.755254 -288.152078)
		(width 0.0762)
		(layer "F.Cu")
		(net "M_A_CPU0_SB_DQ<23>")
	)
	(arc
		(start 327.53808 -288.151824)
		(mid 327.417431 -288.127523)
		(end 327.304908 -288.077656)
		(width 0.0762)
		(layer "F.Cu")
		(net "M_A_CPU0_SB_DQ<23>")
	)
	(arc
		(start 326.93102 -288.077656)
		(mid 326.648064 -288.153833)
		(end 326.365108 -288.077656)
		(width 0.0762)
		(layer "F.Cu")
		(net "M_A_CPU0_SB_DQ<23>")
	)
	(segment
		(start 308.666134 -306.559966)
		(end 308.66588 -306.56022)
		(width 0.10668)
		(layer "F.Cu")
		(net "M_A_CPU0_SB_DQ<22>")
	)
	(segment
		(start 308.610508 -306.56022)
		(end 308.610254 -306.559966)
		(width 0.101346)
		(layer "F.Cu")
		(net "M_A_CPU0_SB_DQ<22>")
	)
	(segment
		(start 309.296816 -306.849272)
		(end 309.111142 -306.849272)
		(width 0.10668)
		(layer "F.Cu")
		(net "M_A_CPU0_SB_DQ<22>")
	)
	(segment
		(start 309.64505 -306.108354)
		(end 309.403496 -306.349908)
		(width 0.10668)
		(layer "F.Cu")
		(net "M_A_CPU0_SB_DQ<22>")
	)
	(segment
		(start 323.954648 -287.217104)
		(end 323.901054 -287.16351)
		(width 0.0762)
		(layer "F.Cu")
		(net "M_A_CPU0_SB_DQ<22>")
	)
	(segment
		(start 306.139342 -306.559966)
		(end 305.502056 -307.197252)
		(width 0.101346)
		(layer "F.Cu")
		(net "M_A_CPU0_SB_DQ<22>")
	)
	(segment
		(start 310.016906 -306.178458)
		(end 309.86603 -306.178458)
		(width 0.10668)
		(layer "F.Cu")
		(net "M_A_CPU0_SB_DQ<22>")
	)
	(segment
		(start 308.610254 -306.559966)
		(end 306.139342 -306.559966)
		(width 0.101346)
		(layer "F.Cu")
		(net "M_A_CPU0_SB_DQ<22>")
	)
	(segment
		(start 304.598578 -306.985162)
		(end 303.268126 -306.985162)
		(width 0.101346)
		(layer "F.Cu")
		(net "M_A_CPU0_SB_DQ<22>")
	)
	(segment
		(start 319.15862 -297.040808)
		(end 310.624982 -305.574446)
		(width 0.10668)
		(layer "F.Cu")
		(net "M_A_CPU0_SB_DQ<22>")
	)
	(segment
		(start 305.502056 -307.197252)
		(end 304.810668 -307.197252)
		(width 0.101346)
		(layer "F.Cu")
		(net "M_A_CPU0_SB_DQ<22>")
	)
	(segment
		(start 322.875402 -287.16351)
		(end 319.15862 -290.880292)
		(width 0.10668)
		(layer "F.Cu")
		(net "M_A_CPU0_SB_DQ<22>")
	)
	(segment
		(start 310.07812 -305.82616)
		(end 310.148224 -305.896264)
		(width 0.10668)
		(layer "F.Cu")
		(net "M_A_CPU0_SB_DQ<22>")
	)
	(segment
		(start 308.66588 -306.56022)
		(end 308.610508 -306.56022)
		(width 0.101346)
		(layer "F.Cu")
		(net "M_A_CPU0_SB_DQ<22>")
	)
	(segment
		(start 309.403496 -306.742592)
		(end 309.296816 -306.849272)
		(width 0.10668)
		(layer "F.Cu")
		(net "M_A_CPU0_SB_DQ<22>")
	)
	(segment
		(start 309.403496 -306.349908)
		(end 309.403496 -306.742592)
		(width 0.10668)
		(layer "F.Cu")
		(net "M_A_CPU0_SB_DQ<22>")
	)
	(segment
		(start 309.004462 -306.742592)
		(end 309.004462 -306.666646)
		(width 0.10668)
		(layer "F.Cu")
		(net "M_A_CPU0_SB_DQ<22>")
	)
	(segment
		(start 309.111142 -306.849272)
		(end 309.004462 -306.742592)
		(width 0.10668)
		(layer "F.Cu")
		(net "M_A_CPU0_SB_DQ<22>")
	)
	(segment
		(start 310.624982 -305.574446)
		(end 310.17972 -305.573684)
		(width 0.10668)
		(layer "F.Cu")
		(net "M_A_CPU0_SB_DQ<22>")
	)
	(segment
		(start 304.810668 -307.197252)
		(end 304.598578 -306.985162)
		(width 0.101346)
		(layer "F.Cu")
		(net "M_A_CPU0_SB_DQ<22>")
	)
	(segment
		(start 310.07812 -305.675284)
		(end 310.07812 -305.82616)
		(width 0.10668)
		(layer "F.Cu")
		(net "M_A_CPU0_SB_DQ<22>")
	)
	(segment
		(start 309.86603 -306.178458)
		(end 309.795926 -306.108354)
		(width 0.10668)
		(layer "F.Cu")
		(net "M_A_CPU0_SB_DQ<22>")
	)
	(segment
		(start 310.148224 -306.04714)
		(end 310.016906 -306.178458)
		(width 0.10668)
		(layer "F.Cu")
		(net "M_A_CPU0_SB_DQ<22>")
	)
	(segment
		(start 325.70801 -287.217104)
		(end 323.954648 -287.217104)
		(width 0.0762)
		(layer "F.Cu")
		(net "M_A_CPU0_SB_DQ<22>")
	)
	(segment
		(start 310.17972 -305.573684)
		(end 310.07812 -305.675284)
		(width 0.10668)
		(layer "F.Cu")
		(net "M_A_CPU0_SB_DQ<22>")
	)
	(segment
		(start 310.148224 -305.896264)
		(end 310.148224 -306.04714)
		(width 0.10668)
		(layer "F.Cu")
		(net "M_A_CPU0_SB_DQ<22>")
	)
	(segment
		(start 319.15862 -290.880292)
		(end 319.15862 -297.040808)
		(width 0.10668)
		(layer "F.Cu")
		(net "M_A_CPU0_SB_DQ<22>")
	)
	(segment
		(start 323.901054 -287.16351)
		(end 322.875402 -287.16351)
		(width 0.10668)
		(layer "F.Cu")
		(net "M_A_CPU0_SB_DQ<22>")
	)
	(segment
		(start 308.897782 -306.559966)
		(end 308.666134 -306.559966)
		(width 0.10668)
		(layer "F.Cu")
		(net "M_A_CPU0_SB_DQ<22>")
	)
	(segment
		(start 309.004462 -306.666646)
		(end 308.897782 -306.559966)
		(width 0.10668)
		(layer "F.Cu")
		(net "M_A_CPU0_SB_DQ<22>")
	)
	(segment
		(start 309.795926 -306.108354)
		(end 309.64505 -306.108354)
		(width 0.10668)
		(layer "F.Cu")
		(net "M_A_CPU0_SB_DQ<22>")
	)
	(arc
		(start 326.12076 -287.341056)
		(mid 326.003947 -287.31638)
		(end 325.894954 -287.26765)
		(width 0.0762)
		(layer "F.Cu")
		(net "M_A_CPU0_SB_DQ<22>")
	)
	(arc
		(start 326.648064 -287.59023)
		(mid 326.405747 -287.42051)
		(end 326.12076 -287.341056)
		(width 0.0762)
		(layer "F.Cu")
		(net "M_A_CPU0_SB_DQ<22>")
	)
	(arc
		(start 325.894954 -287.26765)
		(mid 325.804821 -287.23003)
		(end 325.70801 -287.217104)
		(width 0.0762)
		(layer "F.Cu")
		(net "M_A_CPU0_SB_DQ<22>")
	)
	(segment
		(start 314.331096 -302.349916)
		(end 314.199524 -302.481488)
		(width 0.10668)
		(layer "F.Cu")
		(net "M_A_CPU0_SB_DQ<21>")
	)
	(segment
		(start 318.714628 -298.267628)
		(end 318.583056 -298.3992)
		(width 0.10668)
		(layer "F.Cu")
		(net "M_A_CPU0_SB_DQ<21>")
	)
	(segment
		(start 310.248808 -306.432204)
		(end 310.248808 -306.733448)
		(width 0.10668)
		(layer "F.Cu")
		(net "M_A_CPU0_SB_DQ<21>")
	)
	(segment
		(start 311.377584 -305.303428)
		(end 311.377584 -305.604672)
		(width 0.10668)
		(layer "F.Cu")
		(net "M_A_CPU0_SB_DQ<21>")
	)
	(segment
		(start 317.585852 -299.09516)
		(end 317.585852 -299.396404)
		(width 0.10668)
		(layer "F.Cu")
		(net "M_A_CPU0_SB_DQ<21>")
	)
	(segment
		(start 316.588648 -300.092364)
		(end 316.457076 -300.223936)
		(width 0.10668)
		(layer "F.Cu")
		(net "M_A_CPU0_SB_DQ<21>")
	)
	(segment
		(start 309.815992 -306.86502)
		(end 309.36946 -307.311552)
		(width 0.10668)
		(layer "F.Cu")
		(net "M_A_CPU0_SB_DQ<21>")
	)
	(segment
		(start 323.901054 -287.595564)
		(end 322.924932 -287.595564)
		(width 0.10668)
		(layer "F.Cu")
		(net "M_A_CPU0_SB_DQ<21>")
	)
	(segment
		(start 309.36946 -307.311552)
		(end 309.218584 -307.311552)
		(width 0.10668)
		(layer "F.Cu")
		(net "M_A_CPU0_SB_DQ<21>")
	)
	(segment
		(start 315.459872 -301.22114)
		(end 315.3283 -301.352712)
		(width 0.10668)
		(layer "F.Cu")
		(net "M_A_CPU0_SB_DQ<21>")
	)
	(segment
		(start 312.50636 -304.174652)
		(end 312.50636 -304.475896)
		(width 0.10668)
		(layer "F.Cu")
		(net "M_A_CPU0_SB_DQ<21>")
	)
	(segment
		(start 327.587864 -287.59023)
		(end 327.688702 -287.763712)
		(width 0.0762)
		(layer "F.Cu")
		(net "M_A_CPU0_SB_DQ<21>")
	)
	(segment
		(start 308.845966 -307.835046)
		(end 307.368194 -307.835046)
		(width 0.10668)
		(layer "F.Cu")
		(net "M_A_CPU0_SB_DQ<21>")
	)
	(segment
		(start 313.070748 -303.911508)
		(end 312.939176 -304.04308)
		(width 0.10668)
		(layer "F.Cu")
		(net "M_A_CPU0_SB_DQ<21>")
	)
	(segment
		(start 324.776846 -287.963356)
		(end 324.409054 -287.595564)
		(width 0.0762)
		(layer "F.Cu")
		(net "M_A_CPU0_SB_DQ<21>")
	)
	(segment
		(start 308.93639 -307.594)
		(end 308.936644 -307.744368)
		(width 0.10668)
		(layer "F.Cu")
		(net "M_A_CPU0_SB_DQ<21>")
	)
	(segment
		(start 311.941972 -304.73904)
		(end 311.941972 -305.040284)
		(width 0.10668)
		(layer "F.Cu")
		(net "M_A_CPU0_SB_DQ<21>")
	)
	(segment
		(start 313.766708 -302.914304)
		(end 313.635136 -303.045876)
		(width 0.10668)
		(layer "F.Cu")
		(net "M_A_CPU0_SB_DQ<21>")
	)
	(segment
		(start 315.892688 -300.788324)
		(end 315.892688 -301.089568)
		(width 0.10668)
		(layer "F.Cu")
		(net "M_A_CPU0_SB_DQ<21>")
	)
	(segment
		(start 319.279016 -297.70324)
		(end 319.147444 -297.834812)
		(width 0.10668)
		(layer "F.Cu")
		(net "M_A_CPU0_SB_DQ<21>")
	)
	(segment
		(start 318.281812 -298.3992)
		(end 318.15024 -298.530772)
		(width 0.10668)
		(layer "F.Cu")
		(net "M_A_CPU0_SB_DQ<21>")
	)
	(segment
		(start 319.49898 -297.182032)
		(end 319.279016 -297.401996)
		(width 0.10668)
		(layer "F.Cu")
		(net "M_A_CPU0_SB_DQ<21>")
	)
	(segment
		(start 310.813196 -306.16906)
		(end 310.681624 -306.300632)
		(width 0.10668)
		(layer "F.Cu")
		(net "M_A_CPU0_SB_DQ<21>")
	)
	(segment
		(start 318.714628 -297.966384)
		(end 318.714628 -298.267628)
		(width 0.10668)
		(layer "F.Cu")
		(net "M_A_CPU0_SB_DQ<21>")
	)
	(segment
		(start 316.02426 -300.656752)
		(end 315.892688 -300.788324)
		(width 0.10668)
		(layer "F.Cu")
		(net "M_A_CPU0_SB_DQ<21>")
	)
	(segment
		(start 311.509156 -305.171856)
		(end 311.377584 -305.303428)
		(width 0.10668)
		(layer "F.Cu")
		(net "M_A_CPU0_SB_DQ<21>")
	)
	(segment
		(start 314.067952 -302.914304)
		(end 313.766708 -302.914304)
		(width 0.10668)
		(layer "F.Cu")
		(net "M_A_CPU0_SB_DQ<21>")
	)
	(segment
		(start 311.377584 -305.604672)
		(end 311.246012 -305.736244)
		(width 0.10668)
		(layer "F.Cu")
		(net "M_A_CPU0_SB_DQ<21>")
	)
	(segment
		(start 314.63234 -302.349916)
		(end 314.331096 -302.349916)
		(width 0.10668)
		(layer "F.Cu")
		(net "M_A_CPU0_SB_DQ<21>")
	)
	(segment
		(start 312.50636 -304.475896)
		(end 312.374788 -304.607468)
		(width 0.10668)
		(layer "F.Cu")
		(net "M_A_CPU0_SB_DQ<21>")
	)
	(segment
		(start 315.3283 -301.653956)
		(end 315.196728 -301.785528)
		(width 0.10668)
		(layer "F.Cu")
		(net "M_A_CPU0_SB_DQ<21>")
	)
	(segment
		(start 313.503564 -303.478692)
		(end 313.20232 -303.478692)
		(width 0.10668)
		(layer "F.Cu")
		(net "M_A_CPU0_SB_DQ<21>")
	)
	(segment
		(start 315.892688 -301.089568)
		(end 315.761116 -301.22114)
		(width 0.10668)
		(layer "F.Cu")
		(net "M_A_CPU0_SB_DQ<21>")
	)
	(segment
		(start 310.117236 -306.86502)
		(end 309.815992 -306.86502)
		(width 0.10668)
		(layer "F.Cu")
		(net "M_A_CPU0_SB_DQ<21>")
	)
	(segment
		(start 327.409302 -287.917636)
		(end 327.40092 -287.91281)
		(width 0.0762)
		(layer "F.Cu")
		(net "M_A_CPU0_SB_DQ<21>")
	)
	(segment
		(start 312.073544 -304.607468)
		(end 311.941972 -304.73904)
		(width 0.10668)
		(layer "F.Cu")
		(net "M_A_CPU0_SB_DQ<21>")
	)
	(segment
		(start 311.941972 -305.040284)
		(end 311.8104 -305.171856)
		(width 0.10668)
		(layer "F.Cu")
		(net "M_A_CPU0_SB_DQ<21>")
	)
	(segment
		(start 313.20232 -303.478692)
		(end 313.070748 -303.610264)
		(width 0.10668)
		(layer "F.Cu")
		(net "M_A_CPU0_SB_DQ<21>")
	)
	(segment
		(start 316.457076 -300.52518)
		(end 316.325504 -300.656752)
		(width 0.10668)
		(layer "F.Cu")
		(net "M_A_CPU0_SB_DQ<21>")
	)
	(segment
		(start 317.021464 -299.960792)
		(end 316.889892 -300.092364)
		(width 0.10668)
		(layer "F.Cu")
		(net "M_A_CPU0_SB_DQ<21>")
	)
	(segment
		(start 311.246012 -305.736244)
		(end 310.944768 -305.736244)
		(width 0.10668)
		(layer "F.Cu")
		(net "M_A_CPU0_SB_DQ<21>")
	)
	(segment
		(start 310.38038 -306.300632)
		(end 310.248808 -306.432204)
		(width 0.10668)
		(layer "F.Cu")
		(net "M_A_CPU0_SB_DQ<21>")
	)
	(segment
		(start 319.49898 -291.021516)
		(end 319.49898 -297.182032)
		(width 0.10668)
		(layer "F.Cu")
		(net "M_A_CPU0_SB_DQ<21>")
	)
	(segment
		(start 315.3283 -301.352712)
		(end 315.3283 -301.653956)
		(width 0.10668)
		(layer "F.Cu")
		(net "M_A_CPU0_SB_DQ<21>")
	)
	(segment
		(start 324.409054 -287.595564)
		(end 323.901054 -287.595564)
		(width 0.0762)
		(layer "F.Cu")
		(net "M_A_CPU0_SB_DQ<21>")
	)
	(segment
		(start 318.018668 -298.963588)
		(end 317.717424 -298.963588)
		(width 0.10668)
		(layer "F.Cu")
		(net "M_A_CPU0_SB_DQ<21>")
	)
	(segment
		(start 308.952646 -307.196744)
		(end 308.821328 -307.328062)
		(width 0.10668)
		(layer "F.Cu")
		(net "M_A_CPU0_SB_DQ<21>")
	)
	(segment
		(start 312.637932 -304.04308)
		(end 312.50636 -304.174652)
		(width 0.10668)
		(layer "F.Cu")
		(net "M_A_CPU0_SB_DQ<21>")
	)
	(segment
		(start 312.374788 -304.607468)
		(end 312.073544 -304.607468)
		(width 0.10668)
		(layer "F.Cu")
		(net "M_A_CPU0_SB_DQ<21>")
	)
	(segment
		(start 314.895484 -301.785528)
		(end 314.763912 -301.9171)
		(width 0.10668)
		(layer "F.Cu")
		(net "M_A_CPU0_SB_DQ<21>")
	)
	(segment
		(start 309.218584 -307.311552)
		(end 309.103522 -307.19649)
		(width 0.10668)
		(layer "F.Cu")
		(net "M_A_CPU0_SB_DQ<21>")
	)
	(segment
		(start 318.583056 -298.3992)
		(end 318.281812 -298.3992)
		(width 0.10668)
		(layer "F.Cu")
		(net "M_A_CPU0_SB_DQ<21>")
	)
	(segment
		(start 313.070748 -303.610264)
		(end 313.070748 -303.911508)
		(width 0.10668)
		(layer "F.Cu")
		(net "M_A_CPU0_SB_DQ<21>")
	)
	(segment
		(start 308.821328 -307.478938)
		(end 308.93639 -307.594)
		(width 0.10668)
		(layer "F.Cu")
		(net "M_A_CPU0_SB_DQ<21>")
	)
	(segment
		(start 318.15024 -298.832016)
		(end 318.018668 -298.963588)
		(width 0.10668)
		(layer "F.Cu")
		(net "M_A_CPU0_SB_DQ<21>")
	)
	(segment
		(start 317.585852 -299.396404)
		(end 317.45428 -299.527976)
		(width 0.10668)
		(layer "F.Cu")
		(net "M_A_CPU0_SB_DQ<21>")
	)
	(segment
		(start 310.944768 -305.736244)
		(end 310.813196 -305.867816)
		(width 0.10668)
		(layer "F.Cu")
		(net "M_A_CPU0_SB_DQ<21>")
	)
	(segment
		(start 317.45428 -299.527976)
		(end 317.153036 -299.527976)
		(width 0.10668)
		(layer "F.Cu")
		(net "M_A_CPU0_SB_DQ<21>")
	)
	(segment
		(start 314.763912 -302.218344)
		(end 314.63234 -302.349916)
		(width 0.10668)
		(layer "F.Cu")
		(net "M_A_CPU0_SB_DQ<21>")
	)
	(segment
		(start 314.763912 -301.9171)
		(end 314.763912 -302.218344)
		(width 0.10668)
		(layer "F.Cu")
		(net "M_A_CPU0_SB_DQ<21>")
	)
	(segment
		(start 315.761116 -301.22114)
		(end 315.459872 -301.22114)
		(width 0.10668)
		(layer "F.Cu")
		(net "M_A_CPU0_SB_DQ<21>")
	)
	(segment
		(start 322.924932 -287.595564)
		(end 319.49898 -291.021516)
		(width 0.10668)
		(layer "F.Cu")
		(net "M_A_CPU0_SB_DQ<21>")
	)
	(segment
		(start 313.635136 -303.34712)
		(end 313.503564 -303.478692)
		(width 0.10668)
		(layer "F.Cu")
		(net "M_A_CPU0_SB_DQ<21>")
	)
	(segment
		(start 326.835008 -287.91281)
		(end 326.826626 -287.917636)
		(width 0.0762)
		(layer "F.Cu")
		(net "M_A_CPU0_SB_DQ<21>")
	)
	(segment
		(start 319.279016 -297.401996)
		(end 319.279016 -297.70324)
		(width 0.10668)
		(layer "F.Cu")
		(net "M_A_CPU0_SB_DQ<21>")
	)
	(segment
		(start 308.821328 -307.328062)
		(end 308.821328 -307.478938)
		(width 0.10668)
		(layer "F.Cu")
		(net "M_A_CPU0_SB_DQ<21>")
	)
	(segment
		(start 325.70801 -287.963356)
		(end 324.776846 -287.963356)
		(width 0.0762)
		(layer "F.Cu")
		(net "M_A_CPU0_SB_DQ<21>")
	)
	(segment
		(start 316.325504 -300.656752)
		(end 316.02426 -300.656752)
		(width 0.10668)
		(layer "F.Cu")
		(net "M_A_CPU0_SB_DQ<21>")
	)
	(segment
		(start 310.248808 -306.733448)
		(end 310.117236 -306.86502)
		(width 0.10668)
		(layer "F.Cu")
		(net "M_A_CPU0_SB_DQ<21>")
	)
	(segment
		(start 318.15024 -298.530772)
		(end 318.15024 -298.832016)
		(width 0.10668)
		(layer "F.Cu")
		(net "M_A_CPU0_SB_DQ<21>")
	)
	(segment
		(start 310.813196 -305.867816)
		(end 310.813196 -306.16906)
		(width 0.10668)
		(layer "F.Cu")
		(net "M_A_CPU0_SB_DQ<21>")
	)
	(segment
		(start 310.681624 -306.300632)
		(end 310.38038 -306.300632)
		(width 0.10668)
		(layer "F.Cu")
		(net "M_A_CPU0_SB_DQ<21>")
	)
	(segment
		(start 316.457076 -300.223936)
		(end 316.457076 -300.52518)
		(width 0.10668)
		(layer "F.Cu")
		(net "M_A_CPU0_SB_DQ<21>")
	)
	(segment
		(start 317.021464 -299.659548)
		(end 317.021464 -299.960792)
		(width 0.10668)
		(layer "F.Cu")
		(net "M_A_CPU0_SB_DQ<21>")
	)
	(segment
		(start 317.717424 -298.963588)
		(end 317.585852 -299.09516)
		(width 0.10668)
		(layer "F.Cu")
		(net "M_A_CPU0_SB_DQ<21>")
	)
	(segment
		(start 314.199524 -302.782732)
		(end 314.067952 -302.914304)
		(width 0.10668)
		(layer "F.Cu")
		(net "M_A_CPU0_SB_DQ<21>")
	)
	(segment
		(start 315.196728 -301.785528)
		(end 314.895484 -301.785528)
		(width 0.10668)
		(layer "F.Cu")
		(net "M_A_CPU0_SB_DQ<21>")
	)
	(segment
		(start 311.8104 -305.171856)
		(end 311.509156 -305.171856)
		(width 0.10668)
		(layer "F.Cu")
		(net "M_A_CPU0_SB_DQ<21>")
	)
	(segment
		(start 319.147444 -297.834812)
		(end 318.8462 -297.834812)
		(width 0.10668)
		(layer "F.Cu")
		(net "M_A_CPU0_SB_DQ<21>")
	)
	(segment
		(start 313.635136 -303.045876)
		(end 313.635136 -303.34712)
		(width 0.10668)
		(layer "F.Cu")
		(net "M_A_CPU0_SB_DQ<21>")
	)
	(segment
		(start 309.103522 -307.19649)
		(end 308.952646 -307.196744)
		(width 0.10668)
		(layer "F.Cu")
		(net "M_A_CPU0_SB_DQ<21>")
	)
	(segment
		(start 316.889892 -300.092364)
		(end 316.588648 -300.092364)
		(width 0.10668)
		(layer "F.Cu")
		(net "M_A_CPU0_SB_DQ<21>")
	)
	(segment
		(start 308.936644 -307.744368)
		(end 308.845966 -307.835046)
		(width 0.10668)
		(layer "F.Cu")
		(net "M_A_CPU0_SB_DQ<21>")
	)
	(segment
		(start 318.8462 -297.834812)
		(end 318.714628 -297.966384)
		(width 0.10668)
		(layer "F.Cu")
		(net "M_A_CPU0_SB_DQ<21>")
	)
	(segment
		(start 314.199524 -302.481488)
		(end 314.199524 -302.782732)
		(width 0.10668)
		(layer "F.Cu")
		(net "M_A_CPU0_SB_DQ<21>")
	)
	(segment
		(start 312.939176 -304.04308)
		(end 312.637932 -304.04308)
		(width 0.10668)
		(layer "F.Cu")
		(net "M_A_CPU0_SB_DQ<21>")
	)
	(segment
		(start 317.153036 -299.527976)
		(end 317.021464 -299.659548)
		(width 0.10668)
		(layer "F.Cu")
		(net "M_A_CPU0_SB_DQ<21>")
	)
	(arc
		(start 327.688702 -287.763712)
		(mid 327.672777 -287.904404)
		(end 327.542652 -287.960308)
		(width 0.0762)
		(layer "F.Cu")
		(net "M_A_CPU0_SB_DQ<21>")
	)
	(arc
		(start 327.40092 -287.91281)
		(mid 327.117964 -287.836633)
		(end 326.835008 -287.91281)
		(width 0.0762)
		(layer "F.Cu")
		(net "M_A_CPU0_SB_DQ<21>")
	)
	(arc
		(start 326.826626 -287.917636)
		(mid 326.643118 -287.96313)
		(end 326.460866 -287.91281)
		(width 0.0762)
		(layer "F.Cu")
		(net "M_A_CPU0_SB_DQ<21>")
	)
	(arc
		(start 327.542652 -287.960308)
		(mid 327.473954 -287.945292)
		(end 327.409302 -287.917636)
		(width 0.0762)
		(layer "F.Cu")
		(net "M_A_CPU0_SB_DQ<21>")
	)
	(arc
		(start 325.738998 -287.962086)
		(mid 325.723517 -287.963042)
		(end 325.70801 -287.963356)
		(width 0.0762)
		(layer "F.Cu")
		(net "M_A_CPU0_SB_DQ<21>")
	)
	(arc
		(start 326.460866 -287.91281)
		(mid 326.17791 -287.836633)
		(end 325.894954 -287.91281)
		(width 0.0762)
		(layer "F.Cu")
		(net "M_A_CPU0_SB_DQ<21>")
	)
	(arc
		(start 325.894954 -287.91281)
		(mid 325.819714 -287.946123)
		(end 325.738998 -287.962086)
		(width 0.0762)
		(layer "F.Cu")
		(net "M_A_CPU0_SB_DQ<21>")
	)
	(segment
		(start 315.622432 -299.648626)
		(end 315.622432 -299.799502)
		(width 0.10668)
		(layer "F.Cu")
		(net "M_A_CPU0_SB_DQ<20>")
	)
	(segment
		(start 311.0484 -304.66919)
		(end 310.897524 -304.66919)
		(width 0.10668)
		(layer "F.Cu")
		(net "M_A_CPU0_SB_DQ<20>")
	)
	(segment
		(start 311.107328 -304.16373)
		(end 311.107328 -304.314606)
		(width 0.10668)
		(layer "F.Cu")
		(net "M_A_CPU0_SB_DQ<20>")
	)
	(segment
		(start 314.999116 -300.718474)
		(end 314.84824 -300.718474)
		(width 0.10668)
		(layer "F.Cu")
		(net "M_A_CPU0_SB_DQ<20>")
	)
	(segment
		(start 311.671716 -303.599342)
		(end 311.671716 -303.750218)
		(width 0.10668)
		(layer "F.Cu")
		(net "M_A_CPU0_SB_DQ<20>")
	)
	(segment
		(start 314.84824 -300.718474)
		(end 314.77585 -300.646084)
		(width 0.10668)
		(layer "F.Cu")
		(net "M_A_CPU0_SB_DQ<20>")
	)
	(segment
		(start 310.61533 -304.951384)
		(end 310.61533 -305.10226)
		(width 0.10668)
		(layer "F.Cu")
		(net "M_A_CPU0_SB_DQ<20>")
	)
	(segment
		(start 317.952374 -297.61434)
		(end 317.952374 -297.765216)
		(width 0.10668)
		(layer "F.Cu")
		(net "M_A_CPU0_SB_DQ<20>")
	)
	(segment
		(start 315.058044 -300.36389)
		(end 315.130434 -300.43628)
		(width 0.10668)
		(layer "F.Cu")
		(net "M_A_CPU0_SB_DQ<20>")
	)
	(segment
		(start 314.493656 -300.777402)
		(end 314.493656 -300.928278)
		(width 0.10668)
		(layer "F.Cu")
		(net "M_A_CPU0_SB_DQ<20>")
	)
	(segment
		(start 316.469014 -298.95292)
		(end 316.318138 -298.95292)
		(width 0.10668)
		(layer "F.Cu")
		(net "M_A_CPU0_SB_DQ<20>")
	)
	(segment
		(start 311.95391 -303.468024)
		(end 311.803034 -303.468024)
		(width 0.10668)
		(layer "F.Cu")
		(net "M_A_CPU0_SB_DQ<20>")
	)
	(segment
		(start 316.882526 -298.388532)
		(end 316.751208 -298.51985)
		(width 0.10668)
		(layer "F.Cu")
		(net "M_A_CPU0_SB_DQ<20>")
	)
	(segment
		(start 318.234568 -297.332146)
		(end 318.162178 -297.259756)
		(width 0.10668)
		(layer "F.Cu")
		(net "M_A_CPU0_SB_DQ<20>")
	)
	(segment
		(start 315.412628 -300.154086)
		(end 315.340238 -300.081696)
		(width 0.10668)
		(layer "F.Cu")
		(net "M_A_CPU0_SB_DQ<20>")
	)
	(segment
		(start 313.647074 -301.77486)
		(end 313.496198 -301.77486)
		(width 0.10668)
		(layer "F.Cu")
		(net "M_A_CPU0_SB_DQ<20>")
	)
	(segment
		(start 317.387986 -298.178728)
		(end 317.387986 -298.329604)
		(width 0.10668)
		(layer "F.Cu")
		(net "M_A_CPU0_SB_DQ<20>")
	)
	(segment
		(start 314.211462 -301.210472)
		(end 314.060586 -301.210472)
		(width 0.10668)
		(layer "F.Cu")
		(net "M_A_CPU0_SB_DQ<20>")
	)
	(segment
		(start 312.872882 -302.844708)
		(end 312.741564 -302.976026)
		(width 0.10668)
		(layer "F.Cu")
		(net "M_A_CPU0_SB_DQ<20>")
	)
	(segment
		(start 318.444372 -296.977562)
		(end 318.516762 -297.049952)
		(width 0.10668)
		(layer "F.Cu")
		(net "M_A_CPU0_SB_DQ<20>")
	)
	(segment
		(start 317.59779 -297.824144)
		(end 317.446914 -297.824144)
		(width 0.10668)
		(layer "F.Cu")
		(net "M_A_CPU0_SB_DQ<20>")
	)
	(segment
		(start 315.189362 -300.081696)
		(end 315.058044 -300.213014)
		(width 0.10668)
		(layer "F.Cu")
		(net "M_A_CPU0_SB_DQ<20>")
	)
	(segment
		(start 313.305952 -302.411638)
		(end 313.155076 -302.411638)
		(width 0.10668)
		(layer "F.Cu")
		(net "M_A_CPU0_SB_DQ<20>")
	)
	(segment
		(start 312.800492 -302.621442)
		(end 312.872882 -302.693832)
		(width 0.10668)
		(layer "F.Cu")
		(net "M_A_CPU0_SB_DQ<20>")
	)
	(segment
		(start 311.671716 -303.750218)
		(end 311.744106 -303.822608)
		(width 0.10668)
		(layer "F.Cu")
		(net "M_A_CPU0_SB_DQ<20>")
	)
	(segment
		(start 324.282308 -287.026604)
		(end 324.038214 -286.78251)
		(width 0.0762)
		(layer "F.Cu")
		(net "M_A_CPU0_SB_DQ<20>")
	)
	(segment
		(start 315.904626 -299.517308)
		(end 315.75375 -299.517308)
		(width 0.10668)
		(layer "F.Cu")
		(net "M_A_CPU0_SB_DQ<20>")
	)
	(segment
		(start 314.434728 -301.282862)
		(end 314.283852 -301.282862)
		(width 0.10668)
		(layer "F.Cu")
		(net "M_A_CPU0_SB_DQ<20>")
	)
	(segment
		(start 317.315596 -297.955462)
		(end 317.315596 -298.106338)
		(width 0.10668)
		(layer "F.Cu")
		(net "M_A_CPU0_SB_DQ<20>")
	)
	(segment
		(start 314.283852 -301.282862)
		(end 314.211462 -301.210472)
		(width 0.10668)
		(layer "F.Cu")
		(net "M_A_CPU0_SB_DQ<20>")
	)
	(segment
		(start 312.741564 -302.976026)
		(end 312.590688 -302.976026)
		(width 0.10668)
		(layer "F.Cu")
		(net "M_A_CPU0_SB_DQ<20>")
	)
	(segment
		(start 317.387986 -298.329604)
		(end 317.256668 -298.460922)
		(width 0.10668)
		(layer "F.Cu")
		(net "M_A_CPU0_SB_DQ<20>")
	)
	(segment
		(start 313.36488 -301.906178)
		(end 313.36488 -302.057054)
		(width 0.10668)
		(layer "F.Cu")
		(net "M_A_CPU0_SB_DQ<20>")
	)
	(segment
		(start 313.496198 -301.77486)
		(end 313.36488 -301.906178)
		(width 0.10668)
		(layer "F.Cu")
		(net "M_A_CPU0_SB_DQ<20>")
	)
	(segment
		(start 312.236104 -303.034954)
		(end 312.236104 -303.18583)
		(width 0.10668)
		(layer "F.Cu")
		(net "M_A_CPU0_SB_DQ<20>")
	)
	(segment
		(start 317.105792 -298.460922)
		(end 317.033402 -298.388532)
		(width 0.10668)
		(layer "F.Cu")
		(net "M_A_CPU0_SB_DQ<20>")
	)
	(segment
		(start 314.624974 -300.646084)
		(end 314.493656 -300.777402)
		(width 0.10668)
		(layer "F.Cu")
		(net "M_A_CPU0_SB_DQ<20>")
	)
	(segment
		(start 316.25921 -299.45838)
		(end 316.127892 -299.589698)
		(width 0.10668)
		(layer "F.Cu")
		(net "M_A_CPU0_SB_DQ<20>")
	)
	(segment
		(start 315.622432 -299.799502)
		(end 315.694822 -299.871892)
		(width 0.10668)
		(layer "F.Cu")
		(net "M_A_CPU0_SB_DQ<20>")
	)
	(segment
		(start 316.69228 -299.02531)
		(end 316.541404 -299.02531)
		(width 0.10668)
		(layer "F.Cu")
		(net "M_A_CPU0_SB_DQ<20>")
	)
	(segment
		(start 309.136034 -306.135024)
		(end 307.368194 -306.135024)
		(width 0.10668)
		(layer "F.Cu")
		(net "M_A_CPU0_SB_DQ<20>")
	)
	(segment
		(start 313.719464 -301.84725)
		(end 313.647074 -301.77486)
		(width 0.10668)
		(layer "F.Cu")
		(net "M_A_CPU0_SB_DQ<20>")
	)
	(segment
		(start 316.18682 -299.235114)
		(end 316.25921 -299.307504)
		(width 0.10668)
		(layer "F.Cu")
		(net "M_A_CPU0_SB_DQ<20>")
	)
	(segment
		(start 314.060586 -301.210472)
		(end 313.929268 -301.34179)
		(width 0.10668)
		(layer "F.Cu")
		(net "M_A_CPU0_SB_DQ<20>")
	)
	(segment
		(start 312.0263 -303.540414)
		(end 311.95391 -303.468024)
		(width 0.10668)
		(layer "F.Cu")
		(net "M_A_CPU0_SB_DQ<20>")
	)
	(segment
		(start 310.61533 -305.10226)
		(end 310.484012 -305.233578)
		(width 0.10668)
		(layer "F.Cu")
		(net "M_A_CPU0_SB_DQ<20>")
	)
	(segment
		(start 312.872882 -302.693832)
		(end 312.872882 -302.844708)
		(width 0.10668)
		(layer "F.Cu")
		(net "M_A_CPU0_SB_DQ<20>")
	)
	(segment
		(start 317.446914 -297.824144)
		(end 317.315596 -297.955462)
		(width 0.10668)
		(layer "F.Cu")
		(net "M_A_CPU0_SB_DQ<20>")
	)
	(segment
		(start 315.694822 -300.022768)
		(end 315.563504 -300.154086)
		(width 0.10668)
		(layer "F.Cu")
		(net "M_A_CPU0_SB_DQ<20>")
	)
	(segment
		(start 313.082686 -302.339248)
		(end 312.93181 -302.339248)
		(width 0.10668)
		(layer "F.Cu")
		(net "M_A_CPU0_SB_DQ<20>")
	)
	(segment
		(start 317.033402 -298.388532)
		(end 316.882526 -298.388532)
		(width 0.10668)
		(layer "F.Cu")
		(net "M_A_CPU0_SB_DQ<20>")
	)
	(segment
		(start 312.800492 -302.470566)
		(end 312.800492 -302.621442)
		(width 0.10668)
		(layer "F.Cu")
		(net "M_A_CPU0_SB_DQ<20>")
	)
	(segment
		(start 312.308494 -303.409096)
		(end 312.177176 -303.540414)
		(width 0.10668)
		(layer "F.Cu")
		(net "M_A_CPU0_SB_DQ<20>")
	)
	(segment
		(start 318.81826 -290.739068)
		(end 318.81826 -296.452798)
		(width 0.10668)
		(layer "F.Cu")
		(net "M_A_CPU0_SB_DQ<20>")
	)
	(segment
		(start 310.10987 -305.161188)
		(end 309.136034 -306.135024)
		(width 0.10668)
		(layer "F.Cu")
		(net "M_A_CPU0_SB_DQ<20>")
	)
	(segment
		(start 325.70801 -287.026604)
		(end 324.282308 -287.026604)
		(width 0.0762)
		(layer "F.Cu")
		(net "M_A_CPU0_SB_DQ<20>")
	)
	(segment
		(start 317.821056 -297.896534)
		(end 317.67018 -297.896534)
		(width 0.10668)
		(layer "F.Cu")
		(net "M_A_CPU0_SB_DQ<20>")
	)
	(segment
		(start 315.130434 -300.43628)
		(end 315.130434 -300.587156)
		(width 0.10668)
		(layer "F.Cu")
		(net "M_A_CPU0_SB_DQ<20>")
	)
	(segment
		(start 315.694822 -299.871892)
		(end 315.694822 -300.022768)
		(width 0.10668)
		(layer "F.Cu")
		(net "M_A_CPU0_SB_DQ<20>")
	)
	(segment
		(start 313.36488 -302.057054)
		(end 313.43727 -302.129444)
		(width 0.10668)
		(layer "F.Cu")
		(net "M_A_CPU0_SB_DQ<20>")
	)
	(segment
		(start 315.130434 -300.587156)
		(end 314.999116 -300.718474)
		(width 0.10668)
		(layer "F.Cu")
		(net "M_A_CPU0_SB_DQ<20>")
	)
	(segment
		(start 311.107328 -304.314606)
		(end 311.179718 -304.386996)
		(width 0.10668)
		(layer "F.Cu")
		(net "M_A_CPU0_SB_DQ<20>")
	)
	(segment
		(start 317.879984 -297.391074)
		(end 317.879984 -297.54195)
		(width 0.10668)
		(layer "F.Cu")
		(net "M_A_CPU0_SB_DQ<20>")
	)
	(segment
		(start 315.75375 -299.517308)
		(end 315.622432 -299.648626)
		(width 0.10668)
		(layer "F.Cu")
		(net "M_A_CPU0_SB_DQ<20>")
	)
	(segment
		(start 315.058044 -300.213014)
		(end 315.058044 -300.36389)
		(width 0.10668)
		(layer "F.Cu")
		(net "M_A_CPU0_SB_DQ<20>")
	)
	(segment
		(start 315.563504 -300.154086)
		(end 315.412628 -300.154086)
		(width 0.10668)
		(layer "F.Cu")
		(net "M_A_CPU0_SB_DQ<20>")
	)
	(segment
		(start 312.177176 -303.540414)
		(end 312.0263 -303.540414)
		(width 0.10668)
		(layer "F.Cu")
		(net "M_A_CPU0_SB_DQ<20>")
	)
	(segment
		(start 311.179718 -304.537872)
		(end 311.0484 -304.66919)
		(width 0.10668)
		(layer "F.Cu")
		(net "M_A_CPU0_SB_DQ<20>")
	)
	(segment
		(start 316.541404 -299.02531)
		(end 316.469014 -298.95292)
		(width 0.10668)
		(layer "F.Cu")
		(net "M_A_CPU0_SB_DQ<20>")
	)
	(segment
		(start 315.340238 -300.081696)
		(end 315.189362 -300.081696)
		(width 0.10668)
		(layer "F.Cu")
		(net "M_A_CPU0_SB_DQ<20>")
	)
	(segment
		(start 311.803034 -303.468024)
		(end 311.671716 -303.599342)
		(width 0.10668)
		(layer "F.Cu")
		(net "M_A_CPU0_SB_DQ<20>")
	)
	(segment
		(start 311.612788 -304.104802)
		(end 311.461912 -304.104802)
		(width 0.10668)
		(layer "F.Cu")
		(net "M_A_CPU0_SB_DQ<20>")
	)
	(segment
		(start 311.179718 -304.386996)
		(end 311.179718 -304.537872)
		(width 0.10668)
		(layer "F.Cu")
		(net "M_A_CPU0_SB_DQ<20>")
	)
	(segment
		(start 317.256668 -298.460922)
		(end 317.105792 -298.460922)
		(width 0.10668)
		(layer "F.Cu")
		(net "M_A_CPU0_SB_DQ<20>")
	)
	(segment
		(start 310.333136 -305.233578)
		(end 310.260746 -305.161188)
		(width 0.10668)
		(layer "F.Cu")
		(net "M_A_CPU0_SB_DQ<20>")
	)
	(segment
		(start 313.929268 -301.492666)
		(end 314.001658 -301.565056)
		(width 0.10668)
		(layer "F.Cu")
		(net "M_A_CPU0_SB_DQ<20>")
	)
	(segment
		(start 311.744106 -303.973484)
		(end 311.612788 -304.104802)
		(width 0.10668)
		(layer "F.Cu")
		(net "M_A_CPU0_SB_DQ<20>")
	)
	(segment
		(start 310.484012 -305.233578)
		(end 310.333136 -305.233578)
		(width 0.10668)
		(layer "F.Cu")
		(net "M_A_CPU0_SB_DQ<20>")
	)
	(segment
		(start 312.236104 -303.18583)
		(end 312.308494 -303.25822)
		(width 0.10668)
		(layer "F.Cu")
		(net "M_A_CPU0_SB_DQ<20>")
	)
	(segment
		(start 318.444372 -296.826686)
		(end 318.444372 -296.977562)
		(width 0.10668)
		(layer "F.Cu")
		(net "M_A_CPU0_SB_DQ<20>")
	)
	(segment
		(start 314.001658 -301.565056)
		(end 314.001658 -301.715932)
		(width 0.10668)
		(layer "F.Cu")
		(net "M_A_CPU0_SB_DQ<20>")
	)
	(segment
		(start 311.389522 -304.032412)
		(end 311.238646 -304.032412)
		(width 0.10668)
		(layer "F.Cu")
		(net "M_A_CPU0_SB_DQ<20>")
	)
	(segment
		(start 316.18682 -299.084238)
		(end 316.18682 -299.235114)
		(width 0.10668)
		(layer "F.Cu")
		(net "M_A_CPU0_SB_DQ<20>")
	)
	(segment
		(start 312.367422 -302.903636)
		(end 312.236104 -303.034954)
		(width 0.10668)
		(layer "F.Cu")
		(net "M_A_CPU0_SB_DQ<20>")
	)
	(segment
		(start 310.674258 -304.5968)
		(end 310.54294 -304.728118)
		(width 0.10668)
		(layer "F.Cu")
		(net "M_A_CPU0_SB_DQ<20>")
	)
	(segment
		(start 312.93181 -302.339248)
		(end 312.800492 -302.470566)
		(width 0.10668)
		(layer "F.Cu")
		(net "M_A_CPU0_SB_DQ<20>")
	)
	(segment
		(start 310.54294 -304.878994)
		(end 310.61533 -304.951384)
		(width 0.10668)
		(layer "F.Cu")
		(net "M_A_CPU0_SB_DQ<20>")
	)
	(segment
		(start 326.17791 -286.780224)
		(end 326.276208 -286.949388)
		(width 0.0762)
		(layer "F.Cu")
		(net "M_A_CPU0_SB_DQ<20>")
	)
	(segment
		(start 310.260746 -305.161188)
		(end 310.10987 -305.161188)
		(width 0.10668)
		(layer "F.Cu")
		(net "M_A_CPU0_SB_DQ<20>")
	)
	(segment
		(start 316.127892 -299.589698)
		(end 315.977016 -299.589698)
		(width 0.10668)
		(layer "F.Cu")
		(net "M_A_CPU0_SB_DQ<20>")
	)
	(segment
		(start 313.929268 -301.34179)
		(end 313.929268 -301.492666)
		(width 0.10668)
		(layer "F.Cu")
		(net "M_A_CPU0_SB_DQ<20>")
	)
	(segment
		(start 314.566046 -301.151544)
		(end 314.434728 -301.282862)
		(width 0.10668)
		(layer "F.Cu")
		(net "M_A_CPU0_SB_DQ<20>")
	)
	(segment
		(start 316.318138 -298.95292)
		(end 316.18682 -299.084238)
		(width 0.10668)
		(layer "F.Cu")
		(net "M_A_CPU0_SB_DQ<20>")
	)
	(segment
		(start 318.516762 -297.049952)
		(end 318.516762 -297.200828)
		(width 0.10668)
		(layer "F.Cu")
		(net "M_A_CPU0_SB_DQ<20>")
	)
	(segment
		(start 312.308494 -303.25822)
		(end 312.308494 -303.409096)
		(width 0.10668)
		(layer "F.Cu")
		(net "M_A_CPU0_SB_DQ<20>")
	)
	(segment
		(start 311.461912 -304.104802)
		(end 311.389522 -304.032412)
		(width 0.10668)
		(layer "F.Cu")
		(net "M_A_CPU0_SB_DQ<20>")
	)
	(segment
		(start 318.385444 -297.332146)
		(end 318.234568 -297.332146)
		(width 0.10668)
		(layer "F.Cu")
		(net "M_A_CPU0_SB_DQ<20>")
	)
	(segment
		(start 324.038214 -286.78251)
		(end 322.774818 -286.78251)
		(width 0.10668)
		(layer "F.Cu")
		(net "M_A_CPU0_SB_DQ<20>")
	)
	(segment
		(start 317.315596 -298.106338)
		(end 317.387986 -298.178728)
		(width 0.10668)
		(layer "F.Cu")
		(net "M_A_CPU0_SB_DQ<20>")
	)
	(segment
		(start 318.81826 -296.452798)
		(end 318.444372 -296.826686)
		(width 0.10668)
		(layer "F.Cu")
		(net "M_A_CPU0_SB_DQ<20>")
	)
	(segment
		(start 318.162178 -297.259756)
		(end 318.011302 -297.259756)
		(width 0.10668)
		(layer "F.Cu")
		(net "M_A_CPU0_SB_DQ<20>")
	)
	(segment
		(start 312.518298 -302.903636)
		(end 312.367422 -302.903636)
		(width 0.10668)
		(layer "F.Cu")
		(net "M_A_CPU0_SB_DQ<20>")
	)
	(segment
		(start 316.823598 -298.743116)
		(end 316.823598 -298.893992)
		(width 0.10668)
		(layer "F.Cu")
		(net "M_A_CPU0_SB_DQ<20>")
	)
	(segment
		(start 311.744106 -303.822608)
		(end 311.744106 -303.973484)
		(width 0.10668)
		(layer "F.Cu")
		(net "M_A_CPU0_SB_DQ<20>")
	)
	(segment
		(start 316.751208 -298.670726)
		(end 316.823598 -298.743116)
		(width 0.10668)
		(layer "F.Cu")
		(net "M_A_CPU0_SB_DQ<20>")
	)
	(segment
		(start 316.751208 -298.51985)
		(end 316.751208 -298.670726)
		(width 0.10668)
		(layer "F.Cu")
		(net "M_A_CPU0_SB_DQ<20>")
	)
	(segment
		(start 317.879984 -297.54195)
		(end 317.952374 -297.61434)
		(width 0.10668)
		(layer "F.Cu")
		(net "M_A_CPU0_SB_DQ<20>")
	)
	(segment
		(start 313.155076 -302.411638)
		(end 313.082686 -302.339248)
		(width 0.10668)
		(layer "F.Cu")
		(net "M_A_CPU0_SB_DQ<20>")
	)
	(segment
		(start 313.87034 -301.84725)
		(end 313.719464 -301.84725)
		(width 0.10668)
		(layer "F.Cu")
		(net "M_A_CPU0_SB_DQ<20>")
	)
	(segment
		(start 317.67018 -297.896534)
		(end 317.59779 -297.824144)
		(width 0.10668)
		(layer "F.Cu")
		(net "M_A_CPU0_SB_DQ<20>")
	)
	(segment
		(start 314.566046 -301.000668)
		(end 314.566046 -301.151544)
		(width 0.10668)
		(layer "F.Cu")
		(net "M_A_CPU0_SB_DQ<20>")
	)
	(segment
		(start 317.952374 -297.765216)
		(end 317.821056 -297.896534)
		(width 0.10668)
		(layer "F.Cu")
		(net "M_A_CPU0_SB_DQ<20>")
	)
	(segment
		(start 314.493656 -300.928278)
		(end 314.566046 -301.000668)
		(width 0.10668)
		(layer "F.Cu")
		(net "M_A_CPU0_SB_DQ<20>")
	)
	(segment
		(start 316.25921 -299.307504)
		(end 316.25921 -299.45838)
		(width 0.10668)
		(layer "F.Cu")
		(net "M_A_CPU0_SB_DQ<20>")
	)
	(segment
		(start 322.774818 -286.78251)
		(end 318.81826 -290.739068)
		(width 0.10668)
		(layer "F.Cu")
		(net "M_A_CPU0_SB_DQ<20>")
	)
	(segment
		(start 314.001658 -301.715932)
		(end 313.87034 -301.84725)
		(width 0.10668)
		(layer "F.Cu")
		(net "M_A_CPU0_SB_DQ<20>")
	)
	(segment
		(start 318.011302 -297.259756)
		(end 317.879984 -297.391074)
		(width 0.10668)
		(layer "F.Cu")
		(net "M_A_CPU0_SB_DQ<20>")
	)
	(segment
		(start 314.77585 -300.646084)
		(end 314.624974 -300.646084)
		(width 0.10668)
		(layer "F.Cu")
		(net "M_A_CPU0_SB_DQ<20>")
	)
	(segment
		(start 318.516762 -297.200828)
		(end 318.385444 -297.332146)
		(width 0.10668)
		(layer "F.Cu")
		(net "M_A_CPU0_SB_DQ<20>")
	)
	(segment
		(start 313.43727 -302.28032)
		(end 313.305952 -302.411638)
		(width 0.10668)
		(layer "F.Cu")
		(net "M_A_CPU0_SB_DQ<20>")
	)
	(segment
		(start 311.238646 -304.032412)
		(end 311.107328 -304.16373)
		(width 0.10668)
		(layer "F.Cu")
		(net "M_A_CPU0_SB_DQ<20>")
	)
	(segment
		(start 310.54294 -304.728118)
		(end 310.54294 -304.878994)
		(width 0.10668)
		(layer "F.Cu")
		(net "M_A_CPU0_SB_DQ<20>")
	)
	(segment
		(start 316.823598 -298.893992)
		(end 316.69228 -299.02531)
		(width 0.10668)
		(layer "F.Cu")
		(net "M_A_CPU0_SB_DQ<20>")
	)
	(segment
		(start 325.999348 -287.10763)
		(end 325.990966 -287.102804)
		(width 0.0762)
		(layer "F.Cu")
		(net "M_A_CPU0_SB_DQ<20>")
	)
	(segment
		(start 312.590688 -302.976026)
		(end 312.518298 -302.903636)
		(width 0.10668)
		(layer "F.Cu")
		(net "M_A_CPU0_SB_DQ<20>")
	)
	(segment
		(start 313.43727 -302.129444)
		(end 313.43727 -302.28032)
		(width 0.10668)
		(layer "F.Cu")
		(net "M_A_CPU0_SB_DQ<20>")
	)
	(segment
		(start 315.977016 -299.589698)
		(end 315.904626 -299.517308)
		(width 0.10668)
		(layer "F.Cu")
		(net "M_A_CPU0_SB_DQ<20>")
	)
	(segment
		(start 310.897524 -304.66919)
		(end 310.825134 -304.5968)
		(width 0.10668)
		(layer "F.Cu")
		(net "M_A_CPU0_SB_DQ<20>")
	)
	(segment
		(start 310.825134 -304.5968)
		(end 310.674258 -304.5968)
		(width 0.10668)
		(layer "F.Cu")
		(net "M_A_CPU0_SB_DQ<20>")
	)
	(arc
		(start 325.990966 -287.102804)
		(mid 325.85453 -287.045979)
		(end 325.70801 -287.026604)
		(width 0.0762)
		(layer "F.Cu")
		(net "M_A_CPU0_SB_DQ<20>")
	)
	(arc
		(start 326.13854 -287.151064)
		(mid 326.066802 -287.136212)
		(end 325.999348 -287.10763)
		(width 0.0762)
		(layer "F.Cu")
		(net "M_A_CPU0_SB_DQ<20>")
	)
	(arc
		(start 326.276208 -286.949388)
		(mid 326.267615 -287.091267)
		(end 326.13854 -287.151064)
		(width 0.0762)
		(layer "F.Cu")
		(net "M_A_CPU0_SB_DQ<20>")
	)
	(segment
		(start 313.710574 -277.443438)
		(end 313.579256 -277.574756)
		(width 0.10668)
		(layer "F.Cu")
		(net "M_A_CPU0_SB_DQ<1>")
	)
	(segment
		(start 314.499244 -276.952456)
		(end 314.425838 -276.87905)
		(width 0.10668)
		(layer "F.Cu")
		(net "M_A_CPU0_SB_DQ<1>")
	)
	(segment
		(start 313.579256 -277.574756)
		(end 313.579256 -277.725632)
		(width 0.10668)
		(layer "F.Cu")
		(net "M_A_CPU0_SB_DQ<1>")
	)
	(segment
		(start 316.604142 -274.54987)
		(end 316.401196 -274.752816)
		(width 0.10668)
		(layer "F.Cu")
		(net "M_A_CPU0_SB_DQ<1>")
	)
	(segment
		(start 315.214508 -276.388068)
		(end 315.063632 -276.388068)
		(width 0.10668)
		(layer "F.Cu")
		(net "M_A_CPU0_SB_DQ<1>")
	)
	(segment
		(start 310.699404 -280.903172)
		(end 310.548528 -280.903172)
		(width 0.10668)
		(layer "F.Cu")
		(net "M_A_CPU0_SB_DQ<1>")
	)
	(segment
		(start 312.01741 -279.136602)
		(end 311.886092 -279.26792)
		(width 0.10668)
		(layer "F.Cu")
		(net "M_A_CPU0_SB_DQ<1>")
	)
	(segment
		(start 308.267354 -283.185108)
		(end 307.368194 -283.185108)
		(width 0.10668)
		(layer "F.Cu")
		(net "M_A_CPU0_SB_DQ<1>")
	)
	(segment
		(start 309.62854 -281.525472)
		(end 309.62854 -281.676348)
		(width 0.10668)
		(layer "F.Cu")
		(net "M_A_CPU0_SB_DQ<1>")
	)
	(segment
		(start 313.579256 -277.725632)
		(end 313.652662 -277.799038)
		(width 0.10668)
		(layer "F.Cu")
		(net "M_A_CPU0_SB_DQ<1>")
	)
	(segment
		(start 312.523886 -278.927814)
		(end 312.523886 -279.07869)
		(width 0.10668)
		(layer "F.Cu")
		(net "M_A_CPU0_SB_DQ<1>")
	)
	(segment
		(start 312.45048 -278.854408)
		(end 312.523886 -278.927814)
		(width 0.10668)
		(layer "F.Cu")
		(net "M_A_CPU0_SB_DQ<1>")
	)
	(segment
		(start 311.39511 -280.207466)
		(end 311.263792 -280.338784)
		(width 0.10668)
		(layer "F.Cu")
		(net "M_A_CPU0_SB_DQ<1>")
	)
	(segment
		(start 311.959498 -279.643078)
		(end 311.82818 -279.774396)
		(width 0.10668)
		(layer "F.Cu")
		(net "M_A_CPU0_SB_DQ<1>")
	)
	(segment
		(start 310.475122 -280.829766)
		(end 310.324246 -280.829766)
		(width 0.10668)
		(layer "F.Cu")
		(net "M_A_CPU0_SB_DQ<1>")
	)
	(segment
		(start 316.119002 -275.185886)
		(end 315.968126 -275.185886)
		(width 0.10668)
		(layer "F.Cu")
		(net "M_A_CPU0_SB_DQ<1>")
	)
	(segment
		(start 309.62854 -281.676348)
		(end 309.701946 -281.749754)
		(width 0.10668)
		(layer "F.Cu")
		(net "M_A_CPU0_SB_DQ<1>")
	)
	(segment
		(start 327.409302 -274.95754)
		(end 327.40092 -274.952714)
		(width 0.0762)
		(layer "F.Cu")
		(net "M_A_CPU0_SB_DQ<1>")
	)
	(segment
		(start 314.781438 -276.821138)
		(end 314.65012 -276.952456)
		(width 0.10668)
		(layer "F.Cu")
		(net "M_A_CPU0_SB_DQ<1>")
	)
	(segment
		(start 315.27242 -275.881592)
		(end 315.27242 -276.032468)
		(width 0.10668)
		(layer "F.Cu")
		(net "M_A_CPU0_SB_DQ<1>")
	)
	(segment
		(start 314.425838 -276.87905)
		(end 314.274962 -276.87905)
		(width 0.10668)
		(layer "F.Cu")
		(net "M_A_CPU0_SB_DQ<1>")
	)
	(segment
		(start 316.474602 -275.127974)
		(end 316.343284 -275.259292)
		(width 0.10668)
		(layer "F.Cu")
		(net "M_A_CPU0_SB_DQ<1>")
	)
	(segment
		(start 309.570628 -282.031948)
		(end 309.419752 -282.031948)
		(width 0.10668)
		(layer "F.Cu")
		(net "M_A_CPU0_SB_DQ<1>")
	)
	(segment
		(start 308.384194 -282.37815)
		(end 308.384194 -283.068268)
		(width 0.10668)
		(layer "F.Cu")
		(net "M_A_CPU0_SB_DQ<1>")
	)
	(segment
		(start 315.968126 -275.185886)
		(end 315.836808 -275.317204)
		(width 0.10668)
		(layer "F.Cu")
		(net "M_A_CPU0_SB_DQ<1>")
	)
	(segment
		(start 313.521344 -278.081232)
		(end 313.370468 -278.081232)
		(width 0.10668)
		(layer "F.Cu")
		(net "M_A_CPU0_SB_DQ<1>")
	)
	(segment
		(start 313.297062 -278.007826)
		(end 313.146186 -278.007826)
		(width 0.10668)
		(layer "F.Cu")
		(net "M_A_CPU0_SB_DQ<1>")
	)
	(segment
		(start 313.652662 -277.799038)
		(end 313.652662 -277.949914)
		(width 0.10668)
		(layer "F.Cu")
		(net "M_A_CPU0_SB_DQ<1>")
	)
	(segment
		(start 311.677304 -279.774396)
		(end 311.603898 -279.70099)
		(width 0.10668)
		(layer "F.Cu")
		(net "M_A_CPU0_SB_DQ<1>")
	)
	(segment
		(start 315.836808 -275.317204)
		(end 315.836808 -275.46808)
		(width 0.10668)
		(layer "F.Cu")
		(net "M_A_CPU0_SB_DQ<1>")
	)
	(segment
		(start 313.088274 -278.514302)
		(end 312.956956 -278.64562)
		(width 0.10668)
		(layer "F.Cu")
		(net "M_A_CPU0_SB_DQ<1>")
	)
	(segment
		(start 314.21705 -277.385526)
		(end 314.085732 -277.516844)
		(width 0.10668)
		(layer "F.Cu")
		(net "M_A_CPU0_SB_DQ<1>")
	)
	(segment
		(start 315.910214 -275.541486)
		(end 315.910214 -275.692362)
		(width 0.10668)
		(layer "F.Cu")
		(net "M_A_CPU0_SB_DQ<1>")
	)
	(segment
		(start 313.86145 -277.443438)
		(end 313.710574 -277.443438)
		(width 0.10668)
		(layer "F.Cu")
		(net "M_A_CPU0_SB_DQ<1>")
	)
	(segment
		(start 309.701946 -281.749754)
		(end 309.701946 -281.90063)
		(width 0.10668)
		(layer "F.Cu")
		(net "M_A_CPU0_SB_DQ<1>")
	)
	(segment
		(start 324.9041 -275.00326)
		(end 324.45071 -274.54987)
		(width 0.0762)
		(layer "F.Cu")
		(net "M_A_CPU0_SB_DQ<1>")
	)
	(segment
		(start 315.910214 -275.692362)
		(end 315.778896 -275.82368)
		(width 0.10668)
		(layer "F.Cu")
		(net "M_A_CPU0_SB_DQ<1>")
	)
	(segment
		(start 315.836808 -275.46808)
		(end 315.910214 -275.541486)
		(width 0.10668)
		(layer "F.Cu")
		(net "M_A_CPU0_SB_DQ<1>")
	)
	(segment
		(start 315.063632 -276.388068)
		(end 314.990226 -276.314662)
		(width 0.10668)
		(layer "F.Cu")
		(net "M_A_CPU0_SB_DQ<1>")
	)
	(segment
		(start 315.345826 -276.25675)
		(end 315.214508 -276.388068)
		(width 0.10668)
		(layer "F.Cu")
		(net "M_A_CPU0_SB_DQ<1>")
	)
	(segment
		(start 312.732674 -278.572214)
		(end 312.581798 -278.572214)
		(width 0.10668)
		(layer "F.Cu")
		(net "M_A_CPU0_SB_DQ<1>")
	)
	(segment
		(start 315.27242 -276.032468)
		(end 315.345826 -276.105874)
		(width 0.10668)
		(layer "F.Cu")
		(net "M_A_CPU0_SB_DQ<1>")
	)
	(segment
		(start 315.778896 -275.82368)
		(end 315.62802 -275.82368)
		(width 0.10668)
		(layer "F.Cu")
		(net "M_A_CPU0_SB_DQ<1>")
	)
	(segment
		(start 311.321704 -279.983184)
		(end 311.39511 -280.05659)
		(width 0.10668)
		(layer "F.Cu")
		(net "M_A_CPU0_SB_DQ<1>")
	)
	(segment
		(start 316.401196 -274.752816)
		(end 316.401196 -274.903692)
		(width 0.10668)
		(layer "F.Cu")
		(net "M_A_CPU0_SB_DQ<1>")
	)
	(segment
		(start 313.014868 -278.139144)
		(end 313.014868 -278.29002)
		(width 0.10668)
		(layer "F.Cu")
		(net "M_A_CPU0_SB_DQ<1>")
	)
	(segment
		(start 312.241692 -279.210008)
		(end 312.168286 -279.136602)
		(width 0.10668)
		(layer "F.Cu")
		(net "M_A_CPU0_SB_DQ<1>")
	)
	(segment
		(start 312.523886 -279.07869)
		(end 312.392568 -279.210008)
		(width 0.10668)
		(layer "F.Cu")
		(net "M_A_CPU0_SB_DQ<1>")
	)
	(segment
		(start 323.901054 -274.54987)
		(end 316.604142 -274.54987)
		(width 0.10668)
		(layer "F.Cu")
		(net "M_A_CPU0_SB_DQ<1>")
	)
	(segment
		(start 310.192928 -281.11196)
		(end 310.266334 -281.185366)
		(width 0.10668)
		(layer "F.Cu")
		(net "M_A_CPU0_SB_DQ<1>")
	)
	(segment
		(start 314.781438 -276.670262)
		(end 314.781438 -276.821138)
		(width 0.10668)
		(layer "F.Cu")
		(net "M_A_CPU0_SB_DQ<1>")
	)
	(segment
		(start 314.65012 -276.952456)
		(end 314.499244 -276.952456)
		(width 0.10668)
		(layer "F.Cu")
		(net "M_A_CPU0_SB_DQ<1>")
	)
	(segment
		(start 314.085732 -277.516844)
		(end 313.934856 -277.516844)
		(width 0.10668)
		(layer "F.Cu")
		(net "M_A_CPU0_SB_DQ<1>")
	)
	(segment
		(start 310.888634 -280.265378)
		(end 310.757316 -280.396696)
		(width 0.10668)
		(layer "F.Cu")
		(net "M_A_CPU0_SB_DQ<1>")
	)
	(segment
		(start 313.146186 -278.007826)
		(end 313.014868 -278.139144)
		(width 0.10668)
		(layer "F.Cu")
		(net "M_A_CPU0_SB_DQ<1>")
	)
	(segment
		(start 312.956956 -278.64562)
		(end 312.80608 -278.64562)
		(width 0.10668)
		(layer "F.Cu")
		(net "M_A_CPU0_SB_DQ<1>")
	)
	(segment
		(start 310.192928 -280.961084)
		(end 310.192928 -281.11196)
		(width 0.10668)
		(layer "F.Cu")
		(net "M_A_CPU0_SB_DQ<1>")
	)
	(segment
		(start 308.892702 -282.26131)
		(end 308.501034 -282.26131)
		(width 0.10668)
		(layer "F.Cu")
		(net "M_A_CPU0_SB_DQ<1>")
	)
	(segment
		(start 324.45071 -274.54987)
		(end 323.901054 -274.54987)
		(width 0.0762)
		(layer "F.Cu")
		(net "M_A_CPU0_SB_DQ<1>")
	)
	(segment
		(start 313.088274 -278.363426)
		(end 313.088274 -278.514302)
		(width 0.10668)
		(layer "F.Cu")
		(net "M_A_CPU0_SB_DQ<1>")
	)
	(segment
		(start 314.21705 -277.23465)
		(end 314.21705 -277.385526)
		(width 0.10668)
		(layer "F.Cu")
		(net "M_A_CPU0_SB_DQ<1>")
	)
	(segment
		(start 326.835008 -274.952714)
		(end 326.826626 -274.95754)
		(width 0.0762)
		(layer "F.Cu")
		(net "M_A_CPU0_SB_DQ<1>")
	)
	(segment
		(start 308.501034 -282.26131)
		(end 308.384194 -282.37815)
		(width 0.10668)
		(layer "F.Cu")
		(net "M_A_CPU0_SB_DQ<1>")
	)
	(segment
		(start 309.910734 -281.394154)
		(end 309.759858 -281.394154)
		(width 0.10668)
		(layer "F.Cu")
		(net "M_A_CPU0_SB_DQ<1>")
	)
	(segment
		(start 314.274962 -276.87905)
		(end 314.143644 -277.010368)
		(width 0.10668)
		(layer "F.Cu")
		(net "M_A_CPU0_SB_DQ<1>")
	)
	(segment
		(start 314.83935 -276.314662)
		(end 314.708032 -276.44598)
		(width 0.10668)
		(layer "F.Cu")
		(net "M_A_CPU0_SB_DQ<1>")
	)
	(segment
		(start 311.886092 -279.26792)
		(end 311.886092 -279.418796)
		(width 0.10668)
		(layer "F.Cu")
		(net "M_A_CPU0_SB_DQ<1>")
	)
	(segment
		(start 309.98414 -281.46756)
		(end 309.910734 -281.394154)
		(width 0.10668)
		(layer "F.Cu")
		(net "M_A_CPU0_SB_DQ<1>")
	)
	(segment
		(start 316.401196 -274.903692)
		(end 316.474602 -274.977098)
		(width 0.10668)
		(layer "F.Cu")
		(net "M_A_CPU0_SB_DQ<1>")
	)
	(segment
		(start 309.419752 -282.031948)
		(end 309.346346 -281.958542)
		(width 0.10668)
		(layer "F.Cu")
		(net "M_A_CPU0_SB_DQ<1>")
	)
	(segment
		(start 308.384194 -283.068268)
		(end 308.267354 -283.185108)
		(width 0.10668)
		(layer "F.Cu")
		(net "M_A_CPU0_SB_DQ<1>")
	)
	(segment
		(start 313.014868 -278.29002)
		(end 313.088274 -278.363426)
		(width 0.10668)
		(layer "F.Cu")
		(net "M_A_CPU0_SB_DQ<1>")
	)
	(segment
		(start 311.453022 -279.70099)
		(end 311.321704 -279.832308)
		(width 0.10668)
		(layer "F.Cu")
		(net "M_A_CPU0_SB_DQ<1>")
	)
	(segment
		(start 315.345826 -276.105874)
		(end 315.345826 -276.25675)
		(width 0.10668)
		(layer "F.Cu")
		(net "M_A_CPU0_SB_DQ<1>")
	)
	(segment
		(start 309.19547 -281.958542)
		(end 308.892702 -282.26131)
		(width 0.10668)
		(layer "F.Cu")
		(net "M_A_CPU0_SB_DQ<1>")
	)
	(segment
		(start 311.263792 -280.338784)
		(end 311.112916 -280.338784)
		(width 0.10668)
		(layer "F.Cu")
		(net "M_A_CPU0_SB_DQ<1>")
	)
	(segment
		(start 316.474602 -274.977098)
		(end 316.474602 -275.127974)
		(width 0.10668)
		(layer "F.Cu")
		(net "M_A_CPU0_SB_DQ<1>")
	)
	(segment
		(start 315.403738 -275.750274)
		(end 315.27242 -275.881592)
		(width 0.10668)
		(layer "F.Cu")
		(net "M_A_CPU0_SB_DQ<1>")
	)
	(segment
		(start 314.708032 -276.596856)
		(end 314.781438 -276.670262)
		(width 0.10668)
		(layer "F.Cu")
		(net "M_A_CPU0_SB_DQ<1>")
	)
	(segment
		(start 310.548528 -280.903172)
		(end 310.475122 -280.829766)
		(width 0.10668)
		(layer "F.Cu")
		(net "M_A_CPU0_SB_DQ<1>")
	)
	(segment
		(start 311.886092 -279.418796)
		(end 311.959498 -279.492202)
		(width 0.10668)
		(layer "F.Cu")
		(net "M_A_CPU0_SB_DQ<1>")
	)
	(segment
		(start 311.112916 -280.338784)
		(end 311.03951 -280.265378)
		(width 0.10668)
		(layer "F.Cu")
		(net "M_A_CPU0_SB_DQ<1>")
	)
	(segment
		(start 316.343284 -275.259292)
		(end 316.192408 -275.259292)
		(width 0.10668)
		(layer "F.Cu")
		(net "M_A_CPU0_SB_DQ<1>")
	)
	(segment
		(start 310.266334 -281.336242)
		(end 310.135016 -281.46756)
		(width 0.10668)
		(layer "F.Cu")
		(net "M_A_CPU0_SB_DQ<1>")
	)
	(segment
		(start 310.830722 -280.620978)
		(end 310.830722 -280.771854)
		(width 0.10668)
		(layer "F.Cu")
		(net "M_A_CPU0_SB_DQ<1>")
	)
	(segment
		(start 310.324246 -280.829766)
		(end 310.192928 -280.961084)
		(width 0.10668)
		(layer "F.Cu")
		(net "M_A_CPU0_SB_DQ<1>")
	)
	(segment
		(start 310.266334 -281.185366)
		(end 310.266334 -281.336242)
		(width 0.10668)
		(layer "F.Cu")
		(net "M_A_CPU0_SB_DQ<1>")
	)
	(segment
		(start 311.39511 -280.05659)
		(end 311.39511 -280.207466)
		(width 0.10668)
		(layer "F.Cu")
		(net "M_A_CPU0_SB_DQ<1>")
	)
	(segment
		(start 315.62802 -275.82368)
		(end 315.554614 -275.750274)
		(width 0.10668)
		(layer "F.Cu")
		(net "M_A_CPU0_SB_DQ<1>")
	)
	(segment
		(start 312.168286 -279.136602)
		(end 312.01741 -279.136602)
		(width 0.10668)
		(layer "F.Cu")
		(net "M_A_CPU0_SB_DQ<1>")
	)
	(segment
		(start 309.346346 -281.958542)
		(end 309.19547 -281.958542)
		(width 0.10668)
		(layer "F.Cu")
		(net "M_A_CPU0_SB_DQ<1>")
	)
	(segment
		(start 313.934856 -277.516844)
		(end 313.86145 -277.443438)
		(width 0.10668)
		(layer "F.Cu")
		(net "M_A_CPU0_SB_DQ<1>")
	)
	(segment
		(start 310.830722 -280.771854)
		(end 310.699404 -280.903172)
		(width 0.10668)
		(layer "F.Cu")
		(net "M_A_CPU0_SB_DQ<1>")
	)
	(segment
		(start 312.581798 -278.572214)
		(end 312.45048 -278.703532)
		(width 0.10668)
		(layer "F.Cu")
		(net "M_A_CPU0_SB_DQ<1>")
	)
	(segment
		(start 313.370468 -278.081232)
		(end 313.297062 -278.007826)
		(width 0.10668)
		(layer "F.Cu")
		(net "M_A_CPU0_SB_DQ<1>")
	)
	(segment
		(start 311.959498 -279.492202)
		(end 311.959498 -279.643078)
		(width 0.10668)
		(layer "F.Cu")
		(net "M_A_CPU0_SB_DQ<1>")
	)
	(segment
		(start 309.759858 -281.394154)
		(end 309.62854 -281.525472)
		(width 0.10668)
		(layer "F.Cu")
		(net "M_A_CPU0_SB_DQ<1>")
	)
	(segment
		(start 313.652662 -277.949914)
		(end 313.521344 -278.081232)
		(width 0.10668)
		(layer "F.Cu")
		(net "M_A_CPU0_SB_DQ<1>")
	)
	(segment
		(start 316.192408 -275.259292)
		(end 316.119002 -275.185886)
		(width 0.10668)
		(layer "F.Cu")
		(net "M_A_CPU0_SB_DQ<1>")
	)
	(segment
		(start 312.45048 -278.703532)
		(end 312.45048 -278.854408)
		(width 0.10668)
		(layer "F.Cu")
		(net "M_A_CPU0_SB_DQ<1>")
	)
	(segment
		(start 312.80608 -278.64562)
		(end 312.732674 -278.572214)
		(width 0.10668)
		(layer "F.Cu")
		(net "M_A_CPU0_SB_DQ<1>")
	)
	(segment
		(start 327.587864 -274.630134)
		(end 327.688702 -274.803616)
		(width 0.0762)
		(layer "F.Cu")
		(net "M_A_CPU0_SB_DQ<1>")
	)
	(segment
		(start 309.701946 -281.90063)
		(end 309.570628 -282.031948)
		(width 0.10668)
		(layer "F.Cu")
		(net "M_A_CPU0_SB_DQ<1>")
	)
	(segment
		(start 314.143644 -277.161244)
		(end 314.21705 -277.23465)
		(width 0.10668)
		(layer "F.Cu")
		(net "M_A_CPU0_SB_DQ<1>")
	)
	(segment
		(start 311.82818 -279.774396)
		(end 311.677304 -279.774396)
		(width 0.10668)
		(layer "F.Cu")
		(net "M_A_CPU0_SB_DQ<1>")
	)
	(segment
		(start 310.135016 -281.46756)
		(end 309.98414 -281.46756)
		(width 0.10668)
		(layer "F.Cu")
		(net "M_A_CPU0_SB_DQ<1>")
	)
	(segment
		(start 315.554614 -275.750274)
		(end 315.403738 -275.750274)
		(width 0.10668)
		(layer "F.Cu")
		(net "M_A_CPU0_SB_DQ<1>")
	)
	(segment
		(start 311.03951 -280.265378)
		(end 310.888634 -280.265378)
		(width 0.10668)
		(layer "F.Cu")
		(net "M_A_CPU0_SB_DQ<1>")
	)
	(segment
		(start 312.392568 -279.210008)
		(end 312.241692 -279.210008)
		(width 0.10668)
		(layer "F.Cu")
		(net "M_A_CPU0_SB_DQ<1>")
	)
	(segment
		(start 310.757316 -280.396696)
		(end 310.757316 -280.547572)
		(width 0.10668)
		(layer "F.Cu")
		(net "M_A_CPU0_SB_DQ<1>")
	)
	(segment
		(start 314.990226 -276.314662)
		(end 314.83935 -276.314662)
		(width 0.10668)
		(layer "F.Cu")
		(net "M_A_CPU0_SB_DQ<1>")
	)
	(segment
		(start 314.708032 -276.44598)
		(end 314.708032 -276.596856)
		(width 0.10668)
		(layer "F.Cu")
		(net "M_A_CPU0_SB_DQ<1>")
	)
	(segment
		(start 311.603898 -279.70099)
		(end 311.453022 -279.70099)
		(width 0.10668)
		(layer "F.Cu")
		(net "M_A_CPU0_SB_DQ<1>")
	)
	(segment
		(start 310.757316 -280.547572)
		(end 310.830722 -280.620978)
		(width 0.10668)
		(layer "F.Cu")
		(net "M_A_CPU0_SB_DQ<1>")
	)
	(segment
		(start 314.143644 -277.010368)
		(end 314.143644 -277.161244)
		(width 0.10668)
		(layer "F.Cu")
		(net "M_A_CPU0_SB_DQ<1>")
	)
	(segment
		(start 325.70801 -275.00326)
		(end 324.9041 -275.00326)
		(width 0.0762)
		(layer "F.Cu")
		(net "M_A_CPU0_SB_DQ<1>")
	)
	(segment
		(start 311.321704 -279.832308)
		(end 311.321704 -279.983184)
		(width 0.10668)
		(layer "F.Cu")
		(net "M_A_CPU0_SB_DQ<1>")
	)
	(arc
		(start 326.826626 -274.95754)
		(mid 326.643118 -275.003034)
		(end 326.460866 -274.952714)
		(width 0.0762)
		(layer "F.Cu")
		(net "M_A_CPU0_SB_DQ<1>")
	)
	(arc
		(start 327.688702 -274.803616)
		(mid 327.672777 -274.944308)
		(end 327.542652 -275.000212)
		(width 0.0762)
		(layer "F.Cu")
		(net "M_A_CPU0_SB_DQ<1>")
	)
	(arc
		(start 327.40092 -274.952714)
		(mid 327.117964 -274.876537)
		(end 326.835008 -274.952714)
		(width 0.0762)
		(layer "F.Cu")
		(net "M_A_CPU0_SB_DQ<1>")
	)
	(arc
		(start 325.738998 -275.00199)
		(mid 325.723517 -275.002946)
		(end 325.70801 -275.00326)
		(width 0.0762)
		(layer "F.Cu")
		(net "M_A_CPU0_SB_DQ<1>")
	)
	(arc
		(start 327.542652 -275.000212)
		(mid 327.473954 -274.985196)
		(end 327.409302 -274.95754)
		(width 0.0762)
		(layer "F.Cu")
		(net "M_A_CPU0_SB_DQ<1>")
	)
	(arc
		(start 326.460866 -274.952714)
		(mid 326.17791 -274.876537)
		(end 325.894954 -274.952714)
		(width 0.0762)
		(layer "F.Cu")
		(net "M_A_CPU0_SB_DQ<1>")
	)
	(arc
		(start 325.894954 -274.952714)
		(mid 325.819714 -274.986027)
		(end 325.738998 -275.00199)
		(width 0.0762)
		(layer "F.Cu")
		(net "M_A_CPU0_SB_DQ<1>")
	)
	(segment
		(start 309.110888 -301.576486)
		(end 309.4736 -301.939198)
		(width 0.10668)
		(layer "F.Cu")
		(net "M_A_CPU0_SB_DQ<19>")
	)
	(segment
		(start 321.986656 -284.83306)
		(end 316.90437 -289.915346)
		(width 0.10668)
		(layer "F.Cu")
		(net "M_A_CPU0_SB_DQ<19>")
	)
	(segment
		(start 305.655726 -302.310038)
		(end 305.230784 -302.73498)
		(width 0.101346)
		(layer "F.Cu")
		(net "M_A_CPU0_SB_DQ<19>")
	)
	(segment
		(start 309.253382 -302.310038)
		(end 308.66588 -302.310038)
		(width 0.10668)
		(layer "F.Cu")
		(net "M_A_CPU0_SB_DQ<19>")
	)
	(segment
		(start 325.708264 -284.913832)
		(end 324.038976 -284.913832)
		(width 0.0762)
		(layer "F.Cu")
		(net "M_A_CPU0_SB_DQ<19>")
	)
	(segment
		(start 309.4736 -301.939198)
		(end 309.473346 -302.090074)
		(width 0.10668)
		(layer "F.Cu")
		(net "M_A_CPU0_SB_DQ<19>")
	)
	(segment
		(start 325.999348 -284.832806)
		(end 325.990966 -284.837632)
		(width 0.0762)
		(layer "F.Cu")
		(net "M_A_CPU0_SB_DQ<19>")
	)
	(segment
		(start 323.958204 -284.83306)
		(end 321.986656 -284.83306)
		(width 0.10668)
		(layer "F.Cu")
		(net "M_A_CPU0_SB_DQ<19>")
	)
	(segment
		(start 309.906416 -301.657004)
		(end 309.75554 -301.657004)
		(width 0.10668)
		(layer "F.Cu")
		(net "M_A_CPU0_SB_DQ<19>")
	)
	(segment
		(start 309.392828 -301.294292)
		(end 309.24246 -301.294038)
		(width 0.10668)
		(layer "F.Cu")
		(net "M_A_CPU0_SB_DQ<19>")
	)
	(segment
		(start 309.75554 -301.657004)
		(end 309.392828 -301.294292)
		(width 0.10668)
		(layer "F.Cu")
		(net "M_A_CPU0_SB_DQ<19>")
	)
	(segment
		(start 316.90437 -289.915346)
		(end 316.90437 -294.65905)
		(width 0.10668)
		(layer "F.Cu")
		(net "M_A_CPU0_SB_DQ<19>")
	)
	(segment
		(start 305.230784 -302.73498)
		(end 303.268126 -302.73498)
		(width 0.101346)
		(layer "F.Cu")
		(net "M_A_CPU0_SB_DQ<19>")
	)
	(segment
		(start 309.24246 -301.294038)
		(end 309.110888 -301.42561)
		(width 0.10668)
		(layer "F.Cu")
		(net "M_A_CPU0_SB_DQ<19>")
	)
	(segment
		(start 308.66588 -302.310038)
		(end 305.655726 -302.310038)
		(width 0.101346)
		(layer "F.Cu")
		(net "M_A_CPU0_SB_DQ<19>")
	)
	(segment
		(start 324.038976 -284.913832)
		(end 323.958204 -284.83306)
		(width 0.0762)
		(layer "F.Cu")
		(net "M_A_CPU0_SB_DQ<19>")
	)
	(segment
		(start 309.473346 -302.090074)
		(end 309.253382 -302.310038)
		(width 0.10668)
		(layer "F.Cu")
		(net "M_A_CPU0_SB_DQ<19>")
	)
	(segment
		(start 309.110888 -301.42561)
		(end 309.110888 -301.576486)
		(width 0.10668)
		(layer "F.Cu")
		(net "M_A_CPU0_SB_DQ<19>")
	)
	(segment
		(start 316.90437 -294.65905)
		(end 309.906416 -301.657004)
		(width 0.10668)
		(layer "F.Cu")
		(net "M_A_CPU0_SB_DQ<19>")
	)
	(arc
		(start 325.755254 -284.912054)
		(mid 325.731777 -284.91343)
		(end 325.708264 -284.913832)
		(width 0.0762)
		(layer "F.Cu")
		(net "M_A_CPU0_SB_DQ<19>")
	)
	(arc
		(start 325.990966 -284.837632)
		(mid 325.877242 -284.887933)
		(end 325.755254 -284.912054)
		(width 0.0762)
		(layer "F.Cu")
		(net "M_A_CPU0_SB_DQ<19>")
	)
	(arc
		(start 326.365108 -284.837632)
		(mid 326.182857 -284.787282)
		(end 325.999348 -284.832806)
		(width 0.0762)
		(layer "F.Cu")
		(net "M_A_CPU0_SB_DQ<19>")
	)
	(arc
		(start 328.058018 -285.160212)
		(mid 327.820406 -284.989224)
		(end 327.53808 -284.9118)
		(width 0.0762)
		(layer "F.Cu")
		(net "M_A_CPU0_SB_DQ<19>")
	)
	(arc
		(start 326.93102 -284.837632)
		(mid 326.648064 -284.913809)
		(end 326.365108 -284.837632)
		(width 0.0762)
		(layer "F.Cu")
		(net "M_A_CPU0_SB_DQ<19>")
	)
	(arc
		(start 327.304908 -284.837632)
		(mid 327.117964 -284.787377)
		(end 326.93102 -284.837632)
		(width 0.0762)
		(layer "F.Cu")
		(net "M_A_CPU0_SB_DQ<19>")
	)
	(arc
		(start 327.53808 -284.9118)
		(mid 327.417431 -284.887499)
		(end 327.304908 -284.837632)
		(width 0.0762)
		(layer "F.Cu")
		(net "M_A_CPU0_SB_DQ<19>")
	)
	(segment
		(start 305.634898 -301.034958)
		(end 305.533552 -300.933612)
		(width 0.101346)
		(layer "F.Cu")
		(net "M_A_CPU0_SB_DQ<18>")
	)
	(segment
		(start 305.038506 -301.677324)
		(end 304.847498 -301.677324)
		(width 0.101346)
		(layer "F.Cu")
		(net "M_A_CPU0_SB_DQ<18>")
	)
	(segment
		(start 304.251106 -301.034958)
		(end 303.268126 -301.034958)
		(width 0.101346)
		(layer "F.Cu")
		(net "M_A_CPU0_SB_DQ<18>")
	)
	(segment
		(start 306.316634 -300.610016)
		(end 305.891692 -301.034958)
		(width 0.101346)
		(layer "F.Cu")
		(net "M_A_CPU0_SB_DQ<18>")
	)
	(segment
		(start 305.533552 -300.933612)
		(end 305.533552 -300.493938)
		(width 0.101346)
		(layer "F.Cu")
		(net "M_A_CPU0_SB_DQ<18>")
	)
	(segment
		(start 316.22365 -289.632898)
		(end 316.22365 -293.869618)
		(width 0.10668)
		(layer "F.Cu")
		(net "M_A_CPU0_SB_DQ<18>")
	)
	(segment
		(start 304.746152 -301.575978)
		(end 304.746152 -300.493938)
		(width 0.101346)
		(layer "F.Cu")
		(net "M_A_CPU0_SB_DQ<18>")
	)
	(segment
		(start 305.139852 -300.493938)
		(end 305.139852 -301.575978)
		(width 0.101346)
		(layer "F.Cu")
		(net "M_A_CPU0_SB_DQ<18>")
	)
	(segment
		(start 305.432206 -300.392592)
		(end 305.241198 -300.392592)
		(width 0.101346)
		(layer "F.Cu")
		(net "M_A_CPU0_SB_DQ<18>")
	)
	(segment
		(start 304.352452 -300.493938)
		(end 304.352452 -300.933612)
		(width 0.101346)
		(layer "F.Cu")
		(net "M_A_CPU0_SB_DQ<18>")
	)
	(segment
		(start 305.533552 -300.493938)
		(end 305.432206 -300.392592)
		(width 0.101346)
		(layer "F.Cu")
		(net "M_A_CPU0_SB_DQ<18>")
	)
	(segment
		(start 304.746152 -300.493938)
		(end 304.644806 -300.392592)
		(width 0.101346)
		(layer "F.Cu")
		(net "M_A_CPU0_SB_DQ<18>")
	)
	(segment
		(start 321.704208 -284.15234)
		(end 316.22365 -289.632898)
		(width 0.10668)
		(layer "F.Cu")
		(net "M_A_CPU0_SB_DQ<18>")
	)
	(segment
		(start 305.891692 -301.034958)
		(end 305.634898 -301.034958)
		(width 0.101346)
		(layer "F.Cu")
		(net "M_A_CPU0_SB_DQ<18>")
	)
	(segment
		(start 305.241198 -300.392592)
		(end 305.139852 -300.493938)
		(width 0.101346)
		(layer "F.Cu")
		(net "M_A_CPU0_SB_DQ<18>")
	)
	(segment
		(start 323.901054 -284.15234)
		(end 321.704208 -284.15234)
		(width 0.10668)
		(layer "F.Cu")
		(net "M_A_CPU0_SB_DQ<18>")
	)
	(segment
		(start 304.644806 -300.392592)
		(end 304.453798 -300.392592)
		(width 0.101346)
		(layer "F.Cu")
		(net "M_A_CPU0_SB_DQ<18>")
	)
	(segment
		(start 325.70801 -283.97708)
		(end 324.493636 -283.97708)
		(width 0.0762)
		(layer "F.Cu")
		(net "M_A_CPU0_SB_DQ<18>")
	)
	(segment
		(start 305.139852 -301.575978)
		(end 305.038506 -301.677324)
		(width 0.101346)
		(layer "F.Cu")
		(net "M_A_CPU0_SB_DQ<18>")
	)
	(segment
		(start 316.22365 -293.869618)
		(end 309.483252 -300.610016)
		(width 0.10668)
		(layer "F.Cu")
		(net "M_A_CPU0_SB_DQ<18>")
	)
	(segment
		(start 304.847498 -301.677324)
		(end 304.746152 -301.575978)
		(width 0.101346)
		(layer "F.Cu")
		(net "M_A_CPU0_SB_DQ<18>")
	)
	(segment
		(start 309.483252 -300.610016)
		(end 308.66588 -300.610016)
		(width 0.10668)
		(layer "F.Cu")
		(net "M_A_CPU0_SB_DQ<18>")
	)
	(segment
		(start 304.352452 -300.933612)
		(end 304.251106 -301.034958)
		(width 0.101346)
		(layer "F.Cu")
		(net "M_A_CPU0_SB_DQ<18>")
	)
	(segment
		(start 308.66588 -300.610016)
		(end 306.316634 -300.610016)
		(width 0.101346)
		(layer "F.Cu")
		(net "M_A_CPU0_SB_DQ<18>")
	)
	(segment
		(start 324.318376 -284.15234)
		(end 323.901054 -284.15234)
		(width 0.0762)
		(layer "F.Cu")
		(net "M_A_CPU0_SB_DQ<18>")
	)
	(segment
		(start 324.493636 -283.97708)
		(end 324.318376 -284.15234)
		(width 0.0762)
		(layer "F.Cu")
		(net "M_A_CPU0_SB_DQ<18>")
	)
	(segment
		(start 304.453798 -300.392592)
		(end 304.352452 -300.493938)
		(width 0.101346)
		(layer "F.Cu")
		(net "M_A_CPU0_SB_DQ<18>")
	)
	(arc
		(start 326.648064 -284.350206)
		(mid 326.405747 -284.180486)
		(end 326.12076 -284.101032)
		(width 0.0762)
		(layer "F.Cu")
		(net "M_A_CPU0_SB_DQ<18>")
	)
	(arc
		(start 325.894954 -284.027626)
		(mid 325.804821 -283.990006)
		(end 325.70801 -283.97708)
		(width 0.0762)
		(layer "F.Cu")
		(net "M_A_CPU0_SB_DQ<18>")
	)
	(arc
		(start 326.12076 -284.101032)
		(mid 326.003947 -284.076356)
		(end 325.894954 -284.027626)
		(width 0.0762)
		(layer "F.Cu")
		(net "M_A_CPU0_SB_DQ<18>")
	)
	(segment
		(start 315.615574 -295.315386)
		(end 315.512958 -295.21277)
		(width 0.10668)
		(layer "F.Cu")
		(net "M_A_CPU0_SB_DQ<17>")
	)
	(segment
		(start 315.362082 -295.21277)
		(end 315.23051 -295.344342)
		(width 0.10668)
		(layer "F.Cu")
		(net "M_A_CPU0_SB_DQ<17>")
	)
	(segment
		(start 311.10047 -299.83049)
		(end 310.997854 -299.727874)
		(width 0.10668)
		(layer "F.Cu")
		(net "M_A_CPU0_SB_DQ<17>")
	)
	(segment
		(start 325.70801 -284.723332)
		(end 324.762876 -284.723332)
		(width 0.0762)
		(layer "F.Cu")
		(net "M_A_CPU0_SB_DQ<17>")
	)
	(segment
		(start 311.251346 -299.830236)
		(end 311.10047 -299.83049)
		(width 0.10668)
		(layer "F.Cu")
		(net "M_A_CPU0_SB_DQ<17>")
	)
	(segment
		(start 327.409302 -284.677612)
		(end 327.40092 -284.672786)
		(width 0.0762)
		(layer "F.Cu")
		(net "M_A_CPU0_SB_DQ<17>")
	)
	(segment
		(start 314.94857 -295.777158)
		(end 314.797694 -295.777158)
		(width 0.10668)
		(layer "F.Cu")
		(net "M_A_CPU0_SB_DQ<17>")
	)
	(segment
		(start 312.229246 -298.701714)
		(end 312.12663 -298.599098)
		(width 0.10668)
		(layer "F.Cu")
		(net "M_A_CPU0_SB_DQ<17>")
	)
	(segment
		(start 313.255406 -297.470322)
		(end 313.10453 -297.470322)
		(width 0.10668)
		(layer "F.Cu")
		(net "M_A_CPU0_SB_DQ<17>")
	)
	(segment
		(start 311.562242 -299.163486)
		(end 311.411366 -299.163486)
		(width 0.10668)
		(layer "F.Cu")
		(net "M_A_CPU0_SB_DQ<17>")
	)
	(segment
		(start 313.640216 -297.29049)
		(end 313.640216 -297.441366)
		(width 0.10668)
		(layer "F.Cu")
		(net "M_A_CPU0_SB_DQ<17>")
	)
	(segment
		(start 310.715406 -299.859446)
		(end 310.71566 -300.009814)
		(width 0.10668)
		(layer "F.Cu")
		(net "M_A_CPU0_SB_DQ<17>")
	)
	(segment
		(start 316.077346 -294.648382)
		(end 315.92647 -294.648382)
		(width 0.10668)
		(layer "F.Cu")
		(net "M_A_CPU0_SB_DQ<17>")
	)
	(segment
		(start 310.997854 -299.727874)
		(end 310.846978 -299.727874)
		(width 0.10668)
		(layer "F.Cu")
		(net "M_A_CPU0_SB_DQ<17>")
	)
	(segment
		(start 310.71566 -300.009814)
		(end 310.818276 -300.11243)
		(width 0.10668)
		(layer "F.Cu")
		(net "M_A_CPU0_SB_DQ<17>")
	)
	(segment
		(start 316.462156 -294.46855)
		(end 316.462156 -294.619426)
		(width 0.10668)
		(layer "F.Cu")
		(net "M_A_CPU0_SB_DQ<17>")
	)
	(segment
		(start 313.075828 -298.005754)
		(end 312.94451 -298.137072)
		(width 0.10668)
		(layer "F.Cu")
		(net "M_A_CPU0_SB_DQ<17>")
	)
	(segment
		(start 327.587864 -284.350206)
		(end 327.688702 -284.523688)
		(width 0.0762)
		(layer "F.Cu")
		(net "M_A_CPU0_SB_DQ<17>")
	)
	(segment
		(start 315.795152 -294.930322)
		(end 315.897768 -295.032938)
		(width 0.10668)
		(layer "F.Cu")
		(net "M_A_CPU0_SB_DQ<17>")
	)
	(segment
		(start 314.637674 -296.443908)
		(end 314.486798 -296.444162)
		(width 0.10668)
		(layer "F.Cu")
		(net "M_A_CPU0_SB_DQ<17>")
	)
	(segment
		(start 312.12663 -298.599098)
		(end 311.975754 -298.599098)
		(width 0.10668)
		(layer "F.Cu")
		(net "M_A_CPU0_SB_DQ<17>")
	)
	(segment
		(start 312.40857 -298.166282)
		(end 312.408824 -298.31665)
		(width 0.10668)
		(layer "F.Cu")
		(net "M_A_CPU0_SB_DQ<17>")
	)
	(segment
		(start 316.35954 -294.365934)
		(end 316.462156 -294.46855)
		(width 0.10668)
		(layer "F.Cu")
		(net "M_A_CPU0_SB_DQ<17>")
	)
	(segment
		(start 308.851554 -300.950376)
		(end 308.703218 -301.098712)
		(width 0.10668)
		(layer "F.Cu")
		(net "M_A_CPU0_SB_DQ<17>")
	)
	(segment
		(start 310.536082 -300.394878)
		(end 310.433466 -300.292262)
		(width 0.10668)
		(layer "F.Cu")
		(net "M_A_CPU0_SB_DQ<17>")
	)
	(segment
		(start 309.869078 -300.85665)
		(end 309.717948 -300.85665)
		(width 0.10668)
		(layer "F.Cu")
		(net "M_A_CPU0_SB_DQ<17>")
	)
	(segment
		(start 315.23051 -295.344342)
		(end 315.230764 -295.49471)
		(width 0.10668)
		(layer "F.Cu")
		(net "M_A_CPU0_SB_DQ<17>")
	)
	(segment
		(start 314.486798 -296.444162)
		(end 314.384182 -296.341546)
		(width 0.10668)
		(layer "F.Cu")
		(net "M_A_CPU0_SB_DQ<17>")
	)
	(segment
		(start 311.844182 -298.73067)
		(end 311.844436 -298.881038)
		(width 0.10668)
		(layer "F.Cu")
		(net "M_A_CPU0_SB_DQ<17>")
	)
	(segment
		(start 311.975754 -298.599098)
		(end 311.844182 -298.73067)
		(width 0.10668)
		(layer "F.Cu")
		(net "M_A_CPU0_SB_DQ<17>")
	)
	(segment
		(start 315.33338 -295.597326)
		(end 315.33338 -295.748202)
		(width 0.10668)
		(layer "F.Cu")
		(net "M_A_CPU0_SB_DQ<17>")
	)
	(segment
		(start 311.280048 -299.445426)
		(end 311.382664 -299.548042)
		(width 0.10668)
		(layer "F.Cu")
		(net "M_A_CPU0_SB_DQ<17>")
	)
	(segment
		(start 313.075828 -297.854878)
		(end 313.075828 -298.005754)
		(width 0.10668)
		(layer "F.Cu")
		(net "M_A_CPU0_SB_DQ<17>")
	)
	(segment
		(start 314.384182 -296.341546)
		(end 314.233306 -296.341546)
		(width 0.10668)
		(layer "F.Cu")
		(net "M_A_CPU0_SB_DQ<17>")
	)
	(segment
		(start 309.717948 -300.85665)
		(end 309.624222 -300.950376)
		(width 0.10668)
		(layer "F.Cu")
		(net "M_A_CPU0_SB_DQ<17>")
	)
	(segment
		(start 312.973212 -297.752262)
		(end 313.075828 -297.854878)
		(width 0.10668)
		(layer "F.Cu")
		(net "M_A_CPU0_SB_DQ<17>")
	)
	(segment
		(start 314.768992 -296.161714)
		(end 314.768992 -296.31259)
		(width 0.10668)
		(layer "F.Cu")
		(net "M_A_CPU0_SB_DQ<17>")
	)
	(segment
		(start 313.640216 -297.441366)
		(end 313.508898 -297.572684)
		(width 0.10668)
		(layer "F.Cu")
		(net "M_A_CPU0_SB_DQ<17>")
	)
	(segment
		(start 315.76645 -295.315132)
		(end 315.615574 -295.315386)
		(width 0.10668)
		(layer "F.Cu")
		(net "M_A_CPU0_SB_DQ<17>")
	)
	(segment
		(start 313.5376 -297.187874)
		(end 313.640216 -297.29049)
		(width 0.10668)
		(layer "F.Cu")
		(net "M_A_CPU0_SB_DQ<17>")
	)
	(segment
		(start 316.462156 -294.619426)
		(end 316.330838 -294.750744)
		(width 0.10668)
		(layer "F.Cu")
		(net "M_A_CPU0_SB_DQ<17>")
	)
	(segment
		(start 312.380122 -298.70146)
		(end 312.229246 -298.701714)
		(width 0.10668)
		(layer "F.Cu")
		(net "M_A_CPU0_SB_DQ<17>")
	)
	(segment
		(start 309.971694 -300.959266)
		(end 309.869078 -300.85665)
		(width 0.10668)
		(layer "F.Cu")
		(net "M_A_CPU0_SB_DQ<17>")
	)
	(segment
		(start 312.691018 -298.03471)
		(end 312.540142 -298.03471)
		(width 0.10668)
		(layer "F.Cu")
		(net "M_A_CPU0_SB_DQ<17>")
	)
	(segment
		(start 314.101734 -296.473118)
		(end 314.101988 -296.623486)
		(width 0.10668)
		(layer "F.Cu")
		(net "M_A_CPU0_SB_DQ<17>")
	)
	(segment
		(start 310.433466 -300.292262)
		(end 310.28259 -300.292262)
		(width 0.10668)
		(layer "F.Cu")
		(net "M_A_CPU0_SB_DQ<17>")
	)
	(segment
		(start 321.845432 -284.4927)
		(end 316.56401 -289.774122)
		(width 0.10668)
		(layer "F.Cu")
		(net "M_A_CPU0_SB_DQ<17>")
	)
	(segment
		(start 308.703218 -301.568866)
		(end 308.386988 -301.885096)
		(width 0.10668)
		(layer "F.Cu")
		(net "M_A_CPU0_SB_DQ<17>")
	)
	(segment
		(start 315.897768 -295.183814)
		(end 315.76645 -295.315132)
		(width 0.10668)
		(layer "F.Cu")
		(net "M_A_CPU0_SB_DQ<17>")
	)
	(segment
		(start 313.537346 -297.037506)
		(end 313.5376 -297.187874)
		(width 0.10668)
		(layer "F.Cu")
		(net "M_A_CPU0_SB_DQ<17>")
	)
	(segment
		(start 314.233306 -296.341546)
		(end 314.101734 -296.473118)
		(width 0.10668)
		(layer "F.Cu")
		(net "M_A_CPU0_SB_DQ<17>")
	)
	(segment
		(start 315.512958 -295.21277)
		(end 315.362082 -295.21277)
		(width 0.10668)
		(layer "F.Cu")
		(net "M_A_CPU0_SB_DQ<17>")
	)
	(segment
		(start 312.51144 -298.570142)
		(end 312.380122 -298.70146)
		(width 0.10668)
		(layer "F.Cu")
		(net "M_A_CPU0_SB_DQ<17>")
	)
	(segment
		(start 313.92241 -297.00855)
		(end 313.819794 -296.905934)
		(width 0.10668)
		(layer "F.Cu")
		(net "M_A_CPU0_SB_DQ<17>")
	)
	(segment
		(start 313.10453 -297.470322)
		(end 312.972958 -297.601894)
		(width 0.10668)
		(layer "F.Cu")
		(net "M_A_CPU0_SB_DQ<17>")
	)
	(segment
		(start 308.703218 -301.098712)
		(end 308.703218 -301.568866)
		(width 0.10668)
		(layer "F.Cu")
		(net "M_A_CPU0_SB_DQ<17>")
	)
	(segment
		(start 311.411366 -299.163486)
		(end 311.279794 -299.295058)
		(width 0.10668)
		(layer "F.Cu")
		(net "M_A_CPU0_SB_DQ<17>")
	)
	(segment
		(start 310.12257 -300.959012)
		(end 309.971694 -300.959266)
		(width 0.10668)
		(layer "F.Cu")
		(net "M_A_CPU0_SB_DQ<17>")
	)
	(segment
		(start 326.835008 -284.672786)
		(end 326.826626 -284.677612)
		(width 0.0762)
		(layer "F.Cu")
		(net "M_A_CPU0_SB_DQ<17>")
	)
	(segment
		(start 315.202062 -295.87952)
		(end 315.051186 -295.879774)
		(width 0.10668)
		(layer "F.Cu")
		(net "M_A_CPU0_SB_DQ<17>")
	)
	(segment
		(start 314.204604 -296.726102)
		(end 314.204604 -296.876978)
		(width 0.10668)
		(layer "F.Cu")
		(net "M_A_CPU0_SB_DQ<17>")
	)
	(segment
		(start 310.28259 -300.292262)
		(end 310.151018 -300.423834)
		(width 0.10668)
		(layer "F.Cu")
		(net "M_A_CPU0_SB_DQ<17>")
	)
	(segment
		(start 316.56401 -289.774122)
		(end 316.56401 -294.010842)
		(width 0.10668)
		(layer "F.Cu")
		(net "M_A_CPU0_SB_DQ<17>")
	)
	(segment
		(start 324.532244 -284.4927)
		(end 323.901054 -284.4927)
		(width 0.0762)
		(layer "F.Cu")
		(net "M_A_CPU0_SB_DQ<17>")
	)
	(segment
		(start 314.666376 -296.059098)
		(end 314.768992 -296.161714)
		(width 0.10668)
		(layer "F.Cu")
		(net "M_A_CPU0_SB_DQ<17>")
	)
	(segment
		(start 314.768992 -296.31259)
		(end 314.637674 -296.443908)
		(width 0.10668)
		(layer "F.Cu")
		(net "M_A_CPU0_SB_DQ<17>")
	)
	(segment
		(start 324.762876 -284.723332)
		(end 324.532244 -284.4927)
		(width 0.0762)
		(layer "F.Cu")
		(net "M_A_CPU0_SB_DQ<17>")
	)
	(segment
		(start 311.844436 -298.881038)
		(end 311.947052 -298.983654)
		(width 0.10668)
		(layer "F.Cu")
		(net "M_A_CPU0_SB_DQ<17>")
	)
	(segment
		(start 314.101988 -296.623486)
		(end 314.204604 -296.726102)
		(width 0.10668)
		(layer "F.Cu")
		(net "M_A_CPU0_SB_DQ<17>")
	)
	(segment
		(start 310.686958 -300.394624)
		(end 310.536082 -300.394878)
		(width 0.10668)
		(layer "F.Cu")
		(net "M_A_CPU0_SB_DQ<17>")
	)
	(segment
		(start 323.901054 -284.4927)
		(end 321.845432 -284.4927)
		(width 0.10668)
		(layer "F.Cu")
		(net "M_A_CPU0_SB_DQ<17>")
	)
	(segment
		(start 310.818276 -300.11243)
		(end 310.818276 -300.263306)
		(width 0.10668)
		(layer "F.Cu")
		(net "M_A_CPU0_SB_DQ<17>")
	)
	(segment
		(start 310.253888 -300.676818)
		(end 310.253888 -300.827694)
		(width 0.10668)
		(layer "F.Cu")
		(net "M_A_CPU0_SB_DQ<17>")
	)
	(segment
		(start 311.947052 -298.983654)
		(end 311.947052 -299.13453)
		(width 0.10668)
		(layer "F.Cu")
		(net "M_A_CPU0_SB_DQ<17>")
	)
	(segment
		(start 316.330838 -294.750744)
		(end 316.179962 -294.750998)
		(width 0.10668)
		(layer "F.Cu")
		(net "M_A_CPU0_SB_DQ<17>")
	)
	(segment
		(start 310.253888 -300.827694)
		(end 310.12257 -300.959012)
		(width 0.10668)
		(layer "F.Cu")
		(net "M_A_CPU0_SB_DQ<17>")
	)
	(segment
		(start 312.51144 -298.419266)
		(end 312.51144 -298.570142)
		(width 0.10668)
		(layer "F.Cu")
		(net "M_A_CPU0_SB_DQ<17>")
	)
	(segment
		(start 310.151272 -300.574202)
		(end 310.253888 -300.676818)
		(width 0.10668)
		(layer "F.Cu")
		(net "M_A_CPU0_SB_DQ<17>")
	)
	(segment
		(start 315.897768 -295.032938)
		(end 315.897768 -295.183814)
		(width 0.10668)
		(layer "F.Cu")
		(net "M_A_CPU0_SB_DQ<17>")
	)
	(segment
		(start 316.359286 -294.215566)
		(end 316.35954 -294.365934)
		(width 0.10668)
		(layer "F.Cu")
		(net "M_A_CPU0_SB_DQ<17>")
	)
	(segment
		(start 315.051186 -295.879774)
		(end 314.94857 -295.777158)
		(width 0.10668)
		(layer "F.Cu")
		(net "M_A_CPU0_SB_DQ<17>")
	)
	(segment
		(start 311.947052 -299.13453)
		(end 311.815734 -299.265848)
		(width 0.10668)
		(layer "F.Cu")
		(net "M_A_CPU0_SB_DQ<17>")
	)
	(segment
		(start 315.794898 -294.779954)
		(end 315.795152 -294.930322)
		(width 0.10668)
		(layer "F.Cu")
		(net "M_A_CPU0_SB_DQ<17>")
	)
	(segment
		(start 314.204604 -296.876978)
		(end 314.073286 -297.008296)
		(width 0.10668)
		(layer "F.Cu")
		(net "M_A_CPU0_SB_DQ<17>")
	)
	(segment
		(start 312.94451 -298.137072)
		(end 312.793634 -298.137326)
		(width 0.10668)
		(layer "F.Cu")
		(net "M_A_CPU0_SB_DQ<17>")
	)
	(segment
		(start 311.664858 -299.266102)
		(end 311.562242 -299.163486)
		(width 0.10668)
		(layer "F.Cu")
		(net "M_A_CPU0_SB_DQ<17>")
	)
	(segment
		(start 313.508898 -297.572684)
		(end 313.358022 -297.572938)
		(width 0.10668)
		(layer "F.Cu")
		(net "M_A_CPU0_SB_DQ<17>")
	)
	(segment
		(start 315.230764 -295.49471)
		(end 315.33338 -295.597326)
		(width 0.10668)
		(layer "F.Cu")
		(net "M_A_CPU0_SB_DQ<17>")
	)
	(segment
		(start 313.819794 -296.905934)
		(end 313.668918 -296.905934)
		(width 0.10668)
		(layer "F.Cu")
		(net "M_A_CPU0_SB_DQ<17>")
	)
	(segment
		(start 308.386988 -301.885096)
		(end 307.368194 -301.885096)
		(width 0.10668)
		(layer "F.Cu")
		(net "M_A_CPU0_SB_DQ<17>")
	)
	(segment
		(start 312.408824 -298.31665)
		(end 312.51144 -298.419266)
		(width 0.10668)
		(layer "F.Cu")
		(net "M_A_CPU0_SB_DQ<17>")
	)
	(segment
		(start 311.382664 -299.548042)
		(end 311.382664 -299.698918)
		(width 0.10668)
		(layer "F.Cu")
		(net "M_A_CPU0_SB_DQ<17>")
	)
	(segment
		(start 314.666122 -295.90873)
		(end 314.666376 -296.059098)
		(width 0.10668)
		(layer "F.Cu")
		(net "M_A_CPU0_SB_DQ<17>")
	)
	(segment
		(start 316.56401 -294.010842)
		(end 316.359286 -294.215566)
		(width 0.10668)
		(layer "F.Cu")
		(net "M_A_CPU0_SB_DQ<17>")
	)
	(segment
		(start 313.668918 -296.905934)
		(end 313.537346 -297.037506)
		(width 0.10668)
		(layer "F.Cu")
		(net "M_A_CPU0_SB_DQ<17>")
	)
	(segment
		(start 310.846978 -299.727874)
		(end 310.715406 -299.859446)
		(width 0.10668)
		(layer "F.Cu")
		(net "M_A_CPU0_SB_DQ<17>")
	)
	(segment
		(start 309.624222 -300.950376)
		(end 308.851554 -300.950376)
		(width 0.10668)
		(layer "F.Cu")
		(net "M_A_CPU0_SB_DQ<17>")
	)
	(segment
		(start 312.793634 -298.137326)
		(end 312.691018 -298.03471)
		(width 0.10668)
		(layer "F.Cu")
		(net "M_A_CPU0_SB_DQ<17>")
	)
	(segment
		(start 315.92647 -294.648382)
		(end 315.794898 -294.779954)
		(width 0.10668)
		(layer "F.Cu")
		(net "M_A_CPU0_SB_DQ<17>")
	)
	(segment
		(start 314.797694 -295.777158)
		(end 314.666122 -295.90873)
		(width 0.10668)
		(layer "F.Cu")
		(net "M_A_CPU0_SB_DQ<17>")
	)
	(segment
		(start 314.073286 -297.008296)
		(end 313.92241 -297.00855)
		(width 0.10668)
		(layer "F.Cu")
		(net "M_A_CPU0_SB_DQ<17>")
	)
	(segment
		(start 311.279794 -299.295058)
		(end 311.280048 -299.445426)
		(width 0.10668)
		(layer "F.Cu")
		(net "M_A_CPU0_SB_DQ<17>")
	)
	(segment
		(start 313.358022 -297.572938)
		(end 313.255406 -297.470322)
		(width 0.10668)
		(layer "F.Cu")
		(net "M_A_CPU0_SB_DQ<17>")
	)
	(segment
		(start 310.151018 -300.423834)
		(end 310.151272 -300.574202)
		(width 0.10668)
		(layer "F.Cu")
		(net "M_A_CPU0_SB_DQ<17>")
	)
	(segment
		(start 312.972958 -297.601894)
		(end 312.973212 -297.752262)
		(width 0.10668)
		(layer "F.Cu")
		(net "M_A_CPU0_SB_DQ<17>")
	)
	(segment
		(start 312.540142 -298.03471)
		(end 312.40857 -298.166282)
		(width 0.10668)
		(layer "F.Cu")
		(net "M_A_CPU0_SB_DQ<17>")
	)
	(segment
		(start 311.382664 -299.698918)
		(end 311.251346 -299.830236)
		(width 0.10668)
		(layer "F.Cu")
		(net "M_A_CPU0_SB_DQ<17>")
	)
	(segment
		(start 315.33338 -295.748202)
		(end 315.202062 -295.87952)
		(width 0.10668)
		(layer "F.Cu")
		(net "M_A_CPU0_SB_DQ<17>")
	)
	(segment
		(start 316.179962 -294.750998)
		(end 316.077346 -294.648382)
		(width 0.10668)
		(layer "F.Cu")
		(net "M_A_CPU0_SB_DQ<17>")
	)
	(segment
		(start 311.815734 -299.265848)
		(end 311.664858 -299.266102)
		(width 0.10668)
		(layer "F.Cu")
		(net "M_A_CPU0_SB_DQ<17>")
	)
	(segment
		(start 310.818276 -300.263306)
		(end 310.686958 -300.394624)
		(width 0.10668)
		(layer "F.Cu")
		(net "M_A_CPU0_SB_DQ<17>")
	)
	(arc
		(start 327.688702 -284.523688)
		(mid 327.672777 -284.66438)
		(end 327.542652 -284.720284)
		(width 0.0762)
		(layer "F.Cu")
		(net "M_A_CPU0_SB_DQ<17>")
	)
	(arc
		(start 326.460866 -284.672786)
		(mid 326.17791 -284.596609)
		(end 325.894954 -284.672786)
		(width 0.0762)
		(layer "F.Cu")
		(net "M_A_CPU0_SB_DQ<17>")
	)
	(arc
		(start 325.894954 -284.672786)
		(mid 325.819714 -284.706099)
		(end 325.738998 -284.722062)
		(width 0.0762)
		(layer "F.Cu")
		(net "M_A_CPU0_SB_DQ<17>")
	)
	(arc
		(start 327.40092 -284.672786)
		(mid 327.117964 -284.596609)
		(end 326.835008 -284.672786)
		(width 0.0762)
		(layer "F.Cu")
		(net "M_A_CPU0_SB_DQ<17>")
	)
	(arc
		(start 326.826626 -284.677612)
		(mid 326.643118 -284.723106)
		(end 326.460866 -284.672786)
		(width 0.0762)
		(layer "F.Cu")
		(net "M_A_CPU0_SB_DQ<17>")
	)
	(arc
		(start 325.738998 -284.722062)
		(mid 325.723517 -284.723018)
		(end 325.70801 -284.723332)
		(width 0.0762)
		(layer "F.Cu")
		(net "M_A_CPU0_SB_DQ<17>")
	)
	(arc
		(start 327.542652 -284.720284)
		(mid 327.473954 -284.705268)
		(end 327.409302 -284.677612)
		(width 0.0762)
		(layer "F.Cu")
		(net "M_A_CPU0_SB_DQ<17>")
	)
	(segment
		(start 311.77865 -297.171872)
		(end 311.647332 -297.30319)
		(width 0.10668)
		(layer "F.Cu")
		(net "M_A_CPU0_SB_DQ<16>")
	)
	(segment
		(start 311.544716 -297.915838)
		(end 311.365138 -297.73626)
		(width 0.10668)
		(layer "F.Cu")
		(net "M_A_CPU0_SB_DQ<16>")
	)
	(segment
		(start 310.41594 -299.044614)
		(end 310.236362 -298.865036)
		(width 0.10668)
		(layer "F.Cu")
		(net "M_A_CPU0_SB_DQ<16>")
	)
	(segment
		(start 310.698134 -298.913296)
		(end 310.566816 -299.044614)
		(width 0.10668)
		(layer "F.Cu")
		(net "M_A_CPU0_SB_DQ<16>")
	)
	(segment
		(start 310.518556 -298.431966)
		(end 310.518556 -298.582842)
		(width 0.10668)
		(layer "F.Cu")
		(net "M_A_CPU0_SB_DQ<16>")
	)
	(segment
		(start 309.287164 -300.17339)
		(end 309.107586 -299.993812)
		(width 0.10668)
		(layer "F.Cu")
		(net "M_A_CPU0_SB_DQ<16>")
	)
	(segment
		(start 312.907426 -296.043096)
		(end 312.776108 -296.174414)
		(width 0.10668)
		(layer "F.Cu")
		(net "M_A_CPU0_SB_DQ<16>")
	)
	(segment
		(start 314.469272 -294.48125)
		(end 314.469272 -294.632126)
		(width 0.10668)
		(layer "F.Cu")
		(net "M_A_CPU0_SB_DQ<16>")
	)
	(segment
		(start 312.391298 -297.069256)
		(end 312.391298 -297.220132)
		(width 0.10668)
		(layer "F.Cu")
		(net "M_A_CPU0_SB_DQ<16>")
	)
	(segment
		(start 310.085486 -298.865036)
		(end 309.954168 -298.996354)
		(width 0.10668)
		(layer "F.Cu")
		(net "M_A_CPU0_SB_DQ<16>")
	)
	(segment
		(start 314.366656 -295.093898)
		(end 314.187078 -294.91432)
		(width 0.10668)
		(layer "F.Cu")
		(net "M_A_CPU0_SB_DQ<16>")
	)
	(segment
		(start 311.82691 -297.78452)
		(end 311.695592 -297.915838)
		(width 0.10668)
		(layer "F.Cu")
		(net "M_A_CPU0_SB_DQ<16>")
	)
	(segment
		(start 312.955686 -296.655744)
		(end 312.824368 -296.787062)
		(width 0.10668)
		(layer "F.Cu")
		(net "M_A_CPU0_SB_DQ<16>")
	)
	(segment
		(start 312.343038 -296.607484)
		(end 312.21172 -296.738802)
		(width 0.10668)
		(layer "F.Cu")
		(net "M_A_CPU0_SB_DQ<16>")
	)
	(segment
		(start 314.931044 -294.52951)
		(end 314.751466 -294.349932)
		(width 0.10668)
		(layer "F.Cu")
		(net "M_A_CPU0_SB_DQ<16>")
	)
	(segment
		(start 310.133746 -299.326808)
		(end 310.133746 -299.477684)
		(width 0.10668)
		(layer "F.Cu")
		(net "M_A_CPU0_SB_DQ<16>")
	)
	(segment
		(start 312.824368 -296.787062)
		(end 312.673492 -296.787062)
		(width 0.10668)
		(layer "F.Cu")
		(net "M_A_CPU0_SB_DQ<16>")
	)
	(segment
		(start 310.980328 -298.480226)
		(end 310.80075 -298.300648)
		(width 0.10668)
		(layer "F.Cu")
		(net "M_A_CPU0_SB_DQ<16>")
	)
	(segment
		(start 311.214262 -297.73626)
		(end 311.082944 -297.867578)
		(width 0.10668)
		(layer "F.Cu")
		(net "M_A_CPU0_SB_DQ<16>")
	)
	(segment
		(start 315.88329 -293.067232)
		(end 315.598048 -293.352474)
		(width 0.10668)
		(layer "F.Cu")
		(net "M_A_CPU0_SB_DQ<16>")
	)
	(segment
		(start 309.521098 -299.429424)
		(end 309.38978 -299.560742)
		(width 0.10668)
		(layer "F.Cu")
		(net "M_A_CPU0_SB_DQ<16>")
	)
	(segment
		(start 312.955686 -296.504868)
		(end 312.955686 -296.655744)
		(width 0.10668)
		(layer "F.Cu")
		(net "M_A_CPU0_SB_DQ<16>")
	)
	(segment
		(start 310.698134 -298.76242)
		(end 310.698134 -298.913296)
		(width 0.10668)
		(layer "F.Cu")
		(net "M_A_CPU0_SB_DQ<16>")
	)
	(segment
		(start 312.21172 -296.889678)
		(end 312.391298 -297.069256)
		(width 0.10668)
		(layer "F.Cu")
		(net "M_A_CPU0_SB_DQ<16>")
	)
	(segment
		(start 311.262522 -298.198032)
		(end 311.262522 -298.348908)
		(width 0.10668)
		(layer "F.Cu")
		(net "M_A_CPU0_SB_DQ<16>")
	)
	(segment
		(start 309.569358 -299.891196)
		(end 309.569358 -300.042072)
		(width 0.10668)
		(layer "F.Cu")
		(net "M_A_CPU0_SB_DQ<16>")
	)
	(segment
		(start 315.315854 -293.785544)
		(end 315.164978 -293.785544)
		(width 0.10668)
		(layer "F.Cu")
		(net "M_A_CPU0_SB_DQ<16>")
	)
	(segment
		(start 326.17791 -283.5402)
		(end 326.276208 -283.709364)
		(width 0.0762)
		(layer "F.Cu")
		(net "M_A_CPU0_SB_DQ<16>")
	)
	(segment
		(start 324.204584 -283.78658)
		(end 324.179184 -283.81198)
		(width 0.0762)
		(layer "F.Cu")
		(net "M_A_CPU0_SB_DQ<16>")
	)
	(segment
		(start 312.25998 -297.35145)
		(end 312.109104 -297.35145)
		(width 0.10668)
		(layer "F.Cu")
		(net "M_A_CPU0_SB_DQ<16>")
	)
	(segment
		(start 309.107586 -299.993812)
		(end 308.95671 -299.993812)
		(width 0.10668)
		(layer "F.Cu")
		(net "M_A_CPU0_SB_DQ<16>")
	)
	(segment
		(start 325.70801 -283.78658)
		(end 324.204584 -283.78658)
		(width 0.0762)
		(layer "F.Cu")
		(net "M_A_CPU0_SB_DQ<16>")
	)
	(segment
		(start 309.954168 -298.996354)
		(end 309.954168 -299.14723)
		(width 0.10668)
		(layer "F.Cu")
		(net "M_A_CPU0_SB_DQ<16>")
	)
	(segment
		(start 315.03366 -293.916862)
		(end 315.03366 -294.067738)
		(width 0.10668)
		(layer "F.Cu")
		(net "M_A_CPU0_SB_DQ<16>")
	)
	(segment
		(start 311.365138 -297.73626)
		(end 311.214262 -297.73626)
		(width 0.10668)
		(layer "F.Cu")
		(net "M_A_CPU0_SB_DQ<16>")
	)
	(segment
		(start 310.566816 -299.044614)
		(end 310.41594 -299.044614)
		(width 0.10668)
		(layer "F.Cu")
		(net "M_A_CPU0_SB_DQ<16>")
	)
	(segment
		(start 313.058302 -296.043096)
		(end 312.907426 -296.043096)
		(width 0.10668)
		(layer "F.Cu")
		(net "M_A_CPU0_SB_DQ<16>")
	)
	(segment
		(start 314.187078 -294.91432)
		(end 314.036202 -294.91432)
		(width 0.10668)
		(layer "F.Cu")
		(net "M_A_CPU0_SB_DQ<16>")
	)
	(segment
		(start 314.517532 -295.093898)
		(end 314.366656 -295.093898)
		(width 0.10668)
		(layer "F.Cu")
		(net "M_A_CPU0_SB_DQ<16>")
	)
	(segment
		(start 315.164978 -293.785544)
		(end 315.03366 -293.916862)
		(width 0.10668)
		(layer "F.Cu")
		(net "M_A_CPU0_SB_DQ<16>")
	)
	(segment
		(start 313.520074 -295.94048)
		(end 313.520074 -296.091356)
		(width 0.10668)
		(layer "F.Cu")
		(net "M_A_CPU0_SB_DQ<16>")
	)
	(segment
		(start 313.802268 -295.658286)
		(end 313.62269 -295.478708)
		(width 0.10668)
		(layer "F.Cu")
		(net "M_A_CPU0_SB_DQ<16>")
	)
	(segment
		(start 311.131204 -298.480226)
		(end 310.980328 -298.480226)
		(width 0.10668)
		(layer "F.Cu")
		(net "M_A_CPU0_SB_DQ<16>")
	)
	(segment
		(start 313.23788 -296.222674)
		(end 313.058302 -296.043096)
		(width 0.10668)
		(layer "F.Cu")
		(net "M_A_CPU0_SB_DQ<16>")
	)
	(segment
		(start 309.38978 -299.711618)
		(end 309.569358 -299.891196)
		(width 0.10668)
		(layer "F.Cu")
		(net "M_A_CPU0_SB_DQ<16>")
	)
	(segment
		(start 314.751466 -294.349932)
		(end 314.60059 -294.349932)
		(width 0.10668)
		(layer "F.Cu")
		(net "M_A_CPU0_SB_DQ<16>")
	)
	(segment
		(start 324.179184 -283.81198)
		(end 321.562984 -283.81198)
		(width 0.10668)
		(layer "F.Cu")
		(net "M_A_CPU0_SB_DQ<16>")
	)
	(segment
		(start 314.084462 -295.376092)
		(end 314.084462 -295.526968)
		(width 0.10668)
		(layer "F.Cu")
		(net "M_A_CPU0_SB_DQ<16>")
	)
	(segment
		(start 315.777626 -293.682928)
		(end 315.777626 -293.833804)
		(width 0.10668)
		(layer "F.Cu")
		(net "M_A_CPU0_SB_DQ<16>")
	)
	(segment
		(start 314.469272 -294.632126)
		(end 314.64885 -294.811704)
		(width 0.10668)
		(layer "F.Cu")
		(net "M_A_CPU0_SB_DQ<16>")
	)
	(segment
		(start 313.904884 -295.045638)
		(end 313.904884 -295.196514)
		(width 0.10668)
		(layer "F.Cu")
		(net "M_A_CPU0_SB_DQ<16>")
	)
	(segment
		(start 313.340496 -295.610026)
		(end 313.340496 -295.760902)
		(width 0.10668)
		(layer "F.Cu")
		(net "M_A_CPU0_SB_DQ<16>")
	)
	(segment
		(start 315.495432 -293.965122)
		(end 315.315854 -293.785544)
		(width 0.10668)
		(layer "F.Cu")
		(net "M_A_CPU0_SB_DQ<16>")
	)
	(segment
		(start 309.851552 -299.609002)
		(end 309.671974 -299.429424)
		(width 0.10668)
		(layer "F.Cu")
		(net "M_A_CPU0_SB_DQ<16>")
	)
	(segment
		(start 312.109104 -297.35145)
		(end 311.929526 -297.171872)
		(width 0.10668)
		(layer "F.Cu")
		(net "M_A_CPU0_SB_DQ<16>")
	)
	(segment
		(start 309.43804 -300.17339)
		(end 309.287164 -300.17339)
		(width 0.10668)
		(layer "F.Cu")
		(net "M_A_CPU0_SB_DQ<16>")
	)
	(segment
		(start 310.133746 -299.477684)
		(end 310.002428 -299.609002)
		(width 0.10668)
		(layer "F.Cu")
		(net "M_A_CPU0_SB_DQ<16>")
	)
	(segment
		(start 310.80075 -298.300648)
		(end 310.649874 -298.300648)
		(width 0.10668)
		(layer "F.Cu")
		(net "M_A_CPU0_SB_DQ<16>")
	)
	(segment
		(start 311.262522 -298.348908)
		(end 311.131204 -298.480226)
		(width 0.10668)
		(layer "F.Cu")
		(net "M_A_CPU0_SB_DQ<16>")
	)
	(segment
		(start 309.954168 -299.14723)
		(end 310.133746 -299.326808)
		(width 0.10668)
		(layer "F.Cu")
		(net "M_A_CPU0_SB_DQ<16>")
	)
	(segment
		(start 314.64885 -294.96258)
		(end 314.517532 -295.093898)
		(width 0.10668)
		(layer "F.Cu")
		(net "M_A_CPU0_SB_DQ<16>")
	)
	(segment
		(start 310.518556 -298.582842)
		(end 310.698134 -298.76242)
		(width 0.10668)
		(layer "F.Cu")
		(net "M_A_CPU0_SB_DQ<16>")
	)
	(segment
		(start 312.673492 -296.787062)
		(end 312.493914 -296.607484)
		(width 0.10668)
		(layer "F.Cu")
		(net "M_A_CPU0_SB_DQ<16>")
	)
	(segment
		(start 311.82691 -297.633644)
		(end 311.82691 -297.78452)
		(width 0.10668)
		(layer "F.Cu")
		(net "M_A_CPU0_SB_DQ<16>")
	)
	(segment
		(start 315.598048 -293.352474)
		(end 315.598048 -293.50335)
		(width 0.10668)
		(layer "F.Cu")
		(net "M_A_CPU0_SB_DQ<16>")
	)
	(segment
		(start 310.002428 -299.609002)
		(end 309.851552 -299.609002)
		(width 0.10668)
		(layer "F.Cu")
		(net "M_A_CPU0_SB_DQ<16>")
	)
	(segment
		(start 310.649874 -298.300648)
		(end 310.518556 -298.431966)
		(width 0.10668)
		(layer "F.Cu")
		(net "M_A_CPU0_SB_DQ<16>")
	)
	(segment
		(start 309.671974 -299.429424)
		(end 309.521098 -299.429424)
		(width 0.10668)
		(layer "F.Cu")
		(net "M_A_CPU0_SB_DQ<16>")
	)
	(segment
		(start 312.493914 -296.607484)
		(end 312.343038 -296.607484)
		(width 0.10668)
		(layer "F.Cu")
		(net "M_A_CPU0_SB_DQ<16>")
	)
	(segment
		(start 308.95671 -299.993812)
		(end 308.765448 -300.185074)
		(width 0.10668)
		(layer "F.Cu")
		(net "M_A_CPU0_SB_DQ<16>")
	)
	(segment
		(start 315.08192 -294.52951)
		(end 314.931044 -294.52951)
		(width 0.10668)
		(layer "F.Cu")
		(net "M_A_CPU0_SB_DQ<16>")
	)
	(segment
		(start 313.388756 -296.222674)
		(end 313.23788 -296.222674)
		(width 0.10668)
		(layer "F.Cu")
		(net "M_A_CPU0_SB_DQ<16>")
	)
	(segment
		(start 310.236362 -298.865036)
		(end 310.085486 -298.865036)
		(width 0.10668)
		(layer "F.Cu")
		(net "M_A_CPU0_SB_DQ<16>")
	)
	(segment
		(start 315.03366 -294.067738)
		(end 315.213238 -294.247316)
		(width 0.10668)
		(layer "F.Cu")
		(net "M_A_CPU0_SB_DQ<16>")
	)
	(segment
		(start 311.929526 -297.171872)
		(end 311.77865 -297.171872)
		(width 0.10668)
		(layer "F.Cu")
		(net "M_A_CPU0_SB_DQ<16>")
	)
	(segment
		(start 321.562984 -283.81198)
		(end 315.88329 -289.491674)
		(width 0.10668)
		(layer "F.Cu")
		(net "M_A_CPU0_SB_DQ<16>")
	)
	(segment
		(start 314.036202 -294.91432)
		(end 313.904884 -295.045638)
		(width 0.10668)
		(layer "F.Cu")
		(net "M_A_CPU0_SB_DQ<16>")
	)
	(segment
		(start 312.776108 -296.32529)
		(end 312.955686 -296.504868)
		(width 0.10668)
		(layer "F.Cu")
		(net "M_A_CPU0_SB_DQ<16>")
	)
	(segment
		(start 315.213238 -294.398192)
		(end 315.08192 -294.52951)
		(width 0.10668)
		(layer "F.Cu")
		(net "M_A_CPU0_SB_DQ<16>")
	)
	(segment
		(start 313.62269 -295.478708)
		(end 313.471814 -295.478708)
		(width 0.10668)
		(layer "F.Cu")
		(net "M_A_CPU0_SB_DQ<16>")
	)
	(segment
		(start 313.340496 -295.760902)
		(end 313.520074 -295.94048)
		(width 0.10668)
		(layer "F.Cu")
		(net "M_A_CPU0_SB_DQ<16>")
	)
	(segment
		(start 311.647332 -297.454066)
		(end 311.82691 -297.633644)
		(width 0.10668)
		(layer "F.Cu")
		(net "M_A_CPU0_SB_DQ<16>")
	)
	(segment
		(start 308.765448 -300.185074)
		(end 307.368194 -300.185074)
		(width 0.10668)
		(layer "F.Cu")
		(net "M_A_CPU0_SB_DQ<16>")
	)
	(segment
		(start 314.60059 -294.349932)
		(end 314.469272 -294.48125)
		(width 0.10668)
		(layer "F.Cu")
		(net "M_A_CPU0_SB_DQ<16>")
	)
	(segment
		(start 313.904884 -295.196514)
		(end 314.084462 -295.376092)
		(width 0.10668)
		(layer "F.Cu")
		(net "M_A_CPU0_SB_DQ<16>")
	)
	(segment
		(start 315.88329 -289.491674)
		(end 315.88329 -293.067232)
		(width 0.10668)
		(layer "F.Cu")
		(net "M_A_CPU0_SB_DQ<16>")
	)
	(segment
		(start 309.38978 -299.560742)
		(end 309.38978 -299.711618)
		(width 0.10668)
		(layer "F.Cu")
		(net "M_A_CPU0_SB_DQ<16>")
	)
	(segment
		(start 311.647332 -297.30319)
		(end 311.647332 -297.454066)
		(width 0.10668)
		(layer "F.Cu")
		(net "M_A_CPU0_SB_DQ<16>")
	)
	(segment
		(start 312.776108 -296.174414)
		(end 312.776108 -296.32529)
		(width 0.10668)
		(layer "F.Cu")
		(net "M_A_CPU0_SB_DQ<16>")
	)
	(segment
		(start 314.64885 -294.811704)
		(end 314.64885 -294.96258)
		(width 0.10668)
		(layer "F.Cu")
		(net "M_A_CPU0_SB_DQ<16>")
	)
	(segment
		(start 313.520074 -296.091356)
		(end 313.388756 -296.222674)
		(width 0.10668)
		(layer "F.Cu")
		(net "M_A_CPU0_SB_DQ<16>")
	)
	(segment
		(start 325.999348 -283.867606)
		(end 325.990966 -283.86278)
		(width 0.0762)
		(layer "F.Cu")
		(net "M_A_CPU0_SB_DQ<16>")
	)
	(segment
		(start 311.695592 -297.915838)
		(end 311.544716 -297.915838)
		(width 0.10668)
		(layer "F.Cu")
		(net "M_A_CPU0_SB_DQ<16>")
	)
	(segment
		(start 312.21172 -296.738802)
		(end 312.21172 -296.889678)
		(width 0.10668)
		(layer "F.Cu")
		(net "M_A_CPU0_SB_DQ<16>")
	)
	(segment
		(start 309.569358 -300.042072)
		(end 309.43804 -300.17339)
		(width 0.10668)
		(layer "F.Cu")
		(net "M_A_CPU0_SB_DQ<16>")
	)
	(segment
		(start 315.646308 -293.965122)
		(end 315.495432 -293.965122)
		(width 0.10668)
		(layer "F.Cu")
		(net "M_A_CPU0_SB_DQ<16>")
	)
	(segment
		(start 312.391298 -297.220132)
		(end 312.25998 -297.35145)
		(width 0.10668)
		(layer "F.Cu")
		(net "M_A_CPU0_SB_DQ<16>")
	)
	(segment
		(start 313.953144 -295.658286)
		(end 313.802268 -295.658286)
		(width 0.10668)
		(layer "F.Cu")
		(net "M_A_CPU0_SB_DQ<16>")
	)
	(segment
		(start 315.777626 -293.833804)
		(end 315.646308 -293.965122)
		(width 0.10668)
		(layer "F.Cu")
		(net "M_A_CPU0_SB_DQ<16>")
	)
	(segment
		(start 315.213238 -294.247316)
		(end 315.213238 -294.398192)
		(width 0.10668)
		(layer "F.Cu")
		(net "M_A_CPU0_SB_DQ<16>")
	)
	(segment
		(start 315.598048 -293.50335)
		(end 315.777626 -293.682928)
		(width 0.10668)
		(layer "F.Cu")
		(net "M_A_CPU0_SB_DQ<16>")
	)
	(segment
		(start 311.082944 -297.867578)
		(end 311.082944 -298.018454)
		(width 0.10668)
		(layer "F.Cu")
		(net "M_A_CPU0_SB_DQ<16>")
	)
	(segment
		(start 313.471814 -295.478708)
		(end 313.340496 -295.610026)
		(width 0.10668)
		(layer "F.Cu")
		(net "M_A_CPU0_SB_DQ<16>")
	)
	(segment
		(start 314.084462 -295.526968)
		(end 313.953144 -295.658286)
		(width 0.10668)
		(layer "F.Cu")
		(net "M_A_CPU0_SB_DQ<16>")
	)
	(segment
		(start 311.082944 -298.018454)
		(end 311.262522 -298.198032)
		(width 0.10668)
		(layer "F.Cu")
		(net "M_A_CPU0_SB_DQ<16>")
	)
	(arc
		(start 326.276208 -283.709364)
		(mid 326.267615 -283.851243)
		(end 326.13854 -283.91104)
		(width 0.0762)
		(layer "F.Cu")
		(net "M_A_CPU0_SB_DQ<16>")
	)
	(arc
		(start 325.990966 -283.86278)
		(mid 325.85453 -283.805955)
		(end 325.70801 -283.78658)
		(width 0.0762)
		(layer "F.Cu")
		(net "M_A_CPU0_SB_DQ<16>")
	)
	(arc
		(start 326.13854 -283.91104)
		(mid 326.066802 -283.896188)
		(end 325.999348 -283.867606)
		(width 0.0762)
		(layer "F.Cu")
		(net "M_A_CPU0_SB_DQ<16>")
	)
	(segment
		(start 305.097688 -299.33519)
		(end 303.268126 -299.33519)
		(width 0.101346)
		(layer "F.Cu")
		(net "M_A_CPU0_SB_DQ<15>")
	)
	(segment
		(start 323.850254 -283.34589)
		(end 321.38239 -283.34589)
		(width 0.10668)
		(layer "F.Cu")
		(net "M_A_CPU0_SB_DQ<15>")
	)
	(segment
		(start 324.360286 -283.34589)
		(end 323.850254 -283.34589)
		(width 0.0762)
		(layer "F.Cu")
		(net "M_A_CPU0_SB_DQ<15>")
	)
	(segment
		(start 325.999348 -283.212794)
		(end 325.990966 -283.21762)
		(width 0.0762)
		(layer "F.Cu")
		(net "M_A_CPU0_SB_DQ<15>")
	)
	(segment
		(start 308.66588 -298.757594)
		(end 308.297326 -298.910248)
		(width 0.101346)
		(layer "F.Cu")
		(net "M_A_CPU0_SB_DQ<15>")
	)
	(segment
		(start 308.297326 -298.910248)
		(end 306.123594 -298.910248)
		(width 0.101346)
		(layer "F.Cu")
		(net "M_A_CPU0_SB_DQ<15>")
	)
	(segment
		(start 306.123594 -298.910248)
		(end 305.097688 -299.33519)
		(width 0.101346)
		(layer "F.Cu")
		(net "M_A_CPU0_SB_DQ<15>")
	)
	(segment
		(start 315.418216 -292.885368)
		(end 310.168544 -298.13504)
		(width 0.10668)
		(layer "F.Cu")
		(net "M_A_CPU0_SB_DQ<15>")
	)
	(segment
		(start 325.708264 -283.29382)
		(end 324.412356 -283.29382)
		(width 0.0762)
		(layer "F.Cu")
		(net "M_A_CPU0_SB_DQ<15>")
	)
	(segment
		(start 310.168544 -298.13504)
		(end 308.66588 -298.757594)
		(width 0.10668)
		(layer "F.Cu")
		(net "M_A_CPU0_SB_DQ<15>")
	)
	(segment
		(start 321.38239 -283.34589)
		(end 315.418216 -289.310064)
		(width 0.10668)
		(layer "F.Cu")
		(net "M_A_CPU0_SB_DQ<15>")
	)
	(segment
		(start 315.418216 -289.310064)
		(end 315.418216 -292.885368)
		(width 0.10668)
		(layer "F.Cu")
		(net "M_A_CPU0_SB_DQ<15>")
	)
	(segment
		(start 324.412356 -283.29382)
		(end 324.360286 -283.34589)
		(width 0.0762)
		(layer "F.Cu")
		(net "M_A_CPU0_SB_DQ<15>")
	)
	(arc
		(start 325.990966 -283.21762)
		(mid 325.877242 -283.267921)
		(end 325.755254 -283.292042)
		(width 0.0762)
		(layer "F.Cu")
		(net "M_A_CPU0_SB_DQ<15>")
	)
	(arc
		(start 327.304908 -283.21762)
		(mid 327.117964 -283.167365)
		(end 326.93102 -283.21762)
		(width 0.0762)
		(layer "F.Cu")
		(net "M_A_CPU0_SB_DQ<15>")
	)
	(arc
		(start 325.755254 -283.292042)
		(mid 325.731777 -283.293418)
		(end 325.708264 -283.29382)
		(width 0.0762)
		(layer "F.Cu")
		(net "M_A_CPU0_SB_DQ<15>")
	)
	(arc
		(start 326.365108 -283.21762)
		(mid 326.182857 -283.16727)
		(end 325.999348 -283.212794)
		(width 0.0762)
		(layer "F.Cu")
		(net "M_A_CPU0_SB_DQ<15>")
	)
	(arc
		(start 326.93102 -283.21762)
		(mid 326.648064 -283.293797)
		(end 326.365108 -283.21762)
		(width 0.0762)
		(layer "F.Cu")
		(net "M_A_CPU0_SB_DQ<15>")
	)
	(arc
		(start 327.53808 -283.291788)
		(mid 327.417431 -283.267487)
		(end 327.304908 -283.21762)
		(width 0.0762)
		(layer "F.Cu")
		(net "M_A_CPU0_SB_DQ<15>")
	)
	(arc
		(start 328.058018 -283.5402)
		(mid 327.820406 -283.369212)
		(end 327.53808 -283.291788)
		(width 0.0762)
		(layer "F.Cu")
		(net "M_A_CPU0_SB_DQ<15>")
	)
	(segment
		(start 305.41214 -297.992546)
		(end 305.310794 -298.093892)
		(width 0.101346)
		(layer "F.Cu")
		(net "M_A_CPU0_SB_DQ<14>")
	)
	(segment
		(start 305.7144 -297.635168)
		(end 305.513486 -297.635168)
		(width 0.101346)
		(layer "F.Cu")
		(net "M_A_CPU0_SB_DQ<14>")
	)
	(segment
		(start 323.953124 -282.184602)
		(end 321.58051 -282.184602)
		(width 0.10668)
		(layer "F.Cu")
		(net "M_A_CPU0_SB_DQ<14>")
	)
	(segment
		(start 305.119786 -298.093892)
		(end 305.01844 -297.992546)
		(width 0.101346)
		(layer "F.Cu")
		(net "M_A_CPU0_SB_DQ<14>")
	)
	(segment
		(start 304.917094 -297.635168)
		(end 303.268126 -297.635168)
		(width 0.101346)
		(layer "F.Cu")
		(net "M_A_CPU0_SB_DQ<14>")
	)
	(segment
		(start 306.139342 -297.210226)
		(end 305.7144 -297.635168)
		(width 0.101346)
		(layer "F.Cu")
		(net "M_A_CPU0_SB_DQ<14>")
	)
	(segment
		(start 310.443626 -296.888154)
		(end 308.932326 -296.888154)
		(width 0.10668)
		(layer "F.Cu")
		(net "M_A_CPU0_SB_DQ<14>")
	)
	(segment
		(start 324.311518 -282.357068)
		(end 324.139052 -282.184602)
		(width 0.0762)
		(layer "F.Cu")
		(net "M_A_CPU0_SB_DQ<14>")
	)
	(segment
		(start 305.01844 -297.992546)
		(end 305.01844 -297.736514)
		(width 0.101346)
		(layer "F.Cu")
		(net "M_A_CPU0_SB_DQ<14>")
	)
	(segment
		(start 305.310794 -298.093892)
		(end 305.119786 -298.093892)
		(width 0.101346)
		(layer "F.Cu")
		(net "M_A_CPU0_SB_DQ<14>")
	)
	(segment
		(start 321.58051 -282.184602)
		(end 314.737496 -289.027616)
		(width 0.10668)
		(layer "F.Cu")
		(net "M_A_CPU0_SB_DQ<14>")
	)
	(segment
		(start 308.610254 -297.210226)
		(end 306.139342 -297.210226)
		(width 0.101346)
		(layer "F.Cu")
		(net "M_A_CPU0_SB_DQ<14>")
	)
	(segment
		(start 308.932326 -296.888154)
		(end 308.66588 -297.1546)
		(width 0.10668)
		(layer "F.Cu")
		(net "M_A_CPU0_SB_DQ<14>")
	)
	(segment
		(start 325.70801 -282.357068)
		(end 324.311518 -282.357068)
		(width 0.0762)
		(layer "F.Cu")
		(net "M_A_CPU0_SB_DQ<14>")
	)
	(segment
		(start 308.66588 -297.1546)
		(end 308.610254 -297.210226)
		(width 0.101346)
		(layer "F.Cu")
		(net "M_A_CPU0_SB_DQ<14>")
	)
	(segment
		(start 305.01844 -297.736514)
		(end 304.917094 -297.635168)
		(width 0.101346)
		(layer "F.Cu")
		(net "M_A_CPU0_SB_DQ<14>")
	)
	(segment
		(start 305.513486 -297.635168)
		(end 305.41214 -297.736514)
		(width 0.101346)
		(layer "F.Cu")
		(net "M_A_CPU0_SB_DQ<14>")
	)
	(segment
		(start 324.139052 -282.184602)
		(end 323.953124 -282.184602)
		(width 0.0762)
		(layer "F.Cu")
		(net "M_A_CPU0_SB_DQ<14>")
	)
	(segment
		(start 314.737496 -289.027616)
		(end 314.737496 -292.594284)
		(width 0.10668)
		(layer "F.Cu")
		(net "M_A_CPU0_SB_DQ<14>")
	)
	(segment
		(start 305.41214 -297.736514)
		(end 305.41214 -297.992546)
		(width 0.101346)
		(layer "F.Cu")
		(net "M_A_CPU0_SB_DQ<14>")
	)
	(segment
		(start 314.737496 -292.594284)
		(end 310.443626 -296.888154)
		(width 0.10668)
		(layer "F.Cu")
		(net "M_A_CPU0_SB_DQ<14>")
	)
	(arc
		(start 326.648064 -282.730194)
		(mid 326.405747 -282.560474)
		(end 326.12076 -282.48102)
		(width 0.0762)
		(layer "F.Cu")
		(net "M_A_CPU0_SB_DQ<14>")
	)
	(arc
		(start 325.894954 -282.407614)
		(mid 325.804821 -282.369994)
		(end 325.70801 -282.357068)
		(width 0.0762)
		(layer "F.Cu")
		(net "M_A_CPU0_SB_DQ<14>")
	)
	(arc
		(start 326.12076 -282.48102)
		(mid 326.003947 -282.456344)
		(end 325.894954 -282.407614)
		(width 0.0762)
		(layer "F.Cu")
		(net "M_A_CPU0_SB_DQ<14>")
	)
	(segment
		(start 323.402198 -282.528772)
		(end 323.216524 -282.528772)
		(width 0.10668)
		(layer "F.Cu")
		(net "M_A_CPU0_SB_DQ<13>")
	)
	(segment
		(start 309.762652 -297.357546)
		(end 309.655972 -297.464226)
		(width 0.10668)
		(layer "F.Cu")
		(net "M_A_CPU0_SB_DQ<13>")
	)
	(segment
		(start 321.513708 -282.89885)
		(end 321.407028 -283.00553)
		(width 0.10668)
		(layer "F.Cu")
		(net "M_A_CPU0_SB_DQ<13>")
	)
	(segment
		(start 324.619874 -283.00553)
		(end 323.901054 -283.00553)
		(width 0.0762)
		(layer "F.Cu")
		(net "M_A_CPU0_SB_DQ<13>")
	)
	(segment
		(start 322.311776 -282.635452)
		(end 322.311776 -282.89885)
		(width 0.10668)
		(layer "F.Cu")
		(net "M_A_CPU0_SB_DQ<13>")
	)
	(segment
		(start 309.256938 -297.877992)
		(end 309.256938 -297.464226)
		(width 0.10668)
		(layer "F.Cu")
		(net "M_A_CPU0_SB_DQ<13>")
	)
	(segment
		(start 321.407028 -283.00553)
		(end 321.241166 -283.00553)
		(width 0.10668)
		(layer "F.Cu")
		(net "M_A_CPU0_SB_DQ<13>")
	)
	(segment
		(start 321.241166 -283.00553)
		(end 315.077856 -289.16884)
		(width 0.10668)
		(layer "F.Cu")
		(net "M_A_CPU0_SB_DQ<13>")
	)
	(segment
		(start 315.077856 -289.16884)
		(end 315.077856 -292.744144)
		(width 0.10668)
		(layer "F.Cu")
		(net "M_A_CPU0_SB_DQ<13>")
	)
	(segment
		(start 322.81749 -283.00553)
		(end 322.71081 -282.89885)
		(width 0.10668)
		(layer "F.Cu")
		(net "M_A_CPU0_SB_DQ<13>")
	)
	(segment
		(start 323.109844 -282.635452)
		(end 323.109844 -282.89885)
		(width 0.10668)
		(layer "F.Cu")
		(net "M_A_CPU0_SB_DQ<13>")
	)
	(segment
		(start 321.620388 -282.626308)
		(end 321.513708 -282.732988)
		(width 0.10668)
		(layer "F.Cu")
		(net "M_A_CPU0_SB_DQ<13>")
	)
	(segment
		(start 308.523894 -297.803824)
		(end 308.523894 -298.368212)
		(width 0.10668)
		(layer "F.Cu")
		(net "M_A_CPU0_SB_DQ<13>")
	)
	(segment
		(start 326.835008 -283.052774)
		(end 326.826626 -283.0576)
		(width 0.0762)
		(layer "F.Cu")
		(net "M_A_CPU0_SB_DQ<13>")
	)
	(segment
		(start 309.655972 -297.464226)
		(end 309.655972 -297.877992)
		(width 0.10668)
		(layer "F.Cu")
		(net "M_A_CPU0_SB_DQ<13>")
	)
	(segment
		(start 323.615558 -283.00553)
		(end 323.508878 -282.89885)
		(width 0.10668)
		(layer "F.Cu")
		(net "M_A_CPU0_SB_DQ<13>")
	)
	(segment
		(start 323.508878 -282.635452)
		(end 323.402198 -282.528772)
		(width 0.10668)
		(layer "F.Cu")
		(net "M_A_CPU0_SB_DQ<13>")
	)
	(segment
		(start 327.587864 -282.730194)
		(end 327.688702 -282.903676)
		(width 0.0762)
		(layer "F.Cu")
		(net "M_A_CPU0_SB_DQ<13>")
	)
	(segment
		(start 310.464454 -297.357546)
		(end 309.762652 -297.357546)
		(width 0.10668)
		(layer "F.Cu")
		(net "M_A_CPU0_SB_DQ<13>")
	)
	(segment
		(start 321.806062 -282.626308)
		(end 321.620388 -282.626308)
		(width 0.10668)
		(layer "F.Cu")
		(net "M_A_CPU0_SB_DQ<13>")
	)
	(segment
		(start 309.363618 -297.984672)
		(end 309.256938 -297.877992)
		(width 0.10668)
		(layer "F.Cu")
		(net "M_A_CPU0_SB_DQ<13>")
	)
	(segment
		(start 322.71081 -282.635452)
		(end 322.60413 -282.528772)
		(width 0.10668)
		(layer "F.Cu")
		(net "M_A_CPU0_SB_DQ<13>")
	)
	(segment
		(start 322.311776 -282.89885)
		(end 322.205096 -283.00553)
		(width 0.10668)
		(layer "F.Cu")
		(net "M_A_CPU0_SB_DQ<13>")
	)
	(segment
		(start 323.109844 -282.89885)
		(end 323.003164 -283.00553)
		(width 0.10668)
		(layer "F.Cu")
		(net "M_A_CPU0_SB_DQ<13>")
	)
	(segment
		(start 321.912742 -282.89885)
		(end 321.912742 -282.732988)
		(width 0.10668)
		(layer "F.Cu")
		(net "M_A_CPU0_SB_DQ<13>")
	)
	(segment
		(start 309.655972 -297.877992)
		(end 309.549292 -297.984672)
		(width 0.10668)
		(layer "F.Cu")
		(net "M_A_CPU0_SB_DQ<13>")
	)
	(segment
		(start 308.970172 -297.357546)
		(end 308.523894 -297.803824)
		(width 0.10668)
		(layer "F.Cu")
		(net "M_A_CPU0_SB_DQ<13>")
	)
	(segment
		(start 315.077856 -292.744144)
		(end 310.464454 -297.357546)
		(width 0.10668)
		(layer "F.Cu")
		(net "M_A_CPU0_SB_DQ<13>")
	)
	(segment
		(start 322.71081 -282.89885)
		(end 322.71081 -282.635452)
		(width 0.10668)
		(layer "F.Cu")
		(net "M_A_CPU0_SB_DQ<13>")
	)
	(segment
		(start 321.912742 -282.732988)
		(end 321.806062 -282.626308)
		(width 0.10668)
		(layer "F.Cu")
		(net "M_A_CPU0_SB_DQ<13>")
	)
	(segment
		(start 309.256938 -297.464226)
		(end 309.150258 -297.357546)
		(width 0.10668)
		(layer "F.Cu")
		(net "M_A_CPU0_SB_DQ<13>")
	)
	(segment
		(start 325.70801 -283.10332)
		(end 324.717664 -283.10332)
		(width 0.0762)
		(layer "F.Cu")
		(net "M_A_CPU0_SB_DQ<13>")
	)
	(segment
		(start 322.418456 -282.528772)
		(end 322.311776 -282.635452)
		(width 0.10668)
		(layer "F.Cu")
		(net "M_A_CPU0_SB_DQ<13>")
	)
	(segment
		(start 323.216524 -282.528772)
		(end 323.109844 -282.635452)
		(width 0.10668)
		(layer "F.Cu")
		(net "M_A_CPU0_SB_DQ<13>")
	)
	(segment
		(start 327.409302 -283.0576)
		(end 327.40092 -283.052774)
		(width 0.0762)
		(layer "F.Cu")
		(net "M_A_CPU0_SB_DQ<13>")
	)
	(segment
		(start 309.549292 -297.984672)
		(end 309.363618 -297.984672)
		(width 0.10668)
		(layer "F.Cu")
		(net "M_A_CPU0_SB_DQ<13>")
	)
	(segment
		(start 323.003164 -283.00553)
		(end 322.81749 -283.00553)
		(width 0.10668)
		(layer "F.Cu")
		(net "M_A_CPU0_SB_DQ<13>")
	)
	(segment
		(start 324.717664 -283.10332)
		(end 324.619874 -283.00553)
		(width 0.0762)
		(layer "F.Cu")
		(net "M_A_CPU0_SB_DQ<13>")
	)
	(segment
		(start 322.60413 -282.528772)
		(end 322.418456 -282.528772)
		(width 0.10668)
		(layer "F.Cu")
		(net "M_A_CPU0_SB_DQ<13>")
	)
	(segment
		(start 323.508878 -282.89885)
		(end 323.508878 -282.635452)
		(width 0.10668)
		(layer "F.Cu")
		(net "M_A_CPU0_SB_DQ<13>")
	)
	(segment
		(start 321.513708 -282.732988)
		(end 321.513708 -282.89885)
		(width 0.10668)
		(layer "F.Cu")
		(net "M_A_CPU0_SB_DQ<13>")
	)
	(segment
		(start 323.901054 -283.00553)
		(end 323.615558 -283.00553)
		(width 0.10668)
		(layer "F.Cu")
		(net "M_A_CPU0_SB_DQ<13>")
	)
	(segment
		(start 322.205096 -283.00553)
		(end 322.019422 -283.00553)
		(width 0.10668)
		(layer "F.Cu")
		(net "M_A_CPU0_SB_DQ<13>")
	)
	(segment
		(start 308.523894 -298.368212)
		(end 308.407054 -298.485052)
		(width 0.10668)
		(layer "F.Cu")
		(net "M_A_CPU0_SB_DQ<13>")
	)
	(segment
		(start 308.407054 -298.485052)
		(end 307.368194 -298.485052)
		(width 0.10668)
		(layer "F.Cu")
		(net "M_A_CPU0_SB_DQ<13>")
	)
	(segment
		(start 322.019422 -283.00553)
		(end 321.912742 -282.89885)
		(width 0.10668)
		(layer "F.Cu")
		(net "M_A_CPU0_SB_DQ<13>")
	)
	(segment
		(start 309.150258 -297.357546)
		(end 308.970172 -297.357546)
		(width 0.10668)
		(layer "F.Cu")
		(net "M_A_CPU0_SB_DQ<13>")
	)
	(arc
		(start 325.738998 -283.10205)
		(mid 325.723517 -283.103006)
		(end 325.70801 -283.10332)
		(width 0.0762)
		(layer "F.Cu")
		(net "M_A_CPU0_SB_DQ<13>")
	)
	(arc
		(start 327.40092 -283.052774)
		(mid 327.117964 -282.976597)
		(end 326.835008 -283.052774)
		(width 0.0762)
		(layer "F.Cu")
		(net "M_A_CPU0_SB_DQ<13>")
	)
	(arc
		(start 326.460866 -283.052774)
		(mid 326.17791 -282.976597)
		(end 325.894954 -283.052774)
		(width 0.0762)
		(layer "F.Cu")
		(net "M_A_CPU0_SB_DQ<13>")
	)
	(arc
		(start 327.542652 -283.100272)
		(mid 327.473954 -283.085256)
		(end 327.409302 -283.0576)
		(width 0.0762)
		(layer "F.Cu")
		(net "M_A_CPU0_SB_DQ<13>")
	)
	(arc
		(start 326.826626 -283.0576)
		(mid 326.643118 -283.103094)
		(end 326.460866 -283.052774)
		(width 0.0762)
		(layer "F.Cu")
		(net "M_A_CPU0_SB_DQ<13>")
	)
	(arc
		(start 325.894954 -283.052774)
		(mid 325.819714 -283.086087)
		(end 325.738998 -283.10205)
		(width 0.0762)
		(layer "F.Cu")
		(net "M_A_CPU0_SB_DQ<13>")
	)
	(arc
		(start 327.688702 -282.903676)
		(mid 327.672777 -283.044368)
		(end 327.542652 -283.100272)
		(width 0.0762)
		(layer "F.Cu")
		(net "M_A_CPU0_SB_DQ<13>")
	)
	(segment
		(start 310.998108 -295.701212)
		(end 310.998108 -295.852088)
		(width 0.10668)
		(layer "F.Cu")
		(net "M_A_CPU0_SB_DQ<12>")
	)
	(segment
		(start 312.09107 -294.12311)
		(end 311.959752 -294.254428)
		(width 0.10668)
		(layer "F.Cu")
		(net "M_A_CPU0_SB_DQ<12>")
	)
	(segment
		(start 309.833518 -296.380662)
		(end 309.693056 -296.521124)
		(width 0.10668)
		(layer "F.Cu")
		(net "M_A_CPU0_SB_DQ<12>")
	)
	(segment
		(start 314.217304 -292.147752)
		(end 314.384436 -292.314884)
		(width 0.10668)
		(layer "F.Cu")
		(net "M_A_CPU0_SB_DQ<12>")
	)
	(segment
		(start 314.384436 -292.46576)
		(end 314.253118 -292.597078)
		(width 0.10668)
		(layer "F.Cu")
		(net "M_A_CPU0_SB_DQ<12>")
	)
	(segment
		(start 314.390278 -288.89325)
		(end 314.390278 -291.823902)
		(width 0.10668)
		(layer "F.Cu")
		(net "M_A_CPU0_SB_DQ<12>")
	)
	(segment
		(start 313.93511 -292.429946)
		(end 313.784234 -292.429946)
		(width 0.10668)
		(layer "F.Cu")
		(net "M_A_CPU0_SB_DQ<12>")
	)
	(segment
		(start 314.253118 -292.597078)
		(end 314.102242 -292.597078)
		(width 0.10668)
		(layer "F.Cu")
		(net "M_A_CPU0_SB_DQ<12>")
	)
	(segment
		(start 312.241946 -294.12311)
		(end 312.09107 -294.12311)
		(width 0.10668)
		(layer "F.Cu")
		(net "M_A_CPU0_SB_DQ<12>")
	)
	(segment
		(start 312.806334 -293.558722)
		(end 312.655458 -293.558722)
		(width 0.10668)
		(layer "F.Cu")
		(net "M_A_CPU0_SB_DQ<12>")
	)
	(segment
		(start 310.998108 -295.852088)
		(end 310.86679 -295.983406)
		(width 0.10668)
		(layer "F.Cu")
		(net "M_A_CPU0_SB_DQ<12>")
	)
	(segment
		(start 311.280302 -295.419018)
		(end 311.11317 -295.251886)
		(width 0.10668)
		(layer "F.Cu")
		(net "M_A_CPU0_SB_DQ<12>")
	)
	(segment
		(start 312.52414 -293.840916)
		(end 312.691272 -294.008048)
		(width 0.10668)
		(layer "F.Cu")
		(net "M_A_CPU0_SB_DQ<12>")
	)
	(segment
		(start 311.395364 -294.969692)
		(end 311.562496 -295.136824)
		(width 0.10668)
		(layer "F.Cu")
		(net "M_A_CPU0_SB_DQ<12>")
	)
	(segment
		(start 310.151526 -296.547794)
		(end 309.984394 -296.380662)
		(width 0.10668)
		(layer "F.Cu")
		(net "M_A_CPU0_SB_DQ<12>")
	)
	(segment
		(start 313.124342 -293.725854)
		(end 312.973466 -293.725854)
		(width 0.10668)
		(layer "F.Cu")
		(net "M_A_CPU0_SB_DQ<12>")
	)
	(segment
		(start 313.088528 -293.125652)
		(end 313.088528 -293.276528)
		(width 0.10668)
		(layer "F.Cu")
		(net "M_A_CPU0_SB_DQ<12>")
	)
	(segment
		(start 326.17791 -281.920188)
		(end 326.276208 -282.089352)
		(width 0.0762)
		(layer "F.Cu")
		(net "M_A_CPU0_SB_DQ<12>")
	)
	(segment
		(start 309.693056 -296.521124)
		(end 308.65826 -296.521124)
		(width 0.10668)
		(layer "F.Cu")
		(net "M_A_CPU0_SB_DQ<12>")
	)
	(segment
		(start 313.219846 -292.994334)
		(end 313.088528 -293.125652)
		(width 0.10668)
		(layer "F.Cu")
		(net "M_A_CPU0_SB_DQ<12>")
	)
	(segment
		(start 312.973466 -293.725854)
		(end 312.806334 -293.558722)
		(width 0.10668)
		(layer "F.Cu")
		(net "M_A_CPU0_SB_DQ<12>")
	)
	(segment
		(start 310.830976 -295.383204)
		(end 310.830976 -295.53408)
		(width 0.10668)
		(layer "F.Cu")
		(net "M_A_CPU0_SB_DQ<12>")
	)
	(segment
		(start 310.86679 -295.983406)
		(end 310.715914 -295.983406)
		(width 0.10668)
		(layer "F.Cu")
		(net "M_A_CPU0_SB_DQ<12>")
	)
	(segment
		(start 314.217304 -291.996876)
		(end 314.217304 -292.147752)
		(width 0.10668)
		(layer "F.Cu")
		(net "M_A_CPU0_SB_DQ<12>")
	)
	(segment
		(start 310.43372 -296.416476)
		(end 310.302402 -296.547794)
		(width 0.10668)
		(layer "F.Cu")
		(net "M_A_CPU0_SB_DQ<12>")
	)
	(segment
		(start 311.431178 -295.419018)
		(end 311.280302 -295.419018)
		(width 0.10668)
		(layer "F.Cu")
		(net "M_A_CPU0_SB_DQ<12>")
	)
	(segment
		(start 313.820048 -293.030148)
		(end 313.68873 -293.161466)
		(width 0.10668)
		(layer "F.Cu")
		(net "M_A_CPU0_SB_DQ<12>")
	)
	(segment
		(start 313.088528 -293.276528)
		(end 313.25566 -293.44366)
		(width 0.10668)
		(layer "F.Cu")
		(net "M_A_CPU0_SB_DQ<12>")
	)
	(segment
		(start 310.830976 -295.53408)
		(end 310.998108 -295.701212)
		(width 0.10668)
		(layer "F.Cu")
		(net "M_A_CPU0_SB_DQ<12>")
	)
	(segment
		(start 325.999348 -282.247594)
		(end 325.990966 -282.242768)
		(width 0.0762)
		(layer "F.Cu")
		(net "M_A_CPU0_SB_DQ<12>")
	)
	(segment
		(start 312.559954 -294.290242)
		(end 312.409078 -294.290242)
		(width 0.10668)
		(layer "F.Cu")
		(net "M_A_CPU0_SB_DQ<12>")
	)
	(segment
		(start 308.65826 -296.521124)
		(end 308.394354 -296.78503)
		(width 0.10668)
		(layer "F.Cu")
		(net "M_A_CPU0_SB_DQ<12>")
	)
	(segment
		(start 311.677558 -294.687498)
		(end 311.526682 -294.687498)
		(width 0.10668)
		(layer "F.Cu")
		(net "M_A_CPU0_SB_DQ<12>")
	)
	(segment
		(start 308.394354 -296.78503)
		(end 307.368194 -296.78503)
		(width 0.10668)
		(layer "F.Cu")
		(net "M_A_CPU0_SB_DQ<12>")
	)
	(segment
		(start 310.302402 -296.547794)
		(end 310.151526 -296.547794)
		(width 0.10668)
		(layer "F.Cu")
		(net "M_A_CPU0_SB_DQ<12>")
	)
	(segment
		(start 314.384436 -292.314884)
		(end 314.384436 -292.46576)
		(width 0.10668)
		(layer "F.Cu")
		(net "M_A_CPU0_SB_DQ<12>")
	)
	(segment
		(start 311.995566 -294.85463)
		(end 311.84469 -294.85463)
		(width 0.10668)
		(layer "F.Cu")
		(net "M_A_CPU0_SB_DQ<12>")
	)
	(segment
		(start 314.390278 -291.823902)
		(end 314.217304 -291.996876)
		(width 0.10668)
		(layer "F.Cu")
		(net "M_A_CPU0_SB_DQ<12>")
	)
	(segment
		(start 313.784234 -292.429946)
		(end 313.652916 -292.561264)
		(width 0.10668)
		(layer "F.Cu")
		(net "M_A_CPU0_SB_DQ<12>")
	)
	(segment
		(start 313.820048 -292.879272)
		(end 313.820048 -293.030148)
		(width 0.10668)
		(layer "F.Cu")
		(net "M_A_CPU0_SB_DQ<12>")
	)
	(segment
		(start 310.715914 -295.983406)
		(end 310.548782 -295.816274)
		(width 0.10668)
		(layer "F.Cu")
		(net "M_A_CPU0_SB_DQ<12>")
	)
	(segment
		(start 321.446652 -281.836876)
		(end 314.390278 -288.89325)
		(width 0.10668)
		(layer "F.Cu")
		(net "M_A_CPU0_SB_DQ<12>")
	)
	(segment
		(start 313.68873 -293.161466)
		(end 313.537854 -293.161466)
		(width 0.10668)
		(layer "F.Cu")
		(net "M_A_CPU0_SB_DQ<12>")
	)
	(segment
		(start 310.397906 -295.816274)
		(end 310.266588 -295.947592)
		(width 0.10668)
		(layer "F.Cu")
		(net "M_A_CPU0_SB_DQ<12>")
	)
	(segment
		(start 310.266588 -295.947592)
		(end 310.266588 -296.098468)
		(width 0.10668)
		(layer "F.Cu")
		(net "M_A_CPU0_SB_DQ<12>")
	)
	(segment
		(start 311.959752 -294.254428)
		(end 311.959752 -294.405304)
		(width 0.10668)
		(layer "F.Cu")
		(net "M_A_CPU0_SB_DQ<12>")
	)
	(segment
		(start 313.537854 -293.161466)
		(end 313.370722 -292.994334)
		(width 0.10668)
		(layer "F.Cu")
		(net "M_A_CPU0_SB_DQ<12>")
	)
	(segment
		(start 313.25566 -293.44366)
		(end 313.25566 -293.594536)
		(width 0.10668)
		(layer "F.Cu")
		(net "M_A_CPU0_SB_DQ<12>")
	)
	(segment
		(start 309.984394 -296.380662)
		(end 309.833518 -296.380662)
		(width 0.10668)
		(layer "F.Cu")
		(net "M_A_CPU0_SB_DQ<12>")
	)
	(segment
		(start 312.691272 -294.008048)
		(end 312.691272 -294.158924)
		(width 0.10668)
		(layer "F.Cu")
		(net "M_A_CPU0_SB_DQ<12>")
	)
	(segment
		(start 312.126884 -294.723312)
		(end 311.995566 -294.85463)
		(width 0.10668)
		(layer "F.Cu")
		(net "M_A_CPU0_SB_DQ<12>")
	)
	(segment
		(start 311.526682 -294.687498)
		(end 311.395364 -294.818816)
		(width 0.10668)
		(layer "F.Cu")
		(net "M_A_CPU0_SB_DQ<12>")
	)
	(segment
		(start 313.370722 -292.994334)
		(end 313.219846 -292.994334)
		(width 0.10668)
		(layer "F.Cu")
		(net "M_A_CPU0_SB_DQ<12>")
	)
	(segment
		(start 311.11317 -295.251886)
		(end 310.962294 -295.251886)
		(width 0.10668)
		(layer "F.Cu")
		(net "M_A_CPU0_SB_DQ<12>")
	)
	(segment
		(start 311.562496 -295.136824)
		(end 311.562496 -295.2877)
		(width 0.10668)
		(layer "F.Cu")
		(net "M_A_CPU0_SB_DQ<12>")
	)
	(segment
		(start 311.395364 -294.818816)
		(end 311.395364 -294.969692)
		(width 0.10668)
		(layer "F.Cu")
		(net "M_A_CPU0_SB_DQ<12>")
	)
	(segment
		(start 324.543674 -282.166568)
		(end 324.213982 -281.836876)
		(width 0.0762)
		(layer "F.Cu")
		(net "M_A_CPU0_SB_DQ<12>")
	)
	(segment
		(start 312.52414 -293.69004)
		(end 312.52414 -293.840916)
		(width 0.10668)
		(layer "F.Cu")
		(net "M_A_CPU0_SB_DQ<12>")
	)
	(segment
		(start 312.126884 -294.572436)
		(end 312.126884 -294.723312)
		(width 0.10668)
		(layer "F.Cu")
		(net "M_A_CPU0_SB_DQ<12>")
	)
	(segment
		(start 311.562496 -295.2877)
		(end 311.431178 -295.419018)
		(width 0.10668)
		(layer "F.Cu")
		(net "M_A_CPU0_SB_DQ<12>")
	)
	(segment
		(start 310.266588 -296.098468)
		(end 310.43372 -296.2656)
		(width 0.10668)
		(layer "F.Cu")
		(net "M_A_CPU0_SB_DQ<12>")
	)
	(segment
		(start 313.652916 -292.561264)
		(end 313.652916 -292.71214)
		(width 0.10668)
		(layer "F.Cu")
		(net "M_A_CPU0_SB_DQ<12>")
	)
	(segment
		(start 312.691272 -294.158924)
		(end 312.559954 -294.290242)
		(width 0.10668)
		(layer "F.Cu")
		(net "M_A_CPU0_SB_DQ<12>")
	)
	(segment
		(start 313.652916 -292.71214)
		(end 313.820048 -292.879272)
		(width 0.10668)
		(layer "F.Cu")
		(net "M_A_CPU0_SB_DQ<12>")
	)
	(segment
		(start 311.84469 -294.85463)
		(end 311.677558 -294.687498)
		(width 0.10668)
		(layer "F.Cu")
		(net "M_A_CPU0_SB_DQ<12>")
	)
	(segment
		(start 323.909436 -281.836876)
		(end 321.446652 -281.836876)
		(width 0.10668)
		(layer "F.Cu")
		(net "M_A_CPU0_SB_DQ<12>")
	)
	(segment
		(start 311.959752 -294.405304)
		(end 312.126884 -294.572436)
		(width 0.10668)
		(layer "F.Cu")
		(net "M_A_CPU0_SB_DQ<12>")
	)
	(segment
		(start 310.962294 -295.251886)
		(end 310.830976 -295.383204)
		(width 0.10668)
		(layer "F.Cu")
		(net "M_A_CPU0_SB_DQ<12>")
	)
	(segment
		(start 324.213982 -281.836876)
		(end 323.909436 -281.836876)
		(width 0.0762)
		(layer "F.Cu")
		(net "M_A_CPU0_SB_DQ<12>")
	)
	(segment
		(start 325.70801 -282.166568)
		(end 324.543674 -282.166568)
		(width 0.0762)
		(layer "F.Cu")
		(net "M_A_CPU0_SB_DQ<12>")
	)
	(segment
		(start 312.655458 -293.558722)
		(end 312.52414 -293.69004)
		(width 0.10668)
		(layer "F.Cu")
		(net "M_A_CPU0_SB_DQ<12>")
	)
	(segment
		(start 310.43372 -296.2656)
		(end 310.43372 -296.416476)
		(width 0.10668)
		(layer "F.Cu")
		(net "M_A_CPU0_SB_DQ<12>")
	)
	(segment
		(start 314.102242 -292.597078)
		(end 313.93511 -292.429946)
		(width 0.10668)
		(layer "F.Cu")
		(net "M_A_CPU0_SB_DQ<12>")
	)
	(segment
		(start 312.409078 -294.290242)
		(end 312.241946 -294.12311)
		(width 0.10668)
		(layer "F.Cu")
		(net "M_A_CPU0_SB_DQ<12>")
	)
	(segment
		(start 313.25566 -293.594536)
		(end 313.124342 -293.725854)
		(width 0.10668)
		(layer "F.Cu")
		(net "M_A_CPU0_SB_DQ<12>")
	)
	(segment
		(start 310.548782 -295.816274)
		(end 310.397906 -295.816274)
		(width 0.10668)
		(layer "F.Cu")
		(net "M_A_CPU0_SB_DQ<12>")
	)
	(arc
		(start 326.13854 -282.291028)
		(mid 326.066802 -282.276176)
		(end 325.999348 -282.247594)
		(width 0.0762)
		(layer "F.Cu")
		(net "M_A_CPU0_SB_DQ<12>")
	)
	(arc
		(start 325.990966 -282.242768)
		(mid 325.85453 -282.185943)
		(end 325.70801 -282.166568)
		(width 0.0762)
		(layer "F.Cu")
		(net "M_A_CPU0_SB_DQ<12>")
	)
	(arc
		(start 326.276208 -282.089352)
		(mid 326.267615 -282.231231)
		(end 326.13854 -282.291028)
		(width 0.0762)
		(layer "F.Cu")
		(net "M_A_CPU0_SB_DQ<12>")
	)
	(segment
		(start 325.999348 -279.97277)
		(end 325.990966 -279.977596)
		(width 0.0762)
		(layer "F.Cu")
		(net "M_A_CPU0_SB_DQ<11>")
	)
	(segment
		(start 324.190868 -279.90546)
		(end 320.153792 -279.90546)
		(width 0.10668)
		(layer "F.Cu")
		(net "M_A_CPU0_SB_DQ<11>")
	)
	(segment
		(start 305.76012 -292.960044)
		(end 305.335178 -293.384986)
		(width 0.101346)
		(layer "F.Cu")
		(net "M_A_CPU0_SB_DQ<11>")
	)
	(segment
		(start 308.50078 -292.739318)
		(end 308.280054 -292.960044)
		(width 0.101346)
		(layer "F.Cu")
		(net "M_A_CPU0_SB_DQ<11>")
	)
	(segment
		(start 312.250328 -289.997896)
		(end 312.250328 -290.737036)
		(width 0.10668)
		(layer "F.Cu")
		(net "M_A_CPU0_SB_DQ<11>")
	)
	(segment
		(start 304.997104 -293.28364)
		(end 304.997104 -293.130478)
		(width 0.101346)
		(layer "F.Cu")
		(net "M_A_CPU0_SB_DQ<11>")
	)
	(segment
		(start 304.895758 -293.029132)
		(end 304.70475 -293.029132)
		(width 0.101346)
		(layer "F.Cu")
		(net "M_A_CPU0_SB_DQ<11>")
	)
	(segment
		(start 312.250328 -290.737036)
		(end 310.578754 -292.40861)
		(width 0.10668)
		(layer "F.Cu")
		(net "M_A_CPU0_SB_DQ<11>")
	)
	(segment
		(start 305.09845 -293.384986)
		(end 304.997104 -293.28364)
		(width 0.101346)
		(layer "F.Cu")
		(net "M_A_CPU0_SB_DQ<11>")
	)
	(segment
		(start 325.708264 -280.053796)
		(end 324.339204 -280.053796)
		(width 0.0762)
		(layer "F.Cu")
		(net "M_A_CPU0_SB_DQ<11>")
	)
	(segment
		(start 304.603404 -293.28364)
		(end 304.502058 -293.384986)
		(width 0.101346)
		(layer "F.Cu")
		(net "M_A_CPU0_SB_DQ<11>")
	)
	(segment
		(start 305.335178 -293.384986)
		(end 305.09845 -293.384986)
		(width 0.101346)
		(layer "F.Cu")
		(net "M_A_CPU0_SB_DQ<11>")
	)
	(segment
		(start 309.883302 -292.146736)
		(end 309.093362 -292.146736)
		(width 0.10668)
		(layer "F.Cu")
		(net "M_A_CPU0_SB_DQ<11>")
	)
	(segment
		(start 304.502058 -293.384986)
		(end 303.268126 -293.384986)
		(width 0.101346)
		(layer "F.Cu")
		(net "M_A_CPU0_SB_DQ<11>")
	)
	(segment
		(start 310.145176 -292.40861)
		(end 309.883302 -292.146736)
		(width 0.10668)
		(layer "F.Cu")
		(net "M_A_CPU0_SB_DQ<11>")
	)
	(segment
		(start 304.997104 -293.130478)
		(end 304.895758 -293.029132)
		(width 0.101346)
		(layer "F.Cu")
		(net "M_A_CPU0_SB_DQ<11>")
	)
	(segment
		(start 308.280054 -292.960044)
		(end 305.76012 -292.960044)
		(width 0.101346)
		(layer "F.Cu")
		(net "M_A_CPU0_SB_DQ<11>")
	)
	(segment
		(start 310.578754 -292.40861)
		(end 310.145176 -292.40861)
		(width 0.10668)
		(layer "F.Cu")
		(net "M_A_CPU0_SB_DQ<11>")
	)
	(segment
		(start 324.339204 -280.053796)
		(end 324.190868 -279.90546)
		(width 0.0762)
		(layer "F.Cu")
		(net "M_A_CPU0_SB_DQ<11>")
	)
	(segment
		(start 312.02122 -288.038032)
		(end 312.02122 -289.768788)
		(width 0.10668)
		(layer "F.Cu")
		(net "M_A_CPU0_SB_DQ<11>")
	)
	(segment
		(start 320.153792 -279.90546)
		(end 312.02122 -288.038032)
		(width 0.10668)
		(layer "F.Cu")
		(net "M_A_CPU0_SB_DQ<11>")
	)
	(segment
		(start 309.093362 -292.146736)
		(end 308.50078 -292.739318)
		(width 0.10668)
		(layer "F.Cu")
		(net "M_A_CPU0_SB_DQ<11>")
	)
	(segment
		(start 312.02122 -289.768788)
		(end 312.250328 -289.997896)
		(width 0.10668)
		(layer "F.Cu")
		(net "M_A_CPU0_SB_DQ<11>")
	)
	(segment
		(start 304.70475 -293.029132)
		(end 304.603404 -293.130478)
		(width 0.101346)
		(layer "F.Cu")
		(net "M_A_CPU0_SB_DQ<11>")
	)
	(segment
		(start 304.603404 -293.130478)
		(end 304.603404 -293.28364)
		(width 0.101346)
		(layer "F.Cu")
		(net "M_A_CPU0_SB_DQ<11>")
	)
	(arc
		(start 325.990966 -279.977596)
		(mid 325.877242 -280.027897)
		(end 325.755254 -280.052018)
		(width 0.0762)
		(layer "F.Cu")
		(net "M_A_CPU0_SB_DQ<11>")
	)
	(arc
		(start 328.058018 -280.300176)
		(mid 327.820406 -280.129188)
		(end 327.53808 -280.051764)
		(width 0.0762)
		(layer "F.Cu")
		(net "M_A_CPU0_SB_DQ<11>")
	)
	(arc
		(start 327.53808 -280.051764)
		(mid 327.417431 -280.027463)
		(end 327.304908 -279.977596)
		(width 0.0762)
		(layer "F.Cu")
		(net "M_A_CPU0_SB_DQ<11>")
	)
	(arc
		(start 326.365108 -279.977596)
		(mid 326.182857 -279.927246)
		(end 325.999348 -279.97277)
		(width 0.0762)
		(layer "F.Cu")
		(net "M_A_CPU0_SB_DQ<11>")
	)
	(arc
		(start 325.755254 -280.052018)
		(mid 325.731777 -280.053394)
		(end 325.708264 -280.053796)
		(width 0.0762)
		(layer "F.Cu")
		(net "M_A_CPU0_SB_DQ<11>")
	)
	(arc
		(start 327.304908 -279.977596)
		(mid 327.117964 -279.927341)
		(end 326.93102 -279.977596)
		(width 0.0762)
		(layer "F.Cu")
		(net "M_A_CPU0_SB_DQ<11>")
	)
	(arc
		(start 326.93102 -279.977596)
		(mid 326.648064 -280.053773)
		(end 326.365108 -279.977596)
		(width 0.0762)
		(layer "F.Cu")
		(net "M_A_CPU0_SB_DQ<11>")
	)
	(segment
		(start 323.906134 -279.22474)
		(end 319.871344 -279.22474)
		(width 0.10668)
		(layer "F.Cu")
		(net "M_A_CPU0_SB_DQ<10>")
	)
	(segment
		(start 305.82997 -292.125146)
		(end 305.82997 -291.361368)
		(width 0.101346)
		(layer "F.Cu")
		(net "M_A_CPU0_SB_DQ<10>")
	)
	(segment
		(start 305.143916 -292.226492)
		(end 305.04257 -292.125146)
		(width 0.101346)
		(layer "F.Cu")
		(net "M_A_CPU0_SB_DQ<10>")
	)
	(segment
		(start 305.334924 -292.226492)
		(end 305.143916 -292.226492)
		(width 0.101346)
		(layer "F.Cu")
		(net "M_A_CPU0_SB_DQ<10>")
	)
	(segment
		(start 304.31994 -291.684964)
		(end 303.268126 -291.684964)
		(width 0.101346)
		(layer "F.Cu")
		(net "M_A_CPU0_SB_DQ<10>")
	)
	(segment
		(start 305.537616 -291.260022)
		(end 305.43627 -291.361368)
		(width 0.101346)
		(layer "F.Cu")
		(net "M_A_CPU0_SB_DQ<10>")
	)
	(segment
		(start 325.70801 -279.117044)
		(end 324.506844 -279.117044)
		(width 0.0762)
		(layer "F.Cu")
		(net "M_A_CPU0_SB_DQ<10>")
	)
	(segment
		(start 306.122324 -292.226492)
		(end 305.931316 -292.226492)
		(width 0.101346)
		(layer "F.Cu")
		(net "M_A_CPU0_SB_DQ<10>")
	)
	(segment
		(start 305.931316 -292.226492)
		(end 305.82997 -292.125146)
		(width 0.101346)
		(layer "F.Cu")
		(net "M_A_CPU0_SB_DQ<10>")
	)
	(segment
		(start 309.429404 -291.466016)
		(end 308.795928 -291.466016)
		(width 0.10668)
		(layer "F.Cu")
		(net "M_A_CPU0_SB_DQ<10>")
	)
	(segment
		(start 306.22367 -292.125146)
		(end 306.122324 -292.226492)
		(width 0.101346)
		(layer "F.Cu")
		(net "M_A_CPU0_SB_DQ<10>")
	)
	(segment
		(start 305.04257 -292.125146)
		(end 305.04257 -291.361368)
		(width 0.101346)
		(layer "F.Cu")
		(net "M_A_CPU0_SB_DQ<10>")
	)
	(segment
		(start 304.941224 -291.260022)
		(end 304.744882 -291.260022)
		(width 0.101346)
		(layer "F.Cu")
		(net "M_A_CPU0_SB_DQ<10>")
	)
	(segment
		(start 324.506844 -279.117044)
		(end 324.399148 -279.22474)
		(width 0.0762)
		(layer "F.Cu")
		(net "M_A_CPU0_SB_DQ<10>")
	)
	(segment
		(start 324.399148 -279.22474)
		(end 323.906134 -279.22474)
		(width 0.0762)
		(layer "F.Cu")
		(net "M_A_CPU0_SB_DQ<10>")
	)
	(segment
		(start 305.43627 -291.361368)
		(end 305.43627 -292.125146)
		(width 0.101346)
		(layer "F.Cu")
		(net "M_A_CPU0_SB_DQ<10>")
	)
	(segment
		(start 305.04257 -291.361368)
		(end 304.941224 -291.260022)
		(width 0.101346)
		(layer "F.Cu")
		(net "M_A_CPU0_SB_DQ<10>")
	)
	(segment
		(start 305.728624 -291.260022)
		(end 305.537616 -291.260022)
		(width 0.101346)
		(layer "F.Cu")
		(net "M_A_CPU0_SB_DQ<10>")
	)
	(segment
		(start 306.22367 -291.361368)
		(end 306.22367 -292.125146)
		(width 0.101346)
		(layer "F.Cu")
		(net "M_A_CPU0_SB_DQ<10>")
	)
	(segment
		(start 305.43627 -292.125146)
		(end 305.334924 -292.226492)
		(width 0.101346)
		(layer "F.Cu")
		(net "M_A_CPU0_SB_DQ<10>")
	)
	(segment
		(start 311.3405 -289.55492)
		(end 309.429404 -291.466016)
		(width 0.10668)
		(layer "F.Cu")
		(net "M_A_CPU0_SB_DQ<10>")
	)
	(segment
		(start 308.589934 -291.260022)
		(end 306.325016 -291.260022)
		(width 0.101346)
		(layer "F.Cu")
		(net "M_A_CPU0_SB_DQ<10>")
	)
	(segment
		(start 305.82997 -291.361368)
		(end 305.728624 -291.260022)
		(width 0.101346)
		(layer "F.Cu")
		(net "M_A_CPU0_SB_DQ<10>")
	)
	(segment
		(start 304.744882 -291.260022)
		(end 304.31994 -291.684964)
		(width 0.101346)
		(layer "F.Cu")
		(net "M_A_CPU0_SB_DQ<10>")
	)
	(segment
		(start 319.871344 -279.22474)
		(end 311.3405 -287.755584)
		(width 0.10668)
		(layer "F.Cu")
		(net "M_A_CPU0_SB_DQ<10>")
	)
	(segment
		(start 308.795928 -291.466016)
		(end 308.589934 -291.260022)
		(width 0.101346)
		(layer "F.Cu")
		(net "M_A_CPU0_SB_DQ<10>")
	)
	(segment
		(start 311.3405 -287.755584)
		(end 311.3405 -289.55492)
		(width 0.10668)
		(layer "F.Cu")
		(net "M_A_CPU0_SB_DQ<10>")
	)
	(segment
		(start 306.325016 -291.260022)
		(end 306.22367 -291.361368)
		(width 0.101346)
		(layer "F.Cu")
		(net "M_A_CPU0_SB_DQ<10>")
	)
	(arc
		(start 325.894954 -279.16759)
		(mid 325.804821 -279.12997)
		(end 325.70801 -279.117044)
		(width 0.0762)
		(layer "F.Cu")
		(net "M_A_CPU0_SB_DQ<10>")
	)
	(arc
		(start 326.12076 -279.240996)
		(mid 326.003947 -279.21632)
		(end 325.894954 -279.16759)
		(width 0.0762)
		(layer "F.Cu")
		(net "M_A_CPU0_SB_DQ<10>")
	)
	(arc
		(start 326.648064 -279.49017)
		(mid 326.405747 -279.32045)
		(end 326.12076 -279.240996)
		(width 0.0762)
		(layer "F.Cu")
		(net "M_A_CPU0_SB_DQ<10>")
	)
	(segment
		(start 310.63438 -278.969724)
		(end 310.503062 -279.101042)
		(width 0.10668)
		(layer "F.Cu")
		(net "M_A_CPU0_SB_DQ<0>")
	)
	(segment
		(start 315.582554 -274.02155)
		(end 315.582554 -274.172426)
		(width 0.10668)
		(layer "F.Cu")
		(net "M_A_CPU0_SB_DQ<0>")
	)
	(segment
		(start 310.514238 -279.676606)
		(end 310.363362 -279.676606)
		(width 0.10668)
		(layer "F.Cu")
		(net "M_A_CPU0_SB_DQ<0>")
	)
	(segment
		(start 309.234586 -280.805382)
		(end 309.133748 -280.704544)
		(width 0.10668)
		(layer "F.Cu")
		(net "M_A_CPU0_SB_DQ<0>")
	)
	(segment
		(start 309.133748 -280.704544)
		(end 308.618128 -280.704544)
		(width 0.10668)
		(layer "F.Cu")
		(net "M_A_CPU0_SB_DQ<0>")
	)
	(segment
		(start 312.47842 -277.27656)
		(end 312.327544 -277.27656)
		(width 0.10668)
		(layer "F.Cu")
		(net "M_A_CPU0_SB_DQ<0>")
	)
	(segment
		(start 314.464954 -275.72589)
		(end 314.314078 -275.72589)
		(width 0.10668)
		(layer "F.Cu")
		(net "M_A_CPU0_SB_DQ<0>")
	)
	(segment
		(start 311.914032 -277.840948)
		(end 311.763156 -277.840948)
		(width 0.10668)
		(layer "F.Cu")
		(net "M_A_CPU0_SB_DQ<0>")
	)
	(segment
		(start 311.209944 -278.830024)
		(end 311.209944 -278.9809)
		(width 0.10668)
		(layer "F.Cu")
		(net "M_A_CPU0_SB_DQ<0>")
	)
	(segment
		(start 312.196226 -277.407878)
		(end 312.196226 -277.558754)
		(width 0.10668)
		(layer "F.Cu")
		(net "M_A_CPU0_SB_DQ<0>")
	)
	(segment
		(start 313.88939 -275.86559)
		(end 314.031884 -276.008084)
		(width 0.10668)
		(layer "F.Cu")
		(net "M_A_CPU0_SB_DQ<0>")
	)
	(segment
		(start 313.467496 -276.572472)
		(end 313.467496 -276.723348)
		(width 0.10668)
		(layer "F.Cu")
		(net "M_A_CPU0_SB_DQ<0>")
	)
	(segment
		(start 314.878466 -275.161502)
		(end 314.735972 -275.019008)
		(width 0.10668)
		(layer "F.Cu")
		(net "M_A_CPU0_SB_DQ<0>")
	)
	(segment
		(start 313.900566 -276.290278)
		(end 313.74969 -276.290278)
		(width 0.10668)
		(layer "F.Cu")
		(net "M_A_CPU0_SB_DQ<0>")
	)
	(segment
		(start 325.999348 -274.147534)
		(end 325.990966 -274.142708)
		(width 0.0762)
		(layer "F.Cu")
		(net "M_A_CPU0_SB_DQ<0>")
	)
	(segment
		(start 314.596272 -275.594572)
		(end 314.464954 -275.72589)
		(width 0.10668)
		(layer "F.Cu")
		(net "M_A_CPU0_SB_DQ<0>")
	)
	(segment
		(start 311.774332 -278.265636)
		(end 311.774332 -278.416512)
		(width 0.10668)
		(layer "F.Cu")
		(net "M_A_CPU0_SB_DQ<0>")
	)
	(segment
		(start 308.618128 -280.704544)
		(end 308.511448 -280.811224)
		(width 0.10668)
		(layer "F.Cu")
		(net "M_A_CPU0_SB_DQ<0>")
	)
	(segment
		(start 312.33872 -277.852124)
		(end 312.207402 -277.983442)
		(width 0.10668)
		(layer "F.Cu")
		(net "M_A_CPU0_SB_DQ<0>")
	)
	(segment
		(start 309.51678 -280.674064)
		(end 309.385462 -280.805382)
		(width 0.10668)
		(layer "F.Cu")
		(net "M_A_CPU0_SB_DQ<0>")
	)
	(segment
		(start 313.042808 -276.712172)
		(end 312.891932 -276.712172)
		(width 0.10668)
		(layer "F.Cu")
		(net "M_A_CPU0_SB_DQ<0>")
	)
	(segment
		(start 309.938674 -279.816306)
		(end 310.081168 -279.9588)
		(width 0.10668)
		(layer "F.Cu")
		(net "M_A_CPU0_SB_DQ<0>")
	)
	(segment
		(start 315.149484 -274.45462)
		(end 315.018166 -274.585938)
		(width 0.10668)
		(layer "F.Cu")
		(net "M_A_CPU0_SB_DQ<0>")
	)
	(segment
		(start 310.503062 -279.251918)
		(end 310.645556 -279.394412)
		(width 0.10668)
		(layer "F.Cu")
		(net "M_A_CPU0_SB_DQ<0>")
	)
	(segment
		(start 311.643014 -278.54783)
		(end 311.492138 -278.54783)
		(width 0.10668)
		(layer "F.Cu")
		(net "M_A_CPU0_SB_DQ<0>")
	)
	(segment
		(start 312.196226 -277.558754)
		(end 312.33872 -277.701248)
		(width 0.10668)
		(layer "F.Cu")
		(net "M_A_CPU0_SB_DQ<0>")
	)
	(segment
		(start 315.59373 -274.597114)
		(end 315.442854 -274.597114)
		(width 0.10668)
		(layer "F.Cu")
		(net "M_A_CPU0_SB_DQ<0>")
	)
	(segment
		(start 312.207402 -277.983442)
		(end 312.056526 -277.983442)
		(width 0.10668)
		(layer "F.Cu")
		(net "M_A_CPU0_SB_DQ<0>")
	)
	(segment
		(start 312.760614 -276.84349)
		(end 312.760614 -276.994366)
		(width 0.10668)
		(layer "F.Cu")
		(net "M_A_CPU0_SB_DQ<0>")
	)
	(segment
		(start 311.06745 -278.536654)
		(end 311.06745 -278.68753)
		(width 0.10668)
		(layer "F.Cu")
		(net "M_A_CPU0_SB_DQ<0>")
	)
	(segment
		(start 314.031884 -276.15896)
		(end 313.900566 -276.290278)
		(width 0.10668)
		(layer "F.Cu")
		(net "M_A_CPU0_SB_DQ<0>")
	)
	(segment
		(start 315.16066 -274.879308)
		(end 315.16066 -275.030184)
		(width 0.10668)
		(layer "F.Cu")
		(net "M_A_CPU0_SB_DQ<0>")
	)
	(segment
		(start 311.492138 -278.54783)
		(end 311.349644 -278.405336)
		(width 0.10668)
		(layer "F.Cu")
		(net "M_A_CPU0_SB_DQ<0>")
	)
	(segment
		(start 314.031884 -276.008084)
		(end 314.031884 -276.15896)
		(width 0.10668)
		(layer "F.Cu")
		(net "M_A_CPU0_SB_DQ<0>")
	)
	(segment
		(start 315.775594 -273.82851)
		(end 315.582554 -274.02155)
		(width 0.10668)
		(layer "F.Cu")
		(net "M_A_CPU0_SB_DQ<0>")
	)
	(segment
		(start 309.374286 -280.380694)
		(end 309.51678 -280.523188)
		(width 0.10668)
		(layer "F.Cu")
		(net "M_A_CPU0_SB_DQ<0>")
	)
	(segment
		(start 311.349644 -278.405336)
		(end 311.198768 -278.405336)
		(width 0.10668)
		(layer "F.Cu")
		(net "M_A_CPU0_SB_DQ<0>")
	)
	(segment
		(start 312.620914 -277.419054)
		(end 312.47842 -277.27656)
		(width 0.10668)
		(layer "F.Cu")
		(net "M_A_CPU0_SB_DQ<0>")
	)
	(segment
		(start 312.77179 -277.419054)
		(end 312.620914 -277.419054)
		(width 0.10668)
		(layer "F.Cu")
		(net "M_A_CPU0_SB_DQ<0>")
	)
	(segment
		(start 324.324472 -274.066508)
		(end 324.086474 -273.82851)
		(width 0.0762)
		(layer "F.Cu")
		(net "M_A_CPU0_SB_DQ<0>")
	)
	(segment
		(start 314.596272 -275.443696)
		(end 314.596272 -275.594572)
		(width 0.10668)
		(layer "F.Cu")
		(net "M_A_CPU0_SB_DQ<0>")
	)
	(segment
		(start 311.631838 -277.972266)
		(end 311.631838 -278.123142)
		(width 0.10668)
		(layer "F.Cu")
		(net "M_A_CPU0_SB_DQ<0>")
	)
	(segment
		(start 314.453778 -275.301202)
		(end 314.596272 -275.443696)
		(width 0.10668)
		(layer "F.Cu")
		(net "M_A_CPU0_SB_DQ<0>")
	)
	(segment
		(start 310.645556 -279.394412)
		(end 310.645556 -279.545288)
		(width 0.10668)
		(layer "F.Cu")
		(net "M_A_CPU0_SB_DQ<0>")
	)
	(segment
		(start 313.185302 -276.854666)
		(end 313.042808 -276.712172)
		(width 0.10668)
		(layer "F.Cu")
		(net "M_A_CPU0_SB_DQ<0>")
	)
	(segment
		(start 315.582554 -274.172426)
		(end 315.725048 -274.31492)
		(width 0.10668)
		(layer "F.Cu")
		(net "M_A_CPU0_SB_DQ<0>")
	)
	(segment
		(start 313.325002 -276.429978)
		(end 313.467496 -276.572472)
		(width 0.10668)
		(layer "F.Cu")
		(net "M_A_CPU0_SB_DQ<0>")
	)
	(segment
		(start 312.760614 -276.994366)
		(end 312.903108 -277.13686)
		(width 0.10668)
		(layer "F.Cu")
		(net "M_A_CPU0_SB_DQ<0>")
	)
	(segment
		(start 313.88939 -275.714714)
		(end 313.88939 -275.86559)
		(width 0.10668)
		(layer "F.Cu")
		(net "M_A_CPU0_SB_DQ<0>")
	)
	(segment
		(start 312.327544 -277.27656)
		(end 312.196226 -277.407878)
		(width 0.10668)
		(layer "F.Cu")
		(net "M_A_CPU0_SB_DQ<0>")
	)
	(segment
		(start 310.081168 -279.9588)
		(end 310.081168 -280.109676)
		(width 0.10668)
		(layer "F.Cu")
		(net "M_A_CPU0_SB_DQ<0>")
	)
	(segment
		(start 314.735972 -275.019008)
		(end 314.585096 -275.019008)
		(width 0.10668)
		(layer "F.Cu")
		(net "M_A_CPU0_SB_DQ<0>")
	)
	(segment
		(start 311.774332 -278.416512)
		(end 311.643014 -278.54783)
		(width 0.10668)
		(layer "F.Cu")
		(net "M_A_CPU0_SB_DQ<0>")
	)
	(segment
		(start 311.631838 -278.123142)
		(end 311.774332 -278.265636)
		(width 0.10668)
		(layer "F.Cu")
		(net "M_A_CPU0_SB_DQ<0>")
	)
	(segment
		(start 326.17791 -273.820128)
		(end 326.276208 -273.989292)
		(width 0.0762)
		(layer "F.Cu")
		(net "M_A_CPU0_SB_DQ<0>")
	)
	(segment
		(start 311.198768 -278.405336)
		(end 311.06745 -278.536654)
		(width 0.10668)
		(layer "F.Cu")
		(net "M_A_CPU0_SB_DQ<0>")
	)
	(segment
		(start 315.725048 -274.31492)
		(end 315.725048 -274.465796)
		(width 0.10668)
		(layer "F.Cu")
		(net "M_A_CPU0_SB_DQ<0>")
	)
	(segment
		(start 314.453778 -275.150326)
		(end 314.453778 -275.301202)
		(width 0.10668)
		(layer "F.Cu")
		(net "M_A_CPU0_SB_DQ<0>")
	)
	(segment
		(start 308.394608 -281.485086)
		(end 307.368194 -281.485086)
		(width 0.10668)
		(layer "F.Cu")
		(net "M_A_CPU0_SB_DQ<0>")
	)
	(segment
		(start 315.018166 -274.585938)
		(end 315.018166 -274.736814)
		(width 0.10668)
		(layer "F.Cu")
		(net "M_A_CPU0_SB_DQ<0>")
	)
	(segment
		(start 315.442854 -274.597114)
		(end 315.30036 -274.45462)
		(width 0.10668)
		(layer "F.Cu")
		(net "M_A_CPU0_SB_DQ<0>")
	)
	(segment
		(start 311.209944 -278.9809)
		(end 311.078626 -279.112218)
		(width 0.10668)
		(layer "F.Cu")
		(net "M_A_CPU0_SB_DQ<0>")
	)
	(segment
		(start 309.65648 -280.0985)
		(end 309.505604 -280.0985)
		(width 0.10668)
		(layer "F.Cu")
		(net "M_A_CPU0_SB_DQ<0>")
	)
	(segment
		(start 312.903108 -277.13686)
		(end 312.903108 -277.287736)
		(width 0.10668)
		(layer "F.Cu")
		(net "M_A_CPU0_SB_DQ<0>")
	)
	(segment
		(start 311.078626 -279.112218)
		(end 310.92775 -279.112218)
		(width 0.10668)
		(layer "F.Cu")
		(net "M_A_CPU0_SB_DQ<0>")
	)
	(segment
		(start 313.325002 -276.279102)
		(end 313.325002 -276.429978)
		(width 0.10668)
		(layer "F.Cu")
		(net "M_A_CPU0_SB_DQ<0>")
	)
	(segment
		(start 312.891932 -276.712172)
		(end 312.760614 -276.84349)
		(width 0.10668)
		(layer "F.Cu")
		(net "M_A_CPU0_SB_DQ<0>")
	)
	(segment
		(start 310.081168 -280.109676)
		(end 309.94985 -280.240994)
		(width 0.10668)
		(layer "F.Cu")
		(net "M_A_CPU0_SB_DQ<0>")
	)
	(segment
		(start 313.607196 -276.147784)
		(end 313.45632 -276.147784)
		(width 0.10668)
		(layer "F.Cu")
		(net "M_A_CPU0_SB_DQ<0>")
	)
	(segment
		(start 308.511448 -280.811224)
		(end 308.511448 -281.368246)
		(width 0.10668)
		(layer "F.Cu")
		(net "M_A_CPU0_SB_DQ<0>")
	)
	(segment
		(start 310.363362 -279.676606)
		(end 310.220868 -279.534112)
		(width 0.10668)
		(layer "F.Cu")
		(net "M_A_CPU0_SB_DQ<0>")
	)
	(segment
		(start 325.70801 -274.066508)
		(end 324.324472 -274.066508)
		(width 0.0762)
		(layer "F.Cu")
		(net "M_A_CPU0_SB_DQ<0>")
	)
	(segment
		(start 315.16066 -275.030184)
		(end 315.029342 -275.161502)
		(width 0.10668)
		(layer "F.Cu")
		(net "M_A_CPU0_SB_DQ<0>")
	)
	(segment
		(start 311.06745 -278.68753)
		(end 311.209944 -278.830024)
		(width 0.10668)
		(layer "F.Cu")
		(net "M_A_CPU0_SB_DQ<0>")
	)
	(segment
		(start 312.056526 -277.983442)
		(end 311.914032 -277.840948)
		(width 0.10668)
		(layer "F.Cu")
		(net "M_A_CPU0_SB_DQ<0>")
	)
	(segment
		(start 311.763156 -277.840948)
		(end 311.631838 -277.972266)
		(width 0.10668)
		(layer "F.Cu")
		(net "M_A_CPU0_SB_DQ<0>")
	)
	(segment
		(start 309.94985 -280.240994)
		(end 309.798974 -280.240994)
		(width 0.10668)
		(layer "F.Cu")
		(net "M_A_CPU0_SB_DQ<0>")
	)
	(segment
		(start 313.467496 -276.723348)
		(end 313.336178 -276.854666)
		(width 0.10668)
		(layer "F.Cu")
		(net "M_A_CPU0_SB_DQ<0>")
	)
	(segment
		(start 314.171584 -275.583396)
		(end 314.020708 -275.583396)
		(width 0.10668)
		(layer "F.Cu")
		(net "M_A_CPU0_SB_DQ<0>")
	)
	(segment
		(start 315.30036 -274.45462)
		(end 315.149484 -274.45462)
		(width 0.10668)
		(layer "F.Cu")
		(net "M_A_CPU0_SB_DQ<0>")
	)
	(segment
		(start 309.385462 -280.805382)
		(end 309.234586 -280.805382)
		(width 0.10668)
		(layer "F.Cu")
		(net "M_A_CPU0_SB_DQ<0>")
	)
	(segment
		(start 312.33872 -277.701248)
		(end 312.33872 -277.852124)
		(width 0.10668)
		(layer "F.Cu")
		(net "M_A_CPU0_SB_DQ<0>")
	)
	(segment
		(start 313.45632 -276.147784)
		(end 313.325002 -276.279102)
		(width 0.10668)
		(layer "F.Cu")
		(net "M_A_CPU0_SB_DQ<0>")
	)
	(segment
		(start 310.069992 -279.534112)
		(end 309.938674 -279.66543)
		(width 0.10668)
		(layer "F.Cu")
		(net "M_A_CPU0_SB_DQ<0>")
	)
	(segment
		(start 310.645556 -279.545288)
		(end 310.514238 -279.676606)
		(width 0.10668)
		(layer "F.Cu")
		(net "M_A_CPU0_SB_DQ<0>")
	)
	(segment
		(start 309.798974 -280.240994)
		(end 309.65648 -280.0985)
		(width 0.10668)
		(layer "F.Cu")
		(net "M_A_CPU0_SB_DQ<0>")
	)
	(segment
		(start 315.029342 -275.161502)
		(end 314.878466 -275.161502)
		(width 0.10668)
		(layer "F.Cu")
		(net "M_A_CPU0_SB_DQ<0>")
	)
	(segment
		(start 310.92775 -279.112218)
		(end 310.785256 -278.969724)
		(width 0.10668)
		(layer "F.Cu")
		(net "M_A_CPU0_SB_DQ<0>")
	)
	(segment
		(start 310.220868 -279.534112)
		(end 310.069992 -279.534112)
		(width 0.10668)
		(layer "F.Cu")
		(net "M_A_CPU0_SB_DQ<0>")
	)
	(segment
		(start 309.51678 -280.523188)
		(end 309.51678 -280.674064)
		(width 0.10668)
		(layer "F.Cu")
		(net "M_A_CPU0_SB_DQ<0>")
	)
	(segment
		(start 310.503062 -279.101042)
		(end 310.503062 -279.251918)
		(width 0.10668)
		(layer "F.Cu")
		(net "M_A_CPU0_SB_DQ<0>")
	)
	(segment
		(start 315.725048 -274.465796)
		(end 315.59373 -274.597114)
		(width 0.10668)
		(layer "F.Cu")
		(net "M_A_CPU0_SB_DQ<0>")
	)
	(segment
		(start 312.903108 -277.287736)
		(end 312.77179 -277.419054)
		(width 0.10668)
		(layer "F.Cu")
		(net "M_A_CPU0_SB_DQ<0>")
	)
	(segment
		(start 314.585096 -275.019008)
		(end 314.453778 -275.150326)
		(width 0.10668)
		(layer "F.Cu")
		(net "M_A_CPU0_SB_DQ<0>")
	)
	(segment
		(start 314.020708 -275.583396)
		(end 313.88939 -275.714714)
		(width 0.10668)
		(layer "F.Cu")
		(net "M_A_CPU0_SB_DQ<0>")
	)
	(segment
		(start 309.374286 -280.229818)
		(end 309.374286 -280.380694)
		(width 0.10668)
		(layer "F.Cu")
		(net "M_A_CPU0_SB_DQ<0>")
	)
	(segment
		(start 310.785256 -278.969724)
		(end 310.63438 -278.969724)
		(width 0.10668)
		(layer "F.Cu")
		(net "M_A_CPU0_SB_DQ<0>")
	)
	(segment
		(start 313.336178 -276.854666)
		(end 313.185302 -276.854666)
		(width 0.10668)
		(layer "F.Cu")
		(net "M_A_CPU0_SB_DQ<0>")
	)
	(segment
		(start 309.505604 -280.0985)
		(end 309.374286 -280.229818)
		(width 0.10668)
		(layer "F.Cu")
		(net "M_A_CPU0_SB_DQ<0>")
	)
	(segment
		(start 314.314078 -275.72589)
		(end 314.171584 -275.583396)
		(width 0.10668)
		(layer "F.Cu")
		(net "M_A_CPU0_SB_DQ<0>")
	)
	(segment
		(start 313.74969 -276.290278)
		(end 313.607196 -276.147784)
		(width 0.10668)
		(layer "F.Cu")
		(net "M_A_CPU0_SB_DQ<0>")
	)
	(segment
		(start 315.018166 -274.736814)
		(end 315.16066 -274.879308)
		(width 0.10668)
		(layer "F.Cu")
		(net "M_A_CPU0_SB_DQ<0>")
	)
	(segment
		(start 324.086474 -273.82851)
		(end 315.775594 -273.82851)
		(width 0.10668)
		(layer "F.Cu")
		(net "M_A_CPU0_SB_DQ<0>")
	)
	(segment
		(start 308.511448 -281.368246)
		(end 308.394608 -281.485086)
		(width 0.10668)
		(layer "F.Cu")
		(net "M_A_CPU0_SB_DQ<0>")
	)
	(segment
		(start 309.938674 -279.66543)
		(end 309.938674 -279.816306)
		(width 0.10668)
		(layer "F.Cu")
		(net "M_A_CPU0_SB_DQ<0>")
	)
	(arc
		(start 325.990966 -274.142708)
		(mid 325.85453 -274.085883)
		(end 325.70801 -274.066508)
		(width 0.0762)
		(layer "F.Cu")
		(net "M_A_CPU0_SB_DQ<0>")
	)
	(arc
		(start 326.13854 -274.190968)
		(mid 326.066802 -274.176116)
		(end 325.999348 -274.147534)
		(width 0.0762)
		(layer "F.Cu")
		(net "M_A_CPU0_SB_DQ<0>")
	)
	(arc
		(start 326.276208 -273.989292)
		(mid 326.267615 -274.131171)
		(end 326.13854 -274.190968)
		(width 0.0762)
		(layer "F.Cu")
		(net "M_A_CPU0_SB_DQ<0>")
	)
	(segment
		(start 324.640194 -266.36091)
		(end 324.042786 -266.36091)
		(width 0.10668)
		(layer "F.Cu")
		(net "M_A_CPU0_SB_CS_N<1>")
	)
	(segment
		(start 305.645312 -268.735048)
		(end 303.268126 -268.735048)
		(width 0.101346)
		(layer "F.Cu")
		(net "M_A_CPU0_SB_CS_N<1>")
	)
	(segment
		(start 308.610254 -269.160244)
		(end 306.070508 -269.160244)
		(width 0.101346)
		(layer "F.Cu")
		(net "M_A_CPU0_SB_CS_N<1>")
	)
	(segment
		(start 306.070508 -269.160244)
		(end 305.645312 -268.735048)
		(width 0.101346)
		(layer "F.Cu")
		(net "M_A_CPU0_SB_CS_N<1>")
	)
	(segment
		(start 308.610508 -269.15999)
		(end 308.610254 -269.160244)
		(width 0.101346)
		(layer "F.Cu")
		(net "M_A_CPU0_SB_CS_N<1>")
	)
	(segment
		(start 311.463436 -267.636752)
		(end 309.153814 -267.636752)
		(width 0.10668)
		(layer "F.Cu")
		(net "M_A_CPU0_SB_CS_N<1>")
	)
	(segment
		(start 324.042786 -266.36091)
		(end 323.521324 -265.839448)
		(width 0.10668)
		(layer "F.Cu")
		(net "M_A_CPU0_SB_CS_N<1>")
	)
	(segment
		(start 313.26074 -265.839448)
		(end 311.463436 -267.636752)
		(width 0.10668)
		(layer "F.Cu")
		(net "M_A_CPU0_SB_CS_N<1>")
	)
	(segment
		(start 324.844156 -266.156948)
		(end 324.640194 -266.36091)
		(width 0.0762)
		(layer "F.Cu")
		(net "M_A_CPU0_SB_CS_N<1>")
	)
	(segment
		(start 323.521324 -265.839448)
		(end 313.26074 -265.839448)
		(width 0.10668)
		(layer "F.Cu")
		(net "M_A_CPU0_SB_CS_N<1>")
	)
	(segment
		(start 325.70801 -266.156948)
		(end 324.844156 -266.156948)
		(width 0.0762)
		(layer "F.Cu")
		(net "M_A_CPU0_SB_CS_N<1>")
	)
	(segment
		(start 308.797198 -268.9733)
		(end 308.610508 -269.15999)
		(width 0.10668)
		(layer "F.Cu")
		(net "M_A_CPU0_SB_CS_N<1>")
	)
	(segment
		(start 308.797198 -267.993368)
		(end 308.797198 -268.9733)
		(width 0.10668)
		(layer "F.Cu")
		(net "M_A_CPU0_SB_CS_N<1>")
	)
	(segment
		(start 309.153814 -267.636752)
		(end 308.797198 -267.993368)
		(width 0.10668)
		(layer "F.Cu")
		(net "M_A_CPU0_SB_CS_N<1>")
	)
	(arc
		(start 325.894954 -266.207494)
		(mid 325.804821 -266.169874)
		(end 325.70801 -266.156948)
		(width 0.0762)
		(layer "F.Cu")
		(net "M_A_CPU0_SB_CS_N<1>")
	)
	(arc
		(start 326.199246 -266.28344)
		(mid 326.04171 -266.267064)
		(end 325.894954 -266.207494)
		(width 0.0762)
		(layer "F.Cu")
		(net "M_A_CPU0_SB_CS_N<1>")
	)
	(arc
		(start 326.648064 -266.530074)
		(mid 326.457777 -266.344648)
		(end 326.199246 -266.28344)
		(width 0.0762)
		(layer "F.Cu")
		(net "M_A_CPU0_SB_CS_N<1>")
	)
	(segment
		(start 308.798976 -267.35913)
		(end 308.798976 -267.510006)
		(width 0.10668)
		(layer "F.Cu")
		(net "M_A_CPU0_SB_CS_N<0>")
	)
	(segment
		(start 310.58231 -266.737338)
		(end 310.396636 -266.737338)
		(width 0.10668)
		(layer "F.Cu")
		(net "M_A_CPU0_SB_CS_N<0>")
	)
	(segment
		(start 310.79567 -267.296392)
		(end 310.68899 -267.189712)
		(width 0.10668)
		(layer "F.Cu")
		(net "M_A_CPU0_SB_CS_N<0>")
	)
	(segment
		(start 309.890922 -266.844018)
		(end 309.784242 -266.737338)
		(width 0.10668)
		(layer "F.Cu")
		(net "M_A_CPU0_SB_CS_N<0>")
	)
	(segment
		(start 312.744612 -265.87323)
		(end 312.744612 -265.872976)
		(width 0.10668)
		(layer "F.Cu")
		(net "M_A_CPU0_SB_CS_N<0>")
	)
	(segment
		(start 308.770274 -266.916916)
		(end 308.638956 -267.048234)
		(width 0.10668)
		(layer "F.Cu")
		(net "M_A_CPU0_SB_CS_N<0>")
	)
	(segment
		(start 311.194704 -266.737338)
		(end 311.088024 -266.844018)
		(width 0.10668)
		(layer "F.Cu")
		(net "M_A_CPU0_SB_CS_N<0>")
	)
	(segment
		(start 313.118754 -265.499088)
		(end 312.744612 -265.87323)
		(width 0.10668)
		(layer "F.Cu")
		(net "M_A_CPU0_SB_CS_N<0>")
	)
	(segment
		(start 311.088024 -267.189712)
		(end 310.981344 -267.296392)
		(width 0.10668)
		(layer "F.Cu")
		(net "M_A_CPU0_SB_CS_N<0>")
	)
	(segment
		(start 324.521576 -265.499088)
		(end 313.118754 -265.499088)
		(width 0.10668)
		(layer "F.Cu")
		(net "M_A_CPU0_SB_CS_N<0>")
	)
	(segment
		(start 309.08117 -267.076936)
		(end 308.92115 -266.916916)
		(width 0.10668)
		(layer "F.Cu")
		(net "M_A_CPU0_SB_CS_N<0>")
	)
	(segment
		(start 310.289956 -267.189712)
		(end 310.183276 -267.296392)
		(width 0.10668)
		(layer "F.Cu")
		(net "M_A_CPU0_SB_CS_N<0>")
	)
	(segment
		(start 309.232046 -267.076936)
		(end 309.08117 -267.076936)
		(width 0.10668)
		(layer "F.Cu")
		(net "M_A_CPU0_SB_CS_N<0>")
	)
	(segment
		(start 308.798976 -267.510006)
		(end 308.423818 -267.885164)
		(width 0.10668)
		(layer "F.Cu")
		(net "M_A_CPU0_SB_CS_N<0>")
	)
	(segment
		(start 310.289956 -266.844018)
		(end 310.289956 -267.189712)
		(width 0.10668)
		(layer "F.Cu")
		(net "M_A_CPU0_SB_CS_N<0>")
	)
	(segment
		(start 308.638956 -267.048234)
		(end 308.638956 -267.19911)
		(width 0.10668)
		(layer "F.Cu")
		(net "M_A_CPU0_SB_CS_N<0>")
	)
	(segment
		(start 310.68899 -266.844018)
		(end 310.58231 -266.737338)
		(width 0.10668)
		(layer "F.Cu")
		(net "M_A_CPU0_SB_CS_N<0>")
	)
	(segment
		(start 311.088024 -266.844018)
		(end 311.088024 -267.189712)
		(width 0.10668)
		(layer "F.Cu")
		(net "M_A_CPU0_SB_CS_N<0>")
	)
	(segment
		(start 325.999348 -265.392662)
		(end 325.990966 -265.397488)
		(width 0.0762)
		(layer "F.Cu")
		(net "M_A_CPU0_SB_CS_N<0>")
	)
	(segment
		(start 312.744612 -265.872976)
		(end 311.88025 -266.737338)
		(width 0.10668)
		(layer "F.Cu")
		(net "M_A_CPU0_SB_CS_N<0>")
	)
	(segment
		(start 310.981344 -267.296392)
		(end 310.79567 -267.296392)
		(width 0.10668)
		(layer "F.Cu")
		(net "M_A_CPU0_SB_CS_N<0>")
	)
	(segment
		(start 311.88025 -266.737338)
		(end 311.194704 -266.737338)
		(width 0.10668)
		(layer "F.Cu")
		(net "M_A_CPU0_SB_CS_N<0>")
	)
	(segment
		(start 309.890922 -267.189712)
		(end 309.890922 -266.844018)
		(width 0.10668)
		(layer "F.Cu")
		(net "M_A_CPU0_SB_CS_N<0>")
	)
	(segment
		(start 309.997602 -267.296392)
		(end 309.890922 -267.189712)
		(width 0.10668)
		(layer "F.Cu")
		(net "M_A_CPU0_SB_CS_N<0>")
	)
	(segment
		(start 325.072248 -265.499088)
		(end 324.521576 -265.499088)
		(width 0.0762)
		(layer "F.Cu")
		(net "M_A_CPU0_SB_CS_N<0>")
	)
	(segment
		(start 309.571644 -266.737338)
		(end 309.232046 -267.076936)
		(width 0.10668)
		(layer "F.Cu")
		(net "M_A_CPU0_SB_CS_N<0>")
	)
	(segment
		(start 308.638956 -267.19911)
		(end 308.798976 -267.35913)
		(width 0.10668)
		(layer "F.Cu")
		(net "M_A_CPU0_SB_CS_N<0>")
	)
	(segment
		(start 310.68899 -267.189712)
		(end 310.68899 -266.844018)
		(width 0.10668)
		(layer "F.Cu")
		(net "M_A_CPU0_SB_CS_N<0>")
	)
	(segment
		(start 310.183276 -267.296392)
		(end 309.997602 -267.296392)
		(width 0.10668)
		(layer "F.Cu")
		(net "M_A_CPU0_SB_CS_N<0>")
	)
	(segment
		(start 310.396636 -266.737338)
		(end 310.289956 -266.844018)
		(width 0.10668)
		(layer "F.Cu")
		(net "M_A_CPU0_SB_CS_N<0>")
	)
	(segment
		(start 309.784242 -266.737338)
		(end 309.571644 -266.737338)
		(width 0.10668)
		(layer "F.Cu")
		(net "M_A_CPU0_SB_CS_N<0>")
	)
	(segment
		(start 308.92115 -266.916916)
		(end 308.770274 -266.916916)
		(width 0.10668)
		(layer "F.Cu")
		(net "M_A_CPU0_SB_CS_N<0>")
	)
	(segment
		(start 308.423818 -267.885164)
		(end 307.368194 -267.885164)
		(width 0.10668)
		(layer "F.Cu")
		(net "M_A_CPU0_SB_CS_N<0>")
	)
	(arc
		(start 326.93102 -265.397488)
		(mid 326.648064 -265.473665)
		(end 326.365108 -265.397488)
		(width 0.0762)
		(layer "F.Cu")
		(net "M_A_CPU0_SB_CS_N<0>")
	)
	(arc
		(start 326.365108 -265.397488)
		(mid 326.182857 -265.347138)
		(end 325.999348 -265.392662)
		(width 0.0762)
		(layer "F.Cu")
		(net "M_A_CPU0_SB_CS_N<0>")
	)
	(arc
		(start 327.601834 -265.473688)
		(mid 327.448085 -265.456179)
		(end 327.304908 -265.397488)
		(width 0.0762)
		(layer "F.Cu")
		(net "M_A_CPU0_SB_CS_N<0>")
	)
	(arc
		(start 325.990966 -265.397488)
		(mid 325.877242 -265.447789)
		(end 325.755254 -265.47191)
		(width 0.0762)
		(layer "F.Cu")
		(net "M_A_CPU0_SB_CS_N<0>")
	)
	(arc
		(start 327.304908 -265.397488)
		(mid 327.117964 -265.347233)
		(end 326.93102 -265.397488)
		(width 0.0762)
		(layer "F.Cu")
		(net "M_A_CPU0_SB_CS_N<0>")
	)
	(arc
		(start 325.755254 -265.47191)
		(mid 325.414021 -265.492293)
		(end 325.072248 -265.499088)
		(width 0.0762)
		(layer "F.Cu")
		(net "M_A_CPU0_SB_CS_N<0>")
	)
	(arc
		(start 328.058018 -265.720068)
		(mid 327.862669 -265.536249)
		(end 327.601834 -265.473688)
		(width 0.0762)
		(layer "F.Cu")
		(net "M_A_CPU0_SB_CS_N<0>")
	)
	(segment
		(start 309.10149 -274.26031)
		(end 308.66588 -274.26031)
		(width 0.10668)
		(layer "F.Cu")
		(net "M_A_CPU0_SB_CB<7>")
	)
	(segment
		(start 314.335668 -269.026132)
		(end 309.10149 -274.26031)
		(width 0.10668)
		(layer "F.Cu")
		(net "M_A_CPU0_SB_CB<7>")
	)
	(segment
		(start 321.85737 -269.026132)
		(end 314.335668 -269.026132)
		(width 0.10668)
		(layer "F.Cu")
		(net "M_A_CPU0_SB_CB<7>")
	)
	(segment
		(start 304.772568 -274.260056)
		(end 304.347626 -274.684998)
		(width 0.101346)
		(layer "F.Cu")
		(net "M_A_CPU0_SB_CB<7>")
	)
	(segment
		(start 325.999348 -270.252698)
		(end 325.990966 -270.257524)
		(width 0.0762)
		(layer "F.Cu")
		(net "M_A_CPU0_SB_CB<7>")
	)
	(segment
		(start 324.495668 -270.333724)
		(end 324.447154 -270.28521)
		(width 0.0762)
		(layer "F.Cu")
		(net "M_A_CPU0_SB_CB<7>")
	)
	(segment
		(start 323.116448 -270.28521)
		(end 321.85737 -269.026132)
		(width 0.10668)
		(layer "F.Cu")
		(net "M_A_CPU0_SB_CB<7>")
	)
	(segment
		(start 323.82714 -270.28521)
		(end 323.116448 -270.28521)
		(width 0.10668)
		(layer "F.Cu")
		(net "M_A_CPU0_SB_CB<7>")
	)
	(segment
		(start 325.708264 -270.333724)
		(end 324.495668 -270.333724)
		(width 0.0762)
		(layer "F.Cu")
		(net "M_A_CPU0_SB_CB<7>")
	)
	(segment
		(start 304.347626 -274.684998)
		(end 303.268126 -274.684998)
		(width 0.101346)
		(layer "F.Cu")
		(net "M_A_CPU0_SB_CB<7>")
	)
	(segment
		(start 324.447154 -270.28521)
		(end 323.82714 -270.28521)
		(width 0.0762)
		(layer "F.Cu")
		(net "M_A_CPU0_SB_CB<7>")
	)
	(segment
		(start 308.610508 -274.26031)
		(end 308.610254 -274.260056)
		(width 0.101346)
		(layer "F.Cu")
		(net "M_A_CPU0_SB_CB<7>")
	)
	(segment
		(start 308.66588 -274.26031)
		(end 308.610508 -274.26031)
		(width 0.101346)
		(layer "F.Cu")
		(net "M_A_CPU0_SB_CB<7>")
	)
	(segment
		(start 308.610254 -274.260056)
		(end 304.772568 -274.260056)
		(width 0.101346)
		(layer "F.Cu")
		(net "M_A_CPU0_SB_CB<7>")
	)
	(arc
		(start 325.755254 -270.331946)
		(mid 325.731777 -270.333322)
		(end 325.708264 -270.333724)
		(width 0.0762)
		(layer "F.Cu")
		(net "M_A_CPU0_SB_CB<7>")
	)
	(arc
		(start 328.058018 -270.580104)
		(mid 327.820406 -270.409116)
		(end 327.53808 -270.331692)
		(width 0.0762)
		(layer "F.Cu")
		(net "M_A_CPU0_SB_CB<7>")
	)
	(arc
		(start 326.365108 -270.257524)
		(mid 326.182857 -270.207174)
		(end 325.999348 -270.252698)
		(width 0.0762)
		(layer "F.Cu")
		(net "M_A_CPU0_SB_CB<7>")
	)
	(arc
		(start 327.53808 -270.331692)
		(mid 327.417431 -270.307391)
		(end 327.304908 -270.257524)
		(width 0.0762)
		(layer "F.Cu")
		(net "M_A_CPU0_SB_CB<7>")
	)
	(arc
		(start 326.93102 -270.257524)
		(mid 326.648064 -270.333701)
		(end 326.365108 -270.257524)
		(width 0.0762)
		(layer "F.Cu")
		(net "M_A_CPU0_SB_CB<7>")
	)
	(arc
		(start 327.304908 -270.257524)
		(mid 327.117964 -270.207269)
		(end 326.93102 -270.257524)
		(width 0.0762)
		(layer "F.Cu")
		(net "M_A_CPU0_SB_CB<7>")
	)
	(arc
		(start 325.990966 -270.257524)
		(mid 325.877242 -270.307825)
		(end 325.755254 -270.331946)
		(width 0.0762)
		(layer "F.Cu")
		(net "M_A_CPU0_SB_CB<7>")
	)
	(segment
		(start 312.043318 -269.64513)
		(end 311.892442 -269.64513)
		(width 0.10668)
		(layer "F.Cu")
		(net "M_A_CPU0_SB_CB<6>")
	)
	(segment
		(start 312.889646 -268.798548)
		(end 313.008772 -268.917674)
		(width 0.10668)
		(layer "F.Cu")
		(net "M_A_CPU0_SB_CB<6>")
	)
	(segment
		(start 313.008772 -268.917674)
		(end 313.008772 -269.06855)
		(width 0.10668)
		(layer "F.Cu")
		(net "M_A_CPU0_SB_CB<6>")
	)
	(segment
		(start 312.8899 -268.647672)
		(end 312.889646 -268.798548)
		(width 0.10668)
		(layer "F.Cu")
		(net "M_A_CPU0_SB_CB<6>")
	)
	(segment
		(start 309.412132 -272.250662)
		(end 309.412132 -272.401538)
		(width 0.10668)
		(layer "F.Cu")
		(net "M_A_CPU0_SB_CB<6>")
	)
	(segment
		(start 308.586124 -272.560034)
		(end 304.74285 -272.560034)
		(width 0.101346)
		(layer "F.Cu")
		(net "M_A_CPU0_SB_CB<6>")
	)
	(segment
		(start 309.412132 -272.401538)
		(end 309.280814 -272.532856)
		(width 0.10668)
		(layer "F.Cu")
		(net "M_A_CPU0_SB_CB<6>")
	)
	(segment
		(start 325.70801 -269.396972)
		(end 324.233286 -269.396972)
		(width 0.0762)
		(layer "F.Cu")
		(net "M_A_CPU0_SB_CB<6>")
	)
	(segment
		(start 309.364888 -271.78127)
		(end 309.229252 -271.916906)
		(width 0.10668)
		(layer "F.Cu")
		(net "M_A_CPU0_SB_CB<6>")
	)
	(segment
		(start 312.444384 -269.482062)
		(end 312.444384 -269.632938)
		(width 0.10668)
		(layer "F.Cu")
		(net "M_A_CPU0_SB_CB<6>")
	)
	(segment
		(start 304.317908 -272.984976)
		(end 303.268126 -272.984976)
		(width 0.101346)
		(layer "F.Cu")
		(net "M_A_CPU0_SB_CB<6>")
	)
	(segment
		(start 304.74285 -272.560034)
		(end 304.317908 -272.984976)
		(width 0.101346)
		(layer "F.Cu")
		(net "M_A_CPU0_SB_CB<6>")
	)
	(segment
		(start 323.398896 -269.60449)
		(end 322.139818 -268.345412)
		(width 0.10668)
		(layer "F.Cu")
		(net "M_A_CPU0_SB_CB<6>")
	)
	(segment
		(start 312.325258 -269.362936)
		(end 312.444384 -269.482062)
		(width 0.10668)
		(layer "F.Cu")
		(net "M_A_CPU0_SB_CB<6>")
	)
	(segment
		(start 313.008772 -269.06855)
		(end 312.8772 -269.200122)
		(width 0.10668)
		(layer "F.Cu")
		(net "M_A_CPU0_SB_CB<6>")
	)
	(segment
		(start 312.162444 -269.764256)
		(end 312.043318 -269.64513)
		(width 0.10668)
		(layer "F.Cu")
		(net "M_A_CPU0_SB_CB<6>")
	)
	(segment
		(start 324.025768 -269.60449)
		(end 323.398896 -269.60449)
		(width 0.10668)
		(layer "F.Cu")
		(net "M_A_CPU0_SB_CB<6>")
	)
	(segment
		(start 312.607706 -269.080742)
		(end 312.45683 -269.080742)
		(width 0.10668)
		(layer "F.Cu")
		(net "M_A_CPU0_SB_CB<6>")
	)
	(segment
		(start 324.233286 -269.396972)
		(end 324.025768 -269.60449)
		(width 0.0762)
		(layer "F.Cu")
		(net "M_A_CPU0_SB_CB<6>")
	)
	(segment
		(start 309.280814 -272.532856)
		(end 309.129938 -272.532856)
		(width 0.10668)
		(layer "F.Cu")
		(net "M_A_CPU0_SB_CB<6>")
	)
	(segment
		(start 312.8772 -269.200122)
		(end 312.726832 -269.199868)
		(width 0.10668)
		(layer "F.Cu")
		(net "M_A_CPU0_SB_CB<6>")
	)
	(segment
		(start 311.892442 -269.64513)
		(end 309.756302 -271.78127)
		(width 0.10668)
		(layer "F.Cu")
		(net "M_A_CPU0_SB_CB<6>")
	)
	(segment
		(start 309.229252 -271.916906)
		(end 309.229252 -272.067782)
		(width 0.10668)
		(layer "F.Cu")
		(net "M_A_CPU0_SB_CB<6>")
	)
	(segment
		(start 308.796182 -272.349976)
		(end 308.586124 -272.560034)
		(width 0.10668)
		(layer "F.Cu")
		(net "M_A_CPU0_SB_CB<6>")
	)
	(segment
		(start 309.129938 -272.532856)
		(end 308.947058 -272.349976)
		(width 0.10668)
		(layer "F.Cu")
		(net "M_A_CPU0_SB_CB<6>")
	)
	(segment
		(start 312.726832 -269.199868)
		(end 312.607706 -269.080742)
		(width 0.10668)
		(layer "F.Cu")
		(net "M_A_CPU0_SB_CB<6>")
	)
	(segment
		(start 308.947058 -272.349976)
		(end 308.796182 -272.349976)
		(width 0.10668)
		(layer "F.Cu")
		(net "M_A_CPU0_SB_CB<6>")
	)
	(segment
		(start 309.756302 -271.78127)
		(end 309.364888 -271.78127)
		(width 0.10668)
		(layer "F.Cu")
		(net "M_A_CPU0_SB_CB<6>")
	)
	(segment
		(start 322.139818 -268.345412)
		(end 313.19216 -268.345412)
		(width 0.10668)
		(layer "F.Cu")
		(net "M_A_CPU0_SB_CB<6>")
	)
	(segment
		(start 312.444384 -269.632938)
		(end 312.312812 -269.76451)
		(width 0.10668)
		(layer "F.Cu")
		(net "M_A_CPU0_SB_CB<6>")
	)
	(segment
		(start 312.312812 -269.76451)
		(end 312.162444 -269.764256)
		(width 0.10668)
		(layer "F.Cu")
		(net "M_A_CPU0_SB_CB<6>")
	)
	(segment
		(start 309.229252 -272.067782)
		(end 309.412132 -272.250662)
		(width 0.10668)
		(layer "F.Cu")
		(net "M_A_CPU0_SB_CB<6>")
	)
	(segment
		(start 312.325512 -269.21206)
		(end 312.325258 -269.362936)
		(width 0.10668)
		(layer "F.Cu")
		(net "M_A_CPU0_SB_CB<6>")
	)
	(segment
		(start 312.45683 -269.080742)
		(end 312.325512 -269.21206)
		(width 0.10668)
		(layer "F.Cu")
		(net "M_A_CPU0_SB_CB<6>")
	)
	(segment
		(start 313.19216 -268.345412)
		(end 312.8899 -268.647672)
		(width 0.10668)
		(layer "F.Cu")
		(net "M_A_CPU0_SB_CB<6>")
	)
	(arc
		(start 325.894954 -269.447518)
		(mid 325.804821 -269.409898)
		(end 325.70801 -269.396972)
		(width 0.0762)
		(layer "F.Cu")
		(net "M_A_CPU0_SB_CB<6>")
	)
	(arc
		(start 326.12076 -269.520924)
		(mid 326.003947 -269.496248)
		(end 325.894954 -269.447518)
		(width 0.0762)
		(layer "F.Cu")
		(net "M_A_CPU0_SB_CB<6>")
	)
	(arc
		(start 326.648064 -269.770098)
		(mid 326.405747 -269.600378)
		(end 326.12076 -269.520924)
		(width 0.0762)
		(layer "F.Cu")
		(net "M_A_CPU0_SB_CB<6>")
	)
	(segment
		(start 310.84647 -271.451578)
		(end 310.84647 -271.602454)
		(width 0.10668)
		(layer "F.Cu")
		(net "M_A_CPU0_SB_CB<5>")
	)
	(segment
		(start 311.984136 -270.895826)
		(end 311.83326 -270.895826)
		(width 0.10668)
		(layer "F.Cu")
		(net "M_A_CPU0_SB_CB<5>")
	)
	(segment
		(start 310.42229 -272.30705)
		(end 310.422544 -272.457418)
		(width 0.10668)
		(layer "F.Cu")
		(net "M_A_CPU0_SB_CB<5>")
	)
	(segment
		(start 308.462934 -273.835114)
		(end 307.368194 -273.835114)
		(width 0.10668)
		(layer "F.Cu")
		(net "M_A_CPU0_SB_CB<5>")
	)
	(segment
		(start 312.115454 -270.613886)
		(end 312.115708 -270.764254)
		(width 0.10668)
		(layer "F.Cu")
		(net "M_A_CPU0_SB_CB<5>")
	)
	(segment
		(start 323.878194 -269.94485)
		(end 323.257672 -269.94485)
		(width 0.10668)
		(layer "F.Cu")
		(net "M_A_CPU0_SB_CB<5>")
	)
	(segment
		(start 312.397648 -270.331438)
		(end 312.25744 -270.19123)
		(width 0.10668)
		(layer "F.Cu")
		(net "M_A_CPU0_SB_CB<5>")
	)
	(segment
		(start 309.726584 -273.153378)
		(end 309.575708 -273.153378)
		(width 0.10668)
		(layer "F.Cu")
		(net "M_A_CPU0_SB_CB<5>")
	)
	(segment
		(start 311.551066 -271.178274)
		(end 311.55132 -271.328642)
		(width 0.10668)
		(layer "F.Cu")
		(net "M_A_CPU0_SB_CB<5>")
	)
	(segment
		(start 308.871112 -273.577558)
		(end 308.720236 -273.577812)
		(width 0.10668)
		(layer "F.Cu")
		(net "M_A_CPU0_SB_CB<5>")
	)
	(segment
		(start 327.409302 -270.097504)
		(end 327.40092 -270.092678)
		(width 0.0762)
		(layer "F.Cu")
		(net "M_A_CPU0_SB_CB<5>")
	)
	(segment
		(start 310.140096 -272.58899)
		(end 309.999888 -272.448782)
		(width 0.10668)
		(layer "F.Cu")
		(net "M_A_CPU0_SB_CB<5>")
	)
	(segment
		(start 309.858156 -273.021806)
		(end 309.726584 -273.153378)
		(width 0.10668)
		(layer "F.Cu")
		(net "M_A_CPU0_SB_CB<5>")
	)
	(segment
		(start 309.166768 -272.895568)
		(end 309.03545 -273.026886)
		(width 0.10668)
		(layer "F.Cu")
		(net "M_A_CPU0_SB_CB<5>")
	)
	(segment
		(start 310.704484 -272.024602)
		(end 310.564276 -271.884394)
		(width 0.10668)
		(layer "F.Cu")
		(net "M_A_CPU0_SB_CB<5>")
	)
	(segment
		(start 310.84647 -271.602454)
		(end 310.986678 -271.742662)
		(width 0.10668)
		(layer "F.Cu")
		(net "M_A_CPU0_SB_CB<5>")
	)
	(segment
		(start 311.268872 -271.460214)
		(end 311.128664 -271.320006)
		(width 0.10668)
		(layer "F.Cu")
		(net "M_A_CPU0_SB_CB<5>")
	)
	(segment
		(start 309.857902 -272.871438)
		(end 309.858156 -273.021806)
		(width 0.10668)
		(layer "F.Cu")
		(net "M_A_CPU0_SB_CB<5>")
	)
	(segment
		(start 309.849012 -272.449036)
		(end 309.717694 -272.580354)
		(width 0.10668)
		(layer "F.Cu")
		(net "M_A_CPU0_SB_CB<5>")
	)
	(segment
		(start 327.587864 -269.770098)
		(end 327.688702 -269.94358)
		(width 0.0762)
		(layer "F.Cu")
		(net "M_A_CPU0_SB_CB<5>")
	)
	(segment
		(start 309.317644 -272.895314)
		(end 309.166768 -272.895568)
		(width 0.10668)
		(layer "F.Cu")
		(net "M_A_CPU0_SB_CB<5>")
	)
	(segment
		(start 309.03545 -273.026886)
		(end 309.03545 -273.177762)
		(width 0.10668)
		(layer "F.Cu")
		(net "M_A_CPU0_SB_CB<5>")
	)
	(segment
		(start 312.25744 -270.19123)
		(end 312.106564 -270.191484)
		(width 0.10668)
		(layer "F.Cu")
		(net "M_A_CPU0_SB_CB<5>")
	)
	(segment
		(start 311.975246 -270.322802)
		(end 311.975246 -270.473678)
		(width 0.10668)
		(layer "F.Cu")
		(net "M_A_CPU0_SB_CB<5>")
	)
	(segment
		(start 310.977788 -271.32026)
		(end 310.84647 -271.451578)
		(width 0.10668)
		(layer "F.Cu")
		(net "M_A_CPU0_SB_CB<5>")
	)
	(segment
		(start 310.986932 -271.89303)
		(end 310.85536 -272.024602)
		(width 0.10668)
		(layer "F.Cu")
		(net "M_A_CPU0_SB_CB<5>")
	)
	(segment
		(start 310.282082 -272.166842)
		(end 310.42229 -272.30705)
		(width 0.10668)
		(layer "F.Cu")
		(net "M_A_CPU0_SB_CB<5>")
	)
	(segment
		(start 311.542176 -270.755872)
		(end 311.410858 -270.88719)
		(width 0.10668)
		(layer "F.Cu")
		(net "M_A_CPU0_SB_CB<5>")
	)
	(segment
		(start 311.975246 -270.473678)
		(end 312.115454 -270.613886)
		(width 0.10668)
		(layer "F.Cu")
		(net "M_A_CPU0_SB_CB<5>")
	)
	(segment
		(start 310.85536 -272.024602)
		(end 310.704484 -272.024602)
		(width 0.10668)
		(layer "F.Cu")
		(net "M_A_CPU0_SB_CB<5>")
	)
	(segment
		(start 309.162196 -273.717766)
		(end 309.01132 -273.717766)
		(width 0.10668)
		(layer "F.Cu")
		(net "M_A_CPU0_SB_CB<5>")
	)
	(segment
		(start 309.293768 -273.586194)
		(end 309.162196 -273.717766)
		(width 0.10668)
		(layer "F.Cu")
		(net "M_A_CPU0_SB_CB<5>")
	)
	(segment
		(start 326.835008 -270.092678)
		(end 326.826626 -270.097504)
		(width 0.0762)
		(layer "F.Cu")
		(net "M_A_CPU0_SB_CB<5>")
	)
	(segment
		(start 309.03545 -273.177762)
		(end 309.293514 -273.435826)
		(width 0.10668)
		(layer "F.Cu")
		(net "M_A_CPU0_SB_CB<5>")
	)
	(segment
		(start 311.419748 -271.460214)
		(end 311.268872 -271.460214)
		(width 0.10668)
		(layer "F.Cu")
		(net "M_A_CPU0_SB_CB<5>")
	)
	(segment
		(start 325.70801 -270.143224)
		(end 324.584568 -270.143224)
		(width 0.0762)
		(layer "F.Cu")
		(net "M_A_CPU0_SB_CB<5>")
	)
	(segment
		(start 311.693052 -270.755618)
		(end 311.542176 -270.755872)
		(width 0.10668)
		(layer "F.Cu")
		(net "M_A_CPU0_SB_CB<5>")
	)
	(segment
		(start 310.4134 -271.884648)
		(end 310.282082 -272.015966)
		(width 0.10668)
		(layer "F.Cu")
		(net "M_A_CPU0_SB_CB<5>")
	)
	(segment
		(start 312.548524 -270.331438)
		(end 312.397648 -270.331438)
		(width 0.10668)
		(layer "F.Cu")
		(net "M_A_CPU0_SB_CB<5>")
	)
	(segment
		(start 309.717694 -272.580354)
		(end 309.717694 -272.73123)
		(width 0.10668)
		(layer "F.Cu")
		(net "M_A_CPU0_SB_CB<5>")
	)
	(segment
		(start 309.575708 -273.153378)
		(end 309.317644 -272.895314)
		(width 0.10668)
		(layer "F.Cu")
		(net "M_A_CPU0_SB_CB<5>")
	)
	(segment
		(start 310.290972 -272.58899)
		(end 310.140096 -272.58899)
		(width 0.10668)
		(layer "F.Cu")
		(net "M_A_CPU0_SB_CB<5>")
	)
	(segment
		(start 311.55132 -271.328642)
		(end 311.419748 -271.460214)
		(width 0.10668)
		(layer "F.Cu")
		(net "M_A_CPU0_SB_CB<5>")
	)
	(segment
		(start 308.720236 -273.577812)
		(end 308.462934 -273.835114)
		(width 0.10668)
		(layer "F.Cu")
		(net "M_A_CPU0_SB_CB<5>")
	)
	(segment
		(start 309.717694 -272.73123)
		(end 309.857902 -272.871438)
		(width 0.10668)
		(layer "F.Cu")
		(net "M_A_CPU0_SB_CB<5>")
	)
	(segment
		(start 314.19419 -268.685772)
		(end 312.548524 -270.331438)
		(width 0.10668)
		(layer "F.Cu")
		(net "M_A_CPU0_SB_CB<5>")
	)
	(segment
		(start 311.410858 -270.88719)
		(end 311.410858 -271.038066)
		(width 0.10668)
		(layer "F.Cu")
		(net "M_A_CPU0_SB_CB<5>")
	)
	(segment
		(start 311.410858 -271.038066)
		(end 311.551066 -271.178274)
		(width 0.10668)
		(layer "F.Cu")
		(net "M_A_CPU0_SB_CB<5>")
	)
	(segment
		(start 309.293514 -273.435826)
		(end 309.293768 -273.586194)
		(width 0.10668)
		(layer "F.Cu")
		(net "M_A_CPU0_SB_CB<5>")
	)
	(segment
		(start 309.01132 -273.717766)
		(end 308.871112 -273.577558)
		(width 0.10668)
		(layer "F.Cu")
		(net "M_A_CPU0_SB_CB<5>")
	)
	(segment
		(start 309.999888 -272.448782)
		(end 309.849012 -272.449036)
		(width 0.10668)
		(layer "F.Cu")
		(net "M_A_CPU0_SB_CB<5>")
	)
	(segment
		(start 321.998594 -268.685772)
		(end 314.19419 -268.685772)
		(width 0.10668)
		(layer "F.Cu")
		(net "M_A_CPU0_SB_CB<5>")
	)
	(segment
		(start 311.83326 -270.895826)
		(end 311.693052 -270.755618)
		(width 0.10668)
		(layer "F.Cu")
		(net "M_A_CPU0_SB_CB<5>")
	)
	(segment
		(start 323.257672 -269.94485)
		(end 321.998594 -268.685772)
		(width 0.10668)
		(layer "F.Cu")
		(net "M_A_CPU0_SB_CB<5>")
	)
	(segment
		(start 310.422544 -272.457418)
		(end 310.290972 -272.58899)
		(width 0.10668)
		(layer "F.Cu")
		(net "M_A_CPU0_SB_CB<5>")
	)
	(segment
		(start 310.282082 -272.015966)
		(end 310.282082 -272.166842)
		(width 0.10668)
		(layer "F.Cu")
		(net "M_A_CPU0_SB_CB<5>")
	)
	(segment
		(start 312.106564 -270.191484)
		(end 311.975246 -270.322802)
		(width 0.10668)
		(layer "F.Cu")
		(net "M_A_CPU0_SB_CB<5>")
	)
	(segment
		(start 324.584568 -270.143224)
		(end 324.386194 -269.94485)
		(width 0.0762)
		(layer "F.Cu")
		(net "M_A_CPU0_SB_CB<5>")
	)
	(segment
		(start 324.386194 -269.94485)
		(end 323.878194 -269.94485)
		(width 0.0762)
		(layer "F.Cu")
		(net "M_A_CPU0_SB_CB<5>")
	)
	(segment
		(start 310.564276 -271.884394)
		(end 310.4134 -271.884648)
		(width 0.10668)
		(layer "F.Cu")
		(net "M_A_CPU0_SB_CB<5>")
	)
	(segment
		(start 311.128664 -271.320006)
		(end 310.977788 -271.32026)
		(width 0.10668)
		(layer "F.Cu")
		(net "M_A_CPU0_SB_CB<5>")
	)
	(segment
		(start 312.115708 -270.764254)
		(end 311.984136 -270.895826)
		(width 0.10668)
		(layer "F.Cu")
		(net "M_A_CPU0_SB_CB<5>")
	)
	(segment
		(start 310.986678 -271.742662)
		(end 310.986932 -271.89303)
		(width 0.10668)
		(layer "F.Cu")
		(net "M_A_CPU0_SB_CB<5>")
	)
	(arc
		(start 327.40092 -270.092678)
		(mid 327.117964 -270.016501)
		(end 326.835008 -270.092678)
		(width 0.0762)
		(layer "F.Cu")
		(net "M_A_CPU0_SB_CB<5>")
	)
	(arc
		(start 327.542652 -270.140176)
		(mid 327.473954 -270.12516)
		(end 327.409302 -270.097504)
		(width 0.0762)
		(layer "F.Cu")
		(net "M_A_CPU0_SB_CB<5>")
	)
	(arc
		(start 325.738998 -270.141954)
		(mid 325.723517 -270.14291)
		(end 325.70801 -270.143224)
		(width 0.0762)
		(layer "F.Cu")
		(net "M_A_CPU0_SB_CB<5>")
	)
	(arc
		(start 327.688702 -269.94358)
		(mid 327.672777 -270.084272)
		(end 327.542652 -270.140176)
		(width 0.0762)
		(layer "F.Cu")
		(net "M_A_CPU0_SB_CB<5>")
	)
	(arc
		(start 325.894954 -270.092678)
		(mid 325.819714 -270.125991)
		(end 325.738998 -270.141954)
		(width 0.0762)
		(layer "F.Cu")
		(net "M_A_CPU0_SB_CB<5>")
	)
	(arc
		(start 326.826626 -270.097504)
		(mid 326.643118 -270.142998)
		(end 326.460866 -270.092678)
		(width 0.0762)
		(layer "F.Cu")
		(net "M_A_CPU0_SB_CB<5>")
	)
	(arc
		(start 326.460866 -270.092678)
		(mid 326.17791 -270.016501)
		(end 325.894954 -270.092678)
		(width 0.0762)
		(layer "F.Cu")
		(net "M_A_CPU0_SB_CB<5>")
	)
	(segment
		(start 320.20002 -267.735812)
		(end 320.09334 -267.629132)
		(width 0.10668)
		(layer "F.Cu")
		(net "M_A_CPU0_SB_CB<4>")
	)
	(segment
		(start 319.508632 -268.005052)
		(end 319.401952 -267.898372)
		(width 0.10668)
		(layer "F.Cu")
		(net "M_A_CPU0_SB_CB<4>")
	)
	(segment
		(start 317.007748 -267.898372)
		(end 317.007748 -267.735812)
		(width 0.10668)
		(layer "F.Cu")
		(net "M_A_CPU0_SB_CB<4>")
	)
	(segment
		(start 323.105272 -268.829282)
		(end 323.105272 -268.678406)
		(width 0.10668)
		(layer "F.Cu")
		(net "M_A_CPU0_SB_CB<4>")
	)
	(segment
		(start 322.509388 -267.732002)
		(end 322.358512 -267.732002)
		(width 0.10668)
		(layer "F.Cu")
		(net "M_A_CPU0_SB_CB<4>")
	)
	(segment
		(start 321.905122 -267.629132)
		(end 321.503802 -267.629132)
		(width 0.10668)
		(layer "F.Cu")
		(net "M_A_CPU0_SB_CB<4>")
	)
	(segment
		(start 323.868034 -269.26413)
		(end 323.54012 -269.26413)
		(width 0.10668)
		(layer "F.Cu")
		(net "M_A_CPU0_SB_CB<4>")
	)
	(segment
		(start 308.31663 -272.135092)
		(end 307.368194 -272.135092)
		(width 0.10668)
		(layer "F.Cu")
		(net "M_A_CPU0_SB_CB<4>")
	)
	(segment
		(start 325.999348 -269.287498)
		(end 325.990966 -269.282672)
		(width 0.0762)
		(layer "F.Cu")
		(net "M_A_CPU0_SB_CB<4>")
	)
	(segment
		(start 315.012578 -267.735812)
		(end 315.012578 -267.898372)
		(width 0.10668)
		(layer "F.Cu")
		(net "M_A_CPU0_SB_CB<4>")
	)
	(segment
		(start 319.694306 -268.005052)
		(end 319.508632 -268.005052)
		(width 0.10668)
		(layer "F.Cu")
		(net "M_A_CPU0_SB_CB<4>")
	)
	(segment
		(start 314.720224 -268.005052)
		(end 314.613544 -267.898372)
		(width 0.10668)
		(layer "F.Cu")
		(net "M_A_CPU0_SB_CB<4>")
	)
	(segment
		(start 320.599054 -267.735812)
		(end 320.599054 -267.898372)
		(width 0.10668)
		(layer "F.Cu")
		(net "M_A_CPU0_SB_CB<4>")
	)
	(segment
		(start 317.513462 -267.629132)
		(end 317.406782 -267.735812)
		(width 0.10668)
		(layer "F.Cu")
		(net "M_A_CPU0_SB_CB<4>")
	)
	(segment
		(start 323.073776 -268.29639)
		(end 322.9229 -268.29639)
		(width 0.10668)
		(layer "F.Cu")
		(net "M_A_CPU0_SB_CB<4>")
	)
	(segment
		(start 317.114428 -268.005052)
		(end 317.007748 -267.898372)
		(width 0.10668)
		(layer "F.Cu")
		(net "M_A_CPU0_SB_CB<4>")
	)
	(segment
		(start 323.105272 -268.678406)
		(end 323.205094 -268.578584)
		(width 0.10668)
		(layer "F.Cu")
		(net "M_A_CPU0_SB_CB<4>")
	)
	(segment
		(start 318.603884 -267.898372)
		(end 318.603884 -267.735812)
		(width 0.10668)
		(layer "F.Cu")
		(net "M_A_CPU0_SB_CB<4>")
	)
	(segment
		(start 325.70801 -269.206472)
		(end 323.925692 -269.206472)
		(width 0.0762)
		(layer "F.Cu")
		(net "M_A_CPU0_SB_CB<4>")
	)
	(segment
		(start 321.290442 -268.005052)
		(end 321.104768 -268.005052)
		(width 0.10668)
		(layer "F.Cu")
		(net "M_A_CPU0_SB_CB<4>")
	)
	(segment
		(start 323.925692 -269.206472)
		(end 323.868034 -269.26413)
		(width 0.0762)
		(layer "F.Cu")
		(net "M_A_CPU0_SB_CB<4>")
	)
	(segment
		(start 323.54012 -269.26413)
		(end 323.105272 -268.829282)
		(width 0.10668)
		(layer "F.Cu")
		(net "M_A_CPU0_SB_CB<4>")
	)
	(segment
		(start 318.497204 -267.629132)
		(end 318.31153 -267.629132)
		(width 0.10668)
		(layer "F.Cu")
		(net "M_A_CPU0_SB_CB<4>")
	)
	(segment
		(start 318.09817 -268.005052)
		(end 317.912496 -268.005052)
		(width 0.10668)
		(layer "F.Cu")
		(net "M_A_CPU0_SB_CB<4>")
	)
	(segment
		(start 323.205094 -268.578584)
		(end 323.205094 -268.427708)
		(width 0.10668)
		(layer "F.Cu")
		(net "M_A_CPU0_SB_CB<4>")
	)
	(segment
		(start 320.998088 -267.898372)
		(end 320.998088 -267.735812)
		(width 0.10668)
		(layer "F.Cu")
		(net "M_A_CPU0_SB_CB<4>")
	)
	(segment
		(start 322.9229 -268.29639)
		(end 322.823078 -268.396212)
		(width 0.10668)
		(layer "F.Cu")
		(net "M_A_CPU0_SB_CB<4>")
	)
	(segment
		(start 317.007748 -267.735812)
		(end 316.901068 -267.629132)
		(width 0.10668)
		(layer "F.Cu")
		(net "M_A_CPU0_SB_CB<4>")
	)
	(segment
		(start 317.300102 -268.005052)
		(end 317.114428 -268.005052)
		(width 0.10668)
		(layer "F.Cu")
		(net "M_A_CPU0_SB_CB<4>")
	)
	(segment
		(start 321.397122 -267.898372)
		(end 321.290442 -268.005052)
		(width 0.10668)
		(layer "F.Cu")
		(net "M_A_CPU0_SB_CB<4>")
	)
	(segment
		(start 323.205094 -268.427708)
		(end 323.073776 -268.29639)
		(width 0.10668)
		(layer "F.Cu")
		(net "M_A_CPU0_SB_CB<4>")
	)
	(segment
		(start 318.20485 -267.735812)
		(end 318.20485 -267.898372)
		(width 0.10668)
		(layer "F.Cu")
		(net "M_A_CPU0_SB_CB<4>")
	)
	(segment
		(start 320.20002 -267.898372)
		(end 320.20002 -267.735812)
		(width 0.10668)
		(layer "F.Cu")
		(net "M_A_CPU0_SB_CB<4>")
	)
	(segment
		(start 314.21451 -267.898372)
		(end 314.10783 -268.005052)
		(width 0.10668)
		(layer "F.Cu")
		(net "M_A_CPU0_SB_CB<4>")
	)
	(segment
		(start 314.613544 -267.735812)
		(end 314.506864 -267.629132)
		(width 0.10668)
		(layer "F.Cu")
		(net "M_A_CPU0_SB_CB<4>")
	)
	(segment
		(start 309.615078 -271.44091)
		(end 309.010812 -271.44091)
		(width 0.10668)
		(layer "F.Cu")
		(net "M_A_CPU0_SB_CB<4>")
	)
	(segment
		(start 315.810646 -267.735812)
		(end 315.810646 -267.898372)
		(width 0.10668)
		(layer "F.Cu")
		(net "M_A_CPU0_SB_CB<4>")
	)
	(segment
		(start 317.805816 -267.735812)
		(end 317.699136 -267.629132)
		(width 0.10668)
		(layer "F.Cu")
		(net "M_A_CPU0_SB_CB<4>")
	)
	(segment
		(start 319.295272 -267.629132)
		(end 319.109598 -267.629132)
		(width 0.10668)
		(layer "F.Cu")
		(net "M_A_CPU0_SB_CB<4>")
	)
	(segment
		(start 320.705734 -267.629132)
		(end 320.599054 -267.735812)
		(width 0.10668)
		(layer "F.Cu")
		(net "M_A_CPU0_SB_CB<4>")
	)
	(segment
		(start 320.492374 -268.005052)
		(end 320.3067 -268.005052)
		(width 0.10668)
		(layer "F.Cu")
		(net "M_A_CPU0_SB_CB<4>")
	)
	(segment
		(start 322.640706 -268.014196)
		(end 322.640706 -267.86332)
		(width 0.10668)
		(layer "F.Cu")
		(net "M_A_CPU0_SB_CB<4>")
	)
	(segment
		(start 316.901068 -267.629132)
		(end 316.715394 -267.629132)
		(width 0.10668)
		(layer "F.Cu")
		(net "M_A_CPU0_SB_CB<4>")
	)
	(segment
		(start 316.608714 -267.735812)
		(end 316.608714 -267.898372)
		(width 0.10668)
		(layer "F.Cu")
		(net "M_A_CPU0_SB_CB<4>")
	)
	(segment
		(start 317.699136 -267.629132)
		(end 317.513462 -267.629132)
		(width 0.10668)
		(layer "F.Cu")
		(net "M_A_CPU0_SB_CB<4>")
	)
	(segment
		(start 315.119258 -267.629132)
		(end 315.012578 -267.735812)
		(width 0.10668)
		(layer "F.Cu")
		(net "M_A_CPU0_SB_CB<4>")
	)
	(segment
		(start 316.608714 -267.898372)
		(end 316.502034 -268.005052)
		(width 0.10668)
		(layer "F.Cu")
		(net "M_A_CPU0_SB_CB<4>")
	)
	(segment
		(start 322.640706 -267.86332)
		(end 322.509388 -267.732002)
		(width 0.10668)
		(layer "F.Cu")
		(net "M_A_CPU0_SB_CB<4>")
	)
	(segment
		(start 317.912496 -268.005052)
		(end 317.805816 -267.898372)
		(width 0.10668)
		(layer "F.Cu")
		(net "M_A_CPU0_SB_CB<4>")
	)
	(segment
		(start 318.710564 -268.005052)
		(end 318.603884 -267.898372)
		(width 0.10668)
		(layer "F.Cu")
		(net "M_A_CPU0_SB_CB<4>")
	)
	(segment
		(start 315.703966 -268.005052)
		(end 315.518292 -268.005052)
		(width 0.10668)
		(layer "F.Cu")
		(net "M_A_CPU0_SB_CB<4>")
	)
	(segment
		(start 314.10783 -268.005052)
		(end 313.922156 -268.005052)
		(width 0.10668)
		(layer "F.Cu")
		(net "M_A_CPU0_SB_CB<4>")
	)
	(segment
		(start 317.805816 -267.898372)
		(end 317.805816 -267.735812)
		(width 0.10668)
		(layer "F.Cu")
		(net "M_A_CPU0_SB_CB<4>")
	)
	(segment
		(start 320.09334 -267.629132)
		(end 319.907666 -267.629132)
		(width 0.10668)
		(layer "F.Cu")
		(net "M_A_CPU0_SB_CB<4>")
	)
	(segment
		(start 313.708796 -267.629132)
		(end 313.426856 -267.629132)
		(width 0.10668)
		(layer "F.Cu")
		(net "M_A_CPU0_SB_CB<4>")
	)
	(segment
		(start 314.506864 -267.629132)
		(end 314.32119 -267.629132)
		(width 0.10668)
		(layer "F.Cu")
		(net "M_A_CPU0_SB_CB<4>")
	)
	(segment
		(start 313.426856 -267.629132)
		(end 309.615078 -271.44091)
		(width 0.10668)
		(layer "F.Cu")
		(net "M_A_CPU0_SB_CB<4>")
	)
	(segment
		(start 317.406782 -267.898372)
		(end 317.300102 -268.005052)
		(width 0.10668)
		(layer "F.Cu")
		(net "M_A_CPU0_SB_CB<4>")
	)
	(segment
		(start 319.002918 -267.898372)
		(end 318.896238 -268.005052)
		(width 0.10668)
		(layer "F.Cu")
		(net "M_A_CPU0_SB_CB<4>")
	)
	(segment
		(start 321.397122 -267.735812)
		(end 321.397122 -267.898372)
		(width 0.10668)
		(layer "F.Cu")
		(net "M_A_CPU0_SB_CB<4>")
	)
	(segment
		(start 326.17791 -268.960092)
		(end 326.276208 -269.129256)
		(width 0.0762)
		(layer "F.Cu")
		(net "M_A_CPU0_SB_CB<4>")
	)
	(segment
		(start 316.103 -267.629132)
		(end 315.917326 -267.629132)
		(width 0.10668)
		(layer "F.Cu")
		(net "M_A_CPU0_SB_CB<4>")
	)
	(segment
		(start 320.891408 -267.629132)
		(end 320.705734 -267.629132)
		(width 0.10668)
		(layer "F.Cu")
		(net "M_A_CPU0_SB_CB<4>")
	)
	(segment
		(start 313.815476 -267.735812)
		(end 313.708796 -267.629132)
		(width 0.10668)
		(layer "F.Cu")
		(net "M_A_CPU0_SB_CB<4>")
	)
	(segment
		(start 316.20968 -267.735812)
		(end 316.103 -267.629132)
		(width 0.10668)
		(layer "F.Cu")
		(net "M_A_CPU0_SB_CB<4>")
	)
	(segment
		(start 315.304932 -267.629132)
		(end 315.119258 -267.629132)
		(width 0.10668)
		(layer "F.Cu")
		(net "M_A_CPU0_SB_CB<4>")
	)
	(segment
		(start 319.401952 -267.898372)
		(end 319.401952 -267.735812)
		(width 0.10668)
		(layer "F.Cu")
		(net "M_A_CPU0_SB_CB<4>")
	)
	(segment
		(start 316.31636 -268.005052)
		(end 316.20968 -267.898372)
		(width 0.10668)
		(layer "F.Cu")
		(net "M_A_CPU0_SB_CB<4>")
	)
	(segment
		(start 317.406782 -267.735812)
		(end 317.406782 -267.898372)
		(width 0.10668)
		(layer "F.Cu")
		(net "M_A_CPU0_SB_CB<4>")
	)
	(segment
		(start 313.922156 -268.005052)
		(end 313.815476 -267.898372)
		(width 0.10668)
		(layer "F.Cu")
		(net "M_A_CPU0_SB_CB<4>")
	)
	(segment
		(start 318.603884 -267.735812)
		(end 318.497204 -267.629132)
		(width 0.10668)
		(layer "F.Cu")
		(net "M_A_CPU0_SB_CB<4>")
	)
	(segment
		(start 316.20968 -267.898372)
		(end 316.20968 -267.735812)
		(width 0.10668)
		(layer "F.Cu")
		(net "M_A_CPU0_SB_CB<4>")
	)
	(segment
		(start 319.800986 -267.898372)
		(end 319.694306 -268.005052)
		(width 0.10668)
		(layer "F.Cu")
		(net "M_A_CPU0_SB_CB<4>")
	)
	(segment
		(start 319.800986 -267.735812)
		(end 319.800986 -267.898372)
		(width 0.10668)
		(layer "F.Cu")
		(net "M_A_CPU0_SB_CB<4>")
	)
	(segment
		(start 313.815476 -267.898372)
		(end 313.815476 -267.735812)
		(width 0.10668)
		(layer "F.Cu")
		(net "M_A_CPU0_SB_CB<4>")
	)
	(segment
		(start 315.518292 -268.005052)
		(end 315.411612 -267.898372)
		(width 0.10668)
		(layer "F.Cu")
		(net "M_A_CPU0_SB_CB<4>")
	)
	(segment
		(start 315.411612 -267.898372)
		(end 315.411612 -267.735812)
		(width 0.10668)
		(layer "F.Cu")
		(net "M_A_CPU0_SB_CB<4>")
	)
	(segment
		(start 314.32119 -267.629132)
		(end 314.21451 -267.735812)
		(width 0.10668)
		(layer "F.Cu")
		(net "M_A_CPU0_SB_CB<4>")
	)
	(segment
		(start 322.540884 -268.264894)
		(end 322.540884 -268.114018)
		(width 0.10668)
		(layer "F.Cu")
		(net "M_A_CPU0_SB_CB<4>")
	)
	(segment
		(start 315.810646 -267.898372)
		(end 315.703966 -268.005052)
		(width 0.10668)
		(layer "F.Cu")
		(net "M_A_CPU0_SB_CB<4>")
	)
	(segment
		(start 322.672202 -268.396212)
		(end 322.540884 -268.264894)
		(width 0.10668)
		(layer "F.Cu")
		(net "M_A_CPU0_SB_CB<4>")
	)
	(segment
		(start 321.104768 -268.005052)
		(end 320.998088 -267.898372)
		(width 0.10668)
		(layer "F.Cu")
		(net "M_A_CPU0_SB_CB<4>")
	)
	(segment
		(start 315.012578 -267.898372)
		(end 314.905898 -268.005052)
		(width 0.10668)
		(layer "F.Cu")
		(net "M_A_CPU0_SB_CB<4>")
	)
	(segment
		(start 322.107814 -267.831824)
		(end 321.905122 -267.629132)
		(width 0.10668)
		(layer "F.Cu")
		(net "M_A_CPU0_SB_CB<4>")
	)
	(segment
		(start 315.411612 -267.735812)
		(end 315.304932 -267.629132)
		(width 0.10668)
		(layer "F.Cu")
		(net "M_A_CPU0_SB_CB<4>")
	)
	(segment
		(start 319.109598 -267.629132)
		(end 319.002918 -267.735812)
		(width 0.10668)
		(layer "F.Cu")
		(net "M_A_CPU0_SB_CB<4>")
	)
	(segment
		(start 316.715394 -267.629132)
		(end 316.608714 -267.735812)
		(width 0.10668)
		(layer "F.Cu")
		(net "M_A_CPU0_SB_CB<4>")
	)
	(segment
		(start 320.599054 -267.898372)
		(end 320.492374 -268.005052)
		(width 0.10668)
		(layer "F.Cu")
		(net "M_A_CPU0_SB_CB<4>")
	)
	(segment
		(start 321.503802 -267.629132)
		(end 321.397122 -267.735812)
		(width 0.10668)
		(layer "F.Cu")
		(net "M_A_CPU0_SB_CB<4>")
	)
	(segment
		(start 322.540884 -268.114018)
		(end 322.640706 -268.014196)
		(width 0.10668)
		(layer "F.Cu")
		(net "M_A_CPU0_SB_CB<4>")
	)
	(segment
		(start 320.998088 -267.735812)
		(end 320.891408 -267.629132)
		(width 0.10668)
		(layer "F.Cu")
		(net "M_A_CPU0_SB_CB<4>")
	)
	(segment
		(start 318.896238 -268.005052)
		(end 318.710564 -268.005052)
		(width 0.10668)
		(layer "F.Cu")
		(net "M_A_CPU0_SB_CB<4>")
	)
	(segment
		(start 316.502034 -268.005052)
		(end 316.31636 -268.005052)
		(width 0.10668)
		(layer "F.Cu")
		(net "M_A_CPU0_SB_CB<4>")
	)
	(segment
		(start 318.31153 -267.629132)
		(end 318.20485 -267.735812)
		(width 0.10668)
		(layer "F.Cu")
		(net "M_A_CPU0_SB_CB<4>")
	)
	(segment
		(start 314.613544 -267.898372)
		(end 314.613544 -267.735812)
		(width 0.10668)
		(layer "F.Cu")
		(net "M_A_CPU0_SB_CB<4>")
	)
	(segment
		(start 315.917326 -267.629132)
		(end 315.810646 -267.735812)
		(width 0.10668)
		(layer "F.Cu")
		(net "M_A_CPU0_SB_CB<4>")
	)
	(segment
		(start 322.358512 -267.732002)
		(end 322.25869 -267.831824)
		(width 0.10668)
		(layer "F.Cu")
		(net "M_A_CPU0_SB_CB<4>")
	)
	(segment
		(start 322.25869 -267.831824)
		(end 322.107814 -267.831824)
		(width 0.10668)
		(layer "F.Cu")
		(net "M_A_CPU0_SB_CB<4>")
	)
	(segment
		(start 314.21451 -267.735812)
		(end 314.21451 -267.898372)
		(width 0.10668)
		(layer "F.Cu")
		(net "M_A_CPU0_SB_CB<4>")
	)
	(segment
		(start 314.905898 -268.005052)
		(end 314.720224 -268.005052)
		(width 0.10668)
		(layer "F.Cu")
		(net "M_A_CPU0_SB_CB<4>")
	)
	(segment
		(start 322.823078 -268.396212)
		(end 322.672202 -268.396212)
		(width 0.10668)
		(layer "F.Cu")
		(net "M_A_CPU0_SB_CB<4>")
	)
	(segment
		(start 309.010812 -271.44091)
		(end 308.31663 -272.135092)
		(width 0.10668)
		(layer "F.Cu")
		(net "M_A_CPU0_SB_CB<4>")
	)
	(segment
		(start 319.907666 -267.629132)
		(end 319.800986 -267.735812)
		(width 0.10668)
		(layer "F.Cu")
		(net "M_A_CPU0_SB_CB<4>")
	)
	(segment
		(start 318.20485 -267.898372)
		(end 318.09817 -268.005052)
		(width 0.10668)
		(layer "F.Cu")
		(net "M_A_CPU0_SB_CB<4>")
	)
	(segment
		(start 320.3067 -268.005052)
		(end 320.20002 -267.898372)
		(width 0.10668)
		(layer "F.Cu")
		(net "M_A_CPU0_SB_CB<4>")
	)
	(segment
		(start 319.401952 -267.735812)
		(end 319.295272 -267.629132)
		(width 0.10668)
		(layer "F.Cu")
		(net "M_A_CPU0_SB_CB<4>")
	)
	(segment
		(start 319.002918 -267.735812)
		(end 319.002918 -267.898372)
		(width 0.10668)
		(layer "F.Cu")
		(net "M_A_CPU0_SB_CB<4>")
	)
	(arc
		(start 325.990966 -269.282672)
		(mid 325.85453 -269.225847)
		(end 325.70801 -269.206472)
		(width 0.0762)
		(layer "F.Cu")
		(net "M_A_CPU0_SB_CB<4>")
	)
	(arc
		(start 326.13854 -269.330932)
		(mid 326.066802 -269.31608)
		(end 325.999348 -269.287498)
		(width 0.0762)
		(layer "F.Cu")
		(net "M_A_CPU0_SB_CB<4>")
	)
	(arc
		(start 326.276208 -269.129256)
		(mid 326.267615 -269.271135)
		(end 326.13854 -269.330932)
		(width 0.0762)
		(layer "F.Cu")
		(net "M_A_CPU0_SB_CB<4>")
	)
	(segment
		(start 306.114958 -280.210006)
		(end 305.089052 -280.634948)
		(width 0.101346)
		(layer "F.Cu")
		(net "M_A_CPU0_SB_CB<3>")
	)
	(segment
		(start 308.66588 -280.210006)
		(end 306.114958 -280.210006)
		(width 0.101346)
		(layer "F.Cu")
		(net "M_A_CPU0_SB_CB<3>")
	)
	(segment
		(start 325.999348 -273.492722)
		(end 325.990966 -273.497548)
		(width 0.0762)
		(layer "F.Cu")
		(net "M_A_CPU0_SB_CB<3>")
	)
	(segment
		(start 315.59373 -273.36369)
		(end 308.747414 -280.210006)
		(width 0.10668)
		(layer "F.Cu")
		(net "M_A_CPU0_SB_CB<3>")
	)
	(segment
		(start 323.908674 -273.36369)
		(end 315.59373 -273.36369)
		(width 0.10668)
		(layer "F.Cu")
		(net "M_A_CPU0_SB_CB<3>")
	)
	(segment
		(start 324.672198 -273.573748)
		(end 324.46214 -273.36369)
		(width 0.0762)
		(layer "F.Cu")
		(net "M_A_CPU0_SB_CB<3>")
	)
	(segment
		(start 325.708264 -273.573748)
		(end 324.672198 -273.573748)
		(width 0.0762)
		(layer "F.Cu")
		(net "M_A_CPU0_SB_CB<3>")
	)
	(segment
		(start 308.747414 -280.210006)
		(end 308.66588 -280.210006)
		(width 0.10668)
		(layer "F.Cu")
		(net "M_A_CPU0_SB_CB<3>")
	)
	(segment
		(start 305.089052 -280.634948)
		(end 303.268126 -280.634948)
		(width 0.101346)
		(layer "F.Cu")
		(net "M_A_CPU0_SB_CB<3>")
	)
	(segment
		(start 324.46214 -273.36369)
		(end 323.908674 -273.36369)
		(width 0.0762)
		(layer "F.Cu")
		(net "M_A_CPU0_SB_CB<3>")
	)
	(arc
		(start 327.304908 -273.497548)
		(mid 327.117964 -273.447293)
		(end 326.93102 -273.497548)
		(width 0.0762)
		(layer "F.Cu")
		(net "M_A_CPU0_SB_CB<3>")
	)
	(arc
		(start 325.990966 -273.497548)
		(mid 325.877242 -273.547849)
		(end 325.755254 -273.57197)
		(width 0.0762)
		(layer "F.Cu")
		(net "M_A_CPU0_SB_CB<3>")
	)
	(arc
		(start 328.058018 -273.820128)
		(mid 327.820406 -273.64914)
		(end 327.53808 -273.571716)
		(width 0.0762)
		(layer "F.Cu")
		(net "M_A_CPU0_SB_CB<3>")
	)
	(arc
		(start 327.53808 -273.571716)
		(mid 327.417431 -273.547415)
		(end 327.304908 -273.497548)
		(width 0.0762)
		(layer "F.Cu")
		(net "M_A_CPU0_SB_CB<3>")
	)
	(arc
		(start 326.365108 -273.497548)
		(mid 326.182857 -273.447198)
		(end 325.999348 -273.492722)
		(width 0.0762)
		(layer "F.Cu")
		(net "M_A_CPU0_SB_CB<3>")
	)
	(arc
		(start 326.93102 -273.497548)
		(mid 326.648064 -273.573725)
		(end 326.365108 -273.497548)
		(width 0.0762)
		(layer "F.Cu")
		(net "M_A_CPU0_SB_CB<3>")
	)
	(arc
		(start 325.755254 -273.57197)
		(mid 325.731777 -273.573346)
		(end 325.708264 -273.573748)
		(width 0.0762)
		(layer "F.Cu")
		(net "M_A_CPU0_SB_CB<3>")
	)
	(segment
		(start 314.974478 -272.58899)
		(end 309.053484 -278.509984)
		(width 0.10668)
		(layer "F.Cu")
		(net "M_A_CPU0_SB_CB<2>")
	)
	(segment
		(start 317.269622 -272.48231)
		(end 317.269622 -272.175732)
		(width 0.10668)
		(layer "F.Cu")
		(net "M_A_CPU0_SB_CB<2>")
	)
	(segment
		(start 316.1792 -272.069052)
		(end 316.07252 -272.175732)
		(width 0.10668)
		(layer "F.Cu")
		(net "M_A_CPU0_SB_CB<2>")
	)
	(segment
		(start 316.977268 -272.069052)
		(end 316.870588 -272.175732)
		(width 0.10668)
		(layer "F.Cu")
		(net "M_A_CPU0_SB_CB<2>")
	)
	(segment
		(start 317.162942 -272.069052)
		(end 316.977268 -272.069052)
		(width 0.10668)
		(layer "F.Cu")
		(net "M_A_CPU0_SB_CB<2>")
	)
	(segment
		(start 323.89572 -272.58899)
		(end 317.376302 -272.58899)
		(width 0.10668)
		(layer "F.Cu")
		(net "M_A_CPU0_SB_CB<2>")
	)
	(segment
		(start 306.121054 -278.509984)
		(end 305.695858 -278.93518)
		(width 0.101346)
		(layer "F.Cu")
		(net "M_A_CPU0_SB_CB<2>")
	)
	(segment
		(start 325.70801 -272.636996)
		(end 324.833742 -272.636996)
		(width 0.0762)
		(layer "F.Cu")
		(net "M_A_CPU0_SB_CB<2>")
	)
	(segment
		(start 324.785736 -272.58899)
		(end 323.89572 -272.58899)
		(width 0.0762)
		(layer "F.Cu")
		(net "M_A_CPU0_SB_CB<2>")
	)
	(segment
		(start 317.376302 -272.58899)
		(end 317.269622 -272.48231)
		(width 0.10668)
		(layer "F.Cu")
		(net "M_A_CPU0_SB_CB<2>")
	)
	(segment
		(start 308.66588 -278.509984)
		(end 306.121054 -278.509984)
		(width 0.101346)
		(layer "F.Cu")
		(net "M_A_CPU0_SB_CB<2>")
	)
	(segment
		(start 309.053484 -278.509984)
		(end 308.66588 -278.509984)
		(width 0.10668)
		(layer "F.Cu")
		(net "M_A_CPU0_SB_CB<2>")
	)
	(segment
		(start 305.695858 -278.93518)
		(end 303.268126 -278.93518)
		(width 0.101346)
		(layer "F.Cu")
		(net "M_A_CPU0_SB_CB<2>")
	)
	(segment
		(start 316.870588 -272.175732)
		(end 316.870588 -272.48231)
		(width 0.10668)
		(layer "F.Cu")
		(net "M_A_CPU0_SB_CB<2>")
	)
	(segment
		(start 316.07252 -272.175732)
		(end 316.07252 -272.48231)
		(width 0.10668)
		(layer "F.Cu")
		(net "M_A_CPU0_SB_CB<2>")
	)
	(segment
		(start 324.833742 -272.636996)
		(end 324.785736 -272.58899)
		(width 0.0762)
		(layer "F.Cu")
		(net "M_A_CPU0_SB_CB<2>")
	)
	(segment
		(start 317.269622 -272.175732)
		(end 317.162942 -272.069052)
		(width 0.10668)
		(layer "F.Cu")
		(net "M_A_CPU0_SB_CB<2>")
	)
	(segment
		(start 316.471554 -272.48231)
		(end 316.471554 -272.175732)
		(width 0.10668)
		(layer "F.Cu")
		(net "M_A_CPU0_SB_CB<2>")
	)
	(segment
		(start 316.578234 -272.58899)
		(end 316.471554 -272.48231)
		(width 0.10668)
		(layer "F.Cu")
		(net "M_A_CPU0_SB_CB<2>")
	)
	(segment
		(start 316.07252 -272.48231)
		(end 315.96584 -272.58899)
		(width 0.10668)
		(layer "F.Cu")
		(net "M_A_CPU0_SB_CB<2>")
	)
	(segment
		(start 316.763908 -272.58899)
		(end 316.578234 -272.58899)
		(width 0.10668)
		(layer "F.Cu")
		(net "M_A_CPU0_SB_CB<2>")
	)
	(segment
		(start 316.364874 -272.069052)
		(end 316.1792 -272.069052)
		(width 0.10668)
		(layer "F.Cu")
		(net "M_A_CPU0_SB_CB<2>")
	)
	(segment
		(start 315.96584 -272.58899)
		(end 314.974478 -272.58899)
		(width 0.10668)
		(layer "F.Cu")
		(net "M_A_CPU0_SB_CB<2>")
	)
	(segment
		(start 316.870588 -272.48231)
		(end 316.763908 -272.58899)
		(width 0.10668)
		(layer "F.Cu")
		(net "M_A_CPU0_SB_CB<2>")
	)
	(segment
		(start 316.471554 -272.175732)
		(end 316.364874 -272.069052)
		(width 0.10668)
		(layer "F.Cu")
		(net "M_A_CPU0_SB_CB<2>")
	)
	(arc
		(start 326.12076 -272.760948)
		(mid 326.003947 -272.736272)
		(end 325.894954 -272.687542)
		(width 0.0762)
		(layer "F.Cu")
		(net "M_A_CPU0_SB_CB<2>")
	)
	(arc
		(start 326.648064 -273.010122)
		(mid 326.405747 -272.840402)
		(end 326.12076 -272.760948)
		(width 0.0762)
		(layer "F.Cu")
		(net "M_A_CPU0_SB_CB<2>")
	)
	(arc
		(start 325.894954 -272.687542)
		(mid 325.804821 -272.649922)
		(end 325.70801 -272.636996)
		(width 0.0762)
		(layer "F.Cu")
		(net "M_A_CPU0_SB_CB<2>")
	)
	(segment
		(start 314.394596 -274.080986)
		(end 314.263278 -274.212304)
		(width 0.10668)
		(layer "F.Cu")
		(net "M_A_CPU0_SB_CB<1>")
	)
	(segment
		(start 312.636916 -275.558758)
		(end 312.701432 -275.623274)
		(width 0.10668)
		(layer "F.Cu")
		(net "M_A_CPU0_SB_CB<1>")
	)
	(segment
		(start 311.639458 -276.405594)
		(end 311.507886 -276.537166)
		(width 0.10668)
		(layer "F.Cu")
		(net "M_A_CPU0_SB_CB<1>")
	)
	(segment
		(start 314.612274 -273.583654)
		(end 314.461398 -273.583654)
		(width 0.10668)
		(layer "F.Cu")
		(net "M_A_CPU0_SB_CB<1>")
	)
	(segment
		(start 314.958984 -273.365722)
		(end 314.958984 -273.516598)
		(width 0.10668)
		(layer "F.Cu")
		(net "M_A_CPU0_SB_CB<1>")
	)
	(segment
		(start 310.943498 -277.101554)
		(end 310.943752 -277.251922)
		(width 0.10668)
		(layer "F.Cu")
		(net "M_A_CPU0_SB_CB<1>")
	)
	(segment
		(start 310.726074 -277.598886)
		(end 310.661558 -277.53437)
		(width 0.10668)
		(layer "F.Cu")
		(net "M_A_CPU0_SB_CB<1>")
	)
	(segment
		(start 312.137044 -276.187662)
		(end 312.137044 -276.338538)
		(width 0.10668)
		(layer "F.Cu")
		(net "M_A_CPU0_SB_CB<1>")
	)
	(segment
		(start 313.20105 -274.844002)
		(end 313.201304 -274.99437)
		(width 0.10668)
		(layer "F.Cu")
		(net "M_A_CPU0_SB_CB<1>")
	)
	(segment
		(start 309.879492 -278.445214)
		(end 309.879492 -278.59609)
		(width 0.10668)
		(layer "F.Cu")
		(net "M_A_CPU0_SB_CB<1>")
	)
	(segment
		(start 323.901054 -272.92935)
		(end 315.115702 -272.92935)
		(width 0.10668)
		(layer "F.Cu")
		(net "M_A_CPU0_SB_CB<1>")
	)
	(segment
		(start 314.329826 -273.715226)
		(end 314.33008 -273.865594)
		(width 0.10668)
		(layer "F.Cu")
		(net "M_A_CPU0_SB_CB<1>")
	)
	(segment
		(start 312.005726 -276.469856)
		(end 311.85485 -276.47011)
		(width 0.10668)
		(layer "F.Cu")
		(net "M_A_CPU0_SB_CB<1>")
	)
	(segment
		(start 311.572656 -276.75205)
		(end 311.572656 -276.902926)
		(width 0.10668)
		(layer "F.Cu")
		(net "M_A_CPU0_SB_CB<1>")
	)
	(segment
		(start 309.250588 -278.945086)
		(end 309.315104 -279.009602)
		(width 0.10668)
		(layer "F.Cu")
		(net "M_A_CPU0_SB_CB<1>")
	)
	(segment
		(start 310.44388 -278.031702)
		(end 310.312562 -278.16302)
		(width 0.10668)
		(layer "F.Cu")
		(net "M_A_CPU0_SB_CB<1>")
	)
	(segment
		(start 312.354722 -275.841206)
		(end 312.203846 -275.841206)
		(width 0.10668)
		(layer "F.Cu")
		(net "M_A_CPU0_SB_CB<1>")
	)
	(segment
		(start 312.419238 -275.905722)
		(end 312.354722 -275.841206)
		(width 0.10668)
		(layer "F.Cu")
		(net "M_A_CPU0_SB_CB<1>")
	)
	(segment
		(start 313.69889 -274.776692)
		(end 313.548014 -274.776946)
		(width 0.10668)
		(layer "F.Cu")
		(net "M_A_CPU0_SB_CB<1>")
	)
	(segment
		(start 312.570114 -275.905468)
		(end 312.419238 -275.905722)
		(width 0.10668)
		(layer "F.Cu")
		(net "M_A_CPU0_SB_CB<1>")
	)
	(segment
		(start 324.297294 -272.92935)
		(end 323.901054 -272.92935)
		(width 0.0762)
		(layer "F.Cu")
		(net "M_A_CPU0_SB_CB<1>")
	)
	(segment
		(start 312.072528 -276.123146)
		(end 312.137044 -276.187662)
		(width 0.10668)
		(layer "F.Cu")
		(net "M_A_CPU0_SB_CB<1>")
	)
	(segment
		(start 327.409302 -273.337528)
		(end 327.40092 -273.332702)
		(width 0.0762)
		(layer "F.Cu")
		(net "M_A_CPU0_SB_CB<1>")
	)
	(segment
		(start 312.91911 -275.276818)
		(end 312.768234 -275.276818)
		(width 0.10668)
		(layer "F.Cu")
		(net "M_A_CPU0_SB_CB<1>")
	)
	(segment
		(start 310.943752 -277.251922)
		(end 311.008268 -277.316438)
		(width 0.10668)
		(layer "F.Cu")
		(net "M_A_CPU0_SB_CB<1>")
	)
	(segment
		(start 309.814976 -278.380698)
		(end 309.879492 -278.445214)
		(width 0.10668)
		(layer "F.Cu")
		(net "M_A_CPU0_SB_CB<1>")
	)
	(segment
		(start 311.85485 -276.47011)
		(end 311.790334 -276.405594)
		(width 0.10668)
		(layer "F.Cu")
		(net "M_A_CPU0_SB_CB<1>")
	)
	(segment
		(start 308.817518 -279.227534)
		(end 308.259988 -279.785064)
		(width 0.10668)
		(layer "F.Cu")
		(net "M_A_CPU0_SB_CB<1>")
	)
	(segment
		(start 310.661558 -277.53437)
		(end 310.510682 -277.53437)
		(width 0.10668)
		(layer "F.Cu")
		(net "M_A_CPU0_SB_CB<1>")
	)
	(segment
		(start 314.461398 -273.583654)
		(end 314.329826 -273.715226)
		(width 0.10668)
		(layer "F.Cu")
		(net "M_A_CPU0_SB_CB<1>")
	)
	(segment
		(start 315.115702 -272.92935)
		(end 314.894214 -273.150838)
		(width 0.10668)
		(layer "F.Cu")
		(net "M_A_CPU0_SB_CB<1>")
	)
	(segment
		(start 313.830208 -274.645374)
		(end 313.69889 -274.776692)
		(width 0.10668)
		(layer "F.Cu")
		(net "M_A_CPU0_SB_CB<1>")
	)
	(segment
		(start 314.827666 -273.647916)
		(end 314.67679 -273.64817)
		(width 0.10668)
		(layer "F.Cu")
		(net "M_A_CPU0_SB_CB<1>")
	)
	(segment
		(start 311.07507 -276.969982)
		(end 310.943498 -277.101554)
		(width 0.10668)
		(layer "F.Cu")
		(net "M_A_CPU0_SB_CB<1>")
	)
	(segment
		(start 312.701432 -275.77415)
		(end 312.570114 -275.905468)
		(width 0.10668)
		(layer "F.Cu")
		(net "M_A_CPU0_SB_CB<1>")
	)
	(segment
		(start 312.983626 -275.341334)
		(end 312.91911 -275.276818)
		(width 0.10668)
		(layer "F.Cu")
		(net "M_A_CPU0_SB_CB<1>")
	)
	(segment
		(start 309.183786 -279.291796)
		(end 309.03291 -279.29205)
		(width 0.10668)
		(layer "F.Cu")
		(net "M_A_CPU0_SB_CB<1>")
	)
	(segment
		(start 310.09717 -278.098758)
		(end 309.946294 -278.098758)
		(width 0.10668)
		(layer "F.Cu")
		(net "M_A_CPU0_SB_CB<1>")
	)
	(segment
		(start 313.26582 -275.058886)
		(end 313.26582 -275.209762)
		(width 0.10668)
		(layer "F.Cu")
		(net "M_A_CPU0_SB_CB<1>")
	)
	(segment
		(start 312.137044 -276.338538)
		(end 312.005726 -276.469856)
		(width 0.10668)
		(layer "F.Cu")
		(net "M_A_CPU0_SB_CB<1>")
	)
	(segment
		(start 325.70801 -273.383248)
		(end 324.751192 -273.383248)
		(width 0.0762)
		(layer "F.Cu")
		(net "M_A_CPU0_SB_CB<1>")
	)
	(segment
		(start 311.441338 -277.034244)
		(end 311.290462 -277.034498)
		(width 0.10668)
		(layer "F.Cu")
		(net "M_A_CPU0_SB_CB<1>")
	)
	(segment
		(start 313.134502 -275.34108)
		(end 312.983626 -275.341334)
		(width 0.10668)
		(layer "F.Cu")
		(net "M_A_CPU0_SB_CB<1>")
	)
	(segment
		(start 312.072274 -275.972778)
		(end 312.072528 -276.123146)
		(width 0.10668)
		(layer "F.Cu")
		(net "M_A_CPU0_SB_CB<1>")
	)
	(segment
		(start 309.381906 -278.663146)
		(end 309.250334 -278.794718)
		(width 0.10668)
		(layer "F.Cu")
		(net "M_A_CPU0_SB_CB<1>")
	)
	(segment
		(start 311.290462 -277.034498)
		(end 311.225946 -276.969982)
		(width 0.10668)
		(layer "F.Cu")
		(net "M_A_CPU0_SB_CB<1>")
	)
	(segment
		(start 309.315104 -279.009602)
		(end 309.315104 -279.160478)
		(width 0.10668)
		(layer "F.Cu")
		(net "M_A_CPU0_SB_CB<1>")
	)
	(segment
		(start 311.008268 -277.467314)
		(end 310.87695 -277.598632)
		(width 0.10668)
		(layer "F.Cu")
		(net "M_A_CPU0_SB_CB<1>")
	)
	(segment
		(start 309.946294 -278.098758)
		(end 309.814722 -278.23033)
		(width 0.10668)
		(layer "F.Cu")
		(net "M_A_CPU0_SB_CB<1>")
	)
	(segment
		(start 312.203846 -275.841206)
		(end 312.072274 -275.972778)
		(width 0.10668)
		(layer "F.Cu")
		(net "M_A_CPU0_SB_CB<1>")
	)
	(segment
		(start 309.597298 -278.727662)
		(end 309.532782 -278.663146)
		(width 0.10668)
		(layer "F.Cu")
		(net "M_A_CPU0_SB_CB<1>")
	)
	(segment
		(start 314.958984 -273.516598)
		(end 314.827666 -273.647916)
		(width 0.10668)
		(layer "F.Cu")
		(net "M_A_CPU0_SB_CB<1>")
	)
	(segment
		(start 324.751192 -273.383248)
		(end 324.297294 -272.92935)
		(width 0.0762)
		(layer "F.Cu")
		(net "M_A_CPU0_SB_CB<1>")
	)
	(segment
		(start 308.968394 -279.227534)
		(end 308.817518 -279.227534)
		(width 0.10668)
		(layer "F.Cu")
		(net "M_A_CPU0_SB_CB<1>")
	)
	(segment
		(start 313.89701 -274.148042)
		(end 313.765438 -274.279614)
		(width 0.10668)
		(layer "F.Cu")
		(net "M_A_CPU0_SB_CB<1>")
	)
	(segment
		(start 311.50814 -276.687534)
		(end 311.572656 -276.75205)
		(width 0.10668)
		(layer "F.Cu")
		(net "M_A_CPU0_SB_CB<1>")
	)
	(segment
		(start 313.765692 -274.429982)
		(end 313.830208 -274.494498)
		(width 0.10668)
		(layer "F.Cu")
		(net "M_A_CPU0_SB_CB<1>")
	)
	(segment
		(start 309.532782 -278.663146)
		(end 309.381906 -278.663146)
		(width 0.10668)
		(layer "F.Cu")
		(net "M_A_CPU0_SB_CB<1>")
	)
	(segment
		(start 309.03291 -279.29205)
		(end 308.968394 -279.227534)
		(width 0.10668)
		(layer "F.Cu")
		(net "M_A_CPU0_SB_CB<1>")
	)
	(segment
		(start 311.008268 -277.316438)
		(end 311.008268 -277.467314)
		(width 0.10668)
		(layer "F.Cu")
		(net "M_A_CPU0_SB_CB<1>")
	)
	(segment
		(start 310.312562 -278.16302)
		(end 310.161686 -278.163274)
		(width 0.10668)
		(layer "F.Cu")
		(net "M_A_CPU0_SB_CB<1>")
	)
	(segment
		(start 326.835008 -273.332702)
		(end 326.826626 -273.337528)
		(width 0.0762)
		(layer "F.Cu")
		(net "M_A_CPU0_SB_CB<1>")
	)
	(segment
		(start 313.483498 -274.71243)
		(end 313.332622 -274.71243)
		(width 0.10668)
		(layer "F.Cu")
		(net "M_A_CPU0_SB_CB<1>")
	)
	(segment
		(start 314.112402 -274.212558)
		(end 314.047886 -274.148042)
		(width 0.10668)
		(layer "F.Cu")
		(net "M_A_CPU0_SB_CB<1>")
	)
	(segment
		(start 314.67679 -273.64817)
		(end 314.612274 -273.583654)
		(width 0.10668)
		(layer "F.Cu")
		(net "M_A_CPU0_SB_CB<1>")
	)
	(segment
		(start 309.315104 -279.160478)
		(end 309.183786 -279.291796)
		(width 0.10668)
		(layer "F.Cu")
		(net "M_A_CPU0_SB_CB<1>")
	)
	(segment
		(start 313.201304 -274.99437)
		(end 313.26582 -275.058886)
		(width 0.10668)
		(layer "F.Cu")
		(net "M_A_CPU0_SB_CB<1>")
	)
	(segment
		(start 310.37911 -277.665942)
		(end 310.379364 -277.81631)
		(width 0.10668)
		(layer "F.Cu")
		(net "M_A_CPU0_SB_CB<1>")
	)
	(segment
		(start 313.548014 -274.776946)
		(end 313.483498 -274.71243)
		(width 0.10668)
		(layer "F.Cu")
		(net "M_A_CPU0_SB_CB<1>")
	)
	(segment
		(start 311.225946 -276.969982)
		(end 311.07507 -276.969982)
		(width 0.10668)
		(layer "F.Cu")
		(net "M_A_CPU0_SB_CB<1>")
	)
	(segment
		(start 313.26582 -275.209762)
		(end 313.134502 -275.34108)
		(width 0.10668)
		(layer "F.Cu")
		(net "M_A_CPU0_SB_CB<1>")
	)
	(segment
		(start 313.332622 -274.71243)
		(end 313.20105 -274.844002)
		(width 0.10668)
		(layer "F.Cu")
		(net "M_A_CPU0_SB_CB<1>")
	)
	(segment
		(start 311.507886 -276.537166)
		(end 311.50814 -276.687534)
		(width 0.10668)
		(layer "F.Cu")
		(net "M_A_CPU0_SB_CB<1>")
	)
	(segment
		(start 314.894468 -273.301206)
		(end 314.958984 -273.365722)
		(width 0.10668)
		(layer "F.Cu")
		(net "M_A_CPU0_SB_CB<1>")
	)
	(segment
		(start 314.394596 -273.93011)
		(end 314.394596 -274.080986)
		(width 0.10668)
		(layer "F.Cu")
		(net "M_A_CPU0_SB_CB<1>")
	)
	(segment
		(start 312.701432 -275.623274)
		(end 312.701432 -275.77415)
		(width 0.10668)
		(layer "F.Cu")
		(net "M_A_CPU0_SB_CB<1>")
	)
	(segment
		(start 310.510682 -277.53437)
		(end 310.37911 -277.665942)
		(width 0.10668)
		(layer "F.Cu")
		(net "M_A_CPU0_SB_CB<1>")
	)
	(segment
		(start 309.250334 -278.794718)
		(end 309.250588 -278.945086)
		(width 0.10668)
		(layer "F.Cu")
		(net "M_A_CPU0_SB_CB<1>")
	)
	(segment
		(start 312.636662 -275.40839)
		(end 312.636916 -275.558758)
		(width 0.10668)
		(layer "F.Cu")
		(net "M_A_CPU0_SB_CB<1>")
	)
	(segment
		(start 314.33008 -273.865594)
		(end 314.394596 -273.93011)
		(width 0.10668)
		(layer "F.Cu")
		(net "M_A_CPU0_SB_CB<1>")
	)
	(segment
		(start 311.572656 -276.902926)
		(end 311.441338 -277.034244)
		(width 0.10668)
		(layer "F.Cu")
		(net "M_A_CPU0_SB_CB<1>")
	)
	(segment
		(start 308.259988 -279.785064)
		(end 307.368194 -279.785064)
		(width 0.10668)
		(layer "F.Cu")
		(net "M_A_CPU0_SB_CB<1>")
	)
	(segment
		(start 310.44388 -277.880826)
		(end 310.44388 -278.031702)
		(width 0.10668)
		(layer "F.Cu")
		(net "M_A_CPU0_SB_CB<1>")
	)
	(segment
		(start 309.748174 -278.727408)
		(end 309.597298 -278.727662)
		(width 0.10668)
		(layer "F.Cu")
		(net "M_A_CPU0_SB_CB<1>")
	)
	(segment
		(start 310.87695 -277.598632)
		(end 310.726074 -277.598886)
		(width 0.10668)
		(layer "F.Cu")
		(net "M_A_CPU0_SB_CB<1>")
	)
	(segment
		(start 314.263278 -274.212304)
		(end 314.112402 -274.212558)
		(width 0.10668)
		(layer "F.Cu")
		(net "M_A_CPU0_SB_CB<1>")
	)
	(segment
		(start 314.047886 -274.148042)
		(end 313.89701 -274.148042)
		(width 0.10668)
		(layer "F.Cu")
		(net "M_A_CPU0_SB_CB<1>")
	)
	(segment
		(start 309.814722 -278.23033)
		(end 309.814976 -278.380698)
		(width 0.10668)
		(layer "F.Cu")
		(net "M_A_CPU0_SB_CB<1>")
	)
	(segment
		(start 327.587864 -273.010122)
		(end 327.688702 -273.183604)
		(width 0.0762)
		(layer "F.Cu")
		(net "M_A_CPU0_SB_CB<1>")
	)
	(segment
		(start 314.894214 -273.150838)
		(end 314.894468 -273.301206)
		(width 0.10668)
		(layer "F.Cu")
		(net "M_A_CPU0_SB_CB<1>")
	)
	(segment
		(start 310.379364 -277.81631)
		(end 310.44388 -277.880826)
		(width 0.10668)
		(layer "F.Cu")
		(net "M_A_CPU0_SB_CB<1>")
	)
	(segment
		(start 313.830208 -274.494498)
		(end 313.830208 -274.645374)
		(width 0.10668)
		(layer "F.Cu")
		(net "M_A_CPU0_SB_CB<1>")
	)
	(segment
		(start 309.879492 -278.59609)
		(end 309.748174 -278.727408)
		(width 0.10668)
		(layer "F.Cu")
		(net "M_A_CPU0_SB_CB<1>")
	)
	(segment
		(start 311.790334 -276.405594)
		(end 311.639458 -276.405594)
		(width 0.10668)
		(layer "F.Cu")
		(net "M_A_CPU0_SB_CB<1>")
	)
	(segment
		(start 312.768234 -275.276818)
		(end 312.636662 -275.40839)
		(width 0.10668)
		(layer "F.Cu")
		(net "M_A_CPU0_SB_CB<1>")
	)
	(segment
		(start 310.161686 -278.163274)
		(end 310.09717 -278.098758)
		(width 0.10668)
		(layer "F.Cu")
		(net "M_A_CPU0_SB_CB<1>")
	)
	(segment
		(start 313.765438 -274.279614)
		(end 313.765692 -274.429982)
		(width 0.10668)
		(layer "F.Cu")
		(net "M_A_CPU0_SB_CB<1>")
	)
	(arc
		(start 325.894954 -273.332702)
		(mid 325.819714 -273.366015)
		(end 325.738998 -273.381978)
		(width 0.0762)
		(layer "F.Cu")
		(net "M_A_CPU0_SB_CB<1>")
	)
	(arc
		(start 326.826626 -273.337528)
		(mid 326.643118 -273.383022)
		(end 326.460866 -273.332702)
		(width 0.0762)
		(layer "F.Cu")
		(net "M_A_CPU0_SB_CB<1>")
	)
	(arc
		(start 327.688702 -273.183604)
		(mid 327.672777 -273.324296)
		(end 327.542652 -273.3802)
		(width 0.0762)
		(layer "F.Cu")
		(net "M_A_CPU0_SB_CB<1>")
	)
	(arc
		(start 326.460866 -273.332702)
		(mid 326.17791 -273.256525)
		(end 325.894954 -273.332702)
		(width 0.0762)
		(layer "F.Cu")
		(net "M_A_CPU0_SB_CB<1>")
	)
	(arc
		(start 327.542652 -273.3802)
		(mid 327.473954 -273.365184)
		(end 327.409302 -273.337528)
		(width 0.0762)
		(layer "F.Cu")
		(net "M_A_CPU0_SB_CB<1>")
	)
	(arc
		(start 325.738998 -273.381978)
		(mid 325.723517 -273.382934)
		(end 325.70801 -273.383248)
		(width 0.0762)
		(layer "F.Cu")
		(net "M_A_CPU0_SB_CB<1>")
	)
	(arc
		(start 327.40092 -273.332702)
		(mid 327.117964 -273.256525)
		(end 326.835008 -273.332702)
		(width 0.0762)
		(layer "F.Cu")
		(net "M_A_CPU0_SB_CB<1>")
	)
	(segment
		(start 324.986396 -272.24863)
		(end 323.92112 -272.24863)
		(width 0.0762)
		(layer "F.Cu")
		(net "M_A_CPU0_SB_CB<0>")
	)
	(segment
		(start 320.488564 -272.221452)
		(end 320.30289 -272.221452)
		(width 0.10668)
		(layer "F.Cu")
		(net "M_A_CPU0_SB_CB<0>")
	)
	(segment
		(start 320.30289 -272.221452)
		(end 320.19621 -272.114772)
		(width 0.10668)
		(layer "F.Cu")
		(net "M_A_CPU0_SB_CB<0>")
	)
	(segment
		(start 319.903856 -271.595342)
		(end 319.797176 -271.702022)
		(width 0.10668)
		(layer "F.Cu")
		(net "M_A_CPU0_SB_CB<0>")
	)
	(segment
		(start 321.393312 -272.114772)
		(end 321.286632 -272.221452)
		(width 0.10668)
		(layer "F.Cu")
		(net "M_A_CPU0_SB_CB<0>")
	)
	(segment
		(start 318.493394 -271.595342)
		(end 318.30772 -271.595342)
		(width 0.10668)
		(layer "F.Cu")
		(net "M_A_CPU0_SB_CB<0>")
	)
	(segment
		(start 320.19621 -272.114772)
		(end 320.19621 -271.702022)
		(width 0.10668)
		(layer "F.Cu")
		(net "M_A_CPU0_SB_CB<0>")
	)
	(segment
		(start 319.398142 -272.114772)
		(end 319.398142 -271.702022)
		(width 0.10668)
		(layer "F.Cu")
		(net "M_A_CPU0_SB_CB<0>")
	)
	(segment
		(start 320.994278 -271.702022)
		(end 320.887598 -271.595342)
		(width 0.10668)
		(layer "F.Cu")
		(net "M_A_CPU0_SB_CB<0>")
	)
	(segment
		(start 320.701924 -271.595342)
		(end 320.595244 -271.702022)
		(width 0.10668)
		(layer "F.Cu")
		(net "M_A_CPU0_SB_CB<0>")
	)
	(segment
		(start 325.184262 -272.446496)
		(end 324.986396 -272.24863)
		(width 0.0762)
		(layer "F.Cu")
		(net "M_A_CPU0_SB_CB<0>")
	)
	(segment
		(start 317.908686 -272.221452)
		(end 317.802006 -272.114772)
		(width 0.10668)
		(layer "F.Cu")
		(net "M_A_CPU0_SB_CB<0>")
	)
	(segment
		(start 308.996842 -278.085042)
		(end 307.368194 -278.085042)
		(width 0.10668)
		(layer "F.Cu")
		(net "M_A_CPU0_SB_CB<0>")
	)
	(segment
		(start 319.105788 -271.595342)
		(end 318.999108 -271.702022)
		(width 0.10668)
		(layer "F.Cu")
		(net "M_A_CPU0_SB_CB<0>")
	)
	(segment
		(start 317.802006 -271.702022)
		(end 317.695326 -271.595342)
		(width 0.10668)
		(layer "F.Cu")
		(net "M_A_CPU0_SB_CB<0>")
	)
	(segment
		(start 321.100958 -272.221452)
		(end 320.994278 -272.114772)
		(width 0.10668)
		(layer "F.Cu")
		(net "M_A_CPU0_SB_CB<0>")
	)
	(segment
		(start 319.797176 -271.702022)
		(end 319.797176 -272.114772)
		(width 0.10668)
		(layer "F.Cu")
		(net "M_A_CPU0_SB_CB<0>")
	)
	(segment
		(start 319.504822 -272.221452)
		(end 319.398142 -272.114772)
		(width 0.10668)
		(layer "F.Cu")
		(net "M_A_CPU0_SB_CB<0>")
	)
	(segment
		(start 321.286632 -272.221452)
		(end 321.100958 -272.221452)
		(width 0.10668)
		(layer "F.Cu")
		(net "M_A_CPU0_SB_CB<0>")
	)
	(segment
		(start 320.19621 -271.702022)
		(end 320.08953 -271.595342)
		(width 0.10668)
		(layer "F.Cu")
		(net "M_A_CPU0_SB_CB<0>")
	)
	(segment
		(start 320.994278 -272.114772)
		(end 320.994278 -271.702022)
		(width 0.10668)
		(layer "F.Cu")
		(net "M_A_CPU0_SB_CB<0>")
	)
	(segment
		(start 320.595244 -272.114772)
		(end 320.488564 -272.221452)
		(width 0.10668)
		(layer "F.Cu")
		(net "M_A_CPU0_SB_CB<0>")
	)
	(segment
		(start 319.797176 -272.114772)
		(end 319.690496 -272.221452)
		(width 0.10668)
		(layer "F.Cu")
		(net "M_A_CPU0_SB_CB<0>")
	)
	(segment
		(start 318.20104 -271.702022)
		(end 318.20104 -272.114772)
		(width 0.10668)
		(layer "F.Cu")
		(net "M_A_CPU0_SB_CB<0>")
	)
	(segment
		(start 320.08953 -271.595342)
		(end 319.903856 -271.595342)
		(width 0.10668)
		(layer "F.Cu")
		(net "M_A_CPU0_SB_CB<0>")
	)
	(segment
		(start 318.600074 -271.702022)
		(end 318.493394 -271.595342)
		(width 0.10668)
		(layer "F.Cu")
		(net "M_A_CPU0_SB_CB<0>")
	)
	(segment
		(start 318.09436 -272.221452)
		(end 317.908686 -272.221452)
		(width 0.10668)
		(layer "F.Cu")
		(net "M_A_CPU0_SB_CB<0>")
	)
	(segment
		(start 320.595244 -271.702022)
		(end 320.595244 -272.114772)
		(width 0.10668)
		(layer "F.Cu")
		(net "M_A_CPU0_SB_CB<0>")
	)
	(segment
		(start 318.30772 -271.595342)
		(end 318.20104 -271.702022)
		(width 0.10668)
		(layer "F.Cu")
		(net "M_A_CPU0_SB_CB<0>")
	)
	(segment
		(start 317.802006 -272.114772)
		(end 317.802006 -271.702022)
		(width 0.10668)
		(layer "F.Cu")
		(net "M_A_CPU0_SB_CB<0>")
	)
	(segment
		(start 318.706754 -272.221452)
		(end 318.600074 -272.114772)
		(width 0.10668)
		(layer "F.Cu")
		(net "M_A_CPU0_SB_CB<0>")
	)
	(segment
		(start 315.486542 -271.595342)
		(end 308.996842 -278.085042)
		(width 0.10668)
		(layer "F.Cu")
		(net "M_A_CPU0_SB_CB<0>")
	)
	(segment
		(start 326.17791 -272.200116)
		(end 326.276208 -272.36928)
		(width 0.0762)
		(layer "F.Cu")
		(net "M_A_CPU0_SB_CB<0>")
	)
	(segment
		(start 321.499992 -271.595342)
		(end 321.393312 -271.702022)
		(width 0.10668)
		(layer "F.Cu")
		(net "M_A_CPU0_SB_CB<0>")
	)
	(segment
		(start 322.405502 -272.24863)
		(end 321.752214 -271.595342)
		(width 0.10668)
		(layer "F.Cu")
		(net "M_A_CPU0_SB_CB<0>")
	)
	(segment
		(start 319.398142 -271.702022)
		(end 319.291462 -271.595342)
		(width 0.10668)
		(layer "F.Cu")
		(net "M_A_CPU0_SB_CB<0>")
	)
	(segment
		(start 318.20104 -272.114772)
		(end 318.09436 -272.221452)
		(width 0.10668)
		(layer "F.Cu")
		(net "M_A_CPU0_SB_CB<0>")
	)
	(segment
		(start 325.999348 -272.527522)
		(end 325.990966 -272.522696)
		(width 0.0762)
		(layer "F.Cu")
		(net "M_A_CPU0_SB_CB<0>")
	)
	(segment
		(start 319.291462 -271.595342)
		(end 319.105788 -271.595342)
		(width 0.10668)
		(layer "F.Cu")
		(net "M_A_CPU0_SB_CB<0>")
	)
	(segment
		(start 320.887598 -271.595342)
		(end 320.701924 -271.595342)
		(width 0.10668)
		(layer "F.Cu")
		(net "M_A_CPU0_SB_CB<0>")
	)
	(segment
		(start 323.92112 -272.24863)
		(end 322.405502 -272.24863)
		(width 0.10668)
		(layer "F.Cu")
		(net "M_A_CPU0_SB_CB<0>")
	)
	(segment
		(start 321.752214 -271.595342)
		(end 321.499992 -271.595342)
		(width 0.10668)
		(layer "F.Cu")
		(net "M_A_CPU0_SB_CB<0>")
	)
	(segment
		(start 317.695326 -271.595342)
		(end 315.486542 -271.595342)
		(width 0.10668)
		(layer "F.Cu")
		(net "M_A_CPU0_SB_CB<0>")
	)
	(segment
		(start 321.393312 -271.702022)
		(end 321.393312 -272.114772)
		(width 0.10668)
		(layer "F.Cu")
		(net "M_A_CPU0_SB_CB<0>")
	)
	(segment
		(start 318.999108 -271.702022)
		(end 318.999108 -272.114772)
		(width 0.10668)
		(layer "F.Cu")
		(net "M_A_CPU0_SB_CB<0>")
	)
	(segment
		(start 318.600074 -272.114772)
		(end 318.600074 -271.702022)
		(width 0.10668)
		(layer "F.Cu")
		(net "M_A_CPU0_SB_CB<0>")
	)
	(segment
		(start 319.690496 -272.221452)
		(end 319.504822 -272.221452)
		(width 0.10668)
		(layer "F.Cu")
		(net "M_A_CPU0_SB_CB<0>")
	)
	(segment
		(start 318.999108 -272.114772)
		(end 318.892428 -272.221452)
		(width 0.10668)
		(layer "F.Cu")
		(net "M_A_CPU0_SB_CB<0>")
	)
	(segment
		(start 325.70801 -272.446496)
		(end 325.184262 -272.446496)
		(width 0.0762)
		(layer "F.Cu")
		(net "M_A_CPU0_SB_CB<0>")
	)
	(segment
		(start 318.892428 -272.221452)
		(end 318.706754 -272.221452)
		(width 0.10668)
		(layer "F.Cu")
		(net "M_A_CPU0_SB_CB<0>")
	)
	(arc
		(start 326.13854 -272.570956)
		(mid 326.066802 -272.556104)
		(end 325.999348 -272.527522)
		(width 0.0762)
		(layer "F.Cu")
		(net "M_A_CPU0_SB_CB<0>")
	)
	(arc
		(start 326.276208 -272.36928)
		(mid 326.267615 -272.511159)
		(end 326.13854 -272.570956)
		(width 0.0762)
		(layer "F.Cu")
		(net "M_A_CPU0_SB_CB<0>")
	)
	(arc
		(start 325.990966 -272.522696)
		(mid 325.85453 -272.465871)
		(end 325.70801 -272.446496)
		(width 0.0762)
		(layer "F.Cu")
		(net "M_A_CPU0_SB_CB<0>")
	)
	(segment
		(start 309.360316 -265.939778)
		(end 309.360316 -265.37539)
		(width 0.10668)
		(layer "F.Cu")
		(net "M_A_CPU0_SB_CA<6>")
	)
	(segment
		(start 321.33921 -264.104882)
		(end 320.682874 -264.761218)
		(width 0.10668)
		(layer "F.Cu")
		(net "M_A_CPU0_SB_CA<6>")
	)
	(segment
		(start 311.91962 -265.25855)
		(end 309.87619 -265.25855)
		(width 0.10668)
		(layer "F.Cu")
		(net "M_A_CPU0_SB_CA<6>")
	)
	(segment
		(start 309.360316 -265.37539)
		(end 309.243476 -265.25855)
		(width 0.10668)
		(layer "F.Cu")
		(net "M_A_CPU0_SB_CA<6>")
	)
	(segment
		(start 309.87619 -265.25855)
		(end 309.75935 -265.37539)
		(width 0.10668)
		(layer "F.Cu")
		(net "M_A_CPU0_SB_CA<6>")
	)
	(segment
		(start 324.444106 -264.104882)
		(end 324.096634 -264.104882)
		(width 0.0762)
		(layer "F.Cu")
		(net "M_A_CPU0_SB_CA<6>")
	)
	(segment
		(start 325.999348 -264.427462)
		(end 325.990966 -264.422636)
		(width 0.0762)
		(layer "F.Cu")
		(net "M_A_CPU0_SB_CA<6>")
	)
	(segment
		(start 309.243476 -265.25855)
		(end 308.691026 -265.25855)
		(width 0.10668)
		(layer "F.Cu")
		(net "M_A_CPU0_SB_CA<6>")
	)
	(segment
		(start 311.668414 -265.774424)
		(end 311.668414 -265.939778)
		(width 0.10668)
		(layer "F.Cu")
		(net "M_A_CPU0_SB_CA<6>")
	)
	(segment
		(start 324.68566 -264.346436)
		(end 324.444106 -264.104882)
		(width 0.0762)
		(layer "F.Cu")
		(net "M_A_CPU0_SB_CA<6>")
	)
	(segment
		(start 309.75935 -265.540744)
		(end 309.87619 -265.657584)
		(width 0.10668)
		(layer "F.Cu")
		(net "M_A_CPU0_SB_CA<6>")
	)
	(segment
		(start 308.691026 -265.25855)
		(end 307.764434 -266.185142)
		(width 0.10668)
		(layer "F.Cu")
		(net "M_A_CPU0_SB_CA<6>")
	)
	(segment
		(start 325.70801 -264.346436)
		(end 324.68566 -264.346436)
		(width 0.0762)
		(layer "F.Cu")
		(net "M_A_CPU0_SB_CA<6>")
	)
	(segment
		(start 309.477156 -266.056618)
		(end 309.360316 -265.939778)
		(width 0.10668)
		(layer "F.Cu")
		(net "M_A_CPU0_SB_CA<6>")
	)
	(segment
		(start 312.416952 -264.761218)
		(end 311.91962 -265.25855)
		(width 0.10668)
		(layer "F.Cu")
		(net "M_A_CPU0_SB_CA<6>")
	)
	(segment
		(start 309.75935 -265.37539)
		(end 309.75935 -265.540744)
		(width 0.10668)
		(layer "F.Cu")
		(net "M_A_CPU0_SB_CA<6>")
	)
	(segment
		(start 307.764434 -266.185142)
		(end 307.368194 -266.185142)
		(width 0.10668)
		(layer "F.Cu")
		(net "M_A_CPU0_SB_CA<6>")
	)
	(segment
		(start 311.668414 -265.939778)
		(end 311.551574 -266.056618)
		(width 0.10668)
		(layer "F.Cu")
		(net "M_A_CPU0_SB_CA<6>")
	)
	(segment
		(start 324.096634 -264.104882)
		(end 321.33921 -264.104882)
		(width 0.10668)
		(layer "F.Cu")
		(net "M_A_CPU0_SB_CA<6>")
	)
	(segment
		(start 320.682874 -264.761218)
		(end 312.416952 -264.761218)
		(width 0.10668)
		(layer "F.Cu")
		(net "M_A_CPU0_SB_CA<6>")
	)
	(segment
		(start 326.17791 -264.100056)
		(end 326.276208 -264.26922)
		(width 0.0762)
		(layer "F.Cu")
		(net "M_A_CPU0_SB_CA<6>")
	)
	(segment
		(start 311.551574 -266.056618)
		(end 309.477156 -266.056618)
		(width 0.10668)
		(layer "F.Cu")
		(net "M_A_CPU0_SB_CA<6>")
	)
	(segment
		(start 309.87619 -265.657584)
		(end 311.551574 -265.657584)
		(width 0.10668)
		(layer "F.Cu")
		(net "M_A_CPU0_SB_CA<6>")
	)
	(segment
		(start 311.551574 -265.657584)
		(end 311.668414 -265.774424)
		(width 0.10668)
		(layer "F.Cu")
		(net "M_A_CPU0_SB_CA<6>")
	)
	(arc
		(start 326.276208 -264.26922)
		(mid 326.267615 -264.411099)
		(end 326.13854 -264.470896)
		(width 0.0762)
		(layer "F.Cu")
		(net "M_A_CPU0_SB_CA<6>")
	)
	(arc
		(start 325.990966 -264.422636)
		(mid 325.85453 -264.365811)
		(end 325.70801 -264.346436)
		(width 0.0762)
		(layer "F.Cu")
		(net "M_A_CPU0_SB_CA<6>")
	)
	(arc
		(start 326.13854 -264.470896)
		(mid 326.066802 -264.456044)
		(end 325.999348 -264.427462)
		(width 0.0762)
		(layer "F.Cu")
		(net "M_A_CPU0_SB_CA<6>")
	)
	(segment
		(start 311.786524 -264.910062)
		(end 308.610508 -264.910062)
		(width 0.10668)
		(layer "F.Cu")
		(net "M_A_CPU0_SB_CA<5>")
	)
	(segment
		(start 325.539354 -263.92759)
		(end 324.698614 -263.92759)
		(width 0.0762)
		(layer "F.Cu")
		(net "M_A_CPU0_SB_CA<5>")
	)
	(segment
		(start 312.275728 -264.420858)
		(end 311.786524 -264.910062)
		(width 0.10668)
		(layer "F.Cu")
		(net "M_A_CPU0_SB_CA<5>")
	)
	(segment
		(start 320.54165 -264.420858)
		(end 312.275728 -264.420858)
		(width 0.10668)
		(layer "F.Cu")
		(net "M_A_CPU0_SB_CA<5>")
	)
	(segment
		(start 324.698614 -263.92759)
		(end 324.535546 -263.764522)
		(width 0.0762)
		(layer "F.Cu")
		(net "M_A_CPU0_SB_CA<5>")
	)
	(segment
		(start 324.535546 -263.764522)
		(end 324.038214 -263.764522)
		(width 0.0762)
		(layer "F.Cu")
		(net "M_A_CPU0_SB_CA<5>")
	)
	(segment
		(start 308.610508 -264.910062)
		(end 306.070508 -264.910062)
		(width 0.101346)
		(layer "F.Cu")
		(net "M_A_CPU0_SB_CA<5>")
	)
	(segment
		(start 321.197986 -263.764522)
		(end 320.54165 -264.420858)
		(width 0.10668)
		(layer "F.Cu")
		(net "M_A_CPU0_SB_CA<5>")
	)
	(segment
		(start 306.070508 -264.910062)
		(end 305.645566 -265.335004)
		(width 0.101346)
		(layer "F.Cu")
		(net "M_A_CPU0_SB_CA<5>")
	)
	(segment
		(start 325.613268 -263.853676)
		(end 325.539354 -263.92759)
		(width 0.0762)
		(layer "F.Cu")
		(net "M_A_CPU0_SB_CA<5>")
	)
	(segment
		(start 324.038214 -263.764522)
		(end 321.197986 -263.764522)
		(width 0.10668)
		(layer "F.Cu")
		(net "M_A_CPU0_SB_CA<5>")
	)
	(segment
		(start 325.999348 -263.77265)
		(end 325.990966 -263.777476)
		(width 0.0762)
		(layer "F.Cu")
		(net "M_A_CPU0_SB_CA<5>")
	)
	(segment
		(start 325.708264 -263.853676)
		(end 325.613268 -263.853676)
		(width 0.0762)
		(layer "F.Cu")
		(net "M_A_CPU0_SB_CA<5>")
	)
	(segment
		(start 305.645566 -265.335004)
		(end 303.268126 -265.335004)
		(width 0.101346)
		(layer "F.Cu")
		(net "M_A_CPU0_SB_CA<5>")
	)
	(arc
		(start 326.365108 -263.777476)
		(mid 326.182857 -263.727126)
		(end 325.999348 -263.77265)
		(width 0.0762)
		(layer "F.Cu")
		(net "M_A_CPU0_SB_CA<5>")
	)
	(arc
		(start 325.990966 -263.777476)
		(mid 325.877242 -263.827777)
		(end 325.755254 -263.851898)
		(width 0.0762)
		(layer "F.Cu")
		(net "M_A_CPU0_SB_CA<5>")
	)
	(arc
		(start 327.601834 -263.853676)
		(mid 327.448085 -263.836167)
		(end 327.304908 -263.777476)
		(width 0.0762)
		(layer "F.Cu")
		(net "M_A_CPU0_SB_CA<5>")
	)
	(arc
		(start 328.058018 -264.100056)
		(mid 327.862669 -263.916237)
		(end 327.601834 -263.853676)
		(width 0.0762)
		(layer "F.Cu")
		(net "M_A_CPU0_SB_CA<5>")
	)
	(arc
		(start 326.93102 -263.777476)
		(mid 326.648064 -263.853653)
		(end 326.365108 -263.777476)
		(width 0.0762)
		(layer "F.Cu")
		(net "M_A_CPU0_SB_CA<5>")
	)
	(arc
		(start 327.304908 -263.777476)
		(mid 327.117964 -263.727221)
		(end 326.93102 -263.777476)
		(width 0.0762)
		(layer "F.Cu")
		(net "M_A_CPU0_SB_CA<5>")
	)
	(arc
		(start 325.755254 -263.851898)
		(mid 325.731777 -263.853274)
		(end 325.708264 -263.853676)
		(width 0.0762)
		(layer "F.Cu")
		(net "M_A_CPU0_SB_CA<5>")
	)
	(segment
		(start 327.409302 -263.617456)
		(end 327.40092 -263.61263)
		(width 0.0762)
		(layer "F.Cu")
		(net "M_A_CPU0_SB_CA<4>")
	)
	(segment
		(start 309.389018 -263.67867)
		(end 309.272178 -263.56183)
		(width 0.10668)
		(layer "F.Cu")
		(net "M_A_CPU0_SB_CA<4>")
	)
	(segment
		(start 315.30925 -264.080498)
		(end 314.790582 -263.56183)
		(width 0.10668)
		(layer "F.Cu")
		(net "M_A_CPU0_SB_CA<4>")
	)
	(segment
		(start 309.505858 -264.359898)
		(end 309.389018 -264.243058)
		(width 0.10668)
		(layer "F.Cu")
		(net "M_A_CPU0_SB_CA<4>")
	)
	(segment
		(start 327.587864 -263.29005)
		(end 327.696322 -263.47674)
		(width 0.0762)
		(layer "F.Cu")
		(net "M_A_CPU0_SB_CA<4>")
	)
	(segment
		(start 311.528714 -264.243058)
		(end 311.411874 -264.359898)
		(width 0.10668)
		(layer "F.Cu")
		(net "M_A_CPU0_SB_CA<4>")
	)
	(segment
		(start 308.78526 -263.56183)
		(end 307.86197 -264.48512)
		(width 0.10668)
		(layer "F.Cu")
		(net "M_A_CPU0_SB_CA<4>")
	)
	(segment
		(start 309.389018 -264.243058)
		(end 309.389018 -263.67867)
		(width 0.10668)
		(layer "F.Cu")
		(net "M_A_CPU0_SB_CA<4>")
	)
	(segment
		(start 311.411874 -264.359898)
		(end 309.505858 -264.359898)
		(width 0.10668)
		(layer "F.Cu")
		(net "M_A_CPU0_SB_CA<4>")
	)
	(segment
		(start 309.904892 -263.960864)
		(end 311.411874 -263.960864)
		(width 0.10668)
		(layer "F.Cu")
		(net "M_A_CPU0_SB_CA<4>")
	)
	(segment
		(start 320.400426 -264.080498)
		(end 315.30925 -264.080498)
		(width 0.10668)
		(layer "F.Cu")
		(net "M_A_CPU0_SB_CA<4>")
	)
	(segment
		(start 309.272178 -263.56183)
		(end 308.78526 -263.56183)
		(width 0.10668)
		(layer "F.Cu")
		(net "M_A_CPU0_SB_CA<4>")
	)
	(segment
		(start 309.788052 -263.67867)
		(end 309.788052 -263.844024)
		(width 0.10668)
		(layer "F.Cu")
		(net "M_A_CPU0_SB_CA<4>")
	)
	(segment
		(start 309.904892 -263.56183)
		(end 309.788052 -263.67867)
		(width 0.10668)
		(layer "F.Cu")
		(net "M_A_CPU0_SB_CA<4>")
	)
	(segment
		(start 325.70801 -263.663176)
		(end 324.85584 -263.663176)
		(width 0.0762)
		(layer "F.Cu")
		(net "M_A_CPU0_SB_CA<4>")
	)
	(segment
		(start 314.790582 -263.56183)
		(end 309.904892 -263.56183)
		(width 0.10668)
		(layer "F.Cu")
		(net "M_A_CPU0_SB_CA<4>")
	)
	(segment
		(start 324.616826 -263.424162)
		(end 324.038214 -263.424162)
		(width 0.0762)
		(layer "F.Cu")
		(net "M_A_CPU0_SB_CA<4>")
	)
	(segment
		(start 307.86197 -264.48512)
		(end 307.368194 -264.48512)
		(width 0.10668)
		(layer "F.Cu")
		(net "M_A_CPU0_SB_CA<4>")
	)
	(segment
		(start 309.788052 -263.844024)
		(end 309.904892 -263.960864)
		(width 0.10668)
		(layer "F.Cu")
		(net "M_A_CPU0_SB_CA<4>")
	)
	(segment
		(start 321.056762 -263.424162)
		(end 320.400426 -264.080498)
		(width 0.10668)
		(layer "F.Cu")
		(net "M_A_CPU0_SB_CA<4>")
	)
	(segment
		(start 324.038214 -263.424162)
		(end 321.056762 -263.424162)
		(width 0.10668)
		(layer "F.Cu")
		(net "M_A_CPU0_SB_CA<4>")
	)
	(segment
		(start 324.85584 -263.663176)
		(end 324.616826 -263.424162)
		(width 0.0762)
		(layer "F.Cu")
		(net "M_A_CPU0_SB_CA<4>")
	)
	(segment
		(start 311.528714 -264.077704)
		(end 311.528714 -264.243058)
		(width 0.10668)
		(layer "F.Cu")
		(net "M_A_CPU0_SB_CA<4>")
	)
	(segment
		(start 311.411874 -263.960864)
		(end 311.528714 -264.077704)
		(width 0.10668)
		(layer "F.Cu")
		(net "M_A_CPU0_SB_CA<4>")
	)
	(segment
		(start 326.835008 -263.61263)
		(end 326.826626 -263.617456)
		(width 0.0762)
		(layer "F.Cu")
		(net "M_A_CPU0_SB_CA<4>")
	)
	(arc
		(start 327.40092 -263.61263)
		(mid 327.117964 -263.536453)
		(end 326.835008 -263.61263)
		(width 0.0762)
		(layer "F.Cu")
		(net "M_A_CPU0_SB_CA<4>")
	)
	(arc
		(start 327.544684 -263.660382)
		(mid 327.47493 -263.645425)
		(end 327.409302 -263.617456)
		(width 0.0762)
		(layer "F.Cu")
		(net "M_A_CPU0_SB_CA<4>")
	)
	(arc
		(start 326.460866 -263.61263)
		(mid 326.17791 -263.536453)
		(end 325.894954 -263.61263)
		(width 0.0762)
		(layer "F.Cu")
		(net "M_A_CPU0_SB_CA<4>")
	)
	(arc
		(start 325.894954 -263.61263)
		(mid 325.804821 -263.65025)
		(end 325.70801 -263.663176)
		(width 0.0762)
		(layer "F.Cu")
		(net "M_A_CPU0_SB_CA<4>")
	)
	(arc
		(start 326.826626 -263.617456)
		(mid 326.643118 -263.66295)
		(end 326.460866 -263.61263)
		(width 0.0762)
		(layer "F.Cu")
		(net "M_A_CPU0_SB_CA<4>")
	)
	(arc
		(start 327.696322 -263.47674)
		(mid 327.670405 -263.609782)
		(end 327.544684 -263.660382)
		(width 0.0762)
		(layer "F.Cu")
		(net "M_A_CPU0_SB_CA<4>")
	)
	(segment
		(start 320.259202 -263.740138)
		(end 315.450474 -263.740138)
		(width 0.10668)
		(layer "F.Cu")
		(net "M_A_CPU0_SB_CA<3>")
	)
	(segment
		(start 308.610508 -263.21004)
		(end 306.070508 -263.21004)
		(width 0.101346)
		(layer "F.Cu")
		(net "M_A_CPU0_SB_CA<3>")
	)
	(segment
		(start 314.920376 -263.21004)
		(end 308.610508 -263.21004)
		(width 0.10668)
		(layer "F.Cu")
		(net "M_A_CPU0_SB_CA<3>")
	)
	(segment
		(start 324.72376 -262.916924)
		(end 324.556882 -263.083802)
		(width 0.0762)
		(layer "F.Cu")
		(net "M_A_CPU0_SB_CA<3>")
	)
	(segment
		(start 305.645566 -263.634982)
		(end 303.268126 -263.634982)
		(width 0.101346)
		(layer "F.Cu")
		(net "M_A_CPU0_SB_CA<3>")
	)
	(segment
		(start 320.915538 -263.083802)
		(end 320.259202 -263.740138)
		(width 0.10668)
		(layer "F.Cu")
		(net "M_A_CPU0_SB_CA<3>")
	)
	(segment
		(start 306.070508 -263.21004)
		(end 305.645566 -263.634982)
		(width 0.101346)
		(layer "F.Cu")
		(net "M_A_CPU0_SB_CA<3>")
	)
	(segment
		(start 324.038214 -263.083802)
		(end 320.915538 -263.083802)
		(width 0.10668)
		(layer "F.Cu")
		(net "M_A_CPU0_SB_CA<3>")
	)
	(segment
		(start 324.556882 -263.083802)
		(end 324.038214 -263.083802)
		(width 0.0762)
		(layer "F.Cu")
		(net "M_A_CPU0_SB_CA<3>")
	)
	(segment
		(start 325.70801 -262.916924)
		(end 324.72376 -262.916924)
		(width 0.0762)
		(layer "F.Cu")
		(net "M_A_CPU0_SB_CA<3>")
	)
	(segment
		(start 315.450474 -263.740138)
		(end 314.920376 -263.21004)
		(width 0.10668)
		(layer "F.Cu")
		(net "M_A_CPU0_SB_CA<3>")
	)
	(arc
		(start 326.648064 -263.29005)
		(mid 326.405747 -263.12033)
		(end 326.12076 -263.040876)
		(width 0.0762)
		(layer "F.Cu")
		(net "M_A_CPU0_SB_CA<3>")
	)
	(arc
		(start 325.894954 -262.96747)
		(mid 325.804821 -262.92985)
		(end 325.70801 -262.916924)
		(width 0.0762)
		(layer "F.Cu")
		(net "M_A_CPU0_SB_CA<3>")
	)
	(arc
		(start 326.12076 -263.040876)
		(mid 326.003947 -263.0162)
		(end 325.894954 -262.96747)
		(width 0.0762)
		(layer "F.Cu")
		(net "M_A_CPU0_SB_CA<3>")
	)
	(segment
		(start 311.295034 -262.274304)
		(end 311.411874 -262.391144)
		(width 0.10668)
		(layer "F.Cu")
		(net "M_A_CPU0_SB_CA<2>")
	)
	(segment
		(start 309.592472 -261.87527)
		(end 309.475632 -261.99211)
		(width 0.10668)
		(layer "F.Cu")
		(net "M_A_CPU0_SB_CA<2>")
	)
	(segment
		(start 309.475632 -262.157464)
		(end 309.592472 -262.274304)
		(width 0.10668)
		(layer "F.Cu")
		(net "M_A_CPU0_SB_CA<2>")
	)
	(segment
		(start 309.592472 -262.274304)
		(end 311.295034 -262.274304)
		(width 0.10668)
		(layer "F.Cu")
		(net "M_A_CPU0_SB_CA<2>")
	)
	(segment
		(start 324.038214 -262.723884)
		(end 320.793872 -262.723884)
		(width 0.10668)
		(layer "F.Cu")
		(net "M_A_CPU0_SB_CA<2>")
	)
	(segment
		(start 326.17791 -262.480044)
		(end 326.276208 -262.649208)
		(width 0.0762)
		(layer "F.Cu")
		(net "M_A_CPU0_SB_CA<2>")
	)
	(segment
		(start 325.299832 -262.723884)
		(end 324.038214 -262.723884)
		(width 0.0762)
		(layer "F.Cu")
		(net "M_A_CPU0_SB_CA<2>")
	)
	(segment
		(start 309.475632 -261.99211)
		(end 309.475632 -262.157464)
		(width 0.10668)
		(layer "F.Cu")
		(net "M_A_CPU0_SB_CA<2>")
	)
	(segment
		(start 309.024274 -262.149844)
		(end 308.89448 -262.02005)
		(width 0.10668)
		(layer "F.Cu")
		(net "M_A_CPU0_SB_CA<2>")
	)
	(segment
		(start 309.193438 -262.673338)
		(end 309.024274 -262.504174)
		(width 0.10668)
		(layer "F.Cu")
		(net "M_A_CPU0_SB_CA<2>")
	)
	(segment
		(start 320.117978 -263.399778)
		(end 315.591698 -263.399778)
		(width 0.10668)
		(layer "F.Cu")
		(net "M_A_CPU0_SB_CA<2>")
	)
	(segment
		(start 320.793872 -262.723884)
		(end 320.117978 -263.399778)
		(width 0.10668)
		(layer "F.Cu")
		(net "M_A_CPU0_SB_CA<2>")
	)
	(segment
		(start 307.845206 -262.785098)
		(end 307.368194 -262.785098)
		(width 0.10668)
		(layer "F.Cu")
		(net "M_A_CPU0_SB_CA<2>")
	)
	(segment
		(start 308.89448 -262.02005)
		(end 308.610254 -262.02005)
		(width 0.10668)
		(layer "F.Cu")
		(net "M_A_CPU0_SB_CA<2>")
	)
	(segment
		(start 311.295034 -262.673338)
		(end 309.193438 -262.673338)
		(width 0.10668)
		(layer "F.Cu")
		(net "M_A_CPU0_SB_CA<2>")
	)
	(segment
		(start 315.591698 -263.399778)
		(end 314.06719 -261.87527)
		(width 0.10668)
		(layer "F.Cu")
		(net "M_A_CPU0_SB_CA<2>")
	)
	(segment
		(start 311.411874 -262.556498)
		(end 311.295034 -262.673338)
		(width 0.10668)
		(layer "F.Cu")
		(net "M_A_CPU0_SB_CA<2>")
	)
	(segment
		(start 308.610254 -262.02005)
		(end 307.845206 -262.785098)
		(width 0.10668)
		(layer "F.Cu")
		(net "M_A_CPU0_SB_CA<2>")
	)
	(segment
		(start 325.302372 -262.726424)
		(end 325.299832 -262.723884)
		(width 0.0762)
		(layer "F.Cu")
		(net "M_A_CPU0_SB_CA<2>")
	)
	(segment
		(start 314.06719 -261.87527)
		(end 309.592472 -261.87527)
		(width 0.10668)
		(layer "F.Cu")
		(net "M_A_CPU0_SB_CA<2>")
	)
	(segment
		(start 311.411874 -262.391144)
		(end 311.411874 -262.556498)
		(width 0.10668)
		(layer "F.Cu")
		(net "M_A_CPU0_SB_CA<2>")
	)
	(segment
		(start 309.024274 -262.504174)
		(end 309.024274 -262.149844)
		(width 0.10668)
		(layer "F.Cu")
		(net "M_A_CPU0_SB_CA<2>")
	)
	(segment
		(start 325.70801 -262.726424)
		(end 325.302372 -262.726424)
		(width 0.0762)
		(layer "F.Cu")
		(net "M_A_CPU0_SB_CA<2>")
	)
	(segment
		(start 325.999348 -262.80745)
		(end 325.990966 -262.802624)
		(width 0.0762)
		(layer "F.Cu")
		(net "M_A_CPU0_SB_CA<2>")
	)
	(arc
		(start 326.13854 -262.850884)
		(mid 326.066802 -262.836032)
		(end 325.999348 -262.80745)
		(width 0.0762)
		(layer "F.Cu")
		(net "M_A_CPU0_SB_CA<2>")
	)
	(arc
		(start 325.990966 -262.802624)
		(mid 325.85453 -262.745799)
		(end 325.70801 -262.726424)
		(width 0.0762)
		(layer "F.Cu")
		(net "M_A_CPU0_SB_CA<2>")
	)
	(arc
		(start 326.276208 -262.649208)
		(mid 326.267615 -262.791087)
		(end 326.13854 -262.850884)
		(width 0.0762)
		(layer "F.Cu")
		(net "M_A_CPU0_SB_CA<2>")
	)
	(segment
		(start 315.742574 -263.059418)
		(end 314.193174 -261.510018)
		(width 0.10668)
		(layer "F.Cu")
		(net "M_A_CPU0_SB_CA<1>")
	)
	(segment
		(start 324.038214 -262.383524)
		(end 320.652648 -262.383524)
		(width 0.10668)
		(layer "F.Cu")
		(net "M_A_CPU0_SB_CA<1>")
	)
	(segment
		(start 325.71055 -262.233664)
		(end 324.48754 -262.233664)
		(width 0.0762)
		(layer "F.Cu")
		(net "M_A_CPU0_SB_CA<1>")
	)
	(segment
		(start 306.070508 -261.510018)
		(end 305.645566 -261.93496)
		(width 0.101346)
		(layer "F.Cu")
		(net "M_A_CPU0_SB_CA<1>")
	)
	(segment
		(start 320.652648 -262.383524)
		(end 319.976754 -263.059418)
		(width 0.10668)
		(layer "F.Cu")
		(net "M_A_CPU0_SB_CA<1>")
	)
	(segment
		(start 319.976754 -263.059418)
		(end 315.742574 -263.059418)
		(width 0.10668)
		(layer "F.Cu")
		(net "M_A_CPU0_SB_CA<1>")
	)
	(segment
		(start 324.33768 -262.383524)
		(end 324.038214 -262.383524)
		(width 0.0762)
		(layer "F.Cu")
		(net "M_A_CPU0_SB_CA<1>")
	)
	(segment
		(start 314.193174 -261.510018)
		(end 308.610508 -261.510018)
		(width 0.10668)
		(layer "F.Cu")
		(net "M_A_CPU0_SB_CA<1>")
	)
	(segment
		(start 305.645566 -261.93496)
		(end 303.268126 -261.93496)
		(width 0.101346)
		(layer "F.Cu")
		(net "M_A_CPU0_SB_CA<1>")
	)
	(segment
		(start 325.999348 -262.152638)
		(end 325.990966 -262.157464)
		(width 0.0762)
		(layer "F.Cu")
		(net "M_A_CPU0_SB_CA<1>")
	)
	(segment
		(start 324.48754 -262.233664)
		(end 324.33768 -262.383524)
		(width 0.0762)
		(layer "F.Cu")
		(net "M_A_CPU0_SB_CA<1>")
	)
	(segment
		(start 308.610508 -261.510018)
		(end 306.070508 -261.510018)
		(width 0.101346)
		(layer "F.Cu")
		(net "M_A_CPU0_SB_CA<1>")
	)
	(arc
		(start 327.601834 -262.233664)
		(mid 327.448085 -262.216155)
		(end 327.304908 -262.157464)
		(width 0.0762)
		(layer "F.Cu")
		(net "M_A_CPU0_SB_CA<1>")
	)
	(arc
		(start 328.058018 -262.480044)
		(mid 327.862669 -262.296225)
		(end 327.601834 -262.233664)
		(width 0.0762)
		(layer "F.Cu")
		(net "M_A_CPU0_SB_CA<1>")
	)
	(arc
		(start 327.304908 -262.157464)
		(mid 327.117964 -262.107209)
		(end 326.93102 -262.157464)
		(width 0.0762)
		(layer "F.Cu")
		(net "M_A_CPU0_SB_CA<1>")
	)
	(arc
		(start 326.365108 -262.157464)
		(mid 326.182857 -262.107114)
		(end 325.999348 -262.152638)
		(width 0.0762)
		(layer "F.Cu")
		(net "M_A_CPU0_SB_CA<1>")
	)
	(arc
		(start 326.93102 -262.157464)
		(mid 326.648064 -262.233641)
		(end 326.365108 -262.157464)
		(width 0.0762)
		(layer "F.Cu")
		(net "M_A_CPU0_SB_CA<1>")
	)
	(arc
		(start 325.755254 -262.231886)
		(mid 325.73292 -262.233221)
		(end 325.71055 -262.233664)
		(width 0.0762)
		(layer "F.Cu")
		(net "M_A_CPU0_SB_CA<1>")
	)
	(arc
		(start 325.990966 -262.157464)
		(mid 325.877242 -262.207765)
		(end 325.755254 -262.231886)
		(width 0.0762)
		(layer "F.Cu")
		(net "M_A_CPU0_SB_CA<1>")
	)
	(segment
		(start 312.685684 -261.085076)
		(end 312.50001 -261.085076)
		(width 0.10668)
		(layer "F.Cu")
		(net "M_A_CPU0_SB_CA<0>")
	)
	(segment
		(start 319.83553 -262.719058)
		(end 315.883798 -262.719058)
		(width 0.10668)
		(layer "F.Cu")
		(net "M_A_CPU0_SB_CA<0>")
	)
	(segment
		(start 310.39816 -260.753352)
		(end 310.39816 -260.978396)
		(width 0.10668)
		(layer "F.Cu")
		(net "M_A_CPU0_SB_CA<0>")
	)
	(segment
		(start 311.488582 -260.646672)
		(end 311.302908 -260.646672)
		(width 0.10668)
		(layer "F.Cu")
		(net "M_A_CPU0_SB_CA<0>")
	)
	(segment
		(start 311.302908 -260.646672)
		(end 311.196228 -260.753352)
		(width 0.10668)
		(layer "F.Cu")
		(net "M_A_CPU0_SB_CA<0>")
	)
	(segment
		(start 327.587864 -261.670038)
		(end 327.696322 -261.856728)
		(width 0.0762)
		(layer "F.Cu")
		(net "M_A_CPU0_SB_CA<0>")
	)
	(segment
		(start 311.196228 -260.978396)
		(end 311.089548 -261.085076)
		(width 0.10668)
		(layer "F.Cu")
		(net "M_A_CPU0_SB_CA<0>")
	)
	(segment
		(start 310.797194 -260.753352)
		(end 310.690514 -260.646672)
		(width 0.10668)
		(layer "F.Cu")
		(net "M_A_CPU0_SB_CA<0>")
	)
	(segment
		(start 310.50484 -260.646672)
		(end 310.39816 -260.753352)
		(width 0.10668)
		(layer "F.Cu")
		(net "M_A_CPU0_SB_CA<0>")
	)
	(segment
		(start 313.084718 -260.646672)
		(end 312.899044 -260.646672)
		(width 0.10668)
		(layer "F.Cu")
		(net "M_A_CPU0_SB_CA<0>")
	)
	(segment
		(start 310.29148 -261.085076)
		(end 307.368194 -261.085076)
		(width 0.10668)
		(layer "F.Cu")
		(net "M_A_CPU0_SB_CA<0>")
	)
	(segment
		(start 311.595262 -260.978396)
		(end 311.595262 -260.753352)
		(width 0.10668)
		(layer "F.Cu")
		(net "M_A_CPU0_SB_CA<0>")
	)
	(segment
		(start 325.70801 -262.043164)
		(end 324.038214 -262.043164)
		(width 0.0762)
		(layer "F.Cu")
		(net "M_A_CPU0_SB_CA<0>")
	)
	(segment
		(start 312.792364 -260.753352)
		(end 312.792364 -260.978396)
		(width 0.10668)
		(layer "F.Cu")
		(net "M_A_CPU0_SB_CA<0>")
	)
	(segment
		(start 311.887616 -261.085076)
		(end 311.701942 -261.085076)
		(width 0.10668)
		(layer "F.Cu")
		(net "M_A_CPU0_SB_CA<0>")
	)
	(segment
		(start 310.39816 -260.978396)
		(end 310.29148 -261.085076)
		(width 0.10668)
		(layer "F.Cu")
		(net "M_A_CPU0_SB_CA<0>")
	)
	(segment
		(start 314.249816 -261.085076)
		(end 313.298078 -261.085076)
		(width 0.10668)
		(layer "F.Cu")
		(net "M_A_CPU0_SB_CA<0>")
	)
	(segment
		(start 310.690514 -260.646672)
		(end 310.50484 -260.646672)
		(width 0.10668)
		(layer "F.Cu")
		(net "M_A_CPU0_SB_CA<0>")
	)
	(segment
		(start 320.511424 -262.043164)
		(end 319.83553 -262.719058)
		(width 0.10668)
		(layer "F.Cu")
		(net "M_A_CPU0_SB_CA<0>")
	)
	(segment
		(start 310.797194 -260.978396)
		(end 310.797194 -260.753352)
		(width 0.10668)
		(layer "F.Cu")
		(net "M_A_CPU0_SB_CA<0>")
	)
	(segment
		(start 313.298078 -261.085076)
		(end 313.191398 -260.978396)
		(width 0.10668)
		(layer "F.Cu")
		(net "M_A_CPU0_SB_CA<0>")
	)
	(segment
		(start 311.595262 -260.753352)
		(end 311.488582 -260.646672)
		(width 0.10668)
		(layer "F.Cu")
		(net "M_A_CPU0_SB_CA<0>")
	)
	(segment
		(start 312.899044 -260.646672)
		(end 312.792364 -260.753352)
		(width 0.10668)
		(layer "F.Cu")
		(net "M_A_CPU0_SB_CA<0>")
	)
	(segment
		(start 312.39333 -260.753352)
		(end 312.28665 -260.646672)
		(width 0.10668)
		(layer "F.Cu")
		(net "M_A_CPU0_SB_CA<0>")
	)
	(segment
		(start 312.100976 -260.646672)
		(end 311.994296 -260.753352)
		(width 0.10668)
		(layer "F.Cu")
		(net "M_A_CPU0_SB_CA<0>")
	)
	(segment
		(start 313.191398 -260.978396)
		(end 313.191398 -260.753352)
		(width 0.10668)
		(layer "F.Cu")
		(net "M_A_CPU0_SB_CA<0>")
	)
	(segment
		(start 324.038214 -262.043164)
		(end 320.511424 -262.043164)
		(width 0.10668)
		(layer "F.Cu")
		(net "M_A_CPU0_SB_CA<0>")
	)
	(segment
		(start 315.883798 -262.719058)
		(end 314.249816 -261.085076)
		(width 0.10668)
		(layer "F.Cu")
		(net "M_A_CPU0_SB_CA<0>")
	)
	(segment
		(start 312.39333 -260.978396)
		(end 312.39333 -260.753352)
		(width 0.10668)
		(layer "F.Cu")
		(net "M_A_CPU0_SB_CA<0>")
	)
	(segment
		(start 312.792364 -260.978396)
		(end 312.685684 -261.085076)
		(width 0.10668)
		(layer "F.Cu")
		(net "M_A_CPU0_SB_CA<0>")
	)
	(segment
		(start 311.994296 -260.978396)
		(end 311.887616 -261.085076)
		(width 0.10668)
		(layer "F.Cu")
		(net "M_A_CPU0_SB_CA<0>")
	)
	(segment
		(start 311.196228 -260.753352)
		(end 311.196228 -260.978396)
		(width 0.10668)
		(layer "F.Cu")
		(net "M_A_CPU0_SB_CA<0>")
	)
	(segment
		(start 326.835008 -261.992618)
		(end 326.826626 -261.997444)
		(width 0.0762)
		(layer "F.Cu")
		(net "M_A_CPU0_SB_CA<0>")
	)
	(segment
		(start 312.50001 -261.085076)
		(end 312.39333 -260.978396)
		(width 0.10668)
		(layer "F.Cu")
		(net "M_A_CPU0_SB_CA<0>")
	)
	(segment
		(start 327.409302 -261.997444)
		(end 327.40092 -261.992618)
		(width 0.0762)
		(layer "F.Cu")
		(net "M_A_CPU0_SB_CA<0>")
	)
	(segment
		(start 311.994296 -260.753352)
		(end 311.994296 -260.978396)
		(width 0.10668)
		(layer "F.Cu")
		(net "M_A_CPU0_SB_CA<0>")
	)
	(segment
		(start 313.191398 -260.753352)
		(end 313.084718 -260.646672)
		(width 0.10668)
		(layer "F.Cu")
		(net "M_A_CPU0_SB_CA<0>")
	)
	(segment
		(start 311.701942 -261.085076)
		(end 311.595262 -260.978396)
		(width 0.10668)
		(layer "F.Cu")
		(net "M_A_CPU0_SB_CA<0>")
	)
	(segment
		(start 311.089548 -261.085076)
		(end 310.903874 -261.085076)
		(width 0.10668)
		(layer "F.Cu")
		(net "M_A_CPU0_SB_CA<0>")
	)
	(segment
		(start 312.28665 -260.646672)
		(end 312.100976 -260.646672)
		(width 0.10668)
		(layer "F.Cu")
		(net "M_A_CPU0_SB_CA<0>")
	)
	(segment
		(start 310.903874 -261.085076)
		(end 310.797194 -260.978396)
		(width 0.10668)
		(layer "F.Cu")
		(net "M_A_CPU0_SB_CA<0>")
	)
	(arc
		(start 325.894954 -261.992618)
		(mid 325.804821 -262.030238)
		(end 325.70801 -262.043164)
		(width 0.0762)
		(layer "F.Cu")
		(net "M_A_CPU0_SB_CA<0>")
	)
	(arc
		(start 327.40092 -261.992618)
		(mid 327.117964 -261.916441)
		(end 326.835008 -261.992618)
		(width 0.0762)
		(layer "F.Cu")
		(net "M_A_CPU0_SB_CA<0>")
	)
	(arc
		(start 327.696322 -261.856728)
		(mid 327.670405 -261.98977)
		(end 327.544684 -262.04037)
		(width 0.0762)
		(layer "F.Cu")
		(net "M_A_CPU0_SB_CA<0>")
	)
	(arc
		(start 327.544684 -262.04037)
		(mid 327.47493 -262.025413)
		(end 327.409302 -261.997444)
		(width 0.0762)
		(layer "F.Cu")
		(net "M_A_CPU0_SB_CA<0>")
	)
	(arc
		(start 326.460866 -261.992618)
		(mid 326.17791 -261.916441)
		(end 325.894954 -261.992618)
		(width 0.0762)
		(layer "F.Cu")
		(net "M_A_CPU0_SB_CA<0>")
	)
	(arc
		(start 326.826626 -261.997444)
		(mid 326.643118 -262.042938)
		(end 326.460866 -261.992618)
		(width 0.0762)
		(layer "F.Cu")
		(net "M_A_CPU0_SB_CA<0>")
	)
	(segment
		(start 309.879492 -268.372844)
		(end 309.728616 -268.373098)
		(width 0.10668)
		(layer "F.Cu")
		(net "M_A_CPU0_SA_RSP<0>")
	)
	(segment
		(start 310.480964 -267.977112)
		(end 310.275224 -267.977112)
		(width 0.10668)
		(layer "F.Cu")
		(net "M_A_CPU0_SA_RSP<0>")
	)
	(segment
		(start 311.093358 -267.977112)
		(end 310.986678 -268.083792)
		(width 0.10668)
		(layer "F.Cu")
		(net "M_A_CPU0_SA_RSP<0>")
	)
	(segment
		(start 308.66715 -269.585186)
		(end 307.368194 -269.585186)
		(width 0.10668)
		(layer "F.Cu")
		(net "M_A_CPU0_SA_RSP<0>")
	)
	(segment
		(start 323.3801 -266.179808)
		(end 313.401964 -266.179808)
		(width 0.10668)
		(layer "F.Cu")
		(net "M_A_CPU0_SA_RSP<0>")
	)
	(segment
		(start 309.139082 -268.347698)
		(end 309.446422 -268.655038)
		(width 0.10668)
		(layer "F.Cu")
		(net "M_A_CPU0_SA_RSP<0>")
	)
	(segment
		(start 310.275224 -267.977112)
		(end 309.879492 -268.372844)
		(width 0.10668)
		(layer "F.Cu")
		(net "M_A_CPU0_SA_RSP<0>")
	)
	(segment
		(start 324.671944 -266.70127)
		(end 323.901562 -266.70127)
		(width 0.10668)
		(layer "F.Cu")
		(net "M_A_CPU0_SA_RSP<0>")
	)
	(segment
		(start 327.587864 -266.530074)
		(end 327.696322 -266.716764)
		(width 0.0762)
		(layer "F.Cu")
		(net "M_A_CPU0_SA_RSP<0>")
	)
	(segment
		(start 310.587644 -268.304772)
		(end 310.587644 -268.083792)
		(width 0.10668)
		(layer "F.Cu")
		(net "M_A_CPU0_SA_RSP<0>")
	)
	(segment
		(start 326.835008 -266.852654)
		(end 326.826626 -266.85748)
		(width 0.0762)
		(layer "F.Cu")
		(net "M_A_CPU0_SA_RSP<0>")
	)
	(segment
		(start 309.446422 -268.655038)
		(end 309.446422 -268.805914)
		(width 0.10668)
		(layer "F.Cu")
		(net "M_A_CPU0_SA_RSP<0>")
	)
	(segment
		(start 309.138828 -268.19733)
		(end 309.139082 -268.347698)
		(width 0.10668)
		(layer "F.Cu")
		(net "M_A_CPU0_SA_RSP<0>")
	)
	(segment
		(start 323.901562 -266.70127)
		(end 323.3801 -266.179808)
		(width 0.10668)
		(layer "F.Cu")
		(net "M_A_CPU0_SA_RSP<0>")
	)
	(segment
		(start 327.409302 -266.85748)
		(end 327.40092 -266.852654)
		(width 0.0762)
		(layer "F.Cu")
		(net "M_A_CPU0_SA_RSP<0>")
	)
	(segment
		(start 309.421276 -268.065758)
		(end 309.2704 -268.065758)
		(width 0.10668)
		(layer "F.Cu")
		(net "M_A_CPU0_SA_RSP<0>")
	)
	(segment
		(start 311.60466 -267.977112)
		(end 311.093358 -267.977112)
		(width 0.10668)
		(layer "F.Cu")
		(net "M_A_CPU0_SA_RSP<0>")
	)
	(segment
		(start 325.70801 -266.9032)
		(end 324.873874 -266.9032)
		(width 0.0762)
		(layer "F.Cu")
		(net "M_A_CPU0_SA_RSP<0>")
	)
	(segment
		(start 310.986678 -268.083792)
		(end 310.986678 -268.304772)
		(width 0.10668)
		(layer "F.Cu")
		(net "M_A_CPU0_SA_RSP<0>")
	)
	(segment
		(start 310.587644 -268.083792)
		(end 310.480964 -267.977112)
		(width 0.10668)
		(layer "F.Cu")
		(net "M_A_CPU0_SA_RSP<0>")
	)
	(segment
		(start 310.879998 -268.411452)
		(end 310.694324 -268.411452)
		(width 0.10668)
		(layer "F.Cu")
		(net "M_A_CPU0_SA_RSP<0>")
	)
	(segment
		(start 309.2704 -268.065758)
		(end 309.138828 -268.19733)
		(width 0.10668)
		(layer "F.Cu")
		(net "M_A_CPU0_SA_RSP<0>")
	)
	(segment
		(start 313.401964 -266.179808)
		(end 311.60466 -267.977112)
		(width 0.10668)
		(layer "F.Cu")
		(net "M_A_CPU0_SA_RSP<0>")
	)
	(segment
		(start 310.986678 -268.304772)
		(end 310.879998 -268.411452)
		(width 0.10668)
		(layer "F.Cu")
		(net "M_A_CPU0_SA_RSP<0>")
	)
	(segment
		(start 309.446422 -268.805914)
		(end 308.66715 -269.585186)
		(width 0.10668)
		(layer "F.Cu")
		(net "M_A_CPU0_SA_RSP<0>")
	)
	(segment
		(start 324.873874 -266.9032)
		(end 324.671944 -266.70127)
		(width 0.0762)
		(layer "F.Cu")
		(net "M_A_CPU0_SA_RSP<0>")
	)
	(segment
		(start 310.694324 -268.411452)
		(end 310.587644 -268.304772)
		(width 0.10668)
		(layer "F.Cu")
		(net "M_A_CPU0_SA_RSP<0>")
	)
	(segment
		(start 309.728616 -268.373098)
		(end 309.421276 -268.065758)
		(width 0.10668)
		(layer "F.Cu")
		(net "M_A_CPU0_SA_RSP<0>")
	)
	(arc
		(start 326.826626 -266.85748)
		(mid 326.643118 -266.902974)
		(end 326.460866 -266.852654)
		(width 0.0762)
		(layer "F.Cu")
		(net "M_A_CPU0_SA_RSP<0>")
	)
	(arc
		(start 327.40092 -266.852654)
		(mid 327.117964 -266.776477)
		(end 326.835008 -266.852654)
		(width 0.0762)
		(layer "F.Cu")
		(net "M_A_CPU0_SA_RSP<0>")
	)
	(arc
		(start 326.460866 -266.852654)
		(mid 326.17791 -266.776477)
		(end 325.894954 -266.852654)
		(width 0.0762)
		(layer "F.Cu")
		(net "M_A_CPU0_SA_RSP<0>")
	)
	(arc
		(start 327.696322 -266.716764)
		(mid 327.670405 -266.849806)
		(end 327.544684 -266.900406)
		(width 0.0762)
		(layer "F.Cu")
		(net "M_A_CPU0_SA_RSP<0>")
	)
	(arc
		(start 327.544684 -266.900406)
		(mid 327.47493 -266.885449)
		(end 327.409302 -266.85748)
		(width 0.0762)
		(layer "F.Cu")
		(net "M_A_CPU0_SA_RSP<0>")
	)
	(arc
		(start 325.894954 -266.852654)
		(mid 325.804821 -266.890274)
		(end 325.70801 -266.9032)
		(width 0.0762)
		(layer "F.Cu")
		(net "M_A_CPU0_SA_RSP<0>")
	)
	(segment
		(start 327.109328 -255.76276)
		(end 327.108312 -255.763268)
		(width 0.0762)
		(layer "F.Cu")
		(net "M_A_CPU0_SA_PAR")
	)
	(segment
		(start 322.682108 -256.933192)
		(end 322.682108 -256.745994)
		(width 0.10668)
		(layer "F.Cu")
		(net "M_A_CPU0_SA_PAR")
	)
	(segment
		(start 322.974462 -257.039872)
		(end 322.788788 -257.039872)
		(width 0.10668)
		(layer "F.Cu")
		(net "M_A_CPU0_SA_PAR")
	)
	(segment
		(start 322.682108 -256.745994)
		(end 322.575428 -256.639314)
		(width 0.10668)
		(layer "F.Cu")
		(net "M_A_CPU0_SA_PAR")
	)
	(segment
		(start 314.59805 -255.45669)
		(end 310.60517 -255.45669)
		(width 0.10668)
		(layer "F.Cu")
		(net "M_A_CPU0_SA_PAR")
	)
	(segment
		(start 327.108312 -255.763268)
		(end 327.100946 -255.767586)
		(width 0.0762)
		(layer "F.Cu")
		(net "M_A_CPU0_SA_PAR")
	)
	(segment
		(start 309.433468 -254.284988)
		(end 307.368194 -254.284988)
		(width 0.10668)
		(layer "F.Cu")
		(net "M_A_CPU0_SA_PAR")
	)
	(segment
		(start 323.081142 -256.745994)
		(end 323.081142 -256.933192)
		(width 0.10668)
		(layer "F.Cu")
		(net "M_A_CPU0_SA_PAR")
	)
	(segment
		(start 323.187822 -256.639314)
		(end 323.081142 -256.745994)
		(width 0.10668)
		(layer "F.Cu")
		(net "M_A_CPU0_SA_PAR")
	)
	(segment
		(start 323.081142 -256.933192)
		(end 322.974462 -257.039872)
		(width 0.10668)
		(layer "F.Cu")
		(net "M_A_CPU0_SA_PAR")
	)
	(segment
		(start 322.098162 -256.639314)
		(end 319.67932 -254.220472)
		(width 0.10668)
		(layer "F.Cu")
		(net "M_A_CPU0_SA_PAR")
	)
	(segment
		(start 322.575428 -256.639314)
		(end 322.098162 -256.639314)
		(width 0.10668)
		(layer "F.Cu")
		(net "M_A_CPU0_SA_PAR")
	)
	(segment
		(start 323.87921 -256.745994)
		(end 323.87921 -256.933192)
		(width 0.10668)
		(layer "F.Cu")
		(net "M_A_CPU0_SA_PAR")
	)
	(segment
		(start 323.373496 -256.639314)
		(end 323.187822 -256.639314)
		(width 0.10668)
		(layer "F.Cu")
		(net "M_A_CPU0_SA_PAR")
	)
	(segment
		(start 319.67932 -254.220472)
		(end 315.834268 -254.220472)
		(width 0.10668)
		(layer "F.Cu")
		(net "M_A_CPU0_SA_PAR")
	)
	(segment
		(start 310.60517 -255.45669)
		(end 309.433468 -254.284988)
		(width 0.10668)
		(layer "F.Cu")
		(net "M_A_CPU0_SA_PAR")
	)
	(segment
		(start 323.586856 -257.039872)
		(end 323.480176 -256.933192)
		(width 0.10668)
		(layer "F.Cu")
		(net "M_A_CPU0_SA_PAR")
	)
	(segment
		(start 324.39737 -256.227834)
		(end 323.87921 -256.745994)
		(width 0.10668)
		(layer "F.Cu")
		(net "M_A_CPU0_SA_PAR")
	)
	(segment
		(start 324.39737 -255.938274)
		(end 324.39737 -256.227834)
		(width 0.0762)
		(layer "F.Cu")
		(net "M_A_CPU0_SA_PAR")
	)
	(segment
		(start 322.788788 -257.039872)
		(end 322.682108 -256.933192)
		(width 0.10668)
		(layer "F.Cu")
		(net "M_A_CPU0_SA_PAR")
	)
	(segment
		(start 325.383906 -255.71069)
		(end 324.624954 -255.71069)
		(width 0.0762)
		(layer "F.Cu")
		(net "M_A_CPU0_SA_PAR")
	)
	(segment
		(start 323.87921 -256.933192)
		(end 323.77253 -257.039872)
		(width 0.10668)
		(layer "F.Cu")
		(net "M_A_CPU0_SA_PAR")
	)
	(segment
		(start 323.77253 -257.039872)
		(end 323.586856 -257.039872)
		(width 0.10668)
		(layer "F.Cu")
		(net "M_A_CPU0_SA_PAR")
	)
	(segment
		(start 327.28789 -256.090166)
		(end 327.28789 -256.089912)
		(width 0.0762)
		(layer "F.Cu")
		(net "M_A_CPU0_SA_PAR")
	)
	(segment
		(start 315.834268 -254.220472)
		(end 314.59805 -255.45669)
		(width 0.10668)
		(layer "F.Cu")
		(net "M_A_CPU0_SA_PAR")
	)
	(segment
		(start 323.480176 -256.933192)
		(end 323.480176 -256.745994)
		(width 0.10668)
		(layer "F.Cu")
		(net "M_A_CPU0_SA_PAR")
	)
	(segment
		(start 326.535034 -255.767586)
		(end 326.526652 -255.76276)
		(width 0.0762)
		(layer "F.Cu")
		(net "M_A_CPU0_SA_PAR")
	)
	(segment
		(start 323.480176 -256.745994)
		(end 323.373496 -256.639314)
		(width 0.10668)
		(layer "F.Cu")
		(net "M_A_CPU0_SA_PAR")
	)
	(segment
		(start 324.624954 -255.71069)
		(end 324.39737 -255.938274)
		(width 0.0762)
		(layer "F.Cu")
		(net "M_A_CPU0_SA_PAR")
	)
	(segment
		(start 327.28789 -256.089912)
		(end 327.393046 -255.909064)
		(width 0.0762)
		(layer "F.Cu")
		(net "M_A_CPU0_SA_PAR")
	)
	(arc
		(start 325.59498 -255.767586)
		(mid 325.493212 -255.725152)
		(end 325.383906 -255.71069)
		(width 0.0762)
		(layer "F.Cu")
		(net "M_A_CPU0_SA_PAR")
	)
	(arc
		(start 326.160892 -255.767586)
		(mid 325.877936 -255.843763)
		(end 325.59498 -255.767586)
		(width 0.0762)
		(layer "F.Cu")
		(net "M_A_CPU0_SA_PAR")
	)
	(arc
		(start 327.100946 -255.767586)
		(mid 326.81799 -255.843763)
		(end 326.535034 -255.767586)
		(width 0.0762)
		(layer "F.Cu")
		(net "M_A_CPU0_SA_PAR")
	)
	(arc
		(start 326.526652 -255.76276)
		(mid 326.343144 -255.717266)
		(end 326.160892 -255.767586)
		(width 0.0762)
		(layer "F.Cu")
		(net "M_A_CPU0_SA_PAR")
	)
	(arc
		(start 327.289414 -255.717294)
		(mid 327.19649 -255.728617)
		(end 327.109328 -255.76276)
		(width 0.0762)
		(layer "F.Cu")
		(net "M_A_CPU0_SA_PAR")
	)
	(arc
		(start 327.393046 -255.909064)
		(mid 327.384109 -255.79004)
		(end 327.289414 -255.717294)
		(width 0.0762)
		(layer "F.Cu")
		(net "M_A_CPU0_SA_PAR")
	)
	(segment
		(start 304.123852 -239.517682)
		(end 303.806352 -239.835182)
		(width 0.101346)
		(layer "F.Cu")
		(net "M_A_CPU0_SA_DQS_DP<9>")
	)
	(segment
		(start 304.690526 -239.517682)
		(end 304.123852 -239.517682)
		(width 0.101346)
		(layer "F.Cu")
		(net "M_A_CPU0_SA_DQS_DP<9>")
	)
	(segment
		(start 324.53453 -247.61698)
		(end 324.377558 -247.773952)
		(width 0.0762)
		(layer "F.Cu")
		(net "M_A_CPU0_SA_DQS_DP<9>")
	)
	(segment
		(start 305.483006 -239.943894)
		(end 305.116738 -239.943894)
		(width 0.101346)
		(layer "F.Cu")
		(net "M_A_CPU0_SA_DQS_DP<9>")
	)
	(segment
		(start 305.116738 -239.943894)
		(end 304.690526 -239.517682)
		(width 0.101346)
		(layer "F.Cu")
		(net "M_A_CPU0_SA_DQS_DP<9>")
	)
	(segment
		(start 303.806352 -239.835182)
		(end 303.268126 -239.835182)
		(width 0.101346)
		(layer "F.Cu")
		(net "M_A_CPU0_SA_DQS_DP<9>")
	)
	(segment
		(start 323.895974 -247.839992)
		(end 314.741814 -247.839992)
		(width 0.12954)
		(layer "F.Cu")
		(net "M_A_CPU0_SA_DQS_DP<9>")
	)
	(segment
		(start 308.51348 -239.976152)
		(end 308.229508 -240.260124)
		(width 0.12954)
		(layer "F.Cu")
		(net "M_A_CPU0_SA_DQS_DP<9>")
	)
	(segment
		(start 310.393588 -243.491766)
		(end 310.393588 -242.464082)
		(width 0.12954)
		(layer "F.Cu")
		(net "M_A_CPU0_SA_DQS_DP<9>")
	)
	(segment
		(start 308.954678 -241.025172)
		(end 308.954678 -240.225072)
		(width 0.12954)
		(layer "F.Cu")
		(net "M_A_CPU0_SA_DQS_DP<9>")
	)
	(segment
		(start 324.377558 -247.773952)
		(end 323.981064 -247.773952)
		(width 0.0762)
		(layer "F.Cu")
		(net "M_A_CPU0_SA_DQS_DP<9>")
	)
	(segment
		(start 308.954678 -240.225072)
		(end 308.705758 -239.976152)
		(width 0.12954)
		(layer "F.Cu")
		(net "M_A_CPU0_SA_DQS_DP<9>")
	)
	(segment
		(start 308.705758 -239.976152)
		(end 308.51348 -239.976152)
		(width 0.12954)
		(layer "F.Cu")
		(net "M_A_CPU0_SA_DQS_DP<9>")
	)
	(segment
		(start 308.229508 -240.260124)
		(end 305.799236 -240.260124)
		(width 0.101346)
		(layer "F.Cu")
		(net "M_A_CPU0_SA_DQS_DP<9>")
	)
	(segment
		(start 305.799236 -240.260124)
		(end 305.483006 -239.943894)
		(width 0.101346)
		(layer "F.Cu")
		(net "M_A_CPU0_SA_DQS_DP<9>")
	)
	(segment
		(start 310.393588 -242.464082)
		(end 308.954678 -241.025172)
		(width 0.12954)
		(layer "F.Cu")
		(net "M_A_CPU0_SA_DQS_DP<9>")
	)
	(segment
		(start 327.109328 -247.6627)
		(end 327.100946 -247.667526)
		(width 0.0762)
		(layer "F.Cu")
		(net "M_A_CPU0_SA_DQS_DP<9>")
	)
	(segment
		(start 326.535034 -247.667526)
		(end 326.526652 -247.6627)
		(width 0.0762)
		(layer "F.Cu")
		(net "M_A_CPU0_SA_DQS_DP<9>")
	)
	(segment
		(start 314.741814 -247.839992)
		(end 310.393588 -243.491766)
		(width 0.12954)
		(layer "F.Cu")
		(net "M_A_CPU0_SA_DQS_DP<9>")
	)
	(segment
		(start 327.28789 -247.990106)
		(end 327.388728 -247.816624)
		(width 0.0762)
		(layer "F.Cu")
		(net "M_A_CPU0_SA_DQS_DP<9>")
	)
	(segment
		(start 323.981064 -247.773952)
		(end 323.915024 -247.839992)
		(width 0.0762)
		(layer "F.Cu")
		(net "M_A_CPU0_SA_DQS_DP<9>")
	)
	(segment
		(start 323.915024 -247.839992)
		(end 323.895974 -247.839992)
		(width 0.0762)
		(layer "F.Cu")
		(net "M_A_CPU0_SA_DQS_DP<9>")
	)
	(segment
		(start 325.408036 -247.61698)
		(end 324.53453 -247.61698)
		(width 0.0762)
		(layer "F.Cu")
		(net "M_A_CPU0_SA_DQS_DP<9>")
	)
	(arc
		(start 327.242678 -247.620028)
		(mid 327.17398 -247.635044)
		(end 327.109328 -247.6627)
		(width 0.0762)
		(layer "F.Cu")
		(net "M_A_CPU0_SA_DQS_DP<9>")
	)
	(arc
		(start 325.439024 -247.61825)
		(mid 325.423543 -247.617294)
		(end 325.408036 -247.61698)
		(width 0.0762)
		(layer "F.Cu")
		(net "M_A_CPU0_SA_DQS_DP<9>")
	)
	(arc
		(start 327.388728 -247.816624)
		(mid 327.372803 -247.675932)
		(end 327.242678 -247.620028)
		(width 0.0762)
		(layer "F.Cu")
		(net "M_A_CPU0_SA_DQS_DP<9>")
	)
	(arc
		(start 326.160892 -247.667526)
		(mid 325.877936 -247.743703)
		(end 325.59498 -247.667526)
		(width 0.0762)
		(layer "F.Cu")
		(net "M_A_CPU0_SA_DQS_DP<9>")
	)
	(arc
		(start 327.100946 -247.667526)
		(mid 326.81799 -247.743703)
		(end 326.535034 -247.667526)
		(width 0.0762)
		(layer "F.Cu")
		(net "M_A_CPU0_SA_DQS_DP<9>")
	)
	(arc
		(start 326.526652 -247.6627)
		(mid 326.343144 -247.617206)
		(end 326.160892 -247.667526)
		(width 0.0762)
		(layer "F.Cu")
		(net "M_A_CPU0_SA_DQS_DP<9>")
	)
	(arc
		(start 325.59498 -247.667526)
		(mid 325.51974 -247.634213)
		(end 325.439024 -247.61825)
		(width 0.0762)
		(layer "F.Cu")
		(net "M_A_CPU0_SA_DQS_DP<9>")
	)
	(segment
		(start 324.591172 -242.756944)
		(end 324.489064 -242.859052)
		(width 0.0762)
		(layer "F.Cu")
		(net "M_A_CPU0_SA_DQS_DP<8>")
	)
	(segment
		(start 308.810914 -231.521508)
		(end 308.810914 -230.771192)
		(width 0.12954)
		(layer "F.Cu")
		(net "M_A_CPU0_SA_DQS_DP<8>")
	)
	(segment
		(start 324.392544 -242.95989)
		(end 323.97954 -242.95989)
		(width 0.0762)
		(layer "F.Cu")
		(net "M_A_CPU0_SA_DQS_DP<8>")
	)
	(segment
		(start 319.417192 -243.02593)
		(end 309.967884 -233.576622)
		(width 0.12954)
		(layer "F.Cu")
		(net "M_A_CPU0_SA_DQS_DP<8>")
	)
	(segment
		(start 323.97954 -242.95989)
		(end 323.9135 -243.02593)
		(width 0.0762)
		(layer "F.Cu")
		(net "M_A_CPU0_SA_DQS_DP<8>")
	)
	(segment
		(start 305.799236 -230.91013)
		(end 305.483006 -230.5939)
		(width 0.101346)
		(layer "F.Cu")
		(net "M_A_CPU0_SA_DQS_DP<8>")
	)
	(segment
		(start 323.89445 -243.02593)
		(end 319.417192 -243.02593)
		(width 0.12954)
		(layer "F.Cu")
		(net "M_A_CPU0_SA_DQS_DP<8>")
	)
	(segment
		(start 309.967884 -232.678478)
		(end 308.810914 -231.521508)
		(width 0.12954)
		(layer "F.Cu")
		(net "M_A_CPU0_SA_DQS_DP<8>")
	)
	(segment
		(start 305.09845 -230.5939)
		(end 304.672238 -230.167688)
		(width 0.101346)
		(layer "F.Cu")
		(net "M_A_CPU0_SA_DQS_DP<8>")
	)
	(segment
		(start 323.9135 -243.02593)
		(end 323.89445 -243.02593)
		(width 0.0762)
		(layer "F.Cu")
		(net "M_A_CPU0_SA_DQS_DP<8>")
	)
	(segment
		(start 324.489064 -242.859052)
		(end 324.392544 -242.95989)
		(width 0.0762)
		(layer "F.Cu")
		(net "M_A_CPU0_SA_DQS_DP<8>")
	)
	(segment
		(start 304.123852 -230.167688)
		(end 303.806352 -230.485188)
		(width 0.101346)
		(layer "F.Cu")
		(net "M_A_CPU0_SA_DQS_DP<8>")
	)
	(segment
		(start 309.967884 -233.576622)
		(end 309.967884 -232.678478)
		(width 0.12954)
		(layer "F.Cu")
		(net "M_A_CPU0_SA_DQS_DP<8>")
	)
	(segment
		(start 304.672238 -230.167688)
		(end 304.123852 -230.167688)
		(width 0.101346)
		(layer "F.Cu")
		(net "M_A_CPU0_SA_DQS_DP<8>")
	)
	(segment
		(start 308.810914 -230.771192)
		(end 308.681374 -230.641652)
		(width 0.12954)
		(layer "F.Cu")
		(net "M_A_CPU0_SA_DQS_DP<8>")
	)
	(segment
		(start 308.497986 -230.641652)
		(end 308.229508 -230.91013)
		(width 0.12954)
		(layer "F.Cu")
		(net "M_A_CPU0_SA_DQS_DP<8>")
	)
	(segment
		(start 327.109328 -242.802664)
		(end 327.100946 -242.80749)
		(width 0.0762)
		(layer "F.Cu")
		(net "M_A_CPU0_SA_DQS_DP<8>")
	)
	(segment
		(start 305.483006 -230.5939)
		(end 305.09845 -230.5939)
		(width 0.101346)
		(layer "F.Cu")
		(net "M_A_CPU0_SA_DQS_DP<8>")
	)
	(segment
		(start 325.408036 -242.756944)
		(end 324.591172 -242.756944)
		(width 0.0762)
		(layer "F.Cu")
		(net "M_A_CPU0_SA_DQS_DP<8>")
	)
	(segment
		(start 327.28789 -243.13007)
		(end 327.388728 -242.956588)
		(width 0.0762)
		(layer "F.Cu")
		(net "M_A_CPU0_SA_DQS_DP<8>")
	)
	(segment
		(start 303.806352 -230.485188)
		(end 303.268126 -230.485188)
		(width 0.101346)
		(layer "F.Cu")
		(net "M_A_CPU0_SA_DQS_DP<8>")
	)
	(segment
		(start 308.681374 -230.641652)
		(end 308.497986 -230.641652)
		(width 0.12954)
		(layer "F.Cu")
		(net "M_A_CPU0_SA_DQS_DP<8>")
	)
	(segment
		(start 326.535034 -242.80749)
		(end 326.526652 -242.802664)
		(width 0.0762)
		(layer "F.Cu")
		(net "M_A_CPU0_SA_DQS_DP<8>")
	)
	(segment
		(start 308.229508 -230.91013)
		(end 305.799236 -230.91013)
		(width 0.101346)
		(layer "F.Cu")
		(net "M_A_CPU0_SA_DQS_DP<8>")
	)
	(arc
		(start 327.242678 -242.759992)
		(mid 327.17398 -242.775008)
		(end 327.109328 -242.802664)
		(width 0.0762)
		(layer "F.Cu")
		(net "M_A_CPU0_SA_DQS_DP<8>")
	)
	(arc
		(start 326.526652 -242.802664)
		(mid 326.343144 -242.75717)
		(end 326.160892 -242.80749)
		(width 0.0762)
		(layer "F.Cu")
		(net "M_A_CPU0_SA_DQS_DP<8>")
	)
	(arc
		(start 327.100946 -242.80749)
		(mid 326.81799 -242.883667)
		(end 326.535034 -242.80749)
		(width 0.0762)
		(layer "F.Cu")
		(net "M_A_CPU0_SA_DQS_DP<8>")
	)
	(arc
		(start 325.439024 -242.758214)
		(mid 325.423543 -242.757258)
		(end 325.408036 -242.756944)
		(width 0.0762)
		(layer "F.Cu")
		(net "M_A_CPU0_SA_DQS_DP<8>")
	)
	(arc
		(start 326.160892 -242.80749)
		(mid 325.877936 -242.883667)
		(end 325.59498 -242.80749)
		(width 0.0762)
		(layer "F.Cu")
		(net "M_A_CPU0_SA_DQS_DP<8>")
	)
	(arc
		(start 325.59498 -242.80749)
		(mid 325.51974 -242.774177)
		(end 325.439024 -242.758214)
		(width 0.0762)
		(layer "F.Cu")
		(net "M_A_CPU0_SA_DQS_DP<8>")
	)
	(arc
		(start 327.388728 -242.956588)
		(mid 327.372803 -242.815896)
		(end 327.242678 -242.759992)
		(width 0.0762)
		(layer "F.Cu")
		(net "M_A_CPU0_SA_DQS_DP<8>")
	)
	(segment
		(start 313.284108 -224.739454)
		(end 309.840884 -221.29623)
		(width 0.12954)
		(layer "F.Cu")
		(net "M_A_CPU0_SA_DQS_DP<7>")
	)
	(segment
		(start 303.800256 -221.13494)
		(end 303.268126 -221.13494)
		(width 0.101346)
		(layer "F.Cu")
		(net "M_A_CPU0_SA_DQS_DP<7>")
	)
	(segment
		(start 309.840884 -221.29623)
		(end 308.49316 -221.29623)
		(width 0.12954)
		(layer "F.Cu")
		(net "M_A_CPU0_SA_DQS_DP<7>")
	)
	(segment
		(start 304.45329 -220.81744)
		(end 304.117756 -220.81744)
		(width 0.101346)
		(layer "F.Cu")
		(net "M_A_CPU0_SA_DQS_DP<7>")
	)
	(segment
		(start 304.878232 -221.242382)
		(end 304.45329 -220.81744)
		(width 0.101346)
		(layer "F.Cu")
		(net "M_A_CPU0_SA_DQS_DP<7>")
	)
	(segment
		(start 324.565518 -237.896908)
		(end 324.437756 -238.02467)
		(width 0.0762)
		(layer "F.Cu")
		(net "M_A_CPU0_SA_DQS_DP<7>")
	)
	(segment
		(start 323.946012 -238.19993)
		(end 323.926962 -238.19993)
		(width 0.0762)
		(layer "F.Cu")
		(net "M_A_CPU0_SA_DQS_DP<7>")
	)
	(segment
		(start 305.689508 -221.559882)
		(end 305.372008 -221.242382)
		(width 0.101346)
		(layer "F.Cu")
		(net "M_A_CPU0_SA_DQS_DP<7>")
	)
	(segment
		(start 321.864736 -238.19993)
		(end 313.284108 -229.619302)
		(width 0.12954)
		(layer "F.Cu")
		(net "M_A_CPU0_SA_DQS_DP<7>")
	)
	(segment
		(start 327.28789 -238.270034)
		(end 327.388728 -238.096552)
		(width 0.0762)
		(layer "F.Cu")
		(net "M_A_CPU0_SA_DQS_DP<7>")
	)
	(segment
		(start 304.117756 -220.81744)
		(end 303.800256 -221.13494)
		(width 0.101346)
		(layer "F.Cu")
		(net "M_A_CPU0_SA_DQS_DP<7>")
	)
	(segment
		(start 308.49316 -221.29623)
		(end 308.229508 -221.559882)
		(width 0.12954)
		(layer "F.Cu")
		(net "M_A_CPU0_SA_DQS_DP<7>")
	)
	(segment
		(start 324.437756 -238.02467)
		(end 324.348602 -238.13389)
		(width 0.0762)
		(layer "F.Cu")
		(net "M_A_CPU0_SA_DQS_DP<7>")
	)
	(segment
		(start 308.229508 -221.559882)
		(end 305.689508 -221.559882)
		(width 0.101346)
		(layer "F.Cu")
		(net "M_A_CPU0_SA_DQS_DP<7>")
	)
	(segment
		(start 323.926962 -238.19993)
		(end 321.864736 -238.19993)
		(width 0.12954)
		(layer "F.Cu")
		(net "M_A_CPU0_SA_DQS_DP<7>")
	)
	(segment
		(start 326.535034 -237.947454)
		(end 326.526652 -237.942628)
		(width 0.0762)
		(layer "F.Cu")
		(net "M_A_CPU0_SA_DQS_DP<7>")
	)
	(segment
		(start 324.348602 -238.13389)
		(end 324.012052 -238.13389)
		(width 0.0762)
		(layer "F.Cu")
		(net "M_A_CPU0_SA_DQS_DP<7>")
	)
	(segment
		(start 327.109328 -237.942628)
		(end 327.100946 -237.947454)
		(width 0.0762)
		(layer "F.Cu")
		(net "M_A_CPU0_SA_DQS_DP<7>")
	)
	(segment
		(start 324.012052 -238.13389)
		(end 323.946012 -238.19993)
		(width 0.0762)
		(layer "F.Cu")
		(net "M_A_CPU0_SA_DQS_DP<7>")
	)
	(segment
		(start 313.284108 -229.619302)
		(end 313.284108 -224.739454)
		(width 0.12954)
		(layer "F.Cu")
		(net "M_A_CPU0_SA_DQS_DP<7>")
	)
	(segment
		(start 305.372008 -221.242382)
		(end 304.878232 -221.242382)
		(width 0.101346)
		(layer "F.Cu")
		(net "M_A_CPU0_SA_DQS_DP<7>")
	)
	(segment
		(start 325.408036 -237.896908)
		(end 324.565518 -237.896908)
		(width 0.0762)
		(layer "F.Cu")
		(net "M_A_CPU0_SA_DQS_DP<7>")
	)
	(arc
		(start 326.526652 -237.942628)
		(mid 326.343144 -237.897134)
		(end 326.160892 -237.947454)
		(width 0.0762)
		(layer "F.Cu")
		(net "M_A_CPU0_SA_DQS_DP<7>")
	)
	(arc
		(start 325.59498 -237.947454)
		(mid 325.51974 -237.914141)
		(end 325.439024 -237.898178)
		(width 0.0762)
		(layer "F.Cu")
		(net "M_A_CPU0_SA_DQS_DP<7>")
	)
	(arc
		(start 325.439024 -237.898178)
		(mid 325.423543 -237.897222)
		(end 325.408036 -237.896908)
		(width 0.0762)
		(layer "F.Cu")
		(net "M_A_CPU0_SA_DQS_DP<7>")
	)
	(arc
		(start 326.160892 -237.947454)
		(mid 325.877936 -238.023631)
		(end 325.59498 -237.947454)
		(width 0.0762)
		(layer "F.Cu")
		(net "M_A_CPU0_SA_DQS_DP<7>")
	)
	(arc
		(start 327.100946 -237.947454)
		(mid 326.81799 -238.023631)
		(end 326.535034 -237.947454)
		(width 0.0762)
		(layer "F.Cu")
		(net "M_A_CPU0_SA_DQS_DP<7>")
	)
	(arc
		(start 327.388728 -238.096552)
		(mid 327.372803 -237.95586)
		(end 327.242678 -237.899956)
		(width 0.0762)
		(layer "F.Cu")
		(net "M_A_CPU0_SA_DQS_DP<7>")
	)
	(arc
		(start 327.242678 -237.899956)
		(mid 327.17398 -237.914972)
		(end 327.109328 -237.942628)
		(width 0.0762)
		(layer "F.Cu")
		(net "M_A_CPU0_SA_DQS_DP<7>")
	)
	(segment
		(start 304.905664 -211.892388)
		(end 304.480722 -211.467446)
		(width 0.101346)
		(layer "F.Cu")
		(net "M_A_CPU0_SA_DQS_DP<6>")
	)
	(segment
		(start 305.372008 -211.892388)
		(end 304.905664 -211.892388)
		(width 0.101346)
		(layer "F.Cu")
		(net "M_A_CPU0_SA_DQS_DP<6>")
	)
	(segment
		(start 327.109328 -233.082592)
		(end 327.100946 -233.087418)
		(width 0.0762)
		(layer "F.Cu")
		(net "M_A_CPU0_SA_DQS_DP<6>")
	)
	(segment
		(start 317.670688 -227.757482)
		(end 317.670688 -219.685108)
		(width 0.12954)
		(layer "F.Cu")
		(net "M_A_CPU0_SA_DQS_DP<6>")
	)
	(segment
		(start 327.28789 -233.409998)
		(end 327.388728 -233.236516)
		(width 0.0762)
		(layer "F.Cu")
		(net "M_A_CPU0_SA_DQS_DP<6>")
	)
	(segment
		(start 326.535034 -233.087418)
		(end 326.526652 -233.082592)
		(width 0.0762)
		(layer "F.Cu")
		(net "M_A_CPU0_SA_DQS_DP<6>")
	)
	(segment
		(start 317.670688 -219.685108)
		(end 310.2102 -212.224874)
		(width 0.12954)
		(layer "F.Cu")
		(net "M_A_CPU0_SA_DQS_DP<6>")
	)
	(segment
		(start 325.408036 -233.036872)
		(end 324.484238 -233.036872)
		(width 0.0762)
		(layer "F.Cu")
		(net "M_A_CPU0_SA_DQS_DP<6>")
	)
	(segment
		(start 303.800256 -211.784946)
		(end 303.268126 -211.784946)
		(width 0.101346)
		(layer "F.Cu")
		(net "M_A_CPU0_SA_DQS_DP<6>")
	)
	(segment
		(start 304.117756 -211.467446)
		(end 303.800256 -211.784946)
		(width 0.101346)
		(layer "F.Cu")
		(net "M_A_CPU0_SA_DQS_DP<6>")
	)
	(segment
		(start 305.689508 -212.209888)
		(end 305.372008 -211.892388)
		(width 0.101346)
		(layer "F.Cu")
		(net "M_A_CPU0_SA_DQS_DP<6>")
	)
	(segment
		(start 324.484238 -233.036872)
		(end 324.377558 -233.143552)
		(width 0.0762)
		(layer "F.Cu")
		(net "M_A_CPU0_SA_DQS_DP<6>")
	)
	(segment
		(start 304.480722 -211.467446)
		(end 304.117756 -211.467446)
		(width 0.101346)
		(layer "F.Cu")
		(net "M_A_CPU0_SA_DQS_DP<6>")
	)
	(segment
		(start 323.981064 -233.143552)
		(end 323.915024 -233.209592)
		(width 0.0762)
		(layer "F.Cu")
		(net "M_A_CPU0_SA_DQS_DP<6>")
	)
	(segment
		(start 308.795166 -211.945728)
		(end 308.493668 -211.945728)
		(width 0.12954)
		(layer "F.Cu")
		(net "M_A_CPU0_SA_DQS_DP<6>")
	)
	(segment
		(start 324.377558 -233.143552)
		(end 323.981064 -233.143552)
		(width 0.0762)
		(layer "F.Cu")
		(net "M_A_CPU0_SA_DQS_DP<6>")
	)
	(segment
		(start 323.915024 -233.209592)
		(end 323.895974 -233.209592)
		(width 0.0762)
		(layer "F.Cu")
		(net "M_A_CPU0_SA_DQS_DP<6>")
	)
	(segment
		(start 309.074312 -212.224874)
		(end 308.795166 -211.945728)
		(width 0.12954)
		(layer "F.Cu")
		(net "M_A_CPU0_SA_DQS_DP<6>")
	)
	(segment
		(start 308.229508 -212.209888)
		(end 305.689508 -212.209888)
		(width 0.101346)
		(layer "F.Cu")
		(net "M_A_CPU0_SA_DQS_DP<6>")
	)
	(segment
		(start 323.122798 -233.209592)
		(end 317.670688 -227.757482)
		(width 0.12954)
		(layer "F.Cu")
		(net "M_A_CPU0_SA_DQS_DP<6>")
	)
	(segment
		(start 310.2102 -212.224874)
		(end 309.074312 -212.224874)
		(width 0.12954)
		(layer "F.Cu")
		(net "M_A_CPU0_SA_DQS_DP<6>")
	)
	(segment
		(start 308.493668 -211.945728)
		(end 308.229508 -212.209888)
		(width 0.12954)
		(layer "F.Cu")
		(net "M_A_CPU0_SA_DQS_DP<6>")
	)
	(segment
		(start 323.895974 -233.209592)
		(end 323.122798 -233.209592)
		(width 0.12954)
		(layer "F.Cu")
		(net "M_A_CPU0_SA_DQS_DP<6>")
	)
	(arc
		(start 327.242678 -233.03992)
		(mid 327.17398 -233.054936)
		(end 327.109328 -233.082592)
		(width 0.0762)
		(layer "F.Cu")
		(net "M_A_CPU0_SA_DQS_DP<6>")
	)
	(arc
		(start 325.59498 -233.087418)
		(mid 325.51974 -233.054105)
		(end 325.439024 -233.038142)
		(width 0.0762)
		(layer "F.Cu")
		(net "M_A_CPU0_SA_DQS_DP<6>")
	)
	(arc
		(start 327.100946 -233.087418)
		(mid 326.81799 -233.163595)
		(end 326.535034 -233.087418)
		(width 0.0762)
		(layer "F.Cu")
		(net "M_A_CPU0_SA_DQS_DP<6>")
	)
	(arc
		(start 325.439024 -233.038142)
		(mid 325.423543 -233.037186)
		(end 325.408036 -233.036872)
		(width 0.0762)
		(layer "F.Cu")
		(net "M_A_CPU0_SA_DQS_DP<6>")
	)
	(arc
		(start 327.388728 -233.236516)
		(mid 327.372803 -233.095824)
		(end 327.242678 -233.03992)
		(width 0.0762)
		(layer "F.Cu")
		(net "M_A_CPU0_SA_DQS_DP<6>")
	)
	(arc
		(start 326.526652 -233.082592)
		(mid 326.343144 -233.037098)
		(end 326.160892 -233.087418)
		(width 0.0762)
		(layer "F.Cu")
		(net "M_A_CPU0_SA_DQS_DP<6>")
	)
	(arc
		(start 326.160892 -233.087418)
		(mid 325.877936 -233.163595)
		(end 325.59498 -233.087418)
		(width 0.0762)
		(layer "F.Cu")
		(net "M_A_CPU0_SA_DQS_DP<6>")
	)
	(segment
		(start 326.535034 -228.227636)
		(end 326.526652 -228.22281)
		(width 0.0762)
		(layer "F.Cu")
		(net "M_A_CPU0_SA_DQS_DP<5>")
	)
	(segment
		(start 324.002908 -227.714302)
		(end 323.909436 -227.714302)
		(width 0.0762)
		(layer "F.Cu")
		(net "M_A_CPU0_SA_DQS_DP<5>")
	)
	(segment
		(start 323.909436 -227.714302)
		(end 323.895974 -227.70084)
		(width 0.0762)
		(layer "F.Cu")
		(net "M_A_CPU0_SA_DQS_DP<5>")
	)
	(segment
		(start 322.057268 -225.86188)
		(end 322.057268 -216.712038)
		(width 0.12954)
		(layer "F.Cu")
		(net "M_A_CPU0_SA_DQS_DP<5>")
	)
	(segment
		(start 308.755796 -202.587352)
		(end 308.50205 -202.587352)
		(width 0.12954)
		(layer "F.Cu")
		(net "M_A_CPU0_SA_DQS_DP<5>")
	)
	(segment
		(start 323.896228 -227.70084)
		(end 322.057268 -225.86188)
		(width 0.12954)
		(layer "F.Cu")
		(net "M_A_CPU0_SA_DQS_DP<5>")
	)
	(segment
		(start 322.057268 -216.712038)
		(end 320.390774 -215.045544)
		(width 0.12954)
		(layer "F.Cu")
		(net "M_A_CPU0_SA_DQS_DP<5>")
	)
	(segment
		(start 325.264526 -227.923852)
		(end 324.212458 -227.923852)
		(width 0.0762)
		(layer "F.Cu")
		(net "M_A_CPU0_SA_DQS_DP<5>")
	)
	(segment
		(start 320.390774 -214.222838)
		(end 320.1162 -213.948264)
		(width 0.12954)
		(layer "F.Cu")
		(net "M_A_CPU0_SA_DQS_DP<5>")
	)
	(segment
		(start 304.890424 -202.542394)
		(end 304.465482 -202.117452)
		(width 0.101346)
		(layer "F.Cu")
		(net "M_A_CPU0_SA_DQS_DP<5>")
	)
	(segment
		(start 304.117756 -202.117452)
		(end 303.800256 -202.434952)
		(width 0.101346)
		(layer "F.Cu")
		(net "M_A_CPU0_SA_DQS_DP<5>")
	)
	(segment
		(start 319.603882 -213.673182)
		(end 319.603882 -213.435946)
		(width 0.12954)
		(layer "F.Cu")
		(net "M_A_CPU0_SA_DQS_DP<5>")
	)
	(segment
		(start 303.800256 -202.434952)
		(end 303.268126 -202.434952)
		(width 0.101346)
		(layer "F.Cu")
		(net "M_A_CPU0_SA_DQS_DP<5>")
	)
	(segment
		(start 319.878964 -213.948264)
		(end 319.603882 -213.673182)
		(width 0.12954)
		(layer "F.Cu")
		(net "M_A_CPU0_SA_DQS_DP<5>")
	)
	(segment
		(start 325.47941 -228.138736)
		(end 325.264526 -227.923852)
		(width 0.0762)
		(layer "F.Cu")
		(net "M_A_CPU0_SA_DQS_DP<5>")
	)
	(segment
		(start 305.689508 -202.859894)
		(end 305.372008 -202.542394)
		(width 0.101346)
		(layer "F.Cu")
		(net "M_A_CPU0_SA_DQS_DP<5>")
	)
	(segment
		(start 305.372008 -202.542394)
		(end 304.890424 -202.542394)
		(width 0.101346)
		(layer "F.Cu")
		(net "M_A_CPU0_SA_DQS_DP<5>")
	)
	(segment
		(start 320.390774 -215.045544)
		(end 320.390774 -214.222838)
		(width 0.12954)
		(layer "F.Cu")
		(net "M_A_CPU0_SA_DQS_DP<5>")
	)
	(segment
		(start 319.603882 -213.435946)
		(end 308.755796 -202.587352)
		(width 0.12954)
		(layer "F.Cu")
		(net "M_A_CPU0_SA_DQS_DP<5>")
	)
	(segment
		(start 320.1162 -213.948264)
		(end 319.878964 -213.948264)
		(width 0.12954)
		(layer "F.Cu")
		(net "M_A_CPU0_SA_DQS_DP<5>")
	)
	(segment
		(start 308.229508 -202.859894)
		(end 305.689508 -202.859894)
		(width 0.101346)
		(layer "F.Cu")
		(net "M_A_CPU0_SA_DQS_DP<5>")
	)
	(segment
		(start 327.28789 -228.550216)
		(end 327.388728 -228.376734)
		(width 0.0762)
		(layer "F.Cu")
		(net "M_A_CPU0_SA_DQS_DP<5>")
	)
	(segment
		(start 323.895974 -227.70084)
		(end 323.896228 -227.70084)
		(width 0.12954)
		(layer "F.Cu")
		(net "M_A_CPU0_SA_DQS_DP<5>")
	)
	(segment
		(start 304.465482 -202.117452)
		(end 304.117756 -202.117452)
		(width 0.101346)
		(layer "F.Cu")
		(net "M_A_CPU0_SA_DQS_DP<5>")
	)
	(segment
		(start 324.212458 -227.923852)
		(end 324.002908 -227.714302)
		(width 0.0762)
		(layer "F.Cu")
		(net "M_A_CPU0_SA_DQS_DP<5>")
	)
	(segment
		(start 327.109328 -228.22281)
		(end 327.100946 -228.227636)
		(width 0.0762)
		(layer "F.Cu")
		(net "M_A_CPU0_SA_DQS_DP<5>")
	)
	(segment
		(start 308.50205 -202.587352)
		(end 308.229508 -202.859894)
		(width 0.12954)
		(layer "F.Cu")
		(net "M_A_CPU0_SA_DQS_DP<5>")
	)
	(arc
		(start 327.388728 -228.376734)
		(mid 327.372803 -228.236042)
		(end 327.242678 -228.180138)
		(width 0.0762)
		(layer "F.Cu")
		(net "M_A_CPU0_SA_DQS_DP<5>")
	)
	(arc
		(start 326.526652 -228.22281)
		(mid 326.343144 -228.177316)
		(end 326.160892 -228.227636)
		(width 0.0762)
		(layer "F.Cu")
		(net "M_A_CPU0_SA_DQS_DP<5>")
	)
	(arc
		(start 327.242678 -228.180138)
		(mid 327.17398 -228.195154)
		(end 327.109328 -228.22281)
		(width 0.0762)
		(layer "F.Cu")
		(net "M_A_CPU0_SA_DQS_DP<5>")
	)
	(arc
		(start 326.160892 -228.227636)
		(mid 325.805032 -228.299078)
		(end 325.47941 -228.138736)
		(width 0.0762)
		(layer "F.Cu")
		(net "M_A_CPU0_SA_DQS_DP<5>")
	)
	(arc
		(start 327.100946 -228.227636)
		(mid 326.81799 -228.303813)
		(end 326.535034 -228.227636)
		(width 0.0762)
		(layer "F.Cu")
		(net "M_A_CPU0_SA_DQS_DP<5>")
	)
	(segment
		(start 314.1853 -244.254782)
		(end 313.838336 -243.907818)
		(width 0.12954)
		(layer "F.Cu")
		(net "M_A_CPU0_SA_DQS_DP<4>")
	)
	(segment
		(start 311.625488 -243.214144)
		(end 311.460388 -243.049044)
		(width 0.12954)
		(layer "F.Cu")
		(net "M_A_CPU0_SA_DQS_DP<4>")
	)
	(segment
		(start 313.388248 -243.907564)
		(end 312.945018 -244.350794)
		(width 0.12954)
		(layer "F.Cu")
		(net "M_A_CPU0_SA_DQS_DP<4>")
	)
	(segment
		(start 310.021478 -240.58245)
		(end 310.021478 -239.768634)
		(width 0.12954)
		(layer "F.Cu")
		(net "M_A_CPU0_SA_DQS_DP<4>")
	)
	(segment
		(start 314.87872 -246.283988)
		(end 315.321696 -245.841012)
		(width 0.12954)
		(layer "F.Cu")
		(net "M_A_CPU0_SA_DQS_DP<4>")
	)
	(segment
		(start 314.081668 -245.487444)
		(end 313.898788 -245.487444)
		(width 0.12954)
		(layer "F.Cu")
		(net "M_A_CPU0_SA_DQS_DP<4>")
	)
	(segment
		(start 313.898788 -245.487444)
		(end 313.74207 -245.330726)
		(width 0.12954)
		(layer "F.Cu")
		(net "M_A_CPU0_SA_DQS_DP<4>")
	)
	(segment
		(start 313.048396 -243.567712)
		(end 313.04865 -243.118132)
		(width 0.12954)
		(layer "F.Cu")
		(net "M_A_CPU0_SA_DQS_DP<4>")
	)
	(segment
		(start 313.74207 -245.147338)
		(end 314.185046 -244.704362)
		(width 0.12954)
		(layer "F.Cu")
		(net "M_A_CPU0_SA_DQS_DP<4>")
	)
	(segment
		(start 308.636416 -238.383572)
		(end 308.151276 -238.383572)
		(width 0.12954)
		(layer "F.Cu")
		(net "M_A_CPU0_SA_DQS_DP<4>")
	)
	(segment
		(start 311.460388 -243.049044)
		(end 311.460388 -242.02136)
		(width 0.12954)
		(layer "F.Cu")
		(net "M_A_CPU0_SA_DQS_DP<4>")
	)
	(segment
		(start 311.808368 -243.214144)
		(end 311.625488 -243.214144)
		(width 0.12954)
		(layer "F.Cu")
		(net "M_A_CPU0_SA_DQS_DP<4>")
	)
	(segment
		(start 314.185046 -244.704362)
		(end 314.1853 -244.254782)
		(width 0.12954)
		(layer "F.Cu")
		(net "M_A_CPU0_SA_DQS_DP<4>")
	)
	(segment
		(start 312.701686 -242.771168)
		(end 312.251598 -242.770914)
		(width 0.12954)
		(layer "F.Cu")
		(net "M_A_CPU0_SA_DQS_DP<4>")
	)
	(segment
		(start 325.408036 -246.74322)
		(end 324.454774 -246.74322)
		(width 0.0762)
		(layer "F.Cu")
		(net "M_A_CPU0_SA_DQS_DP<4>")
	)
	(segment
		(start 307.902864 -238.13516)
		(end 307.368194 -238.13516)
		(width 0.12954)
		(layer "F.Cu")
		(net "M_A_CPU0_SA_DQS_DP<4>")
	)
	(segment
		(start 308.151276 -238.383572)
		(end 307.902864 -238.13516)
		(width 0.12954)
		(layer "F.Cu")
		(net "M_A_CPU0_SA_DQS_DP<4>")
	)
	(segment
		(start 313.74207 -245.330726)
		(end 313.74207 -245.147338)
		(width 0.12954)
		(layer "F.Cu")
		(net "M_A_CPU0_SA_DQS_DP<4>")
	)
	(segment
		(start 324.369684 -246.67718)
		(end 315.088524 -246.67718)
		(width 0.12954)
		(layer "F.Cu")
		(net "M_A_CPU0_SA_DQS_DP<4>")
	)
	(segment
		(start 314.524898 -245.044214)
		(end 314.081668 -245.487444)
		(width 0.12954)
		(layer "F.Cu")
		(net "M_A_CPU0_SA_DQS_DP<4>")
	)
	(segment
		(start 312.251598 -242.770914)
		(end 311.808368 -243.214144)
		(width 0.12954)
		(layer "F.Cu")
		(net "M_A_CPU0_SA_DQS_DP<4>")
	)
	(segment
		(start 313.04865 -243.118132)
		(end 312.701686 -242.771168)
		(width 0.12954)
		(layer "F.Cu")
		(net "M_A_CPU0_SA_DQS_DP<4>")
	)
	(segment
		(start 315.32195 -245.391432)
		(end 314.974986 -245.044468)
		(width 0.12954)
		(layer "F.Cu")
		(net "M_A_CPU0_SA_DQS_DP<4>")
	)
	(segment
		(start 324.454774 -246.74322)
		(end 324.388734 -246.67718)
		(width 0.0762)
		(layer "F.Cu")
		(net "M_A_CPU0_SA_DQS_DP<4>")
	)
	(segment
		(start 310.021478 -239.768634)
		(end 308.636416 -238.383572)
		(width 0.12954)
		(layer "F.Cu")
		(net "M_A_CPU0_SA_DQS_DP<4>")
	)
	(segment
		(start 315.088524 -246.67718)
		(end 314.87872 -246.467376)
		(width 0.12954)
		(layer "F.Cu")
		(net "M_A_CPU0_SA_DQS_DP<4>")
	)
	(segment
		(start 312.762138 -244.350794)
		(end 312.60542 -244.194076)
		(width 0.12954)
		(layer "F.Cu")
		(net "M_A_CPU0_SA_DQS_DP<4>")
	)
	(segment
		(start 312.60542 -244.010688)
		(end 313.048396 -243.567712)
		(width 0.12954)
		(layer "F.Cu")
		(net "M_A_CPU0_SA_DQS_DP<4>")
	)
	(segment
		(start 324.388734 -246.67718)
		(end 324.369684 -246.67718)
		(width 0.0762)
		(layer "F.Cu")
		(net "M_A_CPU0_SA_DQS_DP<4>")
	)
	(segment
		(start 315.321696 -245.841012)
		(end 315.32195 -245.391432)
		(width 0.12954)
		(layer "F.Cu")
		(net "M_A_CPU0_SA_DQS_DP<4>")
	)
	(segment
		(start 312.60542 -244.194076)
		(end 312.60542 -244.010688)
		(width 0.12954)
		(layer "F.Cu")
		(net "M_A_CPU0_SA_DQS_DP<4>")
	)
	(segment
		(start 314.87872 -246.467376)
		(end 314.87872 -246.283988)
		(width 0.12954)
		(layer "F.Cu")
		(net "M_A_CPU0_SA_DQS_DP<4>")
	)
	(segment
		(start 311.460388 -242.02136)
		(end 310.021478 -240.58245)
		(width 0.12954)
		(layer "F.Cu")
		(net "M_A_CPU0_SA_DQS_DP<4>")
	)
	(segment
		(start 313.838336 -243.907818)
		(end 313.388248 -243.907564)
		(width 0.12954)
		(layer "F.Cu")
		(net "M_A_CPU0_SA_DQS_DP<4>")
	)
	(segment
		(start 314.974986 -245.044468)
		(end 314.524898 -245.044214)
		(width 0.12954)
		(layer "F.Cu")
		(net "M_A_CPU0_SA_DQS_DP<4>")
	)
	(segment
		(start 312.945018 -244.350794)
		(end 312.762138 -244.350794)
		(width 0.12954)
		(layer "F.Cu")
		(net "M_A_CPU0_SA_DQS_DP<4>")
	)
	(arc
		(start 325.59498 -246.692674)
		(mid 325.504847 -246.730294)
		(end 325.408036 -246.74322)
		(width 0.0762)
		(layer "F.Cu")
		(net "M_A_CPU0_SA_DQS_DP<4>")
	)
	(arc
		(start 326.34809 -246.370094)
		(mid 326.105773 -246.539814)
		(end 325.820786 -246.619268)
		(width 0.0762)
		(layer "F.Cu")
		(net "M_A_CPU0_SA_DQS_DP<4>")
	)
	(arc
		(start 325.820786 -246.619268)
		(mid 325.703973 -246.643944)
		(end 325.59498 -246.692674)
		(width 0.0762)
		(layer "F.Cu")
		(net "M_A_CPU0_SA_DQS_DP<4>")
	)
	(segment
		(start 315.153802 -237.070646)
		(end 315.305694 -236.918754)
		(width 0.12954)
		(layer "F.Cu")
		(net "M_A_CPU0_SA_DQS_DP<3>")
	)
	(segment
		(start 311.895744 -233.508804)
		(end 311.895744 -233.0577)
		(width 0.12954)
		(layer "F.Cu")
		(net "M_A_CPU0_SA_DQS_DP<3>")
	)
	(segment
		(start 313.03849 -235.137706)
		(end 312.880502 -234.979718)
		(width 0.12954)
		(layer "F.Cu")
		(net "M_A_CPU0_SA_DQS_DP<3>")
	)
	(segment
		(start 316.097158 -237.259114)
		(end 315.646054 -237.259114)
		(width 0.12954)
		(layer "F.Cu")
		(net "M_A_CPU0_SA_DQS_DP<3>")
	)
	(segment
		(start 325.408036 -241.883184)
		(end 324.56882 -241.883184)
		(width 0.0762)
		(layer "F.Cu")
		(net "M_A_CPU0_SA_DQS_DP<3>")
	)
	(segment
		(start 315.305694 -236.918754)
		(end 315.305694 -236.46765)
		(width 0.12954)
		(layer "F.Cu")
		(net "M_A_CPU0_SA_DQS_DP<3>")
	)
	(segment
		(start 323.981064 -242.010184)
		(end 323.915024 -241.944144)
		(width 0.0762)
		(layer "F.Cu")
		(net "M_A_CPU0_SA_DQS_DP<3>")
	)
	(segment
		(start 318.715644 -240.328704)
		(end 318.715644 -239.8776)
		(width 0.12954)
		(layer "F.Cu")
		(net "M_A_CPU0_SA_DQS_DP<3>")
	)
	(segment
		(start 312.880502 -234.979718)
		(end 312.880502 -234.797346)
		(width 0.12954)
		(layer "F.Cu")
		(net "M_A_CPU0_SA_DQS_DP<3>")
	)
	(segment
		(start 317.919354 -239.532414)
		(end 317.767462 -239.684306)
		(width 0.12954)
		(layer "F.Cu")
		(net "M_A_CPU0_SA_DQS_DP<3>")
	)
	(segment
		(start 317.233808 -238.395764)
		(end 316.782704 -238.395764)
		(width 0.12954)
		(layer "F.Cu")
		(net "M_A_CPU0_SA_DQS_DP<3>")
	)
	(segment
		(start 313.032394 -234.645454)
		(end 313.032394 -234.19435)
		(width 0.12954)
		(layer "F.Cu")
		(net "M_A_CPU0_SA_DQS_DP<3>")
	)
	(segment
		(start 314.960508 -236.122464)
		(end 314.509404 -236.122464)
		(width 0.12954)
		(layer "F.Cu")
		(net "M_A_CPU0_SA_DQS_DP<3>")
	)
	(segment
		(start 314.169044 -235.331)
		(end 313.823858 -234.985814)
		(width 0.12954)
		(layer "F.Cu")
		(net "M_A_CPU0_SA_DQS_DP<3>")
	)
	(segment
		(start 323.895974 -241.944144)
		(end 320.782188 -241.944144)
		(width 0.12954)
		(layer "F.Cu")
		(net "M_A_CPU0_SA_DQS_DP<3>")
	)
	(segment
		(start 318.72174 -240.820956)
		(end 318.563752 -240.662968)
		(width 0.12954)
		(layer "F.Cu")
		(net "M_A_CPU0_SA_DQS_DP<3>")
	)
	(segment
		(start 316.442344 -238.055404)
		(end 316.442344 -237.6043)
		(width 0.12954)
		(layer "F.Cu")
		(net "M_A_CPU0_SA_DQS_DP<3>")
	)
	(segment
		(start 308.166516 -229.048818)
		(end 307.902864 -228.785166)
		(width 0.12954)
		(layer "F.Cu")
		(net "M_A_CPU0_SA_DQS_DP<3>")
	)
	(segment
		(start 317.427102 -239.526318)
		(end 317.427102 -239.343946)
		(width 0.12954)
		(layer "F.Cu")
		(net "M_A_CPU0_SA_DQS_DP<3>")
	)
	(segment
		(start 320.782188 -241.944144)
		(end 319.507108 -240.669064)
		(width 0.12954)
		(layer "F.Cu")
		(net "M_A_CPU0_SA_DQS_DP<3>")
	)
	(segment
		(start 314.169044 -235.782104)
		(end 314.169044 -235.331)
		(width 0.12954)
		(layer "F.Cu")
		(net "M_A_CPU0_SA_DQS_DP<3>")
	)
	(segment
		(start 315.31179 -237.411006)
		(end 315.153802 -237.253018)
		(width 0.12954)
		(layer "F.Cu")
		(net "M_A_CPU0_SA_DQS_DP<3>")
	)
	(segment
		(start 313.823858 -234.985814)
		(end 313.372754 -234.985814)
		(width 0.12954)
		(layer "F.Cu")
		(net "M_A_CPU0_SA_DQS_DP<3>")
	)
	(segment
		(start 312.236104 -233.849164)
		(end 312.084212 -234.001056)
		(width 0.12954)
		(layer "F.Cu")
		(net "M_A_CPU0_SA_DQS_DP<3>")
	)
	(segment
		(start 324.56882 -241.883184)
		(end 324.44182 -242.010184)
		(width 0.0762)
		(layer "F.Cu")
		(net "M_A_CPU0_SA_DQS_DP<3>")
	)
	(segment
		(start 314.17514 -236.274356)
		(end 314.017152 -236.116368)
		(width 0.12954)
		(layer "F.Cu")
		(net "M_A_CPU0_SA_DQS_DP<3>")
	)
	(segment
		(start 317.427102 -239.343946)
		(end 317.578994 -239.192054)
		(width 0.12954)
		(layer "F.Cu")
		(net "M_A_CPU0_SA_DQS_DP<3>")
	)
	(segment
		(start 316.782704 -238.395764)
		(end 316.630812 -238.547656)
		(width 0.12954)
		(layer "F.Cu")
		(net "M_A_CPU0_SA_DQS_DP<3>")
	)
	(segment
		(start 315.646054 -237.259114)
		(end 315.494162 -237.411006)
		(width 0.12954)
		(layer "F.Cu")
		(net "M_A_CPU0_SA_DQS_DP<3>")
	)
	(segment
		(start 307.902864 -228.785166)
		(end 307.368194 -228.785166)
		(width 0.12954)
		(layer "F.Cu")
		(net "M_A_CPU0_SA_DQS_DP<3>")
	)
	(segment
		(start 316.290452 -238.389668)
		(end 316.290452 -238.207296)
		(width 0.12954)
		(layer "F.Cu")
		(net "M_A_CPU0_SA_DQS_DP<3>")
	)
	(segment
		(start 311.743852 -233.660696)
		(end 311.895744 -233.508804)
		(width 0.12954)
		(layer "F.Cu")
		(net "M_A_CPU0_SA_DQS_DP<3>")
	)
	(segment
		(start 311.90184 -234.001056)
		(end 311.743852 -233.843068)
		(width 0.12954)
		(layer "F.Cu")
		(net "M_A_CPU0_SA_DQS_DP<3>")
	)
	(segment
		(start 316.630812 -238.547656)
		(end 316.44844 -238.547656)
		(width 0.12954)
		(layer "F.Cu")
		(net "M_A_CPU0_SA_DQS_DP<3>")
	)
	(segment
		(start 319.507108 -240.669064)
		(end 319.056004 -240.669064)
		(width 0.12954)
		(layer "F.Cu")
		(net "M_A_CPU0_SA_DQS_DP<3>")
	)
	(segment
		(start 317.58509 -239.684306)
		(end 317.427102 -239.526318)
		(width 0.12954)
		(layer "F.Cu")
		(net "M_A_CPU0_SA_DQS_DP<3>")
	)
	(segment
		(start 314.357512 -236.274356)
		(end 314.17514 -236.274356)
		(width 0.12954)
		(layer "F.Cu")
		(net "M_A_CPU0_SA_DQS_DP<3>")
	)
	(segment
		(start 318.715644 -239.8776)
		(end 318.370458 -239.532414)
		(width 0.12954)
		(layer "F.Cu")
		(net "M_A_CPU0_SA_DQS_DP<3>")
	)
	(segment
		(start 317.578994 -238.74095)
		(end 317.233808 -238.395764)
		(width 0.12954)
		(layer "F.Cu")
		(net "M_A_CPU0_SA_DQS_DP<3>")
	)
	(segment
		(start 319.056004 -240.669064)
		(end 318.904112 -240.820956)
		(width 0.12954)
		(layer "F.Cu")
		(net "M_A_CPU0_SA_DQS_DP<3>")
	)
	(segment
		(start 314.509404 -236.122464)
		(end 314.357512 -236.274356)
		(width 0.12954)
		(layer "F.Cu")
		(net "M_A_CPU0_SA_DQS_DP<3>")
	)
	(segment
		(start 316.44844 -238.547656)
		(end 316.290452 -238.389668)
		(width 0.12954)
		(layer "F.Cu")
		(net "M_A_CPU0_SA_DQS_DP<3>")
	)
	(segment
		(start 313.372754 -234.985814)
		(end 313.220862 -235.137706)
		(width 0.12954)
		(layer "F.Cu")
		(net "M_A_CPU0_SA_DQS_DP<3>")
	)
	(segment
		(start 308.674262 -229.048818)
		(end 308.166516 -229.048818)
		(width 0.12954)
		(layer "F.Cu")
		(net "M_A_CPU0_SA_DQS_DP<3>")
	)
	(segment
		(start 311.743852 -233.843068)
		(end 311.743852 -233.660696)
		(width 0.12954)
		(layer "F.Cu")
		(net "M_A_CPU0_SA_DQS_DP<3>")
	)
	(segment
		(start 315.153802 -237.253018)
		(end 315.153802 -237.070646)
		(width 0.12954)
		(layer "F.Cu")
		(net "M_A_CPU0_SA_DQS_DP<3>")
	)
	(segment
		(start 318.370458 -239.532414)
		(end 317.919354 -239.532414)
		(width 0.12954)
		(layer "F.Cu")
		(net "M_A_CPU0_SA_DQS_DP<3>")
	)
	(segment
		(start 312.084212 -234.001056)
		(end 311.90184 -234.001056)
		(width 0.12954)
		(layer "F.Cu")
		(net "M_A_CPU0_SA_DQS_DP<3>")
	)
	(segment
		(start 316.442344 -237.6043)
		(end 316.097158 -237.259114)
		(width 0.12954)
		(layer "F.Cu")
		(net "M_A_CPU0_SA_DQS_DP<3>")
	)
	(segment
		(start 312.880502 -234.797346)
		(end 313.032394 -234.645454)
		(width 0.12954)
		(layer "F.Cu")
		(net "M_A_CPU0_SA_DQS_DP<3>")
	)
	(segment
		(start 318.563752 -240.480596)
		(end 318.715644 -240.328704)
		(width 0.12954)
		(layer "F.Cu")
		(net "M_A_CPU0_SA_DQS_DP<3>")
	)
	(segment
		(start 323.915024 -241.944144)
		(end 323.895974 -241.944144)
		(width 0.0762)
		(layer "F.Cu")
		(net "M_A_CPU0_SA_DQS_DP<3>")
	)
	(segment
		(start 315.494162 -237.411006)
		(end 315.31179 -237.411006)
		(width 0.12954)
		(layer "F.Cu")
		(net "M_A_CPU0_SA_DQS_DP<3>")
	)
	(segment
		(start 316.290452 -238.207296)
		(end 316.442344 -238.055404)
		(width 0.12954)
		(layer "F.Cu")
		(net "M_A_CPU0_SA_DQS_DP<3>")
	)
	(segment
		(start 314.017152 -235.933996)
		(end 314.169044 -235.782104)
		(width 0.12954)
		(layer "F.Cu")
		(net "M_A_CPU0_SA_DQS_DP<3>")
	)
	(segment
		(start 309.88889 -231.050846)
		(end 309.88889 -230.263446)
		(width 0.12954)
		(layer "F.Cu")
		(net "M_A_CPU0_SA_DQS_DP<3>")
	)
	(segment
		(start 317.578994 -239.192054)
		(end 317.578994 -238.74095)
		(width 0.12954)
		(layer "F.Cu")
		(net "M_A_CPU0_SA_DQS_DP<3>")
	)
	(segment
		(start 318.904112 -240.820956)
		(end 318.72174 -240.820956)
		(width 0.12954)
		(layer "F.Cu")
		(net "M_A_CPU0_SA_DQS_DP<3>")
	)
	(segment
		(start 309.88889 -230.263446)
		(end 308.674262 -229.048818)
		(width 0.12954)
		(layer "F.Cu")
		(net "M_A_CPU0_SA_DQS_DP<3>")
	)
	(segment
		(start 318.563752 -240.662968)
		(end 318.563752 -240.480596)
		(width 0.12954)
		(layer "F.Cu")
		(net "M_A_CPU0_SA_DQS_DP<3>")
	)
	(segment
		(start 315.305694 -236.46765)
		(end 314.960508 -236.122464)
		(width 0.12954)
		(layer "F.Cu")
		(net "M_A_CPU0_SA_DQS_DP<3>")
	)
	(segment
		(start 313.220862 -235.137706)
		(end 313.03849 -235.137706)
		(width 0.12954)
		(layer "F.Cu")
		(net "M_A_CPU0_SA_DQS_DP<3>")
	)
	(segment
		(start 314.017152 -236.116368)
		(end 314.017152 -235.933996)
		(width 0.12954)
		(layer "F.Cu")
		(net "M_A_CPU0_SA_DQS_DP<3>")
	)
	(segment
		(start 317.767462 -239.684306)
		(end 317.58509 -239.684306)
		(width 0.12954)
		(layer "F.Cu")
		(net "M_A_CPU0_SA_DQS_DP<3>")
	)
	(segment
		(start 324.44182 -242.010184)
		(end 323.981064 -242.010184)
		(width 0.0762)
		(layer "F.Cu")
		(net "M_A_CPU0_SA_DQS_DP<3>")
	)
	(segment
		(start 311.895744 -233.0577)
		(end 309.88889 -231.050846)
		(width 0.12954)
		(layer "F.Cu")
		(net "M_A_CPU0_SA_DQS_DP<3>")
	)
	(segment
		(start 312.687208 -233.849164)
		(end 312.236104 -233.849164)
		(width 0.12954)
		(layer "F.Cu")
		(net "M_A_CPU0_SA_DQS_DP<3>")
	)
	(segment
		(start 313.032394 -234.19435)
		(end 312.687208 -233.849164)
		(width 0.12954)
		(layer "F.Cu")
		(net "M_A_CPU0_SA_DQS_DP<3>")
	)
	(arc
		(start 326.34809 -241.510058)
		(mid 326.105773 -241.679778)
		(end 325.820786 -241.759232)
		(width 0.0762)
		(layer "F.Cu")
		(net "M_A_CPU0_SA_DQS_DP<3>")
	)
	(arc
		(start 325.820786 -241.759232)
		(mid 325.703973 -241.783908)
		(end 325.59498 -241.832638)
		(width 0.0762)
		(layer "F.Cu")
		(net "M_A_CPU0_SA_DQS_DP<3>")
	)
	(arc
		(start 325.59498 -241.832638)
		(mid 325.504847 -241.870258)
		(end 325.408036 -241.883184)
		(width 0.0762)
		(layer "F.Cu")
		(net "M_A_CPU0_SA_DQS_DP<3>")
	)
	(segment
		(start 324.174104 -237.16869)
		(end 324.108064 -237.10265)
		(width 0.0762)
		(layer "F.Cu")
		(net "M_A_CPU0_SA_DQS_DP<2>")
	)
	(segment
		(start 313.538108 -222.30715)
		(end 313.049666 -222.795592)
		(width 0.12954)
		(layer "F.Cu")
		(net "M_A_CPU0_SA_DQS_DP<2>")
	)
	(segment
		(start 312.709814 -222.45574)
		(end 313.364626 -221.800928)
		(width 0.12954)
		(layer "F.Cu")
		(net "M_A_CPU0_SA_DQS_DP<2>")
	)
	(segment
		(start 311.264808 -220.03385)
		(end 310.776366 -220.522292)
		(width 0.12954)
		(layer "F.Cu")
		(net "M_A_CPU0_SA_DQS_DP<2>")
	)
	(segment
		(start 311.573164 -221.502478)
		(end 311.573164 -221.31909)
		(width 0.12954)
		(layer "F.Cu")
		(net "M_A_CPU0_SA_DQS_DP<2>")
	)
	(segment
		(start 313.846464 -223.775778)
		(end 313.846464 -223.59239)
		(width 0.12954)
		(layer "F.Cu")
		(net "M_A_CPU0_SA_DQS_DP<2>")
	)
	(segment
		(start 313.988196 -222.30715)
		(end 313.538108 -222.30715)
		(width 0.12954)
		(layer "F.Cu")
		(net "M_A_CPU0_SA_DQS_DP<2>")
	)
	(segment
		(start 313.364626 -221.800928)
		(end 313.364626 -221.35084)
		(width 0.12954)
		(layer "F.Cu")
		(net "M_A_CPU0_SA_DQS_DP<2>")
	)
	(segment
		(start 324.089014 -237.10265)
		(end 322.290694 -237.10265)
		(width 0.12954)
		(layer "F.Cu")
		(net "M_A_CPU0_SA_DQS_DP<2>")
	)
	(segment
		(start 314.350908 -224.280222)
		(end 313.846464 -223.775778)
		(width 0.12954)
		(layer "F.Cu")
		(net "M_A_CPU0_SA_DQS_DP<2>")
	)
	(segment
		(start 311.729628 -221.658942)
		(end 311.573164 -221.502478)
		(width 0.12954)
		(layer "F.Cu")
		(net "M_A_CPU0_SA_DQS_DP<2>")
	)
	(segment
		(start 312.709814 -222.639128)
		(end 312.709814 -222.45574)
		(width 0.12954)
		(layer "F.Cu")
		(net "M_A_CPU0_SA_DQS_DP<2>")
	)
	(segment
		(start 311.573164 -221.31909)
		(end 312.061606 -220.830648)
		(width 0.12954)
		(layer "F.Cu")
		(net "M_A_CPU0_SA_DQS_DP<2>")
	)
	(segment
		(start 309.76951 -219.698824)
		(end 308.166516 -219.698824)
		(width 0.12954)
		(layer "F.Cu")
		(net "M_A_CPU0_SA_DQS_DP<2>")
	)
	(segment
		(start 311.913016 -221.658942)
		(end 311.729628 -221.658942)
		(width 0.12954)
		(layer "F.Cu")
		(net "M_A_CPU0_SA_DQS_DP<2>")
	)
	(segment
		(start 324.108064 -237.10265)
		(end 324.089014 -237.10265)
		(width 0.0762)
		(layer "F.Cu")
		(net "M_A_CPU0_SA_DQS_DP<2>")
	)
	(segment
		(start 313.017916 -221.00413)
		(end 312.567828 -221.00413)
		(width 0.12954)
		(layer "F.Cu")
		(net "M_A_CPU0_SA_DQS_DP<2>")
	)
	(segment
		(start 313.049666 -222.795592)
		(end 312.866278 -222.795592)
		(width 0.12954)
		(layer "F.Cu")
		(net "M_A_CPU0_SA_DQS_DP<2>")
	)
	(segment
		(start 314.334906 -223.103948)
		(end 314.334906 -222.65386)
		(width 0.12954)
		(layer "F.Cu")
		(net "M_A_CPU0_SA_DQS_DP<2>")
	)
	(segment
		(start 314.350908 -229.162864)
		(end 314.350908 -224.280222)
		(width 0.12954)
		(layer "F.Cu")
		(net "M_A_CPU0_SA_DQS_DP<2>")
	)
	(segment
		(start 311.714896 -220.03385)
		(end 311.264808 -220.03385)
		(width 0.12954)
		(layer "F.Cu")
		(net "M_A_CPU0_SA_DQS_DP<2>")
	)
	(segment
		(start 313.364626 -221.35084)
		(end 313.017916 -221.00413)
		(width 0.12954)
		(layer "F.Cu")
		(net "M_A_CPU0_SA_DQS_DP<2>")
	)
	(segment
		(start 322.290694 -237.10265)
		(end 314.350908 -229.162864)
		(width 0.12954)
		(layer "F.Cu")
		(net "M_A_CPU0_SA_DQS_DP<2>")
	)
	(segment
		(start 325.408036 -237.023148)
		(end 324.439788 -237.023148)
		(width 0.0762)
		(layer "F.Cu")
		(net "M_A_CPU0_SA_DQS_DP<2>")
	)
	(segment
		(start 324.439788 -237.023148)
		(end 324.294246 -237.16869)
		(width 0.0762)
		(layer "F.Cu")
		(net "M_A_CPU0_SA_DQS_DP<2>")
	)
	(segment
		(start 312.061606 -220.830648)
		(end 312.061606 -220.38056)
		(width 0.12954)
		(layer "F.Cu")
		(net "M_A_CPU0_SA_DQS_DP<2>")
	)
	(segment
		(start 307.902864 -219.435172)
		(end 307.368194 -219.435172)
		(width 0.12954)
		(layer "F.Cu")
		(net "M_A_CPU0_SA_DQS_DP<2>")
	)
	(segment
		(start 312.567828 -221.00413)
		(end 311.913016 -221.658942)
		(width 0.12954)
		(layer "F.Cu")
		(net "M_A_CPU0_SA_DQS_DP<2>")
	)
	(segment
		(start 308.166516 -219.698824)
		(end 307.902864 -219.435172)
		(width 0.12954)
		(layer "F.Cu")
		(net "M_A_CPU0_SA_DQS_DP<2>")
	)
	(segment
		(start 310.776366 -220.522292)
		(end 310.592978 -220.522292)
		(width 0.12954)
		(layer "F.Cu")
		(net "M_A_CPU0_SA_DQS_DP<2>")
	)
	(segment
		(start 313.846464 -223.59239)
		(end 314.334906 -223.103948)
		(width 0.12954)
		(layer "F.Cu")
		(net "M_A_CPU0_SA_DQS_DP<2>")
	)
	(segment
		(start 310.592978 -220.522292)
		(end 309.76951 -219.698824)
		(width 0.12954)
		(layer "F.Cu")
		(net "M_A_CPU0_SA_DQS_DP<2>")
	)
	(segment
		(start 324.294246 -237.16869)
		(end 324.174104 -237.16869)
		(width 0.0762)
		(layer "F.Cu")
		(net "M_A_CPU0_SA_DQS_DP<2>")
	)
	(segment
		(start 312.061606 -220.38056)
		(end 311.714896 -220.03385)
		(width 0.12954)
		(layer "F.Cu")
		(net "M_A_CPU0_SA_DQS_DP<2>")
	)
	(segment
		(start 312.866278 -222.795592)
		(end 312.709814 -222.639128)
		(width 0.12954)
		(layer "F.Cu")
		(net "M_A_CPU0_SA_DQS_DP<2>")
	)
	(segment
		(start 314.334906 -222.65386)
		(end 313.988196 -222.30715)
		(width 0.12954)
		(layer "F.Cu")
		(net "M_A_CPU0_SA_DQS_DP<2>")
	)
	(arc
		(start 325.59498 -236.972602)
		(mid 325.504847 -237.010222)
		(end 325.408036 -237.023148)
		(width 0.0762)
		(layer "F.Cu")
		(net "M_A_CPU0_SA_DQS_DP<2>")
	)
	(arc
		(start 325.820786 -236.899196)
		(mid 325.703973 -236.923872)
		(end 325.59498 -236.972602)
		(width 0.0762)
		(layer "F.Cu")
		(net "M_A_CPU0_SA_DQS_DP<2>")
	)
	(arc
		(start 326.34809 -236.650022)
		(mid 326.105773 -236.819742)
		(end 325.820786 -236.899196)
		(width 0.0762)
		(layer "F.Cu")
		(net "M_A_CPU0_SA_DQS_DP<2>")
	)
	(segment
		(start 315.419486 -215.924638)
		(end 315.263022 -215.768174)
		(width 0.12954)
		(layer "F.Cu")
		(net "M_A_CPU0_SA_DQS_DP<1>")
	)
	(segment
		(start 314.126372 -214.448136)
		(end 314.34278 -214.231728)
		(width 0.12954)
		(layer "F.Cu")
		(net "M_A_CPU0_SA_DQS_DP<1>")
	)
	(segment
		(start 325.408036 -232.163112)
		(end 324.203314 -232.163112)
		(width 0.0762)
		(layer "F.Cu")
		(net "M_A_CPU0_SA_DQS_DP<1>")
	)
	(segment
		(start 318.737488 -219.24264)
		(end 317.536322 -218.041474)
		(width 0.12954)
		(layer "F.Cu")
		(net "M_A_CPU0_SA_DQS_DP<1>")
	)
	(segment
		(start 315.13272 -214.57158)
		(end 314.682632 -214.57158)
		(width 0.12954)
		(layer "F.Cu")
		(net "M_A_CPU0_SA_DQS_DP<1>")
	)
	(segment
		(start 315.263022 -215.768174)
		(end 315.263022 -215.584786)
		(width 0.12954)
		(layer "F.Cu")
		(net "M_A_CPU0_SA_DQS_DP<1>")
	)
	(segment
		(start 313.329574 -213.651338)
		(end 313.146186 -213.651338)
		(width 0.12954)
		(layer "F.Cu")
		(net "M_A_CPU0_SA_DQS_DP<1>")
	)
	(segment
		(start 312.409332 -212.29828)
		(end 312.192924 -212.514688)
		(width 0.12954)
		(layer "F.Cu")
		(net "M_A_CPU0_SA_DQS_DP<1>")
	)
	(segment
		(start 312.192924 -212.514688)
		(end 312.009536 -212.514688)
		(width 0.12954)
		(layer "F.Cu")
		(net "M_A_CPU0_SA_DQS_DP<1>")
	)
	(segment
		(start 312.009536 -212.514688)
		(end 311.853072 -212.358224)
		(width 0.12954)
		(layer "F.Cu")
		(net "M_A_CPU0_SA_DQS_DP<1>")
	)
	(segment
		(start 316.556136 -217.061288)
		(end 316.399672 -216.904824)
		(width 0.12954)
		(layer "F.Cu")
		(net "M_A_CPU0_SA_DQS_DP<1>")
	)
	(segment
		(start 318.737488 -227.301044)
		(end 318.737488 -219.24264)
		(width 0.12954)
		(layer "F.Cu")
		(net "M_A_CPU0_SA_DQS_DP<1>")
	)
	(segment
		(start 308.729126 -210.34883)
		(end 308.166516 -210.34883)
		(width 0.12954)
		(layer "F.Cu")
		(net "M_A_CPU0_SA_DQS_DP<1>")
	)
	(segment
		(start 311.173876 -211.260436)
		(end 311.056274 -211.378038)
		(width 0.12954)
		(layer "F.Cu")
		(net "M_A_CPU0_SA_DQS_DP<1>")
	)
	(segment
		(start 313.20613 -212.64499)
		(end 312.85942 -212.29828)
		(width 0.12954)
		(layer "F.Cu")
		(net "M_A_CPU0_SA_DQS_DP<1>")
	)
	(segment
		(start 324.118224 -232.097072)
		(end 323.533516 -232.097072)
		(width 0.12954)
		(layer "F.Cu")
		(net "M_A_CPU0_SA_DQS_DP<1>")
	)
	(segment
		(start 317.536322 -218.041474)
		(end 317.536322 -217.858086)
		(width 0.12954)
		(layer "F.Cu")
		(net "M_A_CPU0_SA_DQS_DP<1>")
	)
	(segment
		(start 316.399672 -216.721436)
		(end 316.61608 -216.505028)
		(width 0.12954)
		(layer "F.Cu")
		(net "M_A_CPU0_SA_DQS_DP<1>")
	)
	(segment
		(start 315.47943 -214.91829)
		(end 315.13272 -214.57158)
		(width 0.12954)
		(layer "F.Cu")
		(net "M_A_CPU0_SA_DQS_DP<1>")
	)
	(segment
		(start 317.40602 -216.84488)
		(end 316.955932 -216.84488)
		(width 0.12954)
		(layer "F.Cu")
		(net "M_A_CPU0_SA_DQS_DP<1>")
	)
	(segment
		(start 314.682632 -214.57158)
		(end 314.466224 -214.787988)
		(width 0.12954)
		(layer "F.Cu")
		(net "M_A_CPU0_SA_DQS_DP<1>")
	)
	(segment
		(start 314.466224 -214.787988)
		(end 314.282836 -214.787988)
		(width 0.12954)
		(layer "F.Cu")
		(net "M_A_CPU0_SA_DQS_DP<1>")
	)
	(segment
		(start 309.536592 -211.156296)
		(end 308.729126 -210.34883)
		(width 0.12954)
		(layer "F.Cu")
		(net "M_A_CPU0_SA_DQS_DP<1>")
	)
	(segment
		(start 311.056274 -211.378038)
		(end 310.872886 -211.378038)
		(width 0.12954)
		(layer "F.Cu")
		(net "M_A_CPU0_SA_DQS_DP<1>")
	)
	(segment
		(start 311.970674 -212.057234)
		(end 311.970674 -211.607146)
		(width 0.12954)
		(layer "F.Cu")
		(net "M_A_CPU0_SA_DQS_DP<1>")
	)
	(segment
		(start 310.872886 -211.378038)
		(end 310.651144 -211.156296)
		(width 0.12954)
		(layer "F.Cu")
		(net "M_A_CPU0_SA_DQS_DP<1>")
	)
	(segment
		(start 308.166516 -210.34883)
		(end 307.902864 -210.085178)
		(width 0.12954)
		(layer "F.Cu")
		(net "M_A_CPU0_SA_DQS_DP<1>")
	)
	(segment
		(start 313.20613 -213.095078)
		(end 313.20613 -212.64499)
		(width 0.12954)
		(layer "F.Cu")
		(net "M_A_CPU0_SA_DQS_DP<1>")
	)
	(segment
		(start 314.282836 -214.787988)
		(end 314.126372 -214.631524)
		(width 0.12954)
		(layer "F.Cu")
		(net "M_A_CPU0_SA_DQS_DP<1>")
	)
	(segment
		(start 312.989722 -213.494874)
		(end 312.989722 -213.311486)
		(width 0.12954)
		(layer "F.Cu")
		(net "M_A_CPU0_SA_DQS_DP<1>")
	)
	(segment
		(start 311.623964 -211.260436)
		(end 311.173876 -211.260436)
		(width 0.12954)
		(layer "F.Cu")
		(net "M_A_CPU0_SA_DQS_DP<1>")
	)
	(segment
		(start 324.203314 -232.163112)
		(end 324.137274 -232.097072)
		(width 0.0762)
		(layer "F.Cu")
		(net "M_A_CPU0_SA_DQS_DP<1>")
	)
	(segment
		(start 317.536322 -217.858086)
		(end 317.75273 -217.641678)
		(width 0.12954)
		(layer "F.Cu")
		(net "M_A_CPU0_SA_DQS_DP<1>")
	)
	(segment
		(start 312.989722 -213.311486)
		(end 313.20613 -213.095078)
		(width 0.12954)
		(layer "F.Cu")
		(net "M_A_CPU0_SA_DQS_DP<1>")
	)
	(segment
		(start 312.85942 -212.29828)
		(end 312.409332 -212.29828)
		(width 0.12954)
		(layer "F.Cu")
		(net "M_A_CPU0_SA_DQS_DP<1>")
	)
	(segment
		(start 316.61608 -216.05494)
		(end 316.26937 -215.70823)
		(width 0.12954)
		(layer "F.Cu")
		(net "M_A_CPU0_SA_DQS_DP<1>")
	)
	(segment
		(start 311.970674 -211.607146)
		(end 311.623964 -211.260436)
		(width 0.12954)
		(layer "F.Cu")
		(net "M_A_CPU0_SA_DQS_DP<1>")
	)
	(segment
		(start 315.47943 -215.368378)
		(end 315.47943 -214.91829)
		(width 0.12954)
		(layer "F.Cu")
		(net "M_A_CPU0_SA_DQS_DP<1>")
	)
	(segment
		(start 316.739524 -217.061288)
		(end 316.556136 -217.061288)
		(width 0.12954)
		(layer "F.Cu")
		(net "M_A_CPU0_SA_DQS_DP<1>")
	)
	(segment
		(start 307.902864 -210.085178)
		(end 307.368194 -210.085178)
		(width 0.12954)
		(layer "F.Cu")
		(net "M_A_CPU0_SA_DQS_DP<1>")
	)
	(segment
		(start 316.61608 -216.505028)
		(end 316.61608 -216.05494)
		(width 0.12954)
		(layer "F.Cu")
		(net "M_A_CPU0_SA_DQS_DP<1>")
	)
	(segment
		(start 317.75273 -217.19159)
		(end 317.40602 -216.84488)
		(width 0.12954)
		(layer "F.Cu")
		(net "M_A_CPU0_SA_DQS_DP<1>")
	)
	(segment
		(start 311.853072 -212.174836)
		(end 311.970674 -212.057234)
		(width 0.12954)
		(layer "F.Cu")
		(net "M_A_CPU0_SA_DQS_DP<1>")
	)
	(segment
		(start 315.263022 -215.584786)
		(end 315.47943 -215.368378)
		(width 0.12954)
		(layer "F.Cu")
		(net "M_A_CPU0_SA_DQS_DP<1>")
	)
	(segment
		(start 315.819282 -215.70823)
		(end 315.602874 -215.924638)
		(width 0.12954)
		(layer "F.Cu")
		(net "M_A_CPU0_SA_DQS_DP<1>")
	)
	(segment
		(start 324.137274 -232.097072)
		(end 324.118224 -232.097072)
		(width 0.0762)
		(layer "F.Cu")
		(net "M_A_CPU0_SA_DQS_DP<1>")
	)
	(segment
		(start 323.533516 -232.097072)
		(end 318.737488 -227.301044)
		(width 0.12954)
		(layer "F.Cu")
		(net "M_A_CPU0_SA_DQS_DP<1>")
	)
	(segment
		(start 314.34278 -214.231728)
		(end 314.34278 -213.78164)
		(width 0.12954)
		(layer "F.Cu")
		(net "M_A_CPU0_SA_DQS_DP<1>")
	)
	(segment
		(start 316.26937 -215.70823)
		(end 315.819282 -215.70823)
		(width 0.12954)
		(layer "F.Cu")
		(net "M_A_CPU0_SA_DQS_DP<1>")
	)
	(segment
		(start 317.75273 -217.641678)
		(end 317.75273 -217.19159)
		(width 0.12954)
		(layer "F.Cu")
		(net "M_A_CPU0_SA_DQS_DP<1>")
	)
	(segment
		(start 314.34278 -213.78164)
		(end 313.99607 -213.43493)
		(width 0.12954)
		(layer "F.Cu")
		(net "M_A_CPU0_SA_DQS_DP<1>")
	)
	(segment
		(start 313.99607 -213.43493)
		(end 313.545982 -213.43493)
		(width 0.12954)
		(layer "F.Cu")
		(net "M_A_CPU0_SA_DQS_DP<1>")
	)
	(segment
		(start 310.651144 -211.156296)
		(end 309.536592 -211.156296)
		(width 0.12954)
		(layer "F.Cu")
		(net "M_A_CPU0_SA_DQS_DP<1>")
	)
	(segment
		(start 311.853072 -212.358224)
		(end 311.853072 -212.174836)
		(width 0.12954)
		(layer "F.Cu")
		(net "M_A_CPU0_SA_DQS_DP<1>")
	)
	(segment
		(start 313.146186 -213.651338)
		(end 312.989722 -213.494874)
		(width 0.12954)
		(layer "F.Cu")
		(net "M_A_CPU0_SA_DQS_DP<1>")
	)
	(segment
		(start 315.602874 -215.924638)
		(end 315.419486 -215.924638)
		(width 0.12954)
		(layer "F.Cu")
		(net "M_A_CPU0_SA_DQS_DP<1>")
	)
	(segment
		(start 316.955932 -216.84488)
		(end 316.739524 -217.061288)
		(width 0.12954)
		(layer "F.Cu")
		(net "M_A_CPU0_SA_DQS_DP<1>")
	)
	(segment
		(start 313.545982 -213.43493)
		(end 313.329574 -213.651338)
		(width 0.12954)
		(layer "F.Cu")
		(net "M_A_CPU0_SA_DQS_DP<1>")
	)
	(segment
		(start 314.126372 -214.631524)
		(end 314.126372 -214.448136)
		(width 0.12954)
		(layer "F.Cu")
		(net "M_A_CPU0_SA_DQS_DP<1>")
	)
	(segment
		(start 316.399672 -216.904824)
		(end 316.399672 -216.721436)
		(width 0.12954)
		(layer "F.Cu")
		(net "M_A_CPU0_SA_DQS_DP<1>")
	)
	(arc
		(start 325.59498 -232.112566)
		(mid 325.504847 -232.150186)
		(end 325.408036 -232.163112)
		(width 0.0762)
		(layer "F.Cu")
		(net "M_A_CPU0_SA_DQS_DP<1>")
	)
	(arc
		(start 325.820786 -232.03916)
		(mid 325.703973 -232.063836)
		(end 325.59498 -232.112566)
		(width 0.0762)
		(layer "F.Cu")
		(net "M_A_CPU0_SA_DQS_DP<1>")
	)
	(arc
		(start 326.34809 -231.789986)
		(mid 326.105773 -231.959706)
		(end 325.820786 -232.03916)
		(width 0.0762)
		(layer "F.Cu")
		(net "M_A_CPU0_SA_DQS_DP<1>")
	)
	(segment
		(start 321.865244 -214.010748)
		(end 321.865244 -213.559644)
		(width 0.12954)
		(layer "F.Cu")
		(net "M_A_CPU0_SA_DQS_DP<0>")
	)
	(segment
		(start 320.001646 -211.696046)
		(end 319.63741 -211.33181)
		(width 0.12954)
		(layer "F.Cu")
		(net "M_A_CPU0_SA_DQS_DP<0>")
	)
	(segment
		(start 324.420992 -226.672902)
		(end 324.420992 -226.673156)
		(width 0.12954)
		(layer "F.Cu")
		(net "M_A_CPU0_SA_DQS_DP<0>")
	)
	(segment
		(start 313.181746 -204.876146)
		(end 312.81751 -204.51191)
		(width 0.12954)
		(layer "F.Cu")
		(net "M_A_CPU0_SA_DQS_DP<0>")
	)
	(segment
		(start 324.434454 -226.78009)
		(end 324.434454 -226.686364)
		(width 0.0762)
		(layer "F.Cu")
		(net "M_A_CPU0_SA_DQS_DP<0>")
	)
	(segment
		(start 315.455046 -207.744822)
		(end 315.455046 -207.149446)
		(width 0.12954)
		(layer "F.Cu")
		(net "M_A_CPU0_SA_DQS_DP<0>")
	)
	(segment
		(start 318.50076 -210.19516)
		(end 317.905384 -210.19516)
		(width 0.12954)
		(layer "F.Cu")
		(net "M_A_CPU0_SA_DQS_DP<0>")
	)
	(segment
		(start 310.54421 -202.23861)
		(end 309.948834 -202.23861)
		(width 0.12954)
		(layer "F.Cu")
		(net "M_A_CPU0_SA_DQS_DP<0>")
	)
	(segment
		(start 311.085484 -203.37526)
		(end 310.908446 -203.198222)
		(width 0.12954)
		(layer "F.Cu")
		(net "M_A_CPU0_SA_DQS_DP<0>")
	)
	(segment
		(start 324.434454 -226.686364)
		(end 324.420992 -226.672902)
		(width 0.0762)
		(layer "F.Cu")
		(net "M_A_CPU0_SA_DQS_DP<0>")
	)
	(segment
		(start 309.771796 -201.466196)
		(end 309.304436 -200.998836)
		(width 0.12954)
		(layer "F.Cu")
		(net "M_A_CPU0_SA_DQS_DP<0>")
	)
	(segment
		(start 315.632084 -207.92186)
		(end 315.455046 -207.744822)
		(width 0.12954)
		(layer "F.Cu")
		(net "M_A_CPU0_SA_DQS_DP<0>")
	)
	(segment
		(start 307.902864 -200.735184)
		(end 307.368194 -200.735184)
		(width 0.12954)
		(layer "F.Cu")
		(net "M_A_CPU0_SA_DQS_DP<0>")
	)
	(segment
		(start 315.09081 -206.78521)
		(end 314.495434 -206.78521)
		(width 0.12954)
		(layer "F.Cu")
		(net "M_A_CPU0_SA_DQS_DP<0>")
	)
	(segment
		(start 316.591696 -208.286096)
		(end 316.22746 -207.92186)
		(width 0.12954)
		(layer "F.Cu")
		(net "M_A_CPU0_SA_DQS_DP<0>")
	)
	(segment
		(start 316.591696 -208.881472)
		(end 316.591696 -208.286096)
		(width 0.12954)
		(layer "F.Cu")
		(net "M_A_CPU0_SA_DQS_DP<0>")
	)
	(segment
		(start 309.771796 -202.061572)
		(end 309.771796 -201.466196)
		(width 0.12954)
		(layer "F.Cu")
		(net "M_A_CPU0_SA_DQS_DP<0>")
	)
	(segment
		(start 312.222134 -204.51191)
		(end 312.045096 -204.334872)
		(width 0.12954)
		(layer "F.Cu")
		(net "M_A_CPU0_SA_DQS_DP<0>")
	)
	(segment
		(start 322.205604 -214.351108)
		(end 321.797934 -214.758778)
		(width 0.12954)
		(layer "F.Cu")
		(net "M_A_CPU0_SA_DQS_DP<0>")
	)
	(segment
		(start 318.864996 -211.154772)
		(end 318.864996 -210.559396)
		(width 0.12954)
		(layer "F.Cu")
		(net "M_A_CPU0_SA_DQS_DP<0>")
	)
	(segment
		(start 317.36411 -209.05851)
		(end 316.768734 -209.05851)
		(width 0.12954)
		(layer "F.Cu")
		(net "M_A_CPU0_SA_DQS_DP<0>")
	)
	(segment
		(start 316.768734 -209.05851)
		(end 316.591696 -208.881472)
		(width 0.12954)
		(layer "F.Cu")
		(net "M_A_CPU0_SA_DQS_DP<0>")
	)
	(segment
		(start 325.408036 -227.30333)
		(end 324.957694 -227.30333)
		(width 0.0762)
		(layer "F.Cu")
		(net "M_A_CPU0_SA_DQS_DP<0>")
	)
	(segment
		(start 324.420992 -226.673156)
		(end 323.124068 -225.376232)
		(width 0.12954)
		(layer "F.Cu")
		(net "M_A_CPU0_SA_DQS_DP<0>")
	)
	(segment
		(start 321.615562 -214.758778)
		(end 321.457574 -214.60079)
		(width 0.12954)
		(layer "F.Cu")
		(net "M_A_CPU0_SA_DQS_DP<0>")
	)
	(segment
		(start 309.304436 -200.998836)
		(end 308.166516 -200.998836)
		(width 0.12954)
		(layer "F.Cu")
		(net "M_A_CPU0_SA_DQS_DP<0>")
	)
	(segment
		(start 323.124068 -214.818468)
		(end 322.656708 -214.351108)
		(width 0.12954)
		(layer "F.Cu")
		(net "M_A_CPU0_SA_DQS_DP<0>")
	)
	(segment
		(start 308.166516 -200.998836)
		(end 307.902864 -200.735184)
		(width 0.12954)
		(layer "F.Cu")
		(net "M_A_CPU0_SA_DQS_DP<0>")
	)
	(segment
		(start 320.77406 -212.46846)
		(end 320.178684 -212.46846)
		(width 0.12954)
		(layer "F.Cu")
		(net "M_A_CPU0_SA_DQS_DP<0>")
	)
	(segment
		(start 310.908446 -202.602846)
		(end 310.54421 -202.23861)
		(width 0.12954)
		(layer "F.Cu")
		(net "M_A_CPU0_SA_DQS_DP<0>")
	)
	(segment
		(start 323.124068 -225.376232)
		(end 323.124068 -214.818468)
		(width 0.12954)
		(layer "F.Cu")
		(net "M_A_CPU0_SA_DQS_DP<0>")
	)
	(segment
		(start 317.728346 -210.018122)
		(end 317.728346 -209.422746)
		(width 0.12954)
		(layer "F.Cu")
		(net "M_A_CPU0_SA_DQS_DP<0>")
	)
	(segment
		(start 312.045096 -204.334872)
		(end 312.045096 -203.739496)
		(width 0.12954)
		(layer "F.Cu")
		(net "M_A_CPU0_SA_DQS_DP<0>")
	)
	(segment
		(start 313.181746 -205.471522)
		(end 313.181746 -204.876146)
		(width 0.12954)
		(layer "F.Cu")
		(net "M_A_CPU0_SA_DQS_DP<0>")
	)
	(segment
		(start 313.358784 -205.64856)
		(end 313.181746 -205.471522)
		(width 0.12954)
		(layer "F.Cu")
		(net "M_A_CPU0_SA_DQS_DP<0>")
	)
	(segment
		(start 319.63741 -211.33181)
		(end 319.042034 -211.33181)
		(width 0.12954)
		(layer "F.Cu")
		(net "M_A_CPU0_SA_DQS_DP<0>")
	)
	(segment
		(start 318.864996 -210.559396)
		(end 318.50076 -210.19516)
		(width 0.12954)
		(layer "F.Cu")
		(net "M_A_CPU0_SA_DQS_DP<0>")
	)
	(segment
		(start 321.457574 -214.60079)
		(end 321.457574 -214.418418)
		(width 0.12954)
		(layer "F.Cu")
		(net "M_A_CPU0_SA_DQS_DP<0>")
	)
	(segment
		(start 321.865244 -213.559644)
		(end 320.77406 -212.46846)
		(width 0.12954)
		(layer "F.Cu")
		(net "M_A_CPU0_SA_DQS_DP<0>")
	)
	(segment
		(start 309.948834 -202.23861)
		(end 309.771796 -202.061572)
		(width 0.12954)
		(layer "F.Cu")
		(net "M_A_CPU0_SA_DQS_DP<0>")
	)
	(segment
		(start 310.908446 -203.198222)
		(end 310.908446 -202.602846)
		(width 0.12954)
		(layer "F.Cu")
		(net "M_A_CPU0_SA_DQS_DP<0>")
	)
	(segment
		(start 324.957694 -227.30333)
		(end 324.434454 -226.78009)
		(width 0.0762)
		(layer "F.Cu")
		(net "M_A_CPU0_SA_DQS_DP<0>")
	)
	(segment
		(start 317.728346 -209.422746)
		(end 317.36411 -209.05851)
		(width 0.12954)
		(layer "F.Cu")
		(net "M_A_CPU0_SA_DQS_DP<0>")
	)
	(segment
		(start 321.457574 -214.418418)
		(end 321.865244 -214.010748)
		(width 0.12954)
		(layer "F.Cu")
		(net "M_A_CPU0_SA_DQS_DP<0>")
	)
	(segment
		(start 316.22746 -207.92186)
		(end 315.632084 -207.92186)
		(width 0.12954)
		(layer "F.Cu")
		(net "M_A_CPU0_SA_DQS_DP<0>")
	)
	(segment
		(start 319.042034 -211.33181)
		(end 318.864996 -211.154772)
		(width 0.12954)
		(layer "F.Cu")
		(net "M_A_CPU0_SA_DQS_DP<0>")
	)
	(segment
		(start 314.495434 -206.78521)
		(end 314.318396 -206.608172)
		(width 0.12954)
		(layer "F.Cu")
		(net "M_A_CPU0_SA_DQS_DP<0>")
	)
	(segment
		(start 314.318396 -206.608172)
		(end 314.318396 -206.012796)
		(width 0.12954)
		(layer "F.Cu")
		(net "M_A_CPU0_SA_DQS_DP<0>")
	)
	(segment
		(start 314.318396 -206.012796)
		(end 313.95416 -205.64856)
		(width 0.12954)
		(layer "F.Cu")
		(net "M_A_CPU0_SA_DQS_DP<0>")
	)
	(segment
		(start 317.905384 -210.19516)
		(end 317.728346 -210.018122)
		(width 0.12954)
		(layer "F.Cu")
		(net "M_A_CPU0_SA_DQS_DP<0>")
	)
	(segment
		(start 320.178684 -212.46846)
		(end 320.001646 -212.291422)
		(width 0.12954)
		(layer "F.Cu")
		(net "M_A_CPU0_SA_DQS_DP<0>")
	)
	(segment
		(start 322.656708 -214.351108)
		(end 322.205604 -214.351108)
		(width 0.12954)
		(layer "F.Cu")
		(net "M_A_CPU0_SA_DQS_DP<0>")
	)
	(segment
		(start 311.68086 -203.37526)
		(end 311.085484 -203.37526)
		(width 0.12954)
		(layer "F.Cu")
		(net "M_A_CPU0_SA_DQS_DP<0>")
	)
	(segment
		(start 313.95416 -205.64856)
		(end 313.358784 -205.64856)
		(width 0.12954)
		(layer "F.Cu")
		(net "M_A_CPU0_SA_DQS_DP<0>")
	)
	(segment
		(start 312.81751 -204.51191)
		(end 312.222134 -204.51191)
		(width 0.12954)
		(layer "F.Cu")
		(net "M_A_CPU0_SA_DQS_DP<0>")
	)
	(segment
		(start 321.797934 -214.758778)
		(end 321.615562 -214.758778)
		(width 0.12954)
		(layer "F.Cu")
		(net "M_A_CPU0_SA_DQS_DP<0>")
	)
	(segment
		(start 315.455046 -207.149446)
		(end 315.09081 -206.78521)
		(width 0.12954)
		(layer "F.Cu")
		(net "M_A_CPU0_SA_DQS_DP<0>")
	)
	(segment
		(start 320.001646 -212.291422)
		(end 320.001646 -211.696046)
		(width 0.12954)
		(layer "F.Cu")
		(net "M_A_CPU0_SA_DQS_DP<0>")
	)
	(segment
		(start 312.045096 -203.739496)
		(end 311.68086 -203.37526)
		(width 0.12954)
		(layer "F.Cu")
		(net "M_A_CPU0_SA_DQS_DP<0>")
	)
	(arc
		(start 325.59498 -227.252784)
		(mid 325.504847 -227.290404)
		(end 325.408036 -227.30333)
		(width 0.0762)
		(layer "F.Cu")
		(net "M_A_CPU0_SA_DQS_DP<0>")
	)
	(arc
		(start 325.820786 -227.179378)
		(mid 325.703973 -227.204054)
		(end 325.59498 -227.252784)
		(width 0.0762)
		(layer "F.Cu")
		(net "M_A_CPU0_SA_DQS_DP<0>")
	)
	(arc
		(start 326.34809 -226.930204)
		(mid 326.105773 -227.099924)
		(end 325.820786 -227.179378)
		(width 0.0762)
		(layer "F.Cu")
		(net "M_A_CPU0_SA_DQS_DP<0>")
	)
	(segment
		(start 308.229508 -239.41024)
		(end 305.808888 -239.41024)
		(width 0.101346)
		(layer "F.Cu")
		(net "M_A_CPU0_SA_DQS_DN<9>")
	)
	(segment
		(start 310.716168 -242.330224)
		(end 309.277258 -240.891314)
		(width 0.12954)
		(layer "F.Cu")
		(net "M_A_CPU0_SA_DQS_DN<9>")
	)
	(segment
		(start 305.49088 -239.728248)
		(end 305.206146 -239.728248)
		(width 0.101346)
		(layer "F.Cu")
		(net "M_A_CPU0_SA_DQS_DN<9>")
	)
	(segment
		(start 308.839616 -239.653572)
		(end 308.47284 -239.653572)
		(width 0.12954)
		(layer "F.Cu")
		(net "M_A_CPU0_SA_DQS_DN<9>")
	)
	(segment
		(start 324.298564 -247.583452)
		(end 323.981064 -247.583452)
		(width 0.0762)
		(layer "F.Cu")
		(net "M_A_CPU0_SA_DQS_DN<9>")
	)
	(segment
		(start 325.699374 -247.507506)
		(end 325.690992 -247.50268)
		(width 0.0762)
		(layer "F.Cu")
		(net "M_A_CPU0_SA_DQS_DN<9>")
	)
	(segment
		(start 314.875672 -247.517412)
		(end 310.716168 -243.357908)
		(width 0.12954)
		(layer "F.Cu")
		(net "M_A_CPU0_SA_DQS_DN<9>")
	)
	(segment
		(start 305.206146 -239.728248)
		(end 304.779934 -239.302036)
		(width 0.101346)
		(layer "F.Cu")
		(net "M_A_CPU0_SA_DQS_DN<9>")
	)
	(segment
		(start 325.40829 -247.42648)
		(end 324.455536 -247.42648)
		(width 0.0762)
		(layer "F.Cu")
		(net "M_A_CPU0_SA_DQS_DN<9>")
	)
	(segment
		(start 309.277258 -240.891314)
		(end 309.277258 -240.091214)
		(width 0.12954)
		(layer "F.Cu")
		(net "M_A_CPU0_SA_DQS_DN<9>")
	)
	(segment
		(start 310.716168 -243.357908)
		(end 310.716168 -242.330224)
		(width 0.12954)
		(layer "F.Cu")
		(net "M_A_CPU0_SA_DQS_DN<9>")
	)
	(segment
		(start 304.117502 -239.302036)
		(end 303.80051 -238.985044)
		(width 0.101346)
		(layer "F.Cu")
		(net "M_A_CPU0_SA_DQS_DN<9>")
	)
	(segment
		(start 303.80051 -238.985044)
		(end 303.268126 -238.985044)
		(width 0.101346)
		(layer "F.Cu")
		(net "M_A_CPU0_SA_DQS_DN<9>")
	)
	(segment
		(start 309.277258 -240.091214)
		(end 308.839616 -239.653572)
		(width 0.12954)
		(layer "F.Cu")
		(net "M_A_CPU0_SA_DQS_DN<9>")
	)
	(segment
		(start 305.808888 -239.41024)
		(end 305.49088 -239.728248)
		(width 0.101346)
		(layer "F.Cu")
		(net "M_A_CPU0_SA_DQS_DN<9>")
	)
	(segment
		(start 323.895974 -247.517412)
		(end 314.875672 -247.517412)
		(width 0.12954)
		(layer "F.Cu")
		(net "M_A_CPU0_SA_DQS_DN<9>")
	)
	(segment
		(start 324.455536 -247.42648)
		(end 324.298564 -247.583452)
		(width 0.0762)
		(layer "F.Cu")
		(net "M_A_CPU0_SA_DQS_DN<9>")
	)
	(segment
		(start 323.915024 -247.517412)
		(end 323.895974 -247.517412)
		(width 0.0762)
		(layer "F.Cu")
		(net "M_A_CPU0_SA_DQS_DN<9>")
	)
	(segment
		(start 308.47284 -239.653572)
		(end 308.229508 -239.41024)
		(width 0.12954)
		(layer "F.Cu")
		(net "M_A_CPU0_SA_DQS_DN<9>")
	)
	(segment
		(start 323.981064 -247.583452)
		(end 323.915024 -247.517412)
		(width 0.0762)
		(layer "F.Cu")
		(net "M_A_CPU0_SA_DQS_DN<9>")
	)
	(segment
		(start 304.779934 -239.302036)
		(end 304.117502 -239.302036)
		(width 0.101346)
		(layer "F.Cu")
		(net "M_A_CPU0_SA_DQS_DN<9>")
	)
	(arc
		(start 326.065134 -247.50268)
		(mid 325.882883 -247.55303)
		(end 325.699374 -247.507506)
		(width 0.0762)
		(layer "F.Cu")
		(net "M_A_CPU0_SA_DQS_DN<9>")
	)
	(arc
		(start 326.631046 -247.50268)
		(mid 326.34809 -247.426503)
		(end 326.065134 -247.50268)
		(width 0.0762)
		(layer "F.Cu")
		(net "M_A_CPU0_SA_DQS_DN<9>")
	)
	(arc
		(start 325.690992 -247.50268)
		(mid 325.577268 -247.452379)
		(end 325.45528 -247.428258)
		(width 0.0762)
		(layer "F.Cu")
		(net "M_A_CPU0_SA_DQS_DN<9>")
	)
	(arc
		(start 325.45528 -247.428258)
		(mid 325.431803 -247.426882)
		(end 325.40829 -247.42648)
		(width 0.0762)
		(layer "F.Cu")
		(net "M_A_CPU0_SA_DQS_DN<9>")
	)
	(arc
		(start 327.758044 -247.1801)
		(mid 327.520432 -247.351088)
		(end 327.238106 -247.428512)
		(width 0.0762)
		(layer "F.Cu")
		(net "M_A_CPU0_SA_DQS_DN<9>")
	)
	(arc
		(start 327.004934 -247.50268)
		(mid 326.81799 -247.552935)
		(end 326.631046 -247.50268)
		(width 0.0762)
		(layer "F.Cu")
		(net "M_A_CPU0_SA_DQS_DN<9>")
	)
	(arc
		(start 327.238106 -247.428512)
		(mid 327.117457 -247.452813)
		(end 327.004934 -247.50268)
		(width 0.0762)
		(layer "F.Cu")
		(net "M_A_CPU0_SA_DQS_DN<9>")
	)
	(segment
		(start 308.815232 -230.319072)
		(end 308.488334 -230.319072)
		(width 0.12954)
		(layer "F.Cu")
		(net "M_A_CPU0_SA_DQS_DN<8>")
	)
	(segment
		(start 325.40829 -242.566444)
		(end 324.512178 -242.566444)
		(width 0.0762)
		(layer "F.Cu")
		(net "M_A_CPU0_SA_DQS_DN<8>")
	)
	(segment
		(start 323.9135 -242.70335)
		(end 323.89445 -242.70335)
		(width 0.0762)
		(layer "F.Cu")
		(net "M_A_CPU0_SA_DQS_DN<8>")
	)
	(segment
		(start 309.133494 -231.38765)
		(end 309.133494 -230.637334)
		(width 0.12954)
		(layer "F.Cu")
		(net "M_A_CPU0_SA_DQS_DN<8>")
	)
	(segment
		(start 323.89445 -242.70335)
		(end 319.55105 -242.70335)
		(width 0.12954)
		(layer "F.Cu")
		(net "M_A_CPU0_SA_DQS_DN<8>")
	)
	(segment
		(start 305.49088 -230.378254)
		(end 305.187858 -230.378254)
		(width 0.101346)
		(layer "F.Cu")
		(net "M_A_CPU0_SA_DQS_DN<8>")
	)
	(segment
		(start 324.35292 -242.725702)
		(end 324.31101 -242.76939)
		(width 0.0762)
		(layer "F.Cu")
		(net "M_A_CPU0_SA_DQS_DN<8>")
	)
	(segment
		(start 308.488334 -230.319072)
		(end 308.229508 -230.060246)
		(width 0.12954)
		(layer "F.Cu")
		(net "M_A_CPU0_SA_DQS_DN<8>")
	)
	(segment
		(start 310.290464 -232.54462)
		(end 309.133494 -231.38765)
		(width 0.12954)
		(layer "F.Cu")
		(net "M_A_CPU0_SA_DQS_DN<8>")
	)
	(segment
		(start 319.55105 -242.70335)
		(end 310.290464 -233.442764)
		(width 0.12954)
		(layer "F.Cu")
		(net "M_A_CPU0_SA_DQS_DN<8>")
	)
	(segment
		(start 303.80051 -229.63505)
		(end 303.268126 -229.63505)
		(width 0.101346)
		(layer "F.Cu")
		(net "M_A_CPU0_SA_DQS_DN<8>")
	)
	(segment
		(start 305.187858 -230.378254)
		(end 304.761646 -229.952042)
		(width 0.101346)
		(layer "F.Cu")
		(net "M_A_CPU0_SA_DQS_DN<8>")
	)
	(segment
		(start 309.133494 -230.637334)
		(end 308.815232 -230.319072)
		(width 0.12954)
		(layer "F.Cu")
		(net "M_A_CPU0_SA_DQS_DN<8>")
	)
	(segment
		(start 325.699374 -242.64747)
		(end 325.690992 -242.642644)
		(width 0.0762)
		(layer "F.Cu")
		(net "M_A_CPU0_SA_DQS_DN<8>")
	)
	(segment
		(start 304.761646 -229.952042)
		(end 304.117502 -229.952042)
		(width 0.101346)
		(layer "F.Cu")
		(net "M_A_CPU0_SA_DQS_DN<8>")
	)
	(segment
		(start 310.290464 -233.442764)
		(end 310.290464 -232.54462)
		(width 0.12954)
		(layer "F.Cu")
		(net "M_A_CPU0_SA_DQS_DN<8>")
	)
	(segment
		(start 324.512178 -242.566444)
		(end 324.35292 -242.725702)
		(width 0.0762)
		(layer "F.Cu")
		(net "M_A_CPU0_SA_DQS_DN<8>")
	)
	(segment
		(start 304.117502 -229.952042)
		(end 303.80051 -229.63505)
		(width 0.101346)
		(layer "F.Cu")
		(net "M_A_CPU0_SA_DQS_DN<8>")
	)
	(segment
		(start 323.97954 -242.76939)
		(end 323.9135 -242.70335)
		(width 0.0762)
		(layer "F.Cu")
		(net "M_A_CPU0_SA_DQS_DN<8>")
	)
	(segment
		(start 324.31101 -242.76939)
		(end 323.97954 -242.76939)
		(width 0.0762)
		(layer "F.Cu")
		(net "M_A_CPU0_SA_DQS_DN<8>")
	)
	(segment
		(start 308.229508 -230.060246)
		(end 305.808888 -230.060246)
		(width 0.101346)
		(layer "F.Cu")
		(net "M_A_CPU0_SA_DQS_DN<8>")
	)
	(segment
		(start 305.808888 -230.060246)
		(end 305.49088 -230.378254)
		(width 0.101346)
		(layer "F.Cu")
		(net "M_A_CPU0_SA_DQS_DN<8>")
	)
	(arc
		(start 326.065134 -242.642644)
		(mid 325.882883 -242.692994)
		(end 325.699374 -242.64747)
		(width 0.0762)
		(layer "F.Cu")
		(net "M_A_CPU0_SA_DQS_DN<8>")
	)
	(arc
		(start 327.238106 -242.568476)
		(mid 327.117457 -242.592777)
		(end 327.004934 -242.642644)
		(width 0.0762)
		(layer "F.Cu")
		(net "M_A_CPU0_SA_DQS_DN<8>")
	)
	(arc
		(start 325.45528 -242.568222)
		(mid 325.431803 -242.566846)
		(end 325.40829 -242.566444)
		(width 0.0762)
		(layer "F.Cu")
		(net "M_A_CPU0_SA_DQS_DN<8>")
	)
	(arc
		(start 325.690992 -242.642644)
		(mid 325.577268 -242.592343)
		(end 325.45528 -242.568222)
		(width 0.0762)
		(layer "F.Cu")
		(net "M_A_CPU0_SA_DQS_DN<8>")
	)
	(arc
		(start 327.004934 -242.642644)
		(mid 326.81799 -242.692899)
		(end 326.631046 -242.642644)
		(width 0.0762)
		(layer "F.Cu")
		(net "M_A_CPU0_SA_DQS_DN<8>")
	)
	(arc
		(start 326.631046 -242.642644)
		(mid 326.34809 -242.566467)
		(end 326.065134 -242.642644)
		(width 0.0762)
		(layer "F.Cu")
		(net "M_A_CPU0_SA_DQS_DN<8>")
	)
	(arc
		(start 327.758044 -242.320064)
		(mid 327.520432 -242.491052)
		(end 327.238106 -242.568476)
		(width 0.0762)
		(layer "F.Cu")
		(net "M_A_CPU0_SA_DQS_DN<8>")
	)
	(segment
		(start 304.96764 -221.026736)
		(end 304.542698 -220.601794)
		(width 0.101346)
		(layer "F.Cu")
		(net "M_A_CPU0_SA_DQS_DN<7>")
	)
	(segment
		(start 308.49316 -220.97365)
		(end 308.229508 -220.709998)
		(width 0.12954)
		(layer "F.Cu")
		(net "M_A_CPU0_SA_DQS_DN<7>")
	)
	(segment
		(start 304.542698 -220.601794)
		(end 304.116994 -220.601794)
		(width 0.101346)
		(layer "F.Cu")
		(net "M_A_CPU0_SA_DQS_DN<7>")
	)
	(segment
		(start 325.40829 -237.706408)
		(end 324.486524 -237.706408)
		(width 0.0762)
		(layer "F.Cu")
		(net "M_A_CPU0_SA_DQS_DN<7>")
	)
	(segment
		(start 321.998594 -237.87735)
		(end 313.606688 -229.485444)
		(width 0.12954)
		(layer "F.Cu")
		(net "M_A_CPU0_SA_DQS_DN<7>")
	)
	(segment
		(start 323.926962 -237.87735)
		(end 321.998594 -237.87735)
		(width 0.12954)
		(layer "F.Cu")
		(net "M_A_CPU0_SA_DQS_DN<7>")
	)
	(segment
		(start 304.116994 -220.601794)
		(end 303.800256 -220.285056)
		(width 0.101346)
		(layer "F.Cu")
		(net "M_A_CPU0_SA_DQS_DN<7>")
	)
	(segment
		(start 323.946012 -237.87735)
		(end 323.926962 -237.87735)
		(width 0.0762)
		(layer "F.Cu")
		(net "M_A_CPU0_SA_DQS_DN<7>")
	)
	(segment
		(start 324.486524 -237.706408)
		(end 324.296278 -237.896654)
		(width 0.0762)
		(layer "F.Cu")
		(net "M_A_CPU0_SA_DQS_DN<7>")
	)
	(segment
		(start 305.689508 -220.709998)
		(end 305.37277 -221.026736)
		(width 0.101346)
		(layer "F.Cu")
		(net "M_A_CPU0_SA_DQS_DN<7>")
	)
	(segment
		(start 324.012052 -237.94339)
		(end 323.946012 -237.87735)
		(width 0.0762)
		(layer "F.Cu")
		(net "M_A_CPU0_SA_DQS_DN<7>")
	)
	(segment
		(start 313.606688 -224.605596)
		(end 309.974742 -220.97365)
		(width 0.12954)
		(layer "F.Cu")
		(net "M_A_CPU0_SA_DQS_DN<7>")
	)
	(segment
		(start 309.974742 -220.97365)
		(end 308.49316 -220.97365)
		(width 0.12954)
		(layer "F.Cu")
		(net "M_A_CPU0_SA_DQS_DN<7>")
	)
	(segment
		(start 324.296278 -237.896654)
		(end 324.258178 -237.94339)
		(width 0.0762)
		(layer "F.Cu")
		(net "M_A_CPU0_SA_DQS_DN<7>")
	)
	(segment
		(start 303.800256 -220.285056)
		(end 303.268126 -220.285056)
		(width 0.101346)
		(layer "F.Cu")
		(net "M_A_CPU0_SA_DQS_DN<7>")
	)
	(segment
		(start 324.258178 -237.94339)
		(end 324.012052 -237.94339)
		(width 0.0762)
		(layer "F.Cu")
		(net "M_A_CPU0_SA_DQS_DN<7>")
	)
	(segment
		(start 325.699374 -237.787434)
		(end 325.690992 -237.782608)
		(width 0.0762)
		(layer "F.Cu")
		(net "M_A_CPU0_SA_DQS_DN<7>")
	)
	(segment
		(start 305.37277 -221.026736)
		(end 304.96764 -221.026736)
		(width 0.101346)
		(layer "F.Cu")
		(net "M_A_CPU0_SA_DQS_DN<7>")
	)
	(segment
		(start 313.606688 -229.485444)
		(end 313.606688 -224.605596)
		(width 0.12954)
		(layer "F.Cu")
		(net "M_A_CPU0_SA_DQS_DN<7>")
	)
	(segment
		(start 308.229508 -220.709998)
		(end 305.689508 -220.709998)
		(width 0.101346)
		(layer "F.Cu")
		(net "M_A_CPU0_SA_DQS_DN<7>")
	)
	(arc
		(start 327.004934 -237.782608)
		(mid 326.81799 -237.832863)
		(end 326.631046 -237.782608)
		(width 0.0762)
		(layer "F.Cu")
		(net "M_A_CPU0_SA_DQS_DN<7>")
	)
	(arc
		(start 326.631046 -237.782608)
		(mid 326.34809 -237.706431)
		(end 326.065134 -237.782608)
		(width 0.0762)
		(layer "F.Cu")
		(net "M_A_CPU0_SA_DQS_DN<7>")
	)
	(arc
		(start 325.45528 -237.708186)
		(mid 325.431803 -237.70681)
		(end 325.40829 -237.706408)
		(width 0.0762)
		(layer "F.Cu")
		(net "M_A_CPU0_SA_DQS_DN<7>")
	)
	(arc
		(start 326.065134 -237.782608)
		(mid 325.882883 -237.832958)
		(end 325.699374 -237.787434)
		(width 0.0762)
		(layer "F.Cu")
		(net "M_A_CPU0_SA_DQS_DN<7>")
	)
	(arc
		(start 327.238106 -237.70844)
		(mid 327.117457 -237.732741)
		(end 327.004934 -237.782608)
		(width 0.0762)
		(layer "F.Cu")
		(net "M_A_CPU0_SA_DQS_DN<7>")
	)
	(arc
		(start 327.758044 -237.460028)
		(mid 327.520432 -237.631016)
		(end 327.238106 -237.70844)
		(width 0.0762)
		(layer "F.Cu")
		(net "M_A_CPU0_SA_DQS_DN<7>")
	)
	(arc
		(start 325.690992 -237.782608)
		(mid 325.577268 -237.732307)
		(end 325.45528 -237.708186)
		(width 0.0762)
		(layer "F.Cu")
		(net "M_A_CPU0_SA_DQS_DN<7>")
	)
	(segment
		(start 323.981064 -232.953052)
		(end 323.915024 -232.887012)
		(width 0.0762)
		(layer "F.Cu")
		(net "M_A_CPU0_SA_DQS_DN<6>")
	)
	(segment
		(start 325.699374 -232.927398)
		(end 325.690992 -232.922572)
		(width 0.0762)
		(layer "F.Cu")
		(net "M_A_CPU0_SA_DQS_DN<6>")
	)
	(segment
		(start 310.344058 -211.902294)
		(end 309.20817 -211.902294)
		(width 0.12954)
		(layer "F.Cu")
		(net "M_A_CPU0_SA_DQS_DN<6>")
	)
	(segment
		(start 317.993268 -219.55125)
		(end 310.344058 -211.902294)
		(width 0.12954)
		(layer "F.Cu")
		(net "M_A_CPU0_SA_DQS_DN<6>")
	)
	(segment
		(start 309.20817 -211.902294)
		(end 308.929024 -211.623148)
		(width 0.12954)
		(layer "F.Cu")
		(net "M_A_CPU0_SA_DQS_DN<6>")
	)
	(segment
		(start 308.929024 -211.623148)
		(end 308.492652 -211.623148)
		(width 0.12954)
		(layer "F.Cu")
		(net "M_A_CPU0_SA_DQS_DN<6>")
	)
	(segment
		(start 305.37277 -211.676742)
		(end 304.995072 -211.676742)
		(width 0.101346)
		(layer "F.Cu")
		(net "M_A_CPU0_SA_DQS_DN<6>")
	)
	(segment
		(start 304.116994 -211.2518)
		(end 303.800256 -210.935062)
		(width 0.101346)
		(layer "F.Cu")
		(net "M_A_CPU0_SA_DQS_DN<6>")
	)
	(segment
		(start 324.405244 -232.846372)
		(end 324.298564 -232.953052)
		(width 0.0762)
		(layer "F.Cu")
		(net "M_A_CPU0_SA_DQS_DN<6>")
	)
	(segment
		(start 303.800256 -210.935062)
		(end 303.268126 -210.935062)
		(width 0.101346)
		(layer "F.Cu")
		(net "M_A_CPU0_SA_DQS_DN<6>")
	)
	(segment
		(start 325.40829 -232.846372)
		(end 324.405244 -232.846372)
		(width 0.0762)
		(layer "F.Cu")
		(net "M_A_CPU0_SA_DQS_DN<6>")
	)
	(segment
		(start 305.689508 -211.360004)
		(end 305.37277 -211.676742)
		(width 0.101346)
		(layer "F.Cu")
		(net "M_A_CPU0_SA_DQS_DN<6>")
	)
	(segment
		(start 308.492652 -211.623148)
		(end 308.229508 -211.360004)
		(width 0.12954)
		(layer "F.Cu")
		(net "M_A_CPU0_SA_DQS_DN<6>")
	)
	(segment
		(start 323.895974 -232.887012)
		(end 323.256656 -232.887012)
		(width 0.12954)
		(layer "F.Cu")
		(net "M_A_CPU0_SA_DQS_DN<6>")
	)
	(segment
		(start 324.298564 -232.953052)
		(end 323.981064 -232.953052)
		(width 0.0762)
		(layer "F.Cu")
		(net "M_A_CPU0_SA_DQS_DN<6>")
	)
	(segment
		(start 317.993268 -227.623624)
		(end 317.993268 -219.55125)
		(width 0.12954)
		(layer "F.Cu")
		(net "M_A_CPU0_SA_DQS_DN<6>")
	)
	(segment
		(start 323.915024 -232.887012)
		(end 323.895974 -232.887012)
		(width 0.0762)
		(layer "F.Cu")
		(net "M_A_CPU0_SA_DQS_DN<6>")
	)
	(segment
		(start 304.995072 -211.676742)
		(end 304.57013 -211.2518)
		(width 0.101346)
		(layer "F.Cu")
		(net "M_A_CPU0_SA_DQS_DN<6>")
	)
	(segment
		(start 308.229508 -211.360004)
		(end 305.689508 -211.360004)
		(width 0.101346)
		(layer "F.Cu")
		(net "M_A_CPU0_SA_DQS_DN<6>")
	)
	(segment
		(start 304.57013 -211.2518)
		(end 304.116994 -211.2518)
		(width 0.101346)
		(layer "F.Cu")
		(net "M_A_CPU0_SA_DQS_DN<6>")
	)
	(segment
		(start 323.256656 -232.887012)
		(end 317.993268 -227.623624)
		(width 0.12954)
		(layer "F.Cu")
		(net "M_A_CPU0_SA_DQS_DN<6>")
	)
	(arc
		(start 325.45528 -232.84815)
		(mid 325.431803 -232.846774)
		(end 325.40829 -232.846372)
		(width 0.0762)
		(layer "F.Cu")
		(net "M_A_CPU0_SA_DQS_DN<6>")
	)
	(arc
		(start 325.690992 -232.922572)
		(mid 325.577268 -232.872271)
		(end 325.45528 -232.84815)
		(width 0.0762)
		(layer "F.Cu")
		(net "M_A_CPU0_SA_DQS_DN<6>")
	)
	(arc
		(start 327.758044 -232.599992)
		(mid 327.520432 -232.77098)
		(end 327.238106 -232.848404)
		(width 0.0762)
		(layer "F.Cu")
		(net "M_A_CPU0_SA_DQS_DN<6>")
	)
	(arc
		(start 326.631046 -232.922572)
		(mid 326.34809 -232.846395)
		(end 326.065134 -232.922572)
		(width 0.0762)
		(layer "F.Cu")
		(net "M_A_CPU0_SA_DQS_DN<6>")
	)
	(arc
		(start 327.238106 -232.848404)
		(mid 327.117457 -232.872705)
		(end 327.004934 -232.922572)
		(width 0.0762)
		(layer "F.Cu")
		(net "M_A_CPU0_SA_DQS_DN<6>")
	)
	(arc
		(start 326.065134 -232.922572)
		(mid 325.882883 -232.972922)
		(end 325.699374 -232.927398)
		(width 0.0762)
		(layer "F.Cu")
		(net "M_A_CPU0_SA_DQS_DN<6>")
	)
	(arc
		(start 327.004934 -232.922572)
		(mid 326.81799 -232.972827)
		(end 326.631046 -232.922572)
		(width 0.0762)
		(layer "F.Cu")
		(net "M_A_CPU0_SA_DQS_DN<6>")
	)
	(segment
		(start 308.48427 -202.264772)
		(end 308.229508 -202.01001)
		(width 0.12954)
		(layer "F.Cu")
		(net "M_A_CPU0_SA_DQS_DN<5>")
	)
	(segment
		(start 325.34352 -227.733352)
		(end 324.291452 -227.733352)
		(width 0.0762)
		(layer "F.Cu")
		(net "M_A_CPU0_SA_DQS_DN<5>")
	)
	(segment
		(start 308.229508 -202.01001)
		(end 305.689508 -202.01001)
		(width 0.101346)
		(layer "F.Cu")
		(net "M_A_CPU0_SA_DQS_DN<5>")
	)
	(segment
		(start 322.379848 -216.57818)
		(end 320.713354 -214.911686)
		(width 0.12954)
		(layer "F.Cu")
		(net "M_A_CPU0_SA_DQS_DN<5>")
	)
	(segment
		(start 304.116994 -201.901806)
		(end 303.800256 -201.585068)
		(width 0.101346)
		(layer "F.Cu")
		(net "M_A_CPU0_SA_DQS_DN<5>")
	)
	(segment
		(start 304.979832 -202.326748)
		(end 304.55489 -201.901806)
		(width 0.101346)
		(layer "F.Cu")
		(net "M_A_CPU0_SA_DQS_DN<5>")
	)
	(segment
		(start 325.614284 -228.003862)
		(end 325.34352 -227.733352)
		(width 0.0762)
		(layer "F.Cu")
		(net "M_A_CPU0_SA_DQS_DN<5>")
	)
	(segment
		(start 308.889654 -202.264772)
		(end 308.48427 -202.264772)
		(width 0.12954)
		(layer "F.Cu")
		(net "M_A_CPU0_SA_DQS_DN<5>")
	)
	(segment
		(start 324.137782 -227.579682)
		(end 324.138036 -227.48621)
		(width 0.0762)
		(layer "F.Cu")
		(net "M_A_CPU0_SA_DQS_DN<5>")
	)
	(segment
		(start 324.124574 -227.472748)
		(end 322.379848 -225.728022)
		(width 0.12954)
		(layer "F.Cu")
		(net "M_A_CPU0_SA_DQS_DN<5>")
	)
	(segment
		(start 324.138036 -227.48621)
		(end 324.124574 -227.472748)
		(width 0.0762)
		(layer "F.Cu")
		(net "M_A_CPU0_SA_DQS_DN<5>")
	)
	(segment
		(start 304.55489 -201.901806)
		(end 304.116994 -201.901806)
		(width 0.101346)
		(layer "F.Cu")
		(net "M_A_CPU0_SA_DQS_DN<5>")
	)
	(segment
		(start 305.37277 -202.326748)
		(end 304.979832 -202.326748)
		(width 0.101346)
		(layer "F.Cu")
		(net "M_A_CPU0_SA_DQS_DN<5>")
	)
	(segment
		(start 322.379848 -225.728022)
		(end 322.379848 -216.57818)
		(width 0.12954)
		(layer "F.Cu")
		(net "M_A_CPU0_SA_DQS_DN<5>")
	)
	(segment
		(start 303.800256 -201.585068)
		(end 303.268126 -201.585068)
		(width 0.101346)
		(layer "F.Cu")
		(net "M_A_CPU0_SA_DQS_DN<5>")
	)
	(segment
		(start 305.689508 -202.01001)
		(end 305.37277 -202.326748)
		(width 0.101346)
		(layer "F.Cu")
		(net "M_A_CPU0_SA_DQS_DN<5>")
	)
	(segment
		(start 320.713354 -214.911686)
		(end 320.713354 -214.08898)
		(width 0.12954)
		(layer "F.Cu")
		(net "M_A_CPU0_SA_DQS_DN<5>")
	)
	(segment
		(start 320.713354 -214.08898)
		(end 308.889654 -202.264772)
		(width 0.12954)
		(layer "F.Cu")
		(net "M_A_CPU0_SA_DQS_DN<5>")
	)
	(segment
		(start 324.291452 -227.733352)
		(end 324.137782 -227.579682)
		(width 0.0762)
		(layer "F.Cu")
		(net "M_A_CPU0_SA_DQS_DN<5>")
	)
	(arc
		(start 326.631046 -228.06279)
		(mid 326.34809 -227.986613)
		(end 326.065134 -228.06279)
		(width 0.0762)
		(layer "F.Cu")
		(net "M_A_CPU0_SA_DQS_DN<5>")
	)
	(arc
		(start 326.065134 -228.06279)
		(mid 325.877936 -228.113172)
		(end 325.690738 -228.06279)
		(width 0.0762)
		(layer "F.Cu")
		(net "M_A_CPU0_SA_DQS_DN<5>")
	)
	(arc
		(start 327.758044 -227.74021)
		(mid 327.520432 -227.911198)
		(end 327.238106 -227.988622)
		(width 0.0762)
		(layer "F.Cu")
		(net "M_A_CPU0_SA_DQS_DN<5>")
	)
	(arc
		(start 327.004934 -228.06279)
		(mid 326.81799 -228.113045)
		(end 326.631046 -228.06279)
		(width 0.0762)
		(layer "F.Cu")
		(net "M_A_CPU0_SA_DQS_DN<5>")
	)
	(arc
		(start 325.690738 -228.06279)
		(mid 325.650593 -228.035814)
		(end 325.614284 -228.003862)
		(width 0.0762)
		(layer "F.Cu")
		(net "M_A_CPU0_SA_DQS_DN<5>")
	)
	(arc
		(start 327.238106 -227.988622)
		(mid 327.117457 -228.012923)
		(end 327.004934 -228.06279)
		(width 0.0762)
		(layer "F.Cu")
		(net "M_A_CPU0_SA_DQS_DN<5>")
	)
	(segment
		(start 309.698898 -239.902492)
		(end 308.502558 -238.706152)
		(width 0.12954)
		(layer "F.Cu")
		(net "M_A_CPU0_SA_DQS_DN<4>")
	)
	(segment
		(start 313.41949 -245.01348)
		(end 313.862212 -244.570504)
		(width 0.12954)
		(layer "F.Cu")
		(net "M_A_CPU0_SA_DQS_DN<4>")
	)
	(segment
		(start 325.699374 -246.852694)
		(end 325.690992 -246.85752)
		(width 0.0762)
		(layer "F.Cu")
		(net "M_A_CPU0_SA_DQS_DN<4>")
	)
	(segment
		(start 314.999116 -245.525036)
		(end 314.841128 -245.367302)
		(width 0.12954)
		(layer "F.Cu")
		(net "M_A_CPU0_SA_DQS_DN<4>")
	)
	(segment
		(start 325.408036 -246.93372)
		(end 324.454774 -246.93372)
		(width 0.0762)
		(layer "F.Cu")
		(net "M_A_CPU0_SA_DQS_DN<4>")
	)
	(segment
		(start 312.385202 -243.093748)
		(end 311.942226 -243.536724)
		(width 0.12954)
		(layer "F.Cu")
		(net "M_A_CPU0_SA_DQS_DN<4>")
	)
	(segment
		(start 324.369684 -246.99976)
		(end 314.954666 -246.99976)
		(width 0.12954)
		(layer "F.Cu")
		(net "M_A_CPU0_SA_DQS_DN<4>")
	)
	(segment
		(start 324.388734 -246.99976)
		(end 324.369684 -246.99976)
		(width 0.0762)
		(layer "F.Cu")
		(net "M_A_CPU0_SA_DQS_DN<4>")
	)
	(segment
		(start 311.49163 -243.536724)
		(end 311.137808 -243.182902)
		(width 0.12954)
		(layer "F.Cu")
		(net "M_A_CPU0_SA_DQS_DN<4>")
	)
	(segment
		(start 314.998862 -245.707154)
		(end 314.999116 -245.525036)
		(width 0.12954)
		(layer "F.Cu")
		(net "M_A_CPU0_SA_DQS_DN<4>")
	)
	(segment
		(start 312.28284 -243.87683)
		(end 312.725562 -243.433854)
		(width 0.12954)
		(layer "F.Cu")
		(net "M_A_CPU0_SA_DQS_DN<4>")
	)
	(segment
		(start 314.55614 -246.601234)
		(end 314.55614 -246.15013)
		(width 0.12954)
		(layer "F.Cu")
		(net "M_A_CPU0_SA_DQS_DN<4>")
	)
	(segment
		(start 314.841128 -245.367302)
		(end 314.658502 -245.367048)
		(width 0.12954)
		(layer "F.Cu")
		(net "M_A_CPU0_SA_DQS_DN<4>")
	)
	(segment
		(start 313.704478 -244.230652)
		(end 313.521852 -244.230398)
		(width 0.12954)
		(layer "F.Cu")
		(net "M_A_CPU0_SA_DQS_DN<4>")
	)
	(segment
		(start 314.954666 -246.99976)
		(end 314.55614 -246.601234)
		(width 0.12954)
		(layer "F.Cu")
		(net "M_A_CPU0_SA_DQS_DN<4>")
	)
	(segment
		(start 313.862466 -244.388386)
		(end 313.704478 -244.230652)
		(width 0.12954)
		(layer "F.Cu")
		(net "M_A_CPU0_SA_DQS_DN<4>")
	)
	(segment
		(start 311.137808 -243.182902)
		(end 311.137808 -242.155218)
		(width 0.12954)
		(layer "F.Cu")
		(net "M_A_CPU0_SA_DQS_DN<4>")
	)
	(segment
		(start 314.55614 -246.15013)
		(end 314.998862 -245.707154)
		(width 0.12954)
		(layer "F.Cu")
		(net "M_A_CPU0_SA_DQS_DN<4>")
	)
	(segment
		(start 309.698898 -240.716308)
		(end 309.698898 -239.902492)
		(width 0.12954)
		(layer "F.Cu")
		(net "M_A_CPU0_SA_DQS_DN<4>")
	)
	(segment
		(start 307.902864 -238.985044)
		(end 307.368194 -238.985044)
		(width 0.12954)
		(layer "F.Cu")
		(net "M_A_CPU0_SA_DQS_DN<4>")
	)
	(segment
		(start 312.28284 -244.327934)
		(end 312.28284 -243.87683)
		(width 0.12954)
		(layer "F.Cu")
		(net "M_A_CPU0_SA_DQS_DN<4>")
	)
	(segment
		(start 311.942226 -243.536724)
		(end 311.49163 -243.536724)
		(width 0.12954)
		(layer "F.Cu")
		(net "M_A_CPU0_SA_DQS_DN<4>")
	)
	(segment
		(start 313.76493 -245.810024)
		(end 313.41949 -245.464584)
		(width 0.12954)
		(layer "F.Cu")
		(net "M_A_CPU0_SA_DQS_DN<4>")
	)
	(segment
		(start 313.862212 -244.570504)
		(end 313.862466 -244.388386)
		(width 0.12954)
		(layer "F.Cu")
		(net "M_A_CPU0_SA_DQS_DN<4>")
	)
	(segment
		(start 312.62828 -244.673374)
		(end 312.28284 -244.327934)
		(width 0.12954)
		(layer "F.Cu")
		(net "M_A_CPU0_SA_DQS_DN<4>")
	)
	(segment
		(start 312.567828 -243.094002)
		(end 312.385202 -243.093748)
		(width 0.12954)
		(layer "F.Cu")
		(net "M_A_CPU0_SA_DQS_DN<4>")
	)
	(segment
		(start 312.725562 -243.433854)
		(end 312.725816 -243.251736)
		(width 0.12954)
		(layer "F.Cu")
		(net "M_A_CPU0_SA_DQS_DN<4>")
	)
	(segment
		(start 325.877936 -247.1801)
		(end 325.976234 -247.010936)
		(width 0.0762)
		(layer "F.Cu")
		(net "M_A_CPU0_SA_DQS_DN<4>")
	)
	(segment
		(start 324.454774 -246.93372)
		(end 324.388734 -246.99976)
		(width 0.0762)
		(layer "F.Cu")
		(net "M_A_CPU0_SA_DQS_DN<4>")
	)
	(segment
		(start 308.181756 -238.706152)
		(end 307.902864 -238.985044)
		(width 0.12954)
		(layer "F.Cu")
		(net "M_A_CPU0_SA_DQS_DN<4>")
	)
	(segment
		(start 311.137808 -242.155218)
		(end 309.698898 -240.716308)
		(width 0.12954)
		(layer "F.Cu")
		(net "M_A_CPU0_SA_DQS_DN<4>")
	)
	(segment
		(start 308.502558 -238.706152)
		(end 308.181756 -238.706152)
		(width 0.12954)
		(layer "F.Cu")
		(net "M_A_CPU0_SA_DQS_DN<4>")
	)
	(segment
		(start 314.658502 -245.367048)
		(end 314.215526 -245.810024)
		(width 0.12954)
		(layer "F.Cu")
		(net "M_A_CPU0_SA_DQS_DN<4>")
	)
	(segment
		(start 314.215526 -245.810024)
		(end 313.76493 -245.810024)
		(width 0.12954)
		(layer "F.Cu")
		(net "M_A_CPU0_SA_DQS_DN<4>")
	)
	(segment
		(start 312.725816 -243.251736)
		(end 312.567828 -243.094002)
		(width 0.12954)
		(layer "F.Cu")
		(net "M_A_CPU0_SA_DQS_DN<4>")
	)
	(segment
		(start 313.41949 -245.464584)
		(end 313.41949 -245.01348)
		(width 0.12954)
		(layer "F.Cu")
		(net "M_A_CPU0_SA_DQS_DN<4>")
	)
	(segment
		(start 313.078876 -244.673374)
		(end 312.62828 -244.673374)
		(width 0.12954)
		(layer "F.Cu")
		(net "M_A_CPU0_SA_DQS_DN<4>")
	)
	(segment
		(start 313.521852 -244.230398)
		(end 313.078876 -244.673374)
		(width 0.12954)
		(layer "F.Cu")
		(net "M_A_CPU0_SA_DQS_DN<4>")
	)
	(arc
		(start 325.976234 -247.010936)
		(mid 325.967641 -246.869057)
		(end 325.838566 -246.80926)
		(width 0.0762)
		(layer "F.Cu")
		(net "M_A_CPU0_SA_DQS_DN<4>")
	)
	(arc
		(start 325.690992 -246.85752)
		(mid 325.554556 -246.914345)
		(end 325.408036 -246.93372)
		(width 0.0762)
		(layer "F.Cu")
		(net "M_A_CPU0_SA_DQS_DN<4>")
	)
	(arc
		(start 325.838566 -246.80926)
		(mid 325.766828 -246.824112)
		(end 325.699374 -246.852694)
		(width 0.0762)
		(layer "F.Cu")
		(net "M_A_CPU0_SA_DQS_DN<4>")
	)
	(segment
		(start 313.694572 -235.800138)
		(end 313.846464 -235.648246)
		(width 0.12954)
		(layer "F.Cu")
		(net "M_A_CPU0_SA_DQS_DN<3>")
	)
	(segment
		(start 323.915024 -242.266724)
		(end 323.895974 -242.266724)
		(width 0.0762)
		(layer "F.Cu")
		(net "M_A_CPU0_SA_DQS_DN<3>")
	)
	(segment
		(start 311.421272 -233.976926)
		(end 311.421272 -233.526838)
		(width 0.12954)
		(layer "F.Cu")
		(net "M_A_CPU0_SA_DQS_DN<3>")
	)
	(segment
		(start 313.506612 -235.308394)
		(end 313.35472 -235.460286)
		(width 0.12954)
		(layer "F.Cu")
		(net "M_A_CPU0_SA_DQS_DN<3>")
	)
	(segment
		(start 317.09995 -238.718344)
		(end 316.916562 -238.718344)
		(width 0.12954)
		(layer "F.Cu")
		(net "M_A_CPU0_SA_DQS_DN<3>")
	)
	(segment
		(start 314.831222 -237.386876)
		(end 314.831222 -236.936788)
		(width 0.12954)
		(layer "F.Cu")
		(net "M_A_CPU0_SA_DQS_DN<3>")
	)
	(segment
		(start 314.041282 -236.596936)
		(end 313.694572 -236.250226)
		(width 0.12954)
		(layer "F.Cu")
		(net "M_A_CPU0_SA_DQS_DN<3>")
	)
	(segment
		(start 313.694572 -236.250226)
		(end 313.694572 -235.800138)
		(width 0.12954)
		(layer "F.Cu")
		(net "M_A_CPU0_SA_DQS_DN<3>")
	)
	(segment
		(start 309.56631 -230.397304)
		(end 308.540404 -229.371398)
		(width 0.12954)
		(layer "F.Cu")
		(net "M_A_CPU0_SA_DQS_DN<3>")
	)
	(segment
		(start 314.82665 -236.445044)
		(end 314.643262 -236.445044)
		(width 0.12954)
		(layer "F.Cu")
		(net "M_A_CPU0_SA_DQS_DN<3>")
	)
	(segment
		(start 325.877936 -242.320064)
		(end 325.976234 -242.1509)
		(width 0.0762)
		(layer "F.Cu")
		(net "M_A_CPU0_SA_DQS_DN<3>")
	)
	(segment
		(start 312.904632 -235.460286)
		(end 312.557922 -235.113576)
		(width 0.12954)
		(layer "F.Cu")
		(net "M_A_CPU0_SA_DQS_DN<3>")
	)
	(segment
		(start 317.104522 -239.660176)
		(end 317.104522 -239.210088)
		(width 0.12954)
		(layer "F.Cu")
		(net "M_A_CPU0_SA_DQS_DN<3>")
	)
	(segment
		(start 324.647814 -242.073684)
		(end 324.520814 -242.200684)
		(width 0.0762)
		(layer "F.Cu")
		(net "M_A_CPU0_SA_DQS_DN<3>")
	)
	(segment
		(start 320.64833 -242.266724)
		(end 319.37325 -240.991644)
		(width 0.12954)
		(layer "F.Cu")
		(net "M_A_CPU0_SA_DQS_DN<3>")
	)
	(segment
		(start 313.846464 -235.464858)
		(end 313.69 -235.308394)
		(width 0.12954)
		(layer "F.Cu")
		(net "M_A_CPU0_SA_DQS_DN<3>")
	)
	(segment
		(start 319.37325 -240.991644)
		(end 319.189862 -240.991644)
		(width 0.12954)
		(layer "F.Cu")
		(net "M_A_CPU0_SA_DQS_DN<3>")
	)
	(segment
		(start 314.983114 -236.784896)
		(end 314.983114 -236.601508)
		(width 0.12954)
		(layer "F.Cu")
		(net "M_A_CPU0_SA_DQS_DN<3>")
	)
	(segment
		(start 314.983114 -236.601508)
		(end 314.82665 -236.445044)
		(width 0.12954)
		(layer "F.Cu")
		(net "M_A_CPU0_SA_DQS_DN<3>")
	)
	(segment
		(start 313.846464 -235.648246)
		(end 313.846464 -235.464858)
		(width 0.12954)
		(layer "F.Cu")
		(net "M_A_CPU0_SA_DQS_DN<3>")
	)
	(segment
		(start 317.256414 -239.058196)
		(end 317.256414 -238.874808)
		(width 0.12954)
		(layer "F.Cu")
		(net "M_A_CPU0_SA_DQS_DN<3>")
	)
	(segment
		(start 318.587882 -241.143536)
		(end 318.241172 -240.796826)
		(width 0.12954)
		(layer "F.Cu")
		(net "M_A_CPU0_SA_DQS_DN<3>")
	)
	(segment
		(start 325.408036 -242.073684)
		(end 324.647814 -242.073684)
		(width 0.0762)
		(layer "F.Cu")
		(net "M_A_CPU0_SA_DQS_DN<3>")
	)
	(segment
		(start 325.699374 -241.992658)
		(end 325.690992 -241.997484)
		(width 0.0762)
		(layer "F.Cu")
		(net "M_A_CPU0_SA_DQS_DN<3>")
	)
	(segment
		(start 318.241172 -240.346738)
		(end 318.393064 -240.194846)
		(width 0.12954)
		(layer "F.Cu")
		(net "M_A_CPU0_SA_DQS_DN<3>")
	)
	(segment
		(start 316.314582 -238.870236)
		(end 315.967872 -238.523526)
		(width 0.12954)
		(layer "F.Cu")
		(net "M_A_CPU0_SA_DQS_DN<3>")
	)
	(segment
		(start 323.981064 -242.200684)
		(end 323.915024 -242.266724)
		(width 0.0762)
		(layer "F.Cu")
		(net "M_A_CPU0_SA_DQS_DN<3>")
	)
	(segment
		(start 314.831222 -236.936788)
		(end 314.983114 -236.784896)
		(width 0.12954)
		(layer "F.Cu")
		(net "M_A_CPU0_SA_DQS_DN<3>")
	)
	(segment
		(start 314.643262 -236.445044)
		(end 314.49137 -236.596936)
		(width 0.12954)
		(layer "F.Cu")
		(net "M_A_CPU0_SA_DQS_DN<3>")
	)
	(segment
		(start 311.767982 -234.323636)
		(end 311.421272 -233.976926)
		(width 0.12954)
		(layer "F.Cu")
		(net "M_A_CPU0_SA_DQS_DN<3>")
	)
	(segment
		(start 315.779912 -237.581694)
		(end 315.62802 -237.733586)
		(width 0.12954)
		(layer "F.Cu")
		(net "M_A_CPU0_SA_DQS_DN<3>")
	)
	(segment
		(start 318.2366 -239.854994)
		(end 318.053212 -239.854994)
		(width 0.12954)
		(layer "F.Cu")
		(net "M_A_CPU0_SA_DQS_DN<3>")
	)
	(segment
		(start 312.369962 -234.171744)
		(end 312.21807 -234.323636)
		(width 0.12954)
		(layer "F.Cu")
		(net "M_A_CPU0_SA_DQS_DN<3>")
	)
	(segment
		(start 313.35472 -235.460286)
		(end 312.904632 -235.460286)
		(width 0.12954)
		(layer "F.Cu")
		(net "M_A_CPU0_SA_DQS_DN<3>")
	)
	(segment
		(start 315.967872 -238.523526)
		(end 315.967872 -238.073438)
		(width 0.12954)
		(layer "F.Cu")
		(net "M_A_CPU0_SA_DQS_DN<3>")
	)
	(segment
		(start 323.895974 -242.266724)
		(end 320.64833 -242.266724)
		(width 0.12954)
		(layer "F.Cu")
		(net "M_A_CPU0_SA_DQS_DN<3>")
	)
	(segment
		(start 318.241172 -240.796826)
		(end 318.241172 -240.346738)
		(width 0.12954)
		(layer "F.Cu")
		(net "M_A_CPU0_SA_DQS_DN<3>")
	)
	(segment
		(start 313.69 -235.308394)
		(end 313.506612 -235.308394)
		(width 0.12954)
		(layer "F.Cu")
		(net "M_A_CPU0_SA_DQS_DN<3>")
	)
	(segment
		(start 307.902864 -229.63505)
		(end 307.368194 -229.63505)
		(width 0.12954)
		(layer "F.Cu")
		(net "M_A_CPU0_SA_DQS_DN<3>")
	)
	(segment
		(start 317.104522 -239.210088)
		(end 317.256414 -239.058196)
		(width 0.12954)
		(layer "F.Cu")
		(net "M_A_CPU0_SA_DQS_DN<3>")
	)
	(segment
		(start 319.189862 -240.991644)
		(end 319.03797 -241.143536)
		(width 0.12954)
		(layer "F.Cu")
		(net "M_A_CPU0_SA_DQS_DN<3>")
	)
	(segment
		(start 324.520814 -242.200684)
		(end 323.981064 -242.200684)
		(width 0.0762)
		(layer "F.Cu")
		(net "M_A_CPU0_SA_DQS_DN<3>")
	)
	(segment
		(start 315.967872 -238.073438)
		(end 316.119764 -237.921546)
		(width 0.12954)
		(layer "F.Cu")
		(net "M_A_CPU0_SA_DQS_DN<3>")
	)
	(segment
		(start 315.177932 -237.733586)
		(end 314.831222 -237.386876)
		(width 0.12954)
		(layer "F.Cu")
		(net "M_A_CPU0_SA_DQS_DN<3>")
	)
	(segment
		(start 315.62802 -237.733586)
		(end 315.177932 -237.733586)
		(width 0.12954)
		(layer "F.Cu")
		(net "M_A_CPU0_SA_DQS_DN<3>")
	)
	(segment
		(start 319.03797 -241.143536)
		(end 318.587882 -241.143536)
		(width 0.12954)
		(layer "F.Cu")
		(net "M_A_CPU0_SA_DQS_DN<3>")
	)
	(segment
		(start 312.709814 -234.511596)
		(end 312.709814 -234.328208)
		(width 0.12954)
		(layer "F.Cu")
		(net "M_A_CPU0_SA_DQS_DN<3>")
	)
	(segment
		(start 316.76467 -238.870236)
		(end 316.314582 -238.870236)
		(width 0.12954)
		(layer "F.Cu")
		(net "M_A_CPU0_SA_DQS_DN<3>")
	)
	(segment
		(start 312.55335 -234.171744)
		(end 312.369962 -234.171744)
		(width 0.12954)
		(layer "F.Cu")
		(net "M_A_CPU0_SA_DQS_DN<3>")
	)
	(segment
		(start 316.119764 -237.921546)
		(end 316.119764 -237.738158)
		(width 0.12954)
		(layer "F.Cu")
		(net "M_A_CPU0_SA_DQS_DN<3>")
	)
	(segment
		(start 312.557922 -235.113576)
		(end 312.557922 -234.663488)
		(width 0.12954)
		(layer "F.Cu")
		(net "M_A_CPU0_SA_DQS_DN<3>")
	)
	(segment
		(start 316.916562 -238.718344)
		(end 316.76467 -238.870236)
		(width 0.12954)
		(layer "F.Cu")
		(net "M_A_CPU0_SA_DQS_DN<3>")
	)
	(segment
		(start 318.053212 -239.854994)
		(end 317.90132 -240.006886)
		(width 0.12954)
		(layer "F.Cu")
		(net "M_A_CPU0_SA_DQS_DN<3>")
	)
	(segment
		(start 309.56631 -231.184704)
		(end 309.56631 -230.397304)
		(width 0.12954)
		(layer "F.Cu")
		(net "M_A_CPU0_SA_DQS_DN<3>")
	)
	(segment
		(start 318.393064 -240.011458)
		(end 318.2366 -239.854994)
		(width 0.12954)
		(layer "F.Cu")
		(net "M_A_CPU0_SA_DQS_DN<3>")
	)
	(segment
		(start 315.9633 -237.581694)
		(end 315.779912 -237.581694)
		(width 0.12954)
		(layer "F.Cu")
		(net "M_A_CPU0_SA_DQS_DN<3>")
	)
	(segment
		(start 314.49137 -236.596936)
		(end 314.041282 -236.596936)
		(width 0.12954)
		(layer "F.Cu")
		(net "M_A_CPU0_SA_DQS_DN<3>")
	)
	(segment
		(start 308.540404 -229.371398)
		(end 308.166516 -229.371398)
		(width 0.12954)
		(layer "F.Cu")
		(net "M_A_CPU0_SA_DQS_DN<3>")
	)
	(segment
		(start 311.421272 -233.526838)
		(end 311.573164 -233.374946)
		(width 0.12954)
		(layer "F.Cu")
		(net "M_A_CPU0_SA_DQS_DN<3>")
	)
	(segment
		(start 312.709814 -234.328208)
		(end 312.55335 -234.171744)
		(width 0.12954)
		(layer "F.Cu")
		(net "M_A_CPU0_SA_DQS_DN<3>")
	)
	(segment
		(start 311.573164 -233.191558)
		(end 309.56631 -231.184704)
		(width 0.12954)
		(layer "F.Cu")
		(net "M_A_CPU0_SA_DQS_DN<3>")
	)
	(segment
		(start 317.451232 -240.006886)
		(end 317.104522 -239.660176)
		(width 0.12954)
		(layer "F.Cu")
		(net "M_A_CPU0_SA_DQS_DN<3>")
	)
	(segment
		(start 317.90132 -240.006886)
		(end 317.451232 -240.006886)
		(width 0.12954)
		(layer "F.Cu")
		(net "M_A_CPU0_SA_DQS_DN<3>")
	)
	(segment
		(start 312.21807 -234.323636)
		(end 311.767982 -234.323636)
		(width 0.12954)
		(layer "F.Cu")
		(net "M_A_CPU0_SA_DQS_DN<3>")
	)
	(segment
		(start 317.256414 -238.874808)
		(end 317.09995 -238.718344)
		(width 0.12954)
		(layer "F.Cu")
		(net "M_A_CPU0_SA_DQS_DN<3>")
	)
	(segment
		(start 316.119764 -237.738158)
		(end 315.9633 -237.581694)
		(width 0.12954)
		(layer "F.Cu")
		(net "M_A_CPU0_SA_DQS_DN<3>")
	)
	(segment
		(start 308.166516 -229.371398)
		(end 307.902864 -229.63505)
		(width 0.12954)
		(layer "F.Cu")
		(net "M_A_CPU0_SA_DQS_DN<3>")
	)
	(segment
		(start 311.573164 -233.374946)
		(end 311.573164 -233.191558)
		(width 0.12954)
		(layer "F.Cu")
		(net "M_A_CPU0_SA_DQS_DN<3>")
	)
	(segment
		(start 312.557922 -234.663488)
		(end 312.709814 -234.511596)
		(width 0.12954)
		(layer "F.Cu")
		(net "M_A_CPU0_SA_DQS_DN<3>")
	)
	(segment
		(start 318.393064 -240.194846)
		(end 318.393064 -240.011458)
		(width 0.12954)
		(layer "F.Cu")
		(net "M_A_CPU0_SA_DQS_DN<3>")
	)
	(arc
		(start 325.838566 -241.949224)
		(mid 325.766828 -241.964076)
		(end 325.699374 -241.992658)
		(width 0.0762)
		(layer "F.Cu")
		(net "M_A_CPU0_SA_DQS_DN<3>")
	)
	(arc
		(start 325.690992 -241.997484)
		(mid 325.554556 -242.054309)
		(end 325.408036 -242.073684)
		(width 0.0762)
		(layer "F.Cu")
		(net "M_A_CPU0_SA_DQS_DN<3>")
	)
	(arc
		(start 325.976234 -242.1509)
		(mid 325.967641 -242.009021)
		(end 325.838566 -241.949224)
		(width 0.0762)
		(layer "F.Cu")
		(net "M_A_CPU0_SA_DQS_DN<3>")
	)
	(segment
		(start 308.166516 -220.021404)
		(end 307.902864 -220.285056)
		(width 0.12954)
		(layer "F.Cu")
		(net "M_A_CPU0_SA_DQS_DN<2>")
	)
	(segment
		(start 313.523884 -223.458532)
		(end 314.012326 -222.97009)
		(width 0.12954)
		(layer "F.Cu")
		(net "M_A_CPU0_SA_DQS_DN<2>")
	)
	(segment
		(start 314.028328 -224.41408)
		(end 313.523884 -223.909636)
		(width 0.12954)
		(layer "F.Cu")
		(net "M_A_CPU0_SA_DQS_DN<2>")
	)
	(segment
		(start 310.45912 -220.844872)
		(end 309.635652 -220.021404)
		(width 0.12954)
		(layer "F.Cu")
		(net "M_A_CPU0_SA_DQS_DN<2>")
	)
	(segment
		(start 311.59577 -221.981522)
		(end 311.250584 -221.636336)
		(width 0.12954)
		(layer "F.Cu")
		(net "M_A_CPU0_SA_DQS_DN<2>")
	)
	(segment
		(start 313.671966 -222.62973)
		(end 313.183524 -223.118172)
		(width 0.12954)
		(layer "F.Cu")
		(net "M_A_CPU0_SA_DQS_DN<2>")
	)
	(segment
		(start 324.108064 -237.42523)
		(end 324.089014 -237.42523)
		(width 0.0762)
		(layer "F.Cu")
		(net "M_A_CPU0_SA_DQS_DN<2>")
	)
	(segment
		(start 314.028328 -229.296722)
		(end 314.028328 -224.41408)
		(width 0.12954)
		(layer "F.Cu")
		(net "M_A_CPU0_SA_DQS_DN<2>")
	)
	(segment
		(start 314.012326 -222.787718)
		(end 313.854338 -222.62973)
		(width 0.12954)
		(layer "F.Cu")
		(net "M_A_CPU0_SA_DQS_DN<2>")
	)
	(segment
		(start 325.408036 -237.213648)
		(end 324.518782 -237.213648)
		(width 0.0762)
		(layer "F.Cu")
		(net "M_A_CPU0_SA_DQS_DN<2>")
	)
	(segment
		(start 313.854338 -222.62973)
		(end 313.671966 -222.62973)
		(width 0.12954)
		(layer "F.Cu")
		(net "M_A_CPU0_SA_DQS_DN<2>")
	)
	(segment
		(start 310.910224 -220.844872)
		(end 310.45912 -220.844872)
		(width 0.12954)
		(layer "F.Cu")
		(net "M_A_CPU0_SA_DQS_DN<2>")
	)
	(segment
		(start 311.739026 -220.514418)
		(end 311.581038 -220.35643)
		(width 0.12954)
		(layer "F.Cu")
		(net "M_A_CPU0_SA_DQS_DN<2>")
	)
	(segment
		(start 313.042046 -221.66707)
		(end 313.042046 -221.484698)
		(width 0.12954)
		(layer "F.Cu")
		(net "M_A_CPU0_SA_DQS_DN<2>")
	)
	(segment
		(start 313.523884 -223.909636)
		(end 313.523884 -223.458532)
		(width 0.12954)
		(layer "F.Cu")
		(net "M_A_CPU0_SA_DQS_DN<2>")
	)
	(segment
		(start 312.701686 -221.32671)
		(end 312.046874 -221.981522)
		(width 0.12954)
		(layer "F.Cu")
		(net "M_A_CPU0_SA_DQS_DN<2>")
	)
	(segment
		(start 307.902864 -220.285056)
		(end 307.368194 -220.285056)
		(width 0.12954)
		(layer "F.Cu")
		(net "M_A_CPU0_SA_DQS_DN<2>")
	)
	(segment
		(start 311.250584 -221.185232)
		(end 311.739026 -220.69679)
		(width 0.12954)
		(layer "F.Cu")
		(net "M_A_CPU0_SA_DQS_DN<2>")
	)
	(segment
		(start 324.518782 -237.213648)
		(end 324.37324 -237.35919)
		(width 0.0762)
		(layer "F.Cu")
		(net "M_A_CPU0_SA_DQS_DN<2>")
	)
	(segment
		(start 324.089014 -237.42523)
		(end 322.156836 -237.42523)
		(width 0.12954)
		(layer "F.Cu")
		(net "M_A_CPU0_SA_DQS_DN<2>")
	)
	(segment
		(start 325.877936 -237.460028)
		(end 325.976234 -237.290864)
		(width 0.0762)
		(layer "F.Cu")
		(net "M_A_CPU0_SA_DQS_DN<2>")
	)
	(segment
		(start 324.174104 -237.35919)
		(end 324.108064 -237.42523)
		(width 0.0762)
		(layer "F.Cu")
		(net "M_A_CPU0_SA_DQS_DN<2>")
	)
	(segment
		(start 311.739026 -220.69679)
		(end 311.739026 -220.514418)
		(width 0.12954)
		(layer "F.Cu")
		(net "M_A_CPU0_SA_DQS_DN<2>")
	)
	(segment
		(start 312.73242 -223.118172)
		(end 312.387234 -222.772986)
		(width 0.12954)
		(layer "F.Cu")
		(net "M_A_CPU0_SA_DQS_DN<2>")
	)
	(segment
		(start 309.635652 -220.021404)
		(end 308.166516 -220.021404)
		(width 0.12954)
		(layer "F.Cu")
		(net "M_A_CPU0_SA_DQS_DN<2>")
	)
	(segment
		(start 313.042046 -221.484698)
		(end 312.884058 -221.32671)
		(width 0.12954)
		(layer "F.Cu")
		(net "M_A_CPU0_SA_DQS_DN<2>")
	)
	(segment
		(start 314.012326 -222.97009)
		(end 314.012326 -222.787718)
		(width 0.12954)
		(layer "F.Cu")
		(net "M_A_CPU0_SA_DQS_DN<2>")
	)
	(segment
		(start 311.581038 -220.35643)
		(end 311.398666 -220.35643)
		(width 0.12954)
		(layer "F.Cu")
		(net "M_A_CPU0_SA_DQS_DN<2>")
	)
	(segment
		(start 312.046874 -221.981522)
		(end 311.59577 -221.981522)
		(width 0.12954)
		(layer "F.Cu")
		(net "M_A_CPU0_SA_DQS_DN<2>")
	)
	(segment
		(start 322.156836 -237.42523)
		(end 314.028328 -229.296722)
		(width 0.12954)
		(layer "F.Cu")
		(net "M_A_CPU0_SA_DQS_DN<2>")
	)
	(segment
		(start 312.387234 -222.321882)
		(end 313.042046 -221.66707)
		(width 0.12954)
		(layer "F.Cu")
		(net "M_A_CPU0_SA_DQS_DN<2>")
	)
	(segment
		(start 325.699374 -237.132622)
		(end 325.690992 -237.137448)
		(width 0.0762)
		(layer "F.Cu")
		(net "M_A_CPU0_SA_DQS_DN<2>")
	)
	(segment
		(start 312.387234 -222.772986)
		(end 312.387234 -222.321882)
		(width 0.12954)
		(layer "F.Cu")
		(net "M_A_CPU0_SA_DQS_DN<2>")
	)
	(segment
		(start 311.250584 -221.636336)
		(end 311.250584 -221.185232)
		(width 0.12954)
		(layer "F.Cu")
		(net "M_A_CPU0_SA_DQS_DN<2>")
	)
	(segment
		(start 311.398666 -220.35643)
		(end 310.910224 -220.844872)
		(width 0.12954)
		(layer "F.Cu")
		(net "M_A_CPU0_SA_DQS_DN<2>")
	)
	(segment
		(start 313.183524 -223.118172)
		(end 312.73242 -223.118172)
		(width 0.12954)
		(layer "F.Cu")
		(net "M_A_CPU0_SA_DQS_DN<2>")
	)
	(segment
		(start 312.884058 -221.32671)
		(end 312.701686 -221.32671)
		(width 0.12954)
		(layer "F.Cu")
		(net "M_A_CPU0_SA_DQS_DN<2>")
	)
	(segment
		(start 324.37324 -237.35919)
		(end 324.174104 -237.35919)
		(width 0.0762)
		(layer "F.Cu")
		(net "M_A_CPU0_SA_DQS_DN<2>")
	)
	(arc
		(start 325.976234 -237.290864)
		(mid 325.967641 -237.148985)
		(end 325.838566 -237.089188)
		(width 0.0762)
		(layer "F.Cu")
		(net "M_A_CPU0_SA_DQS_DN<2>")
	)
	(arc
		(start 325.690992 -237.137448)
		(mid 325.554556 -237.194273)
		(end 325.408036 -237.213648)
		(width 0.0762)
		(layer "F.Cu")
		(net "M_A_CPU0_SA_DQS_DN<2>")
	)
	(arc
		(start 325.838566 -237.089188)
		(mid 325.766828 -237.10404)
		(end 325.699374 -237.132622)
		(width 0.0762)
		(layer "F.Cu")
		(net "M_A_CPU0_SA_DQS_DN<2>")
	)
	(segment
		(start 323.399658 -232.419652)
		(end 318.414908 -227.434902)
		(width 0.12954)
		(layer "F.Cu")
		(net "M_A_CPU0_SA_DQS_DN<1>")
	)
	(segment
		(start 311.648094 -211.923376)
		(end 311.648094 -211.741004)
		(width 0.12954)
		(layer "F.Cu")
		(net "M_A_CPU0_SA_DQS_DN<1>")
	)
	(segment
		(start 325.408036 -232.353612)
		(end 324.203314 -232.353612)
		(width 0.0762)
		(layer "F.Cu")
		(net "M_A_CPU0_SA_DQS_DN<1>")
	)
	(segment
		(start 311.307734 -211.583016)
		(end 311.190132 -211.700618)
		(width 0.12954)
		(layer "F.Cu")
		(net "M_A_CPU0_SA_DQS_DN<1>")
	)
	(segment
		(start 311.490106 -211.583016)
		(end 311.307734 -211.583016)
		(width 0.12954)
		(layer "F.Cu")
		(net "M_A_CPU0_SA_DQS_DN<1>")
	)
	(segment
		(start 313.803792 -214.765382)
		(end 313.803792 -214.314278)
		(width 0.12954)
		(layer "F.Cu")
		(net "M_A_CPU0_SA_DQS_DN<1>")
	)
	(segment
		(start 316.2935 -216.37117)
		(end 316.2935 -216.188798)
		(width 0.12954)
		(layer "F.Cu")
		(net "M_A_CPU0_SA_DQS_DN<1>")
	)
	(segment
		(start 324.118224 -232.419652)
		(end 323.399658 -232.419652)
		(width 0.12954)
		(layer "F.Cu")
		(net "M_A_CPU0_SA_DQS_DN<1>")
	)
	(segment
		(start 316.873382 -217.383868)
		(end 316.422278 -217.383868)
		(width 0.12954)
		(layer "F.Cu")
		(net "M_A_CPU0_SA_DQS_DN<1>")
	)
	(segment
		(start 315.95314 -216.03081)
		(end 315.736732 -216.247218)
		(width 0.12954)
		(layer "F.Cu")
		(net "M_A_CPU0_SA_DQS_DN<1>")
	)
	(segment
		(start 308.166516 -210.67141)
		(end 307.902864 -210.935062)
		(width 0.12954)
		(layer "F.Cu")
		(net "M_A_CPU0_SA_DQS_DN<1>")
	)
	(segment
		(start 315.15685 -215.052148)
		(end 314.998862 -214.89416)
		(width 0.12954)
		(layer "F.Cu")
		(net "M_A_CPU0_SA_DQS_DN<1>")
	)
	(segment
		(start 313.67984 -213.75751)
		(end 313.463432 -213.973918)
		(width 0.12954)
		(layer "F.Cu")
		(net "M_A_CPU0_SA_DQS_DN<1>")
	)
	(segment
		(start 313.803792 -214.314278)
		(end 314.0202 -214.09787)
		(width 0.12954)
		(layer "F.Cu")
		(net "M_A_CPU0_SA_DQS_DN<1>")
	)
	(segment
		(start 311.190132 -211.700618)
		(end 310.739028 -211.700618)
		(width 0.12954)
		(layer "F.Cu")
		(net "M_A_CPU0_SA_DQS_DN<1>")
	)
	(segment
		(start 314.600082 -215.110568)
		(end 314.148978 -215.110568)
		(width 0.12954)
		(layer "F.Cu")
		(net "M_A_CPU0_SA_DQS_DN<1>")
	)
	(segment
		(start 325.699374 -232.272586)
		(end 325.690992 -232.277412)
		(width 0.0762)
		(layer "F.Cu")
		(net "M_A_CPU0_SA_DQS_DN<1>")
	)
	(segment
		(start 316.135512 -216.03081)
		(end 315.95314 -216.03081)
		(width 0.12954)
		(layer "F.Cu")
		(net "M_A_CPU0_SA_DQS_DN<1>")
	)
	(segment
		(start 316.2935 -216.188798)
		(end 316.135512 -216.03081)
		(width 0.12954)
		(layer "F.Cu")
		(net "M_A_CPU0_SA_DQS_DN<1>")
	)
	(segment
		(start 312.667142 -213.177628)
		(end 312.88355 -212.96122)
		(width 0.12954)
		(layer "F.Cu")
		(net "M_A_CPU0_SA_DQS_DN<1>")
	)
	(segment
		(start 324.137274 -232.419652)
		(end 324.118224 -232.419652)
		(width 0.0762)
		(layer "F.Cu")
		(net "M_A_CPU0_SA_DQS_DN<1>")
	)
	(segment
		(start 313.012328 -213.973918)
		(end 312.667142 -213.628732)
		(width 0.12954)
		(layer "F.Cu")
		(net "M_A_CPU0_SA_DQS_DN<1>")
	)
	(segment
		(start 312.54319 -212.62086)
		(end 312.326782 -212.837268)
		(width 0.12954)
		(layer "F.Cu")
		(net "M_A_CPU0_SA_DQS_DN<1>")
	)
	(segment
		(start 310.739028 -211.700618)
		(end 310.517286 -211.478876)
		(width 0.12954)
		(layer "F.Cu")
		(net "M_A_CPU0_SA_DQS_DN<1>")
	)
	(segment
		(start 312.326782 -212.837268)
		(end 311.875678 -212.837268)
		(width 0.12954)
		(layer "F.Cu")
		(net "M_A_CPU0_SA_DQS_DN<1>")
	)
	(segment
		(start 311.530492 -212.040978)
		(end 311.648094 -211.923376)
		(width 0.12954)
		(layer "F.Cu")
		(net "M_A_CPU0_SA_DQS_DN<1>")
	)
	(segment
		(start 314.940442 -215.902032)
		(end 314.940442 -215.450928)
		(width 0.12954)
		(layer "F.Cu")
		(net "M_A_CPU0_SA_DQS_DN<1>")
	)
	(segment
		(start 312.725562 -212.62086)
		(end 312.54319 -212.62086)
		(width 0.12954)
		(layer "F.Cu")
		(net "M_A_CPU0_SA_DQS_DN<1>")
	)
	(segment
		(start 314.0202 -214.09787)
		(end 314.0202 -213.915498)
		(width 0.12954)
		(layer "F.Cu")
		(net "M_A_CPU0_SA_DQS_DN<1>")
	)
	(segment
		(start 315.15685 -215.23452)
		(end 315.15685 -215.052148)
		(width 0.12954)
		(layer "F.Cu")
		(net "M_A_CPU0_SA_DQS_DN<1>")
	)
	(segment
		(start 314.998862 -214.89416)
		(end 314.81649 -214.89416)
		(width 0.12954)
		(layer "F.Cu")
		(net "M_A_CPU0_SA_DQS_DN<1>")
	)
	(segment
		(start 314.81649 -214.89416)
		(end 314.600082 -215.110568)
		(width 0.12954)
		(layer "F.Cu")
		(net "M_A_CPU0_SA_DQS_DN<1>")
	)
	(segment
		(start 317.43015 -217.325448)
		(end 317.272162 -217.16746)
		(width 0.12954)
		(layer "F.Cu")
		(net "M_A_CPU0_SA_DQS_DN<1>")
	)
	(segment
		(start 312.667142 -213.628732)
		(end 312.667142 -213.177628)
		(width 0.12954)
		(layer "F.Cu")
		(net "M_A_CPU0_SA_DQS_DN<1>")
	)
	(segment
		(start 312.88355 -212.778848)
		(end 312.725562 -212.62086)
		(width 0.12954)
		(layer "F.Cu")
		(net "M_A_CPU0_SA_DQS_DN<1>")
	)
	(segment
		(start 318.414908 -227.434902)
		(end 318.414908 -219.376498)
		(width 0.12954)
		(layer "F.Cu")
		(net "M_A_CPU0_SA_DQS_DN<1>")
	)
	(segment
		(start 325.877936 -232.599992)
		(end 325.976234 -232.430828)
		(width 0.0762)
		(layer "F.Cu")
		(net "M_A_CPU0_SA_DQS_DN<1>")
	)
	(segment
		(start 316.422278 -217.383868)
		(end 316.077092 -217.038682)
		(width 0.12954)
		(layer "F.Cu")
		(net "M_A_CPU0_SA_DQS_DN<1>")
	)
	(segment
		(start 307.902864 -210.935062)
		(end 307.368194 -210.935062)
		(width 0.12954)
		(layer "F.Cu")
		(net "M_A_CPU0_SA_DQS_DN<1>")
	)
	(segment
		(start 315.285628 -216.247218)
		(end 314.940442 -215.902032)
		(width 0.12954)
		(layer "F.Cu")
		(net "M_A_CPU0_SA_DQS_DN<1>")
	)
	(segment
		(start 311.875678 -212.837268)
		(end 311.530492 -212.492082)
		(width 0.12954)
		(layer "F.Cu")
		(net "M_A_CPU0_SA_DQS_DN<1>")
	)
	(segment
		(start 317.213742 -217.724228)
		(end 317.43015 -217.50782)
		(width 0.12954)
		(layer "F.Cu")
		(net "M_A_CPU0_SA_DQS_DN<1>")
	)
	(segment
		(start 314.0202 -213.915498)
		(end 313.862212 -213.75751)
		(width 0.12954)
		(layer "F.Cu")
		(net "M_A_CPU0_SA_DQS_DN<1>")
	)
	(segment
		(start 312.88355 -212.96122)
		(end 312.88355 -212.778848)
		(width 0.12954)
		(layer "F.Cu")
		(net "M_A_CPU0_SA_DQS_DN<1>")
	)
	(segment
		(start 317.43015 -217.50782)
		(end 317.43015 -217.325448)
		(width 0.12954)
		(layer "F.Cu")
		(net "M_A_CPU0_SA_DQS_DN<1>")
	)
	(segment
		(start 316.077092 -216.587578)
		(end 316.2935 -216.37117)
		(width 0.12954)
		(layer "F.Cu")
		(net "M_A_CPU0_SA_DQS_DN<1>")
	)
	(segment
		(start 313.463432 -213.973918)
		(end 313.012328 -213.973918)
		(width 0.12954)
		(layer "F.Cu")
		(net "M_A_CPU0_SA_DQS_DN<1>")
	)
	(segment
		(start 316.077092 -217.038682)
		(end 316.077092 -216.587578)
		(width 0.12954)
		(layer "F.Cu")
		(net "M_A_CPU0_SA_DQS_DN<1>")
	)
	(segment
		(start 311.530492 -212.492082)
		(end 311.530492 -212.040978)
		(width 0.12954)
		(layer "F.Cu")
		(net "M_A_CPU0_SA_DQS_DN<1>")
	)
	(segment
		(start 314.940442 -215.450928)
		(end 315.15685 -215.23452)
		(width 0.12954)
		(layer "F.Cu")
		(net "M_A_CPU0_SA_DQS_DN<1>")
	)
	(segment
		(start 318.414908 -219.376498)
		(end 317.213742 -218.175332)
		(width 0.12954)
		(layer "F.Cu")
		(net "M_A_CPU0_SA_DQS_DN<1>")
	)
	(segment
		(start 314.148978 -215.110568)
		(end 313.803792 -214.765382)
		(width 0.12954)
		(layer "F.Cu")
		(net "M_A_CPU0_SA_DQS_DN<1>")
	)
	(segment
		(start 311.648094 -211.741004)
		(end 311.490106 -211.583016)
		(width 0.12954)
		(layer "F.Cu")
		(net "M_A_CPU0_SA_DQS_DN<1>")
	)
	(segment
		(start 309.402734 -211.478876)
		(end 308.595268 -210.67141)
		(width 0.12954)
		(layer "F.Cu")
		(net "M_A_CPU0_SA_DQS_DN<1>")
	)
	(segment
		(start 313.862212 -213.75751)
		(end 313.67984 -213.75751)
		(width 0.12954)
		(layer "F.Cu")
		(net "M_A_CPU0_SA_DQS_DN<1>")
	)
	(segment
		(start 324.203314 -232.353612)
		(end 324.137274 -232.419652)
		(width 0.0762)
		(layer "F.Cu")
		(net "M_A_CPU0_SA_DQS_DN<1>")
	)
	(segment
		(start 310.517286 -211.478876)
		(end 309.402734 -211.478876)
		(width 0.12954)
		(layer "F.Cu")
		(net "M_A_CPU0_SA_DQS_DN<1>")
	)
	(segment
		(start 317.272162 -217.16746)
		(end 317.08979 -217.16746)
		(width 0.12954)
		(layer "F.Cu")
		(net "M_A_CPU0_SA_DQS_DN<1>")
	)
	(segment
		(start 308.595268 -210.67141)
		(end 308.166516 -210.67141)
		(width 0.12954)
		(layer "F.Cu")
		(net "M_A_CPU0_SA_DQS_DN<1>")
	)
	(segment
		(start 317.08979 -217.16746)
		(end 316.873382 -217.383868)
		(width 0.12954)
		(layer "F.Cu")
		(net "M_A_CPU0_SA_DQS_DN<1>")
	)
	(segment
		(start 315.736732 -216.247218)
		(end 315.285628 -216.247218)
		(width 0.12954)
		(layer "F.Cu")
		(net "M_A_CPU0_SA_DQS_DN<1>")
	)
	(segment
		(start 317.213742 -218.175332)
		(end 317.213742 -217.724228)
		(width 0.12954)
		(layer "F.Cu")
		(net "M_A_CPU0_SA_DQS_DN<1>")
	)
	(arc
		(start 325.690992 -232.277412)
		(mid 325.554556 -232.334237)
		(end 325.408036 -232.353612)
		(width 0.0762)
		(layer "F.Cu")
		(net "M_A_CPU0_SA_DQS_DN<1>")
	)
	(arc
		(start 325.838566 -232.229152)
		(mid 325.766828 -232.244004)
		(end 325.699374 -232.272586)
		(width 0.0762)
		(layer "F.Cu")
		(net "M_A_CPU0_SA_DQS_DN<1>")
	)
	(arc
		(start 325.976234 -232.430828)
		(mid 325.967641 -232.288949)
		(end 325.838566 -232.229152)
		(width 0.0762)
		(layer "F.Cu")
		(net "M_A_CPU0_SA_DQS_DN<1>")
	)
	(segment
		(start 309.814976 -202.56119)
		(end 309.449216 -202.19543)
		(width 0.12954)
		(layer "F.Cu")
		(net "M_A_CPU0_SA_DQS_DN<0>")
	)
	(segment
		(start 312.683652 -204.83449)
		(end 312.088276 -204.83449)
		(width 0.12954)
		(layer "F.Cu")
		(net "M_A_CPU0_SA_DQS_DN<0>")
	)
	(segment
		(start 310.585866 -202.736704)
		(end 310.410352 -202.56119)
		(width 0.12954)
		(layer "F.Cu")
		(net "M_A_CPU0_SA_DQS_DN<0>")
	)
	(segment
		(start 316.269116 -208.419954)
		(end 316.093602 -208.24444)
		(width 0.12954)
		(layer "F.Cu")
		(net "M_A_CPU0_SA_DQS_DN<0>")
	)
	(segment
		(start 307.902864 -201.585068)
		(end 307.368194 -201.585068)
		(width 0.12954)
		(layer "F.Cu")
		(net "M_A_CPU0_SA_DQS_DN<0>")
	)
	(segment
		(start 321.931792 -215.081358)
		(end 321.481704 -215.081358)
		(width 0.12954)
		(layer "F.Cu")
		(net "M_A_CPU0_SA_DQS_DN<0>")
	)
	(segment
		(start 316.634876 -209.38109)
		(end 316.269116 -209.01533)
		(width 0.12954)
		(layer "F.Cu")
		(net "M_A_CPU0_SA_DQS_DN<0>")
	)
	(segment
		(start 324.8787 -227.49383)
		(end 324.299834 -226.914964)
		(width 0.0762)
		(layer "F.Cu")
		(net "M_A_CPU0_SA_DQS_DN<0>")
	)
	(segment
		(start 318.542416 -210.693254)
		(end 318.366902 -210.51774)
		(width 0.12954)
		(layer "F.Cu")
		(net "M_A_CPU0_SA_DQS_DN<0>")
	)
	(segment
		(start 322.801488 -216.109042)
		(end 322.633848 -215.941402)
		(width 0.12954)
		(layer "F.Cu")
		(net "M_A_CPU0_SA_DQS_DN<0>")
	)
	(segment
		(start 320.044826 -212.79104)
		(end 319.679066 -212.42528)
		(width 0.12954)
		(layer "F.Cu")
		(net "M_A_CPU0_SA_DQS_DN<0>")
	)
	(segment
		(start 310.410352 -202.56119)
		(end 309.814976 -202.56119)
		(width 0.12954)
		(layer "F.Cu")
		(net "M_A_CPU0_SA_DQS_DN<0>")
	)
	(segment
		(start 324.1929 -226.901502)
		(end 322.801488 -225.51009)
		(width 0.12954)
		(layer "F.Cu")
		(net "M_A_CPU0_SA_DQS_DN<0>")
	)
	(segment
		(start 308.166516 -201.321416)
		(end 307.902864 -201.585068)
		(width 0.12954)
		(layer "F.Cu")
		(net "M_A_CPU0_SA_DQS_DN<0>")
	)
	(segment
		(start 313.995816 -206.146654)
		(end 313.820302 -205.97114)
		(width 0.12954)
		(layer "F.Cu")
		(net "M_A_CPU0_SA_DQS_DN<0>")
	)
	(segment
		(start 322.633848 -215.552782)
		(end 322.801488 -215.385142)
		(width 0.12954)
		(layer "F.Cu")
		(net "M_A_CPU0_SA_DQS_DN<0>")
	)
	(segment
		(start 313.224926 -205.97114)
		(end 312.859166 -205.60538)
		(width 0.12954)
		(layer "F.Cu")
		(net "M_A_CPU0_SA_DQS_DN<0>")
	)
	(segment
		(start 316.269116 -209.01533)
		(end 316.269116 -208.419954)
		(width 0.12954)
		(layer "F.Cu")
		(net "M_A_CPU0_SA_DQS_DN<0>")
	)
	(segment
		(start 321.542664 -213.87689)
		(end 321.542664 -213.693502)
		(width 0.12954)
		(layer "F.Cu")
		(net "M_A_CPU0_SA_DQS_DN<0>")
	)
	(segment
		(start 309.170578 -201.321416)
		(end 308.166516 -201.321416)
		(width 0.12954)
		(layer "F.Cu")
		(net "M_A_CPU0_SA_DQS_DN<0>")
	)
	(segment
		(start 321.542664 -213.693502)
		(end 320.640202 -212.79104)
		(width 0.12954)
		(layer "F.Cu")
		(net "M_A_CPU0_SA_DQS_DN<0>")
	)
	(segment
		(start 321.134994 -214.734648)
		(end 321.134994 -214.28456)
		(width 0.12954)
		(layer "F.Cu")
		(net "M_A_CPU0_SA_DQS_DN<0>")
	)
	(segment
		(start 318.908176 -211.65439)
		(end 318.542416 -211.28863)
		(width 0.12954)
		(layer "F.Cu")
		(net "M_A_CPU0_SA_DQS_DN<0>")
	)
	(segment
		(start 322.52285 -214.673688)
		(end 322.339462 -214.673688)
		(width 0.12954)
		(layer "F.Cu")
		(net "M_A_CPU0_SA_DQS_DN<0>")
	)
	(segment
		(start 310.585866 -203.33208)
		(end 310.585866 -202.736704)
		(width 0.12954)
		(layer "F.Cu")
		(net "M_A_CPU0_SA_DQS_DN<0>")
	)
	(segment
		(start 325.408036 -227.49383)
		(end 324.8787 -227.49383)
		(width 0.0762)
		(layer "F.Cu")
		(net "M_A_CPU0_SA_DQS_DN<0>")
	)
	(segment
		(start 314.956952 -207.10779)
		(end 314.361576 -207.10779)
		(width 0.12954)
		(layer "F.Cu")
		(net "M_A_CPU0_SA_DQS_DN<0>")
	)
	(segment
		(start 325.877936 -227.74021)
		(end 325.976234 -227.571046)
		(width 0.0762)
		(layer "F.Cu")
		(net "M_A_CPU0_SA_DQS_DN<0>")
	)
	(segment
		(start 312.088276 -204.83449)
		(end 311.722516 -204.46873)
		(width 0.12954)
		(layer "F.Cu")
		(net "M_A_CPU0_SA_DQS_DN<0>")
	)
	(segment
		(start 313.820302 -205.97114)
		(end 313.224926 -205.97114)
		(width 0.12954)
		(layer "F.Cu")
		(net "M_A_CPU0_SA_DQS_DN<0>")
	)
	(segment
		(start 316.093602 -208.24444)
		(end 315.498226 -208.24444)
		(width 0.12954)
		(layer "F.Cu")
		(net "M_A_CPU0_SA_DQS_DN<0>")
	)
	(segment
		(start 311.722516 -204.46873)
		(end 311.722516 -203.873354)
		(width 0.12954)
		(layer "F.Cu")
		(net "M_A_CPU0_SA_DQS_DN<0>")
	)
	(segment
		(start 312.859166 -205.60538)
		(end 312.859166 -205.010004)
		(width 0.12954)
		(layer "F.Cu")
		(net "M_A_CPU0_SA_DQS_DN<0>")
	)
	(segment
		(start 315.498226 -208.24444)
		(end 315.132466 -207.87868)
		(width 0.12954)
		(layer "F.Cu")
		(net "M_A_CPU0_SA_DQS_DN<0>")
	)
	(segment
		(start 325.699374 -227.412804)
		(end 325.690992 -227.41763)
		(width 0.0762)
		(layer "F.Cu")
		(net "M_A_CPU0_SA_DQS_DN<0>")
	)
	(segment
		(start 322.801488 -215.385142)
		(end 322.801488 -214.952326)
		(width 0.12954)
		(layer "F.Cu")
		(net "M_A_CPU0_SA_DQS_DN<0>")
	)
	(segment
		(start 322.633848 -215.941402)
		(end 322.633848 -215.552782)
		(width 0.12954)
		(layer "F.Cu")
		(net "M_A_CPU0_SA_DQS_DN<0>")
	)
	(segment
		(start 319.679066 -212.42528)
		(end 319.679066 -211.829904)
		(width 0.12954)
		(layer "F.Cu")
		(net "M_A_CPU0_SA_DQS_DN<0>")
	)
	(segment
		(start 324.299834 -226.914964)
		(end 324.206362 -226.914964)
		(width 0.0762)
		(layer "F.Cu")
		(net "M_A_CPU0_SA_DQS_DN<0>")
	)
	(segment
		(start 319.679066 -211.829904)
		(end 319.503552 -211.65439)
		(width 0.12954)
		(layer "F.Cu")
		(net "M_A_CPU0_SA_DQS_DN<0>")
	)
	(segment
		(start 322.801488 -214.952326)
		(end 322.52285 -214.673688)
		(width 0.12954)
		(layer "F.Cu")
		(net "M_A_CPU0_SA_DQS_DN<0>")
	)
	(segment
		(start 322.801488 -225.51009)
		(end 322.801488 -216.109042)
		(width 0.12954)
		(layer "F.Cu")
		(net "M_A_CPU0_SA_DQS_DN<0>")
	)
	(segment
		(start 310.951626 -203.69784)
		(end 310.585866 -203.33208)
		(width 0.12954)
		(layer "F.Cu")
		(net "M_A_CPU0_SA_DQS_DN<0>")
	)
	(segment
		(start 319.503552 -211.65439)
		(end 318.908176 -211.65439)
		(width 0.12954)
		(layer "F.Cu")
		(net "M_A_CPU0_SA_DQS_DN<0>")
	)
	(segment
		(start 320.640202 -212.79104)
		(end 320.044826 -212.79104)
		(width 0.12954)
		(layer "F.Cu")
		(net "M_A_CPU0_SA_DQS_DN<0>")
	)
	(segment
		(start 311.722516 -203.873354)
		(end 311.547002 -203.69784)
		(width 0.12954)
		(layer "F.Cu")
		(net "M_A_CPU0_SA_DQS_DN<0>")
	)
	(segment
		(start 313.995816 -206.74203)
		(end 313.995816 -206.146654)
		(width 0.12954)
		(layer "F.Cu")
		(net "M_A_CPU0_SA_DQS_DN<0>")
	)
	(segment
		(start 317.405766 -210.15198)
		(end 317.405766 -209.556604)
		(width 0.12954)
		(layer "F.Cu")
		(net "M_A_CPU0_SA_DQS_DN<0>")
	)
	(segment
		(start 322.339462 -214.673688)
		(end 321.931792 -215.081358)
		(width 0.12954)
		(layer "F.Cu")
		(net "M_A_CPU0_SA_DQS_DN<0>")
	)
	(segment
		(start 315.132466 -207.283304)
		(end 314.956952 -207.10779)
		(width 0.12954)
		(layer "F.Cu")
		(net "M_A_CPU0_SA_DQS_DN<0>")
	)
	(segment
		(start 321.134994 -214.28456)
		(end 321.542664 -213.87689)
		(width 0.12954)
		(layer "F.Cu")
		(net "M_A_CPU0_SA_DQS_DN<0>")
	)
	(segment
		(start 317.230252 -209.38109)
		(end 316.634876 -209.38109)
		(width 0.12954)
		(layer "F.Cu")
		(net "M_A_CPU0_SA_DQS_DN<0>")
	)
	(segment
		(start 312.859166 -205.010004)
		(end 312.683652 -204.83449)
		(width 0.12954)
		(layer "F.Cu")
		(net "M_A_CPU0_SA_DQS_DN<0>")
	)
	(segment
		(start 318.542416 -211.28863)
		(end 318.542416 -210.693254)
		(width 0.12954)
		(layer "F.Cu")
		(net "M_A_CPU0_SA_DQS_DN<0>")
	)
	(segment
		(start 321.481704 -215.081358)
		(end 321.134994 -214.734648)
		(width 0.12954)
		(layer "F.Cu")
		(net "M_A_CPU0_SA_DQS_DN<0>")
	)
	(segment
		(start 315.132466 -207.87868)
		(end 315.132466 -207.283304)
		(width 0.12954)
		(layer "F.Cu")
		(net "M_A_CPU0_SA_DQS_DN<0>")
	)
	(segment
		(start 309.449216 -201.600054)
		(end 309.170578 -201.321416)
		(width 0.12954)
		(layer "F.Cu")
		(net "M_A_CPU0_SA_DQS_DN<0>")
	)
	(segment
		(start 314.361576 -207.10779)
		(end 313.995816 -206.74203)
		(width 0.12954)
		(layer "F.Cu")
		(net "M_A_CPU0_SA_DQS_DN<0>")
	)
	(segment
		(start 317.771526 -210.51774)
		(end 317.405766 -210.15198)
		(width 0.12954)
		(layer "F.Cu")
		(net "M_A_CPU0_SA_DQS_DN<0>")
	)
	(segment
		(start 311.547002 -203.69784)
		(end 310.951626 -203.69784)
		(width 0.12954)
		(layer "F.Cu")
		(net "M_A_CPU0_SA_DQS_DN<0>")
	)
	(segment
		(start 324.206362 -226.914964)
		(end 324.1929 -226.901502)
		(width 0.0762)
		(layer "F.Cu")
		(net "M_A_CPU0_SA_DQS_DN<0>")
	)
	(segment
		(start 318.366902 -210.51774)
		(end 317.771526 -210.51774)
		(width 0.12954)
		(layer "F.Cu")
		(net "M_A_CPU0_SA_DQS_DN<0>")
	)
	(segment
		(start 317.405766 -209.556604)
		(end 317.230252 -209.38109)
		(width 0.12954)
		(layer "F.Cu")
		(net "M_A_CPU0_SA_DQS_DN<0>")
	)
	(segment
		(start 309.449216 -202.19543)
		(end 309.449216 -201.600054)
		(width 0.12954)
		(layer "F.Cu")
		(net "M_A_CPU0_SA_DQS_DN<0>")
	)
	(arc
		(start 325.976234 -227.571046)
		(mid 325.967641 -227.429167)
		(end 325.838566 -227.36937)
		(width 0.0762)
		(layer "F.Cu")
		(net "M_A_CPU0_SA_DQS_DN<0>")
	)
	(arc
		(start 325.838566 -227.36937)
		(mid 325.766828 -227.384222)
		(end 325.699374 -227.412804)
		(width 0.0762)
		(layer "F.Cu")
		(net "M_A_CPU0_SA_DQS_DN<0>")
	)
	(arc
		(start 325.690992 -227.41763)
		(mid 325.554556 -227.474455)
		(end 325.408036 -227.49383)
		(width 0.0762)
		(layer "F.Cu")
		(net "M_A_CPU0_SA_DQS_DN<0>")
	)
	(segment
		(start 310.675274 -209.992214)
		(end 310.524398 -209.99196)
		(width 0.10668)
		(layer "F.Cu")
		(net "M_A_CPU0_SA_DQ<9>")
	)
	(segment
		(start 310.106314 -209.432398)
		(end 309.955438 -209.432144)
		(width 0.10668)
		(layer "F.Cu")
		(net "M_A_CPU0_SA_DQ<9>")
	)
	(segment
		(start 311.080658 -209.58683)
		(end 310.675274 -209.992214)
		(width 0.10668)
		(layer "F.Cu")
		(net "M_A_CPU0_SA_DQ<9>")
	)
	(segment
		(start 323.743828 -231.22636)
		(end 319.488058 -226.97059)
		(width 0.10668)
		(layer "F.Cu")
		(net "M_A_CPU0_SA_DQ<9>")
	)
	(segment
		(start 325.699374 -231.307386)
		(end 325.690992 -231.30256)
		(width 0.0762)
		(layer "F.Cu")
		(net "M_A_CPU0_SA_DQ<9>")
	)
	(segment
		(start 310.667146 -209.022442)
		(end 310.51627 -209.022442)
		(width 0.10668)
		(layer "F.Cu")
		(net "M_A_CPU0_SA_DQ<9>")
	)
	(segment
		(start 310.524398 -209.99196)
		(end 310.39308 -209.860642)
		(width 0.10668)
		(layer "F.Cu")
		(net "M_A_CPU0_SA_DQ<9>")
	)
	(segment
		(start 319.488058 -226.97059)
		(end 319.488058 -217.843354)
		(width 0.10668)
		(layer "F.Cu")
		(net "M_A_CPU0_SA_DQ<9>")
	)
	(segment
		(start 310.39308 -209.709766)
		(end 310.798464 -209.304382)
		(width 0.10668)
		(layer "F.Cu")
		(net "M_A_CPU0_SA_DQ<9>")
	)
	(segment
		(start 325.408036 -231.22636)
		(end 324.146164 -231.22636)
		(width 0.0762)
		(layer "F.Cu")
		(net "M_A_CPU0_SA_DQ<9>")
	)
	(segment
		(start 310.51627 -209.022442)
		(end 310.106314 -209.432398)
		(width 0.10668)
		(layer "F.Cu")
		(net "M_A_CPU0_SA_DQ<9>")
	)
	(segment
		(start 309.82412 -209.14995)
		(end 310.234076 -208.739994)
		(width 0.10668)
		(layer "F.Cu")
		(net "M_A_CPU0_SA_DQ<9>")
	)
	(segment
		(start 310.798718 -209.154014)
		(end 310.667146 -209.022442)
		(width 0.10668)
		(layer "F.Cu")
		(net "M_A_CPU0_SA_DQ<9>")
	)
	(segment
		(start 310.23433 -208.589626)
		(end 310.02986 -208.385156)
		(width 0.10668)
		(layer "F.Cu")
		(net "M_A_CPU0_SA_DQ<9>")
	)
	(segment
		(start 310.798464 -209.304382)
		(end 310.798718 -209.154014)
		(width 0.10668)
		(layer "F.Cu")
		(net "M_A_CPU0_SA_DQ<9>")
	)
	(segment
		(start 319.488058 -217.843354)
		(end 311.231534 -209.58683)
		(width 0.10668)
		(layer "F.Cu")
		(net "M_A_CPU0_SA_DQ<9>")
	)
	(segment
		(start 309.955438 -209.432144)
		(end 309.82412 -209.300826)
		(width 0.10668)
		(layer "F.Cu")
		(net "M_A_CPU0_SA_DQ<9>")
	)
	(segment
		(start 310.39308 -209.860642)
		(end 310.39308 -209.709766)
		(width 0.10668)
		(layer "F.Cu")
		(net "M_A_CPU0_SA_DQ<9>")
	)
	(segment
		(start 309.82412 -209.300826)
		(end 309.82412 -209.14995)
		(width 0.10668)
		(layer "F.Cu")
		(net "M_A_CPU0_SA_DQ<9>")
	)
	(segment
		(start 310.02986 -208.385156)
		(end 307.368194 -208.385156)
		(width 0.10668)
		(layer "F.Cu")
		(net "M_A_CPU0_SA_DQ<9>")
	)
	(segment
		(start 310.234076 -208.739994)
		(end 310.23433 -208.589626)
		(width 0.10668)
		(layer "F.Cu")
		(net "M_A_CPU0_SA_DQ<9>")
	)
	(segment
		(start 324.146164 -231.22636)
		(end 323.743828 -231.22636)
		(width 0.10668)
		(layer "F.Cu")
		(net "M_A_CPU0_SA_DQ<9>")
	)
	(segment
		(start 311.231534 -209.58683)
		(end 311.080658 -209.58683)
		(width 0.10668)
		(layer "F.Cu")
		(net "M_A_CPU0_SA_DQ<9>")
	)
	(arc
		(start 326.631046 -231.30256)
		(mid 326.34809 -231.226383)
		(end 326.065134 -231.30256)
		(width 0.0762)
		(layer "F.Cu")
		(net "M_A_CPU0_SA_DQ<9>")
	)
	(arc
		(start 327.004934 -231.30256)
		(mid 326.81799 -231.352849)
		(end 326.631046 -231.30256)
		(width 0.0762)
		(layer "F.Cu")
		(net "M_A_CPU0_SA_DQ<9>")
	)
	(arc
		(start 326.065134 -231.30256)
		(mid 325.882883 -231.352944)
		(end 325.699374 -231.307386)
		(width 0.0762)
		(layer "F.Cu")
		(net "M_A_CPU0_SA_DQ<9>")
	)
	(arc
		(start 327.289414 -231.226106)
		(mid 327.142093 -231.245425)
		(end 327.004934 -231.30256)
		(width 0.0762)
		(layer "F.Cu")
		(net "M_A_CPU0_SA_DQ<9>")
	)
	(arc
		(start 325.690992 -231.30256)
		(mid 325.554556 -231.245735)
		(end 325.408036 -231.22636)
		(width 0.0762)
		(layer "F.Cu")
		(net "M_A_CPU0_SA_DQ<9>")
	)
	(arc
		(start 327.758044 -230.97998)
		(mid 327.554079 -231.160829)
		(end 327.289414 -231.226106)
		(width 0.0762)
		(layer "F.Cu")
		(net "M_A_CPU0_SA_DQ<9>")
	)
	(segment
		(start 310.893968 -207.558132)
		(end 310.636412 -207.815688)
		(width 0.10668)
		(layer "F.Cu")
		(net "M_A_CPU0_SA_DQ<8>")
	)
	(segment
		(start 310.612028 -207.12557)
		(end 310.480456 -206.993998)
		(width 0.10668)
		(layer "F.Cu")
		(net "M_A_CPU0_SA_DQ<8>")
	)
	(segment
		(start 310.920384 -208.24698)
		(end 310.920384 -208.096104)
		(width 0.10668)
		(layer "F.Cu")
		(net "M_A_CPU0_SA_DQ<8>")
	)
	(segment
		(start 310.611774 -207.275938)
		(end 310.612028 -207.12557)
		(width 0.10668)
		(layer "F.Cu")
		(net "M_A_CPU0_SA_DQ<8>")
	)
	(segment
		(start 309.794402 -206.551276)
		(end 309.643526 -206.551022)
		(width 0.10668)
		(layer "F.Cu")
		(net "M_A_CPU0_SA_DQ<8>")
	)
	(segment
		(start 309.421276 -207.33766)
		(end 309.92572 -206.833216)
		(width 0.10668)
		(layer "F.Cu")
		(net "M_A_CPU0_SA_DQ<8>")
	)
	(segment
		(start 310.353964 -207.683862)
		(end 310.354218 -207.533494)
		(width 0.10668)
		(layer "F.Cu")
		(net "M_A_CPU0_SA_DQ<8>")
	)
	(segment
		(start 320.168778 -226.688142)
		(end 320.168778 -217.495374)
		(width 0.10668)
		(layer "F.Cu")
		(net "M_A_CPU0_SA_DQ<8>")
	)
	(segment
		(start 310.920384 -208.096104)
		(end 311.176162 -207.840326)
		(width 0.10668)
		(layer "F.Cu")
		(net "M_A_CPU0_SA_DQ<8>")
	)
	(segment
		(start 309.92572 -206.833216)
		(end 309.925974 -206.682848)
		(width 0.10668)
		(layer "F.Cu")
		(net "M_A_CPU0_SA_DQ<8>")
	)
	(segment
		(start 320.168778 -217.495374)
		(end 310.920384 -208.24698)
		(width 0.10668)
		(layer "F.Cu")
		(net "M_A_CPU0_SA_DQ<8>")
	)
	(segment
		(start 311.176416 -207.689958)
		(end 311.044844 -207.558386)
		(width 0.10668)
		(layer "F.Cu")
		(net "M_A_CPU0_SA_DQ<8>")
	)
	(segment
		(start 324.294754 -230.41737)
		(end 323.898006 -230.41737)
		(width 0.10668)
		(layer "F.Cu")
		(net "M_A_CPU0_SA_DQ<8>")
	)
	(segment
		(start 309.552594 -207.6196)
		(end 309.421022 -207.488028)
		(width 0.10668)
		(layer "F.Cu")
		(net "M_A_CPU0_SA_DQ<8>")
	)
	(segment
		(start 323.898006 -230.41737)
		(end 320.168778 -226.688142)
		(width 0.10668)
		(layer "F.Cu")
		(net "M_A_CPU0_SA_DQ<8>")
	)
	(segment
		(start 324.426834 -230.54945)
		(end 324.294754 -230.41737)
		(width 0.0762)
		(layer "F.Cu")
		(net "M_A_CPU0_SA_DQ<8>")
	)
	(segment
		(start 310.636412 -207.815688)
		(end 310.485536 -207.815434)
		(width 0.10668)
		(layer "F.Cu")
		(net "M_A_CPU0_SA_DQ<8>")
	)
	(segment
		(start 309.70347 -207.619854)
		(end 309.552594 -207.6196)
		(width 0.10668)
		(layer "F.Cu")
		(net "M_A_CPU0_SA_DQ<8>")
	)
	(segment
		(start 309.925974 -206.682848)
		(end 309.794402 -206.551276)
		(width 0.10668)
		(layer "F.Cu")
		(net "M_A_CPU0_SA_DQ<8>")
	)
	(segment
		(start 310.485536 -207.815434)
		(end 310.353964 -207.683862)
		(width 0.10668)
		(layer "F.Cu")
		(net "M_A_CPU0_SA_DQ<8>")
	)
	(segment
		(start 311.044844 -207.558386)
		(end 310.893968 -207.558132)
		(width 0.10668)
		(layer "F.Cu")
		(net "M_A_CPU0_SA_DQ<8>")
	)
	(segment
		(start 310.480456 -206.993998)
		(end 310.32958 -206.993744)
		(width 0.10668)
		(layer "F.Cu")
		(net "M_A_CPU0_SA_DQ<8>")
	)
	(segment
		(start 309.643526 -206.551022)
		(end 309.50916 -206.685388)
		(width 0.10668)
		(layer "F.Cu")
		(net "M_A_CPU0_SA_DQ<8>")
	)
	(segment
		(start 309.50916 -206.685388)
		(end 309.358538 -206.685134)
		(width 0.10668)
		(layer "F.Cu")
		(net "M_A_CPU0_SA_DQ<8>")
	)
	(segment
		(start 309.421022 -207.488028)
		(end 309.421276 -207.33766)
		(width 0.10668)
		(layer "F.Cu")
		(net "M_A_CPU0_SA_DQ<8>")
	)
	(segment
		(start 325.38416 -230.54945)
		(end 324.426834 -230.54945)
		(width 0.0762)
		(layer "F.Cu")
		(net "M_A_CPU0_SA_DQ<8>")
	)
	(segment
		(start 309.358538 -206.685134)
		(end 307.368194 -206.685134)
		(width 0.10668)
		(layer "F.Cu")
		(net "M_A_CPU0_SA_DQ<8>")
	)
	(segment
		(start 310.354218 -207.533494)
		(end 310.611774 -207.275938)
		(width 0.10668)
		(layer "F.Cu")
		(net "M_A_CPU0_SA_DQ<8>")
	)
	(segment
		(start 311.176162 -207.840326)
		(end 311.176416 -207.689958)
		(width 0.10668)
		(layer "F.Cu")
		(net "M_A_CPU0_SA_DQ<8>")
	)
	(segment
		(start 310.32958 -206.993744)
		(end 309.70347 -207.619854)
		(width 0.10668)
		(layer "F.Cu")
		(net "M_A_CPU0_SA_DQ<8>")
	)
	(arc
		(start 325.830438 -230.418132)
		(mid 325.708582 -230.442288)
		(end 325.59498 -230.492554)
		(width 0.0762)
		(layer "F.Cu")
		(net "M_A_CPU0_SA_DQ<8>")
	)
	(arc
		(start 325.59498 -230.492554)
		(mid 325.49334 -230.534969)
		(end 325.38416 -230.54945)
		(width 0.0762)
		(layer "F.Cu")
		(net "M_A_CPU0_SA_DQ<8>")
	)
	(arc
		(start 326.34809 -230.169974)
		(mid 326.111962 -230.341409)
		(end 325.830438 -230.418132)
		(width 0.0762)
		(layer "F.Cu")
		(net "M_A_CPU0_SA_DQ<8>")
	)
	(segment
		(start 309.911496 -206.090774)
		(end 309.76062 -206.090774)
		(width 0.10668)
		(layer "F.Cu")
		(net "M_A_CPU0_SA_DQ<7>")
	)
	(segment
		(start 309.629302 -205.959456)
		(end 309.629302 -205.80858)
		(width 0.10668)
		(layer "F.Cu")
		(net "M_A_CPU0_SA_DQ<7>")
	)
	(segment
		(start 311.633616 -207.49641)
		(end 310.145176 -206.00797)
		(width 0.10668)
		(layer "F.Cu")
		(net "M_A_CPU0_SA_DQ<7>")
	)
	(segment
		(start 308.610508 -205.410054)
		(end 306.070508 -205.410054)
		(width 0.101346)
		(layer "F.Cu")
		(net "M_A_CPU0_SA_DQ<7>")
	)
	(segment
		(start 325.408036 -229.797102)
		(end 323.99859 -229.797102)
		(width 0.0762)
		(layer "F.Cu")
		(net "M_A_CPU0_SA_DQ<7>")
	)
	(segment
		(start 326.535034 -229.847648)
		(end 326.526652 -229.842822)
		(width 0.0762)
		(layer "F.Cu")
		(net "M_A_CPU0_SA_DQ<7>")
	)
	(segment
		(start 309.629302 -205.80858)
		(end 309.712106 -205.725776)
		(width 0.10668)
		(layer "F.Cu")
		(net "M_A_CPU0_SA_DQ<7>")
	)
	(segment
		(start 320.625978 -217.30589)
		(end 311.633616 -208.313528)
		(width 0.10668)
		(layer "F.Cu")
		(net "M_A_CPU0_SA_DQ<7>")
	)
	(segment
		(start 309.76062 -206.090774)
		(end 309.629302 -205.959456)
		(width 0.10668)
		(layer "F.Cu")
		(net "M_A_CPU0_SA_DQ<7>")
	)
	(segment
		(start 309.712106 -205.5749)
		(end 309.54726 -205.410054)
		(width 0.10668)
		(layer "F.Cu")
		(net "M_A_CPU0_SA_DQ<7>")
	)
	(segment
		(start 306.070508 -205.410054)
		(end 305.645566 -205.834996)
		(width 0.101346)
		(layer "F.Cu")
		(net "M_A_CPU0_SA_DQ<7>")
	)
	(segment
		(start 327.28789 -230.169974)
		(end 327.388728 -229.996746)
		(width 0.0762)
		(layer "F.Cu")
		(net "M_A_CPU0_SA_DQ<7>")
	)
	(segment
		(start 327.109328 -229.842822)
		(end 327.100946 -229.847648)
		(width 0.0762)
		(layer "F.Cu")
		(net "M_A_CPU0_SA_DQ<7>")
	)
	(segment
		(start 311.633616 -208.313528)
		(end 311.633616 -207.49641)
		(width 0.10668)
		(layer "F.Cu")
		(net "M_A_CPU0_SA_DQ<7>")
	)
	(segment
		(start 309.54726 -205.410054)
		(end 308.610508 -205.410054)
		(width 0.10668)
		(layer "F.Cu")
		(net "M_A_CPU0_SA_DQ<7>")
	)
	(segment
		(start 309.712106 -205.725776)
		(end 309.712106 -205.5749)
		(width 0.10668)
		(layer "F.Cu")
		(net "M_A_CPU0_SA_DQ<7>")
	)
	(segment
		(start 323.996558 -229.79507)
		(end 323.924422 -229.79507)
		(width 0.10668)
		(layer "F.Cu")
		(net "M_A_CPU0_SA_DQ<7>")
	)
	(segment
		(start 305.645566 -205.834996)
		(end 303.268126 -205.834996)
		(width 0.101346)
		(layer "F.Cu")
		(net "M_A_CPU0_SA_DQ<7>")
	)
	(segment
		(start 310.145176 -206.00797)
		(end 309.9943 -206.00797)
		(width 0.10668)
		(layer "F.Cu")
		(net "M_A_CPU0_SA_DQ<7>")
	)
	(segment
		(start 323.99859 -229.797102)
		(end 323.996558 -229.79507)
		(width 0.0762)
		(layer "F.Cu")
		(net "M_A_CPU0_SA_DQ<7>")
	)
	(segment
		(start 309.9943 -206.00797)
		(end 309.911496 -206.090774)
		(width 0.10668)
		(layer "F.Cu")
		(net "M_A_CPU0_SA_DQ<7>")
	)
	(segment
		(start 320.625978 -226.496626)
		(end 320.625978 -217.30589)
		(width 0.10668)
		(layer "F.Cu")
		(net "M_A_CPU0_SA_DQ<7>")
	)
	(segment
		(start 323.924422 -229.79507)
		(end 320.625978 -226.496626)
		(width 0.10668)
		(layer "F.Cu")
		(net "M_A_CPU0_SA_DQ<7>")
	)
	(arc
		(start 326.160892 -229.847648)
		(mid 325.877936 -229.923825)
		(end 325.59498 -229.847648)
		(width 0.0762)
		(layer "F.Cu")
		(net "M_A_CPU0_SA_DQ<7>")
	)
	(arc
		(start 325.439024 -229.798372)
		(mid 325.423543 -229.797416)
		(end 325.408036 -229.797102)
		(width 0.0762)
		(layer "F.Cu")
		(net "M_A_CPU0_SA_DQ<7>")
	)
	(arc
		(start 326.526652 -229.842822)
		(mid 326.343144 -229.797328)
		(end 326.160892 -229.847648)
		(width 0.0762)
		(layer "F.Cu")
		(net "M_A_CPU0_SA_DQ<7>")
	)
	(arc
		(start 325.59498 -229.847648)
		(mid 325.51974 -229.814335)
		(end 325.439024 -229.798372)
		(width 0.0762)
		(layer "F.Cu")
		(net "M_A_CPU0_SA_DQ<7>")
	)
	(arc
		(start 327.100946 -229.847648)
		(mid 326.81799 -229.923825)
		(end 326.535034 -229.847648)
		(width 0.0762)
		(layer "F.Cu")
		(net "M_A_CPU0_SA_DQ<7>")
	)
	(arc
		(start 327.242678 -229.80015)
		(mid 327.17398 -229.815166)
		(end 327.109328 -229.842822)
		(width 0.0762)
		(layer "F.Cu")
		(net "M_A_CPU0_SA_DQ<7>")
	)
	(arc
		(start 327.388728 -229.996746)
		(mid 327.372803 -229.856054)
		(end 327.242678 -229.80015)
		(width 0.0762)
		(layer "F.Cu")
		(net "M_A_CPU0_SA_DQ<7>")
	)
	(segment
		(start 321.306698 -226.212146)
		(end 321.306698 -217.023442)
		(width 0.10668)
		(layer "F.Cu")
		(net "M_A_CPU0_SA_DQ<6>")
	)
	(segment
		(start 308.610508 -204.56017)
		(end 306.070508 -204.56017)
		(width 0.101346)
		(layer "F.Cu")
		(net "M_A_CPU0_SA_DQ<6>")
	)
	(segment
		(start 306.070508 -204.56017)
		(end 305.645312 -204.134974)
		(width 0.101346)
		(layer "F.Cu")
		(net "M_A_CPU0_SA_DQ<6>")
	)
	(segment
		(start 321.306698 -217.023442)
		(end 316.462664 -212.179408)
		(width 0.10668)
		(layer "F.Cu")
		(net "M_A_CPU0_SA_DQ<6>")
	)
	(segment
		(start 305.016916 -204.995272)
		(end 304.91557 -204.893926)
		(width 0.101346)
		(layer "F.Cu")
		(net "M_A_CPU0_SA_DQ<6>")
	)
	(segment
		(start 325.877936 -229.360222)
		(end 325.973694 -229.195376)
		(width 0.0762)
		(layer "F.Cu")
		(net "M_A_CPU0_SA_DQ<6>")
	)
	(segment
		(start 305.207924 -204.995272)
		(end 305.016916 -204.995272)
		(width 0.101346)
		(layer "F.Cu")
		(net "M_A_CPU0_SA_DQ<6>")
	)
	(segment
		(start 325.699374 -229.032816)
		(end 325.690992 -229.037642)
		(width 0.0762)
		(layer "F.Cu")
		(net "M_A_CPU0_SA_DQ<6>")
	)
	(segment
		(start 304.91557 -204.23632)
		(end 304.814224 -204.134974)
		(width 0.101346)
		(layer "F.Cu")
		(net "M_A_CPU0_SA_DQ<6>")
	)
	(segment
		(start 316.462664 -212.179408)
		(end 316.462664 -211.36229)
		(width 0.10668)
		(layer "F.Cu")
		(net "M_A_CPU0_SA_DQ<6>")
	)
	(segment
		(start 324.254622 -228.95687)
		(end 324.051422 -228.95687)
		(width 0.10668)
		(layer "F.Cu")
		(net "M_A_CPU0_SA_DQ<6>")
	)
	(segment
		(start 316.462664 -211.36229)
		(end 309.660544 -204.56017)
		(width 0.10668)
		(layer "F.Cu")
		(net "M_A_CPU0_SA_DQ<6>")
	)
	(segment
		(start 305.30927 -204.23632)
		(end 305.30927 -204.893926)
		(width 0.101346)
		(layer "F.Cu")
		(net "M_A_CPU0_SA_DQ<6>")
	)
	(segment
		(start 325.262494 -229.16261)
		(end 324.460362 -229.16261)
		(width 0.0762)
		(layer "F.Cu")
		(net "M_A_CPU0_SA_DQ<6>")
	)
	(segment
		(start 309.660544 -204.56017)
		(end 308.610508 -204.56017)
		(width 0.10668)
		(layer "F.Cu")
		(net "M_A_CPU0_SA_DQ<6>")
	)
	(segment
		(start 304.91557 -204.893926)
		(end 304.91557 -204.23632)
		(width 0.101346)
		(layer "F.Cu")
		(net "M_A_CPU0_SA_DQ<6>")
	)
	(segment
		(start 304.814224 -204.134974)
		(end 303.268126 -204.134974)
		(width 0.101346)
		(layer "F.Cu")
		(net "M_A_CPU0_SA_DQ<6>")
	)
	(segment
		(start 324.460362 -229.16261)
		(end 324.254622 -228.95687)
		(width 0.0762)
		(layer "F.Cu")
		(net "M_A_CPU0_SA_DQ<6>")
	)
	(segment
		(start 305.645312 -204.134974)
		(end 305.410616 -204.134974)
		(width 0.101346)
		(layer "F.Cu")
		(net "M_A_CPU0_SA_DQ<6>")
	)
	(segment
		(start 305.410616 -204.134974)
		(end 305.30927 -204.23632)
		(width 0.101346)
		(layer "F.Cu")
		(net "M_A_CPU0_SA_DQ<6>")
	)
	(segment
		(start 305.30927 -204.893926)
		(end 305.207924 -204.995272)
		(width 0.101346)
		(layer "F.Cu")
		(net "M_A_CPU0_SA_DQ<6>")
	)
	(segment
		(start 324.051422 -228.95687)
		(end 321.306698 -226.212146)
		(width 0.10668)
		(layer "F.Cu")
		(net "M_A_CPU0_SA_DQ<6>")
	)
	(arc
		(start 325.827644 -228.990652)
		(mid 325.761576 -229.005861)
		(end 325.699374 -229.032816)
		(width 0.0762)
		(layer "F.Cu")
		(net "M_A_CPU0_SA_DQ<6>")
	)
	(arc
		(start 325.690992 -229.037642)
		(mid 325.48567 -229.130738)
		(end 325.262494 -229.16261)
		(width 0.0762)
		(layer "F.Cu")
		(net "M_A_CPU0_SA_DQ<6>")
	)
	(arc
		(start 325.973694 -229.195376)
		(mid 325.962504 -229.04882)
		(end 325.827644 -228.990652)
		(width 0.0762)
		(layer "F.Cu")
		(net "M_A_CPU0_SA_DQ<6>")
	)
	(segment
		(start 312.604404 -208.198466)
		(end 312.453528 -208.198466)
		(width 0.10668)
		(layer "F.Cu")
		(net "M_A_CPU0_SA_DQ<5>")
	)
	(segment
		(start 313.582304 -209.327242)
		(end 313.43092 -209.478626)
		(width 0.10668)
		(layer "F.Cu")
		(net "M_A_CPU0_SA_DQ<5>")
	)
	(segment
		(start 325.699374 -229.687628)
		(end 325.690992 -229.682802)
		(width 0.0762)
		(layer "F.Cu")
		(net "M_A_CPU0_SA_DQ<5>")
	)
	(segment
		(start 312.453528 -208.198466)
		(end 312.302144 -208.34985)
		(width 0.10668)
		(layer "F.Cu")
		(net "M_A_CPU0_SA_DQ<5>")
	)
	(segment
		(start 312.151268 -208.349596)
		(end 311.973976 -208.172304)
		(width 0.10668)
		(layer "F.Cu")
		(net "M_A_CPU0_SA_DQ<5>")
	)
	(segment
		(start 314.993528 -210.58759)
		(end 314.861956 -210.456018)
		(width 0.10668)
		(layer "F.Cu")
		(net "M_A_CPU0_SA_DQ<5>")
	)
	(segment
		(start 324.14845 -229.358444)
		(end 323.970396 -229.358444)
		(width 0.10668)
		(layer "F.Cu")
		(net "M_A_CPU0_SA_DQ<5>")
	)
	(segment
		(start 325.40829 -229.606602)
		(end 324.396608 -229.606602)
		(width 0.0762)
		(layer "F.Cu")
		(net "M_A_CPU0_SA_DQ<5>")
	)
	(segment
		(start 314.84189 -210.889342)
		(end 314.993274 -210.737958)
		(width 0.10668)
		(layer "F.Cu")
		(net "M_A_CPU0_SA_DQ<5>")
	)
	(segment
		(start 314.42914 -210.023202)
		(end 314.297568 -209.89163)
		(width 0.10668)
		(layer "F.Cu")
		(net "M_A_CPU0_SA_DQ<5>")
	)
	(segment
		(start 314.71108 -210.456018)
		(end 314.559696 -210.607402)
		(width 0.10668)
		(layer "F.Cu")
		(net "M_A_CPU0_SA_DQ<5>")
	)
	(segment
		(start 315.406278 -211.45373)
		(end 315.557662 -211.302346)
		(width 0.10668)
		(layer "F.Cu")
		(net "M_A_CPU0_SA_DQ<5>")
	)
	(segment
		(start 311.973976 -208.172304)
		(end 311.973976 -207.355186)
		(width 0.10668)
		(layer "F.Cu")
		(net "M_A_CPU0_SA_DQ<5>")
	)
	(segment
		(start 313.844432 -210.04276)
		(end 313.713114 -209.911442)
		(width 0.10668)
		(layer "F.Cu")
		(net "M_A_CPU0_SA_DQ<5>")
	)
	(segment
		(start 315.557916 -211.151978)
		(end 315.426344 -211.020406)
		(width 0.10668)
		(layer "F.Cu")
		(net "M_A_CPU0_SA_DQ<5>")
	)
	(segment
		(start 314.559696 -210.607402)
		(end 314.40882 -210.607148)
		(width 0.10668)
		(layer "F.Cu")
		(net "M_A_CPU0_SA_DQ<5>")
	)
	(segment
		(start 324.396608 -229.606602)
		(end 324.14845 -229.358444)
		(width 0.0762)
		(layer "F.Cu")
		(net "M_A_CPU0_SA_DQ<5>")
	)
	(segment
		(start 312.715656 -208.913984)
		(end 312.584338 -208.782666)
		(width 0.10668)
		(layer "F.Cu")
		(net "M_A_CPU0_SA_DQ<5>")
	)
	(segment
		(start 315.970666 -212.018118)
		(end 316.12205 -211.866734)
		(width 0.10668)
		(layer "F.Cu")
		(net "M_A_CPU0_SA_DQ<5>")
	)
	(segment
		(start 314.277502 -210.324954)
		(end 314.428886 -210.17357)
		(width 0.10668)
		(layer "F.Cu")
		(net "M_A_CPU0_SA_DQ<5>")
	)
	(segment
		(start 320.966338 -226.354386)
		(end 320.966338 -217.164666)
		(width 0.10668)
		(layer "F.Cu")
		(net "M_A_CPU0_SA_DQ<5>")
	)
	(segment
		(start 313.30011 -209.044794)
		(end 313.300364 -208.894426)
		(width 0.10668)
		(layer "F.Cu")
		(net "M_A_CPU0_SA_DQ<5>")
	)
	(segment
		(start 314.277502 -210.47583)
		(end 314.277502 -210.324954)
		(width 0.10668)
		(layer "F.Cu")
		(net "M_A_CPU0_SA_DQ<5>")
	)
	(segment
		(start 315.124084 -211.17179)
		(end 314.973208 -211.171536)
		(width 0.10668)
		(layer "F.Cu")
		(net "M_A_CPU0_SA_DQ<5>")
	)
	(segment
		(start 313.864498 -209.609182)
		(end 313.864752 -209.458814)
		(width 0.10668)
		(layer "F.Cu")
		(net "M_A_CPU0_SA_DQ<5>")
	)
	(segment
		(start 313.148726 -209.196178)
		(end 313.30011 -209.044794)
		(width 0.10668)
		(layer "F.Cu")
		(net "M_A_CPU0_SA_DQ<5>")
	)
	(segment
		(start 313.280044 -209.478372)
		(end 313.148726 -209.347054)
		(width 0.10668)
		(layer "F.Cu")
		(net "M_A_CPU0_SA_DQ<5>")
	)
	(segment
		(start 312.584338 -208.63179)
		(end 312.735722 -208.480406)
		(width 0.10668)
		(layer "F.Cu")
		(net "M_A_CPU0_SA_DQ<5>")
	)
	(segment
		(start 313.43092 -209.478626)
		(end 313.280044 -209.478372)
		(width 0.10668)
		(layer "F.Cu")
		(net "M_A_CPU0_SA_DQ<5>")
	)
	(segment
		(start 313.148726 -209.347054)
		(end 313.148726 -209.196178)
		(width 0.10668)
		(layer "F.Cu")
		(net "M_A_CPU0_SA_DQ<5>")
	)
	(segment
		(start 315.426344 -211.020406)
		(end 315.275468 -211.020406)
		(width 0.10668)
		(layer "F.Cu")
		(net "M_A_CPU0_SA_DQ<5>")
	)
	(segment
		(start 315.406278 -211.604606)
		(end 315.406278 -211.45373)
		(width 0.10668)
		(layer "F.Cu")
		(net "M_A_CPU0_SA_DQ<5>")
	)
	(segment
		(start 313.864752 -209.458814)
		(end 313.73318 -209.327242)
		(width 0.10668)
		(layer "F.Cu")
		(net "M_A_CPU0_SA_DQ<5>")
	)
	(segment
		(start 313.713114 -209.760566)
		(end 313.864498 -209.609182)
		(width 0.10668)
		(layer "F.Cu")
		(net "M_A_CPU0_SA_DQ<5>")
	)
	(segment
		(start 312.584338 -208.782666)
		(end 312.584338 -208.63179)
		(width 0.10668)
		(layer "F.Cu")
		(net "M_A_CPU0_SA_DQ<5>")
	)
	(segment
		(start 314.297568 -209.89163)
		(end 314.146692 -209.89163)
		(width 0.10668)
		(layer "F.Cu")
		(net "M_A_CPU0_SA_DQ<5>")
	)
	(segment
		(start 313.300364 -208.894426)
		(end 313.168792 -208.762854)
		(width 0.10668)
		(layer "F.Cu")
		(net "M_A_CPU0_SA_DQ<5>")
	)
	(segment
		(start 312.735976 -208.330038)
		(end 312.604404 -208.198466)
		(width 0.10668)
		(layer "F.Cu")
		(net "M_A_CPU0_SA_DQ<5>")
	)
	(segment
		(start 313.017916 -208.762854)
		(end 312.866532 -208.914238)
		(width 0.10668)
		(layer "F.Cu")
		(net "M_A_CPU0_SA_DQ<5>")
	)
	(segment
		(start 315.275468 -211.020406)
		(end 315.124084 -211.17179)
		(width 0.10668)
		(layer "F.Cu")
		(net "M_A_CPU0_SA_DQ<5>")
	)
	(segment
		(start 314.993274 -210.737958)
		(end 314.993528 -210.58759)
		(width 0.10668)
		(layer "F.Cu")
		(net "M_A_CPU0_SA_DQ<5>")
	)
	(segment
		(start 316.122304 -211.716366)
		(end 315.990732 -211.584794)
		(width 0.10668)
		(layer "F.Cu")
		(net "M_A_CPU0_SA_DQ<5>")
	)
	(segment
		(start 313.995308 -210.043014)
		(end 313.844432 -210.04276)
		(width 0.10668)
		(layer "F.Cu")
		(net "M_A_CPU0_SA_DQ<5>")
	)
	(segment
		(start 313.713114 -209.911442)
		(end 313.713114 -209.760566)
		(width 0.10668)
		(layer "F.Cu")
		(net "M_A_CPU0_SA_DQ<5>")
	)
	(segment
		(start 314.40882 -210.607148)
		(end 314.277502 -210.47583)
		(width 0.10668)
		(layer "F.Cu")
		(net "M_A_CPU0_SA_DQ<5>")
	)
	(segment
		(start 313.73318 -209.327242)
		(end 313.582304 -209.327242)
		(width 0.10668)
		(layer "F.Cu")
		(net "M_A_CPU0_SA_DQ<5>")
	)
	(segment
		(start 315.688472 -211.736178)
		(end 315.537596 -211.735924)
		(width 0.10668)
		(layer "F.Cu")
		(net "M_A_CPU0_SA_DQ<5>")
	)
	(segment
		(start 314.146692 -209.89163)
		(end 313.995308 -210.043014)
		(width 0.10668)
		(layer "F.Cu")
		(net "M_A_CPU0_SA_DQ<5>")
	)
	(segment
		(start 315.557662 -211.302346)
		(end 315.557916 -211.151978)
		(width 0.10668)
		(layer "F.Cu")
		(net "M_A_CPU0_SA_DQ<5>")
	)
	(segment
		(start 313.168792 -208.762854)
		(end 313.017916 -208.762854)
		(width 0.10668)
		(layer "F.Cu")
		(net "M_A_CPU0_SA_DQ<5>")
	)
	(segment
		(start 312.302144 -208.34985)
		(end 312.151268 -208.349596)
		(width 0.10668)
		(layer "F.Cu")
		(net "M_A_CPU0_SA_DQ<5>")
	)
	(segment
		(start 323.970396 -229.358444)
		(end 320.966338 -226.354386)
		(width 0.10668)
		(layer "F.Cu")
		(net "M_A_CPU0_SA_DQ<5>")
	)
	(segment
		(start 312.866532 -208.914238)
		(end 312.715656 -208.913984)
		(width 0.10668)
		(layer "F.Cu")
		(net "M_A_CPU0_SA_DQ<5>")
	)
	(segment
		(start 312.735722 -208.480406)
		(end 312.735976 -208.330038)
		(width 0.10668)
		(layer "F.Cu")
		(net "M_A_CPU0_SA_DQ<5>")
	)
	(segment
		(start 320.966338 -217.164666)
		(end 315.970666 -212.168994)
		(width 0.10668)
		(layer "F.Cu")
		(net "M_A_CPU0_SA_DQ<5>")
	)
	(segment
		(start 314.428886 -210.17357)
		(end 314.42914 -210.023202)
		(width 0.10668)
		(layer "F.Cu")
		(net "M_A_CPU0_SA_DQ<5>")
	)
	(segment
		(start 315.990732 -211.584794)
		(end 315.839856 -211.584794)
		(width 0.10668)
		(layer "F.Cu")
		(net "M_A_CPU0_SA_DQ<5>")
	)
	(segment
		(start 314.84189 -211.040218)
		(end 314.84189 -210.889342)
		(width 0.10668)
		(layer "F.Cu")
		(net "M_A_CPU0_SA_DQ<5>")
	)
	(segment
		(start 315.970666 -212.168994)
		(end 315.970666 -212.018118)
		(width 0.10668)
		(layer "F.Cu")
		(net "M_A_CPU0_SA_DQ<5>")
	)
	(segment
		(start 315.537596 -211.735924)
		(end 315.406278 -211.604606)
		(width 0.10668)
		(layer "F.Cu")
		(net "M_A_CPU0_SA_DQ<5>")
	)
	(segment
		(start 314.861956 -210.456018)
		(end 314.71108 -210.456018)
		(width 0.10668)
		(layer "F.Cu")
		(net "M_A_CPU0_SA_DQ<5>")
	)
	(segment
		(start 315.839856 -211.584794)
		(end 315.688472 -211.736178)
		(width 0.10668)
		(layer "F.Cu")
		(net "M_A_CPU0_SA_DQ<5>")
	)
	(segment
		(start 314.973208 -211.171536)
		(end 314.84189 -211.040218)
		(width 0.10668)
		(layer "F.Cu")
		(net "M_A_CPU0_SA_DQ<5>")
	)
	(segment
		(start 311.973976 -207.355186)
		(end 309.603902 -204.985112)
		(width 0.10668)
		(layer "F.Cu")
		(net "M_A_CPU0_SA_DQ<5>")
	)
	(segment
		(start 316.12205 -211.866734)
		(end 316.122304 -211.716366)
		(width 0.10668)
		(layer "F.Cu")
		(net "M_A_CPU0_SA_DQ<5>")
	)
	(segment
		(start 309.603902 -204.985112)
		(end 307.368194 -204.985112)
		(width 0.10668)
		(layer "F.Cu")
		(net "M_A_CPU0_SA_DQ<5>")
	)
	(arc
		(start 325.45528 -229.60838)
		(mid 325.431803 -229.607004)
		(end 325.40829 -229.606602)
		(width 0.0762)
		(layer "F.Cu")
		(net "M_A_CPU0_SA_DQ<5>")
	)
	(arc
		(start 327.004934 -229.682802)
		(mid 326.81799 -229.733057)
		(end 326.631046 -229.682802)
		(width 0.0762)
		(layer "F.Cu")
		(net "M_A_CPU0_SA_DQ<5>")
	)
	(arc
		(start 327.238106 -229.608634)
		(mid 327.117457 -229.632935)
		(end 327.004934 -229.682802)
		(width 0.0762)
		(layer "F.Cu")
		(net "M_A_CPU0_SA_DQ<5>")
	)
	(arc
		(start 326.631046 -229.682802)
		(mid 326.34809 -229.606625)
		(end 326.065134 -229.682802)
		(width 0.0762)
		(layer "F.Cu")
		(net "M_A_CPU0_SA_DQ<5>")
	)
	(arc
		(start 325.690992 -229.682802)
		(mid 325.577268 -229.632501)
		(end 325.45528 -229.60838)
		(width 0.0762)
		(layer "F.Cu")
		(net "M_A_CPU0_SA_DQ<5>")
	)
	(arc
		(start 326.065134 -229.682802)
		(mid 325.882883 -229.733152)
		(end 325.699374 -229.687628)
		(width 0.0762)
		(layer "F.Cu")
		(net "M_A_CPU0_SA_DQ<5>")
	)
	(arc
		(start 327.758044 -229.360222)
		(mid 327.520432 -229.53121)
		(end 327.238106 -229.608634)
		(width 0.0762)
		(layer "F.Cu")
		(net "M_A_CPU0_SA_DQ<5>")
	)
	(segment
		(start 317.352172 -211.920582)
		(end 317.094362 -212.178392)
		(width 0.10668)
		(layer "F.Cu")
		(net "M_A_CPU0_SA_DQ<4>")
	)
	(segment
		(start 309.08244 -204.21727)
		(end 308.931564 -204.21727)
		(width 0.10668)
		(layer "F.Cu")
		(net "M_A_CPU0_SA_DQ<4>")
	)
	(segment
		(start 318.480948 -213.049358)
		(end 318.223138 -213.307168)
		(width 0.10668)
		(layer "F.Cu")
		(net "M_A_CPU0_SA_DQ<4>")
	)
	(segment
		(start 317.072518 -211.484972)
		(end 309.519066 -203.93152)
		(width 0.10668)
		(layer "F.Cu")
		(net "M_A_CPU0_SA_DQ<4>")
	)
	(segment
		(start 321.647058 -216.881964)
		(end 319.634108 -214.869014)
		(width 0.10668)
		(layer "F.Cu")
		(net "M_A_CPU0_SA_DQ<4>")
	)
	(segment
		(start 318.072262 -213.307168)
		(end 317.940944 -213.17585)
		(width 0.10668)
		(layer "F.Cu")
		(net "M_A_CPU0_SA_DQ<4>")
	)
	(segment
		(start 309.085996 -203.649326)
		(end 309.085996 -203.49845)
		(width 0.10668)
		(layer "F.Cu")
		(net "M_A_CPU0_SA_DQ<4>")
	)
	(segment
		(start 319.201038 -214.435944)
		(end 319.06972 -214.304626)
		(width 0.10668)
		(layer "F.Cu")
		(net "M_A_CPU0_SA_DQ<4>")
	)
	(segment
		(start 319.634108 -214.718138)
		(end 319.780158 -214.572088)
		(width 0.10668)
		(layer "F.Cu")
		(net "M_A_CPU0_SA_DQ<4>")
	)
	(segment
		(start 317.65875 -212.74278)
		(end 317.507874 -212.74278)
		(width 0.10668)
		(layer "F.Cu")
		(net "M_A_CPU0_SA_DQ<4>")
	)
	(segment
		(start 324.472554 -228.72827)
		(end 324.366636 -228.622352)
		(width 0.10668)
		(layer "F.Cu")
		(net "M_A_CPU0_SA_DQ<4>")
	)
	(segment
		(start 319.22974 -213.99373)
		(end 319.22974 -213.842854)
		(width 0.10668)
		(layer "F.Cu")
		(net "M_A_CPU0_SA_DQ<4>")
	)
	(segment
		(start 324.225412 -228.622352)
		(end 321.647058 -226.043998)
		(width 0.10668)
		(layer "F.Cu")
		(net "M_A_CPU0_SA_DQ<4>")
	)
	(segment
		(start 318.223138 -213.307168)
		(end 318.072262 -213.307168)
		(width 0.10668)
		(layer "F.Cu")
		(net "M_A_CPU0_SA_DQ<4>")
	)
	(segment
		(start 317.634366 -212.0519)
		(end 317.503048 -211.920582)
		(width 0.10668)
		(layer "F.Cu")
		(net "M_A_CPU0_SA_DQ<4>")
	)
	(segment
		(start 308.931564 -204.21727)
		(end 308.800246 -204.085952)
		(width 0.10668)
		(layer "F.Cu")
		(net "M_A_CPU0_SA_DQ<4>")
	)
	(segment
		(start 316.812422 -212.047328)
		(end 316.812422 -211.896198)
		(width 0.10668)
		(layer "F.Cu")
		(net "M_A_CPU0_SA_DQ<4>")
	)
	(segment
		(start 319.64884 -214.289894)
		(end 319.497964 -214.289894)
		(width 0.10668)
		(layer "F.Cu")
		(net "M_A_CPU0_SA_DQ<4>")
	)
	(segment
		(start 319.098422 -213.711536)
		(end 318.947546 -213.711536)
		(width 0.10668)
		(layer "F.Cu")
		(net "M_A_CPU0_SA_DQ<4>")
	)
	(segment
		(start 325.313294 -228.94671)
		(end 324.690994 -228.94671)
		(width 0.0762)
		(layer "F.Cu")
		(net "M_A_CPU0_SA_DQ<4>")
	)
	(segment
		(start 324.690994 -228.94671)
		(end 324.472554 -228.72827)
		(width 0.0762)
		(layer "F.Cu")
		(net "M_A_CPU0_SA_DQ<4>")
	)
	(segment
		(start 317.91656 -212.48497)
		(end 317.65875 -212.74278)
		(width 0.10668)
		(layer "F.Cu")
		(net "M_A_CPU0_SA_DQ<4>")
	)
	(segment
		(start 324.366636 -228.622352)
		(end 324.225412 -228.622352)
		(width 0.10668)
		(layer "F.Cu")
		(net "M_A_CPU0_SA_DQ<4>")
	)
	(segment
		(start 318.505332 -213.589362)
		(end 318.763142 -213.331552)
		(width 0.10668)
		(layer "F.Cu")
		(net "M_A_CPU0_SA_DQ<4>")
	)
	(segment
		(start 316.943486 -212.178392)
		(end 316.812422 -212.047328)
		(width 0.10668)
		(layer "F.Cu")
		(net "M_A_CPU0_SA_DQ<4>")
	)
	(segment
		(start 317.072518 -211.636102)
		(end 317.072518 -211.484972)
		(width 0.10668)
		(layer "F.Cu")
		(net "M_A_CPU0_SA_DQ<4>")
	)
	(segment
		(start 308.800246 -203.935076)
		(end 309.085996 -203.649326)
		(width 0.10668)
		(layer "F.Cu")
		(net "M_A_CPU0_SA_DQ<4>")
	)
	(segment
		(start 318.763142 -213.180676)
		(end 318.631824 -213.049358)
		(width 0.10668)
		(layer "F.Cu")
		(net "M_A_CPU0_SA_DQ<4>")
	)
	(segment
		(start 308.872636 -203.28509)
		(end 307.368194 -203.28509)
		(width 0.10668)
		(layer "F.Cu")
		(net "M_A_CPU0_SA_DQ<4>")
	)
	(segment
		(start 319.634108 -214.869014)
		(end 319.634108 -214.718138)
		(width 0.10668)
		(layer "F.Cu")
		(net "M_A_CPU0_SA_DQ<4>")
	)
	(segment
		(start 317.503048 -211.920582)
		(end 317.352172 -211.920582)
		(width 0.10668)
		(layer "F.Cu")
		(net "M_A_CPU0_SA_DQ<4>")
	)
	(segment
		(start 318.505332 -213.740238)
		(end 318.505332 -213.589362)
		(width 0.10668)
		(layer "F.Cu")
		(net "M_A_CPU0_SA_DQ<4>")
	)
	(segment
		(start 317.940944 -213.17585)
		(end 317.940944 -213.024974)
		(width 0.10668)
		(layer "F.Cu")
		(net "M_A_CPU0_SA_DQ<4>")
	)
	(segment
		(start 318.63665 -213.871556)
		(end 318.505332 -213.740238)
		(width 0.10668)
		(layer "F.Cu")
		(net "M_A_CPU0_SA_DQ<4>")
	)
	(segment
		(start 319.351914 -214.435944)
		(end 319.201038 -214.435944)
		(width 0.10668)
		(layer "F.Cu")
		(net "M_A_CPU0_SA_DQ<4>")
	)
	(segment
		(start 309.36819 -203.93152)
		(end 309.08244 -204.21727)
		(width 0.10668)
		(layer "F.Cu")
		(net "M_A_CPU0_SA_DQ<4>")
	)
	(segment
		(start 318.198754 -212.767164)
		(end 318.198754 -212.616288)
		(width 0.10668)
		(layer "F.Cu")
		(net "M_A_CPU0_SA_DQ<4>")
	)
	(segment
		(start 318.763142 -213.331552)
		(end 318.763142 -213.180676)
		(width 0.10668)
		(layer "F.Cu")
		(net "M_A_CPU0_SA_DQ<4>")
	)
	(segment
		(start 309.519066 -203.93152)
		(end 309.36819 -203.93152)
		(width 0.10668)
		(layer "F.Cu")
		(net "M_A_CPU0_SA_DQ<4>")
	)
	(segment
		(start 318.631824 -213.049358)
		(end 318.480948 -213.049358)
		(width 0.10668)
		(layer "F.Cu")
		(net "M_A_CPU0_SA_DQ<4>")
	)
	(segment
		(start 319.780158 -214.421212)
		(end 319.64884 -214.289894)
		(width 0.10668)
		(layer "F.Cu")
		(net "M_A_CPU0_SA_DQ<4>")
	)
	(segment
		(start 317.376556 -212.460586)
		(end 317.634366 -212.202776)
		(width 0.10668)
		(layer "F.Cu")
		(net "M_A_CPU0_SA_DQ<4>")
	)
	(segment
		(start 319.06972 -214.304626)
		(end 319.06972 -214.15375)
		(width 0.10668)
		(layer "F.Cu")
		(net "M_A_CPU0_SA_DQ<4>")
	)
	(segment
		(start 316.812422 -211.896198)
		(end 317.072518 -211.636102)
		(width 0.10668)
		(layer "F.Cu")
		(net "M_A_CPU0_SA_DQ<4>")
	)
	(segment
		(start 318.067436 -212.48497)
		(end 317.91656 -212.48497)
		(width 0.10668)
		(layer "F.Cu")
		(net "M_A_CPU0_SA_DQ<4>")
	)
	(segment
		(start 319.22974 -213.842854)
		(end 319.098422 -213.711536)
		(width 0.10668)
		(layer "F.Cu")
		(net "M_A_CPU0_SA_DQ<4>")
	)
	(segment
		(start 319.06972 -214.15375)
		(end 319.22974 -213.99373)
		(width 0.10668)
		(layer "F.Cu")
		(net "M_A_CPU0_SA_DQ<4>")
	)
	(segment
		(start 317.376556 -212.611462)
		(end 317.376556 -212.460586)
		(width 0.10668)
		(layer "F.Cu")
		(net "M_A_CPU0_SA_DQ<4>")
	)
	(segment
		(start 319.780158 -214.572088)
		(end 319.780158 -214.421212)
		(width 0.10668)
		(layer "F.Cu")
		(net "M_A_CPU0_SA_DQ<4>")
	)
	(segment
		(start 321.647058 -226.043998)
		(end 321.647058 -216.881964)
		(width 0.10668)
		(layer "F.Cu")
		(net "M_A_CPU0_SA_DQ<4>")
	)
	(segment
		(start 318.787526 -213.871556)
		(end 318.63665 -213.871556)
		(width 0.10668)
		(layer "F.Cu")
		(net "M_A_CPU0_SA_DQ<4>")
	)
	(segment
		(start 308.800246 -204.085952)
		(end 308.800246 -203.935076)
		(width 0.10668)
		(layer "F.Cu")
		(net "M_A_CPU0_SA_DQ<4>")
	)
	(segment
		(start 317.094362 -212.178392)
		(end 316.943486 -212.178392)
		(width 0.10668)
		(layer "F.Cu")
		(net "M_A_CPU0_SA_DQ<4>")
	)
	(segment
		(start 318.947546 -213.711536)
		(end 318.787526 -213.871556)
		(width 0.10668)
		(layer "F.Cu")
		(net "M_A_CPU0_SA_DQ<4>")
	)
	(segment
		(start 317.507874 -212.74278)
		(end 317.376556 -212.611462)
		(width 0.10668)
		(layer "F.Cu")
		(net "M_A_CPU0_SA_DQ<4>")
	)
	(segment
		(start 318.198754 -212.616288)
		(end 318.067436 -212.48497)
		(width 0.10668)
		(layer "F.Cu")
		(net "M_A_CPU0_SA_DQ<4>")
	)
	(segment
		(start 309.085996 -203.49845)
		(end 308.872636 -203.28509)
		(width 0.10668)
		(layer "F.Cu")
		(net "M_A_CPU0_SA_DQ<4>")
	)
	(segment
		(start 317.940944 -213.024974)
		(end 318.198754 -212.767164)
		(width 0.10668)
		(layer "F.Cu")
		(net "M_A_CPU0_SA_DQ<4>")
	)
	(segment
		(start 317.634366 -212.202776)
		(end 317.634366 -212.0519)
		(width 0.10668)
		(layer "F.Cu")
		(net "M_A_CPU0_SA_DQ<4>")
	)
	(segment
		(start 319.497964 -214.289894)
		(end 319.351914 -214.435944)
		(width 0.10668)
		(layer "F.Cu")
		(net "M_A_CPU0_SA_DQ<4>")
	)
	(arc
		(start 325.59498 -228.872796)
		(mid 325.458904 -228.927917)
		(end 325.313294 -228.94671)
		(width 0.0762)
		(layer "F.Cu")
		(net "M_A_CPU0_SA_DQ<4>")
	)
	(arc
		(start 326.34809 -228.550216)
		(mid 326.111728 -228.721809)
		(end 325.82993 -228.798628)
		(width 0.0762)
		(layer "F.Cu")
		(net "M_A_CPU0_SA_DQ<4>")
	)
	(arc
		(start 325.82993 -228.798628)
		(mid 325.708345 -228.822699)
		(end 325.59498 -228.872796)
		(width 0.0762)
		(layer "F.Cu")
		(net "M_A_CPU0_SA_DQ<4>")
	)
	(segment
		(start 326.535034 -226.607624)
		(end 326.526652 -226.602798)
		(width 0.0762)
		(layer "F.Cu")
		(net "M_A_CPU0_SA_DQ<3>")
	)
	(segment
		(start 305.74488 -200.310242)
		(end 305.587654 -200.153016)
		(width 0.101346)
		(layer "F.Cu")
		(net "M_A_CPU0_SA_DQ<3>")
	)
	(segment
		(start 327.38314 -226.76612)
		(end 327.38314 -226.673156)
		(width 0.0762)
		(layer "F.Cu")
		(net "M_A_CPU0_SA_DQ<3>")
	)
	(segment
		(start 305.587654 -200.153016)
		(end 304.940716 -199.885046)
		(width 0.101346)
		(layer "F.Cu")
		(net "M_A_CPU0_SA_DQ<3>")
	)
	(segment
		(start 327.28789 -226.930204)
		(end 327.38314 -226.76612)
		(width 0.0762)
		(layer "F.Cu")
		(net "M_A_CPU0_SA_DQ<3>")
	)
	(segment
		(start 324.303898 -225.955352)
		(end 323.534278 -225.185732)
		(width 0.10668)
		(layer "F.Cu")
		(net "M_A_CPU0_SA_DQ<3>")
	)
	(segment
		(start 323.534278 -225.185732)
		(end 323.534278 -214.648288)
		(width 0.10668)
		(layer "F.Cu")
		(net "M_A_CPU0_SA_DQ<3>")
	)
	(segment
		(start 323.534278 -214.648288)
		(end 309.196232 -200.310242)
		(width 0.10668)
		(layer "F.Cu")
		(net "M_A_CPU0_SA_DQ<3>")
	)
	(segment
		(start 309.196232 -200.310242)
		(end 308.28488 -200.310242)
		(width 0.10668)
		(layer "F.Cu")
		(net "M_A_CPU0_SA_DQ<3>")
	)
	(segment
		(start 327.109328 -226.602798)
		(end 327.100946 -226.607624)
		(width 0.0762)
		(layer "F.Cu")
		(net "M_A_CPU0_SA_DQ<3>")
	)
	(segment
		(start 325.25589 -226.29495)
		(end 324.643496 -226.29495)
		(width 0.0762)
		(layer "F.Cu")
		(net "M_A_CPU0_SA_DQ<3>")
	)
	(segment
		(start 308.28488 -200.310242)
		(end 305.74488 -200.310242)
		(width 0.101346)
		(layer "F.Cu")
		(net "M_A_CPU0_SA_DQ<3>")
	)
	(segment
		(start 325.47941 -226.518724)
		(end 325.25589 -226.29495)
		(width 0.0762)
		(layer "F.Cu")
		(net "M_A_CPU0_SA_DQ<3>")
	)
	(segment
		(start 324.643496 -226.29495)
		(end 324.303898 -225.955352)
		(width 0.0762)
		(layer "F.Cu")
		(net "M_A_CPU0_SA_DQ<3>")
	)
	(segment
		(start 304.940716 -199.885046)
		(end 303.268126 -199.885046)
		(width 0.101346)
		(layer "F.Cu")
		(net "M_A_CPU0_SA_DQ<3>")
	)
	(arc
		(start 327.26884 -226.55784)
		(mid 327.186549 -226.571331)
		(end 327.109328 -226.602798)
		(width 0.0762)
		(layer "F.Cu")
		(net "M_A_CPU0_SA_DQ<3>")
	)
	(arc
		(start 326.526652 -226.602798)
		(mid 326.343144 -226.557304)
		(end 326.160892 -226.607624)
		(width 0.0762)
		(layer "F.Cu")
		(net "M_A_CPU0_SA_DQ<3>")
	)
	(arc
		(start 326.160892 -226.607624)
		(mid 325.805032 -226.679066)
		(end 325.47941 -226.518724)
		(width 0.0762)
		(layer "F.Cu")
		(net "M_A_CPU0_SA_DQ<3>")
	)
	(arc
		(start 327.100946 -226.607624)
		(mid 326.81799 -226.683801)
		(end 326.535034 -226.607624)
		(width 0.0762)
		(layer "F.Cu")
		(net "M_A_CPU0_SA_DQ<3>")
	)
	(arc
		(start 327.38314 -226.673156)
		(mid 327.349723 -226.591975)
		(end 327.26884 -226.55784)
		(width 0.0762)
		(layer "F.Cu")
		(net "M_A_CPU0_SA_DQ<3>")
	)
	(segment
		(start 308.239668 -233.460036)
		(end 306.522628 -233.460036)
		(width 0.101346)
		(layer "F.Cu")
		(net "M_A_CPU0_SA_DQ<31>")
	)
	(segment
		(start 327.109328 -244.422676)
		(end 327.108312 -244.423184)
		(width 0.0762)
		(layer "F.Cu")
		(net "M_A_CPU0_SA_DQ<31>")
	)
	(segment
		(start 324.343014 -244.47373)
		(end 318.20231 -244.47373)
		(width 0.10668)
		(layer "F.Cu")
		(net "M_A_CPU0_SA_DQ<31>")
	)
	(segment
		(start 325.389494 -244.37213)
		(end 324.444614 -244.37213)
		(width 0.0762)
		(layer "F.Cu")
		(net "M_A_CPU0_SA_DQ<31>")
	)
	(segment
		(start 312.714386 -239.687354)
		(end 309.633874 -236.606842)
		(width 0.10668)
		(layer "F.Cu")
		(net "M_A_CPU0_SA_DQ<31>")
	)
	(segment
		(start 327.28789 -244.750082)
		(end 327.28789 -244.749828)
		(width 0.0762)
		(layer "F.Cu")
		(net "M_A_CPU0_SA_DQ<31>")
	)
	(segment
		(start 309.633874 -235.905294)
		(end 308.536594 -234.808014)
		(width 0.10668)
		(layer "F.Cu")
		(net "M_A_CPU0_SA_DQ<31>")
	)
	(segment
		(start 306.522628 -233.460036)
		(end 306.097686 -233.884978)
		(width 0.101346)
		(layer "F.Cu")
		(net "M_A_CPU0_SA_DQ<31>")
	)
	(segment
		(start 313.415934 -239.687354)
		(end 312.714386 -239.687354)
		(width 0.10668)
		(layer "F.Cu")
		(net "M_A_CPU0_SA_DQ<31>")
	)
	(segment
		(start 306.097686 -233.884978)
		(end 303.268126 -233.884978)
		(width 0.101346)
		(layer "F.Cu")
		(net "M_A_CPU0_SA_DQ<31>")
	)
	(segment
		(start 327.28789 -244.749828)
		(end 327.393046 -244.56898)
		(width 0.0762)
		(layer "F.Cu")
		(net "M_A_CPU0_SA_DQ<31>")
	)
	(segment
		(start 327.108312 -244.423184)
		(end 327.100946 -244.427502)
		(width 0.0762)
		(layer "F.Cu")
		(net "M_A_CPU0_SA_DQ<31>")
	)
	(segment
		(start 308.536594 -233.756962)
		(end 308.407308 -233.627676)
		(width 0.10668)
		(layer "F.Cu")
		(net "M_A_CPU0_SA_DQ<31>")
	)
	(segment
		(start 318.20231 -244.47373)
		(end 313.415934 -239.687354)
		(width 0.10668)
		(layer "F.Cu")
		(net "M_A_CPU0_SA_DQ<31>")
	)
	(segment
		(start 309.633874 -236.606842)
		(end 309.633874 -235.905294)
		(width 0.10668)
		(layer "F.Cu")
		(net "M_A_CPU0_SA_DQ<31>")
	)
	(segment
		(start 326.535034 -244.427502)
		(end 326.526652 -244.422676)
		(width 0.0762)
		(layer "F.Cu")
		(net "M_A_CPU0_SA_DQ<31>")
	)
	(segment
		(start 308.536594 -234.808014)
		(end 308.536594 -233.756962)
		(width 0.10668)
		(layer "F.Cu")
		(net "M_A_CPU0_SA_DQ<31>")
	)
	(segment
		(start 308.407308 -233.627676)
		(end 308.239668 -233.460036)
		(width 0.101346)
		(layer "F.Cu")
		(net "M_A_CPU0_SA_DQ<31>")
	)
	(segment
		(start 324.444614 -244.37213)
		(end 324.343014 -244.47373)
		(width 0.0762)
		(layer "F.Cu")
		(net "M_A_CPU0_SA_DQ<31>")
	)
	(arc
		(start 326.526652 -244.422676)
		(mid 326.343144 -244.377182)
		(end 326.160892 -244.427502)
		(width 0.0762)
		(layer "F.Cu")
		(net "M_A_CPU0_SA_DQ<31>")
	)
	(arc
		(start 327.100946 -244.427502)
		(mid 326.81799 -244.503679)
		(end 326.535034 -244.427502)
		(width 0.0762)
		(layer "F.Cu")
		(net "M_A_CPU0_SA_DQ<31>")
	)
	(arc
		(start 327.393046 -244.56898)
		(mid 327.384109 -244.449956)
		(end 327.289414 -244.37721)
		(width 0.0762)
		(layer "F.Cu")
		(net "M_A_CPU0_SA_DQ<31>")
	)
	(arc
		(start 326.160892 -244.427502)
		(mid 325.877936 -244.503679)
		(end 325.59498 -244.427502)
		(width 0.0762)
		(layer "F.Cu")
		(net "M_A_CPU0_SA_DQ<31>")
	)
	(arc
		(start 327.289414 -244.37721)
		(mid 327.19649 -244.388533)
		(end 327.109328 -244.422676)
		(width 0.0762)
		(layer "F.Cu")
		(net "M_A_CPU0_SA_DQ<31>")
	)
	(arc
		(start 325.59498 -244.427502)
		(mid 325.495907 -244.386188)
		(end 325.389494 -244.37213)
		(width 0.0762)
		(layer "F.Cu")
		(net "M_A_CPU0_SA_DQ<31>")
	)
	(segment
		(start 310.72963 -236.037628)
		(end 310.598312 -235.90631)
		(width 0.10668)
		(layer "F.Cu")
		(net "M_A_CPU0_SA_DQ<30>")
	)
	(segment
		(start 311.1627 -236.470698)
		(end 311.1627 -236.319822)
		(width 0.10668)
		(layer "F.Cu")
		(net "M_A_CPU0_SA_DQ<30>")
	)
	(segment
		(start 303.73828 -232.184956)
		(end 303.268126 -232.184956)
		(width 0.101346)
		(layer "F.Cu")
		(net "M_A_CPU0_SA_DQ<30>")
	)
	(segment
		(start 323.923914 -243.79047)
		(end 318.482472 -243.79047)
		(width 0.10668)
		(layer "F.Cu")
		(net "M_A_CPU0_SA_DQ<30>")
	)
	(segment
		(start 311.844944 -236.615478)
		(end 311.713626 -236.48416)
		(width 0.10668)
		(layer "F.Cu")
		(net "M_A_CPU0_SA_DQ<30>")
	)
	(segment
		(start 311.844944 -236.766354)
		(end 311.844944 -236.615478)
		(width 0.10668)
		(layer "F.Cu")
		(net "M_A_CPU0_SA_DQ<30>")
	)
	(segment
		(start 311.713626 -236.48416)
		(end 311.56275 -236.48416)
		(width 0.10668)
		(layer "F.Cu")
		(net "M_A_CPU0_SA_DQ<30>")
	)
	(segment
		(start 323.926454 -243.79301)
		(end 323.923914 -243.79047)
		(width 0.0762)
		(layer "F.Cu")
		(net "M_A_CPU0_SA_DQ<30>")
	)
	(segment
		(start 310.58485 -235.355384)
		(end 310.433974 -235.355384)
		(width 0.10668)
		(layer "F.Cu")
		(net "M_A_CPU0_SA_DQ<30>")
	)
	(segment
		(start 310.880506 -236.037628)
		(end 310.72963 -236.037628)
		(width 0.10668)
		(layer "F.Cu")
		(net "M_A_CPU0_SA_DQ<30>")
	)
	(segment
		(start 325.699374 -243.61267)
		(end 325.690992 -243.617496)
		(width 0.0762)
		(layer "F.Cu")
		(net "M_A_CPU0_SA_DQ<30>")
	)
	(segment
		(start 308.776116 -232.610152)
		(end 308.610508 -232.610152)
		(width 0.10668)
		(layer "F.Cu")
		(net "M_A_CPU0_SA_DQ<30>")
	)
	(segment
		(start 311.280556 -236.201966)
		(end 311.280556 -236.05109)
		(width 0.10668)
		(layer "F.Cu")
		(net "M_A_CPU0_SA_DQ<30>")
	)
	(segment
		(start 325.048626 -243.79301)
		(end 323.926454 -243.79301)
		(width 0.0762)
		(layer "F.Cu")
		(net "M_A_CPU0_SA_DQ<30>")
	)
	(segment
		(start 306.070508 -232.610152)
		(end 306.06873 -232.61193)
		(width 0.101346)
		(layer "F.Cu")
		(net "M_A_CPU0_SA_DQ<30>")
	)
	(segment
		(start 311.1627 -236.319822)
		(end 311.280556 -236.201966)
		(width 0.10668)
		(layer "F.Cu")
		(net "M_A_CPU0_SA_DQ<30>")
	)
	(segment
		(start 309.990998 -235.298996)
		(end 309.990998 -234.755182)
		(width 0.10668)
		(layer "F.Cu")
		(net "M_A_CPU0_SA_DQ<30>")
	)
	(segment
		(start 310.998362 -235.919772)
		(end 310.880506 -236.037628)
		(width 0.10668)
		(layer "F.Cu")
		(net "M_A_CPU0_SA_DQ<30>")
	)
	(segment
		(start 306.06873 -232.61193)
		(end 304.165254 -232.61193)
		(width 0.101346)
		(layer "F.Cu")
		(net "M_A_CPU0_SA_DQ<30>")
	)
	(segment
		(start 310.716168 -235.637578)
		(end 310.716168 -235.486702)
		(width 0.10668)
		(layer "F.Cu")
		(net "M_A_CPU0_SA_DQ<30>")
	)
	(segment
		(start 310.598312 -235.755434)
		(end 310.716168 -235.637578)
		(width 0.10668)
		(layer "F.Cu")
		(net "M_A_CPU0_SA_DQ<30>")
	)
	(segment
		(start 304.165254 -232.61193)
		(end 303.73828 -232.184956)
		(width 0.101346)
		(layer "F.Cu")
		(net "M_A_CPU0_SA_DQ<30>")
	)
	(segment
		(start 309.217314 -233.05135)
		(end 308.776116 -232.610152)
		(width 0.10668)
		(layer "F.Cu")
		(net "M_A_CPU0_SA_DQ<30>")
	)
	(segment
		(start 311.727088 -237.035086)
		(end 311.727088 -236.88421)
		(width 0.10668)
		(layer "F.Cu")
		(net "M_A_CPU0_SA_DQ<30>")
	)
	(segment
		(start 311.56275 -236.48416)
		(end 311.444894 -236.602016)
		(width 0.10668)
		(layer "F.Cu")
		(net "M_A_CPU0_SA_DQ<30>")
	)
	(segment
		(start 310.716168 -235.486702)
		(end 310.58485 -235.355384)
		(width 0.10668)
		(layer "F.Cu")
		(net "M_A_CPU0_SA_DQ<30>")
	)
	(segment
		(start 311.149238 -235.919772)
		(end 310.998362 -235.919772)
		(width 0.10668)
		(layer "F.Cu")
		(net "M_A_CPU0_SA_DQ<30>")
	)
	(segment
		(start 309.990998 -234.755182)
		(end 309.217314 -233.981498)
		(width 0.10668)
		(layer "F.Cu")
		(net "M_A_CPU0_SA_DQ<30>")
	)
	(segment
		(start 311.294018 -236.602016)
		(end 311.1627 -236.470698)
		(width 0.10668)
		(layer "F.Cu")
		(net "M_A_CPU0_SA_DQ<30>")
	)
	(segment
		(start 308.610508 -232.610152)
		(end 306.070508 -232.610152)
		(width 0.101346)
		(layer "F.Cu")
		(net "M_A_CPU0_SA_DQ<30>")
	)
	(segment
		(start 318.482472 -243.79047)
		(end 311.727088 -237.035086)
		(width 0.10668)
		(layer "F.Cu")
		(net "M_A_CPU0_SA_DQ<30>")
	)
	(segment
		(start 310.165242 -235.47324)
		(end 309.990998 -235.298996)
		(width 0.10668)
		(layer "F.Cu")
		(net "M_A_CPU0_SA_DQ<30>")
	)
	(segment
		(start 310.433974 -235.355384)
		(end 310.316118 -235.47324)
		(width 0.10668)
		(layer "F.Cu")
		(net "M_A_CPU0_SA_DQ<30>")
	)
	(segment
		(start 310.316118 -235.47324)
		(end 310.165242 -235.47324)
		(width 0.10668)
		(layer "F.Cu")
		(net "M_A_CPU0_SA_DQ<30>")
	)
	(segment
		(start 309.217314 -233.981498)
		(end 309.217314 -233.05135)
		(width 0.10668)
		(layer "F.Cu")
		(net "M_A_CPU0_SA_DQ<30>")
	)
	(segment
		(start 311.280556 -236.05109)
		(end 311.149238 -235.919772)
		(width 0.10668)
		(layer "F.Cu")
		(net "M_A_CPU0_SA_DQ<30>")
	)
	(segment
		(start 311.727088 -236.88421)
		(end 311.844944 -236.766354)
		(width 0.10668)
		(layer "F.Cu")
		(net "M_A_CPU0_SA_DQ<30>")
	)
	(segment
		(start 311.444894 -236.602016)
		(end 311.294018 -236.602016)
		(width 0.10668)
		(layer "F.Cu")
		(net "M_A_CPU0_SA_DQ<30>")
	)
	(segment
		(start 325.877936 -243.940076)
		(end 325.9709 -243.780056)
		(width 0.0762)
		(layer "F.Cu")
		(net "M_A_CPU0_SA_DQ<30>")
	)
	(segment
		(start 310.598312 -235.90631)
		(end 310.598312 -235.755434)
		(width 0.10668)
		(layer "F.Cu")
		(net "M_A_CPU0_SA_DQ<30>")
	)
	(arc
		(start 325.690992 -243.617496)
		(mid 325.650394 -243.638872)
		(end 325.608188 -243.656866)
		(width 0.0762)
		(layer "F.Cu")
		(net "M_A_CPU0_SA_DQ<30>")
	)
	(arc
		(start 325.608188 -243.656866)
		(mid 325.369832 -243.734248)
		(end 325.124826 -243.786914)
		(width 0.0762)
		(layer "F.Cu")
		(net "M_A_CPU0_SA_DQ<30>")
	)
	(arc
		(start 325.839074 -243.569236)
		(mid 325.767066 -243.584018)
		(end 325.699374 -243.61267)
		(width 0.0762)
		(layer "F.Cu")
		(net "M_A_CPU0_SA_DQ<30>")
	)
	(arc
		(start 325.9709 -243.780056)
		(mid 325.97074 -243.633495)
		(end 325.839074 -243.569236)
		(width 0.0762)
		(layer "F.Cu")
		(net "M_A_CPU0_SA_DQ<30>")
	)
	(arc
		(start 325.124826 -243.786914)
		(mid 325.086849 -243.7915)
		(end 325.048626 -243.79301)
		(width 0.0762)
		(layer "F.Cu")
		(net "M_A_CPU0_SA_DQ<30>")
	)
	(segment
		(start 312.287412 -202.419458)
		(end 312.287412 -201.93508)
		(width 0.10668)
		(layer "F.Cu")
		(net "M_A_CPU0_SA_DQ<2>")
	)
	(segment
		(start 306.070508 -198.61022)
		(end 305.645312 -198.185024)
		(width 0.101346)
		(layer "F.Cu")
		(net "M_A_CPU0_SA_DQ<2>")
	)
	(segment
		(start 324.214998 -224.830386)
		(end 324.214998 -214.347044)
		(width 0.10668)
		(layer "F.Cu")
		(net "M_A_CPU0_SA_DQ<2>")
	)
	(segment
		(start 324.214998 -214.347044)
		(end 312.287412 -202.419458)
		(width 0.10668)
		(layer "F.Cu")
		(net "M_A_CPU0_SA_DQ<2>")
	)
	(segment
		(start 325.100442 -225.71583)
		(end 324.214998 -224.830386)
		(width 0.0762)
		(layer "F.Cu")
		(net "M_A_CPU0_SA_DQ<2>")
	)
	(segment
		(start 305.645312 -198.185024)
		(end 303.268126 -198.185024)
		(width 0.101346)
		(layer "F.Cu")
		(net "M_A_CPU0_SA_DQ<2>")
	)
	(segment
		(start 312.287412 -201.93508)
		(end 308.962552 -198.61022)
		(width 0.10668)
		(layer "F.Cu")
		(net "M_A_CPU0_SA_DQ<2>")
	)
	(segment
		(start 325.473568 -225.71583)
		(end 325.100442 -225.71583)
		(width 0.0762)
		(layer "F.Cu")
		(net "M_A_CPU0_SA_DQ<2>")
	)
	(segment
		(start 308.962552 -198.61022)
		(end 306.070508 -198.61022)
		(width 0.101346)
		(layer "F.Cu")
		(net "M_A_CPU0_SA_DQ<2>")
	)
	(arc
		(start 325.877936 -226.120198)
		(mid 325.759499 -225.834267)
		(end 325.473568 -225.71583)
		(width 0.0762)
		(layer "F.Cu")
		(net "M_A_CPU0_SA_DQ<2>")
	)
	(segment
		(start 312.745628 -238.68634)
		(end 312.549032 -238.882936)
		(width 0.10668)
		(layer "F.Cu")
		(net "M_A_CPU0_SA_DQ<29>")
	)
	(segment
		(start 310.77027 -236.560106)
		(end 310.638952 -236.428788)
		(width 0.10668)
		(layer "F.Cu")
		(net "M_A_CPU0_SA_DQ<29>")
	)
	(segment
		(start 313.027822 -238.817658)
		(end 312.896504 -238.68634)
		(width 0.10668)
		(layer "F.Cu")
		(net "M_A_CPU0_SA_DQ<29>")
	)
	(segment
		(start 310.00954 -236.494066)
		(end 310.00954 -236.34319)
		(width 0.10668)
		(layer "F.Cu")
		(net "M_A_CPU0_SA_DQ<29>")
	)
	(segment
		(start 311.616852 -237.557564)
		(end 311.420256 -237.75416)
		(width 0.10668)
		(layer "F.Cu")
		(net "M_A_CPU0_SA_DQ<29>")
	)
	(segment
		(start 312.896504 -238.68634)
		(end 312.745628 -238.68634)
		(width 0.10668)
		(layer "F.Cu")
		(net "M_A_CPU0_SA_DQ<29>")
	)
	(segment
		(start 309.225188 -234.705906)
		(end 309.14594 -234.785154)
		(width 0.10668)
		(layer "F.Cu")
		(net "M_A_CPU0_SA_DQ<29>")
	)
	(segment
		(start 312.463434 -238.25327)
		(end 312.332116 -238.121952)
		(width 0.10668)
		(layer "F.Cu")
		(net "M_A_CPU0_SA_DQ<29>")
	)
	(segment
		(start 311.984644 -238.318548)
		(end 311.834276 -238.318802)
		(width 0.10668)
		(layer "F.Cu")
		(net "M_A_CPU0_SA_DQ<29>")
	)
	(segment
		(start 311.138316 -237.471966)
		(end 311.334912 -237.27537)
		(width 0.10668)
		(layer "F.Cu")
		(net "M_A_CPU0_SA_DQ<29>")
	)
	(segment
		(start 311.899046 -237.688882)
		(end 311.767728 -237.557564)
		(width 0.10668)
		(layer "F.Cu")
		(net "M_A_CPU0_SA_DQ<29>")
	)
	(segment
		(start 312.932064 -239.064546)
		(end 313.028076 -238.968534)
		(width 0.10668)
		(layer "F.Cu")
		(net "M_A_CPU0_SA_DQ<29>")
	)
	(segment
		(start 311.8993 -237.839758)
		(end 311.899046 -237.688882)
		(width 0.10668)
		(layer "F.Cu")
		(net "M_A_CPU0_SA_DQ<29>")
	)
	(segment
		(start 311.834276 -238.318802)
		(end 311.702704 -238.18723)
		(width 0.10668)
		(layer "F.Cu")
		(net "M_A_CPU0_SA_DQ<29>")
	)
	(segment
		(start 325.699374 -244.267482)
		(end 325.690992 -244.262656)
		(width 0.0762)
		(layer "F.Cu")
		(net "M_A_CPU0_SA_DQ<29>")
	)
	(segment
		(start 310.488076 -236.428788)
		(end 310.29148 -236.625384)
		(width 0.10668)
		(layer "F.Cu")
		(net "M_A_CPU0_SA_DQ<29>")
	)
	(segment
		(start 311.334912 -237.27537)
		(end 311.334658 -237.124494)
		(width 0.10668)
		(layer "F.Cu")
		(net "M_A_CPU0_SA_DQ<29>")
	)
	(segment
		(start 310.206136 -236.146594)
		(end 310.205882 -235.995718)
		(width 0.10668)
		(layer "F.Cu")
		(net "M_A_CPU0_SA_DQ<29>")
	)
	(segment
		(start 311.702704 -238.18723)
		(end 311.702704 -238.036354)
		(width 0.10668)
		(layer "F.Cu")
		(net "M_A_CPU0_SA_DQ<29>")
	)
	(segment
		(start 311.052464 -236.993176)
		(end 310.855868 -237.189772)
		(width 0.10668)
		(layer "F.Cu")
		(net "M_A_CPU0_SA_DQ<29>")
	)
	(segment
		(start 313.028076 -238.968534)
		(end 313.027822 -238.817658)
		(width 0.10668)
		(layer "F.Cu")
		(net "M_A_CPU0_SA_DQ<29>")
	)
	(segment
		(start 313.214004 -239.34674)
		(end 313.063636 -239.346994)
		(width 0.10668)
		(layer "F.Cu")
		(net "M_A_CPU0_SA_DQ<29>")
	)
	(segment
		(start 311.138316 -237.622842)
		(end 311.138316 -237.471966)
		(width 0.10668)
		(layer "F.Cu")
		(net "M_A_CPU0_SA_DQ<29>")
	)
	(segment
		(start 323.911214 -244.13083)
		(end 318.340994 -244.13083)
		(width 0.10668)
		(layer "F.Cu")
		(net "M_A_CPU0_SA_DQ<29>")
	)
	(segment
		(start 327.004934 -244.262402)
		(end 327.004934 -244.262656)
		(width 0.0762)
		(layer "F.Cu")
		(net "M_A_CPU0_SA_DQ<29>")
	)
	(segment
		(start 311.767728 -237.557564)
		(end 311.616852 -237.557564)
		(width 0.10668)
		(layer "F.Cu")
		(net "M_A_CPU0_SA_DQ<29>")
	)
	(segment
		(start 310.638952 -236.428788)
		(end 310.488076 -236.428788)
		(width 0.10668)
		(layer "F.Cu")
		(net "M_A_CPU0_SA_DQ<29>")
	)
	(segment
		(start 310.141112 -236.625638)
		(end 310.00954 -236.494066)
		(width 0.10668)
		(layer "F.Cu")
		(net "M_A_CPU0_SA_DQ<29>")
	)
	(segment
		(start 310.205882 -235.995718)
		(end 309.428134 -235.21797)
		(width 0.10668)
		(layer "F.Cu")
		(net "M_A_CPU0_SA_DQ<29>")
	)
	(segment
		(start 311.20334 -236.993176)
		(end 311.052464 -236.993176)
		(width 0.10668)
		(layer "F.Cu")
		(net "M_A_CPU0_SA_DQ<29>")
	)
	(segment
		(start 311.269888 -237.754414)
		(end 311.138316 -237.622842)
		(width 0.10668)
		(layer "F.Cu")
		(net "M_A_CPU0_SA_DQ<29>")
	)
	(segment
		(start 310.00954 -236.34319)
		(end 310.206136 -236.146594)
		(width 0.10668)
		(layer "F.Cu")
		(net "M_A_CPU0_SA_DQ<29>")
	)
	(segment
		(start 312.267092 -238.751618)
		(end 312.267092 -238.600742)
		(width 0.10668)
		(layer "F.Cu")
		(net "M_A_CPU0_SA_DQ<29>")
	)
	(segment
		(start 308.995064 -234.7849)
		(end 308.876954 -234.66679)
		(width 0.10668)
		(layer "F.Cu")
		(net "M_A_CPU0_SA_DQ<29>")
	)
	(segment
		(start 312.18124 -238.121952)
		(end 311.984644 -238.318548)
		(width 0.10668)
		(layer "F.Cu")
		(net "M_A_CPU0_SA_DQ<29>")
	)
	(segment
		(start 310.7055 -237.190026)
		(end 310.573928 -237.058454)
		(width 0.10668)
		(layer "F.Cu")
		(net "M_A_CPU0_SA_DQ<29>")
	)
	(segment
		(start 309.14594 -234.785154)
		(end 308.995064 -234.7849)
		(width 0.10668)
		(layer "F.Cu")
		(net "M_A_CPU0_SA_DQ<29>")
	)
	(segment
		(start 309.507636 -234.837478)
		(end 309.376064 -234.705906)
		(width 0.10668)
		(layer "F.Cu")
		(net "M_A_CPU0_SA_DQ<29>")
	)
	(segment
		(start 308.71922 -233.035094)
		(end 307.368194 -233.035094)
		(width 0.10668)
		(layer "F.Cu")
		(net "M_A_CPU0_SA_DQ<29>")
	)
	(segment
		(start 311.420256 -237.75416)
		(end 311.269888 -237.754414)
		(width 0.10668)
		(layer "F.Cu")
		(net "M_A_CPU0_SA_DQ<29>")
	)
	(segment
		(start 312.463688 -238.404146)
		(end 312.463434 -238.25327)
		(width 0.10668)
		(layer "F.Cu")
		(net "M_A_CPU0_SA_DQ<29>")
	)
	(segment
		(start 324.332854 -244.13083)
		(end 323.911214 -244.13083)
		(width 0.0762)
		(layer "F.Cu")
		(net "M_A_CPU0_SA_DQ<29>")
	)
	(segment
		(start 324.363334 -244.10035)
		(end 324.332854 -244.13083)
		(width 0.0762)
		(layer "F.Cu")
		(net "M_A_CPU0_SA_DQ<29>")
	)
	(segment
		(start 310.770524 -236.710982)
		(end 310.77027 -236.560106)
		(width 0.10668)
		(layer "F.Cu")
		(net "M_A_CPU0_SA_DQ<29>")
	)
	(segment
		(start 312.267092 -238.600742)
		(end 312.463688 -238.404146)
		(width 0.10668)
		(layer "F.Cu")
		(net "M_A_CPU0_SA_DQ<29>")
	)
	(segment
		(start 311.702704 -238.036354)
		(end 311.8993 -237.839758)
		(width 0.10668)
		(layer "F.Cu")
		(net "M_A_CPU0_SA_DQ<29>")
	)
	(segment
		(start 308.876954 -233.192828)
		(end 308.71922 -233.035094)
		(width 0.10668)
		(layer "F.Cu")
		(net "M_A_CPU0_SA_DQ<29>")
	)
	(segment
		(start 312.549032 -238.882936)
		(end 312.398664 -238.88319)
		(width 0.10668)
		(layer "F.Cu")
		(net "M_A_CPU0_SA_DQ<29>")
	)
	(segment
		(start 309.428134 -235.067094)
		(end 309.507382 -234.987846)
		(width 0.10668)
		(layer "F.Cu")
		(net "M_A_CPU0_SA_DQ<29>")
	)
	(segment
		(start 312.932064 -239.215422)
		(end 312.932064 -239.064546)
		(width 0.10668)
		(layer "F.Cu")
		(net "M_A_CPU0_SA_DQ<29>")
	)
	(segment
		(start 310.573928 -237.058454)
		(end 310.573928 -236.907578)
		(width 0.10668)
		(layer "F.Cu")
		(net "M_A_CPU0_SA_DQ<29>")
	)
	(segment
		(start 313.310016 -239.250728)
		(end 313.214004 -239.34674)
		(width 0.10668)
		(layer "F.Cu")
		(net "M_A_CPU0_SA_DQ<29>")
	)
	(segment
		(start 310.855868 -237.189772)
		(end 310.7055 -237.190026)
		(width 0.10668)
		(layer "F.Cu")
		(net "M_A_CPU0_SA_DQ<29>")
	)
	(segment
		(start 310.573928 -236.907578)
		(end 310.770524 -236.710982)
		(width 0.10668)
		(layer "F.Cu")
		(net "M_A_CPU0_SA_DQ<29>")
	)
	(segment
		(start 311.334658 -237.124494)
		(end 311.20334 -236.993176)
		(width 0.10668)
		(layer "F.Cu")
		(net "M_A_CPU0_SA_DQ<29>")
	)
	(segment
		(start 309.428134 -235.21797)
		(end 309.428134 -235.067094)
		(width 0.10668)
		(layer "F.Cu")
		(net "M_A_CPU0_SA_DQ<29>")
	)
	(segment
		(start 325.08825 -244.10035)
		(end 324.363334 -244.10035)
		(width 0.0762)
		(layer "F.Cu")
		(net "M_A_CPU0_SA_DQ<29>")
	)
	(segment
		(start 312.398664 -238.88319)
		(end 312.267092 -238.751618)
		(width 0.10668)
		(layer "F.Cu")
		(net "M_A_CPU0_SA_DQ<29>")
	)
	(segment
		(start 313.063636 -239.346994)
		(end 312.932064 -239.215422)
		(width 0.10668)
		(layer "F.Cu")
		(net "M_A_CPU0_SA_DQ<29>")
	)
	(segment
		(start 312.332116 -238.121952)
		(end 312.18124 -238.121952)
		(width 0.10668)
		(layer "F.Cu")
		(net "M_A_CPU0_SA_DQ<29>")
	)
	(segment
		(start 313.460892 -239.250728)
		(end 313.310016 -239.250728)
		(width 0.10668)
		(layer "F.Cu")
		(net "M_A_CPU0_SA_DQ<29>")
	)
	(segment
		(start 309.507382 -234.987846)
		(end 309.507636 -234.837478)
		(width 0.10668)
		(layer "F.Cu")
		(net "M_A_CPU0_SA_DQ<29>")
	)
	(segment
		(start 318.340994 -244.13083)
		(end 313.460892 -239.250728)
		(width 0.10668)
		(layer "F.Cu")
		(net "M_A_CPU0_SA_DQ<29>")
	)
	(segment
		(start 310.29148 -236.625384)
		(end 310.141112 -236.625638)
		(width 0.10668)
		(layer "F.Cu")
		(net "M_A_CPU0_SA_DQ<29>")
	)
	(segment
		(start 309.376064 -234.705906)
		(end 309.225188 -234.705906)
		(width 0.10668)
		(layer "F.Cu")
		(net "M_A_CPU0_SA_DQ<29>")
	)
	(segment
		(start 308.876954 -234.66679)
		(end 308.876954 -233.192828)
		(width 0.10668)
		(layer "F.Cu")
		(net "M_A_CPU0_SA_DQ<29>")
	)
	(arc
		(start 327.289414 -244.185948)
		(mid 327.142093 -244.205267)
		(end 327.004934 -244.262402)
		(width 0.0762)
		(layer "F.Cu")
		(net "M_A_CPU0_SA_DQ<29>")
	)
	(arc
		(start 327.758044 -243.940076)
		(mid 327.554028 -244.12077)
		(end 327.289414 -244.185948)
		(width 0.0762)
		(layer "F.Cu")
		(net "M_A_CPU0_SA_DQ<29>")
	)
	(arc
		(start 327.004934 -244.262656)
		(mid 326.81799 -244.312911)
		(end 326.631046 -244.262656)
		(width 0.0762)
		(layer "F.Cu")
		(net "M_A_CPU0_SA_DQ<29>")
	)
	(arc
		(start 325.690992 -244.262656)
		(mid 325.400359 -244.141619)
		(end 325.08825 -244.10035)
		(width 0.0762)
		(layer "F.Cu")
		(net "M_A_CPU0_SA_DQ<29>")
	)
	(arc
		(start 326.631046 -244.262656)
		(mid 326.34809 -244.186479)
		(end 326.065134 -244.262656)
		(width 0.0762)
		(layer "F.Cu")
		(net "M_A_CPU0_SA_DQ<29>")
	)
	(arc
		(start 326.065134 -244.262656)
		(mid 325.882883 -244.313006)
		(end 325.699374 -244.267482)
		(width 0.0762)
		(layer "F.Cu")
		(net "M_A_CPU0_SA_DQ<29>")
	)
	(segment
		(start 324.155054 -243.50599)
		(end 324.099174 -243.45011)
		(width 0.0762)
		(layer "F.Cu")
		(net "M_A_CPU0_SA_DQ<28>")
	)
	(segment
		(start 318.156844 -242.98021)
		(end 318.157098 -242.829842)
		(width 0.10668)
		(layer "F.Cu")
		(net "M_A_CPU0_SA_DQ<28>")
	)
	(segment
		(start 315.454792 -239.888268)
		(end 315.454792 -239.737392)
		(width 0.10668)
		(layer "F.Cu")
		(net "M_A_CPU0_SA_DQ<28>")
	)
	(segment
		(start 315.172598 -239.60582)
		(end 315.052964 -239.725454)
		(width 0.10668)
		(layer "F.Cu")
		(net "M_A_CPU0_SA_DQ<28>")
	)
	(segment
		(start 315.899292 -240.722658)
		(end 315.899546 -240.57229)
		(width 0.10668)
		(layer "F.Cu")
		(net "M_A_CPU0_SA_DQ<28>")
	)
	(segment
		(start 313.077352 -237.900718)
		(end 313.077606 -237.75035)
		(width 0.10668)
		(layer "F.Cu")
		(net "M_A_CPU0_SA_DQ<28>")
	)
	(segment
		(start 313.63031 -237.91291)
		(end 313.479434 -237.912656)
		(width 0.10668)
		(layer "F.Cu")
		(net "M_A_CPU0_SA_DQ<28>")
	)
	(segment
		(start 315.887862 -240.170462)
		(end 315.736986 -240.170208)
		(width 0.10668)
		(layer "F.Cu")
		(net "M_A_CPU0_SA_DQ<28>")
	)
	(segment
		(start 318.276732 -242.559332)
		(end 318.145414 -242.428014)
		(width 0.10668)
		(layer "F.Cu")
		(net "M_A_CPU0_SA_DQ<28>")
	)
	(segment
		(start 318.709802 -242.992402)
		(end 318.558926 -242.992148)
		(width 0.10668)
		(layer "F.Cu")
		(net "M_A_CPU0_SA_DQ<28>")
	)
	(segment
		(start 307.991256 -231.335072)
		(end 307.368194 -231.335072)
		(width 0.10668)
		(layer "F.Cu")
		(net "M_A_CPU0_SA_DQ<28>")
	)
	(segment
		(start 315.334904 -240.15827)
		(end 315.335158 -240.007902)
		(width 0.10668)
		(layer "F.Cu")
		(net "M_A_CPU0_SA_DQ<28>")
	)
	(segment
		(start 316.18174 -240.85423)
		(end 316.030864 -240.85423)
		(width 0.10668)
		(layer "F.Cu")
		(net "M_A_CPU0_SA_DQ<28>")
	)
	(segment
		(start 316.45225 -240.73485)
		(end 316.301374 -240.734596)
		(width 0.10668)
		(layer "F.Cu")
		(net "M_A_CPU0_SA_DQ<28>")
	)
	(segment
		(start 314.759086 -239.041686)
		(end 314.60821 -239.041432)
		(width 0.10668)
		(layer "F.Cu")
		(net "M_A_CPU0_SA_DQ<28>")
	)
	(segment
		(start 313.773312 -238.596678)
		(end 313.64174 -238.465106)
		(width 0.10668)
		(layer "F.Cu")
		(net "M_A_CPU0_SA_DQ<28>")
	)
	(segment
		(start 314.488576 -239.161066)
		(end 314.3377 -239.161066)
		(width 0.10668)
		(layer "F.Cu")
		(net "M_A_CPU0_SA_DQ<28>")
	)
	(segment
		(start 314.77077 -239.443514)
		(end 314.890404 -239.32388)
		(width 0.10668)
		(layer "F.Cu")
		(net "M_A_CPU0_SA_DQ<28>")
	)
	(segment
		(start 316.595252 -241.418618)
		(end 316.46368 -241.287046)
		(width 0.10668)
		(layer "F.Cu")
		(net "M_A_CPU0_SA_DQ<28>")
	)
	(segment
		(start 312.632852 -237.066328)
		(end 312.632852 -236.915452)
		(width 0.10668)
		(layer "F.Cu")
		(net "M_A_CPU0_SA_DQ<28>")
	)
	(segment
		(start 316.01918 -240.30178)
		(end 315.887862 -240.170462)
		(width 0.10668)
		(layer "F.Cu")
		(net "M_A_CPU0_SA_DQ<28>")
	)
	(segment
		(start 313.19724 -237.630716)
		(end 313.19724 -237.47984)
		(width 0.10668)
		(layer "F.Cu")
		(net "M_A_CPU0_SA_DQ<28>")
	)
	(segment
		(start 314.3377 -239.161066)
		(end 314.206128 -239.029494)
		(width 0.10668)
		(layer "F.Cu")
		(net "M_A_CPU0_SA_DQ<28>")
	)
	(segment
		(start 312.644536 -237.467902)
		(end 312.512964 -237.33633)
		(width 0.10668)
		(layer "F.Cu")
		(net "M_A_CPU0_SA_DQ<28>")
	)
	(segment
		(start 314.206382 -238.879126)
		(end 314.326016 -238.759492)
		(width 0.10668)
		(layer "F.Cu")
		(net "M_A_CPU0_SA_DQ<28>")
	)
	(segment
		(start 313.077606 -237.75035)
		(end 313.19724 -237.630716)
		(width 0.10668)
		(layer "F.Cu")
		(net "M_A_CPU0_SA_DQ<28>")
	)
	(segment
		(start 315.052964 -239.725454)
		(end 314.902088 -239.725454)
		(width 0.10668)
		(layer "F.Cu")
		(net "M_A_CPU0_SA_DQ<28>")
	)
	(segment
		(start 316.463934 -241.136678)
		(end 316.583568 -241.017044)
		(width 0.10668)
		(layer "F.Cu")
		(net "M_A_CPU0_SA_DQ<28>")
	)
	(segment
		(start 317.147956 -241.581432)
		(end 317.147956 -241.430556)
		(width 0.10668)
		(layer "F.Cu")
		(net "M_A_CPU0_SA_DQ<28>")
	)
	(segment
		(start 316.746128 -241.418618)
		(end 316.595252 -241.418618)
		(width 0.10668)
		(layer "F.Cu")
		(net "M_A_CPU0_SA_DQ<28>")
	)
	(segment
		(start 317.310516 -241.983006)
		(end 317.15964 -241.983006)
		(width 0.10668)
		(layer "F.Cu")
		(net "M_A_CPU0_SA_DQ<28>")
	)
	(segment
		(start 314.326016 -238.608616)
		(end 314.194698 -238.477298)
		(width 0.10668)
		(layer "F.Cu")
		(net "M_A_CPU0_SA_DQ<28>")
	)
	(segment
		(start 314.890404 -239.32388)
		(end 314.890404 -239.173004)
		(width 0.10668)
		(layer "F.Cu")
		(net "M_A_CPU0_SA_DQ<28>")
	)
	(segment
		(start 315.454792 -239.737392)
		(end 315.323474 -239.606074)
		(width 0.10668)
		(layer "F.Cu")
		(net "M_A_CPU0_SA_DQ<28>")
	)
	(segment
		(start 316.583568 -240.866168)
		(end 316.45225 -240.73485)
		(width 0.10668)
		(layer "F.Cu")
		(net "M_A_CPU0_SA_DQ<28>")
	)
	(segment
		(start 319.16751 -243.45011)
		(end 318.709802 -242.992402)
		(width 0.10668)
		(layer "F.Cu")
		(net "M_A_CPU0_SA_DQ<28>")
	)
	(segment
		(start 313.479434 -237.912656)
		(end 313.3598 -238.03229)
		(width 0.10668)
		(layer "F.Cu")
		(net "M_A_CPU0_SA_DQ<28>")
	)
	(segment
		(start 318.558926 -242.992148)
		(end 318.439292 -243.111782)
		(width 0.10668)
		(layer "F.Cu")
		(net "M_A_CPU0_SA_DQ<28>")
	)
	(segment
		(start 317.712344 -242.14582)
		(end 317.712344 -241.994944)
		(width 0.10668)
		(layer "F.Cu")
		(net "M_A_CPU0_SA_DQ<28>")
	)
	(segment
		(start 313.065922 -237.348522)
		(end 312.915046 -237.348268)
		(width 0.10668)
		(layer "F.Cu")
		(net "M_A_CPU0_SA_DQ<28>")
	)
	(segment
		(start 309.557674 -232.90149)
		(end 307.991256 -231.335072)
		(width 0.10668)
		(layer "F.Cu")
		(net "M_A_CPU0_SA_DQ<28>")
	)
	(segment
		(start 316.301374 -240.734596)
		(end 316.18174 -240.85423)
		(width 0.10668)
		(layer "F.Cu")
		(net "M_A_CPU0_SA_DQ<28>")
	)
	(segment
		(start 314.206128 -239.029494)
		(end 314.206382 -238.879126)
		(width 0.10668)
		(layer "F.Cu")
		(net "M_A_CPU0_SA_DQ<28>")
	)
	(segment
		(start 312.512964 -237.33633)
		(end 312.513218 -237.185962)
		(width 0.10668)
		(layer "F.Cu")
		(net "M_A_CPU0_SA_DQ<28>")
	)
	(segment
		(start 309.557674 -233.840274)
		(end 309.557674 -232.90149)
		(width 0.10668)
		(layer "F.Cu")
		(net "M_A_CPU0_SA_DQ<28>")
	)
	(segment
		(start 314.890404 -239.173004)
		(end 314.759086 -239.041686)
		(width 0.10668)
		(layer "F.Cu")
		(net "M_A_CPU0_SA_DQ<28>")
	)
	(segment
		(start 317.147956 -241.430556)
		(end 317.016638 -241.299238)
		(width 0.10668)
		(layer "F.Cu")
		(net "M_A_CPU0_SA_DQ<28>")
	)
	(segment
		(start 317.592456 -242.415822)
		(end 317.59271 -242.265454)
		(width 0.10668)
		(layer "F.Cu")
		(net "M_A_CPU0_SA_DQ<28>")
	)
	(segment
		(start 318.439292 -243.111782)
		(end 318.288416 -243.111782)
		(width 0.10668)
		(layer "F.Cu")
		(net "M_A_CPU0_SA_DQ<28>")
	)
	(segment
		(start 317.43015 -241.863372)
		(end 317.310516 -241.983006)
		(width 0.10668)
		(layer "F.Cu")
		(net "M_A_CPU0_SA_DQ<28>")
	)
	(segment
		(start 315.617352 -240.289842)
		(end 315.466476 -240.289842)
		(width 0.10668)
		(layer "F.Cu")
		(net "M_A_CPU0_SA_DQ<28>")
	)
	(segment
		(start 314.326016 -238.759492)
		(end 314.326016 -238.608616)
		(width 0.10668)
		(layer "F.Cu")
		(net "M_A_CPU0_SA_DQ<28>")
	)
	(segment
		(start 316.865762 -241.298984)
		(end 316.746128 -241.418618)
		(width 0.10668)
		(layer "F.Cu")
		(net "M_A_CPU0_SA_DQ<28>")
	)
	(segment
		(start 318.145414 -242.428014)
		(end 317.994538 -242.42776)
		(width 0.10668)
		(layer "F.Cu")
		(net "M_A_CPU0_SA_DQ<28>")
	)
	(segment
		(start 313.761628 -238.044228)
		(end 313.63031 -237.91291)
		(width 0.10668)
		(layer "F.Cu")
		(net "M_A_CPU0_SA_DQ<28>")
	)
	(segment
		(start 312.632852 -236.915452)
		(end 309.557674 -233.840274)
		(width 0.10668)
		(layer "F.Cu")
		(net "M_A_CPU0_SA_DQ<28>")
	)
	(segment
		(start 315.736986 -240.170208)
		(end 315.617352 -240.289842)
		(width 0.10668)
		(layer "F.Cu")
		(net "M_A_CPU0_SA_DQ<28>")
	)
	(segment
		(start 315.466476 -240.289842)
		(end 315.334904 -240.15827)
		(width 0.10668)
		(layer "F.Cu")
		(net "M_A_CPU0_SA_DQ<28>")
	)
	(segment
		(start 314.902088 -239.725454)
		(end 314.770516 -239.593882)
		(width 0.10668)
		(layer "F.Cu")
		(net "M_A_CPU0_SA_DQ<28>")
	)
	(segment
		(start 314.60821 -239.041432)
		(end 314.488576 -239.161066)
		(width 0.10668)
		(layer "F.Cu")
		(net "M_A_CPU0_SA_DQ<28>")
	)
	(segment
		(start 317.59271 -242.265454)
		(end 317.712344 -242.14582)
		(width 0.10668)
		(layer "F.Cu")
		(net "M_A_CPU0_SA_DQ<28>")
	)
	(segment
		(start 318.276732 -242.710208)
		(end 318.276732 -242.559332)
		(width 0.10668)
		(layer "F.Cu")
		(net "M_A_CPU0_SA_DQ<28>")
	)
	(segment
		(start 317.581026 -241.863626)
		(end 317.43015 -241.863372)
		(width 0.10668)
		(layer "F.Cu")
		(net "M_A_CPU0_SA_DQ<28>")
	)
	(segment
		(start 314.194698 -238.477298)
		(end 314.043822 -238.477044)
		(width 0.10668)
		(layer "F.Cu")
		(net "M_A_CPU0_SA_DQ<28>")
	)
	(segment
		(start 316.01918 -240.452656)
		(end 316.01918 -240.30178)
		(width 0.10668)
		(layer "F.Cu")
		(net "M_A_CPU0_SA_DQ<28>")
	)
	(segment
		(start 317.994538 -242.42776)
		(end 317.874904 -242.547394)
		(width 0.10668)
		(layer "F.Cu")
		(net "M_A_CPU0_SA_DQ<28>")
	)
	(segment
		(start 313.3598 -238.03229)
		(end 313.208924 -238.03229)
		(width 0.10668)
		(layer "F.Cu")
		(net "M_A_CPU0_SA_DQ<28>")
	)
	(segment
		(start 312.915046 -237.348268)
		(end 312.795412 -237.467902)
		(width 0.10668)
		(layer "F.Cu")
		(net "M_A_CPU0_SA_DQ<28>")
	)
	(segment
		(start 312.795412 -237.467902)
		(end 312.644536 -237.467902)
		(width 0.10668)
		(layer "F.Cu")
		(net "M_A_CPU0_SA_DQ<28>")
	)
	(segment
		(start 313.761628 -238.195104)
		(end 313.761628 -238.044228)
		(width 0.10668)
		(layer "F.Cu")
		(net "M_A_CPU0_SA_DQ<28>")
	)
	(segment
		(start 324.099174 -243.45011)
		(end 319.16751 -243.45011)
		(width 0.10668)
		(layer "F.Cu")
		(net "M_A_CPU0_SA_DQ<28>")
	)
	(segment
		(start 314.043822 -238.477044)
		(end 313.924188 -238.596678)
		(width 0.10668)
		(layer "F.Cu")
		(net "M_A_CPU0_SA_DQ<28>")
	)
	(segment
		(start 317.028322 -241.701066)
		(end 317.147956 -241.581432)
		(width 0.10668)
		(layer "F.Cu")
		(net "M_A_CPU0_SA_DQ<28>")
	)
	(segment
		(start 317.724028 -242.547394)
		(end 317.592456 -242.415822)
		(width 0.10668)
		(layer "F.Cu")
		(net "M_A_CPU0_SA_DQ<28>")
	)
	(segment
		(start 317.874904 -242.547394)
		(end 317.724028 -242.547394)
		(width 0.10668)
		(layer "F.Cu")
		(net "M_A_CPU0_SA_DQ<28>")
	)
	(segment
		(start 313.924188 -238.596678)
		(end 313.773312 -238.596678)
		(width 0.10668)
		(layer "F.Cu")
		(net "M_A_CPU0_SA_DQ<28>")
	)
	(segment
		(start 316.030864 -240.85423)
		(end 315.899292 -240.722658)
		(width 0.10668)
		(layer "F.Cu")
		(net "M_A_CPU0_SA_DQ<28>")
	)
	(segment
		(start 316.46368 -241.287046)
		(end 316.463934 -241.136678)
		(width 0.10668)
		(layer "F.Cu")
		(net "M_A_CPU0_SA_DQ<28>")
	)
	(segment
		(start 318.157098 -242.829842)
		(end 318.276732 -242.710208)
		(width 0.10668)
		(layer "F.Cu")
		(net "M_A_CPU0_SA_DQ<28>")
	)
	(segment
		(start 314.770516 -239.593882)
		(end 314.77077 -239.443514)
		(width 0.10668)
		(layer "F.Cu")
		(net "M_A_CPU0_SA_DQ<28>")
	)
	(segment
		(start 315.899546 -240.57229)
		(end 316.01918 -240.452656)
		(width 0.10668)
		(layer "F.Cu")
		(net "M_A_CPU0_SA_DQ<28>")
	)
	(segment
		(start 313.641994 -238.314738)
		(end 313.761628 -238.195104)
		(width 0.10668)
		(layer "F.Cu")
		(net "M_A_CPU0_SA_DQ<28>")
	)
	(segment
		(start 313.64174 -238.465106)
		(end 313.641994 -238.314738)
		(width 0.10668)
		(layer "F.Cu")
		(net "M_A_CPU0_SA_DQ<28>")
	)
	(segment
		(start 313.19724 -237.47984)
		(end 313.065922 -237.348522)
		(width 0.10668)
		(layer "F.Cu")
		(net "M_A_CPU0_SA_DQ<28>")
	)
	(segment
		(start 318.288416 -243.111782)
		(end 318.156844 -242.98021)
		(width 0.10668)
		(layer "F.Cu")
		(net "M_A_CPU0_SA_DQ<28>")
	)
	(segment
		(start 317.016638 -241.299238)
		(end 316.865762 -241.298984)
		(width 0.10668)
		(layer "F.Cu")
		(net "M_A_CPU0_SA_DQ<28>")
	)
	(segment
		(start 317.15964 -241.983006)
		(end 317.028068 -241.851434)
		(width 0.10668)
		(layer "F.Cu")
		(net "M_A_CPU0_SA_DQ<28>")
	)
	(segment
		(start 315.335158 -240.007902)
		(end 315.454792 -239.888268)
		(width 0.10668)
		(layer "F.Cu")
		(net "M_A_CPU0_SA_DQ<28>")
	)
	(segment
		(start 313.208924 -238.03229)
		(end 313.077352 -237.900718)
		(width 0.10668)
		(layer "F.Cu")
		(net "M_A_CPU0_SA_DQ<28>")
	)
	(segment
		(start 317.028068 -241.851434)
		(end 317.028322 -241.701066)
		(width 0.10668)
		(layer "F.Cu")
		(net "M_A_CPU0_SA_DQ<28>")
	)
	(segment
		(start 317.712344 -241.994944)
		(end 317.581026 -241.863626)
		(width 0.10668)
		(layer "F.Cu")
		(net "M_A_CPU0_SA_DQ<28>")
	)
	(segment
		(start 316.583568 -241.017044)
		(end 316.583568 -240.866168)
		(width 0.10668)
		(layer "F.Cu")
		(net "M_A_CPU0_SA_DQ<28>")
	)
	(segment
		(start 315.323474 -239.606074)
		(end 315.172598 -239.60582)
		(width 0.10668)
		(layer "F.Cu")
		(net "M_A_CPU0_SA_DQ<28>")
	)
	(segment
		(start 325.340726 -243.50599)
		(end 324.155054 -243.50599)
		(width 0.0762)
		(layer "F.Cu")
		(net "M_A_CPU0_SA_DQ<28>")
	)
	(segment
		(start 312.513218 -237.185962)
		(end 312.632852 -237.066328)
		(width 0.10668)
		(layer "F.Cu")
		(net "M_A_CPU0_SA_DQ<28>")
	)
	(arc
		(start 325.59498 -243.45265)
		(mid 325.51974 -243.485963)
		(end 325.439024 -243.501926)
		(width 0.0762)
		(layer "F.Cu")
		(net "M_A_CPU0_SA_DQ<28>")
	)
	(arc
		(start 325.830438 -243.378228)
		(mid 325.708582 -243.402384)
		(end 325.59498 -243.45265)
		(width 0.0762)
		(layer "F.Cu")
		(net "M_A_CPU0_SA_DQ<28>")
	)
	(arc
		(start 326.34809 -243.13007)
		(mid 326.111962 -243.301505)
		(end 325.830438 -243.378228)
		(width 0.0762)
		(layer "F.Cu")
		(net "M_A_CPU0_SA_DQ<28>")
	)
	(arc
		(start 325.439024 -243.501926)
		(mid 325.389917 -243.504967)
		(end 325.340726 -243.50599)
		(width 0.0762)
		(layer "F.Cu")
		(net "M_A_CPU0_SA_DQ<28>")
	)
	(segment
		(start 308.575964 -228.360224)
		(end 308.28488 -228.360224)
		(width 0.10668)
		(layer "F.Cu")
		(net "M_A_CPU0_SA_DQ<27>")
	)
	(segment
		(start 327.108312 -241.18316)
		(end 327.100946 -241.187478)
		(width 0.0762)
		(layer "F.Cu")
		(net "M_A_CPU0_SA_DQ<27>")
	)
	(segment
		(start 305.74488 -228.360224)
		(end 305.319684 -227.935028)
		(width 0.101346)
		(layer "F.Cu")
		(net "M_A_CPU0_SA_DQ<27>")
	)
	(segment
		(start 308.28488 -228.360224)
		(end 305.74488 -228.360224)
		(width 0.101346)
		(layer "F.Cu")
		(net "M_A_CPU0_SA_DQ<27>")
	)
	(segment
		(start 325.385938 -241.13109)
		(end 324.584314 -241.13109)
		(width 0.0762)
		(layer "F.Cu")
		(net "M_A_CPU0_SA_DQ<27>")
	)
	(segment
		(start 324.584314 -241.13109)
		(end 324.215252 -241.500152)
		(width 0.0762)
		(layer "F.Cu")
		(net "M_A_CPU0_SA_DQ<27>")
	)
	(segment
		(start 324.215252 -241.500152)
		(end 320.918332 -241.500152)
		(width 0.10668)
		(layer "F.Cu")
		(net "M_A_CPU0_SA_DQ<27>")
	)
	(segment
		(start 310.374538 -230.158798)
		(end 308.575964 -228.360224)
		(width 0.10668)
		(layer "F.Cu")
		(net "M_A_CPU0_SA_DQ<27>")
	)
	(segment
		(start 320.918332 -241.500152)
		(end 310.374538 -230.956358)
		(width 0.10668)
		(layer "F.Cu")
		(net "M_A_CPU0_SA_DQ<27>")
	)
	(segment
		(start 310.374538 -230.956358)
		(end 310.374538 -230.158798)
		(width 0.10668)
		(layer "F.Cu")
		(net "M_A_CPU0_SA_DQ<27>")
	)
	(segment
		(start 305.319684 -227.935028)
		(end 303.268126 -227.935028)
		(width 0.101346)
		(layer "F.Cu")
		(net "M_A_CPU0_SA_DQ<27>")
	)
	(segment
		(start 327.28789 -241.510058)
		(end 327.28789 -241.509804)
		(width 0.0762)
		(layer "F.Cu")
		(net "M_A_CPU0_SA_DQ<27>")
	)
	(segment
		(start 326.535034 -241.187478)
		(end 326.526652 -241.182652)
		(width 0.0762)
		(layer "F.Cu")
		(net "M_A_CPU0_SA_DQ<27>")
	)
	(segment
		(start 327.109328 -241.182652)
		(end 327.108312 -241.18316)
		(width 0.0762)
		(layer "F.Cu")
		(net "M_A_CPU0_SA_DQ<27>")
	)
	(segment
		(start 327.28789 -241.509804)
		(end 327.393046 -241.328956)
		(width 0.0762)
		(layer "F.Cu")
		(net "M_A_CPU0_SA_DQ<27>")
	)
	(arc
		(start 327.289414 -241.137186)
		(mid 327.19649 -241.148509)
		(end 327.109328 -241.182652)
		(width 0.0762)
		(layer "F.Cu")
		(net "M_A_CPU0_SA_DQ<27>")
	)
	(arc
		(start 326.526652 -241.182652)
		(mid 326.343144 -241.137158)
		(end 326.160892 -241.187478)
		(width 0.0762)
		(layer "F.Cu")
		(net "M_A_CPU0_SA_DQ<27>")
	)
	(arc
		(start 327.100946 -241.187478)
		(mid 326.81799 -241.263655)
		(end 326.535034 -241.187478)
		(width 0.0762)
		(layer "F.Cu")
		(net "M_A_CPU0_SA_DQ<27>")
	)
	(arc
		(start 327.393046 -241.328956)
		(mid 327.384109 -241.209932)
		(end 327.289414 -241.137186)
		(width 0.0762)
		(layer "F.Cu")
		(net "M_A_CPU0_SA_DQ<27>")
	)
	(arc
		(start 326.160892 -241.187478)
		(mid 325.877936 -241.263655)
		(end 325.59498 -241.187478)
		(width 0.0762)
		(layer "F.Cu")
		(net "M_A_CPU0_SA_DQ<27>")
	)
	(arc
		(start 325.59498 -241.187478)
		(mid 325.494188 -241.145472)
		(end 325.385938 -241.13109)
		(width 0.0762)
		(layer "F.Cu")
		(net "M_A_CPU0_SA_DQ<27>")
	)
	(segment
		(start 324.762876 -240.63325)
		(end 324.373494 -240.63325)
		(width 0.0762)
		(layer "F.Cu")
		(net "M_A_CPU0_SA_DQ<26>")
	)
	(segment
		(start 309.350664 -227.1776)
		(end 309.350664 -226.745038)
		(width 0.10668)
		(layer "F.Cu")
		(net "M_A_CPU0_SA_DQ<26>")
	)
	(segment
		(start 323.911214 -240.80851)
		(end 321.304666 -240.80851)
		(width 0.10668)
		(layer "F.Cu")
		(net "M_A_CPU0_SA_DQ<26>")
	)
	(segment
		(start 309.265828 -226.660202)
		(end 308.610508 -226.660202)
		(width 0.10668)
		(layer "F.Cu")
		(net "M_A_CPU0_SA_DQ<26>")
	)
	(segment
		(start 311.055258 -230.559102)
		(end 311.055258 -228.882194)
		(width 0.10668)
		(layer "F.Cu")
		(net "M_A_CPU0_SA_DQ<26>")
	)
	(segment
		(start 321.304666 -240.80851)
		(end 311.055258 -230.559102)
		(width 0.10668)
		(layer "F.Cu")
		(net "M_A_CPU0_SA_DQ<26>")
	)
	(segment
		(start 325.877936 -240.700052)
		(end 325.9709 -240.540032)
		(width 0.0762)
		(layer "F.Cu")
		(net "M_A_CPU0_SA_DQ<26>")
	)
	(segment
		(start 305.645312 -226.235006)
		(end 303.268126 -226.235006)
		(width 0.101346)
		(layer "F.Cu")
		(net "M_A_CPU0_SA_DQ<26>")
	)
	(segment
		(start 324.198234 -240.80851)
		(end 323.911214 -240.80851)
		(width 0.0762)
		(layer "F.Cu")
		(net "M_A_CPU0_SA_DQ<26>")
	)
	(segment
		(start 309.350664 -226.745038)
		(end 309.265828 -226.660202)
		(width 0.10668)
		(layer "F.Cu")
		(net "M_A_CPU0_SA_DQ<26>")
	)
	(segment
		(start 306.070508 -226.660202)
		(end 305.645312 -226.235006)
		(width 0.101346)
		(layer "F.Cu")
		(net "M_A_CPU0_SA_DQ<26>")
	)
	(segment
		(start 311.055258 -228.882194)
		(end 309.350664 -227.1776)
		(width 0.10668)
		(layer "F.Cu")
		(net "M_A_CPU0_SA_DQ<26>")
	)
	(segment
		(start 308.610508 -226.660202)
		(end 306.070508 -226.660202)
		(width 0.101346)
		(layer "F.Cu")
		(net "M_A_CPU0_SA_DQ<26>")
	)
	(segment
		(start 324.373494 -240.63325)
		(end 324.198234 -240.80851)
		(width 0.0762)
		(layer "F.Cu")
		(net "M_A_CPU0_SA_DQ<26>")
	)
	(arc
		(start 325.699374 -240.372646)
		(mid 325.248916 -240.566877)
		(end 324.762876 -240.63325)
		(width 0.0762)
		(layer "F.Cu")
		(net "M_A_CPU0_SA_DQ<26>")
	)
	(arc
		(start 325.839074 -240.329212)
		(mid 325.767066 -240.343994)
		(end 325.699374 -240.372646)
		(width 0.0762)
		(layer "F.Cu")
		(net "M_A_CPU0_SA_DQ<26>")
	)
	(arc
		(start 325.9709 -240.540032)
		(mid 325.97074 -240.393471)
		(end 325.839074 -240.329212)
		(width 0.0762)
		(layer "F.Cu")
		(net "M_A_CPU0_SA_DQ<26>")
	)
	(segment
		(start 309.86222 -229.153466)
		(end 309.730648 -229.021894)
		(width 0.10668)
		(layer "F.Cu")
		(net "M_A_CPU0_SA_DQ<25>")
	)
	(segment
		(start 310.534558 -229.402132)
		(end 310.714898 -229.221792)
		(width 0.10668)
		(layer "F.Cu")
		(net "M_A_CPU0_SA_DQ<25>")
	)
	(segment
		(start 309.93715 -228.251766)
		(end 309.786274 -228.251512)
		(width 0.10668)
		(layer "F.Cu")
		(net "M_A_CPU0_SA_DQ<25>")
	)
	(segment
		(start 309.001414 -227.566982)
		(end 308.64937 -227.919026)
		(width 0.10668)
		(layer "F.Cu")
		(net "M_A_CPU0_SA_DQ<25>")
	)
	(segment
		(start 309.50408 -227.969572)
		(end 309.50408 -227.818696)
		(width 0.10668)
		(layer "F.Cu")
		(net "M_A_CPU0_SA_DQ<25>")
	)
	(segment
		(start 309.730902 -228.871526)
		(end 310.068468 -228.53396)
		(width 0.10668)
		(layer "F.Cu")
		(net "M_A_CPU0_SA_DQ<25>")
	)
	(segment
		(start 307.868828 -227.085144)
		(end 307.368194 -227.085144)
		(width 0.10668)
		(layer "F.Cu")
		(net "M_A_CPU0_SA_DQ<25>")
	)
	(segment
		(start 309.448708 -228.589078)
		(end 309.297832 -228.589078)
		(width 0.10668)
		(layer "F.Cu")
		(net "M_A_CPU0_SA_DQ<25>")
	)
	(segment
		(start 309.166514 -228.307138)
		(end 309.50408 -227.969572)
		(width 0.10668)
		(layer "F.Cu")
		(net "M_A_CPU0_SA_DQ<25>")
	)
	(segment
		(start 310.501538 -228.816154)
		(end 310.350662 -228.8159)
		(width 0.10668)
		(layer "F.Cu")
		(net "M_A_CPU0_SA_DQ<25>")
	)
	(segment
		(start 308.64937 -227.919026)
		(end 308.48427 -227.919026)
		(width 0.10668)
		(layer "F.Cu")
		(net "M_A_CPU0_SA_DQ<25>")
	)
	(segment
		(start 309.252366 -227.566982)
		(end 309.001414 -227.566982)
		(width 0.10668)
		(layer "F.Cu")
		(net "M_A_CPU0_SA_DQ<25>")
	)
	(segment
		(start 309.786274 -228.251512)
		(end 309.448708 -228.589078)
		(width 0.10668)
		(layer "F.Cu")
		(net "M_A_CPU0_SA_DQ<25>")
	)
	(segment
		(start 309.730648 -229.021894)
		(end 309.730902 -228.871526)
		(width 0.10668)
		(layer "F.Cu")
		(net "M_A_CPU0_SA_DQ<25>")
	)
	(segment
		(start 309.297832 -228.589078)
		(end 309.16626 -228.457506)
		(width 0.10668)
		(layer "F.Cu")
		(net "M_A_CPU0_SA_DQ<25>")
	)
	(segment
		(start 309.50408 -227.818696)
		(end 309.252366 -227.566982)
		(width 0.10668)
		(layer "F.Cu")
		(net "M_A_CPU0_SA_DQ<25>")
	)
	(segment
		(start 324.419214 -240.93805)
		(end 324.198234 -241.15903)
		(width 0.0762)
		(layer "F.Cu")
		(net "M_A_CPU0_SA_DQ<25>")
	)
	(segment
		(start 323.906134 -241.15903)
		(end 321.058794 -241.15903)
		(width 0.10668)
		(layer "F.Cu")
		(net "M_A_CPU0_SA_DQ<25>")
	)
	(segment
		(start 310.714898 -229.801166)
		(end 310.534558 -229.620826)
		(width 0.10668)
		(layer "F.Cu")
		(net "M_A_CPU0_SA_DQ<25>")
	)
	(segment
		(start 324.198234 -241.15903)
		(end 323.906134 -241.15903)
		(width 0.0762)
		(layer "F.Cu")
		(net "M_A_CPU0_SA_DQ<25>")
	)
	(segment
		(start 325.699374 -241.027458)
		(end 325.690992 -241.022632)
		(width 0.0762)
		(layer "F.Cu")
		(net "M_A_CPU0_SA_DQ<25>")
	)
	(segment
		(start 308.48427 -227.919026)
		(end 308.313074 -227.74783)
		(width 0.10668)
		(layer "F.Cu")
		(net "M_A_CPU0_SA_DQ<25>")
	)
	(segment
		(start 309.16626 -228.457506)
		(end 309.166514 -228.307138)
		(width 0.10668)
		(layer "F.Cu")
		(net "M_A_CPU0_SA_DQ<25>")
	)
	(segment
		(start 321.058794 -241.15903)
		(end 310.714898 -230.815134)
		(width 0.10668)
		(layer "F.Cu")
		(net "M_A_CPU0_SA_DQ<25>")
	)
	(segment
		(start 327.004934 -241.022378)
		(end 327.004934 -241.022632)
		(width 0.0762)
		(layer "F.Cu")
		(net "M_A_CPU0_SA_DQ<25>")
	)
	(segment
		(start 310.714898 -230.815134)
		(end 310.714898 -229.801166)
		(width 0.10668)
		(layer "F.Cu")
		(net "M_A_CPU0_SA_DQ<25>")
	)
	(segment
		(start 308.313074 -227.52939)
		(end 307.868828 -227.085144)
		(width 0.10668)
		(layer "F.Cu")
		(net "M_A_CPU0_SA_DQ<25>")
	)
	(segment
		(start 310.714898 -229.029514)
		(end 310.501538 -228.816154)
		(width 0.10668)
		(layer "F.Cu")
		(net "M_A_CPU0_SA_DQ<25>")
	)
	(segment
		(start 310.714898 -229.221792)
		(end 310.714898 -229.029514)
		(width 0.10668)
		(layer "F.Cu")
		(net "M_A_CPU0_SA_DQ<25>")
	)
	(segment
		(start 325.376794 -240.93805)
		(end 324.419214 -240.93805)
		(width 0.0762)
		(layer "F.Cu")
		(net "M_A_CPU0_SA_DQ<25>")
	)
	(segment
		(start 310.534558 -229.620826)
		(end 310.534558 -229.402132)
		(width 0.10668)
		(layer "F.Cu")
		(net "M_A_CPU0_SA_DQ<25>")
	)
	(segment
		(start 310.068468 -228.53396)
		(end 310.068468 -228.383084)
		(width 0.10668)
		(layer "F.Cu")
		(net "M_A_CPU0_SA_DQ<25>")
	)
	(segment
		(start 310.068468 -228.383084)
		(end 309.93715 -228.251766)
		(width 0.10668)
		(layer "F.Cu")
		(net "M_A_CPU0_SA_DQ<25>")
	)
	(segment
		(start 310.013096 -229.153466)
		(end 309.86222 -229.153466)
		(width 0.10668)
		(layer "F.Cu")
		(net "M_A_CPU0_SA_DQ<25>")
	)
	(segment
		(start 308.313074 -227.74783)
		(end 308.313074 -227.52939)
		(width 0.10668)
		(layer "F.Cu")
		(net "M_A_CPU0_SA_DQ<25>")
	)
	(segment
		(start 310.350662 -228.8159)
		(end 310.013096 -229.153466)
		(width 0.10668)
		(layer "F.Cu")
		(net "M_A_CPU0_SA_DQ<25>")
	)
	(arc
		(start 325.690992 -241.022632)
		(mid 325.539495 -240.959513)
		(end 325.376794 -240.93805)
		(width 0.0762)
		(layer "F.Cu")
		(net "M_A_CPU0_SA_DQ<25>")
	)
	(arc
		(start 326.065134 -241.022632)
		(mid 325.882883 -241.072982)
		(end 325.699374 -241.027458)
		(width 0.0762)
		(layer "F.Cu")
		(net "M_A_CPU0_SA_DQ<25>")
	)
	(arc
		(start 327.289414 -240.945924)
		(mid 327.142093 -240.965243)
		(end 327.004934 -241.022378)
		(width 0.0762)
		(layer "F.Cu")
		(net "M_A_CPU0_SA_DQ<25>")
	)
	(arc
		(start 327.758044 -240.700052)
		(mid 327.554028 -240.880746)
		(end 327.289414 -240.945924)
		(width 0.0762)
		(layer "F.Cu")
		(net "M_A_CPU0_SA_DQ<25>")
	)
	(arc
		(start 326.631046 -241.022632)
		(mid 326.34809 -240.946455)
		(end 326.065134 -241.022632)
		(width 0.0762)
		(layer "F.Cu")
		(net "M_A_CPU0_SA_DQ<25>")
	)
	(arc
		(start 327.004934 -241.022632)
		(mid 326.81799 -241.072887)
		(end 326.631046 -241.022632)
		(width 0.0762)
		(layer "F.Cu")
		(net "M_A_CPU0_SA_DQ<25>")
	)
	(segment
		(start 311.240678 -228.292152)
		(end 310.955436 -228.292152)
		(width 0.10668)
		(layer "F.Cu")
		(net "M_A_CPU0_SA_DQ<24>")
	)
	(segment
		(start 310.117236 -226.451414)
		(end 310.117236 -226.300538)
		(width 0.10668)
		(layer "F.Cu")
		(net "M_A_CPU0_SA_DQ<24>")
	)
	(segment
		(start 309.691024 -227.02774)
		(end 309.691278 -226.877372)
		(width 0.10668)
		(layer "F.Cu")
		(net "M_A_CPU0_SA_DQ<24>")
	)
	(segment
		(start 310.255666 -227.44176)
		(end 310.681624 -227.015802)
		(width 0.10668)
		(layer "F.Cu")
		(net "M_A_CPU0_SA_DQ<24>")
	)
	(segment
		(start 324.337934 -240.31829)
		(end 324.190614 -240.46561)
		(width 0.0762)
		(layer "F.Cu")
		(net "M_A_CPU0_SA_DQ<24>")
	)
	(segment
		(start 325.202296 -240.31829)
		(end 324.337934 -240.31829)
		(width 0.0762)
		(layer "F.Cu")
		(net "M_A_CPU0_SA_DQ<24>")
	)
	(segment
		(start 310.955436 -228.292152)
		(end 310.8198 -228.156516)
		(width 0.10668)
		(layer "F.Cu")
		(net "M_A_CPU0_SA_DQ<24>")
	)
	(segment
		(start 310.681624 -227.015802)
		(end 310.681624 -226.864926)
		(width 0.10668)
		(layer "F.Cu")
		(net "M_A_CPU0_SA_DQ<24>")
	)
	(segment
		(start 323.911214 -240.46561)
		(end 321.44335 -240.46561)
		(width 0.10668)
		(layer "F.Cu")
		(net "M_A_CPU0_SA_DQ<24>")
	)
	(segment
		(start 310.117236 -226.300538)
		(end 309.985918 -226.16922)
		(width 0.10668)
		(layer "F.Cu")
		(net "M_A_CPU0_SA_DQ<24>")
	)
	(segment
		(start 310.386984 -227.7237)
		(end 310.255412 -227.592128)
		(width 0.10668)
		(layer "F.Cu")
		(net "M_A_CPU0_SA_DQ<24>")
	)
	(segment
		(start 310.681624 -226.864926)
		(end 310.550306 -226.733608)
		(width 0.10668)
		(layer "F.Cu")
		(net "M_A_CPU0_SA_DQ<24>")
	)
	(segment
		(start 310.53786 -227.7237)
		(end 310.386984 -227.7237)
		(width 0.10668)
		(layer "F.Cu")
		(net "M_A_CPU0_SA_DQ<24>")
	)
	(segment
		(start 311.114694 -227.297996)
		(end 310.963818 -227.297742)
		(width 0.10668)
		(layer "F.Cu")
		(net "M_A_CPU0_SA_DQ<24>")
	)
	(segment
		(start 309.985918 -226.16922)
		(end 309.835042 -226.168966)
		(width 0.10668)
		(layer "F.Cu")
		(net "M_A_CPU0_SA_DQ<24>")
	)
	(segment
		(start 309.691278 -226.877372)
		(end 310.117236 -226.451414)
		(width 0.10668)
		(layer "F.Cu")
		(net "M_A_CPU0_SA_DQ<24>")
	)
	(segment
		(start 310.39943 -226.733354)
		(end 309.973472 -227.159312)
		(width 0.10668)
		(layer "F.Cu")
		(net "M_A_CPU0_SA_DQ<24>")
	)
	(segment
		(start 310.820054 -228.006148)
		(end 311.246012 -227.58019)
		(width 0.10668)
		(layer "F.Cu")
		(net "M_A_CPU0_SA_DQ<24>")
	)
	(segment
		(start 311.395618 -228.447092)
		(end 311.240678 -228.292152)
		(width 0.10668)
		(layer "F.Cu")
		(net "M_A_CPU0_SA_DQ<24>")
	)
	(segment
		(start 321.44335 -240.46561)
		(end 311.395618 -230.417878)
		(width 0.10668)
		(layer "F.Cu")
		(net "M_A_CPU0_SA_DQ<24>")
	)
	(segment
		(start 309.973472 -227.159312)
		(end 309.822596 -227.159312)
		(width 0.10668)
		(layer "F.Cu")
		(net "M_A_CPU0_SA_DQ<24>")
	)
	(segment
		(start 309.822596 -227.159312)
		(end 309.691024 -227.02774)
		(width 0.10668)
		(layer "F.Cu")
		(net "M_A_CPU0_SA_DQ<24>")
	)
	(segment
		(start 310.8198 -228.156516)
		(end 310.820054 -228.006148)
		(width 0.10668)
		(layer "F.Cu")
		(net "M_A_CPU0_SA_DQ<24>")
	)
	(segment
		(start 311.246012 -227.58019)
		(end 311.246012 -227.429314)
		(width 0.10668)
		(layer "F.Cu")
		(net "M_A_CPU0_SA_DQ<24>")
	)
	(segment
		(start 310.963818 -227.297742)
		(end 310.53786 -227.7237)
		(width 0.10668)
		(layer "F.Cu")
		(net "M_A_CPU0_SA_DQ<24>")
	)
	(segment
		(start 310.255412 -227.592128)
		(end 310.255666 -227.44176)
		(width 0.10668)
		(layer "F.Cu")
		(net "M_A_CPU0_SA_DQ<24>")
	)
	(segment
		(start 309.835042 -226.168966)
		(end 308.83225 -226.168966)
		(width 0.10668)
		(layer "F.Cu")
		(net "M_A_CPU0_SA_DQ<24>")
	)
	(segment
		(start 308.048406 -225.385122)
		(end 307.368194 -225.385122)
		(width 0.10668)
		(layer "F.Cu")
		(net "M_A_CPU0_SA_DQ<24>")
	)
	(segment
		(start 324.190614 -240.46561)
		(end 323.911214 -240.46561)
		(width 0.0762)
		(layer "F.Cu")
		(net "M_A_CPU0_SA_DQ<24>")
	)
	(segment
		(start 311.395618 -230.417878)
		(end 311.395618 -228.447092)
		(width 0.10668)
		(layer "F.Cu")
		(net "M_A_CPU0_SA_DQ<24>")
	)
	(segment
		(start 310.550306 -226.733608)
		(end 310.39943 -226.733354)
		(width 0.10668)
		(layer "F.Cu")
		(net "M_A_CPU0_SA_DQ<24>")
	)
	(segment
		(start 311.246012 -227.429314)
		(end 311.114694 -227.297996)
		(width 0.10668)
		(layer "F.Cu")
		(net "M_A_CPU0_SA_DQ<24>")
	)
	(segment
		(start 308.83225 -226.168966)
		(end 308.048406 -225.385122)
		(width 0.10668)
		(layer "F.Cu")
		(net "M_A_CPU0_SA_DQ<24>")
	)
	(arc
		(start 326.34809 -239.890046)
		(mid 326.111962 -240.061481)
		(end 325.830438 -240.138204)
		(width 0.0762)
		(layer "F.Cu")
		(net "M_A_CPU0_SA_DQ<24>")
	)
	(arc
		(start 325.830438 -240.138204)
		(mid 325.708582 -240.16236)
		(end 325.59498 -240.212626)
		(width 0.0762)
		(layer "F.Cu")
		(net "M_A_CPU0_SA_DQ<24>")
	)
	(arc
		(start 325.59498 -240.212626)
		(mid 325.405616 -240.29138)
		(end 325.202296 -240.31829)
		(width 0.0762)
		(layer "F.Cu")
		(net "M_A_CPU0_SA_DQ<24>")
	)
	(segment
		(start 323.906134 -240.00841)
		(end 321.632834 -240.00841)
		(width 0.10668)
		(layer "F.Cu")
		(net "M_A_CPU0_SA_DQ<23>")
	)
	(segment
		(start 309.12943 -224.77984)
		(end 308.815486 -225.093784)
		(width 0.10668)
		(layer "F.Cu")
		(net "M_A_CPU0_SA_DQ<23>")
	)
	(segment
		(start 309.411624 -225.062034)
		(end 309.411624 -224.911158)
		(width 0.10668)
		(layer "F.Cu")
		(net "M_A_CPU0_SA_DQ<23>")
	)
	(segment
		(start 309.09768 -225.526854)
		(end 309.09768 -225.375978)
		(width 0.10668)
		(layer "F.Cu")
		(net "M_A_CPU0_SA_DQ<23>")
	)
	(segment
		(start 309.844694 -225.344228)
		(end 309.693818 -225.344228)
		(width 0.10668)
		(layer "F.Cu")
		(net "M_A_CPU0_SA_DQ<23>")
	)
	(segment
		(start 305.645566 -224.534984)
		(end 303.268126 -224.534984)
		(width 0.101346)
		(layer "F.Cu")
		(net "M_A_CPU0_SA_DQ<23>")
	)
	(segment
		(start 309.280306 -224.77984)
		(end 309.12943 -224.77984)
		(width 0.10668)
		(layer "F.Cu")
		(net "M_A_CPU0_SA_DQ<23>")
	)
	(segment
		(start 321.632834 -240.00841)
		(end 311.852818 -230.228394)
		(width 0.10668)
		(layer "F.Cu")
		(net "M_A_CPU0_SA_DQ<23>")
	)
	(segment
		(start 327.28789 -239.890046)
		(end 327.28789 -239.889792)
		(width 0.0762)
		(layer "F.Cu")
		(net "M_A_CPU0_SA_DQ<23>")
	)
	(segment
		(start 309.411624 -224.911158)
		(end 309.280306 -224.77984)
		(width 0.10668)
		(layer "F.Cu")
		(net "M_A_CPU0_SA_DQ<23>")
	)
	(segment
		(start 308.847236 -224.34677)
		(end 308.610508 -224.110042)
		(width 0.10668)
		(layer "F.Cu")
		(net "M_A_CPU0_SA_DQ<23>")
	)
	(segment
		(start 327.109328 -239.56264)
		(end 327.108312 -239.563148)
		(width 0.0762)
		(layer "F.Cu")
		(net "M_A_CPU0_SA_DQ<23>")
	)
	(segment
		(start 324.629272 -239.51057)
		(end 324.131432 -240.00841)
		(width 0.0762)
		(layer "F.Cu")
		(net "M_A_CPU0_SA_DQ<23>")
	)
	(segment
		(start 308.847236 -224.497646)
		(end 308.847236 -224.34677)
		(width 0.10668)
		(layer "F.Cu")
		(net "M_A_CPU0_SA_DQ<23>")
	)
	(segment
		(start 308.533292 -224.81159)
		(end 308.847236 -224.497646)
		(width 0.10668)
		(layer "F.Cu")
		(net "M_A_CPU0_SA_DQ<23>")
	)
	(segment
		(start 308.815486 -225.093784)
		(end 308.66461 -225.093784)
		(width 0.10668)
		(layer "F.Cu")
		(net "M_A_CPU0_SA_DQ<23>")
	)
	(segment
		(start 306.070508 -224.110042)
		(end 305.645566 -224.534984)
		(width 0.101346)
		(layer "F.Cu")
		(net "M_A_CPU0_SA_DQ<23>")
	)
	(segment
		(start 308.66461 -225.093784)
		(end 308.533292 -224.962466)
		(width 0.10668)
		(layer "F.Cu")
		(net "M_A_CPU0_SA_DQ<23>")
	)
	(segment
		(start 311.852818 -227.352352)
		(end 309.844694 -225.344228)
		(width 0.10668)
		(layer "F.Cu")
		(net "M_A_CPU0_SA_DQ<23>")
	)
	(segment
		(start 308.610508 -224.110042)
		(end 306.070508 -224.110042)
		(width 0.101346)
		(layer "F.Cu")
		(net "M_A_CPU0_SA_DQ<23>")
	)
	(segment
		(start 309.693818 -225.344228)
		(end 309.379874 -225.658172)
		(width 0.10668)
		(layer "F.Cu")
		(net "M_A_CPU0_SA_DQ<23>")
	)
	(segment
		(start 311.852818 -230.228394)
		(end 311.852818 -227.352352)
		(width 0.10668)
		(layer "F.Cu")
		(net "M_A_CPU0_SA_DQ<23>")
	)
	(segment
		(start 326.535034 -239.567466)
		(end 326.526652 -239.56264)
		(width 0.0762)
		(layer "F.Cu")
		(net "M_A_CPU0_SA_DQ<23>")
	)
	(segment
		(start 309.228998 -225.658172)
		(end 309.09768 -225.526854)
		(width 0.10668)
		(layer "F.Cu")
		(net "M_A_CPU0_SA_DQ<23>")
	)
	(segment
		(start 324.131432 -240.00841)
		(end 323.906134 -240.00841)
		(width 0.0762)
		(layer "F.Cu")
		(net "M_A_CPU0_SA_DQ<23>")
	)
	(segment
		(start 309.379874 -225.658172)
		(end 309.228998 -225.658172)
		(width 0.10668)
		(layer "F.Cu")
		(net "M_A_CPU0_SA_DQ<23>")
	)
	(segment
		(start 325.383906 -239.51057)
		(end 324.629272 -239.51057)
		(width 0.0762)
		(layer "F.Cu")
		(net "M_A_CPU0_SA_DQ<23>")
	)
	(segment
		(start 309.09768 -225.375978)
		(end 309.411624 -225.062034)
		(width 0.10668)
		(layer "F.Cu")
		(net "M_A_CPU0_SA_DQ<23>")
	)
	(segment
		(start 327.108312 -239.563148)
		(end 327.100946 -239.567466)
		(width 0.0762)
		(layer "F.Cu")
		(net "M_A_CPU0_SA_DQ<23>")
	)
	(segment
		(start 308.533292 -224.962466)
		(end 308.533292 -224.81159)
		(width 0.10668)
		(layer "F.Cu")
		(net "M_A_CPU0_SA_DQ<23>")
	)
	(segment
		(start 327.28789 -239.889792)
		(end 327.393046 -239.708944)
		(width 0.0762)
		(layer "F.Cu")
		(net "M_A_CPU0_SA_DQ<23>")
	)
	(arc
		(start 325.59498 -239.567466)
		(mid 325.493212 -239.525032)
		(end 325.383906 -239.51057)
		(width 0.0762)
		(layer "F.Cu")
		(net "M_A_CPU0_SA_DQ<23>")
	)
	(arc
		(start 327.100946 -239.567466)
		(mid 326.81799 -239.643643)
		(end 326.535034 -239.567466)
		(width 0.0762)
		(layer "F.Cu")
		(net "M_A_CPU0_SA_DQ<23>")
	)
	(arc
		(start 326.526652 -239.56264)
		(mid 326.343144 -239.517146)
		(end 326.160892 -239.567466)
		(width 0.0762)
		(layer "F.Cu")
		(net "M_A_CPU0_SA_DQ<23>")
	)
	(arc
		(start 327.289414 -239.517174)
		(mid 327.19649 -239.528497)
		(end 327.109328 -239.56264)
		(width 0.0762)
		(layer "F.Cu")
		(net "M_A_CPU0_SA_DQ<23>")
	)
	(arc
		(start 326.160892 -239.567466)
		(mid 325.877936 -239.643643)
		(end 325.59498 -239.567466)
		(width 0.0762)
		(layer "F.Cu")
		(net "M_A_CPU0_SA_DQ<23>")
	)
	(arc
		(start 327.393046 -239.708944)
		(mid 327.384109 -239.58992)
		(end 327.289414 -239.517174)
		(width 0.0762)
		(layer "F.Cu")
		(net "M_A_CPU0_SA_DQ<23>")
	)
	(segment
		(start 325.038466 -238.93653)
		(end 324.411594 -238.93653)
		(width 0.0762)
		(layer "F.Cu")
		(net "M_A_CPU0_SA_DQ<22>")
	)
	(segment
		(start 304.815748 -223.334326)
		(end 304.714402 -223.435672)
		(width 0.101346)
		(layer "F.Cu")
		(net "M_A_CPU0_SA_DQ<22>")
	)
	(segment
		(start 304.320702 -222.834962)
		(end 303.268126 -222.834962)
		(width 0.101346)
		(layer "F.Cu")
		(net "M_A_CPU0_SA_DQ<22>")
	)
	(segment
		(start 323.908674 -239.32515)
		(end 321.912742 -239.32515)
		(width 0.10668)
		(layer "F.Cu")
		(net "M_A_CPU0_SA_DQ<22>")
	)
	(segment
		(start 306.418996 -223.260158)
		(end 305.9938 -222.834962)
		(width 0.101346)
		(layer "F.Cu")
		(net "M_A_CPU0_SA_DQ<22>")
	)
	(segment
		(start 309.77332 -223.260158)
		(end 309.475886 -223.260158)
		(width 0.10668)
		(layer "F.Cu")
		(net "M_A_CPU0_SA_DQ<22>")
	)
	(segment
		(start 325.877936 -239.08004)
		(end 325.9709 -238.92002)
		(width 0.0762)
		(layer "F.Cu")
		(net "M_A_CPU0_SA_DQ<22>")
	)
	(segment
		(start 305.108102 -222.834962)
		(end 304.917094 -222.834962)
		(width 0.101346)
		(layer "F.Cu")
		(net "M_A_CPU0_SA_DQ<22>")
	)
	(segment
		(start 309.242206 -222.79737)
		(end 309.076852 -222.79737)
		(width 0.10668)
		(layer "F.Cu")
		(net "M_A_CPU0_SA_DQ<22>")
	)
	(segment
		(start 304.523394 -223.435672)
		(end 304.422048 -223.334326)
		(width 0.101346)
		(layer "F.Cu")
		(net "M_A_CPU0_SA_DQ<22>")
	)
	(segment
		(start 308.960012 -222.91421)
		(end 308.960012 -223.143318)
		(width 0.10668)
		(layer "F.Cu")
		(net "M_A_CPU0_SA_DQ<22>")
	)
	(segment
		(start 309.076852 -222.79737)
		(end 308.960012 -222.91421)
		(width 0.10668)
		(layer "F.Cu")
		(net "M_A_CPU0_SA_DQ<22>")
	)
	(segment
		(start 309.359046 -222.91421)
		(end 309.242206 -222.79737)
		(width 0.10668)
		(layer "F.Cu")
		(net "M_A_CPU0_SA_DQ<22>")
	)
	(segment
		(start 308.843172 -223.260158)
		(end 308.610508 -223.260158)
		(width 0.10668)
		(layer "F.Cu")
		(net "M_A_CPU0_SA_DQ<22>")
	)
	(segment
		(start 304.815748 -222.936308)
		(end 304.815748 -223.334326)
		(width 0.101346)
		(layer "F.Cu")
		(net "M_A_CPU0_SA_DQ<22>")
	)
	(segment
		(start 305.9938 -222.834962)
		(end 305.704494 -222.834962)
		(width 0.101346)
		(layer "F.Cu")
		(net "M_A_CPU0_SA_DQ<22>")
	)
	(segment
		(start 309.475886 -223.260158)
		(end 309.359046 -223.143318)
		(width 0.10668)
		(layer "F.Cu")
		(net "M_A_CPU0_SA_DQ<22>")
	)
	(segment
		(start 308.610508 -223.260158)
		(end 306.418996 -223.260158)
		(width 0.101346)
		(layer "F.Cu")
		(net "M_A_CPU0_SA_DQ<22>")
	)
	(segment
		(start 304.714402 -223.435672)
		(end 304.523394 -223.435672)
		(width 0.101346)
		(layer "F.Cu")
		(net "M_A_CPU0_SA_DQ<22>")
	)
	(segment
		(start 324.022974 -239.32515)
		(end 323.908674 -239.32515)
		(width 0.0762)
		(layer "F.Cu")
		(net "M_A_CPU0_SA_DQ<22>")
	)
	(segment
		(start 305.603148 -222.936308)
		(end 305.603148 -223.334326)
		(width 0.101346)
		(layer "F.Cu")
		(net "M_A_CPU0_SA_DQ<22>")
	)
	(segment
		(start 309.359046 -223.143318)
		(end 309.359046 -222.91421)
		(width 0.10668)
		(layer "F.Cu")
		(net "M_A_CPU0_SA_DQ<22>")
	)
	(segment
		(start 312.533538 -226.020376)
		(end 309.77332 -223.260158)
		(width 0.10668)
		(layer "F.Cu")
		(net "M_A_CPU0_SA_DQ<22>")
	)
	(segment
		(start 324.411594 -238.93653)
		(end 324.022974 -239.32515)
		(width 0.0762)
		(layer "F.Cu")
		(net "M_A_CPU0_SA_DQ<22>")
	)
	(segment
		(start 304.917094 -222.834962)
		(end 304.815748 -222.936308)
		(width 0.101346)
		(layer "F.Cu")
		(net "M_A_CPU0_SA_DQ<22>")
	)
	(segment
		(start 305.209448 -222.936308)
		(end 305.108102 -222.834962)
		(width 0.101346)
		(layer "F.Cu")
		(net "M_A_CPU0_SA_DQ<22>")
	)
	(segment
		(start 305.209448 -223.334326)
		(end 305.209448 -222.936308)
		(width 0.101346)
		(layer "F.Cu")
		(net "M_A_CPU0_SA_DQ<22>")
	)
	(segment
		(start 305.310794 -223.435672)
		(end 305.209448 -223.334326)
		(width 0.101346)
		(layer "F.Cu")
		(net "M_A_CPU0_SA_DQ<22>")
	)
	(segment
		(start 312.533538 -229.945946)
		(end 312.533538 -226.020376)
		(width 0.10668)
		(layer "F.Cu")
		(net "M_A_CPU0_SA_DQ<22>")
	)
	(segment
		(start 305.501802 -223.435672)
		(end 305.310794 -223.435672)
		(width 0.101346)
		(layer "F.Cu")
		(net "M_A_CPU0_SA_DQ<22>")
	)
	(segment
		(start 305.704494 -222.834962)
		(end 305.603148 -222.936308)
		(width 0.101346)
		(layer "F.Cu")
		(net "M_A_CPU0_SA_DQ<22>")
	)
	(segment
		(start 304.422048 -223.334326)
		(end 304.422048 -222.936308)
		(width 0.101346)
		(layer "F.Cu")
		(net "M_A_CPU0_SA_DQ<22>")
	)
	(segment
		(start 321.912742 -239.32515)
		(end 312.533538 -229.945946)
		(width 0.10668)
		(layer "F.Cu")
		(net "M_A_CPU0_SA_DQ<22>")
	)
	(segment
		(start 305.603148 -223.334326)
		(end 305.501802 -223.435672)
		(width 0.101346)
		(layer "F.Cu")
		(net "M_A_CPU0_SA_DQ<22>")
	)
	(segment
		(start 304.422048 -222.936308)
		(end 304.320702 -222.834962)
		(width 0.101346)
		(layer "F.Cu")
		(net "M_A_CPU0_SA_DQ<22>")
	)
	(segment
		(start 308.960012 -223.143318)
		(end 308.843172 -223.260158)
		(width 0.10668)
		(layer "F.Cu")
		(net "M_A_CPU0_SA_DQ<22>")
	)
	(arc
		(start 325.699374 -238.752634)
		(mid 325.381477 -238.889718)
		(end 325.038466 -238.93653)
		(width 0.0762)
		(layer "F.Cu")
		(net "M_A_CPU0_SA_DQ<22>")
	)
	(arc
		(start 325.9709 -238.92002)
		(mid 325.97074 -238.773459)
		(end 325.839074 -238.7092)
		(width 0.0762)
		(layer "F.Cu")
		(net "M_A_CPU0_SA_DQ<22>")
	)
	(arc
		(start 325.839074 -238.7092)
		(mid 325.767066 -238.723982)
		(end 325.699374 -238.752634)
		(width 0.0762)
		(layer "F.Cu")
		(net "M_A_CPU0_SA_DQ<22>")
	)
	(segment
		(start 311.855104 -225.974402)
		(end 311.487566 -226.34194)
		(width 0.10668)
		(layer "F.Cu")
		(net "M_A_CPU0_SA_DQ<21>")
	)
	(segment
		(start 310.641238 -225.495358)
		(end 311.008776 -225.12782)
		(width 0.10668)
		(layer "F.Cu")
		(net "M_A_CPU0_SA_DQ<21>")
	)
	(segment
		(start 311.573164 -225.692208)
		(end 311.57291 -225.541332)
		(width 0.10668)
		(layer "F.Cu")
		(net "M_A_CPU0_SA_DQ<21>")
	)
	(segment
		(start 310.726328 -224.845626)
		(end 310.35879 -225.213164)
		(width 0.10668)
		(layer "F.Cu")
		(net "M_A_CPU0_SA_DQ<21>")
	)
	(segment
		(start 309.794402 -224.648776)
		(end 309.644034 -224.64903)
		(width 0.10668)
		(layer "F.Cu")
		(net "M_A_CPU0_SA_DQ<21>")
	)
	(segment
		(start 312.137552 -226.256596)
		(end 312.137298 -226.10572)
		(width 0.10668)
		(layer "F.Cu")
		(net "M_A_CPU0_SA_DQ<21>")
	)
	(segment
		(start 311.008776 -225.12782)
		(end 311.008522 -224.976944)
		(width 0.10668)
		(layer "F.Cu")
		(net "M_A_CPU0_SA_DQ<21>")
	)
	(segment
		(start 325.044816 -239.22863)
		(end 324.556374 -239.22863)
		(width 0.0762)
		(layer "F.Cu")
		(net "M_A_CPU0_SA_DQ<21>")
	)
	(segment
		(start 310.641238 -225.646234)
		(end 310.641238 -225.495358)
		(width 0.10668)
		(layer "F.Cu")
		(net "M_A_CPU0_SA_DQ<21>")
	)
	(segment
		(start 309.079646 -224.084642)
		(end 308.680104 -223.6851)
		(width 0.10668)
		(layer "F.Cu")
		(net "M_A_CPU0_SA_DQ<21>")
	)
	(segment
		(start 311.770014 -226.624134)
		(end 312.137552 -226.256596)
		(width 0.10668)
		(layer "F.Cu")
		(net "M_A_CPU0_SA_DQ<21>")
	)
	(segment
		(start 311.770014 -226.77501)
		(end 311.770014 -226.624134)
		(width 0.10668)
		(layer "F.Cu")
		(net "M_A_CPU0_SA_DQ<21>")
	)
	(segment
		(start 321.771518 -239.66551)
		(end 312.193178 -230.08717)
		(width 0.10668)
		(layer "F.Cu")
		(net "M_A_CPU0_SA_DQ<21>")
	)
	(segment
		(start 311.337198 -226.342194)
		(end 311.205626 -226.210622)
		(width 0.10668)
		(layer "F.Cu")
		(net "M_A_CPU0_SA_DQ<21>")
	)
	(segment
		(start 310.923178 -225.777552)
		(end 310.77281 -225.777806)
		(width 0.10668)
		(layer "F.Cu")
		(net "M_A_CPU0_SA_DQ<21>")
	)
	(segment
		(start 308.680104 -223.6851)
		(end 307.368194 -223.6851)
		(width 0.10668)
		(layer "F.Cu")
		(net "M_A_CPU0_SA_DQ<21>")
	)
	(segment
		(start 311.205626 -226.210622)
		(end 311.205626 -226.059746)
		(width 0.10668)
		(layer "F.Cu")
		(net "M_A_CPU0_SA_DQ<21>")
	)
	(segment
		(start 312.137298 -226.10572)
		(end 312.00598 -225.974402)
		(width 0.10668)
		(layer "F.Cu")
		(net "M_A_CPU0_SA_DQ<21>")
	)
	(segment
		(start 310.444388 -224.563432)
		(end 310.444134 -224.412556)
		(width 0.10668)
		(layer "F.Cu")
		(net "M_A_CPU0_SA_DQ<21>")
	)
	(segment
		(start 310.35879 -225.213164)
		(end 310.208422 -225.213418)
		(width 0.10668)
		(layer "F.Cu")
		(net "M_A_CPU0_SA_DQ<21>")
	)
	(segment
		(start 310.77281 -225.777806)
		(end 310.641238 -225.646234)
		(width 0.10668)
		(layer "F.Cu")
		(net "M_A_CPU0_SA_DQ<21>")
	)
	(segment
		(start 327.004934 -239.402366)
		(end 327.004934 -239.40262)
		(width 0.0762)
		(layer "F.Cu")
		(net "M_A_CPU0_SA_DQ<21>")
	)
	(segment
		(start 310.07685 -225.081846)
		(end 310.07685 -224.93097)
		(width 0.10668)
		(layer "F.Cu")
		(net "M_A_CPU0_SA_DQ<21>")
	)
	(segment
		(start 309.512462 -224.517458)
		(end 309.512462 -224.366582)
		(width 0.10668)
		(layer "F.Cu")
		(net "M_A_CPU0_SA_DQ<21>")
	)
	(segment
		(start 309.512462 -224.366582)
		(end 309.88 -223.999044)
		(width 0.10668)
		(layer "F.Cu")
		(net "M_A_CPU0_SA_DQ<21>")
	)
	(segment
		(start 325.699374 -239.407446)
		(end 325.690992 -239.40262)
		(width 0.0762)
		(layer "F.Cu")
		(net "M_A_CPU0_SA_DQ<21>")
	)
	(segment
		(start 309.88 -223.999044)
		(end 309.879746 -223.848168)
		(width 0.10668)
		(layer "F.Cu")
		(net "M_A_CPU0_SA_DQ<21>")
	)
	(segment
		(start 309.644034 -224.64903)
		(end 309.512462 -224.517458)
		(width 0.10668)
		(layer "F.Cu")
		(net "M_A_CPU0_SA_DQ<21>")
	)
	(segment
		(start 310.312816 -224.281238)
		(end 310.16194 -224.281238)
		(width 0.10668)
		(layer "F.Cu")
		(net "M_A_CPU0_SA_DQ<21>")
	)
	(segment
		(start 323.916294 -239.66551)
		(end 321.771518 -239.66551)
		(width 0.10668)
		(layer "F.Cu")
		(net "M_A_CPU0_SA_DQ<21>")
	)
	(segment
		(start 311.441592 -225.410014)
		(end 311.290716 -225.410014)
		(width 0.10668)
		(layer "F.Cu")
		(net "M_A_CPU0_SA_DQ<21>")
	)
	(segment
		(start 312.193178 -227.198174)
		(end 311.770014 -226.77501)
		(width 0.10668)
		(layer "F.Cu")
		(net "M_A_CPU0_SA_DQ<21>")
	)
	(segment
		(start 324.119494 -239.66551)
		(end 323.916294 -239.66551)
		(width 0.0762)
		(layer "F.Cu")
		(net "M_A_CPU0_SA_DQ<21>")
	)
	(segment
		(start 309.597552 -223.71685)
		(end 309.230014 -224.084388)
		(width 0.10668)
		(layer "F.Cu")
		(net "M_A_CPU0_SA_DQ<21>")
	)
	(segment
		(start 311.008522 -224.976944)
		(end 310.877204 -224.845626)
		(width 0.10668)
		(layer "F.Cu")
		(net "M_A_CPU0_SA_DQ<21>")
	)
	(segment
		(start 309.879746 -223.848168)
		(end 309.748428 -223.71685)
		(width 0.10668)
		(layer "F.Cu")
		(net "M_A_CPU0_SA_DQ<21>")
	)
	(segment
		(start 311.487566 -226.34194)
		(end 311.337198 -226.342194)
		(width 0.10668)
		(layer "F.Cu")
		(net "M_A_CPU0_SA_DQ<21>")
	)
	(segment
		(start 310.16194 -224.281238)
		(end 309.794402 -224.648776)
		(width 0.10668)
		(layer "F.Cu")
		(net "M_A_CPU0_SA_DQ<21>")
	)
	(segment
		(start 324.556374 -239.22863)
		(end 324.119494 -239.66551)
		(width 0.0762)
		(layer "F.Cu")
		(net "M_A_CPU0_SA_DQ<21>")
	)
	(segment
		(start 311.205626 -226.059746)
		(end 311.573164 -225.692208)
		(width 0.10668)
		(layer "F.Cu")
		(net "M_A_CPU0_SA_DQ<21>")
	)
	(segment
		(start 309.748428 -223.71685)
		(end 309.597552 -223.71685)
		(width 0.10668)
		(layer "F.Cu")
		(net "M_A_CPU0_SA_DQ<21>")
	)
	(segment
		(start 310.208422 -225.213418)
		(end 310.07685 -225.081846)
		(width 0.10668)
		(layer "F.Cu")
		(net "M_A_CPU0_SA_DQ<21>")
	)
	(segment
		(start 312.193178 -230.08717)
		(end 312.193178 -227.198174)
		(width 0.10668)
		(layer "F.Cu")
		(net "M_A_CPU0_SA_DQ<21>")
	)
	(segment
		(start 309.230014 -224.084388)
		(end 309.079646 -224.084642)
		(width 0.10668)
		(layer "F.Cu")
		(net "M_A_CPU0_SA_DQ<21>")
	)
	(segment
		(start 311.57291 -225.541332)
		(end 311.441592 -225.410014)
		(width 0.10668)
		(layer "F.Cu")
		(net "M_A_CPU0_SA_DQ<21>")
	)
	(segment
		(start 310.877204 -224.845626)
		(end 310.726328 -224.845626)
		(width 0.10668)
		(layer "F.Cu")
		(net "M_A_CPU0_SA_DQ<21>")
	)
	(segment
		(start 312.00598 -225.974402)
		(end 311.855104 -225.974402)
		(width 0.10668)
		(layer "F.Cu")
		(net "M_A_CPU0_SA_DQ<21>")
	)
	(segment
		(start 310.444134 -224.412556)
		(end 310.312816 -224.281238)
		(width 0.10668)
		(layer "F.Cu")
		(net "M_A_CPU0_SA_DQ<21>")
	)
	(segment
		(start 310.07685 -224.93097)
		(end 310.444388 -224.563432)
		(width 0.10668)
		(layer "F.Cu")
		(net "M_A_CPU0_SA_DQ<21>")
	)
	(segment
		(start 311.290716 -225.410014)
		(end 310.923178 -225.777552)
		(width 0.10668)
		(layer "F.Cu")
		(net "M_A_CPU0_SA_DQ<21>")
	)
	(arc
		(start 326.065134 -239.40262)
		(mid 325.882883 -239.45297)
		(end 325.699374 -239.407446)
		(width 0.0762)
		(layer "F.Cu")
		(net "M_A_CPU0_SA_DQ<21>")
	)
	(arc
		(start 327.004934 -239.40262)
		(mid 326.81799 -239.452875)
		(end 326.631046 -239.40262)
		(width 0.0762)
		(layer "F.Cu")
		(net "M_A_CPU0_SA_DQ<21>")
	)
	(arc
		(start 325.690992 -239.40262)
		(mid 325.379418 -239.27285)
		(end 325.044816 -239.22863)
		(width 0.0762)
		(layer "F.Cu")
		(net "M_A_CPU0_SA_DQ<21>")
	)
	(arc
		(start 327.758044 -239.08004)
		(mid 327.554028 -239.260734)
		(end 327.289414 -239.325912)
		(width 0.0762)
		(layer "F.Cu")
		(net "M_A_CPU0_SA_DQ<21>")
	)
	(arc
		(start 326.631046 -239.40262)
		(mid 326.34809 -239.326443)
		(end 326.065134 -239.40262)
		(width 0.0762)
		(layer "F.Cu")
		(net "M_A_CPU0_SA_DQ<21>")
	)
	(arc
		(start 327.289414 -239.325912)
		(mid 327.142093 -239.345231)
		(end 327.004934 -239.402366)
		(width 0.0762)
		(layer "F.Cu")
		(net "M_A_CPU0_SA_DQ<21>")
	)
	(segment
		(start 312.797444 -224.837498)
		(end 312.666126 -224.70618)
		(width 0.10668)
		(layer "F.Cu")
		(net "M_A_CPU0_SA_DQ<20>")
	)
	(segment
		(start 309.69331 -221.88424)
		(end 309.361586 -222.215964)
		(width 0.10668)
		(layer "F.Cu")
		(net "M_A_CPU0_SA_DQ<20>")
	)
	(segment
		(start 311.619138 -224.473516)
		(end 311.468262 -224.473516)
		(width 0.10668)
		(layer "F.Cu")
		(net "M_A_CPU0_SA_DQ<20>")
	)
	(segment
		(start 312.51525 -224.70618)
		(end 312.183526 -225.037904)
		(width 0.10668)
		(layer "F.Cu")
		(net "M_A_CPU0_SA_DQ<20>")
	)
	(segment
		(start 325.374 -238.65205)
		(end 324.182994 -238.65205)
		(width 0.0762)
		(layer "F.Cu")
		(net "M_A_CPU0_SA_DQ<20>")
	)
	(segment
		(start 310.339486 -223.34474)
		(end 310.208168 -223.213422)
		(width 0.10668)
		(layer "F.Cu")
		(net "M_A_CPU0_SA_DQ<20>")
	)
	(segment
		(start 312.46572 -225.320098)
		(end 312.797444 -224.988374)
		(width 0.10668)
		(layer "F.Cu")
		(net "M_A_CPU0_SA_DQ<20>")
	)
	(segment
		(start 312.03265 -225.037904)
		(end 311.901332 -224.906586)
		(width 0.10668)
		(layer "F.Cu")
		(net "M_A_CPU0_SA_DQ<20>")
	)
	(segment
		(start 310.539892 -222.730822)
		(end 310.539892 -222.579946)
		(width 0.10668)
		(layer "F.Cu")
		(net "M_A_CPU0_SA_DQ<20>")
	)
	(segment
		(start 311.668668 -223.859598)
		(end 311.668668 -223.708722)
		(width 0.10668)
		(layer "F.Cu")
		(net "M_A_CPU0_SA_DQ<20>")
	)
	(segment
		(start 310.490362 -223.34474)
		(end 310.339486 -223.34474)
		(width 0.10668)
		(layer "F.Cu")
		(net "M_A_CPU0_SA_DQ<20>")
	)
	(segment
		(start 309.975504 -222.015558)
		(end 309.844186 -221.88424)
		(width 0.10668)
		(layer "F.Cu")
		(net "M_A_CPU0_SA_DQ<20>")
	)
	(segment
		(start 310.408574 -222.448628)
		(end 310.257698 -222.448628)
		(width 0.10668)
		(layer "F.Cu")
		(net "M_A_CPU0_SA_DQ<20>")
	)
	(segment
		(start 311.386474 -223.577404)
		(end 311.05475 -223.909128)
		(width 0.10668)
		(layer "F.Cu")
		(net "M_A_CPU0_SA_DQ<20>")
	)
	(segment
		(start 324.182994 -238.65205)
		(end 323.870574 -238.96447)
		(width 0.0762)
		(layer "F.Cu")
		(net "M_A_CPU0_SA_DQ<20>")
	)
	(segment
		(start 310.208168 -223.062546)
		(end 310.539892 -222.730822)
		(width 0.10668)
		(layer "F.Cu")
		(net "M_A_CPU0_SA_DQ<20>")
	)
	(segment
		(start 312.101738 -224.141792)
		(end 311.950862 -224.141792)
		(width 0.10668)
		(layer "F.Cu")
		(net "M_A_CPU0_SA_DQ<20>")
	)
	(segment
		(start 310.772556 -223.77781)
		(end 310.772556 -223.626934)
		(width 0.10668)
		(layer "F.Cu")
		(net "M_A_CPU0_SA_DQ<20>")
	)
	(segment
		(start 312.666126 -224.70618)
		(end 312.51525 -224.70618)
		(width 0.10668)
		(layer "F.Cu")
		(net "M_A_CPU0_SA_DQ<20>")
	)
	(segment
		(start 309.361586 -222.215964)
		(end 309.21071 -222.215964)
		(width 0.10668)
		(layer "F.Cu")
		(net "M_A_CPU0_SA_DQ<20>")
	)
	(segment
		(start 311.10428 -223.29521)
		(end 311.10428 -223.144334)
		(width 0.10668)
		(layer "F.Cu")
		(net "M_A_CPU0_SA_DQ<20>")
	)
	(segment
		(start 312.873898 -229.804722)
		(end 312.873898 -225.879152)
		(width 0.10668)
		(layer "F.Cu")
		(net "M_A_CPU0_SA_DQ<20>")
	)
	(segment
		(start 310.772556 -223.626934)
		(end 311.10428 -223.29521)
		(width 0.10668)
		(layer "F.Cu")
		(net "M_A_CPU0_SA_DQ<20>")
	)
	(segment
		(start 309.64378 -222.649034)
		(end 309.64378 -222.498158)
		(width 0.10668)
		(layer "F.Cu")
		(net "M_A_CPU0_SA_DQ<20>")
	)
	(segment
		(start 322.033646 -238.96447)
		(end 312.873898 -229.804722)
		(width 0.10668)
		(layer "F.Cu")
		(net "M_A_CPU0_SA_DQ<20>")
	)
	(segment
		(start 308.979824 -221.985078)
		(end 307.368194 -221.985078)
		(width 0.10668)
		(layer "F.Cu")
		(net "M_A_CPU0_SA_DQ<20>")
	)
	(segment
		(start 312.183526 -225.037904)
		(end 312.03265 -225.037904)
		(width 0.10668)
		(layer "F.Cu")
		(net "M_A_CPU0_SA_DQ<20>")
	)
	(segment
		(start 311.668668 -223.708722)
		(end 311.53735 -223.577404)
		(width 0.10668)
		(layer "F.Cu")
		(net "M_A_CPU0_SA_DQ<20>")
	)
	(segment
		(start 310.822086 -223.013016)
		(end 310.490362 -223.34474)
		(width 0.10668)
		(layer "F.Cu")
		(net "M_A_CPU0_SA_DQ<20>")
	)
	(segment
		(start 311.901332 -224.75571)
		(end 312.233056 -224.423986)
		(width 0.10668)
		(layer "F.Cu")
		(net "M_A_CPU0_SA_DQ<20>")
	)
	(segment
		(start 310.208168 -223.213422)
		(end 310.208168 -223.062546)
		(width 0.10668)
		(layer "F.Cu")
		(net "M_A_CPU0_SA_DQ<20>")
	)
	(segment
		(start 312.873898 -225.879152)
		(end 312.46572 -225.470974)
		(width 0.10668)
		(layer "F.Cu")
		(net "M_A_CPU0_SA_DQ<20>")
	)
	(segment
		(start 311.468262 -224.473516)
		(end 311.336944 -224.342198)
		(width 0.10668)
		(layer "F.Cu")
		(net "M_A_CPU0_SA_DQ<20>")
	)
	(segment
		(start 309.975504 -222.166434)
		(end 309.975504 -222.015558)
		(width 0.10668)
		(layer "F.Cu")
		(net "M_A_CPU0_SA_DQ<20>")
	)
	(segment
		(start 312.233056 -224.423986)
		(end 312.233056 -224.27311)
		(width 0.10668)
		(layer "F.Cu")
		(net "M_A_CPU0_SA_DQ<20>")
	)
	(segment
		(start 311.53735 -223.577404)
		(end 311.386474 -223.577404)
		(width 0.10668)
		(layer "F.Cu")
		(net "M_A_CPU0_SA_DQ<20>")
	)
	(segment
		(start 311.05475 -223.909128)
		(end 310.903874 -223.909128)
		(width 0.10668)
		(layer "F.Cu")
		(net "M_A_CPU0_SA_DQ<20>")
	)
	(segment
		(start 309.64378 -222.498158)
		(end 309.975504 -222.166434)
		(width 0.10668)
		(layer "F.Cu")
		(net "M_A_CPU0_SA_DQ<20>")
	)
	(segment
		(start 310.903874 -223.909128)
		(end 310.772556 -223.77781)
		(width 0.10668)
		(layer "F.Cu")
		(net "M_A_CPU0_SA_DQ<20>")
	)
	(segment
		(start 311.10428 -223.144334)
		(end 310.972962 -223.013016)
		(width 0.10668)
		(layer "F.Cu")
		(net "M_A_CPU0_SA_DQ<20>")
	)
	(segment
		(start 309.21071 -222.215964)
		(end 308.979824 -221.985078)
		(width 0.10668)
		(layer "F.Cu")
		(net "M_A_CPU0_SA_DQ<20>")
	)
	(segment
		(start 309.775098 -222.780352)
		(end 309.64378 -222.649034)
		(width 0.10668)
		(layer "F.Cu")
		(net "M_A_CPU0_SA_DQ<20>")
	)
	(segment
		(start 309.925974 -222.780352)
		(end 309.775098 -222.780352)
		(width 0.10668)
		(layer "F.Cu")
		(net "M_A_CPU0_SA_DQ<20>")
	)
	(segment
		(start 312.46572 -225.470974)
		(end 312.46572 -225.320098)
		(width 0.10668)
		(layer "F.Cu")
		(net "M_A_CPU0_SA_DQ<20>")
	)
	(segment
		(start 311.336944 -224.191322)
		(end 311.668668 -223.859598)
		(width 0.10668)
		(layer "F.Cu")
		(net "M_A_CPU0_SA_DQ<20>")
	)
	(segment
		(start 311.950862 -224.141792)
		(end 311.619138 -224.473516)
		(width 0.10668)
		(layer "F.Cu")
		(net "M_A_CPU0_SA_DQ<20>")
	)
	(segment
		(start 312.233056 -224.27311)
		(end 312.101738 -224.141792)
		(width 0.10668)
		(layer "F.Cu")
		(net "M_A_CPU0_SA_DQ<20>")
	)
	(segment
		(start 311.336944 -224.342198)
		(end 311.336944 -224.191322)
		(width 0.10668)
		(layer "F.Cu")
		(net "M_A_CPU0_SA_DQ<20>")
	)
	(segment
		(start 312.797444 -224.988374)
		(end 312.797444 -224.837498)
		(width 0.10668)
		(layer "F.Cu")
		(net "M_A_CPU0_SA_DQ<20>")
	)
	(segment
		(start 323.870574 -238.96447)
		(end 322.033646 -238.96447)
		(width 0.10668)
		(layer "F.Cu")
		(net "M_A_CPU0_SA_DQ<20>")
	)
	(segment
		(start 310.539892 -222.579946)
		(end 310.408574 -222.448628)
		(width 0.10668)
		(layer "F.Cu")
		(net "M_A_CPU0_SA_DQ<20>")
	)
	(segment
		(start 310.972962 -223.013016)
		(end 310.822086 -223.013016)
		(width 0.10668)
		(layer "F.Cu")
		(net "M_A_CPU0_SA_DQ<20>")
	)
	(segment
		(start 310.257698 -222.448628)
		(end 309.925974 -222.780352)
		(width 0.10668)
		(layer "F.Cu")
		(net "M_A_CPU0_SA_DQ<20>")
	)
	(segment
		(start 309.844186 -221.88424)
		(end 309.69331 -221.88424)
		(width 0.10668)
		(layer "F.Cu")
		(net "M_A_CPU0_SA_DQ<20>")
	)
	(segment
		(start 311.901332 -224.906586)
		(end 311.901332 -224.75571)
		(width 0.10668)
		(layer "F.Cu")
		(net "M_A_CPU0_SA_DQ<20>")
	)
	(arc
		(start 325.830438 -238.518192)
		(mid 325.708582 -238.542348)
		(end 325.59498 -238.592614)
		(width 0.0762)
		(layer "F.Cu")
		(net "M_A_CPU0_SA_DQ<20>")
	)
	(arc
		(start 326.34809 -238.270034)
		(mid 326.111962 -238.441469)
		(end 325.830438 -238.518192)
		(width 0.0762)
		(layer "F.Cu")
		(net "M_A_CPU0_SA_DQ<20>")
	)
	(arc
		(start 325.59498 -238.592614)
		(mid 325.488418 -238.636939)
		(end 325.374 -238.65205)
		(width 0.0762)
		(layer "F.Cu")
		(net "M_A_CPU0_SA_DQ<20>")
	)
	(segment
		(start 311.286906 -201.90968)
		(end 311.286906 -201.758804)
		(width 0.10668)
		(layer "F.Cu")
		(net "M_A_CPU0_SA_DQ<1>")
	)
	(segment
		(start 324.884034 -226.03333)
		(end 324.572376 -225.721672)
		(width 0.0762)
		(layer "F.Cu")
		(net "M_A_CPU0_SA_DQ<1>")
	)
	(segment
		(start 310.818276 -200.947782)
		(end 310.686958 -200.816464)
		(width 0.10668)
		(layer "F.Cu")
		(net "M_A_CPU0_SA_DQ<1>")
	)
	(segment
		(start 310.253888 -200.383394)
		(end 310.12257 -200.252076)
		(width 0.10668)
		(layer "F.Cu")
		(net "M_A_CPU0_SA_DQ<1>")
	)
	(segment
		(start 324.572376 -225.721672)
		(end 323.874638 -225.023934)
		(width 0.10668)
		(layer "F.Cu")
		(net "M_A_CPU0_SA_DQ<1>")
	)
	(segment
		(start 309.72506 -200.347834)
		(end 309.593742 -200.216516)
		(width 0.10668)
		(layer "F.Cu")
		(net "M_A_CPU0_SA_DQ<1>")
	)
	(segment
		(start 323.874638 -214.507064)
		(end 311.851294 -202.48372)
		(width 0.10668)
		(layer "F.Cu")
		(net "M_A_CPU0_SA_DQ<1>")
	)
	(segment
		(start 311.851294 -202.323192)
		(end 311.947052 -202.227434)
		(width 0.10668)
		(layer "F.Cu")
		(net "M_A_CPU0_SA_DQ<1>")
	)
	(segment
		(start 325.263764 -226.03333)
		(end 324.884034 -226.03333)
		(width 0.0762)
		(layer "F.Cu")
		(net "M_A_CPU0_SA_DQ<1>")
	)
	(segment
		(start 311.5691 -202.040998)
		(end 311.418224 -202.040998)
		(width 0.10668)
		(layer "F.Cu")
		(net "M_A_CPU0_SA_DQ<1>")
	)
	(segment
		(start 309.029354 -199.501252)
		(end 309.125112 -199.405494)
		(width 0.10668)
		(layer "F.Cu")
		(net "M_A_CPU0_SA_DQ<1>")
	)
	(segment
		(start 310.686958 -200.816464)
		(end 310.536082 -200.816464)
		(width 0.10668)
		(layer "F.Cu")
		(net "M_A_CPU0_SA_DQ<1>")
	)
	(segment
		(start 325.614284 -226.38385)
		(end 325.263764 -226.03333)
		(width 0.0762)
		(layer "F.Cu")
		(net "M_A_CPU0_SA_DQ<1>")
	)
	(segment
		(start 309.558182 -199.687688)
		(end 309.407306 -199.687688)
		(width 0.10668)
		(layer "F.Cu")
		(net "M_A_CPU0_SA_DQ<1>")
	)
	(segment
		(start 310.15813 -200.630028)
		(end 310.253888 -200.53427)
		(width 0.10668)
		(layer "F.Cu")
		(net "M_A_CPU0_SA_DQ<1>")
	)
	(segment
		(start 309.125112 -199.405494)
		(end 309.125112 -199.254618)
		(width 0.10668)
		(layer "F.Cu")
		(net "M_A_CPU0_SA_DQ<1>")
	)
	(segment
		(start 309.6895 -199.819006)
		(end 309.558182 -199.687688)
		(width 0.10668)
		(layer "F.Cu")
		(net "M_A_CPU0_SA_DQ<1>")
	)
	(segment
		(start 309.311548 -199.783446)
		(end 309.160672 -199.783446)
		(width 0.10668)
		(layer "F.Cu")
		(net "M_A_CPU0_SA_DQ<1>")
	)
	(segment
		(start 310.722518 -201.345292)
		(end 310.722518 -201.194416)
		(width 0.10668)
		(layer "F.Cu")
		(net "M_A_CPU0_SA_DQ<1>")
	)
	(segment
		(start 309.407306 -199.687688)
		(end 309.311548 -199.783446)
		(width 0.10668)
		(layer "F.Cu")
		(net "M_A_CPU0_SA_DQ<1>")
	)
	(segment
		(start 311.382664 -201.663046)
		(end 311.382664 -201.51217)
		(width 0.10668)
		(layer "F.Cu")
		(net "M_A_CPU0_SA_DQ<1>")
	)
	(segment
		(start 309.125112 -199.254618)
		(end 308.905656 -199.035162)
		(width 0.10668)
		(layer "F.Cu")
		(net "M_A_CPU0_SA_DQ<1>")
	)
	(segment
		(start 310.722518 -201.194416)
		(end 310.818276 -201.098658)
		(width 0.10668)
		(layer "F.Cu")
		(net "M_A_CPU0_SA_DQ<1>")
	)
	(segment
		(start 311.664858 -201.94524)
		(end 311.5691 -202.040998)
		(width 0.10668)
		(layer "F.Cu")
		(net "M_A_CPU0_SA_DQ<1>")
	)
	(segment
		(start 309.029354 -199.652128)
		(end 309.029354 -199.501252)
		(width 0.10668)
		(layer "F.Cu")
		(net "M_A_CPU0_SA_DQ<1>")
	)
	(segment
		(start 311.286906 -201.758804)
		(end 311.382664 -201.663046)
		(width 0.10668)
		(layer "F.Cu")
		(net "M_A_CPU0_SA_DQ<1>")
	)
	(segment
		(start 311.851294 -202.48372)
		(end 311.851294 -202.323192)
		(width 0.10668)
		(layer "F.Cu")
		(net "M_A_CPU0_SA_DQ<1>")
	)
	(segment
		(start 310.12257 -200.252076)
		(end 309.971694 -200.252076)
		(width 0.10668)
		(layer "F.Cu")
		(net "M_A_CPU0_SA_DQ<1>")
	)
	(segment
		(start 310.15813 -200.780904)
		(end 310.15813 -200.630028)
		(width 0.10668)
		(layer "F.Cu")
		(net "M_A_CPU0_SA_DQ<1>")
	)
	(segment
		(start 310.253888 -200.53427)
		(end 310.253888 -200.383394)
		(width 0.10668)
		(layer "F.Cu")
		(net "M_A_CPU0_SA_DQ<1>")
	)
	(segment
		(start 311.251346 -201.380852)
		(end 311.10047 -201.380852)
		(width 0.10668)
		(layer "F.Cu")
		(net "M_A_CPU0_SA_DQ<1>")
	)
	(segment
		(start 310.818276 -201.098658)
		(end 310.818276 -200.947782)
		(width 0.10668)
		(layer "F.Cu")
		(net "M_A_CPU0_SA_DQ<1>")
	)
	(segment
		(start 309.160672 -199.783446)
		(end 309.029354 -199.652128)
		(width 0.10668)
		(layer "F.Cu")
		(net "M_A_CPU0_SA_DQ<1>")
	)
	(segment
		(start 323.874638 -225.023934)
		(end 323.874638 -214.507064)
		(width 0.10668)
		(layer "F.Cu")
		(net "M_A_CPU0_SA_DQ<1>")
	)
	(segment
		(start 310.536082 -200.816464)
		(end 310.440324 -200.912222)
		(width 0.10668)
		(layer "F.Cu")
		(net "M_A_CPU0_SA_DQ<1>")
	)
	(segment
		(start 309.971694 -200.252076)
		(end 309.875936 -200.347834)
		(width 0.10668)
		(layer "F.Cu")
		(net "M_A_CPU0_SA_DQ<1>")
	)
	(segment
		(start 311.815734 -201.94524)
		(end 311.664858 -201.94524)
		(width 0.10668)
		(layer "F.Cu")
		(net "M_A_CPU0_SA_DQ<1>")
	)
	(segment
		(start 310.853836 -201.47661)
		(end 310.722518 -201.345292)
		(width 0.10668)
		(layer "F.Cu")
		(net "M_A_CPU0_SA_DQ<1>")
	)
	(segment
		(start 311.10047 -201.380852)
		(end 311.004712 -201.47661)
		(width 0.10668)
		(layer "F.Cu")
		(net "M_A_CPU0_SA_DQ<1>")
	)
	(segment
		(start 308.905656 -199.035162)
		(end 307.368194 -199.035162)
		(width 0.10668)
		(layer "F.Cu")
		(net "M_A_CPU0_SA_DQ<1>")
	)
	(segment
		(start 311.418224 -202.040998)
		(end 311.286906 -201.90968)
		(width 0.10668)
		(layer "F.Cu")
		(net "M_A_CPU0_SA_DQ<1>")
	)
	(segment
		(start 311.382664 -201.51217)
		(end 311.251346 -201.380852)
		(width 0.10668)
		(layer "F.Cu")
		(net "M_A_CPU0_SA_DQ<1>")
	)
	(segment
		(start 311.004712 -201.47661)
		(end 310.853836 -201.47661)
		(width 0.10668)
		(layer "F.Cu")
		(net "M_A_CPU0_SA_DQ<1>")
	)
	(segment
		(start 310.440324 -200.912222)
		(end 310.289448 -200.912222)
		(width 0.10668)
		(layer "F.Cu")
		(net "M_A_CPU0_SA_DQ<1>")
	)
	(segment
		(start 311.947052 -202.227434)
		(end 311.947052 -202.076558)
		(width 0.10668)
		(layer "F.Cu")
		(net "M_A_CPU0_SA_DQ<1>")
	)
	(segment
		(start 310.289448 -200.912222)
		(end 310.15813 -200.780904)
		(width 0.10668)
		(layer "F.Cu")
		(net "M_A_CPU0_SA_DQ<1>")
	)
	(segment
		(start 309.875936 -200.347834)
		(end 309.72506 -200.347834)
		(width 0.10668)
		(layer "F.Cu")
		(net "M_A_CPU0_SA_DQ<1>")
	)
	(segment
		(start 309.593742 -200.216516)
		(end 309.593742 -200.06564)
		(width 0.10668)
		(layer "F.Cu")
		(net "M_A_CPU0_SA_DQ<1>")
	)
	(segment
		(start 309.593742 -200.06564)
		(end 309.6895 -199.969882)
		(width 0.10668)
		(layer "F.Cu")
		(net "M_A_CPU0_SA_DQ<1>")
	)
	(segment
		(start 311.947052 -202.076558)
		(end 311.815734 -201.94524)
		(width 0.10668)
		(layer "F.Cu")
		(net "M_A_CPU0_SA_DQ<1>")
	)
	(segment
		(start 309.6895 -199.969882)
		(end 309.6895 -199.819006)
		(width 0.10668)
		(layer "F.Cu")
		(net "M_A_CPU0_SA_DQ<1>")
	)
	(arc
		(start 327.004934 -226.442778)
		(mid 326.81799 -226.493033)
		(end 326.631046 -226.442778)
		(width 0.0762)
		(layer "F.Cu")
		(net "M_A_CPU0_SA_DQ<1>")
	)
	(arc
		(start 326.065134 -226.442778)
		(mid 325.829665 -226.490023)
		(end 325.614284 -226.38385)
		(width 0.0762)
		(layer "F.Cu")
		(net "M_A_CPU0_SA_DQ<1>")
	)
	(arc
		(start 327.279 -226.366578)
		(mid 327.137087 -226.38712)
		(end 327.004934 -226.442778)
		(width 0.0762)
		(layer "F.Cu")
		(net "M_A_CPU0_SA_DQ<1>")
	)
	(arc
		(start 326.631046 -226.442778)
		(mid 326.34809 -226.366601)
		(end 326.065134 -226.442778)
		(width 0.0762)
		(layer "F.Cu")
		(net "M_A_CPU0_SA_DQ<1>")
	)
	(arc
		(start 327.758044 -226.120198)
		(mid 327.548333 -226.301336)
		(end 327.279 -226.366578)
		(width 0.0762)
		(layer "F.Cu")
		(net "M_A_CPU0_SA_DQ<1>")
	)
	(segment
		(start 324.142354 -236.68609)
		(end 323.875654 -236.68609)
		(width 0.0762)
		(layer "F.Cu")
		(net "M_A_CPU0_SA_DQ<19>")
	)
	(segment
		(start 310.346852 -219.01023)
		(end 308.28488 -219.01023)
		(width 0.10668)
		(layer "F.Cu")
		(net "M_A_CPU0_SA_DQ<19>")
	)
	(segment
		(start 327.28789 -236.649768)
		(end 327.393046 -236.46892)
		(width 0.0762)
		(layer "F.Cu")
		(net "M_A_CPU0_SA_DQ<19>")
	)
	(segment
		(start 305.74488 -219.01023)
		(end 305.587654 -218.853004)
		(width 0.101346)
		(layer "F.Cu")
		(net "M_A_CPU0_SA_DQ<19>")
	)
	(segment
		(start 327.28789 -236.650022)
		(end 327.28789 -236.649768)
		(width 0.0762)
		(layer "F.Cu")
		(net "M_A_CPU0_SA_DQ<19>")
	)
	(segment
		(start 327.108312 -236.323124)
		(end 327.100946 -236.327442)
		(width 0.0762)
		(layer "F.Cu")
		(net "M_A_CPU0_SA_DQ<19>")
	)
	(segment
		(start 314.761118 -222.167196)
		(end 312.492644 -219.898722)
		(width 0.10668)
		(layer "F.Cu")
		(net "M_A_CPU0_SA_DQ<19>")
	)
	(segment
		(start 327.109328 -236.322616)
		(end 327.108312 -236.323124)
		(width 0.0762)
		(layer "F.Cu")
		(net "M_A_CPU0_SA_DQ<19>")
	)
	(segment
		(start 308.28488 -219.01023)
		(end 305.74488 -219.01023)
		(width 0.101346)
		(layer "F.Cu")
		(net "M_A_CPU0_SA_DQ<19>")
	)
	(segment
		(start 314.761118 -228.976682)
		(end 314.761118 -222.167196)
		(width 0.10668)
		(layer "F.Cu")
		(net "M_A_CPU0_SA_DQ<19>")
	)
	(segment
		(start 326.535034 -236.327442)
		(end 326.526652 -236.322616)
		(width 0.0762)
		(layer "F.Cu")
		(net "M_A_CPU0_SA_DQ<19>")
	)
	(segment
		(start 322.470526 -236.68609)
		(end 314.761118 -228.976682)
		(width 0.10668)
		(layer "F.Cu")
		(net "M_A_CPU0_SA_DQ<19>")
	)
	(segment
		(start 323.875654 -236.68609)
		(end 322.470526 -236.68609)
		(width 0.10668)
		(layer "F.Cu")
		(net "M_A_CPU0_SA_DQ<19>")
	)
	(segment
		(start 312.492644 -219.898722)
		(end 310.346852 -219.01023)
		(width 0.10668)
		(layer "F.Cu")
		(net "M_A_CPU0_SA_DQ<19>")
	)
	(segment
		(start 304.940716 -218.585034)
		(end 303.268126 -218.585034)
		(width 0.101346)
		(layer "F.Cu")
		(net "M_A_CPU0_SA_DQ<19>")
	)
	(segment
		(start 305.587654 -218.853004)
		(end 304.940716 -218.585034)
		(width 0.101346)
		(layer "F.Cu")
		(net "M_A_CPU0_SA_DQ<19>")
	)
	(segment
		(start 324.556374 -236.27207)
		(end 324.142354 -236.68609)
		(width 0.0762)
		(layer "F.Cu")
		(net "M_A_CPU0_SA_DQ<19>")
	)
	(segment
		(start 325.389494 -236.27207)
		(end 324.556374 -236.27207)
		(width 0.0762)
		(layer "F.Cu")
		(net "M_A_CPU0_SA_DQ<19>")
	)
	(arc
		(start 327.100946 -236.327442)
		(mid 326.81799 -236.403619)
		(end 326.535034 -236.327442)
		(width 0.0762)
		(layer "F.Cu")
		(net "M_A_CPU0_SA_DQ<19>")
	)
	(arc
		(start 325.59498 -236.327442)
		(mid 325.495907 -236.286128)
		(end 325.389494 -236.27207)
		(width 0.0762)
		(layer "F.Cu")
		(net "M_A_CPU0_SA_DQ<19>")
	)
	(arc
		(start 326.160892 -236.327442)
		(mid 325.877936 -236.403619)
		(end 325.59498 -236.327442)
		(width 0.0762)
		(layer "F.Cu")
		(net "M_A_CPU0_SA_DQ<19>")
	)
	(arc
		(start 327.289414 -236.27715)
		(mid 327.19649 -236.288473)
		(end 327.109328 -236.322616)
		(width 0.0762)
		(layer "F.Cu")
		(net "M_A_CPU0_SA_DQ<19>")
	)
	(arc
		(start 326.526652 -236.322616)
		(mid 326.343144 -236.277122)
		(end 326.160892 -236.327442)
		(width 0.0762)
		(layer "F.Cu")
		(net "M_A_CPU0_SA_DQ<19>")
	)
	(arc
		(start 327.393046 -236.46892)
		(mid 327.384109 -236.349896)
		(end 327.289414 -236.27715)
		(width 0.0762)
		(layer "F.Cu")
		(net "M_A_CPU0_SA_DQ<19>")
	)
	(segment
		(start 308.610508 -217.310208)
		(end 306.070508 -217.310208)
		(width 0.101346)
		(layer "F.Cu")
		(net "M_A_CPU0_SA_DQ<18>")
	)
	(segment
		(start 305.645312 -216.885012)
		(end 303.268126 -216.885012)
		(width 0.101346)
		(layer "F.Cu")
		(net "M_A_CPU0_SA_DQ<18>")
	)
	(segment
		(start 311.203086 -217.310208)
		(end 308.610508 -217.310208)
		(width 0.10668)
		(layer "F.Cu")
		(net "M_A_CPU0_SA_DQ<18>")
	)
	(segment
		(start 315.441838 -221.54896)
		(end 311.203086 -217.310208)
		(width 0.10668)
		(layer "F.Cu")
		(net "M_A_CPU0_SA_DQ<18>")
	)
	(segment
		(start 315.441838 -228.694234)
		(end 315.441838 -221.54896)
		(width 0.10668)
		(layer "F.Cu")
		(net "M_A_CPU0_SA_DQ<18>")
	)
	(segment
		(start 324.403974 -235.65485)
		(end 324.089014 -235.96981)
		(width 0.0762)
		(layer "F.Cu")
		(net "M_A_CPU0_SA_DQ<18>")
	)
	(segment
		(start 306.070508 -217.310208)
		(end 305.645312 -216.885012)
		(width 0.101346)
		(layer "F.Cu")
		(net "M_A_CPU0_SA_DQ<18>")
	)
	(segment
		(start 322.717414 -235.96981)
		(end 315.441838 -228.694234)
		(width 0.10668)
		(layer "F.Cu")
		(net "M_A_CPU0_SA_DQ<18>")
	)
	(segment
		(start 325.877936 -235.840016)
		(end 325.9709 -235.679996)
		(width 0.0762)
		(layer "F.Cu")
		(net "M_A_CPU0_SA_DQ<18>")
	)
	(segment
		(start 324.089014 -235.96981)
		(end 323.885814 -235.96981)
		(width 0.0762)
		(layer "F.Cu")
		(net "M_A_CPU0_SA_DQ<18>")
	)
	(segment
		(start 325.699374 -235.51261)
		(end 325.690992 -235.517436)
		(width 0.0762)
		(layer "F.Cu")
		(net "M_A_CPU0_SA_DQ<18>")
	)
	(segment
		(start 323.885814 -235.96981)
		(end 322.717414 -235.96981)
		(width 0.10668)
		(layer "F.Cu")
		(net "M_A_CPU0_SA_DQ<18>")
	)
	(segment
		(start 325.180706 -235.65485)
		(end 324.403974 -235.65485)
		(width 0.0762)
		(layer "F.Cu")
		(net "M_A_CPU0_SA_DQ<18>")
	)
	(arc
		(start 325.839074 -235.469176)
		(mid 325.767066 -235.483958)
		(end 325.699374 -235.51261)
		(width 0.0762)
		(layer "F.Cu")
		(net "M_A_CPU0_SA_DQ<18>")
	)
	(arc
		(start 325.690992 -235.517436)
		(mid 325.444946 -235.619938)
		(end 325.180706 -235.65485)
		(width 0.0762)
		(layer "F.Cu")
		(net "M_A_CPU0_SA_DQ<18>")
	)
	(arc
		(start 325.9709 -235.679996)
		(mid 325.97074 -235.533435)
		(end 325.839074 -235.469176)
		(width 0.0762)
		(layer "F.Cu")
		(net "M_A_CPU0_SA_DQ<18>")
	)
	(segment
		(start 309.97398 -218.576652)
		(end 309.8673 -218.469972)
		(width 0.10668)
		(layer "F.Cu")
		(net "M_A_CPU0_SA_DQ<17>")
	)
	(segment
		(start 310.266334 -218.469972)
		(end 310.159654 -218.576652)
		(width 0.10668)
		(layer "F.Cu")
		(net "M_A_CPU0_SA_DQ<17>")
	)
	(segment
		(start 327.004934 -236.162342)
		(end 327.004934 -236.162596)
		(width 0.0762)
		(layer "F.Cu")
		(net "M_A_CPU0_SA_DQ<17>")
	)
	(segment
		(start 310.373014 -217.73515)
		(end 310.266334 -217.84183)
		(width 0.10668)
		(layer "F.Cu")
		(net "M_A_CPU0_SA_DQ<17>")
	)
	(segment
		(start 315.101478 -222.025972)
		(end 310.810656 -217.73515)
		(width 0.10668)
		(layer "F.Cu")
		(net "M_A_CPU0_SA_DQ<17>")
	)
	(segment
		(start 308.962552 -217.73515)
		(end 307.368194 -217.73515)
		(width 0.10668)
		(layer "F.Cu")
		(net "M_A_CPU0_SA_DQ<17>")
	)
	(segment
		(start 324.124574 -236.34319)
		(end 323.878194 -236.34319)
		(width 0.0762)
		(layer "F.Cu")
		(net "M_A_CPU0_SA_DQ<17>")
	)
	(segment
		(start 309.468266 -217.84183)
		(end 309.468266 -218.469972)
		(width 0.10668)
		(layer "F.Cu")
		(net "M_A_CPU0_SA_DQ<17>")
	)
	(segment
		(start 309.574946 -217.73515)
		(end 309.468266 -217.84183)
		(width 0.10668)
		(layer "F.Cu")
		(net "M_A_CPU0_SA_DQ<17>")
	)
	(segment
		(start 310.810656 -217.73515)
		(end 310.373014 -217.73515)
		(width 0.10668)
		(layer "F.Cu")
		(net "M_A_CPU0_SA_DQ<17>")
	)
	(segment
		(start 309.8673 -217.84183)
		(end 309.76062 -217.73515)
		(width 0.10668)
		(layer "F.Cu")
		(net "M_A_CPU0_SA_DQ<17>")
	)
	(segment
		(start 309.76062 -217.73515)
		(end 309.574946 -217.73515)
		(width 0.10668)
		(layer "F.Cu")
		(net "M_A_CPU0_SA_DQ<17>")
	)
	(segment
		(start 322.60921 -236.34319)
		(end 315.101478 -228.835458)
		(width 0.10668)
		(layer "F.Cu")
		(net "M_A_CPU0_SA_DQ<17>")
	)
	(segment
		(start 315.101478 -228.835458)
		(end 315.101478 -222.025972)
		(width 0.10668)
		(layer "F.Cu")
		(net "M_A_CPU0_SA_DQ<17>")
	)
	(segment
		(start 309.361586 -218.576652)
		(end 309.175912 -218.576652)
		(width 0.10668)
		(layer "F.Cu")
		(net "M_A_CPU0_SA_DQ<17>")
	)
	(segment
		(start 325.012812 -235.97997)
		(end 324.487794 -235.97997)
		(width 0.0762)
		(layer "F.Cu")
		(net "M_A_CPU0_SA_DQ<17>")
	)
	(segment
		(start 325.699374 -236.167422)
		(end 325.690992 -236.162596)
		(width 0.0762)
		(layer "F.Cu")
		(net "M_A_CPU0_SA_DQ<17>")
	)
	(segment
		(start 309.8673 -218.469972)
		(end 309.8673 -217.84183)
		(width 0.10668)
		(layer "F.Cu")
		(net "M_A_CPU0_SA_DQ<17>")
	)
	(segment
		(start 323.878194 -236.34319)
		(end 322.60921 -236.34319)
		(width 0.10668)
		(layer "F.Cu")
		(net "M_A_CPU0_SA_DQ<17>")
	)
	(segment
		(start 309.468266 -218.469972)
		(end 309.361586 -218.576652)
		(width 0.10668)
		(layer "F.Cu")
		(net "M_A_CPU0_SA_DQ<17>")
	)
	(segment
		(start 324.487794 -235.97997)
		(end 324.124574 -236.34319)
		(width 0.0762)
		(layer "F.Cu")
		(net "M_A_CPU0_SA_DQ<17>")
	)
	(segment
		(start 309.069232 -218.469972)
		(end 309.069232 -217.84183)
		(width 0.10668)
		(layer "F.Cu")
		(net "M_A_CPU0_SA_DQ<17>")
	)
	(segment
		(start 310.159654 -218.576652)
		(end 309.97398 -218.576652)
		(width 0.10668)
		(layer "F.Cu")
		(net "M_A_CPU0_SA_DQ<17>")
	)
	(segment
		(start 309.175912 -218.576652)
		(end 309.069232 -218.469972)
		(width 0.10668)
		(layer "F.Cu")
		(net "M_A_CPU0_SA_DQ<17>")
	)
	(segment
		(start 309.069232 -217.84183)
		(end 308.962552 -217.73515)
		(width 0.10668)
		(layer "F.Cu")
		(net "M_A_CPU0_SA_DQ<17>")
	)
	(segment
		(start 310.266334 -217.84183)
		(end 310.266334 -218.469972)
		(width 0.10668)
		(layer "F.Cu")
		(net "M_A_CPU0_SA_DQ<17>")
	)
	(arc
		(start 326.065134 -236.162596)
		(mid 325.882883 -236.212946)
		(end 325.699374 -236.167422)
		(width 0.0762)
		(layer "F.Cu")
		(net "M_A_CPU0_SA_DQ<17>")
	)
	(arc
		(start 327.758044 -235.840016)
		(mid 327.554028 -236.02071)
		(end 327.289414 -236.085888)
		(width 0.0762)
		(layer "F.Cu")
		(net "M_A_CPU0_SA_DQ<17>")
	)
	(arc
		(start 327.289414 -236.085888)
		(mid 327.142093 -236.105207)
		(end 327.004934 -236.162342)
		(width 0.0762)
		(layer "F.Cu")
		(net "M_A_CPU0_SA_DQ<17>")
	)
	(arc
		(start 327.004934 -236.162596)
		(mid 326.81799 -236.212851)
		(end 326.631046 -236.162596)
		(width 0.0762)
		(layer "F.Cu")
		(net "M_A_CPU0_SA_DQ<17>")
	)
	(arc
		(start 325.690992 -236.162596)
		(mid 325.363982 -236.026425)
		(end 325.012812 -235.97997)
		(width 0.0762)
		(layer "F.Cu")
		(net "M_A_CPU0_SA_DQ<17>")
	)
	(arc
		(start 326.631046 -236.162596)
		(mid 326.34809 -236.086419)
		(end 326.065134 -236.162596)
		(width 0.0762)
		(layer "F.Cu")
		(net "M_A_CPU0_SA_DQ<17>")
	)
	(segment
		(start 309.691786 -216.963752)
		(end 309.585106 -216.857072)
		(width 0.10668)
		(layer "F.Cu")
		(net "M_A_CPU0_SA_DQ<16>")
	)
	(segment
		(start 315.782198 -228.55301)
		(end 315.782198 -221.39148)
		(width 0.10668)
		(layer "F.Cu")
		(net "M_A_CPU0_SA_DQ<16>")
	)
	(segment
		(start 324.155054 -235.58373)
		(end 323.916294 -235.58373)
		(width 0.0762)
		(layer "F.Cu")
		(net "M_A_CPU0_SA_DQ<16>")
	)
	(segment
		(start 325.38797 -235.40847)
		(end 324.330314 -235.40847)
		(width 0.0762)
		(layer "F.Cu")
		(net "M_A_CPU0_SA_DQ<16>")
	)
	(segment
		(start 309.079392 -216.963752)
		(end 308.893718 -216.963752)
		(width 0.10668)
		(layer "F.Cu")
		(net "M_A_CPU0_SA_DQ<16>")
	)
	(segment
		(start 309.585106 -216.857072)
		(end 309.585106 -216.013792)
		(width 0.10668)
		(layer "F.Cu")
		(net "M_A_CPU0_SA_DQ<16>")
	)
	(segment
		(start 324.330314 -235.40847)
		(end 324.155054 -235.58373)
		(width 0.0762)
		(layer "F.Cu")
		(net "M_A_CPU0_SA_DQ<16>")
	)
	(segment
		(start 323.916294 -235.58373)
		(end 322.812918 -235.58373)
		(width 0.10668)
		(layer "F.Cu")
		(net "M_A_CPU0_SA_DQ<16>")
	)
	(segment
		(start 309.585106 -216.013792)
		(end 309.478426 -215.907112)
		(width 0.10668)
		(layer "F.Cu")
		(net "M_A_CPU0_SA_DQ<16>")
	)
	(segment
		(start 309.87746 -216.963752)
		(end 309.691786 -216.963752)
		(width 0.10668)
		(layer "F.Cu")
		(net "M_A_CPU0_SA_DQ<16>")
	)
	(segment
		(start 309.98414 -216.857072)
		(end 309.87746 -216.963752)
		(width 0.10668)
		(layer "F.Cu")
		(net "M_A_CPU0_SA_DQ<16>")
	)
	(segment
		(start 309.186072 -216.013792)
		(end 309.186072 -216.857072)
		(width 0.10668)
		(layer "F.Cu")
		(net "M_A_CPU0_SA_DQ<16>")
	)
	(segment
		(start 322.812918 -235.58373)
		(end 315.782198 -228.55301)
		(width 0.10668)
		(layer "F.Cu")
		(net "M_A_CPU0_SA_DQ<16>")
	)
	(segment
		(start 308.787038 -216.141808)
		(end 308.680358 -216.035128)
		(width 0.10668)
		(layer "F.Cu")
		(net "M_A_CPU0_SA_DQ<16>")
	)
	(segment
		(start 310.425846 -216.035128)
		(end 310.09082 -216.035128)
		(width 0.10668)
		(layer "F.Cu")
		(net "M_A_CPU0_SA_DQ<16>")
	)
	(segment
		(start 308.893718 -216.963752)
		(end 308.787038 -216.857072)
		(width 0.10668)
		(layer "F.Cu")
		(net "M_A_CPU0_SA_DQ<16>")
	)
	(segment
		(start 309.98414 -216.141808)
		(end 309.98414 -216.857072)
		(width 0.10668)
		(layer "F.Cu")
		(net "M_A_CPU0_SA_DQ<16>")
	)
	(segment
		(start 309.478426 -215.907112)
		(end 309.292752 -215.907112)
		(width 0.10668)
		(layer "F.Cu")
		(net "M_A_CPU0_SA_DQ<16>")
	)
	(segment
		(start 315.782198 -221.39148)
		(end 310.425846 -216.035128)
		(width 0.10668)
		(layer "F.Cu")
		(net "M_A_CPU0_SA_DQ<16>")
	)
	(segment
		(start 309.292752 -215.907112)
		(end 309.186072 -216.013792)
		(width 0.10668)
		(layer "F.Cu")
		(net "M_A_CPU0_SA_DQ<16>")
	)
	(segment
		(start 309.186072 -216.857072)
		(end 309.079392 -216.963752)
		(width 0.10668)
		(layer "F.Cu")
		(net "M_A_CPU0_SA_DQ<16>")
	)
	(segment
		(start 308.680358 -216.035128)
		(end 307.368194 -216.035128)
		(width 0.10668)
		(layer "F.Cu")
		(net "M_A_CPU0_SA_DQ<16>")
	)
	(segment
		(start 308.787038 -216.857072)
		(end 308.787038 -216.141808)
		(width 0.10668)
		(layer "F.Cu")
		(net "M_A_CPU0_SA_DQ<16>")
	)
	(segment
		(start 310.09082 -216.035128)
		(end 309.98414 -216.141808)
		(width 0.10668)
		(layer "F.Cu")
		(net "M_A_CPU0_SA_DQ<16>")
	)
	(arc
		(start 325.59498 -235.35259)
		(mid 325.495173 -235.394219)
		(end 325.38797 -235.40847)
		(width 0.0762)
		(layer "F.Cu")
		(net "M_A_CPU0_SA_DQ<16>")
	)
	(arc
		(start 325.830438 -235.278168)
		(mid 325.708582 -235.302324)
		(end 325.59498 -235.35259)
		(width 0.0762)
		(layer "F.Cu")
		(net "M_A_CPU0_SA_DQ<16>")
	)
	(arc
		(start 326.34809 -235.03001)
		(mid 326.111962 -235.201445)
		(end 325.830438 -235.278168)
		(width 0.0762)
		(layer "F.Cu")
		(net "M_A_CPU0_SA_DQ<16>")
	)
	(segment
		(start 310.381396 -215.34374)
		(end 310.23052 -215.34374)
		(width 0.10668)
		(layer "F.Cu")
		(net "M_A_CPU0_SA_DQ<15>")
	)
	(segment
		(start 327.28789 -235.03001)
		(end 327.28789 -235.029756)
		(width 0.0762)
		(layer "F.Cu")
		(net "M_A_CPU0_SA_DQ<15>")
	)
	(segment
		(start 316.239398 -228.363526)
		(end 316.239398 -221.201742)
		(width 0.10668)
		(layer "F.Cu")
		(net "M_A_CPU0_SA_DQ<15>")
	)
	(segment
		(start 310.131968 -215.442292)
		(end 309.981092 -215.442292)
		(width 0.10668)
		(layer "F.Cu")
		(net "M_A_CPU0_SA_DQ<15>")
	)
	(segment
		(start 309.797704 -214.760048)
		(end 308.610508 -214.760048)
		(width 0.10668)
		(layer "F.Cu")
		(net "M_A_CPU0_SA_DQ<15>")
	)
	(segment
		(start 309.981092 -215.442292)
		(end 309.849774 -215.310974)
		(width 0.10668)
		(layer "F.Cu")
		(net "M_A_CPU0_SA_DQ<15>")
	)
	(segment
		(start 326.535034 -234.70743)
		(end 326.526652 -234.702604)
		(width 0.0762)
		(layer "F.Cu")
		(net "M_A_CPU0_SA_DQ<15>")
	)
	(segment
		(start 327.109328 -234.702604)
		(end 327.108312 -234.703112)
		(width 0.0762)
		(layer "F.Cu")
		(net "M_A_CPU0_SA_DQ<15>")
	)
	(segment
		(start 308.610508 -214.760048)
		(end 306.070508 -214.760048)
		(width 0.101346)
		(layer "F.Cu")
		(net "M_A_CPU0_SA_DQ<15>")
	)
	(segment
		(start 324.49008 -234.656884)
		(end 324.063614 -235.08335)
		(width 0.0762)
		(layer "F.Cu")
		(net "M_A_CPU0_SA_DQ<15>")
	)
	(segment
		(start 309.849774 -215.160098)
		(end 309.948326 -215.061546)
		(width 0.10668)
		(layer "F.Cu")
		(net "M_A_CPU0_SA_DQ<15>")
	)
	(segment
		(start 327.108312 -234.703112)
		(end 327.100946 -234.70743)
		(width 0.0762)
		(layer "F.Cu")
		(net "M_A_CPU0_SA_DQ<15>")
	)
	(segment
		(start 309.948326 -214.91067)
		(end 309.797704 -214.760048)
		(width 0.10668)
		(layer "F.Cu")
		(net "M_A_CPU0_SA_DQ<15>")
	)
	(segment
		(start 322.959222 -235.08335)
		(end 316.239398 -228.363526)
		(width 0.10668)
		(layer "F.Cu")
		(net "M_A_CPU0_SA_DQ<15>")
	)
	(segment
		(start 309.948326 -215.061546)
		(end 309.948326 -214.91067)
		(width 0.10668)
		(layer "F.Cu")
		(net "M_A_CPU0_SA_DQ<15>")
	)
	(segment
		(start 316.239398 -221.201742)
		(end 310.381396 -215.34374)
		(width 0.10668)
		(layer "F.Cu")
		(net "M_A_CPU0_SA_DQ<15>")
	)
	(segment
		(start 309.849774 -215.310974)
		(end 309.849774 -215.160098)
		(width 0.10668)
		(layer "F.Cu")
		(net "M_A_CPU0_SA_DQ<15>")
	)
	(segment
		(start 324.063614 -235.08335)
		(end 324.002654 -235.08335)
		(width 0.0762)
		(layer "F.Cu")
		(net "M_A_CPU0_SA_DQ<15>")
	)
	(segment
		(start 310.23052 -215.34374)
		(end 310.131968 -215.442292)
		(width 0.10668)
		(layer "F.Cu")
		(net "M_A_CPU0_SA_DQ<15>")
	)
	(segment
		(start 324.002654 -235.08335)
		(end 322.959222 -235.08335)
		(width 0.10668)
		(layer "F.Cu")
		(net "M_A_CPU0_SA_DQ<15>")
	)
	(segment
		(start 306.070508 -214.760048)
		(end 305.645566 -215.18499)
		(width 0.101346)
		(layer "F.Cu")
		(net "M_A_CPU0_SA_DQ<15>")
	)
	(segment
		(start 325.408036 -234.656884)
		(end 324.49008 -234.656884)
		(width 0.0762)
		(layer "F.Cu")
		(net "M_A_CPU0_SA_DQ<15>")
	)
	(segment
		(start 305.645566 -215.18499)
		(end 303.268126 -215.18499)
		(width 0.101346)
		(layer "F.Cu")
		(net "M_A_CPU0_SA_DQ<15>")
	)
	(segment
		(start 327.28789 -235.029756)
		(end 327.393046 -234.848908)
		(width 0.0762)
		(layer "F.Cu")
		(net "M_A_CPU0_SA_DQ<15>")
	)
	(arc
		(start 326.526652 -234.702604)
		(mid 326.343144 -234.65711)
		(end 326.160892 -234.70743)
		(width 0.0762)
		(layer "F.Cu")
		(net "M_A_CPU0_SA_DQ<15>")
	)
	(arc
		(start 327.393046 -234.848908)
		(mid 327.384109 -234.729884)
		(end 327.289414 -234.657138)
		(width 0.0762)
		(layer "F.Cu")
		(net "M_A_CPU0_SA_DQ<15>")
	)
	(arc
		(start 325.59498 -234.70743)
		(mid 325.504847 -234.66981)
		(end 325.408036 -234.656884)
		(width 0.0762)
		(layer "F.Cu")
		(net "M_A_CPU0_SA_DQ<15>")
	)
	(arc
		(start 327.100946 -234.70743)
		(mid 326.81799 -234.783607)
		(end 326.535034 -234.70743)
		(width 0.0762)
		(layer "F.Cu")
		(net "M_A_CPU0_SA_DQ<15>")
	)
	(arc
		(start 327.289414 -234.657138)
		(mid 327.19649 -234.668461)
		(end 327.109328 -234.702604)
		(width 0.0762)
		(layer "F.Cu")
		(net "M_A_CPU0_SA_DQ<15>")
	)
	(arc
		(start 326.160892 -234.70743)
		(mid 325.877936 -234.783607)
		(end 325.59498 -234.70743)
		(width 0.0762)
		(layer "F.Cu")
		(net "M_A_CPU0_SA_DQ<15>")
	)
	(segment
		(start 303.776126 -213.484968)
		(end 303.268126 -213.484968)
		(width 0.101346)
		(layer "F.Cu")
		(net "M_A_CPU0_SA_DQ<14>")
	)
	(segment
		(start 324.871588 -234.11815)
		(end 324.055994 -234.11815)
		(width 0.0762)
		(layer "F.Cu")
		(net "M_A_CPU0_SA_DQ<14>")
	)
	(segment
		(start 316.920118 -228.081078)
		(end 316.920118 -220.055694)
		(width 0.10668)
		(layer "F.Cu")
		(net "M_A_CPU0_SA_DQ<14>")
	)
	(segment
		(start 324.055994 -234.11815)
		(end 323.969634 -234.20451)
		(width 0.0762)
		(layer "F.Cu")
		(net "M_A_CPU0_SA_DQ<14>")
	)
	(segment
		(start 309.484522 -213.803484)
		(end 309.484522 -213.237572)
		(width 0.10668)
		(layer "F.Cu")
		(net "M_A_CPU0_SA_DQ<14>")
	)
	(segment
		(start 312.140854 -216.139776)
		(end 309.911242 -213.910164)
		(width 0.10668)
		(layer "F.Cu")
		(net "M_A_CPU0_SA_DQ<14>")
	)
	(segment
		(start 309.484522 -213.237572)
		(end 309.377842 -213.130892)
		(width 0.10668)
		(layer "F.Cu")
		(net "M_A_CPU0_SA_DQ<14>")
	)
	(segment
		(start 325.877936 -234.220004)
		(end 325.9709 -234.059984)
		(width 0.0762)
		(layer "F.Cu")
		(net "M_A_CPU0_SA_DQ<14>")
	)
	(segment
		(start 316.920118 -220.055694)
		(end 313.0042 -216.139776)
		(width 0.10668)
		(layer "F.Cu")
		(net "M_A_CPU0_SA_DQ<14>")
	)
	(segment
		(start 323.969634 -234.20451)
		(end 323.04355 -234.20451)
		(width 0.10668)
		(layer "F.Cu")
		(net "M_A_CPU0_SA_DQ<14>")
	)
	(segment
		(start 313.0042 -216.139776)
		(end 312.140854 -216.139776)
		(width 0.10668)
		(layer "F.Cu")
		(net "M_A_CPU0_SA_DQ<14>")
	)
	(segment
		(start 309.085488 -213.803484)
		(end 308.978808 -213.910164)
		(width 0.10668)
		(layer "F.Cu")
		(net "M_A_CPU0_SA_DQ<14>")
	)
	(segment
		(start 306.070508 -213.910164)
		(end 306.066444 -213.914228)
		(width 0.101346)
		(layer "F.Cu")
		(net "M_A_CPU0_SA_DQ<14>")
	)
	(segment
		(start 309.192168 -213.130892)
		(end 309.085488 -213.237572)
		(width 0.10668)
		(layer "F.Cu")
		(net "M_A_CPU0_SA_DQ<14>")
	)
	(segment
		(start 304.205386 -213.914228)
		(end 303.776126 -213.484968)
		(width 0.101346)
		(layer "F.Cu")
		(net "M_A_CPU0_SA_DQ<14>")
	)
	(segment
		(start 308.978808 -213.910164)
		(end 308.610508 -213.910164)
		(width 0.10668)
		(layer "F.Cu")
		(net "M_A_CPU0_SA_DQ<14>")
	)
	(segment
		(start 325.699374 -233.892598)
		(end 325.690992 -233.897424)
		(width 0.0762)
		(layer "F.Cu")
		(net "M_A_CPU0_SA_DQ<14>")
	)
	(segment
		(start 309.911242 -213.910164)
		(end 309.591202 -213.910164)
		(width 0.10668)
		(layer "F.Cu")
		(net "M_A_CPU0_SA_DQ<14>")
	)
	(segment
		(start 308.610508 -213.910164)
		(end 306.070508 -213.910164)
		(width 0.101346)
		(layer "F.Cu")
		(net "M_A_CPU0_SA_DQ<14>")
	)
	(segment
		(start 323.04355 -234.20451)
		(end 316.920118 -228.081078)
		(width 0.10668)
		(layer "F.Cu")
		(net "M_A_CPU0_SA_DQ<14>")
	)
	(segment
		(start 309.085488 -213.237572)
		(end 309.085488 -213.803484)
		(width 0.10668)
		(layer "F.Cu")
		(net "M_A_CPU0_SA_DQ<14>")
	)
	(segment
		(start 309.591202 -213.910164)
		(end 309.484522 -213.803484)
		(width 0.10668)
		(layer "F.Cu")
		(net "M_A_CPU0_SA_DQ<14>")
	)
	(segment
		(start 309.377842 -213.130892)
		(end 309.192168 -213.130892)
		(width 0.10668)
		(layer "F.Cu")
		(net "M_A_CPU0_SA_DQ<14>")
	)
	(segment
		(start 306.066444 -213.914228)
		(end 304.205386 -213.914228)
		(width 0.101346)
		(layer "F.Cu")
		(net "M_A_CPU0_SA_DQ<14>")
	)
	(arc
		(start 325.9709 -234.059984)
		(mid 325.97074 -233.913423)
		(end 325.839074 -233.849164)
		(width 0.0762)
		(layer "F.Cu")
		(net "M_A_CPU0_SA_DQ<14>")
	)
	(arc
		(start 325.839074 -233.849164)
		(mid 325.767066 -233.863946)
		(end 325.699374 -233.892598)
		(width 0.0762)
		(layer "F.Cu")
		(net "M_A_CPU0_SA_DQ<14>")
	)
	(arc
		(start 325.690992 -233.897424)
		(mid 325.295887 -234.061963)
		(end 324.871588 -234.11815)
		(width 0.0762)
		(layer "F.Cu")
		(net "M_A_CPU0_SA_DQ<14>")
	)
	(segment
		(start 313.09183 -217.57259)
		(end 313.09183 -217.40749)
		(width 0.10668)
		(layer "F.Cu")
		(net "M_A_CPU0_SA_DQ<13>")
	)
	(segment
		(start 314.884816 -218.601544)
		(end 314.719716 -218.601544)
		(width 0.10668)
		(layer "F.Cu")
		(net "M_A_CPU0_SA_DQ<13>")
	)
	(segment
		(start 315.349382 -219.665042)
		(end 315.566298 -219.448126)
		(width 0.10668)
		(layer "F.Cu")
		(net "M_A_CPU0_SA_DQ<13>")
	)
	(segment
		(start 315.566298 -219.283026)
		(end 315.449204 -219.165932)
		(width 0.10668)
		(layer "F.Cu")
		(net "M_A_CPU0_SA_DQ<13>")
	)
	(segment
		(start 315.848492 -219.73032)
		(end 315.631576 -219.947236)
		(width 0.10668)
		(layer "F.Cu")
		(net "M_A_CPU0_SA_DQ<13>")
	)
	(segment
		(start 312.527442 -217.008202)
		(end 312.527442 -216.843102)
		(width 0.10668)
		(layer "F.Cu")
		(net "M_A_CPU0_SA_DQ<13>")
	)
	(segment
		(start 315.349382 -219.830142)
		(end 315.349382 -219.665042)
		(width 0.10668)
		(layer "F.Cu")
		(net "M_A_CPU0_SA_DQ<13>")
	)
	(segment
		(start 313.773312 -218.254072)
		(end 313.656218 -218.136978)
		(width 0.10668)
		(layer "F.Cu")
		(net "M_A_CPU0_SA_DQ<13>")
	)
	(segment
		(start 313.374024 -217.689684)
		(end 313.208924 -217.689684)
		(width 0.10668)
		(layer "F.Cu")
		(net "M_A_CPU0_SA_DQ<13>")
	)
	(segment
		(start 325.408036 -234.466384)
		(end 324.2564 -234.466384)
		(width 0.0762)
		(layer "F.Cu")
		(net "M_A_CPU0_SA_DQ<13>")
	)
	(segment
		(start 314.437522 -218.31935)
		(end 314.437522 -218.15425)
		(width 0.10668)
		(layer "F.Cu")
		(net "M_A_CPU0_SA_DQ<13>")
	)
	(segment
		(start 314.784994 -219.100654)
		(end 315.00191 -218.883738)
		(width 0.10668)
		(layer "F.Cu")
		(net "M_A_CPU0_SA_DQ<13>")
	)
	(segment
		(start 313.938412 -218.254072)
		(end 313.773312 -218.254072)
		(width 0.10668)
		(layer "F.Cu")
		(net "M_A_CPU0_SA_DQ<13>")
	)
	(segment
		(start 323.893434 -234.65409)
		(end 323.011546 -234.65409)
		(width 0.10668)
		(layer "F.Cu")
		(net "M_A_CPU0_SA_DQ<13>")
	)
	(segment
		(start 313.256422 -217.242898)
		(end 313.256422 -217.077798)
		(width 0.10668)
		(layer "F.Cu")
		(net "M_A_CPU0_SA_DQ<13>")
	)
	(segment
		(start 312.32602 -216.480136)
		(end 312.245248 -216.560908)
		(width 0.10668)
		(layer "F.Cu")
		(net "M_A_CPU0_SA_DQ<13>")
	)
	(segment
		(start 316.579758 -228.222302)
		(end 316.579758 -221.060518)
		(width 0.10668)
		(layer "F.Cu")
		(net "M_A_CPU0_SA_DQ<13>")
	)
	(segment
		(start 313.256422 -217.077798)
		(end 313.139328 -216.960704)
		(width 0.10668)
		(layer "F.Cu")
		(net "M_A_CPU0_SA_DQ<13>")
	)
	(segment
		(start 313.656218 -217.971878)
		(end 313.873134 -217.754962)
		(width 0.10668)
		(layer "F.Cu")
		(net "M_A_CPU0_SA_DQ<13>")
	)
	(segment
		(start 316.579758 -221.060518)
		(end 315.91377 -220.39453)
		(width 0.10668)
		(layer "F.Cu")
		(net "M_A_CPU0_SA_DQ<13>")
	)
	(segment
		(start 312.080148 -216.560908)
		(end 309.854346 -214.335106)
		(width 0.10668)
		(layer "F.Cu")
		(net "M_A_CPU0_SA_DQ<13>")
	)
	(segment
		(start 313.139328 -216.960704)
		(end 312.974228 -216.960704)
		(width 0.10668)
		(layer "F.Cu")
		(net "M_A_CPU0_SA_DQ<13>")
	)
	(segment
		(start 314.155328 -218.037156)
		(end 313.938412 -218.254072)
		(width 0.10668)
		(layer "F.Cu")
		(net "M_A_CPU0_SA_DQ<13>")
	)
	(segment
		(start 313.656218 -218.136978)
		(end 313.656218 -217.971878)
		(width 0.10668)
		(layer "F.Cu")
		(net "M_A_CPU0_SA_DQ<13>")
	)
	(segment
		(start 309.854346 -214.335106)
		(end 307.368194 -214.335106)
		(width 0.10668)
		(layer "F.Cu")
		(net "M_A_CPU0_SA_DQ<13>")
	)
	(segment
		(start 312.809636 -217.125296)
		(end 312.644536 -217.125296)
		(width 0.10668)
		(layer "F.Cu")
		(net "M_A_CPU0_SA_DQ<13>")
	)
	(segment
		(start 312.974228 -216.960704)
		(end 312.809636 -217.125296)
		(width 0.10668)
		(layer "F.Cu")
		(net "M_A_CPU0_SA_DQ<13>")
	)
	(segment
		(start 327.004934 -234.54233)
		(end 327.004934 -234.542584)
		(width 0.0762)
		(layer "F.Cu")
		(net "M_A_CPU0_SA_DQ<13>")
	)
	(segment
		(start 312.644536 -217.125296)
		(end 312.527442 -217.008202)
		(width 0.10668)
		(layer "F.Cu")
		(net "M_A_CPU0_SA_DQ<13>")
	)
	(segment
		(start 325.699374 -234.54741)
		(end 325.690992 -234.542584)
		(width 0.0762)
		(layer "F.Cu")
		(net "M_A_CPU0_SA_DQ<13>")
	)
	(segment
		(start 312.608214 -216.59723)
		(end 312.49112 -216.480136)
		(width 0.10668)
		(layer "F.Cu")
		(net "M_A_CPU0_SA_DQ<13>")
	)
	(segment
		(start 315.91377 -220.22943)
		(end 316.130686 -220.012514)
		(width 0.10668)
		(layer "F.Cu")
		(net "M_A_CPU0_SA_DQ<13>")
	)
	(segment
		(start 315.631576 -219.947236)
		(end 315.466476 -219.947236)
		(width 0.10668)
		(layer "F.Cu")
		(net "M_A_CPU0_SA_DQ<13>")
	)
	(segment
		(start 315.466476 -219.947236)
		(end 315.349382 -219.830142)
		(width 0.10668)
		(layer "F.Cu")
		(net "M_A_CPU0_SA_DQ<13>")
	)
	(segment
		(start 314.784994 -219.265754)
		(end 314.784994 -219.100654)
		(width 0.10668)
		(layer "F.Cu")
		(net "M_A_CPU0_SA_DQ<13>")
	)
	(segment
		(start 314.5028 -218.81846)
		(end 314.3377 -218.81846)
		(width 0.10668)
		(layer "F.Cu")
		(net "M_A_CPU0_SA_DQ<13>")
	)
	(segment
		(start 313.09183 -217.40749)
		(end 313.256422 -217.242898)
		(width 0.10668)
		(layer "F.Cu")
		(net "M_A_CPU0_SA_DQ<13>")
	)
	(segment
		(start 312.49112 -216.480136)
		(end 312.32602 -216.480136)
		(width 0.10668)
		(layer "F.Cu")
		(net "M_A_CPU0_SA_DQ<13>")
	)
	(segment
		(start 324.068694 -234.65409)
		(end 323.893434 -234.65409)
		(width 0.0762)
		(layer "F.Cu")
		(net "M_A_CPU0_SA_DQ<13>")
	)
	(segment
		(start 314.437522 -218.15425)
		(end 314.320428 -218.037156)
		(width 0.10668)
		(layer "F.Cu")
		(net "M_A_CPU0_SA_DQ<13>")
	)
	(segment
		(start 313.208924 -217.689684)
		(end 313.09183 -217.57259)
		(width 0.10668)
		(layer "F.Cu")
		(net "M_A_CPU0_SA_DQ<13>")
	)
	(segment
		(start 314.719716 -218.601544)
		(end 314.5028 -218.81846)
		(width 0.10668)
		(layer "F.Cu")
		(net "M_A_CPU0_SA_DQ<13>")
	)
	(segment
		(start 324.2564 -234.466384)
		(end 324.068694 -234.65409)
		(width 0.0762)
		(layer "F.Cu")
		(net "M_A_CPU0_SA_DQ<13>")
	)
	(segment
		(start 316.130686 -219.847414)
		(end 316.013592 -219.73032)
		(width 0.10668)
		(layer "F.Cu")
		(net "M_A_CPU0_SA_DQ<13>")
	)
	(segment
		(start 314.902088 -219.382848)
		(end 314.784994 -219.265754)
		(width 0.10668)
		(layer "F.Cu")
		(net "M_A_CPU0_SA_DQ<13>")
	)
	(segment
		(start 313.59094 -217.472768)
		(end 313.374024 -217.689684)
		(width 0.10668)
		(layer "F.Cu")
		(net "M_A_CPU0_SA_DQ<13>")
	)
	(segment
		(start 315.284104 -219.165932)
		(end 315.067188 -219.382848)
		(width 0.10668)
		(layer "F.Cu")
		(net "M_A_CPU0_SA_DQ<13>")
	)
	(segment
		(start 315.00191 -218.883738)
		(end 315.00191 -218.718638)
		(width 0.10668)
		(layer "F.Cu")
		(net "M_A_CPU0_SA_DQ<13>")
	)
	(segment
		(start 314.320428 -218.037156)
		(end 314.155328 -218.037156)
		(width 0.10668)
		(layer "F.Cu")
		(net "M_A_CPU0_SA_DQ<13>")
	)
	(segment
		(start 316.013592 -219.73032)
		(end 315.848492 -219.73032)
		(width 0.10668)
		(layer "F.Cu")
		(net "M_A_CPU0_SA_DQ<13>")
	)
	(segment
		(start 315.91377 -220.39453)
		(end 315.91377 -220.22943)
		(width 0.10668)
		(layer "F.Cu")
		(net "M_A_CPU0_SA_DQ<13>")
	)
	(segment
		(start 314.3377 -218.81846)
		(end 314.220606 -218.701366)
		(width 0.10668)
		(layer "F.Cu")
		(net "M_A_CPU0_SA_DQ<13>")
	)
	(segment
		(start 315.00191 -218.718638)
		(end 314.884816 -218.601544)
		(width 0.10668)
		(layer "F.Cu")
		(net "M_A_CPU0_SA_DQ<13>")
	)
	(segment
		(start 313.75604 -217.472768)
		(end 313.59094 -217.472768)
		(width 0.10668)
		(layer "F.Cu")
		(net "M_A_CPU0_SA_DQ<13>")
	)
	(segment
		(start 312.608214 -216.76233)
		(end 312.608214 -216.59723)
		(width 0.10668)
		(layer "F.Cu")
		(net "M_A_CPU0_SA_DQ<13>")
	)
	(segment
		(start 315.067188 -219.382848)
		(end 314.902088 -219.382848)
		(width 0.10668)
		(layer "F.Cu")
		(net "M_A_CPU0_SA_DQ<13>")
	)
	(segment
		(start 313.873134 -217.754962)
		(end 313.873134 -217.589862)
		(width 0.10668)
		(layer "F.Cu")
		(net "M_A_CPU0_SA_DQ<13>")
	)
	(segment
		(start 313.873134 -217.589862)
		(end 313.75604 -217.472768)
		(width 0.10668)
		(layer "F.Cu")
		(net "M_A_CPU0_SA_DQ<13>")
	)
	(segment
		(start 315.566298 -219.448126)
		(end 315.566298 -219.283026)
		(width 0.10668)
		(layer "F.Cu")
		(net "M_A_CPU0_SA_DQ<13>")
	)
	(segment
		(start 312.527442 -216.843102)
		(end 312.608214 -216.76233)
		(width 0.10668)
		(layer "F.Cu")
		(net "M_A_CPU0_SA_DQ<13>")
	)
	(segment
		(start 312.245248 -216.560908)
		(end 312.080148 -216.560908)
		(width 0.10668)
		(layer "F.Cu")
		(net "M_A_CPU0_SA_DQ<13>")
	)
	(segment
		(start 323.011546 -234.65409)
		(end 316.579758 -228.222302)
		(width 0.10668)
		(layer "F.Cu")
		(net "M_A_CPU0_SA_DQ<13>")
	)
	(segment
		(start 314.220606 -218.701366)
		(end 314.220606 -218.536266)
		(width 0.10668)
		(layer "F.Cu")
		(net "M_A_CPU0_SA_DQ<13>")
	)
	(segment
		(start 314.220606 -218.536266)
		(end 314.437522 -218.31935)
		(width 0.10668)
		(layer "F.Cu")
		(net "M_A_CPU0_SA_DQ<13>")
	)
	(segment
		(start 315.449204 -219.165932)
		(end 315.284104 -219.165932)
		(width 0.10668)
		(layer "F.Cu")
		(net "M_A_CPU0_SA_DQ<13>")
	)
	(segment
		(start 316.130686 -220.012514)
		(end 316.130686 -219.847414)
		(width 0.10668)
		(layer "F.Cu")
		(net "M_A_CPU0_SA_DQ<13>")
	)
	(arc
		(start 327.289414 -234.465876)
		(mid 327.142093 -234.485195)
		(end 327.004934 -234.54233)
		(width 0.0762)
		(layer "F.Cu")
		(net "M_A_CPU0_SA_DQ<13>")
	)
	(arc
		(start 327.758044 -234.220004)
		(mid 327.554028 -234.400698)
		(end 327.289414 -234.465876)
		(width 0.0762)
		(layer "F.Cu")
		(net "M_A_CPU0_SA_DQ<13>")
	)
	(arc
		(start 327.004934 -234.542584)
		(mid 326.81799 -234.592839)
		(end 326.631046 -234.542584)
		(width 0.0762)
		(layer "F.Cu")
		(net "M_A_CPU0_SA_DQ<13>")
	)
	(arc
		(start 325.690992 -234.542584)
		(mid 325.554556 -234.485759)
		(end 325.408036 -234.466384)
		(width 0.0762)
		(layer "F.Cu")
		(net "M_A_CPU0_SA_DQ<13>")
	)
	(arc
		(start 326.631046 -234.542584)
		(mid 326.34809 -234.466407)
		(end 326.065134 -234.542584)
		(width 0.0762)
		(layer "F.Cu")
		(net "M_A_CPU0_SA_DQ<13>")
	)
	(arc
		(start 326.065134 -234.542584)
		(mid 325.882883 -234.592934)
		(end 325.699374 -234.54741)
		(width 0.0762)
		(layer "F.Cu")
		(net "M_A_CPU0_SA_DQ<13>")
	)
	(segment
		(start 311.868058 -214.462868)
		(end 311.73674 -214.33155)
		(width 0.10668)
		(layer "F.Cu")
		(net "M_A_CPU0_SA_DQ<12>")
	)
	(segment
		(start 311.585864 -214.33155)
		(end 311.285128 -214.632286)
		(width 0.10668)
		(layer "F.Cu")
		(net "M_A_CPU0_SA_DQ<12>")
	)
	(segment
		(start 325.38035 -233.79049)
		(end 323.903594 -233.79049)
		(width 0.0762)
		(layer "F.Cu")
		(net "M_A_CPU0_SA_DQ<12>")
	)
	(segment
		(start 310.438546 -213.93658)
		(end 310.438546 -213.785704)
		(width 0.10668)
		(layer "F.Cu")
		(net "M_A_CPU0_SA_DQ<12>")
	)
	(segment
		(start 310.438546 -213.785704)
		(end 310.739282 -213.484968)
		(width 0.10668)
		(layer "F.Cu")
		(net "M_A_CPU0_SA_DQ<12>")
	)
	(segment
		(start 310.569864 -214.067898)
		(end 310.438546 -213.93658)
		(width 0.10668)
		(layer "F.Cu")
		(net "M_A_CPU0_SA_DQ<12>")
	)
	(segment
		(start 311.69864 -215.196674)
		(end 311.567322 -215.065356)
		(width 0.10668)
		(layer "F.Cu")
		(net "M_A_CPU0_SA_DQ<12>")
	)
	(segment
		(start 312.150252 -214.895938)
		(end 311.849516 -215.196674)
		(width 0.10668)
		(layer "F.Cu")
		(net "M_A_CPU0_SA_DQ<12>")
	)
	(segment
		(start 312.13171 -215.629744)
		(end 312.13171 -215.478868)
		(width 0.10668)
		(layer "F.Cu")
		(net "M_A_CPU0_SA_DQ<12>")
	)
	(segment
		(start 309.874158 -213.221316)
		(end 310.174894 -212.92058)
		(width 0.10668)
		(layer "F.Cu")
		(net "M_A_CPU0_SA_DQ<12>")
	)
	(segment
		(start 312.432446 -215.027256)
		(end 312.301128 -214.895938)
		(width 0.10668)
		(layer "F.Cu")
		(net "M_A_CPU0_SA_DQ<12>")
	)
	(segment
		(start 311.002934 -214.350092)
		(end 311.30367 -214.049356)
		(width 0.10668)
		(layer "F.Cu")
		(net "M_A_CPU0_SA_DQ<12>")
	)
	(segment
		(start 312.263028 -215.761062)
		(end 312.13171 -215.629744)
		(width 0.10668)
		(layer "F.Cu")
		(net "M_A_CPU0_SA_DQ<12>")
	)
	(segment
		(start 310.457088 -213.202774)
		(end 310.156352 -213.50351)
		(width 0.10668)
		(layer "F.Cu")
		(net "M_A_CPU0_SA_DQ<12>")
	)
	(segment
		(start 311.021476 -213.767162)
		(end 310.72074 -214.067898)
		(width 0.10668)
		(layer "F.Cu")
		(net "M_A_CPU0_SA_DQ<12>")
	)
	(segment
		(start 323.903594 -233.79049)
		(end 323.111114 -233.79049)
		(width 0.10668)
		(layer "F.Cu")
		(net "M_A_CPU0_SA_DQ<12>")
	)
	(segment
		(start 311.285128 -214.632286)
		(end 311.134252 -214.632286)
		(width 0.10668)
		(layer "F.Cu")
		(net "M_A_CPU0_SA_DQ<12>")
	)
	(segment
		(start 312.413904 -215.761062)
		(end 312.263028 -215.761062)
		(width 0.10668)
		(layer "F.Cu")
		(net "M_A_CPU0_SA_DQ<12>")
	)
	(segment
		(start 310.174894 -212.92058)
		(end 310.174894 -212.769704)
		(width 0.10668)
		(layer "F.Cu")
		(net "M_A_CPU0_SA_DQ<12>")
	)
	(segment
		(start 317.260478 -227.939854)
		(end 317.260478 -219.855288)
		(width 0.10668)
		(layer "F.Cu")
		(net "M_A_CPU0_SA_DQ<12>")
	)
	(segment
		(start 312.71464 -215.460326)
		(end 312.413904 -215.761062)
		(width 0.10668)
		(layer "F.Cu")
		(net "M_A_CPU0_SA_DQ<12>")
	)
	(segment
		(start 310.607964 -213.202774)
		(end 310.457088 -213.202774)
		(width 0.10668)
		(layer "F.Cu")
		(net "M_A_CPU0_SA_DQ<12>")
	)
	(segment
		(start 311.30367 -213.89848)
		(end 311.172352 -213.767162)
		(width 0.10668)
		(layer "F.Cu")
		(net "M_A_CPU0_SA_DQ<12>")
	)
	(segment
		(start 312.301128 -214.895938)
		(end 312.150252 -214.895938)
		(width 0.10668)
		(layer "F.Cu")
		(net "M_A_CPU0_SA_DQ<12>")
	)
	(segment
		(start 312.432446 -215.178132)
		(end 312.432446 -215.027256)
		(width 0.10668)
		(layer "F.Cu")
		(net "M_A_CPU0_SA_DQ<12>")
	)
	(segment
		(start 311.849516 -215.196674)
		(end 311.69864 -215.196674)
		(width 0.10668)
		(layer "F.Cu")
		(net "M_A_CPU0_SA_DQ<12>")
	)
	(segment
		(start 312.13171 -215.478868)
		(end 312.432446 -215.178132)
		(width 0.10668)
		(layer "F.Cu")
		(net "M_A_CPU0_SA_DQ<12>")
	)
	(segment
		(start 310.739282 -213.484968)
		(end 310.739282 -213.334092)
		(width 0.10668)
		(layer "F.Cu")
		(net "M_A_CPU0_SA_DQ<12>")
	)
	(segment
		(start 311.172352 -213.767162)
		(end 311.021476 -213.767162)
		(width 0.10668)
		(layer "F.Cu")
		(net "M_A_CPU0_SA_DQ<12>")
	)
	(segment
		(start 310.174894 -212.769704)
		(end 310.040274 -212.635084)
		(width 0.10668)
		(layer "F.Cu")
		(net "M_A_CPU0_SA_DQ<12>")
	)
	(segment
		(start 312.865516 -215.460326)
		(end 312.71464 -215.460326)
		(width 0.10668)
		(layer "F.Cu")
		(net "M_A_CPU0_SA_DQ<12>")
	)
	(segment
		(start 310.156352 -213.50351)
		(end 310.005476 -213.50351)
		(width 0.10668)
		(layer "F.Cu")
		(net "M_A_CPU0_SA_DQ<12>")
	)
	(segment
		(start 311.134252 -214.632286)
		(end 311.002934 -214.500968)
		(width 0.10668)
		(layer "F.Cu")
		(net "M_A_CPU0_SA_DQ<12>")
	)
	(segment
		(start 311.002934 -214.500968)
		(end 311.002934 -214.350092)
		(width 0.10668)
		(layer "F.Cu")
		(net "M_A_CPU0_SA_DQ<12>")
	)
	(segment
		(start 311.868058 -214.613744)
		(end 311.868058 -214.462868)
		(width 0.10668)
		(layer "F.Cu")
		(net "M_A_CPU0_SA_DQ<12>")
	)
	(segment
		(start 310.72074 -214.067898)
		(end 310.569864 -214.067898)
		(width 0.10668)
		(layer "F.Cu")
		(net "M_A_CPU0_SA_DQ<12>")
	)
	(segment
		(start 310.739282 -213.334092)
		(end 310.607964 -213.202774)
		(width 0.10668)
		(layer "F.Cu")
		(net "M_A_CPU0_SA_DQ<12>")
	)
	(segment
		(start 323.111114 -233.79049)
		(end 317.260478 -227.939854)
		(width 0.10668)
		(layer "F.Cu")
		(net "M_A_CPU0_SA_DQ<12>")
	)
	(segment
		(start 310.005476 -213.50351)
		(end 309.874158 -213.372192)
		(width 0.10668)
		(layer "F.Cu")
		(net "M_A_CPU0_SA_DQ<12>")
	)
	(segment
		(start 317.260478 -219.855288)
		(end 312.865516 -215.460326)
		(width 0.10668)
		(layer "F.Cu")
		(net "M_A_CPU0_SA_DQ<12>")
	)
	(segment
		(start 311.567322 -214.91448)
		(end 311.868058 -214.613744)
		(width 0.10668)
		(layer "F.Cu")
		(net "M_A_CPU0_SA_DQ<12>")
	)
	(segment
		(start 309.874158 -213.372192)
		(end 309.874158 -213.221316)
		(width 0.10668)
		(layer "F.Cu")
		(net "M_A_CPU0_SA_DQ<12>")
	)
	(segment
		(start 310.040274 -212.635084)
		(end 307.368194 -212.635084)
		(width 0.10668)
		(layer "F.Cu")
		(net "M_A_CPU0_SA_DQ<12>")
	)
	(segment
		(start 311.73674 -214.33155)
		(end 311.585864 -214.33155)
		(width 0.10668)
		(layer "F.Cu")
		(net "M_A_CPU0_SA_DQ<12>")
	)
	(segment
		(start 311.567322 -215.065356)
		(end 311.567322 -214.91448)
		(width 0.10668)
		(layer "F.Cu")
		(net "M_A_CPU0_SA_DQ<12>")
	)
	(segment
		(start 311.30367 -214.049356)
		(end 311.30367 -213.89848)
		(width 0.10668)
		(layer "F.Cu")
		(net "M_A_CPU0_SA_DQ<12>")
	)
	(arc
		(start 326.34809 -233.409998)
		(mid 326.111962 -233.581433)
		(end 325.830438 -233.658156)
		(width 0.0762)
		(layer "F.Cu")
		(net "M_A_CPU0_SA_DQ<12>")
	)
	(arc
		(start 325.830438 -233.658156)
		(mid 325.708582 -233.682312)
		(end 325.59498 -233.732578)
		(width 0.0762)
		(layer "F.Cu")
		(net "M_A_CPU0_SA_DQ<12>")
	)
	(arc
		(start 325.59498 -233.732578)
		(mid 325.491502 -233.775754)
		(end 325.38035 -233.79049)
		(width 0.0762)
		(layer "F.Cu")
		(net "M_A_CPU0_SA_DQ<12>")
	)
	(segment
		(start 308.28488 -209.660236)
		(end 305.74488 -209.660236)
		(width 0.101346)
		(layer "F.Cu")
		(net "M_A_CPU0_SA_DQ<11>")
	)
	(segment
		(start 327.108312 -231.463342)
		(end 327.100946 -231.46766)
		(width 0.0762)
		(layer "F.Cu")
		(net "M_A_CPU0_SA_DQ<11>")
	)
	(segment
		(start 311.819036 -210.896962)
		(end 308.833266 -209.660236)
		(width 0.10668)
		(layer "F.Cu")
		(net "M_A_CPU0_SA_DQ<11>")
	)
	(segment
		(start 324.542404 -231.41686)
		(end 324.360794 -231.59847)
		(width 0.0762)
		(layer "F.Cu")
		(net "M_A_CPU0_SA_DQ<11>")
	)
	(segment
		(start 325.408036 -231.41686)
		(end 324.542404 -231.41686)
		(width 0.0762)
		(layer "F.Cu")
		(net "M_A_CPU0_SA_DQ<11>")
	)
	(segment
		(start 318.327532 -217.180668)
		(end 312.496454 -211.34959)
		(width 0.10668)
		(layer "F.Cu")
		(net "M_A_CPU0_SA_DQ<11>")
	)
	(segment
		(start 308.833266 -209.660236)
		(end 308.28488 -209.660236)
		(width 0.10668)
		(layer "F.Cu")
		(net "M_A_CPU0_SA_DQ<11>")
	)
	(segment
		(start 312.496454 -211.34959)
		(end 311.819036 -210.896962)
		(width 0.10668)
		(layer "F.Cu")
		(net "M_A_CPU0_SA_DQ<11>")
	)
	(segment
		(start 319.147698 -219.16009)
		(end 318.327532 -217.180668)
		(width 0.10668)
		(layer "F.Cu")
		(net "M_A_CPU0_SA_DQ<11>")
	)
	(segment
		(start 305.319684 -209.23504)
		(end 303.268126 -209.23504)
		(width 0.101346)
		(layer "F.Cu")
		(net "M_A_CPU0_SA_DQ<11>")
	)
	(segment
		(start 324.360794 -231.59847)
		(end 323.634354 -231.59847)
		(width 0.10668)
		(layer "F.Cu")
		(net "M_A_CPU0_SA_DQ<11>")
	)
	(segment
		(start 319.147698 -227.111814)
		(end 319.147698 -219.16009)
		(width 0.10668)
		(layer "F.Cu")
		(net "M_A_CPU0_SA_DQ<11>")
	)
	(segment
		(start 327.109328 -231.462834)
		(end 327.108312 -231.463342)
		(width 0.0762)
		(layer "F.Cu")
		(net "M_A_CPU0_SA_DQ<11>")
	)
	(segment
		(start 326.535034 -231.46766)
		(end 326.526652 -231.462834)
		(width 0.0762)
		(layer "F.Cu")
		(net "M_A_CPU0_SA_DQ<11>")
	)
	(segment
		(start 327.28789 -231.789986)
		(end 327.393046 -231.609138)
		(width 0.0762)
		(layer "F.Cu")
		(net "M_A_CPU0_SA_DQ<11>")
	)
	(segment
		(start 305.74488 -209.660236)
		(end 305.319684 -209.23504)
		(width 0.101346)
		(layer "F.Cu")
		(net "M_A_CPU0_SA_DQ<11>")
	)
	(segment
		(start 323.634354 -231.59847)
		(end 319.147698 -227.111814)
		(width 0.10668)
		(layer "F.Cu")
		(net "M_A_CPU0_SA_DQ<11>")
	)
	(arc
		(start 327.100946 -231.46766)
		(mid 326.81799 -231.543837)
		(end 326.535034 -231.46766)
		(width 0.0762)
		(layer "F.Cu")
		(net "M_A_CPU0_SA_DQ<11>")
	)
	(arc
		(start 326.526652 -231.462834)
		(mid 326.343144 -231.417309)
		(end 326.160892 -231.46766)
		(width 0.0762)
		(layer "F.Cu")
		(net "M_A_CPU0_SA_DQ<11>")
	)
	(arc
		(start 326.160892 -231.46766)
		(mid 325.877936 -231.543837)
		(end 325.59498 -231.46766)
		(width 0.0762)
		(layer "F.Cu")
		(net "M_A_CPU0_SA_DQ<11>")
	)
	(arc
		(start 325.59498 -231.46766)
		(mid 325.504867 -231.429891)
		(end 325.408036 -231.41686)
		(width 0.0762)
		(layer "F.Cu")
		(net "M_A_CPU0_SA_DQ<11>")
	)
	(arc
		(start 327.393046 -231.609138)
		(mid 327.384109 -231.490114)
		(end 327.289414 -231.417368)
		(width 0.0762)
		(layer "F.Cu")
		(net "M_A_CPU0_SA_DQ<11>")
	)
	(arc
		(start 327.289414 -231.417368)
		(mid 327.19649 -231.428691)
		(end 327.109328 -231.462834)
		(width 0.0762)
		(layer "F.Cu")
		(net "M_A_CPU0_SA_DQ<11>")
	)
	(segment
		(start 323.868542 -230.86949)
		(end 319.828418 -226.829366)
		(width 0.10668)
		(layer "F.Cu")
		(net "M_A_CPU0_SA_DQ<10>")
	)
	(segment
		(start 319.828418 -217.640154)
		(end 310.148478 -207.960214)
		(width 0.10668)
		(layer "F.Cu")
		(net "M_A_CPU0_SA_DQ<10>")
	)
	(segment
		(start 324.238874 -230.86949)
		(end 323.868542 -230.86949)
		(width 0.10668)
		(layer "F.Cu")
		(net "M_A_CPU0_SA_DQ<10>")
	)
	(segment
		(start 325.699374 -230.652574)
		(end 325.690992 -230.6574)
		(width 0.0762)
		(layer "F.Cu")
		(net "M_A_CPU0_SA_DQ<10>")
	)
	(segment
		(start 324.903592 -230.86949)
		(end 324.238874 -230.86949)
		(width 0.0762)
		(layer "F.Cu")
		(net "M_A_CPU0_SA_DQ<10>")
	)
	(segment
		(start 305.645312 -207.535018)
		(end 303.268126 -207.535018)
		(width 0.101346)
		(layer "F.Cu")
		(net "M_A_CPU0_SA_DQ<10>")
	)
	(segment
		(start 325.877936 -230.97998)
		(end 325.9709 -230.81996)
		(width 0.0762)
		(layer "F.Cu")
		(net "M_A_CPU0_SA_DQ<10>")
	)
	(segment
		(start 308.610508 -207.960214)
		(end 306.070508 -207.960214)
		(width 0.101346)
		(layer "F.Cu")
		(net "M_A_CPU0_SA_DQ<10>")
	)
	(segment
		(start 310.148478 -207.960214)
		(end 308.610508 -207.960214)
		(width 0.10668)
		(layer "F.Cu")
		(net "M_A_CPU0_SA_DQ<10>")
	)
	(segment
		(start 319.828418 -226.829366)
		(end 319.828418 -217.640154)
		(width 0.10668)
		(layer "F.Cu")
		(net "M_A_CPU0_SA_DQ<10>")
	)
	(segment
		(start 306.070508 -207.960214)
		(end 305.645312 -207.535018)
		(width 0.101346)
		(layer "F.Cu")
		(net "M_A_CPU0_SA_DQ<10>")
	)
	(arc
		(start 325.9709 -230.81996)
		(mid 325.97074 -230.673399)
		(end 325.839074 -230.60914)
		(width 0.0762)
		(layer "F.Cu")
		(net "M_A_CPU0_SA_DQ<10>")
	)
	(arc
		(start 325.839074 -230.60914)
		(mid 325.767066 -230.623922)
		(end 325.699374 -230.652574)
		(width 0.0762)
		(layer "F.Cu")
		(net "M_A_CPU0_SA_DQ<10>")
	)
	(arc
		(start 325.690992 -230.6574)
		(mid 325.311324 -230.815539)
		(end 324.903592 -230.86949)
		(width 0.0762)
		(layer "F.Cu")
		(net "M_A_CPU0_SA_DQ<10>")
	)
	(segment
		(start 323.070982 -212.075776)
		(end 322.953888 -211.958682)
		(width 0.10668)
		(layer "F.Cu")
		(net "M_A_CPU0_SA_DQ<0>")
	)
	(segment
		(start 322.066666 -211.552028)
		(end 321.901566 -211.552028)
		(width 0.10668)
		(layer "F.Cu")
		(net "M_A_CPU0_SA_DQ<0>")
	)
	(segment
		(start 323.353176 -212.52307)
		(end 323.195442 -212.680804)
		(width 0.10668)
		(layer "F.Cu")
		(net "M_A_CPU0_SA_DQ<0>")
	)
	(segment
		(start 323.518276 -212.52307)
		(end 323.353176 -212.52307)
		(width 0.10668)
		(layer "F.Cu")
		(net "M_A_CPU0_SA_DQ<0>")
	)
	(segment
		(start 323.917564 -213.087458)
		(end 323.75983 -213.245192)
		(width 0.10668)
		(layer "F.Cu")
		(net "M_A_CPU0_SA_DQ<0>")
	)
	(segment
		(start 324.082664 -213.087458)
		(end 323.917564 -213.087458)
		(width 0.10668)
		(layer "F.Cu")
		(net "M_A_CPU0_SA_DQ<0>")
	)
	(segment
		(start 325.331074 -224.73285)
		(end 324.995794 -224.39757)
		(width 0.0762)
		(layer "F.Cu")
		(net "M_A_CPU0_SA_DQ<0>")
	)
	(segment
		(start 321.784472 -211.434934)
		(end 321.784472 -211.269834)
		(width 0.10668)
		(layer "F.Cu")
		(net "M_A_CPU0_SA_DQ<0>")
	)
	(segment
		(start 321.942206 -211.1121)
		(end 321.942206 -210.947)
		(width 0.10668)
		(layer "F.Cu")
		(net "M_A_CPU0_SA_DQ<0>")
	)
	(segment
		(start 324.995794 -224.39757)
		(end 324.802754 -224.39757)
		(width 0.0762)
		(layer "F.Cu")
		(net "M_A_CPU0_SA_DQ<0>")
	)
	(segment
		(start 322.2244 -211.394294)
		(end 322.066666 -211.552028)
		(width 0.10668)
		(layer "F.Cu")
		(net "M_A_CPU0_SA_DQ<0>")
	)
	(segment
		(start 321.220084 -210.705446)
		(end 321.377818 -210.547712)
		(width 0.10668)
		(layer "F.Cu")
		(net "M_A_CPU0_SA_DQ<0>")
	)
	(segment
		(start 320.208402 -209.858864)
		(end 312.627772 -202.278234)
		(width 0.10668)
		(layer "F.Cu")
		(net "M_A_CPU0_SA_DQ<0>")
	)
	(segment
		(start 312.627772 -202.278234)
		(end 312.627772 -201.793856)
		(width 0.10668)
		(layer "F.Cu")
		(net "M_A_CPU0_SA_DQ<0>")
	)
	(segment
		(start 324.199758 -213.369652)
		(end 324.199758 -213.204552)
		(width 0.10668)
		(layer "F.Cu")
		(net "M_A_CPU0_SA_DQ<0>")
	)
	(segment
		(start 320.93789 -210.423252)
		(end 320.77279 -210.423252)
		(width 0.10668)
		(layer "F.Cu")
		(net "M_A_CPU0_SA_DQ<0>")
	)
	(segment
		(start 325.89216 -225.014028)
		(end 325.711312 -225.014028)
		(width 0.0762)
		(layer "F.Cu")
		(net "M_A_CPU0_SA_DQ<0>")
	)
	(segment
		(start 323.477636 -212.962998)
		(end 323.63537 -212.805264)
		(width 0.10668)
		(layer "F.Cu")
		(net "M_A_CPU0_SA_DQ<0>")
	)
	(segment
		(start 320.81343 -209.983324)
		(end 320.81343 -209.818224)
		(width 0.10668)
		(layer "F.Cu")
		(net "M_A_CPU0_SA_DQ<0>")
	)
	(segment
		(start 321.220084 -210.870546)
		(end 321.220084 -210.705446)
		(width 0.10668)
		(layer "F.Cu")
		(net "M_A_CPU0_SA_DQ<0>")
	)
	(segment
		(start 320.655696 -210.141058)
		(end 320.81343 -209.983324)
		(width 0.10668)
		(layer "F.Cu")
		(net "M_A_CPU0_SA_DQ<0>")
	)
	(segment
		(start 322.34886 -211.999322)
		(end 322.34886 -211.834222)
		(width 0.10668)
		(layer "F.Cu")
		(net "M_A_CPU0_SA_DQ<0>")
	)
	(segment
		(start 323.63537 -212.805264)
		(end 323.63537 -212.640164)
		(width 0.10668)
		(layer "F.Cu")
		(net "M_A_CPU0_SA_DQ<0>")
	)
	(segment
		(start 320.531236 -209.70113)
		(end 320.373502 -209.858864)
		(width 0.10668)
		(layer "F.Cu")
		(net "M_A_CPU0_SA_DQ<0>")
	)
	(segment
		(start 324.199758 -213.204552)
		(end 324.082664 -213.087458)
		(width 0.10668)
		(layer "F.Cu")
		(net "M_A_CPU0_SA_DQ<0>")
	)
	(segment
		(start 325.711312 -225.014028)
		(end 325.430134 -224.73285)
		(width 0.0762)
		(layer "F.Cu")
		(net "M_A_CPU0_SA_DQ<0>")
	)
	(segment
		(start 321.337178 -210.98764)
		(end 321.220084 -210.870546)
		(width 0.10668)
		(layer "F.Cu")
		(net "M_A_CPU0_SA_DQ<0>")
	)
	(segment
		(start 322.465954 -212.116416)
		(end 322.34886 -211.999322)
		(width 0.10668)
		(layer "F.Cu")
		(net "M_A_CPU0_SA_DQ<0>")
	)
	(segment
		(start 321.784472 -211.269834)
		(end 321.942206 -211.1121)
		(width 0.10668)
		(layer "F.Cu")
		(net "M_A_CPU0_SA_DQ<0>")
	)
	(segment
		(start 308.169056 -197.33514)
		(end 307.368194 -197.33514)
		(width 0.10668)
		(layer "F.Cu")
		(net "M_A_CPU0_SA_DQ<0>")
	)
	(segment
		(start 320.655696 -210.306158)
		(end 320.655696 -210.141058)
		(width 0.10668)
		(layer "F.Cu")
		(net "M_A_CPU0_SA_DQ<0>")
	)
	(segment
		(start 323.195442 -212.680804)
		(end 323.030342 -212.680804)
		(width 0.10668)
		(layer "F.Cu")
		(net "M_A_CPU0_SA_DQ<0>")
	)
	(segment
		(start 321.260724 -210.265518)
		(end 321.095624 -210.265518)
		(width 0.10668)
		(layer "F.Cu")
		(net "M_A_CPU0_SA_DQ<0>")
	)
	(segment
		(start 321.377818 -210.382612)
		(end 321.260724 -210.265518)
		(width 0.10668)
		(layer "F.Cu")
		(net "M_A_CPU0_SA_DQ<0>")
	)
	(segment
		(start 322.913248 -212.56371)
		(end 322.913248 -212.39861)
		(width 0.10668)
		(layer "F.Cu")
		(net "M_A_CPU0_SA_DQ<0>")
	)
	(segment
		(start 322.506594 -211.511388)
		(end 322.3895 -211.394294)
		(width 0.10668)
		(layer "F.Cu")
		(net "M_A_CPU0_SA_DQ<0>")
	)
	(segment
		(start 312.627772 -201.793856)
		(end 308.169056 -197.33514)
		(width 0.10668)
		(layer "F.Cu")
		(net "M_A_CPU0_SA_DQ<0>")
	)
	(segment
		(start 324.042024 -213.692486)
		(end 324.042024 -213.527386)
		(width 0.10668)
		(layer "F.Cu")
		(net "M_A_CPU0_SA_DQ<0>")
	)
	(segment
		(start 322.34886 -211.834222)
		(end 322.506594 -211.676488)
		(width 0.10668)
		(layer "F.Cu")
		(net "M_A_CPU0_SA_DQ<0>")
	)
	(segment
		(start 320.81343 -209.818224)
		(end 320.696336 -209.70113)
		(width 0.10668)
		(layer "F.Cu")
		(net "M_A_CPU0_SA_DQ<0>")
	)
	(segment
		(start 324.802754 -224.39757)
		(end 324.555358 -224.150174)
		(width 0.0762)
		(layer "F.Cu")
		(net "M_A_CPU0_SA_DQ<0>")
	)
	(segment
		(start 321.825112 -210.829906)
		(end 321.660012 -210.829906)
		(width 0.10668)
		(layer "F.Cu")
		(net "M_A_CPU0_SA_DQ<0>")
	)
	(segment
		(start 324.555358 -224.150174)
		(end 324.555358 -214.20582)
		(width 0.10668)
		(layer "F.Cu")
		(net "M_A_CPU0_SA_DQ<0>")
	)
	(segment
		(start 323.477636 -213.128098)
		(end 323.477636 -212.962998)
		(width 0.10668)
		(layer "F.Cu")
		(net "M_A_CPU0_SA_DQ<0>")
	)
	(segment
		(start 322.788788 -211.958682)
		(end 322.631054 -212.116416)
		(width 0.10668)
		(layer "F.Cu")
		(net "M_A_CPU0_SA_DQ<0>")
	)
	(segment
		(start 320.696336 -209.70113)
		(end 320.531236 -209.70113)
		(width 0.10668)
		(layer "F.Cu")
		(net "M_A_CPU0_SA_DQ<0>")
	)
	(segment
		(start 323.75983 -213.245192)
		(end 323.59473 -213.245192)
		(width 0.10668)
		(layer "F.Cu")
		(net "M_A_CPU0_SA_DQ<0>")
	)
	(segment
		(start 324.042024 -213.527386)
		(end 324.199758 -213.369652)
		(width 0.10668)
		(layer "F.Cu")
		(net "M_A_CPU0_SA_DQ<0>")
	)
	(segment
		(start 323.030342 -212.680804)
		(end 322.913248 -212.56371)
		(width 0.10668)
		(layer "F.Cu")
		(net "M_A_CPU0_SA_DQ<0>")
	)
	(segment
		(start 323.070982 -212.240876)
		(end 323.070982 -212.075776)
		(width 0.10668)
		(layer "F.Cu")
		(net "M_A_CPU0_SA_DQ<0>")
	)
	(segment
		(start 320.77279 -210.423252)
		(end 320.655696 -210.306158)
		(width 0.10668)
		(layer "F.Cu")
		(net "M_A_CPU0_SA_DQ<0>")
	)
	(segment
		(start 322.953888 -211.958682)
		(end 322.788788 -211.958682)
		(width 0.10668)
		(layer "F.Cu")
		(net "M_A_CPU0_SA_DQ<0>")
	)
	(segment
		(start 322.3895 -211.394294)
		(end 322.2244 -211.394294)
		(width 0.10668)
		(layer "F.Cu")
		(net "M_A_CPU0_SA_DQ<0>")
	)
	(segment
		(start 323.59473 -213.245192)
		(end 323.477636 -213.128098)
		(width 0.10668)
		(layer "F.Cu")
		(net "M_A_CPU0_SA_DQ<0>")
	)
	(segment
		(start 322.631054 -212.116416)
		(end 322.465954 -212.116416)
		(width 0.10668)
		(layer "F.Cu")
		(net "M_A_CPU0_SA_DQ<0>")
	)
	(segment
		(start 321.377818 -210.547712)
		(end 321.377818 -210.382612)
		(width 0.10668)
		(layer "F.Cu")
		(net "M_A_CPU0_SA_DQ<0>")
	)
	(segment
		(start 325.430134 -224.73285)
		(end 325.331074 -224.73285)
		(width 0.0762)
		(layer "F.Cu")
		(net "M_A_CPU0_SA_DQ<0>")
	)
	(segment
		(start 321.942206 -210.947)
		(end 321.825112 -210.829906)
		(width 0.10668)
		(layer "F.Cu")
		(net "M_A_CPU0_SA_DQ<0>")
	)
	(segment
		(start 320.373502 -209.858864)
		(end 320.208402 -209.858864)
		(width 0.10668)
		(layer "F.Cu")
		(net "M_A_CPU0_SA_DQ<0>")
	)
	(segment
		(start 321.660012 -210.829906)
		(end 321.502278 -210.98764)
		(width 0.10668)
		(layer "F.Cu")
		(net "M_A_CPU0_SA_DQ<0>")
	)
	(segment
		(start 321.095624 -210.265518)
		(end 320.93789 -210.423252)
		(width 0.10668)
		(layer "F.Cu")
		(net "M_A_CPU0_SA_DQ<0>")
	)
	(segment
		(start 322.506594 -211.676488)
		(end 322.506594 -211.511388)
		(width 0.10668)
		(layer "F.Cu")
		(net "M_A_CPU0_SA_DQ<0>")
	)
	(segment
		(start 321.502278 -210.98764)
		(end 321.337178 -210.98764)
		(width 0.10668)
		(layer "F.Cu")
		(net "M_A_CPU0_SA_DQ<0>")
	)
	(segment
		(start 321.901566 -211.552028)
		(end 321.784472 -211.434934)
		(width 0.10668)
		(layer "F.Cu")
		(net "M_A_CPU0_SA_DQ<0>")
	)
	(segment
		(start 323.63537 -212.640164)
		(end 323.518276 -212.52307)
		(width 0.10668)
		(layer "F.Cu")
		(net "M_A_CPU0_SA_DQ<0>")
	)
	(segment
		(start 322.913248 -212.39861)
		(end 323.070982 -212.240876)
		(width 0.10668)
		(layer "F.Cu")
		(net "M_A_CPU0_SA_DQ<0>")
	)
	(segment
		(start 324.555358 -214.20582)
		(end 324.042024 -213.692486)
		(width 0.10668)
		(layer "F.Cu")
		(net "M_A_CPU0_SA_DQ<0>")
	)
	(arc
		(start 326.34809 -225.310192)
		(mid 326.136006 -225.13766)
		(end 325.89216 -225.014028)
		(width 0.0762)
		(layer "F.Cu")
		(net "M_A_CPU0_SA_DQ<0>")
	)
	(segment
		(start 327.28789 -252.850142)
		(end 327.28789 -252.849888)
		(width 0.0762)
		(layer "F.Cu")
		(net "M_A_CPU0_SA_CS_N<1>")
	)
	(segment
		(start 308.372764 -247.059958)
		(end 306.070508 -247.059958)
		(width 0.101346)
		(layer "F.Cu")
		(net "M_A_CPU0_SA_CS_N<1>")
	)
	(segment
		(start 327.109328 -252.522736)
		(end 327.108312 -252.523244)
		(width 0.0762)
		(layer "F.Cu")
		(net "M_A_CPU0_SA_CS_N<1>")
	)
	(segment
		(start 309.389018 -248.923048)
		(end 308.685438 -248.219468)
		(width 0.10668)
		(layer "F.Cu")
		(net "M_A_CPU0_SA_CS_N<1>")
	)
	(segment
		(start 308.685438 -248.219468)
		(end 308.685438 -247.372632)
		(width 0.10668)
		(layer "F.Cu")
		(net "M_A_CPU0_SA_CS_N<1>")
	)
	(segment
		(start 326.535034 -252.527562)
		(end 326.526652 -252.522736)
		(width 0.0762)
		(layer "F.Cu")
		(net "M_A_CPU0_SA_CS_N<1>")
	)
	(segment
		(start 306.070508 -247.059958)
		(end 305.645566 -246.635016)
		(width 0.101346)
		(layer "F.Cu")
		(net "M_A_CPU0_SA_CS_N<1>")
	)
	(segment
		(start 308.685438 -247.372632)
		(end 308.372764 -247.059958)
		(width 0.101346)
		(layer "F.Cu")
		(net "M_A_CPU0_SA_CS_N<1>")
	)
	(segment
		(start 305.645566 -246.635016)
		(end 303.268126 -246.635016)
		(width 0.101346)
		(layer "F.Cu")
		(net "M_A_CPU0_SA_CS_N<1>")
	)
	(segment
		(start 321.51955 -252.20803)
		(end 320.740532 -251.429012)
		(width 0.10668)
		(layer "F.Cu")
		(net "M_A_CPU0_SA_CS_N<1>")
	)
	(segment
		(start 325.380096 -252.46965)
		(end 324.627494 -252.46965)
		(width 0.0762)
		(layer "F.Cu")
		(net "M_A_CPU0_SA_CS_N<1>")
	)
	(segment
		(start 327.108312 -252.523244)
		(end 327.100946 -252.527562)
		(width 0.0762)
		(layer "F.Cu")
		(net "M_A_CPU0_SA_CS_N<1>")
	)
	(segment
		(start 309.389018 -249.522742)
		(end 309.389018 -248.923048)
		(width 0.10668)
		(layer "F.Cu")
		(net "M_A_CPU0_SA_CS_N<1>")
	)
	(segment
		(start 327.28789 -252.849888)
		(end 327.393046 -252.66904)
		(width 0.0762)
		(layer "F.Cu")
		(net "M_A_CPU0_SA_CS_N<1>")
	)
	(segment
		(start 311.295288 -251.429012)
		(end 309.389018 -249.522742)
		(width 0.10668)
		(layer "F.Cu")
		(net "M_A_CPU0_SA_CS_N<1>")
	)
	(segment
		(start 324.627494 -252.46965)
		(end 324.365874 -252.20803)
		(width 0.10668)
		(layer "F.Cu")
		(net "M_A_CPU0_SA_CS_N<1>")
	)
	(segment
		(start 324.365874 -252.20803)
		(end 321.51955 -252.20803)
		(width 0.10668)
		(layer "F.Cu")
		(net "M_A_CPU0_SA_CS_N<1>")
	)
	(segment
		(start 320.740532 -251.429012)
		(end 311.295288 -251.429012)
		(width 0.10668)
		(layer "F.Cu")
		(net "M_A_CPU0_SA_CS_N<1>")
	)
	(arc
		(start 326.160892 -252.527562)
		(mid 325.877936 -252.603739)
		(end 325.59498 -252.527562)
		(width 0.0762)
		(layer "F.Cu")
		(net "M_A_CPU0_SA_CS_N<1>")
	)
	(arc
		(start 327.289414 -252.47727)
		(mid 327.19649 -252.488593)
		(end 327.109328 -252.522736)
		(width 0.0762)
		(layer "F.Cu")
		(net "M_A_CPU0_SA_CS_N<1>")
	)
	(arc
		(start 326.526652 -252.522736)
		(mid 326.343144 -252.477242)
		(end 326.160892 -252.527562)
		(width 0.0762)
		(layer "F.Cu")
		(net "M_A_CPU0_SA_CS_N<1>")
	)
	(arc
		(start 325.59498 -252.527562)
		(mid 325.491378 -252.484342)
		(end 325.380096 -252.46965)
		(width 0.0762)
		(layer "F.Cu")
		(net "M_A_CPU0_SA_CS_N<1>")
	)
	(arc
		(start 327.393046 -252.66904)
		(mid 327.384109 -252.550016)
		(end 327.289414 -252.47727)
		(width 0.0762)
		(layer "F.Cu")
		(net "M_A_CPU0_SA_CS_N<1>")
	)
	(arc
		(start 327.100946 -252.527562)
		(mid 326.81799 -252.603739)
		(end 326.535034 -252.527562)
		(width 0.0762)
		(layer "F.Cu")
		(net "M_A_CPU0_SA_CS_N<1>")
	)
	(segment
		(start 308.15026 -246.047514)
		(end 308.037738 -245.934992)
		(width 0.10668)
		(layer "F.Cu")
		(net "M_A_CPU0_SA_CS_N<0>")
	)
	(segment
		(start 309.025798 -246.923052)
		(end 308.15026 -246.047514)
		(width 0.101346)
		(layer "F.Cu")
		(net "M_A_CPU0_SA_CS_N<0>")
	)
	(segment
		(start 321.660774 -251.86767)
		(end 320.881756 -251.088652)
		(width 0.10668)
		(layer "F.Cu")
		(net "M_A_CPU0_SA_CS_N<0>")
	)
	(segment
		(start 309.729378 -249.381518)
		(end 309.729378 -248.78157)
		(width 0.10668)
		(layer "F.Cu")
		(net "M_A_CPU0_SA_CS_N<0>")
	)
	(segment
		(start 323.462904 -251.477272)
		(end 323.356224 -251.370592)
		(width 0.10668)
		(layer "F.Cu")
		(net "M_A_CPU0_SA_CS_N<0>")
	)
	(segment
		(start 323.356224 -251.370592)
		(end 323.17055 -251.370592)
		(width 0.10668)
		(layer "F.Cu")
		(net "M_A_CPU0_SA_CS_N<0>")
	)
	(segment
		(start 322.95719 -251.86767)
		(end 322.771516 -251.86767)
		(width 0.10668)
		(layer "F.Cu")
		(net "M_A_CPU0_SA_CS_N<0>")
	)
	(segment
		(start 322.372482 -251.370592)
		(end 322.265802 -251.477272)
		(width 0.10668)
		(layer "F.Cu")
		(net "M_A_CPU0_SA_CS_N<0>")
	)
	(segment
		(start 325.134478 -251.86767)
		(end 324.249034 -251.86767)
		(width 0.0762)
		(layer "F.Cu")
		(net "M_A_CPU0_SA_CS_N<0>")
	)
	(segment
		(start 308.037738 -245.934992)
		(end 307.518054 -245.934992)
		(width 0.10668)
		(layer "F.Cu")
		(net "M_A_CPU0_SA_CS_N<0>")
	)
	(segment
		(start 322.159122 -251.86767)
		(end 321.660774 -251.86767)
		(width 0.10668)
		(layer "F.Cu")
		(net "M_A_CPU0_SA_CS_N<0>")
	)
	(segment
		(start 322.664836 -251.477272)
		(end 322.558156 -251.370592)
		(width 0.10668)
		(layer "F.Cu")
		(net "M_A_CPU0_SA_CS_N<0>")
	)
	(segment
		(start 309.025798 -248.07799)
		(end 309.025798 -246.923052)
		(width 0.10668)
		(layer "F.Cu")
		(net "M_A_CPU0_SA_CS_N<0>")
	)
	(segment
		(start 322.265802 -251.477272)
		(end 322.265802 -251.76099)
		(width 0.10668)
		(layer "F.Cu")
		(net "M_A_CPU0_SA_CS_N<0>")
	)
	(segment
		(start 311.436512 -251.088652)
		(end 309.729378 -249.381518)
		(width 0.10668)
		(layer "F.Cu")
		(net "M_A_CPU0_SA_CS_N<0>")
	)
	(segment
		(start 323.17055 -251.370592)
		(end 323.06387 -251.477272)
		(width 0.10668)
		(layer "F.Cu")
		(net "M_A_CPU0_SA_CS_N<0>")
	)
	(segment
		(start 325.699374 -251.71273)
		(end 325.690992 -251.717556)
		(width 0.0762)
		(layer "F.Cu")
		(net "M_A_CPU0_SA_CS_N<0>")
	)
	(segment
		(start 324.249034 -251.86767)
		(end 323.569584 -251.86767)
		(width 0.10668)
		(layer "F.Cu")
		(net "M_A_CPU0_SA_CS_N<0>")
	)
	(segment
		(start 322.558156 -251.370592)
		(end 322.372482 -251.370592)
		(width 0.10668)
		(layer "F.Cu")
		(net "M_A_CPU0_SA_CS_N<0>")
	)
	(segment
		(start 322.664836 -251.76099)
		(end 322.664836 -251.477272)
		(width 0.10668)
		(layer "F.Cu")
		(net "M_A_CPU0_SA_CS_N<0>")
	)
	(segment
		(start 307.518054 -245.934992)
		(end 307.368194 -245.785132)
		(width 0.10668)
		(layer "F.Cu")
		(net "M_A_CPU0_SA_CS_N<0>")
	)
	(segment
		(start 320.881756 -251.088652)
		(end 311.436512 -251.088652)
		(width 0.10668)
		(layer "F.Cu")
		(net "M_A_CPU0_SA_CS_N<0>")
	)
	(segment
		(start 323.06387 -251.477272)
		(end 323.06387 -251.76099)
		(width 0.10668)
		(layer "F.Cu")
		(net "M_A_CPU0_SA_CS_N<0>")
	)
	(segment
		(start 325.877936 -252.040136)
		(end 325.9709 -251.880116)
		(width 0.0762)
		(layer "F.Cu")
		(net "M_A_CPU0_SA_CS_N<0>")
	)
	(segment
		(start 323.06387 -251.76099)
		(end 322.95719 -251.86767)
		(width 0.10668)
		(layer "F.Cu")
		(net "M_A_CPU0_SA_CS_N<0>")
	)
	(segment
		(start 322.265802 -251.76099)
		(end 322.159122 -251.86767)
		(width 0.10668)
		(layer "F.Cu")
		(net "M_A_CPU0_SA_CS_N<0>")
	)
	(segment
		(start 323.569584 -251.86767)
		(end 323.462904 -251.76099)
		(width 0.10668)
		(layer "F.Cu")
		(net "M_A_CPU0_SA_CS_N<0>")
	)
	(segment
		(start 323.462904 -251.76099)
		(end 323.462904 -251.477272)
		(width 0.10668)
		(layer "F.Cu")
		(net "M_A_CPU0_SA_CS_N<0>")
	)
	(segment
		(start 309.729378 -248.78157)
		(end 309.025798 -248.07799)
		(width 0.10668)
		(layer "F.Cu")
		(net "M_A_CPU0_SA_CS_N<0>")
	)
	(segment
		(start 322.771516 -251.86767)
		(end 322.664836 -251.76099)
		(width 0.10668)
		(layer "F.Cu")
		(net "M_A_CPU0_SA_CS_N<0>")
	)
	(arc
		(start 325.839074 -251.669296)
		(mid 325.767066 -251.684078)
		(end 325.699374 -251.71273)
		(width 0.0762)
		(layer "F.Cu")
		(net "M_A_CPU0_SA_CS_N<0>")
	)
	(arc
		(start 325.690992 -251.717556)
		(mid 325.422675 -251.829453)
		(end 325.134478 -251.86767)
		(width 0.0762)
		(layer "F.Cu")
		(net "M_A_CPU0_SA_CS_N<0>")
	)
	(arc
		(start 325.9709 -251.880116)
		(mid 325.97074 -251.733555)
		(end 325.839074 -251.669296)
		(width 0.0762)
		(layer "F.Cu")
		(net "M_A_CPU0_SA_CS_N<0>")
	)
	(segment
		(start 311.217818 -248.75744)
		(end 311.217818 -248.16435)
		(width 0.10668)
		(layer "F.Cu")
		(net "M_A_CPU0_SA_CB<7>")
	)
	(segment
		(start 326.535034 -249.287538)
		(end 326.526652 -249.282712)
		(width 0.0762)
		(layer "F.Cu")
		(net "M_A_CPU0_SA_CB<7>")
	)
	(segment
		(start 310.514238 -246.266208)
		(end 308.962298 -244.714268)
		(width 0.10668)
		(layer "F.Cu")
		(net "M_A_CPU0_SA_CB<7>")
	)
	(segment
		(start 308.962298 -243.423948)
		(end 308.52364 -242.98529)
		(width 0.10668)
		(layer "F.Cu")
		(net "M_A_CPU0_SA_CB<7>")
	)
	(segment
		(start 322.42125 -249.55881)
		(end 322.15201 -249.28957)
		(width 0.10668)
		(layer "F.Cu")
		(net "M_A_CPU0_SA_CB<7>")
	)
	(segment
		(start 322.15201 -249.28957)
		(end 315.17844 -249.28957)
		(width 0.10668)
		(layer "F.Cu")
		(net "M_A_CPU0_SA_CB<7>")
	)
	(segment
		(start 305.044602 -243.234972)
		(end 303.268126 -243.234972)
		(width 0.101346)
		(layer "F.Cu")
		(net "M_A_CPU0_SA_CB<7>")
	)
	(segment
		(start 324.576694 -249.23115)
		(end 324.249034 -249.55881)
		(width 0.0762)
		(layer "F.Cu")
		(net "M_A_CPU0_SA_CB<7>")
	)
	(segment
		(start 308.52364 -242.98529)
		(end 308.34838 -242.81003)
		(width 0.101346)
		(layer "F.Cu")
		(net "M_A_CPU0_SA_CB<7>")
	)
	(segment
		(start 315.17844 -249.28957)
		(end 314.428378 -249.600212)
		(width 0.10668)
		(layer "F.Cu")
		(net "M_A_CPU0_SA_CB<7>")
	)
	(segment
		(start 325.385938 -249.23115)
		(end 324.576694 -249.23115)
		(width 0.0762)
		(layer "F.Cu")
		(net "M_A_CPU0_SA_CB<7>")
	)
	(segment
		(start 327.28789 -249.610118)
		(end 327.28789 -249.609864)
		(width 0.0762)
		(layer "F.Cu")
		(net "M_A_CPU0_SA_CB<7>")
	)
	(segment
		(start 314.428378 -249.600212)
		(end 312.06059 -249.600212)
		(width 0.10668)
		(layer "F.Cu")
		(net "M_A_CPU0_SA_CB<7>")
	)
	(segment
		(start 308.34838 -242.81003)
		(end 306.070508 -242.81003)
		(width 0.101346)
		(layer "F.Cu")
		(net "M_A_CPU0_SA_CB<7>")
	)
	(segment
		(start 327.108312 -249.28322)
		(end 327.100946 -249.287538)
		(width 0.0762)
		(layer "F.Cu")
		(net "M_A_CPU0_SA_CB<7>")
	)
	(segment
		(start 308.962298 -244.714268)
		(end 308.962298 -243.423948)
		(width 0.10668)
		(layer "F.Cu")
		(net "M_A_CPU0_SA_CB<7>")
	)
	(segment
		(start 312.06059 -249.600212)
		(end 311.217818 -248.75744)
		(width 0.10668)
		(layer "F.Cu")
		(net "M_A_CPU0_SA_CB<7>")
	)
	(segment
		(start 327.28789 -249.609864)
		(end 327.393046 -249.429016)
		(width 0.0762)
		(layer "F.Cu")
		(net "M_A_CPU0_SA_CB<7>")
	)
	(segment
		(start 306.070508 -242.81003)
		(end 305.044602 -243.234972)
		(width 0.101346)
		(layer "F.Cu")
		(net "M_A_CPU0_SA_CB<7>")
	)
	(segment
		(start 310.514238 -247.46077)
		(end 310.514238 -246.266208)
		(width 0.10668)
		(layer "F.Cu")
		(net "M_A_CPU0_SA_CB<7>")
	)
	(segment
		(start 327.109328 -249.282712)
		(end 327.108312 -249.28322)
		(width 0.0762)
		(layer "F.Cu")
		(net "M_A_CPU0_SA_CB<7>")
	)
	(segment
		(start 324.249034 -249.55881)
		(end 322.42125 -249.55881)
		(width 0.10668)
		(layer "F.Cu")
		(net "M_A_CPU0_SA_CB<7>")
	)
	(segment
		(start 311.217818 -248.16435)
		(end 310.514238 -247.46077)
		(width 0.10668)
		(layer "F.Cu")
		(net "M_A_CPU0_SA_CB<7>")
	)
	(arc
		(start 327.289414 -249.237246)
		(mid 327.19649 -249.248569)
		(end 327.109328 -249.282712)
		(width 0.0762)
		(layer "F.Cu")
		(net "M_A_CPU0_SA_CB<7>")
	)
	(arc
		(start 326.160892 -249.287538)
		(mid 325.877936 -249.363715)
		(end 325.59498 -249.287538)
		(width 0.0762)
		(layer "F.Cu")
		(net "M_A_CPU0_SA_CB<7>")
	)
	(arc
		(start 326.526652 -249.282712)
		(mid 326.343144 -249.237218)
		(end 326.160892 -249.287538)
		(width 0.0762)
		(layer "F.Cu")
		(net "M_A_CPU0_SA_CB<7>")
	)
	(arc
		(start 327.100946 -249.287538)
		(mid 326.81799 -249.363715)
		(end 326.535034 -249.287538)
		(width 0.0762)
		(layer "F.Cu")
		(net "M_A_CPU0_SA_CB<7>")
	)
	(arc
		(start 325.59498 -249.287538)
		(mid 325.494188 -249.245532)
		(end 325.385938 -249.23115)
		(width 0.0762)
		(layer "F.Cu")
		(net "M_A_CPU0_SA_CB<7>")
	)
	(arc
		(start 327.393046 -249.429016)
		(mid 327.384109 -249.309992)
		(end 327.289414 -249.237246)
		(width 0.0762)
		(layer "F.Cu")
		(net "M_A_CPU0_SA_CB<7>")
	)
	(segment
		(start 324.339712 -248.553732)
		(end 324.038214 -248.85523)
		(width 0.0762)
		(layer "F.Cu")
		(net "M_A_CPU0_SA_CB<6>")
	)
	(segment
		(start 305.109626 -241.782092)
		(end 304.992786 -241.898932)
		(width 0.101346)
		(layer "F.Cu")
		(net "M_A_CPU0_SA_CB<6>")
	)
	(segment
		(start 325.877936 -248.800112)
		(end 325.976234 -248.630948)
		(width 0.0762)
		(layer "F.Cu")
		(net "M_A_CPU0_SA_CB<6>")
	)
	(segment
		(start 312.34507 -247.133872)
		(end 311.850786 -246.639588)
		(width 0.10668)
		(layer "F.Cu")
		(net "M_A_CPU0_SA_CB<6>")
	)
	(segment
		(start 305.645312 -241.53495)
		(end 305.226466 -241.53495)
		(width 0.101346)
		(layer "F.Cu")
		(net "M_A_CPU0_SA_CB<6>")
	)
	(segment
		(start 311.850786 -246.639588)
		(end 311.69991 -246.639588)
		(width 0.10668)
		(layer "F.Cu")
		(net "M_A_CPU0_SA_CB<6>")
	)
	(segment
		(start 324.038214 -248.85523)
		(end 323.921374 -248.85523)
		(width 0.0762)
		(layer "F.Cu")
		(net "M_A_CPU0_SA_CB<6>")
	)
	(segment
		(start 311.417716 -246.206518)
		(end 309.643018 -244.43182)
		(width 0.10668)
		(layer "F.Cu")
		(net "M_A_CPU0_SA_CB<6>")
	)
	(segment
		(start 304.710592 -241.782092)
		(end 304.710592 -241.65179)
		(width 0.101346)
		(layer "F.Cu")
		(net "M_A_CPU0_SA_CB<6>")
	)
	(segment
		(start 311.69991 -246.639588)
		(end 311.4802 -246.859298)
		(width 0.10668)
		(layer "F.Cu")
		(net "M_A_CPU0_SA_CB<6>")
	)
	(segment
		(start 311.198006 -246.72798)
		(end 311.198006 -246.577104)
		(width 0.10668)
		(layer "F.Cu")
		(net "M_A_CPU0_SA_CB<6>")
	)
	(segment
		(start 309.643018 -242.992656)
		(end 308.610508 -241.960146)
		(width 0.10668)
		(layer "F.Cu")
		(net "M_A_CPU0_SA_CB<6>")
	)
	(segment
		(start 325.408036 -248.553732)
		(end 324.339712 -248.553732)
		(width 0.0762)
		(layer "F.Cu")
		(net "M_A_CPU0_SA_CB<6>")
	)
	(segment
		(start 311.417716 -246.357394)
		(end 311.417716 -246.206518)
		(width 0.10668)
		(layer "F.Cu")
		(net "M_A_CPU0_SA_CB<6>")
	)
	(segment
		(start 304.593752 -241.53495)
		(end 303.268126 -241.53495)
		(width 0.101346)
		(layer "F.Cu")
		(net "M_A_CPU0_SA_CB<6>")
	)
	(segment
		(start 322.680838 -248.85523)
		(end 322.434458 -248.60885)
		(width 0.10668)
		(layer "F.Cu")
		(net "M_A_CPU0_SA_CB<6>")
	)
	(segment
		(start 313.12358 -248.60885)
		(end 312.34507 -247.83034)
		(width 0.10668)
		(layer "F.Cu")
		(net "M_A_CPU0_SA_CB<6>")
	)
	(segment
		(start 306.070508 -241.960146)
		(end 305.645312 -241.53495)
		(width 0.101346)
		(layer "F.Cu")
		(net "M_A_CPU0_SA_CB<6>")
	)
	(segment
		(start 322.434458 -248.60885)
		(end 313.12358 -248.60885)
		(width 0.10668)
		(layer "F.Cu")
		(net "M_A_CPU0_SA_CB<6>")
	)
	(segment
		(start 309.643018 -244.43182)
		(end 309.643018 -242.992656)
		(width 0.10668)
		(layer "F.Cu")
		(net "M_A_CPU0_SA_CB<6>")
	)
	(segment
		(start 308.610508 -241.960146)
		(end 306.070508 -241.960146)
		(width 0.101346)
		(layer "F.Cu")
		(net "M_A_CPU0_SA_CB<6>")
	)
	(segment
		(start 305.109626 -241.65179)
		(end 305.109626 -241.782092)
		(width 0.101346)
		(layer "F.Cu")
		(net "M_A_CPU0_SA_CB<6>")
	)
	(segment
		(start 311.198006 -246.577104)
		(end 311.417716 -246.357394)
		(width 0.10668)
		(layer "F.Cu")
		(net "M_A_CPU0_SA_CB<6>")
	)
	(segment
		(start 311.329324 -246.859298)
		(end 311.198006 -246.72798)
		(width 0.10668)
		(layer "F.Cu")
		(net "M_A_CPU0_SA_CB<6>")
	)
	(segment
		(start 312.34507 -247.83034)
		(end 312.34507 -247.133872)
		(width 0.10668)
		(layer "F.Cu")
		(net "M_A_CPU0_SA_CB<6>")
	)
	(segment
		(start 311.4802 -246.859298)
		(end 311.329324 -246.859298)
		(width 0.10668)
		(layer "F.Cu")
		(net "M_A_CPU0_SA_CB<6>")
	)
	(segment
		(start 323.921374 -248.85523)
		(end 322.680838 -248.85523)
		(width 0.10668)
		(layer "F.Cu")
		(net "M_A_CPU0_SA_CB<6>")
	)
	(segment
		(start 304.710592 -241.65179)
		(end 304.593752 -241.53495)
		(width 0.101346)
		(layer "F.Cu")
		(net "M_A_CPU0_SA_CB<6>")
	)
	(segment
		(start 305.226466 -241.53495)
		(end 305.109626 -241.65179)
		(width 0.101346)
		(layer "F.Cu")
		(net "M_A_CPU0_SA_CB<6>")
	)
	(segment
		(start 325.699374 -248.472706)
		(end 325.690992 -248.477532)
		(width 0.0762)
		(layer "F.Cu")
		(net "M_A_CPU0_SA_CB<6>")
	)
	(segment
		(start 304.827432 -241.898932)
		(end 304.710592 -241.782092)
		(width 0.101346)
		(layer "F.Cu")
		(net "M_A_CPU0_SA_CB<6>")
	)
	(segment
		(start 304.992786 -241.898932)
		(end 304.827432 -241.898932)
		(width 0.101346)
		(layer "F.Cu")
		(net "M_A_CPU0_SA_CB<6>")
	)
	(arc
		(start 325.976234 -248.630948)
		(mid 325.967641 -248.489069)
		(end 325.838566 -248.429272)
		(width 0.0762)
		(layer "F.Cu")
		(net "M_A_CPU0_SA_CB<6>")
	)
	(arc
		(start 325.690992 -248.477532)
		(mid 325.554556 -248.534357)
		(end 325.408036 -248.553732)
		(width 0.0762)
		(layer "F.Cu")
		(net "M_A_CPU0_SA_CB<6>")
	)
	(arc
		(start 325.838566 -248.429272)
		(mid 325.766828 -248.444124)
		(end 325.699374 -248.472706)
		(width 0.0762)
		(layer "F.Cu")
		(net "M_A_CPU0_SA_CB<6>")
	)
	(segment
		(start 312.104786 -249.162824)
		(end 312.104786 -249.011948)
		(width 0.10668)
		(layer "F.Cu")
		(net "M_A_CPU0_SA_CB<5>")
	)
	(segment
		(start 324.388734 -248.93397)
		(end 324.119494 -249.20321)
		(width 0.0762)
		(layer "F.Cu")
		(net "M_A_CPU0_SA_CB<5>")
	)
	(segment
		(start 325.699374 -249.127518)
		(end 325.690992 -249.122692)
		(width 0.0762)
		(layer "F.Cu")
		(net "M_A_CPU0_SA_CB<5>")
	)
	(segment
		(start 312.987182 -249.074432)
		(end 312.773568 -249.074432)
		(width 0.10668)
		(layer "F.Cu")
		(net "M_A_CPU0_SA_CB<5>")
	)
	(segment
		(start 324.990206 -248.93397)
		(end 324.388734 -248.93397)
		(width 0.0762)
		(layer "F.Cu")
		(net "M_A_CPU0_SA_CB<5>")
	)
	(segment
		(start 312.201814 -249.259852)
		(end 312.104786 -249.162824)
		(width 0.10668)
		(layer "F.Cu")
		(net "M_A_CPU0_SA_CB<5>")
	)
	(segment
		(start 313.571636 -249.074432)
		(end 313.386216 -249.259852)
		(width 0.10668)
		(layer "F.Cu")
		(net "M_A_CPU0_SA_CB<5>")
	)
	(segment
		(start 311.722516 -247.143524)
		(end 311.275984 -247.590056)
		(width 0.10668)
		(layer "F.Cu")
		(net "M_A_CPU0_SA_CB<5>")
	)
	(segment
		(start 310.854598 -247.319546)
		(end 310.854598 -246.124984)
		(width 0.10668)
		(layer "F.Cu")
		(net "M_A_CPU0_SA_CB<5>")
	)
	(segment
		(start 310.854598 -246.124984)
		(end 309.302658 -244.573044)
		(width 0.10668)
		(layer "F.Cu")
		(net "M_A_CPU0_SA_CB<5>")
	)
	(segment
		(start 312.104786 -249.011948)
		(end 312.499502 -248.617232)
		(width 0.10668)
		(layer "F.Cu")
		(net "M_A_CPU0_SA_CB<5>")
	)
	(segment
		(start 327.004934 -249.122438)
		(end 327.004934 -249.122692)
		(width 0.0762)
		(layer "F.Cu")
		(net "M_A_CPU0_SA_CB<5>")
	)
	(segment
		(start 313.386216 -249.259852)
		(end 313.172602 -249.259852)
		(width 0.10668)
		(layer "F.Cu")
		(net "M_A_CPU0_SA_CB<5>")
	)
	(segment
		(start 311.558178 -247.872504)
		(end 312.00471 -247.425972)
		(width 0.10668)
		(layer "F.Cu")
		(net "M_A_CPU0_SA_CB<5>")
	)
	(segment
		(start 322.293234 -248.94921)
		(end 315.110622 -248.94921)
		(width 0.10668)
		(layer "F.Cu")
		(net "M_A_CPU0_SA_CB<5>")
	)
	(segment
		(start 315.110622 -248.94921)
		(end 314.36056 -249.259852)
		(width 0.10668)
		(layer "F.Cu")
		(net "M_A_CPU0_SA_CB<5>")
	)
	(segment
		(start 311.125108 -247.590056)
		(end 310.854598 -247.319546)
		(width 0.10668)
		(layer "F.Cu")
		(net "M_A_CPU0_SA_CB<5>")
	)
	(segment
		(start 312.773568 -249.074432)
		(end 312.588148 -249.259852)
		(width 0.10668)
		(layer "F.Cu")
		(net "M_A_CPU0_SA_CB<5>")
	)
	(segment
		(start 311.558178 -248.616216)
		(end 311.558178 -247.872504)
		(width 0.10668)
		(layer "F.Cu")
		(net "M_A_CPU0_SA_CB<5>")
	)
	(segment
		(start 324.119494 -249.20321)
		(end 322.547234 -249.20321)
		(width 0.10668)
		(layer "F.Cu")
		(net "M_A_CPU0_SA_CB<5>")
	)
	(segment
		(start 311.822592 -248.729754)
		(end 311.671716 -248.729754)
		(width 0.10668)
		(layer "F.Cu")
		(net "M_A_CPU0_SA_CB<5>")
	)
	(segment
		(start 313.97067 -249.259852)
		(end 313.78525 -249.074432)
		(width 0.10668)
		(layer "F.Cu")
		(net "M_A_CPU0_SA_CB<5>")
	)
	(segment
		(start 311.275984 -247.590056)
		(end 311.125108 -247.590056)
		(width 0.10668)
		(layer "F.Cu")
		(net "M_A_CPU0_SA_CB<5>")
	)
	(segment
		(start 313.78525 -249.074432)
		(end 313.571636 -249.074432)
		(width 0.10668)
		(layer "F.Cu")
		(net "M_A_CPU0_SA_CB<5>")
	)
	(segment
		(start 312.499502 -248.617232)
		(end 312.499502 -248.466356)
		(width 0.10668)
		(layer "F.Cu")
		(net "M_A_CPU0_SA_CB<5>")
	)
	(segment
		(start 312.217308 -248.335038)
		(end 311.822592 -248.729754)
		(width 0.10668)
		(layer "F.Cu")
		(net "M_A_CPU0_SA_CB<5>")
	)
	(segment
		(start 308.411372 -242.385088)
		(end 307.368194 -242.385088)
		(width 0.10668)
		(layer "F.Cu")
		(net "M_A_CPU0_SA_CB<5>")
	)
	(segment
		(start 313.172602 -249.259852)
		(end 312.987182 -249.074432)
		(width 0.10668)
		(layer "F.Cu")
		(net "M_A_CPU0_SA_CB<5>")
	)
	(segment
		(start 311.671716 -248.729754)
		(end 311.558178 -248.616216)
		(width 0.10668)
		(layer "F.Cu")
		(net "M_A_CPU0_SA_CB<5>")
	)
	(segment
		(start 312.499502 -248.466356)
		(end 312.368184 -248.335038)
		(width 0.10668)
		(layer "F.Cu")
		(net "M_A_CPU0_SA_CB<5>")
	)
	(segment
		(start 322.547234 -249.20321)
		(end 322.293234 -248.94921)
		(width 0.10668)
		(layer "F.Cu")
		(net "M_A_CPU0_SA_CB<5>")
	)
	(segment
		(start 312.368184 -248.335038)
		(end 312.217308 -248.335038)
		(width 0.10668)
		(layer "F.Cu")
		(net "M_A_CPU0_SA_CB<5>")
	)
	(segment
		(start 314.36056 -249.259852)
		(end 313.97067 -249.259852)
		(width 0.10668)
		(layer "F.Cu")
		(net "M_A_CPU0_SA_CB<5>")
	)
	(segment
		(start 312.00471 -247.425972)
		(end 312.00471 -247.275096)
		(width 0.10668)
		(layer "F.Cu")
		(net "M_A_CPU0_SA_CB<5>")
	)
	(segment
		(start 311.873392 -247.143778)
		(end 311.722516 -247.143524)
		(width 0.10668)
		(layer "F.Cu")
		(net "M_A_CPU0_SA_CB<5>")
	)
	(segment
		(start 312.588148 -249.259852)
		(end 312.201814 -249.259852)
		(width 0.10668)
		(layer "F.Cu")
		(net "M_A_CPU0_SA_CB<5>")
	)
	(segment
		(start 312.00471 -247.275096)
		(end 311.873392 -247.143778)
		(width 0.10668)
		(layer "F.Cu")
		(net "M_A_CPU0_SA_CB<5>")
	)
	(segment
		(start 309.302658 -244.573044)
		(end 309.302658 -243.276374)
		(width 0.10668)
		(layer "F.Cu")
		(net "M_A_CPU0_SA_CB<5>")
	)
	(segment
		(start 309.302658 -243.276374)
		(end 308.411372 -242.385088)
		(width 0.10668)
		(layer "F.Cu")
		(net "M_A_CPU0_SA_CB<5>")
	)
	(arc
		(start 326.065134 -249.122692)
		(mid 325.882883 -249.173042)
		(end 325.699374 -249.127518)
		(width 0.0762)
		(layer "F.Cu")
		(net "M_A_CPU0_SA_CB<5>")
	)
	(arc
		(start 327.289414 -249.045984)
		(mid 327.142093 -249.065303)
		(end 327.004934 -249.122438)
		(width 0.0762)
		(layer "F.Cu")
		(net "M_A_CPU0_SA_CB<5>")
	)
	(arc
		(start 326.631046 -249.122692)
		(mid 326.34809 -249.046515)
		(end 326.065134 -249.122692)
		(width 0.0762)
		(layer "F.Cu")
		(net "M_A_CPU0_SA_CB<5>")
	)
	(arc
		(start 327.004934 -249.122692)
		(mid 326.81799 -249.172947)
		(end 326.631046 -249.122692)
		(width 0.0762)
		(layer "F.Cu")
		(net "M_A_CPU0_SA_CB<5>")
	)
	(arc
		(start 327.758044 -248.800112)
		(mid 327.554028 -248.980806)
		(end 327.289414 -249.045984)
		(width 0.0762)
		(layer "F.Cu")
		(net "M_A_CPU0_SA_CB<5>")
	)
	(arc
		(start 325.690992 -249.122692)
		(mid 325.353082 -248.981975)
		(end 324.990206 -248.93397)
		(width 0.0762)
		(layer "F.Cu")
		(net "M_A_CPU0_SA_CB<5>")
	)
	(segment
		(start 310.74868 -244.57787)
		(end 310.74868 -244.426994)
		(width 0.10668)
		(layer "F.Cu")
		(net "M_A_CPU0_SA_CB<4>")
	)
	(segment
		(start 324.050152 -248.26849)
		(end 323.87159 -248.447052)
		(width 0.10668)
		(layer "F.Cu")
		(net "M_A_CPU0_SA_CB<4>")
	)
	(segment
		(start 324.260464 -248.363232)
		(end 324.165722 -248.26849)
		(width 0.0762)
		(layer "F.Cu")
		(net "M_A_CPU0_SA_CB<4>")
	)
	(segment
		(start 312.816748 -247.74017)
		(end 312.68543 -247.608852)
		(width 0.10668)
		(layer "F.Cu")
		(net "M_A_CPU0_SA_CB<4>")
	)
	(segment
		(start 312.278268 -246.585486)
		(end 312.278268 -246.43461)
		(width 0.10668)
		(layer "F.Cu")
		(net "M_A_CPU0_SA_CB<4>")
	)
	(segment
		(start 323.651118 -248.447052)
		(end 323.472556 -248.26849)
		(width 0.10668)
		(layer "F.Cu")
		(net "M_A_CPU0_SA_CB<4>")
	)
	(segment
		(start 310.30291 -244.459252)
		(end 310.152034 -244.459252)
		(width 0.10668)
		(layer "F.Cu")
		(net "M_A_CPU0_SA_CB<4>")
	)
	(segment
		(start 310.74868 -244.426994)
		(end 310.617362 -244.295676)
		(width 0.10668)
		(layer "F.Cu")
		(net "M_A_CPU0_SA_CB<4>")
	)
	(segment
		(start 311.431686 -245.588028)
		(end 311.28081 -245.588028)
		(width 0.10668)
		(layer "F.Cu")
		(net "M_A_CPU0_SA_CB<4>")
	)
	(segment
		(start 310.617362 -244.295676)
		(end 310.466486 -244.295676)
		(width 0.10668)
		(layer "F.Cu")
		(net "M_A_CPU0_SA_CB<4>")
	)
	(segment
		(start 311.746138 -245.424452)
		(end 311.595262 -245.424452)
		(width 0.10668)
		(layer "F.Cu")
		(net "M_A_CPU0_SA_CB<4>")
	)
	(segment
		(start 313.294522 -247.97766)
		(end 313.721496 -247.550686)
		(width 0.10668)
		(layer "F.Cu")
		(net "M_A_CPU0_SA_CB<4>")
	)
	(segment
		(start 322.674488 -248.26849)
		(end 313.434476 -248.26849)
		(width 0.10668)
		(layer "F.Cu")
		(net "M_A_CPU0_SA_CB<4>")
	)
	(segment
		(start 324.165722 -248.26849)
		(end 324.050152 -248.26849)
		(width 0.10668)
		(layer "F.Cu")
		(net "M_A_CPU0_SA_CB<4>")
	)
	(segment
		(start 312.441844 -246.120158)
		(end 312.310526 -245.98884)
		(width 0.10668)
		(layer "F.Cu")
		(net "M_A_CPU0_SA_CB<4>")
	)
	(segment
		(start 311.149492 -245.45671)
		(end 311.149492 -245.305834)
		(width 0.10668)
		(layer "F.Cu")
		(net "M_A_CPU0_SA_CB<4>")
	)
	(segment
		(start 311.71388 -245.870222)
		(end 311.877456 -245.706646)
		(width 0.10668)
		(layer "F.Cu")
		(net "M_A_CPU0_SA_CB<4>")
	)
	(segment
		(start 311.149492 -245.305834)
		(end 311.313068 -245.142258)
		(width 0.10668)
		(layer "F.Cu")
		(net "M_A_CPU0_SA_CB<4>")
	)
	(segment
		(start 313.434476 -248.26849)
		(end 313.294522 -248.128536)
		(width 0.10668)
		(layer "F.Cu")
		(net "M_A_CPU0_SA_CB<4>")
	)
	(segment
		(start 312.560462 -246.716804)
		(end 312.409586 -246.716804)
		(width 0.10668)
		(layer "F.Cu")
		(net "M_A_CPU0_SA_CB<4>")
	)
	(segment
		(start 311.71388 -246.021098)
		(end 311.71388 -245.870222)
		(width 0.10668)
		(layer "F.Cu")
		(net "M_A_CPU0_SA_CB<4>")
	)
	(segment
		(start 312.967624 -247.74017)
		(end 312.816748 -247.74017)
		(width 0.10668)
		(layer "F.Cu")
		(net "M_A_CPU0_SA_CB<4>")
	)
	(segment
		(start 323.252084 -248.26849)
		(end 323.073522 -248.447052)
		(width 0.10668)
		(layer "F.Cu")
		(net "M_A_CPU0_SA_CB<4>")
	)
	(segment
		(start 311.877456 -245.706646)
		(end 311.877456 -245.55577)
		(width 0.10668)
		(layer "F.Cu")
		(net "M_A_CPU0_SA_CB<4>")
	)
	(segment
		(start 311.313068 -245.142258)
		(end 311.313068 -244.991382)
		(width 0.10668)
		(layer "F.Cu")
		(net "M_A_CPU0_SA_CB<4>")
	)
	(segment
		(start 310.585104 -244.892322)
		(end 310.585104 -244.741446)
		(width 0.10668)
		(layer "F.Cu")
		(net "M_A_CPU0_SA_CB<4>")
	)
	(segment
		(start 322.85305 -248.447052)
		(end 322.674488 -248.26849)
		(width 0.10668)
		(layer "F.Cu")
		(net "M_A_CPU0_SA_CB<4>")
	)
	(segment
		(start 323.472556 -248.26849)
		(end 323.252084 -248.26849)
		(width 0.10668)
		(layer "F.Cu")
		(net "M_A_CPU0_SA_CB<4>")
	)
	(segment
		(start 307.89753 -240.685066)
		(end 307.368194 -240.685066)
		(width 0.10668)
		(layer "F.Cu")
		(net "M_A_CPU0_SA_CB<4>")
	)
	(segment
		(start 312.409586 -246.716804)
		(end 312.278268 -246.585486)
		(width 0.10668)
		(layer "F.Cu")
		(net "M_A_CPU0_SA_CB<4>")
	)
	(segment
		(start 313.006232 -246.835422)
		(end 313.006232 -246.684546)
		(width 0.10668)
		(layer "F.Cu")
		(net "M_A_CPU0_SA_CB<4>")
	)
	(segment
		(start 310.466486 -244.295676)
		(end 310.30291 -244.459252)
		(width 0.10668)
		(layer "F.Cu")
		(net "M_A_CPU0_SA_CB<4>")
	)
	(segment
		(start 312.874914 -246.553228)
		(end 312.724038 -246.553228)
		(width 0.10668)
		(layer "F.Cu")
		(net "M_A_CPU0_SA_CB<4>")
	)
	(segment
		(start 311.595262 -245.424452)
		(end 311.431686 -245.588028)
		(width 0.10668)
		(layer "F.Cu")
		(net "M_A_CPU0_SA_CB<4>")
	)
	(segment
		(start 323.073522 -248.447052)
		(end 322.85305 -248.447052)
		(width 0.10668)
		(layer "F.Cu")
		(net "M_A_CPU0_SA_CB<4>")
	)
	(segment
		(start 312.441844 -246.271034)
		(end 312.441844 -246.120158)
		(width 0.10668)
		(layer "F.Cu")
		(net "M_A_CPU0_SA_CB<4>")
	)
	(segment
		(start 312.310526 -245.98884)
		(end 312.15965 -245.98884)
		(width 0.10668)
		(layer "F.Cu")
		(net "M_A_CPU0_SA_CB<4>")
	)
	(segment
		(start 323.87159 -248.447052)
		(end 323.651118 -248.447052)
		(width 0.10668)
		(layer "F.Cu")
		(net "M_A_CPU0_SA_CB<4>")
	)
	(segment
		(start 310.716422 -245.02364)
		(end 310.585104 -244.892322)
		(width 0.10668)
		(layer "F.Cu")
		(net "M_A_CPU0_SA_CB<4>")
	)
	(segment
		(start 311.18175 -244.860064)
		(end 311.030874 -244.860064)
		(width 0.10668)
		(layer "F.Cu")
		(net "M_A_CPU0_SA_CB<4>")
	)
	(segment
		(start 313.721496 -247.550686)
		(end 313.721496 -247.39981)
		(width 0.10668)
		(layer "F.Cu")
		(net "M_A_CPU0_SA_CB<4>")
	)
	(segment
		(start 311.877456 -245.55577)
		(end 311.746138 -245.424452)
		(width 0.10668)
		(layer "F.Cu")
		(net "M_A_CPU0_SA_CB<4>")
	)
	(segment
		(start 312.278268 -246.43461)
		(end 312.441844 -246.271034)
		(width 0.10668)
		(layer "F.Cu")
		(net "M_A_CPU0_SA_CB<4>")
	)
	(segment
		(start 310.867298 -245.02364)
		(end 310.716422 -245.02364)
		(width 0.10668)
		(layer "F.Cu")
		(net "M_A_CPU0_SA_CB<4>")
	)
	(segment
		(start 309.983378 -242.771168)
		(end 307.89753 -240.685066)
		(width 0.10668)
		(layer "F.Cu")
		(net "M_A_CPU0_SA_CB<4>")
	)
	(segment
		(start 312.15965 -245.98884)
		(end 311.996074 -246.152416)
		(width 0.10668)
		(layer "F.Cu")
		(net "M_A_CPU0_SA_CB<4>")
	)
	(segment
		(start 310.152034 -244.459252)
		(end 309.983378 -244.290596)
		(width 0.10668)
		(layer "F.Cu")
		(net "M_A_CPU0_SA_CB<4>")
	)
	(segment
		(start 312.68543 -247.457976)
		(end 312.842656 -247.30075)
		(width 0.10668)
		(layer "F.Cu")
		(net "M_A_CPU0_SA_CB<4>")
	)
	(segment
		(start 311.313068 -244.991382)
		(end 311.18175 -244.860064)
		(width 0.10668)
		(layer "F.Cu")
		(net "M_A_CPU0_SA_CB<4>")
	)
	(segment
		(start 311.28081 -245.588028)
		(end 311.149492 -245.45671)
		(width 0.10668)
		(layer "F.Cu")
		(net "M_A_CPU0_SA_CB<4>")
	)
	(segment
		(start 313.590178 -247.268492)
		(end 313.439302 -247.268492)
		(width 0.10668)
		(layer "F.Cu")
		(net "M_A_CPU0_SA_CB<4>")
	)
	(segment
		(start 313.721496 -247.39981)
		(end 313.590178 -247.268492)
		(width 0.10668)
		(layer "F.Cu")
		(net "M_A_CPU0_SA_CB<4>")
	)
	(segment
		(start 313.439302 -247.268492)
		(end 312.967624 -247.74017)
		(width 0.10668)
		(layer "F.Cu")
		(net "M_A_CPU0_SA_CB<4>")
	)
	(segment
		(start 312.842656 -246.998998)
		(end 313.006232 -246.835422)
		(width 0.10668)
		(layer "F.Cu")
		(net "M_A_CPU0_SA_CB<4>")
	)
	(segment
		(start 311.996074 -246.152416)
		(end 311.845198 -246.152416)
		(width 0.10668)
		(layer "F.Cu")
		(net "M_A_CPU0_SA_CB<4>")
	)
	(segment
		(start 309.983378 -244.290596)
		(end 309.983378 -242.771168)
		(width 0.10668)
		(layer "F.Cu")
		(net "M_A_CPU0_SA_CB<4>")
	)
	(segment
		(start 313.006232 -246.684546)
		(end 312.874914 -246.553228)
		(width 0.10668)
		(layer "F.Cu")
		(net "M_A_CPU0_SA_CB<4>")
	)
	(segment
		(start 311.030874 -244.860064)
		(end 310.867298 -245.02364)
		(width 0.10668)
		(layer "F.Cu")
		(net "M_A_CPU0_SA_CB<4>")
	)
	(segment
		(start 325.408036 -248.363232)
		(end 324.260464 -248.363232)
		(width 0.0762)
		(layer "F.Cu")
		(net "M_A_CPU0_SA_CB<4>")
	)
	(segment
		(start 310.585104 -244.741446)
		(end 310.74868 -244.57787)
		(width 0.10668)
		(layer "F.Cu")
		(net "M_A_CPU0_SA_CB<4>")
	)
	(segment
		(start 312.68543 -247.608852)
		(end 312.68543 -247.457976)
		(width 0.10668)
		(layer "F.Cu")
		(net "M_A_CPU0_SA_CB<4>")
	)
	(segment
		(start 313.294522 -248.128536)
		(end 313.294522 -247.97766)
		(width 0.10668)
		(layer "F.Cu")
		(net "M_A_CPU0_SA_CB<4>")
	)
	(segment
		(start 312.842656 -247.30075)
		(end 312.842656 -246.998998)
		(width 0.10668)
		(layer "F.Cu")
		(net "M_A_CPU0_SA_CB<4>")
	)
	(segment
		(start 311.845198 -246.152416)
		(end 311.71388 -246.021098)
		(width 0.10668)
		(layer "F.Cu")
		(net "M_A_CPU0_SA_CB<4>")
	)
	(segment
		(start 312.724038 -246.553228)
		(end 312.560462 -246.716804)
		(width 0.10668)
		(layer "F.Cu")
		(net "M_A_CPU0_SA_CB<4>")
	)
	(arc
		(start 326.34809 -247.990106)
		(mid 326.105773 -248.159826)
		(end 325.820786 -248.23928)
		(width 0.0762)
		(layer "F.Cu")
		(net "M_A_CPU0_SA_CB<4>")
	)
	(arc
		(start 325.820786 -248.23928)
		(mid 325.703973 -248.263956)
		(end 325.59498 -248.312686)
		(width 0.0762)
		(layer "F.Cu")
		(net "M_A_CPU0_SA_CB<4>")
	)
	(arc
		(start 325.59498 -248.312686)
		(mid 325.504847 -248.350306)
		(end 325.408036 -248.363232)
		(width 0.0762)
		(layer "F.Cu")
		(net "M_A_CPU0_SA_CB<4>")
	)
	(segment
		(start 305.319684 -237.285022)
		(end 303.268126 -237.285022)
		(width 0.101346)
		(layer "F.Cu")
		(net "M_A_CPU0_SA_CB<3>")
	)
	(segment
		(start 325.391526 -245.99265)
		(end 324.482714 -245.99265)
		(width 0.0762)
		(layer "F.Cu")
		(net "M_A_CPU0_SA_CB<3>")
	)
	(segment
		(start 327.108312 -246.043196)
		(end 327.100946 -246.047514)
		(width 0.0762)
		(layer "F.Cu")
		(net "M_A_CPU0_SA_CB<3>")
	)
	(segment
		(start 327.28789 -246.370094)
		(end 327.28789 -246.36984)
		(width 0.0762)
		(layer "F.Cu")
		(net "M_A_CPU0_SA_CB<3>")
	)
	(segment
		(start 308.28488 -237.710218)
		(end 305.74488 -237.710218)
		(width 0.101346)
		(layer "F.Cu")
		(net "M_A_CPU0_SA_CB<3>")
	)
	(segment
		(start 310.431688 -239.564672)
		(end 308.577234 -237.710218)
		(width 0.10668)
		(layer "F.Cu")
		(net "M_A_CPU0_SA_CB<3>")
	)
	(segment
		(start 312.424572 -242.360704)
		(end 310.431688 -240.36782)
		(width 0.10668)
		(layer "F.Cu")
		(net "M_A_CPU0_SA_CB<3>")
	)
	(segment
		(start 305.74488 -237.710218)
		(end 305.319684 -237.285022)
		(width 0.101346)
		(layer "F.Cu")
		(net "M_A_CPU0_SA_CB<3>")
	)
	(segment
		(start 324.482714 -245.99265)
		(end 324.386194 -246.08917)
		(width 0.0762)
		(layer "F.Cu")
		(net "M_A_CPU0_SA_CB<3>")
	)
	(segment
		(start 327.28789 -246.36984)
		(end 327.393046 -246.188992)
		(width 0.0762)
		(layer "F.Cu")
		(net "M_A_CPU0_SA_CB<3>")
	)
	(segment
		(start 326.535034 -246.047514)
		(end 326.526652 -246.042688)
		(width 0.0762)
		(layer "F.Cu")
		(net "M_A_CPU0_SA_CB<3>")
	)
	(segment
		(start 312.871612 -242.360704)
		(end 312.424572 -242.360704)
		(width 0.10668)
		(layer "F.Cu")
		(net "M_A_CPU0_SA_CB<3>")
	)
	(segment
		(start 316.600078 -246.08917)
		(end 312.871612 -242.360704)
		(width 0.10668)
		(layer "F.Cu")
		(net "M_A_CPU0_SA_CB<3>")
	)
	(segment
		(start 327.109328 -246.042688)
		(end 327.108312 -246.043196)
		(width 0.0762)
		(layer "F.Cu")
		(net "M_A_CPU0_SA_CB<3>")
	)
	(segment
		(start 308.577234 -237.710218)
		(end 308.28488 -237.710218)
		(width 0.10668)
		(layer "F.Cu")
		(net "M_A_CPU0_SA_CB<3>")
	)
	(segment
		(start 324.386194 -246.08917)
		(end 316.600078 -246.08917)
		(width 0.10668)
		(layer "F.Cu")
		(net "M_A_CPU0_SA_CB<3>")
	)
	(segment
		(start 310.431688 -240.36782)
		(end 310.431688 -239.564672)
		(width 0.10668)
		(layer "F.Cu")
		(net "M_A_CPU0_SA_CB<3>")
	)
	(arc
		(start 327.289414 -245.997222)
		(mid 327.19649 -246.008545)
		(end 327.109328 -246.042688)
		(width 0.0762)
		(layer "F.Cu")
		(net "M_A_CPU0_SA_CB<3>")
	)
	(arc
		(start 325.59498 -246.047514)
		(mid 325.496883 -246.006627)
		(end 325.391526 -245.99265)
		(width 0.0762)
		(layer "F.Cu")
		(net "M_A_CPU0_SA_CB<3>")
	)
	(arc
		(start 327.100946 -246.047514)
		(mid 326.81799 -246.123691)
		(end 326.535034 -246.047514)
		(width 0.0762)
		(layer "F.Cu")
		(net "M_A_CPU0_SA_CB<3>")
	)
	(arc
		(start 326.160892 -246.047514)
		(mid 325.877936 -246.123691)
		(end 325.59498 -246.047514)
		(width 0.0762)
		(layer "F.Cu")
		(net "M_A_CPU0_SA_CB<3>")
	)
	(arc
		(start 327.393046 -246.188992)
		(mid 327.384109 -246.069968)
		(end 327.289414 -245.997222)
		(width 0.0762)
		(layer "F.Cu")
		(net "M_A_CPU0_SA_CB<3>")
	)
	(arc
		(start 326.526652 -246.042688)
		(mid 326.343144 -245.997194)
		(end 326.160892 -246.047514)
		(width 0.0762)
		(layer "F.Cu")
		(net "M_A_CPU0_SA_CB<3>")
	)
	(segment
		(start 325.044816 -245.37543)
		(end 324.228714 -245.37543)
		(width 0.0762)
		(layer "F.Cu")
		(net "M_A_CPU0_SA_CB<2>")
	)
	(segment
		(start 313.10961 -241.361468)
		(end 313.109864 -241.2111)
		(width 0.10668)
		(layer "F.Cu")
		(net "M_A_CPU0_SA_CB<2>")
	)
	(segment
		(start 308.610508 -236.010196)
		(end 306.070508 -236.010196)
		(width 0.101346)
		(layer "F.Cu")
		(net "M_A_CPU0_SA_CB<2>")
	)
	(segment
		(start 304.730658 -235.585)
		(end 303.268126 -235.585)
		(width 0.101346)
		(layer "F.Cu")
		(net "M_A_CPU0_SA_CB<2>")
	)
	(segment
		(start 325.877936 -245.560088)
		(end 325.9709 -245.400068)
		(width 0.0762)
		(layer "F.Cu")
		(net "M_A_CPU0_SA_CB<2>")
	)
	(segment
		(start 305.225704 -236.095286)
		(end 305.124358 -236.196632)
		(width 0.101346)
		(layer "F.Cu")
		(net "M_A_CPU0_SA_CB<2>")
	)
	(segment
		(start 313.54268 -241.643916)
		(end 313.391804 -241.643916)
		(width 0.10668)
		(layer "F.Cu")
		(net "M_A_CPU0_SA_CB<2>")
	)
	(segment
		(start 305.225704 -235.686346)
		(end 305.225704 -236.095286)
		(width 0.101346)
		(layer "F.Cu")
		(net "M_A_CPU0_SA_CB<2>")
	)
	(segment
		(start 305.124358 -236.196632)
		(end 304.93335 -236.196632)
		(width 0.101346)
		(layer "F.Cu")
		(net "M_A_CPU0_SA_CB<2>")
	)
	(segment
		(start 313.326018 -241.709702)
		(end 313.175142 -241.709448)
		(width 0.10668)
		(layer "F.Cu")
		(net "M_A_CPU0_SA_CB<2>")
	)
	(segment
		(start 304.832004 -236.095286)
		(end 304.832004 -235.686346)
		(width 0.101346)
		(layer "F.Cu")
		(net "M_A_CPU0_SA_CB<2>")
	)
	(segment
		(start 313.043824 -241.57813)
		(end 313.043824 -241.427254)
		(width 0.10668)
		(layer "F.Cu")
		(net "M_A_CPU0_SA_CB<2>")
	)
	(segment
		(start 324.142354 -245.28907)
		(end 317.187834 -245.28907)
		(width 0.10668)
		(layer "F.Cu")
		(net "M_A_CPU0_SA_CB<2>")
	)
	(segment
		(start 306.070508 -236.010196)
		(end 305.645312 -235.585)
		(width 0.101346)
		(layer "F.Cu")
		(net "M_A_CPU0_SA_CB<2>")
	)
	(segment
		(start 313.043824 -241.427254)
		(end 313.10961 -241.361468)
		(width 0.10668)
		(layer "F.Cu")
		(net "M_A_CPU0_SA_CB<2>")
	)
	(segment
		(start 305.32705 -235.585)
		(end 305.225704 -235.686346)
		(width 0.101346)
		(layer "F.Cu")
		(net "M_A_CPU0_SA_CB<2>")
	)
	(segment
		(start 324.228714 -245.37543)
		(end 324.142354 -245.28907)
		(width 0.0762)
		(layer "F.Cu")
		(net "M_A_CPU0_SA_CB<2>")
	)
	(segment
		(start 313.391804 -241.643916)
		(end 313.326018 -241.709702)
		(width 0.10668)
		(layer "F.Cu")
		(net "M_A_CPU0_SA_CB<2>")
	)
	(segment
		(start 313.175142 -241.709448)
		(end 313.043824 -241.57813)
		(width 0.10668)
		(layer "F.Cu")
		(net "M_A_CPU0_SA_CB<2>")
	)
	(segment
		(start 317.187834 -245.28907)
		(end 313.54268 -241.643916)
		(width 0.10668)
		(layer "F.Cu")
		(net "M_A_CPU0_SA_CB<2>")
	)
	(segment
		(start 308.836314 -236.236002)
		(end 308.610508 -236.010196)
		(width 0.10668)
		(layer "F.Cu")
		(net "M_A_CPU0_SA_CB<2>")
	)
	(segment
		(start 305.645312 -235.585)
		(end 305.32705 -235.585)
		(width 0.101346)
		(layer "F.Cu")
		(net "M_A_CPU0_SA_CB<2>")
	)
	(segment
		(start 325.699374 -245.232682)
		(end 325.690992 -245.237508)
		(width 0.0762)
		(layer "F.Cu")
		(net "M_A_CPU0_SA_CB<2>")
	)
	(segment
		(start 313.109864 -241.2111)
		(end 308.836314 -236.93755)
		(width 0.10668)
		(layer "F.Cu")
		(net "M_A_CPU0_SA_CB<2>")
	)
	(segment
		(start 308.836314 -236.93755)
		(end 308.836314 -236.236002)
		(width 0.10668)
		(layer "F.Cu")
		(net "M_A_CPU0_SA_CB<2>")
	)
	(segment
		(start 304.93335 -236.196632)
		(end 304.832004 -236.095286)
		(width 0.101346)
		(layer "F.Cu")
		(net "M_A_CPU0_SA_CB<2>")
	)
	(segment
		(start 304.832004 -235.686346)
		(end 304.730658 -235.585)
		(width 0.101346)
		(layer "F.Cu")
		(net "M_A_CPU0_SA_CB<2>")
	)
	(arc
		(start 325.9709 -245.400068)
		(mid 325.97074 -245.253507)
		(end 325.839074 -245.189248)
		(width 0.0762)
		(layer "F.Cu")
		(net "M_A_CPU0_SA_CB<2>")
	)
	(arc
		(start 325.593456 -245.282466)
		(mid 325.323049 -245.352054)
		(end 325.044816 -245.37543)
		(width 0.0762)
		(layer "F.Cu")
		(net "M_A_CPU0_SA_CB<2>")
	)
	(arc
		(start 325.839074 -245.189248)
		(mid 325.767066 -245.20403)
		(end 325.699374 -245.232682)
		(width 0.0762)
		(layer "F.Cu")
		(net "M_A_CPU0_SA_CB<2>")
	)
	(arc
		(start 325.690992 -245.237508)
		(mid 325.643298 -245.262318)
		(end 325.593456 -245.282466)
		(width 0.0762)
		(layer "F.Cu")
		(net "M_A_CPU0_SA_CB<2>")
	)
	(segment
		(start 323.936614 -245.69547)
		(end 316.687962 -245.69547)
		(width 0.10668)
		(layer "F.Cu")
		(net "M_A_CPU0_SA_CB<1>")
	)
	(segment
		(start 314.14847 -242.87607)
		(end 313.868562 -242.87607)
		(width 0.10668)
		(layer "F.Cu")
		(net "M_A_CPU0_SA_CB<1>")
	)
	(segment
		(start 310.837834 -240.292382)
		(end 310.772048 -240.226596)
		(width 0.10668)
		(layer "F.Cu")
		(net "M_A_CPU0_SA_CB<1>")
	)
	(segment
		(start 312.52922 -241.1603)
		(end 312.378344 -241.1603)
		(width 0.10668)
		(layer "F.Cu")
		(net "M_A_CPU0_SA_CB<1>")
	)
	(segment
		(start 310.772048 -240.226596)
		(end 310.772048 -239.366044)
		(width 0.10668)
		(layer "F.Cu")
		(net "M_A_CPU0_SA_CB<1>")
	)
	(segment
		(start 314.29071 -243.01831)
		(end 314.14847 -242.87607)
		(width 0.10668)
		(layer "F.Cu")
		(net "M_A_CPU0_SA_CB<1>")
	)
	(segment
		(start 323.967094 -245.72595)
		(end 323.936614 -245.69547)
		(width 0.0762)
		(layer "F.Cu")
		(net "M_A_CPU0_SA_CB<1>")
	)
	(segment
		(start 310.98871 -240.292382)
		(end 310.837834 -240.292382)
		(width 0.10668)
		(layer "F.Cu")
		(net "M_A_CPU0_SA_CB<1>")
	)
	(segment
		(start 312.09615 -240.878106)
		(end 312.09615 -240.72723)
		(width 0.10668)
		(layer "F.Cu")
		(net "M_A_CPU0_SA_CB<1>")
	)
	(segment
		(start 314.855098 -243.862606)
		(end 314.855098 -243.582698)
		(width 0.10668)
		(layer "F.Cu")
		(net "M_A_CPU0_SA_CB<1>")
	)
	(segment
		(start 312.39968 -241.854228)
		(end 312.39968 -241.703352)
		(width 0.10668)
		(layer "F.Cu")
		(net "M_A_CPU0_SA_CB<1>")
	)
	(segment
		(start 311.402222 -240.85677)
		(end 311.270904 -240.725452)
		(width 0.10668)
		(layer "F.Cu")
		(net "M_A_CPU0_SA_CB<1>")
	)
	(segment
		(start 311.96661 -241.421158)
		(end 311.835292 -241.28984)
		(width 0.10668)
		(layer "F.Cu")
		(net "M_A_CPU0_SA_CB<1>")
	)
	(segment
		(start 311.400444 -240.031524)
		(end 311.249568 -240.031524)
		(width 0.10668)
		(layer "F.Cu")
		(net "M_A_CPU0_SA_CB<1>")
	)
	(segment
		(start 315.419486 -244.147086)
		(end 315.277246 -244.004846)
		(width 0.10668)
		(layer "F.Cu")
		(net "M_A_CPU0_SA_CB<1>")
	)
	(segment
		(start 311.270904 -240.725452)
		(end 311.270904 -240.574576)
		(width 0.10668)
		(layer "F.Cu")
		(net "M_A_CPU0_SA_CB<1>")
	)
	(segment
		(start 314.43295 -243.440458)
		(end 314.29071 -243.298218)
		(width 0.10668)
		(layer "F.Cu")
		(net "M_A_CPU0_SA_CB<1>")
	)
	(segment
		(start 315.419486 -244.426994)
		(end 315.419486 -244.147086)
		(width 0.10668)
		(layer "F.Cu")
		(net "M_A_CPU0_SA_CB<1>")
	)
	(segment
		(start 316.406022 -245.133622)
		(end 316.126114 -245.133622)
		(width 0.10668)
		(layer "F.Cu")
		(net "M_A_CPU0_SA_CB<1>")
	)
	(segment
		(start 315.983874 -244.991382)
		(end 315.983874 -244.711474)
		(width 0.10668)
		(layer "F.Cu")
		(net "M_A_CPU0_SA_CB<1>")
	)
	(segment
		(start 311.531762 -240.313718)
		(end 311.531762 -240.162842)
		(width 0.10668)
		(layer "F.Cu")
		(net "M_A_CPU0_SA_CB<1>")
	)
	(segment
		(start 325.699374 -245.887494)
		(end 325.690992 -245.882668)
		(width 0.0762)
		(layer "F.Cu")
		(net "M_A_CPU0_SA_CB<1>")
	)
	(segment
		(start 312.378344 -241.1603)
		(end 312.117486 -241.421158)
		(width 0.10668)
		(layer "F.Cu")
		(net "M_A_CPU0_SA_CB<1>")
	)
	(segment
		(start 316.126114 -245.133622)
		(end 315.983874 -244.991382)
		(width 0.10668)
		(layer "F.Cu")
		(net "M_A_CPU0_SA_CB<1>")
	)
	(segment
		(start 310.772048 -239.366044)
		(end 307.841142 -236.435138)
		(width 0.10668)
		(layer "F.Cu")
		(net "M_A_CPU0_SA_CB<1>")
	)
	(segment
		(start 314.29071 -243.298218)
		(end 314.29071 -243.01831)
		(width 0.10668)
		(layer "F.Cu")
		(net "M_A_CPU0_SA_CB<1>")
	)
	(segment
		(start 311.553098 -240.85677)
		(end 311.402222 -240.85677)
		(width 0.10668)
		(layer "F.Cu")
		(net "M_A_CPU0_SA_CB<1>")
	)
	(segment
		(start 313.584082 -242.311682)
		(end 313.304174 -242.311682)
		(width 0.10668)
		(layer "F.Cu")
		(net "M_A_CPU0_SA_CB<1>")
	)
	(segment
		(start 314.712858 -243.440458)
		(end 314.43295 -243.440458)
		(width 0.10668)
		(layer "F.Cu")
		(net "M_A_CPU0_SA_CB<1>")
	)
	(segment
		(start 315.841634 -244.569234)
		(end 315.561726 -244.569234)
		(width 0.10668)
		(layer "F.Cu")
		(net "M_A_CPU0_SA_CB<1>")
	)
	(segment
		(start 314.855098 -243.582698)
		(end 314.712858 -243.440458)
		(width 0.10668)
		(layer "F.Cu")
		(net "M_A_CPU0_SA_CB<1>")
	)
	(segment
		(start 315.277246 -244.004846)
		(end 314.997338 -244.004846)
		(width 0.10668)
		(layer "F.Cu")
		(net "M_A_CPU0_SA_CB<1>")
	)
	(segment
		(start 311.249568 -240.031524)
		(end 310.98871 -240.292382)
		(width 0.10668)
		(layer "F.Cu")
		(net "M_A_CPU0_SA_CB<1>")
	)
	(segment
		(start 311.964832 -240.595912)
		(end 311.813956 -240.595912)
		(width 0.10668)
		(layer "F.Cu")
		(net "M_A_CPU0_SA_CB<1>")
	)
	(segment
		(start 316.687962 -245.69547)
		(end 316.548262 -245.55577)
		(width 0.10668)
		(layer "F.Cu")
		(net "M_A_CPU0_SA_CB<1>")
	)
	(segment
		(start 312.660538 -241.291618)
		(end 312.52922 -241.1603)
		(width 0.10668)
		(layer "F.Cu")
		(net "M_A_CPU0_SA_CB<1>")
	)
	(segment
		(start 312.117486 -241.421158)
		(end 311.96661 -241.421158)
		(width 0.10668)
		(layer "F.Cu")
		(net "M_A_CPU0_SA_CB<1>")
	)
	(segment
		(start 312.660538 -241.442494)
		(end 312.660538 -241.291618)
		(width 0.10668)
		(layer "F.Cu")
		(net "M_A_CPU0_SA_CB<1>")
	)
	(segment
		(start 315.983874 -244.711474)
		(end 315.841634 -244.569234)
		(width 0.10668)
		(layer "F.Cu")
		(net "M_A_CPU0_SA_CB<1>")
	)
	(segment
		(start 313.726322 -242.73383)
		(end 313.726322 -242.453922)
		(width 0.10668)
		(layer "F.Cu")
		(net "M_A_CPU0_SA_CB<1>")
	)
	(segment
		(start 315.561726 -244.569234)
		(end 315.419486 -244.426994)
		(width 0.10668)
		(layer "F.Cu")
		(net "M_A_CPU0_SA_CB<1>")
	)
	(segment
		(start 327.004934 -245.882414)
		(end 327.004934 -245.882668)
		(width 0.0762)
		(layer "F.Cu")
		(net "M_A_CPU0_SA_CB<1>")
	)
	(segment
		(start 313.012836 -242.020344)
		(end 312.565796 -242.020344)
		(width 0.10668)
		(layer "F.Cu")
		(net "M_A_CPU0_SA_CB<1>")
	)
	(segment
		(start 313.726322 -242.453922)
		(end 313.584082 -242.311682)
		(width 0.10668)
		(layer "F.Cu")
		(net "M_A_CPU0_SA_CB<1>")
	)
	(segment
		(start 307.841142 -236.435138)
		(end 307.368194 -236.435138)
		(width 0.10668)
		(layer "F.Cu")
		(net "M_A_CPU0_SA_CB<1>")
	)
	(segment
		(start 312.39968 -241.703352)
		(end 312.660538 -241.442494)
		(width 0.10668)
		(layer "F.Cu")
		(net "M_A_CPU0_SA_CB<1>")
	)
	(segment
		(start 311.813956 -240.595912)
		(end 311.553098 -240.85677)
		(width 0.10668)
		(layer "F.Cu")
		(net "M_A_CPU0_SA_CB<1>")
	)
	(segment
		(start 311.270904 -240.574576)
		(end 311.531762 -240.313718)
		(width 0.10668)
		(layer "F.Cu")
		(net "M_A_CPU0_SA_CB<1>")
	)
	(segment
		(start 314.997338 -244.004846)
		(end 314.855098 -243.862606)
		(width 0.10668)
		(layer "F.Cu")
		(net "M_A_CPU0_SA_CB<1>")
	)
	(segment
		(start 311.835292 -241.138964)
		(end 312.09615 -240.878106)
		(width 0.10668)
		(layer "F.Cu")
		(net "M_A_CPU0_SA_CB<1>")
	)
	(segment
		(start 325.109078 -245.72595)
		(end 323.967094 -245.72595)
		(width 0.0762)
		(layer "F.Cu")
		(net "M_A_CPU0_SA_CB<1>")
	)
	(segment
		(start 316.548262 -245.275862)
		(end 316.406022 -245.133622)
		(width 0.10668)
		(layer "F.Cu")
		(net "M_A_CPU0_SA_CB<1>")
	)
	(segment
		(start 312.09615 -240.72723)
		(end 311.964832 -240.595912)
		(width 0.10668)
		(layer "F.Cu")
		(net "M_A_CPU0_SA_CB<1>")
	)
	(segment
		(start 316.548262 -245.55577)
		(end 316.548262 -245.275862)
		(width 0.10668)
		(layer "F.Cu")
		(net "M_A_CPU0_SA_CB<1>")
	)
	(segment
		(start 313.304174 -242.311682)
		(end 313.012836 -242.020344)
		(width 0.10668)
		(layer "F.Cu")
		(net "M_A_CPU0_SA_CB<1>")
	)
	(segment
		(start 312.565796 -242.020344)
		(end 312.39968 -241.854228)
		(width 0.10668)
		(layer "F.Cu")
		(net "M_A_CPU0_SA_CB<1>")
	)
	(segment
		(start 313.868562 -242.87607)
		(end 313.726322 -242.73383)
		(width 0.10668)
		(layer "F.Cu")
		(net "M_A_CPU0_SA_CB<1>")
	)
	(segment
		(start 311.531762 -240.162842)
		(end 311.400444 -240.031524)
		(width 0.10668)
		(layer "F.Cu")
		(net "M_A_CPU0_SA_CB<1>")
	)
	(segment
		(start 311.835292 -241.28984)
		(end 311.835292 -241.138964)
		(width 0.10668)
		(layer "F.Cu")
		(net "M_A_CPU0_SA_CB<1>")
	)
	(arc
		(start 325.690992 -245.882668)
		(mid 325.410401 -245.765818)
		(end 325.109078 -245.72595)
		(width 0.0762)
		(layer "F.Cu")
		(net "M_A_CPU0_SA_CB<1>")
	)
	(arc
		(start 327.289414 -245.80596)
		(mid 327.142093 -245.825279)
		(end 327.004934 -245.882414)
		(width 0.0762)
		(layer "F.Cu")
		(net "M_A_CPU0_SA_CB<1>")
	)
	(arc
		(start 327.004934 -245.882668)
		(mid 326.81799 -245.932923)
		(end 326.631046 -245.882668)
		(width 0.0762)
		(layer "F.Cu")
		(net "M_A_CPU0_SA_CB<1>")
	)
	(arc
		(start 327.758044 -245.560088)
		(mid 327.554028 -245.740782)
		(end 327.289414 -245.80596)
		(width 0.0762)
		(layer "F.Cu")
		(net "M_A_CPU0_SA_CB<1>")
	)
	(arc
		(start 326.065134 -245.882668)
		(mid 325.882883 -245.933018)
		(end 325.699374 -245.887494)
		(width 0.0762)
		(layer "F.Cu")
		(net "M_A_CPU0_SA_CB<1>")
	)
	(arc
		(start 326.631046 -245.882668)
		(mid 326.34809 -245.806491)
		(end 326.065134 -245.882668)
		(width 0.0762)
		(layer "F.Cu")
		(net "M_A_CPU0_SA_CB<1>")
	)
	(segment
		(start 313.831732 -240.99139)
		(end 313.831732 -240.840514)
		(width 0.10668)
		(layer "F.Cu")
		(net "M_A_CPU0_SA_CB<0>")
	)
	(segment
		(start 317.063628 -244.68328)
		(end 317.063374 -244.532404)
		(width 0.10668)
		(layer "F.Cu")
		(net "M_A_CPU0_SA_CB<0>")
	)
	(segment
		(start 317.063374 -244.532404)
		(end 317.21806 -244.377718)
		(width 0.10668)
		(layer "F.Cu")
		(net "M_A_CPU0_SA_CB<0>")
	)
	(segment
		(start 314.39612 -241.555778)
		(end 314.39612 -241.404902)
		(width 0.10668)
		(layer "F.Cu")
		(net "M_A_CPU0_SA_CB<0>")
	)
	(segment
		(start 316.49924 -244.118892)
		(end 316.498986 -243.968016)
		(width 0.10668)
		(layer "F.Cu")
		(net "M_A_CPU0_SA_CB<0>")
	)
	(segment
		(start 314.39612 -241.404902)
		(end 314.264548 -241.27333)
		(width 0.10668)
		(layer "F.Cu")
		(net "M_A_CPU0_SA_CB<0>")
	)
	(segment
		(start 315.934598 -243.403628)
		(end 316.089284 -243.248942)
		(width 0.10668)
		(layer "F.Cu")
		(net "M_A_CPU0_SA_CB<0>")
	)
	(segment
		(start 314.828936 -241.837718)
		(end 314.678568 -241.837972)
		(width 0.10668)
		(layer "F.Cu")
		(net "M_A_CPU0_SA_CB<0>")
	)
	(segment
		(start 314.806076 -242.425728)
		(end 314.805822 -242.274852)
		(width 0.10668)
		(layer "F.Cu")
		(net "M_A_CPU0_SA_CB<0>")
	)
	(segment
		(start 317.21806 -244.377718)
		(end 317.21806 -244.226842)
		(width 0.10668)
		(layer "F.Cu")
		(net "M_A_CPU0_SA_CB<0>")
	)
	(segment
		(start 314.11418 -241.273584)
		(end 313.959494 -241.42827)
		(width 0.10668)
		(layer "F.Cu")
		(net "M_A_CPU0_SA_CB<0>")
	)
	(segment
		(start 315.934852 -243.554504)
		(end 315.934598 -243.403628)
		(width 0.10668)
		(layer "F.Cu")
		(net "M_A_CPU0_SA_CB<0>")
	)
	(segment
		(start 313.112912 -240.732564)
		(end 313.112658 -240.581688)
		(width 0.10668)
		(layer "F.Cu")
		(net "M_A_CPU0_SA_CB<0>")
	)
	(segment
		(start 314.960508 -241.96929)
		(end 314.828936 -241.837718)
		(width 0.10668)
		(layer "F.Cu")
		(net "M_A_CPU0_SA_CB<0>")
	)
	(segment
		(start 313.267344 -240.427002)
		(end 313.267344 -240.276126)
		(width 0.10668)
		(layer "F.Cu")
		(net "M_A_CPU0_SA_CB<0>")
	)
	(segment
		(start 316.781434 -244.25021)
		(end 316.630558 -244.25021)
		(width 0.10668)
		(layer "F.Cu")
		(net "M_A_CPU0_SA_CB<0>")
	)
	(segment
		(start 315.652658 -243.121434)
		(end 315.501782 -243.121434)
		(width 0.10668)
		(layer "F.Cu")
		(net "M_A_CPU0_SA_CB<0>")
	)
	(segment
		(start 313.24423 -240.863882)
		(end 313.112912 -240.732564)
		(width 0.10668)
		(layer "F.Cu")
		(net "M_A_CPU0_SA_CB<0>")
	)
	(segment
		(start 315.08827 -242.557046)
		(end 314.937394 -242.557046)
		(width 0.10668)
		(layer "F.Cu")
		(net "M_A_CPU0_SA_CB<0>")
	)
	(segment
		(start 314.264548 -241.27333)
		(end 314.11418 -241.273584)
		(width 0.10668)
		(layer "F.Cu")
		(net "M_A_CPU0_SA_CB<0>")
	)
	(segment
		(start 313.267344 -240.276126)
		(end 313.135772 -240.144554)
		(width 0.10668)
		(layer "F.Cu")
		(net "M_A_CPU0_SA_CB<0>")
	)
	(segment
		(start 309.176674 -236.094778)
		(end 307.817012 -234.735116)
		(width 0.10668)
		(layer "F.Cu")
		(net "M_A_CPU0_SA_CB<0>")
	)
	(segment
		(start 316.93612 -244.095524)
		(end 316.781434 -244.25021)
		(width 0.10668)
		(layer "F.Cu")
		(net "M_A_CPU0_SA_CB<0>")
	)
	(segment
		(start 314.960508 -242.120166)
		(end 314.960508 -241.96929)
		(width 0.10668)
		(layer "F.Cu")
		(net "M_A_CPU0_SA_CB<0>")
	)
	(segment
		(start 316.06617 -243.685822)
		(end 315.934852 -243.554504)
		(width 0.10668)
		(layer "F.Cu")
		(net "M_A_CPU0_SA_CB<0>")
	)
	(segment
		(start 314.678568 -241.837972)
		(end 314.523882 -241.992658)
		(width 0.10668)
		(layer "F.Cu")
		(net "M_A_CPU0_SA_CB<0>")
	)
	(segment
		(start 316.217046 -243.685822)
		(end 316.06617 -243.685822)
		(width 0.10668)
		(layer "F.Cu")
		(net "M_A_CPU0_SA_CB<0>")
	)
	(segment
		(start 316.5221 -243.530882)
		(end 316.371732 -243.531136)
		(width 0.10668)
		(layer "F.Cu")
		(net "M_A_CPU0_SA_CB<0>")
	)
	(segment
		(start 315.393324 -242.402106)
		(end 315.242956 -242.40236)
		(width 0.10668)
		(layer "F.Cu")
		(net "M_A_CPU0_SA_CB<0>")
	)
	(segment
		(start 314.241688 -241.86134)
		(end 314.241434 -241.710464)
		(width 0.10668)
		(layer "F.Cu")
		(net "M_A_CPU0_SA_CB<0>")
	)
	(segment
		(start 317.21806 -244.226842)
		(end 317.086488 -244.09527)
		(width 0.10668)
		(layer "F.Cu")
		(net "M_A_CPU0_SA_CB<0>")
	)
	(segment
		(start 312.985404 -240.144808)
		(end 312.830718 -240.299494)
		(width 0.10668)
		(layer "F.Cu")
		(net "M_A_CPU0_SA_CB<0>")
	)
	(segment
		(start 312.830718 -240.299494)
		(end 312.679842 -240.299494)
		(width 0.10668)
		(layer "F.Cu")
		(net "M_A_CPU0_SA_CB<0>")
	)
	(segment
		(start 316.630558 -244.25021)
		(end 316.49924 -244.118892)
		(width 0.10668)
		(layer "F.Cu")
		(net "M_A_CPU0_SA_CB<0>")
	)
	(segment
		(start 315.524896 -242.684554)
		(end 315.524896 -242.533678)
		(width 0.10668)
		(layer "F.Cu")
		(net "M_A_CPU0_SA_CB<0>")
	)
	(segment
		(start 313.677046 -241.146076)
		(end 313.831732 -240.99139)
		(width 0.10668)
		(layer "F.Cu")
		(net "M_A_CPU0_SA_CB<0>")
	)
	(segment
		(start 314.523882 -241.992658)
		(end 314.373006 -241.992658)
		(width 0.10668)
		(layer "F.Cu")
		(net "M_A_CPU0_SA_CB<0>")
	)
	(segment
		(start 314.241434 -241.710464)
		(end 314.39612 -241.555778)
		(width 0.10668)
		(layer "F.Cu")
		(net "M_A_CPU0_SA_CB<0>")
	)
	(segment
		(start 315.501782 -243.121434)
		(end 315.370464 -242.990116)
		(width 0.10668)
		(layer "F.Cu")
		(net "M_A_CPU0_SA_CB<0>")
	)
	(segment
		(start 313.70016 -240.708942)
		(end 313.549792 -240.709196)
		(width 0.10668)
		(layer "F.Cu")
		(net "M_A_CPU0_SA_CB<0>")
	)
	(segment
		(start 315.957712 -242.966494)
		(end 315.807344 -242.966748)
		(width 0.10668)
		(layer "F.Cu")
		(net "M_A_CPU0_SA_CB<0>")
	)
	(segment
		(start 314.805822 -242.274852)
		(end 314.960508 -242.120166)
		(width 0.10668)
		(layer "F.Cu")
		(net "M_A_CPU0_SA_CB<0>")
	)
	(segment
		(start 316.089284 -243.098066)
		(end 315.957712 -242.966494)
		(width 0.10668)
		(layer "F.Cu")
		(net "M_A_CPU0_SA_CB<0>")
	)
	(segment
		(start 313.808618 -241.42827)
		(end 313.6773 -241.296952)
		(width 0.10668)
		(layer "F.Cu")
		(net "M_A_CPU0_SA_CB<0>")
	)
	(segment
		(start 324.515734 -245.12651)
		(end 324.337934 -244.94871)
		(width 0.0762)
		(layer "F.Cu")
		(net "M_A_CPU0_SA_CB<0>")
	)
	(segment
		(start 313.395106 -240.863882)
		(end 313.24423 -240.863882)
		(width 0.10668)
		(layer "F.Cu")
		(net "M_A_CPU0_SA_CB<0>")
	)
	(segment
		(start 315.524896 -242.533678)
		(end 315.393324 -242.402106)
		(width 0.10668)
		(layer "F.Cu")
		(net "M_A_CPU0_SA_CB<0>")
	)
	(segment
		(start 316.653672 -243.81333)
		(end 316.653672 -243.662454)
		(width 0.10668)
		(layer "F.Cu")
		(net "M_A_CPU0_SA_CB<0>")
	)
	(segment
		(start 324.337934 -244.94871)
		(end 317.329058 -244.94871)
		(width 0.10668)
		(layer "F.Cu")
		(net "M_A_CPU0_SA_CB<0>")
	)
	(segment
		(start 316.653672 -243.662454)
		(end 316.5221 -243.530882)
		(width 0.10668)
		(layer "F.Cu")
		(net "M_A_CPU0_SA_CB<0>")
	)
	(segment
		(start 313.6773 -241.296952)
		(end 313.677046 -241.146076)
		(width 0.10668)
		(layer "F.Cu")
		(net "M_A_CPU0_SA_CB<0>")
	)
	(segment
		(start 313.959494 -241.42827)
		(end 313.808618 -241.42827)
		(width 0.10668)
		(layer "F.Cu")
		(net "M_A_CPU0_SA_CB<0>")
	)
	(segment
		(start 313.135772 -240.144554)
		(end 312.985404 -240.144808)
		(width 0.10668)
		(layer "F.Cu")
		(net "M_A_CPU0_SA_CB<0>")
	)
	(segment
		(start 314.937394 -242.557046)
		(end 314.806076 -242.425728)
		(width 0.10668)
		(layer "F.Cu")
		(net "M_A_CPU0_SA_CB<0>")
	)
	(segment
		(start 313.112658 -240.581688)
		(end 313.267344 -240.427002)
		(width 0.10668)
		(layer "F.Cu")
		(net "M_A_CPU0_SA_CB<0>")
	)
	(segment
		(start 316.498986 -243.968016)
		(end 316.653672 -243.81333)
		(width 0.10668)
		(layer "F.Cu")
		(net "M_A_CPU0_SA_CB<0>")
	)
	(segment
		(start 313.549792 -240.709196)
		(end 313.395106 -240.863882)
		(width 0.10668)
		(layer "F.Cu")
		(net "M_A_CPU0_SA_CB<0>")
	)
	(segment
		(start 316.089284 -243.248942)
		(end 316.089284 -243.098066)
		(width 0.10668)
		(layer "F.Cu")
		(net "M_A_CPU0_SA_CB<0>")
	)
	(segment
		(start 325.32828 -245.12651)
		(end 324.515734 -245.12651)
		(width 0.0762)
		(layer "F.Cu")
		(net "M_A_CPU0_SA_CB<0>")
	)
	(segment
		(start 307.817012 -234.735116)
		(end 307.368194 -234.735116)
		(width 0.10668)
		(layer "F.Cu")
		(net "M_A_CPU0_SA_CB<0>")
	)
	(segment
		(start 309.176674 -236.796326)
		(end 309.176674 -236.094778)
		(width 0.10668)
		(layer "F.Cu")
		(net "M_A_CPU0_SA_CB<0>")
	)
	(segment
		(start 315.370464 -242.990116)
		(end 315.37021 -242.83924)
		(width 0.10668)
		(layer "F.Cu")
		(net "M_A_CPU0_SA_CB<0>")
	)
	(segment
		(start 314.373006 -241.992658)
		(end 314.241688 -241.86134)
		(width 0.10668)
		(layer "F.Cu")
		(net "M_A_CPU0_SA_CB<0>")
	)
	(segment
		(start 316.371732 -243.531136)
		(end 316.217046 -243.685822)
		(width 0.10668)
		(layer "F.Cu")
		(net "M_A_CPU0_SA_CB<0>")
	)
	(segment
		(start 317.329058 -244.94871)
		(end 317.063628 -244.68328)
		(width 0.10668)
		(layer "F.Cu")
		(net "M_A_CPU0_SA_CB<0>")
	)
	(segment
		(start 315.242956 -242.40236)
		(end 315.08827 -242.557046)
		(width 0.10668)
		(layer "F.Cu")
		(net "M_A_CPU0_SA_CB<0>")
	)
	(segment
		(start 312.679842 -240.299494)
		(end 309.176674 -236.796326)
		(width 0.10668)
		(layer "F.Cu")
		(net "M_A_CPU0_SA_CB<0>")
	)
	(segment
		(start 313.831732 -240.840514)
		(end 313.70016 -240.708942)
		(width 0.10668)
		(layer "F.Cu")
		(net "M_A_CPU0_SA_CB<0>")
	)
	(segment
		(start 315.37021 -242.83924)
		(end 315.524896 -242.684554)
		(width 0.10668)
		(layer "F.Cu")
		(net "M_A_CPU0_SA_CB<0>")
	)
	(segment
		(start 317.086488 -244.09527)
		(end 316.93612 -244.095524)
		(width 0.10668)
		(layer "F.Cu")
		(net "M_A_CPU0_SA_CB<0>")
	)
	(segment
		(start 315.807344 -242.966748)
		(end 315.652658 -243.121434)
		(width 0.10668)
		(layer "F.Cu")
		(net "M_A_CPU0_SA_CB<0>")
	)
	(arc
		(start 325.59498 -245.072662)
		(mid 325.51974 -245.105975)
		(end 325.439024 -245.121938)
		(width 0.0762)
		(layer "F.Cu")
		(net "M_A_CPU0_SA_CB<0>")
	)
	(arc
		(start 325.830438 -244.99824)
		(mid 325.708582 -245.022396)
		(end 325.59498 -245.072662)
		(width 0.0762)
		(layer "F.Cu")
		(net "M_A_CPU0_SA_CB<0>")
	)
	(arc
		(start 326.34809 -244.750082)
		(mid 326.111962 -244.921517)
		(end 325.830438 -244.99824)
		(width 0.0762)
		(layer "F.Cu")
		(net "M_A_CPU0_SA_CB<0>")
	)
	(arc
		(start 325.439024 -245.121938)
		(mid 325.383699 -245.125369)
		(end 325.32828 -245.12651)
		(width 0.0762)
		(layer "F.Cu")
		(net "M_A_CPU0_SA_CB<0>")
	)
	(segment
		(start 312.08091 -255.00965)
		(end 312.08091 -254.751332)
		(width 0.10668)
		(layer "F.Cu")
		(net "M_A_CPU0_SA_CA<6>")
	)
	(segment
		(start 313.677046 -255.00965)
		(end 313.677046 -254.751332)
		(width 0.10668)
		(layer "F.Cu")
		(net "M_A_CPU0_SA_CA<6>")
	)
	(segment
		(start 313.570366 -254.644652)
		(end 313.384692 -254.644652)
		(width 0.10668)
		(layer "F.Cu")
		(net "M_A_CPU0_SA_CA<6>")
	)
	(segment
		(start 313.783726 -255.11633)
		(end 313.677046 -255.00965)
		(width 0.10668)
		(layer "F.Cu")
		(net "M_A_CPU0_SA_CA<6>")
	)
	(segment
		(start 314.456826 -255.11633)
		(end 313.783726 -255.11633)
		(width 0.10668)
		(layer "F.Cu")
		(net "M_A_CPU0_SA_CA<6>")
	)
	(segment
		(start 311.681876 -255.00965)
		(end 311.575196 -255.11633)
		(width 0.10668)
		(layer "F.Cu")
		(net "M_A_CPU0_SA_CA<6>")
	)
	(segment
		(start 313.278012 -254.751332)
		(end 313.278012 -255.00965)
		(width 0.10668)
		(layer "F.Cu")
		(net "M_A_CPU0_SA_CA<6>")
	)
	(segment
		(start 311.575196 -255.11633)
		(end 310.781446 -255.11633)
		(width 0.10668)
		(layer "F.Cu")
		(net "M_A_CPU0_SA_CA<6>")
	)
	(segment
		(start 312.08091 -254.751332)
		(end 311.97423 -254.644652)
		(width 0.10668)
		(layer "F.Cu")
		(net "M_A_CPU0_SA_CA<6>")
	)
	(segment
		(start 312.878978 -254.751332)
		(end 312.772298 -254.644652)
		(width 0.10668)
		(layer "F.Cu")
		(net "M_A_CPU0_SA_CA<6>")
	)
	(segment
		(start 312.18759 -255.11633)
		(end 312.08091 -255.00965)
		(width 0.10668)
		(layer "F.Cu")
		(net "M_A_CPU0_SA_CA<6>")
	)
	(segment
		(start 319.820544 -253.880112)
		(end 315.693044 -253.880112)
		(width 0.10668)
		(layer "F.Cu")
		(net "M_A_CPU0_SA_CA<6>")
	)
	(segment
		(start 312.479944 -255.00965)
		(end 312.373264 -255.11633)
		(width 0.10668)
		(layer "F.Cu")
		(net "M_A_CPU0_SA_CA<6>")
	)
	(segment
		(start 325.699374 -255.607566)
		(end 325.690992 -255.60274)
		(width 0.0762)
		(layer "F.Cu")
		(net "M_A_CPU0_SA_CA<6>")
	)
	(segment
		(start 324.551294 -255.45161)
		(end 324.020434 -255.98247)
		(width 0.0762)
		(layer "F.Cu")
		(net "M_A_CPU0_SA_CA<6>")
	)
	(segment
		(start 311.788556 -254.644652)
		(end 311.681876 -254.751332)
		(width 0.10668)
		(layer "F.Cu")
		(net "M_A_CPU0_SA_CA<6>")
	)
	(segment
		(start 310.781446 -255.11633)
		(end 308.250082 -252.584966)
		(width 0.10668)
		(layer "F.Cu")
		(net "M_A_CPU0_SA_CA<6>")
	)
	(segment
		(start 312.479944 -254.751332)
		(end 312.479944 -255.00965)
		(width 0.10668)
		(layer "F.Cu")
		(net "M_A_CPU0_SA_CA<6>")
	)
	(segment
		(start 325.213726 -255.45161)
		(end 324.551294 -255.45161)
		(width 0.0762)
		(layer "F.Cu")
		(net "M_A_CPU0_SA_CA<6>")
	)
	(segment
		(start 311.97423 -254.644652)
		(end 311.788556 -254.644652)
		(width 0.10668)
		(layer "F.Cu")
		(net "M_A_CPU0_SA_CA<6>")
	)
	(segment
		(start 308.250082 -252.584966)
		(end 307.368194 -252.584966)
		(width 0.10668)
		(layer "F.Cu")
		(net "M_A_CPU0_SA_CA<6>")
	)
	(segment
		(start 313.278012 -255.00965)
		(end 313.171332 -255.11633)
		(width 0.10668)
		(layer "F.Cu")
		(net "M_A_CPU0_SA_CA<6>")
	)
	(segment
		(start 311.681876 -254.751332)
		(end 311.681876 -255.00965)
		(width 0.10668)
		(layer "F.Cu")
		(net "M_A_CPU0_SA_CA<6>")
	)
	(segment
		(start 322.239386 -256.298954)
		(end 319.820544 -253.880112)
		(width 0.10668)
		(layer "F.Cu")
		(net "M_A_CPU0_SA_CA<6>")
	)
	(segment
		(start 313.677046 -254.751332)
		(end 313.570366 -254.644652)
		(width 0.10668)
		(layer "F.Cu")
		(net "M_A_CPU0_SA_CA<6>")
	)
	(segment
		(start 313.171332 -255.11633)
		(end 312.985658 -255.11633)
		(width 0.10668)
		(layer "F.Cu")
		(net "M_A_CPU0_SA_CA<6>")
	)
	(segment
		(start 324.020434 -255.98247)
		(end 323.70395 -256.298954)
		(width 0.10668)
		(layer "F.Cu")
		(net "M_A_CPU0_SA_CA<6>")
	)
	(segment
		(start 312.772298 -254.644652)
		(end 312.586624 -254.644652)
		(width 0.10668)
		(layer "F.Cu")
		(net "M_A_CPU0_SA_CA<6>")
	)
	(segment
		(start 312.373264 -255.11633)
		(end 312.18759 -255.11633)
		(width 0.10668)
		(layer "F.Cu")
		(net "M_A_CPU0_SA_CA<6>")
	)
	(segment
		(start 312.586624 -254.644652)
		(end 312.479944 -254.751332)
		(width 0.10668)
		(layer "F.Cu")
		(net "M_A_CPU0_SA_CA<6>")
	)
	(segment
		(start 323.70395 -256.298954)
		(end 322.239386 -256.298954)
		(width 0.10668)
		(layer "F.Cu")
		(net "M_A_CPU0_SA_CA<6>")
	)
	(segment
		(start 315.693044 -253.880112)
		(end 314.456826 -255.11633)
		(width 0.10668)
		(layer "F.Cu")
		(net "M_A_CPU0_SA_CA<6>")
	)
	(segment
		(start 313.384692 -254.644652)
		(end 313.278012 -254.751332)
		(width 0.10668)
		(layer "F.Cu")
		(net "M_A_CPU0_SA_CA<6>")
	)
	(segment
		(start 312.878978 -255.00965)
		(end 312.878978 -254.751332)
		(width 0.10668)
		(layer "F.Cu")
		(net "M_A_CPU0_SA_CA<6>")
	)
	(segment
		(start 312.985658 -255.11633)
		(end 312.878978 -255.00965)
		(width 0.10668)
		(layer "F.Cu")
		(net "M_A_CPU0_SA_CA<6>")
	)
	(segment
		(start 327.004934 -255.602486)
		(end 327.004934 -255.60274)
		(width 0.0762)
		(layer "F.Cu")
		(net "M_A_CPU0_SA_CA<6>")
	)
	(arc
		(start 325.289926 -255.457706)
		(mid 325.251953 -255.453074)
		(end 325.213726 -255.45161)
		(width 0.0762)
		(layer "F.Cu")
		(net "M_A_CPU0_SA_CA<6>")
	)
	(arc
		(start 327.004934 -255.60274)
		(mid 326.81799 -255.652995)
		(end 326.631046 -255.60274)
		(width 0.0762)
		(layer "F.Cu")
		(net "M_A_CPU0_SA_CA<6>")
	)
	(arc
		(start 327.758044 -255.28016)
		(mid 327.554028 -255.460854)
		(end 327.289414 -255.526032)
		(width 0.0762)
		(layer "F.Cu")
		(net "M_A_CPU0_SA_CA<6>")
	)
	(arc
		(start 326.065134 -255.60274)
		(mid 325.882883 -255.65309)
		(end 325.699374 -255.607566)
		(width 0.0762)
		(layer "F.Cu")
		(net "M_A_CPU0_SA_CA<6>")
	)
	(arc
		(start 325.690992 -255.60274)
		(mid 325.496999 -255.512133)
		(end 325.289926 -255.457706)
		(width 0.0762)
		(layer "F.Cu")
		(net "M_A_CPU0_SA_CA<6>")
	)
	(arc
		(start 327.289414 -255.526032)
		(mid 327.142093 -255.545351)
		(end 327.004934 -255.602486)
		(width 0.0762)
		(layer "F.Cu")
		(net "M_A_CPU0_SA_CA<6>")
	)
	(arc
		(start 326.631046 -255.60274)
		(mid 326.34809 -255.526563)
		(end 326.065134 -255.60274)
		(width 0.0762)
		(layer "F.Cu")
		(net "M_A_CPU0_SA_CA<6>")
	)
	(segment
		(start 325.877936 -255.28016)
		(end 325.976234 -255.110996)
		(width 0.0762)
		(layer "F.Cu")
		(net "M_A_CPU0_SA_CA<5>")
	)
	(segment
		(start 323.54393 -255.958594)
		(end 322.38061 -255.958594)
		(width 0.10668)
		(layer "F.Cu")
		(net "M_A_CPU0_SA_CA<5>")
	)
	(segment
		(start 314.850526 -254.240792)
		(end 310.387492 -254.240792)
		(width 0.10668)
		(layer "F.Cu")
		(net "M_A_CPU0_SA_CA<5>")
	)
	(segment
		(start 325.699374 -254.952754)
		(end 325.690992 -254.95758)
		(width 0.0762)
		(layer "F.Cu")
		(net "M_A_CPU0_SA_CA<5>")
	)
	(segment
		(start 310.387492 -254.240792)
		(end 308.474364 -252.327664)
		(width 0.10668)
		(layer "F.Cu")
		(net "M_A_CPU0_SA_CA<5>")
	)
	(segment
		(start 315.551566 -253.539752)
		(end 314.850526 -254.240792)
		(width 0.10668)
		(layer "F.Cu")
		(net "M_A_CPU0_SA_CA<5>")
	)
	(segment
		(start 325.408036 -255.03378)
		(end 324.468744 -255.03378)
		(width 0.0762)
		(layer "F.Cu")
		(net "M_A_CPU0_SA_CA<5>")
	)
	(segment
		(start 308.474364 -252.327664)
		(end 308.306724 -252.160024)
		(width 0.101346)
		(layer "F.Cu")
		(net "M_A_CPU0_SA_CA<5>")
	)
	(segment
		(start 324.468744 -255.03378)
		(end 323.54393 -255.958594)
		(width 0.0762)
		(layer "F.Cu")
		(net "M_A_CPU0_SA_CA<5>")
	)
	(segment
		(start 308.306724 -252.160024)
		(end 306.070508 -252.160024)
		(width 0.101346)
		(layer "F.Cu")
		(net "M_A_CPU0_SA_CA<5>")
	)
	(segment
		(start 319.961768 -253.539752)
		(end 315.551566 -253.539752)
		(width 0.10668)
		(layer "F.Cu")
		(net "M_A_CPU0_SA_CA<5>")
	)
	(segment
		(start 305.645566 -251.735082)
		(end 303.268126 -251.735082)
		(width 0.101346)
		(layer "F.Cu")
		(net "M_A_CPU0_SA_CA<5>")
	)
	(segment
		(start 322.38061 -255.958594)
		(end 319.961768 -253.539752)
		(width 0.10668)
		(layer "F.Cu")
		(net "M_A_CPU0_SA_CA<5>")
	)
	(segment
		(start 306.070508 -252.160024)
		(end 305.645566 -251.735082)
		(width 0.101346)
		(layer "F.Cu")
		(net "M_A_CPU0_SA_CA<5>")
	)
	(arc
		(start 325.690992 -254.95758)
		(mid 325.554556 -255.014405)
		(end 325.408036 -255.03378)
		(width 0.0762)
		(layer "F.Cu")
		(net "M_A_CPU0_SA_CA<5>")
	)
	(arc
		(start 325.838566 -254.90932)
		(mid 325.766828 -254.924172)
		(end 325.699374 -254.952754)
		(width 0.0762)
		(layer "F.Cu")
		(net "M_A_CPU0_SA_CA<5>")
	)
	(arc
		(start 325.976234 -255.110996)
		(mid 325.967641 -254.969117)
		(end 325.838566 -254.90932)
		(width 0.0762)
		(layer "F.Cu")
		(net "M_A_CPU0_SA_CA<5>")
	)
	(segment
		(start 322.62953 -255.294892)
		(end 322.52285 -255.401572)
		(width 0.10668)
		(layer "F.Cu")
		(net "M_A_CPU0_SA_CA<4>")
	)
	(segment
		(start 323.427598 -254.99949)
		(end 323.427598 -255.294892)
		(width 0.10668)
		(layer "F.Cu")
		(net "M_A_CPU0_SA_CA<4>")
	)
	(segment
		(start 311.665874 -253.199392)
		(end 309.925466 -253.199392)
		(width 0.10668)
		(layer "F.Cu")
		(net "M_A_CPU0_SA_CA<4>")
	)
	(segment
		(start 324.142862 -254.856742)
		(end 324.106794 -254.89281)
		(width 0.10668)
		(layer "F.Cu")
		(net "M_A_CPU0_SA_CA<4>")
	)
	(segment
		(start 312.171588 -253.689612)
		(end 312.064908 -253.796292)
		(width 0.10668)
		(layer "F.Cu")
		(net "M_A_CPU0_SA_CA<4>")
	)
	(segment
		(start 323.534278 -254.89281)
		(end 323.427598 -254.99949)
		(width 0.10668)
		(layer "F.Cu")
		(net "M_A_CPU0_SA_CA<4>")
	)
	(segment
		(start 312.969656 -253.689612)
		(end 312.862976 -253.796292)
		(width 0.10668)
		(layer "F.Cu")
		(net "M_A_CPU0_SA_CA<4>")
	)
	(segment
		(start 313.874404 -253.199392)
		(end 313.767724 -253.306072)
		(width 0.10668)
		(layer "F.Cu")
		(net "M_A_CPU0_SA_CA<4>")
	)
	(segment
		(start 323.320918 -255.401572)
		(end 323.135244 -255.401572)
		(width 0.10668)
		(layer "F.Cu")
		(net "M_A_CPU0_SA_CA<4>")
	)
	(segment
		(start 322.337176 -255.401572)
		(end 322.230496 -255.294892)
		(width 0.10668)
		(layer "F.Cu")
		(net "M_A_CPU0_SA_CA<4>")
	)
	(segment
		(start 313.767724 -253.689612)
		(end 313.661044 -253.796292)
		(width 0.10668)
		(layer "F.Cu")
		(net "M_A_CPU0_SA_CA<4>")
	)
	(segment
		(start 308.370224 -251.3457)
		(end 307.909468 -250.884944)
		(width 0.10668)
		(layer "F.Cu")
		(net "M_A_CPU0_SA_CA<4>")
	)
	(segment
		(start 322.123816 -254.89281)
		(end 321.79641 -254.89281)
		(width 0.10668)
		(layer "F.Cu")
		(net "M_A_CPU0_SA_CA<4>")
	)
	(segment
		(start 312.570622 -253.306072)
		(end 312.463942 -253.199392)
		(width 0.10668)
		(layer "F.Cu")
		(net "M_A_CPU0_SA_CA<4>")
	)
	(segment
		(start 322.921884 -254.89281)
		(end 322.73621 -254.89281)
		(width 0.10668)
		(layer "F.Cu")
		(net "M_A_CPU0_SA_CA<4>")
	)
	(segment
		(start 312.862976 -253.796292)
		(end 312.677302 -253.796292)
		(width 0.10668)
		(layer "F.Cu")
		(net "M_A_CPU0_SA_CA<4>")
	)
	(segment
		(start 323.135244 -255.401572)
		(end 323.028564 -255.294892)
		(width 0.10668)
		(layer "F.Cu")
		(net "M_A_CPU0_SA_CA<4>")
	)
	(segment
		(start 312.570622 -253.689612)
		(end 312.570622 -253.306072)
		(width 0.10668)
		(layer "F.Cu")
		(net "M_A_CPU0_SA_CA<4>")
	)
	(segment
		(start 313.47537 -253.796292)
		(end 313.36869 -253.689612)
		(width 0.10668)
		(layer "F.Cu")
		(net "M_A_CPU0_SA_CA<4>")
	)
	(segment
		(start 322.52285 -255.401572)
		(end 322.337176 -255.401572)
		(width 0.10668)
		(layer "F.Cu")
		(net "M_A_CPU0_SA_CA<4>")
	)
	(segment
		(start 311.879234 -253.796292)
		(end 311.772554 -253.689612)
		(width 0.10668)
		(layer "F.Cu")
		(net "M_A_CPU0_SA_CA<4>")
	)
	(segment
		(start 313.26201 -253.199392)
		(end 313.076336 -253.199392)
		(width 0.10668)
		(layer "F.Cu")
		(net "M_A_CPU0_SA_CA<4>")
	)
	(segment
		(start 322.73621 -254.89281)
		(end 322.62953 -254.99949)
		(width 0.10668)
		(layer "F.Cu")
		(net "M_A_CPU0_SA_CA<4>")
	)
	(segment
		(start 312.969656 -253.306072)
		(end 312.969656 -253.689612)
		(width 0.10668)
		(layer "F.Cu")
		(net "M_A_CPU0_SA_CA<4>")
	)
	(segment
		(start 313.767724 -253.306072)
		(end 313.767724 -253.689612)
		(width 0.10668)
		(layer "F.Cu")
		(net "M_A_CPU0_SA_CA<4>")
	)
	(segment
		(start 322.62953 -254.99949)
		(end 322.62953 -255.294892)
		(width 0.10668)
		(layer "F.Cu")
		(net "M_A_CPU0_SA_CA<4>")
	)
	(segment
		(start 322.230496 -255.294892)
		(end 322.230496 -254.99949)
		(width 0.10668)
		(layer "F.Cu")
		(net "M_A_CPU0_SA_CA<4>")
	)
	(segment
		(start 312.171588 -253.306072)
		(end 312.171588 -253.689612)
		(width 0.10668)
		(layer "F.Cu")
		(net "M_A_CPU0_SA_CA<4>")
	)
	(segment
		(start 308.370224 -251.64415)
		(end 308.370224 -251.3457)
		(width 0.10668)
		(layer "F.Cu")
		(net "M_A_CPU0_SA_CA<4>")
	)
	(segment
		(start 312.677302 -253.796292)
		(end 312.570622 -253.689612)
		(width 0.10668)
		(layer "F.Cu")
		(net "M_A_CPU0_SA_CA<4>")
	)
	(segment
		(start 313.36869 -253.306072)
		(end 313.26201 -253.199392)
		(width 0.10668)
		(layer "F.Cu")
		(net "M_A_CPU0_SA_CA<4>")
	)
	(segment
		(start 312.064908 -253.796292)
		(end 311.879234 -253.796292)
		(width 0.10668)
		(layer "F.Cu")
		(net "M_A_CPU0_SA_CA<4>")
	)
	(segment
		(start 323.427598 -255.294892)
		(end 323.320918 -255.401572)
		(width 0.10668)
		(layer "F.Cu")
		(net "M_A_CPU0_SA_CA<4>")
	)
	(segment
		(start 312.278268 -253.199392)
		(end 312.171588 -253.306072)
		(width 0.10668)
		(layer "F.Cu")
		(net "M_A_CPU0_SA_CA<4>")
	)
	(segment
		(start 313.661044 -253.796292)
		(end 313.47537 -253.796292)
		(width 0.10668)
		(layer "F.Cu")
		(net "M_A_CPU0_SA_CA<4>")
	)
	(segment
		(start 307.909468 -250.884944)
		(end 307.368194 -250.884944)
		(width 0.10668)
		(layer "F.Cu")
		(net "M_A_CPU0_SA_CA<4>")
	)
	(segment
		(start 323.028564 -255.294892)
		(end 323.028564 -254.99949)
		(width 0.10668)
		(layer "F.Cu")
		(net "M_A_CPU0_SA_CA<4>")
	)
	(segment
		(start 311.772554 -253.689612)
		(end 311.772554 -253.306072)
		(width 0.10668)
		(layer "F.Cu")
		(net "M_A_CPU0_SA_CA<4>")
	)
	(segment
		(start 313.36869 -253.689612)
		(end 313.36869 -253.306072)
		(width 0.10668)
		(layer "F.Cu")
		(net "M_A_CPU0_SA_CA<4>")
	)
	(segment
		(start 320.102992 -253.199392)
		(end 313.874404 -253.199392)
		(width 0.10668)
		(layer "F.Cu")
		(net "M_A_CPU0_SA_CA<4>")
	)
	(segment
		(start 311.772554 -253.306072)
		(end 311.665874 -253.199392)
		(width 0.10668)
		(layer "F.Cu")
		(net "M_A_CPU0_SA_CA<4>")
	)
	(segment
		(start 312.463942 -253.199392)
		(end 312.278268 -253.199392)
		(width 0.10668)
		(layer "F.Cu")
		(net "M_A_CPU0_SA_CA<4>")
	)
	(segment
		(start 321.79641 -254.89281)
		(end 320.102992 -253.199392)
		(width 0.10668)
		(layer "F.Cu")
		(net "M_A_CPU0_SA_CA<4>")
	)
	(segment
		(start 324.106794 -254.89281)
		(end 323.534278 -254.89281)
		(width 0.10668)
		(layer "F.Cu")
		(net "M_A_CPU0_SA_CA<4>")
	)
	(segment
		(start 323.028564 -254.99949)
		(end 322.921884 -254.89281)
		(width 0.10668)
		(layer "F.Cu")
		(net "M_A_CPU0_SA_CA<4>")
	)
	(segment
		(start 324.156324 -254.84328)
		(end 324.142862 -254.856742)
		(width 0.0762)
		(layer "F.Cu")
		(net "M_A_CPU0_SA_CA<4>")
	)
	(segment
		(start 322.230496 -254.99949)
		(end 322.123816 -254.89281)
		(width 0.10668)
		(layer "F.Cu")
		(net "M_A_CPU0_SA_CA<4>")
	)
	(segment
		(start 325.408036 -254.84328)
		(end 324.156324 -254.84328)
		(width 0.0762)
		(layer "F.Cu")
		(net "M_A_CPU0_SA_CA<4>")
	)
	(segment
		(start 309.925466 -253.199392)
		(end 308.370224 -251.64415)
		(width 0.10668)
		(layer "F.Cu")
		(net "M_A_CPU0_SA_CA<4>")
	)
	(segment
		(start 313.076336 -253.199392)
		(end 312.969656 -253.306072)
		(width 0.10668)
		(layer "F.Cu")
		(net "M_A_CPU0_SA_CA<4>")
	)
	(arc
		(start 325.59498 -254.792734)
		(mid 325.504847 -254.830354)
		(end 325.408036 -254.84328)
		(width 0.0762)
		(layer "F.Cu")
		(net "M_A_CPU0_SA_CA<4>")
	)
	(arc
		(start 326.34809 -254.470154)
		(mid 326.105773 -254.639874)
		(end 325.820786 -254.719328)
		(width 0.0762)
		(layer "F.Cu")
		(net "M_A_CPU0_SA_CA<4>")
	)
	(arc
		(start 325.820786 -254.719328)
		(mid 325.703973 -254.744004)
		(end 325.59498 -254.792734)
		(width 0.0762)
		(layer "F.Cu")
		(net "M_A_CPU0_SA_CA<4>")
	)
	(segment
		(start 327.108312 -254.143256)
		(end 327.100946 -254.147574)
		(width 0.0762)
		(layer "F.Cu")
		(net "M_A_CPU0_SA_CA<3>")
	)
	(segment
		(start 323.962014 -254.55245)
		(end 321.937634 -254.55245)
		(width 0.10668)
		(layer "F.Cu")
		(net "M_A_CPU0_SA_CA<3>")
	)
	(segment
		(start 306.070508 -250.460002)
		(end 305.645566 -250.03506)
		(width 0.101346)
		(layer "F.Cu")
		(net "M_A_CPU0_SA_CA<3>")
	)
	(segment
		(start 308.710584 -250.893072)
		(end 308.445154 -250.627642)
		(width 0.10668)
		(layer "F.Cu")
		(net "M_A_CPU0_SA_CA<3>")
	)
	(segment
		(start 305.645566 -250.03506)
		(end 303.268126 -250.03506)
		(width 0.101346)
		(layer "F.Cu")
		(net "M_A_CPU0_SA_CA<3>")
	)
	(segment
		(start 326.535034 -254.147574)
		(end 326.526652 -254.142748)
		(width 0.0762)
		(layer "F.Cu")
		(net "M_A_CPU0_SA_CA<3>")
	)
	(segment
		(start 324.421754 -254.09271)
		(end 324.196964 -254.3175)
		(width 0.0762)
		(layer "F.Cu")
		(net "M_A_CPU0_SA_CA<3>")
	)
	(segment
		(start 310.067198 -252.859032)
		(end 308.710584 -251.502418)
		(width 0.10668)
		(layer "F.Cu")
		(net "M_A_CPU0_SA_CA<3>")
	)
	(segment
		(start 327.28789 -254.4699)
		(end 327.393046 -254.289052)
		(width 0.0762)
		(layer "F.Cu")
		(net "M_A_CPU0_SA_CA<3>")
	)
	(segment
		(start 320.244216 -252.859032)
		(end 310.067198 -252.859032)
		(width 0.10668)
		(layer "F.Cu")
		(net "M_A_CPU0_SA_CA<3>")
	)
	(segment
		(start 324.196964 -254.3175)
		(end 323.962014 -254.55245)
		(width 0.10668)
		(layer "F.Cu")
		(net "M_A_CPU0_SA_CA<3>")
	)
	(segment
		(start 327.28789 -254.470154)
		(end 327.28789 -254.4699)
		(width 0.0762)
		(layer "F.Cu")
		(net "M_A_CPU0_SA_CA<3>")
	)
	(segment
		(start 325.391526 -254.09271)
		(end 324.421754 -254.09271)
		(width 0.0762)
		(layer "F.Cu")
		(net "M_A_CPU0_SA_CA<3>")
	)
	(segment
		(start 321.937634 -254.55245)
		(end 320.244216 -252.859032)
		(width 0.10668)
		(layer "F.Cu")
		(net "M_A_CPU0_SA_CA<3>")
	)
	(segment
		(start 308.445154 -250.627642)
		(end 308.277514 -250.460002)
		(width 0.101346)
		(layer "F.Cu")
		(net "M_A_CPU0_SA_CA<3>")
	)
	(segment
		(start 308.710584 -251.502418)
		(end 308.710584 -250.893072)
		(width 0.10668)
		(layer "F.Cu")
		(net "M_A_CPU0_SA_CA<3>")
	)
	(segment
		(start 308.277514 -250.460002)
		(end 306.070508 -250.460002)
		(width 0.101346)
		(layer "F.Cu")
		(net "M_A_CPU0_SA_CA<3>")
	)
	(segment
		(start 327.109328 -254.142748)
		(end 327.108312 -254.143256)
		(width 0.0762)
		(layer "F.Cu")
		(net "M_A_CPU0_SA_CA<3>")
	)
	(arc
		(start 327.100946 -254.147574)
		(mid 326.81799 -254.223751)
		(end 326.535034 -254.147574)
		(width 0.0762)
		(layer "F.Cu")
		(net "M_A_CPU0_SA_CA<3>")
	)
	(arc
		(start 326.160892 -254.147574)
		(mid 325.877936 -254.223751)
		(end 325.59498 -254.147574)
		(width 0.0762)
		(layer "F.Cu")
		(net "M_A_CPU0_SA_CA<3>")
	)
	(arc
		(start 326.526652 -254.142748)
		(mid 326.343144 -254.097254)
		(end 326.160892 -254.147574)
		(width 0.0762)
		(layer "F.Cu")
		(net "M_A_CPU0_SA_CA<3>")
	)
	(arc
		(start 327.289414 -254.097282)
		(mid 327.19649 -254.108605)
		(end 327.109328 -254.142748)
		(width 0.0762)
		(layer "F.Cu")
		(net "M_A_CPU0_SA_CA<3>")
	)
	(arc
		(start 325.59498 -254.147574)
		(mid 325.496883 -254.106687)
		(end 325.391526 -254.09271)
		(width 0.0762)
		(layer "F.Cu")
		(net "M_A_CPU0_SA_CA<3>")
	)
	(arc
		(start 327.393046 -254.289052)
		(mid 327.384109 -254.170028)
		(end 327.289414 -254.097282)
		(width 0.0762)
		(layer "F.Cu")
		(net "M_A_CPU0_SA_CA<3>")
	)
	(segment
		(start 309.400956 -251.455174)
		(end 309.563262 -251.292868)
		(width 0.10668)
		(layer "F.Cu")
		(net "M_A_CPU0_SA_CA<2>")
	)
	(segment
		(start 310.12765 -251.857256)
		(end 310.12765 -251.70638)
		(width 0.10668)
		(layer "F.Cu")
		(net "M_A_CPU0_SA_CA<2>")
	)
	(segment
		(start 325.699374 -253.987554)
		(end 325.690992 -253.982728)
		(width 0.0762)
		(layer "F.Cu")
		(net "M_A_CPU0_SA_CA<2>")
	)
	(segment
		(start 327.004934 -253.982474)
		(end 327.004934 -253.982728)
		(width 0.0762)
		(layer "F.Cu")
		(net "M_A_CPU0_SA_CA<2>")
	)
	(segment
		(start 310.56072 -252.13945)
		(end 310.409844 -252.13945)
		(width 0.10668)
		(layer "F.Cu")
		(net "M_A_CPU0_SA_CA<2>")
	)
	(segment
		(start 322.078858 -254.21209)
		(end 320.38544 -252.518672)
		(width 0.10668)
		(layer "F.Cu")
		(net "M_A_CPU0_SA_CA<2>")
	)
	(segment
		(start 309.400956 -251.60605)
		(end 309.400956 -251.455174)
		(width 0.10668)
		(layer "F.Cu")
		(net "M_A_CPU0_SA_CA<2>")
	)
	(segment
		(start 310.247538 -252.301756)
		(end 310.096662 -252.301756)
		(width 0.10668)
		(layer "F.Cu")
		(net "M_A_CPU0_SA_CA<2>")
	)
	(segment
		(start 308.367938 -249.946668)
		(end 308.367938 -249.350276)
		(width 0.10668)
		(layer "F.Cu")
		(net "M_A_CPU0_SA_CA<2>")
	)
	(segment
		(start 323.963284 -254.06858)
		(end 323.819774 -254.21209)
		(width 0.10668)
		(layer "F.Cu")
		(net "M_A_CPU0_SA_CA<2>")
	)
	(segment
		(start 325.109078 -253.82601)
		(end 324.205854 -253.82601)
		(width 0.0762)
		(layer "F.Cu")
		(net "M_A_CPU0_SA_CA<2>")
	)
	(segment
		(start 309.563262 -251.141992)
		(end 308.367938 -249.946668)
		(width 0.10668)
		(layer "F.Cu")
		(net "M_A_CPU0_SA_CA<2>")
	)
	(segment
		(start 309.965344 -252.019562)
		(end 310.12765 -251.857256)
		(width 0.10668)
		(layer "F.Cu")
		(net "M_A_CPU0_SA_CA<2>")
	)
	(segment
		(start 309.965344 -252.170438)
		(end 309.965344 -252.019562)
		(width 0.10668)
		(layer "F.Cu")
		(net "M_A_CPU0_SA_CA<2>")
	)
	(segment
		(start 310.096662 -252.301756)
		(end 309.965344 -252.170438)
		(width 0.10668)
		(layer "F.Cu")
		(net "M_A_CPU0_SA_CA<2>")
	)
	(segment
		(start 324.205854 -253.82601)
		(end 323.963284 -254.06858)
		(width 0.0762)
		(layer "F.Cu")
		(net "M_A_CPU0_SA_CA<2>")
	)
	(segment
		(start 309.996332 -251.575062)
		(end 309.845456 -251.575062)
		(width 0.10668)
		(layer "F.Cu")
		(net "M_A_CPU0_SA_CA<2>")
	)
	(segment
		(start 310.12765 -251.70638)
		(end 309.996332 -251.575062)
		(width 0.10668)
		(layer "F.Cu")
		(net "M_A_CPU0_SA_CA<2>")
	)
	(segment
		(start 320.38544 -252.518672)
		(end 310.939942 -252.518672)
		(width 0.10668)
		(layer "F.Cu")
		(net "M_A_CPU0_SA_CA<2>")
	)
	(segment
		(start 323.819774 -254.21209)
		(end 322.078858 -254.21209)
		(width 0.10668)
		(layer "F.Cu")
		(net "M_A_CPU0_SA_CA<2>")
	)
	(segment
		(start 308.202838 -249.185176)
		(end 307.368194 -249.185176)
		(width 0.10668)
		(layer "F.Cu")
		(net "M_A_CPU0_SA_CA<2>")
	)
	(segment
		(start 309.563262 -251.292868)
		(end 309.563262 -251.141992)
		(width 0.10668)
		(layer "F.Cu")
		(net "M_A_CPU0_SA_CA<2>")
	)
	(segment
		(start 309.68315 -251.737368)
		(end 309.532274 -251.737368)
		(width 0.10668)
		(layer "F.Cu")
		(net "M_A_CPU0_SA_CA<2>")
	)
	(segment
		(start 310.939942 -252.518672)
		(end 310.56072 -252.13945)
		(width 0.10668)
		(layer "F.Cu")
		(net "M_A_CPU0_SA_CA<2>")
	)
	(segment
		(start 308.367938 -249.350276)
		(end 308.202838 -249.185176)
		(width 0.10668)
		(layer "F.Cu")
		(net "M_A_CPU0_SA_CA<2>")
	)
	(segment
		(start 309.845456 -251.575062)
		(end 309.68315 -251.737368)
		(width 0.10668)
		(layer "F.Cu")
		(net "M_A_CPU0_SA_CA<2>")
	)
	(segment
		(start 310.409844 -252.13945)
		(end 310.247538 -252.301756)
		(width 0.10668)
		(layer "F.Cu")
		(net "M_A_CPU0_SA_CA<2>")
	)
	(segment
		(start 309.532274 -251.737368)
		(end 309.400956 -251.60605)
		(width 0.10668)
		(layer "F.Cu")
		(net "M_A_CPU0_SA_CA<2>")
	)
	(arc
		(start 326.065134 -253.982728)
		(mid 325.882883 -254.033078)
		(end 325.699374 -253.987554)
		(width 0.0762)
		(layer "F.Cu")
		(net "M_A_CPU0_SA_CA<2>")
	)
	(arc
		(start 325.690992 -253.982728)
		(mid 325.410401 -253.865878)
		(end 325.109078 -253.82601)
		(width 0.0762)
		(layer "F.Cu")
		(net "M_A_CPU0_SA_CA<2>")
	)
	(arc
		(start 327.004934 -253.982728)
		(mid 326.81799 -254.032983)
		(end 326.631046 -253.982728)
		(width 0.0762)
		(layer "F.Cu")
		(net "M_A_CPU0_SA_CA<2>")
	)
	(arc
		(start 326.631046 -253.982728)
		(mid 326.34809 -253.906551)
		(end 326.065134 -253.982728)
		(width 0.0762)
		(layer "F.Cu")
		(net "M_A_CPU0_SA_CA<2>")
	)
	(arc
		(start 327.289414 -253.90602)
		(mid 327.142093 -253.925339)
		(end 327.004934 -253.982474)
		(width 0.0762)
		(layer "F.Cu")
		(net "M_A_CPU0_SA_CA<2>")
	)
	(arc
		(start 327.758044 -253.660148)
		(mid 327.554028 -253.840842)
		(end 327.289414 -253.90602)
		(width 0.0762)
		(layer "F.Cu")
		(net "M_A_CPU0_SA_CA<2>")
	)
	(segment
		(start 308.259226 -248.75998)
		(end 306.070508 -248.75998)
		(width 0.101346)
		(layer "F.Cu")
		(net "M_A_CPU0_SA_CA<1>")
	)
	(segment
		(start 324.022974 -253.52629)
		(end 323.930264 -253.619)
		(width 0.0762)
		(layer "F.Cu")
		(net "M_A_CPU0_SA_CA<1>")
	)
	(segment
		(start 306.070508 -248.75998)
		(end 305.645566 -248.335038)
		(width 0.101346)
		(layer "F.Cu")
		(net "M_A_CPU0_SA_CA<1>")
	)
	(segment
		(start 308.708298 -249.805444)
		(end 308.708298 -249.209052)
		(width 0.10668)
		(layer "F.Cu")
		(net "M_A_CPU0_SA_CA<1>")
	)
	(segment
		(start 305.645566 -248.335038)
		(end 303.268126 -248.335038)
		(width 0.101346)
		(layer "F.Cu")
		(net "M_A_CPU0_SA_CA<1>")
	)
	(segment
		(start 323.930264 -253.619)
		(end 323.677534 -253.87173)
		(width 0.10668)
		(layer "F.Cu")
		(net "M_A_CPU0_SA_CA<1>")
	)
	(segment
		(start 308.453536 -248.95429)
		(end 308.259226 -248.75998)
		(width 0.101346)
		(layer "F.Cu")
		(net "M_A_CPU0_SA_CA<1>")
	)
	(segment
		(start 325.877936 -253.660148)
		(end 325.9709 -253.500128)
		(width 0.0762)
		(layer "F.Cu")
		(net "M_A_CPU0_SA_CA<1>")
	)
	(segment
		(start 311.081166 -252.178312)
		(end 308.708298 -249.805444)
		(width 0.10668)
		(layer "F.Cu")
		(net "M_A_CPU0_SA_CA<1>")
	)
	(segment
		(start 324.991222 -253.52629)
		(end 324.022974 -253.52629)
		(width 0.0762)
		(layer "F.Cu")
		(net "M_A_CPU0_SA_CA<1>")
	)
	(segment
		(start 323.677534 -253.87173)
		(end 322.220082 -253.87173)
		(width 0.10668)
		(layer "F.Cu")
		(net "M_A_CPU0_SA_CA<1>")
	)
	(segment
		(start 325.699374 -253.332742)
		(end 325.690992 -253.337568)
		(width 0.0762)
		(layer "F.Cu")
		(net "M_A_CPU0_SA_CA<1>")
	)
	(segment
		(start 320.526664 -252.178312)
		(end 311.081166 -252.178312)
		(width 0.10668)
		(layer "F.Cu")
		(net "M_A_CPU0_SA_CA<1>")
	)
	(segment
		(start 308.708298 -249.209052)
		(end 308.453536 -248.95429)
		(width 0.10668)
		(layer "F.Cu")
		(net "M_A_CPU0_SA_CA<1>")
	)
	(segment
		(start 322.220082 -253.87173)
		(end 320.526664 -252.178312)
		(width 0.10668)
		(layer "F.Cu")
		(net "M_A_CPU0_SA_CA<1>")
	)
	(arc
		(start 325.690992 -253.337568)
		(mid 325.353609 -253.478286)
		(end 324.991222 -253.52629)
		(width 0.0762)
		(layer "F.Cu")
		(net "M_A_CPU0_SA_CA<1>")
	)
	(arc
		(start 325.9709 -253.500128)
		(mid 325.97074 -253.353567)
		(end 325.839074 -253.289308)
		(width 0.0762)
		(layer "F.Cu")
		(net "M_A_CPU0_SA_CA<1>")
	)
	(arc
		(start 325.839074 -253.289308)
		(mid 325.767066 -253.30409)
		(end 325.699374 -253.332742)
		(width 0.0762)
		(layer "F.Cu")
		(net "M_A_CPU0_SA_CA<1>")
	)
	(segment
		(start 308.610508 -248.626122)
		(end 308.581806 -248.59742)
		(width 0.101346)
		(layer "F.Cu")
		(net "M_A_CPU0_SA_CA<0>")
	)
	(segment
		(start 325.385938 -253.22911)
		(end 323.801994 -253.22911)
		(width 0.0762)
		(layer "F.Cu")
		(net "M_A_CPU0_SA_CA<0>")
	)
	(segment
		(start 322.103242 -252.571504)
		(end 321.952366 -252.57125)
		(width 0.10668)
		(layer "F.Cu")
		(net "M_A_CPU0_SA_CA<0>")
	)
	(segment
		(start 322.034154 -253.204218)
		(end 322.034408 -253.05385)
		(width 0.10668)
		(layer "F.Cu")
		(net "M_A_CPU0_SA_CA<0>")
	)
	(segment
		(start 309.048658 -249.064272)
		(end 308.610508 -248.626122)
		(width 0.10668)
		(layer "F.Cu")
		(net "M_A_CPU0_SA_CA<0>")
	)
	(segment
		(start 323.350636 -252.696472)
		(end 323.243956 -252.589792)
		(width 0.10668)
		(layer "F.Cu")
		(net "M_A_CPU0_SA_CA<0>")
	)
	(segment
		(start 321.752214 -252.771402)
		(end 321.601338 -252.771402)
		(width 0.10668)
		(layer "F.Cu")
		(net "M_A_CPU0_SA_CA<0>")
	)
	(segment
		(start 311.222644 -251.837952)
		(end 309.048658 -249.663966)
		(width 0.10668)
		(layer "F.Cu")
		(net "M_A_CPU0_SA_CA<0>")
	)
	(segment
		(start 321.601338 -252.771402)
		(end 320.667888 -251.837952)
		(width 0.10668)
		(layer "F.Cu")
		(net "M_A_CPU0_SA_CA<0>")
	)
	(segment
		(start 322.23456 -252.853698)
		(end 322.23456 -252.702822)
		(width 0.10668)
		(layer "F.Cu")
		(net "M_A_CPU0_SA_CA<0>")
	)
	(segment
		(start 323.058282 -252.589792)
		(end 322.951602 -252.696472)
		(width 0.10668)
		(layer "F.Cu")
		(net "M_A_CPU0_SA_CA<0>")
	)
	(segment
		(start 321.952366 -252.57125)
		(end 321.752214 -252.771402)
		(width 0.10668)
		(layer "F.Cu")
		(net "M_A_CPU0_SA_CA<0>")
	)
	(segment
		(start 308.581806 -248.59742)
		(end 308.345078 -248.360692)
		(width 0.10668)
		(layer "F.Cu")
		(net "M_A_CPU0_SA_CA<0>")
	)
	(segment
		(start 308.345078 -247.985534)
		(end 307.844698 -247.485154)
		(width 0.10668)
		(layer "F.Cu")
		(net "M_A_CPU0_SA_CA<0>")
	)
	(segment
		(start 323.243956 -252.589792)
		(end 323.058282 -252.589792)
		(width 0.10668)
		(layer "F.Cu")
		(net "M_A_CPU0_SA_CA<0>")
	)
	(segment
		(start 320.667888 -251.837952)
		(end 311.222644 -251.837952)
		(width 0.10668)
		(layer "F.Cu")
		(net "M_A_CPU0_SA_CA<0>")
	)
	(segment
		(start 322.951602 -252.696472)
		(end 322.951602 -253.24181)
		(width 0.10668)
		(layer "F.Cu")
		(net "M_A_CPU0_SA_CA<0>")
	)
	(segment
		(start 322.844922 -253.34849)
		(end 322.178426 -253.34849)
		(width 0.10668)
		(layer "F.Cu")
		(net "M_A_CPU0_SA_CA<0>")
	)
	(segment
		(start 308.345078 -248.360692)
		(end 308.345078 -247.985534)
		(width 0.10668)
		(layer "F.Cu")
		(net "M_A_CPU0_SA_CA<0>")
	)
	(segment
		(start 323.682614 -253.34849)
		(end 323.457316 -253.34849)
		(width 0.10668)
		(layer "F.Cu")
		(net "M_A_CPU0_SA_CA<0>")
	)
	(segment
		(start 309.048658 -249.663966)
		(end 309.048658 -249.064272)
		(width 0.10668)
		(layer "F.Cu")
		(net "M_A_CPU0_SA_CA<0>")
	)
	(segment
		(start 322.178426 -253.34849)
		(end 322.034154 -253.204218)
		(width 0.10668)
		(layer "F.Cu")
		(net "M_A_CPU0_SA_CA<0>")
	)
	(segment
		(start 322.23456 -252.702822)
		(end 322.103242 -252.571504)
		(width 0.10668)
		(layer "F.Cu")
		(net "M_A_CPU0_SA_CA<0>")
	)
	(segment
		(start 323.350636 -253.24181)
		(end 323.350636 -252.696472)
		(width 0.10668)
		(layer "F.Cu")
		(net "M_A_CPU0_SA_CA<0>")
	)
	(segment
		(start 322.034408 -253.05385)
		(end 322.23456 -252.853698)
		(width 0.10668)
		(layer "F.Cu")
		(net "M_A_CPU0_SA_CA<0>")
	)
	(segment
		(start 307.844698 -247.485154)
		(end 307.368194 -247.485154)
		(width 0.10668)
		(layer "F.Cu")
		(net "M_A_CPU0_SA_CA<0>")
	)
	(segment
		(start 323.801994 -253.22911)
		(end 323.682614 -253.34849)
		(width 0.10668)
		(layer "F.Cu")
		(net "M_A_CPU0_SA_CA<0>")
	)
	(segment
		(start 323.457316 -253.34849)
		(end 323.350636 -253.24181)
		(width 0.10668)
		(layer "F.Cu")
		(net "M_A_CPU0_SA_CA<0>")
	)
	(segment
		(start 322.951602 -253.24181)
		(end 322.844922 -253.34849)
		(width 0.10668)
		(layer "F.Cu")
		(net "M_A_CPU0_SA_CA<0>")
	)
	(arc
		(start 325.830438 -253.0983)
		(mid 325.708582 -253.122456)
		(end 325.59498 -253.172722)
		(width 0.0762)
		(layer "F.Cu")
		(net "M_A_CPU0_SA_CA<0>")
	)
	(arc
		(start 326.34809 -252.850142)
		(mid 326.111962 -253.021577)
		(end 325.830438 -253.0983)
		(width 0.0762)
		(layer "F.Cu")
		(net "M_A_CPU0_SA_CA<0>")
	)
	(arc
		(start 325.59498 -253.172722)
		(mid 325.494197 -253.214779)
		(end 325.385938 -253.22911)
		(width 0.0762)
		(layer "F.Cu")
		(net "M_A_CPU0_SA_CA<0>")
	)
	(segment
		(start 311.681368 -250.514612)
		(end 310.303418 -249.136662)
		(width 0.10668)
		(layer "F.Cu")
		(net "M_A_CPU0_RESET_N")
	)
	(segment
		(start 310.303418 -248.543572)
		(end 309.599838 -247.839992)
		(width 0.10668)
		(layer "F.Cu")
		(net "M_A_CPU0_RESET_N")
	)
	(segment
		(start 325.52767 -250.77039)
		(end 322.06057 -250.77039)
		(width 0.10668)
		(layer "F.Cu")
		(net "M_A_CPU0_RESET_N")
	)
	(segment
		(start 309.599838 -247.839992)
		(end 309.599838 -246.6848)
		(width 0.10668)
		(layer "F.Cu")
		(net "M_A_CPU0_RESET_N")
	)
	(segment
		(start 322.06057 -250.77039)
		(end 321.804792 -250.514612)
		(width 0.10668)
		(layer "F.Cu")
		(net "M_A_CPU0_RESET_N")
	)
	(segment
		(start 304.63109 -244.934994)
		(end 303.268126 -244.934994)
		(width 0.101346)
		(layer "F.Cu")
		(net "M_A_CPU0_RESET_N")
	)
	(segment
		(start 308.274974 -245.359936)
		(end 305.056032 -245.359936)
		(width 0.101346)
		(layer "F.Cu")
		(net "M_A_CPU0_RESET_N")
	)
	(segment
		(start 309.599838 -246.6848)
		(end 308.610508 -245.69547)
		(width 0.10668)
		(layer "F.Cu")
		(net "M_A_CPU0_RESET_N")
	)
	(segment
		(start 310.303418 -249.136662)
		(end 310.303418 -248.543572)
		(width 0.10668)
		(layer "F.Cu")
		(net "M_A_CPU0_RESET_N")
	)
	(segment
		(start 308.610508 -245.69547)
		(end 308.274974 -245.359936)
		(width 0.101346)
		(layer "F.Cu")
		(net "M_A_CPU0_RESET_N")
	)
	(segment
		(start 321.804792 -250.514612)
		(end 311.681368 -250.514612)
		(width 0.10668)
		(layer "F.Cu")
		(net "M_A_CPU0_RESET_N")
	)
	(segment
		(start 305.056032 -245.359936)
		(end 304.63109 -244.934994)
		(width 0.101346)
		(layer "F.Cu")
		(net "M_A_CPU0_RESET_N")
	)
	(segment
		(start 325.877936 -250.420124)
		(end 325.52767 -250.77039)
		(width 0.10668)
		(layer "F.Cu")
		(net "M_A_CPU0_RESET_N")
	)
	(segment
		(start 306.528978 -255.93421)
		(end 305.623214 -255.028446)
		(width 0.14732)
		(layer "F.Cu")
		(net "M_A_CPU0_CLK_DP<0>")
	)
	(segment
		(start 319.4812 -254.697992)
		(end 316.032134 -254.697992)
		(width 0.14732)
		(layer "F.Cu")
		(net "M_A_CPU0_CLK_DP<0>")
	)
	(segment
		(start 305.623214 -254.352806)
		(end 304.960274 -253.689866)
		(width 0.14732)
		(layer "F.Cu")
		(net "M_A_CPU0_CLK_DP<0>")
	)
	(segment
		(start 325.13651 -256.467102)
		(end 324.645782 -256.95783)
		(width 0.0762)
		(layer "F.Cu")
		(net "M_A_CPU0_CLK_DP<0>")
	)
	(segment
		(start 322.3006 -257.517392)
		(end 319.4812 -254.697992)
		(width 0.14732)
		(layer "F.Cu")
		(net "M_A_CPU0_CLK_DP<0>")
	)
	(segment
		(start 324.53961 -256.95783)
		(end 324.526148 -256.971292)
		(width 0.0762)
		(layer "F.Cu")
		(net "M_A_CPU0_CLK_DP<0>")
	)
	(segment
		(start 303.769268 -253.435104)
		(end 303.268126 -253.435104)
		(width 0.14732)
		(layer "F.Cu")
		(net "M_A_CPU0_CLK_DP<0>")
	)
	(segment
		(start 314.795916 -255.93421)
		(end 306.528978 -255.93421)
		(width 0.14732)
		(layer "F.Cu")
		(net "M_A_CPU0_CLK_DP<0>")
	)
	(segment
		(start 324.645782 -256.95783)
		(end 324.53961 -256.95783)
		(width 0.0762)
		(layer "F.Cu")
		(net "M_A_CPU0_CLK_DP<0>")
	)
	(segment
		(start 324.526148 -256.971292)
		(end 323.980048 -257.517392)
		(width 0.14732)
		(layer "F.Cu")
		(net "M_A_CPU0_CLK_DP<0>")
	)
	(segment
		(start 305.623214 -255.028446)
		(end 305.623214 -254.352806)
		(width 0.14732)
		(layer "F.Cu")
		(net "M_A_CPU0_CLK_DP<0>")
	)
	(segment
		(start 323.980048 -257.517392)
		(end 322.3006 -257.517392)
		(width 0.14732)
		(layer "F.Cu")
		(net "M_A_CPU0_CLK_DP<0>")
	)
	(segment
		(start 316.032134 -254.697992)
		(end 314.795916 -255.93421)
		(width 0.14732)
		(layer "F.Cu")
		(net "M_A_CPU0_CLK_DP<0>")
	)
	(segment
		(start 325.316088 -256.467102)
		(end 325.13651 -256.467102)
		(width 0.0762)
		(layer "F.Cu")
		(net "M_A_CPU0_CLK_DP<0>")
	)
	(segment
		(start 304.960274 -253.689866)
		(end 304.02403 -253.689866)
		(width 0.14732)
		(layer "F.Cu")
		(net "M_A_CPU0_CLK_DP<0>")
	)
	(segment
		(start 304.02403 -253.689866)
		(end 303.769268 -253.435104)
		(width 0.14732)
		(layer "F.Cu")
		(net "M_A_CPU0_CLK_DP<0>")
	)
	(arc
		(start 325.59498 -256.412746)
		(mid 325.51974 -256.446059)
		(end 325.439024 -256.462022)
		(width 0.0762)
		(layer "F.Cu")
		(net "M_A_CPU0_CLK_DP<0>")
	)
	(arc
		(start 326.34809 -256.090166)
		(mid 326.111962 -256.261601)
		(end 325.830438 -256.338324)
		(width 0.0762)
		(layer "F.Cu")
		(net "M_A_CPU0_CLK_DP<0>")
	)
	(arc
		(start 325.439024 -256.462022)
		(mid 325.377608 -256.465827)
		(end 325.316088 -256.467102)
		(width 0.0762)
		(layer "F.Cu")
		(net "M_A_CPU0_CLK_DP<0>")
	)
	(arc
		(start 325.830438 -256.338324)
		(mid 325.708582 -256.36248)
		(end 325.59498 -256.412746)
		(width 0.0762)
		(layer "F.Cu")
		(net "M_A_CPU0_CLK_DP<0>")
	)
	(segment
		(start 325.45528 -256.652014)
		(end 325.454518 -256.65303)
		(width 0.0762)
		(layer "F.Cu")
		(net "M_A_CPU0_CLK_DN<0>")
	)
	(segment
		(start 325.699374 -256.572766)
		(end 325.690992 -256.577592)
		(width 0.0762)
		(layer "F.Cu")
		(net "M_A_CPU0_CLK_DN<0>")
	)
	(segment
		(start 325.215504 -256.657602)
		(end 324.780402 -257.092704)
		(width 0.0762)
		(layer "F.Cu")
		(net "M_A_CPU0_CLK_DN<0>")
	)
	(segment
		(start 325.314056 -256.658618)
		(end 325.21652 -256.658618)
		(width 0.0762)
		(layer "F.Cu")
		(net "M_A_CPU0_CLK_DN<0>")
	)
	(segment
		(start 306.387754 -256.27457)
		(end 305.282854 -255.16967)
		(width 0.14732)
		(layer "F.Cu")
		(net "M_A_CPU0_CLK_DN<0>")
	)
	(segment
		(start 305.282854 -254.49403)
		(end 304.81905 -254.030226)
		(width 0.14732)
		(layer "F.Cu")
		(net "M_A_CPU0_CLK_DN<0>")
	)
	(segment
		(start 324.780402 -257.092704)
		(end 324.780402 -257.198622)
		(width 0.0762)
		(layer "F.Cu")
		(net "M_A_CPU0_CLK_DN<0>")
	)
	(segment
		(start 319.339976 -255.038352)
		(end 316.173358 -255.038352)
		(width 0.14732)
		(layer "F.Cu")
		(net "M_A_CPU0_CLK_DN<0>")
	)
	(segment
		(start 325.877936 -256.900172)
		(end 325.9709 -256.740152)
		(width 0.0762)
		(layer "F.Cu")
		(net "M_A_CPU0_CLK_DN<0>")
	)
	(segment
		(start 325.21652 -256.658618)
		(end 325.215504 -256.657602)
		(width 0.0762)
		(layer "F.Cu")
		(net "M_A_CPU0_CLK_DN<0>")
	)
	(segment
		(start 305.282854 -255.16967)
		(end 305.282854 -254.49403)
		(width 0.14732)
		(layer "F.Cu")
		(net "M_A_CPU0_CLK_DN<0>")
	)
	(segment
		(start 303.769776 -254.284988)
		(end 303.268126 -254.284988)
		(width 0.14732)
		(layer "F.Cu")
		(net "M_A_CPU0_CLK_DN<0>")
	)
	(segment
		(start 324.121272 -257.857752)
		(end 322.159376 -257.857752)
		(width 0.14732)
		(layer "F.Cu")
		(net "M_A_CPU0_CLK_DN<0>")
	)
	(segment
		(start 324.76694 -257.212084)
		(end 324.121272 -257.857752)
		(width 0.14732)
		(layer "F.Cu")
		(net "M_A_CPU0_CLK_DN<0>")
	)
	(segment
		(start 304.81905 -254.030226)
		(end 304.024538 -254.030226)
		(width 0.14732)
		(layer "F.Cu")
		(net "M_A_CPU0_CLK_DN<0>")
	)
	(segment
		(start 304.024538 -254.030226)
		(end 303.769776 -254.284988)
		(width 0.14732)
		(layer "F.Cu")
		(net "M_A_CPU0_CLK_DN<0>")
	)
	(segment
		(start 316.173358 -255.038352)
		(end 314.93714 -256.27457)
		(width 0.14732)
		(layer "F.Cu")
		(net "M_A_CPU0_CLK_DN<0>")
	)
	(segment
		(start 314.93714 -256.27457)
		(end 306.387754 -256.27457)
		(width 0.14732)
		(layer "F.Cu")
		(net "M_A_CPU0_CLK_DN<0>")
	)
	(segment
		(start 324.780402 -257.198622)
		(end 324.76694 -257.212084)
		(width 0.0762)
		(layer "F.Cu")
		(net "M_A_CPU0_CLK_DN<0>")
	)
	(segment
		(start 322.159376 -257.857752)
		(end 319.339976 -255.038352)
		(width 0.14732)
		(layer "F.Cu")
		(net "M_A_CPU0_CLK_DN<0>")
	)
	(arc
		(start 325.454518 -256.65303)
		(mid 325.384343 -256.657224)
		(end 325.314056 -256.658618)
		(width 0.0762)
		(layer "F.Cu")
		(net "M_A_CPU0_CLK_DN<0>")
	)
	(arc
		(start 325.9709 -256.740152)
		(mid 325.97074 -256.593591)
		(end 325.839074 -256.529332)
		(width 0.0762)
		(layer "F.Cu")
		(net "M_A_CPU0_CLK_DN<0>")
	)
	(arc
		(start 325.839074 -256.529332)
		(mid 325.767066 -256.544114)
		(end 325.699374 -256.572766)
		(width 0.0762)
		(layer "F.Cu")
		(net "M_A_CPU0_CLK_DN<0>")
	)
	(arc
		(start 325.690992 -256.577592)
		(mid 325.577268 -256.627893)
		(end 325.45528 -256.652014)
		(width 0.0762)
		(layer "F.Cu")
		(net "M_A_CPU0_CLK_DN<0>")
	)
	(segment
		(start 323.976492 -250.359672)
		(end 322.259198 -250.359672)
		(width 0.10668)
		(layer "F.Cu")
		(net "M_A_CPU0_ALERT_R_N")
	)
	(segment
		(start 311.822592 -250.174252)
		(end 310.643778 -248.995438)
		(width 0.10668)
		(layer "F.Cu")
		(net "M_A_CPU0_ALERT_R_N")
	)
	(segment
		(start 306.070508 -244.42039)
		(end 305.735228 -244.08511)
		(width 0.10668)
		(layer "F.Cu")
		(net "M_A_CPU0_ALERT_R_N")
	)
	(segment
		(start 309.940198 -246.504206)
		(end 308.388258 -244.952266)
		(width 0.10668)
		(layer "F.Cu")
		(net "M_A_CPU0_ALERT_R_N")
	)
	(segment
		(start 308.388258 -244.616732)
		(end 308.281578 -244.510052)
		(width 0.101346)
		(layer "F.Cu")
		(net "M_A_CPU0_ALERT_R_N")
	)
	(segment
		(start 322.073778 -250.174252)
		(end 311.822592 -250.174252)
		(width 0.10668)
		(layer "F.Cu")
		(net "M_A_CPU0_ALERT_R_N")
	)
	(segment
		(start 325.64705 -249.910092)
		(end 325.398638 -250.05411)
		(width 0.0762)
		(layer "F.Cu")
		(net "M_A_CPU0_ALERT_R_N")
	)
	(segment
		(start 310.643778 -248.995438)
		(end 310.643778 -248.402348)
		(width 0.10668)
		(layer "F.Cu")
		(net "M_A_CPU0_ALERT_R_N")
	)
	(segment
		(start 308.281578 -244.510052)
		(end 306.16017 -244.510052)
		(width 0.101346)
		(layer "F.Cu")
		(net "M_A_CPU0_ALERT_R_N")
	)
	(segment
		(start 308.388258 -244.677692)
		(end 308.388258 -244.616732)
		(width 0.101346)
		(layer "F.Cu")
		(net "M_A_CPU0_ALERT_R_N")
	)
	(segment
		(start 324.736714 -250.23191)
		(end 324.104508 -250.231656)
		(width 0.10668)
		(layer "F.Cu")
		(net "M_A_CPU0_ALERT_R_N")
	)
	(segment
		(start 308.388258 -244.952266)
		(end 308.388258 -244.677692)
		(width 0.10668)
		(layer "F.Cu")
		(net "M_A_CPU0_ALERT_R_N")
	)
	(segment
		(start 324.104508 -250.231656)
		(end 323.976492 -250.359672)
		(width 0.10668)
		(layer "F.Cu")
		(net "M_A_CPU0_ALERT_R_N")
	)
	(segment
		(start 309.940198 -247.698768)
		(end 309.940198 -246.504206)
		(width 0.10668)
		(layer "F.Cu")
		(net "M_A_CPU0_ALERT_R_N")
	)
	(segment
		(start 310.643778 -248.402348)
		(end 309.940198 -247.698768)
		(width 0.10668)
		(layer "F.Cu")
		(net "M_A_CPU0_ALERT_R_N")
	)
	(segment
		(start 306.16017 -244.510052)
		(end 306.070508 -244.42039)
		(width 0.101346)
		(layer "F.Cu")
		(net "M_A_CPU0_ALERT_R_N")
	)
	(segment
		(start 322.259198 -250.359672)
		(end 322.073778 -250.174252)
		(width 0.10668)
		(layer "F.Cu")
		(net "M_A_CPU0_ALERT_R_N")
	)
	(via
		(at 305.735228 -244.08511)
		(size 0.4826)
		(drill 0.254)
		(layers "F.Cu" "B.Cu")
		(net "M_A_CPU0_ALERT_R_N")
	)
	(arc
		(start 325.830438 -249.858276)
		(mid 325.773252 -249.866052)
		(end 325.717154 -249.879612)
		(width 0.0762)
		(layer "F.Cu")
		(net "M_A_CPU0_ALERT_R_N")
	)
	(arc
		(start 325.717154 -249.879612)
		(mid 325.681201 -249.892779)
		(end 325.64705 -249.910092)
		(width 0.0762)
		(layer "F.Cu")
		(net "M_A_CPU0_ALERT_R_N")
	)
	(arc
		(start 326.34809 -249.610118)
		(mid 326.111962 -249.781553)
		(end 325.830438 -249.858276)
		(width 0.0762)
		(layer "F.Cu")
		(net "M_A_CPU0_ALERT_R_N")
	)
	(arc
		(start 325.398638 -250.05411)
		(mid 325.079413 -250.186697)
		(end 324.736714 -250.23191)
		(width 0.0762)
		(layer "F.Cu")
		(net "M_A_CPU0_ALERT_R_N")
	)
	(via
		(at 307.368194 -244.08511)
		(size 0.4826)
		(drill 0.254)
		(layers "F.Cu" "B.Cu")
		(net "M_A_CPU0_ALERT_N")
	)
	(segment
		(start 306.535328 -244.08511)
		(end 307.368194 -244.08511)
		(width 0.10668)
		(layer "B.Cu")
		(net "M_A_CPU0_ALERT_N")
	)
	(segment
		(start 397.517366 -137.335768)
		(end 400.102324 -137.335768)
		(width 0.10668)
		(layer "F.Cu")
		(net "MB0_P12V_STBY_PWRGD")
	)
	(segment
		(start 400.102324 -137.335768)
		(end 400.98726 -138.220704)
		(width 0.10668)
		(layer "F.Cu")
		(net "MB0_P12V_STBY_PWRGD")
	)
	(segment
		(start 261.20852 -187.1726)
		(end 261.20852 -185.255154)
		(width 0.10668)
		(layer "F.Cu")
		(net "MB0_P12V_STBY_PWRGD")
	)
	(segment
		(start 193.779902 -381.6604)
		(end 192.573402 -381.6604)
		(width 0.10668)
		(layer "F.Cu")
		(net "MB0_P12V_STBY_PWRGD")
	)
	(segment
		(start 180.79593 -405.39162)
		(end 181.18074 -404.462234)
		(width 0.10668)
		(layer "F.Cu")
		(net "MB0_P12V_STBY_PWRGD")
	)
	(segment
		(start 400.98726 -138.220704)
		(end 408.2415 -138.220704)
		(width 0.10668)
		(layer "F.Cu")
		(net "MB0_P12V_STBY_PWRGD")
	)
	(segment
		(start 261.688834 -195.35902)
		(end 262.298688 -194.749166)
		(width 0.10668)
		(layer "F.Cu")
		(net "MB0_P12V_STBY_PWRGD")
	)
	(segment
		(start 261.20852 -185.255154)
		(end 262.26135 -184.202324)
		(width 0.10668)
		(layer "F.Cu")
		(net "MB0_P12V_STBY_PWRGD")
	)
	(segment
		(start 179.347368 -407.543)
		(end 180.183028 -406.70734)
		(width 0.10668)
		(layer "F.Cu")
		(net "MB0_P12V_STBY_PWRGD")
	)
	(segment
		(start 261.688834 -336.447638)
		(end 261.688834 -195.35902)
		(width 0.10668)
		(layer "F.Cu")
		(net "MB0_P12V_STBY_PWRGD")
	)
	(segment
		(start 180.183028 -405.74087)
		(end 180.278024 -405.645874)
		(width 0.10668)
		(layer "F.Cu")
		(net "MB0_P12V_STBY_PWRGD")
	)
	(segment
		(start 180.278024 -405.645874)
		(end 180.541676 -405.645874)
		(width 0.10668)
		(layer "F.Cu")
		(net "MB0_P12V_STBY_PWRGD")
	)
	(segment
		(start 181.18074 -404.462234)
		(end 181.485794 -404.15718)
		(width 0.10668)
		(layer "F.Cu")
		(net "MB0_P12V_STBY_PWRGD")
	)
	(segment
		(start 179.08905 -408.559)
		(end 179.08905 -407.543)
		(width 0.10668)
		(layer "F.Cu")
		(net "MB0_P12V_STBY_PWRGD")
	)
	(segment
		(start 228.805232 -365.200692)
		(end 231.527858 -362.478066)
		(width 0.10668)
		(layer "F.Cu")
		(net "MB0_P12V_STBY_PWRGD")
	)
	(segment
		(start 180.183028 -406.70734)
		(end 180.183028 -405.74087)
		(width 0.10668)
		(layer "F.Cu")
		(net "MB0_P12V_STBY_PWRGD")
	)
	(segment
		(start 395.409674 -125.36551)
		(end 395.409674 -135.228076)
		(width 0.10668)
		(layer "F.Cu")
		(net "MB0_P12V_STBY_PWRGD")
	)
	(segment
		(start 394.501116 -124.456952)
		(end 395.409674 -125.36551)
		(width 0.10668)
		(layer "F.Cu")
		(net "MB0_P12V_STBY_PWRGD")
	)
	(segment
		(start 408.2415 -138.220704)
		(end 408.608022 -137.854182)
		(width 0.10668)
		(layer "F.Cu")
		(net "MB0_P12V_STBY_PWRGD")
	)
	(segment
		(start 262.298688 -194.749166)
		(end 262.298688 -188.262768)
		(width 0.10668)
		(layer "F.Cu")
		(net "MB0_P12V_STBY_PWRGD")
	)
	(segment
		(start 408.608022 -137.854182)
		(end 409.078176 -137.854182)
		(width 0.10668)
		(layer "F.Cu")
		(net "MB0_P12V_STBY_PWRGD")
	)
	(segment
		(start 260.096 -338.040472)
		(end 261.688834 -336.447638)
		(width 0.10668)
		(layer "F.Cu")
		(net "MB0_P12V_STBY_PWRGD")
	)
	(segment
		(start 180.541676 -405.645874)
		(end 180.79593 -405.39162)
		(width 0.10668)
		(layer "F.Cu")
		(net "MB0_P12V_STBY_PWRGD")
	)
	(segment
		(start 260.096 -345.309698)
		(end 260.096 -338.040472)
		(width 0.10668)
		(layer "F.Cu")
		(net "MB0_P12V_STBY_PWRGD")
	)
	(segment
		(start 242.927632 -362.478066)
		(end 260.096 -345.309698)
		(width 0.10668)
		(layer "F.Cu")
		(net "MB0_P12V_STBY_PWRGD")
	)
	(segment
		(start 395.409674 -135.228076)
		(end 397.517366 -137.335768)
		(width 0.10668)
		(layer "F.Cu")
		(net "MB0_P12V_STBY_PWRGD")
	)
	(segment
		(start 181.485794 -404.15718)
		(end 182.578502 -404.15718)
		(width 0.10668)
		(layer "F.Cu")
		(net "MB0_P12V_STBY_PWRGD")
	)
	(segment
		(start 262.26135 -184.202324)
		(end 262.26135 -149.970744)
		(width 0.10668)
		(layer "F.Cu")
		(net "MB0_P12V_STBY_PWRGD")
	)
	(segment
		(start 231.527858 -362.478066)
		(end 242.927632 -362.478066)
		(width 0.10668)
		(layer "F.Cu")
		(net "MB0_P12V_STBY_PWRGD")
	)
	(segment
		(start 394.501116 -121.682002)
		(end 394.501116 -124.456952)
		(width 0.10668)
		(layer "F.Cu")
		(net "MB0_P12V_STBY_PWRGD")
	)
	(segment
		(start 262.26135 -149.970744)
		(end 261.475474 -149.184868)
		(width 0.10668)
		(layer "F.Cu")
		(net "MB0_P12V_STBY_PWRGD")
	)
	(segment
		(start 179.08905 -407.543)
		(end 179.347368 -407.543)
		(width 0.10668)
		(layer "F.Cu")
		(net "MB0_P12V_STBY_PWRGD")
	)
	(segment
		(start 213.8426 -138.524488)
		(end 214.181182 -138.524488)
		(width 0.10668)
		(layer "F.Cu")
		(net "MB0_P12V_STBY_PWRGD")
	)
	(segment
		(start 214.181182 -138.524488)
		(end 214.564214 -138.141456)
		(width 0.10668)
		(layer "F.Cu")
		(net "MB0_P12V_STBY_PWRGD")
	)
	(segment
		(start 262.298688 -188.262768)
		(end 261.20852 -187.1726)
		(width 0.10668)
		(layer "F.Cu")
		(net "MB0_P12V_STBY_PWRGD")
	)
	(via
		(at 261.475474 -149.184868)
		(size 0.508)
		(drill 0.254)
		(layers "F.Cu" "B.Cu")
		(net "MB0_P12V_STBY_PWRGD")
	)
	(via
		(at 228.805232 -365.200692)
		(size 0.508)
		(drill 0.254)
		(layers "F.Cu" "B.Cu")
		(net "MB0_P12V_STBY_PWRGD")
	)
	(via
		(at 222.92056 -80.210406)
		(size 0.508)
		(drill 0.254)
		(layers "F.Cu" "B.Cu")
		(net "MB0_P12V_STBY_PWRGD")
	)
	(via
		(at 313.436 -97.917)
		(size 0.508)
		(drill 0.254)
		(layers "F.Cu" "B.Cu")
		(net "MB0_P12V_STBY_PWRGD")
	)
	(via
		(at 225.646488 -139.069572)
		(size 0.508)
		(drill 0.254)
		(layers "F.Cu" "B.Cu")
		(net "MB0_P12V_STBY_PWRGD")
	)
	(via
		(at 310.411876 -75.454764)
		(size 0.508)
		(drill 0.254)
		(layers "F.Cu" "B.Cu")
		(net "MB0_P12V_STBY_PWRGD")
	)
	(via
		(at 214.564214 -138.141456)
		(size 0.508)
		(drill 0.254)
		(layers "F.Cu" "B.Cu")
		(net "MB0_P12V_STBY_PWRGD")
	)
	(via
		(at 180.183028 -406.70734)
		(size 0.762)
		(drill 0.254)
		(layers "F.Cu" "B.Cu")
		(net "MB0_P12V_STBY_PWRGD")
	)
	(via
		(at 394.501116 -121.682002)
		(size 0.508)
		(drill 0.254)
		(layers "F.Cu" "B.Cu")
		(net "MB0_P12V_STBY_PWRGD")
	)
	(via
		(at 192.573402 -381.6604)
		(size 0.508)
		(drill 0.254)
		(layers "F.Cu" "B.Cu")
		(net "MB0_P12V_STBY_PWRGD")
	)
	(segment
		(start 310.411876 -76.089764)
		(end 310.411876 -75.454764)
		(width 0.10668)
		(layer "B.Cu")
		(net "MB0_P12V_STBY_PWRGD")
	)
	(segment
		(start 311.427876 -76.089764)
		(end 310.411876 -76.089764)
		(width 0.10668)
		(layer "B.Cu")
		(net "MB0_P12V_STBY_PWRGD")
	)
	(segment
		(start 308.334664 -75.454764)
		(end 302.27524 -81.514188)
		(width 0.11684)
		(layer "In2.Cu")
		(net "MB0_P12V_STBY_PWRGD")
	)
	(segment
		(start 285.730442 -81.514188)
		(end 280.539698 -76.323444)
		(width 0.11684)
		(layer "In2.Cu")
		(net "MB0_P12V_STBY_PWRGD")
	)
	(segment
		(start 310.411876 -75.454764)
		(end 308.334664 -75.454764)
		(width 0.11684)
		(layer "In2.Cu")
		(net "MB0_P12V_STBY_PWRGD")
	)
	(segment
		(start 280.539698 -76.323444)
		(end 257.398012 -76.323444)
		(width 0.11684)
		(layer "In2.Cu")
		(net "MB0_P12V_STBY_PWRGD")
	)
	(segment
		(start 234.521248 -75.405234)
		(end 222.92056 -80.210406)
		(width 0.11684)
		(layer "In2.Cu")
		(net "MB0_P12V_STBY_PWRGD")
	)
	(segment
		(start 257.398012 -76.323444)
		(end 256.479802 -75.405234)
		(width 0.11684)
		(layer "In2.Cu")
		(net "MB0_P12V_STBY_PWRGD")
	)
	(segment
		(start 256.479802 -75.405234)
		(end 234.521248 -75.405234)
		(width 0.11684)
		(layer "In2.Cu")
		(net "MB0_P12V_STBY_PWRGD")
	)
	(segment
		(start 302.27524 -81.514188)
		(end 285.730442 -81.514188)
		(width 0.11684)
		(layer "In2.Cu")
		(net "MB0_P12V_STBY_PWRGD")
	)
	(segment
		(start 225.646488 -138.424158)
		(end 224.742756 -137.520426)
		(width 0.11684)
		(layer "In4.Cu")
		(net "MB0_P12V_STBY_PWRGD")
	)
	(segment
		(start 222.92056 -83.911694)
		(end 222.92056 -80.210406)
		(width 0.11684)
		(layer "In4.Cu")
		(net "MB0_P12V_STBY_PWRGD")
	)
	(segment
		(start 313.436 -78.613)
		(end 313.436 -97.917)
		(width 0.11684)
		(layer "In4.Cu")
		(net "MB0_P12V_STBY_PWRGD")
	)
	(segment
		(start 224.742756 -137.520426)
		(end 224.742756 -101.18598)
		(width 0.11684)
		(layer "In4.Cu")
		(net "MB0_P12V_STBY_PWRGD")
	)
	(segment
		(start 310.411876 -75.454764)
		(end 310.411876 -75.588876)
		(width 0.11684)
		(layer "In4.Cu")
		(net "MB0_P12V_STBY_PWRGD")
	)
	(segment
		(start 221.22003 -95.90024)
		(end 221.22003 -85.612224)
		(width 0.11684)
		(layer "In4.Cu")
		(net "MB0_P12V_STBY_PWRGD")
	)
	(segment
		(start 224.742756 -101.18598)
		(end 222.24238 -98.685604)
		(width 0.11684)
		(layer "In4.Cu")
		(net "MB0_P12V_STBY_PWRGD")
	)
	(segment
		(start 310.411876 -75.588876)
		(end 313.436 -78.613)
		(width 0.11684)
		(layer "In4.Cu")
		(net "MB0_P12V_STBY_PWRGD")
	)
	(segment
		(start 222.24238 -96.92259)
		(end 221.22003 -95.90024)
		(width 0.11684)
		(layer "In4.Cu")
		(net "MB0_P12V_STBY_PWRGD")
	)
	(segment
		(start 225.646488 -139.069572)
		(end 225.646488 -138.424158)
		(width 0.11684)
		(layer "In4.Cu")
		(net "MB0_P12V_STBY_PWRGD")
	)
	(segment
		(start 221.22003 -85.612224)
		(end 222.92056 -83.911694)
		(width 0.11684)
		(layer "In4.Cu")
		(net "MB0_P12V_STBY_PWRGD")
	)
	(segment
		(start 222.24238 -98.685604)
		(end 222.24238 -96.92259)
		(width 0.11684)
		(layer "In4.Cu")
		(net "MB0_P12V_STBY_PWRGD")
	)
	(segment
		(start 240.525808 -138.067288)
		(end 240.777776 -138.319256)
		(width 0.11684)
		(layer "In6.Cu")
		(net "MB0_P12V_STBY_PWRGD")
	)
	(segment
		(start 192.036446 -378.44476)
		(end 192.036446 -381.123444)
		(width 0.11684)
		(layer "In6.Cu")
		(net "MB0_P12V_STBY_PWRGD")
	)
	(segment
		(start 327.834244 -98.594164)
		(end 321.239642 -98.594164)
		(width 0.11684)
		(layer "In6.Cu")
		(net "MB0_P12V_STBY_PWRGD")
	)
	(segment
		(start 227.045012 -139.069572)
		(end 228.007164 -138.10742)
		(width 0.11684)
		(layer "In6.Cu")
		(net "MB0_P12V_STBY_PWRGD")
	)
	(segment
		(start 179.7939 -405.212296)
		(end 179.7939 -399.887948)
		(width 0.11684)
		(layer "In6.Cu")
		(net "MB0_P12V_STBY_PWRGD")
	)
	(segment
		(start 245.493794 -142.886176)
		(end 251.792486 -149.184868)
		(width 0.11684)
		(layer "In6.Cu")
		(net "MB0_P12V_STBY_PWRGD")
	)
	(segment
		(start 180.183028 -405.601424)
		(end 179.7939 -405.212296)
		(width 0.11684)
		(layer "In6.Cu")
		(net "MB0_P12V_STBY_PWRGD")
	)
	(segment
		(start 240.792508 -138.319256)
		(end 245.359428 -142.886176)
		(width 0.11684)
		(layer "In6.Cu")
		(net "MB0_P12V_STBY_PWRGD")
	)
	(segment
		(start 228.805232 -365.200692)
		(end 228.805232 -368.237008)
		(width 0.11684)
		(layer "In6.Cu")
		(net "MB0_P12V_STBY_PWRGD")
	)
	(segment
		(start 245.359428 -142.886176)
		(end 245.493794 -142.886176)
		(width 0.11684)
		(layer "In6.Cu")
		(net "MB0_P12V_STBY_PWRGD")
	)
	(segment
		(start 228.007164 -138.067288)
		(end 240.525808 -138.067288)
		(width 0.11684)
		(layer "In6.Cu")
		(net "MB0_P12V_STBY_PWRGD")
	)
	(segment
		(start 228.805232 -368.237008)
		(end 221.859602 -375.182638)
		(width 0.11684)
		(layer "In6.Cu")
		(net "MB0_P12V_STBY_PWRGD")
	)
	(segment
		(start 214.564214 -138.141456)
		(end 214.638382 -138.067288)
		(width 0.11684)
		(layer "In6.Cu")
		(net "MB0_P12V_STBY_PWRGD")
	)
	(segment
		(start 336.42808 -107.188)
		(end 327.834244 -98.594164)
		(width 0.11684)
		(layer "In6.Cu")
		(net "MB0_P12V_STBY_PWRGD")
	)
	(segment
		(start 321.239642 -98.594164)
		(end 320.099182 -99.734624)
		(width 0.11684)
		(layer "In6.Cu")
		(net "MB0_P12V_STBY_PWRGD")
	)
	(segment
		(start 318.688212 -99.734624)
		(end 317.547752 -98.594164)
		(width 0.11684)
		(layer "In6.Cu")
		(net "MB0_P12V_STBY_PWRGD")
	)
	(segment
		(start 179.7939 -399.887948)
		(end 179.264056 -399.358104)
		(width 0.11684)
		(layer "In6.Cu")
		(net "MB0_P12V_STBY_PWRGD")
	)
	(segment
		(start 195.298568 -375.182638)
		(end 192.036446 -378.44476)
		(width 0.11684)
		(layer "In6.Cu")
		(net "MB0_P12V_STBY_PWRGD")
	)
	(segment
		(start 193.148966 -382.235964)
		(end 192.573402 -381.6604)
		(width 0.11684)
		(layer "In6.Cu")
		(net "MB0_P12V_STBY_PWRGD")
	)
	(segment
		(start 240.777776 -138.319256)
		(end 240.792508 -138.319256)
		(width 0.11684)
		(layer "In6.Cu")
		(net "MB0_P12V_STBY_PWRGD")
	)
	(segment
		(start 314.96 -97.917)
		(end 313.436 -97.917)
		(width 0.11684)
		(layer "In6.Cu")
		(net "MB0_P12V_STBY_PWRGD")
	)
	(segment
		(start 222.604584 -139.069572)
		(end 225.646488 -139.069572)
		(width 0.11684)
		(layer "In6.Cu")
		(net "MB0_P12V_STBY_PWRGD")
	)
	(segment
		(start 214.638382 -138.067288)
		(end 221.6023 -138.067288)
		(width 0.11684)
		(layer "In6.Cu")
		(net "MB0_P12V_STBY_PWRGD")
	)
	(segment
		(start 320.099182 -99.734624)
		(end 318.688212 -99.734624)
		(width 0.11684)
		(layer "In6.Cu")
		(net "MB0_P12V_STBY_PWRGD")
	)
	(segment
		(start 179.264056 -399.358104)
		(end 179.264056 -396.260574)
		(width 0.11684)
		(layer "In6.Cu")
		(net "MB0_P12V_STBY_PWRGD")
	)
	(segment
		(start 317.547752 -98.594164)
		(end 315.637164 -98.594164)
		(width 0.11684)
		(layer "In6.Cu")
		(net "MB0_P12V_STBY_PWRGD")
	)
	(segment
		(start 315.637164 -98.594164)
		(end 314.96 -97.917)
		(width 0.11684)
		(layer "In6.Cu")
		(net "MB0_P12V_STBY_PWRGD")
	)
	(segment
		(start 193.148966 -387.872732)
		(end 193.148966 -382.235964)
		(width 0.11684)
		(layer "In6.Cu")
		(net "MB0_P12V_STBY_PWRGD")
	)
	(segment
		(start 376.760232 -107.188)
		(end 336.42808 -107.188)
		(width 0.11684)
		(layer "In6.Cu")
		(net "MB0_P12V_STBY_PWRGD")
	)
	(segment
		(start 394.501116 -121.682002)
		(end 390.685528 -117.866414)
		(width 0.11684)
		(layer "In6.Cu")
		(net "MB0_P12V_STBY_PWRGD")
	)
	(segment
		(start 251.792486 -149.184868)
		(end 261.475474 -149.184868)
		(width 0.11684)
		(layer "In6.Cu")
		(net "MB0_P12V_STBY_PWRGD")
	)
	(segment
		(start 387.438646 -117.866414)
		(end 376.760232 -107.188)
		(width 0.11684)
		(layer "In6.Cu")
		(net "MB0_P12V_STBY_PWRGD")
	)
	(segment
		(start 390.685528 -117.866414)
		(end 387.438646 -117.866414)
		(width 0.11684)
		(layer "In6.Cu")
		(net "MB0_P12V_STBY_PWRGD")
	)
	(segment
		(start 192.036446 -381.123444)
		(end 192.573402 -381.6604)
		(width 0.11684)
		(layer "In6.Cu")
		(net "MB0_P12V_STBY_PWRGD")
	)
	(segment
		(start 221.859602 -375.182638)
		(end 195.298568 -375.182638)
		(width 0.11684)
		(layer "In6.Cu")
		(net "MB0_P12V_STBY_PWRGD")
	)
	(segment
		(start 182.538878 -392.985752)
		(end 188.035946 -392.985752)
		(width 0.11684)
		(layer "In6.Cu")
		(net "MB0_P12V_STBY_PWRGD")
	)
	(segment
		(start 179.264056 -396.260574)
		(end 182.538878 -392.985752)
		(width 0.11684)
		(layer "In6.Cu")
		(net "MB0_P12V_STBY_PWRGD")
	)
	(segment
		(start 225.646488 -139.069572)
		(end 227.045012 -139.069572)
		(width 0.11684)
		(layer "In6.Cu")
		(net "MB0_P12V_STBY_PWRGD")
	)
	(segment
		(start 188.035946 -392.985752)
		(end 193.148966 -387.872732)
		(width 0.11684)
		(layer "In6.Cu")
		(net "MB0_P12V_STBY_PWRGD")
	)
	(segment
		(start 221.6023 -138.067288)
		(end 222.604584 -139.069572)
		(width 0.11684)
		(layer "In6.Cu")
		(net "MB0_P12V_STBY_PWRGD")
	)
	(segment
		(start 228.007164 -138.10742)
		(end 228.007164 -138.067288)
		(width 0.11684)
		(layer "In6.Cu")
		(net "MB0_P12V_STBY_PWRGD")
	)
	(segment
		(start 180.183028 -406.70734)
		(end 180.183028 -405.601424)
		(width 0.11684)
		(layer "In6.Cu")
		(net "MB0_P12V_STBY_PWRGD")
	)
	(segment
		(start 164.944806 -43.193462)
		(end 165.938454 -43.193462)
		(width 0.10668)
		(layer "F.Cu")
		(net "M2_SSD0_CLKREQ_EN_N_BUF")
	)
	(segment
		(start 165.938454 -43.193462)
		(end 166.155878 -42.976038)
		(width 0.10668)
		(layer "F.Cu")
		(net "M2_SSD0_CLKREQ_EN_N_BUF")
	)
	(segment
		(start 169.558208 -43.549824)
		(end 166.729664 -43.549824)
		(width 0.10668)
		(layer "F.Cu")
		(net "M2_SSD0_CLKREQ_EN_N_BUF")
	)
	(segment
		(start 166.729664 -43.549824)
		(end 166.155878 -42.976038)
		(width 0.10668)
		(layer "F.Cu")
		(net "M2_SSD0_CLKREQ_EN_N_BUF")
	)
	(segment
		(start 164.944806 -42.177462)
		(end 164.944806 -43.193462)
		(width 0.10668)
		(layer "F.Cu")
		(net "M2_SSD0_CLKREQ_EN_N_BUF")
	)
	(via
		(at 166.155878 -42.976038)
		(size 0.762)
		(drill 0.381)
		(layers "F.Cu" "B.Cu")
		(net "M2_SSD0_CLKREQ_EN_N_BUF")
	)
	(segment
		(start 143.740632 -102.544118)
		(end 143.054832 -102.544118)
		(width 0.10668)
		(layer "F.Cu")
		(net "M2_SSD0_CLKREQ_EN_N")
	)
	(segment
		(start 164.144706 -43.193462)
		(end 162.963352 -43.193462)
		(width 0.10668)
		(layer "F.Cu")
		(net "M2_SSD0_CLKREQ_EN_N")
	)
	(segment
		(start 164.157914 -43.20667)
		(end 164.144706 -43.193462)
		(width 0.10668)
		(layer "F.Cu")
		(net "M2_SSD0_CLKREQ_EN_N")
	)
	(segment
		(start 143.054832 -102.544118)
		(end 142.800832 -102.798118)
		(width 0.10668)
		(layer "F.Cu")
		(net "M2_SSD0_CLKREQ_EN_N")
	)
	(segment
		(start 164.157914 -44.247054)
		(end 164.157914 -43.20667)
		(width 0.10668)
		(layer "F.Cu")
		(net "M2_SSD0_CLKREQ_EN_N")
	)
	(segment
		(start 186.817 -99.894898)
		(end 186.817 -99.278948)
		(width 0.10668)
		(layer "F.Cu")
		(net "M2_SSD0_CLKREQ_EN_N")
	)
	(segment
		(start 162.963352 -43.193462)
		(end 162.794442 -43.024552)
		(width 0.10668)
		(layer "F.Cu")
		(net "M2_SSD0_CLKREQ_EN_N")
	)
	(via
		(at 153.244804 -109.10062)
		(size 0.508)
		(drill 0.254)
		(layers "F.Cu" "B.Cu")
		(net "M2_SSD0_CLKREQ_EN_N")
	)
	(via
		(at 162.794442 -43.024552)
		(size 0.508)
		(drill 0.254)
		(layers "F.Cu" "B.Cu")
		(net "M2_SSD0_CLKREQ_EN_N")
	)
	(via
		(at 142.800832 -102.798118)
		(size 0.508)
		(drill 0.254)
		(layers "F.Cu" "B.Cu")
		(net "M2_SSD0_CLKREQ_EN_N")
	)
	(via
		(at 186.817 -99.278948)
		(size 0.508)
		(drill 0.254)
		(layers "F.Cu" "B.Cu")
		(net "M2_SSD0_CLKREQ_EN_N")
	)
	(via
		(at 153.295604 -58.41873)
		(size 0.508)
		(drill 0.254)
		(layers "F.Cu" "B.Cu")
		(net "M2_SSD0_CLKREQ_EN_N")
	)
	(segment
		(start 157.329378 -57.074308)
		(end 155.984956 -58.41873)
		(width 0.11684)
		(layer "In2.Cu")
		(net "M2_SSD0_CLKREQ_EN_N")
	)
	(segment
		(start 155.984956 -58.41873)
		(end 153.295604 -58.41873)
		(width 0.11684)
		(layer "In2.Cu")
		(net "M2_SSD0_CLKREQ_EN_N")
	)
	(segment
		(start 184.633108 -101.46284)
		(end 186.817 -99.278948)
		(width 0.11684)
		(layer "In2.Cu")
		(net "M2_SSD0_CLKREQ_EN_N")
	)
	(segment
		(start 162.794442 -43.024552)
		(end 166.018972 -43.024552)
		(width 0.11684)
		(layer "In2.Cu")
		(net "M2_SSD0_CLKREQ_EN_N")
	)
	(segment
		(start 164.555678 -105.23601)
		(end 165.185344 -104.606344)
		(width 0.11684)
		(layer "In2.Cu")
		(net "M2_SSD0_CLKREQ_EN_N")
	)
	(segment
		(start 167.836342 -44.841922)
		(end 167.836342 -47.530258)
		(width 0.11684)
		(layer "In2.Cu")
		(net "M2_SSD0_CLKREQ_EN_N")
	)
	(segment
		(start 158.292292 -57.074308)
		(end 157.329378 -57.074308)
		(width 0.11684)
		(layer "In2.Cu")
		(net "M2_SSD0_CLKREQ_EN_N")
	)
	(segment
		(start 168.752774 -103.141272)
		(end 168.798748 -103.095298)
		(width 0.11684)
		(layer "In2.Cu")
		(net "M2_SSD0_CLKREQ_EN_N")
	)
	(segment
		(start 166.511732 -104.606344)
		(end 167.976804 -103.141272)
		(width 0.11684)
		(layer "In2.Cu")
		(net "M2_SSD0_CLKREQ_EN_N")
	)
	(segment
		(start 166.018972 -43.024552)
		(end 167.836342 -44.841922)
		(width 0.11684)
		(layer "In2.Cu")
		(net "M2_SSD0_CLKREQ_EN_N")
	)
	(segment
		(start 173.919388 -101.46284)
		(end 184.633108 -101.46284)
		(width 0.11684)
		(layer "In2.Cu")
		(net "M2_SSD0_CLKREQ_EN_N")
	)
	(segment
		(start 165.185344 -104.606344)
		(end 166.511732 -104.606344)
		(width 0.11684)
		(layer "In2.Cu")
		(net "M2_SSD0_CLKREQ_EN_N")
	)
	(segment
		(start 168.798748 -103.095298)
		(end 172.28693 -103.095298)
		(width 0.11684)
		(layer "In2.Cu")
		(net "M2_SSD0_CLKREQ_EN_N")
	)
	(segment
		(start 153.244804 -109.10062)
		(end 153.709116 -109.564932)
		(width 0.11684)
		(layer "In2.Cu")
		(net "M2_SSD0_CLKREQ_EN_N")
	)
	(segment
		(start 167.976804 -103.141272)
		(end 168.752774 -103.141272)
		(width 0.11684)
		(layer "In2.Cu")
		(net "M2_SSD0_CLKREQ_EN_N")
	)
	(segment
		(start 162.265106 -107.888278)
		(end 164.555678 -105.597706)
		(width 0.11684)
		(layer "In2.Cu")
		(net "M2_SSD0_CLKREQ_EN_N")
	)
	(segment
		(start 159.182054 -109.564932)
		(end 160.858708 -107.888278)
		(width 0.11684)
		(layer "In2.Cu")
		(net "M2_SSD0_CLKREQ_EN_N")
	)
	(segment
		(start 160.858708 -107.888278)
		(end 162.265106 -107.888278)
		(width 0.11684)
		(layer "In2.Cu")
		(net "M2_SSD0_CLKREQ_EN_N")
	)
	(segment
		(start 167.836342 -47.530258)
		(end 158.292292 -57.074308)
		(width 0.11684)
		(layer "In2.Cu")
		(net "M2_SSD0_CLKREQ_EN_N")
	)
	(segment
		(start 172.28693 -103.095298)
		(end 173.919388 -101.46284)
		(width 0.11684)
		(layer "In2.Cu")
		(net "M2_SSD0_CLKREQ_EN_N")
	)
	(segment
		(start 164.555678 -105.597706)
		(end 164.555678 -105.23601)
		(width 0.11684)
		(layer "In2.Cu")
		(net "M2_SSD0_CLKREQ_EN_N")
	)
	(segment
		(start 153.709116 -109.564932)
		(end 159.182054 -109.564932)
		(width 0.11684)
		(layer "In2.Cu")
		(net "M2_SSD0_CLKREQ_EN_N")
	)
	(segment
		(start 152.977596 -108.833412)
		(end 151.375618 -108.833412)
		(width 0.11684)
		(layer "In4.Cu")
		(net "M2_SSD0_CLKREQ_EN_N")
	)
	(segment
		(start 153.295604 -63.051944)
		(end 159.69234 -69.44868)
		(width 0.11684)
		(layer "In4.Cu")
		(net "M2_SSD0_CLKREQ_EN_N")
	)
	(segment
		(start 151.375618 -108.833412)
		(end 145.340324 -102.798118)
		(width 0.11684)
		(layer "In4.Cu")
		(net "M2_SSD0_CLKREQ_EN_N")
	)
	(segment
		(start 153.912062 -109.767878)
		(end 153.244804 -109.10062)
		(width 0.11684)
		(layer "In4.Cu")
		(net "M2_SSD0_CLKREQ_EN_N")
	)
	(segment
		(start 156.001212 -109.767878)
		(end 153.912062 -109.767878)
		(width 0.11684)
		(layer "In4.Cu")
		(net "M2_SSD0_CLKREQ_EN_N")
	)
	(segment
		(start 159.69234 -106.07675)
		(end 156.001212 -109.767878)
		(width 0.11684)
		(layer "In4.Cu")
		(net "M2_SSD0_CLKREQ_EN_N")
	)
	(segment
		(start 159.69234 -69.44868)
		(end 159.69234 -106.07675)
		(width 0.11684)
		(layer "In4.Cu")
		(net "M2_SSD0_CLKREQ_EN_N")
	)
	(segment
		(start 145.340324 -102.798118)
		(end 142.800832 -102.798118)
		(width 0.11684)
		(layer "In4.Cu")
		(net "M2_SSD0_CLKREQ_EN_N")
	)
	(segment
		(start 153.244804 -109.10062)
		(end 152.977596 -108.833412)
		(width 0.11684)
		(layer "In4.Cu")
		(net "M2_SSD0_CLKREQ_EN_N")
	)
	(segment
		(start 153.295604 -58.41873)
		(end 153.295604 -63.051944)
		(width 0.11684)
		(layer "In4.Cu")
		(net "M2_SSD0_CLKREQ_EN_N")
	)
	(segment
		(start 169.558208 -43.049952)
		(end 167.636698 -43.049952)
		(width 0.10668)
		(layer "F.Cu")
		(net "M2_0_PEWAKE_N")
	)
	(segment
		(start 167.636698 -43.049952)
		(end 166.235634 -41.648888)
		(width 0.10668)
		(layer "F.Cu")
		(net "M2_0_PEWAKE_N")
	)
	(segment
		(start 165.699694 -41.112948)
		(end 166.235634 -41.648888)
		(width 0.10668)
		(layer "F.Cu")
		(net "M2_0_PEWAKE_N")
	)
	(segment
		(start 164.944806 -41.112948)
		(end 165.699694 -41.112948)
		(width 0.10668)
		(layer "F.Cu")
		(net "M2_0_PEWAKE_N")
	)
	(via
		(at 166.235634 -41.648888)
		(size 0.762)
		(drill 0.381)
		(layers "F.Cu" "B.Cu")
		(net "M2_0_PEWAKE_N")
	)
	(segment
		(start 149.91969 -101.672898)
		(end 149.53234 -101.672898)
		(width 0.10668)
		(layer "F.Cu")
		(net "LED_M2_SSD_0_ACT_N")
	)
	(segment
		(start 149.53234 -101.672898)
		(end 149.27834 -101.418898)
		(width 0.10668)
		(layer "F.Cu")
		(net "LED_M2_SSD_0_ACT_N")
	)
	(segment
		(start 170.610276 -54.04993)
		(end 169.558208 -54.04993)
		(width 0.10668)
		(layer "F.Cu")
		(net "LED_M2_SSD_0_ACT_N")
	)
	(segment
		(start 170.941746 -54.3814)
		(end 170.610276 -54.04993)
		(width 0.10668)
		(layer "F.Cu")
		(net "LED_M2_SSD_0_ACT_N")
	)
	(segment
		(start 172.269404 -54.805834)
		(end 171.84497 -54.3814)
		(width 0.10668)
		(layer "F.Cu")
		(net "LED_M2_SSD_0_ACT_N")
	)
	(segment
		(start 171.84497 -54.3814)
		(end 170.941746 -54.3814)
		(width 0.10668)
		(layer "F.Cu")
		(net "LED_M2_SSD_0_ACT_N")
	)
	(via
		(at 172.269404 -54.805834)
		(size 0.508)
		(drill 0.254)
		(layers "F.Cu" "B.Cu")
		(net "LED_M2_SSD_0_ACT_N")
	)
	(via
		(at 149.27834 -101.418898)
		(size 0.508)
		(drill 0.254)
		(layers "F.Cu" "B.Cu")
		(net "LED_M2_SSD_0_ACT_N")
	)
	(segment
		(start 147.85975 -100.000308)
		(end 142.071598 -100.000308)
		(width 0.11684)
		(layer "In15.Cu")
		(net "LED_M2_SSD_0_ACT_N")
	)
	(segment
		(start 143.980916 -89.353644)
		(end 154.492452 -89.353644)
		(width 0.11684)
		(layer "In15.Cu")
		(net "LED_M2_SSD_0_ACT_N")
	)
	(segment
		(start 171.010834 -54.805834)
		(end 172.269404 -54.805834)
		(width 0.11684)
		(layer "In15.Cu")
		(net "LED_M2_SSD_0_ACT_N")
	)
	(segment
		(start 149.27834 -101.418898)
		(end 147.85975 -100.000308)
		(width 0.11684)
		(layer "In15.Cu")
		(net "LED_M2_SSD_0_ACT_N")
	)
	(segment
		(start 162.352482 -81.493614)
		(end 162.352482 -63.464186)
		(width 0.11684)
		(layer "In15.Cu")
		(net "LED_M2_SSD_0_ACT_N")
	)
	(segment
		(start 162.352482 -63.464186)
		(end 171.010834 -54.805834)
		(width 0.11684)
		(layer "In15.Cu")
		(net "LED_M2_SSD_0_ACT_N")
	)
	(segment
		(start 154.492452 -89.353644)
		(end 162.352482 -81.493614)
		(width 0.11684)
		(layer "In15.Cu")
		(net "LED_M2_SSD_0_ACT_N")
	)
	(segment
		(start 139.248896 -94.085664)
		(end 143.980916 -89.353644)
		(width 0.11684)
		(layer "In15.Cu")
		(net "LED_M2_SSD_0_ACT_N")
	)
	(segment
		(start 139.248896 -97.177606)
		(end 139.248896 -94.085664)
		(width 0.11684)
		(layer "In15.Cu")
		(net "LED_M2_SSD_0_ACT_N")
	)
	(segment
		(start 142.071598 -100.000308)
		(end 139.248896 -97.177606)
		(width 0.11684)
		(layer "In15.Cu")
		(net "LED_M2_SSD_0_ACT_N")
	)
	(segment
		(start 150.71979 -101.672898)
		(end 150.71979 -102.688898)
		(width 0.10668)
		(layer "F.Cu")
		(net "LED_HDD_ACTIVITY_N")
	)
	(segment
		(start 150.71979 -102.688898)
		(end 151.93899 -102.688898)
		(width 0.10668)
		(layer "F.Cu")
		(net "LED_HDD_ACTIVITY_N")
	)
	(segment
		(start 153.22423 -102.688898)
		(end 151.93899 -102.688898)
		(width 0.10668)
		(layer "F.Cu")
		(net "LED_HDD_ACTIVITY_N")
	)
	(via
		(at 151.93899 -102.688898)
		(size 0.762)
		(drill 0.381)
		(layers "F.Cu" "B.Cu")
		(net "LED_HDD_ACTIVITY_N")
	)
	(segment
		(start 185.801 -92.274898)
		(end 185.801 -91.658948)
		(width 0.10668)
		(layer "F.Cu")
		(net "LED_HDD_ACTIVITY_B_N")
	)
	(segment
		(start 128.371346 -21.772118)
		(end 128.218184 -21.92528)
		(width 0.10668)
		(layer "F.Cu")
		(net "LED_HDD_ACTIVITY_B_N")
	)
	(segment
		(start 155.12415 -102.038912)
		(end 156.30779 -102.038912)
		(width 0.10668)
		(layer "F.Cu")
		(net "LED_HDD_ACTIVITY_B_N")
	)
	(segment
		(start 156.30779 -102.038912)
		(end 156.96819 -102.038912)
		(width 0.10668)
		(layer "F.Cu")
		(net "LED_HDD_ACTIVITY_B_N")
	)
	(segment
		(start 130.946906 -21.772118)
		(end 128.371346 -21.772118)
		(width 0.10668)
		(layer "F.Cu")
		(net "LED_HDD_ACTIVITY_B_N")
	)
	(via
		(at 156.96819 -102.038912)
		(size 0.508)
		(drill 0.254)
		(layers "F.Cu" "B.Cu")
		(net "LED_HDD_ACTIVITY_B_N")
	)
	(via
		(at 185.801 -91.658948)
		(size 0.508)
		(drill 0.254)
		(layers "F.Cu" "B.Cu")
		(net "LED_HDD_ACTIVITY_B_N")
	)
	(via
		(at 133.26872 -106.070908)
		(size 0.508)
		(drill 0.254)
		(layers "F.Cu" "B.Cu")
		(net "LED_HDD_ACTIVITY_B_N")
	)
	(via
		(at 128.218184 -21.92528)
		(size 0.508)
		(drill 0.254)
		(layers "F.Cu" "B.Cu")
		(net "LED_HDD_ACTIVITY_B_N")
	)
	(segment
		(start 156.96819 -102.038912)
		(end 153.468578 -102.038912)
		(width 0.10668)
		(layer "B.Cu")
		(net "LED_HDD_ACTIVITY_B_N")
	)
	(segment
		(start 152.84069 -102.6668)
		(end 150.330662 -102.6668)
		(width 0.10668)
		(layer "B.Cu")
		(net "LED_HDD_ACTIVITY_B_N")
	)
	(segment
		(start 153.468578 -102.038912)
		(end 152.84069 -102.6668)
		(width 0.10668)
		(layer "B.Cu")
		(net "LED_HDD_ACTIVITY_B_N")
	)
	(segment
		(start 150.330662 -102.6668)
		(end 146.8755 -106.121962)
		(width 0.10668)
		(layer "B.Cu")
		(net "LED_HDD_ACTIVITY_B_N")
	)
	(segment
		(start 133.319774 -106.121962)
		(end 133.26872 -106.070908)
		(width 0.10668)
		(layer "B.Cu")
		(net "LED_HDD_ACTIVITY_B_N")
	)
	(segment
		(start 146.8755 -106.121962)
		(end 133.319774 -106.121962)
		(width 0.10668)
		(layer "B.Cu")
		(net "LED_HDD_ACTIVITY_B_N")
	)
	(segment
		(start 185.28538 -92.174568)
		(end 177.35296 -92.174568)
		(width 0.11684)
		(layer "In2.Cu")
		(net "LED_HDD_ACTIVITY_B_N")
	)
	(segment
		(start 173.123098 -91.86418)
		(end 172.737526 -91.86418)
		(width 0.11684)
		(layer "In2.Cu")
		(net "LED_HDD_ACTIVITY_B_N")
	)
	(segment
		(start 171.88307 -92.718636)
		(end 166.254938 -92.718636)
		(width 0.11684)
		(layer "In2.Cu")
		(net "LED_HDD_ACTIVITY_B_N")
	)
	(segment
		(start 185.801 -91.658948)
		(end 185.28538 -92.174568)
		(width 0.11684)
		(layer "In2.Cu")
		(net "LED_HDD_ACTIVITY_B_N")
	)
	(segment
		(start 166.254938 -92.718636)
		(end 156.96819 -102.005384)
		(width 0.11684)
		(layer "In2.Cu")
		(net "LED_HDD_ACTIVITY_B_N")
	)
	(segment
		(start 173.37786 -92.118942)
		(end 173.123098 -91.86418)
		(width 0.11684)
		(layer "In2.Cu")
		(net "LED_HDD_ACTIVITY_B_N")
	)
	(segment
		(start 172.737526 -91.86418)
		(end 171.88307 -92.718636)
		(width 0.11684)
		(layer "In2.Cu")
		(net "LED_HDD_ACTIVITY_B_N")
	)
	(segment
		(start 177.35296 -92.174568)
		(end 177.207418 -92.029026)
		(width 0.11684)
		(layer "In2.Cu")
		(net "LED_HDD_ACTIVITY_B_N")
	)
	(segment
		(start 177.207418 -92.029026)
		(end 176.405286 -92.029026)
		(width 0.11684)
		(layer "In2.Cu")
		(net "LED_HDD_ACTIVITY_B_N")
	)
	(segment
		(start 176.405286 -92.029026)
		(end 176.31537 -92.118942)
		(width 0.11684)
		(layer "In2.Cu")
		(net "LED_HDD_ACTIVITY_B_N")
	)
	(segment
		(start 156.96819 -102.005384)
		(end 156.96819 -102.038912)
		(width 0.11684)
		(layer "In2.Cu")
		(net "LED_HDD_ACTIVITY_B_N")
	)
	(segment
		(start 176.31537 -92.118942)
		(end 173.37786 -92.118942)
		(width 0.11684)
		(layer "In2.Cu")
		(net "LED_HDD_ACTIVITY_B_N")
	)
	(segment
		(start 117.6274 -39.243)
		(end 119.866918 -41.482518)
		(width 0.11684)
		(layer "In4.Cu")
		(net "LED_HDD_ACTIVITY_B_N")
	)
	(segment
		(start 111.584994 -85.31733)
		(end 132.338572 -106.070908)
		(width 0.11684)
		(layer "In4.Cu")
		(net "LED_HDD_ACTIVITY_B_N")
	)
	(segment
		(start 119.866918 -46.384972)
		(end 117.074442 -49.177448)
		(width 0.11684)
		(layer "In4.Cu")
		(net "LED_HDD_ACTIVITY_B_N")
	)
	(segment
		(start 119.866918 -41.482518)
		(end 119.866918 -46.384972)
		(width 0.11684)
		(layer "In4.Cu")
		(net "LED_HDD_ACTIVITY_B_N")
	)
	(segment
		(start 128.218184 -21.92528)
		(end 127.01016 -21.92528)
		(width 0.11684)
		(layer "In4.Cu")
		(net "LED_HDD_ACTIVITY_B_N")
	)
	(segment
		(start 127.01016 -21.92528)
		(end 122.01144 -26.924)
		(width 0.11684)
		(layer "In4.Cu")
		(net "LED_HDD_ACTIVITY_B_N")
	)
	(segment
		(start 102.85222 -71.17334)
		(end 108.44657 -76.76769)
		(width 0.11684)
		(layer "In4.Cu")
		(net "LED_HDD_ACTIVITY_B_N")
	)
	(segment
		(start 117.074442 -49.177448)
		(end 107.189778 -49.177448)
		(width 0.11684)
		(layer "In4.Cu")
		(net "LED_HDD_ACTIVITY_B_N")
	)
	(segment
		(start 107.189778 -49.177448)
		(end 102.85222 -53.515006)
		(width 0.11684)
		(layer "In4.Cu")
		(net "LED_HDD_ACTIVITY_B_N")
	)
	(segment
		(start 108.44657 -76.76769)
		(end 108.44657 -80.017112)
		(width 0.11684)
		(layer "In4.Cu")
		(net "LED_HDD_ACTIVITY_B_N")
	)
	(segment
		(start 111.584994 -83.155536)
		(end 111.584994 -85.31733)
		(width 0.11684)
		(layer "In4.Cu")
		(net "LED_HDD_ACTIVITY_B_N")
	)
	(segment
		(start 117.6274 -27.8384)
		(end 117.6274 -39.243)
		(width 0.11684)
		(layer "In4.Cu")
		(net "LED_HDD_ACTIVITY_B_N")
	)
	(segment
		(start 118.5418 -26.924)
		(end 117.6274 -27.8384)
		(width 0.11684)
		(layer "In4.Cu")
		(net "LED_HDD_ACTIVITY_B_N")
	)
	(segment
		(start 108.44657 -80.017112)
		(end 111.584994 -83.155536)
		(width 0.11684)
		(layer "In4.Cu")
		(net "LED_HDD_ACTIVITY_B_N")
	)
	(segment
		(start 132.338572 -106.070908)
		(end 133.26872 -106.070908)
		(width 0.11684)
		(layer "In4.Cu")
		(net "LED_HDD_ACTIVITY_B_N")
	)
	(segment
		(start 102.85222 -53.515006)
		(end 102.85222 -71.17334)
		(width 0.11684)
		(layer "In4.Cu")
		(net "LED_HDD_ACTIVITY_B_N")
	)
	(segment
		(start 122.01144 -26.924)
		(end 118.5418 -26.924)
		(width 0.11684)
		(layer "In4.Cu")
		(net "LED_HDD_ACTIVITY_B_N")
	)
	(segment
		(start 335.28508 -15.596616)
		(end 335.28508 -14.377416)
		(width 0.10668)
		(layer "F.Cu")
		(net "LED_BIOS_DBG_MODE_R")
	)
	(segment
		(start 336.68462 -14.653768)
		(end 336.408268 -14.377416)
		(width 0.10668)
		(layer "F.Cu")
		(net "LED_BIOS_DBG_MODE_R")
	)
	(segment
		(start 336.408268 -14.377416)
		(end 335.28508 -14.377416)
		(width 0.10668)
		(layer "F.Cu")
		(net "LED_BIOS_DBG_MODE_R")
	)
	(segment
		(start 336.68462 -15.449296)
		(end 336.68462 -14.653768)
		(width 0.10668)
		(layer "F.Cu")
		(net "LED_BIOS_DBG_MODE_R")
	)
	(via
		(at 335.28508 -14.377416)
		(size 0.762)
		(drill 0.381)
		(layers "F.Cu" "B.Cu")
		(net "LED_BIOS_DBG_MODE_R")
	)
	(segment
		(start 338.233258 -21.256498)
		(end 338.683346 -21.706586)
		(width 0.10668)
		(layer "F.Cu")
		(net "LED_BIOS_DBG_MODE_N")
	)
	(segment
		(start 338.683346 -23.497286)
		(end 338.683346 -22.278086)
		(width 0.10668)
		(layer "F.Cu")
		(net "LED_BIOS_DBG_MODE_N")
	)
	(segment
		(start 338.683346 -21.706586)
		(end 338.683346 -22.278086)
		(width 0.10668)
		(layer "F.Cu")
		(net "LED_BIOS_DBG_MODE_N")
	)
	(segment
		(start 337.195414 -21.256498)
		(end 338.233258 -21.256498)
		(width 0.10668)
		(layer "F.Cu")
		(net "LED_BIOS_DBG_MODE_N")
	)
	(segment
		(start 336.195416 -23.497286)
		(end 338.683346 -23.497286)
		(width 0.10668)
		(layer "F.Cu")
		(net "LED_BIOS_DBG_MODE_N")
	)
	(via
		(at 338.683346 -22.278086)
		(size 0.762)
		(drill 0.381)
		(layers "F.Cu" "B.Cu")
		(net "LED_BIOS_DBG_MODE_N")
	)
	(segment
		(start 337.67649 -17.894808)
		(end 337.67649 -17.391126)
		(width 0.10668)
		(layer "F.Cu")
		(net "LED_BIOS_DBG_MODE")
	)
	(segment
		(start 337.67649 -17.391126)
		(end 336.68462 -16.399256)
		(width 0.10668)
		(layer "F.Cu")
		(net "LED_BIOS_DBG_MODE")
	)
	(segment
		(start 336.612738 -17.894808)
		(end 337.67649 -17.894808)
		(width 0.10668)
		(layer "F.Cu")
		(net "LED_BIOS_DBG_MODE")
	)
	(segment
		(start 336.195416 -19.016726)
		(end 336.195416 -18.31213)
		(width 0.10668)
		(layer "F.Cu")
		(net "LED_BIOS_DBG_MODE")
	)
	(segment
		(start 336.195416 -18.31213)
		(end 336.612738 -17.894808)
		(width 0.10668)
		(layer "F.Cu")
		(net "LED_BIOS_DBG_MODE")
	)
	(via
		(at 337.67649 -17.894808)
		(size 0.762)
		(drill 0.381)
		(layers "F.Cu" "B.Cu")
		(net "LED_BIOS_DBG_MODE")
	)
	(segment
		(start 260.902958 -106.263948)
		(end 260.902958 -104.094534)
		(width 0.10668)
		(layer "F.Cu")
		(net "JTAG_TRST_R_N")
	)
	(segment
		(start 264.267188 -107.173776)
		(end 263.2202 -107.173776)
		(width 0.10668)
		(layer "F.Cu")
		(net "JTAG_TRST_R_N")
	)
	(segment
		(start 263.2202 -107.173776)
		(end 263.130284 -107.08386)
		(width 0.10668)
		(layer "F.Cu")
		(net "JTAG_TRST_R_N")
	)
	(segment
		(start 260.874256 -98.105976)
		(end 261.434326 -98.105976)
		(width 0.10668)
		(layer "F.Cu")
		(net "JTAG_TRST_R_N")
	)
	(segment
		(start 265.173206 -98.105976)
		(end 264.17143 -98.105976)
		(width 0.10668)
		(layer "F.Cu")
		(net "JTAG_TRST_R_N")
	)
	(segment
		(start 263.130284 -107.08386)
		(end 261.72287 -107.08386)
		(width 0.10668)
		(layer "F.Cu")
		(net "JTAG_TRST_R_N")
	)
	(segment
		(start 260.234176 -98.746056)
		(end 260.874256 -98.105976)
		(width 0.10668)
		(layer "F.Cu")
		(net "JTAG_TRST_R_N")
	)
	(segment
		(start 263.611868 -101.385624)
		(end 264.841736 -101.385624)
		(width 0.10668)
		(layer "F.Cu")
		(net "JTAG_TRST_R_N")
	)
	(segment
		(start 261.72287 -107.08386)
		(end 260.902958 -106.263948)
		(width 0.10668)
		(layer "F.Cu")
		(net "JTAG_TRST_R_N")
	)
	(segment
		(start 260.902958 -104.094534)
		(end 263.611868 -101.385624)
		(width 0.10668)
		(layer "F.Cu")
		(net "JTAG_TRST_R_N")
	)
	(segment
		(start 264.26795 -107.173014)
		(end 264.267188 -107.173776)
		(width 0.10668)
		(layer "F.Cu")
		(net "JTAG_TRST_R_N")
	)
	(segment
		(start 265.724894 -100.502466)
		(end 265.724894 -98.657664)
		(width 0.10668)
		(layer "F.Cu")
		(net "JTAG_TRST_R_N")
	)
	(segment
		(start 264.841736 -101.385624)
		(end 265.724894 -100.502466)
		(width 0.10668)
		(layer "F.Cu")
		(net "JTAG_TRST_R_N")
	)
	(segment
		(start 261.434326 -98.105976)
		(end 264.17143 -98.105976)
		(width 0.10668)
		(layer "F.Cu")
		(net "JTAG_TRST_R_N")
	)
	(segment
		(start 265.724894 -98.657664)
		(end 265.173206 -98.105976)
		(width 0.10668)
		(layer "F.Cu")
		(net "JTAG_TRST_R_N")
	)
	(via
		(at 261.434326 -98.105976)
		(size 0.762)
		(drill 0.381)
		(layers "F.Cu" "B.Cu")
		(net "JTAG_TRST_R_N")
	)
	(segment
		(start 286.361632 -98.112834)
		(end 286.218122 -97.969324)
		(width 0.10668)
		(layer "F.Cu")
		(net "JTAG_TRST_N")
	)
	(segment
		(start 258.318 -104.14254)
		(end 258.318 -99.862132)
		(width 0.10668)
		(layer "F.Cu")
		(net "JTAG_TRST_N")
	)
	(segment
		(start 257.057144 -105.403396)
		(end 258.318 -104.14254)
		(width 0.10668)
		(layer "F.Cu")
		(net "JTAG_TRST_N")
	)
	(segment
		(start 290.733226 -98.004122)
		(end 290.733226 -94.518226)
		(width 0.10668)
		(layer "F.Cu")
		(net "JTAG_TRST_N")
	)
	(segment
		(start 253.852426 -105.403396)
		(end 257.057144 -105.403396)
		(width 0.10668)
		(layer "F.Cu")
		(net "JTAG_TRST_N")
	)
	(segment
		(start 252.56363 -104.1146)
		(end 253.852426 -105.403396)
		(width 0.10668)
		(layer "F.Cu")
		(net "JTAG_TRST_N")
	)
	(segment
		(start 265.12266 -88.35771)
		(end 255.325626 -98.154744)
		(width 0.10668)
		(layer "F.Cu")
		(net "JTAG_TRST_N")
	)
	(segment
		(start 290.733226 -94.518226)
		(end 289.56 -93.345)
		(width 0.10668)
		(layer "F.Cu")
		(net "JTAG_TRST_N")
	)
	(segment
		(start 286.218122 -97.969324)
		(end 284.266386 -97.969324)
		(width 0.10668)
		(layer "F.Cu")
		(net "JTAG_TRST_N")
	)
	(segment
		(start 258.318 -99.862132)
		(end 259.434076 -98.746056)
		(width 0.10668)
		(layer "F.Cu")
		(net "JTAG_TRST_N")
	)
	(segment
		(start 287.842452 -97.943924)
		(end 286.530542 -97.943924)
		(width 0.10668)
		(layer "F.Cu")
		(net "JTAG_TRST_N")
	)
	(segment
		(start 277.146258 -88.35771)
		(end 265.12266 -88.35771)
		(width 0.10668)
		(layer "F.Cu")
		(net "JTAG_TRST_N")
	)
	(segment
		(start 287.86582 -97.967292)
		(end 287.842452 -97.943924)
		(width 0.10668)
		(layer "F.Cu")
		(net "JTAG_TRST_N")
	)
	(segment
		(start 255.325626 -98.154744)
		(end 254.178816 -98.154744)
		(width 0.10668)
		(layer "F.Cu")
		(net "JTAG_TRST_N")
	)
	(segment
		(start 286.530542 -97.943924)
		(end 286.361632 -98.112834)
		(width 0.10668)
		(layer "F.Cu")
		(net "JTAG_TRST_N")
	)
	(segment
		(start 289.56 -93.345)
		(end 282.133548 -93.345)
		(width 0.10668)
		(layer "F.Cu")
		(net "JTAG_TRST_N")
	)
	(segment
		(start 287.86582 -98.194368)
		(end 288.5186 -98.847148)
		(width 0.10668)
		(layer "F.Cu")
		(net "JTAG_TRST_N")
	)
	(segment
		(start 288.5186 -98.847148)
		(end 289.8902 -98.847148)
		(width 0.10668)
		(layer "F.Cu")
		(net "JTAG_TRST_N")
	)
	(segment
		(start 252.56363 -101.865938)
		(end 252.56363 -104.1146)
		(width 0.10668)
		(layer "F.Cu")
		(net "JTAG_TRST_N")
	)
	(segment
		(start 282.133548 -93.345)
		(end 277.146258 -88.35771)
		(width 0.10668)
		(layer "F.Cu")
		(net "JTAG_TRST_N")
	)
	(segment
		(start 289.8902 -98.847148)
		(end 290.733226 -98.004122)
		(width 0.10668)
		(layer "F.Cu")
		(net "JTAG_TRST_N")
	)
	(segment
		(start 287.86582 -97.967292)
		(end 287.86582 -98.194368)
		(width 0.10668)
		(layer "F.Cu")
		(net "JTAG_TRST_N")
	)
	(segment
		(start 254.178816 -98.154744)
		(end 252.56363 -99.76993)
		(width 0.10668)
		(layer "F.Cu")
		(net "JTAG_TRST_N")
	)
	(segment
		(start 252.56363 -99.76993)
		(end 252.56363 -101.865938)
		(width 0.10668)
		(layer "F.Cu")
		(net "JTAG_TRST_N")
	)
	(via
		(at 286.361632 -98.112834)
		(size 0.762)
		(drill 0.381)
		(layers "F.Cu" "B.Cu")
		(net "JTAG_TRST_N")
	)
	(segment
		(start 264.26795 -106.522774)
		(end 262.157972 -106.522774)
		(width 0.10668)
		(layer "F.Cu")
		(net "JTAG_TMS_R")
	)
	(segment
		(start 265.297158 -97.455736)
		(end 264.17143 -97.455736)
		(width 0.10668)
		(layer "F.Cu")
		(net "JTAG_TMS_R")
	)
	(segment
		(start 262.157972 -106.522774)
		(end 261.362698 -105.7275)
		(width 0.10668)
		(layer "F.Cu")
		(net "JTAG_TMS_R")
	)
	(segment
		(start 260.234176 -97.476056)
		(end 260.488176 -97.222056)
		(width 0.10668)
		(layer "F.Cu")
		(net "JTAG_TMS_R")
	)
	(segment
		(start 263.802368 -101.845364)
		(end 265.032236 -101.845364)
		(width 0.10668)
		(layer "F.Cu")
		(net "JTAG_TMS_R")
	)
	(segment
		(start 266.184634 -100.692966)
		(end 266.184634 -98.343212)
		(width 0.10668)
		(layer "F.Cu")
		(net "JTAG_TMS_R")
	)
	(segment
		(start 260.488176 -97.222056)
		(end 262.399526 -97.222056)
		(width 0.10668)
		(layer "F.Cu")
		(net "JTAG_TMS_R")
	)
	(segment
		(start 266.184634 -98.343212)
		(end 265.297158 -97.455736)
		(width 0.10668)
		(layer "F.Cu")
		(net "JTAG_TMS_R")
	)
	(segment
		(start 262.399526 -97.222056)
		(end 262.633206 -97.455736)
		(width 0.10668)
		(layer "F.Cu")
		(net "JTAG_TMS_R")
	)
	(segment
		(start 261.362698 -105.7275)
		(end 261.362698 -104.285034)
		(width 0.10668)
		(layer "F.Cu")
		(net "JTAG_TMS_R")
	)
	(segment
		(start 261.362698 -104.285034)
		(end 263.802368 -101.845364)
		(width 0.10668)
		(layer "F.Cu")
		(net "JTAG_TMS_R")
	)
	(segment
		(start 265.032236 -101.845364)
		(end 266.184634 -100.692966)
		(width 0.10668)
		(layer "F.Cu")
		(net "JTAG_TMS_R")
	)
	(segment
		(start 262.633206 -97.455736)
		(end 264.17143 -97.455736)
		(width 0.10668)
		(layer "F.Cu")
		(net "JTAG_TMS_R")
	)
	(via
		(at 262.399526 -97.222056)
		(size 0.762)
		(drill 0.381)
		(layers "F.Cu" "B.Cu")
		(net "JTAG_TMS_R")
	)
	(segment
		(start 288.798 -93.853)
		(end 281.910028 -93.853)
		(width 0.10668)
		(layer "F.Cu")
		(net "JTAG_TMS")
	)
	(segment
		(start 289.23234 -94.105984)
		(end 289.050984 -94.105984)
		(width 0.10668)
		(layer "F.Cu")
		(net "JTAG_TMS")
	)
	(segment
		(start 253.21387 -103.773986)
		(end 254.19304 -104.753156)
		(width 0.10668)
		(layer "F.Cu")
		(net "JTAG_TMS")
	)
	(segment
		(start 289.360864 -97.319084)
		(end 284.266386 -97.319084)
		(width 0.10668)
		(layer "F.Cu")
		(net "JTAG_TMS")
	)
	(segment
		(start 290.082986 -96.596962)
		(end 289.360864 -97.319084)
		(width 0.10668)
		(layer "F.Cu")
		(net "JTAG_TMS")
	)
	(segment
		(start 257.81 -99.100132)
		(end 259.434076 -97.476056)
		(width 0.10668)
		(layer "F.Cu")
		(net "JTAG_TMS")
	)
	(segment
		(start 276.826218 -88.76919)
		(end 265.398758 -88.76919)
		(width 0.10668)
		(layer "F.Cu")
		(net "JTAG_TMS")
	)
	(segment
		(start 290.082986 -94.95663)
		(end 290.082986 -96.596962)
		(width 0.10668)
		(layer "F.Cu")
		(net "JTAG_TMS")
	)
	(segment
		(start 254.116078 -98.804984)
		(end 253.21387 -99.707192)
		(width 0.10668)
		(layer "F.Cu")
		(net "JTAG_TMS")
	)
	(segment
		(start 253.21387 -101.865938)
		(end 253.21387 -103.773986)
		(width 0.10668)
		(layer "F.Cu")
		(net "JTAG_TMS")
	)
	(segment
		(start 289.23234 -94.105984)
		(end 290.082986 -94.95663)
		(width 0.10668)
		(layer "F.Cu")
		(net "JTAG_TMS")
	)
	(segment
		(start 253.21387 -99.707192)
		(end 253.21387 -101.865938)
		(width 0.10668)
		(layer "F.Cu")
		(net "JTAG_TMS")
	)
	(segment
		(start 257.81 -103.81615)
		(end 257.81 -99.100132)
		(width 0.10668)
		(layer "F.Cu")
		(net "JTAG_TMS")
	)
	(segment
		(start 256.872994 -104.753156)
		(end 257.81 -103.81615)
		(width 0.10668)
		(layer "F.Cu")
		(net "JTAG_TMS")
	)
	(segment
		(start 254.19304 -104.753156)
		(end 256.872994 -104.753156)
		(width 0.10668)
		(layer "F.Cu")
		(net "JTAG_TMS")
	)
	(segment
		(start 265.398758 -88.76919)
		(end 255.362964 -98.804984)
		(width 0.10668)
		(layer "F.Cu")
		(net "JTAG_TMS")
	)
	(segment
		(start 289.050984 -94.105984)
		(end 288.798 -93.853)
		(width 0.10668)
		(layer "F.Cu")
		(net "JTAG_TMS")
	)
	(segment
		(start 281.910028 -93.853)
		(end 276.826218 -88.76919)
		(width 0.10668)
		(layer "F.Cu")
		(net "JTAG_TMS")
	)
	(segment
		(start 255.362964 -98.804984)
		(end 254.116078 -98.804984)
		(width 0.10668)
		(layer "F.Cu")
		(net "JTAG_TMS")
	)
	(via
		(at 289.23234 -94.105984)
		(size 0.762)
		(drill 0.381)
		(layers "F.Cu" "B.Cu")
		(net "JTAG_TMS")
	)
	(segment
		(start 129.092452 -50.674524)
		(end 129.092452 -51.401218)
		(width 0.10668)
		(layer "F.Cu")
		(net "JTAG_TDO")
	)
	(segment
		(start 125.512576 -56.22798)
		(end 125.512576 -55.575708)
		(width 0.10668)
		(layer "F.Cu")
		(net "JTAG_TDO")
	)
	(segment
		(start 129.092452 -51.401218)
		(end 129.083054 -51.410616)
		(width 0.10668)
		(layer "F.Cu")
		(net "JTAG_TDO")
	)
	(via
		(at 129.092452 -50.674524)
		(size 0.508)
		(drill 0.254)
		(layers "F.Cu" "B.Cu")
		(net "JTAG_TDO")
	)
	(via
		(at 125.512576 -56.22798)
		(size 0.508)
		(drill 0.254)
		(layers "F.Cu" "B.Cu")
		(net "JTAG_TDO")
	)
	(segment
		(start 125.512576 -55.703724)
		(end 126.02718 -55.18912)
		(width 0.10668)
		(layer "B.Cu")
		(net "JTAG_TDO")
	)
	(segment
		(start 126.02718 -55.18912)
		(end 126.02718 -53.94706)
		(width 0.10668)
		(layer "B.Cu")
		(net "JTAG_TDO")
	)
	(segment
		(start 125.512576 -56.22798)
		(end 125.512576 -55.703724)
		(width 0.10668)
		(layer "B.Cu")
		(net "JTAG_TDO")
	)
	(segment
		(start 129.092452 -52.271168)
		(end 129.092452 -50.674524)
		(width 0.10668)
		(layer "B.Cu")
		(net "JTAG_TDO")
	)
	(segment
		(start 126.30404 -53.6702)
		(end 127.69342 -53.6702)
		(width 0.10668)
		(layer "B.Cu")
		(net "JTAG_TDO")
	)
	(segment
		(start 126.02718 -53.94706)
		(end 126.30404 -53.6702)
		(width 0.10668)
		(layer "B.Cu")
		(net "JTAG_TDO")
	)
	(segment
		(start 127.69342 -53.6702)
		(end 129.092452 -52.271168)
		(width 0.10668)
		(layer "B.Cu")
		(net "JTAG_TDO")
	)
	(segment
		(start 144.982946 -56.875934)
		(end 144.476216 -56.369204)
		(width 0.10668)
		(layer "F.Cu")
		(net "JTAG_TDI_R")
	)
	(segment
		(start 124.87529 -55.658258)
		(end 124.39269 -55.175658)
		(width 0.10668)
		(layer "F.Cu")
		(net "JTAG_TDI_R")
	)
	(segment
		(start 124.87529 -57.39638)
		(end 124.87529 -55.658258)
		(width 0.10668)
		(layer "F.Cu")
		(net "JTAG_TDI_R")
	)
	(segment
		(start 124.39269 -55.175658)
		(end 124.027438 -55.175658)
		(width 0.10668)
		(layer "F.Cu")
		(net "JTAG_TDI_R")
	)
	(segment
		(start 145.374868 -56.875934)
		(end 144.982946 -56.875934)
		(width 0.10668)
		(layer "F.Cu")
		(net "JTAG_TDI_R")
	)
	(segment
		(start 126.259844 -52.14239)
		(end 126.195074 -52.07762)
		(width 0.10668)
		(layer "F.Cu")
		(net "JTAG_TDI_R")
	)
	(segment
		(start 127.305054 -52.14239)
		(end 126.259844 -52.14239)
		(width 0.10668)
		(layer "F.Cu")
		(net "JTAG_TDI_R")
	)
	(via
		(at 126.195074 -52.07762)
		(size 0.508)
		(drill 0.254)
		(layers "F.Cu" "B.Cu")
		(net "JTAG_TDI_R")
	)
	(via
		(at 144.476216 -56.369204)
		(size 0.508)
		(drill 0.254)
		(layers "F.Cu" "B.Cu")
		(net "JTAG_TDI_R")
	)
	(via
		(at 124.87529 -57.39638)
		(size 0.508)
		(drill 0.254)
		(layers "F.Cu" "B.Cu")
		(net "JTAG_TDI_R")
	)
	(segment
		(start 126.130304 -52.01285)
		(end 126.195074 -52.07762)
		(width 0.10668)
		(layer "B.Cu")
		(net "JTAG_TDI_R")
	)
	(segment
		(start 125.48743 -52.785264)
		(end 126.195074 -52.07762)
		(width 0.10668)
		(layer "B.Cu")
		(net "JTAG_TDI_R")
	)
	(segment
		(start 139.65936 -54.79796)
		(end 138.744452 -54.79796)
		(width 0.10668)
		(layer "B.Cu")
		(net "JTAG_TDI_R")
	)
	(segment
		(start 125.48743 -55.08371)
		(end 125.48743 -52.785264)
		(width 0.10668)
		(layer "B.Cu")
		(net "JTAG_TDI_R")
	)
	(segment
		(start 129.167636 -48.116744)
		(end 126.130304 -51.154076)
		(width 0.10668)
		(layer "B.Cu")
		(net "JTAG_TDI_R")
	)
	(segment
		(start 144.476216 -56.369204)
		(end 141.230604 -56.369204)
		(width 0.10668)
		(layer "B.Cu")
		(net "JTAG_TDI_R")
	)
	(segment
		(start 124.63272 -57.15381)
		(end 124.63272 -55.93842)
		(width 0.10668)
		(layer "B.Cu")
		(net "JTAG_TDI_R")
	)
	(segment
		(start 138.744452 -54.79796)
		(end 132.063236 -48.116744)
		(width 0.10668)
		(layer "B.Cu")
		(net "JTAG_TDI_R")
	)
	(segment
		(start 141.230604 -56.369204)
		(end 139.65936 -54.79796)
		(width 0.10668)
		(layer "B.Cu")
		(net "JTAG_TDI_R")
	)
	(segment
		(start 126.130304 -51.154076)
		(end 126.130304 -52.01285)
		(width 0.10668)
		(layer "B.Cu")
		(net "JTAG_TDI_R")
	)
	(segment
		(start 124.87529 -57.39638)
		(end 124.63272 -57.15381)
		(width 0.10668)
		(layer "B.Cu")
		(net "JTAG_TDI_R")
	)
	(segment
		(start 132.063236 -48.116744)
		(end 129.167636 -48.116744)
		(width 0.10668)
		(layer "B.Cu")
		(net "JTAG_TDI_R")
	)
	(segment
		(start 124.63272 -55.93842)
		(end 125.48743 -55.08371)
		(width 0.10668)
		(layer "B.Cu")
		(net "JTAG_TDI_R")
	)
	(segment
		(start 128.105154 -52.14239)
		(end 128.105154 -53.15839)
		(width 0.10668)
		(layer "F.Cu")
		(net "JTAG_TDI")
	)
	(segment
		(start 129.667254 -52.909216)
		(end 129.495042 -52.737004)
		(width 0.10668)
		(layer "F.Cu")
		(net "JTAG_TDI")
	)
	(segment
		(start 129.667254 -53.274468)
		(end 129.667254 -52.909216)
		(width 0.10668)
		(layer "F.Cu")
		(net "JTAG_TDI")
	)
	(segment
		(start 128.65735 -53.15839)
		(end 128.105154 -53.15839)
		(width 0.10668)
		(layer "F.Cu")
		(net "JTAG_TDI")
	)
	(segment
		(start 129.078736 -52.737004)
		(end 128.65735 -53.15839)
		(width 0.10668)
		(layer "F.Cu")
		(net "JTAG_TDI")
	)
	(segment
		(start 128.105154 -52.14239)
		(end 128.105154 -51.505104)
		(width 0.10668)
		(layer "F.Cu")
		(net "JTAG_TDI")
	)
	(segment
		(start 129.495042 -52.737004)
		(end 129.078736 -52.737004)
		(width 0.10668)
		(layer "F.Cu")
		(net "JTAG_TDI")
	)
	(via
		(at 128.105154 -51.505104)
		(size 0.508)
		(drill 0.254)
		(layers "F.Cu" "B.Cu")
		(net "JTAG_TDI")
	)
	(segment
		(start 264.26795 -105.872788)
		(end 262.37057 -105.872788)
		(width 0.10668)
		(layer "F.Cu")
		(net "JTAG_TCK_R")
	)
	(segment
		(start 262.37057 -105.872788)
		(end 261.822184 -105.324402)
		(width 0.10668)
		(layer "F.Cu")
		(net "JTAG_TCK_R")
	)
	(segment
		(start 265.59891 -96.80575)
		(end 264.17143 -96.80575)
		(width 0.10668)
		(layer "F.Cu")
		(net "JTAG_TCK_R")
	)
	(segment
		(start 265.222736 -102.30485)
		(end 266.64412 -100.883466)
		(width 0.10668)
		(layer "F.Cu")
		(net "JTAG_TCK_R")
	)
	(segment
		(start 262.506968 -96.206056)
		(end 263.106662 -96.80575)
		(width 0.10668)
		(layer "F.Cu")
		(net "JTAG_TCK_R")
	)
	(segment
		(start 260.234176 -96.206056)
		(end 261.434326 -96.206056)
		(width 0.10668)
		(layer "F.Cu")
		(net "JTAG_TCK_R")
	)
	(segment
		(start 266.64412 -100.883466)
		(end 266.64412 -97.85096)
		(width 0.10668)
		(layer "F.Cu")
		(net "JTAG_TCK_R")
	)
	(segment
		(start 261.822184 -104.475534)
		(end 263.992868 -102.30485)
		(width 0.10668)
		(layer "F.Cu")
		(net "JTAG_TCK_R")
	)
	(segment
		(start 261.822184 -105.324402)
		(end 261.822184 -104.475534)
		(width 0.10668)
		(layer "F.Cu")
		(net "JTAG_TCK_R")
	)
	(segment
		(start 266.64412 -97.85096)
		(end 265.59891 -96.80575)
		(width 0.10668)
		(layer "F.Cu")
		(net "JTAG_TCK_R")
	)
	(segment
		(start 261.434326 -96.206056)
		(end 262.506968 -96.206056)
		(width 0.10668)
		(layer "F.Cu")
		(net "JTAG_TCK_R")
	)
	(segment
		(start 263.992868 -102.30485)
		(end 265.222736 -102.30485)
		(width 0.10668)
		(layer "F.Cu")
		(net "JTAG_TCK_R")
	)
	(segment
		(start 263.106662 -96.80575)
		(end 264.17143 -96.80575)
		(width 0.10668)
		(layer "F.Cu")
		(net "JTAG_TCK_R")
	)
	(via
		(at 261.434326 -96.206056)
		(size 0.762)
		(drill 0.381)
		(layers "F.Cu" "B.Cu")
		(net "JTAG_TCK_R")
	)
	(segment
		(start 284.266386 -96.669098)
		(end 285.59125 -96.669098)
		(width 0.10668)
		(layer "F.Cu")
		(net "JTAG_TCK")
	)
	(segment
		(start 265.754104 -89.18067)
		(end 253.863856 -101.070918)
		(width 0.10668)
		(layer "F.Cu")
		(net "JTAG_TCK")
	)
	(segment
		(start 287.86582 -96.655382)
		(end 287.469834 -96.655382)
		(width 0.10668)
		(layer "F.Cu")
		(net "JTAG_TCK")
	)
	(segment
		(start 254.4572 -104.10317)
		(end 256.571496 -104.10317)
		(width 0.10668)
		(layer "F.Cu")
		(net "JTAG_TCK")
	)
	(segment
		(start 285.59125 -96.669098)
		(end 286.5374 -95.722948)
		(width 0.10668)
		(layer "F.Cu")
		(net "JTAG_TCK")
	)
	(segment
		(start 287.469834 -96.655382)
		(end 286.5374 -95.722948)
		(width 0.10668)
		(layer "F.Cu")
		(net "JTAG_TCK")
	)
	(segment
		(start 259.434076 -96.520508)
		(end 259.434076 -96.206056)
		(width 0.10668)
		(layer "F.Cu")
		(net "JTAG_TCK")
	)
	(segment
		(start 257.3274 -103.347266)
		(end 257.3274 -98.627184)
		(width 0.10668)
		(layer "F.Cu")
		(net "JTAG_TCK")
	)
	(segment
		(start 287.86582 -96.655382)
		(end 287.86582 -94.488)
		(width 0.10668)
		(layer "F.Cu")
		(net "JTAG_TCK")
	)
	(segment
		(start 253.863856 -101.865938)
		(end 253.863856 -103.509826)
		(width 0.10668)
		(layer "F.Cu")
		(net "JTAG_TCK")
	)
	(segment
		(start 287.73882 -94.361)
		(end 281.617928 -94.361)
		(width 0.10668)
		(layer "F.Cu")
		(net "JTAG_TCK")
	)
	(segment
		(start 257.3274 -98.627184)
		(end 259.434076 -96.520508)
		(width 0.10668)
		(layer "F.Cu")
		(net "JTAG_TCK")
	)
	(segment
		(start 276.437598 -89.18067)
		(end 265.754104 -89.18067)
		(width 0.10668)
		(layer "F.Cu")
		(net "JTAG_TCK")
	)
	(segment
		(start 281.617928 -94.361)
		(end 276.437598 -89.18067)
		(width 0.10668)
		(layer "F.Cu")
		(net "JTAG_TCK")
	)
	(segment
		(start 256.571496 -104.10317)
		(end 257.3274 -103.347266)
		(width 0.10668)
		(layer "F.Cu")
		(net "JTAG_TCK")
	)
	(segment
		(start 253.863856 -103.509826)
		(end 254.4572 -104.10317)
		(width 0.10668)
		(layer "F.Cu")
		(net "JTAG_TCK")
	)
	(segment
		(start 253.863856 -101.070918)
		(end 253.863856 -101.865938)
		(width 0.10668)
		(layer "F.Cu")
		(net "JTAG_TCK")
	)
	(segment
		(start 287.86582 -94.488)
		(end 287.73882 -94.361)
		(width 0.10668)
		(layer "F.Cu")
		(net "JTAG_TCK")
	)
	(via
		(at 286.5374 -95.722948)
		(size 0.762)
		(drill 0.381)
		(layers "F.Cu" "B.Cu")
		(net "JTAG_TCK")
	)
	(segment
		(start 174.972218 -115.057936)
		(end 179.11699 -115.057936)
		(width 0.10668)
		(layer "F.Cu")
		(net "JTAG_SCM_TRST_R_N")
	)
	(segment
		(start 171.59605 -114.264948)
		(end 172.157898 -114.826796)
		(width 0.10668)
		(layer "F.Cu")
		(net "JTAG_SCM_TRST_R_N")
	)
	(segment
		(start 174.741078 -114.826796)
		(end 174.972218 -115.057936)
		(width 0.10668)
		(layer "F.Cu")
		(net "JTAG_SCM_TRST_R_N")
	)
	(segment
		(start 172.157898 -114.826796)
		(end 172.7835 -114.826796)
		(width 0.10668)
		(layer "F.Cu")
		(net "JTAG_SCM_TRST_R_N")
	)
	(segment
		(start 179.11699 -115.057936)
		(end 179.52212 -114.652806)
		(width 0.10668)
		(layer "F.Cu")
		(net "JTAG_SCM_TRST_R_N")
	)
	(segment
		(start 172.7835 -114.826796)
		(end 174.741078 -114.826796)
		(width 0.10668)
		(layer "F.Cu")
		(net "JTAG_SCM_TRST_R_N")
	)
	(via
		(at 172.7835 -114.826796)
		(size 0.762)
		(drill 0.381)
		(layers "F.Cu" "B.Cu")
		(net "JTAG_SCM_TRST_R_N")
	)
	(segment
		(start 170.79595 -114.264948)
		(end 170.819064 -114.288062)
		(width 0.10668)
		(layer "F.Cu")
		(net "JTAG_SCM_TRST_N")
	)
	(segment
		(start 269.868142 -107.173014)
		(end 272.470626 -107.173014)
		(width 0.10668)
		(layer "F.Cu")
		(net "JTAG_SCM_TRST_N")
	)
	(segment
		(start 272.470626 -107.173014)
		(end 272.475452 -107.168188)
		(width 0.10668)
		(layer "F.Cu")
		(net "JTAG_SCM_TRST_N")
	)
	(segment
		(start 170.74134 -114.772948)
		(end 168.443148 -114.772948)
		(width 0.10668)
		(layer "F.Cu")
		(net "JTAG_SCM_TRST_N")
	)
	(segment
		(start 170.819064 -114.695224)
		(end 170.74134 -114.772948)
		(width 0.10668)
		(layer "F.Cu")
		(net "JTAG_SCM_TRST_N")
	)
	(segment
		(start 170.819064 -114.288062)
		(end 170.819064 -114.695224)
		(width 0.10668)
		(layer "F.Cu")
		(net "JTAG_SCM_TRST_N")
	)
	(segment
		(start 168.443148 -114.772948)
		(end 168.148 -114.4778)
		(width 0.10668)
		(layer "F.Cu")
		(net "JTAG_SCM_TRST_N")
	)
	(segment
		(start 168.148 -114.4778)
		(end 168.148 -114.264948)
		(width 0.10668)
		(layer "F.Cu")
		(net "JTAG_SCM_TRST_N")
	)
	(via
		(at 272.475452 -107.168188)
		(size 0.508)
		(drill 0.254)
		(layers "F.Cu" "B.Cu")
		(net "JTAG_SCM_TRST_N")
	)
	(via
		(at 168.148 -114.264948)
		(size 0.508)
		(drill 0.254)
		(layers "F.Cu" "B.Cu")
		(net "JTAG_SCM_TRST_N")
	)
	(segment
		(start 167.451532 -114.264948)
		(end 168.148 -114.264948)
		(width 0.11684)
		(layer "In2.Cu")
		(net "JTAG_SCM_TRST_N")
	)
	(segment
		(start 165.195758 -113.711228)
		(end 165.998144 -113.711228)
		(width 0.11684)
		(layer "In2.Cu")
		(net "JTAG_SCM_TRST_N")
	)
	(segment
		(start 215.87587 -106.083862)
		(end 213.289388 -103.49738)
		(width 0.11684)
		(layer "In2.Cu")
		(net "JTAG_SCM_TRST_N")
	)
	(segment
		(start 213.289388 -103.49738)
		(end 209.343498 -103.49738)
		(width 0.11684)
		(layer "In2.Cu")
		(net "JTAG_SCM_TRST_N")
	)
	(segment
		(start 208.997042 -102.597204)
		(end 207.921606 -101.521768)
		(width 0.11684)
		(layer "In2.Cu")
		(net "JTAG_SCM_TRST_N")
	)
	(segment
		(start 189.497208 -101.50856)
		(end 187.345828 -103.65994)
		(width 0.11684)
		(layer "In2.Cu")
		(net "JTAG_SCM_TRST_N")
	)
	(segment
		(start 166.469568 -108.797344)
		(end 166.469568 -109.768894)
		(width 0.11684)
		(layer "In2.Cu")
		(net "JTAG_SCM_TRST_N")
	)
	(segment
		(start 164.834316 -111.404146)
		(end 164.834316 -113.349786)
		(width 0.11684)
		(layer "In2.Cu")
		(net "JTAG_SCM_TRST_N")
	)
	(segment
		(start 207.921606 -101.521768)
		(end 204.136752 -101.521768)
		(width 0.11684)
		(layer "In2.Cu")
		(net "JTAG_SCM_TRST_N")
	)
	(segment
		(start 166.02202 -113.687352)
		(end 166.873936 -113.687352)
		(width 0.11684)
		(layer "In2.Cu")
		(net "JTAG_SCM_TRST_N")
	)
	(segment
		(start 262.806434 -114.186716)
		(end 259.664962 -111.045244)
		(width 0.11684)
		(layer "In2.Cu")
		(net "JTAG_SCM_TRST_N")
	)
	(segment
		(start 209.343498 -103.49738)
		(end 208.997042 -103.150924)
		(width 0.11684)
		(layer "In2.Cu")
		(net "JTAG_SCM_TRST_N")
	)
	(segment
		(start 166.469568 -109.768894)
		(end 164.834316 -111.404146)
		(width 0.11684)
		(layer "In2.Cu")
		(net "JTAG_SCM_TRST_N")
	)
	(segment
		(start 174.99965 -103.65994)
		(end 173.091348 -105.568242)
		(width 0.11684)
		(layer "In2.Cu")
		(net "JTAG_SCM_TRST_N")
	)
	(segment
		(start 164.834316 -113.349786)
		(end 165.195758 -113.711228)
		(width 0.11684)
		(layer "In2.Cu")
		(net "JTAG_SCM_TRST_N")
	)
	(segment
		(start 218.266772 -110.517178)
		(end 215.87587 -108.126276)
		(width 0.11684)
		(layer "In2.Cu")
		(net "JTAG_SCM_TRST_N")
	)
	(segment
		(start 173.091348 -105.568242)
		(end 169.69867 -105.568242)
		(width 0.11684)
		(layer "In2.Cu")
		(net "JTAG_SCM_TRST_N")
	)
	(segment
		(start 169.69867 -105.568242)
		(end 166.469568 -108.797344)
		(width 0.11684)
		(layer "In2.Cu")
		(net "JTAG_SCM_TRST_N")
	)
	(segment
		(start 165.998144 -113.711228)
		(end 166.02202 -113.687352)
		(width 0.11684)
		(layer "In2.Cu")
		(net "JTAG_SCM_TRST_N")
	)
	(segment
		(start 259.664962 -111.045244)
		(end 254.505968 -111.045244)
		(width 0.11684)
		(layer "In2.Cu")
		(net "JTAG_SCM_TRST_N")
	)
	(segment
		(start 272.475452 -107.168188)
		(end 265.456924 -114.186716)
		(width 0.11684)
		(layer "In2.Cu")
		(net "JTAG_SCM_TRST_N")
	)
	(segment
		(start 254.505968 -111.045244)
		(end 253.977902 -110.517178)
		(width 0.11684)
		(layer "In2.Cu")
		(net "JTAG_SCM_TRST_N")
	)
	(segment
		(start 215.87587 -108.126276)
		(end 215.87587 -106.083862)
		(width 0.11684)
		(layer "In2.Cu")
		(net "JTAG_SCM_TRST_N")
	)
	(segment
		(start 166.873936 -113.687352)
		(end 167.451532 -114.264948)
		(width 0.11684)
		(layer "In2.Cu")
		(net "JTAG_SCM_TRST_N")
	)
	(segment
		(start 187.345828 -103.65994)
		(end 174.99965 -103.65994)
		(width 0.11684)
		(layer "In2.Cu")
		(net "JTAG_SCM_TRST_N")
	)
	(segment
		(start 208.997042 -103.150924)
		(end 208.997042 -102.597204)
		(width 0.11684)
		(layer "In2.Cu")
		(net "JTAG_SCM_TRST_N")
	)
	(segment
		(start 204.123544 -101.50856)
		(end 189.497208 -101.50856)
		(width 0.11684)
		(layer "In2.Cu")
		(net "JTAG_SCM_TRST_N")
	)
	(segment
		(start 265.456924 -114.186716)
		(end 262.806434 -114.186716)
		(width 0.11684)
		(layer "In2.Cu")
		(net "JTAG_SCM_TRST_N")
	)
	(segment
		(start 253.977902 -110.517178)
		(end 218.266772 -110.517178)
		(width 0.11684)
		(layer "In2.Cu")
		(net "JTAG_SCM_TRST_N")
	)
	(segment
		(start 204.136752 -101.521768)
		(end 204.123544 -101.50856)
		(width 0.11684)
		(layer "In2.Cu")
		(net "JTAG_SCM_TRST_N")
	)
	(segment
		(start 155.09621 -12.206478)
		(end 155.09621 -10.283952)
		(width 0.10668)
		(layer "F.Cu")
		(net "JTAG_SCM_TMS")
	)
	(segment
		(start 106.04881 -59.802268)
		(end 106.70921 -59.802268)
		(width 0.10668)
		(layer "F.Cu")
		(net "JTAG_SCM_TMS")
	)
	(segment
		(start 155.09621 -10.283952)
		(end 155.286456 -10.093706)
		(width 0.10668)
		(layer "F.Cu")
		(net "JTAG_SCM_TMS")
	)
	(segment
		(start 155.286456 -10.093706)
		(end 157.113732 -10.093706)
		(width 0.10668)
		(layer "F.Cu")
		(net "JTAG_SCM_TMS")
	)
	(segment
		(start 108.940346 -59.802268)
		(end 106.70921 -59.802268)
		(width 0.10668)
		(layer "F.Cu")
		(net "JTAG_SCM_TMS")
	)
	(segment
		(start 157.113732 -10.093706)
		(end 157.157928 -10.137902)
		(width 0.10668)
		(layer "F.Cu")
		(net "JTAG_SCM_TMS")
	)
	(segment
		(start 155.057094 -12.245594)
		(end 155.09621 -12.206478)
		(width 0.10668)
		(layer "F.Cu")
		(net "JTAG_SCM_TMS")
	)
	(segment
		(start 155.057094 -13.599922)
		(end 155.057094 -12.245594)
		(width 0.10668)
		(layer "F.Cu")
		(net "JTAG_SCM_TMS")
	)
	(via
		(at 157.157928 -10.137902)
		(size 0.508)
		(drill 0.254)
		(layers "F.Cu" "B.Cu")
		(net "JTAG_SCM_TMS")
	)
	(via
		(at 106.70921 -59.802268)
		(size 0.508)
		(drill 0.254)
		(layers "F.Cu" "B.Cu")
		(net "JTAG_SCM_TMS")
	)
	(segment
		(start 145.39214 -39.960042)
		(end 145.39214 -37.07638)
		(width 0.11684)
		(layer "In4.Cu")
		(net "JTAG_SCM_TMS")
	)
	(segment
		(start 106.874818 -59.63666)
		(end 112.81918 -59.63666)
		(width 0.11684)
		(layer "In4.Cu")
		(net "JTAG_SCM_TMS")
	)
	(segment
		(start 148.528532 -13.664438)
		(end 148.528532 -11.592052)
		(width 0.11684)
		(layer "In4.Cu")
		(net "JTAG_SCM_TMS")
	)
	(segment
		(start 148.528532 -11.592052)
		(end 150.36927 -9.751314)
		(width 0.11684)
		(layer "In4.Cu")
		(net "JTAG_SCM_TMS")
	)
	(segment
		(start 106.70921 -59.802268)
		(end 106.874818 -59.63666)
		(width 0.11684)
		(layer "In4.Cu")
		(net "JTAG_SCM_TMS")
	)
	(segment
		(start 129.363724 -47.391066)
		(end 144.040606 -41.311576)
		(width 0.11684)
		(layer "In4.Cu")
		(net "JTAG_SCM_TMS")
	)
	(segment
		(start 118.249954 -56.375808)
		(end 119.494046 -55.131716)
		(width 0.11684)
		(layer "In4.Cu")
		(net "JTAG_SCM_TMS")
	)
	(segment
		(start 119.494046 -55.131716)
		(end 121.623074 -55.131716)
		(width 0.11684)
		(layer "In4.Cu")
		(net "JTAG_SCM_TMS")
	)
	(segment
		(start 144.7038 -17.48917)
		(end 148.528532 -13.664438)
		(width 0.11684)
		(layer "In4.Cu")
		(net "JTAG_SCM_TMS")
	)
	(segment
		(start 145.39214 -37.07638)
		(end 142.002002 -33.686242)
		(width 0.11684)
		(layer "In4.Cu")
		(net "JTAG_SCM_TMS")
	)
	(segment
		(start 156.77134 -9.751314)
		(end 157.157928 -10.137902)
		(width 0.11684)
		(layer "In4.Cu")
		(net "JTAG_SCM_TMS")
	)
	(segment
		(start 116.080032 -56.375808)
		(end 118.249954 -56.375808)
		(width 0.11684)
		(layer "In4.Cu")
		(net "JTAG_SCM_TMS")
	)
	(segment
		(start 144.7038 -27.190954)
		(end 144.7038 -17.48917)
		(width 0.11684)
		(layer "In4.Cu")
		(net "JTAG_SCM_TMS")
	)
	(segment
		(start 142.002002 -29.892752)
		(end 144.7038 -27.190954)
		(width 0.11684)
		(layer "In4.Cu")
		(net "JTAG_SCM_TMS")
	)
	(segment
		(start 144.040606 -41.311576)
		(end 145.39214 -39.960042)
		(width 0.11684)
		(layer "In4.Cu")
		(net "JTAG_SCM_TMS")
	)
	(segment
		(start 150.36927 -9.751314)
		(end 156.77134 -9.751314)
		(width 0.11684)
		(layer "In4.Cu")
		(net "JTAG_SCM_TMS")
	)
	(segment
		(start 112.81918 -59.63666)
		(end 116.080032 -56.375808)
		(width 0.11684)
		(layer "In4.Cu")
		(net "JTAG_SCM_TMS")
	)
	(segment
		(start 121.623074 -55.131716)
		(end 129.363724 -47.391066)
		(width 0.11684)
		(layer "In4.Cu")
		(net "JTAG_SCM_TMS")
	)
	(segment
		(start 142.002002 -33.686242)
		(end 142.002002 -29.892752)
		(width 0.11684)
		(layer "In4.Cu")
		(net "JTAG_SCM_TMS")
	)
	(segment
		(start 127.053086 -60.482226)
		(end 126.392686 -60.482226)
		(width 0.10668)
		(layer "F.Cu")
		(net "JTAG_SCM_TDO")
	)
	(segment
		(start 128.76403 -60.482226)
		(end 127.053086 -60.482226)
		(width 0.10668)
		(layer "F.Cu")
		(net "JTAG_SCM_TDO")
	)
	(via
		(at 127.053086 -60.482226)
		(size 0.508)
		(drill 0.254)
		(layers "F.Cu" "B.Cu")
		(net "JTAG_SCM_TDO")
	)
	(via
		(at 155.602432 -9.134094)
		(size 0.508)
		(drill 0.254)
		(layers "F.Cu" "B.Cu")
		(net "JTAG_SCM_TDO")
	)
	(via
		(at 128.35001 -50.023776)
		(size 0.508)
		(drill 0.254)
		(layers "F.Cu" "B.Cu")
		(net "JTAG_SCM_TDO")
	)
	(segment
		(start 155.548838 -9.0805)
		(end 155.602432 -9.134094)
		(width 0.10668)
		(layer "B.Cu")
		(net "JTAG_SCM_TDO")
	)
	(segment
		(start 154.577288 -9.0805)
		(end 155.548838 -9.0805)
		(width 0.10668)
		(layer "B.Cu")
		(net "JTAG_SCM_TDO")
	)
	(segment
		(start 138.95324 -27.452574)
		(end 139.2682 -27.137614)
		(width 0.11684)
		(layer "In2.Cu")
		(net "JTAG_SCM_TDO")
	)
	(segment
		(start 138.95324 -30.071822)
		(end 138.95324 -27.452574)
		(width 0.11684)
		(layer "In2.Cu")
		(net "JTAG_SCM_TDO")
	)
	(segment
		(start 142.922498 -18.975832)
		(end 142.922498 -16.27886)
		(width 0.11684)
		(layer "In2.Cu")
		(net "JTAG_SCM_TDO")
	)
	(segment
		(start 129.074926 -49.715928)
		(end 138.5062 -40.284654)
		(width 0.11684)
		(layer "In2.Cu")
		(net "JTAG_SCM_TDO")
	)
	(segment
		(start 143.341598 -12.814808)
		(end 147.986242 -12.814808)
		(width 0.11684)
		(layer "In2.Cu")
		(net "JTAG_SCM_TDO")
	)
	(segment
		(start 138.5062 -36.137342)
		(end 139.2682 -35.375342)
		(width 0.11684)
		(layer "In2.Cu")
		(net "JTAG_SCM_TDO")
	)
	(segment
		(start 142.922498 -16.27886)
		(end 142.149576 -15.505938)
		(width 0.11684)
		(layer "In2.Cu")
		(net "JTAG_SCM_TDO")
	)
	(segment
		(start 142.149576 -14.00683)
		(end 143.341598 -12.814808)
		(width 0.11684)
		(layer "In2.Cu")
		(net "JTAG_SCM_TDO")
	)
	(segment
		(start 151.666956 -9.134094)
		(end 155.602432 -9.134094)
		(width 0.11684)
		(layer "In2.Cu")
		(net "JTAG_SCM_TDO")
	)
	(segment
		(start 128.35001 -50.023776)
		(end 128.657858 -49.715928)
		(width 0.11684)
		(layer "In2.Cu")
		(net "JTAG_SCM_TDO")
	)
	(segment
		(start 138.5062 -40.284654)
		(end 138.5062 -36.137342)
		(width 0.11684)
		(layer "In2.Cu")
		(net "JTAG_SCM_TDO")
	)
	(segment
		(start 139.2682 -35.375342)
		(end 139.2682 -30.386782)
		(width 0.11684)
		(layer "In2.Cu")
		(net "JTAG_SCM_TDO")
	)
	(segment
		(start 142.149576 -15.505938)
		(end 142.149576 -14.00683)
		(width 0.11684)
		(layer "In2.Cu")
		(net "JTAG_SCM_TDO")
	)
	(segment
		(start 128.657858 -49.715928)
		(end 129.074926 -49.715928)
		(width 0.11684)
		(layer "In2.Cu")
		(net "JTAG_SCM_TDO")
	)
	(segment
		(start 139.2682 -27.137614)
		(end 139.2682 -22.63013)
		(width 0.11684)
		(layer "In2.Cu")
		(net "JTAG_SCM_TDO")
	)
	(segment
		(start 147.986242 -12.814808)
		(end 151.666956 -9.134094)
		(width 0.11684)
		(layer "In2.Cu")
		(net "JTAG_SCM_TDO")
	)
	(segment
		(start 139.2682 -30.386782)
		(end 138.95324 -30.071822)
		(width 0.11684)
		(layer "In2.Cu")
		(net "JTAG_SCM_TDO")
	)
	(segment
		(start 139.2682 -22.63013)
		(end 142.922498 -18.975832)
		(width 0.11684)
		(layer "In2.Cu")
		(net "JTAG_SCM_TDO")
	)
	(segment
		(start 127.3556 -51.018186)
		(end 128.35001 -50.023776)
		(width 0.11684)
		(layer "In4.Cu")
		(net "JTAG_SCM_TDO")
	)
	(segment
		(start 127.67818 -55.64378)
		(end 127.3556 -55.3212)
		(width 0.11684)
		(layer "In4.Cu")
		(net "JTAG_SCM_TDO")
	)
	(segment
		(start 127.053086 -60.482226)
		(end 127.67818 -59.857132)
		(width 0.11684)
		(layer "In4.Cu")
		(net "JTAG_SCM_TDO")
	)
	(segment
		(start 127.67818 -59.857132)
		(end 127.67818 -55.64378)
		(width 0.11684)
		(layer "In4.Cu")
		(net "JTAG_SCM_TDO")
	)
	(segment
		(start 127.3556 -55.3212)
		(end 127.3556 -51.018186)
		(width 0.11684)
		(layer "In4.Cu")
		(net "JTAG_SCM_TDO")
	)
	(segment
		(start 135.706358 -59.83224)
		(end 134.614158 -59.83224)
		(width 0.10668)
		(layer "F.Cu")
		(net "JTAG_SCM_TDI")
	)
	(segment
		(start 135.706358 -59.83224)
		(end 138.026902 -59.83224)
		(width 0.10668)
		(layer "F.Cu")
		(net "JTAG_SCM_TDI")
	)
	(via
		(at 131.978654 -49.813718)
		(size 0.508)
		(drill 0.254)
		(layers "F.Cu" "B.Cu")
		(net "JTAG_SCM_TDI")
	)
	(via
		(at 135.706358 -59.83224)
		(size 0.508)
		(drill 0.254)
		(layers "F.Cu" "B.Cu")
		(net "JTAG_SCM_TDI")
	)
	(segment
		(start 131.468114 -49.813718)
		(end 131.978654 -49.813718)
		(width 0.10668)
		(layer "B.Cu")
		(net "JTAG_SCM_TDI")
	)
	(segment
		(start 130.657092 -49.902872)
		(end 131.37896 -49.902872)
		(width 0.10668)
		(layer "B.Cu")
		(net "JTAG_SCM_TDI")
	)
	(segment
		(start 131.37896 -49.902872)
		(end 131.468114 -49.813718)
		(width 0.10668)
		(layer "B.Cu")
		(net "JTAG_SCM_TDI")
	)
	(segment
		(start 132.8801 -57.005982)
		(end 132.8801 -50.715164)
		(width 0.11684)
		(layer "In4.Cu")
		(net "JTAG_SCM_TDI")
	)
	(segment
		(start 132.8801 -50.715164)
		(end 131.978654 -49.813718)
		(width 0.11684)
		(layer "In4.Cu")
		(net "JTAG_SCM_TDI")
	)
	(segment
		(start 135.706358 -59.83224)
		(end 132.8801 -57.005982)
		(width 0.11684)
		(layer "In4.Cu")
		(net "JTAG_SCM_TDI")
	)
	(segment
		(start 115.882674 -59.152282)
		(end 114.790474 -59.152282)
		(width 0.10668)
		(layer "F.Cu")
		(net "JTAG_SCM_TCK")
	)
	(segment
		(start 155.524454 -13.467334)
		(end 155.524454 -11.036046)
		(width 0.10668)
		(layer "F.Cu")
		(net "JTAG_SCM_TCK")
	)
	(segment
		(start 155.657042 -13.599922)
		(end 155.524454 -13.467334)
		(width 0.10668)
		(layer "F.Cu")
		(net "JTAG_SCM_TCK")
	)
	(segment
		(start 117.759734 -59.152282)
		(end 115.882674 -59.152282)
		(width 0.10668)
		(layer "F.Cu")
		(net "JTAG_SCM_TCK")
	)
	(segment
		(start 155.524454 -11.036046)
		(end 155.70835 -10.85215)
		(width 0.10668)
		(layer "F.Cu")
		(net "JTAG_SCM_TCK")
	)
	(segment
		(start 118.318534 -58.868056)
		(end 118.04396 -58.868056)
		(width 0.10668)
		(layer "F.Cu")
		(net "JTAG_SCM_TCK")
	)
	(segment
		(start 118.318534 -58.868056)
		(end 118.318534 -59.884056)
		(width 0.10668)
		(layer "F.Cu")
		(net "JTAG_SCM_TCK")
	)
	(segment
		(start 118.04396 -58.868056)
		(end 117.759734 -59.152282)
		(width 0.10668)
		(layer "F.Cu")
		(net "JTAG_SCM_TCK")
	)
	(via
		(at 155.70835 -10.85215)
		(size 0.508)
		(drill 0.254)
		(layers "F.Cu" "B.Cu")
		(net "JTAG_SCM_TCK")
	)
	(via
		(at 115.882674 -59.152282)
		(size 0.508)
		(drill 0.254)
		(layers "F.Cu" "B.Cu")
		(net "JTAG_SCM_TCK")
	)
	(segment
		(start 115.882674 -59.152282)
		(end 117.744748 -59.152282)
		(width 0.11684)
		(layer "In4.Cu")
		(net "JTAG_SCM_TCK")
	)
	(segment
		(start 145.19529 -17.611852)
		(end 149.29612 -13.511022)
		(width 0.11684)
		(layer "In4.Cu")
		(net "JTAG_SCM_TCK")
	)
	(segment
		(start 142.512542 -33.370266)
		(end 142.512542 -29.978858)
		(width 0.11684)
		(layer "In4.Cu")
		(net "JTAG_SCM_TCK")
	)
	(segment
		(start 155.365196 -10.172954)
		(end 155.70835 -10.516108)
		(width 0.11684)
		(layer "In4.Cu")
		(net "JTAG_SCM_TCK")
	)
	(segment
		(start 142.512542 -29.978858)
		(end 145.19529 -27.29611)
		(width 0.11684)
		(layer "In4.Cu")
		(net "JTAG_SCM_TCK")
	)
	(segment
		(start 155.70835 -10.516108)
		(end 155.70835 -10.85215)
		(width 0.11684)
		(layer "In4.Cu")
		(net "JTAG_SCM_TCK")
	)
	(segment
		(start 149.29612 -11.723878)
		(end 150.847044 -10.172954)
		(width 0.11684)
		(layer "In4.Cu")
		(net "JTAG_SCM_TCK")
	)
	(segment
		(start 145.19529 -27.29611)
		(end 145.19529 -17.611852)
		(width 0.11684)
		(layer "In4.Cu")
		(net "JTAG_SCM_TCK")
	)
	(segment
		(start 144.328642 -41.718738)
		(end 145.81378 -40.2336)
		(width 0.11684)
		(layer "In4.Cu")
		(net "JTAG_SCM_TCK")
	)
	(segment
		(start 118.452646 -58.444384)
		(end 118.452646 -56.820054)
		(width 0.11684)
		(layer "In4.Cu")
		(net "JTAG_SCM_TCK")
	)
	(segment
		(start 145.81378 -36.671504)
		(end 142.512542 -33.370266)
		(width 0.11684)
		(layer "In4.Cu")
		(net "JTAG_SCM_TCK")
	)
	(segment
		(start 129.483612 -47.867824)
		(end 144.328642 -41.718738)
		(width 0.11684)
		(layer "In4.Cu")
		(net "JTAG_SCM_TCK")
	)
	(segment
		(start 119.68353 -55.58917)
		(end 121.762266 -55.58917)
		(width 0.11684)
		(layer "In4.Cu")
		(net "JTAG_SCM_TCK")
	)
	(segment
		(start 118.452646 -56.820054)
		(end 119.68353 -55.58917)
		(width 0.11684)
		(layer "In4.Cu")
		(net "JTAG_SCM_TCK")
	)
	(segment
		(start 150.847044 -10.172954)
		(end 155.365196 -10.172954)
		(width 0.11684)
		(layer "In4.Cu")
		(net "JTAG_SCM_TCK")
	)
	(segment
		(start 117.744748 -59.152282)
		(end 118.452646 -58.444384)
		(width 0.11684)
		(layer "In4.Cu")
		(net "JTAG_SCM_TCK")
	)
	(segment
		(start 121.762266 -55.58917)
		(end 129.483612 -47.867824)
		(width 0.11684)
		(layer "In4.Cu")
		(net "JTAG_SCM_TCK")
	)
	(segment
		(start 145.81378 -40.2336)
		(end 145.81378 -36.671504)
		(width 0.11684)
		(layer "In4.Cu")
		(net "JTAG_SCM_TCK")
	)
	(segment
		(start 149.29612 -13.511022)
		(end 149.29612 -11.723878)
		(width 0.11684)
		(layer "In4.Cu")
		(net "JTAG_SCM_TCK")
	)
	(segment
		(start 178.72202 -113.85296)
		(end 178.33213 -113.46307)
		(width 0.10668)
		(layer "F.Cu")
		(net "JTAG_SCM_PLD_TMS")
	)
	(segment
		(start 105.24871 -61.087254)
		(end 104.63276 -61.087254)
		(width 0.10668)
		(layer "F.Cu")
		(net "JTAG_SCM_PLD_TMS")
	)
	(via
		(at 178.33213 -113.46307)
		(size 0.4572)
		(drill 0.254)
		(layers "F.Cu" "B.Cu")
		(net "JTAG_SCM_PLD_TMS")
	)
	(via
		(at 143.533622 -61.63056)
		(size 0.508)
		(drill 0.254)
		(layers "F.Cu" "B.Cu")
		(net "JTAG_SCM_PLD_TMS")
	)
	(via
		(at 104.63276 -61.087254)
		(size 0.508)
		(drill 0.254)
		(layers "F.Cu" "B.Cu")
		(net "JTAG_SCM_PLD_TMS")
	)
	(segment
		(start 141.977872 -63.64224)
		(end 140.68425 -64.935862)
		(width 0.10668)
		(layer "B.Cu")
		(net "JTAG_SCM_PLD_TMS")
	)
	(segment
		(start 120.041416 -62.375796)
		(end 118.86184 -61.19622)
		(width 0.10668)
		(layer "B.Cu")
		(net "JTAG_SCM_PLD_TMS")
	)
	(segment
		(start 122.447304 -62.375796)
		(end 120.041416 -62.375796)
		(width 0.10668)
		(layer "B.Cu")
		(net "JTAG_SCM_PLD_TMS")
	)
	(segment
		(start 143.533622 -61.898276)
		(end 143.533622 -61.63056)
		(width 0.10668)
		(layer "B.Cu")
		(net "JTAG_SCM_PLD_TMS")
	)
	(segment
		(start 118.86184 -57.33796)
		(end 116.193824 -54.669944)
		(width 0.10668)
		(layer "B.Cu")
		(net "JTAG_SCM_PLD_TMS")
	)
	(segment
		(start 131.05892 -67.84594)
		(end 125.7046 -62.49162)
		(width 0.10668)
		(layer "B.Cu")
		(net "JTAG_SCM_PLD_TMS")
	)
	(segment
		(start 133.231636 -67.84594)
		(end 131.05892 -67.84594)
		(width 0.10668)
		(layer "B.Cu")
		(net "JTAG_SCM_PLD_TMS")
	)
	(segment
		(start 107.329732 -54.669944)
		(end 105.623868 -56.375808)
		(width 0.10668)
		(layer "B.Cu")
		(net "JTAG_SCM_PLD_TMS")
	)
	(segment
		(start 105.623868 -60.512706)
		(end 105.04932 -61.087254)
		(width 0.10668)
		(layer "B.Cu")
		(net "JTAG_SCM_PLD_TMS")
	)
	(segment
		(start 105.04932 -61.087254)
		(end 104.63276 -61.087254)
		(width 0.10668)
		(layer "B.Cu")
		(net "JTAG_SCM_PLD_TMS")
	)
	(segment
		(start 116.193824 -54.669944)
		(end 107.329732 -54.669944)
		(width 0.10668)
		(layer "B.Cu")
		(net "JTAG_SCM_PLD_TMS")
	)
	(segment
		(start 123.72848 -61.09462)
		(end 122.447304 -62.375796)
		(width 0.10668)
		(layer "B.Cu")
		(net "JTAG_SCM_PLD_TMS")
	)
	(segment
		(start 125.21692 -61.09462)
		(end 123.72848 -61.09462)
		(width 0.10668)
		(layer "B.Cu")
		(net "JTAG_SCM_PLD_TMS")
	)
	(segment
		(start 105.623868 -56.375808)
		(end 105.623868 -60.512706)
		(width 0.10668)
		(layer "B.Cu")
		(net "JTAG_SCM_PLD_TMS")
	)
	(segment
		(start 118.86184 -61.19622)
		(end 118.86184 -57.33796)
		(width 0.10668)
		(layer "B.Cu")
		(net "JTAG_SCM_PLD_TMS")
	)
	(segment
		(start 140.68425 -64.935862)
		(end 140.68425 -70.17893)
		(width 0.10668)
		(layer "B.Cu")
		(net "JTAG_SCM_PLD_TMS")
	)
	(segment
		(start 141.977872 -63.64224)
		(end 141.977872 -63.454026)
		(width 0.10668)
		(layer "B.Cu")
		(net "JTAG_SCM_PLD_TMS")
	)
	(segment
		(start 140.00226 -70.86092)
		(end 136.246616 -70.86092)
		(width 0.10668)
		(layer "B.Cu")
		(net "JTAG_SCM_PLD_TMS")
	)
	(segment
		(start 140.68425 -70.17893)
		(end 140.00226 -70.86092)
		(width 0.10668)
		(layer "B.Cu")
		(net "JTAG_SCM_PLD_TMS")
	)
	(segment
		(start 136.246616 -70.86092)
		(end 133.231636 -67.84594)
		(width 0.10668)
		(layer "B.Cu")
		(net "JTAG_SCM_PLD_TMS")
	)
	(segment
		(start 125.7046 -61.5823)
		(end 125.21692 -61.09462)
		(width 0.10668)
		(layer "B.Cu")
		(net "JTAG_SCM_PLD_TMS")
	)
	(segment
		(start 125.7046 -62.49162)
		(end 125.7046 -61.5823)
		(width 0.10668)
		(layer "B.Cu")
		(net "JTAG_SCM_PLD_TMS")
	)
	(segment
		(start 141.977872 -63.454026)
		(end 143.533622 -61.898276)
		(width 0.10668)
		(layer "B.Cu")
		(net "JTAG_SCM_PLD_TMS")
	)
	(segment
		(start 172.434504 -113.403634)
		(end 171.070778 -114.76736)
		(width 0.11684)
		(layer "In4.Cu")
		(net "JTAG_SCM_PLD_TMS")
	)
	(segment
		(start 146.529552 -112.734852)
		(end 144.392142 -112.734852)
		(width 0.11684)
		(layer "In4.Cu")
		(net "JTAG_SCM_PLD_TMS")
	)
	(segment
		(start 171.070778 -114.76736)
		(end 169.827956 -114.76736)
		(width 0.11684)
		(layer "In4.Cu")
		(net "JTAG_SCM_PLD_TMS")
	)
	(segment
		(start 165.817296 -114.663728)
		(end 164.463222 -114.663728)
		(width 0.11684)
		(layer "In4.Cu")
		(net "JTAG_SCM_PLD_TMS")
	)
	(segment
		(start 169.452544 -113.971578)
		(end 169.244772 -113.763806)
		(width 0.11684)
		(layer "In4.Cu")
		(net "JTAG_SCM_PLD_TMS")
	)
	(segment
		(start 141.33068 -109.67339)
		(end 141.33068 -106.872024)
		(width 0.11684)
		(layer "In4.Cu")
		(net "JTAG_SCM_PLD_TMS")
	)
	(segment
		(start 161.506916 -115.902486)
		(end 160.571434 -114.967004)
		(width 0.11684)
		(layer "In4.Cu")
		(net "JTAG_SCM_PLD_TMS")
	)
	(segment
		(start 141.33068 -106.872024)
		(end 140.582396 -106.12374)
		(width 0.11684)
		(layer "In4.Cu")
		(net "JTAG_SCM_PLD_TMS")
	)
	(segment
		(start 176.865788 -113.053368)
		(end 176.515522 -113.403634)
		(width 0.11684)
		(layer "In4.Cu")
		(net "JTAG_SCM_PLD_TMS")
	)
	(segment
		(start 166.647622 -114.90452)
		(end 166.058088 -114.90452)
		(width 0.11684)
		(layer "In4.Cu")
		(net "JTAG_SCM_PLD_TMS")
	)
	(segment
		(start 164.463222 -114.663728)
		(end 163.224464 -115.902486)
		(width 0.11684)
		(layer "In4.Cu")
		(net "JTAG_SCM_PLD_TMS")
	)
	(segment
		(start 177.922428 -113.053368)
		(end 176.865788 -113.053368)
		(width 0.11684)
		(layer "In4.Cu")
		(net "JTAG_SCM_PLD_TMS")
	)
	(segment
		(start 176.515522 -113.403634)
		(end 172.434504 -113.403634)
		(width 0.11684)
		(layer "In4.Cu")
		(net "JTAG_SCM_PLD_TMS")
	)
	(segment
		(start 141.542262 -63.8556)
		(end 143.533622 -61.86424)
		(width 0.11684)
		(layer "In4.Cu")
		(net "JTAG_SCM_PLD_TMS")
	)
	(segment
		(start 178.33213 -113.46307)
		(end 177.922428 -113.053368)
		(width 0.11684)
		(layer "In4.Cu")
		(net "JTAG_SCM_PLD_TMS")
	)
	(segment
		(start 169.827956 -114.76736)
		(end 169.452544 -114.391948)
		(width 0.11684)
		(layer "In4.Cu")
		(net "JTAG_SCM_PLD_TMS")
	)
	(segment
		(start 140.582396 -90.675968)
		(end 134.50316 -84.596732)
		(width 0.11684)
		(layer "In4.Cu")
		(net "JTAG_SCM_PLD_TMS")
	)
	(segment
		(start 169.452544 -114.391948)
		(end 169.452544 -113.971578)
		(width 0.11684)
		(layer "In4.Cu")
		(net "JTAG_SCM_PLD_TMS")
	)
	(segment
		(start 160.571434 -114.967004)
		(end 159.207708 -114.967004)
		(width 0.11684)
		(layer "In4.Cu")
		(net "JTAG_SCM_PLD_TMS")
	)
	(segment
		(start 149.305518 -115.510818)
		(end 146.529552 -112.734852)
		(width 0.11684)
		(layer "In4.Cu")
		(net "JTAG_SCM_PLD_TMS")
	)
	(segment
		(start 140.582396 -106.12374)
		(end 140.582396 -90.675968)
		(width 0.11684)
		(layer "In4.Cu")
		(net "JTAG_SCM_PLD_TMS")
	)
	(segment
		(start 134.50316 -66.971672)
		(end 137.619232 -63.8556)
		(width 0.11684)
		(layer "In4.Cu")
		(net "JTAG_SCM_PLD_TMS")
	)
	(segment
		(start 144.392142 -112.734852)
		(end 141.33068 -109.67339)
		(width 0.11684)
		(layer "In4.Cu")
		(net "JTAG_SCM_PLD_TMS")
	)
	(segment
		(start 158.663894 -115.510818)
		(end 149.305518 -115.510818)
		(width 0.11684)
		(layer "In4.Cu")
		(net "JTAG_SCM_PLD_TMS")
	)
	(segment
		(start 166.058088 -114.90452)
		(end 165.817296 -114.663728)
		(width 0.11684)
		(layer "In4.Cu")
		(net "JTAG_SCM_PLD_TMS")
	)
	(segment
		(start 169.244772 -113.763806)
		(end 167.788336 -113.763806)
		(width 0.11684)
		(layer "In4.Cu")
		(net "JTAG_SCM_PLD_TMS")
	)
	(segment
		(start 134.50316 -84.596732)
		(end 134.50316 -66.971672)
		(width 0.11684)
		(layer "In4.Cu")
		(net "JTAG_SCM_PLD_TMS")
	)
	(segment
		(start 143.533622 -61.86424)
		(end 143.533622 -61.63056)
		(width 0.11684)
		(layer "In4.Cu")
		(net "JTAG_SCM_PLD_TMS")
	)
	(segment
		(start 159.207708 -114.967004)
		(end 158.663894 -115.510818)
		(width 0.11684)
		(layer "In4.Cu")
		(net "JTAG_SCM_PLD_TMS")
	)
	(segment
		(start 137.619232 -63.8556)
		(end 141.542262 -63.8556)
		(width 0.11684)
		(layer "In4.Cu")
		(net "JTAG_SCM_PLD_TMS")
	)
	(segment
		(start 167.788336 -113.763806)
		(end 166.647622 -114.90452)
		(width 0.11684)
		(layer "In4.Cu")
		(net "JTAG_SCM_PLD_TMS")
	)
	(segment
		(start 163.224464 -115.902486)
		(end 161.506916 -115.902486)
		(width 0.11684)
		(layer "In4.Cu")
		(net "JTAG_SCM_PLD_TMS")
	)
	(segment
		(start 125.592586 -61.767212)
		(end 124.876306 -61.767212)
		(width 0.10668)
		(layer "F.Cu")
		(net "JTAG_SCM_PLD_TDO")
	)
	(segment
		(start 180.32222 -113.05286)
		(end 179.93233 -112.66297)
		(width 0.10668)
		(layer "F.Cu")
		(net "JTAG_SCM_PLD_TDO")
	)
	(segment
		(start 124.876306 -61.767212)
		(end 124.860558 -61.78296)
		(width 0.10668)
		(layer "F.Cu")
		(net "JTAG_SCM_PLD_TDO")
	)
	(via
		(at 124.860558 -61.78296)
		(size 0.508)
		(drill 0.254)
		(layers "F.Cu" "B.Cu")
		(net "JTAG_SCM_PLD_TDO")
	)
	(via
		(at 149.597872 -60.988448)
		(size 0.508)
		(drill 0.254)
		(layers "F.Cu" "B.Cu")
		(net "JTAG_SCM_PLD_TDO")
	)
	(via
		(at 179.93233 -112.66297)
		(size 0.4572)
		(drill 0.254)
		(layers "F.Cu" "B.Cu")
		(net "JTAG_SCM_PLD_TDO")
	)
	(segment
		(start 124.860558 -64.550798)
		(end 124.860558 -61.78296)
		(width 0.10668)
		(layer "B.Cu")
		(net "JTAG_SCM_PLD_TDO")
	)
	(segment
		(start 136.075928 -71.2724)
		(end 133.060948 -68.25742)
		(width 0.10668)
		(layer "B.Cu")
		(net "JTAG_SCM_PLD_TDO")
	)
	(segment
		(start 143.383 -70.22592)
		(end 142.33652 -71.2724)
		(width 0.10668)
		(layer "B.Cu")
		(net "JTAG_SCM_PLD_TDO")
	)
	(segment
		(start 142.33652 -71.2724)
		(end 136.075928 -71.2724)
		(width 0.10668)
		(layer "B.Cu")
		(net "JTAG_SCM_PLD_TDO")
	)
	(segment
		(start 149.597872 -63.64224)
		(end 144.80286 -63.64224)
		(width 0.10668)
		(layer "B.Cu")
		(net "JTAG_SCM_PLD_TDO")
	)
	(segment
		(start 144.80286 -63.64224)
		(end 143.383 -65.0621)
		(width 0.10668)
		(layer "B.Cu")
		(net "JTAG_SCM_PLD_TDO")
	)
	(segment
		(start 128.56718 -68.25742)
		(end 124.860558 -64.550798)
		(width 0.10668)
		(layer "B.Cu")
		(net "JTAG_SCM_PLD_TDO")
	)
	(segment
		(start 133.060948 -68.25742)
		(end 128.56718 -68.25742)
		(width 0.10668)
		(layer "B.Cu")
		(net "JTAG_SCM_PLD_TDO")
	)
	(segment
		(start 149.597872 -63.64224)
		(end 149.597872 -60.988448)
		(width 0.10668)
		(layer "B.Cu")
		(net "JTAG_SCM_PLD_TDO")
	)
	(segment
		(start 143.383 -65.0621)
		(end 143.383 -70.22592)
		(width 0.10668)
		(layer "B.Cu")
		(net "JTAG_SCM_PLD_TDO")
	)
	(segment
		(start 170.577764 -116.591842)
		(end 170.577764 -117.120924)
		(width 0.11684)
		(layer "In4.Cu")
		(net "JTAG_SCM_PLD_TDO")
	)
	(segment
		(start 170.577764 -117.120924)
		(end 169.75836 -117.940328)
		(width 0.11684)
		(layer "In4.Cu")
		(net "JTAG_SCM_PLD_TDO")
	)
	(segment
		(start 168.667684 -117.797326)
		(end 167.22852 -117.797326)
		(width 0.11684)
		(layer "In4.Cu")
		(net "JTAG_SCM_PLD_TDO")
	)
	(segment
		(start 145.914872 -116.296694)
		(end 144.597882 -114.979704)
		(width 0.11684)
		(layer "In4.Cu")
		(net "JTAG_SCM_PLD_TDO")
	)
	(segment
		(start 144.597882 -114.979704)
		(end 144.597882 -114.234722)
		(width 0.11684)
		(layer "In4.Cu")
		(net "JTAG_SCM_PLD_TDO")
	)
	(segment
		(start 168.810686 -117.940328)
		(end 168.667684 -117.797326)
		(width 0.11684)
		(layer "In4.Cu")
		(net "JTAG_SCM_PLD_TDO")
	)
	(segment
		(start 125.75286 -61.78296)
		(end 124.860558 -61.78296)
		(width 0.11684)
		(layer "In4.Cu")
		(net "JTAG_SCM_PLD_TDO")
	)
	(segment
		(start 133.65988 -69.68998)
		(end 125.75286 -61.78296)
		(width 0.11684)
		(layer "In4.Cu")
		(net "JTAG_SCM_PLD_TDO")
	)
	(segment
		(start 179.93233 -112.66297)
		(end 179.53228 -113.06302)
		(width 0.11684)
		(layer "In4.Cu")
		(net "JTAG_SCM_PLD_TDO")
	)
	(segment
		(start 138.593576 -105.466896)
		(end 138.593576 -89.879932)
		(width 0.11684)
		(layer "In4.Cu")
		(net "JTAG_SCM_PLD_TDO")
	)
	(segment
		(start 166.55669 -117.125496)
		(end 163.27755 -117.125496)
		(width 0.11684)
		(layer "In4.Cu")
		(net "JTAG_SCM_PLD_TDO")
	)
	(segment
		(start 179.53228 -114.10823)
		(end 178.681634 -114.958876)
		(width 0.11684)
		(layer "In4.Cu")
		(net "JTAG_SCM_PLD_TDO")
	)
	(segment
		(start 149.6822 -116.49075)
		(end 149.032214 -117.140736)
		(width 0.11684)
		(layer "In4.Cu")
		(net "JTAG_SCM_PLD_TDO")
	)
	(segment
		(start 172.21073 -114.958876)
		(end 170.577764 -116.591842)
		(width 0.11684)
		(layer "In4.Cu")
		(net "JTAG_SCM_PLD_TDO")
	)
	(segment
		(start 144.597882 -114.234722)
		(end 140.4874 -110.12424)
		(width 0.11684)
		(layer "In4.Cu")
		(net "JTAG_SCM_PLD_TDO")
	)
	(segment
		(start 133.65988 -84.946236)
		(end 133.65988 -69.68998)
		(width 0.11684)
		(layer "In4.Cu")
		(net "JTAG_SCM_PLD_TDO")
	)
	(segment
		(start 156.813504 -118.667022)
		(end 154.637232 -116.49075)
		(width 0.11684)
		(layer "In4.Cu")
		(net "JTAG_SCM_PLD_TDO")
	)
	(segment
		(start 140.4874 -107.36072)
		(end 138.593576 -105.466896)
		(width 0.11684)
		(layer "In4.Cu")
		(net "JTAG_SCM_PLD_TDO")
	)
	(segment
		(start 179.53228 -113.06302)
		(end 179.53228 -114.10823)
		(width 0.11684)
		(layer "In4.Cu")
		(net "JTAG_SCM_PLD_TDO")
	)
	(segment
		(start 169.75836 -117.940328)
		(end 168.810686 -117.940328)
		(width 0.11684)
		(layer "In4.Cu")
		(net "JTAG_SCM_PLD_TDO")
	)
	(segment
		(start 138.593576 -89.879932)
		(end 133.65988 -84.946236)
		(width 0.11684)
		(layer "In4.Cu")
		(net "JTAG_SCM_PLD_TDO")
	)
	(segment
		(start 149.032214 -117.140736)
		(end 147.952206 -117.140736)
		(width 0.11684)
		(layer "In4.Cu")
		(net "JTAG_SCM_PLD_TDO")
	)
	(segment
		(start 178.681634 -114.958876)
		(end 172.21073 -114.958876)
		(width 0.11684)
		(layer "In4.Cu")
		(net "JTAG_SCM_PLD_TDO")
	)
	(segment
		(start 154.637232 -116.49075)
		(end 149.6822 -116.49075)
		(width 0.11684)
		(layer "In4.Cu")
		(net "JTAG_SCM_PLD_TDO")
	)
	(segment
		(start 147.952206 -117.140736)
		(end 145.914872 -116.296694)
		(width 0.11684)
		(layer "In4.Cu")
		(net "JTAG_SCM_PLD_TDO")
	)
	(segment
		(start 140.4874 -110.12424)
		(end 140.4874 -107.36072)
		(width 0.11684)
		(layer "In4.Cu")
		(net "JTAG_SCM_PLD_TDO")
	)
	(segment
		(start 167.22852 -117.797326)
		(end 166.55669 -117.125496)
		(width 0.11684)
		(layer "In4.Cu")
		(net "JTAG_SCM_PLD_TDO")
	)
	(segment
		(start 161.736024 -118.667022)
		(end 156.813504 -118.667022)
		(width 0.11684)
		(layer "In4.Cu")
		(net "JTAG_SCM_PLD_TDO")
	)
	(segment
		(start 163.27755 -117.125496)
		(end 161.736024 -118.667022)
		(width 0.11684)
		(layer "In4.Cu")
		(net "JTAG_SCM_PLD_TDO")
	)
	(segment
		(start 139.508992 -58.532014)
		(end 138.827002 -58.532014)
		(width 0.10668)
		(layer "F.Cu")
		(net "JTAG_SCM_PLD_TDI")
	)
	(segment
		(start 180.32222 -112.25276)
		(end 179.93233 -111.86287)
		(width 0.10668)
		(layer "F.Cu")
		(net "JTAG_SCM_PLD_TDI")
	)
	(via
		(at 179.93233 -111.86287)
		(size 0.4572)
		(drill 0.254)
		(layers "F.Cu" "B.Cu")
		(net "JTAG_SCM_PLD_TDI")
	)
	(via
		(at 168.032684 -112.902238)
		(size 0.508)
		(drill 0.254)
		(layers "F.Cu" "B.Cu")
		(net "JTAG_SCM_PLD_TDI")
	)
	(via
		(at 139.508992 -58.532014)
		(size 0.508)
		(drill 0.254)
		(layers "F.Cu" "B.Cu")
		(net "JTAG_SCM_PLD_TDI")
	)
	(segment
		(start 167.355266 -112.902238)
		(end 168.032684 -112.902238)
		(width 0.10668)
		(layer "B.Cu")
		(net "JTAG_SCM_PLD_TDI")
	)
	(segment
		(start 141.004036 -90.501216)
		(end 141.004036 -105.948988)
		(width 0.11684)
		(layer "In4.Cu")
		(net "JTAG_SCM_PLD_TDI")
	)
	(segment
		(start 179.543202 -112.263428)
		(end 176.90719 -112.263428)
		(width 0.11684)
		(layer "In4.Cu")
		(net "JTAG_SCM_PLD_TDI")
	)
	(segment
		(start 168.21023 -112.724692)
		(end 168.032684 -112.902238)
		(width 0.11684)
		(layer "In4.Cu")
		(net "JTAG_SCM_PLD_TDI")
	)
	(segment
		(start 176.286668 -112.88395)
		(end 169.07764 -112.88395)
		(width 0.11684)
		(layer "In4.Cu")
		(net "JTAG_SCM_PLD_TDI")
	)
	(segment
		(start 164.984176 -113.78057)
		(end 165.742874 -113.78057)
		(width 0.11684)
		(layer "In4.Cu")
		(net "JTAG_SCM_PLD_TDI")
	)
	(segment
		(start 146.821398 -112.253268)
		(end 148.74113 -114.173)
		(width 0.11684)
		(layer "In4.Cu")
		(net "JTAG_SCM_PLD_TDI")
	)
	(segment
		(start 141.75232 -106.697272)
		(end 141.75232 -109.498384)
		(width 0.11684)
		(layer "In4.Cu")
		(net "JTAG_SCM_PLD_TDI")
	)
	(segment
		(start 148.74113 -114.173)
		(end 150.986998 -114.173)
		(width 0.11684)
		(layer "In4.Cu")
		(net "JTAG_SCM_PLD_TDI")
	)
	(segment
		(start 144.17548 -61.01588)
		(end 144.17548 -63.26378)
		(width 0.11684)
		(layer "In4.Cu")
		(net "JTAG_SCM_PLD_TDI")
	)
	(segment
		(start 169.07764 -112.88395)
		(end 168.918382 -112.724692)
		(width 0.11684)
		(layer "In4.Cu")
		(net "JTAG_SCM_PLD_TDI")
	)
	(segment
		(start 153.855928 -114.632232)
		(end 158.506922 -114.632232)
		(width 0.11684)
		(layer "In4.Cu")
		(net "JTAG_SCM_PLD_TDI")
	)
	(segment
		(start 179.93233 -111.8743)
		(end 179.543202 -112.263428)
		(width 0.11684)
		(layer "In4.Cu")
		(net "JTAG_SCM_PLD_TDI")
	)
	(segment
		(start 158.506922 -114.632232)
		(end 159.507936 -113.631218)
		(width 0.11684)
		(layer "In4.Cu")
		(net "JTAG_SCM_PLD_TDI")
	)
	(segment
		(start 139.508992 -58.532014)
		(end 141.691614 -58.532014)
		(width 0.11684)
		(layer "In4.Cu")
		(net "JTAG_SCM_PLD_TDI")
	)
	(segment
		(start 176.90719 -112.263428)
		(end 176.286668 -112.88395)
		(width 0.11684)
		(layer "In4.Cu")
		(net "JTAG_SCM_PLD_TDI")
	)
	(segment
		(start 134.9248 -67.2465)
		(end 134.9248 -84.42198)
		(width 0.11684)
		(layer "In4.Cu")
		(net "JTAG_SCM_PLD_TDI")
	)
	(segment
		(start 179.93233 -111.86287)
		(end 179.93233 -111.8743)
		(width 0.11684)
		(layer "In4.Cu")
		(net "JTAG_SCM_PLD_TDI")
	)
	(segment
		(start 153.185368 -113.961672)
		(end 153.855928 -114.632232)
		(width 0.11684)
		(layer "In4.Cu")
		(net "JTAG_SCM_PLD_TDI")
	)
	(segment
		(start 150.986998 -114.173)
		(end 151.198326 -113.961672)
		(width 0.11684)
		(layer "In4.Cu")
		(net "JTAG_SCM_PLD_TDI")
	)
	(segment
		(start 164.834824 -113.631218)
		(end 164.984176 -113.78057)
		(width 0.11684)
		(layer "In4.Cu")
		(net "JTAG_SCM_PLD_TDI")
	)
	(segment
		(start 144.17548 -63.26378)
		(end 142.80388 -64.63538)
		(width 0.11684)
		(layer "In4.Cu")
		(net "JTAG_SCM_PLD_TDI")
	)
	(segment
		(start 137.53592 -64.63538)
		(end 134.9248 -67.2465)
		(width 0.11684)
		(layer "In4.Cu")
		(net "JTAG_SCM_PLD_TDI")
	)
	(segment
		(start 168.918382 -112.724692)
		(end 168.21023 -112.724692)
		(width 0.11684)
		(layer "In4.Cu")
		(net "JTAG_SCM_PLD_TDI")
	)
	(segment
		(start 134.9248 -84.42198)
		(end 141.004036 -90.501216)
		(width 0.11684)
		(layer "In4.Cu")
		(net "JTAG_SCM_PLD_TDI")
	)
	(segment
		(start 141.691614 -58.532014)
		(end 144.17548 -61.01588)
		(width 0.11684)
		(layer "In4.Cu")
		(net "JTAG_SCM_PLD_TDI")
	)
	(segment
		(start 159.507936 -113.631218)
		(end 164.834824 -113.631218)
		(width 0.11684)
		(layer "In4.Cu")
		(net "JTAG_SCM_PLD_TDI")
	)
	(segment
		(start 142.80388 -64.63538)
		(end 137.53592 -64.63538)
		(width 0.11684)
		(layer "In4.Cu")
		(net "JTAG_SCM_PLD_TDI")
	)
	(segment
		(start 141.004036 -105.948988)
		(end 141.75232 -106.697272)
		(width 0.11684)
		(layer "In4.Cu")
		(net "JTAG_SCM_PLD_TDI")
	)
	(segment
		(start 151.198326 -113.961672)
		(end 153.185368 -113.961672)
		(width 0.11684)
		(layer "In4.Cu")
		(net "JTAG_SCM_PLD_TDI")
	)
	(segment
		(start 141.75232 -109.498384)
		(end 144.507204 -112.253268)
		(width 0.11684)
		(layer "In4.Cu")
		(net "JTAG_SCM_PLD_TDI")
	)
	(segment
		(start 166.621206 -112.902238)
		(end 168.032684 -112.902238)
		(width 0.11684)
		(layer "In4.Cu")
		(net "JTAG_SCM_PLD_TDI")
	)
	(segment
		(start 165.742874 -113.78057)
		(end 166.621206 -112.902238)
		(width 0.11684)
		(layer "In4.Cu")
		(net "JTAG_SCM_PLD_TDI")
	)
	(segment
		(start 144.507204 -112.253268)
		(end 146.821398 -112.253268)
		(width 0.11684)
		(layer "In4.Cu")
		(net "JTAG_SCM_PLD_TDI")
	)
	(segment
		(start 119.728234 -57.852056)
		(end 119.118634 -57.852056)
		(width 0.10668)
		(layer "F.Cu")
		(net "JTAG_SCM_PLD_TCK")
	)
	(segment
		(start 179.52212 -113.85296)
		(end 179.13223 -113.46307)
		(width 0.10668)
		(layer "F.Cu")
		(net "JTAG_SCM_PLD_TCK")
	)
	(via
		(at 142.182596 -61.766704)
		(size 0.508)
		(drill 0.254)
		(layers "F.Cu" "B.Cu")
		(net "JTAG_SCM_PLD_TCK")
	)
	(via
		(at 119.728234 -57.852056)
		(size 0.508)
		(drill 0.254)
		(layers "F.Cu" "B.Cu")
		(net "JTAG_SCM_PLD_TCK")
	)
	(via
		(at 179.13223 -113.46307)
		(size 0.4572)
		(drill 0.254)
		(layers "F.Cu" "B.Cu")
		(net "JTAG_SCM_PLD_TCK")
	)
	(segment
		(start 126.341886 -62.051438)
		(end 126.341886 -60.571126)
		(width 0.10668)
		(layer "B.Cu")
		(net "JTAG_SCM_PLD_TCK")
	)
	(segment
		(start 140.312648 -63.636652)
		(end 142.182596 -61.766704)
		(width 0.10668)
		(layer "B.Cu")
		(net "JTAG_SCM_PLD_TCK")
	)
	(segment
		(start 137.928604 -63.636652)
		(end 136.90346 -63.636652)
		(width 0.10668)
		(layer "B.Cu")
		(net "JTAG_SCM_PLD_TCK")
	)
	(segment
		(start 136.90346 -63.636652)
		(end 136.897872 -63.64224)
		(width 0.10668)
		(layer "B.Cu")
		(net "JTAG_SCM_PLD_TCK")
	)
	(segment
		(start 137.928604 -63.636652)
		(end 140.312648 -63.636652)
		(width 0.10668)
		(layer "B.Cu")
		(net "JTAG_SCM_PLD_TCK")
	)
	(segment
		(start 121.746518 -59.87034)
		(end 119.728234 -57.852056)
		(width 0.10668)
		(layer "B.Cu")
		(net "JTAG_SCM_PLD_TCK")
	)
	(segment
		(start 136.897872 -63.64224)
		(end 127.932688 -63.64224)
		(width 0.10668)
		(layer "B.Cu")
		(net "JTAG_SCM_PLD_TCK")
	)
	(segment
		(start 125.6411 -59.87034)
		(end 121.746518 -59.87034)
		(width 0.10668)
		(layer "B.Cu")
		(net "JTAG_SCM_PLD_TCK")
	)
	(segment
		(start 126.341886 -60.571126)
		(end 125.6411 -59.87034)
		(width 0.10668)
		(layer "B.Cu")
		(net "JTAG_SCM_PLD_TCK")
	)
	(segment
		(start 127.932688 -63.64224)
		(end 126.341886 -62.051438)
		(width 0.10668)
		(layer "B.Cu")
		(net "JTAG_SCM_PLD_TCK")
	)
	(segment
		(start 178.732688 -113.862612)
		(end 172.595286 -113.862612)
		(width 0.11684)
		(layer "In4.Cu")
		(net "JTAG_SCM_PLD_TCK")
	)
	(segment
		(start 137.44448 -63.43396)
		(end 140.51534 -63.43396)
		(width 0.11684)
		(layer "In4.Cu")
		(net "JTAG_SCM_PLD_TCK")
	)
	(segment
		(start 140.51534 -63.43396)
		(end 142.182596 -61.766704)
		(width 0.11684)
		(layer "In4.Cu")
		(net "JTAG_SCM_PLD_TCK")
	)
	(segment
		(start 158.981902 -116.398294)
		(end 158.575502 -115.991894)
		(width 0.11684)
		(layer "In4.Cu")
		(net "JTAG_SCM_PLD_TCK")
	)
	(segment
		(start 172.595286 -113.862612)
		(end 170.657774 -115.800124)
		(width 0.11684)
		(layer "In4.Cu")
		(net "JTAG_SCM_PLD_TCK")
	)
	(segment
		(start 158.575502 -115.991894)
		(end 148.928836 -115.991894)
		(width 0.11684)
		(layer "In4.Cu")
		(net "JTAG_SCM_PLD_TCK")
	)
	(segment
		(start 140.90904 -107.185968)
		(end 139.015216 -105.292144)
		(width 0.11684)
		(layer "In4.Cu")
		(net "JTAG_SCM_PLD_TCK")
	)
	(segment
		(start 165.667436 -115.800124)
		(end 165.069266 -116.398294)
		(width 0.11684)
		(layer "In4.Cu")
		(net "JTAG_SCM_PLD_TCK")
	)
	(segment
		(start 146.263106 -113.326164)
		(end 144.387062 -113.326164)
		(width 0.11684)
		(layer "In4.Cu")
		(net "JTAG_SCM_PLD_TCK")
	)
	(segment
		(start 170.657774 -115.800124)
		(end 165.667436 -115.800124)
		(width 0.11684)
		(layer "In4.Cu")
		(net "JTAG_SCM_PLD_TCK")
	)
	(segment
		(start 148.928836 -115.991894)
		(end 146.263106 -113.326164)
		(width 0.11684)
		(layer "In4.Cu")
		(net "JTAG_SCM_PLD_TCK")
	)
	(segment
		(start 139.015216 -89.70518)
		(end 134.08152 -84.771484)
		(width 0.11684)
		(layer "In4.Cu")
		(net "JTAG_SCM_PLD_TCK")
	)
	(segment
		(start 134.08152 -84.771484)
		(end 134.08152 -66.79692)
		(width 0.11684)
		(layer "In4.Cu")
		(net "JTAG_SCM_PLD_TCK")
	)
	(segment
		(start 165.069266 -116.398294)
		(end 158.981902 -116.398294)
		(width 0.11684)
		(layer "In4.Cu")
		(net "JTAG_SCM_PLD_TCK")
	)
	(segment
		(start 140.90904 -109.848142)
		(end 140.90904 -107.185968)
		(width 0.11684)
		(layer "In4.Cu")
		(net "JTAG_SCM_PLD_TCK")
	)
	(segment
		(start 139.015216 -105.292144)
		(end 139.015216 -89.70518)
		(width 0.11684)
		(layer "In4.Cu")
		(net "JTAG_SCM_PLD_TCK")
	)
	(segment
		(start 144.387062 -113.326164)
		(end 140.90904 -109.848142)
		(width 0.11684)
		(layer "In4.Cu")
		(net "JTAG_SCM_PLD_TCK")
	)
	(segment
		(start 134.08152 -66.79692)
		(end 137.44448 -63.43396)
		(width 0.11684)
		(layer "In4.Cu")
		(net "JTAG_SCM_PLD_TCK")
	)
	(segment
		(start 179.13223 -113.46307)
		(end 178.732688 -113.862612)
		(width 0.11684)
		(layer "In4.Cu")
		(net "JTAG_SCM_PLD_TCK")
	)
	(segment
		(start 109.923326 -60.452254)
		(end 108.940346 -60.452254)
		(width 0.10668)
		(layer "F.Cu")
		(net "JTAG_SCM_PLD_R_TMS")
	)
	(segment
		(start 106.04881 -61.087254)
		(end 106.70921 -61.087254)
		(width 0.10668)
		(layer "F.Cu")
		(net "JTAG_SCM_PLD_R_TMS")
	)
	(segment
		(start 110.090458 -60.285122)
		(end 109.923326 -60.452254)
		(width 0.10668)
		(layer "F.Cu")
		(net "JTAG_SCM_PLD_R_TMS")
	)
	(segment
		(start 107.34421 -60.452254)
		(end 108.940346 -60.452254)
		(width 0.10668)
		(layer "F.Cu")
		(net "JTAG_SCM_PLD_R_TMS")
	)
	(segment
		(start 107.34421 -60.452254)
		(end 106.70921 -61.087254)
		(width 0.10668)
		(layer "F.Cu")
		(net "JTAG_SCM_PLD_R_TMS")
	)
	(segment
		(start 109.923326 -59.152282)
		(end 110.090458 -59.319414)
		(width 0.10668)
		(layer "F.Cu")
		(net "JTAG_SCM_PLD_R_TMS")
	)
	(segment
		(start 108.940346 -59.152282)
		(end 109.923326 -59.152282)
		(width 0.10668)
		(layer "F.Cu")
		(net "JTAG_SCM_PLD_R_TMS")
	)
	(segment
		(start 110.090458 -59.319414)
		(end 110.090458 -60.285122)
		(width 0.10668)
		(layer "F.Cu")
		(net "JTAG_SCM_PLD_R_TMS")
	)
	(via
		(at 106.70921 -61.087254)
		(size 0.508)
		(drill 0.254)
		(layers "F.Cu" "B.Cu")
		(net "JTAG_SCM_PLD_R_TMS")
	)
	(segment
		(start 129.914142 -59.999372)
		(end 129.914142 -60.96508)
		(width 0.10668)
		(layer "F.Cu")
		(net "JTAG_SCM_PLD_R_TDO")
	)
	(segment
		(start 127.565658 -61.765942)
		(end 127.030226 -61.765942)
		(width 0.10668)
		(layer "F.Cu")
		(net "JTAG_SCM_PLD_R_TDO")
	)
	(segment
		(start 127.028956 -61.767212)
		(end 127.030226 -61.765942)
		(width 0.10668)
		(layer "F.Cu")
		(net "JTAG_SCM_PLD_R_TDO")
	)
	(segment
		(start 126.392686 -61.767212)
		(end 127.028956 -61.767212)
		(width 0.10668)
		(layer "F.Cu")
		(net "JTAG_SCM_PLD_R_TDO")
	)
	(segment
		(start 129.74701 -61.132212)
		(end 128.76403 -61.132212)
		(width 0.10668)
		(layer "F.Cu")
		(net "JTAG_SCM_PLD_R_TDO")
	)
	(segment
		(start 129.74701 -59.83224)
		(end 129.914142 -59.999372)
		(width 0.10668)
		(layer "F.Cu")
		(net "JTAG_SCM_PLD_R_TDO")
	)
	(segment
		(start 128.76403 -61.132212)
		(end 128.199388 -61.132212)
		(width 0.10668)
		(layer "F.Cu")
		(net "JTAG_SCM_PLD_R_TDO")
	)
	(segment
		(start 129.914142 -60.96508)
		(end 129.74701 -61.132212)
		(width 0.10668)
		(layer "F.Cu")
		(net "JTAG_SCM_PLD_R_TDO")
	)
	(segment
		(start 128.76403 -59.83224)
		(end 129.74701 -59.83224)
		(width 0.10668)
		(layer "F.Cu")
		(net "JTAG_SCM_PLD_R_TDO")
	)
	(segment
		(start 128.199388 -61.132212)
		(end 127.565658 -61.765942)
		(width 0.10668)
		(layer "F.Cu")
		(net "JTAG_SCM_PLD_R_TDO")
	)
	(via
		(at 127.030226 -61.765942)
		(size 0.508)
		(drill 0.254)
		(layers "F.Cu" "B.Cu")
		(net "JTAG_SCM_PLD_R_TDO")
	)
	(segment
		(start 133.234938 -58.739532)
		(end 133.442456 -58.532014)
		(width 0.10668)
		(layer "F.Cu")
		(net "JTAG_SCM_PLD_R_TDI")
	)
	(segment
		(start 134.614158 -61.132212)
		(end 133.442456 -61.132212)
		(width 0.10668)
		(layer "F.Cu")
		(net "JTAG_SCM_PLD_R_TDI")
	)
	(segment
		(start 135.706358 -58.532014)
		(end 138.026902 -58.532014)
		(width 0.10668)
		(layer "F.Cu")
		(net "JTAG_SCM_PLD_R_TDI")
	)
	(segment
		(start 133.442456 -61.132212)
		(end 133.234938 -60.924694)
		(width 0.10668)
		(layer "F.Cu")
		(net "JTAG_SCM_PLD_R_TDI")
	)
	(segment
		(start 133.234938 -60.924694)
		(end 133.234938 -58.739532)
		(width 0.10668)
		(layer "F.Cu")
		(net "JTAG_SCM_PLD_R_TDI")
	)
	(segment
		(start 133.442456 -58.532014)
		(end 134.614158 -58.532014)
		(width 0.10668)
		(layer "F.Cu")
		(net "JTAG_SCM_PLD_R_TDI")
	)
	(segment
		(start 134.614158 -58.532014)
		(end 135.706358 -58.532014)
		(width 0.10668)
		(layer "F.Cu")
		(net "JTAG_SCM_PLD_R_TDI")
	)
	(via
		(at 135.706358 -58.532014)
		(size 0.508)
		(drill 0.254)
		(layers "F.Cu" "B.Cu")
		(net "JTAG_SCM_PLD_R_TDI")
	)
	(segment
		(start 113.618772 -60.452254)
		(end 113.411254 -60.244736)
		(width 0.10668)
		(layer "F.Cu")
		(net "JTAG_SCM_PLD_R_TCK")
	)
	(segment
		(start 113.411254 -58.059574)
		(end 113.618772 -57.852056)
		(width 0.10668)
		(layer "F.Cu")
		(net "JTAG_SCM_PLD_R_TCK")
	)
	(segment
		(start 113.411254 -60.244736)
		(end 113.411254 -58.059574)
		(width 0.10668)
		(layer "F.Cu")
		(net "JTAG_SCM_PLD_R_TCK")
	)
	(segment
		(start 113.618772 -57.852056)
		(end 114.790474 -57.852056)
		(width 0.10668)
		(layer "F.Cu")
		(net "JTAG_SCM_PLD_R_TCK")
	)
	(segment
		(start 115.882674 -57.852056)
		(end 118.318534 -57.852056)
		(width 0.10668)
		(layer "F.Cu")
		(net "JTAG_SCM_PLD_R_TCK")
	)
	(segment
		(start 114.790474 -57.852056)
		(end 115.882674 -57.852056)
		(width 0.10668)
		(layer "F.Cu")
		(net "JTAG_SCM_PLD_R_TCK")
	)
	(segment
		(start 114.790474 -60.452254)
		(end 113.618772 -60.452254)
		(width 0.10668)
		(layer "F.Cu")
		(net "JTAG_SCM_PLD_R_TCK")
	)
	(via
		(at 115.882674 -57.852056)
		(size 0.508)
		(drill 0.254)
		(layers "F.Cu" "B.Cu")
		(net "JTAG_SCM_PLD_R_TCK")
	)
	(segment
		(start 271.50441 -106.522774)
		(end 272.169382 -105.857802)
		(width 0.10668)
		(layer "F.Cu")
		(net "JTAG_SCM_MUX_TMS")
	)
	(segment
		(start 105.24871 -57.486042)
		(end 105.24871 -58.502042)
		(width 0.10668)
		(layer "F.Cu")
		(net "JTAG_SCM_MUX_TMS")
	)
	(segment
		(start 105.24871 -58.502042)
		(end 104.431592 -58.502042)
		(width 0.10668)
		(layer "F.Cu")
		(net "JTAG_SCM_MUX_TMS")
	)
	(segment
		(start 269.868142 -106.522774)
		(end 271.50441 -106.522774)
		(width 0.10668)
		(layer "F.Cu")
		(net "JTAG_SCM_MUX_TMS")
	)
	(segment
		(start 104.431592 -58.502042)
		(end 103.897684 -59.03595)
		(width 0.10668)
		(layer "F.Cu")
		(net "JTAG_SCM_MUX_TMS")
	)
	(segment
		(start 272.169382 -105.857802)
		(end 272.475452 -105.857802)
		(width 0.10668)
		(layer "F.Cu")
		(net "JTAG_SCM_MUX_TMS")
	)
	(segment
		(start 111.330486 -76.076302)
		(end 111.330486 -83.217512)
		(width 0.10668)
		(layer "F.Cu")
		(net "JTAG_SCM_MUX_TMS")
	)
	(segment
		(start 103.897684 -68.6435)
		(end 111.330486 -76.076302)
		(width 0.10668)
		(layer "F.Cu")
		(net "JTAG_SCM_MUX_TMS")
	)
	(segment
		(start 111.330486 -83.217512)
		(end 118.75643 -90.643456)
		(width 0.10668)
		(layer "F.Cu")
		(net "JTAG_SCM_MUX_TMS")
	)
	(segment
		(start 103.897684 -59.03595)
		(end 103.897684 -68.6435)
		(width 0.10668)
		(layer "F.Cu")
		(net "JTAG_SCM_MUX_TMS")
	)
	(via
		(at 272.475452 -105.857802)
		(size 0.508)
		(drill 0.254)
		(layers "F.Cu" "B.Cu")
		(net "JTAG_SCM_MUX_TMS")
	)
	(via
		(at 118.75643 -90.643456)
		(size 0.508)
		(drill 0.254)
		(layers "F.Cu" "B.Cu")
		(net "JTAG_SCM_MUX_TMS")
	)
	(segment
		(start 214.829898 -95.095314)
		(end 216.642696 -95.095314)
		(width 0.11684)
		(layer "In2.Cu")
		(net "JTAG_SCM_MUX_TMS")
	)
	(segment
		(start 266.20343 -105.857802)
		(end 272.475452 -105.857802)
		(width 0.11684)
		(layer "In2.Cu")
		(net "JTAG_SCM_MUX_TMS")
	)
	(segment
		(start 237.526068 -102.067868)
		(end 262.413496 -102.067868)
		(width 0.11684)
		(layer "In2.Cu")
		(net "JTAG_SCM_MUX_TMS")
	)
	(segment
		(start 203.277724 -91.853258)
		(end 203.525882 -91.6051)
		(width 0.11684)
		(layer "In2.Cu")
		(net "JTAG_SCM_MUX_TMS")
	)
	(segment
		(start 171.731686 -90.218768)
		(end 171.960794 -89.98966)
		(width 0.11684)
		(layer "In2.Cu")
		(net "JTAG_SCM_MUX_TMS")
	)
	(segment
		(start 217.602054 -96.054672)
		(end 221.726506 -96.054672)
		(width 0.11684)
		(layer "In2.Cu")
		(net "JTAG_SCM_MUX_TMS")
	)
	(segment
		(start 177.948844 -90.1192)
		(end 178.048666 -90.219022)
		(width 0.11684)
		(layer "In2.Cu")
		(net "JTAG_SCM_MUX_TMS")
	)
	(segment
		(start 175.66386 -90.1192)
		(end 177.948844 -90.1192)
		(width 0.11684)
		(layer "In2.Cu")
		(net "JTAG_SCM_MUX_TMS")
	)
	(segment
		(start 195.225924 -90.219022)
		(end 196.86016 -91.853258)
		(width 0.11684)
		(layer "In2.Cu")
		(net "JTAG_SCM_MUX_TMS")
	)
	(segment
		(start 144.60347 -90.643456)
		(end 145.028158 -90.218768)
		(width 0.11684)
		(layer "In2.Cu")
		(net "JTAG_SCM_MUX_TMS")
	)
	(segment
		(start 221.726506 -96.054672)
		(end 222.1484 -96.476566)
		(width 0.11684)
		(layer "In2.Cu")
		(net "JTAG_SCM_MUX_TMS")
	)
	(segment
		(start 262.413496 -102.067868)
		(end 266.20343 -105.857802)
		(width 0.11684)
		(layer "In2.Cu")
		(net "JTAG_SCM_MUX_TMS")
	)
	(segment
		(start 173.89983 -89.98966)
		(end 174.128938 -90.218768)
		(width 0.11684)
		(layer "In2.Cu")
		(net "JTAG_SCM_MUX_TMS")
	)
	(segment
		(start 203.525882 -91.6051)
		(end 211.339684 -91.6051)
		(width 0.11684)
		(layer "In2.Cu")
		(net "JTAG_SCM_MUX_TMS")
	)
	(segment
		(start 118.75643 -90.643456)
		(end 144.60347 -90.643456)
		(width 0.11684)
		(layer "In2.Cu")
		(net "JTAG_SCM_MUX_TMS")
	)
	(segment
		(start 145.028158 -90.218768)
		(end 171.731686 -90.218768)
		(width 0.11684)
		(layer "In2.Cu")
		(net "JTAG_SCM_MUX_TMS")
	)
	(segment
		(start 216.642696 -95.095314)
		(end 217.602054 -96.054672)
		(width 0.11684)
		(layer "In2.Cu")
		(net "JTAG_SCM_MUX_TMS")
	)
	(segment
		(start 196.86016 -91.853258)
		(end 203.277724 -91.853258)
		(width 0.11684)
		(layer "In2.Cu")
		(net "JTAG_SCM_MUX_TMS")
	)
	(segment
		(start 224.027238 -96.476566)
		(end 237.526068 -102.067868)
		(width 0.11684)
		(layer "In2.Cu")
		(net "JTAG_SCM_MUX_TMS")
	)
	(segment
		(start 175.564292 -90.218768)
		(end 175.66386 -90.1192)
		(width 0.11684)
		(layer "In2.Cu")
		(net "JTAG_SCM_MUX_TMS")
	)
	(segment
		(start 211.339684 -91.6051)
		(end 214.829898 -95.095314)
		(width 0.11684)
		(layer "In2.Cu")
		(net "JTAG_SCM_MUX_TMS")
	)
	(segment
		(start 174.128938 -90.218768)
		(end 175.564292 -90.218768)
		(width 0.11684)
		(layer "In2.Cu")
		(net "JTAG_SCM_MUX_TMS")
	)
	(segment
		(start 171.960794 -89.98966)
		(end 173.89983 -89.98966)
		(width 0.11684)
		(layer "In2.Cu")
		(net "JTAG_SCM_MUX_TMS")
	)
	(segment
		(start 178.048666 -90.219022)
		(end 195.225924 -90.219022)
		(width 0.11684)
		(layer "In2.Cu")
		(net "JTAG_SCM_MUX_TMS")
	)
	(segment
		(start 222.1484 -96.476566)
		(end 224.027238 -96.476566)
		(width 0.11684)
		(layer "In2.Cu")
		(net "JTAG_SCM_MUX_TMS")
	)
	(segment
		(start 148.022564 -56.393334)
		(end 148.022564 -56.240934)
		(width 0.10668)
		(layer "F.Cu")
		(net "JTAG_SCM_MUX_TDO")
	)
	(segment
		(start 147.539964 -56.875934)
		(end 148.022564 -56.393334)
		(width 0.10668)
		(layer "F.Cu")
		(net "JTAG_SCM_MUX_TDO")
	)
	(segment
		(start 147.174712 -56.875934)
		(end 147.539964 -56.875934)
		(width 0.10668)
		(layer "F.Cu")
		(net "JTAG_SCM_MUX_TDO")
	)
	(segment
		(start 124.271786 -59.182)
		(end 124.932186 -59.182)
		(width 0.10668)
		(layer "F.Cu")
		(net "JTAG_SCM_MUX_TDO")
	)
	(segment
		(start 125.592586 -59.182)
		(end 124.932186 -59.182)
		(width 0.10668)
		(layer "F.Cu")
		(net "JTAG_SCM_MUX_TDO")
	)
	(via
		(at 124.932186 -59.182)
		(size 0.508)
		(drill 0.254)
		(layers "F.Cu" "B.Cu")
		(net "JTAG_SCM_MUX_TDO")
	)
	(via
		(at 148.022564 -56.240934)
		(size 0.508)
		(drill 0.254)
		(layers "F.Cu" "B.Cu")
		(net "JTAG_SCM_MUX_TDO")
	)
	(segment
		(start 126.23038 -55.847488)
		(end 127.851154 -54.226714)
		(width 0.10668)
		(layer "B.Cu")
		(net "JTAG_SCM_MUX_TDO")
	)
	(segment
		(start 126.23038 -57.883806)
		(end 126.23038 -55.847488)
		(width 0.10668)
		(layer "B.Cu")
		(net "JTAG_SCM_MUX_TDO")
	)
	(segment
		(start 136.04113 -56.0578)
		(end 137.023094 -57.039764)
		(width 0.10668)
		(layer "B.Cu")
		(net "JTAG_SCM_MUX_TDO")
	)
	(segment
		(start 133.124956 -56.0578)
		(end 136.04113 -56.0578)
		(width 0.10668)
		(layer "B.Cu")
		(net "JTAG_SCM_MUX_TDO")
	)
	(segment
		(start 144.769586 -58.686954)
		(end 147.215606 -56.240934)
		(width 0.10668)
		(layer "B.Cu")
		(net "JTAG_SCM_MUX_TDO")
	)
	(segment
		(start 127.851154 -54.226714)
		(end 131.29387 -54.226714)
		(width 0.10668)
		(layer "B.Cu")
		(net "JTAG_SCM_MUX_TDO")
	)
	(segment
		(start 142.053564 -57.039764)
		(end 143.700754 -58.686954)
		(width 0.10668)
		(layer "B.Cu")
		(net "JTAG_SCM_MUX_TDO")
	)
	(segment
		(start 131.29387 -54.226714)
		(end 133.124956 -56.0578)
		(width 0.10668)
		(layer "B.Cu")
		(net "JTAG_SCM_MUX_TDO")
	)
	(segment
		(start 137.023094 -57.039764)
		(end 142.053564 -57.039764)
		(width 0.10668)
		(layer "B.Cu")
		(net "JTAG_SCM_MUX_TDO")
	)
	(segment
		(start 147.215606 -56.240934)
		(end 148.022564 -56.240934)
		(width 0.10668)
		(layer "B.Cu")
		(net "JTAG_SCM_MUX_TDO")
	)
	(segment
		(start 124.932186 -59.182)
		(end 126.23038 -57.883806)
		(width 0.10668)
		(layer "B.Cu")
		(net "JTAG_SCM_MUX_TDO")
	)
	(segment
		(start 143.700754 -58.686954)
		(end 144.769586 -58.686954)
		(width 0.10668)
		(layer "B.Cu")
		(net "JTAG_SCM_MUX_TDO")
	)
	(segment
		(start 140.046202 -60.849764)
		(end 139.560046 -60.363608)
		(width 0.10668)
		(layer "F.Cu")
		(net "JTAG_SCM_MUX_TDI")
	)
	(segment
		(start 139.022836 -60.849764)
		(end 138.827002 -60.849764)
		(width 0.10668)
		(layer "F.Cu")
		(net "JTAG_SCM_MUX_TDI")
	)
	(segment
		(start 147.174712 -57.275984)
		(end 148.022564 -57.275984)
		(width 0.10668)
		(layer "F.Cu")
		(net "JTAG_SCM_MUX_TDI")
	)
	(segment
		(start 139.560046 -60.363608)
		(end 139.508992 -60.363608)
		(width 0.10668)
		(layer "F.Cu")
		(net "JTAG_SCM_MUX_TDI")
	)
	(segment
		(start 139.508992 -60.363608)
		(end 139.022836 -60.849764)
		(width 0.10668)
		(layer "F.Cu")
		(net "JTAG_SCM_MUX_TDI")
	)
	(via
		(at 139.508992 -60.363608)
		(size 0.508)
		(drill 0.254)
		(layers "F.Cu" "B.Cu")
		(net "JTAG_SCM_MUX_TDI")
	)
	(via
		(at 148.022564 -57.275984)
		(size 0.508)
		(drill 0.254)
		(layers "F.Cu" "B.Cu")
		(net "JTAG_SCM_MUX_TDI")
	)
	(segment
		(start 146.971004 -57.275984)
		(end 148.022564 -57.275984)
		(width 0.10668)
		(layer "B.Cu")
		(net "JTAG_SCM_MUX_TDI")
	)
	(segment
		(start 140.774166 -59.098434)
		(end 145.148554 -59.098434)
		(width 0.10668)
		(layer "B.Cu")
		(net "JTAG_SCM_MUX_TDI")
	)
	(segment
		(start 139.508992 -60.363608)
		(end 140.774166 -59.098434)
		(width 0.10668)
		(layer "B.Cu")
		(net "JTAG_SCM_MUX_TDI")
	)
	(segment
		(start 145.148554 -59.098434)
		(end 146.971004 -57.275984)
		(width 0.10668)
		(layer "B.Cu")
		(net "JTAG_SCM_MUX_TDI")
	)
	(segment
		(start 117.564154 -83.576414)
		(end 123.908058 -89.920318)
		(width 0.10668)
		(layer "F.Cu")
		(net "JTAG_SCM_MUX_TCK")
	)
	(segment
		(start 113.249964 -71.476362)
		(end 113.249964 -81.548224)
		(width 0.10668)
		(layer "F.Cu")
		(net "JTAG_SCM_MUX_TCK")
	)
	(segment
		(start 271.078452 -105.872788)
		(end 272.475452 -104.475788)
		(width 0.10668)
		(layer "F.Cu")
		(net "JTAG_SCM_MUX_TCK")
	)
	(segment
		(start 119.118634 -66.08318)
		(end 115.273074 -69.92874)
		(width 0.10668)
		(layer "F.Cu")
		(net "JTAG_SCM_MUX_TCK")
	)
	(segment
		(start 115.278154 -83.576414)
		(end 117.564154 -83.576414)
		(width 0.10668)
		(layer "F.Cu")
		(net "JTAG_SCM_MUX_TCK")
	)
	(segment
		(start 114.797586 -69.92874)
		(end 113.249964 -71.476362)
		(width 0.10668)
		(layer "F.Cu")
		(net "JTAG_SCM_MUX_TCK")
	)
	(segment
		(start 113.249964 -81.548224)
		(end 115.278154 -83.576414)
		(width 0.10668)
		(layer "F.Cu")
		(net "JTAG_SCM_MUX_TCK")
	)
	(segment
		(start 269.868142 -105.872788)
		(end 271.078452 -105.872788)
		(width 0.10668)
		(layer "F.Cu")
		(net "JTAG_SCM_MUX_TCK")
	)
	(segment
		(start 119.118634 -62.932056)
		(end 119.118634 -66.08318)
		(width 0.10668)
		(layer "F.Cu")
		(net "JTAG_SCM_MUX_TCK")
	)
	(segment
		(start 115.273074 -69.92874)
		(end 114.797586 -69.92874)
		(width 0.10668)
		(layer "F.Cu")
		(net "JTAG_SCM_MUX_TCK")
	)
	(segment
		(start 119.118634 -61.916056)
		(end 119.118634 -60.900056)
		(width 0.10668)
		(layer "F.Cu")
		(net "JTAG_SCM_MUX_TCK")
	)
	(segment
		(start 119.118634 -61.916056)
		(end 119.118634 -62.932056)
		(width 0.10668)
		(layer "F.Cu")
		(net "JTAG_SCM_MUX_TCK")
	)
	(via
		(at 272.475452 -104.475788)
		(size 0.508)
		(drill 0.254)
		(layers "F.Cu" "B.Cu")
		(net "JTAG_SCM_MUX_TCK")
	)
	(via
		(at 123.908058 -89.920318)
		(size 0.508)
		(drill 0.254)
		(layers "F.Cu" "B.Cu")
		(net "JTAG_SCM_MUX_TCK")
	)
	(segment
		(start 203.102972 -91.431618)
		(end 203.35113 -91.18346)
		(width 0.11684)
		(layer "In2.Cu")
		(net "JTAG_SCM_MUX_TCK")
	)
	(segment
		(start 211.591652 -91.18346)
		(end 214.927942 -94.51975)
		(width 0.11684)
		(layer "In2.Cu")
		(net "JTAG_SCM_MUX_TCK")
	)
	(segment
		(start 263.431528 -101.591618)
		(end 266.315698 -104.475788)
		(width 0.11684)
		(layer "In2.Cu")
		(net "JTAG_SCM_MUX_TCK")
	)
	(segment
		(start 174.074582 -89.56802)
		(end 174.30369 -89.797128)
		(width 0.11684)
		(layer "In2.Cu")
		(net "JTAG_SCM_MUX_TCK")
	)
	(segment
		(start 266.315698 -104.475788)
		(end 272.475452 -104.475788)
		(width 0.11684)
		(layer "In2.Cu")
		(net "JTAG_SCM_MUX_TCK")
	)
	(segment
		(start 214.927942 -94.51975)
		(end 222.99676 -94.51975)
		(width 0.11684)
		(layer "In2.Cu")
		(net "JTAG_SCM_MUX_TCK")
	)
	(segment
		(start 238.094266 -101.591618)
		(end 263.431528 -101.591618)
		(width 0.11684)
		(layer "In2.Cu")
		(net "JTAG_SCM_MUX_TCK")
	)
	(segment
		(start 178.123596 -89.69756)
		(end 178.223418 -89.797382)
		(width 0.11684)
		(layer "In2.Cu")
		(net "JTAG_SCM_MUX_TCK")
	)
	(segment
		(start 224.39376 -95.91675)
		(end 238.094266 -101.591618)
		(width 0.11684)
		(layer "In2.Cu")
		(net "JTAG_SCM_MUX_TCK")
	)
	(segment
		(start 171.786042 -89.56802)
		(end 174.074582 -89.56802)
		(width 0.11684)
		(layer "In2.Cu")
		(net "JTAG_SCM_MUX_TCK")
	)
	(segment
		(start 174.30369 -89.797128)
		(end 175.38954 -89.797128)
		(width 0.11684)
		(layer "In2.Cu")
		(net "JTAG_SCM_MUX_TCK")
	)
	(segment
		(start 203.35113 -91.18346)
		(end 211.591652 -91.18346)
		(width 0.11684)
		(layer "In2.Cu")
		(net "JTAG_SCM_MUX_TCK")
	)
	(segment
		(start 178.223418 -89.797382)
		(end 195.477892 -89.797382)
		(width 0.11684)
		(layer "In2.Cu")
		(net "JTAG_SCM_MUX_TCK")
	)
	(segment
		(start 124.031248 -89.797128)
		(end 171.556934 -89.797128)
		(width 0.11684)
		(layer "In2.Cu")
		(net "JTAG_SCM_MUX_TCK")
	)
	(segment
		(start 175.489108 -89.69756)
		(end 178.123596 -89.69756)
		(width 0.11684)
		(layer "In2.Cu")
		(net "JTAG_SCM_MUX_TCK")
	)
	(segment
		(start 195.477892 -89.797382)
		(end 197.112128 -91.431618)
		(width 0.11684)
		(layer "In2.Cu")
		(net "JTAG_SCM_MUX_TCK")
	)
	(segment
		(start 175.38954 -89.797128)
		(end 175.489108 -89.69756)
		(width 0.11684)
		(layer "In2.Cu")
		(net "JTAG_SCM_MUX_TCK")
	)
	(segment
		(start 171.556934 -89.797128)
		(end 171.786042 -89.56802)
		(width 0.11684)
		(layer "In2.Cu")
		(net "JTAG_SCM_MUX_TCK")
	)
	(segment
		(start 197.112128 -91.431618)
		(end 203.102972 -91.431618)
		(width 0.11684)
		(layer "In2.Cu")
		(net "JTAG_SCM_MUX_TCK")
	)
	(segment
		(start 123.908058 -89.920318)
		(end 124.031248 -89.797128)
		(width 0.11684)
		(layer "In2.Cu")
		(net "JTAG_SCM_MUX_TCK")
	)
	(segment
		(start 222.99676 -94.51975)
		(end 224.39376 -95.91675)
		(width 0.11684)
		(layer "In2.Cu")
		(net "JTAG_SCM_MUX_TCK")
	)
	(segment
		(start 108.940346 -58.502042)
		(end 106.70921 -58.502042)
		(width 0.10668)
		(layer "F.Cu")
		(net "JTAG_SCM_MUX_R_TMS")
	)
	(segment
		(start 106.04881 -58.502042)
		(end 106.70921 -58.502042)
		(width 0.10668)
		(layer "F.Cu")
		(net "JTAG_SCM_MUX_R_TMS")
	)
	(via
		(at 106.70921 -58.502042)
		(size 0.508)
		(drill 0.254)
		(layers "F.Cu" "B.Cu")
		(net "JTAG_SCM_MUX_R_TMS")
	)
	(segment
		(start 128.76403 -59.182)
		(end 127.053086 -59.182)
		(width 0.10668)
		(layer "F.Cu")
		(net "JTAG_SCM_MUX_R_TDO")
	)
	(segment
		(start 126.392686 -59.182)
		(end 127.053086 -59.182)
		(width 0.10668)
		(layer "F.Cu")
		(net "JTAG_SCM_MUX_R_TDO")
	)
	(via
		(at 127.053086 -59.182)
		(size 0.508)
		(drill 0.254)
		(layers "F.Cu" "B.Cu")
		(net "JTAG_SCM_MUX_R_TDO")
	)
	(segment
		(start 137.17524 -60.849764)
		(end 138.026902 -60.849764)
		(width 0.10668)
		(layer "F.Cu")
		(net "JTAG_SCM_MUX_R_TDI")
	)
	(segment
		(start 136.807702 -60.482226)
		(end 137.17524 -60.849764)
		(width 0.10668)
		(layer "F.Cu")
		(net "JTAG_SCM_MUX_R_TDI")
	)
	(segment
		(start 136.807702 -60.482226)
		(end 134.614158 -60.482226)
		(width 0.10668)
		(layer "F.Cu")
		(net "JTAG_SCM_MUX_R_TDI")
	)
	(via
		(at 136.807702 -60.482226)
		(size 0.508)
		(drill 0.254)
		(layers "F.Cu" "B.Cu")
		(net "JTAG_SCM_MUX_R_TDI")
	)
	(segment
		(start 116.984018 -59.802268)
		(end 114.790474 -59.802268)
		(width 0.10668)
		(layer "F.Cu")
		(net "JTAG_SCM_MUX_R_TCK")
	)
	(segment
		(start 117.605556 -60.900056)
		(end 118.318534 -60.900056)
		(width 0.10668)
		(layer "F.Cu")
		(net "JTAG_SCM_MUX_R_TCK")
	)
	(segment
		(start 116.984018 -59.802268)
		(end 116.984018 -60.278518)
		(width 0.10668)
		(layer "F.Cu")
		(net "JTAG_SCM_MUX_R_TCK")
	)
	(segment
		(start 116.984018 -60.278518)
		(end 117.605556 -60.900056)
		(width 0.10668)
		(layer "F.Cu")
		(net "JTAG_SCM_MUX_R_TCK")
	)
	(via
		(at 116.984018 -59.802268)
		(size 0.508)
		(drill 0.254)
		(layers "F.Cu" "B.Cu")
		(net "JTAG_SCM_MUX_R_TCK")
	)
	(segment
		(start 273.15541 -107.823)
		(end 269.868142 -107.823)
		(width 0.10668)
		(layer "F.Cu")
		(net "JTAG_SCM_DBREQ_N")
	)
	(segment
		(start 273.183604 -107.794806)
		(end 273.15541 -107.823)
		(width 0.10668)
		(layer "F.Cu")
		(net "JTAG_SCM_DBREQ_N")
	)
	(segment
		(start 275.953474 -107.794806)
		(end 276.875494 -108.716826)
		(width 0.10668)
		(layer "F.Cu")
		(net "JTAG_SCM_DBREQ_N")
	)
	(segment
		(start 273.183604 -107.794806)
		(end 275.953474 -107.794806)
		(width 0.10668)
		(layer "F.Cu")
		(net "JTAG_SCM_DBREQ_N")
	)
	(via
		(at 274.021042 -68.4276)
		(size 0.508)
		(drill 0.254)
		(layers "F.Cu" "B.Cu")
		(net "JTAG_SCM_DBREQ_N")
	)
	(via
		(at 143.457676 -14.963394)
		(size 0.508)
		(drill 0.254)
		(layers "F.Cu" "B.Cu")
		(net "JTAG_SCM_DBREQ_N")
	)
	(via
		(at 276.875494 -108.716826)
		(size 0.508)
		(drill 0.254)
		(layers "F.Cu" "B.Cu")
		(net "JTAG_SCM_DBREQ_N")
	)
	(segment
		(start 142.2908 -14.163802)
		(end 142.2908 -14.703044)
		(width 0.10668)
		(layer "B.Cu")
		(net "JTAG_SCM_DBREQ_N")
	)
	(segment
		(start 142.55115 -14.963394)
		(end 143.457676 -14.963394)
		(width 0.10668)
		(layer "B.Cu")
		(net "JTAG_SCM_DBREQ_N")
	)
	(segment
		(start 142.2908 -14.703044)
		(end 142.55115 -14.963394)
		(width 0.10668)
		(layer "B.Cu")
		(net "JTAG_SCM_DBREQ_N")
	)
	(segment
		(start 150.4696 -14.157452)
		(end 152.408128 -16.09598)
		(width 0.11684)
		(layer "In2.Cu")
		(net "JTAG_SCM_DBREQ_N")
	)
	(segment
		(start 269.865602 -64.27216)
		(end 274.021042 -68.4276)
		(width 0.11684)
		(layer "In2.Cu")
		(net "JTAG_SCM_DBREQ_N")
	)
	(segment
		(start 188.47308 -17.66062)
		(end 190.62192 -19.80946)
		(width 0.11684)
		(layer "In2.Cu")
		(net "JTAG_SCM_DBREQ_N")
	)
	(segment
		(start 197.58533 -25.111456)
		(end 200.74509 -28.271216)
		(width 0.11684)
		(layer "In2.Cu")
		(net "JTAG_SCM_DBREQ_N")
	)
	(segment
		(start 190.62192 -19.80946)
		(end 196.59346 -19.80946)
		(width 0.11684)
		(layer "In2.Cu")
		(net "JTAG_SCM_DBREQ_N")
	)
	(segment
		(start 210.971384 -45.748702)
		(end 229.494842 -64.27216)
		(width 0.11684)
		(layer "In2.Cu")
		(net "JTAG_SCM_DBREQ_N")
	)
	(segment
		(start 229.494842 -64.27216)
		(end 269.865602 -64.27216)
		(width 0.11684)
		(layer "In2.Cu")
		(net "JTAG_SCM_DBREQ_N")
	)
	(segment
		(start 196.59346 -19.80946)
		(end 197.58533 -20.80133)
		(width 0.11684)
		(layer "In2.Cu")
		(net "JTAG_SCM_DBREQ_N")
	)
	(segment
		(start 211.372958 -38.439598)
		(end 210.971384 -38.841172)
		(width 0.11684)
		(layer "In2.Cu")
		(net "JTAG_SCM_DBREQ_N")
	)
	(segment
		(start 182.213758 -16.20012)
		(end 188.05906 -16.20012)
		(width 0.11684)
		(layer "In2.Cu")
		(net "JTAG_SCM_DBREQ_N")
	)
	(segment
		(start 197.58533 -20.80133)
		(end 197.58533 -25.111456)
		(width 0.11684)
		(layer "In2.Cu")
		(net "JTAG_SCM_DBREQ_N")
	)
	(segment
		(start 188.05906 -16.20012)
		(end 188.47308 -16.61414)
		(width 0.11684)
		(layer "In2.Cu")
		(net "JTAG_SCM_DBREQ_N")
	)
	(segment
		(start 152.408128 -16.09598)
		(end 172.560488 -16.09598)
		(width 0.11684)
		(layer "In2.Cu")
		(net "JTAG_SCM_DBREQ_N")
	)
	(segment
		(start 188.47308 -16.61414)
		(end 188.47308 -17.66062)
		(width 0.11684)
		(layer "In2.Cu")
		(net "JTAG_SCM_DBREQ_N")
	)
	(segment
		(start 143.457676 -14.777466)
		(end 144.07769 -14.157452)
		(width 0.11684)
		(layer "In2.Cu")
		(net "JTAG_SCM_DBREQ_N")
	)
	(segment
		(start 144.07769 -14.157452)
		(end 150.4696 -14.157452)
		(width 0.11684)
		(layer "In2.Cu")
		(net "JTAG_SCM_DBREQ_N")
	)
	(segment
		(start 172.560488 -16.09598)
		(end 173.111414 -15.545054)
		(width 0.11684)
		(layer "In2.Cu")
		(net "JTAG_SCM_DBREQ_N")
	)
	(segment
		(start 210.971384 -38.841172)
		(end 210.971384 -45.748702)
		(width 0.11684)
		(layer "In2.Cu")
		(net "JTAG_SCM_DBREQ_N")
	)
	(segment
		(start 200.74509 -28.271216)
		(end 205.714346 -28.271216)
		(width 0.11684)
		(layer "In2.Cu")
		(net "JTAG_SCM_DBREQ_N")
	)
	(segment
		(start 175.210978 -15.545054)
		(end 176.132744 -14.623288)
		(width 0.11684)
		(layer "In2.Cu")
		(net "JTAG_SCM_DBREQ_N")
	)
	(segment
		(start 143.457676 -14.963394)
		(end 143.457676 -14.777466)
		(width 0.11684)
		(layer "In2.Cu")
		(net "JTAG_SCM_DBREQ_N")
	)
	(segment
		(start 176.132744 -14.623288)
		(end 180.636926 -14.623288)
		(width 0.11684)
		(layer "In2.Cu")
		(net "JTAG_SCM_DBREQ_N")
	)
	(segment
		(start 180.636926 -14.623288)
		(end 182.213758 -16.20012)
		(width 0.11684)
		(layer "In2.Cu")
		(net "JTAG_SCM_DBREQ_N")
	)
	(segment
		(start 205.714346 -28.271216)
		(end 211.372958 -33.929828)
		(width 0.11684)
		(layer "In2.Cu")
		(net "JTAG_SCM_DBREQ_N")
	)
	(segment
		(start 173.111414 -15.545054)
		(end 175.210978 -15.545054)
		(width 0.11684)
		(layer "In2.Cu")
		(net "JTAG_SCM_DBREQ_N")
	)
	(segment
		(start 211.372958 -33.929828)
		(end 211.372958 -38.439598)
		(width 0.11684)
		(layer "In2.Cu")
		(net "JTAG_SCM_DBREQ_N")
	)
	(segment
		(start 277.537418 -97.515426)
		(end 277.537418 -86.106)
		(width 0.11684)
		(layer "In4.Cu")
		(net "JTAG_SCM_DBREQ_N")
	)
	(segment
		(start 276.875494 -99.113594)
		(end 277.537418 -97.515426)
		(width 0.11684)
		(layer "In4.Cu")
		(net "JTAG_SCM_DBREQ_N")
	)
	(segment
		(start 276.875494 -108.716826)
		(end 276.875494 -99.113594)
		(width 0.11684)
		(layer "In4.Cu")
		(net "JTAG_SCM_DBREQ_N")
	)
	(segment
		(start 277.537418 -86.106)
		(end 274.021042 -68.4276)
		(width 0.11684)
		(layer "In4.Cu")
		(net "JTAG_SCM_DBREQ_N")
	)
	(via
		(at 141.977872 -65.634362)
		(size 0.6604)
		(drill 0.3302)
		(layers "F.Cu" "B.Cu")
		(net "JTAG_PLD_TMS")
	)
	(segment
		(start 141.977872 -69.652896)
		(end 141.977872 -65.634362)
		(width 0.10668)
		(layer "B.Cu")
		(net "JTAG_PLD_TMS")
	)
	(segment
		(start 141.990064 -69.665088)
		(end 141.977872 -69.652896)
		(width 0.10668)
		(layer "B.Cu")
		(net "JTAG_PLD_TMS")
	)
	(segment
		(start 141.977872 -64.44234)
		(end 141.977872 -65.634362)
		(width 0.10668)
		(layer "B.Cu")
		(net "JTAG_PLD_TMS")
	)
	(via
		(at 150.0886 -65.59804)
		(size 0.6604)
		(drill 0.3302)
		(layers "F.Cu" "B.Cu")
		(net "JTAG_PLD_TDO")
	)
	(segment
		(start 149.597872 -64.44234)
		(end 149.98192 -64.44234)
		(width 0.10668)
		(layer "B.Cu")
		(net "JTAG_PLD_TDO")
	)
	(segment
		(start 150.0886 -67.01028)
		(end 150.0886 -65.59804)
		(width 0.10668)
		(layer "B.Cu")
		(net "JTAG_PLD_TDO")
	)
	(segment
		(start 149.597872 -67.501008)
		(end 150.0886 -67.01028)
		(width 0.10668)
		(layer "B.Cu")
		(net "JTAG_PLD_TDO")
	)
	(segment
		(start 149.610064 -69.665088)
		(end 149.597872 -69.652896)
		(width 0.10668)
		(layer "B.Cu")
		(net "JTAG_PLD_TDO")
	)
	(segment
		(start 149.98192 -64.44234)
		(end 150.0886 -64.54902)
		(width 0.10668)
		(layer "B.Cu")
		(net "JTAG_PLD_TDO")
	)
	(segment
		(start 150.0886 -64.54902)
		(end 150.0886 -65.59804)
		(width 0.10668)
		(layer "B.Cu")
		(net "JTAG_PLD_TDO")
	)
	(segment
		(start 149.597872 -69.652896)
		(end 149.597872 -67.501008)
		(width 0.10668)
		(layer "B.Cu")
		(net "JTAG_PLD_TDO")
	)
	(via
		(at 152.137872 -60.675012)
		(size 0.508)
		(drill 0.254)
		(layers "F.Cu" "B.Cu")
		(net "JTAG_PLD_TDI")
	)
	(via
		(at 165.451536 -113.094008)
		(size 0.508)
		(drill 0.254)
		(layers "F.Cu" "B.Cu")
		(net "JTAG_PLD_TDI")
	)
	(segment
		(start 165.474142 -113.094008)
		(end 165.451536 -113.094008)
		(width 0.10668)
		(layer "B.Cu")
		(net "JTAG_PLD_TDI")
	)
	(segment
		(start 152.137872 -69.652896)
		(end 152.150064 -69.665088)
		(width 0.10668)
		(layer "B.Cu")
		(net "JTAG_PLD_TDI")
	)
	(segment
		(start 166.555166 -112.902238)
		(end 166.34841 -113.108994)
		(width 0.10668)
		(layer "B.Cu")
		(net "JTAG_PLD_TDI")
	)
	(segment
		(start 166.34841 -113.108994)
		(end 165.489128 -113.108994)
		(width 0.10668)
		(layer "B.Cu")
		(net "JTAG_PLD_TDI")
	)
	(segment
		(start 165.489128 -113.108994)
		(end 165.474142 -113.094008)
		(width 0.10668)
		(layer "B.Cu")
		(net "JTAG_PLD_TDI")
	)
	(segment
		(start 152.137872 -60.675012)
		(end 152.137872 -69.652896)
		(width 0.10668)
		(layer "B.Cu")
		(net "JTAG_PLD_TDI")
	)
	(segment
		(start 150.976584 -113.470182)
		(end 150.695406 -113.75136)
		(width 0.11684)
		(layer "In4.Cu")
		(net "JTAG_PLD_TDI")
	)
	(segment
		(start 142.17396 -109.323632)
		(end 142.17396 -106.52252)
		(width 0.11684)
		(layer "In4.Cu")
		(net "JTAG_PLD_TDI")
	)
	(segment
		(start 158.309564 -114.181382)
		(end 154.053286 -114.181382)
		(width 0.11684)
		(layer "In4.Cu")
		(net "JTAG_PLD_TDI")
	)
	(segment
		(start 142.17396 -106.52252)
		(end 141.425676 -105.774236)
		(width 0.11684)
		(layer "In4.Cu")
		(net "JTAG_PLD_TDI")
	)
	(segment
		(start 150.695406 -113.75136)
		(end 149.121876 -113.75136)
		(width 0.11684)
		(layer "In4.Cu")
		(net "JTAG_PLD_TDI")
	)
	(segment
		(start 144.570704 -111.720376)
		(end 142.17396 -109.323632)
		(width 0.11684)
		(layer "In4.Cu")
		(net "JTAG_PLD_TDI")
	)
	(segment
		(start 135.34644 -84.247228)
		(end 135.34644 -67.421252)
		(width 0.11684)
		(layer "In4.Cu")
		(net "JTAG_PLD_TDI")
	)
	(segment
		(start 154.053286 -114.181382)
		(end 153.342086 -113.470182)
		(width 0.11684)
		(layer "In4.Cu")
		(net "JTAG_PLD_TDI")
	)
	(segment
		(start 165.451536 -113.094008)
		(end 165.334696 -112.977168)
		(width 0.11684)
		(layer "In4.Cu")
		(net "JTAG_PLD_TDI")
	)
	(segment
		(start 141.425676 -105.774236)
		(end 141.425676 -90.326464)
		(width 0.11684)
		(layer "In4.Cu")
		(net "JTAG_PLD_TDI")
	)
	(segment
		(start 141.425676 -90.326464)
		(end 135.34644 -84.247228)
		(width 0.11684)
		(layer "In4.Cu")
		(net "JTAG_PLD_TDI")
	)
	(segment
		(start 165.334696 -112.977168)
		(end 159.513778 -112.977168)
		(width 0.11684)
		(layer "In4.Cu")
		(net "JTAG_PLD_TDI")
	)
	(segment
		(start 159.513778 -112.977168)
		(end 158.309564 -114.181382)
		(width 0.11684)
		(layer "In4.Cu")
		(net "JTAG_PLD_TDI")
	)
	(segment
		(start 135.34644 -67.421252)
		(end 137.469372 -65.29832)
		(width 0.11684)
		(layer "In4.Cu")
		(net "JTAG_PLD_TDI")
	)
	(segment
		(start 147.090892 -111.720376)
		(end 144.570704 -111.720376)
		(width 0.11684)
		(layer "In4.Cu")
		(net "JTAG_PLD_TDI")
	)
	(segment
		(start 147.514564 -65.29832)
		(end 152.137872 -60.675012)
		(width 0.11684)
		(layer "In4.Cu")
		(net "JTAG_PLD_TDI")
	)
	(segment
		(start 137.469372 -65.29832)
		(end 147.514564 -65.29832)
		(width 0.11684)
		(layer "In4.Cu")
		(net "JTAG_PLD_TDI")
	)
	(segment
		(start 153.342086 -113.470182)
		(end 150.976584 -113.470182)
		(width 0.11684)
		(layer "In4.Cu")
		(net "JTAG_PLD_TDI")
	)
	(segment
		(start 149.121876 -113.75136)
		(end 147.090892 -111.720376)
		(width 0.11684)
		(layer "In4.Cu")
		(net "JTAG_PLD_TDI")
	)
	(via
		(at 136.897872 -65.598294)
		(size 0.6604)
		(drill 0.3302)
		(layers "F.Cu" "B.Cu")
		(net "JTAG_PLD_TCK")
	)
	(segment
		(start 136.910064 -69.665088)
		(end 136.897872 -69.652896)
		(width 0.10668)
		(layer "B.Cu")
		(net "JTAG_PLD_TCK")
	)
	(segment
		(start 136.897872 -69.652896)
		(end 136.897872 -65.598294)
		(width 0.10668)
		(layer "B.Cu")
		(net "JTAG_PLD_TCK")
	)
	(segment
		(start 136.897872 -64.44234)
		(end 136.897872 -65.598294)
		(width 0.10668)
		(layer "B.Cu")
		(net "JTAG_PLD_TCK")
	)
	(segment
		(start 276.86889 -98.673158)
		(end 276.13483 -98.673158)
		(width 0.10668)
		(layer "F.Cu")
		(net "JTAG_P1_R_TRST_N")
	)
	(segment
		(start 278.666194 -97.969324)
		(end 277.572724 -97.969324)
		(width 0.10668)
		(layer "F.Cu")
		(net "JTAG_P1_R_TRST_N")
	)
	(segment
		(start 275.817076 -98.355404)
		(end 275.54174 -98.355404)
		(width 0.10668)
		(layer "F.Cu")
		(net "JTAG_P1_R_TRST_N")
	)
	(segment
		(start 276.13483 -98.673158)
		(end 275.817076 -98.355404)
		(width 0.10668)
		(layer "F.Cu")
		(net "JTAG_P1_R_TRST_N")
	)
	(segment
		(start 277.572724 -97.969324)
		(end 276.86889 -98.673158)
		(width 0.10668)
		(layer "F.Cu")
		(net "JTAG_P1_R_TRST_N")
	)
	(via
		(at 276.86889 -98.673158)
		(size 0.762)
		(drill 0.381)
		(layers "F.Cu" "B.Cu")
		(net "JTAG_P1_R_TRST_N")
	)
	(segment
		(start 277.0378 -97.319084)
		(end 276.87524 -97.156524)
		(width 0.10668)
		(layer "F.Cu")
		(net "JTAG_P1_R_TMS")
	)
	(segment
		(start 276.87524 -97.156524)
		(end 276.501352 -97.156524)
		(width 0.10668)
		(layer "F.Cu")
		(net "JTAG_P1_R_TMS")
	)
	(segment
		(start 276.501352 -97.156524)
		(end 275.72462 -97.156524)
		(width 0.10668)
		(layer "F.Cu")
		(net "JTAG_P1_R_TMS")
	)
	(segment
		(start 278.666194 -97.319084)
		(end 277.0378 -97.319084)
		(width 0.10668)
		(layer "F.Cu")
		(net "JTAG_P1_R_TMS")
	)
	(segment
		(start 275.72462 -97.156524)
		(end 275.54174 -97.339404)
		(width 0.10668)
		(layer "F.Cu")
		(net "JTAG_P1_R_TMS")
	)
	(via
		(at 276.501352 -97.156524)
		(size 0.762)
		(drill 0.381)
		(layers "F.Cu" "B.Cu")
		(net "JTAG_P1_R_TMS")
	)
	(segment
		(start 276.02942 -95.835724)
		(end 275.54174 -96.323404)
		(width 0.10668)
		(layer "F.Cu")
		(net "JTAG_P1_R_TCK")
	)
	(segment
		(start 277.327106 -96.669098)
		(end 276.493732 -95.835724)
		(width 0.10668)
		(layer "F.Cu")
		(net "JTAG_P1_R_TCK")
	)
	(segment
		(start 276.493732 -95.835724)
		(end 276.02942 -95.835724)
		(width 0.10668)
		(layer "F.Cu")
		(net "JTAG_P1_R_TCK")
	)
	(segment
		(start 278.666194 -96.669098)
		(end 277.327106 -96.669098)
		(width 0.10668)
		(layer "F.Cu")
		(net "JTAG_P1_R_TCK")
	)
	(via
		(at 276.493732 -95.835724)
		(size 0.762)
		(drill 0.381)
		(layers "F.Cu" "B.Cu")
		(net "JTAG_P1_R_TCK")
	)
	(segment
		(start 277.125938 -100.11918)
		(end 276.408134 -100.11918)
		(width 0.10668)
		(layer "F.Cu")
		(net "JTAG_P1_R_DBREQ_N")
	)
	(segment
		(start 277.640034 -99.605084)
		(end 277.125938 -100.11918)
		(width 0.10668)
		(layer "F.Cu")
		(net "JTAG_P1_R_DBREQ_N")
	)
	(segment
		(start 277.779734 -98.61931)
		(end 277.640034 -98.75901)
		(width 0.10668)
		(layer "F.Cu")
		(net "JTAG_P1_R_DBREQ_N")
	)
	(segment
		(start 278.666194 -98.61931)
		(end 277.779734 -98.61931)
		(width 0.10668)
		(layer "F.Cu")
		(net "JTAG_P1_R_DBREQ_N")
	)
	(segment
		(start 276.408134 -100.11918)
		(end 276.289516 -100.11918)
		(width 0.10668)
		(layer "F.Cu")
		(net "JTAG_P1_R_DBREQ_N")
	)
	(segment
		(start 276.289516 -100.11918)
		(end 275.54174 -99.371404)
		(width 0.10668)
		(layer "F.Cu")
		(net "JTAG_P1_R_DBREQ_N")
	)
	(segment
		(start 277.640034 -98.75901)
		(end 277.640034 -99.605084)
		(width 0.10668)
		(layer "F.Cu")
		(net "JTAG_P1_R_DBREQ_N")
	)
	(via
		(at 276.408134 -100.11918)
		(size 0.762)
		(drill 0.381)
		(layers "F.Cu" "B.Cu")
		(net "JTAG_P1_R_DBREQ_N")
	)
	(segment
		(start 252.08484 -93.119194)
		(end 252.08484 -94.147386)
		(width 0.10668)
		(layer "F.Cu")
		(net "JTAG_P0_R_TRST_N")
	)
	(segment
		(start 252.08484 -94.147386)
		(end 252.568964 -94.63151)
		(width 0.10668)
		(layer "F.Cu")
		(net "JTAG_P0_R_TRST_N")
	)
	(segment
		(start 252.568964 -96.260412)
		(end 252.56363 -96.265746)
		(width 0.10668)
		(layer "F.Cu")
		(net "JTAG_P0_R_TRST_N")
	)
	(segment
		(start 252.568964 -94.63151)
		(end 252.568964 -96.260412)
		(width 0.10668)
		(layer "F.Cu")
		(net "JTAG_P0_R_TRST_N")
	)
	(via
		(at 252.08484 -94.147386)
		(size 0.508)
		(drill 0.254)
		(layers "F.Cu" "B.Cu")
		(net "JTAG_P0_R_TRST_N")
	)
	(segment
		(start 253.209806 -95.035624)
		(end 253.209806 -96.261682)
		(width 0.10668)
		(layer "F.Cu")
		(net "JTAG_P0_R_TMS")
	)
	(segment
		(start 253.209806 -94.623128)
		(end 253.209806 -95.035624)
		(width 0.10668)
		(layer "F.Cu")
		(net "JTAG_P0_R_TMS")
	)
	(segment
		(start 253.209806 -96.261682)
		(end 253.21387 -96.265746)
		(width 0.10668)
		(layer "F.Cu")
		(net "JTAG_P0_R_TMS")
	)
	(segment
		(start 252.855222 -94.268544)
		(end 253.209806 -94.623128)
		(width 0.10668)
		(layer "F.Cu")
		(net "JTAG_P0_R_TMS")
	)
	(segment
		(start 252.855222 -93.364812)
		(end 252.855222 -94.268544)
		(width 0.10668)
		(layer "F.Cu")
		(net "JTAG_P0_R_TMS")
	)
	(segment
		(start 253.10084 -93.119194)
		(end 252.855222 -93.364812)
		(width 0.10668)
		(layer "F.Cu")
		(net "JTAG_P0_R_TMS")
	)
	(via
		(at 253.209806 -95.035624)
		(size 0.508)
		(drill 0.254)
		(layers "F.Cu" "B.Cu")
		(net "JTAG_P0_R_TMS")
	)
	(segment
		(start 254.11684 -93.86189)
		(end 254.11684 -95.142304)
		(width 0.10668)
		(layer "F.Cu")
		(net "JTAG_P0_R_TCK")
	)
	(segment
		(start 254.11684 -93.119194)
		(end 254.11684 -93.86189)
		(width 0.10668)
		(layer "F.Cu")
		(net "JTAG_P0_R_TCK")
	)
	(segment
		(start 254.11684 -95.142304)
		(end 253.863856 -95.395288)
		(width 0.10668)
		(layer "F.Cu")
		(net "JTAG_P0_R_TCK")
	)
	(segment
		(start 253.863856 -95.395288)
		(end 253.863856 -96.265746)
		(width 0.10668)
		(layer "F.Cu")
		(net "JTAG_P0_R_TCK")
	)
	(via
		(at 254.11684 -93.86189)
		(size 0.508)
		(drill 0.254)
		(layers "F.Cu" "B.Cu")
		(net "JTAG_P0_R_TCK")
	)
	(segment
		(start 251.913644 -95.498412)
		(end 251.913644 -96.265746)
		(width 0.10668)
		(layer "F.Cu")
		(net "JTAG_P0_R_DBREQ_N")
	)
	(segment
		(start 251.06884 -93.119194)
		(end 251.06884 -94.296992)
		(width 0.10668)
		(layer "F.Cu")
		(net "JTAG_P0_R_DBREQ_N")
	)
	(segment
		(start 251.116084 -94.344236)
		(end 251.116084 -94.700852)
		(width 0.10668)
		(layer "F.Cu")
		(net "JTAG_P0_R_DBREQ_N")
	)
	(segment
		(start 251.06884 -94.296992)
		(end 251.116084 -94.344236)
		(width 0.10668)
		(layer "F.Cu")
		(net "JTAG_P0_R_DBREQ_N")
	)
	(segment
		(start 251.116084 -94.700852)
		(end 251.913644 -95.498412)
		(width 0.10668)
		(layer "F.Cu")
		(net "JTAG_P0_R_DBREQ_N")
	)
	(via
		(at 251.116084 -94.344236)
		(size 0.762)
		(drill 0.381)
		(layers "F.Cu" "B.Cu")
		(net "JTAG_P0_R_DBREQ_N")
	)
	(segment
		(start 261.797038 -98.755962)
		(end 261.280148 -98.970084)
		(width 0.10668)
		(layer "F.Cu")
		(net "JTAG_DBREQ_R_N")
	)
	(segment
		(start 264.26795 -107.823)
		(end 262.496046 -107.823)
		(width 0.10668)
		(layer "F.Cu")
		(net "JTAG_DBREQ_R_N")
	)
	(segment
		(start 264.17143 -98.755962)
		(end 261.797038 -98.755962)
		(width 0.10668)
		(layer "F.Cu")
		(net "JTAG_DBREQ_R_N")
	)
	(segment
		(start 265.265408 -99.035108)
		(end 264.986262 -98.755962)
		(width 0.10668)
		(layer "F.Cu")
		(net "JTAG_DBREQ_R_N")
	)
	(segment
		(start 264.651236 -100.926138)
		(end 265.265408 -100.311966)
		(width 0.10668)
		(layer "F.Cu")
		(net "JTAG_DBREQ_R_N")
	)
	(segment
		(start 261.364476 -107.823)
		(end 260.443472 -106.901996)
		(width 0.10668)
		(layer "F.Cu")
		(net "JTAG_DBREQ_R_N")
	)
	(segment
		(start 265.265408 -100.311966)
		(end 265.265408 -99.035108)
		(width 0.10668)
		(layer "F.Cu")
		(net "JTAG_DBREQ_R_N")
	)
	(segment
		(start 260.443472 -103.904034)
		(end 263.421368 -100.926138)
		(width 0.10668)
		(layer "F.Cu")
		(net "JTAG_DBREQ_R_N")
	)
	(segment
		(start 261.280148 -98.970084)
		(end 260.234176 -100.016056)
		(width 0.10668)
		(layer "F.Cu")
		(net "JTAG_DBREQ_R_N")
	)
	(segment
		(start 263.421368 -100.926138)
		(end 264.651236 -100.926138)
		(width 0.10668)
		(layer "F.Cu")
		(net "JTAG_DBREQ_R_N")
	)
	(segment
		(start 260.443472 -106.901996)
		(end 260.443472 -103.904034)
		(width 0.10668)
		(layer "F.Cu")
		(net "JTAG_DBREQ_R_N")
	)
	(segment
		(start 264.986262 -98.755962)
		(end 264.17143 -98.755962)
		(width 0.10668)
		(layer "F.Cu")
		(net "JTAG_DBREQ_R_N")
	)
	(segment
		(start 262.496046 -107.823)
		(end 261.364476 -107.823)
		(width 0.10668)
		(layer "F.Cu")
		(net "JTAG_DBREQ_R_N")
	)
	(via
		(at 262.496046 -107.823)
		(size 0.762)
		(drill 0.381)
		(layers "F.Cu" "B.Cu")
		(net "JTAG_DBREQ_R_N")
	)
	(segment
		(start 285.698438 -98.61931)
		(end 286.535876 -99.456748)
		(width 0.10668)
		(layer "F.Cu")
		(net "JTAG_DBREQ_N")
	)
	(segment
		(start 251.913644 -101.865938)
		(end 251.913644 -104.20096)
		(width 0.10668)
		(layer "F.Cu")
		(net "JTAG_DBREQ_N")
	)
	(segment
		(start 255.358138 -97.504758)
		(end 264.916666 -87.94623)
		(width 0.10668)
		(layer "F.Cu")
		(net "JTAG_DBREQ_N")
	)
	(segment
		(start 258.826 -101.62794)
		(end 259.431536 -101.022404)
		(width 0.10668)
		(layer "F.Cu")
		(net "JTAG_DBREQ_N")
	)
	(segment
		(start 289.71494 -92.79763)
		(end 291.383212 -94.465902)
		(width 0.10668)
		(layer "F.Cu")
		(net "JTAG_DBREQ_N")
	)
	(segment
		(start 286.535876 -99.456748)
		(end 287.3756 -99.456748)
		(width 0.10668)
		(layer "F.Cu")
		(net "JTAG_DBREQ_N")
	)
	(segment
		(start 284.266386 -98.61931)
		(end 285.698438 -98.61931)
		(width 0.10668)
		(layer "F.Cu")
		(net "JTAG_DBREQ_N")
	)
	(segment
		(start 253.766066 -106.053382)
		(end 257.770884 -106.053382)
		(width 0.10668)
		(layer "F.Cu")
		(net "JTAG_DBREQ_N")
	)
	(segment
		(start 251.913644 -104.20096)
		(end 253.766066 -106.053382)
		(width 0.10668)
		(layer "F.Cu")
		(net "JTAG_DBREQ_N")
	)
	(segment
		(start 282.31719 -92.79763)
		(end 289.71494 -92.79763)
		(width 0.10668)
		(layer "F.Cu")
		(net "JTAG_DBREQ_N")
	)
	(segment
		(start 291.383212 -94.465902)
		(end 291.383212 -98.217736)
		(width 0.10668)
		(layer "F.Cu")
		(net "JTAG_DBREQ_N")
	)
	(segment
		(start 290.1442 -99.456748)
		(end 287.3756 -99.456748)
		(width 0.10668)
		(layer "F.Cu")
		(net "JTAG_DBREQ_N")
	)
	(segment
		(start 291.383212 -98.217736)
		(end 290.1442 -99.456748)
		(width 0.10668)
		(layer "F.Cu")
		(net "JTAG_DBREQ_N")
	)
	(segment
		(start 259.431536 -101.022404)
		(end 259.431536 -100.018596)
		(width 0.10668)
		(layer "F.Cu")
		(net "JTAG_DBREQ_N")
	)
	(segment
		(start 251.913644 -101.865938)
		(end 251.913644 -99.723194)
		(width 0.10668)
		(layer "F.Cu")
		(net "JTAG_DBREQ_N")
	)
	(segment
		(start 258.826 -104.998266)
		(end 258.826 -101.62794)
		(width 0.10668)
		(layer "F.Cu")
		(net "JTAG_DBREQ_N")
	)
	(segment
		(start 259.431536 -100.018596)
		(end 259.434076 -100.016056)
		(width 0.10668)
		(layer "F.Cu")
		(net "JTAG_DBREQ_N")
	)
	(segment
		(start 257.770884 -106.053382)
		(end 258.826 -104.998266)
		(width 0.10668)
		(layer "F.Cu")
		(net "JTAG_DBREQ_N")
	)
	(segment
		(start 277.46579 -87.94623)
		(end 282.31719 -92.79763)
		(width 0.10668)
		(layer "F.Cu")
		(net "JTAG_DBREQ_N")
	)
	(segment
		(start 264.916666 -87.94623)
		(end 277.46579 -87.94623)
		(width 0.10668)
		(layer "F.Cu")
		(net "JTAG_DBREQ_N")
	)
	(segment
		(start 254.13208 -97.504758)
		(end 255.358138 -97.504758)
		(width 0.10668)
		(layer "F.Cu")
		(net "JTAG_DBREQ_N")
	)
	(segment
		(start 251.913644 -99.723194)
		(end 254.13208 -97.504758)
		(width 0.10668)
		(layer "F.Cu")
		(net "JTAG_DBREQ_N")
	)
	(via
		(at 287.3756 -99.456748)
		(size 0.762)
		(drill 0.381)
		(layers "F.Cu" "B.Cu")
		(net "JTAG_DBREQ_N")
	)
	(segment
		(start 130.067304 -55.074312)
		(end 130.067304 -56.090058)
		(width 0.10668)
		(layer "F.Cu")
		(net "JTAG_CPUX_TDO")
	)
	(segment
		(start 240.698274 -159.680148)
		(end 241.579908 -159.680148)
		(width 0.10668)
		(layer "F.Cu")
		(net "JTAG_CPUX_TDO")
	)
	(segment
		(start 130.067304 -56.090058)
		(end 129.967736 -56.189626)
		(width 0.10668)
		(layer "F.Cu")
		(net "JTAG_CPUX_TDO")
	)
	(via
		(at 241.579908 -159.680148)
		(size 0.508)
		(drill 0.254)
		(layers "F.Cu" "B.Cu")
		(net "JTAG_CPUX_TDO")
	)
	(via
		(at 129.967736 -56.189626)
		(size 0.508)
		(drill 0.254)
		(layers "F.Cu" "B.Cu")
		(net "JTAG_CPUX_TDO")
	)
	(segment
		(start 222.73006 -101.331522)
		(end 212.87994 -91.481402)
		(width 0.10668)
		(layer "B.Cu")
		(net "JTAG_CPUX_TDO")
	)
	(segment
		(start 156.12745 -72.892158)
		(end 156.12745 -61.736478)
		(width 0.10668)
		(layer "B.Cu")
		(net "JTAG_CPUX_TDO")
	)
	(segment
		(start 236.927898 -161.627566)
		(end 235.55833 -160.257998)
		(width 0.10668)
		(layer "B.Cu")
		(net "JTAG_CPUX_TDO")
	)
	(segment
		(start 135.40867 -61.63056)
		(end 129.967736 -56.189626)
		(width 0.10668)
		(layer "B.Cu")
		(net "JTAG_CPUX_TDO")
	)
	(segment
		(start 141.303248 -61.63056)
		(end 135.40867 -61.63056)
		(width 0.10668)
		(layer "B.Cu")
		(net "JTAG_CPUX_TDO")
	)
	(segment
		(start 157.64002 -78.977744)
		(end 157.64002 -74.404728)
		(width 0.10668)
		(layer "B.Cu")
		(net "JTAG_CPUX_TDO")
	)
	(segment
		(start 226.93884 -146.147028)
		(end 222.73006 -141.938248)
		(width 0.10668)
		(layer "B.Cu")
		(net "JTAG_CPUX_TDO")
	)
	(segment
		(start 141.999208 -60.9346)
		(end 141.303248 -61.63056)
		(width 0.10668)
		(layer "B.Cu")
		(net "JTAG_CPUX_TDO")
	)
	(segment
		(start 157.64002 -74.404728)
		(end 156.12745 -72.892158)
		(width 0.10668)
		(layer "B.Cu")
		(net "JTAG_CPUX_TDO")
	)
	(segment
		(start 241.579908 -159.680148)
		(end 239.63249 -161.627566)
		(width 0.10668)
		(layer "B.Cu")
		(net "JTAG_CPUX_TDO")
	)
	(segment
		(start 146.936968 -60.9346)
		(end 141.999208 -60.9346)
		(width 0.10668)
		(layer "B.Cu")
		(net "JTAG_CPUX_TDO")
	)
	(segment
		(start 156.12745 -61.736478)
		(end 154.233372 -59.8424)
		(width 0.10668)
		(layer "B.Cu")
		(net "JTAG_CPUX_TDO")
	)
	(segment
		(start 166.451026 -82.271362)
		(end 165.286182 -83.436206)
		(width 0.10668)
		(layer "B.Cu")
		(net "JTAG_CPUX_TDO")
	)
	(segment
		(start 230.194866 -160.257998)
		(end 226.93884 -157.001972)
		(width 0.10668)
		(layer "B.Cu")
		(net "JTAG_CPUX_TDO")
	)
	(segment
		(start 185.914792 -82.271362)
		(end 166.451026 -82.271362)
		(width 0.10668)
		(layer "B.Cu")
		(net "JTAG_CPUX_TDO")
	)
	(segment
		(start 212.87994 -89.630504)
		(end 208.530444 -85.281008)
		(width 0.10668)
		(layer "B.Cu")
		(net "JTAG_CPUX_TDO")
	)
	(segment
		(start 154.233372 -59.8424)
		(end 148.029168 -59.8424)
		(width 0.10668)
		(layer "B.Cu")
		(net "JTAG_CPUX_TDO")
	)
	(segment
		(start 222.73006 -141.938248)
		(end 222.73006 -101.331522)
		(width 0.10668)
		(layer "B.Cu")
		(net "JTAG_CPUX_TDO")
	)
	(segment
		(start 226.93884 -157.001972)
		(end 226.93884 -146.147028)
		(width 0.10668)
		(layer "B.Cu")
		(net "JTAG_CPUX_TDO")
	)
	(segment
		(start 239.63249 -161.627566)
		(end 236.927898 -161.627566)
		(width 0.10668)
		(layer "B.Cu")
		(net "JTAG_CPUX_TDO")
	)
	(segment
		(start 198.556118 -85.281008)
		(end 196.52869 -83.25358)
		(width 0.10668)
		(layer "B.Cu")
		(net "JTAG_CPUX_TDO")
	)
	(segment
		(start 148.029168 -59.8424)
		(end 146.936968 -60.9346)
		(width 0.10668)
		(layer "B.Cu")
		(net "JTAG_CPUX_TDO")
	)
	(segment
		(start 165.286182 -83.436206)
		(end 162.098482 -83.436206)
		(width 0.10668)
		(layer "B.Cu")
		(net "JTAG_CPUX_TDO")
	)
	(segment
		(start 162.098482 -83.436206)
		(end 157.64002 -78.977744)
		(width 0.10668)
		(layer "B.Cu")
		(net "JTAG_CPUX_TDO")
	)
	(segment
		(start 208.530444 -85.281008)
		(end 198.556118 -85.281008)
		(width 0.10668)
		(layer "B.Cu")
		(net "JTAG_CPUX_TDO")
	)
	(segment
		(start 235.55833 -160.257998)
		(end 230.194866 -160.257998)
		(width 0.10668)
		(layer "B.Cu")
		(net "JTAG_CPUX_TDO")
	)
	(segment
		(start 186.89701 -83.25358)
		(end 185.914792 -82.271362)
		(width 0.10668)
		(layer "B.Cu")
		(net "JTAG_CPUX_TDO")
	)
	(segment
		(start 212.87994 -91.481402)
		(end 212.87994 -89.630504)
		(width 0.10668)
		(layer "B.Cu")
		(net "JTAG_CPUX_TDO")
	)
	(segment
		(start 196.52869 -83.25358)
		(end 186.89701 -83.25358)
		(width 0.10668)
		(layer "B.Cu")
		(net "JTAG_CPUX_TDO")
	)
	(segment
		(start 126.84252 -56.384698)
		(end 126.84252 -56.51754)
		(width 0.10668)
		(layer "F.Cu")
		(net "JTAG_CPUX_TDI")
	)
	(segment
		(start 236.58957 -147.973542)
		(end 237.614968 -147.973542)
		(width 0.10668)
		(layer "F.Cu")
		(net "JTAG_CPUX_TDI")
	)
	(segment
		(start 237.614968 -147.973542)
		(end 238.07674 -147.51177)
		(width 0.10668)
		(layer "F.Cu")
		(net "JTAG_CPUX_TDI")
	)
	(segment
		(start 232.889806 -149.923754)
		(end 231.325674 -149.923754)
		(width 0.10668)
		(layer "F.Cu")
		(net "JTAG_CPUX_TDI")
	)
	(segment
		(start 127.305054 -55.922164)
		(end 126.84252 -56.384698)
		(width 0.10668)
		(layer "F.Cu")
		(net "JTAG_CPUX_TDI")
	)
	(via
		(at 126.84252 -56.51754)
		(size 0.508)
		(drill 0.254)
		(layers "F.Cu" "B.Cu")
		(net "JTAG_CPUX_TDI")
	)
	(via
		(at 231.325674 -149.923754)
		(size 0.508)
		(drill 0.254)
		(layers "F.Cu" "B.Cu")
		(net "JTAG_CPUX_TDI")
	)
	(via
		(at 238.07674 -147.51177)
		(size 0.508)
		(drill 0.254)
		(layers "F.Cu" "B.Cu")
		(net "JTAG_CPUX_TDI")
	)
	(segment
		(start 141.82852 -60.52312)
		(end 141.13256 -61.21908)
		(width 0.10668)
		(layer "B.Cu")
		(net "JTAG_CPUX_TDI")
	)
	(segment
		(start 133.76656 -57.50306)
		(end 131.497324 -55.233824)
		(width 0.10668)
		(layer "B.Cu")
		(net "JTAG_CPUX_TDI")
	)
	(segment
		(start 233.737658 -147.51177)
		(end 231.325674 -149.923754)
		(width 0.10668)
		(layer "B.Cu")
		(net "JTAG_CPUX_TDI")
	)
	(segment
		(start 165.115494 -83.024726)
		(end 162.26917 -83.024726)
		(width 0.10668)
		(layer "B.Cu")
		(net "JTAG_CPUX_TDI")
	)
	(segment
		(start 158.0515 -78.807056)
		(end 158.0515 -74.23404)
		(width 0.10668)
		(layer "B.Cu")
		(net "JTAG_CPUX_TDI")
	)
	(segment
		(start 196.727572 -82.8421)
		(end 187.067698 -82.8421)
		(width 0.10668)
		(layer "B.Cu")
		(net "JTAG_CPUX_TDI")
	)
	(segment
		(start 156.53893 -72.72147)
		(end 156.53893 -61.56579)
		(width 0.10668)
		(layer "B.Cu")
		(net "JTAG_CPUX_TDI")
	)
	(segment
		(start 198.755 -84.869528)
		(end 196.727572 -82.8421)
		(width 0.10668)
		(layer "B.Cu")
		(net "JTAG_CPUX_TDI")
	)
	(segment
		(start 147.85848 -59.43092)
		(end 146.76628 -60.52312)
		(width 0.10668)
		(layer "B.Cu")
		(net "JTAG_CPUX_TDI")
	)
	(segment
		(start 187.067698 -82.8421)
		(end 186.08548 -81.859882)
		(width 0.10668)
		(layer "B.Cu")
		(net "JTAG_CPUX_TDI")
	)
	(segment
		(start 133.76656 -58.94832)
		(end 133.76656 -57.50306)
		(width 0.10668)
		(layer "B.Cu")
		(net "JTAG_CPUX_TDI")
	)
	(segment
		(start 127.463296 -56.51754)
		(end 126.84252 -56.51754)
		(width 0.10668)
		(layer "B.Cu")
		(net "JTAG_CPUX_TDI")
	)
	(segment
		(start 141.13256 -61.21908)
		(end 136.03732 -61.21908)
		(width 0.10668)
		(layer "B.Cu")
		(net "JTAG_CPUX_TDI")
	)
	(segment
		(start 154.40406 -59.43092)
		(end 147.85848 -59.43092)
		(width 0.10668)
		(layer "B.Cu")
		(net "JTAG_CPUX_TDI")
	)
	(segment
		(start 162.26917 -83.024726)
		(end 158.0515 -78.807056)
		(width 0.10668)
		(layer "B.Cu")
		(net "JTAG_CPUX_TDI")
	)
	(segment
		(start 223.22282 -101.242114)
		(end 213.29142 -91.310714)
		(width 0.10668)
		(layer "B.Cu")
		(net "JTAG_CPUX_TDI")
	)
	(segment
		(start 238.07674 -147.51177)
		(end 233.737658 -147.51177)
		(width 0.10668)
		(layer "B.Cu")
		(net "JTAG_CPUX_TDI")
	)
	(segment
		(start 156.53893 -61.56579)
		(end 154.40406 -59.43092)
		(width 0.10668)
		(layer "B.Cu")
		(net "JTAG_CPUX_TDI")
	)
	(segment
		(start 136.03732 -61.21908)
		(end 133.76656 -58.94832)
		(width 0.10668)
		(layer "B.Cu")
		(net "JTAG_CPUX_TDI")
	)
	(segment
		(start 146.76628 -60.52312)
		(end 141.82852 -60.52312)
		(width 0.10668)
		(layer "B.Cu")
		(net "JTAG_CPUX_TDI")
	)
	(segment
		(start 131.497324 -55.233824)
		(end 128.747012 -55.233824)
		(width 0.10668)
		(layer "B.Cu")
		(net "JTAG_CPUX_TDI")
	)
	(segment
		(start 186.08548 -81.859882)
		(end 166.280338 -81.859882)
		(width 0.10668)
		(layer "B.Cu")
		(net "JTAG_CPUX_TDI")
	)
	(segment
		(start 231.325674 -149.923754)
		(end 223.22282 -141.8209)
		(width 0.10668)
		(layer "B.Cu")
		(net "JTAG_CPUX_TDI")
	)
	(segment
		(start 208.755742 -84.869528)
		(end 198.755 -84.869528)
		(width 0.10668)
		(layer "B.Cu")
		(net "JTAG_CPUX_TDI")
	)
	(segment
		(start 166.280338 -81.859882)
		(end 165.115494 -83.024726)
		(width 0.10668)
		(layer "B.Cu")
		(net "JTAG_CPUX_TDI")
	)
	(segment
		(start 158.0515 -74.23404)
		(end 156.53893 -72.72147)
		(width 0.10668)
		(layer "B.Cu")
		(net "JTAG_CPUX_TDI")
	)
	(segment
		(start 213.29142 -89.405206)
		(end 208.755742 -84.869528)
		(width 0.10668)
		(layer "B.Cu")
		(net "JTAG_CPUX_TDI")
	)
	(segment
		(start 128.747012 -55.233824)
		(end 127.463296 -56.51754)
		(width 0.10668)
		(layer "B.Cu")
		(net "JTAG_CPUX_TDI")
	)
	(segment
		(start 223.22282 -141.8209)
		(end 223.22282 -101.242114)
		(width 0.10668)
		(layer "B.Cu")
		(net "JTAG_CPUX_TDI")
	)
	(segment
		(start 213.29142 -91.310714)
		(end 213.29142 -89.405206)
		(width 0.10668)
		(layer "B.Cu")
		(net "JTAG_CPUX_TDI")
	)
	(segment
		(start 153.153364 -200.102724)
		(end 153.153364 -201.069702)
		(width 0.10668)
		(layer "F.Cu")
		(net "JTAG_CPU1_TRST_N")
	)
	(segment
		(start 273.003772 -98.355404)
		(end 272.859246 -98.49993)
		(width 0.10668)
		(layer "F.Cu")
		(net "JTAG_CPU1_TRST_N")
	)
	(segment
		(start 274.74164 -98.355404)
		(end 273.003772 -98.355404)
		(width 0.10668)
		(layer "F.Cu")
		(net "JTAG_CPU1_TRST_N")
	)
	(segment
		(start 157.851856 -192.248028)
		(end 155.620466 -197.635622)
		(width 0.10668)
		(layer "F.Cu")
		(net "JTAG_CPU1_TRST_N")
	)
	(segment
		(start 155.620466 -197.635622)
		(end 153.153364 -200.102724)
		(width 0.10668)
		(layer "F.Cu")
		(net "JTAG_CPU1_TRST_N")
	)
	(segment
		(start 166.986712 -171.701714)
		(end 157.851856 -180.83657)
		(width 0.10668)
		(layer "F.Cu")
		(net "JTAG_CPU1_TRST_N")
	)
	(segment
		(start 153.153364 -201.069702)
		(end 153.119582 -201.103484)
		(width 0.10668)
		(layer "F.Cu")
		(net "JTAG_CPU1_TRST_N")
	)
	(segment
		(start 166.986712 -171.389294)
		(end 166.986712 -171.701714)
		(width 0.10668)
		(layer "F.Cu")
		(net "JTAG_CPU1_TRST_N")
	)
	(segment
		(start 131.047998 -222.070422)
		(end 131.51485 -221.804484)
		(width 0.10668)
		(layer "F.Cu")
		(net "JTAG_CPU1_TRST_N")
	)
	(segment
		(start 157.851856 -180.83657)
		(end 157.851856 -192.248028)
		(width 0.10668)
		(layer "F.Cu")
		(net "JTAG_CPU1_TRST_N")
	)
	(via
		(at 153.119582 -201.103484)
		(size 0.508)
		(drill 0.254)
		(layers "F.Cu" "B.Cu")
		(net "JTAG_CPU1_TRST_N")
	)
	(via
		(at 131.51485 -221.804484)
		(size 0.4064)
		(drill 0.2032)
		(layers "F.Cu" "B.Cu")
		(net "JTAG_CPU1_TRST_N")
	)
	(via
		(at 272.859246 -98.49993)
		(size 0.508)
		(drill 0.254)
		(layers "F.Cu" "B.Cu")
		(net "JTAG_CPU1_TRST_N")
	)
	(via
		(at 166.986712 -171.389294)
		(size 0.508)
		(drill 0.254)
		(layers "F.Cu" "B.Cu")
		(net "JTAG_CPU1_TRST_N")
	)
	(segment
		(start 151.275034 -201.577702)
		(end 150.259034 -201.577702)
		(width 0.10668)
		(layer "B.Cu")
		(net "JTAG_CPU1_TRST_N")
	)
	(segment
		(start 152.921462 -200.905364)
		(end 151.395938 -200.905364)
		(width 0.10668)
		(layer "B.Cu")
		(net "JTAG_CPU1_TRST_N")
	)
	(segment
		(start 151.395938 -200.905364)
		(end 151.275034 -201.026268)
		(width 0.10668)
		(layer "B.Cu")
		(net "JTAG_CPU1_TRST_N")
	)
	(segment
		(start 153.119582 -201.103484)
		(end 152.921462 -200.905364)
		(width 0.10668)
		(layer "B.Cu")
		(net "JTAG_CPU1_TRST_N")
	)
	(segment
		(start 151.275034 -201.026268)
		(end 151.275034 -201.577702)
		(width 0.10668)
		(layer "B.Cu")
		(net "JTAG_CPU1_TRST_N")
	)
	(segment
		(start 146.973036 -201.44359)
		(end 138.21664 -210.199986)
		(width 0.11684)
		(layer "In2.Cu")
		(net "JTAG_CPU1_TRST_N")
	)
	(segment
		(start 131.51485 -220.974666)
		(end 131.51485 -221.804484)
		(width 0.11684)
		(layer "In2.Cu")
		(net "JTAG_CPU1_TRST_N")
	)
	(segment
		(start 152.274016 -201.44359)
		(end 146.973036 -201.44359)
		(width 0.11684)
		(layer "In2.Cu")
		(net "JTAG_CPU1_TRST_N")
	)
	(segment
		(start 152.614122 -201.103484)
		(end 152.274016 -201.44359)
		(width 0.11684)
		(layer "In2.Cu")
		(net "JTAG_CPU1_TRST_N")
	)
	(segment
		(start 138.21664 -210.199986)
		(end 135.336534 -217.152982)
		(width 0.11684)
		(layer "In2.Cu")
		(net "JTAG_CPU1_TRST_N")
	)
	(segment
		(start 135.336534 -217.152982)
		(end 131.51485 -220.974666)
		(width 0.11684)
		(layer "In2.Cu")
		(net "JTAG_CPU1_TRST_N")
	)
	(segment
		(start 153.119582 -201.103484)
		(end 152.614122 -201.103484)
		(width 0.11684)
		(layer "In2.Cu")
		(net "JTAG_CPU1_TRST_N")
	)
	(segment
		(start 273.81835 -103.68026)
		(end 273.81835 -101.745796)
		(width 0.11684)
		(layer "In4.Cu")
		(net "JTAG_CPU1_TRST_N")
	)
	(segment
		(start 274.508214 -109.48543)
		(end 274.508214 -104.370124)
		(width 0.11684)
		(layer "In4.Cu")
		(net "JTAG_CPU1_TRST_N")
	)
	(segment
		(start 233.379264 -168.011348)
		(end 237.019084 -159.224218)
		(width 0.11684)
		(layer "In4.Cu")
		(net "JTAG_CPU1_TRST_N")
	)
	(segment
		(start 166.986712 -170.442382)
		(end 167.313102 -170.115992)
		(width 0.11684)
		(layer "In4.Cu")
		(net "JTAG_CPU1_TRST_N")
	)
	(segment
		(start 273.003772 -98.355404)
		(end 272.859246 -98.49993)
		(width 0.11684)
		(layer "In4.Cu")
		(net "JTAG_CPU1_TRST_N")
	)
	(segment
		(start 273.901916 -98.355404)
		(end 273.003772 -98.355404)
		(width 0.11684)
		(layer "In4.Cu")
		(net "JTAG_CPU1_TRST_N")
	)
	(segment
		(start 231.271318 -170.119294)
		(end 233.379264 -168.011348)
		(width 0.11684)
		(layer "In4.Cu")
		(net "JTAG_CPU1_TRST_N")
	)
	(segment
		(start 166.986712 -171.389294)
		(end 166.986712 -170.442382)
		(width 0.11684)
		(layer "In4.Cu")
		(net "JTAG_CPU1_TRST_N")
	)
	(segment
		(start 241.549174 -154.694128)
		(end 245.459758 -154.694128)
		(width 0.11684)
		(layer "In4.Cu")
		(net "JTAG_CPU1_TRST_N")
	)
	(segment
		(start 167.313102 -170.115992)
		(end 211.181696 -170.115992)
		(width 0.11684)
		(layer "In4.Cu")
		(net "JTAG_CPU1_TRST_N")
	)
	(segment
		(start 266.61237 -129.371852)
		(end 266.61237 -120.824244)
		(width 0.11684)
		(layer "In4.Cu")
		(net "JTAG_CPU1_TRST_N")
	)
	(segment
		(start 245.459758 -154.694128)
		(end 263.309862 -147.300442)
		(width 0.11684)
		(layer "In4.Cu")
		(net "JTAG_CPU1_TRST_N")
	)
	(segment
		(start 273.25193 -110.741714)
		(end 274.508214 -109.48543)
		(width 0.11684)
		(layer "In4.Cu")
		(net "JTAG_CPU1_TRST_N")
	)
	(segment
		(start 274.53082 -101.033326)
		(end 274.53082 -98.984308)
		(width 0.11684)
		(layer "In4.Cu")
		(net "JTAG_CPU1_TRST_N")
	)
	(segment
		(start 268.055598 -130.81508)
		(end 266.61237 -129.371852)
		(width 0.11684)
		(layer "In4.Cu")
		(net "JTAG_CPU1_TRST_N")
	)
	(segment
		(start 268.055598 -142.554706)
		(end 268.055598 -130.81508)
		(width 0.11684)
		(layer "In4.Cu")
		(net "JTAG_CPU1_TRST_N")
	)
	(segment
		(start 211.181696 -170.115992)
		(end 211.184998 -170.119294)
		(width 0.11684)
		(layer "In4.Cu")
		(net "JTAG_CPU1_TRST_N")
	)
	(segment
		(start 273.81835 -101.745796)
		(end 274.53082 -101.033326)
		(width 0.11684)
		(layer "In4.Cu")
		(net "JTAG_CPU1_TRST_N")
	)
	(segment
		(start 274.508214 -104.370124)
		(end 273.81835 -103.68026)
		(width 0.11684)
		(layer "In4.Cu")
		(net "JTAG_CPU1_TRST_N")
	)
	(segment
		(start 263.309862 -147.300442)
		(end 268.055598 -142.554706)
		(width 0.11684)
		(layer "In4.Cu")
		(net "JTAG_CPU1_TRST_N")
	)
	(segment
		(start 237.019084 -159.224218)
		(end 241.549174 -154.694128)
		(width 0.11684)
		(layer "In4.Cu")
		(net "JTAG_CPU1_TRST_N")
	)
	(segment
		(start 266.61237 -120.824244)
		(end 273.25193 -114.184684)
		(width 0.11684)
		(layer "In4.Cu")
		(net "JTAG_CPU1_TRST_N")
	)
	(segment
		(start 211.184998 -170.119294)
		(end 231.271318 -170.119294)
		(width 0.11684)
		(layer "In4.Cu")
		(net "JTAG_CPU1_TRST_N")
	)
	(segment
		(start 273.25193 -114.184684)
		(end 273.25193 -110.741714)
		(width 0.11684)
		(layer "In4.Cu")
		(net "JTAG_CPU1_TRST_N")
	)
	(segment
		(start 274.53082 -98.984308)
		(end 273.901916 -98.355404)
		(width 0.11684)
		(layer "In4.Cu")
		(net "JTAG_CPU1_TRST_N")
	)
	(segment
		(start 150.751286 -201.854562)
		(end 150.751286 -203.97724)
		(width 0.10668)
		(layer "F.Cu")
		(net "JTAG_CPU1_TMS")
	)
	(segment
		(start 151.287226 -204.51318)
		(end 151.287226 -204.745336)
		(width 0.10668)
		(layer "F.Cu")
		(net "JTAG_CPU1_TMS")
	)
	(segment
		(start 155.269946 -197.335902)
		(end 150.751286 -201.854562)
		(width 0.10668)
		(layer "F.Cu")
		(net "JTAG_CPU1_TMS")
	)
	(segment
		(start 165.157912 -171.389294)
		(end 165.157912 -172.022262)
		(width 0.10668)
		(layer "F.Cu")
		(net "JTAG_CPU1_TMS")
	)
	(segment
		(start 165.157912 -172.022262)
		(end 157.421326 -179.758848)
		(width 0.10668)
		(layer "F.Cu")
		(net "JTAG_CPU1_TMS")
	)
	(segment
		(start 150.751286 -203.97724)
		(end 151.287226 -204.51318)
		(width 0.10668)
		(layer "F.Cu")
		(net "JTAG_CPU1_TMS")
	)
	(segment
		(start 274.74164 -97.339404)
		(end 273.9136 -97.339404)
		(width 0.10668)
		(layer "F.Cu")
		(net "JTAG_CPU1_TMS")
	)
	(segment
		(start 157.421326 -192.141856)
		(end 155.269946 -197.335902)
		(width 0.10668)
		(layer "F.Cu")
		(net "JTAG_CPU1_TMS")
	)
	(segment
		(start 157.421326 -179.758848)
		(end 157.421326 -192.141856)
		(width 0.10668)
		(layer "F.Cu")
		(net "JTAG_CPU1_TMS")
	)
	(segment
		(start 131.987798 -222.070422)
		(end 132.45465 -221.804484)
		(width 0.10668)
		(layer "F.Cu")
		(net "JTAG_CPU1_TMS")
	)
	(via
		(at 151.287226 -204.745336)
		(size 0.508)
		(drill 0.254)
		(layers "F.Cu" "B.Cu")
		(net "JTAG_CPU1_TMS")
	)
	(via
		(at 132.45465 -221.804484)
		(size 0.4064)
		(drill 0.2032)
		(layers "F.Cu" "B.Cu")
		(net "JTAG_CPU1_TMS")
	)
	(via
		(at 165.157912 -171.389294)
		(size 0.508)
		(drill 0.254)
		(layers "F.Cu" "B.Cu")
		(net "JTAG_CPU1_TMS")
	)
	(via
		(at 273.9136 -97.339404)
		(size 0.508)
		(drill 0.254)
		(layers "F.Cu" "B.Cu")
		(net "JTAG_CPU1_TMS")
	)
	(segment
		(start 151.287226 -204.605128)
		(end 151.287226 -204.745336)
		(width 0.10668)
		(layer "B.Cu")
		(net "JTAG_CPU1_TMS")
	)
	(segment
		(start 147.261834 -203.279502)
		(end 147.816824 -202.724512)
		(width 0.10668)
		(layer "B.Cu")
		(net "JTAG_CPU1_TMS")
	)
	(segment
		(start 147.816824 -202.724512)
		(end 149.40661 -202.724512)
		(width 0.10668)
		(layer "B.Cu")
		(net "JTAG_CPU1_TMS")
	)
	(segment
		(start 147.261834 -203.279502)
		(end 146.220434 -203.279502)
		(width 0.10668)
		(layer "B.Cu")
		(net "JTAG_CPU1_TMS")
	)
	(segment
		(start 149.40661 -202.724512)
		(end 151.287226 -204.605128)
		(width 0.10668)
		(layer "B.Cu")
		(net "JTAG_CPU1_TMS")
	)
	(segment
		(start 136.337802 -217.567764)
		(end 139.217654 -210.61553)
		(width 0.11684)
		(layer "In2.Cu")
		(net "JTAG_CPU1_TMS")
	)
	(segment
		(start 139.217654 -210.61553)
		(end 146.87042 -202.962764)
		(width 0.11684)
		(layer "In2.Cu")
		(net "JTAG_CPU1_TMS")
	)
	(segment
		(start 132.45465 -221.804484)
		(end 132.45465 -221.450916)
		(width 0.11684)
		(layer "In2.Cu")
		(net "JTAG_CPU1_TMS")
	)
	(segment
		(start 150.992078 -204.389736)
		(end 151.287226 -204.745336)
		(width 0.11684)
		(layer "In2.Cu")
		(net "JTAG_CPU1_TMS")
	)
	(segment
		(start 146.87042 -202.962764)
		(end 149.601936 -202.962764)
		(width 0.11684)
		(layer "In2.Cu")
		(net "JTAG_CPU1_TMS")
	)
	(segment
		(start 150.488142 -203.839318)
		(end 150.992078 -204.389736)
		(width 0.11684)
		(layer "In2.Cu")
		(net "JTAG_CPU1_TMS")
	)
	(segment
		(start 149.601936 -202.962764)
		(end 150.488142 -203.839318)
		(width 0.11684)
		(layer "In2.Cu")
		(net "JTAG_CPU1_TMS")
	)
	(segment
		(start 132.45465 -221.450916)
		(end 136.337802 -217.567764)
		(width 0.11684)
		(layer "In2.Cu")
		(net "JTAG_CPU1_TMS")
	)
	(segment
		(start 270.866362 -114.028982)
		(end 270.114776 -114.780568)
		(width 0.11684)
		(layer "In4.Cu")
		(net "JTAG_CPU1_TMS")
	)
	(segment
		(start 272.326354 -97.852738)
		(end 272.142458 -98.036634)
		(width 0.11684)
		(layer "In4.Cu")
		(net "JTAG_CPU1_TMS")
	)
	(segment
		(start 269.230348 -114.780568)
		(end 265.690604 -118.320312)
		(width 0.11684)
		(layer "In4.Cu")
		(net "JTAG_CPU1_TMS")
	)
	(segment
		(start 273.9136 -97.339404)
		(end 273.880326 -97.339404)
		(width 0.11684)
		(layer "In4.Cu")
		(net "JTAG_CPU1_TMS")
	)
	(segment
		(start 233.200194 -164.91331)
		(end 231.09682 -167.016684)
		(width 0.11684)
		(layer "In4.Cu")
		(net "JTAG_CPU1_TMS")
	)
	(segment
		(start 231.09682 -167.016684)
		(end 229.830122 -167.016684)
		(width 0.11684)
		(layer "In4.Cu")
		(net "JTAG_CPU1_TMS")
	)
	(segment
		(start 233.200194 -161.678874)
		(end 233.200194 -164.91331)
		(width 0.11684)
		(layer "In4.Cu")
		(net "JTAG_CPU1_TMS")
	)
	(segment
		(start 210.549998 -168.20388)
		(end 166.707566 -168.20388)
		(width 0.11684)
		(layer "In4.Cu")
		(net "JTAG_CPU1_TMS")
	)
	(segment
		(start 267.143484 -131.09575)
		(end 267.143484 -142.038578)
		(width 0.11684)
		(layer "In4.Cu")
		(net "JTAG_CPU1_TMS")
	)
	(segment
		(start 229.830122 -167.016684)
		(end 227.570792 -169.276014)
		(width 0.11684)
		(layer "In4.Cu")
		(net "JTAG_CPU1_TMS")
	)
	(segment
		(start 272.142458 -99.122738)
		(end 270.866362 -100.398834)
		(width 0.11684)
		(layer "In4.Cu")
		(net "JTAG_CPU1_TMS")
	)
	(segment
		(start 245.583456 -153.72969)
		(end 241.149378 -153.72969)
		(width 0.11684)
		(layer "In4.Cu")
		(net "JTAG_CPU1_TMS")
	)
	(segment
		(start 270.114776 -114.780568)
		(end 269.230348 -114.780568)
		(width 0.11684)
		(layer "In4.Cu")
		(net "JTAG_CPU1_TMS")
	)
	(segment
		(start 211.622132 -169.276014)
		(end 210.549998 -168.20388)
		(width 0.11684)
		(layer "In4.Cu")
		(net "JTAG_CPU1_TMS")
	)
	(segment
		(start 227.570792 -169.276014)
		(end 211.622132 -169.276014)
		(width 0.11684)
		(layer "In4.Cu")
		(net "JTAG_CPU1_TMS")
	)
	(segment
		(start 267.143484 -142.038578)
		(end 262.430514 -146.751548)
		(width 0.11684)
		(layer "In4.Cu")
		(net "JTAG_CPU1_TMS")
	)
	(segment
		(start 265.690604 -129.64287)
		(end 267.143484 -131.09575)
		(width 0.11684)
		(layer "In4.Cu")
		(net "JTAG_CPU1_TMS")
	)
	(segment
		(start 265.690604 -118.320312)
		(end 265.690604 -129.64287)
		(width 0.11684)
		(layer "In4.Cu")
		(net "JTAG_CPU1_TMS")
	)
	(segment
		(start 272.142458 -98.036634)
		(end 272.142458 -99.122738)
		(width 0.11684)
		(layer "In4.Cu")
		(net "JTAG_CPU1_TMS")
	)
	(segment
		(start 166.707566 -168.20388)
		(end 165.157912 -169.753534)
		(width 0.11684)
		(layer "In4.Cu")
		(net "JTAG_CPU1_TMS")
	)
	(segment
		(start 262.430514 -146.751548)
		(end 245.583456 -153.72969)
		(width 0.11684)
		(layer "In4.Cu")
		(net "JTAG_CPU1_TMS")
	)
	(segment
		(start 273.880326 -97.339404)
		(end 273.366992 -97.852738)
		(width 0.11684)
		(layer "In4.Cu")
		(net "JTAG_CPU1_TMS")
	)
	(segment
		(start 241.149378 -153.72969)
		(end 233.200194 -161.678874)
		(width 0.11684)
		(layer "In4.Cu")
		(net "JTAG_CPU1_TMS")
	)
	(segment
		(start 270.866362 -100.398834)
		(end 270.866362 -114.028982)
		(width 0.11684)
		(layer "In4.Cu")
		(net "JTAG_CPU1_TMS")
	)
	(segment
		(start 165.157912 -169.753534)
		(end 165.157912 -171.389294)
		(width 0.11684)
		(layer "In4.Cu")
		(net "JTAG_CPU1_TMS")
	)
	(segment
		(start 273.366992 -97.852738)
		(end 272.326354 -97.852738)
		(width 0.11684)
		(layer "In4.Cu")
		(net "JTAG_CPU1_TMS")
	)
	(segment
		(start 236.58957 -159.022542)
		(end 235.848398 -159.022542)
		(width 0.10668)
		(layer "F.Cu")
		(net "JTAG_CPU1_TDO")
	)
	(segment
		(start 235.848398 -159.022542)
		(end 234.946698 -158.120842)
		(width 0.10668)
		(layer "F.Cu")
		(net "JTAG_CPU1_TDO")
	)
	(segment
		(start 175.619918 -183.971946)
		(end 177.183034 -185.535062)
		(width 0.10668)
		(layer "F.Cu")
		(net "JTAG_CPU1_TDO")
	)
	(segment
		(start 175.619918 -172.817028)
		(end 175.619918 -183.971946)
		(width 0.10668)
		(layer "F.Cu")
		(net "JTAG_CPU1_TDO")
	)
	(via
		(at 234.946698 -158.120842)
		(size 0.508)
		(drill 0.254)
		(layers "F.Cu" "B.Cu")
		(net "JTAG_CPU1_TDO")
	)
	(via
		(at 175.619918 -172.817028)
		(size 0.508)
		(drill 0.254)
		(layers "F.Cu" "B.Cu")
		(net "JTAG_CPU1_TDO")
	)
	(via
		(at 157.40253 -192.726056)
		(size 0.6604)
		(drill 0.3302)
		(layers "F.Cu" "B.Cu")
		(net "JTAG_CPU1_TDO")
	)
	(via
		(at 177.183034 -185.535062)
		(size 0.508)
		(drill 0.254)
		(layers "F.Cu" "B.Cu")
		(net "JTAG_CPU1_TDO")
	)
	(segment
		(start 168.639236 -186.88685)
		(end 167.610028 -187.916058)
		(width 0.10668)
		(layer "B.Cu")
		(net "JTAG_CPU1_TDO")
	)
	(segment
		(start 161.606484 -187.916058)
		(end 157.40253 -192.120012)
		(width 0.10668)
		(layer "B.Cu")
		(net "JTAG_CPU1_TDO")
	)
	(segment
		(start 153.357834 -198.834502)
		(end 154.348434 -198.834502)
		(width 0.10668)
		(layer "B.Cu")
		(net "JTAG_CPU1_TDO")
	)
	(segment
		(start 137.045446 -207.348582)
		(end 152.399238 -207.348582)
		(width 0.10668)
		(layer "B.Cu")
		(net "JTAG_CPU1_TDO")
	)
	(segment
		(start 153.907998 -201.006456)
		(end 152.653746 -199.752204)
		(width 0.10668)
		(layer "B.Cu")
		(net "JTAG_CPU1_TDO")
	)
	(segment
		(start 154.435302 -201.006456)
		(end 153.907998 -201.006456)
		(width 0.10668)
		(layer "B.Cu")
		(net "JTAG_CPU1_TDO")
	)
	(segment
		(start 168.639236 -186.58078)
		(end 168.639236 -186.88685)
		(width 0.10668)
		(layer "B.Cu")
		(net "JTAG_CPU1_TDO")
	)
	(segment
		(start 157.40253 -192.726056)
		(end 154.348434 -195.780152)
		(width 0.10668)
		(layer "B.Cu")
		(net "JTAG_CPU1_TDO")
	)
	(segment
		(start 152.653746 -199.752204)
		(end 152.653746 -199.037194)
		(width 0.10668)
		(layer "B.Cu")
		(net "JTAG_CPU1_TDO")
	)
	(segment
		(start 152.653746 -199.037194)
		(end 152.856438 -198.834502)
		(width 0.10668)
		(layer "B.Cu")
		(net "JTAG_CPU1_TDO")
	)
	(segment
		(start 176.137316 -184.489344)
		(end 170.730672 -184.489344)
		(width 0.10668)
		(layer "B.Cu")
		(net "JTAG_CPU1_TDO")
	)
	(segment
		(start 154.69997 -205.04785)
		(end 154.69997 -201.271124)
		(width 0.10668)
		(layer "B.Cu")
		(net "JTAG_CPU1_TDO")
	)
	(segment
		(start 170.730672 -184.489344)
		(end 168.639236 -186.58078)
		(width 0.10668)
		(layer "B.Cu")
		(net "JTAG_CPU1_TDO")
	)
	(segment
		(start 131.59105 -212.802978)
		(end 137.045446 -207.348582)
		(width 0.10668)
		(layer "B.Cu")
		(net "JTAG_CPU1_TDO")
	)
	(segment
		(start 152.399238 -207.348582)
		(end 154.69997 -205.04785)
		(width 0.10668)
		(layer "B.Cu")
		(net "JTAG_CPU1_TDO")
	)
	(segment
		(start 167.610028 -187.916058)
		(end 161.606484 -187.916058)
		(width 0.10668)
		(layer "B.Cu")
		(net "JTAG_CPU1_TDO")
	)
	(segment
		(start 152.856438 -198.834502)
		(end 153.357834 -198.834502)
		(width 0.10668)
		(layer "B.Cu")
		(net "JTAG_CPU1_TDO")
	)
	(segment
		(start 154.348434 -195.780152)
		(end 154.348434 -198.834502)
		(width 0.10668)
		(layer "B.Cu")
		(net "JTAG_CPU1_TDO")
	)
	(segment
		(start 157.40253 -192.120012)
		(end 157.40253 -192.726056)
		(width 0.10668)
		(layer "B.Cu")
		(net "JTAG_CPU1_TDO")
	)
	(segment
		(start 177.183034 -185.535062)
		(end 176.137316 -184.489344)
		(width 0.10668)
		(layer "B.Cu")
		(net "JTAG_CPU1_TDO")
	)
	(segment
		(start 154.69997 -201.271124)
		(end 154.435302 -201.006456)
		(width 0.10668)
		(layer "B.Cu")
		(net "JTAG_CPU1_TDO")
	)
	(segment
		(start 185.687208 -167.958262)
		(end 195.106544 -167.958262)
		(width 0.11684)
		(layer "In2.Cu")
		(net "JTAG_CPU1_TDO")
	)
	(segment
		(start 175.619918 -171.23156)
		(end 176.847754 -170.003724)
		(width 0.11684)
		(layer "In2.Cu")
		(net "JTAG_CPU1_TDO")
	)
	(segment
		(start 195.106544 -167.958262)
		(end 196.665596 -169.517314)
		(width 0.11684)
		(layer "In2.Cu")
		(net "JTAG_CPU1_TDO")
	)
	(segment
		(start 196.665596 -169.517314)
		(end 215.819736 -169.517314)
		(width 0.11684)
		(layer "In2.Cu")
		(net "JTAG_CPU1_TDO")
	)
	(segment
		(start 225.939858 -167.395906)
		(end 234.946698 -158.120842)
		(width 0.11684)
		(layer "In2.Cu")
		(net "JTAG_CPU1_TDO")
	)
	(segment
		(start 183.641746 -170.003724)
		(end 185.687208 -167.958262)
		(width 0.11684)
		(layer "In2.Cu")
		(net "JTAG_CPU1_TDO")
	)
	(segment
		(start 215.819736 -169.517314)
		(end 225.939858 -167.395906)
		(width 0.11684)
		(layer "In2.Cu")
		(net "JTAG_CPU1_TDO")
	)
	(segment
		(start 175.619918 -172.817028)
		(end 175.619918 -171.23156)
		(width 0.11684)
		(layer "In2.Cu")
		(net "JTAG_CPU1_TDO")
	)
	(segment
		(start 176.847754 -170.003724)
		(end 183.641746 -170.003724)
		(width 0.11684)
		(layer "In2.Cu")
		(net "JTAG_CPU1_TDO")
	)
	(segment
		(start 241.014504 -155.97632)
		(end 240.996724 -155.9941)
		(width 0.10668)
		(layer "F.Cu")
		(net "JTAG_CPU1_TDI")
	)
	(segment
		(start 158.723076 -192.547494)
		(end 157.30601 -195.96862)
		(width 0.10668)
		(layer "F.Cu")
		(net "JTAG_CPU1_TDI")
	)
	(segment
		(start 158.723076 -181.558692)
		(end 158.723076 -192.547494)
		(width 0.10668)
		(layer "F.Cu")
		(net "JTAG_CPU1_TDI")
	)
	(segment
		(start 157.13583 -198.035164)
		(end 157.13583 -199.029828)
		(width 0.10668)
		(layer "F.Cu")
		(net "JTAG_CPU1_TDI")
	)
	(segment
		(start 157.30601 -197.864984)
		(end 157.13583 -198.035164)
		(width 0.10668)
		(layer "F.Cu")
		(net "JTAG_CPU1_TDI")
	)
	(segment
		(start 131.047998 -223.690434)
		(end 131.51485 -223.424496)
		(width 0.10668)
		(layer "F.Cu")
		(net "JTAG_CPU1_TDI")
	)
	(segment
		(start 241.934238 -155.97632)
		(end 241.014504 -155.97632)
		(width 0.10668)
		(layer "F.Cu")
		(net "JTAG_CPU1_TDI")
	)
	(segment
		(start 167.68445 -172.597318)
		(end 158.723076 -181.558692)
		(width 0.10668)
		(layer "F.Cu")
		(net "JTAG_CPU1_TDI")
	)
	(segment
		(start 157.30601 -195.96862)
		(end 157.30601 -197.864984)
		(width 0.10668)
		(layer "F.Cu")
		(net "JTAG_CPU1_TDI")
	)
	(via
		(at 167.68445 -172.597318)
		(size 0.508)
		(drill 0.254)
		(layers "F.Cu" "B.Cu")
		(net "JTAG_CPU1_TDI")
	)
	(via
		(at 157.13583 -199.029828)
		(size 0.508)
		(drill 0.254)
		(layers "F.Cu" "B.Cu")
		(net "JTAG_CPU1_TDI")
	)
	(via
		(at 241.934238 -155.97632)
		(size 0.508)
		(drill 0.254)
		(layers "F.Cu" "B.Cu")
		(net "JTAG_CPU1_TDI")
	)
	(via
		(at 131.51485 -223.424496)
		(size 0.4064)
		(drill 0.2032)
		(layers "F.Cu" "B.Cu")
		(net "JTAG_CPU1_TDI")
	)
	(segment
		(start 157.13583 -199.029828)
		(end 156.940504 -198.834502)
		(width 0.10668)
		(layer "B.Cu")
		(net "JTAG_CPU1_TDI")
	)
	(segment
		(start 131.8514 -217.114628)
		(end 131.8514 -215.94191)
		(width 0.10668)
		(layer "B.Cu")
		(net "JTAG_CPU1_TDI")
	)
	(segment
		(start 156.940504 -198.834502)
		(end 156.355034 -198.834502)
		(width 0.10668)
		(layer "B.Cu")
		(net "JTAG_CPU1_TDI")
	)
	(segment
		(start 156.355034 -198.834502)
		(end 155.364434 -198.834502)
		(width 0.10668)
		(layer "B.Cu")
		(net "JTAG_CPU1_TDI")
	)
	(segment
		(start 156.119322 -205.078838)
		(end 156.119322 -202.13447)
		(width 0.10668)
		(layer "B.Cu")
		(net "JTAG_CPU1_TDI")
	)
	(segment
		(start 139.42949 -208.36382)
		(end 152.83434 -208.36382)
		(width 0.10668)
		(layer "B.Cu")
		(net "JTAG_CPU1_TDI")
	)
	(segment
		(start 132.94487 -222.114364)
		(end 132.94487 -218.851734)
		(width 0.10668)
		(layer "B.Cu")
		(net "JTAG_CPU1_TDI")
	)
	(segment
		(start 157.200854 -201.052938)
		(end 157.200854 -199.094852)
		(width 0.10668)
		(layer "B.Cu")
		(net "JTAG_CPU1_TDI")
	)
	(segment
		(start 157.200854 -199.094852)
		(end 157.13583 -199.029828)
		(width 0.10668)
		(layer "B.Cu")
		(net "JTAG_CPU1_TDI")
	)
	(segment
		(start 132.306314 -218.213178)
		(end 131.8514 -217.114628)
		(width 0.10668)
		(layer "B.Cu")
		(net "JTAG_CPU1_TDI")
	)
	(segment
		(start 132.614416 -222.675196)
		(end 132.614416 -222.444818)
		(width 0.10668)
		(layer "B.Cu")
		(net "JTAG_CPU1_TDI")
	)
	(segment
		(start 131.8514 -215.94191)
		(end 139.42949 -208.36382)
		(width 0.10668)
		(layer "B.Cu")
		(net "JTAG_CPU1_TDI")
	)
	(segment
		(start 156.119322 -202.13447)
		(end 157.200854 -201.052938)
		(width 0.10668)
		(layer "B.Cu")
		(net "JTAG_CPU1_TDI")
	)
	(segment
		(start 131.865116 -223.424496)
		(end 132.614416 -222.675196)
		(width 0.10668)
		(layer "B.Cu")
		(net "JTAG_CPU1_TDI")
	)
	(segment
		(start 132.94487 -218.851734)
		(end 132.306314 -218.213178)
		(width 0.10668)
		(layer "B.Cu")
		(net "JTAG_CPU1_TDI")
	)
	(segment
		(start 132.614416 -222.444818)
		(end 132.94487 -222.114364)
		(width 0.10668)
		(layer "B.Cu")
		(net "JTAG_CPU1_TDI")
	)
	(segment
		(start 152.83434 -208.36382)
		(end 156.119322 -205.078838)
		(width 0.10668)
		(layer "B.Cu")
		(net "JTAG_CPU1_TDI")
	)
	(segment
		(start 131.51485 -223.424496)
		(end 131.865116 -223.424496)
		(width 0.10668)
		(layer "B.Cu")
		(net "JTAG_CPU1_TDI")
	)
	(segment
		(start 231.897936 -170.962574)
		(end 169.704258 -170.962574)
		(width 0.11684)
		(layer "In4.Cu")
		(net "JTAG_CPU1_TDI")
	)
	(segment
		(start 235.632752 -167.227758)
		(end 231.897936 -170.962574)
		(width 0.11684)
		(layer "In4.Cu")
		(net "JTAG_CPU1_TDI")
	)
	(segment
		(start 168.069514 -172.597318)
		(end 167.68445 -172.597318)
		(width 0.11684)
		(layer "In4.Cu")
		(net "JTAG_CPU1_TDI")
	)
	(segment
		(start 169.704258 -170.962574)
		(end 168.069514 -172.597318)
		(width 0.11684)
		(layer "In4.Cu")
		(net "JTAG_CPU1_TDI")
	)
	(segment
		(start 239.133126 -158.777432)
		(end 235.632752 -167.227758)
		(width 0.11684)
		(layer "In4.Cu")
		(net "JTAG_CPU1_TDI")
	)
	(segment
		(start 241.934238 -155.97632)
		(end 239.133126 -158.777432)
		(width 0.11684)
		(layer "In4.Cu")
		(net "JTAG_CPU1_TDI")
	)
	(segment
		(start 158.292546 -192.391792)
		(end 155.993846 -197.941438)
		(width 0.10668)
		(layer "F.Cu")
		(net "JTAG_CPU1_TCK")
	)
	(segment
		(start 158.292546 -181.054756)
		(end 158.292546 -192.391792)
		(width 0.10668)
		(layer "F.Cu")
		(net "JTAG_CPU1_TCK")
	)
	(segment
		(start 131.517898 -222.880428)
		(end 131.98475 -222.61449)
		(width 0.10668)
		(layer "F.Cu")
		(net "JTAG_CPU1_TCK")
	)
	(segment
		(start 273.206464 -96.323404)
		(end 272.962116 -96.567752)
		(width 0.10668)
		(layer "F.Cu")
		(net "JTAG_CPU1_TCK")
	)
	(segment
		(start 155.993846 -197.941438)
		(end 153.755852 -200.179432)
		(width 0.10668)
		(layer "F.Cu")
		(net "JTAG_CPU1_TCK")
	)
	(segment
		(start 153.350722 -201.873866)
		(end 153.350722 -201.920602)
		(width 0.10668)
		(layer "F.Cu")
		(net "JTAG_CPU1_TCK")
	)
	(segment
		(start 274.74164 -96.323404)
		(end 273.206464 -96.323404)
		(width 0.10668)
		(layer "F.Cu")
		(net "JTAG_CPU1_TCK")
	)
	(segment
		(start 153.755852 -201.468736)
		(end 153.350722 -201.873866)
		(width 0.10668)
		(layer "F.Cu")
		(net "JTAG_CPU1_TCK")
	)
	(segment
		(start 153.755852 -200.179432)
		(end 153.755852 -201.468736)
		(width 0.10668)
		(layer "F.Cu")
		(net "JTAG_CPU1_TCK")
	)
	(segment
		(start 167.958008 -171.389294)
		(end 158.292546 -181.054756)
		(width 0.10668)
		(layer "F.Cu")
		(net "JTAG_CPU1_TCK")
	)
	(segment
		(start 168.307512 -171.389294)
		(end 167.958008 -171.389294)
		(width 0.10668)
		(layer "F.Cu")
		(net "JTAG_CPU1_TCK")
	)
	(via
		(at 153.350722 -201.920602)
		(size 0.508)
		(drill 0.254)
		(layers "F.Cu" "B.Cu")
		(net "JTAG_CPU1_TCK")
	)
	(via
		(at 168.307512 -171.389294)
		(size 0.508)
		(drill 0.254)
		(layers "F.Cu" "B.Cu")
		(net "JTAG_CPU1_TCK")
	)
	(via
		(at 272.962116 -96.567752)
		(size 0.508)
		(drill 0.254)
		(layers "F.Cu" "B.Cu")
		(net "JTAG_CPU1_TCK")
	)
	(via
		(at 131.98475 -222.61449)
		(size 0.4064)
		(drill 0.2032)
		(layers "F.Cu" "B.Cu")
		(net "JTAG_CPU1_TCK")
	)
	(segment
		(start 153.228294 -202.53071)
		(end 153.350722 -202.408282)
		(width 0.10668)
		(layer "B.Cu")
		(net "JTAG_CPU1_TCK")
	)
	(segment
		(start 153.350722 -202.408282)
		(end 153.350722 -201.920602)
		(width 0.10668)
		(layer "B.Cu")
		(net "JTAG_CPU1_TCK")
	)
	(segment
		(start 152.275286 -201.577702)
		(end 153.228294 -202.53071)
		(width 0.10668)
		(layer "B.Cu")
		(net "JTAG_CPU1_TCK")
	)
	(segment
		(start 152.265634 -201.577702)
		(end 152.275286 -201.577702)
		(width 0.10668)
		(layer "B.Cu")
		(net "JTAG_CPU1_TCK")
	)
	(segment
		(start 135.89508 -217.384376)
		(end 131.98475 -221.294706)
		(width 0.11684)
		(layer "In2.Cu")
		(net "JTAG_CPU1_TCK")
	)
	(segment
		(start 152.996646 -202.274678)
		(end 146.932142 -202.274678)
		(width 0.11684)
		(layer "In2.Cu")
		(net "JTAG_CPU1_TCK")
	)
	(segment
		(start 138.774932 -210.431888)
		(end 135.89508 -217.384376)
		(width 0.11684)
		(layer "In2.Cu")
		(net "JTAG_CPU1_TCK")
	)
	(segment
		(start 153.350722 -201.920602)
		(end 152.996646 -202.274678)
		(width 0.11684)
		(layer "In2.Cu")
		(net "JTAG_CPU1_TCK")
	)
	(segment
		(start 146.932142 -202.274678)
		(end 138.774932 -210.431888)
		(width 0.11684)
		(layer "In2.Cu")
		(net "JTAG_CPU1_TCK")
	)
	(segment
		(start 131.98475 -221.294706)
		(end 131.98475 -222.61449)
		(width 0.11684)
		(layer "In2.Cu")
		(net "JTAG_CPU1_TCK")
	)
	(segment
		(start 237.31601 -159.609536)
		(end 233.736896 -168.250108)
		(width 0.11684)
		(layer "In4.Cu")
		(net "JTAG_CPU1_TCK")
	)
	(segment
		(start 245.397274 -155.176474)
		(end 241.749072 -155.176474)
		(width 0.11684)
		(layer "In4.Cu")
		(net "JTAG_CPU1_TCK")
	)
	(segment
		(start 275.759926 -100.549456)
		(end 274.29079 -102.018592)
		(width 0.11684)
		(layer "In4.Cu")
		(net "JTAG_CPU1_TCK")
	)
	(segment
		(start 273.206464 -96.323404)
		(end 274.35683 -96.323404)
		(width 0.11684)
		(layer "In4.Cu")
		(net "JTAG_CPU1_TCK")
	)
	(segment
		(start 274.29079 -102.018592)
		(end 274.29079 -103.257604)
		(width 0.11684)
		(layer "In4.Cu")
		(net "JTAG_CPU1_TCK")
	)
	(segment
		(start 275.759926 -97.7265)
		(end 275.759926 -100.549456)
		(width 0.11684)
		(layer "In4.Cu")
		(net "JTAG_CPU1_TCK")
	)
	(segment
		(start 270.281908 -141.059916)
		(end 263.779508 -147.562316)
		(width 0.11684)
		(layer "In4.Cu")
		(net "JTAG_CPU1_TCK")
	)
	(segment
		(start 263.779508 -147.562316)
		(end 245.397274 -155.176474)
		(width 0.11684)
		(layer "In4.Cu")
		(net "JTAG_CPU1_TCK")
	)
	(segment
		(start 210.984846 -170.537632)
		(end 169.159174 -170.537632)
		(width 0.11684)
		(layer "In4.Cu")
		(net "JTAG_CPU1_TCK")
	)
	(segment
		(start 233.736896 -168.250108)
		(end 231.44607 -170.540934)
		(width 0.11684)
		(layer "In4.Cu")
		(net "JTAG_CPU1_TCK")
	)
	(segment
		(start 274.35683 -96.323404)
		(end 275.759926 -97.7265)
		(width 0.11684)
		(layer "In4.Cu")
		(net "JTAG_CPU1_TCK")
	)
	(segment
		(start 241.749072 -155.176474)
		(end 237.31601 -159.609536)
		(width 0.11684)
		(layer "In4.Cu")
		(net "JTAG_CPU1_TCK")
	)
	(segment
		(start 275.057108 -104.023922)
		(end 275.057108 -109.619034)
		(width 0.11684)
		(layer "In4.Cu")
		(net "JTAG_CPU1_TCK")
	)
	(segment
		(start 231.44607 -170.540934)
		(end 210.988148 -170.540934)
		(width 0.11684)
		(layer "In4.Cu")
		(net "JTAG_CPU1_TCK")
	)
	(segment
		(start 274.29079 -103.257604)
		(end 275.057108 -104.023922)
		(width 0.11684)
		(layer "In4.Cu")
		(net "JTAG_CPU1_TCK")
	)
	(segment
		(start 267.09497 -121.513346)
		(end 267.09497 -126.031244)
		(width 0.11684)
		(layer "In4.Cu")
		(net "JTAG_CPU1_TCK")
	)
	(segment
		(start 273.734276 -114.87404)
		(end 267.09497 -121.513346)
		(width 0.11684)
		(layer "In4.Cu")
		(net "JTAG_CPU1_TCK")
	)
	(segment
		(start 267.09497 -126.031244)
		(end 270.281908 -129.218182)
		(width 0.11684)
		(layer "In4.Cu")
		(net "JTAG_CPU1_TCK")
	)
	(segment
		(start 210.988148 -170.540934)
		(end 210.984846 -170.537632)
		(width 0.11684)
		(layer "In4.Cu")
		(net "JTAG_CPU1_TCK")
	)
	(segment
		(start 270.281908 -129.218182)
		(end 270.281908 -141.059916)
		(width 0.11684)
		(layer "In4.Cu")
		(net "JTAG_CPU1_TCK")
	)
	(segment
		(start 275.057108 -109.619034)
		(end 273.734276 -110.941866)
		(width 0.11684)
		(layer "In4.Cu")
		(net "JTAG_CPU1_TCK")
	)
	(segment
		(start 272.962116 -96.567752)
		(end 273.206464 -96.323404)
		(width 0.11684)
		(layer "In4.Cu")
		(net "JTAG_CPU1_TCK")
	)
	(segment
		(start 169.159174 -170.537632)
		(end 168.307512 -171.389294)
		(width 0.11684)
		(layer "In4.Cu")
		(net "JTAG_CPU1_TCK")
	)
	(segment
		(start 273.734276 -110.941866)
		(end 273.734276 -114.87404)
		(width 0.11684)
		(layer "In4.Cu")
		(net "JTAG_CPU1_TCK")
	)
	(segment
		(start 130.107944 -223.690434)
		(end 130.574796 -223.424496)
		(width 0.10668)
		(layer "F.Cu")
		(net "JTAG_CPU1_R_TDO")
	)
	(via
		(at 130.574796 -223.424496)
		(size 0.4064)
		(drill 0.2032)
		(layers "F.Cu" "B.Cu")
		(net "JTAG_CPU1_R_TDO")
	)
	(via
		(at 131.59105 -214.798402)
		(size 0.6604)
		(drill 0.3302)
		(layers "F.Cu" "B.Cu")
		(net "JTAG_CPU1_R_TDO")
	)
	(segment
		(start 131.59105 -214.798402)
		(end 131.59105 -213.603078)
		(width 0.10668)
		(layer "B.Cu")
		(net "JTAG_CPU1_R_TDO")
	)
	(segment
		(start 130.574796 -223.424496)
		(end 130.844036 -223.424496)
		(width 0.10668)
		(layer "B.Cu")
		(net "JTAG_CPU1_R_TDO")
	)
	(segment
		(start 132.404358 -220.65488)
		(end 132.404358 -219.012262)
		(width 0.10668)
		(layer "B.Cu")
		(net "JTAG_CPU1_R_TDO")
	)
	(segment
		(start 131.047744 -218.179904)
		(end 130.637026 -217.769186)
		(width 0.10668)
		(layer "B.Cu")
		(net "JTAG_CPU1_R_TDO")
	)
	(segment
		(start 131.939284 -221.777814)
		(end 132.404358 -220.65488)
		(width 0.10668)
		(layer "B.Cu")
		(net "JTAG_CPU1_R_TDO")
	)
	(segment
		(start 130.844036 -223.424496)
		(end 131.458208 -222.810324)
		(width 0.10668)
		(layer "B.Cu")
		(net "JTAG_CPU1_R_TDO")
	)
	(segment
		(start 131.939284 -221.962726)
		(end 131.939284 -221.777814)
		(width 0.10668)
		(layer "B.Cu")
		(net "JTAG_CPU1_R_TDO")
	)
	(segment
		(start 131.458208 -222.810324)
		(end 131.458208 -222.443802)
		(width 0.10668)
		(layer "B.Cu")
		(net "JTAG_CPU1_R_TDO")
	)
	(segment
		(start 132.404358 -219.012262)
		(end 131.68503 -218.292934)
		(width 0.10668)
		(layer "B.Cu")
		(net "JTAG_CPU1_R_TDO")
	)
	(segment
		(start 130.637026 -217.101674)
		(end 131.59105 -214.798402)
		(width 0.10668)
		(layer "B.Cu")
		(net "JTAG_CPU1_R_TDO")
	)
	(segment
		(start 131.412234 -218.179904)
		(end 131.047744 -218.179904)
		(width 0.10668)
		(layer "B.Cu")
		(net "JTAG_CPU1_R_TDO")
	)
	(segment
		(start 131.68503 -218.292934)
		(end 131.412234 -218.179904)
		(width 0.10668)
		(layer "B.Cu")
		(net "JTAG_CPU1_R_TDO")
	)
	(segment
		(start 130.637026 -217.769186)
		(end 130.637026 -217.101674)
		(width 0.10668)
		(layer "B.Cu")
		(net "JTAG_CPU1_R_TDO")
	)
	(segment
		(start 131.458208 -222.443802)
		(end 131.939284 -221.962726)
		(width 0.10668)
		(layer "B.Cu")
		(net "JTAG_CPU1_R_TDO")
	)
	(segment
		(start 238.977424 -155.9941)
		(end 240.196624 -155.9941)
		(width 0.10668)
		(layer "F.Cu")
		(net "JTAG_CPU1_R_TDI")
	)
	(segment
		(start 236.58957 -155.989528)
		(end 238.972852 -155.989528)
		(width 0.10668)
		(layer "F.Cu")
		(net "JTAG_CPU1_R_TDI")
	)
	(segment
		(start 238.972852 -155.989528)
		(end 238.977424 -155.9941)
		(width 0.10668)
		(layer "F.Cu")
		(net "JTAG_CPU1_R_TDI")
	)
	(via
		(at 238.977424 -155.9941)
		(size 0.762)
		(drill 0.381)
		(layers "F.Cu" "B.Cu")
		(net "JTAG_CPU1_R_TDI")
	)
	(segment
		(start 156.970476 -192.088008)
		(end 156.970476 -179.402232)
		(width 0.10668)
		(layer "F.Cu")
		(net "JTAG_CPU1_DBREQ_N")
	)
	(segment
		(start 150.04034 -204.264768)
		(end 150.04034 -201.814176)
		(width 0.10668)
		(layer "F.Cu")
		(net "JTAG_CPU1_DBREQ_N")
	)
	(segment
		(start 154.993594 -196.860922)
		(end 156.970476 -192.088008)
		(width 0.10668)
		(layer "F.Cu")
		(net "JTAG_CPU1_DBREQ_N")
	)
	(segment
		(start 164.197284 -172.175424)
		(end 164.197284 -171.359322)
		(width 0.10668)
		(layer "F.Cu")
		(net "JTAG_CPU1_DBREQ_N")
	)
	(segment
		(start 156.970476 -179.402232)
		(end 164.197284 -172.175424)
		(width 0.10668)
		(layer "F.Cu")
		(net "JTAG_CPU1_DBREQ_N")
	)
	(segment
		(start 131.987798 -223.690434)
		(end 132.45465 -223.424496)
		(width 0.10668)
		(layer "F.Cu")
		(net "JTAG_CPU1_DBREQ_N")
	)
	(segment
		(start 150.04034 -201.814176)
		(end 154.993594 -196.860922)
		(width 0.10668)
		(layer "F.Cu")
		(net "JTAG_CPU1_DBREQ_N")
	)
	(segment
		(start 274.74164 -99.371404)
		(end 273.9136 -99.371404)
		(width 0.10668)
		(layer "F.Cu")
		(net "JTAG_CPU1_DBREQ_N")
	)
	(via
		(at 150.04034 -204.264768)
		(size 0.508)
		(drill 0.254)
		(layers "F.Cu" "B.Cu")
		(net "JTAG_CPU1_DBREQ_N")
	)
	(via
		(at 164.197284 -171.359322)
		(size 0.508)
		(drill 0.254)
		(layers "F.Cu" "B.Cu")
		(net "JTAG_CPU1_DBREQ_N")
	)
	(via
		(at 132.45465 -223.424496)
		(size 0.4064)
		(drill 0.2032)
		(layers "F.Cu" "B.Cu")
		(net "JTAG_CPU1_DBREQ_N")
	)
	(via
		(at 273.9136 -99.371404)
		(size 0.508)
		(drill 0.254)
		(layers "F.Cu" "B.Cu")
		(net "JTAG_CPU1_DBREQ_N")
	)
	(segment
		(start 149.243034 -203.304902)
		(end 149.243034 -203.364592)
		(width 0.10668)
		(layer "B.Cu")
		(net "JTAG_CPU1_DBREQ_N")
	)
	(segment
		(start 150.04034 -204.161898)
		(end 150.04034 -204.264768)
		(width 0.10668)
		(layer "B.Cu")
		(net "JTAG_CPU1_DBREQ_N")
	)
	(segment
		(start 148.252434 -203.304902)
		(end 149.243034 -203.304902)
		(width 0.10668)
		(layer "B.Cu")
		(net "JTAG_CPU1_DBREQ_N")
	)
	(segment
		(start 149.243034 -203.364592)
		(end 150.04034 -204.161898)
		(width 0.10668)
		(layer "B.Cu")
		(net "JTAG_CPU1_DBREQ_N")
	)
	(segment
		(start 146.877532 -204.085952)
		(end 139.294108 -211.669376)
		(width 0.11684)
		(layer "In2.Cu")
		(net "JTAG_CPU1_DBREQ_N")
	)
	(segment
		(start 139.294108 -211.669376)
		(end 136.764268 -217.776806)
		(width 0.11684)
		(layer "In2.Cu")
		(net "JTAG_CPU1_DBREQ_N")
	)
	(segment
		(start 149.861524 -204.085952)
		(end 146.877532 -204.085952)
		(width 0.11684)
		(layer "In2.Cu")
		(net "JTAG_CPU1_DBREQ_N")
	)
	(segment
		(start 132.454396 -223.423988)
		(end 132.45465 -223.424496)
		(width 0.11684)
		(layer "In2.Cu")
		(net "JTAG_CPU1_DBREQ_N")
	)
	(segment
		(start 150.04034 -204.264768)
		(end 149.861524 -204.085952)
		(width 0.11684)
		(layer "In2.Cu")
		(net "JTAG_CPU1_DBREQ_N")
	)
	(segment
		(start 136.764268 -217.776806)
		(end 133.036564 -221.50451)
		(width 0.11684)
		(layer "In2.Cu")
		(net "JTAG_CPU1_DBREQ_N")
	)
	(segment
		(start 133.036564 -221.50451)
		(end 132.454396 -223.423988)
		(width 0.11684)
		(layer "In2.Cu")
		(net "JTAG_CPU1_DBREQ_N")
	)
	(segment
		(start 181.007004 -169.595546)
		(end 181.936136 -168.666414)
		(width 0.11684)
		(layer "In4.Cu")
		(net "JTAG_CPU1_DBREQ_N")
	)
	(segment
		(start 269.766034 -115.49507)
		(end 270.004032 -115.49507)
		(width 0.11684)
		(layer "In4.Cu")
		(net "JTAG_CPU1_DBREQ_N")
	)
	(segment
		(start 165.434518 -172.129704)
		(end 165.777164 -171.787058)
		(width 0.11684)
		(layer "In4.Cu")
		(net "JTAG_CPU1_DBREQ_N")
	)
	(segment
		(start 269.26413 -116.591842)
		(end 269.26413 -115.996974)
		(width 0.11684)
		(layer "In4.Cu")
		(net "JTAG_CPU1_DBREQ_N")
	)
	(segment
		(start 267.570712 -130.926586)
		(end 266.149074 -129.504948)
		(width 0.11684)
		(layer "In4.Cu")
		(net "JTAG_CPU1_DBREQ_N")
	)
	(segment
		(start 233.634026 -161.873438)
		(end 241.333528 -154.173936)
		(width 0.11684)
		(layer "In4.Cu")
		(net "JTAG_CPU1_DBREQ_N")
	)
	(segment
		(start 271.450308 -114.048794)
		(end 271.450308 -103.225854)
		(width 0.11684)
		(layer "In4.Cu")
		(net "JTAG_CPU1_DBREQ_N")
	)
	(segment
		(start 166.465504 -169.595546)
		(end 181.007004 -169.595546)
		(width 0.11684)
		(layer "In4.Cu")
		(net "JTAG_CPU1_DBREQ_N")
	)
	(segment
		(start 228.048058 -169.697654)
		(end 230.307388 -167.438324)
		(width 0.11684)
		(layer "In4.Cu")
		(net "JTAG_CPU1_DBREQ_N")
	)
	(segment
		(start 165.777164 -170.283886)
		(end 166.465504 -169.595546)
		(width 0.11684)
		(layer "In4.Cu")
		(net "JTAG_CPU1_DBREQ_N")
	)
	(segment
		(start 271.450308 -103.225854)
		(end 273.9136 -100.762562)
		(width 0.11684)
		(layer "In4.Cu")
		(net "JTAG_CPU1_DBREQ_N")
	)
	(segment
		(start 270.004032 -115.49507)
		(end 271.450308 -114.048794)
		(width 0.11684)
		(layer "In4.Cu")
		(net "JTAG_CPU1_DBREQ_N")
	)
	(segment
		(start 269.26413 -115.996974)
		(end 269.766034 -115.49507)
		(width 0.11684)
		(layer "In4.Cu")
		(net "JTAG_CPU1_DBREQ_N")
	)
	(segment
		(start 230.307388 -167.438324)
		(end 231.271572 -167.438324)
		(width 0.11684)
		(layer "In4.Cu")
		(net "JTAG_CPU1_DBREQ_N")
	)
	(segment
		(start 266.149074 -119.706898)
		(end 269.26413 -116.591842)
		(width 0.11684)
		(layer "In4.Cu")
		(net "JTAG_CPU1_DBREQ_N")
	)
	(segment
		(start 262.72363 -147.086828)
		(end 267.570712 -142.239746)
		(width 0.11684)
		(layer "In4.Cu")
		(net "JTAG_CPU1_DBREQ_N")
	)
	(segment
		(start 211.378038 -169.697654)
		(end 228.048058 -169.697654)
		(width 0.11684)
		(layer "In4.Cu")
		(net "JTAG_CPU1_DBREQ_N")
	)
	(segment
		(start 181.936136 -168.666414)
		(end 210.346798 -168.666414)
		(width 0.11684)
		(layer "In4.Cu")
		(net "JTAG_CPU1_DBREQ_N")
	)
	(segment
		(start 164.197284 -171.359322)
		(end 164.197284 -171.713906)
		(width 0.11684)
		(layer "In4.Cu")
		(net "JTAG_CPU1_DBREQ_N")
	)
	(segment
		(start 165.777164 -171.787058)
		(end 165.777164 -170.283886)
		(width 0.11684)
		(layer "In4.Cu")
		(net "JTAG_CPU1_DBREQ_N")
	)
	(segment
		(start 241.333528 -154.173936)
		(end 245.613174 -154.173936)
		(width 0.11684)
		(layer "In4.Cu")
		(net "JTAG_CPU1_DBREQ_N")
	)
	(segment
		(start 210.346798 -168.666414)
		(end 211.378038 -169.697654)
		(width 0.11684)
		(layer "In4.Cu")
		(net "JTAG_CPU1_DBREQ_N")
	)
	(segment
		(start 164.197284 -171.713906)
		(end 164.613082 -172.129704)
		(width 0.11684)
		(layer "In4.Cu")
		(net "JTAG_CPU1_DBREQ_N")
	)
	(segment
		(start 266.149074 -129.504948)
		(end 266.149074 -119.706898)
		(width 0.11684)
		(layer "In4.Cu")
		(net "JTAG_CPU1_DBREQ_N")
	)
	(segment
		(start 231.271572 -167.438324)
		(end 233.634026 -165.07587)
		(width 0.11684)
		(layer "In4.Cu")
		(net "JTAG_CPU1_DBREQ_N")
	)
	(segment
		(start 273.9136 -100.762562)
		(end 273.9136 -99.371404)
		(width 0.11684)
		(layer "In4.Cu")
		(net "JTAG_CPU1_DBREQ_N")
	)
	(segment
		(start 233.634026 -165.07587)
		(end 233.634026 -161.873438)
		(width 0.11684)
		(layer "In4.Cu")
		(net "JTAG_CPU1_DBREQ_N")
	)
	(segment
		(start 267.570712 -142.239746)
		(end 267.570712 -130.926586)
		(width 0.11684)
		(layer "In4.Cu")
		(net "JTAG_CPU1_DBREQ_N")
	)
	(segment
		(start 164.613082 -172.129704)
		(end 165.434518 -172.129704)
		(width 0.11684)
		(layer "In4.Cu")
		(net "JTAG_CPU1_DBREQ_N")
	)
	(segment
		(start 245.613174 -154.173936)
		(end 262.72363 -147.086828)
		(width 0.11684)
		(layer "In4.Cu")
		(net "JTAG_CPU1_DBREQ_N")
	)
	(segment
		(start 233.931206 -156.893768)
		(end 234.173522 -157.136084)
		(width 0.10668)
		(layer "F.Cu")
		(net "JTAG_CPU1_BYPASS")
	)
	(segment
		(start 234.173522 -160.660334)
		(end 233.861102 -160.972754)
		(width 0.10668)
		(layer "F.Cu")
		(net "JTAG_CPU1_BYPASS")
	)
	(segment
		(start 234.173522 -157.136084)
		(end 234.173522 -160.660334)
		(width 0.10668)
		(layer "F.Cu")
		(net "JTAG_CPU1_BYPASS")
	)
	(segment
		(start 233.677206 -156.639768)
		(end 233.931206 -156.893768)
		(width 0.10668)
		(layer "F.Cu")
		(net "JTAG_CPU1_BYPASS")
	)
	(segment
		(start 232.889806 -156.639768)
		(end 233.677206 -156.639768)
		(width 0.10668)
		(layer "F.Cu")
		(net "JTAG_CPU1_BYPASS")
	)
	(segment
		(start 233.861102 -160.972754)
		(end 232.889806 -160.972754)
		(width 0.10668)
		(layer "F.Cu")
		(net "JTAG_CPU1_BYPASS")
	)
	(via
		(at 233.931206 -156.893768)
		(size 0.508)
		(drill 0.254)
		(layers "F.Cu" "B.Cu")
		(net "JTAG_CPU1_BYPASS")
	)
	(segment
		(start 252.08484 -92.319094)
		(end 252.08484 -91.28887)
		(width 0.10668)
		(layer "F.Cu")
		(net "JTAG_CPU0_TRST_N")
	)
	(segment
		(start 378.988066 -221.230698)
		(end 380.111254 -220.10751)
		(width 0.10668)
		(layer "F.Cu")
		(net "JTAG_CPU0_TRST_N")
	)
	(segment
		(start 252.08484 -91.28887)
		(end 252.33884 -91.03487)
		(width 0.10668)
		(layer "F.Cu")
		(net "JTAG_CPU0_TRST_N")
	)
	(segment
		(start 378.988066 -222.070168)
		(end 378.988066 -221.230698)
		(width 0.10668)
		(layer "F.Cu")
		(net "JTAG_CPU0_TRST_N")
	)
	(segment
		(start 381.687832 -219.71254)
		(end 381.687832 -218.08059)
		(width 0.10668)
		(layer "F.Cu")
		(net "JTAG_CPU0_TRST_N")
	)
	(segment
		(start 378.606558 -214.999316)
		(end 378.606558 -211.521802)
		(width 0.10668)
		(layer "F.Cu")
		(net "JTAG_CPU0_TRST_N")
	)
	(segment
		(start 378.606558 -211.521802)
		(end 377.637294 -210.552538)
		(width 0.10668)
		(layer "F.Cu")
		(net "JTAG_CPU0_TRST_N")
	)
	(segment
		(start 377.637294 -210.552538)
		(end 377.637294 -209.874866)
		(width 0.10668)
		(layer "F.Cu")
		(net "JTAG_CPU0_TRST_N")
	)
	(segment
		(start 381.687832 -218.08059)
		(end 378.606558 -214.999316)
		(width 0.10668)
		(layer "F.Cu")
		(net "JTAG_CPU0_TRST_N")
	)
	(segment
		(start 381.292862 -220.10751)
		(end 381.687832 -219.71254)
		(width 0.10668)
		(layer "F.Cu")
		(net "JTAG_CPU0_TRST_N")
	)
	(segment
		(start 380.111254 -220.10751)
		(end 381.292862 -220.10751)
		(width 0.10668)
		(layer "F.Cu")
		(net "JTAG_CPU0_TRST_N")
	)
	(via
		(at 377.637294 -209.874866)
		(size 0.508)
		(drill 0.254)
		(layers "F.Cu" "B.Cu")
		(net "JTAG_CPU0_TRST_N")
	)
	(via
		(at 252.33884 -91.03487)
		(size 0.508)
		(drill 0.254)
		(layers "F.Cu" "B.Cu")
		(net "JTAG_CPU0_TRST_N")
	)
	(segment
		(start 376.166126 -209.64017)
		(end 377.402598 -209.64017)
		(width 0.10668)
		(layer "B.Cu")
		(net "JTAG_CPU0_TRST_N")
	)
	(segment
		(start 374.440958 -208.931002)
		(end 375.456958 -208.931002)
		(width 0.10668)
		(layer "B.Cu")
		(net "JTAG_CPU0_TRST_N")
	)
	(segment
		(start 377.402598 -209.64017)
		(end 377.637294 -209.874866)
		(width 0.10668)
		(layer "B.Cu")
		(net "JTAG_CPU0_TRST_N")
	)
	(segment
		(start 375.456958 -208.931002)
		(end 376.166126 -209.64017)
		(width 0.10668)
		(layer "B.Cu")
		(net "JTAG_CPU0_TRST_N")
	)
	(segment
		(start 280.399998 -167.568118)
		(end 269.683992 -156.852112)
		(width 0.11684)
		(layer "In2.Cu")
		(net "JTAG_CPU0_TRST_N")
	)
	(segment
		(start 254.373634 -92.152216)
		(end 253.456186 -92.152216)
		(width 0.11684)
		(layer "In2.Cu")
		(net "JTAG_CPU0_TRST_N")
	)
	(segment
		(start 378.696728 -205.69936)
		(end 377.750578 -204.283564)
		(width 0.11684)
		(layer "In2.Cu")
		(net "JTAG_CPU0_TRST_N")
	)
	(segment
		(start 378.924566 -207.341978)
		(end 378.924566 -206.24927)
		(width 0.11684)
		(layer "In2.Cu")
		(net "JTAG_CPU0_TRST_N")
	)
	(segment
		(start 272.894044 -102.335584)
		(end 267.920978 -102.335584)
		(width 0.11684)
		(layer "In2.Cu")
		(net "JTAG_CPU0_TRST_N")
	)
	(segment
		(start 253.456186 -92.152216)
		(end 252.33884 -91.03487)
		(width 0.11684)
		(layer "In2.Cu")
		(net "JTAG_CPU0_TRST_N")
	)
	(segment
		(start 254.828802 -91.697048)
		(end 254.373634 -92.152216)
		(width 0.11684)
		(layer "In2.Cu")
		(net "JTAG_CPU0_TRST_N")
	)
	(segment
		(start 269.683992 -156.852112)
		(end 269.683992 -139.290298)
		(width 0.11684)
		(layer "In2.Cu")
		(net "JTAG_CPU0_TRST_N")
	)
	(segment
		(start 377.38685 -202.944476)
		(end 366.04956 -202.944476)
		(width 0.11684)
		(layer "In2.Cu")
		(net "JTAG_CPU0_TRST_N")
	)
	(segment
		(start 378.924566 -206.24927)
		(end 378.696728 -205.69936)
		(width 0.11684)
		(layer "In2.Cu")
		(net "JTAG_CPU0_TRST_N")
	)
	(segment
		(start 274.550632 -103.992172)
		(end 272.894044 -102.335584)
		(width 0.11684)
		(layer "In2.Cu")
		(net "JTAG_CPU0_TRST_N")
	)
	(segment
		(start 271.055084 -126.021084)
		(end 271.055084 -112.136936)
		(width 0.11684)
		(layer "In2.Cu")
		(net "JTAG_CPU0_TRST_N")
	)
	(segment
		(start 377.750578 -204.283564)
		(end 377.750578 -203.308204)
		(width 0.11684)
		(layer "In2.Cu")
		(net "JTAG_CPU0_TRST_N")
	)
	(segment
		(start 269.683992 -139.290298)
		(end 272.289778 -136.684512)
		(width 0.11684)
		(layer "In2.Cu")
		(net "JTAG_CPU0_TRST_N")
	)
	(segment
		(start 366.04956 -202.944476)
		(end 332.297786 -180.392324)
		(width 0.11684)
		(layer "In2.Cu")
		(net "JTAG_CPU0_TRST_N")
	)
	(segment
		(start 377.637294 -209.874866)
		(end 377.637294 -208.62925)
		(width 0.11684)
		(layer "In2.Cu")
		(net "JTAG_CPU0_TRST_N")
	)
	(segment
		(start 272.289778 -127.255778)
		(end 271.055084 -126.021084)
		(width 0.11684)
		(layer "In2.Cu")
		(net "JTAG_CPU0_TRST_N")
	)
	(segment
		(start 301.580804 -172.05833)
		(end 297.090592 -167.568118)
		(width 0.11684)
		(layer "In2.Cu")
		(net "JTAG_CPU0_TRST_N")
	)
	(segment
		(start 377.750578 -203.308204)
		(end 377.38685 -202.944476)
		(width 0.11684)
		(layer "In2.Cu")
		(net "JTAG_CPU0_TRST_N")
	)
	(segment
		(start 377.637294 -208.62925)
		(end 378.924566 -207.341978)
		(width 0.11684)
		(layer "In2.Cu")
		(net "JTAG_CPU0_TRST_N")
	)
	(segment
		(start 312.178192 -172.05833)
		(end 301.580804 -172.05833)
		(width 0.11684)
		(layer "In2.Cu")
		(net "JTAG_CPU0_TRST_N")
	)
	(segment
		(start 272.289778 -136.684512)
		(end 272.289778 -127.255778)
		(width 0.11684)
		(layer "In2.Cu")
		(net "JTAG_CPU0_TRST_N")
	)
	(segment
		(start 257.282442 -91.697048)
		(end 254.828802 -91.697048)
		(width 0.11684)
		(layer "In2.Cu")
		(net "JTAG_CPU0_TRST_N")
	)
	(segment
		(start 297.090592 -167.568118)
		(end 280.399998 -167.568118)
		(width 0.11684)
		(layer "In2.Cu")
		(net "JTAG_CPU0_TRST_N")
	)
	(segment
		(start 267.920978 -102.335584)
		(end 257.282442 -91.697048)
		(width 0.11684)
		(layer "In2.Cu")
		(net "JTAG_CPU0_TRST_N")
	)
	(segment
		(start 271.055084 -112.136936)
		(end 274.550632 -108.641388)
		(width 0.11684)
		(layer "In2.Cu")
		(net "JTAG_CPU0_TRST_N")
	)
	(segment
		(start 332.297786 -180.392324)
		(end 312.178192 -172.05833)
		(width 0.11684)
		(layer "In2.Cu")
		(net "JTAG_CPU0_TRST_N")
	)
	(segment
		(start 274.550632 -108.641388)
		(end 274.550632 -103.992172)
		(width 0.11684)
		(layer "In2.Cu")
		(net "JTAG_CPU0_TRST_N")
	)
	(segment
		(start 379.927866 -221.455996)
		(end 380.453392 -220.93047)
		(width 0.10668)
		(layer "F.Cu")
		(net "JTAG_CPU0_TMS")
	)
	(segment
		(start 379.927866 -222.070168)
		(end 379.927866 -221.455996)
		(width 0.10668)
		(layer "F.Cu")
		(net "JTAG_CPU0_TMS")
	)
	(segment
		(start 382.64465 -219.969334)
		(end 382.64465 -217.82659)
		(width 0.10668)
		(layer "F.Cu")
		(net "JTAG_CPU0_TMS")
	)
	(segment
		(start 381.683514 -220.93047)
		(end 382.64465 -219.969334)
		(width 0.10668)
		(layer "F.Cu")
		(net "JTAG_CPU0_TMS")
	)
	(segment
		(start 253.10084 -92.319094)
		(end 253.10084 -91.54287)
		(width 0.10668)
		(layer "F.Cu")
		(net "JTAG_CPU0_TMS")
	)
	(segment
		(start 382.64465 -217.82659)
		(end 379.800358 -214.982298)
		(width 0.10668)
		(layer "F.Cu")
		(net "JTAG_CPU0_TMS")
	)
	(segment
		(start 253.10084 -91.54287)
		(end 253.60884 -91.03487)
		(width 0.10668)
		(layer "F.Cu")
		(net "JTAG_CPU0_TMS")
	)
	(segment
		(start 379.800358 -209.922364)
		(end 379.90018 -209.822542)
		(width 0.10668)
		(layer "F.Cu")
		(net "JTAG_CPU0_TMS")
	)
	(segment
		(start 379.800358 -214.982298)
		(end 379.800358 -209.922364)
		(width 0.10668)
		(layer "F.Cu")
		(net "JTAG_CPU0_TMS")
	)
	(segment
		(start 380.453392 -220.93047)
		(end 381.683514 -220.93047)
		(width 0.10668)
		(layer "F.Cu")
		(net "JTAG_CPU0_TMS")
	)
	(via
		(at 379.90018 -209.822542)
		(size 0.508)
		(drill 0.254)
		(layers "F.Cu" "B.Cu")
		(net "JTAG_CPU0_TMS")
	)
	(via
		(at 253.60884 -91.03487)
		(size 0.508)
		(drill 0.254)
		(layers "F.Cu" "B.Cu")
		(net "JTAG_CPU0_TMS")
	)
	(segment
		(start 379.520958 -209.44332)
		(end 379.90018 -209.822542)
		(width 0.10668)
		(layer "B.Cu")
		(net "JTAG_CPU0_TMS")
	)
	(segment
		(start 379.520958 -208.931002)
		(end 378.504958 -208.931002)
		(width 0.10668)
		(layer "B.Cu")
		(net "JTAG_CPU0_TMS")
	)
	(segment
		(start 379.520958 -208.931002)
		(end 379.520958 -209.44332)
		(width 0.10668)
		(layer "B.Cu")
		(net "JTAG_CPU0_TMS")
	)
	(segment
		(start 379.441964 -204.500988)
		(end 379.90018 -205.607412)
		(width 0.11684)
		(layer "In2.Cu")
		(net "JTAG_CPU0_TMS")
	)
	(segment
		(start 378.403358 -202.030076)
		(end 379.441964 -203.068682)
		(width 0.11684)
		(layer "In2.Cu")
		(net "JTAG_CPU0_TMS")
	)
	(segment
		(start 332.696058 -179.643786)
		(end 366.19942 -202.030076)
		(width 0.11684)
		(layer "In2.Cu")
		(net "JTAG_CPU0_TMS")
	)
	(segment
		(start 270.527272 -156.502608)
		(end 280.723848 -166.699184)
		(width 0.11684)
		(layer "In2.Cu")
		(net "JTAG_CPU0_TMS")
	)
	(segment
		(start 254.40894 -90.23477)
		(end 257.049524 -90.23477)
		(width 0.11684)
		(layer "In2.Cu")
		(net "JTAG_CPU0_TMS")
	)
	(segment
		(start 275.393912 -109.07014)
		(end 273.133058 -111.330994)
		(width 0.11684)
		(layer "In2.Cu")
		(net "JTAG_CPU0_TMS")
	)
	(segment
		(start 312.347356 -171.21505)
		(end 332.696058 -179.643786)
		(width 0.11684)
		(layer "In2.Cu")
		(net "JTAG_CPU0_TMS")
	)
	(segment
		(start 273.254216 -101.466396)
		(end 275.393912 -103.606092)
		(width 0.11684)
		(layer "In2.Cu")
		(net "JTAG_CPU0_TMS")
	)
	(segment
		(start 301.96663 -171.21505)
		(end 312.347356 -171.21505)
		(width 0.11684)
		(layer "In2.Cu")
		(net "JTAG_CPU0_TMS")
	)
	(segment
		(start 270.527272 -139.639802)
		(end 270.527272 -156.502608)
		(width 0.11684)
		(layer "In2.Cu")
		(net "JTAG_CPU0_TMS")
	)
	(segment
		(start 273.133058 -111.330994)
		(end 273.133058 -137.034016)
		(width 0.11684)
		(layer "In2.Cu")
		(net "JTAG_CPU0_TMS")
	)
	(segment
		(start 297.450764 -166.699184)
		(end 301.96663 -171.21505)
		(width 0.11684)
		(layer "In2.Cu")
		(net "JTAG_CPU0_TMS")
	)
	(segment
		(start 273.133058 -137.034016)
		(end 270.527272 -139.639802)
		(width 0.11684)
		(layer "In2.Cu")
		(net "JTAG_CPU0_TMS")
	)
	(segment
		(start 257.049524 -90.23477)
		(end 268.28115 -101.466396)
		(width 0.11684)
		(layer "In2.Cu")
		(net "JTAG_CPU0_TMS")
	)
	(segment
		(start 366.19942 -202.030076)
		(end 378.403358 -202.030076)
		(width 0.11684)
		(layer "In2.Cu")
		(net "JTAG_CPU0_TMS")
	)
	(segment
		(start 280.723848 -166.699184)
		(end 297.450764 -166.699184)
		(width 0.11684)
		(layer "In2.Cu")
		(net "JTAG_CPU0_TMS")
	)
	(segment
		(start 253.60884 -91.03487)
		(end 254.40894 -90.23477)
		(width 0.11684)
		(layer "In2.Cu")
		(net "JTAG_CPU0_TMS")
	)
	(segment
		(start 379.90018 -205.607412)
		(end 379.90018 -209.822542)
		(width 0.11684)
		(layer "In2.Cu")
		(net "JTAG_CPU0_TMS")
	)
	(segment
		(start 268.28115 -101.466396)
		(end 273.254216 -101.466396)
		(width 0.11684)
		(layer "In2.Cu")
		(net "JTAG_CPU0_TMS")
	)
	(segment
		(start 275.393912 -103.606092)
		(end 275.393912 -109.07014)
		(width 0.11684)
		(layer "In2.Cu")
		(net "JTAG_CPU0_TMS")
	)
	(segment
		(start 379.441964 -203.068682)
		(end 379.441964 -204.500988)
		(width 0.11684)
		(layer "In2.Cu")
		(net "JTAG_CPU0_TMS")
	)
	(segment
		(start 237.929166 -155.08986)
		(end 237.929166 -152.691338)
		(width 0.10668)
		(layer "F.Cu")
		(net "JTAG_CPU0_TDO_CPU1_TDI")
	)
	(segment
		(start 237.679484 -155.339542)
		(end 237.929166 -155.08986)
		(width 0.10668)
		(layer "F.Cu")
		(net "JTAG_CPU0_TDO_CPU1_TDI")
	)
	(segment
		(start 237.548674 -152.310846)
		(end 236.593888 -152.310846)
		(width 0.10668)
		(layer "F.Cu")
		(net "JTAG_CPU0_TDO_CPU1_TDI")
	)
	(segment
		(start 236.58957 -155.339542)
		(end 237.679484 -155.339542)
		(width 0.10668)
		(layer "F.Cu")
		(net "JTAG_CPU0_TDO_CPU1_TDI")
	)
	(segment
		(start 236.593888 -152.310846)
		(end 236.58957 -152.306528)
		(width 0.10668)
		(layer "F.Cu")
		(net "JTAG_CPU0_TDO_CPU1_TDI")
	)
	(segment
		(start 229.16515 -152.954228)
		(end 228.682042 -153.437336)
		(width 0.10668)
		(layer "F.Cu")
		(net "JTAG_CPU0_TDO_CPU1_TDI")
	)
	(segment
		(start 237.929166 -152.691338)
		(end 237.548674 -152.310846)
		(width 0.10668)
		(layer "F.Cu")
		(net "JTAG_CPU0_TDO_CPU1_TDI")
	)
	(segment
		(start 228.682042 -153.437336)
		(end 228.682042 -153.511758)
		(width 0.10668)
		(layer "F.Cu")
		(net "JTAG_CPU0_TDO_CPU1_TDI")
	)
	(segment
		(start 232.889806 -157.289754)
		(end 231.27589 -157.289754)
		(width 0.10668)
		(layer "F.Cu")
		(net "JTAG_CPU0_TDO_CPU1_TDI")
	)
	(via
		(at 228.682042 -153.511758)
		(size 0.508)
		(drill 0.254)
		(layers "F.Cu" "B.Cu")
		(net "JTAG_CPU0_TDO_CPU1_TDI")
	)
	(via
		(at 231.27589 -157.289754)
		(size 0.508)
		(drill 0.254)
		(layers "F.Cu" "B.Cu")
		(net "JTAG_CPU0_TDO_CPU1_TDI")
	)
	(via
		(at 237.679484 -155.339542)
		(size 0.508)
		(drill 0.254)
		(layers "F.Cu" "B.Cu")
		(net "JTAG_CPU0_TDO_CPU1_TDI")
	)
	(segment
		(start 230.568754 -153.511758)
		(end 231.249982 -154.192986)
		(width 0.10668)
		(layer "B.Cu")
		(net "JTAG_CPU0_TDO_CPU1_TDI")
	)
	(segment
		(start 228.682042 -153.511758)
		(end 230.568754 -153.511758)
		(width 0.10668)
		(layer "B.Cu")
		(net "JTAG_CPU0_TDO_CPU1_TDI")
	)
	(segment
		(start 231.249982 -157.263846)
		(end 231.27589 -157.289754)
		(width 0.10668)
		(layer "B.Cu")
		(net "JTAG_CPU0_TDO_CPU1_TDI")
	)
	(segment
		(start 233.500422 -155.065222)
		(end 231.27589 -157.289754)
		(width 0.10668)
		(layer "B.Cu")
		(net "JTAG_CPU0_TDO_CPU1_TDI")
	)
	(segment
		(start 237.405164 -155.065222)
		(end 233.500422 -155.065222)
		(width 0.10668)
		(layer "B.Cu")
		(net "JTAG_CPU0_TDO_CPU1_TDI")
	)
	(segment
		(start 231.249982 -154.192986)
		(end 231.249982 -157.263846)
		(width 0.10668)
		(layer "B.Cu")
		(net "JTAG_CPU0_TDO_CPU1_TDI")
	)
	(segment
		(start 237.679484 -155.339542)
		(end 237.405164 -155.065222)
		(width 0.10668)
		(layer "B.Cu")
		(net "JTAG_CPU0_TDO_CPU1_TDI")
	)
	(segment
		(start 236.58957 -151.656542)
		(end 238.635794 -151.656542)
		(width 0.10668)
		(layer "F.Cu")
		(net "JTAG_CPU0_TDO")
	)
	(via
		(at 238.635794 -151.656542)
		(size 0.508)
		(drill 0.254)
		(layers "F.Cu" "B.Cu")
		(net "JTAG_CPU0_TDO")
	)
	(via
		(at 376.980958 -206.498952)
		(size 0.508)
		(drill 0.254)
		(layers "F.Cu" "B.Cu")
		(net "JTAG_CPU0_TDO")
	)
	(segment
		(start 374.523254 -204.701902)
		(end 374.629934 -204.808582)
		(width 0.10668)
		(layer "B.Cu")
		(net "JTAG_CPU0_TDO")
	)
	(segment
		(start 374.821958 -205.502002)
		(end 375.202958 -205.502002)
		(width 0.10668)
		(layer "B.Cu")
		(net "JTAG_CPU0_TDO")
	)
	(segment
		(start 375.202958 -205.502002)
		(end 376.218958 -205.502002)
		(width 0.10668)
		(layer "B.Cu")
		(net "JTAG_CPU0_TDO")
	)
	(segment
		(start 374.186958 -204.701902)
		(end 374.523254 -204.701902)
		(width 0.10668)
		(layer "B.Cu")
		(net "JTAG_CPU0_TDO")
	)
	(segment
		(start 376.218958 -205.736952)
		(end 376.980958 -206.498952)
		(width 0.10668)
		(layer "B.Cu")
		(net "JTAG_CPU0_TDO")
	)
	(segment
		(start 376.218958 -205.502002)
		(end 376.218958 -205.736952)
		(width 0.10668)
		(layer "B.Cu")
		(net "JTAG_CPU0_TDO")
	)
	(segment
		(start 374.629934 -205.309978)
		(end 374.821958 -205.502002)
		(width 0.10668)
		(layer "B.Cu")
		(net "JTAG_CPU0_TDO")
	)
	(segment
		(start 374.629934 -204.808582)
		(end 374.629934 -205.309978)
		(width 0.10668)
		(layer "B.Cu")
		(net "JTAG_CPU0_TDO")
	)
	(segment
		(start 240.40084 -152.12568)
		(end 240.40084 -157.036262)
		(width 0.11684)
		(layer "In2.Cu")
		(net "JTAG_CPU0_TDO")
	)
	(segment
		(start 367.665762 -205.546452)
		(end 376.26544 -205.546452)
		(width 0.11684)
		(layer "In2.Cu")
		(net "JTAG_CPU0_TDO")
	)
	(segment
		(start 376.26544 -205.546452)
		(end 376.980958 -206.26197)
		(width 0.11684)
		(layer "In2.Cu")
		(net "JTAG_CPU0_TDO")
	)
	(segment
		(start 240.40084 -157.036262)
		(end 254.7747 -171.410122)
		(width 0.11684)
		(layer "In2.Cu")
		(net "JTAG_CPU0_TDO")
	)
	(segment
		(start 376.980958 -206.26197)
		(end 376.980958 -206.498952)
		(width 0.11684)
		(layer "In2.Cu")
		(net "JTAG_CPU0_TDO")
	)
	(segment
		(start 300.922436 -173.32325)
		(end 311.9247 -173.32325)
		(width 0.11684)
		(layer "In2.Cu")
		(net "JTAG_CPU0_TDO")
	)
	(segment
		(start 299.009308 -171.410122)
		(end 300.922436 -173.32325)
		(width 0.11684)
		(layer "In2.Cu")
		(net "JTAG_CPU0_TDO")
	)
	(segment
		(start 254.7747 -171.410122)
		(end 299.009308 -171.410122)
		(width 0.11684)
		(layer "In2.Cu")
		(net "JTAG_CPU0_TDO")
	)
	(segment
		(start 239.931702 -151.656542)
		(end 240.40084 -152.12568)
		(width 0.11684)
		(layer "In2.Cu")
		(net "JTAG_CPU0_TDO")
	)
	(segment
		(start 238.635794 -151.656542)
		(end 239.931702 -151.656542)
		(width 0.11684)
		(layer "In2.Cu")
		(net "JTAG_CPU0_TDO")
	)
	(segment
		(start 331.698346 -181.513734)
		(end 367.665762 -205.546452)
		(width 0.11684)
		(layer "In2.Cu")
		(net "JTAG_CPU0_TDO")
	)
	(segment
		(start 311.9247 -173.32325)
		(end 331.698346 -181.513734)
		(width 0.11684)
		(layer "In2.Cu")
		(net "JTAG_CPU0_TDO")
	)
	(segment
		(start 240.821972 -148.6408)
		(end 240.821972 -149.956266)
		(width 0.10668)
		(layer "F.Cu")
		(net "JTAG_CPU0_TDI")
	)
	(segment
		(start 380.90856 -221.26575)
		(end 381.954786 -221.26575)
		(width 0.10668)
		(layer "F.Cu")
		(net "JTAG_CPU0_TDI")
	)
	(segment
		(start 383.080006 -220.14053)
		(end 383.080006 -217.678762)
		(width 0.10668)
		(layer "F.Cu")
		(net "JTAG_CPU0_TDI")
	)
	(segment
		(start 240.821972 -149.956266)
		(end 240.831624 -149.965918)
		(width 0.10668)
		(layer "F.Cu")
		(net "JTAG_CPU0_TDI")
	)
	(segment
		(start 379.933454 -223.07931)
		(end 379.933454 -222.698056)
		(width 0.10668)
		(layer "F.Cu")
		(net "JTAG_CPU0_TDI")
	)
	(segment
		(start 378.988066 -223.69018)
		(end 379.322584 -223.69018)
		(width 0.10668)
		(layer "F.Cu")
		(net "JTAG_CPU0_TDI")
	)
	(segment
		(start 381.954786 -221.26575)
		(end 383.080006 -220.14053)
		(width 0.10668)
		(layer "F.Cu")
		(net "JTAG_CPU0_TDI")
	)
	(segment
		(start 383.080006 -217.678762)
		(end 380.536958 -215.135714)
		(width 0.10668)
		(layer "F.Cu")
		(net "JTAG_CPU0_TDI")
	)
	(segment
		(start 380.347474 -222.284036)
		(end 380.347474 -221.826836)
		(width 0.10668)
		(layer "F.Cu")
		(net "JTAG_CPU0_TDI")
	)
	(segment
		(start 379.933454 -222.698056)
		(end 380.347474 -222.284036)
		(width 0.10668)
		(layer "F.Cu")
		(net "JTAG_CPU0_TDI")
	)
	(segment
		(start 380.347474 -221.826836)
		(end 380.90856 -221.26575)
		(width 0.10668)
		(layer "F.Cu")
		(net "JTAG_CPU0_TDI")
	)
	(segment
		(start 240.831624 -149.965918)
		(end 240.831624 -150.853648)
		(width 0.10668)
		(layer "F.Cu")
		(net "JTAG_CPU0_TDI")
	)
	(segment
		(start 379.322584 -223.69018)
		(end 379.933454 -223.07931)
		(width 0.10668)
		(layer "F.Cu")
		(net "JTAG_CPU0_TDI")
	)
	(segment
		(start 380.536958 -215.135714)
		(end 380.536958 -210.657186)
		(width 0.10668)
		(layer "F.Cu")
		(net "JTAG_CPU0_TDI")
	)
	(via
		(at 380.536958 -210.657186)
		(size 0.508)
		(drill 0.254)
		(layers "F.Cu" "B.Cu")
		(net "JTAG_CPU0_TDI")
	)
	(via
		(at 240.831624 -150.853648)
		(size 0.508)
		(drill 0.254)
		(layers "F.Cu" "B.Cu")
		(net "JTAG_CPU0_TDI")
	)
	(segment
		(start 380.536958 -208.931002)
		(end 380.536958 -210.657186)
		(width 0.10668)
		(layer "B.Cu")
		(net "JTAG_CPU0_TDI")
	)
	(segment
		(start 381.552958 -208.931002)
		(end 380.536958 -208.931002)
		(width 0.10668)
		(layer "B.Cu")
		(net "JTAG_CPU0_TDI")
	)
	(segment
		(start 331.897482 -181.139592)
		(end 367.793778 -205.124812)
		(width 0.11684)
		(layer "In2.Cu")
		(net "JTAG_CPU0_TDI")
	)
	(segment
		(start 240.883694 -156.83611)
		(end 255.013714 -170.96613)
		(width 0.11684)
		(layer "In2.Cu")
		(net "JTAG_CPU0_TDI")
	)
	(segment
		(start 377.62942 -206.20736)
		(end 377.62942 -206.797148)
		(width 0.11684)
		(layer "In2.Cu")
		(net "JTAG_CPU0_TDI")
	)
	(segment
		(start 299.248322 -170.96613)
		(end 301.183802 -172.90161)
		(width 0.11684)
		(layer "In2.Cu")
		(net "JTAG_CPU0_TDI")
	)
	(segment
		(start 240.883694 -150.905718)
		(end 240.883694 -156.83611)
		(width 0.11684)
		(layer "In2.Cu")
		(net "JTAG_CPU0_TDI")
	)
	(segment
		(start 377.62942 -206.797148)
		(end 376.8598 -207.566768)
		(width 0.11684)
		(layer "In2.Cu")
		(net "JTAG_CPU0_TDI")
	)
	(segment
		(start 312.009536 -172.90161)
		(end 331.897482 -181.139592)
		(width 0.11684)
		(layer "In2.Cu")
		(net "JTAG_CPU0_TDI")
	)
	(segment
		(start 377.520962 -211.38134)
		(end 379.741684 -211.38134)
		(width 0.11684)
		(layer "In2.Cu")
		(net "JTAG_CPU0_TDI")
	)
	(segment
		(start 240.831624 -150.853648)
		(end 240.883694 -150.905718)
		(width 0.11684)
		(layer "In2.Cu")
		(net "JTAG_CPU0_TDI")
	)
	(segment
		(start 380.465838 -210.657186)
		(end 380.536958 -210.657186)
		(width 0.11684)
		(layer "In2.Cu")
		(net "JTAG_CPU0_TDI")
	)
	(segment
		(start 376.8598 -210.720178)
		(end 377.520962 -211.38134)
		(width 0.11684)
		(layer "In2.Cu")
		(net "JTAG_CPU0_TDI")
	)
	(segment
		(start 379.741684 -211.38134)
		(end 380.465838 -210.657186)
		(width 0.11684)
		(layer "In2.Cu")
		(net "JTAG_CPU0_TDI")
	)
	(segment
		(start 367.793778 -205.124812)
		(end 376.546872 -205.124812)
		(width 0.11684)
		(layer "In2.Cu")
		(net "JTAG_CPU0_TDI")
	)
	(segment
		(start 376.8598 -207.566768)
		(end 376.8598 -210.720178)
		(width 0.11684)
		(layer "In2.Cu")
		(net "JTAG_CPU0_TDI")
	)
	(segment
		(start 376.546872 -205.124812)
		(end 377.62942 -206.20736)
		(width 0.11684)
		(layer "In2.Cu")
		(net "JTAG_CPU0_TDI")
	)
	(segment
		(start 255.013714 -170.96613)
		(end 299.248322 -170.96613)
		(width 0.11684)
		(layer "In2.Cu")
		(net "JTAG_CPU0_TDI")
	)
	(segment
		(start 301.183802 -172.90161)
		(end 312.009536 -172.90161)
		(width 0.11684)
		(layer "In2.Cu")
		(net "JTAG_CPU0_TDI")
	)
	(segment
		(start 382.166368 -219.850716)
		(end 382.166368 -217.95486)
		(width 0.10668)
		(layer "F.Cu")
		(net "JTAG_CPU0_TCK")
	)
	(segment
		(start 379.152912 -211.351368)
		(end 378.520706 -210.719162)
		(width 0.10668)
		(layer "F.Cu")
		(net "JTAG_CPU0_TCK")
	)
	(segment
		(start 382.166368 -217.95486)
		(end 379.152912 -214.941404)
		(width 0.10668)
		(layer "F.Cu")
		(net "JTAG_CPU0_TCK")
	)
	(segment
		(start 378.520706 -209.877914)
		(end 378.707142 -209.691478)
		(width 0.10668)
		(layer "F.Cu")
		(net "JTAG_CPU0_TCK")
	)
	(segment
		(start 381.498094 -220.51899)
		(end 382.166368 -219.850716)
		(width 0.10668)
		(layer "F.Cu")
		(net "JTAG_CPU0_TCK")
	)
	(segment
		(start 378.520706 -210.719162)
		(end 378.520706 -209.877914)
		(width 0.10668)
		(layer "F.Cu")
		(net "JTAG_CPU0_TCK")
	)
	(segment
		(start 254.11684 -92.319094)
		(end 254.11684 -91.79687)
		(width 0.10668)
		(layer "F.Cu")
		(net "JTAG_CPU0_TCK")
	)
	(segment
		(start 379.152912 -214.941404)
		(end 379.152912 -211.351368)
		(width 0.10668)
		(layer "F.Cu")
		(net "JTAG_CPU0_TCK")
	)
	(segment
		(start 379.457966 -221.343728)
		(end 380.282704 -220.51899)
		(width 0.10668)
		(layer "F.Cu")
		(net "JTAG_CPU0_TCK")
	)
	(segment
		(start 379.457966 -222.880174)
		(end 379.457966 -221.343728)
		(width 0.10668)
		(layer "F.Cu")
		(net "JTAG_CPU0_TCK")
	)
	(segment
		(start 254.11684 -91.79687)
		(end 254.87884 -91.03487)
		(width 0.10668)
		(layer "F.Cu")
		(net "JTAG_CPU0_TCK")
	)
	(segment
		(start 380.282704 -220.51899)
		(end 381.498094 -220.51899)
		(width 0.10668)
		(layer "F.Cu")
		(net "JTAG_CPU0_TCK")
	)
	(via
		(at 254.87884 -91.03487)
		(size 0.508)
		(drill 0.254)
		(layers "F.Cu" "B.Cu")
		(net "JTAG_CPU0_TCK")
	)
	(via
		(at 378.707142 -209.691478)
		(size 0.508)
		(drill 0.254)
		(layers "F.Cu" "B.Cu")
		(net "JTAG_CPU0_TCK")
	)
	(segment
		(start 377.594876 -208.931002)
		(end 378.355352 -209.691478)
		(width 0.10668)
		(layer "B.Cu")
		(net "JTAG_CPU0_TCK")
	)
	(segment
		(start 377.488958 -208.931002)
		(end 376.472958 -208.931002)
		(width 0.10668)
		(layer "B.Cu")
		(net "JTAG_CPU0_TCK")
	)
	(segment
		(start 377.488958 -208.931002)
		(end 377.594876 -208.931002)
		(width 0.10668)
		(layer "B.Cu")
		(net "JTAG_CPU0_TCK")
	)
	(segment
		(start 378.355352 -209.691478)
		(end 378.707142 -209.691478)
		(width 0.10668)
		(layer "B.Cu")
		(net "JTAG_CPU0_TCK")
	)
	(segment
		(start 366.15878 -202.510136)
		(end 378.22124 -202.510136)
		(width 0.11684)
		(layer "In2.Cu")
		(net "JTAG_CPU0_TCK")
	)
	(segment
		(start 270.105632 -139.46505)
		(end 270.105632 -156.67736)
		(width 0.11684)
		(layer "In2.Cu")
		(net "JTAG_CPU0_TCK")
	)
	(segment
		(start 312.262774 -171.63669)
		(end 332.49743 -180.018182)
		(width 0.11684)
		(layer "In2.Cu")
		(net "JTAG_CPU0_TCK")
	)
	(segment
		(start 257.244596 -91.03487)
		(end 268.103858 -101.894132)
		(width 0.11684)
		(layer "In2.Cu")
		(net "JTAG_CPU0_TCK")
	)
	(segment
		(start 270.105632 -156.67736)
		(end 280.555192 -167.12692)
		(width 0.11684)
		(layer "In2.Cu")
		(net "JTAG_CPU0_TCK")
	)
	(segment
		(start 378.883164 -204.852524)
		(end 379.448822 -206.218536)
		(width 0.11684)
		(layer "In2.Cu")
		(net "JTAG_CPU0_TCK")
	)
	(segment
		(start 378.707142 -209.61731)
		(end 378.707142 -209.691478)
		(width 0.11684)
		(layer "In2.Cu")
		(net "JTAG_CPU0_TCK")
	)
	(segment
		(start 378.22124 -202.510136)
		(end 378.883164 -203.17206)
		(width 0.11684)
		(layer "In2.Cu")
		(net "JTAG_CPU0_TCK")
	)
	(segment
		(start 297.273472 -167.12692)
		(end 301.783242 -171.63669)
		(width 0.11684)
		(layer "In2.Cu")
		(net "JTAG_CPU0_TCK")
	)
	(segment
		(start 378.883164 -203.17206)
		(end 378.883164 -204.852524)
		(width 0.11684)
		(layer "In2.Cu")
		(net "JTAG_CPU0_TCK")
	)
	(segment
		(start 379.448822 -208.87563)
		(end 378.707142 -209.61731)
		(width 0.11684)
		(layer "In2.Cu")
		(net "JTAG_CPU0_TCK")
	)
	(segment
		(start 274.972272 -108.886752)
		(end 271.488662 -112.370362)
		(width 0.11684)
		(layer "In2.Cu")
		(net "JTAG_CPU0_TCK")
	)
	(segment
		(start 272.711418 -136.859264)
		(end 270.105632 -139.46505)
		(width 0.11684)
		(layer "In2.Cu")
		(net "JTAG_CPU0_TCK")
	)
	(segment
		(start 272.711418 -126.985014)
		(end 272.711418 -136.859264)
		(width 0.11684)
		(layer "In2.Cu")
		(net "JTAG_CPU0_TCK")
	)
	(segment
		(start 254.87884 -91.03487)
		(end 257.244596 -91.03487)
		(width 0.11684)
		(layer "In2.Cu")
		(net "JTAG_CPU0_TCK")
	)
	(segment
		(start 379.448822 -206.218536)
		(end 379.448822 -208.87563)
		(width 0.11684)
		(layer "In2.Cu")
		(net "JTAG_CPU0_TCK")
	)
	(segment
		(start 271.488662 -125.762258)
		(end 272.711418 -126.985014)
		(width 0.11684)
		(layer "In2.Cu")
		(net "JTAG_CPU0_TCK")
	)
	(segment
		(start 268.103858 -101.894132)
		(end 273.076924 -101.894132)
		(width 0.11684)
		(layer "In2.Cu")
		(net "JTAG_CPU0_TCK")
	)
	(segment
		(start 280.555192 -167.12692)
		(end 297.273472 -167.12692)
		(width 0.11684)
		(layer "In2.Cu")
		(net "JTAG_CPU0_TCK")
	)
	(segment
		(start 301.783242 -171.63669)
		(end 312.262774 -171.63669)
		(width 0.11684)
		(layer "In2.Cu")
		(net "JTAG_CPU0_TCK")
	)
	(segment
		(start 271.488662 -112.370362)
		(end 271.488662 -125.762258)
		(width 0.11684)
		(layer "In2.Cu")
		(net "JTAG_CPU0_TCK")
	)
	(segment
		(start 273.076924 -101.894132)
		(end 274.972272 -103.78948)
		(width 0.11684)
		(layer "In2.Cu")
		(net "JTAG_CPU0_TCK")
	)
	(segment
		(start 332.49743 -180.018182)
		(end 366.15878 -202.510136)
		(width 0.11684)
		(layer "In2.Cu")
		(net "JTAG_CPU0_TCK")
	)
	(segment
		(start 274.972272 -103.78948)
		(end 274.972272 -108.886752)
		(width 0.11684)
		(layer "In2.Cu")
		(net "JTAG_CPU0_TCK")
	)
	(segment
		(start 378.048012 -223.69018)
		(end 378.514864 -223.424242)
		(width 0.10668)
		(layer "F.Cu")
		(net "JTAG_CPU0_R_TDO")
	)
	(via
		(at 378.514864 -223.424242)
		(size 0.4064)
		(drill 0.2032)
		(layers "F.Cu" "B.Cu")
		(net "JTAG_CPU0_R_TDO")
	)
	(via
		(at 376.091958 -206.625952)
		(size 0.508)
		(drill 0.254)
		(layers "F.Cu" "B.Cu")
		(net "JTAG_CPU0_R_TDO")
	)
	(segment
		(start 374.675908 -205.990952)
		(end 375.456958 -205.990952)
		(width 0.10668)
		(layer "B.Cu")
		(net "JTAG_CPU0_R_TDO")
	)
	(segment
		(start 374.186958 -205.502002)
		(end 374.675908 -205.990952)
		(width 0.10668)
		(layer "B.Cu")
		(net "JTAG_CPU0_R_TDO")
	)
	(segment
		(start 375.456958 -205.990952)
		(end 376.091958 -206.625952)
		(width 0.10668)
		(layer "B.Cu")
		(net "JTAG_CPU0_R_TDO")
	)
	(segment
		(start 376.091958 -211.696046)
		(end 376.091958 -206.625952)
		(width 0.11684)
		(layer "In2.Cu")
		(net "JTAG_CPU0_R_TDO")
	)
	(segment
		(start 378.514864 -214.118952)
		(end 376.091958 -211.696046)
		(width 0.11684)
		(layer "In2.Cu")
		(net "JTAG_CPU0_R_TDO")
	)
	(segment
		(start 378.514864 -223.424242)
		(end 378.514864 -214.118952)
		(width 0.11684)
		(layer "In2.Cu")
		(net "JTAG_CPU0_R_TDO")
	)
	(segment
		(start 240.0046 -148.623528)
		(end 240.021872 -148.6408)
		(width 0.10668)
		(layer "F.Cu")
		(net "JTAG_CPU0_R_TDI")
	)
	(segment
		(start 236.58957 -148.623528)
		(end 238.494824 -148.623528)
		(width 0.10668)
		(layer "F.Cu")
		(net "JTAG_CPU0_R_TDI")
	)
	(segment
		(start 238.494824 -148.623528)
		(end 240.0046 -148.623528)
		(width 0.10668)
		(layer "F.Cu")
		(net "JTAG_CPU0_R_TDI")
	)
	(via
		(at 238.494824 -148.623528)
		(size 0.762)
		(drill 0.381)
		(layers "F.Cu" "B.Cu")
		(net "JTAG_CPU0_R_TDI")
	)
	(segment
		(start 380.211584 -223.69018)
		(end 379.927866 -223.69018)
		(width 0.10668)
		(layer "F.Cu")
		(net "JTAG_CPU0_DBREQ_N")
	)
	(segment
		(start 382.56464 -221.677484)
		(end 382.355344 -221.88678)
		(width 0.10668)
		(layer "F.Cu")
		(net "JTAG_CPU0_DBREQ_N")
	)
	(segment
		(start 382.355344 -222.078296)
		(end 381.970788 -222.462852)
		(width 0.10668)
		(layer "F.Cu")
		(net "JTAG_CPU0_DBREQ_N")
	)
	(segment
		(start 380.822454 -222.69831)
		(end 380.822454 -223.07931)
		(width 0.10668)
		(layer "F.Cu")
		(net "JTAG_CPU0_DBREQ_N")
	)
	(segment
		(start 381.057912 -222.462852)
		(end 380.822454 -222.69831)
		(width 0.10668)
		(layer "F.Cu")
		(net "JTAG_CPU0_DBREQ_N")
	)
	(segment
		(start 381.552958 -208.581752)
		(end 382.091184 -209.119978)
		(width 0.10668)
		(layer "F.Cu")
		(net "JTAG_CPU0_DBREQ_N")
	)
	(segment
		(start 380.822454 -223.07931)
		(end 380.211584 -223.69018)
		(width 0.10668)
		(layer "F.Cu")
		(net "JTAG_CPU0_DBREQ_N")
	)
	(segment
		(start 379.546358 -208.581752)
		(end 381.552958 -208.581752)
		(width 0.10668)
		(layer "F.Cu")
		(net "JTAG_CPU0_DBREQ_N")
	)
	(segment
		(start 378.809758 -206.498952)
		(end 379.089158 -206.778352)
		(width 0.10668)
		(layer "F.Cu")
		(net "JTAG_CPU0_DBREQ_N")
	)
	(segment
		(start 378.250958 -206.498952)
		(end 378.809758 -206.498952)
		(width 0.10668)
		(layer "F.Cu")
		(net "JTAG_CPU0_DBREQ_N")
	)
	(segment
		(start 383.944876 -220.652848)
		(end 382.92024 -221.677484)
		(width 0.10668)
		(layer "F.Cu")
		(net "JTAG_CPU0_DBREQ_N")
	)
	(segment
		(start 383.944876 -217.257376)
		(end 383.944876 -220.652848)
		(width 0.10668)
		(layer "F.Cu")
		(net "JTAG_CPU0_DBREQ_N")
	)
	(segment
		(start 382.091184 -215.403684)
		(end 383.944876 -217.257376)
		(width 0.10668)
		(layer "F.Cu")
		(net "JTAG_CPU0_DBREQ_N")
	)
	(segment
		(start 379.089158 -206.778352)
		(end 379.089158 -208.124552)
		(width 0.10668)
		(layer "F.Cu")
		(net "JTAG_CPU0_DBREQ_N")
	)
	(segment
		(start 379.089158 -208.124552)
		(end 379.546358 -208.581752)
		(width 0.10668)
		(layer "F.Cu")
		(net "JTAG_CPU0_DBREQ_N")
	)
	(segment
		(start 382.92024 -221.677484)
		(end 382.56464 -221.677484)
		(width 0.10668)
		(layer "F.Cu")
		(net "JTAG_CPU0_DBREQ_N")
	)
	(segment
		(start 381.970788 -222.462852)
		(end 381.057912 -222.462852)
		(width 0.10668)
		(layer "F.Cu")
		(net "JTAG_CPU0_DBREQ_N")
	)
	(segment
		(start 382.091184 -209.119978)
		(end 382.091184 -215.403684)
		(width 0.10668)
		(layer "F.Cu")
		(net "JTAG_CPU0_DBREQ_N")
	)
	(segment
		(start 251.06884 -92.319094)
		(end 251.06884 -91.03487)
		(width 0.10668)
		(layer "F.Cu")
		(net "JTAG_CPU0_DBREQ_N")
	)
	(segment
		(start 382.355344 -221.88678)
		(end 382.355344 -222.078296)
		(width 0.10668)
		(layer "F.Cu")
		(net "JTAG_CPU0_DBREQ_N")
	)
	(via
		(at 378.250958 -206.498952)
		(size 0.508)
		(drill 0.254)
		(layers "F.Cu" "B.Cu")
		(net "JTAG_CPU0_DBREQ_N")
	)
	(via
		(at 251.06884 -91.03487)
		(size 0.508)
		(drill 0.254)
		(layers "F.Cu" "B.Cu")
		(net "JTAG_CPU0_DBREQ_N")
	)
	(segment
		(start 378.250958 -206.498952)
		(end 378.250958 -205.502002)
		(width 0.10668)
		(layer "B.Cu")
		(net "JTAG_CPU0_DBREQ_N")
	)
	(segment
		(start 378.250958 -205.502002)
		(end 377.234958 -205.502002)
		(width 0.10668)
		(layer "B.Cu")
		(net "JTAG_CPU0_DBREQ_N")
	)
	(segment
		(start 270.587216 -111.831882)
		(end 274.128992 -108.290106)
		(width 0.11684)
		(layer "In2.Cu")
		(net "JTAG_CPU0_DBREQ_N")
	)
	(segment
		(start 366.023144 -203.434188)
		(end 332.09738 -180.765704)
		(width 0.11684)
		(layer "In2.Cu")
		(net "JTAG_CPU0_DBREQ_N")
	)
	(segment
		(start 271.868138 -127.430784)
		(end 270.587216 -126.149862)
		(width 0.11684)
		(layer "In2.Cu")
		(net "JTAG_CPU0_DBREQ_N")
	)
	(segment
		(start 271.868138 -136.50976)
		(end 271.868138 -127.430784)
		(width 0.11684)
		(layer "In2.Cu")
		(net "JTAG_CPU0_DBREQ_N")
	)
	(segment
		(start 269.262352 -157.026864)
		(end 269.262352 -139.115546)
		(width 0.11684)
		(layer "In2.Cu")
		(net "JTAG_CPU0_DBREQ_N")
	)
	(segment
		(start 274.128992 -104.213914)
		(end 272.705576 -102.790498)
		(width 0.11684)
		(layer "In2.Cu")
		(net "JTAG_CPU0_DBREQ_N")
	)
	(segment
		(start 378.250958 -206.498952)
		(end 378.250958 -205.863952)
		(width 0.11684)
		(layer "In2.Cu")
		(net "JTAG_CPU0_DBREQ_N")
	)
	(segment
		(start 255.242568 -93.972888)
		(end 254.428752 -93.159072)
		(width 0.11684)
		(layer "In2.Cu")
		(net "JTAG_CPU0_DBREQ_N")
	)
	(segment
		(start 378.250958 -205.863952)
		(end 377.090178 -204.703172)
		(width 0.11684)
		(layer "In2.Cu")
		(net "JTAG_CPU0_DBREQ_N")
	)
	(segment
		(start 332.09738 -180.765704)
		(end 312.093864 -172.47997)
		(width 0.11684)
		(layer "In2.Cu")
		(net "JTAG_CPU0_DBREQ_N")
	)
	(segment
		(start 374.828054 -204.703172)
		(end 373.55907 -203.434188)
		(width 0.11684)
		(layer "In2.Cu")
		(net "JTAG_CPU0_DBREQ_N")
	)
	(segment
		(start 269.262352 -139.115546)
		(end 271.868138 -136.50976)
		(width 0.11684)
		(layer "In2.Cu")
		(net "JTAG_CPU0_DBREQ_N")
	)
	(segment
		(start 258.9149 -93.972888)
		(end 255.242568 -93.972888)
		(width 0.11684)
		(layer "In2.Cu")
		(net "JTAG_CPU0_DBREQ_N")
	)
	(segment
		(start 312.093864 -172.47997)
		(end 301.358554 -172.47997)
		(width 0.11684)
		(layer "In2.Cu")
		(net "JTAG_CPU0_DBREQ_N")
	)
	(segment
		(start 373.55907 -203.434188)
		(end 366.023144 -203.434188)
		(width 0.11684)
		(layer "In2.Cu")
		(net "JTAG_CPU0_DBREQ_N")
	)
	(segment
		(start 253.193042 -93.159072)
		(end 251.06884 -91.03487)
		(width 0.11684)
		(layer "In2.Cu")
		(net "JTAG_CPU0_DBREQ_N")
	)
	(segment
		(start 280.258774 -168.023286)
		(end 269.262352 -157.026864)
		(width 0.11684)
		(layer "In2.Cu")
		(net "JTAG_CPU0_DBREQ_N")
	)
	(segment
		(start 301.358554 -172.47997)
		(end 296.90187 -168.023286)
		(width 0.11684)
		(layer "In2.Cu")
		(net "JTAG_CPU0_DBREQ_N")
	)
	(segment
		(start 270.587216 -126.149862)
		(end 270.587216 -111.831882)
		(width 0.11684)
		(layer "In2.Cu")
		(net "JTAG_CPU0_DBREQ_N")
	)
	(segment
		(start 267.73251 -102.790498)
		(end 258.9149 -93.972888)
		(width 0.11684)
		(layer "In2.Cu")
		(net "JTAG_CPU0_DBREQ_N")
	)
	(segment
		(start 272.705576 -102.790498)
		(end 267.73251 -102.790498)
		(width 0.11684)
		(layer "In2.Cu")
		(net "JTAG_CPU0_DBREQ_N")
	)
	(segment
		(start 377.090178 -204.703172)
		(end 374.828054 -204.703172)
		(width 0.11684)
		(layer "In2.Cu")
		(net "JTAG_CPU0_DBREQ_N")
	)
	(segment
		(start 296.90187 -168.023286)
		(end 280.258774 -168.023286)
		(width 0.11684)
		(layer "In2.Cu")
		(net "JTAG_CPU0_DBREQ_N")
	)
	(segment
		(start 274.128992 -108.290106)
		(end 274.128992 -104.213914)
		(width 0.11684)
		(layer "In2.Cu")
		(net "JTAG_CPU0_DBREQ_N")
	)
	(segment
		(start 254.428752 -93.159072)
		(end 253.193042 -93.159072)
		(width 0.11684)
		(layer "In2.Cu")
		(net "JTAG_CPU0_DBREQ_N")
	)
	(segment
		(start 227.969318 -153.837132)
		(end 228.288596 -154.15641)
		(width 0.10668)
		(layer "F.Cu")
		(net "JTAG_CPU0_BYPASS")
	)
	(segment
		(start 232.889806 -149.273768)
		(end 229.833424 -149.273768)
		(width 0.10668)
		(layer "F.Cu")
		(net "JTAG_CPU0_BYPASS")
	)
	(segment
		(start 227.969318 -151.137874)
		(end 227.969318 -153.837132)
		(width 0.10668)
		(layer "F.Cu")
		(net "JTAG_CPU0_BYPASS")
	)
	(segment
		(start 228.288596 -154.15641)
		(end 229.160324 -154.15641)
		(width 0.10668)
		(layer "F.Cu")
		(net "JTAG_CPU0_BYPASS")
	)
	(segment
		(start 229.203504 -149.903688)
		(end 227.969318 -151.137874)
		(width 0.10668)
		(layer "F.Cu")
		(net "JTAG_CPU0_BYPASS")
	)
	(segment
		(start 229.833424 -149.273768)
		(end 229.203504 -149.903688)
		(width 0.10668)
		(layer "F.Cu")
		(net "JTAG_CPU0_BYPASS")
	)
	(via
		(at 229.203504 -149.903688)
		(size 0.508)
		(drill 0.254)
		(layers "F.Cu" "B.Cu")
		(net "JTAG_CPU0_BYPASS")
	)
	(segment
		(start 264.17143 -100.055934)
		(end 261.637018 -100.055934)
		(width 0.10668)
		(layer "F.Cu")
		(net "JTAG_BMC_R_D_OE")
	)
	(segment
		(start 166.50716 -79.156052)
		(end 165.206172 -80.45704)
		(width 0.10668)
		(layer "F.Cu")
		(net "JTAG_BMC_R_D_OE")
	)
	(segment
		(start 152.74163 -71.38035)
		(end 163.853622 -71.38035)
		(width 0.10668)
		(layer "F.Cu")
		(net "JTAG_BMC_R_D_OE")
	)
	(segment
		(start 123.527312 -52.534058)
		(end 124.385578 -52.534058)
		(width 0.10668)
		(layer "F.Cu")
		(net "JTAG_BMC_R_D_OE")
	)
	(segment
		(start 145.8341 -70.25386)
		(end 146.5834 -71.00316)
		(width 0.10668)
		(layer "F.Cu")
		(net "JTAG_BMC_R_D_OE")
	)
	(segment
		(start 260.24205 -102.108)
		(end 261.112 -102.108)
		(width 0.10668)
		(layer "F.Cu")
		(net "JTAG_BMC_R_D_OE")
	)
	(segment
		(start 261.637018 -100.055934)
		(end 261.518654 -100.174298)
		(width 0.10668)
		(layer "F.Cu")
		(net "JTAG_BMC_R_D_OE")
	)
	(segment
		(start 145.4912 -67.45986)
		(end 145.8341 -67.80276)
		(width 0.10668)
		(layer "F.Cu")
		(net "JTAG_BMC_R_D_OE")
	)
	(segment
		(start 146.5834 -71.00316)
		(end 152.36444 -71.00316)
		(width 0.10668)
		(layer "F.Cu")
		(net "JTAG_BMC_R_D_OE")
	)
	(segment
		(start 125.652022 -63.896494)
		(end 146.449034 -63.896494)
		(width 0.10668)
		(layer "F.Cu")
		(net "JTAG_BMC_R_D_OE")
	)
	(segment
		(start 159.681672 -80.45704)
		(end 155.840176 -84.298536)
		(width 0.10668)
		(layer "F.Cu")
		(net "JTAG_BMC_R_D_OE")
	)
	(segment
		(start 124.385578 -52.534058)
		(end 126.23038 -54.37886)
		(width 0.10668)
		(layer "F.Cu")
		(net "JTAG_BMC_R_D_OE")
	)
	(segment
		(start 155.840176 -84.298536)
		(end 155.840176 -89.102692)
		(width 0.10668)
		(layer "F.Cu")
		(net "JTAG_BMC_R_D_OE")
	)
	(segment
		(start 145.8341 -67.80276)
		(end 145.8341 -70.25386)
		(width 0.10668)
		(layer "F.Cu")
		(net "JTAG_BMC_R_D_OE")
	)
	(segment
		(start 126.23038 -54.37886)
		(end 126.23038 -57.29732)
		(width 0.10668)
		(layer "F.Cu")
		(net "JTAG_BMC_R_D_OE")
	)
	(segment
		(start 261.62 -101.6)
		(end 261.62 -100.275644)
		(width 0.10668)
		(layer "F.Cu")
		(net "JTAG_BMC_R_D_OE")
	)
	(segment
		(start 163.853622 -71.38035)
		(end 166.50716 -74.033888)
		(width 0.10668)
		(layer "F.Cu")
		(net "JTAG_BMC_R_D_OE")
	)
	(segment
		(start 145.4912 -65.73774)
		(end 145.4912 -67.45986)
		(width 0.10668)
		(layer "F.Cu")
		(net "JTAG_BMC_R_D_OE")
	)
	(segment
		(start 166.50716 -74.033888)
		(end 166.50716 -79.156052)
		(width 0.10668)
		(layer "F.Cu")
		(net "JTAG_BMC_R_D_OE")
	)
	(segment
		(start 122.127518 -58.842402)
		(end 122.127518 -60.37199)
		(width 0.10668)
		(layer "F.Cu")
		(net "JTAG_BMC_R_D_OE")
	)
	(segment
		(start 261.112 -102.108)
		(end 261.62 -101.6)
		(width 0.10668)
		(layer "F.Cu")
		(net "JTAG_BMC_R_D_OE")
	)
	(segment
		(start 145.907506 -65.321434)
		(end 145.4912 -65.73774)
		(width 0.10668)
		(layer "F.Cu")
		(net "JTAG_BMC_R_D_OE")
	)
	(segment
		(start 146.799046 -65.321434)
		(end 145.907506 -65.321434)
		(width 0.10668)
		(layer "F.Cu")
		(net "JTAG_BMC_R_D_OE")
	)
	(segment
		(start 122.57278 -58.39714)
		(end 122.127518 -58.842402)
		(width 0.10668)
		(layer "F.Cu")
		(net "JTAG_BMC_R_D_OE")
	)
	(segment
		(start 126.23038 -57.29732)
		(end 125.13056 -58.39714)
		(width 0.10668)
		(layer "F.Cu")
		(net "JTAG_BMC_R_D_OE")
	)
	(segment
		(start 123.327414 -53.394356)
		(end 123.527312 -53.194458)
		(width 0.10668)
		(layer "F.Cu")
		(net "JTAG_BMC_R_D_OE")
	)
	(segment
		(start 152.36444 -71.00316)
		(end 152.74163 -71.38035)
		(width 0.10668)
		(layer "F.Cu")
		(net "JTAG_BMC_R_D_OE")
	)
	(segment
		(start 146.449034 -63.896494)
		(end 146.799046 -64.246506)
		(width 0.10668)
		(layer "F.Cu")
		(net "JTAG_BMC_R_D_OE")
	)
	(segment
		(start 165.206172 -80.45704)
		(end 159.681672 -80.45704)
		(width 0.10668)
		(layer "F.Cu")
		(net "JTAG_BMC_R_D_OE")
	)
	(segment
		(start 122.127518 -60.37199)
		(end 125.652022 -63.896494)
		(width 0.10668)
		(layer "F.Cu")
		(net "JTAG_BMC_R_D_OE")
	)
	(segment
		(start 125.13056 -58.39714)
		(end 122.57278 -58.39714)
		(width 0.10668)
		(layer "F.Cu")
		(net "JTAG_BMC_R_D_OE")
	)
	(segment
		(start 123.327414 -54.075584)
		(end 123.327414 -53.394356)
		(width 0.10668)
		(layer "F.Cu")
		(net "JTAG_BMC_R_D_OE")
	)
	(segment
		(start 155.840176 -89.102692)
		(end 155.84551 -89.108026)
		(width 0.10668)
		(layer "F.Cu")
		(net "JTAG_BMC_R_D_OE")
	)
	(segment
		(start 146.799046 -64.246506)
		(end 146.799046 -65.321434)
		(width 0.10668)
		(layer "F.Cu")
		(net "JTAG_BMC_R_D_OE")
	)
	(segment
		(start 261.62 -100.275644)
		(end 261.518654 -100.174298)
		(width 0.10668)
		(layer "F.Cu")
		(net "JTAG_BMC_R_D_OE")
	)
	(segment
		(start 123.527312 -53.194458)
		(end 123.527312 -52.534058)
		(width 0.10668)
		(layer "F.Cu")
		(net "JTAG_BMC_R_D_OE")
	)
	(via
		(at 155.84551 -89.108026)
		(size 0.508)
		(drill 0.254)
		(layers "F.Cu" "B.Cu")
		(net "JTAG_BMC_R_D_OE")
	)
	(via
		(at 261.518654 -100.174298)
		(size 0.508)
		(drill 0.254)
		(layers "F.Cu" "B.Cu")
		(net "JTAG_BMC_R_D_OE")
	)
	(segment
		(start 174.478442 -89.375488)
		(end 174.249334 -89.14638)
		(width 0.11684)
		(layer "In2.Cu")
		(net "JTAG_BMC_R_D_OE")
	)
	(segment
		(start 171.382182 -89.375488)
		(end 156.112972 -89.375488)
		(width 0.11684)
		(layer "In2.Cu")
		(net "JTAG_BMC_R_D_OE")
	)
	(segment
		(start 215.152986 -94.09811)
		(end 210.837018 -89.782142)
		(width 0.11684)
		(layer "In2.Cu")
		(net "JTAG_BMC_R_D_OE")
	)
	(segment
		(start 195.95084 -89.375742)
		(end 178.39817 -89.375742)
		(width 0.11684)
		(layer "In2.Cu")
		(net "JTAG_BMC_R_D_OE")
	)
	(segment
		(start 178.298348 -89.27592)
		(end 175.314356 -89.27592)
		(width 0.11684)
		(layer "In2.Cu")
		(net "JTAG_BMC_R_D_OE")
	)
	(segment
		(start 175.214788 -89.375488)
		(end 174.478442 -89.375488)
		(width 0.11684)
		(layer "In2.Cu")
		(net "JTAG_BMC_R_D_OE")
	)
	(segment
		(start 210.837018 -89.782142)
		(end 196.35724 -89.782142)
		(width 0.11684)
		(layer "In2.Cu")
		(net "JTAG_BMC_R_D_OE")
	)
	(segment
		(start 175.314356 -89.27592)
		(end 175.214788 -89.375488)
		(width 0.11684)
		(layer "In2.Cu")
		(net "JTAG_BMC_R_D_OE")
	)
	(segment
		(start 237.06963 -99.565968)
		(end 231.601772 -94.09811)
		(width 0.11684)
		(layer "In2.Cu")
		(net "JTAG_BMC_R_D_OE")
	)
	(segment
		(start 260.910324 -99.565968)
		(end 237.06963 -99.565968)
		(width 0.11684)
		(layer "In2.Cu")
		(net "JTAG_BMC_R_D_OE")
	)
	(segment
		(start 196.35724 -89.782142)
		(end 195.95084 -89.375742)
		(width 0.11684)
		(layer "In2.Cu")
		(net "JTAG_BMC_R_D_OE")
	)
	(segment
		(start 174.249334 -89.14638)
		(end 171.61129 -89.14638)
		(width 0.11684)
		(layer "In2.Cu")
		(net "JTAG_BMC_R_D_OE")
	)
	(segment
		(start 231.601772 -94.09811)
		(end 215.152986 -94.09811)
		(width 0.11684)
		(layer "In2.Cu")
		(net "JTAG_BMC_R_D_OE")
	)
	(segment
		(start 171.61129 -89.14638)
		(end 171.382182 -89.375488)
		(width 0.11684)
		(layer "In2.Cu")
		(net "JTAG_BMC_R_D_OE")
	)
	(segment
		(start 156.112972 -89.375488)
		(end 155.84551 -89.108026)
		(width 0.11684)
		(layer "In2.Cu")
		(net "JTAG_BMC_R_D_OE")
	)
	(segment
		(start 178.39817 -89.375742)
		(end 178.298348 -89.27592)
		(width 0.11684)
		(layer "In2.Cu")
		(net "JTAG_BMC_R_D_OE")
	)
	(segment
		(start 261.518654 -100.174298)
		(end 260.910324 -99.565968)
		(width 0.11684)
		(layer "In2.Cu")
		(net "JTAG_BMC_R_D_OE")
	)
	(segment
		(start 165.37686 -80.86852)
		(end 166.91864 -79.32674)
		(width 0.10668)
		(layer "F.Cu")
		(net "JTAG_BMC_OE_N")
	)
	(segment
		(start 156.87548 -89.65184)
		(end 156.87548 -83.8454)
		(width 0.10668)
		(layer "F.Cu")
		(net "JTAG_BMC_OE_N")
	)
	(segment
		(start 146.382994 -60.406534)
		(end 145.874994 -59.898534)
		(width 0.10668)
		(layer "F.Cu")
		(net "JTAG_BMC_OE_N")
	)
	(segment
		(start 145.874994 -59.238134)
		(end 146.074892 -59.038236)
		(width 0.10668)
		(layer "F.Cu")
		(net "JTAG_BMC_OE_N")
	)
	(segment
		(start 152.90038 -67.4497)
		(end 152.082246 -67.4497)
		(width 0.10668)
		(layer "F.Cu")
		(net "JTAG_BMC_OE_N")
	)
	(segment
		(start 153.31948 -67.8688)
		(end 152.90038 -67.4497)
		(width 0.10668)
		(layer "F.Cu")
		(net "JTAG_BMC_OE_N")
	)
	(segment
		(start 166.91864 -79.32674)
		(end 166.91864 -73.8632)
		(width 0.10668)
		(layer "F.Cu")
		(net "JTAG_BMC_OE_N")
	)
	(segment
		(start 264.26795 -109.122972)
		(end 262.739886 -109.122972)
		(width 0.10668)
		(layer "F.Cu")
		(net "JTAG_BMC_OE_N")
	)
	(segment
		(start 151.577294 -64.582294)
		(end 147.401534 -60.406534)
		(width 0.10668)
		(layer "F.Cu")
		(net "JTAG_BMC_OE_N")
	)
	(segment
		(start 152.082246 -67.4497)
		(end 151.577294 -66.944748)
		(width 0.10668)
		(layer "F.Cu")
		(net "JTAG_BMC_OE_N")
	)
	(segment
		(start 159.85236 -80.86852)
		(end 165.37686 -80.86852)
		(width 0.10668)
		(layer "F.Cu")
		(net "JTAG_BMC_OE_N")
	)
	(segment
		(start 147.401534 -60.406534)
		(end 146.382994 -60.406534)
		(width 0.10668)
		(layer "F.Cu")
		(net "JTAG_BMC_OE_N")
	)
	(segment
		(start 155.223972 -91.303348)
		(end 156.87548 -89.65184)
		(width 0.10668)
		(layer "F.Cu")
		(net "JTAG_BMC_OE_N")
	)
	(segment
		(start 164.02431 -70.96887)
		(end 153.882598 -70.96887)
		(width 0.10668)
		(layer "F.Cu")
		(net "JTAG_BMC_OE_N")
	)
	(segment
		(start 153.882598 -70.96887)
		(end 153.31948 -70.405752)
		(width 0.10668)
		(layer "F.Cu")
		(net "JTAG_BMC_OE_N")
	)
	(segment
		(start 151.577294 -66.944748)
		(end 151.577294 -65.387474)
		(width 0.10668)
		(layer "F.Cu")
		(net "JTAG_BMC_OE_N")
	)
	(segment
		(start 145.874994 -59.898534)
		(end 145.874994 -59.238134)
		(width 0.10668)
		(layer "F.Cu")
		(net "JTAG_BMC_OE_N")
	)
	(segment
		(start 151.577294 -65.387474)
		(end 151.577294 -64.582294)
		(width 0.10668)
		(layer "F.Cu")
		(net "JTAG_BMC_OE_N")
	)
	(segment
		(start 146.074892 -59.038236)
		(end 146.074892 -57.976008)
		(width 0.10668)
		(layer "F.Cu")
		(net "JTAG_BMC_OE_N")
	)
	(segment
		(start 166.91864 -73.8632)
		(end 164.02431 -70.96887)
		(width 0.10668)
		(layer "F.Cu")
		(net "JTAG_BMC_OE_N")
	)
	(segment
		(start 153.31948 -70.405752)
		(end 153.31948 -67.8688)
		(width 0.10668)
		(layer "F.Cu")
		(net "JTAG_BMC_OE_N")
	)
	(segment
		(start 156.87548 -83.8454)
		(end 159.85236 -80.86852)
		(width 0.10668)
		(layer "F.Cu")
		(net "JTAG_BMC_OE_N")
	)
	(via
		(at 155.223972 -91.303348)
		(size 0.508)
		(drill 0.254)
		(layers "F.Cu" "B.Cu")
		(net "JTAG_BMC_OE_N")
	)
	(via
		(at 262.739886 -109.122972)
		(size 0.508)
		(drill 0.254)
		(layers "F.Cu" "B.Cu")
		(net "JTAG_BMC_OE_N")
	)
	(segment
		(start 220.587316 -97.877376)
		(end 220.10116 -97.39122)
		(width 0.11684)
		(layer "In2.Cu")
		(net "JTAG_BMC_OE_N")
	)
	(segment
		(start 177.774092 -90.54084)
		(end 175.838612 -90.54084)
		(width 0.11684)
		(layer "In2.Cu")
		(net "JTAG_BMC_OE_N")
	)
	(segment
		(start 227.043488 -102.61346)
		(end 222.307404 -97.877376)
		(width 0.11684)
		(layer "In2.Cu")
		(net "JTAG_BMC_OE_N")
	)
	(segment
		(start 175.838612 -90.54084)
		(end 175.739044 -90.640408)
		(width 0.11684)
		(layer "In2.Cu")
		(net "JTAG_BMC_OE_N")
	)
	(segment
		(start 262.739886 -109.122972)
		(end 257.11785 -103.500936)
		(width 0.11684)
		(layer "In2.Cu")
		(net "JTAG_BMC_OE_N")
	)
	(segment
		(start 195.051172 -90.640662)
		(end 177.873914 -90.640662)
		(width 0.11684)
		(layer "In2.Cu")
		(net "JTAG_BMC_OE_N")
	)
	(segment
		(start 173.725078 -90.4113)
		(end 172.135546 -90.4113)
		(width 0.11684)
		(layer "In2.Cu")
		(net "JTAG_BMC_OE_N")
	)
	(segment
		(start 209.788252 -92.02674)
		(end 203.700634 -92.02674)
		(width 0.11684)
		(layer "In2.Cu")
		(net "JTAG_BMC_OE_N")
	)
	(segment
		(start 172.135546 -90.4113)
		(end 171.906438 -90.640408)
		(width 0.11684)
		(layer "In2.Cu")
		(net "JTAG_BMC_OE_N")
	)
	(segment
		(start 196.685408 -92.274898)
		(end 195.051172 -90.640662)
		(width 0.11684)
		(layer "In2.Cu")
		(net "JTAG_BMC_OE_N")
	)
	(segment
		(start 173.954186 -90.640408)
		(end 173.725078 -90.4113)
		(width 0.11684)
		(layer "In2.Cu")
		(net "JTAG_BMC_OE_N")
	)
	(segment
		(start 257.11785 -103.500936)
		(end 253.513082 -103.500936)
		(width 0.11684)
		(layer "In2.Cu")
		(net "JTAG_BMC_OE_N")
	)
	(segment
		(start 222.307404 -97.877376)
		(end 220.587316 -97.877376)
		(width 0.11684)
		(layer "In2.Cu")
		(net "JTAG_BMC_OE_N")
	)
	(segment
		(start 252.625606 -102.61346)
		(end 227.043488 -102.61346)
		(width 0.11684)
		(layer "In2.Cu")
		(net "JTAG_BMC_OE_N")
	)
	(segment
		(start 175.739044 -90.640408)
		(end 173.954186 -90.640408)
		(width 0.11684)
		(layer "In2.Cu")
		(net "JTAG_BMC_OE_N")
	)
	(segment
		(start 177.873914 -90.640662)
		(end 177.774092 -90.54084)
		(width 0.11684)
		(layer "In2.Cu")
		(net "JTAG_BMC_OE_N")
	)
	(segment
		(start 220.10116 -97.39122)
		(end 215.152732 -97.39122)
		(width 0.11684)
		(layer "In2.Cu")
		(net "JTAG_BMC_OE_N")
	)
	(segment
		(start 253.513082 -103.500936)
		(end 252.625606 -102.61346)
		(width 0.11684)
		(layer "In2.Cu")
		(net "JTAG_BMC_OE_N")
	)
	(segment
		(start 203.452476 -92.274898)
		(end 196.685408 -92.274898)
		(width 0.11684)
		(layer "In2.Cu")
		(net "JTAG_BMC_OE_N")
	)
	(segment
		(start 171.906438 -90.640408)
		(end 155.886912 -90.640408)
		(width 0.11684)
		(layer "In2.Cu")
		(net "JTAG_BMC_OE_N")
	)
	(segment
		(start 215.152732 -97.39122)
		(end 209.788252 -92.02674)
		(width 0.11684)
		(layer "In2.Cu")
		(net "JTAG_BMC_OE_N")
	)
	(segment
		(start 155.886912 -90.640408)
		(end 155.223972 -91.303348)
		(width 0.11684)
		(layer "In2.Cu")
		(net "JTAG_BMC_OE_N")
	)
	(segment
		(start 203.700634 -92.02674)
		(end 203.452476 -92.274898)
		(width 0.11684)
		(layer "In2.Cu")
		(net "JTAG_BMC_OE_N")
	)
	(segment
		(start 147.599146 -65.321434)
		(end 148.127974 -65.321434)
		(width 0.10668)
		(layer "F.Cu")
		(net "JTAG_BMC_OE")
	)
	(segment
		(start 383.723388 -66.813938)
		(end 400.929348 -66.813938)
		(width 0.10668)
		(layer "F.Cu")
		(net "JTAG_BMC_OE")
	)
	(segment
		(start 400.929348 -66.813938)
		(end 404.710646 -63.03264)
		(width 0.10668)
		(layer "F.Cu")
		(net "JTAG_BMC_OE")
	)
	(segment
		(start 358.871774 -61.091064)
		(end 378.000514 -61.091064)
		(width 0.10668)
		(layer "F.Cu")
		(net "JTAG_BMC_OE")
	)
	(segment
		(start 149.143974 -66.337434)
		(end 149.377146 -66.337434)
		(width 0.10668)
		(layer "F.Cu")
		(net "JTAG_BMC_OE")
	)
	(segment
		(start 148.127974 -65.321434)
		(end 149.143974 -66.337434)
		(width 0.10668)
		(layer "F.Cu")
		(net "JTAG_BMC_OE")
	)
	(segment
		(start 272.211292 -68.758308)
		(end 281.613864 -59.355736)
		(width 0.10668)
		(layer "F.Cu")
		(net "JTAG_BMC_OE")
	)
	(segment
		(start 281.613864 -59.355736)
		(end 357.136446 -59.355736)
		(width 0.10668)
		(layer "F.Cu")
		(net "JTAG_BMC_OE")
	)
	(segment
		(start 147.599146 -66.337434)
		(end 147.599146 -66.97472)
		(width 0.10668)
		(layer "F.Cu")
		(net "JTAG_BMC_OE")
	)
	(segment
		(start 147.599146 -66.337434)
		(end 147.599146 -65.321434)
		(width 0.10668)
		(layer "F.Cu")
		(net "JTAG_BMC_OE")
	)
	(segment
		(start 357.136446 -59.355736)
		(end 358.871774 -61.091064)
		(width 0.10668)
		(layer "F.Cu")
		(net "JTAG_BMC_OE")
	)
	(segment
		(start 426.277532 -56.097678)
		(end 427.337982 -56.097678)
		(width 0.10668)
		(layer "F.Cu")
		(net "JTAG_BMC_OE")
	)
	(segment
		(start 378.000514 -61.091064)
		(end 383.723388 -66.813938)
		(width 0.10668)
		(layer "F.Cu")
		(net "JTAG_BMC_OE")
	)
	(via
		(at 147.599146 -66.97472)
		(size 0.508)
		(drill 0.254)
		(layers "F.Cu" "B.Cu")
		(net "JTAG_BMC_OE")
	)
	(via
		(at 404.710646 -63.03264)
		(size 0.508)
		(drill 0.254)
		(layers "F.Cu" "B.Cu")
		(net "JTAG_BMC_OE")
	)
	(via
		(at 427.337982 -56.097678)
		(size 0.508)
		(drill 0.254)
		(layers "F.Cu" "B.Cu")
		(net "JTAG_BMC_OE")
	)
	(via
		(at 272.211292 -68.758308)
		(size 0.508)
		(drill 0.254)
		(layers "F.Cu" "B.Cu")
		(net "JTAG_BMC_OE")
	)
	(segment
		(start 259.026406 -73.297034)
		(end 259.323586 -73.594214)
		(width 0.11684)
		(layer "In2.Cu")
		(net "JTAG_BMC_OE")
	)
	(segment
		(start 173.092872 -80.800194)
		(end 182.998872 -80.800194)
		(width 0.11684)
		(layer "In2.Cu")
		(net "JTAG_BMC_OE")
	)
	(segment
		(start 259.323586 -73.594214)
		(end 260.248908 -73.594214)
		(width 0.11684)
		(layer "In2.Cu")
		(net "JTAG_BMC_OE")
	)
	(segment
		(start 213.81593 -78.04912)
		(end 220.483176 -78.04912)
		(width 0.11684)
		(layer "In2.Cu")
		(net "JTAG_BMC_OE")
	)
	(segment
		(start 211.581238 -80.283812)
		(end 213.81593 -78.04912)
		(width 0.11684)
		(layer "In2.Cu")
		(net "JTAG_BMC_OE")
	)
	(segment
		(start 271.037304 -67.58432)
		(end 272.211292 -68.758308)
		(width 0.11684)
		(layer "In2.Cu")
		(net "JTAG_BMC_OE")
	)
	(segment
		(start 194.372738 -80.283812)
		(end 211.581238 -80.283812)
		(width 0.11684)
		(layer "In2.Cu")
		(net "JTAG_BMC_OE")
	)
	(segment
		(start 268.14018 -67.58432)
		(end 271.037304 -67.58432)
		(width 0.11684)
		(layer "In2.Cu")
		(net "JTAG_BMC_OE")
	)
	(segment
		(start 260.95325 -71.764398)
		(end 265.88466 -66.832988)
		(width 0.11684)
		(layer "In2.Cu")
		(net "JTAG_BMC_OE")
	)
	(segment
		(start 267.388848 -66.832988)
		(end 268.14018 -67.58432)
		(width 0.11684)
		(layer "In2.Cu")
		(net "JTAG_BMC_OE")
	)
	(segment
		(start 265.88466 -66.832988)
		(end 267.388848 -66.832988)
		(width 0.11684)
		(layer "In2.Cu")
		(net "JTAG_BMC_OE")
	)
	(segment
		(start 420.40302 -63.03264)
		(end 427.337982 -56.097678)
		(width 0.11684)
		(layer "In2.Cu")
		(net "JTAG_BMC_OE")
	)
	(segment
		(start 220.483176 -78.04912)
		(end 231.955848 -73.297034)
		(width 0.11684)
		(layer "In2.Cu")
		(net "JTAG_BMC_OE")
	)
	(segment
		(start 260.95325 -72.889872)
		(end 260.95325 -71.764398)
		(width 0.11684)
		(layer "In2.Cu")
		(net "JTAG_BMC_OE")
	)
	(segment
		(start 231.955848 -73.297034)
		(end 259.026406 -73.297034)
		(width 0.11684)
		(layer "In2.Cu")
		(net "JTAG_BMC_OE")
	)
	(segment
		(start 182.998872 -80.800194)
		(end 184.087262 -81.888584)
		(width 0.11684)
		(layer "In2.Cu")
		(net "JTAG_BMC_OE")
	)
	(segment
		(start 260.248908 -73.594214)
		(end 260.95325 -72.889872)
		(width 0.11684)
		(layer "In2.Cu")
		(net "JTAG_BMC_OE")
	)
	(segment
		(start 147.599146 -66.97472)
		(end 159.267398 -66.97472)
		(width 0.11684)
		(layer "In2.Cu")
		(net "JTAG_BMC_OE")
	)
	(segment
		(start 192.767966 -81.888584)
		(end 194.372738 -80.283812)
		(width 0.11684)
		(layer "In2.Cu")
		(net "JTAG_BMC_OE")
	)
	(segment
		(start 159.267398 -66.97472)
		(end 173.092872 -80.800194)
		(width 0.11684)
		(layer "In2.Cu")
		(net "JTAG_BMC_OE")
	)
	(segment
		(start 184.087262 -81.888584)
		(end 192.767966 -81.888584)
		(width 0.11684)
		(layer "In2.Cu")
		(net "JTAG_BMC_OE")
	)
	(segment
		(start 404.710646 -63.03264)
		(end 420.40302 -63.03264)
		(width 0.11684)
		(layer "In2.Cu")
		(net "JTAG_BMC_OE")
	)
	(segment
		(start 161.62147 -75.481434)
		(end 161.022284 -75.481434)
		(width 0.10668)
		(layer "F.Cu")
		(net "IRQ_WAKE_R_N")
	)
	(segment
		(start 161.022284 -75.481434)
		(end 160.40227 -74.86142)
		(width 0.10668)
		(layer "F.Cu")
		(net "IRQ_WAKE_R_N")
	)
	(segment
		(start 160.40227 -73.64222)
		(end 160.40227 -74.86142)
		(width 0.10668)
		(layer "F.Cu")
		(net "IRQ_WAKE_R_N")
	)
	(via
		(at 160.40227 -74.86142)
		(size 0.762)
		(drill 0.381)
		(layers "F.Cu" "B.Cu")
		(net "IRQ_WAKE_R_N")
	)
	(segment
		(start 392.375898 -317.899288)
		(end 392.589258 -318.112648)
		(width 0.10668)
		(layer "F.Cu")
		(net "IRQ_WAKE_N")
	)
	(segment
		(start 143.081756 -313.563508)
		(end 143.404082 -313.563508)
		(width 0.10668)
		(layer "F.Cu")
		(net "IRQ_WAKE_N")
	)
	(segment
		(start 135.88365 -307.274214)
		(end 141.527784 -312.918348)
		(width 0.10668)
		(layer "F.Cu")
		(net "IRQ_WAKE_N")
	)
	(segment
		(start 137.927842 -295.69029)
		(end 137.927842 -296.022776)
		(width 0.10668)
		(layer "F.Cu")
		(net "IRQ_WAKE_N")
	)
	(segment
		(start 392.054842 -318.920622)
		(end 391.261854 -319.71361)
		(width 0.10668)
		(layer "F.Cu")
		(net "IRQ_WAKE_N")
	)
	(segment
		(start 142.436596 -312.918348)
		(end 143.081756 -313.563508)
		(width 0.10668)
		(layer "F.Cu")
		(net "IRQ_WAKE_N")
	)
	(segment
		(start 392.589258 -318.533272)
		(end 392.201908 -318.920622)
		(width 0.10668)
		(layer "F.Cu")
		(net "IRQ_WAKE_N")
	)
	(segment
		(start 135.88365 -298.066968)
		(end 135.88365 -307.274214)
		(width 0.10668)
		(layer "F.Cu")
		(net "IRQ_WAKE_N")
	)
	(segment
		(start 208.383632 -190.18377)
		(end 208.383632 -202.079352)
		(width 0.10668)
		(layer "F.Cu")
		(net "IRQ_WAKE_N")
	)
	(segment
		(start 186.548268 -171.62653)
		(end 186.548268 -172.336714)
		(width 0.10668)
		(layer "F.Cu")
		(net "IRQ_WAKE_N")
	)
	(segment
		(start 391.261854 -321.941698)
		(end 392.963908 -323.643752)
		(width 0.10668)
		(layer "F.Cu")
		(net "IRQ_WAKE_N")
	)
	(segment
		(start 385.86791 -295.690036)
		(end 385.86791 -296.013886)
		(width 0.10668)
		(layer "F.Cu")
		(net "IRQ_WAKE_N")
	)
	(segment
		(start 382.786636 -299.51045)
		(end 380.564898 -301.732188)
		(width 0.10668)
		(layer "F.Cu")
		(net "IRQ_WAKE_N")
	)
	(segment
		(start 389.519922 -317.899288)
		(end 392.375898 -317.899288)
		(width 0.10668)
		(layer "F.Cu")
		(net "IRQ_WAKE_N")
	)
	(segment
		(start 382.786636 -299.09516)
		(end 382.786636 -299.51045)
		(width 0.10668)
		(layer "F.Cu")
		(net "IRQ_WAKE_N")
	)
	(segment
		(start 203.313538 -182.45074)
		(end 206.50073 -185.637932)
		(width 0.10668)
		(layer "F.Cu")
		(net "IRQ_WAKE_N")
	)
	(segment
		(start 208.872074 -202.567794)
		(end 208.989676 -202.567794)
		(width 0.10668)
		(layer "F.Cu")
		(net "IRQ_WAKE_N")
	)
	(segment
		(start 391.261854 -319.71361)
		(end 391.261854 -321.941698)
		(width 0.10668)
		(layer "F.Cu")
		(net "IRQ_WAKE_N")
	)
	(segment
		(start 137.927842 -296.022776)
		(end 135.88365 -298.066968)
		(width 0.10668)
		(layer "F.Cu")
		(net "IRQ_WAKE_N")
	)
	(segment
		(start 392.201908 -318.920622)
		(end 392.054842 -318.920622)
		(width 0.10668)
		(layer "F.Cu")
		(net "IRQ_WAKE_N")
	)
	(segment
		(start 186.548268 -172.336714)
		(end 196.662294 -182.45074)
		(width 0.10668)
		(layer "F.Cu")
		(net "IRQ_WAKE_N")
	)
	(segment
		(start 392.589258 -318.112648)
		(end 392.589258 -318.533272)
		(width 0.10668)
		(layer "F.Cu")
		(net "IRQ_WAKE_N")
	)
	(segment
		(start 141.527784 -312.918348)
		(end 142.436596 -312.918348)
		(width 0.10668)
		(layer "F.Cu")
		(net "IRQ_WAKE_N")
	)
	(segment
		(start 206.50073 -185.637932)
		(end 208.383632 -190.18377)
		(width 0.10668)
		(layer "F.Cu")
		(net "IRQ_WAKE_N")
	)
	(segment
		(start 380.564898 -308.944264)
		(end 389.519922 -317.899288)
		(width 0.10668)
		(layer "F.Cu")
		(net "IRQ_WAKE_N")
	)
	(segment
		(start 385.86791 -296.013886)
		(end 382.786636 -299.09516)
		(width 0.10668)
		(layer "F.Cu")
		(net "IRQ_WAKE_N")
	)
	(segment
		(start 143.404082 -313.563508)
		(end 143.646398 -313.805824)
		(width 0.10668)
		(layer "F.Cu")
		(net "IRQ_WAKE_N")
	)
	(segment
		(start 208.383632 -202.079352)
		(end 208.872074 -202.567794)
		(width 0.10668)
		(layer "F.Cu")
		(net "IRQ_WAKE_N")
	)
	(segment
		(start 160.40227 -72.84212)
		(end 160.40227 -72.22617)
		(width 0.10668)
		(layer "F.Cu")
		(net "IRQ_WAKE_N")
	)
	(segment
		(start 196.662294 -182.45074)
		(end 203.313538 -182.45074)
		(width 0.10668)
		(layer "F.Cu")
		(net "IRQ_WAKE_N")
	)
	(segment
		(start 380.564898 -301.732188)
		(end 380.564898 -308.944264)
		(width 0.10668)
		(layer "F.Cu")
		(net "IRQ_WAKE_N")
	)
	(via
		(at 219.39123 -366.91824)
		(size 0.508)
		(drill 0.254)
		(layers "F.Cu" "B.Cu")
		(net "IRQ_WAKE_N")
	)
	(via
		(at 392.589258 -318.533272)
		(size 0.508)
		(drill 0.254)
		(layers "F.Cu" "B.Cu")
		(net "IRQ_WAKE_N")
	)
	(via
		(at 186.548268 -171.62653)
		(size 0.508)
		(drill 0.254)
		(layers "F.Cu" "B.Cu")
		(net "IRQ_WAKE_N")
	)
	(via
		(at 211.416138 -317.932562)
		(size 0.508)
		(drill 0.254)
		(layers "F.Cu" "B.Cu")
		(net "IRQ_WAKE_N")
	)
	(via
		(at 143.646398 -313.805824)
		(size 0.508)
		(drill 0.254)
		(layers "F.Cu" "B.Cu")
		(net "IRQ_WAKE_N")
	)
	(via
		(at 163.335462 -127.734314)
		(size 0.508)
		(drill 0.254)
		(layers "F.Cu" "B.Cu")
		(net "IRQ_WAKE_N")
	)
	(via
		(at 160.40227 -72.22617)
		(size 0.508)
		(drill 0.254)
		(layers "F.Cu" "B.Cu")
		(net "IRQ_WAKE_N")
	)
	(via
		(at 208.989676 -202.567794)
		(size 0.508)
		(drill 0.254)
		(layers "F.Cu" "B.Cu")
		(net "IRQ_WAKE_N")
	)
	(segment
		(start 164.134292 -129.450592)
		(end 164.134292 -130.542538)
		(width 0.10668)
		(layer "B.Cu")
		(net "IRQ_WAKE_N")
	)
	(segment
		(start 164.134292 -130.542538)
		(end 171.079668 -137.487914)
		(width 0.10668)
		(layer "B.Cu")
		(net "IRQ_WAKE_N")
	)
	(segment
		(start 163.314126 -128.630426)
		(end 164.134292 -129.450592)
		(width 0.10668)
		(layer "B.Cu")
		(net "IRQ_WAKE_N")
	)
	(segment
		(start 163.335462 -127.734314)
		(end 163.314126 -127.75565)
		(width 0.10668)
		(layer "B.Cu")
		(net "IRQ_WAKE_N")
	)
	(segment
		(start 186.548268 -170.066716)
		(end 186.548268 -171.62653)
		(width 0.10668)
		(layer "B.Cu")
		(net "IRQ_WAKE_N")
	)
	(segment
		(start 163.314126 -127.75565)
		(end 163.314126 -128.630426)
		(width 0.10668)
		(layer "B.Cu")
		(net "IRQ_WAKE_N")
	)
	(segment
		(start 178.45278 -169.939716)
		(end 186.421268 -169.939716)
		(width 0.10668)
		(layer "B.Cu")
		(net "IRQ_WAKE_N")
	)
	(segment
		(start 171.079668 -137.487914)
		(end 171.079668 -153.396442)
		(width 0.10668)
		(layer "B.Cu")
		(net "IRQ_WAKE_N")
	)
	(segment
		(start 175.655224 -167.14216)
		(end 178.45278 -169.939716)
		(width 0.10668)
		(layer "B.Cu")
		(net "IRQ_WAKE_N")
	)
	(segment
		(start 171.079668 -153.396442)
		(end 175.655224 -157.971998)
		(width 0.10668)
		(layer "B.Cu")
		(net "IRQ_WAKE_N")
	)
	(segment
		(start 175.655224 -157.971998)
		(end 175.655224 -167.14216)
		(width 0.10668)
		(layer "B.Cu")
		(net "IRQ_WAKE_N")
	)
	(segment
		(start 186.421268 -169.939716)
		(end 186.548268 -170.066716)
		(width 0.10668)
		(layer "B.Cu")
		(net "IRQ_WAKE_N")
	)
	(segment
		(start 290.31311 -374.21566)
		(end 288.31667 -372.21922)
		(width 0.11684)
		(layer "In2.Cu")
		(net "IRQ_WAKE_N")
	)
	(segment
		(start 385.454652 -337.73364)
		(end 354.138992 -369.0493)
		(width 0.11684)
		(layer "In2.Cu")
		(net "IRQ_WAKE_N")
	)
	(segment
		(start 219.39123 -368.362484)
		(end 219.39123 -366.91824)
		(width 0.11684)
		(layer "In2.Cu")
		(net "IRQ_WAKE_N")
	)
	(segment
		(start 281.707082 -371.15623)
		(end 276.695662 -366.14481)
		(width 0.11684)
		(layer "In2.Cu")
		(net "IRQ_WAKE_N")
	)
	(segment
		(start 220.330776 -369.30203)
		(end 219.39123 -368.362484)
		(width 0.11684)
		(layer "In2.Cu")
		(net "IRQ_WAKE_N")
	)
	(segment
		(start 250.193302 -366.902238)
		(end 233.60507 -366.902238)
		(width 0.11684)
		(layer "In2.Cu")
		(net "IRQ_WAKE_N")
	)
	(segment
		(start 390.481312 -318.442848)
		(end 385.454652 -323.469508)
		(width 0.11684)
		(layer "In2.Cu")
		(net "IRQ_WAKE_N")
	)
	(segment
		(start 233.60507 -366.902238)
		(end 231.205278 -369.30203)
		(width 0.11684)
		(layer "In2.Cu")
		(net "IRQ_WAKE_N")
	)
	(segment
		(start 288.31667 -372.201694)
		(end 287.271206 -371.15623)
		(width 0.11684)
		(layer "In2.Cu")
		(net "IRQ_WAKE_N")
	)
	(segment
		(start 251.250704 -367.95964)
		(end 250.193302 -366.902238)
		(width 0.11684)
		(layer "In2.Cu")
		(net "IRQ_WAKE_N")
	)
	(segment
		(start 392.413236 -318.35725)
		(end 392.413236 -318.179704)
		(width 0.11684)
		(layer "In2.Cu")
		(net "IRQ_WAKE_N")
	)
	(segment
		(start 287.271206 -371.15623)
		(end 281.707082 -371.15623)
		(width 0.11684)
		(layer "In2.Cu")
		(net "IRQ_WAKE_N")
	)
	(segment
		(start 271.632426 -366.208564)
		(end 269.88135 -367.95964)
		(width 0.11684)
		(layer "In2.Cu")
		(net "IRQ_WAKE_N")
	)
	(segment
		(start 392.413236 -318.179704)
		(end 392.17346 -317.939928)
		(width 0.11684)
		(layer "In2.Cu")
		(net "IRQ_WAKE_N")
	)
	(segment
		(start 231.205278 -369.30203)
		(end 220.330776 -369.30203)
		(width 0.11684)
		(layer "In2.Cu")
		(net "IRQ_WAKE_N")
	)
	(segment
		(start 269.88135 -367.95964)
		(end 251.250704 -367.95964)
		(width 0.11684)
		(layer "In2.Cu")
		(net "IRQ_WAKE_N")
	)
	(segment
		(start 392.589258 -318.533272)
		(end 392.413236 -318.35725)
		(width 0.11684)
		(layer "In2.Cu")
		(net "IRQ_WAKE_N")
	)
	(segment
		(start 276.695662 -366.14481)
		(end 271.78635 -366.14481)
		(width 0.11684)
		(layer "In2.Cu")
		(net "IRQ_WAKE_N")
	)
	(segment
		(start 298.102274 -374.21566)
		(end 290.31311 -374.21566)
		(width 0.11684)
		(layer "In2.Cu")
		(net "IRQ_WAKE_N")
	)
	(segment
		(start 390.877298 -318.442848)
		(end 390.481312 -318.442848)
		(width 0.11684)
		(layer "In2.Cu")
		(net "IRQ_WAKE_N")
	)
	(segment
		(start 288.31667 -372.21922)
		(end 288.31667 -372.201694)
		(width 0.11684)
		(layer "In2.Cu")
		(net "IRQ_WAKE_N")
	)
	(segment
		(start 391.380218 -317.939928)
		(end 390.877298 -318.442848)
		(width 0.11684)
		(layer "In2.Cu")
		(net "IRQ_WAKE_N")
	)
	(segment
		(start 271.78635 -366.14481)
		(end 271.632426 -366.208564)
		(width 0.11684)
		(layer "In2.Cu")
		(net "IRQ_WAKE_N")
	)
	(segment
		(start 354.138992 -369.0493)
		(end 322.36664 -373.76227)
		(width 0.11684)
		(layer "In2.Cu")
		(net "IRQ_WAKE_N")
	)
	(segment
		(start 322.36664 -373.76227)
		(end 298.555664 -373.76227)
		(width 0.11684)
		(layer "In2.Cu")
		(net "IRQ_WAKE_N")
	)
	(segment
		(start 298.555664 -373.76227)
		(end 298.102274 -374.21566)
		(width 0.11684)
		(layer "In2.Cu")
		(net "IRQ_WAKE_N")
	)
	(segment
		(start 392.17346 -317.939928)
		(end 391.380218 -317.939928)
		(width 0.11684)
		(layer "In2.Cu")
		(net "IRQ_WAKE_N")
	)
	(segment
		(start 385.454652 -323.469508)
		(end 385.454652 -337.73364)
		(width 0.11684)
		(layer "In2.Cu")
		(net "IRQ_WAKE_N")
	)
	(segment
		(start 211.416138 -318.457834)
		(end 211.416138 -317.932562)
		(width 0.11684)
		(layer "In4.Cu")
		(net "IRQ_WAKE_N")
	)
	(segment
		(start 156.863034 -323.884798)
		(end 159.93237 -323.884798)
		(width 0.11684)
		(layer "In4.Cu")
		(net "IRQ_WAKE_N")
	)
	(segment
		(start 161.57448 -322.242688)
		(end 207.631284 -322.242688)
		(width 0.11684)
		(layer "In4.Cu")
		(net "IRQ_WAKE_N")
	)
	(segment
		(start 144.003268 -315.334904)
		(end 145.9484 -317.280036)
		(width 0.11684)
		(layer "In4.Cu")
		(net "IRQ_WAKE_N")
	)
	(segment
		(start 145.9484 -317.280036)
		(end 145.9484 -318.834262)
		(width 0.11684)
		(layer "In4.Cu")
		(net "IRQ_WAKE_N")
	)
	(segment
		(start 147.377912 -320.263774)
		(end 148.887434 -320.263774)
		(width 0.11684)
		(layer "In4.Cu")
		(net "IRQ_WAKE_N")
	)
	(segment
		(start 151.643588 -325.292212)
		(end 155.45562 -325.292212)
		(width 0.11684)
		(layer "In4.Cu")
		(net "IRQ_WAKE_N")
	)
	(segment
		(start 145.9484 -318.834262)
		(end 147.377912 -320.263774)
		(width 0.11684)
		(layer "In4.Cu")
		(net "IRQ_WAKE_N")
	)
	(segment
		(start 207.631284 -322.242688)
		(end 211.416138 -318.457834)
		(width 0.11684)
		(layer "In4.Cu")
		(net "IRQ_WAKE_N")
	)
	(segment
		(start 149.82571 -323.474334)
		(end 151.643588 -325.292212)
		(width 0.11684)
		(layer "In4.Cu")
		(net "IRQ_WAKE_N")
	)
	(segment
		(start 143.646398 -313.805824)
		(end 144.003268 -314.162694)
		(width 0.11684)
		(layer "In4.Cu")
		(net "IRQ_WAKE_N")
	)
	(segment
		(start 144.003268 -314.162694)
		(end 144.003268 -315.334904)
		(width 0.11684)
		(layer "In4.Cu")
		(net "IRQ_WAKE_N")
	)
	(segment
		(start 159.93237 -323.884798)
		(end 161.57448 -322.242688)
		(width 0.11684)
		(layer "In4.Cu")
		(net "IRQ_WAKE_N")
	)
	(segment
		(start 155.45562 -325.292212)
		(end 156.863034 -323.884798)
		(width 0.11684)
		(layer "In4.Cu")
		(net "IRQ_WAKE_N")
	)
	(segment
		(start 148.887434 -320.263774)
		(end 149.82571 -321.20205)
		(width 0.11684)
		(layer "In4.Cu")
		(net "IRQ_WAKE_N")
	)
	(segment
		(start 149.82571 -321.20205)
		(end 149.82571 -323.474334)
		(width 0.11684)
		(layer "In4.Cu")
		(net "IRQ_WAKE_N")
	)
	(segment
		(start 212.301074 -205.423008)
		(end 212.301074 -317.047626)
		(width 0.11684)
		(layer "In6.Cu")
		(net "IRQ_WAKE_N")
	)
	(segment
		(start 219.39123 -364.78083)
		(end 220.867986 -363.304074)
		(width 0.11684)
		(layer "In6.Cu")
		(net "IRQ_WAKE_N")
	)
	(segment
		(start 208.989676 -202.567794)
		(end 209.44586 -202.567794)
		(width 0.11684)
		(layer "In6.Cu")
		(net "IRQ_WAKE_N")
	)
	(segment
		(start 219.39123 -366.91824)
		(end 219.39123 -364.78083)
		(width 0.11684)
		(layer "In6.Cu")
		(net "IRQ_WAKE_N")
	)
	(segment
		(start 223.22282 -334.570324)
		(end 211.416138 -322.763642)
		(width 0.11684)
		(layer "In6.Cu")
		(net "IRQ_WAKE_N")
	)
	(segment
		(start 220.867986 -360.289094)
		(end 223.22282 -357.93426)
		(width 0.11684)
		(layer "In6.Cu")
		(net "IRQ_WAKE_N")
	)
	(segment
		(start 220.867986 -363.304074)
		(end 220.867986 -360.289094)
		(width 0.11684)
		(layer "In6.Cu")
		(net "IRQ_WAKE_N")
	)
	(segment
		(start 209.44586 -202.567794)
		(end 212.301074 -205.423008)
		(width 0.11684)
		(layer "In6.Cu")
		(net "IRQ_WAKE_N")
	)
	(segment
		(start 211.416138 -322.763642)
		(end 211.416138 -317.932562)
		(width 0.11684)
		(layer "In6.Cu")
		(net "IRQ_WAKE_N")
	)
	(segment
		(start 223.22282 -357.93426)
		(end 223.22282 -334.570324)
		(width 0.11684)
		(layer "In6.Cu")
		(net "IRQ_WAKE_N")
	)
	(segment
		(start 212.301074 -317.047626)
		(end 211.416138 -317.932562)
		(width 0.11684)
		(layer "In6.Cu")
		(net "IRQ_WAKE_N")
	)
	(segment
		(start 160.039304 -106.71175)
		(end 158.60268 -105.275126)
		(width 0.11684)
		(layer "In11.Cu")
		(net "IRQ_WAKE_N")
	)
	(segment
		(start 158.60268 -105.275126)
		(end 158.60268 -89.517474)
		(width 0.11684)
		(layer "In11.Cu")
		(net "IRQ_WAKE_N")
	)
	(segment
		(start 160.039304 -107.506516)
		(end 160.039304 -106.71175)
		(width 0.11684)
		(layer "In11.Cu")
		(net "IRQ_WAKE_N")
	)
	(segment
		(start 163.335462 -127.734314)
		(end 163.335462 -126.263908)
		(width 0.11684)
		(layer "In11.Cu")
		(net "IRQ_WAKE_N")
	)
	(segment
		(start 163.335462 -126.263908)
		(end 158.788862 -121.717308)
		(width 0.11684)
		(layer "In11.Cu")
		(net "IRQ_WAKE_N")
	)
	(segment
		(start 159.75838 -112.97666)
		(end 159.75838 -107.78744)
		(width 0.11684)
		(layer "In11.Cu")
		(net "IRQ_WAKE_N")
	)
	(segment
		(start 160.99155 -87.128604)
		(end 160.99155 -80.160368)
		(width 0.11684)
		(layer "In11.Cu")
		(net "IRQ_WAKE_N")
	)
	(segment
		(start 158.788862 -117.128798)
		(end 160.2486 -115.66906)
		(width 0.11684)
		(layer "In11.Cu")
		(net "IRQ_WAKE_N")
	)
	(segment
		(start 160.2486 -113.46688)
		(end 159.75838 -112.97666)
		(width 0.11684)
		(layer "In11.Cu")
		(net "IRQ_WAKE_N")
	)
	(segment
		(start 158.60268 -89.517474)
		(end 160.99155 -87.128604)
		(width 0.11684)
		(layer "In11.Cu")
		(net "IRQ_WAKE_N")
	)
	(segment
		(start 160.2486 -115.66906)
		(end 160.2486 -113.46688)
		(width 0.11684)
		(layer "In11.Cu")
		(net "IRQ_WAKE_N")
	)
	(segment
		(start 160.99155 -80.160368)
		(end 160.40227 -79.571088)
		(width 0.11684)
		(layer "In11.Cu")
		(net "IRQ_WAKE_N")
	)
	(segment
		(start 158.788862 -121.717308)
		(end 158.788862 -117.128798)
		(width 0.11684)
		(layer "In11.Cu")
		(net "IRQ_WAKE_N")
	)
	(segment
		(start 159.75838 -107.78744)
		(end 160.039304 -107.506516)
		(width 0.11684)
		(layer "In11.Cu")
		(net "IRQ_WAKE_N")
	)
	(segment
		(start 160.40227 -79.571088)
		(end 160.40227 -72.22617)
		(width 0.11684)
		(layer "In11.Cu")
		(net "IRQ_WAKE_N")
	)
	(segment
		(start 159.151574 -121.819924)
		(end 159.350456 -121.621042)
		(width 0.10668)
		(layer "F.Cu")
		(net "IRQ_UV_DETECT_N")
	)
	(segment
		(start 147.193 -119.38)
		(end 146.812 -119.761)
		(width 0.10668)
		(layer "F.Cu")
		(net "IRQ_UV_DETECT_N")
	)
	(segment
		(start 150.10511 -121.158)
		(end 148.844 -121.158)
		(width 0.10668)
		(layer "F.Cu")
		(net "IRQ_UV_DETECT_N")
	)
	(segment
		(start 146.812 -119.761)
		(end 145.56105 -119.761)
		(width 0.10668)
		(layer "F.Cu")
		(net "IRQ_UV_DETECT_N")
	)
	(segment
		(start 154.319478 -121.819924)
		(end 159.151574 -121.819924)
		(width 0.10668)
		(layer "F.Cu")
		(net "IRQ_UV_DETECT_N")
	)
	(segment
		(start 148.844 -121.158)
		(end 148.59 -120.904)
		(width 0.10668)
		(layer "F.Cu")
		(net "IRQ_UV_DETECT_N")
	)
	(segment
		(start 143.383 -121.158)
		(end 143.383 -119.507)
		(width 0.10668)
		(layer "F.Cu")
		(net "IRQ_UV_DETECT_N")
	)
	(segment
		(start 163.30295 -115.280948)
		(end 163.30295 -115.199414)
		(width 0.10668)
		(layer "F.Cu")
		(net "IRQ_UV_DETECT_N")
	)
	(segment
		(start 142.76705 -121.285)
		(end 143.256 -121.285)
		(width 0.10668)
		(layer "F.Cu")
		(net "IRQ_UV_DETECT_N")
	)
	(segment
		(start 145.05305 -119.253)
		(end 145.56105 -119.761)
		(width 0.10668)
		(layer "F.Cu")
		(net "IRQ_UV_DETECT_N")
	)
	(segment
		(start 150.773384 -121.826274)
		(end 150.10511 -121.158)
		(width 0.10668)
		(layer "F.Cu")
		(net "IRQ_UV_DETECT_N")
	)
	(segment
		(start 148.59 -119.634)
		(end 148.336 -119.38)
		(width 0.10668)
		(layer "F.Cu")
		(net "IRQ_UV_DETECT_N")
	)
	(segment
		(start 148.59 -120.904)
		(end 148.59 -119.634)
		(width 0.10668)
		(layer "F.Cu")
		(net "IRQ_UV_DETECT_N")
	)
	(segment
		(start 143.637 -119.253)
		(end 145.05305 -119.253)
		(width 0.10668)
		(layer "F.Cu")
		(net "IRQ_UV_DETECT_N")
	)
	(segment
		(start 143.383 -119.507)
		(end 143.637 -119.253)
		(width 0.10668)
		(layer "F.Cu")
		(net "IRQ_UV_DETECT_N")
	)
	(segment
		(start 148.336 -119.38)
		(end 147.193 -119.38)
		(width 0.10668)
		(layer "F.Cu")
		(net "IRQ_UV_DETECT_N")
	)
	(segment
		(start 163.00323 -114.899694)
		(end 162.385502 -114.899694)
		(width 0.10668)
		(layer "F.Cu")
		(net "IRQ_UV_DETECT_N")
	)
	(segment
		(start 154.313128 -121.826274)
		(end 154.319478 -121.819924)
		(width 0.10668)
		(layer "F.Cu")
		(net "IRQ_UV_DETECT_N")
	)
	(segment
		(start 143.256 -121.285)
		(end 143.383 -121.158)
		(width 0.10668)
		(layer "F.Cu")
		(net "IRQ_UV_DETECT_N")
	)
	(segment
		(start 150.773384 -121.826274)
		(end 154.313128 -121.826274)
		(width 0.10668)
		(layer "F.Cu")
		(net "IRQ_UV_DETECT_N")
	)
	(segment
		(start 163.30295 -115.199414)
		(end 163.00323 -114.899694)
		(width 0.10668)
		(layer "F.Cu")
		(net "IRQ_UV_DETECT_N")
	)
	(via
		(at 162.385502 -114.899694)
		(size 0.508)
		(drill 0.254)
		(layers "F.Cu" "B.Cu")
		(net "IRQ_UV_DETECT_N")
	)
	(via
		(at 159.350456 -121.621042)
		(size 0.508)
		(drill 0.254)
		(layers "F.Cu" "B.Cu")
		(net "IRQ_UV_DETECT_N")
	)
	(segment
		(start 159.350456 -121.621042)
		(end 159.350456 -117.270784)
		(width 0.11684)
		(layer "In11.Cu")
		(net "IRQ_UV_DETECT_N")
	)
	(segment
		(start 159.350456 -117.270784)
		(end 161.721546 -114.899694)
		(width 0.11684)
		(layer "In11.Cu")
		(net "IRQ_UV_DETECT_N")
	)
	(segment
		(start 161.721546 -114.899694)
		(end 162.385502 -114.899694)
		(width 0.11684)
		(layer "In11.Cu")
		(net "IRQ_UV_DETECT_N")
	)
	(segment
		(start 242.840002 -362.04906)
		(end 259.715 -345.174062)
		(width 0.10668)
		(layer "F.Cu")
		(net "IRQ_SML1_PMBUS_ALERT_N")
	)
	(segment
		(start 260.84784 -187.364624)
		(end 260.84784 -185.06313)
		(width 0.10668)
		(layer "F.Cu")
		(net "IRQ_SML1_PMBUS_ALERT_N")
	)
	(segment
		(start 260.84784 -185.06313)
		(end 261.870698 -184.040272)
		(width 0.10668)
		(layer "F.Cu")
		(net "IRQ_SML1_PMBUS_ALERT_N")
	)
	(segment
		(start 260.934454 -147.158456)
		(end 258.892294 -145.116296)
		(width 0.10668)
		(layer "F.Cu")
		(net "IRQ_SML1_PMBUS_ALERT_N")
	)
	(segment
		(start 260.934454 -149.59838)
		(end 260.934454 -147.158456)
		(width 0.10668)
		(layer "F.Cu")
		(net "IRQ_SML1_PMBUS_ALERT_N")
	)
	(segment
		(start 261.927086 -194.586352)
		(end 261.927086 -188.44387)
		(width 0.10668)
		(layer "F.Cu")
		(net "IRQ_SML1_PMBUS_ALERT_N")
	)
	(segment
		(start 261.298182 -195.215256)
		(end 261.927086 -194.586352)
		(width 0.10668)
		(layer "F.Cu")
		(net "IRQ_SML1_PMBUS_ALERT_N")
	)
	(segment
		(start 259.715 -345.174062)
		(end 259.715 -337.868768)
		(width 0.10668)
		(layer "F.Cu")
		(net "IRQ_SML1_PMBUS_ALERT_N")
	)
	(segment
		(start 177.922174 -122.65279)
		(end 177.532284 -123.04268)
		(width 0.10668)
		(layer "F.Cu")
		(net "IRQ_SML1_PMBUS_ALERT_N")
	)
	(segment
		(start 231.276144 -362.04906)
		(end 242.840002 -362.04906)
		(width 0.10668)
		(layer "F.Cu")
		(net "IRQ_SML1_PMBUS_ALERT_N")
	)
	(segment
		(start 261.870698 -184.040272)
		(end 261.870698 -150.534624)
		(width 0.10668)
		(layer "F.Cu")
		(net "IRQ_SML1_PMBUS_ALERT_N")
	)
	(segment
		(start 228.82479 -364.500414)
		(end 231.276144 -362.04906)
		(width 0.10668)
		(layer "F.Cu")
		(net "IRQ_SML1_PMBUS_ALERT_N")
	)
	(segment
		(start 259.715 -337.868768)
		(end 261.298182 -336.285586)
		(width 0.10668)
		(layer "F.Cu")
		(net "IRQ_SML1_PMBUS_ALERT_N")
	)
	(segment
		(start 261.870698 -150.534624)
		(end 260.934454 -149.59838)
		(width 0.10668)
		(layer "F.Cu")
		(net "IRQ_SML1_PMBUS_ALERT_N")
	)
	(segment
		(start 193.779902 -386.660644)
		(end 192.573402 -386.660644)
		(width 0.10668)
		(layer "F.Cu")
		(net "IRQ_SML1_PMBUS_ALERT_N")
	)
	(segment
		(start 261.298182 -336.285586)
		(end 261.298182 -195.215256)
		(width 0.10668)
		(layer "F.Cu")
		(net "IRQ_SML1_PMBUS_ALERT_N")
	)
	(segment
		(start 261.927086 -188.44387)
		(end 260.84784 -187.364624)
		(width 0.10668)
		(layer "F.Cu")
		(net "IRQ_SML1_PMBUS_ALERT_N")
	)
	(via
		(at 182.906924 -408.823668)
		(size 0.508)
		(drill 0.254)
		(layers "F.Cu" "B.Cu")
		(net "IRQ_SML1_PMBUS_ALERT_N")
	)
	(via
		(at 177.532284 -123.04268)
		(size 0.4572)
		(drill 0.254)
		(layers "F.Cu" "B.Cu")
		(net "IRQ_SML1_PMBUS_ALERT_N")
	)
	(via
		(at 258.892294 -145.116296)
		(size 0.508)
		(drill 0.254)
		(layers "F.Cu" "B.Cu")
		(net "IRQ_SML1_PMBUS_ALERT_N")
	)
	(via
		(at 192.573402 -386.660644)
		(size 0.508)
		(drill 0.254)
		(layers "F.Cu" "B.Cu")
		(net "IRQ_SML1_PMBUS_ALERT_N")
	)
	(via
		(at 228.82479 -364.500414)
		(size 0.508)
		(drill 0.254)
		(layers "F.Cu" "B.Cu")
		(net "IRQ_SML1_PMBUS_ALERT_N")
	)
	(segment
		(start 182.952898 -408.777694)
		(end 182.906924 -408.823668)
		(width 0.10668)
		(layer "B.Cu")
		(net "IRQ_SML1_PMBUS_ALERT_N")
	)
	(segment
		(start 182.92445 -404.051262)
		(end 182.92445 -404.40483)
		(width 0.10668)
		(layer "B.Cu")
		(net "IRQ_SML1_PMBUS_ALERT_N")
	)
	(segment
		(start 182.92445 -404.40483)
		(end 183.143652 -404.624032)
		(width 0.10668)
		(layer "B.Cu")
		(net "IRQ_SML1_PMBUS_ALERT_N")
	)
	(segment
		(start 182.952898 -407.925524)
		(end 182.952898 -408.777694)
		(width 0.10668)
		(layer "B.Cu")
		(net "IRQ_SML1_PMBUS_ALERT_N")
	)
	(segment
		(start 183.143652 -404.624032)
		(end 183.143652 -405.92121)
		(width 0.10668)
		(layer "B.Cu")
		(net "IRQ_SML1_PMBUS_ALERT_N")
	)
	(segment
		(start 183.143652 -405.92121)
		(end 182.82412 -406.240742)
		(width 0.10668)
		(layer "B.Cu")
		(net "IRQ_SML1_PMBUS_ALERT_N")
	)
	(segment
		(start 182.82412 -406.240742)
		(end 182.82412 -407.796746)
		(width 0.10668)
		(layer "B.Cu")
		(net "IRQ_SML1_PMBUS_ALERT_N")
	)
	(segment
		(start 182.82412 -407.796746)
		(end 182.952898 -407.925524)
		(width 0.10668)
		(layer "B.Cu")
		(net "IRQ_SML1_PMBUS_ALERT_N")
	)
	(segment
		(start 180.29047 -407.738326)
		(end 181.003702 -407.738326)
		(width 0.11684)
		(layer "In6.Cu")
		(net "IRQ_SML1_PMBUS_ALERT_N")
	)
	(segment
		(start 178.842416 -399.532856)
		(end 179.37226 -400.0627)
		(width 0.11684)
		(layer "In6.Cu")
		(net "IRQ_SML1_PMBUS_ALERT_N")
	)
	(segment
		(start 221.658942 -374.75922)
		(end 195.08724 -374.75922)
		(width 0.11684)
		(layer "In6.Cu")
		(net "IRQ_SML1_PMBUS_ALERT_N")
	)
	(segment
		(start 179.713128 -407.160984)
		(end 180.29047 -407.738326)
		(width 0.11684)
		(layer "In6.Cu")
		(net "IRQ_SML1_PMBUS_ALERT_N")
	)
	(segment
		(start 178.842416 -396.085822)
		(end 178.842416 -399.532856)
		(width 0.11684)
		(layer "In6.Cu")
		(net "IRQ_SML1_PMBUS_ALERT_N")
	)
	(segment
		(start 182.089044 -408.823668)
		(end 182.906924 -408.823668)
		(width 0.11684)
		(layer "In6.Cu")
		(net "IRQ_SML1_PMBUS_ALERT_N")
	)
	(segment
		(start 179.713128 -405.72817)
		(end 179.713128 -407.160984)
		(width 0.11684)
		(layer "In6.Cu")
		(net "IRQ_SML1_PMBUS_ALERT_N")
	)
	(segment
		(start 181.003702 -407.738326)
		(end 182.089044 -408.823668)
		(width 0.11684)
		(layer "In6.Cu")
		(net "IRQ_SML1_PMBUS_ALERT_N")
	)
	(segment
		(start 182.523638 -392.4046)
		(end 178.842416 -396.085822)
		(width 0.11684)
		(layer "In6.Cu")
		(net "IRQ_SML1_PMBUS_ALERT_N")
	)
	(segment
		(start 228.82479 -364.500414)
		(end 228.274626 -365.050578)
		(width 0.11684)
		(layer "In6.Cu")
		(net "IRQ_SML1_PMBUS_ALERT_N")
	)
	(segment
		(start 228.274626 -365.050578)
		(end 228.274626 -368.143536)
		(width 0.11684)
		(layer "In6.Cu")
		(net "IRQ_SML1_PMBUS_ALERT_N")
	)
	(segment
		(start 192.573402 -386.660644)
		(end 186.829446 -392.4046)
		(width 0.11684)
		(layer "In6.Cu")
		(net "IRQ_SML1_PMBUS_ALERT_N")
	)
	(segment
		(start 228.274626 -368.143536)
		(end 221.658942 -374.75922)
		(width 0.11684)
		(layer "In6.Cu")
		(net "IRQ_SML1_PMBUS_ALERT_N")
	)
	(segment
		(start 186.829446 -392.4046)
		(end 182.523638 -392.4046)
		(width 0.11684)
		(layer "In6.Cu")
		(net "IRQ_SML1_PMBUS_ALERT_N")
	)
	(segment
		(start 191.601852 -378.244608)
		(end 191.601852 -385.689094)
		(width 0.11684)
		(layer "In6.Cu")
		(net "IRQ_SML1_PMBUS_ALERT_N")
	)
	(segment
		(start 195.08724 -374.75922)
		(end 191.601852 -378.244608)
		(width 0.11684)
		(layer "In6.Cu")
		(net "IRQ_SML1_PMBUS_ALERT_N")
	)
	(segment
		(start 179.37226 -405.387302)
		(end 179.713128 -405.72817)
		(width 0.11684)
		(layer "In6.Cu")
		(net "IRQ_SML1_PMBUS_ALERT_N")
	)
	(segment
		(start 191.601852 -385.689094)
		(end 192.573402 -386.660644)
		(width 0.11684)
		(layer "In6.Cu")
		(net "IRQ_SML1_PMBUS_ALERT_N")
	)
	(segment
		(start 179.37226 -400.0627)
		(end 179.37226 -405.387302)
		(width 0.11684)
		(layer "In6.Cu")
		(net "IRQ_SML1_PMBUS_ALERT_N")
	)
	(segment
		(start 184.221374 -130.85318)
		(end 184.840626 -130.85318)
		(width 0.11684)
		(layer "In15.Cu")
		(net "IRQ_SML1_PMBUS_ALERT_N")
	)
	(segment
		(start 175.856392 -124.07265)
		(end 175.856392 -134.524242)
		(width 0.11684)
		(layer "In15.Cu")
		(net "IRQ_SML1_PMBUS_ALERT_N")
	)
	(segment
		(start 188.6712 -131.903724)
		(end 188.6712 -133.100572)
		(width 0.11684)
		(layer "In15.Cu")
		(net "IRQ_SML1_PMBUS_ALERT_N")
	)
	(segment
		(start 180.427122 -131.134866)
		(end 180.24221 -130.949954)
		(width 0.11684)
		(layer "In15.Cu")
		(net "IRQ_SML1_PMBUS_ALERT_N")
	)
	(segment
		(start 183.473852 -130.122422)
		(end 183.473852 -130.614928)
		(width 0.11684)
		(layer "In15.Cu")
		(net "IRQ_SML1_PMBUS_ALERT_N")
	)
	(segment
		(start 184.846214 -130.858768)
		(end 185.231786 -130.858768)
		(width 0.11684)
		(layer "In15.Cu")
		(net "IRQ_SML1_PMBUS_ALERT_N")
	)
	(segment
		(start 240.626392 -140.259562)
		(end 245.483126 -145.116296)
		(width 0.11684)
		(layer "In15.Cu")
		(net "IRQ_SML1_PMBUS_ALERT_N")
	)
	(segment
		(start 183.473852 -130.614928)
		(end 183.712104 -130.85318)
		(width 0.11684)
		(layer "In15.Cu")
		(net "IRQ_SML1_PMBUS_ALERT_N")
	)
	(segment
		(start 189.5221 -133.951472)
		(end 194.799458 -133.951472)
		(width 0.11684)
		(layer "In15.Cu")
		(net "IRQ_SML1_PMBUS_ALERT_N")
	)
	(segment
		(start 185.862214 -130.858768)
		(end 186.247786 -130.858768)
		(width 0.11684)
		(layer "In15.Cu")
		(net "IRQ_SML1_PMBUS_ALERT_N")
	)
	(segment
		(start 183.830214 -130.858768)
		(end 184.215786 -130.858768)
		(width 0.11684)
		(layer "In15.Cu")
		(net "IRQ_SML1_PMBUS_ALERT_N")
	)
	(segment
		(start 175.856392 -134.524242)
		(end 176.385728 -135.053578)
		(width 0.11684)
		(layer "In15.Cu")
		(net "IRQ_SML1_PMBUS_ALERT_N")
	)
	(segment
		(start 186.247786 -130.858768)
		(end 186.253374 -130.85318)
		(width 0.11684)
		(layer "In15.Cu")
		(net "IRQ_SML1_PMBUS_ALERT_N")
	)
	(segment
		(start 188.6712 -133.100572)
		(end 189.5221 -133.951472)
		(width 0.11684)
		(layer "In15.Cu")
		(net "IRQ_SML1_PMBUS_ALERT_N")
	)
	(segment
		(start 185.231786 -130.858768)
		(end 185.237374 -130.85318)
		(width 0.11684)
		(layer "In15.Cu")
		(net "IRQ_SML1_PMBUS_ALERT_N")
	)
	(segment
		(start 194.799458 -133.951472)
		(end 195.524882 -133.226048)
		(width 0.11684)
		(layer "In15.Cu")
		(net "IRQ_SML1_PMBUS_ALERT_N")
	)
	(segment
		(start 176.385728 -135.053578)
		(end 180.177694 -135.053578)
		(width 0.11684)
		(layer "In15.Cu")
		(net "IRQ_SML1_PMBUS_ALERT_N")
	)
	(segment
		(start 180.427122 -134.80415)
		(end 180.427122 -131.134866)
		(width 0.11684)
		(layer "In15.Cu")
		(net "IRQ_SML1_PMBUS_ALERT_N")
	)
	(segment
		(start 183.126126 -129.774696)
		(end 183.473852 -130.122422)
		(width 0.11684)
		(layer "In15.Cu")
		(net "IRQ_SML1_PMBUS_ALERT_N")
	)
	(segment
		(start 213.396322 -135.608568)
		(end 213.674198 -135.330692)
		(width 0.11684)
		(layer "In15.Cu")
		(net "IRQ_SML1_PMBUS_ALERT_N")
	)
	(segment
		(start 185.856626 -130.85318)
		(end 185.862214 -130.858768)
		(width 0.11684)
		(layer "In15.Cu")
		(net "IRQ_SML1_PMBUS_ALERT_N")
	)
	(segment
		(start 205.512416 -133.226048)
		(end 207.894936 -135.608568)
		(width 0.11684)
		(layer "In15.Cu")
		(net "IRQ_SML1_PMBUS_ALERT_N")
	)
	(segment
		(start 176.494694 -123.434348)
		(end 175.856392 -124.07265)
		(width 0.11684)
		(layer "In15.Cu")
		(net "IRQ_SML1_PMBUS_ALERT_N")
	)
	(segment
		(start 180.24221 -130.17373)
		(end 180.641244 -129.774696)
		(width 0.11684)
		(layer "In15.Cu")
		(net "IRQ_SML1_PMBUS_ALERT_N")
	)
	(segment
		(start 227.026978 -135.330692)
		(end 231.955848 -140.259562)
		(width 0.11684)
		(layer "In15.Cu")
		(net "IRQ_SML1_PMBUS_ALERT_N")
	)
	(segment
		(start 195.524882 -133.226048)
		(end 205.512416 -133.226048)
		(width 0.11684)
		(layer "In15.Cu")
		(net "IRQ_SML1_PMBUS_ALERT_N")
	)
	(segment
		(start 245.483126 -145.116296)
		(end 258.892294 -145.116296)
		(width 0.11684)
		(layer "In15.Cu")
		(net "IRQ_SML1_PMBUS_ALERT_N")
	)
	(segment
		(start 180.177694 -135.053578)
		(end 180.427122 -134.80415)
		(width 0.11684)
		(layer "In15.Cu")
		(net "IRQ_SML1_PMBUS_ALERT_N")
	)
	(segment
		(start 207.894936 -135.608568)
		(end 213.396322 -135.608568)
		(width 0.11684)
		(layer "In15.Cu")
		(net "IRQ_SML1_PMBUS_ALERT_N")
	)
	(segment
		(start 183.712104 -130.85318)
		(end 183.824626 -130.85318)
		(width 0.11684)
		(layer "In15.Cu")
		(net "IRQ_SML1_PMBUS_ALERT_N")
	)
	(segment
		(start 185.237374 -130.85318)
		(end 185.856626 -130.85318)
		(width 0.11684)
		(layer "In15.Cu")
		(net "IRQ_SML1_PMBUS_ALERT_N")
	)
	(segment
		(start 184.215786 -130.858768)
		(end 184.221374 -130.85318)
		(width 0.11684)
		(layer "In15.Cu")
		(net "IRQ_SML1_PMBUS_ALERT_N")
	)
	(segment
		(start 213.674198 -135.330692)
		(end 227.026978 -135.330692)
		(width 0.11684)
		(layer "In15.Cu")
		(net "IRQ_SML1_PMBUS_ALERT_N")
	)
	(segment
		(start 177.140616 -123.434348)
		(end 176.494694 -123.434348)
		(width 0.11684)
		(layer "In15.Cu")
		(net "IRQ_SML1_PMBUS_ALERT_N")
	)
	(segment
		(start 180.641244 -129.774696)
		(end 183.126126 -129.774696)
		(width 0.11684)
		(layer "In15.Cu")
		(net "IRQ_SML1_PMBUS_ALERT_N")
	)
	(segment
		(start 187.620656 -130.85318)
		(end 188.6712 -131.903724)
		(width 0.11684)
		(layer "In15.Cu")
		(net "IRQ_SML1_PMBUS_ALERT_N")
	)
	(segment
		(start 184.840626 -130.85318)
		(end 184.846214 -130.858768)
		(width 0.11684)
		(layer "In15.Cu")
		(net "IRQ_SML1_PMBUS_ALERT_N")
	)
	(segment
		(start 177.532284 -123.04268)
		(end 177.140616 -123.434348)
		(width 0.11684)
		(layer "In15.Cu")
		(net "IRQ_SML1_PMBUS_ALERT_N")
	)
	(segment
		(start 231.955848 -140.259562)
		(end 240.626392 -140.259562)
		(width 0.11684)
		(layer "In15.Cu")
		(net "IRQ_SML1_PMBUS_ALERT_N")
	)
	(segment
		(start 183.824626 -130.85318)
		(end 183.830214 -130.858768)
		(width 0.11684)
		(layer "In15.Cu")
		(net "IRQ_SML1_PMBUS_ALERT_N")
	)
	(segment
		(start 180.24221 -130.949954)
		(end 180.24221 -130.17373)
		(width 0.11684)
		(layer "In15.Cu")
		(net "IRQ_SML1_PMBUS_ALERT_N")
	)
	(segment
		(start 186.253374 -130.85318)
		(end 187.620656 -130.85318)
		(width 0.11684)
		(layer "In15.Cu")
		(net "IRQ_SML1_PMBUS_ALERT_N")
	)
	(segment
		(start 183.879744 -404.205948)
		(end 183.928512 -404.15718)
		(width 0.10668)
		(layer "F.Cu")
		(net "IRQ_SML1_PMBUS_ALERT")
	)
	(segment
		(start 182.783734 -406.169368)
		(end 183.74106 -405.212042)
		(width 0.10668)
		(layer "F.Cu")
		(net "IRQ_SML1_PMBUS_ALERT")
	)
	(segment
		(start 183.79186 -405.212042)
		(end 183.82234 -405.181562)
		(width 0.10668)
		(layer "F.Cu")
		(net "IRQ_SML1_PMBUS_ALERT")
	)
	(segment
		(start 182.236364 -406.169368)
		(end 182.783734 -406.169368)
		(width 0.10668)
		(layer "F.Cu")
		(net "IRQ_SML1_PMBUS_ALERT")
	)
	(segment
		(start 183.82234 -405.181562)
		(end 183.82234 -404.536656)
		(width 0.10668)
		(layer "F.Cu")
		(net "IRQ_SML1_PMBUS_ALERT")
	)
	(segment
		(start 183.879744 -404.479252)
		(end 183.879744 -404.205948)
		(width 0.10668)
		(layer "F.Cu")
		(net "IRQ_SML1_PMBUS_ALERT")
	)
	(segment
		(start 183.82234 -404.536656)
		(end 183.879744 -404.479252)
		(width 0.10668)
		(layer "F.Cu")
		(net "IRQ_SML1_PMBUS_ALERT")
	)
	(segment
		(start 182.14594 -406.259792)
		(end 182.236364 -406.169368)
		(width 0.10668)
		(layer "F.Cu")
		(net "IRQ_SML1_PMBUS_ALERT")
	)
	(segment
		(start 183.74106 -405.212042)
		(end 183.79186 -405.212042)
		(width 0.10668)
		(layer "F.Cu")
		(net "IRQ_SML1_PMBUS_ALERT")
	)
	(via
		(at 183.79186 -405.212042)
		(size 0.508)
		(drill 0.254)
		(layers "F.Cu" "B.Cu")
		(net "IRQ_SML1_PMBUS_ALERT")
	)
	(segment
		(start 183.72455 -405.144732)
		(end 183.79186 -405.212042)
		(width 0.10668)
		(layer "B.Cu")
		(net "IRQ_SML1_PMBUS_ALERT")
	)
	(segment
		(start 183.72455 -404.051262)
		(end 183.72455 -405.144732)
		(width 0.10668)
		(layer "B.Cu")
		(net "IRQ_SML1_PMBUS_ALERT")
	)
	(segment
		(start 161.62147 -76.13142)
		(end 160.40227 -76.13142)
		(width 0.10668)
		(layer "F.Cu")
		(net "IRQ_LVC3_WAKE_N")
	)
	(segment
		(start 160.40227 -76.13142)
		(end 159.18307 -76.13142)
		(width 0.10668)
		(layer "F.Cu")
		(net "IRQ_LVC3_WAKE_N")
	)
	(segment
		(start 158.16707 -75.15352)
		(end 159.18307 -75.15352)
		(width 0.10668)
		(layer "F.Cu")
		(net "IRQ_LVC3_WAKE_N")
	)
	(segment
		(start 159.18307 -75.15352)
		(end 159.18307 -76.13142)
		(width 0.10668)
		(layer "F.Cu")
		(net "IRQ_LVC3_WAKE_N")
	)
	(segment
		(start 157.15107 -75.15352)
		(end 158.16707 -75.15352)
		(width 0.10668)
		(layer "F.Cu")
		(net "IRQ_LVC3_WAKE_N")
	)
	(via
		(at 160.40227 -76.13142)
		(size 0.762)
		(drill 0.381)
		(layers "F.Cu" "B.Cu")
		(net "IRQ_LVC3_WAKE_N")
	)
	(segment
		(start 163.144454 -38.093904)
		(end 164.142674 -38.093904)
		(width 0.10668)
		(layer "F.Cu")
		(net "IRQ_LVC3_WAKE_BUF_N")
	)
	(segment
		(start 163.168076 -38.070282)
		(end 163.144454 -38.093904)
		(width 0.10668)
		(layer "F.Cu")
		(net "IRQ_LVC3_WAKE_BUF_N")
	)
	(segment
		(start 163.168076 -34.92373)
		(end 163.168076 -36.642548)
		(width 0.10668)
		(layer "F.Cu")
		(net "IRQ_LVC3_WAKE_BUF_N")
	)
	(segment
		(start 163.168076 -36.642548)
		(end 163.168076 -38.070282)
		(width 0.10668)
		(layer "F.Cu")
		(net "IRQ_LVC3_WAKE_BUF_N")
	)
	(via
		(at 163.168076 -36.642548)
		(size 0.762)
		(drill 0.381)
		(layers "F.Cu" "B.Cu")
		(net "IRQ_LVC3_WAKE_BUF_N")
	)
	(segment
		(start 163.52139 -76.13142)
		(end 163.52139 -76.781406)
		(width 0.10668)
		(layer "F.Cu")
		(net "IRQ_LVC3_WAKE")
	)
	(segment
		(start 164.74059 -76.781406)
		(end 164.74059 -78.000606)
		(width 0.10668)
		(layer "F.Cu")
		(net "IRQ_LVC3_WAKE")
	)
	(segment
		(start 163.52139 -76.781406)
		(end 164.74059 -76.781406)
		(width 0.10668)
		(layer "F.Cu")
		(net "IRQ_LVC3_WAKE")
	)
	(via
		(at 164.74059 -76.781406)
		(size 0.762)
		(drill 0.381)
		(layers "F.Cu" "B.Cu")
		(net "IRQ_LVC3_WAKE")
	)
	(segment
		(start 96.633538 -34.329878)
		(end 98.525076 -34.329878)
		(width 0.10668)
		(layer "F.Cu")
		(net "IRQ_LVC3_V3_2_WAKE_BUF_N")
	)
	(segment
		(start 98.525076 -34.329878)
		(end 100.496116 -34.329878)
		(width 0.10668)
		(layer "F.Cu")
		(net "IRQ_LVC3_V3_2_WAKE_BUF_N")
	)
	(segment
		(start 100.496116 -34.329878)
		(end 100.541074 -34.28492)
		(width 0.10668)
		(layer "F.Cu")
		(net "IRQ_LVC3_V3_2_WAKE_BUF_N")
	)
	(segment
		(start 100.551234 -34.29508)
		(end 100.541074 -34.28492)
		(width 0.10668)
		(layer "F.Cu")
		(net "IRQ_LVC3_V3_2_WAKE_BUF_N")
	)
	(segment
		(start 100.551234 -35.30092)
		(end 100.551234 -34.29508)
		(width 0.10668)
		(layer "F.Cu")
		(net "IRQ_LVC3_V3_2_WAKE_BUF_N")
	)
	(via
		(at 98.525076 -34.329878)
		(size 0.762)
		(drill 0.381)
		(layers "F.Cu" "B.Cu")
		(net "IRQ_LVC3_V3_2_WAKE_BUF_N")
	)
	(segment
		(start 104.312212 -40.42156)
		(end 104.14381 -40.589962)
		(width 0.10668)
		(layer "F.Cu")
		(net "IRQ_LVC3_OCP_V3_2_WAKE_N")
	)
	(segment
		(start 104.14381 -40.589962)
		(end 102.866698 -40.589962)
		(width 0.10668)
		(layer "F.Cu")
		(net "IRQ_LVC3_OCP_V3_2_WAKE_N")
	)
	(segment
		(start 100.46716 -39.465758)
		(end 99.47529 -39.465758)
		(width 0.10668)
		(layer "F.Cu")
		(net "IRQ_LVC3_OCP_V3_2_WAKE_N")
	)
	(segment
		(start 102.866698 -40.589962)
		(end 102.163372 -39.886636)
		(width 0.10668)
		(layer "F.Cu")
		(net "IRQ_LVC3_OCP_V3_2_WAKE_N")
	)
	(segment
		(start 102.163372 -39.886636)
		(end 100.888038 -39.886636)
		(width 0.10668)
		(layer "F.Cu")
		(net "IRQ_LVC3_OCP_V3_2_WAKE_N")
	)
	(segment
		(start 76.861924 -8.320024)
		(end 76.861924 -6.69671)
		(width 0.10668)
		(layer "F.Cu")
		(net "IRQ_LVC3_OCP_V3_2_WAKE_N")
	)
	(segment
		(start 100.888038 -39.886636)
		(end 100.46716 -39.465758)
		(width 0.10668)
		(layer "F.Cu")
		(net "IRQ_LVC3_OCP_V3_2_WAKE_N")
	)
	(via
		(at 104.312212 -40.42156)
		(size 0.508)
		(drill 0.254)
		(layers "F.Cu" "B.Cu")
		(net "IRQ_LVC3_OCP_V3_2_WAKE_N")
	)
	(via
		(at 76.861924 -6.69671)
		(size 0.508)
		(drill 0.254)
		(layers "F.Cu" "B.Cu")
		(net "IRQ_LVC3_OCP_V3_2_WAKE_N")
	)
	(segment
		(start 76.861924 -6.69671)
		(end 76.861924 -7.646416)
		(width 0.11684)
		(layer "In4.Cu")
		(net "IRQ_LVC3_OCP_V3_2_WAKE_N")
	)
	(segment
		(start 89.194894 -19.979386)
		(end 89.194894 -25.304242)
		(width 0.11684)
		(layer "In4.Cu")
		(net "IRQ_LVC3_OCP_V3_2_WAKE_N")
	)
	(segment
		(start 76.861924 -7.646416)
		(end 89.194894 -19.979386)
		(width 0.11684)
		(layer "In4.Cu")
		(net "IRQ_LVC3_OCP_V3_2_WAKE_N")
	)
	(segment
		(start 89.194894 -25.304242)
		(end 104.312212 -40.42156)
		(width 0.11684)
		(layer "In4.Cu")
		(net "IRQ_LVC3_OCP_V3_2_WAKE_N")
	)
	(segment
		(start 451.36181 -8.320024)
		(end 451.36181 -7.153402)
		(width 0.10668)
		(layer "F.Cu")
		(net "IRQ_LVC3_OCP_SFF_WAKE_N")
	)
	(segment
		(start 456.613768 -37.15639)
		(end 456.613768 -37.277294)
		(width 0.10668)
		(layer "F.Cu")
		(net "IRQ_LVC3_OCP_SFF_WAKE_N")
	)
	(segment
		(start 456.613768 -37.277294)
		(end 457.252324 -37.91585)
		(width 0.10668)
		(layer "F.Cu")
		(net "IRQ_LVC3_OCP_SFF_WAKE_N")
	)
	(segment
		(start 456.474322 -37.295836)
		(end 456.613768 -37.15639)
		(width 0.10668)
		(layer "F.Cu")
		(net "IRQ_LVC3_OCP_SFF_WAKE_N")
	)
	(segment
		(start 451.36181 -7.153402)
		(end 451.08368 -6.875272)
		(width 0.10668)
		(layer "F.Cu")
		(net "IRQ_LVC3_OCP_SFF_WAKE_N")
	)
	(segment
		(start 457.252324 -37.91585)
		(end 457.9112 -37.91585)
		(width 0.10668)
		(layer "F.Cu")
		(net "IRQ_LVC3_OCP_SFF_WAKE_N")
	)
	(segment
		(start 455.41311 -37.295836)
		(end 456.474322 -37.295836)
		(width 0.10668)
		(layer "F.Cu")
		(net "IRQ_LVC3_OCP_SFF_WAKE_N")
	)
	(via
		(at 451.08368 -6.875272)
		(size 0.508)
		(drill 0.254)
		(layers "F.Cu" "B.Cu")
		(net "IRQ_LVC3_OCP_SFF_WAKE_N")
	)
	(via
		(at 456.613768 -37.15639)
		(size 0.762)
		(drill 0.254)
		(layers "F.Cu" "B.Cu")
		(net "IRQ_LVC3_OCP_SFF_WAKE_N")
	)
	(segment
		(start 456.613768 -37.15639)
		(end 456.771756 -37.15639)
		(width 0.11684)
		(layer "In2.Cu")
		(net "IRQ_LVC3_OCP_SFF_WAKE_N")
	)
	(segment
		(start 451.21068 -6.875272)
		(end 451.08368 -6.875272)
		(width 0.11684)
		(layer "In2.Cu")
		(net "IRQ_LVC3_OCP_SFF_WAKE_N")
	)
	(segment
		(start 460.556356 -33.37179)
		(end 460.556356 -30.465522)
		(width 0.11684)
		(layer "In2.Cu")
		(net "IRQ_LVC3_OCP_SFF_WAKE_N")
	)
	(segment
		(start 460.556356 -30.465522)
		(end 457.436474 -27.34564)
		(width 0.11684)
		(layer "In2.Cu")
		(net "IRQ_LVC3_OCP_SFF_WAKE_N")
	)
	(segment
		(start 457.436474 -15.43558)
		(end 452.336154 -10.33526)
		(width 0.11684)
		(layer "In2.Cu")
		(net "IRQ_LVC3_OCP_SFF_WAKE_N")
	)
	(segment
		(start 452.336154 -8.000746)
		(end 451.21068 -6.875272)
		(width 0.11684)
		(layer "In2.Cu")
		(net "IRQ_LVC3_OCP_SFF_WAKE_N")
	)
	(segment
		(start 457.436474 -27.34564)
		(end 457.436474 -15.43558)
		(width 0.11684)
		(layer "In2.Cu")
		(net "IRQ_LVC3_OCP_SFF_WAKE_N")
	)
	(segment
		(start 452.336154 -10.33526)
		(end 452.336154 -8.000746)
		(width 0.11684)
		(layer "In2.Cu")
		(net "IRQ_LVC3_OCP_SFF_WAKE_N")
	)
	(segment
		(start 456.771756 -37.15639)
		(end 460.556356 -33.37179)
		(width 0.11684)
		(layer "In2.Cu")
		(net "IRQ_LVC3_OCP_SFF_WAKE_N")
	)
	(segment
		(start 161.94405 -106.426)
		(end 160.58896 -106.426)
		(width 0.10668)
		(layer "F.Cu")
		(net "IRQ_HSC_FAULT_N")
	)
	(segment
		(start 162.052 -106.31805)
		(end 161.94405 -106.426)
		(width 0.10668)
		(layer "F.Cu")
		(net "IRQ_HSC_FAULT_N")
	)
	(segment
		(start 189.65291 -172.435266)
		(end 198.290942 -181.073298)
		(width 0.10668)
		(layer "F.Cu")
		(net "IRQ_HSC_FAULT_N")
	)
	(segment
		(start 207.891888 -185.080656)
		(end 209.709512 -189.468506)
		(width 0.10668)
		(layer "F.Cu")
		(net "IRQ_HSC_FAULT_N")
	)
	(segment
		(start 209.709512 -189.468506)
		(end 209.709512 -193.173604)
		(width 0.10668)
		(layer "F.Cu")
		(net "IRQ_HSC_FAULT_N")
	)
	(segment
		(start 163.195 -106.40695)
		(end 163.1061 -106.31805)
		(width 0.10668)
		(layer "F.Cu")
		(net "IRQ_HSC_FAULT_N")
	)
	(segment
		(start 198.290942 -181.073298)
		(end 203.88453 -181.073298)
		(width 0.10668)
		(layer "F.Cu")
		(net "IRQ_HSC_FAULT_N")
	)
	(segment
		(start 164.97173 -105.64622)
		(end 164.31895 -106.299)
		(width 0.10668)
		(layer "F.Cu")
		(net "IRQ_HSC_FAULT_N")
	)
	(segment
		(start 191.81699 -402.341842)
		(end 192.43294 -402.341842)
		(width 0.10668)
		(layer "F.Cu")
		(net "IRQ_HSC_FAULT_N")
	)
	(segment
		(start 163.1061 -106.31805)
		(end 162.052 -106.31805)
		(width 0.10668)
		(layer "F.Cu")
		(net "IRQ_HSC_FAULT_N")
	)
	(segment
		(start 165.614858 -105.64622)
		(end 164.97173 -105.64622)
		(width 0.10668)
		(layer "F.Cu")
		(net "IRQ_HSC_FAULT_N")
	)
	(segment
		(start 193.779902 -379.660404)
		(end 192.573402 -379.660404)
		(width 0.10668)
		(layer "F.Cu")
		(net "IRQ_HSC_FAULT_N")
	)
	(segment
		(start 209.709512 -193.173604)
		(end 208.94675 -193.936366)
		(width 0.10668)
		(layer "F.Cu")
		(net "IRQ_HSC_FAULT_N")
	)
	(segment
		(start 203.88453 -181.073298)
		(end 207.891888 -185.080656)
		(width 0.10668)
		(layer "F.Cu")
		(net "IRQ_HSC_FAULT_N")
	)
	(segment
		(start 164.211 -106.40695)
		(end 163.195 -106.40695)
		(width 0.10668)
		(layer "F.Cu")
		(net "IRQ_HSC_FAULT_N")
	)
	(segment
		(start 164.31895 -106.299)
		(end 164.211 -106.40695)
		(width 0.10668)
		(layer "F.Cu")
		(net "IRQ_HSC_FAULT_N")
	)
	(via
		(at 169.164 -110.200948)
		(size 0.508)
		(drill 0.254)
		(layers "F.Cu" "B.Cu")
		(net "IRQ_HSC_FAULT_N")
	)
	(via
		(at 165.457124 -127.299212)
		(size 0.508)
		(drill 0.254)
		(layers "F.Cu" "B.Cu")
		(net "IRQ_HSC_FAULT_N")
	)
	(via
		(at 192.43294 -402.341842)
		(size 0.508)
		(drill 0.254)
		(layers "F.Cu" "B.Cu")
		(net "IRQ_HSC_FAULT_N")
	)
	(via
		(at 192.573402 -379.660404)
		(size 0.508)
		(drill 0.254)
		(layers "F.Cu" "B.Cu")
		(net "IRQ_HSC_FAULT_N")
	)
	(via
		(at 208.94675 -193.936366)
		(size 0.508)
		(drill 0.254)
		(layers "F.Cu" "B.Cu")
		(net "IRQ_HSC_FAULT_N")
	)
	(via
		(at 165.614858 -105.64622)
		(size 0.508)
		(drill 0.254)
		(layers "F.Cu" "B.Cu")
		(net "IRQ_HSC_FAULT_N")
	)
	(via
		(at 189.65291 -172.435266)
		(size 0.508)
		(drill 0.254)
		(layers "F.Cu" "B.Cu")
		(net "IRQ_HSC_FAULT_N")
	)
	(segment
		(start 171.70527 -134.911338)
		(end 171.70527 -133.794754)
		(width 0.10668)
		(layer "B.Cu")
		(net "IRQ_HSC_FAULT_N")
	)
	(segment
		(start 165.423342 -127.332994)
		(end 165.457124 -127.299212)
		(width 0.10668)
		(layer "B.Cu")
		(net "IRQ_HSC_FAULT_N")
	)
	(segment
		(start 172.327062 -135.53313)
		(end 171.70527 -134.911338)
		(width 0.10668)
		(layer "B.Cu")
		(net "IRQ_HSC_FAULT_N")
	)
	(segment
		(start 189.65291 -172.435266)
		(end 189.65291 -170.383454)
		(width 0.10668)
		(layer "B.Cu")
		(net "IRQ_HSC_FAULT_N")
	)
	(segment
		(start 172.327062 -152.879298)
		(end 172.327062 -135.53313)
		(width 0.10668)
		(layer "B.Cu")
		(net "IRQ_HSC_FAULT_N")
	)
	(segment
		(start 171.70527 -133.794754)
		(end 165.423342 -127.512826)
		(width 0.10668)
		(layer "B.Cu")
		(net "IRQ_HSC_FAULT_N")
	)
	(segment
		(start 165.423342 -127.512826)
		(end 165.423342 -127.332994)
		(width 0.10668)
		(layer "B.Cu")
		(net "IRQ_HSC_FAULT_N")
	)
	(segment
		(start 191.63284 -403.141942)
		(end 192.43294 -402.341842)
		(width 0.10668)
		(layer "B.Cu")
		(net "IRQ_HSC_FAULT_N")
	)
	(segment
		(start 191.26454 -403.141942)
		(end 191.63284 -403.141942)
		(width 0.10668)
		(layer "B.Cu")
		(net "IRQ_HSC_FAULT_N")
	)
	(segment
		(start 176.902618 -157.454854)
		(end 172.327062 -152.879298)
		(width 0.10668)
		(layer "B.Cu")
		(net "IRQ_HSC_FAULT_N")
	)
	(segment
		(start 176.902618 -166.688516)
		(end 176.902618 -157.454854)
		(width 0.10668)
		(layer "B.Cu")
		(net "IRQ_HSC_FAULT_N")
	)
	(segment
		(start 177.82032 -167.606218)
		(end 176.902618 -166.688516)
		(width 0.10668)
		(layer "B.Cu")
		(net "IRQ_HSC_FAULT_N")
	)
	(segment
		(start 189.65291 -170.383454)
		(end 186.875674 -167.606218)
		(width 0.10668)
		(layer "B.Cu")
		(net "IRQ_HSC_FAULT_N")
	)
	(segment
		(start 186.875674 -167.606218)
		(end 177.82032 -167.606218)
		(width 0.10668)
		(layer "B.Cu")
		(net "IRQ_HSC_FAULT_N")
	)
	(segment
		(start 195.749926 -387.134354)
		(end 196.238622 -387.62305)
		(width 0.11684)
		(layer "In6.Cu")
		(net "IRQ_HSC_FAULT_N")
	)
	(segment
		(start 229.354126 -331.42047)
		(end 217.524838 -319.591182)
		(width 0.11684)
		(layer "In6.Cu")
		(net "IRQ_HSC_FAULT_N")
	)
	(segment
		(start 217.524838 -319.591182)
		(end 217.524838 -201.281284)
		(width 0.11684)
		(layer "In6.Cu")
		(net "IRQ_HSC_FAULT_N")
	)
	(segment
		(start 196.238622 -391.183622)
		(end 191.627506 -395.794738)
		(width 0.11684)
		(layer "In6.Cu")
		(net "IRQ_HSC_FAULT_N")
	)
	(segment
		(start 192.573402 -379.660404)
		(end 193.018664 -379.215142)
		(width 0.11684)
		(layer "In6.Cu")
		(net "IRQ_HSC_FAULT_N")
	)
	(segment
		(start 193.018664 -379.215142)
		(end 194.883278 -379.215142)
		(width 0.11684)
		(layer "In6.Cu")
		(net "IRQ_HSC_FAULT_N")
	)
	(segment
		(start 222.09506 -375.609104)
		(end 229.354126 -368.350038)
		(width 0.11684)
		(layer "In6.Cu")
		(net "IRQ_HSC_FAULT_N")
	)
	(segment
		(start 194.883278 -379.215142)
		(end 198.489316 -375.609104)
		(width 0.11684)
		(layer "In6.Cu")
		(net "IRQ_HSC_FAULT_N")
	)
	(segment
		(start 209.921348 -193.677794)
		(end 209.205322 -193.677794)
		(width 0.11684)
		(layer "In6.Cu")
		(net "IRQ_HSC_FAULT_N")
	)
	(segment
		(start 217.524838 -201.281284)
		(end 209.921348 -193.677794)
		(width 0.11684)
		(layer "In6.Cu")
		(net "IRQ_HSC_FAULT_N")
	)
	(segment
		(start 196.238622 -387.62305)
		(end 196.238622 -391.183622)
		(width 0.11684)
		(layer "In6.Cu")
		(net "IRQ_HSC_FAULT_N")
	)
	(segment
		(start 209.205322 -193.677794)
		(end 208.94675 -193.936366)
		(width 0.11684)
		(layer "In6.Cu")
		(net "IRQ_HSC_FAULT_N")
	)
	(segment
		(start 191.627506 -401.536408)
		(end 192.43294 -402.341842)
		(width 0.11684)
		(layer "In6.Cu")
		(net "IRQ_HSC_FAULT_N")
	)
	(segment
		(start 198.489316 -375.609104)
		(end 222.09506 -375.609104)
		(width 0.11684)
		(layer "In6.Cu")
		(net "IRQ_HSC_FAULT_N")
	)
	(segment
		(start 229.354126 -368.350038)
		(end 229.354126 -331.42047)
		(width 0.11684)
		(layer "In6.Cu")
		(net "IRQ_HSC_FAULT_N")
	)
	(segment
		(start 191.627506 -395.794738)
		(end 191.627506 -401.536408)
		(width 0.11684)
		(layer "In6.Cu")
		(net "IRQ_HSC_FAULT_N")
	)
	(segment
		(start 192.573402 -379.660404)
		(end 195.749926 -382.836928)
		(width 0.11684)
		(layer "In6.Cu")
		(net "IRQ_HSC_FAULT_N")
	)
	(segment
		(start 195.749926 -382.836928)
		(end 195.749926 -387.134354)
		(width 0.11684)
		(layer "In6.Cu")
		(net "IRQ_HSC_FAULT_N")
	)
	(segment
		(start 169.63644 -113.9063)
		(end 169.63644 -110.673388)
		(width 0.11684)
		(layer "In11.Cu")
		(net "IRQ_HSC_FAULT_N")
	)
	(segment
		(start 170.134788 -127.299212)
		(end 171.53382 -125.90018)
		(width 0.11684)
		(layer "In11.Cu")
		(net "IRQ_HSC_FAULT_N")
	)
	(segment
		(start 165.457124 -127.299212)
		(end 170.134788 -127.299212)
		(width 0.11684)
		(layer "In11.Cu")
		(net "IRQ_HSC_FAULT_N")
	)
	(segment
		(start 171.53382 -125.90018)
		(end 171.53382 -115.80368)
		(width 0.11684)
		(layer "In11.Cu")
		(net "IRQ_HSC_FAULT_N")
	)
	(segment
		(start 169.63644 -110.673388)
		(end 169.164 -110.200948)
		(width 0.11684)
		(layer "In11.Cu")
		(net "IRQ_HSC_FAULT_N")
	)
	(segment
		(start 171.53382 -115.80368)
		(end 169.63644 -113.9063)
		(width 0.11684)
		(layer "In11.Cu")
		(net "IRQ_HSC_FAULT_N")
	)
	(segment
		(start 167.694356 -109.71149)
		(end 168.674542 -109.71149)
		(width 0.11684)
		(layer "In15.Cu")
		(net "IRQ_HSC_FAULT_N")
	)
	(segment
		(start 165.614858 -105.64622)
		(end 165.614858 -107.631992)
		(width 0.11684)
		(layer "In15.Cu")
		(net "IRQ_HSC_FAULT_N")
	)
	(segment
		(start 165.614858 -107.631992)
		(end 167.694356 -109.71149)
		(width 0.11684)
		(layer "In15.Cu")
		(net "IRQ_HSC_FAULT_N")
	)
	(segment
		(start 168.674542 -109.71149)
		(end 169.164 -110.200948)
		(width 0.11684)
		(layer "In15.Cu")
		(net "IRQ_HSC_FAULT_N")
	)
	(segment
		(start 138.147044 -13.599922)
		(end 138.15695 -13.590016)
		(width 0.10668)
		(layer "F.Cu")
		(net "IRQ0_A56")
	)
	(segment
		(start 138.15695 -13.590016)
		(end 138.15695 -11.639804)
		(width 0.10668)
		(layer "F.Cu")
		(net "IRQ0_A56")
	)
	(segment
		(start 137.404094 -10.886948)
		(end 137.089134 -10.886948)
		(width 0.10668)
		(layer "F.Cu")
		(net "IRQ0_A56")
	)
	(segment
		(start 138.15695 -11.639804)
		(end 137.404094 -10.886948)
		(width 0.10668)
		(layer "F.Cu")
		(net "IRQ0_A56")
	)
	(via
		(at 137.089134 -10.886948)
		(size 0.508)
		(drill 0.254)
		(layers "F.Cu" "B.Cu")
		(net "IRQ0_A56")
	)
	(segment
		(start 135.919718 -10.179812)
		(end 136.626854 -10.886948)
		(width 0.10668)
		(layer "B.Cu")
		(net "IRQ0_A56")
	)
	(segment
		(start 135.919718 -9.42594)
		(end 135.919718 -10.179812)
		(width 0.10668)
		(layer "B.Cu")
		(net "IRQ0_A56")
	)
	(segment
		(start 136.626854 -10.886948)
		(end 137.089134 -10.886948)
		(width 0.10668)
		(layer "B.Cu")
		(net "IRQ0_A56")
	)
	(segment
		(start 114.428016 -295.69029)
		(end 114.894614 -295.956228)
		(width 0.10668)
		(layer "F.Cu")
		(net "INT_CPU1_HP_UBM_N")
	)
	(via
		(at 98.411284 -306.701952)
		(size 0.6604)
		(drill 0.3302)
		(layers "F.Cu" "B.Cu")
		(net "INT_CPU1_HP_UBM_N")
	)
	(via
		(at 114.894614 -295.956228)
		(size 0.4064)
		(drill 0.2032)
		(layers "F.Cu" "B.Cu")
		(net "INT_CPU1_HP_UBM_N")
	)
	(segment
		(start 111.152432 -298.947332)
		(end 112.060228 -298.039536)
		(width 0.10668)
		(layer "B.Cu")
		(net "INT_CPU1_HP_UBM_N")
	)
	(segment
		(start 112.811306 -298.039536)
		(end 114.894614 -295.956228)
		(width 0.10668)
		(layer "B.Cu")
		(net "INT_CPU1_HP_UBM_N")
	)
	(segment
		(start 104.14889 -306.701952)
		(end 111.152432 -299.69841)
		(width 0.10668)
		(layer "B.Cu")
		(net "INT_CPU1_HP_UBM_N")
	)
	(segment
		(start 97.242884 -306.701952)
		(end 98.411284 -306.701952)
		(width 0.10668)
		(layer "B.Cu")
		(net "INT_CPU1_HP_UBM_N")
	)
	(segment
		(start 111.152432 -299.69841)
		(end 111.152432 -298.947332)
		(width 0.10668)
		(layer "B.Cu")
		(net "INT_CPU1_HP_UBM_N")
	)
	(segment
		(start 112.060228 -298.039536)
		(end 112.811306 -298.039536)
		(width 0.10668)
		(layer "B.Cu")
		(net "INT_CPU1_HP_UBM_N")
	)
	(segment
		(start 98.411284 -306.701952)
		(end 104.14889 -306.701952)
		(width 0.10668)
		(layer "B.Cu")
		(net "INT_CPU1_HP_UBM_N")
	)
	(segment
		(start 205.201266 -194.785234)
		(end 205.092554 -194.893946)
		(width 0.10668)
		(layer "F.Cu")
		(net "I3C_SPD_DDRL_CPU1_SCL")
	)
	(segment
		(start 206.248 -194.785234)
		(end 205.201266 -194.785234)
		(width 0.10668)
		(layer "F.Cu")
		(net "I3C_SPD_DDRL_CPU1_SCL")
	)
	(via
		(at 205.092554 -194.893946)
		(size 0.508)
		(drill 0.254)
		(layers "F.Cu" "B.Cu")
		(net "I3C_SPD_DDRL_CPU1_SCL")
	)
	(segment
		(start 205.185518 -194.98691)
		(end 205.092554 -194.893946)
		(width 0.10668)
		(layer "B.Cu")
		(net "I3C_SPD_DDRL_CPU1_SCL")
	)
	(segment
		(start 205.82128 -194.98691)
		(end 205.185518 -194.98691)
		(width 0.10668)
		(layer "B.Cu")
		(net "I3C_SPD_DDRL_CPU1_SCL")
	)
	(segment
		(start 454.188068 -194.78498)
		(end 455.343768 -194.78498)
		(width 0.10668)
		(layer "F.Cu")
		(net "I3C_SPD_DDRL_CPU0_SCL")
	)
	(via
		(at 455.343768 -194.78498)
		(size 0.508)
		(drill 0.254)
		(layers "F.Cu" "B.Cu")
		(net "I3C_SPD_DDRL_CPU0_SCL")
	)
	(segment
		(start 453.832468 -194.96151)
		(end 455.167238 -194.96151)
		(width 0.10668)
		(layer "B.Cu")
		(net "I3C_SPD_DDRL_CPU0_SCL")
	)
	(segment
		(start 455.167238 -194.96151)
		(end 455.343768 -194.78498)
		(width 0.10668)
		(layer "B.Cu")
		(net "I3C_SPD_DDRL_CPU0_SCL")
	)
	(segment
		(start 198.7042 -194.785234)
		(end 199.8599 -194.785234)
		(width 0.10668)
		(layer "F.Cu")
		(net "I3C_SPD_DDRK_CPU1_SCL")
	)
	(via
		(at 199.191118 -194.987164)
		(size 0.6604)
		(drill 0.3302)
		(layers "F.Cu" "B.Cu")
		(net "I3C_SPD_DDRK_CPU1_SCL")
	)
	(via
		(at 199.8599 -194.785234)
		(size 0.4826)
		(drill 0.254)
		(layers "F.Cu" "B.Cu")
		(net "I3C_SPD_DDRK_CPU1_SCL")
	)
	(segment
		(start 199.191118 -194.987164)
		(end 198.441564 -194.987164)
		(width 0.10668)
		(layer "B.Cu")
		(net "I3C_SPD_DDRK_CPU1_SCL")
	)
	(segment
		(start 199.8599 -194.785234)
		(end 199.65797 -194.987164)
		(width 0.10668)
		(layer "B.Cu")
		(net "I3C_SPD_DDRK_CPU1_SCL")
	)
	(segment
		(start 199.65797 -194.987164)
		(end 199.191118 -194.987164)
		(width 0.10668)
		(layer "B.Cu")
		(net "I3C_SPD_DDRK_CPU1_SCL")
	)
	(segment
		(start 198.441564 -194.987164)
		(end 198.3486 -194.8942)
		(width 0.10668)
		(layer "B.Cu")
		(net "I3C_SPD_DDRK_CPU1_SCL")
	)
	(segment
		(start 446.644268 -194.78498)
		(end 447.799968 -194.78498)
		(width 0.10668)
		(layer "F.Cu")
		(net "I3C_SPD_DDRK_CPU0_SCL")
	)
	(via
		(at 447.799968 -194.78498)
		(size 0.4826)
		(drill 0.254)
		(layers "F.Cu" "B.Cu")
		(net "I3C_SPD_DDRK_CPU0_SCL")
	)
	(via
		(at 447.102484 -194.936872)
		(size 0.6604)
		(drill 0.3302)
		(layers "F.Cu" "B.Cu")
		(net "I3C_SPD_DDRK_CPU0_SCL")
	)
	(segment
		(start 447.275204 -194.764152)
		(end 447.102484 -194.936872)
		(width 0.10668)
		(layer "B.Cu")
		(net "I3C_SPD_DDRK_CPU0_SCL")
	)
	(segment
		(start 447.061082 -194.89547)
		(end 446.288414 -194.89547)
		(width 0.10668)
		(layer "B.Cu")
		(net "I3C_SPD_DDRK_CPU0_SCL")
	)
	(segment
		(start 447.799968 -194.78498)
		(end 447.77914 -194.764152)
		(width 0.10668)
		(layer "B.Cu")
		(net "I3C_SPD_DDRK_CPU0_SCL")
	)
	(segment
		(start 447.102484 -194.936872)
		(end 447.061082 -194.89547)
		(width 0.10668)
		(layer "B.Cu")
		(net "I3C_SPD_DDRK_CPU0_SCL")
	)
	(segment
		(start 447.77914 -194.764152)
		(end 447.275204 -194.764152)
		(width 0.10668)
		(layer "B.Cu")
		(net "I3C_SPD_DDRK_CPU0_SCL")
	)
	(segment
		(start 191.160146 -194.785234)
		(end 192.315846 -194.785234)
		(width 0.10668)
		(layer "F.Cu")
		(net "I3C_SPD_DDRJ_CPU1_SCL")
	)
	(via
		(at 191.66713 -195.053204)
		(size 0.6604)
		(drill 0.3302)
		(layers "F.Cu" "B.Cu")
		(net "I3C_SPD_DDRJ_CPU1_SCL")
	)
	(via
		(at 192.315846 -194.785234)
		(size 0.4826)
		(drill 0.254)
		(layers "F.Cu" "B.Cu")
		(net "I3C_SPD_DDRJ_CPU1_SCL")
	)
	(segment
		(start 191.06261 -194.8942)
		(end 190.804546 -194.8942)
		(width 0.10668)
		(layer "B.Cu")
		(net "I3C_SPD_DDRJ_CPU1_SCL")
	)
	(segment
		(start 192.315846 -194.785234)
		(end 192.047876 -195.053204)
		(width 0.10668)
		(layer "B.Cu")
		(net "I3C_SPD_DDRJ_CPU1_SCL")
	)
	(segment
		(start 192.047876 -195.053204)
		(end 191.66713 -195.053204)
		(width 0.10668)
		(layer "B.Cu")
		(net "I3C_SPD_DDRJ_CPU1_SCL")
	)
	(segment
		(start 191.221614 -195.053204)
		(end 191.06261 -194.8942)
		(width 0.10668)
		(layer "B.Cu")
		(net "I3C_SPD_DDRJ_CPU1_SCL")
	)
	(segment
		(start 191.66713 -195.053204)
		(end 191.221614 -195.053204)
		(width 0.10668)
		(layer "B.Cu")
		(net "I3C_SPD_DDRJ_CPU1_SCL")
	)
	(segment
		(start 439.100214 -194.78498)
		(end 440.366658 -194.78498)
		(width 0.10668)
		(layer "F.Cu")
		(net "I3C_SPD_DDRJ_CPU0_SCL")
	)
	(via
		(at 440.366658 -194.78498)
		(size 0.4826)
		(drill 0.254)
		(layers "F.Cu" "B.Cu")
		(net "I3C_SPD_DDRJ_CPU0_SCL")
	)
	(via
		(at 439.651648 -194.812158)
		(size 0.6604)
		(drill 0.3302)
		(layers "F.Cu" "B.Cu")
		(net "I3C_SPD_DDRJ_CPU0_SCL")
	)
	(segment
		(start 439.754518 -194.78498)
		(end 439.72734 -194.812158)
		(width 0.10668)
		(layer "B.Cu")
		(net "I3C_SPD_DDRJ_CPU0_SCL")
	)
	(segment
		(start 439.176414 -194.893946)
		(end 438.744614 -194.893946)
		(width 0.10668)
		(layer "B.Cu")
		(net "I3C_SPD_DDRJ_CPU0_SCL")
	)
	(segment
		(start 439.651648 -194.812158)
		(end 439.258202 -194.812158)
		(width 0.10668)
		(layer "B.Cu")
		(net "I3C_SPD_DDRJ_CPU0_SCL")
	)
	(segment
		(start 439.72734 -194.812158)
		(end 439.651648 -194.812158)
		(width 0.10668)
		(layer "B.Cu")
		(net "I3C_SPD_DDRJ_CPU0_SCL")
	)
	(segment
		(start 439.258202 -194.812158)
		(end 439.176414 -194.893946)
		(width 0.10668)
		(layer "B.Cu")
		(net "I3C_SPD_DDRJ_CPU0_SCL")
	)
	(segment
		(start 440.366658 -194.78498)
		(end 439.754518 -194.78498)
		(width 0.10668)
		(layer "B.Cu")
		(net "I3C_SPD_DDRJ_CPU0_SCL")
	)
	(segment
		(start 183.616092 -194.785234)
		(end 184.771792 -194.785234)
		(width 0.10668)
		(layer "F.Cu")
		(net "I3C_SPD_DDRI_CPU1_SCL")
	)
	(via
		(at 184.771792 -194.785234)
		(size 0.508)
		(drill 0.254)
		(layers "F.Cu" "B.Cu")
		(net "I3C_SPD_DDRI_CPU1_SCL")
	)
	(segment
		(start 184.569862 -194.987164)
		(end 183.35371 -194.987164)
		(width 0.10668)
		(layer "B.Cu")
		(net "I3C_SPD_DDRI_CPU1_SCL")
	)
	(segment
		(start 183.35371 -194.987164)
		(end 183.260746 -194.8942)
		(width 0.10668)
		(layer "B.Cu")
		(net "I3C_SPD_DDRI_CPU1_SCL")
	)
	(segment
		(start 184.771792 -194.785234)
		(end 184.569862 -194.987164)
		(width 0.10668)
		(layer "B.Cu")
		(net "I3C_SPD_DDRI_CPU1_SCL")
	)
	(segment
		(start 431.55616 -194.78498)
		(end 432.71186 -194.78498)
		(width 0.10668)
		(layer "F.Cu")
		(net "I3C_SPD_DDRI_CPU0_SCL")
	)
	(via
		(at 432.71186 -194.78498)
		(size 0.4826)
		(drill 0.254)
		(layers "F.Cu" "B.Cu")
		(net "I3C_SPD_DDRI_CPU0_SCL")
	)
	(via
		(at 432.020472 -194.588892)
		(size 0.6604)
		(drill 0.3302)
		(layers "F.Cu" "B.Cu")
		(net "I3C_SPD_DDRI_CPU0_SCL")
	)
	(segment
		(start 431.2285 -194.85737)
		(end 431.20056 -194.88531)
		(width 0.10668)
		(layer "B.Cu")
		(net "I3C_SPD_DDRI_CPU0_SCL")
	)
	(segment
		(start 432.020472 -194.588892)
		(end 431.751994 -194.85737)
		(width 0.10668)
		(layer "B.Cu")
		(net "I3C_SPD_DDRI_CPU0_SCL")
	)
	(segment
		(start 431.751994 -194.85737)
		(end 431.2285 -194.85737)
		(width 0.10668)
		(layer "B.Cu")
		(net "I3C_SPD_DDRI_CPU0_SCL")
	)
	(segment
		(start 432.515772 -194.588892)
		(end 432.020472 -194.588892)
		(width 0.10668)
		(layer "B.Cu")
		(net "I3C_SPD_DDRI_CPU0_SCL")
	)
	(segment
		(start 432.71186 -194.78498)
		(end 432.515772 -194.588892)
		(width 0.10668)
		(layer "B.Cu")
		(net "I3C_SPD_DDRI_CPU0_SCL")
	)
	(segment
		(start 176.072038 -194.785234)
		(end 177.227738 -194.785234)
		(width 0.10668)
		(layer "F.Cu")
		(net "I3C_SPD_DDRH_CPU1_SCL")
	)
	(via
		(at 177.227738 -194.785234)
		(size 0.4826)
		(drill 0.254)
		(layers "F.Cu" "B.Cu")
		(net "I3C_SPD_DDRH_CPU1_SCL")
	)
	(via
		(at 176.593246 -195.105528)
		(size 0.6604)
		(drill 0.3302)
		(layers "F.Cu" "B.Cu")
		(net "I3C_SPD_DDRH_CPU1_SCL")
	)
	(segment
		(start 175.809656 -194.987164)
		(end 175.716692 -194.8942)
		(width 0.10668)
		(layer "B.Cu")
		(net "I3C_SPD_DDRH_CPU1_SCL")
	)
	(segment
		(start 177.227738 -194.785234)
		(end 176.907444 -195.105528)
		(width 0.10668)
		(layer "B.Cu")
		(net "I3C_SPD_DDRH_CPU1_SCL")
	)
	(segment
		(start 176.474882 -194.987164)
		(end 175.809656 -194.987164)
		(width 0.10668)
		(layer "B.Cu")
		(net "I3C_SPD_DDRH_CPU1_SCL")
	)
	(segment
		(start 176.593246 -195.105528)
		(end 176.474882 -194.987164)
		(width 0.10668)
		(layer "B.Cu")
		(net "I3C_SPD_DDRH_CPU1_SCL")
	)
	(segment
		(start 176.907444 -195.105528)
		(end 176.593246 -195.105528)
		(width 0.10668)
		(layer "B.Cu")
		(net "I3C_SPD_DDRH_CPU1_SCL")
	)
	(segment
		(start 424.012106 -194.78498)
		(end 425.167806 -194.78498)
		(width 0.10668)
		(layer "F.Cu")
		(net "I3C_SPD_DDRH_CPU0_SCL")
	)
	(via
		(at 425.167806 -194.78498)
		(size 0.508)
		(drill 0.254)
		(layers "F.Cu" "B.Cu")
		(net "I3C_SPD_DDRH_CPU0_SCL")
	)
	(segment
		(start 425.167806 -194.78498)
		(end 424.491912 -194.78498)
		(width 0.10668)
		(layer "B.Cu")
		(net "I3C_SPD_DDRH_CPU0_SCL")
	)
	(segment
		(start 424.491912 -194.78498)
		(end 424.391582 -194.88531)
		(width 0.10668)
		(layer "B.Cu")
		(net "I3C_SPD_DDRH_CPU0_SCL")
	)
	(segment
		(start 424.391582 -194.88531)
		(end 423.656506 -194.88531)
		(width 0.10668)
		(layer "B.Cu")
		(net "I3C_SPD_DDRH_CPU0_SCL")
	)
	(segment
		(start 168.527984 -194.785234)
		(end 169.683684 -194.785234)
		(width 0.10668)
		(layer "F.Cu")
		(net "I3C_SPD_DDRG_CPU1_SCL")
	)
	(via
		(at 169.015918 -195.09486)
		(size 0.6604)
		(drill 0.3302)
		(layers "F.Cu" "B.Cu")
		(net "I3C_SPD_DDRG_CPU1_SCL")
	)
	(via
		(at 169.683684 -194.785234)
		(size 0.4826)
		(drill 0.254)
		(layers "F.Cu" "B.Cu")
		(net "I3C_SPD_DDRG_CPU1_SCL")
	)
	(segment
		(start 169.015918 -195.09486)
		(end 168.908222 -194.987164)
		(width 0.10668)
		(layer "B.Cu")
		(net "I3C_SPD_DDRG_CPU1_SCL")
	)
	(segment
		(start 168.265602 -194.987164)
		(end 168.172638 -194.8942)
		(width 0.10668)
		(layer "B.Cu")
		(net "I3C_SPD_DDRG_CPU1_SCL")
	)
	(segment
		(start 169.683684 -194.785234)
		(end 169.374058 -195.09486)
		(width 0.10668)
		(layer "B.Cu")
		(net "I3C_SPD_DDRG_CPU1_SCL")
	)
	(segment
		(start 169.374058 -195.09486)
		(end 169.015918 -195.09486)
		(width 0.10668)
		(layer "B.Cu")
		(net "I3C_SPD_DDRG_CPU1_SCL")
	)
	(segment
		(start 168.908222 -194.987164)
		(end 168.265602 -194.987164)
		(width 0.10668)
		(layer "B.Cu")
		(net "I3C_SPD_DDRG_CPU1_SCL")
	)
	(segment
		(start 416.468052 -194.78498)
		(end 417.623752 -194.78498)
		(width 0.10668)
		(layer "F.Cu")
		(net "I3C_SPD_DDRG_CPU0_SCL")
	)
	(via
		(at 417.623752 -194.78498)
		(size 0.508)
		(drill 0.254)
		(layers "F.Cu" "B.Cu")
		(net "I3C_SPD_DDRG_CPU0_SCL")
	)
	(segment
		(start 416.865562 -194.87007)
		(end 416.127692 -194.87007)
		(width 0.10668)
		(layer "B.Cu")
		(net "I3C_SPD_DDRG_CPU0_SCL")
	)
	(segment
		(start 416.950652 -194.78498)
		(end 416.865562 -194.87007)
		(width 0.10668)
		(layer "B.Cu")
		(net "I3C_SPD_DDRG_CPU0_SCL")
	)
	(segment
		(start 417.623752 -194.78498)
		(end 416.950652 -194.78498)
		(width 0.10668)
		(layer "B.Cu")
		(net "I3C_SPD_DDRG_CPU0_SCL")
	)
	(segment
		(start 416.127692 -194.87007)
		(end 416.112452 -194.88531)
		(width 0.10668)
		(layer "B.Cu")
		(net "I3C_SPD_DDRG_CPU0_SCL")
	)
	(segment
		(start 213.824566 -187.574936)
		(end 213.824566 -200.421748)
		(width 0.10668)
		(layer "F.Cu")
		(net "I3C_SPD_DDRGL_CPU1_SDA")
	)
	(segment
		(start 187.313062 -165.397942)
		(end 187.889134 -165.974014)
		(width 0.10668)
		(layer "F.Cu")
		(net "I3C_SPD_DDRGL_CPU1_SDA")
	)
	(segment
		(start 188.323982 -165.689788)
		(end 188.323982 -165.538912)
		(width 0.10668)
		(layer "F.Cu")
		(net "I3C_SPD_DDRGL_CPU1_SDA")
	)
	(segment
		(start 187.454286 -166.559484)
		(end 187.454286 -166.408608)
		(width 0.10668)
		(layer "F.Cu")
		(net "I3C_SPD_DDRGL_CPU1_SDA")
	)
	(segment
		(start 207.4037 -203.225146)
		(end 207.4037 -195.635372)
		(width 0.10668)
		(layer "F.Cu")
		(net "I3C_SPD_DDRGL_CPU1_SDA")
	)
	(segment
		(start 185.850276 -168.163494)
		(end 187.454286 -166.559484)
		(width 0.10668)
		(layer "F.Cu")
		(net "I3C_SPD_DDRGL_CPU1_SDA")
	)
	(segment
		(start 187.74791 -164.96284)
		(end 187.747656 -164.812472)
		(width 0.10668)
		(layer "F.Cu")
		(net "I3C_SPD_DDRGL_CPU1_SDA")
	)
	(segment
		(start 188.323982 -165.538912)
		(end 187.74791 -164.96284)
		(width 0.10668)
		(layer "F.Cu")
		(net "I3C_SPD_DDRGL_CPU1_SDA")
	)
	(segment
		(start 185.295794 -168.717976)
		(end 185.850276 -168.163494)
		(width 0.10668)
		(layer "F.Cu")
		(net "I3C_SPD_DDRGL_CPU1_SDA")
	)
	(segment
		(start 186.87796 -165.682168)
		(end 187.162186 -165.397942)
		(width 0.10668)
		(layer "F.Cu")
		(net "I3C_SPD_DDRGL_CPU1_SDA")
	)
	(segment
		(start 208.670906 -204.492352)
		(end 207.4037 -203.225146)
		(width 0.10668)
		(layer "F.Cu")
		(net "I3C_SPD_DDRGL_CPU1_SDA")
	)
	(segment
		(start 188.75883 -165.104318)
		(end 188.909706 -165.104064)
		(width 0.10668)
		(layer "F.Cu")
		(net "I3C_SPD_DDRGL_CPU1_SDA")
	)
	(segment
		(start 187.454286 -166.408608)
		(end 186.878214 -165.832536)
		(width 0.10668)
		(layer "F.Cu")
		(net "I3C_SPD_DDRGL_CPU1_SDA")
	)
	(segment
		(start 196.133974 -167.921178)
		(end 197.05955 -167.921178)
		(width 0.10668)
		(layer "F.Cu")
		(net "I3C_SPD_DDRGL_CPU1_SDA")
	)
	(segment
		(start 213.824566 -200.421748)
		(end 209.753962 -204.492352)
		(width 0.10668)
		(layer "F.Cu")
		(net "I3C_SPD_DDRGL_CPU1_SDA")
	)
	(segment
		(start 209.753962 -204.492352)
		(end 208.670906 -204.492352)
		(width 0.10668)
		(layer "F.Cu")
		(net "I3C_SPD_DDRGL_CPU1_SDA")
	)
	(segment
		(start 188.909706 -165.104064)
		(end 189.821312 -164.192458)
		(width 0.10668)
		(layer "F.Cu")
		(net "I3C_SPD_DDRGL_CPU1_SDA")
	)
	(segment
		(start 188.04001 -165.97376)
		(end 188.323982 -165.689788)
		(width 0.10668)
		(layer "F.Cu")
		(net "I3C_SPD_DDRGL_CPU1_SDA")
	)
	(segment
		(start 197.05955 -167.921178)
		(end 211.781898 -182.643526)
		(width 0.10668)
		(layer "F.Cu")
		(net "I3C_SPD_DDRGL_CPU1_SDA")
	)
	(segment
		(start 188.182758 -164.528246)
		(end 188.75883 -165.104318)
		(width 0.10668)
		(layer "F.Cu")
		(net "I3C_SPD_DDRGL_CPU1_SDA")
	)
	(segment
		(start 187.889134 -165.974014)
		(end 188.04001 -165.97376)
		(width 0.10668)
		(layer "F.Cu")
		(net "I3C_SPD_DDRGL_CPU1_SDA")
	)
	(segment
		(start 187.162186 -165.397942)
		(end 187.313062 -165.397942)
		(width 0.10668)
		(layer "F.Cu")
		(net "I3C_SPD_DDRGL_CPU1_SDA")
	)
	(segment
		(start 192.405254 -164.192458)
		(end 196.133974 -167.921178)
		(width 0.10668)
		(layer "F.Cu")
		(net "I3C_SPD_DDRGL_CPU1_SDA")
	)
	(segment
		(start 186.878214 -165.832536)
		(end 186.87796 -165.682168)
		(width 0.10668)
		(layer "F.Cu")
		(net "I3C_SPD_DDRGL_CPU1_SDA")
	)
	(segment
		(start 189.821312 -164.192458)
		(end 192.405254 -164.192458)
		(width 0.10668)
		(layer "F.Cu")
		(net "I3C_SPD_DDRGL_CPU1_SDA")
	)
	(segment
		(start 187.747656 -164.812472)
		(end 188.031882 -164.528246)
		(width 0.10668)
		(layer "F.Cu")
		(net "I3C_SPD_DDRGL_CPU1_SDA")
	)
	(segment
		(start 188.031882 -164.528246)
		(end 188.182758 -164.528246)
		(width 0.10668)
		(layer "F.Cu")
		(net "I3C_SPD_DDRGL_CPU1_SDA")
	)
	(segment
		(start 211.781898 -182.643526)
		(end 213.824566 -187.574936)
		(width 0.10668)
		(layer "F.Cu")
		(net "I3C_SPD_DDRGL_CPU1_SDA")
	)
	(segment
		(start 184.455054 -168.717976)
		(end 185.295794 -168.717976)
		(width 0.10668)
		(layer "F.Cu")
		(net "I3C_SPD_DDRGL_CPU1_SDA")
	)
	(via
		(at 174.916592 -195.8594)
		(size 0.508)
		(drill 0.254)
		(layers "F.Cu" "B.Cu")
		(net "I3C_SPD_DDRGL_CPU1_SDA")
	)
	(via
		(at 197.5485 -195.8594)
		(size 0.508)
		(drill 0.254)
		(layers "F.Cu" "B.Cu")
		(net "I3C_SPD_DDRGL_CPU1_SDA")
	)
	(via
		(at 185.850276 -168.163494)
		(size 0.762)
		(drill 0.381)
		(layers "F.Cu" "B.Cu")
		(net "I3C_SPD_DDRGL_CPU1_SDA")
	)
	(via
		(at 207.4037 -195.635372)
		(size 0.4826)
		(drill 0.254)
		(layers "F.Cu" "B.Cu")
		(net "I3C_SPD_DDRGL_CPU1_SDA")
	)
	(via
		(at 190.004446 -195.8594)
		(size 0.508)
		(drill 0.254)
		(layers "F.Cu" "B.Cu")
		(net "I3C_SPD_DDRGL_CPU1_SDA")
	)
	(via
		(at 182.460646 -195.8594)
		(size 0.508)
		(drill 0.254)
		(layers "F.Cu" "B.Cu")
		(net "I3C_SPD_DDRGL_CPU1_SDA")
	)
	(via
		(at 167.372538 -195.8594)
		(size 0.508)
		(drill 0.254)
		(layers "F.Cu" "B.Cu")
		(net "I3C_SPD_DDRGL_CPU1_SDA")
	)
	(segment
		(start 207.086962 -195.95211)
		(end 207.4037 -195.635372)
		(width 0.10668)
		(layer "B.Cu")
		(net "I3C_SPD_DDRGL_CPU1_SDA")
	)
	(segment
		(start 206.62138 -195.95211)
		(end 207.086962 -195.95211)
		(width 0.10668)
		(layer "B.Cu")
		(net "I3C_SPD_DDRGL_CPU1_SDA")
	)
	(segment
		(start 190.004446 -195.8594)
		(end 189.770004 -195.624958)
		(width 0.11684)
		(layer "In2.Cu")
		(net "I3C_SPD_DDRGL_CPU1_SDA")
	)
	(segment
		(start 183.571642 -195.8594)
		(end 182.460646 -195.8594)
		(width 0.11684)
		(layer "In2.Cu")
		(net "I3C_SPD_DDRGL_CPU1_SDA")
	)
	(segment
		(start 191.852042 -195.209922)
		(end 191.202564 -195.8594)
		(width 0.11684)
		(layer "In2.Cu")
		(net "I3C_SPD_DDRGL_CPU1_SDA")
	)
	(segment
		(start 200.199752 -195.212716)
		(end 199.443086 -195.212716)
		(width 0.11684)
		(layer "In2.Cu")
		(net "I3C_SPD_DDRGL_CPU1_SDA")
	)
	(segment
		(start 174.916592 -195.8594)
		(end 174.550832 -195.49364)
		(width 0.11684)
		(layer "In2.Cu")
		(net "I3C_SPD_DDRGL_CPU1_SDA")
	)
	(segment
		(start 194.818762 -195.466208)
		(end 194.562476 -195.209922)
		(width 0.11684)
		(layer "In2.Cu")
		(net "I3C_SPD_DDRGL_CPU1_SDA")
	)
	(segment
		(start 175.910748 -195.8594)
		(end 176.548034 -195.222114)
		(width 0.11684)
		(layer "In2.Cu")
		(net "I3C_SPD_DDRGL_CPU1_SDA")
	)
	(segment
		(start 199.443086 -195.212716)
		(end 198.796402 -195.8594)
		(width 0.11684)
		(layer "In2.Cu")
		(net "I3C_SPD_DDRGL_CPU1_SDA")
	)
	(segment
		(start 191.202564 -195.8594)
		(end 190.004446 -195.8594)
		(width 0.11684)
		(layer "In2.Cu")
		(net "I3C_SPD_DDRGL_CPU1_SDA")
	)
	(segment
		(start 170.59275 -195.49364)
		(end 170.29684 -195.19773)
		(width 0.11684)
		(layer "In2.Cu")
		(net "I3C_SPD_DDRGL_CPU1_SDA")
	)
	(segment
		(start 198.796402 -195.8594)
		(end 197.5485 -195.8594)
		(width 0.11684)
		(layer "In2.Cu")
		(net "I3C_SPD_DDRGL_CPU1_SDA")
	)
	(segment
		(start 182.250588 -195.649342)
		(end 182.460646 -195.8594)
		(width 0.11684)
		(layer "In2.Cu")
		(net "I3C_SPD_DDRGL_CPU1_SDA")
	)
	(segment
		(start 200.373996 -195.38696)
		(end 200.199752 -195.212716)
		(width 0.11684)
		(layer "In2.Cu")
		(net "I3C_SPD_DDRGL_CPU1_SDA")
	)
	(segment
		(start 176.548034 -195.222114)
		(end 179.887118 -195.222114)
		(width 0.11684)
		(layer "In2.Cu")
		(net "I3C_SPD_DDRGL_CPU1_SDA")
	)
	(segment
		(start 197.155308 -195.466208)
		(end 194.818762 -195.466208)
		(width 0.11684)
		(layer "In2.Cu")
		(net "I3C_SPD_DDRGL_CPU1_SDA")
	)
	(segment
		(start 168.537636 -195.19773)
		(end 167.875966 -195.8594)
		(width 0.11684)
		(layer "In2.Cu")
		(net "I3C_SPD_DDRGL_CPU1_SDA")
	)
	(segment
		(start 167.875966 -195.8594)
		(end 167.372538 -195.8594)
		(width 0.11684)
		(layer "In2.Cu")
		(net "I3C_SPD_DDRGL_CPU1_SDA")
	)
	(segment
		(start 207.4037 -195.635372)
		(end 207.155288 -195.38696)
		(width 0.11684)
		(layer "In2.Cu")
		(net "I3C_SPD_DDRGL_CPU1_SDA")
	)
	(segment
		(start 179.887118 -195.222114)
		(end 180.314346 -195.649342)
		(width 0.11684)
		(layer "In2.Cu")
		(net "I3C_SPD_DDRGL_CPU1_SDA")
	)
	(segment
		(start 197.5485 -195.8594)
		(end 197.155308 -195.466208)
		(width 0.11684)
		(layer "In2.Cu")
		(net "I3C_SPD_DDRGL_CPU1_SDA")
	)
	(segment
		(start 174.550832 -195.49364)
		(end 170.59275 -195.49364)
		(width 0.11684)
		(layer "In2.Cu")
		(net "I3C_SPD_DDRGL_CPU1_SDA")
	)
	(segment
		(start 185.316622 -195.203826)
		(end 184.227216 -195.203826)
		(width 0.11684)
		(layer "In2.Cu")
		(net "I3C_SPD_DDRGL_CPU1_SDA")
	)
	(segment
		(start 180.314346 -195.649342)
		(end 182.250588 -195.649342)
		(width 0.11684)
		(layer "In2.Cu")
		(net "I3C_SPD_DDRGL_CPU1_SDA")
	)
	(segment
		(start 170.29684 -195.19773)
		(end 168.537636 -195.19773)
		(width 0.11684)
		(layer "In2.Cu")
		(net "I3C_SPD_DDRGL_CPU1_SDA")
	)
	(segment
		(start 194.562476 -195.209922)
		(end 191.852042 -195.209922)
		(width 0.11684)
		(layer "In2.Cu")
		(net "I3C_SPD_DDRGL_CPU1_SDA")
	)
	(segment
		(start 207.155288 -195.38696)
		(end 200.373996 -195.38696)
		(width 0.11684)
		(layer "In2.Cu")
		(net "I3C_SPD_DDRGL_CPU1_SDA")
	)
	(segment
		(start 189.770004 -195.624958)
		(end 185.737754 -195.624958)
		(width 0.11684)
		(layer "In2.Cu")
		(net "I3C_SPD_DDRGL_CPU1_SDA")
	)
	(segment
		(start 184.227216 -195.203826)
		(end 183.571642 -195.8594)
		(width 0.11684)
		(layer "In2.Cu")
		(net "I3C_SPD_DDRGL_CPU1_SDA")
	)
	(segment
		(start 185.737754 -195.624958)
		(end 185.316622 -195.203826)
		(width 0.11684)
		(layer "In2.Cu")
		(net "I3C_SPD_DDRGL_CPU1_SDA")
	)
	(segment
		(start 174.916592 -195.8594)
		(end 175.910748 -195.8594)
		(width 0.11684)
		(layer "In2.Cu")
		(net "I3C_SPD_DDRGL_CPU1_SDA")
	)
	(segment
		(start 214.363046 -187.466478)
		(end 214.363046 -200.645268)
		(width 0.10668)
		(layer "F.Cu")
		(net "I3C_SPD_DDRGL_CPU1_SCL")
	)
	(segment
		(start 196.387212 -167.36314)
		(end 197.275196 -167.36314)
		(width 0.10668)
		(layer "F.Cu")
		(net "I3C_SPD_DDRGL_CPU1_SCL")
	)
	(segment
		(start 192.655444 -163.631372)
		(end 196.387212 -167.36314)
		(width 0.10668)
		(layer "F.Cu")
		(net "I3C_SPD_DDRGL_CPU1_SCL")
	)
	(segment
		(start 209.926428 -205.081886)
		(end 208.92897 -205.081886)
		(width 0.10668)
		(layer "F.Cu")
		(net "I3C_SPD_DDRGL_CPU1_SCL")
	)
	(segment
		(start 197.275196 -167.36314)
		(end 212.230462 -182.318406)
		(width 0.10668)
		(layer "F.Cu")
		(net "I3C_SPD_DDRGL_CPU1_SCL")
	)
	(segment
		(start 181.388766 -168.717468)
		(end 180.89118 -168.717468)
		(width 0.10668)
		(layer "F.Cu")
		(net "I3C_SPD_DDRGL_CPU1_SCL")
	)
	(segment
		(start 212.230462 -182.318406)
		(end 214.363046 -187.466478)
		(width 0.10668)
		(layer "F.Cu")
		(net "I3C_SPD_DDRGL_CPU1_SCL")
	)
	(segment
		(start 214.363046 -200.645268)
		(end 209.926428 -205.081886)
		(width 0.10668)
		(layer "F.Cu")
		(net "I3C_SPD_DDRGL_CPU1_SCL")
	)
	(segment
		(start 180.89118 -168.717468)
		(end 180.66893 -168.939718)
		(width 0.10668)
		(layer "F.Cu")
		(net "I3C_SPD_DDRGL_CPU1_SCL")
	)
	(segment
		(start 185.61558 -163.631372)
		(end 192.655444 -163.631372)
		(width 0.10668)
		(layer "F.Cu")
		(net "I3C_SPD_DDRGL_CPU1_SCL")
	)
	(via
		(at 190.004446 -194.8942)
		(size 0.508)
		(drill 0.254)
		(layers "F.Cu" "B.Cu")
		(net "I3C_SPD_DDRGL_CPU1_SCL")
	)
	(via
		(at 174.916592 -194.8942)
		(size 0.508)
		(drill 0.254)
		(layers "F.Cu" "B.Cu")
		(net "I3C_SPD_DDRGL_CPU1_SCL")
	)
	(via
		(at 185.61558 -163.631372)
		(size 0.508)
		(drill 0.254)
		(layers "F.Cu" "B.Cu")
		(net "I3C_SPD_DDRGL_CPU1_SCL")
	)
	(via
		(at 180.66893 -168.939718)
		(size 0.508)
		(drill 0.254)
		(layers "F.Cu" "B.Cu")
		(net "I3C_SPD_DDRGL_CPU1_SCL")
	)
	(via
		(at 167.372538 -194.8942)
		(size 0.508)
		(drill 0.254)
		(layers "F.Cu" "B.Cu")
		(net "I3C_SPD_DDRGL_CPU1_SCL")
	)
	(via
		(at 197.5485 -194.8942)
		(size 0.508)
		(drill 0.254)
		(layers "F.Cu" "B.Cu")
		(net "I3C_SPD_DDRGL_CPU1_SCL")
	)
	(via
		(at 182.460646 -194.8942)
		(size 0.508)
		(drill 0.254)
		(layers "F.Cu" "B.Cu")
		(net "I3C_SPD_DDRGL_CPU1_SCL")
	)
	(via
		(at 207.4037 -194.785234)
		(size 0.508)
		(drill 0.254)
		(layers "F.Cu" "B.Cu")
		(net "I3C_SPD_DDRGL_CPU1_SCL")
	)
	(via
		(at 208.92897 -205.081886)
		(size 0.508)
		(drill 0.254)
		(layers "F.Cu" "B.Cu")
		(net "I3C_SPD_DDRGL_CPU1_SCL")
	)
	(segment
		(start 208.26984 -204.422756)
		(end 208.92897 -205.081886)
		(width 0.10668)
		(layer "B.Cu")
		(net "I3C_SPD_DDRGL_CPU1_SCL")
	)
	(segment
		(start 207.4037 -194.785234)
		(end 208.26984 -195.651374)
		(width 0.10668)
		(layer "B.Cu")
		(net "I3C_SPD_DDRGL_CPU1_SCL")
	)
	(segment
		(start 206.62138 -194.98691)
		(end 207.202024 -194.98691)
		(width 0.10668)
		(layer "B.Cu")
		(net "I3C_SPD_DDRGL_CPU1_SCL")
	)
	(segment
		(start 207.202024 -194.98691)
		(end 207.4037 -194.785234)
		(width 0.10668)
		(layer "B.Cu")
		(net "I3C_SPD_DDRGL_CPU1_SCL")
	)
	(segment
		(start 208.26984 -195.651374)
		(end 208.26984 -204.422756)
		(width 0.10668)
		(layer "B.Cu")
		(net "I3C_SPD_DDRGL_CPU1_SCL")
	)
	(segment
		(start 180.973222 -168.635426)
		(end 180.66893 -168.939718)
		(width 0.11684)
		(layer "In2.Cu")
		(net "I3C_SPD_DDRGL_CPU1_SCL")
	)
	(segment
		(start 172.120306 -194.461892)
		(end 173.872906 -194.461892)
		(width 0.11684)
		(layer "In2.Cu")
		(net "I3C_SPD_DDRGL_CPU1_SCL")
	)
	(segment
		(start 187.216542 -194.474592)
		(end 188.99124 -194.474592)
		(width 0.11684)
		(layer "In2.Cu")
		(net "I3C_SPD_DDRGL_CPU1_SCL")
	)
	(segment
		(start 182.460646 -194.8942)
		(end 182.470552 -194.898264)
		(width 0.11684)
		(layer "In2.Cu")
		(net "I3C_SPD_DDRGL_CPU1_SCL")
	)
	(segment
		(start 185.61558 -163.631372)
		(end 185.61558 -166.345108)
		(width 0.11684)
		(layer "In2.Cu")
		(net "I3C_SPD_DDRGL_CPU1_SCL")
	)
	(segment
		(start 194.809872 -194.474592)
		(end 194.492118 -194.34302)
		(width 0.11684)
		(layer "In2.Cu")
		(net "I3C_SPD_DDRGL_CPU1_SCL")
	)
	(segment
		(start 173.872906 -194.461892)
		(end 174.916592 -194.8942)
		(width 0.11684)
		(layer "In2.Cu")
		(net "I3C_SPD_DDRGL_CPU1_SCL")
	)
	(segment
		(start 185.61558 -166.345108)
		(end 183.325262 -168.635426)
		(width 0.11684)
		(layer "In2.Cu")
		(net "I3C_SPD_DDRGL_CPU1_SCL")
	)
	(segment
		(start 171.833286 -194.34302)
		(end 172.120306 -194.461892)
		(width 0.11684)
		(layer "In2.Cu")
		(net "I3C_SPD_DDRGL_CPU1_SCL")
	)
	(segment
		(start 207.4037 -194.785234)
		(end 207.098138 -194.479672)
		(width 0.11684)
		(layer "In2.Cu")
		(net "I3C_SPD_DDRGL_CPU1_SCL")
	)
	(segment
		(start 196.53504 -194.474592)
		(end 194.809872 -194.474592)
		(width 0.11684)
		(layer "In2.Cu")
		(net "I3C_SPD_DDRGL_CPU1_SCL")
	)
	(segment
		(start 168.703244 -194.34302)
		(end 171.833286 -194.34302)
		(width 0.11684)
		(layer "In2.Cu")
		(net "I3C_SPD_DDRGL_CPU1_SCL")
	)
	(segment
		(start 186.898788 -194.34302)
		(end 187.216542 -194.474592)
		(width 0.11684)
		(layer "In2.Cu")
		(net "I3C_SPD_DDRGL_CPU1_SCL")
	)
	(segment
		(start 201.942192 -194.34048)
		(end 198.88581 -194.34048)
		(width 0.11684)
		(layer "In2.Cu")
		(net "I3C_SPD_DDRGL_CPU1_SCL")
	)
	(segment
		(start 181.441344 -194.472052)
		(end 182.460646 -194.8942)
		(width 0.11684)
		(layer "In2.Cu")
		(net "I3C_SPD_DDRGL_CPU1_SCL")
	)
	(segment
		(start 182.470552 -194.898264)
		(end 183.811164 -194.34302)
		(width 0.11684)
		(layer "In2.Cu")
		(net "I3C_SPD_DDRGL_CPU1_SCL")
	)
	(segment
		(start 207.098138 -194.479672)
		(end 202.278488 -194.479672)
		(width 0.11684)
		(layer "In2.Cu")
		(net "I3C_SPD_DDRGL_CPU1_SCL")
	)
	(segment
		(start 202.278488 -194.479672)
		(end 201.942192 -194.34048)
		(width 0.11684)
		(layer "In2.Cu")
		(net "I3C_SPD_DDRGL_CPU1_SCL")
	)
	(segment
		(start 194.492118 -194.34302)
		(end 191.335152 -194.34302)
		(width 0.11684)
		(layer "In2.Cu")
		(net "I3C_SPD_DDRGL_CPU1_SCL")
	)
	(segment
		(start 197.5485 -194.8942)
		(end 196.53504 -194.474592)
		(width 0.11684)
		(layer "In2.Cu")
		(net "I3C_SPD_DDRGL_CPU1_SCL")
	)
	(segment
		(start 174.916592 -194.8942)
		(end 175.467772 -194.34302)
		(width 0.11684)
		(layer "In2.Cu")
		(net "I3C_SPD_DDRGL_CPU1_SCL")
	)
	(segment
		(start 183.325262 -168.635426)
		(end 180.973222 -168.635426)
		(width 0.11684)
		(layer "In2.Cu")
		(net "I3C_SPD_DDRGL_CPU1_SCL")
	)
	(segment
		(start 175.467772 -194.34302)
		(end 179.004976 -194.34302)
		(width 0.11684)
		(layer "In2.Cu")
		(net "I3C_SPD_DDRGL_CPU1_SCL")
	)
	(segment
		(start 183.811164 -194.34302)
		(end 186.898788 -194.34302)
		(width 0.11684)
		(layer "In2.Cu")
		(net "I3C_SPD_DDRGL_CPU1_SCL")
	)
	(segment
		(start 188.99124 -194.474592)
		(end 190.004446 -194.8942)
		(width 0.11684)
		(layer "In2.Cu")
		(net "I3C_SPD_DDRGL_CPU1_SCL")
	)
	(segment
		(start 167.372538 -194.8942)
		(end 168.703244 -194.34302)
		(width 0.11684)
		(layer "In2.Cu")
		(net "I3C_SPD_DDRGL_CPU1_SCL")
	)
	(segment
		(start 198.88581 -194.34048)
		(end 197.5485 -194.8942)
		(width 0.11684)
		(layer "In2.Cu")
		(net "I3C_SPD_DDRGL_CPU1_SCL")
	)
	(segment
		(start 179.316634 -194.472052)
		(end 181.441344 -194.472052)
		(width 0.11684)
		(layer "In2.Cu")
		(net "I3C_SPD_DDRGL_CPU1_SCL")
	)
	(segment
		(start 179.004976 -194.34302)
		(end 179.316634 -194.472052)
		(width 0.11684)
		(layer "In2.Cu")
		(net "I3C_SPD_DDRGL_CPU1_SCL")
	)
	(segment
		(start 191.335152 -194.34302)
		(end 190.004446 -194.8942)
		(width 0.11684)
		(layer "In2.Cu")
		(net "I3C_SPD_DDRGL_CPU1_SCL")
	)
	(segment
		(start 183.421274 -167.917876)
		(end 183.420766 -167.917368)
		(width 0.10668)
		(layer "F.Cu")
		(net "I3C_SPD_DDRGL_CPU1_LVC1_SDA")
	)
	(segment
		(start 183.684164 -166.341552)
		(end 183.684164 -166.68115)
		(width 0.10668)
		(layer "F.Cu")
		(net "I3C_SPD_DDRGL_CPU1_LVC1_SDA")
	)
	(segment
		(start 183.420766 -167.40124)
		(end 183.420766 -167.917368)
		(width 0.10668)
		(layer "F.Cu")
		(net "I3C_SPD_DDRGL_CPU1_LVC1_SDA")
	)
	(segment
		(start 183.162702 -165.82009)
		(end 183.684164 -166.341552)
		(width 0.10668)
		(layer "F.Cu")
		(net "I3C_SPD_DDRGL_CPU1_LVC1_SDA")
	)
	(segment
		(start 183.684164 -166.68115)
		(end 183.684164 -167.137842)
		(width 0.10668)
		(layer "F.Cu")
		(net "I3C_SPD_DDRGL_CPU1_LVC1_SDA")
	)
	(segment
		(start 183.684164 -167.137842)
		(end 183.420766 -167.40124)
		(width 0.10668)
		(layer "F.Cu")
		(net "I3C_SPD_DDRGL_CPU1_LVC1_SDA")
	)
	(segment
		(start 183.162702 -165.401498)
		(end 183.162702 -165.82009)
		(width 0.10668)
		(layer "F.Cu")
		(net "I3C_SPD_DDRGL_CPU1_LVC1_SDA")
	)
	(segment
		(start 184.455054 -167.917876)
		(end 183.421274 -167.917876)
		(width 0.10668)
		(layer "F.Cu")
		(net "I3C_SPD_DDRGL_CPU1_LVC1_SDA")
	)
	(via
		(at 183.684164 -166.68115)
		(size 0.762)
		(drill 0.381)
		(layers "F.Cu" "B.Cu")
		(net "I3C_SPD_DDRGL_CPU1_LVC1_SDA")
	)
	(segment
		(start 182.66283 -165.401498)
		(end 182.66283 -166.048436)
		(width 0.10668)
		(layer "F.Cu")
		(net "I3C_SPD_DDRGL_CPU1_LVC1_SCL")
	)
	(segment
		(start 182.66283 -166.048436)
		(end 182.404766 -166.3065)
		(width 0.10668)
		(layer "F.Cu")
		(net "I3C_SPD_DDRGL_CPU1_LVC1_SCL")
	)
	(segment
		(start 182.404766 -166.3065)
		(end 182.404766 -166.65702)
		(width 0.10668)
		(layer "F.Cu")
		(net "I3C_SPD_DDRGL_CPU1_LVC1_SCL")
	)
	(segment
		(start 181.388766 -167.917368)
		(end 182.404766 -167.917368)
		(width 0.10668)
		(layer "F.Cu")
		(net "I3C_SPD_DDRGL_CPU1_LVC1_SCL")
	)
	(segment
		(start 182.404766 -166.65702)
		(end 182.404766 -167.917368)
		(width 0.10668)
		(layer "F.Cu")
		(net "I3C_SPD_DDRGL_CPU1_LVC1_SCL")
	)
	(via
		(at 182.404766 -166.65702)
		(size 0.762)
		(drill 0.381)
		(layers "F.Cu" "B.Cu")
		(net "I3C_SPD_DDRGL_CPU1_LVC1_SCL")
	)
	(segment
		(start 184.047892 -169.925238)
		(end 182.30977 -169.925238)
		(width 0.10668)
		(layer "F.Cu")
		(net "I3C_SPD_DDRGL_CPU1_BYPASS_SDA")
	)
	(segment
		(start 161.76244 -194.08394)
		(end 161.76244 -183.219598)
		(width 0.10668)
		(layer "F.Cu")
		(net "I3C_SPD_DDRGL_CPU1_BYPASS_SDA")
	)
	(segment
		(start 161.683954 -194.162426)
		(end 161.76244 -194.08394)
		(width 0.10668)
		(layer "F.Cu")
		(net "I3C_SPD_DDRGL_CPU1_BYPASS_SDA")
	)
	(segment
		(start 174.464472 -170.421046)
		(end 181.813962 -170.421046)
		(width 0.10668)
		(layer "F.Cu")
		(net "I3C_SPD_DDRGL_CPU1_BYPASS_SDA")
	)
	(segment
		(start 171.52493 -172.09135)
		(end 172.29709 -171.31919)
		(width 0.10668)
		(layer "F.Cu")
		(net "I3C_SPD_DDRGL_CPU1_BYPASS_SDA")
	)
	(segment
		(start 171.52493 -173.457108)
		(end 171.52493 -172.09135)
		(width 0.10668)
		(layer "F.Cu")
		(net "I3C_SPD_DDRGL_CPU1_BYPASS_SDA")
	)
	(segment
		(start 172.29709 -171.31919)
		(end 174.464472 -170.421046)
		(width 0.10668)
		(layer "F.Cu")
		(net "I3C_SPD_DDRGL_CPU1_BYPASS_SDA")
	)
	(segment
		(start 182.30977 -169.925238)
		(end 181.813962 -170.421046)
		(width 0.10668)
		(layer "F.Cu")
		(net "I3C_SPD_DDRGL_CPU1_BYPASS_SDA")
	)
	(segment
		(start 184.455054 -169.518076)
		(end 184.047892 -169.925238)
		(width 0.10668)
		(layer "F.Cu")
		(net "I3C_SPD_DDRGL_CPU1_BYPASS_SDA")
	)
	(segment
		(start 161.683954 -195.0466)
		(end 161.683954 -194.162426)
		(width 0.10668)
		(layer "F.Cu")
		(net "I3C_SPD_DDRGL_CPU1_BYPASS_SDA")
	)
	(segment
		(start 161.76244 -183.219598)
		(end 171.52493 -173.457108)
		(width 0.10668)
		(layer "F.Cu")
		(net "I3C_SPD_DDRGL_CPU1_BYPASS_SDA")
	)
	(via
		(at 181.813962 -170.421046)
		(size 0.762)
		(drill 0.381)
		(layers "F.Cu" "B.Cu")
		(net "I3C_SPD_DDRGL_CPU1_BYPASS_SDA")
	)
	(via
		(at 161.683954 -195.0466)
		(size 0.508)
		(drill 0.254)
		(layers "F.Cu" "B.Cu")
		(net "I3C_SPD_DDRGL_CPU1_BYPASS_SDA")
	)
	(segment
		(start 161.276284 -194.202558)
		(end 161.683954 -194.610228)
		(width 0.10668)
		(layer "B.Cu")
		(net "I3C_SPD_DDRGL_CPU1_BYPASS_SDA")
	)
	(segment
		(start 161.276284 -194.107562)
		(end 161.276284 -194.202558)
		(width 0.10668)
		(layer "B.Cu")
		(net "I3C_SPD_DDRGL_CPU1_BYPASS_SDA")
	)
	(segment
		(start 161.683954 -194.610228)
		(end 161.683954 -195.0466)
		(width 0.10668)
		(layer "B.Cu")
		(net "I3C_SPD_DDRGL_CPU1_BYPASS_SDA")
	)
	(segment
		(start 160.462214 -194.979544)
		(end 160.462214 -195.660772)
		(width 0.10668)
		(layer "F.Cu")
		(net "I3C_SPD_DDRGL_CPU1_BYPASS_SCL")
	)
	(segment
		(start 160.846008 -194.052952)
		(end 160.462214 -194.979544)
		(width 0.10668)
		(layer "F.Cu")
		(net "I3C_SPD_DDRGL_CPU1_BYPASS_SCL")
	)
	(segment
		(start 174.865284 -169.672)
		(end 171.992544 -170.86199)
		(width 0.10668)
		(layer "F.Cu")
		(net "I3C_SPD_DDRGL_CPU1_BYPASS_SCL")
	)
	(segment
		(start 178.99634 -169.672)
		(end 174.865284 -169.672)
		(width 0.10668)
		(layer "F.Cu")
		(net "I3C_SPD_DDRGL_CPU1_BYPASS_SCL")
	)
	(segment
		(start 170.98645 -172.962062)
		(end 161.22396 -182.724552)
		(width 0.10668)
		(layer "F.Cu")
		(net "I3C_SPD_DDRGL_CPU1_BYPASS_SCL")
	)
	(segment
		(start 181.234334 -169.672)
		(end 178.99634 -169.672)
		(width 0.10668)
		(layer "F.Cu")
		(net "I3C_SPD_DDRGL_CPU1_BYPASS_SCL")
	)
	(segment
		(start 161.22396 -193.675)
		(end 160.846008 -194.052952)
		(width 0.10668)
		(layer "F.Cu")
		(net "I3C_SPD_DDRGL_CPU1_BYPASS_SCL")
	)
	(segment
		(start 171.992544 -170.86199)
		(end 170.98645 -171.868084)
		(width 0.10668)
		(layer "F.Cu")
		(net "I3C_SPD_DDRGL_CPU1_BYPASS_SCL")
	)
	(segment
		(start 181.388766 -169.517568)
		(end 181.234334 -169.672)
		(width 0.10668)
		(layer "F.Cu")
		(net "I3C_SPD_DDRGL_CPU1_BYPASS_SCL")
	)
	(segment
		(start 161.22396 -182.724552)
		(end 161.22396 -193.675)
		(width 0.10668)
		(layer "F.Cu")
		(net "I3C_SPD_DDRGL_CPU1_BYPASS_SCL")
	)
	(segment
		(start 170.98645 -171.868084)
		(end 170.98645 -172.962062)
		(width 0.10668)
		(layer "F.Cu")
		(net "I3C_SPD_DDRGL_CPU1_BYPASS_SCL")
	)
	(via
		(at 178.99634 -169.672)
		(size 0.762)
		(drill 0.381)
		(layers "F.Cu" "B.Cu")
		(net "I3C_SPD_DDRGL_CPU1_BYPASS_SCL")
	)
	(via
		(at 160.462214 -195.660772)
		(size 0.508)
		(drill 0.254)
		(layers "F.Cu" "B.Cu")
		(net "I3C_SPD_DDRGL_CPU1_BYPASS_SCL")
	)
	(segment
		(start 159.615632 -194.349116)
		(end 159.615632 -194.81419)
		(width 0.10668)
		(layer "B.Cu")
		(net "I3C_SPD_DDRGL_CPU1_BYPASS_SCL")
	)
	(segment
		(start 159.615632 -194.81419)
		(end 160.462214 -195.660772)
		(width 0.10668)
		(layer "B.Cu")
		(net "I3C_SPD_DDRGL_CPU1_BYPASS_SCL")
	)
	(segment
		(start 435.891178 -171.08805)
		(end 436.546244 -171.743116)
		(width 0.10668)
		(layer "F.Cu")
		(net "I3C_SPD_DDRGL_CPU0_SDA")
	)
	(segment
		(start 435.102 -171.08805)
		(end 435.891178 -171.08805)
		(width 0.10668)
		(layer "F.Cu")
		(net "I3C_SPD_DDRGL_CPU0_SDA")
	)
	(via
		(at 445.488314 -195.86067)
		(size 0.508)
		(drill 0.254)
		(layers "F.Cu" "B.Cu")
		(net "I3C_SPD_DDRGL_CPU0_SDA")
	)
	(via
		(at 430.40046 -195.85051)
		(size 0.508)
		(drill 0.254)
		(layers "F.Cu" "B.Cu")
		(net "I3C_SPD_DDRGL_CPU0_SDA")
	)
	(via
		(at 422.856406 -195.85051)
		(size 0.508)
		(drill 0.254)
		(layers "F.Cu" "B.Cu")
		(net "I3C_SPD_DDRGL_CPU0_SDA")
	)
	(via
		(at 453.032368 -195.92671)
		(size 0.508)
		(drill 0.254)
		(layers "F.Cu" "B.Cu")
		(net "I3C_SPD_DDRGL_CPU0_SDA")
	)
	(via
		(at 437.944514 -195.859146)
		(size 0.508)
		(drill 0.254)
		(layers "F.Cu" "B.Cu")
		(net "I3C_SPD_DDRGL_CPU0_SDA")
	)
	(via
		(at 436.546244 -171.743116)
		(size 0.508)
		(drill 0.254)
		(layers "F.Cu" "B.Cu")
		(net "I3C_SPD_DDRGL_CPU0_SDA")
	)
	(via
		(at 415.312352 -195.83527)
		(size 0.508)
		(drill 0.254)
		(layers "F.Cu" "B.Cu")
		(net "I3C_SPD_DDRGL_CPU0_SDA")
	)
	(segment
		(start 452.574406 -190.59906)
		(end 448.867784 -186.892438)
		(width 0.11684)
		(layer "In2.Cu")
		(net "I3C_SPD_DDRGL_CPU0_SDA")
	)
	(segment
		(start 450.596 -194.95135)
		(end 449.86956 -194.95135)
		(width 0.11684)
		(layer "In2.Cu")
		(net "I3C_SPD_DDRGL_CPU0_SDA")
	)
	(segment
		(start 449.86956 -193.70167)
		(end 449.75272 -193.58483)
		(width 0.11684)
		(layer "In2.Cu")
		(net "I3C_SPD_DDRGL_CPU0_SDA")
	)
	(segment
		(start 450.71284 -192.95999)
		(end 450.71284 -192.56883)
		(width 0.11684)
		(layer "In2.Cu")
		(net "I3C_SPD_DDRGL_CPU0_SDA")
	)
	(segment
		(start 450.71284 -195.06819)
		(end 450.596 -194.95135)
		(width 0.11684)
		(layer "In2.Cu")
		(net "I3C_SPD_DDRGL_CPU0_SDA")
	)
	(segment
		(start 450.71284 -193.81851)
		(end 450.596 -193.70167)
		(width 0.11684)
		(layer "In2.Cu")
		(net "I3C_SPD_DDRGL_CPU0_SDA")
	)
	(segment
		(start 450.596 -194.32651)
		(end 450.71284 -194.20967)
		(width 0.11684)
		(layer "In2.Cu")
		(net "I3C_SPD_DDRGL_CPU0_SDA")
	)
	(segment
		(start 453.032368 -195.92671)
		(end 450.83984 -195.92671)
		(width 0.11684)
		(layer "In2.Cu")
		(net "I3C_SPD_DDRGL_CPU0_SDA")
	)
	(segment
		(start 437.816244 -173.013116)
		(end 436.546244 -171.743116)
		(width 0.11684)
		(layer "In2.Cu")
		(net "I3C_SPD_DDRGL_CPU0_SDA")
	)
	(segment
		(start 441.538868 -173.013116)
		(end 437.816244 -173.013116)
		(width 0.11684)
		(layer "In2.Cu")
		(net "I3C_SPD_DDRGL_CPU0_SDA")
	)
	(segment
		(start 450.596 -192.45199)
		(end 449.86956 -192.45199)
		(width 0.11684)
		(layer "In2.Cu")
		(net "I3C_SPD_DDRGL_CPU0_SDA")
	)
	(segment
		(start 449.75272 -193.58483)
		(end 449.75272 -193.19367)
		(width 0.11684)
		(layer "In2.Cu")
		(net "I3C_SPD_DDRGL_CPU0_SDA")
	)
	(segment
		(start 449.86956 -194.32651)
		(end 450.596 -194.32651)
		(width 0.11684)
		(layer "In2.Cu")
		(net "I3C_SPD_DDRGL_CPU0_SDA")
	)
	(segment
		(start 449.75272 -191.94399)
		(end 449.86956 -191.82715)
		(width 0.11684)
		(layer "In2.Cu")
		(net "I3C_SPD_DDRGL_CPU0_SDA")
	)
	(segment
		(start 452.574406 -191.130174)
		(end 452.574406 -190.59906)
		(width 0.11684)
		(layer "In2.Cu")
		(net "I3C_SPD_DDRGL_CPU0_SDA")
	)
	(segment
		(start 450.596 -193.70167)
		(end 449.86956 -193.70167)
		(width 0.11684)
		(layer "In2.Cu")
		(net "I3C_SPD_DDRGL_CPU0_SDA")
	)
	(segment
		(start 449.86956 -194.95135)
		(end 449.75272 -194.83451)
		(width 0.11684)
		(layer "In2.Cu")
		(net "I3C_SPD_DDRGL_CPU0_SDA")
	)
	(segment
		(start 450.71284 -192.56883)
		(end 450.596 -192.45199)
		(width 0.11684)
		(layer "In2.Cu")
		(net "I3C_SPD_DDRGL_CPU0_SDA")
	)
	(segment
		(start 451.15607 -191.26708)
		(end 452.4375 -191.26708)
		(width 0.11684)
		(layer "In2.Cu")
		(net "I3C_SPD_DDRGL_CPU0_SDA")
	)
	(segment
		(start 450.71284 -195.79971)
		(end 450.71284 -195.06819)
		(width 0.11684)
		(layer "In2.Cu")
		(net "I3C_SPD_DDRGL_CPU0_SDA")
	)
	(segment
		(start 452.4375 -191.26708)
		(end 452.574406 -191.130174)
		(width 0.11684)
		(layer "In2.Cu")
		(net "I3C_SPD_DDRGL_CPU0_SDA")
	)
	(segment
		(start 448.867784 -180.342032)
		(end 441.538868 -173.013116)
		(width 0.11684)
		(layer "In2.Cu")
		(net "I3C_SPD_DDRGL_CPU0_SDA")
	)
	(segment
		(start 448.867784 -186.892438)
		(end 448.867784 -180.342032)
		(width 0.11684)
		(layer "In2.Cu")
		(net "I3C_SPD_DDRGL_CPU0_SDA")
	)
	(segment
		(start 450.596 -191.82715)
		(end 451.15607 -191.26708)
		(width 0.11684)
		(layer "In2.Cu")
		(net "I3C_SPD_DDRGL_CPU0_SDA")
	)
	(segment
		(start 449.75272 -192.33515)
		(end 449.75272 -191.94399)
		(width 0.11684)
		(layer "In2.Cu")
		(net "I3C_SPD_DDRGL_CPU0_SDA")
	)
	(segment
		(start 449.86956 -191.82715)
		(end 450.596 -191.82715)
		(width 0.11684)
		(layer "In2.Cu")
		(net "I3C_SPD_DDRGL_CPU0_SDA")
	)
	(segment
		(start 449.75272 -194.44335)
		(end 449.86956 -194.32651)
		(width 0.11684)
		(layer "In2.Cu")
		(net "I3C_SPD_DDRGL_CPU0_SDA")
	)
	(segment
		(start 449.86956 -192.45199)
		(end 449.75272 -192.33515)
		(width 0.11684)
		(layer "In2.Cu")
		(net "I3C_SPD_DDRGL_CPU0_SDA")
	)
	(segment
		(start 450.596 -193.07683)
		(end 450.71284 -192.95999)
		(width 0.11684)
		(layer "In2.Cu")
		(net "I3C_SPD_DDRGL_CPU0_SDA")
	)
	(segment
		(start 449.86956 -193.07683)
		(end 450.596 -193.07683)
		(width 0.11684)
		(layer "In2.Cu")
		(net "I3C_SPD_DDRGL_CPU0_SDA")
	)
	(segment
		(start 449.75272 -194.83451)
		(end 449.75272 -194.44335)
		(width 0.11684)
		(layer "In2.Cu")
		(net "I3C_SPD_DDRGL_CPU0_SDA")
	)
	(segment
		(start 449.75272 -193.19367)
		(end 449.86956 -193.07683)
		(width 0.11684)
		(layer "In2.Cu")
		(net "I3C_SPD_DDRGL_CPU0_SDA")
	)
	(segment
		(start 450.71284 -194.20967)
		(end 450.71284 -193.81851)
		(width 0.11684)
		(layer "In2.Cu")
		(net "I3C_SPD_DDRGL_CPU0_SDA")
	)
	(segment
		(start 450.83984 -195.92671)
		(end 450.71284 -195.79971)
		(width 0.11684)
		(layer "In2.Cu")
		(net "I3C_SPD_DDRGL_CPU0_SDA")
	)
	(segment
		(start 445.488314 -195.86067)
		(end 445.281304 -196.06768)
		(width 0.11684)
		(layer "In11.Cu")
		(net "I3C_SPD_DDRGL_CPU0_SDA")
	)
	(segment
		(start 432.12893 -195.85051)
		(end 430.40046 -195.85051)
		(width 0.11684)
		(layer "In11.Cu")
		(net "I3C_SPD_DDRGL_CPU0_SDA")
	)
	(segment
		(start 424.813222 -196.055488)
		(end 424.608244 -195.85051)
		(width 0.11684)
		(layer "In11.Cu")
		(net "I3C_SPD_DDRGL_CPU0_SDA")
	)
	(segment
		(start 437.944514 -195.859146)
		(end 437.73598 -196.06768)
		(width 0.11684)
		(layer "In11.Cu")
		(net "I3C_SPD_DDRGL_CPU0_SDA")
	)
	(segment
		(start 422.639236 -196.06768)
		(end 417.36899 -196.06768)
		(width 0.11684)
		(layer "In11.Cu")
		(net "I3C_SPD_DDRGL_CPU0_SDA")
	)
	(segment
		(start 424.608244 -195.85051)
		(end 422.856406 -195.85051)
		(width 0.11684)
		(layer "In11.Cu")
		(net "I3C_SPD_DDRGL_CPU0_SDA")
	)
	(segment
		(start 440.025536 -196.06768)
		(end 439.817002 -195.859146)
		(width 0.11684)
		(layer "In11.Cu")
		(net "I3C_SPD_DDRGL_CPU0_SDA")
	)
	(segment
		(start 430.195482 -196.055488)
		(end 424.813222 -196.055488)
		(width 0.11684)
		(layer "In11.Cu")
		(net "I3C_SPD_DDRGL_CPU0_SDA")
	)
	(segment
		(start 445.281304 -196.06768)
		(end 440.025536 -196.06768)
		(width 0.11684)
		(layer "In11.Cu")
		(net "I3C_SPD_DDRGL_CPU0_SDA")
	)
	(segment
		(start 453.032368 -195.92671)
		(end 452.870316 -196.088762)
		(width 0.11684)
		(layer "In11.Cu")
		(net "I3C_SPD_DDRGL_CPU0_SDA")
	)
	(segment
		(start 417.36899 -196.06768)
		(end 417.13658 -195.83527)
		(width 0.11684)
		(layer "In11.Cu")
		(net "I3C_SPD_DDRGL_CPU0_SDA")
	)
	(segment
		(start 430.40046 -195.85051)
		(end 430.195482 -196.055488)
		(width 0.11684)
		(layer "In11.Cu")
		(net "I3C_SPD_DDRGL_CPU0_SDA")
	)
	(segment
		(start 422.856406 -195.85051)
		(end 422.639236 -196.06768)
		(width 0.11684)
		(layer "In11.Cu")
		(net "I3C_SPD_DDRGL_CPU0_SDA")
	)
	(segment
		(start 437.73598 -196.06768)
		(end 432.3461 -196.06768)
		(width 0.11684)
		(layer "In11.Cu")
		(net "I3C_SPD_DDRGL_CPU0_SDA")
	)
	(segment
		(start 432.3461 -196.06768)
		(end 432.12893 -195.85051)
		(width 0.11684)
		(layer "In11.Cu")
		(net "I3C_SPD_DDRGL_CPU0_SDA")
	)
	(segment
		(start 417.13658 -195.83527)
		(end 415.312352 -195.83527)
		(width 0.11684)
		(layer "In11.Cu")
		(net "I3C_SPD_DDRGL_CPU0_SDA")
	)
	(segment
		(start 452.870316 -196.088762)
		(end 447.399664 -196.088762)
		(width 0.11684)
		(layer "In11.Cu")
		(net "I3C_SPD_DDRGL_CPU0_SDA")
	)
	(segment
		(start 439.817002 -195.859146)
		(end 437.944514 -195.859146)
		(width 0.11684)
		(layer "In11.Cu")
		(net "I3C_SPD_DDRGL_CPU0_SDA")
	)
	(segment
		(start 447.171572 -195.86067)
		(end 445.488314 -195.86067)
		(width 0.11684)
		(layer "In11.Cu")
		(net "I3C_SPD_DDRGL_CPU0_SDA")
	)
	(segment
		(start 447.399664 -196.088762)
		(end 447.171572 -195.86067)
		(width 0.11684)
		(layer "In11.Cu")
		(net "I3C_SPD_DDRGL_CPU0_SDA")
	)
	(segment
		(start 439.756804 -163.944808)
		(end 441.159392 -165.347396)
		(width 0.10668)
		(layer "F.Cu")
		(net "I3C_SPD_DDRGL_CPU0_SCL")
	)
	(segment
		(start 435.628288 -165.098984)
		(end 436.782464 -163.944808)
		(width 0.10668)
		(layer "F.Cu")
		(net "I3C_SPD_DDRGL_CPU0_SCL")
	)
	(segment
		(start 435.628288 -165.824662)
		(end 435.628288 -165.098984)
		(width 0.10668)
		(layer "F.Cu")
		(net "I3C_SPD_DDRGL_CPU0_SCL")
	)
	(segment
		(start 436.782464 -163.944808)
		(end 439.756804 -163.944808)
		(width 0.10668)
		(layer "F.Cu")
		(net "I3C_SPD_DDRGL_CPU0_SCL")
	)
	(segment
		(start 435.102 -166.35095)
		(end 435.628288 -165.824662)
		(width 0.10668)
		(layer "F.Cu")
		(net "I3C_SPD_DDRGL_CPU0_SCL")
	)
	(via
		(at 430.40046 -194.88531)
		(size 0.508)
		(drill 0.254)
		(layers "F.Cu" "B.Cu")
		(net "I3C_SPD_DDRGL_CPU0_SCL")
	)
	(via
		(at 453.032368 -194.96151)
		(size 0.508)
		(drill 0.254)
		(layers "F.Cu" "B.Cu")
		(net "I3C_SPD_DDRGL_CPU0_SCL")
	)
	(via
		(at 445.488314 -194.89547)
		(size 0.508)
		(drill 0.254)
		(layers "F.Cu" "B.Cu")
		(net "I3C_SPD_DDRGL_CPU0_SCL")
	)
	(via
		(at 422.856406 -194.88531)
		(size 0.508)
		(drill 0.254)
		(layers "F.Cu" "B.Cu")
		(net "I3C_SPD_DDRGL_CPU0_SCL")
	)
	(via
		(at 437.944514 -194.893946)
		(size 0.508)
		(drill 0.254)
		(layers "F.Cu" "B.Cu")
		(net "I3C_SPD_DDRGL_CPU0_SCL")
	)
	(via
		(at 441.159392 -165.347396)
		(size 0.508)
		(drill 0.254)
		(layers "F.Cu" "B.Cu")
		(net "I3C_SPD_DDRGL_CPU0_SCL")
	)
	(via
		(at 415.312352 -194.87007)
		(size 0.508)
		(drill 0.254)
		(layers "F.Cu" "B.Cu")
		(net "I3C_SPD_DDRGL_CPU0_SCL")
	)
	(segment
		(start 453.032368 -194.96151)
		(end 452.51624 -194.445382)
		(width 0.11684)
		(layer "In2.Cu")
		(net "I3C_SPD_DDRGL_CPU0_SCL")
	)
	(segment
		(start 449.55206 -186.58078)
		(end 449.55206 -180.047138)
		(width 0.11684)
		(layer "In2.Cu")
		(net "I3C_SPD_DDRGL_CPU0_SCL")
	)
	(segment
		(start 440.58332 -169.588688)
		(end 441.92698 -168.245028)
		(width 0.11684)
		(layer "In2.Cu")
		(net "I3C_SPD_DDRGL_CPU0_SCL")
	)
	(segment
		(start 449.55206 -180.047138)
		(end 440.58332 -171.078398)
		(width 0.11684)
		(layer "In2.Cu")
		(net "I3C_SPD_DDRGL_CPU0_SCL")
	)
	(segment
		(start 440.58332 -171.078398)
		(end 440.58332 -169.588688)
		(width 0.11684)
		(layer "In2.Cu")
		(net "I3C_SPD_DDRGL_CPU0_SCL")
	)
	(segment
		(start 441.92698 -166.114984)
		(end 441.159392 -165.347396)
		(width 0.11684)
		(layer "In2.Cu")
		(net "I3C_SPD_DDRGL_CPU0_SCL")
	)
	(segment
		(start 452.51624 -192.06718)
		(end 453.20458 -191.37884)
		(width 0.11684)
		(layer "In2.Cu")
		(net "I3C_SPD_DDRGL_CPU0_SCL")
	)
	(segment
		(start 453.20458 -191.37884)
		(end 453.20458 -190.2333)
		(width 0.11684)
		(layer "In2.Cu")
		(net "I3C_SPD_DDRGL_CPU0_SCL")
	)
	(segment
		(start 453.20458 -190.2333)
		(end 449.55206 -186.58078)
		(width 0.11684)
		(layer "In2.Cu")
		(net "I3C_SPD_DDRGL_CPU0_SCL")
	)
	(segment
		(start 441.92698 -168.245028)
		(end 441.92698 -166.114984)
		(width 0.11684)
		(layer "In2.Cu")
		(net "I3C_SPD_DDRGL_CPU0_SCL")
	)
	(segment
		(start 452.51624 -194.445382)
		(end 452.51624 -192.06718)
		(width 0.11684)
		(layer "In2.Cu")
		(net "I3C_SPD_DDRGL_CPU0_SCL")
	)
	(segment
		(start 425.754038 -195.036948)
		(end 426.01642 -195.29933)
		(width 0.11684)
		(layer "In11.Cu")
		(net "I3C_SPD_DDRGL_CPU0_SCL")
	)
	(segment
		(start 439.890916 -194.34048)
		(end 440.57316 -194.34048)
		(width 0.11684)
		(layer "In11.Cu")
		(net "I3C_SPD_DDRGL_CPU0_SCL")
	)
	(segment
		(start 452.694548 -195.29933)
		(end 453.032368 -194.96151)
		(width 0.11684)
		(layer "In11.Cu")
		(net "I3C_SPD_DDRGL_CPU0_SCL")
	)
	(segment
		(start 433.335938 -194.649852)
		(end 433.335938 -195.074794)
		(width 0.11684)
		(layer "In11.Cu")
		(net "I3C_SPD_DDRGL_CPU0_SCL")
	)
	(segment
		(start 448.228212 -194.34048)
		(end 448.355212 -194.46748)
		(width 0.11684)
		(layer "In11.Cu")
		(net "I3C_SPD_DDRGL_CPU0_SCL")
	)
	(segment
		(start 447.48069 -194.34048)
		(end 448.228212 -194.34048)
		(width 0.11684)
		(layer "In11.Cu")
		(net "I3C_SPD_DDRGL_CPU0_SCL")
	)
	(segment
		(start 437.944514 -194.893946)
		(end 439.33745 -194.893946)
		(width 0.11684)
		(layer "In11.Cu")
		(net "I3C_SPD_DDRGL_CPU0_SCL")
	)
	(segment
		(start 433.031646 -194.34556)
		(end 433.335938 -194.649852)
		(width 0.11684)
		(layer "In11.Cu")
		(net "I3C_SPD_DDRGL_CPU0_SCL")
	)
	(segment
		(start 433.63261 -195.371466)
		(end 437.466994 -195.371466)
		(width 0.11684)
		(layer "In11.Cu")
		(net "I3C_SPD_DDRGL_CPU0_SCL")
	)
	(segment
		(start 440.892692 -194.660012)
		(end 440.892692 -195.087494)
		(width 0.11684)
		(layer "In11.Cu")
		(net "I3C_SPD_DDRGL_CPU0_SCL")
	)
	(segment
		(start 415.312352 -194.87007)
		(end 416.73526 -194.87007)
		(width 0.11684)
		(layer "In11.Cu")
		(net "I3C_SPD_DDRGL_CPU0_SCL")
	)
	(segment
		(start 426.01642 -195.29933)
		(end 429.98644 -195.29933)
		(width 0.11684)
		(layer "In11.Cu")
		(net "I3C_SPD_DDRGL_CPU0_SCL")
	)
	(segment
		(start 448.355212 -194.46748)
		(end 448.355212 -195.00596)
		(width 0.11684)
		(layer "In11.Cu")
		(net "I3C_SPD_DDRGL_CPU0_SCL")
	)
	(segment
		(start 418.179758 -194.941698)
		(end 418.52469 -195.28663)
		(width 0.11684)
		(layer "In11.Cu")
		(net "I3C_SPD_DDRGL_CPU0_SCL")
	)
	(segment
		(start 448.648582 -195.29933)
		(end 452.694548 -195.29933)
		(width 0.11684)
		(layer "In11.Cu")
		(net "I3C_SPD_DDRGL_CPU0_SCL")
	)
	(segment
		(start 417.26485 -194.34048)
		(end 417.900866 -194.34048)
		(width 0.11684)
		(layer "In11.Cu")
		(net "I3C_SPD_DDRGL_CPU0_SCL")
	)
	(segment
		(start 418.52469 -195.28663)
		(end 422.455086 -195.28663)
		(width 0.11684)
		(layer "In11.Cu")
		(net "I3C_SPD_DDRGL_CPU0_SCL")
	)
	(segment
		(start 448.355212 -195.00596)
		(end 448.648582 -195.29933)
		(width 0.11684)
		(layer "In11.Cu")
		(net "I3C_SPD_DDRGL_CPU0_SCL")
	)
	(segment
		(start 432.43373 -194.34556)
		(end 433.031646 -194.34556)
		(width 0.11684)
		(layer "In11.Cu")
		(net "I3C_SPD_DDRGL_CPU0_SCL")
	)
	(segment
		(start 425.472352 -194.33794)
		(end 425.754038 -194.619626)
		(width 0.11684)
		(layer "In11.Cu")
		(net "I3C_SPD_DDRGL_CPU0_SCL")
	)
	(segment
		(start 424.184318 -194.88531)
		(end 424.731688 -194.33794)
		(width 0.11684)
		(layer "In11.Cu")
		(net "I3C_SPD_DDRGL_CPU0_SCL")
	)
	(segment
		(start 437.466994 -195.371466)
		(end 437.944514 -194.893946)
		(width 0.11684)
		(layer "In11.Cu")
		(net "I3C_SPD_DDRGL_CPU0_SCL")
	)
	(segment
		(start 431.89398 -194.88531)
		(end 432.43373 -194.34556)
		(width 0.11684)
		(layer "In11.Cu")
		(net "I3C_SPD_DDRGL_CPU0_SCL")
	)
	(segment
		(start 446.9257 -194.89547)
		(end 447.48069 -194.34048)
		(width 0.11684)
		(layer "In11.Cu")
		(net "I3C_SPD_DDRGL_CPU0_SCL")
	)
	(segment
		(start 416.73526 -194.87007)
		(end 417.26485 -194.34048)
		(width 0.11684)
		(layer "In11.Cu")
		(net "I3C_SPD_DDRGL_CPU0_SCL")
	)
	(segment
		(start 440.57316 -194.34048)
		(end 440.892692 -194.660012)
		(width 0.11684)
		(layer "In11.Cu")
		(net "I3C_SPD_DDRGL_CPU0_SCL")
	)
	(segment
		(start 440.892692 -195.087494)
		(end 441.104528 -195.29933)
		(width 0.11684)
		(layer "In11.Cu")
		(net "I3C_SPD_DDRGL_CPU0_SCL")
	)
	(segment
		(start 430.40046 -194.88531)
		(end 431.89398 -194.88531)
		(width 0.11684)
		(layer "In11.Cu")
		(net "I3C_SPD_DDRGL_CPU0_SCL")
	)
	(segment
		(start 424.731688 -194.33794)
		(end 425.472352 -194.33794)
		(width 0.11684)
		(layer "In11.Cu")
		(net "I3C_SPD_DDRGL_CPU0_SCL")
	)
	(segment
		(start 422.455086 -195.28663)
		(end 422.856406 -194.88531)
		(width 0.11684)
		(layer "In11.Cu")
		(net "I3C_SPD_DDRGL_CPU0_SCL")
	)
	(segment
		(start 441.104528 -195.29933)
		(end 445.084454 -195.29933)
		(width 0.11684)
		(layer "In11.Cu")
		(net "I3C_SPD_DDRGL_CPU0_SCL")
	)
	(segment
		(start 445.084454 -195.29933)
		(end 445.488314 -194.89547)
		(width 0.11684)
		(layer "In11.Cu")
		(net "I3C_SPD_DDRGL_CPU0_SCL")
	)
	(segment
		(start 439.33745 -194.893946)
		(end 439.890916 -194.34048)
		(width 0.11684)
		(layer "In11.Cu")
		(net "I3C_SPD_DDRGL_CPU0_SCL")
	)
	(segment
		(start 445.488314 -194.89547)
		(end 446.9257 -194.89547)
		(width 0.11684)
		(layer "In11.Cu")
		(net "I3C_SPD_DDRGL_CPU0_SCL")
	)
	(segment
		(start 433.335938 -195.074794)
		(end 433.63261 -195.371466)
		(width 0.11684)
		(layer "In11.Cu")
		(net "I3C_SPD_DDRGL_CPU0_SCL")
	)
	(segment
		(start 417.900866 -194.34048)
		(end 418.179758 -194.619372)
		(width 0.11684)
		(layer "In11.Cu")
		(net "I3C_SPD_DDRGL_CPU0_SCL")
	)
	(segment
		(start 425.754038 -194.619626)
		(end 425.754038 -195.036948)
		(width 0.11684)
		(layer "In11.Cu")
		(net "I3C_SPD_DDRGL_CPU0_SCL")
	)
	(segment
		(start 429.98644 -195.29933)
		(end 430.40046 -194.88531)
		(width 0.11684)
		(layer "In11.Cu")
		(net "I3C_SPD_DDRGL_CPU0_SCL")
	)
	(segment
		(start 418.179758 -194.619372)
		(end 418.179758 -194.941698)
		(width 0.11684)
		(layer "In11.Cu")
		(net "I3C_SPD_DDRGL_CPU0_SCL")
	)
	(segment
		(start 422.856406 -194.88531)
		(end 424.184318 -194.88531)
		(width 0.11684)
		(layer "In11.Cu")
		(net "I3C_SPD_DDRGL_CPU0_SCL")
	)
	(segment
		(start 437.848756 -168.966388)
		(end 436.776368 -168.966388)
		(width 0.10668)
		(layer "F.Cu")
		(net "I3C_SPD_DDRGL_CPU0_LVC1_SDA")
	)
	(segment
		(start 435.078886 -170.264836)
		(end 435.078886 -169.224452)
		(width 0.10668)
		(layer "F.Cu")
		(net "I3C_SPD_DDRGL_CPU0_LVC1_SDA")
	)
	(segment
		(start 436.776368 -168.966388)
		(end 436.518304 -169.224452)
		(width 0.10668)
		(layer "F.Cu")
		(net "I3C_SPD_DDRGL_CPU0_LVC1_SDA")
	)
	(segment
		(start 435.102 -170.28795)
		(end 435.078886 -170.264836)
		(width 0.10668)
		(layer "F.Cu")
		(net "I3C_SPD_DDRGL_CPU0_LVC1_SDA")
	)
	(segment
		(start 436.518304 -169.224452)
		(end 435.078886 -169.224452)
		(width 0.10668)
		(layer "F.Cu")
		(net "I3C_SPD_DDRGL_CPU0_LVC1_SDA")
	)
	(via
		(at 436.518304 -169.224452)
		(size 0.762)
		(drill 0.381)
		(layers "F.Cu" "B.Cu")
		(net "I3C_SPD_DDRGL_CPU0_LVC1_SDA")
	)
	(segment
		(start 435.102 -167.15105)
		(end 435.102 -167.616886)
		(width 0.10668)
		(layer "F.Cu")
		(net "I3C_SPD_DDRGL_CPU0_LVC1_SCL")
	)
	(segment
		(start 437.797956 -168.415716)
		(end 437.016398 -168.415716)
		(width 0.10668)
		(layer "F.Cu")
		(net "I3C_SPD_DDRGL_CPU0_LVC1_SCL")
	)
	(segment
		(start 435.078886 -167.64)
		(end 435.078886 -168.208452)
		(width 0.10668)
		(layer "F.Cu")
		(net "I3C_SPD_DDRGL_CPU0_LVC1_SCL")
	)
	(segment
		(start 437.016398 -168.415716)
		(end 436.49011 -167.889428)
		(width 0.10668)
		(layer "F.Cu")
		(net "I3C_SPD_DDRGL_CPU0_LVC1_SCL")
	)
	(segment
		(start 436.49011 -167.889428)
		(end 435.39791 -167.889428)
		(width 0.10668)
		(layer "F.Cu")
		(net "I3C_SPD_DDRGL_CPU0_LVC1_SCL")
	)
	(segment
		(start 435.102 -167.616886)
		(end 435.078886 -167.64)
		(width 0.10668)
		(layer "F.Cu")
		(net "I3C_SPD_DDRGL_CPU0_LVC1_SCL")
	)
	(segment
		(start 437.848756 -168.466516)
		(end 437.797956 -168.415716)
		(width 0.10668)
		(layer "F.Cu")
		(net "I3C_SPD_DDRGL_CPU0_LVC1_SCL")
	)
	(segment
		(start 435.39791 -167.889428)
		(end 435.078886 -168.208452)
		(width 0.10668)
		(layer "F.Cu")
		(net "I3C_SPD_DDRGL_CPU0_LVC1_SCL")
	)
	(via
		(at 436.49011 -167.889428)
		(size 0.762)
		(drill 0.381)
		(layers "F.Cu" "B.Cu")
		(net "I3C_SPD_DDRGL_CPU0_LVC1_SCL")
	)
	(segment
		(start 432.431698 -171.88815)
		(end 431.673 -171.129452)
		(width 0.10668)
		(layer "F.Cu")
		(net "I3C_SPD_DDRGL_CPU0_BYPASS_SDA")
	)
	(segment
		(start 435.102 -171.88815)
		(end 432.431698 -171.88815)
		(width 0.10668)
		(layer "F.Cu")
		(net "I3C_SPD_DDRGL_CPU0_BYPASS_SDA")
	)
	(via
		(at 431.673 -171.129452)
		(size 0.508)
		(drill 0.254)
		(layers "F.Cu" "B.Cu")
		(net "I3C_SPD_DDRGL_CPU0_BYPASS_SDA")
	)
	(via
		(at 384.180842 -205.658466)
		(size 0.508)
		(drill 0.254)
		(layers "F.Cu" "B.Cu")
		(net "I3C_SPD_DDRGL_CPU0_BYPASS_SDA")
	)
	(segment
		(start 383.076958 -206.302102)
		(end 383.720594 -205.658466)
		(width 0.10668)
		(layer "B.Cu")
		(net "I3C_SPD_DDRGL_CPU0_BYPASS_SDA")
	)
	(segment
		(start 383.720594 -205.658466)
		(end 384.180842 -205.658466)
		(width 0.10668)
		(layer "B.Cu")
		(net "I3C_SPD_DDRGL_CPU0_BYPASS_SDA")
	)
	(segment
		(start 430.0347 -177.457862)
		(end 429.576484 -177.916078)
		(width 0.11684)
		(layer "In2.Cu")
		(net "I3C_SPD_DDRGL_CPU0_BYPASS_SDA")
	)
	(segment
		(start 432.527964 -174.799498)
		(end 432.527964 -174.964598)
		(width 0.11684)
		(layer "In2.Cu")
		(net "I3C_SPD_DDRGL_CPU0_BYPASS_SDA")
	)
	(segment
		(start 429.476916 -176.569878)
		(end 429.476916 -176.734978)
		(width 0.11684)
		(layer "In2.Cu")
		(net "I3C_SPD_DDRGL_CPU0_BYPASS_SDA")
	)
	(segment
		(start 431.673 -171.129452)
		(end 431.673 -173.944534)
		(width 0.11684)
		(layer "In2.Cu")
		(net "I3C_SPD_DDRGL_CPU0_BYPASS_SDA")
	)
	(segment
		(start 399.141188 -197.015862)
		(end 392.8364 -203.32065)
		(width 0.11684)
		(layer "In2.Cu")
		(net "I3C_SPD_DDRGL_CPU0_BYPASS_SDA")
	)
	(segment
		(start 431.281332 -176.04613)
		(end 431.281332 -176.21123)
		(width 0.11684)
		(layer "In2.Cu")
		(net "I3C_SPD_DDRGL_CPU0_BYPASS_SDA")
	)
	(segment
		(start 421.85844 -184.188354)
		(end 413.973518 -184.188354)
		(width 0.11684)
		(layer "In2.Cu")
		(net "I3C_SPD_DDRGL_CPU0_BYPASS_SDA")
	)
	(segment
		(start 429.476916 -176.734978)
		(end 430.0347 -177.292762)
		(width 0.11684)
		(layer "In2.Cu")
		(net "I3C_SPD_DDRGL_CPU0_BYPASS_SDA")
	)
	(segment
		(start 386.004308 -203.32065)
		(end 384.180842 -205.144116)
		(width 0.11684)
		(layer "In2.Cu")
		(net "I3C_SPD_DDRGL_CPU0_BYPASS_SDA")
	)
	(segment
		(start 430.723548 -175.488346)
		(end 431.281332 -176.04613)
		(width 0.11684)
		(layer "In2.Cu")
		(net "I3C_SPD_DDRGL_CPU0_BYPASS_SDA")
	)
	(segment
		(start 430.0347 -177.292762)
		(end 430.0347 -177.457862)
		(width 0.11684)
		(layer "In2.Cu")
		(net "I3C_SPD_DDRGL_CPU0_BYPASS_SDA")
	)
	(segment
		(start 429.935132 -176.111662)
		(end 429.476916 -176.569878)
		(width 0.11684)
		(layer "In2.Cu")
		(net "I3C_SPD_DDRGL_CPU0_BYPASS_SDA")
	)
	(segment
		(start 413.973518 -184.188354)
		(end 401.14601 -197.015862)
		(width 0.11684)
		(layer "In2.Cu")
		(net "I3C_SPD_DDRGL_CPU0_BYPASS_SDA")
	)
	(segment
		(start 430.658016 -176.669446)
		(end 430.100232 -176.111662)
		(width 0.11684)
		(layer "In2.Cu")
		(net "I3C_SPD_DDRGL_CPU0_BYPASS_SDA")
	)
	(segment
		(start 428.8536 -177.358294)
		(end 428.6885 -177.358294)
		(width 0.11684)
		(layer "In2.Cu")
		(net "I3C_SPD_DDRGL_CPU0_BYPASS_SDA")
	)
	(segment
		(start 429.411384 -177.916078)
		(end 428.8536 -177.358294)
		(width 0.11684)
		(layer "In2.Cu")
		(net "I3C_SPD_DDRGL_CPU0_BYPASS_SDA")
	)
	(segment
		(start 431.673 -173.944534)
		(end 432.527964 -174.799498)
		(width 0.11684)
		(layer "In2.Cu")
		(net "I3C_SPD_DDRGL_CPU0_BYPASS_SDA")
	)
	(segment
		(start 431.181764 -174.86503)
		(end 430.723548 -175.323246)
		(width 0.11684)
		(layer "In2.Cu")
		(net "I3C_SPD_DDRGL_CPU0_BYPASS_SDA")
	)
	(segment
		(start 431.904648 -175.422814)
		(end 431.346864 -174.86503)
		(width 0.11684)
		(layer "In2.Cu")
		(net "I3C_SPD_DDRGL_CPU0_BYPASS_SDA")
	)
	(segment
		(start 430.100232 -176.111662)
		(end 429.935132 -176.111662)
		(width 0.11684)
		(layer "In2.Cu")
		(net "I3C_SPD_DDRGL_CPU0_BYPASS_SDA")
	)
	(segment
		(start 431.281332 -176.21123)
		(end 430.823116 -176.669446)
		(width 0.11684)
		(layer "In2.Cu")
		(net "I3C_SPD_DDRGL_CPU0_BYPASS_SDA")
	)
	(segment
		(start 429.576484 -177.916078)
		(end 429.411384 -177.916078)
		(width 0.11684)
		(layer "In2.Cu")
		(net "I3C_SPD_DDRGL_CPU0_BYPASS_SDA")
	)
	(segment
		(start 432.069748 -175.422814)
		(end 431.904648 -175.422814)
		(width 0.11684)
		(layer "In2.Cu")
		(net "I3C_SPD_DDRGL_CPU0_BYPASS_SDA")
	)
	(segment
		(start 432.527964 -174.964598)
		(end 432.069748 -175.422814)
		(width 0.11684)
		(layer "In2.Cu")
		(net "I3C_SPD_DDRGL_CPU0_BYPASS_SDA")
	)
	(segment
		(start 428.6885 -177.358294)
		(end 421.85844 -184.188354)
		(width 0.11684)
		(layer "In2.Cu")
		(net "I3C_SPD_DDRGL_CPU0_BYPASS_SDA")
	)
	(segment
		(start 384.180842 -205.144116)
		(end 384.180842 -205.658466)
		(width 0.11684)
		(layer "In2.Cu")
		(net "I3C_SPD_DDRGL_CPU0_BYPASS_SDA")
	)
	(segment
		(start 430.723548 -175.323246)
		(end 430.723548 -175.488346)
		(width 0.11684)
		(layer "In2.Cu")
		(net "I3C_SPD_DDRGL_CPU0_BYPASS_SDA")
	)
	(segment
		(start 430.823116 -176.669446)
		(end 430.658016 -176.669446)
		(width 0.11684)
		(layer "In2.Cu")
		(net "I3C_SPD_DDRGL_CPU0_BYPASS_SDA")
	)
	(segment
		(start 392.8364 -203.32065)
		(end 386.004308 -203.32065)
		(width 0.11684)
		(layer "In2.Cu")
		(net "I3C_SPD_DDRGL_CPU0_BYPASS_SDA")
	)
	(segment
		(start 431.346864 -174.86503)
		(end 431.181764 -174.86503)
		(width 0.11684)
		(layer "In2.Cu")
		(net "I3C_SPD_DDRGL_CPU0_BYPASS_SDA")
	)
	(segment
		(start 401.14601 -197.015862)
		(end 399.141188 -197.015862)
		(width 0.11684)
		(layer "In2.Cu")
		(net "I3C_SPD_DDRGL_CPU0_BYPASS_SDA")
	)
	(segment
		(start 431.673 -166.303452)
		(end 432.425602 -165.55085)
		(width 0.10668)
		(layer "F.Cu")
		(net "I3C_SPD_DDRGL_CPU0_BYPASS_SCL")
	)
	(segment
		(start 432.425602 -165.55085)
		(end 435.102 -165.55085)
		(width 0.10668)
		(layer "F.Cu")
		(net "I3C_SPD_DDRGL_CPU0_BYPASS_SCL")
	)
	(via
		(at 431.673 -166.303452)
		(size 0.508)
		(drill 0.254)
		(layers "F.Cu" "B.Cu")
		(net "I3C_SPD_DDRGL_CPU0_BYPASS_SCL")
	)
	(via
		(at 381.107188 -206.80172)
		(size 0.508)
		(drill 0.254)
		(layers "F.Cu" "B.Cu")
		(net "I3C_SPD_DDRGL_CPU0_BYPASS_SCL")
	)
	(segment
		(start 380.782576 -206.80172)
		(end 381.107188 -206.80172)
		(width 0.10668)
		(layer "B.Cu")
		(net "I3C_SPD_DDRGL_CPU0_BYPASS_SCL")
	)
	(segment
		(start 380.282958 -206.302102)
		(end 380.782576 -206.80172)
		(width 0.10668)
		(layer "B.Cu")
		(net "I3C_SPD_DDRGL_CPU0_BYPASS_SCL")
	)
	(segment
		(start 431.059844 -174.139098)
		(end 421.610028 -183.588914)
		(width 0.11684)
		(layer "In2.Cu")
		(net "I3C_SPD_DDRGL_CPU0_BYPASS_SCL")
	)
	(segment
		(start 413.725106 -183.588914)
		(end 400.897598 -196.416422)
		(width 0.11684)
		(layer "In2.Cu")
		(net "I3C_SPD_DDRGL_CPU0_BYPASS_SCL")
	)
	(segment
		(start 421.610028 -183.588914)
		(end 413.725106 -183.588914)
		(width 0.11684)
		(layer "In2.Cu")
		(net "I3C_SPD_DDRGL_CPU0_BYPASS_SCL")
	)
	(segment
		(start 431.673 -166.303452)
		(end 431.059844 -166.916608)
		(width 0.11684)
		(layer "In2.Cu")
		(net "I3C_SPD_DDRGL_CPU0_BYPASS_SCL")
	)
	(segment
		(start 400.897598 -196.416422)
		(end 398.875504 -196.416422)
		(width 0.11684)
		(layer "In2.Cu")
		(net "I3C_SPD_DDRGL_CPU0_BYPASS_SCL")
	)
	(segment
		(start 392.570716 -202.72121)
		(end 385.669536 -202.72121)
		(width 0.11684)
		(layer "In2.Cu")
		(net "I3C_SPD_DDRGL_CPU0_BYPASS_SCL")
	)
	(segment
		(start 385.669536 -202.72121)
		(end 381.589026 -206.80172)
		(width 0.11684)
		(layer "In2.Cu")
		(net "I3C_SPD_DDRGL_CPU0_BYPASS_SCL")
	)
	(segment
		(start 381.589026 -206.80172)
		(end 381.107188 -206.80172)
		(width 0.11684)
		(layer "In2.Cu")
		(net "I3C_SPD_DDRGL_CPU0_BYPASS_SCL")
	)
	(segment
		(start 398.875504 -196.416422)
		(end 392.570716 -202.72121)
		(width 0.11684)
		(layer "In2.Cu")
		(net "I3C_SPD_DDRGL_CPU0_BYPASS_SCL")
	)
	(segment
		(start 431.059844 -166.916608)
		(end 431.059844 -174.139098)
		(width 0.11684)
		(layer "In2.Cu")
		(net "I3C_SPD_DDRGL_CPU0_BYPASS_SCL")
	)
	(segment
		(start 21.70811 -194.785234)
		(end 22.86381 -194.785234)
		(width 0.10668)
		(layer "F.Cu")
		(net "I3C_SPD_DDRF_CPU1_SCL")
	)
	(via
		(at 22.86381 -194.785234)
		(size 0.4826)
		(drill 0.254)
		(layers "F.Cu" "B.Cu")
		(net "I3C_SPD_DDRF_CPU1_SCL")
	)
	(via
		(at 22.16404 -194.804538)
		(size 0.6604)
		(drill 0.3302)
		(layers "F.Cu" "B.Cu")
		(net "I3C_SPD_DDRF_CPU1_SCL")
	)
	(segment
		(start 22.16404 -194.804538)
		(end 22.183344 -194.785234)
		(width 0.10668)
		(layer "B.Cu")
		(net "I3C_SPD_DDRF_CPU1_SCL")
	)
	(segment
		(start 22.183344 -194.785234)
		(end 22.86381 -194.785234)
		(width 0.10668)
		(layer "B.Cu")
		(net "I3C_SPD_DDRF_CPU1_SCL")
	)
	(segment
		(start 21.319236 -195.012564)
		(end 21.956014 -195.012564)
		(width 0.10668)
		(layer "B.Cu")
		(net "I3C_SPD_DDRF_CPU1_SCL")
	)
	(segment
		(start 21.956014 -195.012564)
		(end 22.16404 -194.804538)
		(width 0.10668)
		(layer "B.Cu")
		(net "I3C_SPD_DDRF_CPU1_SCL")
	)
	(segment
		(start 269.648178 -194.78498)
		(end 270.803878 -194.78498)
		(width 0.10668)
		(layer "F.Cu")
		(net "I3C_SPD_DDRF_CPU0_SCL")
	)
	(via
		(at 270.803878 -194.78498)
		(size 0.4826)
		(drill 0.254)
		(layers "F.Cu" "B.Cu")
		(net "I3C_SPD_DDRF_CPU0_SCL")
	)
	(via
		(at 270.12138 -194.98691)
		(size 0.6604)
		(drill 0.3302)
		(layers "F.Cu" "B.Cu")
		(net "I3C_SPD_DDRF_CPU0_SCL")
	)
	(segment
		(start 270.12138 -194.98691)
		(end 269.385542 -194.98691)
		(width 0.10668)
		(layer "B.Cu")
		(net "I3C_SPD_DDRF_CPU0_SCL")
	)
	(segment
		(start 270.601948 -194.98691)
		(end 270.12138 -194.98691)
		(width 0.10668)
		(layer "B.Cu")
		(net "I3C_SPD_DDRF_CPU0_SCL")
	)
	(segment
		(start 270.803878 -194.78498)
		(end 270.601948 -194.98691)
		(width 0.10668)
		(layer "B.Cu")
		(net "I3C_SPD_DDRF_CPU0_SCL")
	)
	(segment
		(start 269.385542 -194.98691)
		(end 269.292578 -194.893946)
		(width 0.10668)
		(layer "B.Cu")
		(net "I3C_SPD_DDRF_CPU0_SCL")
	)
	(segment
		(start 30.307534 -194.785234)
		(end 30.382464 -194.860164)
		(width 0.10668)
		(layer "F.Cu")
		(net "I3C_SPD_DDRE_CPU1_SCL")
	)
	(segment
		(start 29.252164 -194.785234)
		(end 30.307534 -194.785234)
		(width 0.10668)
		(layer "F.Cu")
		(net "I3C_SPD_DDRE_CPU1_SCL")
	)
	(via
		(at 29.687012 -194.756278)
		(size 0.6604)
		(drill 0.3302)
		(layers "F.Cu" "B.Cu")
		(net "I3C_SPD_DDRE_CPU1_SCL")
	)
	(via
		(at 30.382464 -194.860164)
		(size 0.4826)
		(drill 0.254)
		(layers "F.Cu" "B.Cu")
		(net "I3C_SPD_DDRE_CPU1_SCL")
	)
	(segment
		(start 29.430726 -195.012564)
		(end 29.687012 -194.756278)
		(width 0.10668)
		(layer "B.Cu")
		(net "I3C_SPD_DDRE_CPU1_SCL")
	)
	(segment
		(start 30.278578 -194.756278)
		(end 30.382464 -194.860164)
		(width 0.10668)
		(layer "B.Cu")
		(net "I3C_SPD_DDRE_CPU1_SCL")
	)
	(segment
		(start 29.687012 -194.756278)
		(end 30.278578 -194.756278)
		(width 0.10668)
		(layer "B.Cu")
		(net "I3C_SPD_DDRE_CPU1_SCL")
	)
	(segment
		(start 28.86329 -195.012564)
		(end 29.430726 -195.012564)
		(width 0.10668)
		(layer "B.Cu")
		(net "I3C_SPD_DDRE_CPU1_SCL")
	)
	(segment
		(start 277.192232 -194.78498)
		(end 278.347932 -194.78498)
		(width 0.10668)
		(layer "F.Cu")
		(net "I3C_SPD_DDRE_CPU0_SCL")
	)
	(via
		(at 278.347932 -194.78498)
		(size 0.4826)
		(drill 0.254)
		(layers "F.Cu" "B.Cu")
		(net "I3C_SPD_DDRE_CPU0_SCL")
	)
	(via
		(at 277.651464 -194.657726)
		(size 0.6604)
		(drill 0.3302)
		(layers "F.Cu" "B.Cu")
		(net "I3C_SPD_DDRE_CPU0_SCL")
	)
	(segment
		(start 277.628858 -194.657726)
		(end 277.299674 -194.98691)
		(width 0.10668)
		(layer "B.Cu")
		(net "I3C_SPD_DDRE_CPU0_SCL")
	)
	(segment
		(start 277.721314 -194.587876)
		(end 277.651464 -194.657726)
		(width 0.10668)
		(layer "B.Cu")
		(net "I3C_SPD_DDRE_CPU0_SCL")
	)
	(segment
		(start 278.205692 -194.587876)
		(end 277.721314 -194.587876)
		(width 0.10668)
		(layer "B.Cu")
		(net "I3C_SPD_DDRE_CPU0_SCL")
	)
	(segment
		(start 277.299674 -194.98691)
		(end 276.929596 -194.98691)
		(width 0.10668)
		(layer "B.Cu")
		(net "I3C_SPD_DDRE_CPU0_SCL")
	)
	(segment
		(start 277.651464 -194.657726)
		(end 277.628858 -194.657726)
		(width 0.10668)
		(layer "B.Cu")
		(net "I3C_SPD_DDRE_CPU0_SCL")
	)
	(segment
		(start 278.347932 -194.78498)
		(end 278.347932 -194.730116)
		(width 0.10668)
		(layer "B.Cu")
		(net "I3C_SPD_DDRE_CPU0_SCL")
	)
	(segment
		(start 276.929596 -194.98691)
		(end 276.836632 -194.893946)
		(width 0.10668)
		(layer "B.Cu")
		(net "I3C_SPD_DDRE_CPU0_SCL")
	)
	(segment
		(start 278.347932 -194.730116)
		(end 278.205692 -194.587876)
		(width 0.10668)
		(layer "B.Cu")
		(net "I3C_SPD_DDRE_CPU0_SCL")
	)
	(segment
		(start 36.795964 -194.785234)
		(end 37.951664 -194.785234)
		(width 0.10668)
		(layer "F.Cu")
		(net "I3C_SPD_DDRD_CPU1_SCL")
	)
	(via
		(at 37.951664 -194.785234)
		(size 0.4826)
		(drill 0.254)
		(layers "F.Cu" "B.Cu")
		(net "I3C_SPD_DDRD_CPU1_SCL")
	)
	(via
		(at 37.252402 -194.652138)
		(size 0.6604)
		(drill 0.3302)
		(layers "F.Cu" "B.Cu")
		(net "I3C_SPD_DDRD_CPU1_SCL")
	)
	(segment
		(start 37.252402 -194.652138)
		(end 37.818568 -194.652138)
		(width 0.10668)
		(layer "B.Cu")
		(net "I3C_SPD_DDRD_CPU1_SCL")
	)
	(segment
		(start 37.209476 -194.652138)
		(end 37.252402 -194.652138)
		(width 0.10668)
		(layer "B.Cu")
		(net "I3C_SPD_DDRD_CPU1_SCL")
	)
	(segment
		(start 36.942014 -194.9196)
		(end 37.209476 -194.652138)
		(width 0.10668)
		(layer "B.Cu")
		(net "I3C_SPD_DDRD_CPU1_SCL")
	)
	(segment
		(start 37.818568 -194.652138)
		(end 37.951664 -194.785234)
		(width 0.10668)
		(layer "B.Cu")
		(net "I3C_SPD_DDRD_CPU1_SCL")
	)
	(segment
		(start 36.440618 -194.9196)
		(end 36.942014 -194.9196)
		(width 0.10668)
		(layer "B.Cu")
		(net "I3C_SPD_DDRD_CPU1_SCL")
	)
	(segment
		(start 284.736032 -194.78498)
		(end 285.891732 -194.78498)
		(width 0.10668)
		(layer "F.Cu")
		(net "I3C_SPD_DDRD_CPU0_SCL")
	)
	(via
		(at 285.172912 -194.475354)
		(size 0.6604)
		(drill 0.3302)
		(layers "F.Cu" "B.Cu")
		(net "I3C_SPD_DDRD_CPU0_SCL")
	)
	(via
		(at 285.891732 -194.78498)
		(size 0.4826)
		(drill 0.254)
		(layers "F.Cu" "B.Cu")
		(net "I3C_SPD_DDRD_CPU0_SCL")
	)
	(segment
		(start 285.803086 -194.696334)
		(end 285.447232 -194.696334)
		(width 0.10668)
		(layer "B.Cu")
		(net "I3C_SPD_DDRD_CPU0_SCL")
	)
	(segment
		(start 285.447232 -194.696334)
		(end 285.226252 -194.475354)
		(width 0.10668)
		(layer "B.Cu")
		(net "I3C_SPD_DDRD_CPU0_SCL")
	)
	(segment
		(start 285.891732 -194.78498)
		(end 285.803086 -194.696334)
		(width 0.10668)
		(layer "B.Cu")
		(net "I3C_SPD_DDRD_CPU0_SCL")
	)
	(segment
		(start 285.172912 -194.475354)
		(end 284.91561 -194.475354)
		(width 0.10668)
		(layer "B.Cu")
		(net "I3C_SPD_DDRD_CPU0_SCL")
	)
	(segment
		(start 284.497018 -194.893946)
		(end 284.380686 -194.893946)
		(width 0.10668)
		(layer "B.Cu")
		(net "I3C_SPD_DDRD_CPU0_SCL")
	)
	(segment
		(start 285.226252 -194.475354)
		(end 285.172912 -194.475354)
		(width 0.10668)
		(layer "B.Cu")
		(net "I3C_SPD_DDRD_CPU0_SCL")
	)
	(segment
		(start 284.91561 -194.475354)
		(end 284.497018 -194.893946)
		(width 0.10668)
		(layer "B.Cu")
		(net "I3C_SPD_DDRD_CPU0_SCL")
	)
	(segment
		(start 44.340018 -194.785234)
		(end 45.495718 -194.785234)
		(width 0.10668)
		(layer "F.Cu")
		(net "I3C_SPD_DDRC_CPU1_SCL")
	)
	(via
		(at 44.786804 -194.72021)
		(size 0.6604)
		(drill 0.3302)
		(layers "F.Cu" "B.Cu")
		(net "I3C_SPD_DDRC_CPU1_SCL")
	)
	(via
		(at 45.495718 -194.785234)
		(size 0.4826)
		(drill 0.254)
		(layers "F.Cu" "B.Cu")
		(net "I3C_SPD_DDRC_CPU1_SCL")
	)
	(segment
		(start 43.976798 -194.987164)
		(end 44.002198 -195.012564)
		(width 0.10668)
		(layer "B.Cu")
		(net "I3C_SPD_DDRC_CPU1_SCL")
	)
	(segment
		(start 44.002198 -195.012564)
		(end 44.49445 -195.012564)
		(width 0.10668)
		(layer "B.Cu")
		(net "I3C_SPD_DDRC_CPU1_SCL")
	)
	(segment
		(start 44.49445 -195.012564)
		(end 44.786804 -194.72021)
		(width 0.10668)
		(layer "B.Cu")
		(net "I3C_SPD_DDRC_CPU1_SCL")
	)
	(segment
		(start 44.786804 -194.72021)
		(end 45.430694 -194.72021)
		(width 0.10668)
		(layer "B.Cu")
		(net "I3C_SPD_DDRC_CPU1_SCL")
	)
	(segment
		(start 45.430694 -194.72021)
		(end 45.495718 -194.785234)
		(width 0.10668)
		(layer "B.Cu")
		(net "I3C_SPD_DDRC_CPU1_SCL")
	)
	(segment
		(start 292.280086 -194.78498)
		(end 292.95217 -194.78498)
		(width 0.10668)
		(layer "F.Cu")
		(net "I3C_SPD_DDRC_CPU0_SCL")
	)
	(segment
		(start 292.95217 -194.78498)
		(end 292.968426 -194.768724)
		(width 0.10668)
		(layer "F.Cu")
		(net "I3C_SPD_DDRC_CPU0_SCL")
	)
	(segment
		(start 292.968426 -194.768724)
		(end 293.441628 -194.768724)
		(width 0.10668)
		(layer "F.Cu")
		(net "I3C_SPD_DDRC_CPU0_SCL")
	)
	(via
		(at 293.441628 -194.768724)
		(size 0.508)
		(drill 0.254)
		(layers "F.Cu" "B.Cu")
		(net "I3C_SPD_DDRC_CPU0_SCL")
	)
	(segment
		(start 293.441628 -194.768724)
		(end 292.918642 -194.768724)
		(width 0.10668)
		(layer "B.Cu")
		(net "I3C_SPD_DDRC_CPU0_SCL")
	)
	(segment
		(start 292.79342 -194.893946)
		(end 291.92474 -194.893946)
		(width 0.10668)
		(layer "B.Cu")
		(net "I3C_SPD_DDRC_CPU0_SCL")
	)
	(segment
		(start 292.918642 -194.768724)
		(end 292.79342 -194.893946)
		(width 0.10668)
		(layer "B.Cu")
		(net "I3C_SPD_DDRC_CPU0_SCL")
	)
	(segment
		(start 51.884072 -194.785234)
		(end 53.039772 -194.785234)
		(width 0.10668)
		(layer "F.Cu")
		(net "I3C_SPD_DDRB_CPU1_SCL")
	)
	(via
		(at 53.039772 -194.785234)
		(size 0.508)
		(drill 0.254)
		(layers "F.Cu" "B.Cu")
		(net "I3C_SPD_DDRB_CPU1_SCL")
	)
	(segment
		(start 52.484528 -194.785234)
		(end 53.039772 -194.785234)
		(width 0.10668)
		(layer "B.Cu")
		(net "I3C_SPD_DDRB_CPU1_SCL")
	)
	(segment
		(start 52.350162 -194.9196)
		(end 52.484528 -194.785234)
		(width 0.10668)
		(layer "B.Cu")
		(net "I3C_SPD_DDRB_CPU1_SCL")
	)
	(segment
		(start 51.528472 -194.9196)
		(end 52.350162 -194.9196)
		(width 0.10668)
		(layer "B.Cu")
		(net "I3C_SPD_DDRB_CPU1_SCL")
	)
	(segment
		(start 299.82414 -194.78498)
		(end 300.97984 -194.78498)
		(width 0.10668)
		(layer "F.Cu")
		(net "I3C_SPD_DDRB_CPU0_SCL")
	)
	(via
		(at 300.97984 -194.78498)
		(size 0.508)
		(drill 0.254)
		(layers "F.Cu" "B.Cu")
		(net "I3C_SPD_DDRB_CPU0_SCL")
	)
	(segment
		(start 300.97984 -194.78498)
		(end 300.77791 -194.98691)
		(width 0.10668)
		(layer "B.Cu")
		(net "I3C_SPD_DDRB_CPU0_SCL")
	)
	(segment
		(start 300.77791 -194.98691)
		(end 299.561504 -194.98691)
		(width 0.10668)
		(layer "B.Cu")
		(net "I3C_SPD_DDRB_CPU0_SCL")
	)
	(segment
		(start 299.561504 -194.98691)
		(end 299.46854 -194.893946)
		(width 0.10668)
		(layer "B.Cu")
		(net "I3C_SPD_DDRB_CPU0_SCL")
	)
	(segment
		(start 60.875672 -194.6402)
		(end 60.730638 -194.785234)
		(width 0.10668)
		(layer "F.Cu")
		(net "I3C_SPD_DDRA_CPU1_SCL")
	)
	(segment
		(start 60.730638 -194.785234)
		(end 59.428126 -194.785234)
		(width 0.10668)
		(layer "F.Cu")
		(net "I3C_SPD_DDRA_CPU1_SCL")
	)
	(segment
		(start 61.0108 -194.6402)
		(end 60.875672 -194.6402)
		(width 0.10668)
		(layer "F.Cu")
		(net "I3C_SPD_DDRA_CPU1_SCL")
	)
	(via
		(at 61.0108 -194.6402)
		(size 0.508)
		(drill 0.254)
		(layers "F.Cu" "B.Cu")
		(net "I3C_SPD_DDRA_CPU1_SCL")
	)
	(segment
		(start 61.0108 -194.6402)
		(end 60.959492 -194.6402)
		(width 0.10668)
		(layer "B.Cu")
		(net "I3C_SPD_DDRA_CPU1_SCL")
	)
	(segment
		(start 60.587128 -195.012564)
		(end 59.801252 -195.012564)
		(width 0.10668)
		(layer "B.Cu")
		(net "I3C_SPD_DDRA_CPU1_SCL")
	)
	(segment
		(start 60.959492 -194.6402)
		(end 60.587128 -195.012564)
		(width 0.10668)
		(layer "B.Cu")
		(net "I3C_SPD_DDRA_CPU1_SCL")
	)
	(segment
		(start 307.368194 -194.78498)
		(end 308.523894 -194.78498)
		(width 0.10668)
		(layer "F.Cu")
		(net "I3C_SPD_DDRA_CPU0_SCL")
	)
	(via
		(at 308.523894 -194.78498)
		(size 0.4826)
		(drill 0.254)
		(layers "F.Cu" "B.Cu")
		(net "I3C_SPD_DDRA_CPU0_SCL")
	)
	(segment
		(start 307.74132 -194.98691)
		(end 307.806598 -194.921632)
		(width 0.10668)
		(layer "B.Cu")
		(net "I3C_SPD_DDRA_CPU0_SCL")
	)
	(segment
		(start 308.387242 -194.921632)
		(end 308.523894 -194.78498)
		(width 0.10668)
		(layer "B.Cu")
		(net "I3C_SPD_DDRA_CPU0_SCL")
	)
	(segment
		(start 307.806598 -194.921632)
		(end 308.387242 -194.921632)
		(width 0.10668)
		(layer "B.Cu")
		(net "I3C_SPD_DDRA_CPU0_SCL")
	)
	(segment
		(start 34.265108 -173.55566)
		(end 34.265108 -174.262796)
		(width 0.10668)
		(layer "F.Cu")
		(net "I3C_SPD_DDRAF_CPU1_SDA")
	)
	(via
		(at 43.176698 -195.901564)
		(size 0.508)
		(drill 0.254)
		(layers "F.Cu" "B.Cu")
		(net "I3C_SPD_DDRAF_CPU1_SDA")
	)
	(via
		(at 20.519136 -195.926964)
		(size 0.508)
		(drill 0.254)
		(layers "F.Cu" "B.Cu")
		(net "I3C_SPD_DDRAF_CPU1_SDA")
	)
	(via
		(at 35.640518 -195.8848)
		(size 0.508)
		(drill 0.254)
		(layers "F.Cu" "B.Cu")
		(net "I3C_SPD_DDRAF_CPU1_SDA")
	)
	(via
		(at 50.203354 -195.387214)
		(size 0.508)
		(drill 0.254)
		(layers "F.Cu" "B.Cu")
		(net "I3C_SPD_DDRAF_CPU1_SDA")
	)
	(via
		(at 58.23585 -195.400168)
		(size 0.508)
		(drill 0.254)
		(layers "F.Cu" "B.Cu")
		(net "I3C_SPD_DDRAF_CPU1_SDA")
	)
	(via
		(at 34.265108 -174.262796)
		(size 0.508)
		(drill 0.254)
		(layers "F.Cu" "B.Cu")
		(net "I3C_SPD_DDRAF_CPU1_SDA")
	)
	(via
		(at 28.06319 -195.926964)
		(size 0.508)
		(drill 0.254)
		(layers "F.Cu" "B.Cu")
		(net "I3C_SPD_DDRAF_CPU1_SDA")
	)
	(segment
		(start 58.762646 -195.926964)
		(end 58.23585 -195.400168)
		(width 0.10668)
		(layer "B.Cu")
		(net "I3C_SPD_DDRAF_CPU1_SDA")
	)
	(segment
		(start 59.001152 -195.926964)
		(end 58.762646 -195.926964)
		(width 0.10668)
		(layer "B.Cu")
		(net "I3C_SPD_DDRAF_CPU1_SDA")
	)
	(segment
		(start 50.203354 -195.40982)
		(end 50.720498 -195.926964)
		(width 0.10668)
		(layer "B.Cu")
		(net "I3C_SPD_DDRAF_CPU1_SDA")
	)
	(segment
		(start 50.203354 -195.387214)
		(end 50.203354 -195.40982)
		(width 0.10668)
		(layer "B.Cu")
		(net "I3C_SPD_DDRAF_CPU1_SDA")
	)
	(segment
		(start 50.203354 -195.387214)
		(end 46.069758 -195.387214)
		(width 0.11684)
		(layer "In2.Cu")
		(net "I3C_SPD_DDRAF_CPU1_SDA")
	)
	(segment
		(start 24.545036 -195.216018)
		(end 25.255982 -195.926964)
		(width 0.11684)
		(layer "In2.Cu")
		(net "I3C_SPD_DDRAF_CPU1_SDA")
	)
	(segment
		(start 35.640518 -195.8848)
		(end 36.781994 -195.8848)
		(width 0.11684)
		(layer "In2.Cu")
		(net "I3C_SPD_DDRAF_CPU1_SDA")
	)
	(segment
		(start 20.519136 -195.926964)
		(end 21.74621 -195.926964)
		(width 0.11684)
		(layer "In2.Cu")
		(net "I3C_SPD_DDRAF_CPU1_SDA")
	)
	(segment
		(start 33.055814 -175.47209)
		(end 27.293824 -175.47209)
		(width 0.11684)
		(layer "In2.Cu")
		(net "I3C_SPD_DDRAF_CPU1_SDA")
	)
	(segment
		(start 18.000472 -196.582792)
		(end 19.863308 -196.582792)
		(width 0.11684)
		(layer "In2.Cu")
		(net "I3C_SPD_DDRAF_CPU1_SDA")
	)
	(segment
		(start 50.28438 -195.46824)
		(end 51.778408 -195.46824)
		(width 0.11684)
		(layer "In2.Cu")
		(net "I3C_SPD_DDRAF_CPU1_SDA")
	)
	(segment
		(start 29.831284 -195.926964)
		(end 29.968952 -196.064632)
		(width 0.11684)
		(layer "In2.Cu")
		(net "I3C_SPD_DDRAF_CPU1_SDA")
	)
	(segment
		(start 37.456872 -195.209922)
		(end 38.512496 -195.209922)
		(width 0.11684)
		(layer "In2.Cu")
		(net "I3C_SPD_DDRAF_CPU1_SDA")
	)
	(segment
		(start 29.968952 -196.064632)
		(end 31.367222 -196.064632)
		(width 0.11684)
		(layer "In2.Cu")
		(net "I3C_SPD_DDRAF_CPU1_SDA")
	)
	(segment
		(start 31.367222 -196.064632)
		(end 31.547054 -195.8848)
		(width 0.11684)
		(layer "In2.Cu")
		(net "I3C_SPD_DDRAF_CPU1_SDA")
	)
	(segment
		(start 34.265108 -174.262796)
		(end 33.055814 -175.47209)
		(width 0.11684)
		(layer "In2.Cu")
		(net "I3C_SPD_DDRAF_CPU1_SDA")
	)
	(segment
		(start 21.74621 -195.926964)
		(end 22.457156 -195.216018)
		(width 0.11684)
		(layer "In2.Cu")
		(net "I3C_SPD_DDRAF_CPU1_SDA")
	)
	(segment
		(start 25.255982 -195.926964)
		(end 28.06319 -195.926964)
		(width 0.11684)
		(layer "In2.Cu")
		(net "I3C_SPD_DDRAF_CPU1_SDA")
	)
	(segment
		(start 55.046626 -195.292472)
		(end 58.128154 -195.292472)
		(width 0.11684)
		(layer "In2.Cu")
		(net "I3C_SPD_DDRAF_CPU1_SDA")
	)
	(segment
		(start 44.561506 -195.209922)
		(end 43.869864 -195.901564)
		(width 0.11684)
		(layer "In2.Cu")
		(net "I3C_SPD_DDRAF_CPU1_SDA")
	)
	(segment
		(start 14.8971 -193.47942)
		(end 18.000472 -196.582792)
		(width 0.11684)
		(layer "In2.Cu")
		(net "I3C_SPD_DDRAF_CPU1_SDA")
	)
	(segment
		(start 39.204138 -195.901564)
		(end 43.176698 -195.901564)
		(width 0.11684)
		(layer "In2.Cu")
		(net "I3C_SPD_DDRAF_CPU1_SDA")
	)
	(segment
		(start 19.863308 -196.582792)
		(end 20.519136 -195.926964)
		(width 0.11684)
		(layer "In2.Cu")
		(net "I3C_SPD_DDRAF_CPU1_SDA")
	)
	(segment
		(start 22.457156 -195.216018)
		(end 24.545036 -195.216018)
		(width 0.11684)
		(layer "In2.Cu")
		(net "I3C_SPD_DDRAF_CPU1_SDA")
	)
	(segment
		(start 43.869864 -195.901564)
		(end 43.176698 -195.901564)
		(width 0.11684)
		(layer "In2.Cu")
		(net "I3C_SPD_DDRAF_CPU1_SDA")
	)
	(segment
		(start 38.512496 -195.209922)
		(end 39.204138 -195.901564)
		(width 0.11684)
		(layer "In2.Cu")
		(net "I3C_SPD_DDRAF_CPU1_SDA")
	)
	(segment
		(start 45.892466 -195.209922)
		(end 44.561506 -195.209922)
		(width 0.11684)
		(layer "In2.Cu")
		(net "I3C_SPD_DDRAF_CPU1_SDA")
	)
	(segment
		(start 36.781994 -195.8848)
		(end 37.456872 -195.209922)
		(width 0.11684)
		(layer "In2.Cu")
		(net "I3C_SPD_DDRAF_CPU1_SDA")
	)
	(segment
		(start 27.293824 -175.47209)
		(end 16.56715 -186.198764)
		(width 0.11684)
		(layer "In2.Cu")
		(net "I3C_SPD_DDRAF_CPU1_SDA")
	)
	(segment
		(start 58.128154 -195.292472)
		(end 58.23585 -195.400168)
		(width 0.11684)
		(layer "In2.Cu")
		(net "I3C_SPD_DDRAF_CPU1_SDA")
	)
	(segment
		(start 14.8971 -190.23076)
		(end 14.8971 -193.47942)
		(width 0.11684)
		(layer "In2.Cu")
		(net "I3C_SPD_DDRAF_CPU1_SDA")
	)
	(segment
		(start 51.778408 -195.46824)
		(end 52.033678 -195.21297)
		(width 0.11684)
		(layer "In2.Cu")
		(net "I3C_SPD_DDRAF_CPU1_SDA")
	)
	(segment
		(start 54.967124 -195.21297)
		(end 55.046626 -195.292472)
		(width 0.11684)
		(layer "In2.Cu")
		(net "I3C_SPD_DDRAF_CPU1_SDA")
	)
	(segment
		(start 16.56715 -186.198764)
		(end 14.8971 -190.23076)
		(width 0.11684)
		(layer "In2.Cu")
		(net "I3C_SPD_DDRAF_CPU1_SDA")
	)
	(segment
		(start 31.547054 -195.8848)
		(end 35.640518 -195.8848)
		(width 0.11684)
		(layer "In2.Cu")
		(net "I3C_SPD_DDRAF_CPU1_SDA")
	)
	(segment
		(start 50.203354 -195.387214)
		(end 50.28438 -195.46824)
		(width 0.11684)
		(layer "In2.Cu")
		(net "I3C_SPD_DDRAF_CPU1_SDA")
	)
	(segment
		(start 28.06319 -195.926964)
		(end 29.831284 -195.926964)
		(width 0.11684)
		(layer "In2.Cu")
		(net "I3C_SPD_DDRAF_CPU1_SDA")
	)
	(segment
		(start 46.069758 -195.387214)
		(end 45.892466 -195.209922)
		(width 0.11684)
		(layer "In2.Cu")
		(net "I3C_SPD_DDRAF_CPU1_SDA")
	)
	(segment
		(start 52.033678 -195.21297)
		(end 54.967124 -195.21297)
		(width 0.11684)
		(layer "In2.Cu")
		(net "I3C_SPD_DDRAF_CPU1_SDA")
	)
	(segment
		(start 34.265108 -170.50766)
		(end 34.265108 -169.800524)
		(width 0.10668)
		(layer "F.Cu")
		(net "I3C_SPD_DDRAF_CPU1_SCL")
	)
	(via
		(at 35.640518 -194.9196)
		(size 0.508)
		(drill 0.254)
		(layers "F.Cu" "B.Cu")
		(net "I3C_SPD_DDRAF_CPU1_SCL")
	)
	(via
		(at 20.55241 -194.9196)
		(size 0.508)
		(drill 0.254)
		(layers "F.Cu" "B.Cu")
		(net "I3C_SPD_DDRAF_CPU1_SCL")
	)
	(via
		(at 34.265108 -169.800524)
		(size 0.508)
		(drill 0.254)
		(layers "F.Cu" "B.Cu")
		(net "I3C_SPD_DDRAF_CPU1_SCL")
	)
	(via
		(at 43.176698 -194.987164)
		(size 0.508)
		(drill 0.254)
		(layers "F.Cu" "B.Cu")
		(net "I3C_SPD_DDRAF_CPU1_SCL")
	)
	(via
		(at 58.232802 -194.529202)
		(size 0.508)
		(drill 0.254)
		(layers "F.Cu" "B.Cu")
		(net "I3C_SPD_DDRAF_CPU1_SCL")
	)
	(via
		(at 28.096464 -194.9196)
		(size 0.508)
		(drill 0.254)
		(layers "F.Cu" "B.Cu")
		(net "I3C_SPD_DDRAF_CPU1_SCL")
	)
	(via
		(at 50.728372 -194.9196)
		(size 0.508)
		(drill 0.254)
		(layers "F.Cu" "B.Cu")
		(net "I3C_SPD_DDRAF_CPU1_SCL")
	)
	(segment
		(start 20.519136 -195.012564)
		(end 20.55241 -194.97929)
		(width 0.10668)
		(layer "B.Cu")
		(net "I3C_SPD_DDRAF_CPU1_SCL")
	)
	(segment
		(start 58.232802 -194.529202)
		(end 58.716164 -195.012564)
		(width 0.10668)
		(layer "B.Cu")
		(net "I3C_SPD_DDRAF_CPU1_SCL")
	)
	(segment
		(start 28.096464 -194.97929)
		(end 28.096464 -194.9196)
		(width 0.10668)
		(layer "B.Cu")
		(net "I3C_SPD_DDRAF_CPU1_SCL")
	)
	(segment
		(start 58.716164 -195.012564)
		(end 59.001152 -195.012564)
		(width 0.10668)
		(layer "B.Cu")
		(net "I3C_SPD_DDRAF_CPU1_SCL")
	)
	(segment
		(start 20.55241 -194.97929)
		(end 20.55241 -194.9196)
		(width 0.10668)
		(layer "B.Cu")
		(net "I3C_SPD_DDRAF_CPU1_SCL")
	)
	(segment
		(start 28.06319 -195.012564)
		(end 28.096464 -194.97929)
		(width 0.10668)
		(layer "B.Cu")
		(net "I3C_SPD_DDRAF_CPU1_SCL")
	)
	(segment
		(start 29.488638 -194.34302)
		(end 32.286702 -194.34302)
		(width 0.11684)
		(layer "In2.Cu")
		(net "I3C_SPD_DDRAF_CPU1_SCL")
	)
	(segment
		(start 32.403034 -194.459352)
		(end 35.18027 -194.459352)
		(width 0.11684)
		(layer "In2.Cu")
		(net "I3C_SPD_DDRAF_CPU1_SCL")
	)
	(segment
		(start 18.26133 -195.918836)
		(end 19.19859 -195.918836)
		(width 0.11684)
		(layer "In2.Cu")
		(net "I3C_SPD_DDRAF_CPU1_SCL")
	)
	(segment
		(start 15.531084 -190.360554)
		(end 15.531084 -193.18859)
		(width 0.11684)
		(layer "In2.Cu")
		(net "I3C_SPD_DDRAF_CPU1_SCL")
	)
	(segment
		(start 32.286702 -194.34302)
		(end 32.403034 -194.459352)
		(width 0.11684)
		(layer "In2.Cu")
		(net "I3C_SPD_DDRAF_CPU1_SCL")
	)
	(segment
		(start 24.943308 -194.33794)
		(end 21.13407 -194.33794)
		(width 0.11684)
		(layer "In2.Cu")
		(net "I3C_SPD_DDRAF_CPU1_SCL")
	)
	(segment
		(start 47.681642 -194.33794)
		(end 43.825922 -194.33794)
		(width 0.11684)
		(layer "In2.Cu")
		(net "I3C_SPD_DDRAF_CPU1_SCL")
	)
	(segment
		(start 34.859722 -175.18507)
		(end 33.908746 -176.136046)
		(width 0.11684)
		(layer "In2.Cu")
		(net "I3C_SPD_DDRAF_CPU1_SCL")
	)
	(segment
		(start 25.279604 -194.477132)
		(end 24.943308 -194.33794)
		(width 0.11684)
		(layer "In2.Cu")
		(net "I3C_SPD_DDRAF_CPU1_SCL")
	)
	(segment
		(start 50.273204 -194.464432)
		(end 47.808134 -194.464432)
		(width 0.11684)
		(layer "In2.Cu")
		(net "I3C_SPD_DDRAF_CPU1_SCL")
	)
	(segment
		(start 36.222178 -194.33794)
		(end 35.640518 -194.9196)
		(width 0.11684)
		(layer "In2.Cu")
		(net "I3C_SPD_DDRAF_CPU1_SCL")
	)
	(segment
		(start 51.310032 -194.33794)
		(end 50.728372 -194.9196)
		(width 0.11684)
		(layer "In2.Cu")
		(net "I3C_SPD_DDRAF_CPU1_SCL")
	)
	(segment
		(start 43.825922 -194.33794)
		(end 43.176698 -194.987164)
		(width 0.11684)
		(layer "In2.Cu")
		(net "I3C_SPD_DDRAF_CPU1_SCL")
	)
	(segment
		(start 57.521602 -194.529202)
		(end 57.427876 -194.435476)
		(width 0.11684)
		(layer "In2.Cu")
		(net "I3C_SPD_DDRAF_CPU1_SCL")
	)
	(segment
		(start 27.02814 -194.477132)
		(end 25.279604 -194.477132)
		(width 0.11684)
		(layer "In2.Cu")
		(net "I3C_SPD_DDRAF_CPU1_SCL")
	)
	(segment
		(start 15.531084 -193.18859)
		(end 18.26133 -195.918836)
		(width 0.11684)
		(layer "In2.Cu")
		(net "I3C_SPD_DDRAF_CPU1_SCL")
	)
	(segment
		(start 58.232802 -194.529202)
		(end 57.521602 -194.529202)
		(width 0.11684)
		(layer "In2.Cu")
		(net "I3C_SPD_DDRAF_CPU1_SCL")
	)
	(segment
		(start 28.096464 -194.9196)
		(end 28.160472 -194.9196)
		(width 0.11684)
		(layer "In2.Cu")
		(net "I3C_SPD_DDRAF_CPU1_SCL")
	)
	(segment
		(start 17.077436 -186.627516)
		(end 15.531084 -190.360554)
		(width 0.11684)
		(layer "In2.Cu")
		(net "I3C_SPD_DDRAF_CPU1_SCL")
	)
	(segment
		(start 39.647622 -194.33794)
		(end 36.222178 -194.33794)
		(width 0.11684)
		(layer "In2.Cu")
		(net "I3C_SPD_DDRAF_CPU1_SCL")
	)
	(segment
		(start 19.19859 -195.918836)
		(end 20.197826 -194.9196)
		(width 0.11684)
		(layer "In2.Cu")
		(net "I3C_SPD_DDRAF_CPU1_SCL")
	)
	(segment
		(start 57.427876 -194.435476)
		(end 54.774338 -194.435476)
		(width 0.11684)
		(layer "In2.Cu")
		(net "I3C_SPD_DDRAF_CPU1_SCL")
	)
	(segment
		(start 34.265108 -169.800524)
		(end 34.859722 -170.395138)
		(width 0.11684)
		(layer "In2.Cu")
		(net "I3C_SPD_DDRAF_CPU1_SCL")
	)
	(segment
		(start 42.664126 -194.474592)
		(end 39.784274 -194.474592)
		(width 0.11684)
		(layer "In2.Cu")
		(net "I3C_SPD_DDRAF_CPU1_SCL")
	)
	(segment
		(start 54.676802 -194.33794)
		(end 51.310032 -194.33794)
		(width 0.11684)
		(layer "In2.Cu")
		(net "I3C_SPD_DDRAF_CPU1_SCL")
	)
	(segment
		(start 43.176698 -194.987164)
		(end 42.664126 -194.474592)
		(width 0.11684)
		(layer "In2.Cu")
		(net "I3C_SPD_DDRAF_CPU1_SCL")
	)
	(segment
		(start 39.784274 -194.474592)
		(end 39.647622 -194.33794)
		(width 0.11684)
		(layer "In2.Cu")
		(net "I3C_SPD_DDRAF_CPU1_SCL")
	)
	(segment
		(start 54.774338 -194.435476)
		(end 54.676802 -194.33794)
		(width 0.11684)
		(layer "In2.Cu")
		(net "I3C_SPD_DDRAF_CPU1_SCL")
	)
	(segment
		(start 50.728372 -194.9196)
		(end 50.273204 -194.464432)
		(width 0.11684)
		(layer "In2.Cu")
		(net "I3C_SPD_DDRAF_CPU1_SCL")
	)
	(segment
		(start 33.908746 -176.136046)
		(end 27.568906 -176.136046)
		(width 0.11684)
		(layer "In2.Cu")
		(net "I3C_SPD_DDRAF_CPU1_SCL")
	)
	(segment
		(start 21.13407 -194.33794)
		(end 20.55241 -194.9196)
		(width 0.11684)
		(layer "In2.Cu")
		(net "I3C_SPD_DDRAF_CPU1_SCL")
	)
	(segment
		(start 34.859722 -170.395138)
		(end 34.859722 -175.18507)
		(width 0.11684)
		(layer "In2.Cu")
		(net "I3C_SPD_DDRAF_CPU1_SCL")
	)
	(segment
		(start 27.568906 -176.136046)
		(end 17.077436 -186.627516)
		(width 0.11684)
		(layer "In2.Cu")
		(net "I3C_SPD_DDRAF_CPU1_SCL")
	)
	(segment
		(start 28.160472 -194.9196)
		(end 29.488638 -194.34302)
		(width 0.11684)
		(layer "In2.Cu")
		(net "I3C_SPD_DDRAF_CPU1_SCL")
	)
	(segment
		(start 35.18027 -194.459352)
		(end 35.640518 -194.9196)
		(width 0.11684)
		(layer "In2.Cu")
		(net "I3C_SPD_DDRAF_CPU1_SCL")
	)
	(segment
		(start 27.972512 -194.9196)
		(end 27.02814 -194.477132)
		(width 0.11684)
		(layer "In2.Cu")
		(net "I3C_SPD_DDRAF_CPU1_SCL")
	)
	(segment
		(start 47.808134 -194.464432)
		(end 47.681642 -194.33794)
		(width 0.11684)
		(layer "In2.Cu")
		(net "I3C_SPD_DDRAF_CPU1_SCL")
	)
	(segment
		(start 20.197826 -194.9196)
		(end 20.55241 -194.9196)
		(width 0.11684)
		(layer "In2.Cu")
		(net "I3C_SPD_DDRAF_CPU1_SCL")
	)
	(segment
		(start 28.096464 -194.9196)
		(end 27.972512 -194.9196)
		(width 0.11684)
		(layer "In2.Cu")
		(net "I3C_SPD_DDRAF_CPU1_SCL")
	)
	(segment
		(start 38.14699 -172.230542)
		(end 37.332666 -172.230542)
		(width 0.10668)
		(layer "F.Cu")
		(net "I3C_SPD_DDRAF_CPU1_LVC1_SDA")
	)
	(segment
		(start 36.931092 -172.480986)
		(end 36.563046 -172.11294)
		(width 0.10668)
		(layer "F.Cu")
		(net "I3C_SPD_DDRAF_CPU1_LVC1_SDA")
	)
	(segment
		(start 36.160202 -172.515784)
		(end 35.089084 -172.515784)
		(width 0.10668)
		(layer "F.Cu")
		(net "I3C_SPD_DDRAF_CPU1_LVC1_SDA")
	)
	(segment
		(start 36.563046 -172.11294)
		(end 36.160202 -172.515784)
		(width 0.10668)
		(layer "F.Cu")
		(net "I3C_SPD_DDRAF_CPU1_LVC1_SDA")
	)
	(segment
		(start 37.082222 -172.480986)
		(end 36.931092 -172.480986)
		(width 0.10668)
		(layer "F.Cu")
		(net "I3C_SPD_DDRAF_CPU1_LVC1_SDA")
	)
	(segment
		(start 35.089084 -172.515784)
		(end 35.065208 -172.53966)
		(width 0.10668)
		(layer "F.Cu")
		(net "I3C_SPD_DDRAF_CPU1_LVC1_SDA")
	)
	(segment
		(start 35.065208 -173.55566)
		(end 35.065208 -172.53966)
		(width 0.10668)
		(layer "F.Cu")
		(net "I3C_SPD_DDRAF_CPU1_LVC1_SDA")
	)
	(segment
		(start 37.332666 -172.230542)
		(end 37.082222 -172.480986)
		(width 0.10668)
		(layer "F.Cu")
		(net "I3C_SPD_DDRAF_CPU1_LVC1_SDA")
	)
	(via
		(at 36.563046 -172.11294)
		(size 0.762)
		(drill 0.381)
		(layers "F.Cu" "B.Cu")
		(net "I3C_SPD_DDRAF_CPU1_LVC1_SDA")
	)
	(segment
		(start 35.36696 -171.52366)
		(end 35.065208 -171.52366)
		(width 0.10668)
		(layer "F.Cu")
		(net "I3C_SPD_DDRAF_CPU1_LVC1_SCL")
	)
	(segment
		(start 36.105338 -170.785282)
		(end 35.36696 -171.52366)
		(width 0.10668)
		(layer "F.Cu")
		(net "I3C_SPD_DDRAF_CPU1_LVC1_SCL")
	)
	(segment
		(start 36.486846 -170.785282)
		(end 36.105338 -170.785282)
		(width 0.10668)
		(layer "F.Cu")
		(net "I3C_SPD_DDRAF_CPU1_LVC1_SCL")
	)
	(segment
		(start 36.866576 -170.785282)
		(end 36.486846 -170.785282)
		(width 0.10668)
		(layer "F.Cu")
		(net "I3C_SPD_DDRAF_CPU1_LVC1_SCL")
	)
	(segment
		(start 37.811964 -171.73067)
		(end 36.866576 -170.785282)
		(width 0.10668)
		(layer "F.Cu")
		(net "I3C_SPD_DDRAF_CPU1_LVC1_SCL")
	)
	(segment
		(start 35.065208 -171.52366)
		(end 35.065208 -170.50766)
		(width 0.10668)
		(layer "F.Cu")
		(net "I3C_SPD_DDRAF_CPU1_LVC1_SCL")
	)
	(segment
		(start 38.14699 -171.73067)
		(end 37.811964 -171.73067)
		(width 0.10668)
		(layer "F.Cu")
		(net "I3C_SPD_DDRAF_CPU1_LVC1_SCL")
	)
	(via
		(at 36.486846 -170.785282)
		(size 0.762)
		(drill 0.381)
		(layers "F.Cu" "B.Cu")
		(net "I3C_SPD_DDRAF_CPU1_LVC1_SCL")
	)
	(segment
		(start 43.87215 -171.831)
		(end 43.87215 -172.52442)
		(width 0.10668)
		(layer "F.Cu")
		(net "I3C_SPD_DDRAF_CPU1_BYPASS_SDA")
	)
	(segment
		(start 33.465008 -173.55566)
		(end 33.465008 -174.262796)
		(width 0.10668)
		(layer "F.Cu")
		(net "I3C_SPD_DDRAF_CPU1_BYPASS_SDA")
	)
	(via
		(at 43.87215 -172.52442)
		(size 0.508)
		(drill 0.254)
		(layers "F.Cu" "B.Cu")
		(net "I3C_SPD_DDRAF_CPU1_BYPASS_SDA")
	)
	(via
		(at 33.465008 -174.262796)
		(size 0.508)
		(drill 0.254)
		(layers "F.Cu" "B.Cu")
		(net "I3C_SPD_DDRAF_CPU1_BYPASS_SDA")
	)
	(segment
		(start 34.203386 -175.001174)
		(end 33.465008 -174.262796)
		(width 0.11684)
		(layer "In6.Cu")
		(net "I3C_SPD_DDRAF_CPU1_BYPASS_SDA")
	)
	(segment
		(start 41.427908 -175.001174)
		(end 34.203386 -175.001174)
		(width 0.11684)
		(layer "In6.Cu")
		(net "I3C_SPD_DDRAF_CPU1_BYPASS_SDA")
	)
	(segment
		(start 43.87215 -172.556932)
		(end 41.427908 -175.001174)
		(width 0.11684)
		(layer "In6.Cu")
		(net "I3C_SPD_DDRAF_CPU1_BYPASS_SDA")
	)
	(segment
		(start 43.87215 -172.52442)
		(end 43.87215 -172.556932)
		(width 0.11684)
		(layer "In6.Cu")
		(net "I3C_SPD_DDRAF_CPU1_BYPASS_SDA")
	)
	(segment
		(start 33.465008 -170.50766)
		(end 33.465008 -169.800524)
		(width 0.10668)
		(layer "F.Cu")
		(net "I3C_SPD_DDRAF_CPU1_BYPASS_SCL")
	)
	(segment
		(start 43.87215 -170.307)
		(end 43.87215 -169.646092)
		(width 0.10668)
		(layer "F.Cu")
		(net "I3C_SPD_DDRAF_CPU1_BYPASS_SCL")
	)
	(via
		(at 43.87215 -169.646092)
		(size 0.508)
		(drill 0.254)
		(layers "F.Cu" "B.Cu")
		(net "I3C_SPD_DDRAF_CPU1_BYPASS_SCL")
	)
	(via
		(at 33.465008 -169.800524)
		(size 0.508)
		(drill 0.254)
		(layers "F.Cu" "B.Cu")
		(net "I3C_SPD_DDRAF_CPU1_BYPASS_SCL")
	)
	(segment
		(start 43.87215 -169.646092)
		(end 42.332656 -168.106598)
		(width 0.11684)
		(layer "In6.Cu")
		(net "I3C_SPD_DDRAF_CPU1_BYPASS_SCL")
	)
	(segment
		(start 35.158934 -168.106598)
		(end 33.465008 -169.800524)
		(width 0.11684)
		(layer "In6.Cu")
		(net "I3C_SPD_DDRAF_CPU1_BYPASS_SCL")
	)
	(segment
		(start 42.332656 -168.106598)
		(end 35.158934 -168.106598)
		(width 0.11684)
		(layer "In6.Cu")
		(net "I3C_SPD_DDRAF_CPU1_BYPASS_SCL")
	)
	(segment
		(start 264.094722 -191.705992)
		(end 265.467846 -190.332868)
		(width 0.10668)
		(layer "F.Cu")
		(net "I3C_SPD_DDRAF_CPU0_SDA")
	)
	(segment
		(start 270.069056 -190.332868)
		(end 272.863056 -187.538868)
		(width 0.10668)
		(layer "F.Cu")
		(net "I3C_SPD_DDRAF_CPU0_SDA")
	)
	(segment
		(start 263.930384 -196.781674)
		(end 263.930384 -192.103248)
		(width 0.10668)
		(layer "F.Cu")
		(net "I3C_SPD_DDRAF_CPU0_SDA")
	)
	(segment
		(start 272.863056 -187.538868)
		(end 272.863056 -171.00677)
		(width 0.10668)
		(layer "F.Cu")
		(net "I3C_SPD_DDRAF_CPU0_SDA")
	)
	(segment
		(start 272.863056 -171.00677)
		(end 277.072598 -166.797228)
		(width 0.10668)
		(layer "F.Cu")
		(net "I3C_SPD_DDRAF_CPU0_SDA")
	)
	(segment
		(start 263.930384 -192.103248)
		(end 264.094722 -191.705992)
		(width 0.10668)
		(layer "F.Cu")
		(net "I3C_SPD_DDRAF_CPU0_SDA")
	)
	(segment
		(start 290.117276 -151.20366)
		(end 296.261282 -151.20366)
		(width 0.10668)
		(layer "F.Cu")
		(net "I3C_SPD_DDRAF_CPU0_SDA")
	)
	(segment
		(start 277.072598 -166.797228)
		(end 277.072598 -164.248338)
		(width 0.10668)
		(layer "F.Cu")
		(net "I3C_SPD_DDRAF_CPU0_SDA")
	)
	(segment
		(start 265.467846 -190.332868)
		(end 270.069056 -190.332868)
		(width 0.10668)
		(layer "F.Cu")
		(net "I3C_SPD_DDRAF_CPU0_SDA")
	)
	(segment
		(start 263.872218 -196.83984)
		(end 263.930384 -196.781674)
		(width 0.10668)
		(layer "F.Cu")
		(net "I3C_SPD_DDRAF_CPU0_SDA")
	)
	(segment
		(start 277.072598 -164.248338)
		(end 290.117276 -151.20366)
		(width 0.10668)
		(layer "F.Cu")
		(net "I3C_SPD_DDRAF_CPU0_SDA")
	)
	(segment
		(start 296.261282 -151.20366)
		(end 296.926 -150.538942)
		(width 0.10668)
		(layer "F.Cu")
		(net "I3C_SPD_DDRAF_CPU0_SDA")
	)
	(via
		(at 306.183792 -195.558156)
		(size 0.4826)
		(drill 0.254)
		(layers "F.Cu" "B.Cu")
		(net "I3C_SPD_DDRAF_CPU0_SDA")
	)
	(via
		(at 263.872218 -196.83984)
		(size 0.508)
		(drill 0.254)
		(layers "F.Cu" "B.Cu")
		(net "I3C_SPD_DDRAF_CPU0_SDA")
	)
	(via
		(at 291.12464 -195.859146)
		(size 0.508)
		(drill 0.254)
		(layers "F.Cu" "B.Cu")
		(net "I3C_SPD_DDRAF_CPU0_SDA")
	)
	(via
		(at 276.036532 -195.859146)
		(size 0.508)
		(drill 0.254)
		(layers "F.Cu" "B.Cu")
		(net "I3C_SPD_DDRAF_CPU0_SDA")
	)
	(via
		(at 268.492478 -195.859146)
		(size 0.508)
		(drill 0.254)
		(layers "F.Cu" "B.Cu")
		(net "I3C_SPD_DDRAF_CPU0_SDA")
	)
	(via
		(at 298.66844 -195.859146)
		(size 0.508)
		(drill 0.254)
		(layers "F.Cu" "B.Cu")
		(net "I3C_SPD_DDRAF_CPU0_SDA")
	)
	(via
		(at 283.580586 -195.859146)
		(size 0.508)
		(drill 0.254)
		(layers "F.Cu" "B.Cu")
		(net "I3C_SPD_DDRAF_CPU0_SDA")
	)
	(segment
		(start 306.577746 -195.95211)
		(end 306.183792 -195.558156)
		(width 0.10668)
		(layer "B.Cu")
		(net "I3C_SPD_DDRAF_CPU0_SDA")
	)
	(segment
		(start 306.94122 -195.95211)
		(end 306.577746 -195.95211)
		(width 0.10668)
		(layer "B.Cu")
		(net "I3C_SPD_DDRAF_CPU0_SDA")
	)
	(segment
		(start 285.593282 -195.209668)
		(end 284.943804 -195.859146)
		(width 0.11684)
		(layer "In11.Cu")
		(net "I3C_SPD_DDRAF_CPU0_SDA")
	)
	(segment
		(start 283.387546 -196.052186)
		(end 277.828248 -196.052186)
		(width 0.11684)
		(layer "In11.Cu")
		(net "I3C_SPD_DDRAF_CPU0_SDA")
	)
	(segment
		(start 283.580586 -195.859146)
		(end 283.387546 -196.052186)
		(width 0.11684)
		(layer "In11.Cu")
		(net "I3C_SPD_DDRAF_CPU0_SDA")
	)
	(segment
		(start 305.698652 -196.043296)
		(end 300.583346 -196.043296)
		(width 0.11684)
		(layer "In11.Cu")
		(net "I3C_SPD_DDRAF_CPU0_SDA")
	)
	(segment
		(start 270.56969 -195.209922)
		(end 269.920466 -195.859146)
		(width 0.11684)
		(layer "In11.Cu")
		(net "I3C_SPD_DDRAF_CPU0_SDA")
	)
	(segment
		(start 291.12464 -195.859146)
		(end 290.853622 -195.588128)
		(width 0.11684)
		(layer "In11.Cu")
		(net "I3C_SPD_DDRAF_CPU0_SDA")
	)
	(segment
		(start 286.753046 -195.588128)
		(end 286.374586 -195.209668)
		(width 0.11684)
		(layer "In11.Cu")
		(net "I3C_SPD_DDRAF_CPU0_SDA")
	)
	(segment
		(start 268.492478 -195.859146)
		(end 268.128496 -196.223128)
		(width 0.11684)
		(layer "In11.Cu")
		(net "I3C_SPD_DDRAF_CPU0_SDA")
	)
	(segment
		(start 300.583346 -196.043296)
		(end 300.399196 -195.859146)
		(width 0.11684)
		(layer "In11.Cu")
		(net "I3C_SPD_DDRAF_CPU0_SDA")
	)
	(segment
		(start 277.635208 -195.859146)
		(end 276.036532 -195.859146)
		(width 0.11684)
		(layer "In11.Cu")
		(net "I3C_SPD_DDRAF_CPU0_SDA")
	)
	(segment
		(start 295.452038 -195.411344)
		(end 295.25976 -195.219066)
		(width 0.11684)
		(layer "In11.Cu")
		(net "I3C_SPD_DDRAF_CPU0_SDA")
	)
	(segment
		(start 271.308576 -195.209922)
		(end 270.56969 -195.209922)
		(width 0.11684)
		(layer "In11.Cu")
		(net "I3C_SPD_DDRAF_CPU0_SDA")
	)
	(segment
		(start 277.828248 -196.052186)
		(end 277.635208 -195.859146)
		(width 0.11684)
		(layer "In11.Cu")
		(net "I3C_SPD_DDRAF_CPU0_SDA")
	)
	(segment
		(start 271.503648 -195.404994)
		(end 271.308576 -195.209922)
		(width 0.11684)
		(layer "In11.Cu")
		(net "I3C_SPD_DDRAF_CPU0_SDA")
	)
	(segment
		(start 300.399196 -195.859146)
		(end 298.66844 -195.859146)
		(width 0.11684)
		(layer "In11.Cu")
		(net "I3C_SPD_DDRAF_CPU0_SDA")
	)
	(segment
		(start 268.128496 -196.223128)
		(end 265.36269 -196.223128)
		(width 0.11684)
		(layer "In11.Cu")
		(net "I3C_SPD_DDRAF_CPU0_SDA")
	)
	(segment
		(start 286.374586 -195.209668)
		(end 285.593282 -195.209668)
		(width 0.11684)
		(layer "In11.Cu")
		(net "I3C_SPD_DDRAF_CPU0_SDA")
	)
	(segment
		(start 306.183792 -195.558156)
		(end 305.698652 -196.043296)
		(width 0.11684)
		(layer "In11.Cu")
		(net "I3C_SPD_DDRAF_CPU0_SDA")
	)
	(segment
		(start 292.434264 -195.859146)
		(end 291.12464 -195.859146)
		(width 0.11684)
		(layer "In11.Cu")
		(net "I3C_SPD_DDRAF_CPU0_SDA")
	)
	(segment
		(start 265.36269 -196.223128)
		(end 264.745978 -196.83984)
		(width 0.11684)
		(layer "In11.Cu")
		(net "I3C_SPD_DDRAF_CPU0_SDA")
	)
	(segment
		(start 275.58238 -195.404994)
		(end 271.503648 -195.404994)
		(width 0.11684)
		(layer "In11.Cu")
		(net "I3C_SPD_DDRAF_CPU0_SDA")
	)
	(segment
		(start 298.66844 -195.859146)
		(end 298.220638 -195.411344)
		(width 0.11684)
		(layer "In11.Cu")
		(net "I3C_SPD_DDRAF_CPU0_SDA")
	)
	(segment
		(start 284.943804 -195.859146)
		(end 283.580586 -195.859146)
		(width 0.11684)
		(layer "In11.Cu")
		(net "I3C_SPD_DDRAF_CPU0_SDA")
	)
	(segment
		(start 290.853622 -195.588128)
		(end 286.753046 -195.588128)
		(width 0.11684)
		(layer "In11.Cu")
		(net "I3C_SPD_DDRAF_CPU0_SDA")
	)
	(segment
		(start 293.074344 -195.219066)
		(end 292.434264 -195.859146)
		(width 0.11684)
		(layer "In11.Cu")
		(net "I3C_SPD_DDRAF_CPU0_SDA")
	)
	(segment
		(start 298.220638 -195.411344)
		(end 295.452038 -195.411344)
		(width 0.11684)
		(layer "In11.Cu")
		(net "I3C_SPD_DDRAF_CPU0_SDA")
	)
	(segment
		(start 276.036532 -195.859146)
		(end 275.58238 -195.404994)
		(width 0.11684)
		(layer "In11.Cu")
		(net "I3C_SPD_DDRAF_CPU0_SDA")
	)
	(segment
		(start 295.25976 -195.219066)
		(end 293.074344 -195.219066)
		(width 0.11684)
		(layer "In11.Cu")
		(net "I3C_SPD_DDRAF_CPU0_SDA")
	)
	(segment
		(start 264.745978 -196.83984)
		(end 263.872218 -196.83984)
		(width 0.11684)
		(layer "In11.Cu")
		(net "I3C_SPD_DDRAF_CPU0_SDA")
	)
	(segment
		(start 269.920466 -195.859146)
		(end 268.492478 -195.859146)
		(width 0.11684)
		(layer "In11.Cu")
		(net "I3C_SPD_DDRAF_CPU0_SDA")
	)
	(segment
		(start 276.48916 -166.444168)
		(end 272.271236 -170.662092)
		(width 0.10668)
		(layer "F.Cu")
		(net "I3C_SPD_DDRAF_CPU0_SCL")
	)
	(segment
		(start 269.653512 -189.770004)
		(end 265.26363 -189.770004)
		(width 0.10668)
		(layer "F.Cu")
		(net "I3C_SPD_DDRAF_CPU0_SCL")
	)
	(segment
		(start 296.915078 -146.202908)
		(end 296.273474 -145.561304)
		(width 0.10668)
		(layer "F.Cu")
		(net "I3C_SPD_DDRAF_CPU0_SCL")
	)
	(segment
		(start 263.39038 -192.05829)
		(end 263.39038 -195.577206)
		(width 0.10668)
		(layer "F.Cu")
		(net "I3C_SPD_DDRAF_CPU0_SCL")
	)
	(segment
		(start 263.684258 -191.349376)
		(end 263.39038 -192.05829)
		(width 0.10668)
		(layer "F.Cu")
		(net "I3C_SPD_DDRAF_CPU0_SCL")
	)
	(segment
		(start 272.271236 -187.15228)
		(end 269.653512 -189.770004)
		(width 0.10668)
		(layer "F.Cu")
		(net "I3C_SPD_DDRAF_CPU0_SCL")
	)
	(segment
		(start 294.965374 -145.561304)
		(end 276.48916 -164.037518)
		(width 0.10668)
		(layer "F.Cu")
		(net "I3C_SPD_DDRAF_CPU0_SCL")
	)
	(segment
		(start 263.39038 -195.577206)
		(end 263.252458 -195.715128)
		(width 0.10668)
		(layer "F.Cu")
		(net "I3C_SPD_DDRAF_CPU0_SCL")
	)
	(segment
		(start 276.48916 -164.037518)
		(end 276.48916 -166.444168)
		(width 0.10668)
		(layer "F.Cu")
		(net "I3C_SPD_DDRAF_CPU0_SCL")
	)
	(segment
		(start 296.273474 -145.561304)
		(end 294.965374 -145.561304)
		(width 0.10668)
		(layer "F.Cu")
		(net "I3C_SPD_DDRAF_CPU0_SCL")
	)
	(segment
		(start 272.271236 -170.662092)
		(end 272.271236 -187.15228)
		(width 0.10668)
		(layer "F.Cu")
		(net "I3C_SPD_DDRAF_CPU0_SCL")
	)
	(segment
		(start 265.26363 -189.770004)
		(end 263.684258 -191.349376)
		(width 0.10668)
		(layer "F.Cu")
		(net "I3C_SPD_DDRAF_CPU0_SCL")
	)
	(via
		(at 298.66844 -194.893946)
		(size 0.508)
		(drill 0.254)
		(layers "F.Cu" "B.Cu")
		(net "I3C_SPD_DDRAF_CPU0_SCL")
	)
	(via
		(at 268.492478 -194.893946)
		(size 0.508)
		(drill 0.254)
		(layers "F.Cu" "B.Cu")
		(net "I3C_SPD_DDRAF_CPU0_SCL")
	)
	(via
		(at 306.23002 -194.7164)
		(size 0.508)
		(drill 0.254)
		(layers "F.Cu" "B.Cu")
		(net "I3C_SPD_DDRAF_CPU0_SCL")
	)
	(via
		(at 263.252458 -195.715128)
		(size 0.508)
		(drill 0.254)
		(layers "F.Cu" "B.Cu")
		(net "I3C_SPD_DDRAF_CPU0_SCL")
	)
	(via
		(at 276.036532 -194.893946)
		(size 0.508)
		(drill 0.254)
		(layers "F.Cu" "B.Cu")
		(net "I3C_SPD_DDRAF_CPU0_SCL")
	)
	(via
		(at 283.580586 -194.893946)
		(size 0.508)
		(drill 0.254)
		(layers "F.Cu" "B.Cu")
		(net "I3C_SPD_DDRAF_CPU0_SCL")
	)
	(via
		(at 291.12464 -194.893946)
		(size 0.508)
		(drill 0.254)
		(layers "F.Cu" "B.Cu")
		(net "I3C_SPD_DDRAF_CPU0_SCL")
	)
	(segment
		(start 306.94122 -194.98691)
		(end 306.50053 -194.98691)
		(width 0.10668)
		(layer "B.Cu")
		(net "I3C_SPD_DDRAF_CPU0_SCL")
	)
	(segment
		(start 306.50053 -194.98691)
		(end 306.23002 -194.7164)
		(width 0.10668)
		(layer "B.Cu")
		(net "I3C_SPD_DDRAF_CPU0_SCL")
	)
	(segment
		(start 279.056084 -195.38823)
		(end 283.086302 -195.38823)
		(width 0.11684)
		(layer "In11.Cu")
		(net "I3C_SPD_DDRAF_CPU0_SCL")
	)
	(segment
		(start 306.23002 -194.7164)
		(end 305.778154 -194.7164)
		(width 0.11684)
		(layer "In11.Cu")
		(net "I3C_SPD_DDRAF_CPU0_SCL")
	)
	(segment
		(start 301.687992 -195.38823)
		(end 301.527464 -195.227702)
		(width 0.11684)
		(layer "In11.Cu")
		(net "I3C_SPD_DDRAF_CPU0_SCL")
	)
	(segment
		(start 283.086302 -195.38823)
		(end 283.580586 -194.893946)
		(width 0.11684)
		(layer "In11.Cu")
		(net "I3C_SPD_DDRAF_CPU0_SCL")
	)
	(segment
		(start 298.66844 -194.893946)
		(end 298.208954 -194.43446)
		(width 0.11684)
		(layer "In11.Cu")
		(net "I3C_SPD_DDRAF_CPU0_SCL")
	)
	(segment
		(start 288.717736 -194.408806)
		(end 290.6395 -194.408806)
		(width 0.11684)
		(layer "In11.Cu")
		(net "I3C_SPD_DDRAF_CPU0_SCL")
	)
	(segment
		(start 285.252922 -194.337178)
		(end 288.646108 -194.337178)
		(width 0.11684)
		(layer "In11.Cu")
		(net "I3C_SPD_DDRAF_CPU0_SCL")
	)
	(segment
		(start 277.607522 -195.199)
		(end 278.866854 -195.199)
		(width 0.11684)
		(layer "In11.Cu")
		(net "I3C_SPD_DDRAF_CPU0_SCL")
	)
	(segment
		(start 268.028166 -195.442078)
		(end 263.525508 -195.442078)
		(width 0.11684)
		(layer "In11.Cu")
		(net "I3C_SPD_DDRAF_CPU0_SCL")
	)
	(segment
		(start 283.580586 -194.893946)
		(end 284.696154 -194.893946)
		(width 0.11684)
		(layer "In11.Cu")
		(net "I3C_SPD_DDRAF_CPU0_SCL")
	)
	(segment
		(start 295.361106 -194.336416)
		(end 292.724078 -194.336416)
		(width 0.11684)
		(layer "In11.Cu")
		(net "I3C_SPD_DDRAF_CPU0_SCL")
	)
	(segment
		(start 268.492478 -194.893946)
		(end 268.492478 -194.977766)
		(width 0.11684)
		(layer "In11.Cu")
		(net "I3C_SPD_DDRAF_CPU0_SCL")
	)
	(segment
		(start 305.778154 -194.7164)
		(end 305.106324 -195.38823)
		(width 0.11684)
		(layer "In11.Cu")
		(net "I3C_SPD_DDRAF_CPU0_SCL")
	)
	(segment
		(start 268.492478 -194.977766)
		(end 268.028166 -195.442078)
		(width 0.11684)
		(layer "In11.Cu")
		(net "I3C_SPD_DDRAF_CPU0_SCL")
	)
	(segment
		(start 295.45915 -194.43446)
		(end 295.361106 -194.336416)
		(width 0.11684)
		(layer "In11.Cu")
		(net "I3C_SPD_DDRAF_CPU0_SCL")
	)
	(segment
		(start 292.724078 -194.336416)
		(end 292.166548 -194.893946)
		(width 0.11684)
		(layer "In11.Cu")
		(net "I3C_SPD_DDRAF_CPU0_SCL")
	)
	(segment
		(start 272.311622 -194.361308)
		(end 270.291052 -194.361308)
		(width 0.11684)
		(layer "In11.Cu")
		(net "I3C_SPD_DDRAF_CPU0_SCL")
	)
	(segment
		(start 270.291052 -194.361308)
		(end 269.758414 -194.893946)
		(width 0.11684)
		(layer "In11.Cu")
		(net "I3C_SPD_DDRAF_CPU0_SCL")
	)
	(segment
		(start 276.036532 -194.893946)
		(end 275.607526 -194.46494)
		(width 0.11684)
		(layer "In11.Cu")
		(net "I3C_SPD_DDRAF_CPU0_SCL")
	)
	(segment
		(start 299.934376 -194.893946)
		(end 298.66844 -194.893946)
		(width 0.11684)
		(layer "In11.Cu")
		(net "I3C_SPD_DDRAF_CPU0_SCL")
	)
	(segment
		(start 278.866854 -195.199)
		(end 279.056084 -195.38823)
		(width 0.11684)
		(layer "In11.Cu")
		(net "I3C_SPD_DDRAF_CPU0_SCL")
	)
	(segment
		(start 301.527464 -195.227702)
		(end 300.268132 -195.227702)
		(width 0.11684)
		(layer "In11.Cu")
		(net "I3C_SPD_DDRAF_CPU0_SCL")
	)
	(segment
		(start 269.758414 -194.893946)
		(end 268.492478 -194.893946)
		(width 0.11684)
		(layer "In11.Cu")
		(net "I3C_SPD_DDRAF_CPU0_SCL")
	)
	(segment
		(start 263.525508 -195.442078)
		(end 263.252458 -195.715128)
		(width 0.11684)
		(layer "In11.Cu")
		(net "I3C_SPD_DDRAF_CPU0_SCL")
	)
	(segment
		(start 277.302468 -194.893946)
		(end 277.607522 -195.199)
		(width 0.11684)
		(layer "In11.Cu")
		(net "I3C_SPD_DDRAF_CPU0_SCL")
	)
	(segment
		(start 288.646108 -194.337178)
		(end 288.717736 -194.408806)
		(width 0.11684)
		(layer "In11.Cu")
		(net "I3C_SPD_DDRAF_CPU0_SCL")
	)
	(segment
		(start 290.6395 -194.408806)
		(end 291.12464 -194.893946)
		(width 0.11684)
		(layer "In11.Cu")
		(net "I3C_SPD_DDRAF_CPU0_SCL")
	)
	(segment
		(start 298.208954 -194.43446)
		(end 295.45915 -194.43446)
		(width 0.11684)
		(layer "In11.Cu")
		(net "I3C_SPD_DDRAF_CPU0_SCL")
	)
	(segment
		(start 300.268132 -195.227702)
		(end 299.934376 -194.893946)
		(width 0.11684)
		(layer "In11.Cu")
		(net "I3C_SPD_DDRAF_CPU0_SCL")
	)
	(segment
		(start 275.607526 -194.46494)
		(end 272.415254 -194.46494)
		(width 0.11684)
		(layer "In11.Cu")
		(net "I3C_SPD_DDRAF_CPU0_SCL")
	)
	(segment
		(start 284.696154 -194.893946)
		(end 285.252922 -194.337178)
		(width 0.11684)
		(layer "In11.Cu")
		(net "I3C_SPD_DDRAF_CPU0_SCL")
	)
	(segment
		(start 292.166548 -194.893946)
		(end 291.12464 -194.893946)
		(width 0.11684)
		(layer "In11.Cu")
		(net "I3C_SPD_DDRAF_CPU0_SCL")
	)
	(segment
		(start 305.106324 -195.38823)
		(end 301.687992 -195.38823)
		(width 0.11684)
		(layer "In11.Cu")
		(net "I3C_SPD_DDRAF_CPU0_SCL")
	)
	(segment
		(start 272.415254 -194.46494)
		(end 272.311622 -194.361308)
		(width 0.11684)
		(layer "In11.Cu")
		(net "I3C_SPD_DDRAF_CPU0_SCL")
	)
	(segment
		(start 276.036532 -194.893946)
		(end 277.302468 -194.893946)
		(width 0.11684)
		(layer "In11.Cu")
		(net "I3C_SPD_DDRAF_CPU0_SCL")
	)
	(segment
		(start 300.526704 -148.413978)
		(end 299.348144 -148.413978)
		(width 0.10668)
		(layer "F.Cu")
		(net "I3C_SPD_DDRAF_CPU0_LVC1_SDA")
	)
	(segment
		(start 297.810428 -148.413978)
		(end 297.730418 -148.493988)
		(width 0.10668)
		(layer "F.Cu")
		(net "I3C_SPD_DDRAF_CPU0_LVC1_SDA")
	)
	(segment
		(start 296.924984 -149.738334)
		(end 297.730418 -148.9329)
		(width 0.10668)
		(layer "F.Cu")
		(net "I3C_SPD_DDRAF_CPU0_LVC1_SDA")
	)
	(segment
		(start 296.1259 -150.538942)
		(end 296.1259 -150.095458)
		(width 0.10668)
		(layer "F.Cu")
		(net "I3C_SPD_DDRAF_CPU0_LVC1_SDA")
	)
	(segment
		(start 299.348144 -148.413978)
		(end 297.810428 -148.413978)
		(width 0.10668)
		(layer "F.Cu")
		(net "I3C_SPD_DDRAF_CPU0_LVC1_SDA")
	)
	(segment
		(start 296.1259 -150.095458)
		(end 296.483024 -149.738334)
		(width 0.10668)
		(layer "F.Cu")
		(net "I3C_SPD_DDRAF_CPU0_LVC1_SDA")
	)
	(segment
		(start 301.160688 -148.159724)
		(end 300.780958 -148.159724)
		(width 0.10668)
		(layer "F.Cu")
		(net "I3C_SPD_DDRAF_CPU0_LVC1_SDA")
	)
	(segment
		(start 296.483024 -149.738334)
		(end 296.924984 -149.738334)
		(width 0.10668)
		(layer "F.Cu")
		(net "I3C_SPD_DDRAF_CPU0_LVC1_SDA")
	)
	(segment
		(start 300.780958 -148.159724)
		(end 300.526704 -148.413978)
		(width 0.10668)
		(layer "F.Cu")
		(net "I3C_SPD_DDRAF_CPU0_LVC1_SDA")
	)
	(segment
		(start 297.730418 -148.9329)
		(end 297.730418 -148.493988)
		(width 0.10668)
		(layer "F.Cu")
		(net "I3C_SPD_DDRAF_CPU0_LVC1_SDA")
	)
	(via
		(at 299.348144 -148.413978)
		(size 0.762)
		(drill 0.381)
		(layers "F.Cu" "B.Cu")
		(net "I3C_SPD_DDRAF_CPU0_LVC1_SDA")
	)
	(segment
		(start 297.715178 -147.173696)
		(end 297.715178 -147.472908)
		(width 0.10668)
		(layer "F.Cu")
		(net "I3C_SPD_DDRAF_CPU0_LVC1_SCL")
	)
	(segment
		(start 298.231814 -147.472908)
		(end 299.043344 -146.661378)
		(width 0.10668)
		(layer "F.Cu")
		(net "I3C_SPD_DDRAF_CPU0_LVC1_SCL")
	)
	(segment
		(start 300.499018 -147.659852)
		(end 299.500544 -146.661378)
		(width 0.10668)
		(layer "F.Cu")
		(net "I3C_SPD_DDRAF_CPU0_LVC1_SCL")
	)
	(segment
		(start 301.160688 -147.659852)
		(end 300.499018 -147.659852)
		(width 0.10668)
		(layer "F.Cu")
		(net "I3C_SPD_DDRAF_CPU0_LVC1_SCL")
	)
	(segment
		(start 297.240452 -146.69897)
		(end 297.715178 -147.173696)
		(width 0.10668)
		(layer "F.Cu")
		(net "I3C_SPD_DDRAF_CPU0_LVC1_SCL")
	)
	(segment
		(start 296.114978 -146.202908)
		(end 296.61104 -146.69897)
		(width 0.10668)
		(layer "F.Cu")
		(net "I3C_SPD_DDRAF_CPU0_LVC1_SCL")
	)
	(segment
		(start 299.500544 -146.661378)
		(end 299.043344 -146.661378)
		(width 0.10668)
		(layer "F.Cu")
		(net "I3C_SPD_DDRAF_CPU0_LVC1_SCL")
	)
	(segment
		(start 297.715178 -147.472908)
		(end 298.231814 -147.472908)
		(width 0.10668)
		(layer "F.Cu")
		(net "I3C_SPD_DDRAF_CPU0_LVC1_SCL")
	)
	(segment
		(start 296.61104 -146.69897)
		(end 297.240452 -146.69897)
		(width 0.10668)
		(layer "F.Cu")
		(net "I3C_SPD_DDRAF_CPU0_LVC1_SCL")
	)
	(via
		(at 299.043344 -146.661378)
		(size 0.762)
		(drill 0.381)
		(layers "F.Cu" "B.Cu")
		(net "I3C_SPD_DDRAF_CPU0_LVC1_SCL")
	)
	(segment
		(start 297.7261 -150.538942)
		(end 299.212 -150.538942)
		(width 0.10668)
		(layer "F.Cu")
		(net "I3C_SPD_DDRAF_CPU0_BYPASS_SDA")
	)
	(segment
		(start 319.22339 -191.69761)
		(end 319.80505 -191.11595)
		(width 0.10668)
		(layer "F.Cu")
		(net "I3C_SPD_DDRAF_CPU0_BYPASS_SDA")
	)
	(segment
		(start 311.765188 -171.539408)
		(end 311.765188 -154.140408)
		(width 0.10668)
		(layer "F.Cu")
		(net "I3C_SPD_DDRAF_CPU0_BYPASS_SDA")
	)
	(segment
		(start 308.787292 -151.162512)
		(end 306.491386 -151.162512)
		(width 0.10668)
		(layer "F.Cu")
		(net "I3C_SPD_DDRAF_CPU0_BYPASS_SDA")
	)
	(segment
		(start 306.491386 -151.162512)
		(end 306.242466 -150.913592)
		(width 0.10668)
		(layer "F.Cu")
		(net "I3C_SPD_DDRAF_CPU0_BYPASS_SDA")
	)
	(segment
		(start 319.80505 -191.11595)
		(end 319.80505 -179.57927)
		(width 0.10668)
		(layer "F.Cu")
		(net "I3C_SPD_DDRAF_CPU0_BYPASS_SDA")
	)
	(segment
		(start 319.80505 -179.57927)
		(end 311.765188 -171.539408)
		(width 0.10668)
		(layer "F.Cu")
		(net "I3C_SPD_DDRAF_CPU0_BYPASS_SDA")
	)
	(segment
		(start 311.765188 -154.140408)
		(end 308.787292 -151.162512)
		(width 0.10668)
		(layer "F.Cu")
		(net "I3C_SPD_DDRAF_CPU0_BYPASS_SDA")
	)
	(via
		(at 299.212 -150.538942)
		(size 0.508)
		(drill 0.254)
		(layers "F.Cu" "B.Cu")
		(net "I3C_SPD_DDRAF_CPU0_BYPASS_SDA")
	)
	(via
		(at 306.242466 -150.913592)
		(size 0.508)
		(drill 0.254)
		(layers "F.Cu" "B.Cu")
		(net "I3C_SPD_DDRAF_CPU0_BYPASS_SDA")
	)
	(segment
		(start 305.275996 -151.347678)
		(end 305.710082 -150.913592)
		(width 0.10668)
		(layer "B.Cu")
		(net "I3C_SPD_DDRAF_CPU0_BYPASS_SDA")
	)
	(segment
		(start 300.020736 -151.347678)
		(end 305.275996 -151.347678)
		(width 0.10668)
		(layer "B.Cu")
		(net "I3C_SPD_DDRAF_CPU0_BYPASS_SDA")
	)
	(segment
		(start 299.212 -150.538942)
		(end 300.020736 -151.347678)
		(width 0.10668)
		(layer "B.Cu")
		(net "I3C_SPD_DDRAF_CPU0_BYPASS_SDA")
	)
	(segment
		(start 305.710082 -150.913592)
		(end 306.242466 -150.913592)
		(width 0.10668)
		(layer "B.Cu")
		(net "I3C_SPD_DDRAF_CPU0_BYPASS_SDA")
	)
	(segment
		(start 320.421 -191.137286)
		(end 320.421 -179.324)
		(width 0.10668)
		(layer "F.Cu")
		(net "I3C_SPD_DDRAF_CPU0_BYPASS_SCL")
	)
	(segment
		(start 320.981324 -191.69761)
		(end 320.421 -191.137286)
		(width 0.10668)
		(layer "F.Cu")
		(net "I3C_SPD_DDRAF_CPU0_BYPASS_SCL")
	)
	(segment
		(start 299.212 -145.440908)
		(end 298.45 -146.202908)
		(width 0.10668)
		(layer "F.Cu")
		(net "I3C_SPD_DDRAF_CPU0_BYPASS_SCL")
	)
	(segment
		(start 307.9496 -149.4536)
		(end 306.372514 -149.4536)
		(width 0.10668)
		(layer "F.Cu")
		(net "I3C_SPD_DDRAF_CPU0_BYPASS_SCL")
	)
	(segment
		(start 312.381138 -171.284138)
		(end 312.381138 -153.885138)
		(width 0.10668)
		(layer "F.Cu")
		(net "I3C_SPD_DDRAF_CPU0_BYPASS_SCL")
	)
	(segment
		(start 312.381138 -153.885138)
		(end 307.9496 -149.4536)
		(width 0.10668)
		(layer "F.Cu")
		(net "I3C_SPD_DDRAF_CPU0_BYPASS_SCL")
	)
	(segment
		(start 320.421 -179.324)
		(end 312.381138 -171.284138)
		(width 0.10668)
		(layer "F.Cu")
		(net "I3C_SPD_DDRAF_CPU0_BYPASS_SCL")
	)
	(segment
		(start 298.45 -146.202908)
		(end 297.715178 -146.202908)
		(width 0.10668)
		(layer "F.Cu")
		(net "I3C_SPD_DDRAF_CPU0_BYPASS_SCL")
	)
	(via
		(at 299.212 -145.440908)
		(size 0.508)
		(drill 0.254)
		(layers "F.Cu" "B.Cu")
		(net "I3C_SPD_DDRAF_CPU0_BYPASS_SCL")
	)
	(via
		(at 306.372514 -149.4536)
		(size 0.508)
		(drill 0.254)
		(layers "F.Cu" "B.Cu")
		(net "I3C_SPD_DDRAF_CPU0_BYPASS_SCL")
	)
	(segment
		(start 299.212 -146.304)
		(end 301.244 -148.336)
		(width 0.10668)
		(layer "B.Cu")
		(net "I3C_SPD_DDRAF_CPU0_BYPASS_SCL")
	)
	(segment
		(start 305.254914 -148.336)
		(end 306.372514 -149.4536)
		(width 0.10668)
		(layer "B.Cu")
		(net "I3C_SPD_DDRAF_CPU0_BYPASS_SCL")
	)
	(segment
		(start 299.212 -145.440908)
		(end 299.212 -146.304)
		(width 0.10668)
		(layer "B.Cu")
		(net "I3C_SPD_DDRAF_CPU0_BYPASS_SCL")
	)
	(segment
		(start 301.244 -148.336)
		(end 305.254914 -148.336)
		(width 0.10668)
		(layer "B.Cu")
		(net "I3C_SPD_DDRAF_CPU0_BYPASS_SCL")
	)
	(segment
		(start 183.662828 -162.875722)
		(end 183.079898 -162.292792)
		(width 0.10668)
		(layer "F.Cu")
		(net "I3C_SCM_3_R_SDA")
	)
	(segment
		(start 183.662828 -164.121338)
		(end 183.662828 -162.875722)
		(width 0.10668)
		(layer "F.Cu")
		(net "I3C_SCM_3_R_SDA")
	)
	(segment
		(start 183.079898 -162.292792)
		(end 183.079898 -161.012124)
		(width 0.10668)
		(layer "F.Cu")
		(net "I3C_SCM_3_R_SDA")
	)
	(segment
		(start 183.079898 -161.012124)
		(end 183.896 -161.012124)
		(width 0.10668)
		(layer "F.Cu")
		(net "I3C_SCM_3_R_SDA")
	)
	(via
		(at 183.175402 -14.881352)
		(size 0.508)
		(drill 0.254)
		(layers "F.Cu" "B.Cu")
		(net "I3C_SCM_3_R_SDA")
	)
	(via
		(at 183.896 -161.012124)
		(size 0.508)
		(drill 0.254)
		(layers "F.Cu" "B.Cu")
		(net "I3C_SCM_3_R_SDA")
	)
	(segment
		(start 182.8673 -14.00048)
		(end 182.8673 -14.57325)
		(width 0.10668)
		(layer "B.Cu")
		(net "I3C_SCM_3_R_SDA")
	)
	(segment
		(start 182.8673 -14.57325)
		(end 183.175402 -14.881352)
		(width 0.10668)
		(layer "B.Cu")
		(net "I3C_SCM_3_R_SDA")
	)
	(segment
		(start 202.20813 -131.421124)
		(end 203.46162 -132.674614)
		(width 0.11684)
		(layer "In4.Cu")
		(net "I3C_SCM_3_R_SDA")
	)
	(segment
		(start 204.963268 -124.436632)
		(end 204.082142 -125.317758)
		(width 0.11684)
		(layer "In4.Cu")
		(net "I3C_SCM_3_R_SDA")
	)
	(segment
		(start 208.586832 -72.334374)
		(end 208.87309 -72.620632)
		(width 0.11684)
		(layer "In4.Cu")
		(net "I3C_SCM_3_R_SDA")
	)
	(segment
		(start 205.184502 -137.733786)
		(end 205.184502 -159.198056)
		(width 0.11684)
		(layer "In4.Cu")
		(net "I3C_SCM_3_R_SDA")
	)
	(segment
		(start 183.548528 -23.203408)
		(end 184.89676 -24.55164)
		(width 0.11684)
		(layer "In4.Cu")
		(net "I3C_SCM_3_R_SDA")
	)
	(segment
		(start 182.8673 -16.340582)
		(end 181.991254 -17.216628)
		(width 0.11684)
		(layer "In4.Cu")
		(net "I3C_SCM_3_R_SDA")
	)
	(segment
		(start 181.991254 -19.541236)
		(end 183.548528 -21.09851)
		(width 0.11684)
		(layer "In4.Cu")
		(net "I3C_SCM_3_R_SDA")
	)
	(segment
		(start 205.6257 -94.13748)
		(end 205.245716 -94.517464)
		(width 0.11684)
		(layer "In4.Cu")
		(net "I3C_SCM_3_R_SDA")
	)
	(segment
		(start 198.168514 -34.466022)
		(end 210.152996 -46.450504)
		(width 0.11684)
		(layer "In4.Cu")
		(net "I3C_SCM_3_R_SDA")
	)
	(segment
		(start 186.10326 -27.05354)
		(end 186.10326 -28.329382)
		(width 0.11684)
		(layer "In4.Cu")
		(net "I3C_SCM_3_R_SDA")
	)
	(segment
		(start 208.87309 -75.03541)
		(end 207.27797 -76.63053)
		(width 0.11684)
		(layer "In4.Cu")
		(net "I3C_SCM_3_R_SDA")
	)
	(segment
		(start 181.991254 -17.216628)
		(end 181.991254 -19.541236)
		(width 0.11684)
		(layer "In4.Cu")
		(net "I3C_SCM_3_R_SDA")
	)
	(segment
		(start 205.245716 -101.314504)
		(end 205.683612 -101.7524)
		(width 0.11684)
		(layer "In4.Cu")
		(net "I3C_SCM_3_R_SDA")
	)
	(segment
		(start 192.2399 -34.466022)
		(end 198.168514 -34.466022)
		(width 0.11684)
		(layer "In4.Cu")
		(net "I3C_SCM_3_R_SDA")
	)
	(segment
		(start 207.787748 -86.048596)
		(end 207.787748 -87.345774)
		(width 0.11684)
		(layer "In4.Cu")
		(net "I3C_SCM_3_R_SDA")
	)
	(segment
		(start 208.586832 -58.580274)
		(end 208.586832 -72.334374)
		(width 0.11684)
		(layer "In4.Cu")
		(net "I3C_SCM_3_R_SDA")
	)
	(segment
		(start 205.6257 -89.507822)
		(end 205.6257 -94.13748)
		(width 0.11684)
		(layer "In4.Cu")
		(net "I3C_SCM_3_R_SDA")
	)
	(segment
		(start 205.683612 -101.7524)
		(end 205.683612 -103.854758)
		(width 0.11684)
		(layer "In4.Cu")
		(net "I3C_SCM_3_R_SDA")
	)
	(segment
		(start 202.20813 -128.742186)
		(end 202.20813 -131.421124)
		(width 0.11684)
		(layer "In4.Cu")
		(net "I3C_SCM_3_R_SDA")
	)
	(segment
		(start 185.46318 -25.67686)
		(end 185.46318 -26.41346)
		(width 0.11684)
		(layer "In4.Cu")
		(net "I3C_SCM_3_R_SDA")
	)
	(segment
		(start 182.8673 -15.189454)
		(end 182.8673 -16.340582)
		(width 0.11684)
		(layer "In4.Cu")
		(net "I3C_SCM_3_R_SDA")
	)
	(segment
		(start 184.89676 -24.55164)
		(end 184.89676 -25.11044)
		(width 0.11684)
		(layer "In4.Cu")
		(net "I3C_SCM_3_R_SDA")
	)
	(segment
		(start 186.10326 -28.329382)
		(end 192.2399 -34.466022)
		(width 0.11684)
		(layer "In4.Cu")
		(net "I3C_SCM_3_R_SDA")
	)
	(segment
		(start 204.082142 -125.317758)
		(end 203.281026 -125.317758)
		(width 0.11684)
		(layer "In4.Cu")
		(net "I3C_SCM_3_R_SDA")
	)
	(segment
		(start 185.46318 -26.41346)
		(end 186.10326 -27.05354)
		(width 0.11684)
		(layer "In4.Cu")
		(net "I3C_SCM_3_R_SDA")
	)
	(segment
		(start 199.048624 -165.333934)
		(end 188.21781 -165.333934)
		(width 0.11684)
		(layer "In4.Cu")
		(net "I3C_SCM_3_R_SDA")
	)
	(segment
		(start 207.27797 -85.538818)
		(end 207.787748 -86.048596)
		(width 0.11684)
		(layer "In4.Cu")
		(net "I3C_SCM_3_R_SDA")
	)
	(segment
		(start 205.683612 -103.854758)
		(end 204.559154 -104.979216)
		(width 0.11684)
		(layer "In4.Cu")
		(net "I3C_SCM_3_R_SDA")
	)
	(segment
		(start 205.184502 -159.198056)
		(end 199.048624 -165.333934)
		(width 0.11684)
		(layer "In4.Cu")
		(net "I3C_SCM_3_R_SDA")
	)
	(segment
		(start 203.46162 -132.674614)
		(end 203.46162 -136.010904)
		(width 0.11684)
		(layer "In4.Cu")
		(net "I3C_SCM_3_R_SDA")
	)
	(segment
		(start 205.245716 -94.517464)
		(end 205.245716 -101.314504)
		(width 0.11684)
		(layer "In4.Cu")
		(net "I3C_SCM_3_R_SDA")
	)
	(segment
		(start 204.963268 -121.191782)
		(end 204.963268 -124.436632)
		(width 0.11684)
		(layer "In4.Cu")
		(net "I3C_SCM_3_R_SDA")
	)
	(segment
		(start 183.548528 -21.09851)
		(end 183.548528 -23.203408)
		(width 0.11684)
		(layer "In4.Cu")
		(net "I3C_SCM_3_R_SDA")
	)
	(segment
		(start 208.87309 -72.620632)
		(end 208.87309 -75.03541)
		(width 0.11684)
		(layer "In4.Cu")
		(net "I3C_SCM_3_R_SDA")
	)
	(segment
		(start 207.787748 -87.345774)
		(end 205.6257 -89.507822)
		(width 0.11684)
		(layer "In4.Cu")
		(net "I3C_SCM_3_R_SDA")
	)
	(segment
		(start 202.862688 -128.087628)
		(end 202.20813 -128.742186)
		(width 0.11684)
		(layer "In4.Cu")
		(net "I3C_SCM_3_R_SDA")
	)
	(segment
		(start 202.862688 -125.736096)
		(end 202.862688 -128.087628)
		(width 0.11684)
		(layer "In4.Cu")
		(net "I3C_SCM_3_R_SDA")
	)
	(segment
		(start 210.152996 -46.450504)
		(end 210.152996 -57.01411)
		(width 0.11684)
		(layer "In4.Cu")
		(net "I3C_SCM_3_R_SDA")
	)
	(segment
		(start 184.89676 -25.11044)
		(end 185.46318 -25.67686)
		(width 0.11684)
		(layer "In4.Cu")
		(net "I3C_SCM_3_R_SDA")
	)
	(segment
		(start 183.175402 -14.881352)
		(end 182.8673 -15.189454)
		(width 0.11684)
		(layer "In4.Cu")
		(net "I3C_SCM_3_R_SDA")
	)
	(segment
		(start 203.281026 -125.317758)
		(end 202.862688 -125.736096)
		(width 0.11684)
		(layer "In4.Cu")
		(net "I3C_SCM_3_R_SDA")
	)
	(segment
		(start 204.559154 -104.979216)
		(end 204.559154 -120.787668)
		(width 0.11684)
		(layer "In4.Cu")
		(net "I3C_SCM_3_R_SDA")
	)
	(segment
		(start 210.152996 -57.01411)
		(end 208.586832 -58.580274)
		(width 0.11684)
		(layer "In4.Cu")
		(net "I3C_SCM_3_R_SDA")
	)
	(segment
		(start 188.21781 -165.333934)
		(end 183.896 -161.012124)
		(width 0.11684)
		(layer "In4.Cu")
		(net "I3C_SCM_3_R_SDA")
	)
	(segment
		(start 207.27797 -76.63053)
		(end 207.27797 -85.538818)
		(width 0.11684)
		(layer "In4.Cu")
		(net "I3C_SCM_3_R_SDA")
	)
	(segment
		(start 203.46162 -136.010904)
		(end 205.184502 -137.733786)
		(width 0.11684)
		(layer "In4.Cu")
		(net "I3C_SCM_3_R_SDA")
	)
	(segment
		(start 204.559154 -120.787668)
		(end 204.963268 -121.191782)
		(width 0.11684)
		(layer "In4.Cu")
		(net "I3C_SCM_3_R_SDA")
	)
	(segment
		(start 182.047134 -160.995868)
		(end 182.236364 -161.185098)
		(width 0.10668)
		(layer "F.Cu")
		(net "I3C_SCM_3_R_SCL")
	)
	(segment
		(start 183.162702 -163.221416)
		(end 183.162702 -164.121338)
		(width 0.10668)
		(layer "F.Cu")
		(net "I3C_SCM_3_R_SCL")
	)
	(segment
		(start 182.236364 -162.295078)
		(end 183.162702 -163.221416)
		(width 0.10668)
		(layer "F.Cu")
		(net "I3C_SCM_3_R_SCL")
	)
	(segment
		(start 182.236364 -161.185098)
		(end 182.236364 -162.295078)
		(width 0.10668)
		(layer "F.Cu")
		(net "I3C_SCM_3_R_SCL")
	)
	(segment
		(start 182.047134 -160.995868)
		(end 181.189122 -160.995868)
		(width 0.10668)
		(layer "F.Cu")
		(net "I3C_SCM_3_R_SCL")
	)
	(via
		(at 184.05983 -14.823948)
		(size 0.508)
		(drill 0.254)
		(layers "F.Cu" "B.Cu")
		(net "I3C_SCM_3_R_SCL")
	)
	(via
		(at 181.189122 -160.995868)
		(size 0.508)
		(drill 0.254)
		(layers "F.Cu" "B.Cu")
		(net "I3C_SCM_3_R_SCL")
	)
	(segment
		(start 184.05983 -14.00048)
		(end 184.05983 -14.823948)
		(width 0.10668)
		(layer "B.Cu")
		(net "I3C_SCM_3_R_SCL")
	)
	(segment
		(start 187.88888 -27.071828)
		(end 187.4774 -27.483308)
		(width 0.11684)
		(layer "In4.Cu")
		(net "I3C_SCM_3_R_SCL")
	)
	(segment
		(start 208.387188 -85.47481)
		(end 208.387188 -87.594186)
		(width 0.11684)
		(layer "In4.Cu")
		(net "I3C_SCM_3_R_SCL")
	)
	(segment
		(start 205.685136 -120.954038)
		(end 205.685136 -125.057408)
		(width 0.11684)
		(layer "In4.Cu")
		(net "I3C_SCM_3_R_SCL")
	)
	(segment
		(start 183.534812 -19.133312)
		(end 184.194958 -19.793458)
		(width 0.11684)
		(layer "In4.Cu")
		(net "I3C_SCM_3_R_SCL")
	)
	(segment
		(start 186.639454 -165.955472)
		(end 181.67985 -160.995868)
		(width 0.11684)
		(layer "In4.Cu")
		(net "I3C_SCM_3_R_SCL")
	)
	(segment
		(start 184.194958 -19.793458)
		(end 184.194958 -20.52828)
		(width 0.11684)
		(layer "In4.Cu")
		(net "I3C_SCM_3_R_SCL")
	)
	(segment
		(start 184.194958 -20.52828)
		(end 187.88888 -24.222202)
		(width 0.11684)
		(layer "In4.Cu")
		(net "I3C_SCM_3_R_SCL")
	)
	(segment
		(start 206.22514 -97.611438)
		(end 206.730854 -98.117152)
		(width 0.11684)
		(layer "In4.Cu")
		(net "I3C_SCM_3_R_SCL")
	)
	(segment
		(start 208.387188 -87.594186)
		(end 206.22514 -89.756234)
		(width 0.11684)
		(layer "In4.Cu")
		(net "I3C_SCM_3_R_SCL")
	)
	(segment
		(start 205.296262 -105.59161)
		(end 205.296262 -120.565164)
		(width 0.11684)
		(layer "In4.Cu")
		(net "I3C_SCM_3_R_SCL")
	)
	(segment
		(start 199.541638 -165.955472)
		(end 186.639454 -165.955472)
		(width 0.11684)
		(layer "In4.Cu")
		(net "I3C_SCM_3_R_SCL")
	)
	(segment
		(start 206.730854 -100.680266)
		(end 207.811624 -101.761036)
		(width 0.11684)
		(layer "In4.Cu")
		(net "I3C_SCM_3_R_SCL")
	)
	(segment
		(start 207.811624 -101.761036)
		(end 207.811624 -103.076248)
		(width 0.11684)
		(layer "In4.Cu")
		(net "I3C_SCM_3_R_SCL")
	)
	(segment
		(start 209.79765 -72.0471)
		(end 209.47253 -72.37222)
		(width 0.11684)
		(layer "In4.Cu")
		(net "I3C_SCM_3_R_SCL")
	)
	(segment
		(start 187.4774 -28.780994)
		(end 192.562988 -33.866582)
		(width 0.11684)
		(layer "In4.Cu")
		(net "I3C_SCM_3_R_SCL")
	)
	(segment
		(start 205.685136 -125.057408)
		(end 204.496162 -126.246382)
		(width 0.11684)
		(layer "In4.Cu")
		(net "I3C_SCM_3_R_SCL")
	)
	(segment
		(start 209.47253 -72.37222)
		(end 209.47253 -75.283822)
		(width 0.11684)
		(layer "In4.Cu")
		(net "I3C_SCM_3_R_SCL")
	)
	(segment
		(start 207.899254 -76.857098)
		(end 207.899254 -84.986876)
		(width 0.11684)
		(layer "In4.Cu")
		(net "I3C_SCM_3_R_SCL")
	)
	(segment
		(start 198.416926 -33.866582)
		(end 210.752436 -46.202092)
		(width 0.11684)
		(layer "In4.Cu")
		(net "I3C_SCM_3_R_SCL")
	)
	(segment
		(start 206.730854 -98.117152)
		(end 206.730854 -100.680266)
		(width 0.11684)
		(layer "In4.Cu")
		(net "I3C_SCM_3_R_SCL")
	)
	(segment
		(start 207.811624 -103.076248)
		(end 205.296262 -105.59161)
		(width 0.11684)
		(layer "In4.Cu")
		(net "I3C_SCM_3_R_SCL")
	)
	(segment
		(start 207.899254 -84.986876)
		(end 208.387188 -85.47481)
		(width 0.11684)
		(layer "In4.Cu")
		(net "I3C_SCM_3_R_SCL")
	)
	(segment
		(start 204.496162 -126.246382)
		(end 204.496162 -132.416296)
		(width 0.11684)
		(layer "In4.Cu")
		(net "I3C_SCM_3_R_SCL")
	)
	(segment
		(start 205.296262 -120.565164)
		(end 205.685136 -120.954038)
		(width 0.11684)
		(layer "In4.Cu")
		(net "I3C_SCM_3_R_SCL")
	)
	(segment
		(start 184.05983 -16.178784)
		(end 183.534812 -16.703802)
		(width 0.11684)
		(layer "In4.Cu")
		(net "I3C_SCM_3_R_SCL")
	)
	(segment
		(start 210.752436 -46.202092)
		(end 210.752436 -57.262522)
		(width 0.11684)
		(layer "In4.Cu")
		(net "I3C_SCM_3_R_SCL")
	)
	(segment
		(start 187.88888 -24.222202)
		(end 187.88888 -27.071828)
		(width 0.11684)
		(layer "In4.Cu")
		(net "I3C_SCM_3_R_SCL")
	)
	(segment
		(start 209.47253 -75.283822)
		(end 207.899254 -76.857098)
		(width 0.11684)
		(layer "In4.Cu")
		(net "I3C_SCM_3_R_SCL")
	)
	(segment
		(start 204.496162 -132.416296)
		(end 205.826106 -133.74624)
		(width 0.11684)
		(layer "In4.Cu")
		(net "I3C_SCM_3_R_SCL")
	)
	(segment
		(start 181.67985 -160.995868)
		(end 181.189122 -160.995868)
		(width 0.11684)
		(layer "In4.Cu")
		(net "I3C_SCM_3_R_SCL")
	)
	(segment
		(start 206.22514 -89.756234)
		(end 206.22514 -97.611438)
		(width 0.11684)
		(layer "In4.Cu")
		(net "I3C_SCM_3_R_SCL")
	)
	(segment
		(start 184.05983 -14.823948)
		(end 184.05983 -16.178784)
		(width 0.11684)
		(layer "In4.Cu")
		(net "I3C_SCM_3_R_SCL")
	)
	(segment
		(start 209.79765 -58.217308)
		(end 209.79765 -72.0471)
		(width 0.11684)
		(layer "In4.Cu")
		(net "I3C_SCM_3_R_SCL")
	)
	(segment
		(start 183.534812 -16.703802)
		(end 183.534812 -19.133312)
		(width 0.11684)
		(layer "In4.Cu")
		(net "I3C_SCM_3_R_SCL")
	)
	(segment
		(start 187.4774 -27.483308)
		(end 187.4774 -28.780994)
		(width 0.11684)
		(layer "In4.Cu")
		(net "I3C_SCM_3_R_SCL")
	)
	(segment
		(start 192.562988 -33.866582)
		(end 198.416926 -33.866582)
		(width 0.11684)
		(layer "In4.Cu")
		(net "I3C_SCM_3_R_SCL")
	)
	(segment
		(start 210.752436 -57.262522)
		(end 209.79765 -58.217308)
		(width 0.11684)
		(layer "In4.Cu")
		(net "I3C_SCM_3_R_SCL")
	)
	(segment
		(start 205.826106 -159.671004)
		(end 199.541638 -165.955472)
		(width 0.11684)
		(layer "In4.Cu")
		(net "I3C_SCM_3_R_SCL")
	)
	(segment
		(start 205.826106 -133.74624)
		(end 205.826106 -159.671004)
		(width 0.11684)
		(layer "In4.Cu")
		(net "I3C_SCM_3_R_SCL")
	)
	(segment
		(start 41.08069 -173.851824)
		(end 41.167812 -173.938946)
		(width 0.10668)
		(layer "F.Cu")
		(net "I3C_SCM_2_R_SDA")
	)
	(segment
		(start 39.42715 -172.730668)
		(end 39.959534 -172.730668)
		(width 0.10668)
		(layer "F.Cu")
		(net "I3C_SCM_2_R_SDA")
	)
	(segment
		(start 41.167812 -173.938946)
		(end 42.237914 -173.938946)
		(width 0.10668)
		(layer "F.Cu")
		(net "I3C_SCM_2_R_SDA")
	)
	(segment
		(start 39.959534 -172.730668)
		(end 41.08069 -173.851824)
		(width 0.10668)
		(layer "F.Cu")
		(net "I3C_SCM_2_R_SDA")
	)
	(via
		(at 184.98439 -14.76629)
		(size 0.508)
		(drill 0.254)
		(layers "F.Cu" "B.Cu")
		(net "I3C_SCM_2_R_SDA")
	)
	(via
		(at 41.08069 -173.851824)
		(size 0.508)
		(drill 0.254)
		(layers "F.Cu" "B.Cu")
		(net "I3C_SCM_2_R_SDA")
	)
	(via
		(at 112.09528 -74.97318)
		(size 0.508)
		(drill 0.254)
		(layers "F.Cu" "B.Cu")
		(net "I3C_SCM_2_R_SDA")
	)
	(segment
		(start 184.98439 -14.460982)
		(end 184.98439 -14.76629)
		(width 0.10668)
		(layer "B.Cu")
		(net "I3C_SCM_2_R_SDA")
	)
	(segment
		(start 185.240676 -14.00048)
		(end 185.240676 -14.204696)
		(width 0.10668)
		(layer "B.Cu")
		(net "I3C_SCM_2_R_SDA")
	)
	(segment
		(start 185.240676 -14.204696)
		(end 184.98439 -14.460982)
		(width 0.10668)
		(layer "B.Cu")
		(net "I3C_SCM_2_R_SDA")
	)
	(segment
		(start 63.765684 -128.484884)
		(end 72.649588 -128.484884)
		(width 0.11684)
		(layer "In2.Cu")
		(net "I3C_SCM_2_R_SDA")
	)
	(segment
		(start 43.403266 -165.827202)
		(end 43.403266 -148.847302)
		(width 0.11684)
		(layer "In2.Cu")
		(net "I3C_SCM_2_R_SDA")
	)
	(segment
		(start 59.147202 -133.103366)
		(end 63.765684 -128.484884)
		(width 0.11684)
		(layer "In2.Cu")
		(net "I3C_SCM_2_R_SDA")
	)
	(segment
		(start 43.440604 -148.671534)
		(end 59.008772 -133.103366)
		(width 0.11684)
		(layer "In2.Cu")
		(net "I3C_SCM_2_R_SDA")
	)
	(segment
		(start 41.08069 -173.851824)
		(end 39.931594 -172.702728)
		(width 0.11684)
		(layer "In2.Cu")
		(net "I3C_SCM_2_R_SDA")
	)
	(segment
		(start 72.649588 -128.484884)
		(end 109.991398 -91.143074)
		(width 0.11684)
		(layer "In2.Cu")
		(net "I3C_SCM_2_R_SDA")
	)
	(segment
		(start 109.991398 -91.143074)
		(end 109.991398 -77.077062)
		(width 0.11684)
		(layer "In2.Cu")
		(net "I3C_SCM_2_R_SDA")
	)
	(segment
		(start 43.403266 -148.847302)
		(end 43.440604 -148.809964)
		(width 0.11684)
		(layer "In2.Cu")
		(net "I3C_SCM_2_R_SDA")
	)
	(segment
		(start 59.008772 -133.103366)
		(end 59.147202 -133.103366)
		(width 0.11684)
		(layer "In2.Cu")
		(net "I3C_SCM_2_R_SDA")
	)
	(segment
		(start 39.931594 -172.702728)
		(end 39.931594 -169.298874)
		(width 0.11684)
		(layer "In2.Cu")
		(net "I3C_SCM_2_R_SDA")
	)
	(segment
		(start 39.931594 -169.298874)
		(end 43.403266 -165.827202)
		(width 0.11684)
		(layer "In2.Cu")
		(net "I3C_SCM_2_R_SDA")
	)
	(segment
		(start 43.440604 -148.809964)
		(end 43.440604 -148.671534)
		(width 0.11684)
		(layer "In2.Cu")
		(net "I3C_SCM_2_R_SDA")
	)
	(segment
		(start 109.991398 -77.077062)
		(end 112.09528 -74.97318)
		(width 0.11684)
		(layer "In2.Cu")
		(net "I3C_SCM_2_R_SDA")
	)
	(segment
		(start 159.846772 -13.76426)
		(end 150.310088 -13.76426)
		(width 0.11684)
		(layer "In11.Cu")
		(net "I3C_SCM_2_R_SDA")
	)
	(segment
		(start 181.381908 -13.64996)
		(end 180.04536 -12.313412)
		(width 0.11684)
		(layer "In11.Cu")
		(net "I3C_SCM_2_R_SDA")
	)
	(segment
		(start 104.170988 -35.416236)
		(end 106.16946 -37.414708)
		(width 0.11684)
		(layer "In11.Cu")
		(net "I3C_SCM_2_R_SDA")
	)
	(segment
		(start 136.880092 -9.28624)
		(end 134.61746 -11.548872)
		(width 0.11684)
		(layer "In11.Cu")
		(net "I3C_SCM_2_R_SDA")
	)
	(segment
		(start 177.97526 -9.298432)
		(end 177.97526 -8.142732)
		(width 0.11684)
		(layer "In11.Cu")
		(net "I3C_SCM_2_R_SDA")
	)
	(segment
		(start 104.170988 -30.946344)
		(end 104.170988 -35.416236)
		(width 0.11684)
		(layer "In11.Cu")
		(net "I3C_SCM_2_R_SDA")
	)
	(segment
		(start 180.04536 -11.368532)
		(end 177.97526 -9.298432)
		(width 0.11684)
		(layer "In11.Cu")
		(net "I3C_SCM_2_R_SDA")
	)
	(segment
		(start 184.98439 -14.247876)
		(end 184.386474 -13.64996)
		(width 0.11684)
		(layer "In11.Cu")
		(net "I3C_SCM_2_R_SDA")
	)
	(segment
		(start 105.902506 -62.323726)
		(end 112.09528 -68.5165)
		(width 0.11684)
		(layer "In11.Cu")
		(net "I3C_SCM_2_R_SDA")
	)
	(segment
		(start 177.383948 -7.55142)
		(end 171.779692 -7.55142)
		(width 0.11684)
		(layer "In11.Cu")
		(net "I3C_SCM_2_R_SDA")
	)
	(segment
		(start 127.710692 -16.40078)
		(end 122.897392 -21.21408)
		(width 0.11684)
		(layer "In11.Cu")
		(net "I3C_SCM_2_R_SDA")
	)
	(segment
		(start 164.045392 -9.56564)
		(end 159.846772 -13.76426)
		(width 0.11684)
		(layer "In11.Cu")
		(net "I3C_SCM_2_R_SDA")
	)
	(segment
		(start 171.779692 -7.55142)
		(end 169.765472 -9.56564)
		(width 0.11684)
		(layer "In11.Cu")
		(net "I3C_SCM_2_R_SDA")
	)
	(segment
		(start 150.310088 -13.76426)
		(end 145.832068 -9.28624)
		(width 0.11684)
		(layer "In11.Cu")
		(net "I3C_SCM_2_R_SDA")
	)
	(segment
		(start 169.765472 -9.56564)
		(end 164.045392 -9.56564)
		(width 0.11684)
		(layer "In11.Cu")
		(net "I3C_SCM_2_R_SDA")
	)
	(segment
		(start 122.897392 -21.21408)
		(end 113.903252 -21.21408)
		(width 0.11684)
		(layer "In11.Cu")
		(net "I3C_SCM_2_R_SDA")
	)
	(segment
		(start 113.903252 -21.21408)
		(end 104.170988 -30.946344)
		(width 0.11684)
		(layer "In11.Cu")
		(net "I3C_SCM_2_R_SDA")
	)
	(segment
		(start 112.09528 -68.5165)
		(end 112.09528 -74.97318)
		(width 0.11684)
		(layer "In11.Cu")
		(net "I3C_SCM_2_R_SDA")
	)
	(segment
		(start 106.16946 -37.414708)
		(end 106.16946 -51.932332)
		(width 0.11684)
		(layer "In11.Cu")
		(net "I3C_SCM_2_R_SDA")
	)
	(segment
		(start 184.386474 -13.64996)
		(end 181.381908 -13.64996)
		(width 0.11684)
		(layer "In11.Cu")
		(net "I3C_SCM_2_R_SDA")
	)
	(segment
		(start 145.832068 -9.28624)
		(end 136.880092 -9.28624)
		(width 0.11684)
		(layer "In11.Cu")
		(net "I3C_SCM_2_R_SDA")
	)
	(segment
		(start 131.629912 -16.40078)
		(end 127.710692 -16.40078)
		(width 0.11684)
		(layer "In11.Cu")
		(net "I3C_SCM_2_R_SDA")
	)
	(segment
		(start 105.902506 -52.199286)
		(end 105.902506 -62.323726)
		(width 0.11684)
		(layer "In11.Cu")
		(net "I3C_SCM_2_R_SDA")
	)
	(segment
		(start 180.04536 -12.313412)
		(end 180.04536 -11.368532)
		(width 0.11684)
		(layer "In11.Cu")
		(net "I3C_SCM_2_R_SDA")
	)
	(segment
		(start 134.61746 -13.413232)
		(end 131.629912 -16.40078)
		(width 0.11684)
		(layer "In11.Cu")
		(net "I3C_SCM_2_R_SDA")
	)
	(segment
		(start 134.61746 -11.548872)
		(end 134.61746 -13.413232)
		(width 0.11684)
		(layer "In11.Cu")
		(net "I3C_SCM_2_R_SDA")
	)
	(segment
		(start 177.97526 -8.142732)
		(end 177.383948 -7.55142)
		(width 0.11684)
		(layer "In11.Cu")
		(net "I3C_SCM_2_R_SDA")
	)
	(segment
		(start 106.16946 -51.932332)
		(end 105.902506 -52.199286)
		(width 0.11684)
		(layer "In11.Cu")
		(net "I3C_SCM_2_R_SDA")
	)
	(segment
		(start 184.98439 -14.76629)
		(end 184.98439 -14.247876)
		(width 0.11684)
		(layer "In11.Cu")
		(net "I3C_SCM_2_R_SDA")
	)
	(segment
		(start 41.593262 -172.922946)
		(end 42.237914 -172.922946)
		(width 0.10668)
		(layer "F.Cu")
		(net "I3C_SCM_2_R_SCL")
	)
	(segment
		(start 41.270428 -172.547026)
		(end 41.270428 -172.600112)
		(width 0.10668)
		(layer "F.Cu")
		(net "I3C_SCM_2_R_SCL")
	)
	(segment
		(start 39.42715 -172.230542)
		(end 40.953944 -172.230542)
		(width 0.10668)
		(layer "F.Cu")
		(net "I3C_SCM_2_R_SCL")
	)
	(segment
		(start 40.953944 -172.230542)
		(end 41.270428 -172.547026)
		(width 0.10668)
		(layer "F.Cu")
		(net "I3C_SCM_2_R_SCL")
	)
	(segment
		(start 41.270428 -172.600112)
		(end 41.593262 -172.922946)
		(width 0.10668)
		(layer "F.Cu")
		(net "I3C_SCM_2_R_SCL")
	)
	(via
		(at 185.61939 -14.749272)
		(size 0.508)
		(drill 0.254)
		(layers "F.Cu" "B.Cu")
		(net "I3C_SCM_2_R_SCL")
	)
	(via
		(at 41.270428 -172.547026)
		(size 0.508)
		(drill 0.254)
		(layers "F.Cu" "B.Cu")
		(net "I3C_SCM_2_R_SCL")
	)
	(via
		(at 112.09528 -76.49718)
		(size 0.508)
		(drill 0.254)
		(layers "F.Cu" "B.Cu")
		(net "I3C_SCM_2_R_SCL")
	)
	(segment
		(start 186.345322 -14.00048)
		(end 186.345322 -14.02334)
		(width 0.10668)
		(layer "B.Cu")
		(net "I3C_SCM_2_R_SCL")
	)
	(segment
		(start 186.345322 -14.02334)
		(end 185.61939 -14.749272)
		(width 0.10668)
		(layer "B.Cu")
		(net "I3C_SCM_2_R_SCL")
	)
	(segment
		(start 110.60938 -77.98308)
		(end 112.09528 -76.49718)
		(width 0.11684)
		(layer "In2.Cu")
		(net "I3C_SCM_2_R_SCL")
	)
	(segment
		(start 59.395868 -133.702806)
		(end 63.790576 -129.308098)
		(width 0.11684)
		(layer "In2.Cu")
		(net "I3C_SCM_2_R_SCL")
	)
	(segment
		(start 41.270428 -171.350686)
		(end 40.617648 -170.697906)
		(width 0.11684)
		(layer "In2.Cu")
		(net "I3C_SCM_2_R_SCL")
	)
	(segment
		(start 44.040044 -148.919946)
		(end 59.257184 -133.702806)
		(width 0.11684)
		(layer "In2.Cu")
		(net "I3C_SCM_2_R_SCL")
	)
	(segment
		(start 44.021248 -149.077426)
		(end 44.040044 -149.05863)
		(width 0.11684)
		(layer "In2.Cu")
		(net "I3C_SCM_2_R_SCL")
	)
	(segment
		(start 63.790576 -129.308098)
		(end 72.700388 -129.308098)
		(width 0.11684)
		(layer "In2.Cu")
		(net "I3C_SCM_2_R_SCL")
	)
	(segment
		(start 110.60938 -91.399106)
		(end 110.60938 -77.98308)
		(width 0.11684)
		(layer "In2.Cu")
		(net "I3C_SCM_2_R_SCL")
	)
	(segment
		(start 44.040044 -149.05863)
		(end 44.040044 -148.919946)
		(width 0.11684)
		(layer "In2.Cu")
		(net "I3C_SCM_2_R_SCL")
	)
	(segment
		(start 59.257184 -133.702806)
		(end 59.395868 -133.702806)
		(width 0.11684)
		(layer "In2.Cu")
		(net "I3C_SCM_2_R_SCL")
	)
	(segment
		(start 40.617648 -170.697906)
		(end 40.617648 -169.611294)
		(width 0.11684)
		(layer "In2.Cu")
		(net "I3C_SCM_2_R_SCL")
	)
	(segment
		(start 40.617648 -169.611294)
		(end 44.021248 -166.207694)
		(width 0.11684)
		(layer "In2.Cu")
		(net "I3C_SCM_2_R_SCL")
	)
	(segment
		(start 44.021248 -166.207694)
		(end 44.021248 -149.077426)
		(width 0.11684)
		(layer "In2.Cu")
		(net "I3C_SCM_2_R_SCL")
	)
	(segment
		(start 41.270428 -172.547026)
		(end 41.270428 -171.350686)
		(width 0.11684)
		(layer "In2.Cu")
		(net "I3C_SCM_2_R_SCL")
	)
	(segment
		(start 72.700388 -129.308098)
		(end 110.60938 -91.399106)
		(width 0.11684)
		(layer "In2.Cu")
		(net "I3C_SCM_2_R_SCL")
	)
	(segment
		(start 112.905032 -20.394676)
		(end 122.868944 -20.394676)
		(width 0.11684)
		(layer "In11.Cu")
		(net "I3C_SCM_2_R_SCL")
	)
	(segment
		(start 122.868944 -20.394676)
		(end 127.46228 -15.80134)
		(width 0.11684)
		(layer "In11.Cu")
		(net "I3C_SCM_2_R_SCL")
	)
	(segment
		(start 134.01802 -11.30046)
		(end 136.63168 -8.6868)
		(width 0.11684)
		(layer "In11.Cu")
		(net "I3C_SCM_2_R_SCL")
	)
	(segment
		(start 136.63168 -8.6868)
		(end 146.08048 -8.6868)
		(width 0.11684)
		(layer "In11.Cu")
		(net "I3C_SCM_2_R_SCL")
	)
	(segment
		(start 105.24998 -52.00396)
		(end 105.57002 -51.68392)
		(width 0.11684)
		(layer "In11.Cu")
		(net "I3C_SCM_2_R_SCL")
	)
	(segment
		(start 105.57002 -51.68392)
		(end 105.57002 -37.66312)
		(width 0.11684)
		(layer "In11.Cu")
		(net "I3C_SCM_2_R_SCL")
	)
	(segment
		(start 105.24998 -62.519052)
		(end 105.24998 -52.00396)
		(width 0.11684)
		(layer "In11.Cu")
		(net "I3C_SCM_2_R_SCL")
	)
	(segment
		(start 127.46228 -15.80134)
		(end 131.3815 -15.80134)
		(width 0.11684)
		(layer "In11.Cu")
		(net "I3C_SCM_2_R_SCL")
	)
	(segment
		(start 146.08048 -8.6868)
		(end 150.5585 -13.16482)
		(width 0.11684)
		(layer "In11.Cu")
		(net "I3C_SCM_2_R_SCL")
	)
	(segment
		(start 185.64606 -14.722602)
		(end 185.61939 -14.749272)
		(width 0.11684)
		(layer "In11.Cu")
		(net "I3C_SCM_2_R_SCL")
	)
	(segment
		(start 163.79698 -8.9662)
		(end 169.51706 -8.9662)
		(width 0.11684)
		(layer "In11.Cu")
		(net "I3C_SCM_2_R_SCL")
	)
	(segment
		(start 134.01802 -13.16482)
		(end 134.01802 -11.30046)
		(width 0.11684)
		(layer "In11.Cu")
		(net "I3C_SCM_2_R_SCL")
	)
	(segment
		(start 169.51706 -8.9662)
		(end 171.53128 -6.95198)
		(width 0.11684)
		(layer "In11.Cu")
		(net "I3C_SCM_2_R_SCL")
	)
	(segment
		(start 150.5585 -13.16482)
		(end 159.59836 -13.16482)
		(width 0.11684)
		(layer "In11.Cu")
		(net "I3C_SCM_2_R_SCL")
	)
	(segment
		(start 112.47882 -20.820888)
		(end 112.905032 -20.394676)
		(width 0.11684)
		(layer "In11.Cu")
		(net "I3C_SCM_2_R_SCL")
	)
	(segment
		(start 180.6448 -12.065)
		(end 181.63032 -13.05052)
		(width 0.11684)
		(layer "In11.Cu")
		(net "I3C_SCM_2_R_SCL")
	)
	(segment
		(start 181.63032 -13.05052)
		(end 184.634886 -13.05052)
		(width 0.11684)
		(layer "In11.Cu")
		(net "I3C_SCM_2_R_SCL")
	)
	(segment
		(start 103.55072 -30.71876)
		(end 112.47882 -21.79066)
		(width 0.11684)
		(layer "In11.Cu")
		(net "I3C_SCM_2_R_SCL")
	)
	(segment
		(start 131.3815 -15.80134)
		(end 134.01802 -13.16482)
		(width 0.11684)
		(layer "In11.Cu")
		(net "I3C_SCM_2_R_SCL")
	)
	(segment
		(start 171.53128 -6.95198)
		(end 177.63236 -6.95198)
		(width 0.11684)
		(layer "In11.Cu")
		(net "I3C_SCM_2_R_SCL")
	)
	(segment
		(start 178.5747 -7.89432)
		(end 178.5747 -9.05002)
		(width 0.11684)
		(layer "In11.Cu")
		(net "I3C_SCM_2_R_SCL")
	)
	(segment
		(start 105.57002 -37.66312)
		(end 103.55072 -35.64382)
		(width 0.11684)
		(layer "In11.Cu")
		(net "I3C_SCM_2_R_SCL")
	)
	(segment
		(start 180.6448 -11.12012)
		(end 180.6448 -12.065)
		(width 0.11684)
		(layer "In11.Cu")
		(net "I3C_SCM_2_R_SCL")
	)
	(segment
		(start 177.63236 -6.95198)
		(end 178.5747 -7.89432)
		(width 0.11684)
		(layer "In11.Cu")
		(net "I3C_SCM_2_R_SCL")
	)
	(segment
		(start 112.09528 -76.49718)
		(end 111.49584 -75.89774)
		(width 0.11684)
		(layer "In11.Cu")
		(net "I3C_SCM_2_R_SCL")
	)
	(segment
		(start 184.634886 -13.05052)
		(end 185.64606 -14.061694)
		(width 0.11684)
		(layer "In11.Cu")
		(net "I3C_SCM_2_R_SCL")
	)
	(segment
		(start 111.49584 -68.764912)
		(end 105.24998 -62.519052)
		(width 0.11684)
		(layer "In11.Cu")
		(net "I3C_SCM_2_R_SCL")
	)
	(segment
		(start 185.64606 -14.061694)
		(end 185.64606 -14.722602)
		(width 0.11684)
		(layer "In11.Cu")
		(net "I3C_SCM_2_R_SCL")
	)
	(segment
		(start 159.59836 -13.16482)
		(end 163.79698 -8.9662)
		(width 0.11684)
		(layer "In11.Cu")
		(net "I3C_SCM_2_R_SCL")
	)
	(segment
		(start 111.49584 -75.89774)
		(end 111.49584 -68.764912)
		(width 0.11684)
		(layer "In11.Cu")
		(net "I3C_SCM_2_R_SCL")
	)
	(segment
		(start 103.55072 -35.64382)
		(end 103.55072 -30.71876)
		(width 0.11684)
		(layer "In11.Cu")
		(net "I3C_SCM_2_R_SCL")
	)
	(segment
		(start 178.5747 -9.05002)
		(end 180.6448 -11.12012)
		(width 0.11684)
		(layer "In11.Cu")
		(net "I3C_SCM_2_R_SCL")
	)
	(segment
		(start 112.47882 -21.79066)
		(end 112.47882 -20.820888)
		(width 0.11684)
		(layer "In11.Cu")
		(net "I3C_SCM_2_R_SCL")
	)
	(segment
		(start 441.833508 -169.726864)
		(end 441.833508 -169.829988)
		(width 0.10668)
		(layer "F.Cu")
		(net "I3C_SCM_1_R_SDA")
	)
	(segment
		(start 441.832492 -169.725848)
		(end 441.833508 -169.726864)
		(width 0.10668)
		(layer "F.Cu")
		(net "I3C_SCM_1_R_SDA")
	)
	(segment
		(start 441.833508 -169.829988)
		(end 441.198508 -170.464988)
		(width 0.10668)
		(layer "F.Cu")
		(net "I3C_SCM_1_R_SDA")
	)
	(segment
		(start 441.198508 -170.464988)
		(end 441.198508 -170.559476)
		(width 0.10668)
		(layer "F.Cu")
		(net "I3C_SCM_1_R_SDA")
	)
	(segment
		(start 439.16727 -169.504868)
		(end 440.470036 -169.504868)
		(width 0.10668)
		(layer "F.Cu")
		(net "I3C_SCM_1_R_SDA")
	)
	(segment
		(start 440.691016 -169.725848)
		(end 441.832492 -169.725848)
		(width 0.10668)
		(layer "F.Cu")
		(net "I3C_SCM_1_R_SDA")
	)
	(segment
		(start 440.470036 -169.504868)
		(end 440.691016 -169.725848)
		(width 0.10668)
		(layer "F.Cu")
		(net "I3C_SCM_1_R_SDA")
	)
	(segment
		(start 439.128916 -169.466514)
		(end 439.16727 -169.504868)
		(width 0.10668)
		(layer "F.Cu")
		(net "I3C_SCM_1_R_SDA")
	)
	(via
		(at 308.9402 -120.823228)
		(size 0.508)
		(drill 0.254)
		(layers "F.Cu" "B.Cu")
		(net "I3C_SCM_1_R_SDA")
	)
	(via
		(at 441.198508 -170.559476)
		(size 0.508)
		(drill 0.254)
		(layers "F.Cu" "B.Cu")
		(net "I3C_SCM_1_R_SDA")
	)
	(via
		(at 219.941648 -22.670008)
		(size 0.508)
		(drill 0.254)
		(layers "F.Cu" "B.Cu")
		(net "I3C_SCM_1_R_SDA")
	)
	(via
		(at 187.60186 -15.206472)
		(size 0.508)
		(drill 0.254)
		(layers "F.Cu" "B.Cu")
		(net "I3C_SCM_1_R_SDA")
	)
	(segment
		(start 187.60186 -14.44498)
		(end 187.60186 -15.206472)
		(width 0.10668)
		(layer "B.Cu")
		(net "I3C_SCM_1_R_SDA")
	)
	(segment
		(start 187.349384 -14.192504)
		(end 187.60186 -14.44498)
		(width 0.10668)
		(layer "B.Cu")
		(net "I3C_SCM_1_R_SDA")
	)
	(segment
		(start 187.349384 -14.00048)
		(end 187.349384 -14.192504)
		(width 0.10668)
		(layer "B.Cu")
		(net "I3C_SCM_1_R_SDA")
	)
	(segment
		(start 402.781262 -131.229862)
		(end 354.253546 -131.229862)
		(width 0.11684)
		(layer "In2.Cu")
		(net "I3C_SCM_1_R_SDA")
	)
	(segment
		(start 347.698568 -132.639562)
		(end 343.174574 -128.115568)
		(width 0.11684)
		(layer "In2.Cu")
		(net "I3C_SCM_1_R_SDA")
	)
	(segment
		(start 443.893448 -166.385748)
		(end 441.656216 -164.148516)
		(width 0.11684)
		(layer "In2.Cu")
		(net "I3C_SCM_1_R_SDA")
	)
	(segment
		(start 443.343284 -169.137076)
		(end 443.893448 -168.586912)
		(width 0.11684)
		(layer "In2.Cu")
		(net "I3C_SCM_1_R_SDA")
	)
	(segment
		(start 207.859122 -15.067534)
		(end 211.642452 -18.850864)
		(width 0.11684)
		(layer "In2.Cu")
		(net "I3C_SCM_1_R_SDA")
	)
	(segment
		(start 216.122504 -18.850864)
		(end 219.941648 -22.670008)
		(width 0.11684)
		(layer "In2.Cu")
		(net "I3C_SCM_1_R_SDA")
	)
	(segment
		(start 211.642452 -18.850864)
		(end 216.122504 -18.850864)
		(width 0.11684)
		(layer "In2.Cu")
		(net "I3C_SCM_1_R_SDA")
	)
	(segment
		(start 316.602364 -128.115568)
		(end 309.310024 -120.823228)
		(width 0.11684)
		(layer "In2.Cu")
		(net "I3C_SCM_1_R_SDA")
	)
	(segment
		(start 343.174574 -128.115568)
		(end 316.602364 -128.115568)
		(width 0.11684)
		(layer "In2.Cu")
		(net "I3C_SCM_1_R_SDA")
	)
	(segment
		(start 432.048666 -144.14246)
		(end 416.852608 -128.946402)
		(width 0.11684)
		(layer "In2.Cu")
		(net "I3C_SCM_1_R_SDA")
	)
	(segment
		(start 354.253546 -131.229862)
		(end 352.843846 -132.639562)
		(width 0.11684)
		(layer "In2.Cu")
		(net "I3C_SCM_1_R_SDA")
	)
	(segment
		(start 441.198508 -169.94505)
		(end 442.006482 -169.137076)
		(width 0.11684)
		(layer "In2.Cu")
		(net "I3C_SCM_1_R_SDA")
	)
	(segment
		(start 441.656216 -164.148516)
		(end 441.13196 -164.148516)
		(width 0.11684)
		(layer "In2.Cu")
		(net "I3C_SCM_1_R_SDA")
	)
	(segment
		(start 441.198508 -170.559476)
		(end 441.198508 -169.94505)
		(width 0.11684)
		(layer "In2.Cu")
		(net "I3C_SCM_1_R_SDA")
	)
	(segment
		(start 441.13196 -164.148516)
		(end 432.048666 -155.065222)
		(width 0.11684)
		(layer "In2.Cu")
		(net "I3C_SCM_1_R_SDA")
	)
	(segment
		(start 188.413644 -13.650468)
		(end 190.259716 -13.650468)
		(width 0.11684)
		(layer "In2.Cu")
		(net "I3C_SCM_1_R_SDA")
	)
	(segment
		(start 190.259716 -13.650468)
		(end 191.337438 -14.097)
		(width 0.11684)
		(layer "In2.Cu")
		(net "I3C_SCM_1_R_SDA")
	)
	(segment
		(start 309.310024 -120.823228)
		(end 308.9402 -120.823228)
		(width 0.11684)
		(layer "In2.Cu")
		(net "I3C_SCM_1_R_SDA")
	)
	(segment
		(start 432.048666 -155.065222)
		(end 432.048666 -144.14246)
		(width 0.11684)
		(layer "In2.Cu")
		(net "I3C_SCM_1_R_SDA")
	)
	(segment
		(start 442.006482 -169.137076)
		(end 443.343284 -169.137076)
		(width 0.11684)
		(layer "In2.Cu")
		(net "I3C_SCM_1_R_SDA")
	)
	(segment
		(start 187.55106 -14.513052)
		(end 188.413644 -13.650468)
		(width 0.11684)
		(layer "In2.Cu")
		(net "I3C_SCM_1_R_SDA")
	)
	(segment
		(start 187.55106 -15.155672)
		(end 187.55106 -14.513052)
		(width 0.11684)
		(layer "In2.Cu")
		(net "I3C_SCM_1_R_SDA")
	)
	(segment
		(start 352.843846 -132.639562)
		(end 347.698568 -132.639562)
		(width 0.11684)
		(layer "In2.Cu")
		(net "I3C_SCM_1_R_SDA")
	)
	(segment
		(start 416.852608 -128.946402)
		(end 405.064722 -128.946402)
		(width 0.11684)
		(layer "In2.Cu")
		(net "I3C_SCM_1_R_SDA")
	)
	(segment
		(start 187.60186 -15.206472)
		(end 187.55106 -15.155672)
		(width 0.11684)
		(layer "In2.Cu")
		(net "I3C_SCM_1_R_SDA")
	)
	(segment
		(start 194.571874 -14.097)
		(end 195.542408 -15.067534)
		(width 0.11684)
		(layer "In2.Cu")
		(net "I3C_SCM_1_R_SDA")
	)
	(segment
		(start 191.337438 -14.097)
		(end 194.571874 -14.097)
		(width 0.11684)
		(layer "In2.Cu")
		(net "I3C_SCM_1_R_SDA")
	)
	(segment
		(start 195.542408 -15.067534)
		(end 207.859122 -15.067534)
		(width 0.11684)
		(layer "In2.Cu")
		(net "I3C_SCM_1_R_SDA")
	)
	(segment
		(start 405.064722 -128.946402)
		(end 402.781262 -131.229862)
		(width 0.11684)
		(layer "In2.Cu")
		(net "I3C_SCM_1_R_SDA")
	)
	(segment
		(start 443.893448 -168.586912)
		(end 443.893448 -166.385748)
		(width 0.11684)
		(layer "In2.Cu")
		(net "I3C_SCM_1_R_SDA")
	)
	(segment
		(start 297.693334 -108.29036)
		(end 301.64024 -108.29036)
		(width 0.11684)
		(layer "In4.Cu")
		(net "I3C_SCM_1_R_SDA")
	)
	(segment
		(start 302.94326 -113.540286)
		(end 308.9402 -119.537226)
		(width 0.11684)
		(layer "In4.Cu")
		(net "I3C_SCM_1_R_SDA")
	)
	(segment
		(start 232.364026 -47.997872)
		(end 234.866688 -50.500534)
		(width 0.11684)
		(layer "In4.Cu")
		(net "I3C_SCM_1_R_SDA")
	)
	(segment
		(start 274.336256 -58.834528)
		(end 286.499554 -70.997826)
		(width 0.11684)
		(layer "In4.Cu")
		(net "I3C_SCM_1_R_SDA")
	)
	(segment
		(start 258.16687 -59.210956)
		(end 259.397246 -59.210956)
		(width 0.11684)
		(layer "In4.Cu")
		(net "I3C_SCM_1_R_SDA")
	)
	(segment
		(start 242.6843 -53.223668)
		(end 242.6843 -55.652162)
		(width 0.11684)
		(layer "In4.Cu")
		(net "I3C_SCM_1_R_SDA")
	)
	(segment
		(start 286.499554 -70.997826)
		(end 286.499554 -97.09658)
		(width 0.11684)
		(layer "In4.Cu")
		(net "I3C_SCM_1_R_SDA")
	)
	(segment
		(start 225.321622 -41.38549)
		(end 230.28656 -41.38549)
		(width 0.11684)
		(layer "In4.Cu")
		(net "I3C_SCM_1_R_SDA")
	)
	(segment
		(start 259.773674 -58.834528)
		(end 274.336256 -58.834528)
		(width 0.11684)
		(layer "In4.Cu")
		(net "I3C_SCM_1_R_SDA")
	)
	(segment
		(start 244.799866 -57.767728)
		(end 256.723642 -57.767728)
		(width 0.11684)
		(layer "In4.Cu")
		(net "I3C_SCM_1_R_SDA")
	)
	(segment
		(start 302.94326 -109.59338)
		(end 302.94326 -113.540286)
		(width 0.11684)
		(layer "In4.Cu")
		(net "I3C_SCM_1_R_SDA")
	)
	(segment
		(start 242.6843 -55.652162)
		(end 244.799866 -57.767728)
		(width 0.11684)
		(layer "In4.Cu")
		(net "I3C_SCM_1_R_SDA")
	)
	(segment
		(start 234.866688 -50.500534)
		(end 239.961166 -50.500534)
		(width 0.11684)
		(layer "In4.Cu")
		(net "I3C_SCM_1_R_SDA")
	)
	(segment
		(start 301.64024 -108.29036)
		(end 302.94326 -109.59338)
		(width 0.11684)
		(layer "In4.Cu")
		(net "I3C_SCM_1_R_SDA")
	)
	(segment
		(start 219.941648 -22.670008)
		(end 219.941648 -36.005516)
		(width 0.11684)
		(layer "In4.Cu")
		(net "I3C_SCM_1_R_SDA")
	)
	(segment
		(start 232.364026 -43.462956)
		(end 232.364026 -47.997872)
		(width 0.11684)
		(layer "In4.Cu")
		(net "I3C_SCM_1_R_SDA")
	)
	(segment
		(start 239.961166 -50.500534)
		(end 242.6843 -53.223668)
		(width 0.11684)
		(layer "In4.Cu")
		(net "I3C_SCM_1_R_SDA")
	)
	(segment
		(start 308.9402 -119.537226)
		(end 308.9402 -120.823228)
		(width 0.11684)
		(layer "In4.Cu")
		(net "I3C_SCM_1_R_SDA")
	)
	(segment
		(start 230.28656 -41.38549)
		(end 232.364026 -43.462956)
		(width 0.11684)
		(layer "In4.Cu")
		(net "I3C_SCM_1_R_SDA")
	)
	(segment
		(start 286.499554 -97.09658)
		(end 297.693334 -108.29036)
		(width 0.11684)
		(layer "In4.Cu")
		(net "I3C_SCM_1_R_SDA")
	)
	(segment
		(start 259.397246 -59.210956)
		(end 259.773674 -58.834528)
		(width 0.11684)
		(layer "In4.Cu")
		(net "I3C_SCM_1_R_SDA")
	)
	(segment
		(start 256.723642 -57.767728)
		(end 258.16687 -59.210956)
		(width 0.11684)
		(layer "In4.Cu")
		(net "I3C_SCM_1_R_SDA")
	)
	(segment
		(start 219.941648 -36.005516)
		(end 225.321622 -41.38549)
		(width 0.11684)
		(layer "In4.Cu")
		(net "I3C_SCM_1_R_SDA")
	)
	(segment
		(start 440.61634 -168.710864)
		(end 441.833508 -168.710864)
		(width 0.10668)
		(layer "F.Cu")
		(net "I3C_SCM_1_R_SCL")
	)
	(segment
		(start 441.833508 -168.710864)
		(end 441.833508 -168.27754)
		(width 0.10668)
		(layer "F.Cu")
		(net "I3C_SCM_1_R_SCL")
	)
	(segment
		(start 442.20892 -167.902128)
		(end 442.545724 -167.902128)
		(width 0.10668)
		(layer "F.Cu")
		(net "I3C_SCM_1_R_SCL")
	)
	(segment
		(start 441.833508 -168.27754)
		(end 442.20892 -167.902128)
		(width 0.10668)
		(layer "F.Cu")
		(net "I3C_SCM_1_R_SCL")
	)
	(segment
		(start 439.128916 -168.966388)
		(end 440.360816 -168.966388)
		(width 0.10668)
		(layer "F.Cu")
		(net "I3C_SCM_1_R_SCL")
	)
	(segment
		(start 440.360816 -168.966388)
		(end 440.61634 -168.710864)
		(width 0.10668)
		(layer "F.Cu")
		(net "I3C_SCM_1_R_SCL")
	)
	(via
		(at 188.167518 -14.859762)
		(size 0.508)
		(drill 0.254)
		(layers "F.Cu" "B.Cu")
		(net "I3C_SCM_1_R_SCL")
	)
	(via
		(at 308.0258 -120.830848)
		(size 0.508)
		(drill 0.254)
		(layers "F.Cu" "B.Cu")
		(net "I3C_SCM_1_R_SCL")
	)
	(via
		(at 442.545724 -167.902128)
		(size 0.508)
		(drill 0.254)
		(layers "F.Cu" "B.Cu")
		(net "I3C_SCM_1_R_SCL")
	)
	(via
		(at 219.289122 -22.865334)
		(size 0.508)
		(drill 0.254)
		(layers "F.Cu" "B.Cu")
		(net "I3C_SCM_1_R_SCL")
	)
	(segment
		(start 188.310012 -14.717268)
		(end 188.167518 -14.859762)
		(width 0.10668)
		(layer "B.Cu")
		(net "I3C_SCM_1_R_SCL")
	)
	(segment
		(start 188.310012 -14.00048)
		(end 188.310012 -14.717268)
		(width 0.10668)
		(layer "B.Cu")
		(net "I3C_SCM_1_R_SCL")
	)
	(segment
		(start 405.313134 -129.545842)
		(end 403.029674 -131.829302)
		(width 0.11684)
		(layer "In2.Cu")
		(net "I3C_SCM_1_R_SCL")
	)
	(segment
		(start 207.61071 -15.666974)
		(end 211.489798 -19.546062)
		(width 0.11684)
		(layer "In2.Cu")
		(net "I3C_SCM_1_R_SCL")
	)
	(segment
		(start 188.777372 -14.249908)
		(end 190.08725 -14.249908)
		(width 0.11684)
		(layer "In2.Cu")
		(net "I3C_SCM_1_R_SCL")
	)
	(segment
		(start 215.96985 -19.546062)
		(end 219.289122 -22.865334)
		(width 0.11684)
		(layer "In2.Cu")
		(net "I3C_SCM_1_R_SCL")
	)
	(segment
		(start 431.140616 -144.082516)
		(end 416.603942 -129.545842)
		(width 0.11684)
		(layer "In2.Cu")
		(net "I3C_SCM_1_R_SCL")
	)
	(segment
		(start 347.333824 -133.240272)
		(end 342.80856 -128.715008)
		(width 0.11684)
		(layer "In2.Cu")
		(net "I3C_SCM_1_R_SCL")
	)
	(segment
		(start 416.603942 -129.545842)
		(end 405.313134 -129.545842)
		(width 0.11684)
		(layer "In2.Cu")
		(net "I3C_SCM_1_R_SCL")
	)
	(segment
		(start 188.167518 -14.859762)
		(end 188.777372 -14.249908)
		(width 0.11684)
		(layer "In2.Cu")
		(net "I3C_SCM_1_R_SCL")
	)
	(segment
		(start 442.545724 -167.902128)
		(end 442.545724 -165.885876)
		(width 0.11684)
		(layer "In2.Cu")
		(net "I3C_SCM_1_R_SCL")
	)
	(segment
		(start 308.72176 -121.526808)
		(end 308.0258 -120.830848)
		(width 0.11684)
		(layer "In2.Cu")
		(net "I3C_SCM_1_R_SCL")
	)
	(segment
		(start 431.140616 -155.005024)
		(end 431.140616 -144.082516)
		(width 0.11684)
		(layer "In2.Cu")
		(net "I3C_SCM_1_R_SCL")
	)
	(segment
		(start 308.947566 -121.526808)
		(end 308.72176 -121.526808)
		(width 0.11684)
		(layer "In2.Cu")
		(net "I3C_SCM_1_R_SCL")
	)
	(segment
		(start 316.135766 -128.715008)
		(end 308.947566 -121.526808)
		(width 0.11684)
		(layer "In2.Cu")
		(net "I3C_SCM_1_R_SCL")
	)
	(segment
		(start 190.08725 -14.249908)
		(end 191.361822 -14.77772)
		(width 0.11684)
		(layer "In2.Cu")
		(net "I3C_SCM_1_R_SCL")
	)
	(segment
		(start 211.489798 -19.546062)
		(end 215.96985 -19.546062)
		(width 0.11684)
		(layer "In2.Cu")
		(net "I3C_SCM_1_R_SCL")
	)
	(segment
		(start 191.361822 -14.77772)
		(end 194.340734 -14.77772)
		(width 0.11684)
		(layer "In2.Cu")
		(net "I3C_SCM_1_R_SCL")
	)
	(segment
		(start 441.407804 -164.747956)
		(end 440.883548 -164.747956)
		(width 0.11684)
		(layer "In2.Cu")
		(net "I3C_SCM_1_R_SCL")
	)
	(segment
		(start 403.029674 -131.829302)
		(end 354.527866 -131.829302)
		(width 0.11684)
		(layer "In2.Cu")
		(net "I3C_SCM_1_R_SCL")
	)
	(segment
		(start 354.527866 -131.829302)
		(end 353.116896 -133.240272)
		(width 0.11684)
		(layer "In2.Cu")
		(net "I3C_SCM_1_R_SCL")
	)
	(segment
		(start 442.545724 -165.885876)
		(end 441.407804 -164.747956)
		(width 0.11684)
		(layer "In2.Cu")
		(net "I3C_SCM_1_R_SCL")
	)
	(segment
		(start 195.229988 -15.666974)
		(end 207.61071 -15.666974)
		(width 0.11684)
		(layer "In2.Cu")
		(net "I3C_SCM_1_R_SCL")
	)
	(segment
		(start 440.883548 -164.747956)
		(end 431.140616 -155.005024)
		(width 0.11684)
		(layer "In2.Cu")
		(net "I3C_SCM_1_R_SCL")
	)
	(segment
		(start 353.116896 -133.240272)
		(end 347.333824 -133.240272)
		(width 0.11684)
		(layer "In2.Cu")
		(net "I3C_SCM_1_R_SCL")
	)
	(segment
		(start 194.340734 -14.77772)
		(end 195.229988 -15.666974)
		(width 0.11684)
		(layer "In2.Cu")
		(net "I3C_SCM_1_R_SCL")
	)
	(segment
		(start 342.80856 -128.715008)
		(end 316.135766 -128.715008)
		(width 0.11684)
		(layer "In2.Cu")
		(net "I3C_SCM_1_R_SCL")
	)
	(segment
		(start 231.764586 -43.711368)
		(end 231.764586 -48.246284)
		(width 0.11684)
		(layer "In4.Cu")
		(net "I3C_SCM_1_R_SCL")
	)
	(segment
		(start 242.05946 -53.500528)
		(end 242.05946 -55.908448)
		(width 0.11684)
		(layer "In4.Cu")
		(net "I3C_SCM_1_R_SCL")
	)
	(segment
		(start 274.087844 -59.433968)
		(end 285.900114 -71.246238)
		(width 0.11684)
		(layer "In4.Cu")
		(net "I3C_SCM_1_R_SCL")
	)
	(segment
		(start 242.05946 -55.908448)
		(end 244.52072 -58.369708)
		(width 0.11684)
		(layer "In4.Cu")
		(net "I3C_SCM_1_R_SCL")
	)
	(segment
		(start 239.65916 -51.100228)
		(end 242.05946 -53.500528)
		(width 0.11684)
		(layer "In4.Cu")
		(net "I3C_SCM_1_R_SCL")
	)
	(segment
		(start 260.625336 -59.433968)
		(end 274.087844 -59.433968)
		(width 0.11684)
		(layer "In4.Cu")
		(net "I3C_SCM_1_R_SCL")
	)
	(segment
		(start 219.289122 -22.865334)
		(end 219.289122 -36.276026)
		(width 0.11684)
		(layer "In4.Cu")
		(net "I3C_SCM_1_R_SCL")
	)
	(segment
		(start 254.783844 -59.824366)
		(end 260.234938 -59.824366)
		(width 0.11684)
		(layer "In4.Cu")
		(net "I3C_SCM_1_R_SCL")
	)
	(segment
		(start 231.764586 -48.246284)
		(end 234.61853 -51.100228)
		(width 0.11684)
		(layer "In4.Cu")
		(net "I3C_SCM_1_R_SCL")
	)
	(segment
		(start 302.34382 -109.841792)
		(end 302.34382 -113.788698)
		(width 0.11684)
		(layer "In4.Cu")
		(net "I3C_SCM_1_R_SCL")
	)
	(segment
		(start 230.038148 -41.98493)
		(end 231.764586 -43.711368)
		(width 0.11684)
		(layer "In4.Cu")
		(net "I3C_SCM_1_R_SCL")
	)
	(segment
		(start 260.234938 -59.824366)
		(end 260.625336 -59.433968)
		(width 0.11684)
		(layer "In4.Cu")
		(net "I3C_SCM_1_R_SCL")
	)
	(segment
		(start 285.900114 -71.246238)
		(end 285.900114 -97.344992)
		(width 0.11684)
		(layer "In4.Cu")
		(net "I3C_SCM_1_R_SCL")
	)
	(segment
		(start 253.329186 -58.369708)
		(end 254.783844 -59.824366)
		(width 0.11684)
		(layer "In4.Cu")
		(net "I3C_SCM_1_R_SCL")
	)
	(segment
		(start 244.52072 -58.369708)
		(end 253.329186 -58.369708)
		(width 0.11684)
		(layer "In4.Cu")
		(net "I3C_SCM_1_R_SCL")
	)
	(segment
		(start 297.444922 -108.8898)
		(end 301.391828 -108.8898)
		(width 0.11684)
		(layer "In4.Cu")
		(net "I3C_SCM_1_R_SCL")
	)
	(segment
		(start 308.0258 -119.470678)
		(end 308.0258 -120.830848)
		(width 0.11684)
		(layer "In4.Cu")
		(net "I3C_SCM_1_R_SCL")
	)
	(segment
		(start 285.900114 -97.344992)
		(end 297.444922 -108.8898)
		(width 0.11684)
		(layer "In4.Cu")
		(net "I3C_SCM_1_R_SCL")
	)
	(segment
		(start 302.34382 -113.788698)
		(end 308.0258 -119.470678)
		(width 0.11684)
		(layer "In4.Cu")
		(net "I3C_SCM_1_R_SCL")
	)
	(segment
		(start 234.61853 -51.100228)
		(end 239.65916 -51.100228)
		(width 0.11684)
		(layer "In4.Cu")
		(net "I3C_SCM_1_R_SCL")
	)
	(segment
		(start 219.289122 -36.276026)
		(end 224.998026 -41.98493)
		(width 0.11684)
		(layer "In4.Cu")
		(net "I3C_SCM_1_R_SCL")
	)
	(segment
		(start 224.998026 -41.98493)
		(end 230.038148 -41.98493)
		(width 0.11684)
		(layer "In4.Cu")
		(net "I3C_SCM_1_R_SCL")
	)
	(segment
		(start 301.391828 -108.8898)
		(end 302.34382 -109.841792)
		(width 0.11684)
		(layer "In4.Cu")
		(net "I3C_SCM_1_R_SCL")
	)
	(segment
		(start 302.852074 -148.997924)
		(end 302.514 -148.65985)
		(width 0.10668)
		(layer "F.Cu")
		(net "I3C_SCM_0_R_SDA")
	)
	(segment
		(start 303.615344 -148.997924)
		(end 302.852074 -148.997924)
		(width 0.10668)
		(layer "F.Cu")
		(net "I3C_SCM_0_R_SDA")
	)
	(segment
		(start 304.682398 -149.210522)
		(end 303.827942 -149.210522)
		(width 0.10668)
		(layer "F.Cu")
		(net "I3C_SCM_0_R_SDA")
	)
	(segment
		(start 302.514 -148.65985)
		(end 302.440848 -148.65985)
		(width 0.10668)
		(layer "F.Cu")
		(net "I3C_SCM_0_R_SDA")
	)
	(segment
		(start 303.827942 -149.210522)
		(end 303.615344 -148.997924)
		(width 0.10668)
		(layer "F.Cu")
		(net "I3C_SCM_0_R_SDA")
	)
	(via
		(at 303.615344 -148.997924)
		(size 0.508)
		(drill 0.254)
		(layers "F.Cu" "B.Cu")
		(net "I3C_SCM_0_R_SDA")
	)
	(via
		(at 292.246558 -121.62536)
		(size 0.508)
		(drill 0.254)
		(layers "F.Cu" "B.Cu")
		(net "I3C_SCM_0_R_SDA")
	)
	(via
		(at 231.163622 -62.48781)
		(size 0.508)
		(drill 0.254)
		(layers "F.Cu" "B.Cu")
		(net "I3C_SCM_0_R_SDA")
	)
	(via
		(at 189.633352 -15.177516)
		(size 0.508)
		(drill 0.254)
		(layers "F.Cu" "B.Cu")
		(net "I3C_SCM_0_R_SDA")
	)
	(segment
		(start 189.633352 -14.283182)
		(end 189.633352 -15.177516)
		(width 0.10668)
		(layer "B.Cu")
		(net "I3C_SCM_0_R_SDA")
	)
	(segment
		(start 189.35065 -14.00048)
		(end 189.633352 -14.283182)
		(width 0.10668)
		(layer "B.Cu")
		(net "I3C_SCM_0_R_SDA")
	)
	(segment
		(start 189.633352 -16.682212)
		(end 189.633352 -15.177516)
		(width 0.11684)
		(layer "In2.Cu")
		(net "I3C_SCM_0_R_SDA")
	)
	(segment
		(start 231.163622 -62.48781)
		(end 228.618796 -62.48781)
		(width 0.11684)
		(layer "In2.Cu")
		(net "I3C_SCM_0_R_SDA")
	)
	(segment
		(start 213.145116 -38.502082)
		(end 213.145116 -31.69793)
		(width 0.11684)
		(layer "In2.Cu")
		(net "I3C_SCM_0_R_SDA")
	)
	(segment
		(start 217.770456 -23.096728)
		(end 215.617806 -20.944078)
		(width 0.11684)
		(layer "In2.Cu")
		(net "I3C_SCM_0_R_SDA")
	)
	(segment
		(start 303.083976 -144.72412)
		(end 304.732182 -143.075914)
		(width 0.11684)
		(layer "In2.Cu")
		(net "I3C_SCM_0_R_SDA")
	)
	(segment
		(start 197.466458 -18.429986)
		(end 191.381126 -18.429986)
		(width 0.11684)
		(layer "In2.Cu")
		(net "I3C_SCM_0_R_SDA")
	)
	(segment
		(start 228.618796 -62.48781)
		(end 211.681314 -45.550328)
		(width 0.11684)
		(layer "In2.Cu")
		(net "I3C_SCM_0_R_SDA")
	)
	(segment
		(start 216.723468 -30.810708)
		(end 217.770456 -29.76372)
		(width 0.11684)
		(layer "In2.Cu")
		(net "I3C_SCM_0_R_SDA")
	)
	(segment
		(start 304.732182 -136.431528)
		(end 292.246558 -123.94565)
		(width 0.11684)
		(layer "In2.Cu")
		(net "I3C_SCM_0_R_SDA")
	)
	(segment
		(start 292.246558 -123.94565)
		(end 292.246558 -121.62536)
		(width 0.11684)
		(layer "In2.Cu")
		(net "I3C_SCM_0_R_SDA")
	)
	(segment
		(start 215.617806 -20.944078)
		(end 211.19211 -20.944078)
		(width 0.11684)
		(layer "In2.Cu")
		(net "I3C_SCM_0_R_SDA")
	)
	(segment
		(start 207.113886 -16.865854)
		(end 199.03059 -16.865854)
		(width 0.11684)
		(layer "In2.Cu")
		(net "I3C_SCM_0_R_SDA")
	)
	(segment
		(start 213.145116 -31.69793)
		(end 214.032338 -30.810708)
		(width 0.11684)
		(layer "In2.Cu")
		(net "I3C_SCM_0_R_SDA")
	)
	(segment
		(start 211.19211 -20.944078)
		(end 207.113886 -16.865854)
		(width 0.11684)
		(layer "In2.Cu")
		(net "I3C_SCM_0_R_SDA")
	)
	(segment
		(start 217.770456 -29.76372)
		(end 217.770456 -23.096728)
		(width 0.11684)
		(layer "In2.Cu")
		(net "I3C_SCM_0_R_SDA")
	)
	(segment
		(start 191.381126 -18.429986)
		(end 189.633352 -16.682212)
		(width 0.11684)
		(layer "In2.Cu")
		(net "I3C_SCM_0_R_SDA")
	)
	(segment
		(start 303.083976 -148.466556)
		(end 303.083976 -144.72412)
		(width 0.11684)
		(layer "In2.Cu")
		(net "I3C_SCM_0_R_SDA")
	)
	(segment
		(start 199.03059 -16.865854)
		(end 197.466458 -18.429986)
		(width 0.11684)
		(layer "In2.Cu")
		(net "I3C_SCM_0_R_SDA")
	)
	(segment
		(start 211.681314 -45.550328)
		(end 211.681314 -39.965884)
		(width 0.11684)
		(layer "In2.Cu")
		(net "I3C_SCM_0_R_SDA")
	)
	(segment
		(start 304.732182 -143.075914)
		(end 304.732182 -136.431528)
		(width 0.11684)
		(layer "In2.Cu")
		(net "I3C_SCM_0_R_SDA")
	)
	(segment
		(start 303.615344 -148.997924)
		(end 303.083976 -148.466556)
		(width 0.11684)
		(layer "In2.Cu")
		(net "I3C_SCM_0_R_SDA")
	)
	(segment
		(start 211.681314 -39.965884)
		(end 213.145116 -38.502082)
		(width 0.11684)
		(layer "In2.Cu")
		(net "I3C_SCM_0_R_SDA")
	)
	(segment
		(start 214.032338 -30.810708)
		(end 216.723468 -30.810708)
		(width 0.11684)
		(layer "In2.Cu")
		(net "I3C_SCM_0_R_SDA")
	)
	(segment
		(start 292.246558 -121.62536)
		(end 291.991034 -121.369836)
		(width 0.11684)
		(layer "In4.Cu")
		(net "I3C_SCM_0_R_SDA")
	)
	(segment
		(start 291.991034 -111.09706)
		(end 283.680154 -102.78618)
		(width 0.11684)
		(layer "In4.Cu")
		(net "I3C_SCM_0_R_SDA")
	)
	(segment
		(start 232.33126 -63.655448)
		(end 231.163622 -62.48781)
		(width 0.11684)
		(layer "In4.Cu")
		(net "I3C_SCM_0_R_SDA")
	)
	(segment
		(start 266.298426 -61.735208)
		(end 264.378186 -63.655448)
		(width 0.11684)
		(layer "In4.Cu")
		(net "I3C_SCM_0_R_SDA")
	)
	(segment
		(start 264.378186 -63.655448)
		(end 232.33126 -63.655448)
		(width 0.11684)
		(layer "In4.Cu")
		(net "I3C_SCM_0_R_SDA")
	)
	(segment
		(start 283.680154 -102.78618)
		(end 283.680154 -72.166226)
		(width 0.11684)
		(layer "In4.Cu")
		(net "I3C_SCM_0_R_SDA")
	)
	(segment
		(start 291.991034 -121.369836)
		(end 291.991034 -111.09706)
		(width 0.11684)
		(layer "In4.Cu")
		(net "I3C_SCM_0_R_SDA")
	)
	(segment
		(start 283.680154 -72.166226)
		(end 273.249136 -61.735208)
		(width 0.11684)
		(layer "In4.Cu")
		(net "I3C_SCM_0_R_SDA")
	)
	(segment
		(start 273.249136 -61.735208)
		(end 266.298426 -61.735208)
		(width 0.11684)
		(layer "In4.Cu")
		(net "I3C_SCM_0_R_SDA")
	)
	(segment
		(start 304.419254 -147.677378)
		(end 304.682398 -147.940522)
		(width 0.10668)
		(layer "F.Cu")
		(net "I3C_SCM_0_R_SCL")
	)
	(segment
		(start 303.25822 -148.159724)
		(end 303.589944 -147.828)
		(width 0.10668)
		(layer "F.Cu")
		(net "I3C_SCM_0_R_SCL")
	)
	(segment
		(start 302.440848 -148.159724)
		(end 303.25822 -148.159724)
		(width 0.10668)
		(layer "F.Cu")
		(net "I3C_SCM_0_R_SCL")
	)
	(segment
		(start 303.589944 -147.828)
		(end 303.589944 -147.677378)
		(width 0.10668)
		(layer "F.Cu")
		(net "I3C_SCM_0_R_SCL")
	)
	(segment
		(start 303.589944 -147.677378)
		(end 304.419254 -147.677378)
		(width 0.10668)
		(layer "F.Cu")
		(net "I3C_SCM_0_R_SCL")
	)
	(via
		(at 293.59606 -121.618248)
		(size 0.508)
		(drill 0.254)
		(layers "F.Cu" "B.Cu")
		(net "I3C_SCM_0_R_SCL")
	)
	(via
		(at 303.589944 -147.677378)
		(size 0.508)
		(drill 0.254)
		(layers "F.Cu" "B.Cu")
		(net "I3C_SCM_0_R_SCL")
	)
	(via
		(at 190.367412 -15.215108)
		(size 0.508)
		(drill 0.254)
		(layers "F.Cu" "B.Cu")
		(net "I3C_SCM_0_R_SCL")
	)
	(via
		(at 231.207818 -61.635132)
		(size 0.508)
		(drill 0.254)
		(layers "F.Cu" "B.Cu")
		(net "I3C_SCM_0_R_SCL")
	)
	(segment
		(start 190.367412 -14.00048)
		(end 190.367412 -15.215108)
		(width 0.10668)
		(layer "B.Cu")
		(net "I3C_SCM_0_R_SCL")
	)
	(segment
		(start 216.97188 -31.410148)
		(end 218.369896 -30.012132)
		(width 0.11684)
		(layer "In2.Cu")
		(net "I3C_SCM_0_R_SCL")
	)
	(segment
		(start 218.369896 -30.012132)
		(end 218.369896 -22.848316)
		(width 0.11684)
		(layer "In2.Cu")
		(net "I3C_SCM_0_R_SCL")
	)
	(segment
		(start 305.341782 -143.328644)
		(end 305.341782 -136.178798)
		(width 0.11684)
		(layer "In2.Cu")
		(net "I3C_SCM_0_R_SCL")
	)
	(segment
		(start 213.546436 -46.567598)
		(end 213.546436 -38.948614)
		(width 0.11684)
		(layer "In2.Cu")
		(net "I3C_SCM_0_R_SCL")
	)
	(segment
		(start 305.341782 -136.178798)
		(end 292.96106 -123.798076)
		(width 0.11684)
		(layer "In2.Cu")
		(net "I3C_SCM_0_R_SCL")
	)
	(segment
		(start 214.28075 -31.410148)
		(end 216.97188 -31.410148)
		(width 0.11684)
		(layer "In2.Cu")
		(net "I3C_SCM_0_R_SCL")
	)
	(segment
		(start 228.61397 -61.635132)
		(end 213.546436 -46.567598)
		(width 0.11684)
		(layer "In2.Cu")
		(net "I3C_SCM_0_R_SCL")
	)
	(segment
		(start 303.589944 -147.677378)
		(end 303.806098 -147.461224)
		(width 0.11684)
		(layer "In2.Cu")
		(net "I3C_SCM_0_R_SCL")
	)
	(segment
		(start 292.96106 -122.253248)
		(end 293.59606 -121.618248)
		(width 0.11684)
		(layer "In2.Cu")
		(net "I3C_SCM_0_R_SCL")
	)
	(segment
		(start 231.207818 -61.635132)
		(end 228.61397 -61.635132)
		(width 0.11684)
		(layer "In2.Cu")
		(net "I3C_SCM_0_R_SCL")
	)
	(segment
		(start 292.96106 -123.798076)
		(end 292.96106 -122.253248)
		(width 0.11684)
		(layer "In2.Cu")
		(net "I3C_SCM_0_R_SCL")
	)
	(segment
		(start 207.362298 -16.266414)
		(end 198.782178 -16.266414)
		(width 0.11684)
		(layer "In2.Cu")
		(net "I3C_SCM_0_R_SCL")
	)
	(segment
		(start 303.806098 -144.864328)
		(end 305.341782 -143.328644)
		(width 0.11684)
		(layer "In2.Cu")
		(net "I3C_SCM_0_R_SCL")
	)
	(segment
		(start 213.744556 -38.750494)
		(end 213.744556 -31.946342)
		(width 0.11684)
		(layer "In2.Cu")
		(net "I3C_SCM_0_R_SCL")
	)
	(segment
		(start 198.782178 -16.266414)
		(end 197.218046 -17.830546)
		(width 0.11684)
		(layer "In2.Cu")
		(net "I3C_SCM_0_R_SCL")
	)
	(segment
		(start 197.218046 -17.830546)
		(end 191.739012 -17.830546)
		(width 0.11684)
		(layer "In2.Cu")
		(net "I3C_SCM_0_R_SCL")
	)
	(segment
		(start 211.440522 -20.344638)
		(end 207.362298 -16.266414)
		(width 0.11684)
		(layer "In2.Cu")
		(net "I3C_SCM_0_R_SCL")
	)
	(segment
		(start 191.739012 -17.830546)
		(end 190.367412 -16.458946)
		(width 0.11684)
		(layer "In2.Cu")
		(net "I3C_SCM_0_R_SCL")
	)
	(segment
		(start 190.367412 -16.458946)
		(end 190.367412 -15.215108)
		(width 0.11684)
		(layer "In2.Cu")
		(net "I3C_SCM_0_R_SCL")
	)
	(segment
		(start 213.546436 -38.948614)
		(end 213.744556 -38.750494)
		(width 0.11684)
		(layer "In2.Cu")
		(net "I3C_SCM_0_R_SCL")
	)
	(segment
		(start 213.744556 -31.946342)
		(end 214.28075 -31.410148)
		(width 0.11684)
		(layer "In2.Cu")
		(net "I3C_SCM_0_R_SCL")
	)
	(segment
		(start 218.369896 -22.848316)
		(end 215.866218 -20.344638)
		(width 0.11684)
		(layer "In2.Cu")
		(net "I3C_SCM_0_R_SCL")
	)
	(segment
		(start 215.866218 -20.344638)
		(end 211.440522 -20.344638)
		(width 0.11684)
		(layer "In2.Cu")
		(net "I3C_SCM_0_R_SCL")
	)
	(segment
		(start 303.806098 -147.461224)
		(end 303.806098 -144.864328)
		(width 0.11684)
		(layer "In2.Cu")
		(net "I3C_SCM_0_R_SCL")
	)
	(segment
		(start 264.129774 -63.056008)
		(end 232.628694 -63.056008)
		(width 0.11684)
		(layer "In4.Cu")
		(net "I3C_SCM_0_R_SCL")
	)
	(segment
		(start 273.474688 -61.112908)
		(end 266.072874 -61.112908)
		(width 0.11684)
		(layer "In4.Cu")
		(net "I3C_SCM_0_R_SCL")
	)
	(segment
		(start 232.628694 -63.056008)
		(end 231.207818 -61.635132)
		(width 0.11684)
		(layer "In4.Cu")
		(net "I3C_SCM_0_R_SCL")
	)
	(segment
		(start 266.072874 -61.112908)
		(end 264.129774 -63.056008)
		(width 0.11684)
		(layer "In4.Cu")
		(net "I3C_SCM_0_R_SCL")
	)
	(segment
		(start 284.279594 -102.537768)
		(end 284.279594 -71.917814)
		(width 0.11684)
		(layer "In4.Cu")
		(net "I3C_SCM_0_R_SCL")
	)
	(segment
		(start 293.59606 -121.618248)
		(end 292.590474 -120.612662)
		(width 0.11684)
		(layer "In4.Cu")
		(net "I3C_SCM_0_R_SCL")
	)
	(segment
		(start 292.590474 -120.612662)
		(end 292.590474 -110.848648)
		(width 0.11684)
		(layer "In4.Cu")
		(net "I3C_SCM_0_R_SCL")
	)
	(segment
		(start 292.590474 -110.848648)
		(end 284.279594 -102.537768)
		(width 0.11684)
		(layer "In4.Cu")
		(net "I3C_SCM_0_R_SCL")
	)
	(segment
		(start 284.279594 -71.917814)
		(end 273.474688 -61.112908)
		(width 0.11684)
		(layer "In4.Cu")
		(net "I3C_SCM_0_R_SCL")
	)
	(via
		(at 230.88854 -233.426)
		(size 0.6604)
		(drill 0.3302)
		(layers "F.Cu" "B.Cu")
		(net "I3C_MUX_CPU0_VIO")
	)
	(segment
		(start 230.88854 -234.699302)
		(end 230.88854 -233.426)
		(width 0.10668)
		(layer "B.Cu")
		(net "I3C_MUX_CPU0_VIO")
	)
	(segment
		(start 230.886 -232.68305)
		(end 230.88854 -232.68559)
		(width 0.10668)
		(layer "B.Cu")
		(net "I3C_MUX_CPU0_VIO")
	)
	(segment
		(start 230.88854 -232.68559)
		(end 230.88854 -233.426)
		(width 0.10668)
		(layer "B.Cu")
		(net "I3C_MUX_CPU0_VIO")
	)
	(segment
		(start 230.886 -232.55605)
		(end 231.902 -232.55605)
		(width 0.10668)
		(layer "B.Cu")
		(net "I3C_MUX_CPU0_VIO")
	)
	(segment
		(start 230.886 -232.55605)
		(end 230.886 -232.68305)
		(width 0.10668)
		(layer "B.Cu")
		(net "I3C_MUX_CPU0_VIO")
	)
	(segment
		(start 173.30166 -11.892534)
		(end 173.301914 -11.892788)
		(width 0.10668)
		(layer "F.Cu")
		(net "I3C_BMC_SWB_SDA")
	)
	(segment
		(start 228.206046 -94.530672)
		(end 228.206046 -117.8687)
		(width 0.10668)
		(layer "F.Cu")
		(net "I3C_BMC_SWB_SDA")
	)
	(segment
		(start 242.973352 -204.08138)
		(end 241.78133 -205.273402)
		(width 0.10668)
		(layer "F.Cu")
		(net "I3C_BMC_SWB_SDA")
	)
	(segment
		(start 229.612698 -148.56206)
		(end 227.430838 -150.74392)
		(width 0.10668)
		(layer "F.Cu")
		(net "I3C_BMC_SWB_SDA")
	)
	(segment
		(start 173.467014 -13.599922)
		(end 173.467014 -12.819634)
		(width 0.10668)
		(layer "F.Cu")
		(net "I3C_BMC_SWB_SDA")
	)
	(segment
		(start 229.612698 -142.474442)
		(end 229.612698 -148.56206)
		(width 0.10668)
		(layer "F.Cu")
		(net "I3C_BMC_SWB_SDA")
	)
	(segment
		(start 173.294294 -11.892534)
		(end 173.30166 -11.892534)
		(width 0.10668)
		(layer "F.Cu")
		(net "I3C_BMC_SWB_SDA")
	)
	(segment
		(start 231.24795 -120.910604)
		(end 231.24795 -140.83919)
		(width 0.10668)
		(layer "F.Cu")
		(net "I3C_BMC_SWB_SDA")
	)
	(segment
		(start 227.430838 -150.74392)
		(end 227.430838 -158.290514)
		(width 0.10668)
		(layer "F.Cu")
		(net "I3C_BMC_SWB_SDA")
	)
	(segment
		(start 216.722198 -88.056974)
		(end 221.732348 -88.056974)
		(width 0.10668)
		(layer "F.Cu")
		(net "I3C_BMC_SWB_SDA")
	)
	(segment
		(start 227.430838 -158.290514)
		(end 235.704634 -166.56431)
		(width 0.10668)
		(layer "F.Cu")
		(net "I3C_BMC_SWB_SDA")
	)
	(segment
		(start 231.24795 -140.83919)
		(end 229.612698 -142.474442)
		(width 0.10668)
		(layer "F.Cu")
		(net "I3C_BMC_SWB_SDA")
	)
	(segment
		(start 242.973352 -190.735712)
		(end 242.973352 -204.08138)
		(width 0.10668)
		(layer "F.Cu")
		(net "I3C_BMC_SWB_SDA")
	)
	(segment
		(start 173.467014 -12.819634)
		(end 173.289214 -12.641834)
		(width 0.10668)
		(layer "F.Cu")
		(net "I3C_BMC_SWB_SDA")
	)
	(segment
		(start 235.704634 -166.56431)
		(end 235.704634 -173.186852)
		(width 0.10668)
		(layer "F.Cu")
		(net "I3C_BMC_SWB_SDA")
	)
	(segment
		(start 235.704634 -173.186852)
		(end 242.973352 -190.735712)
		(width 0.10668)
		(layer "F.Cu")
		(net "I3C_BMC_SWB_SDA")
	)
	(segment
		(start 221.732348 -88.056974)
		(end 228.206046 -94.530672)
		(width 0.10668)
		(layer "F.Cu")
		(net "I3C_BMC_SWB_SDA")
	)
	(segment
		(start 228.206046 -117.8687)
		(end 231.24795 -120.910604)
		(width 0.10668)
		(layer "F.Cu")
		(net "I3C_BMC_SWB_SDA")
	)
	(segment
		(start 173.289214 -12.641834)
		(end 173.289214 -11.897614)
		(width 0.10668)
		(layer "F.Cu")
		(net "I3C_BMC_SWB_SDA")
	)
	(segment
		(start 214.200232 -85.535008)
		(end 216.722198 -88.056974)
		(width 0.10668)
		(layer "F.Cu")
		(net "I3C_BMC_SWB_SDA")
	)
	(segment
		(start 214.200232 -85.2297)
		(end 214.200232 -85.535008)
		(width 0.10668)
		(layer "F.Cu")
		(net "I3C_BMC_SWB_SDA")
	)
	(segment
		(start 173.289214 -11.897614)
		(end 173.294294 -11.892534)
		(width 0.10668)
		(layer "F.Cu")
		(net "I3C_BMC_SWB_SDA")
	)
	(via
		(at 214.200232 -85.2297)
		(size 0.508)
		(drill 0.254)
		(layers "F.Cu" "B.Cu")
		(net "I3C_BMC_SWB_SDA")
	)
	(via
		(at 173.301914 -11.892788)
		(size 0.508)
		(drill 0.254)
		(layers "F.Cu" "B.Cu")
		(net "I3C_BMC_SWB_SDA")
	)
	(via
		(at 241.78133 -205.273402)
		(size 0.508)
		(drill 0.254)
		(layers "F.Cu" "B.Cu")
		(net "I3C_BMC_SWB_SDA")
	)
	(via
		(at 288.088578 -423.98442)
		(size 0.508)
		(drill 0.254)
		(layers "F.Cu" "B.Cu")
		(net "I3C_BMC_SWB_SDA")
	)
	(segment
		(start 289.692334 -425.179998)
		(end 289.284156 -425.179998)
		(width 0.10668)
		(layer "B.Cu")
		(net "I3C_BMC_SWB_SDA")
	)
	(segment
		(start 173.301914 -11.892788)
		(end 173.301914 -13.016738)
		(width 0.10668)
		(layer "B.Cu")
		(net "I3C_BMC_SWB_SDA")
	)
	(segment
		(start 289.284156 -425.179998)
		(end 288.088578 -423.98442)
		(width 0.10668)
		(layer "B.Cu")
		(net "I3C_BMC_SWB_SDA")
	)
	(segment
		(start 188.632338 -15.825216)
		(end 188.632338 -14.472158)
		(width 0.11684)
		(layer "In4.Cu")
		(net "I3C_BMC_SWB_SDA")
	)
	(segment
		(start 249.540268 -248.336816)
		(end 249.540268 -212.033612)
		(width 0.11684)
		(layer "In4.Cu")
		(net "I3C_BMC_SWB_SDA")
	)
	(segment
		(start 193.569336 -27.323288)
		(end 193.569336 -22.620478)
		(width 0.11684)
		(layer "In4.Cu")
		(net "I3C_BMC_SWB_SDA")
	)
	(segment
		(start 249.540268 -212.033612)
		(end 242.780058 -205.273402)
		(width 0.11684)
		(layer "In4.Cu")
		(net "I3C_BMC_SWB_SDA")
	)
	(segment
		(start 273.072352 -366.420654)
		(end 270.713962 -366.420654)
		(width 0.11684)
		(layer "In4.Cu")
		(net "I3C_BMC_SWB_SDA")
	)
	(segment
		(start 258.702302 -324.121526)
		(end 258.702302 -257.49885)
		(width 0.11684)
		(layer "In4.Cu")
		(net "I3C_BMC_SWB_SDA")
	)
	(segment
		(start 210.99653 -71.494142)
		(end 210.99653 -59.784996)
		(width 0.11684)
		(layer "In4.Cu")
		(net "I3C_BMC_SWB_SDA")
	)
	(segment
		(start 286.001968 -375.558558)
		(end 286.001968 -372.175024)
		(width 0.11684)
		(layer "In4.Cu")
		(net "I3C_BMC_SWB_SDA")
	)
	(segment
		(start 216.052146 -83.253326)
		(end 216.052146 -82.605626)
		(width 0.11684)
		(layer "In4.Cu")
		(net "I3C_BMC_SWB_SDA")
	)
	(segment
		(start 176.372012 -13.650468)
		(end 175.059594 -13.650468)
		(width 0.11684)
		(layer "In4.Cu")
		(net "I3C_BMC_SWB_SDA")
	)
	(segment
		(start 288.088578 -423.98442)
		(end 285.952946 -423.98442)
		(width 0.11684)
		(layer "In4.Cu")
		(net "I3C_BMC_SWB_SDA")
	)
	(segment
		(start 213.046818 -79.413862)
		(end 214.346028 -79.413862)
		(width 0.11684)
		(layer "In4.Cu")
		(net "I3C_BMC_SWB_SDA")
	)
	(segment
		(start 283.9339 -370.106956)
		(end 276.758654 -370.106956)
		(width 0.11684)
		(layer "In4.Cu")
		(net "I3C_BMC_SWB_SDA")
	)
	(segment
		(start 210.99653 -59.784996)
		(end 211.97062 -58.810906)
		(width 0.11684)
		(layer "In4.Cu")
		(net "I3C_BMC_SWB_SDA")
	)
	(segment
		(start 283.898848 -381.18923)
		(end 283.898848 -377.661678)
		(width 0.11684)
		(layer "In4.Cu")
		(net "I3C_BMC_SWB_SDA")
	)
	(segment
		(start 269.683992 -365.390684)
		(end 269.683992 -364.148116)
		(width 0.11684)
		(layer "In4.Cu")
		(net "I3C_BMC_SWB_SDA")
	)
	(segment
		(start 258.702302 -330.838048)
		(end 256.272792 -328.408538)
		(width 0.11684)
		(layer "In4.Cu")
		(net "I3C_BMC_SWB_SDA")
	)
	(segment
		(start 256.272792 -328.408538)
		(end 256.272792 -326.551036)
		(width 0.11684)
		(layer "In4.Cu")
		(net "I3C_BMC_SWB_SDA")
	)
	(segment
		(start 285.952946 -423.98442)
		(end 285.114746 -423.14622)
		(width 0.11684)
		(layer "In4.Cu")
		(net "I3C_BMC_SWB_SDA")
	)
	(segment
		(start 212.929978 -80.66532)
		(end 212.929978 -79.530702)
		(width 0.11684)
		(layer "In4.Cu")
		(net "I3C_BMC_SWB_SDA")
	)
	(segment
		(start 192.193418 -18.800572)
		(end 189.408562 -16.015716)
		(width 0.11684)
		(layer "In4.Cu")
		(net "I3C_BMC_SWB_SDA")
	)
	(segment
		(start 189.408562 -16.015716)
		(end 188.822838 -16.015716)
		(width 0.11684)
		(layer "In4.Cu")
		(net "I3C_BMC_SWB_SDA")
	)
	(segment
		(start 214.346028 -79.413862)
		(end 214.462868 -79.297022)
		(width 0.11684)
		(layer "In4.Cu")
		(net "I3C_BMC_SWB_SDA")
	)
	(segment
		(start 186.30773 -13.650468)
		(end 185.696606 -13.039344)
		(width 0.11684)
		(layer "In4.Cu")
		(net "I3C_BMC_SWB_SDA")
	)
	(segment
		(start 269.683992 -364.148116)
		(end 258.702302 -353.166426)
		(width 0.11684)
		(layer "In4.Cu")
		(net "I3C_BMC_SWB_SDA")
	)
	(segment
		(start 214.200232 -83.487006)
		(end 214.317072 -83.370166)
		(width 0.11684)
		(layer "In4.Cu")
		(net "I3C_BMC_SWB_SDA")
	)
	(segment
		(start 176.983136 -13.039344)
		(end 176.372012 -13.650468)
		(width 0.11684)
		(layer "In4.Cu")
		(net "I3C_BMC_SWB_SDA")
	)
	(segment
		(start 215.935306 -83.370166)
		(end 216.052146 -83.253326)
		(width 0.11684)
		(layer "In4.Cu")
		(net "I3C_BMC_SWB_SDA")
	)
	(segment
		(start 283.898848 -377.661678)
		(end 286.001968 -375.558558)
		(width 0.11684)
		(layer "In4.Cu")
		(net "I3C_BMC_SWB_SDA")
	)
	(segment
		(start 284.973268 -382.26365)
		(end 283.898848 -381.18923)
		(width 0.11684)
		(layer "In4.Cu")
		(net "I3C_BMC_SWB_SDA")
	)
	(segment
		(start 285.114746 -423.14622)
		(end 285.114746 -415.084768)
		(width 0.11684)
		(layer "In4.Cu")
		(net "I3C_BMC_SWB_SDA")
	)
	(segment
		(start 284.68447 -397.35633)
		(end 286.163004 -395.877796)
		(width 0.11684)
		(layer "In4.Cu")
		(net "I3C_BMC_SWB_SDA")
	)
	(segment
		(start 214.200232 -82.371946)
		(end 214.200232 -81.935574)
		(width 0.11684)
		(layer "In4.Cu")
		(net "I3C_BMC_SWB_SDA")
	)
	(segment
		(start 212.929978 -73.42759)
		(end 210.99653 -71.494142)
		(width 0.11684)
		(layer "In4.Cu")
		(net "I3C_BMC_SWB_SDA")
	)
	(segment
		(start 193.569336 -22.620478)
		(end 192.193418 -21.24456)
		(width 0.11684)
		(layer "In4.Cu")
		(net "I3C_BMC_SWB_SDA")
	)
	(segment
		(start 286.163004 -409.031694)
		(end 286.163004 -401.981162)
		(width 0.11684)
		(layer "In4.Cu")
		(net "I3C_BMC_SWB_SDA")
	)
	(segment
		(start 212.929978 -78.415642)
		(end 212.929978 -73.42759)
		(width 0.11684)
		(layer "In4.Cu")
		(net "I3C_BMC_SWB_SDA")
	)
	(segment
		(start 188.632338 -14.472158)
		(end 187.810648 -13.650468)
		(width 0.11684)
		(layer "In4.Cu")
		(net "I3C_BMC_SWB_SDA")
	)
	(segment
		(start 214.200232 -81.935574)
		(end 212.929978 -80.66532)
		(width 0.11684)
		(layer "In4.Cu")
		(net "I3C_BMC_SWB_SDA")
	)
	(segment
		(start 216.052146 -82.605626)
		(end 215.935306 -82.488786)
		(width 0.11684)
		(layer "In4.Cu")
		(net "I3C_BMC_SWB_SDA")
	)
	(segment
		(start 242.780058 -205.273402)
		(end 241.78133 -205.273402)
		(width 0.11684)
		(layer "In4.Cu")
		(net "I3C_BMC_SWB_SDA")
	)
	(segment
		(start 188.822838 -16.015716)
		(end 188.632338 -15.825216)
		(width 0.11684)
		(layer "In4.Cu")
		(net "I3C_BMC_SWB_SDA")
	)
	(segment
		(start 212.929978 -79.530702)
		(end 213.046818 -79.413862)
		(width 0.11684)
		(layer "In4.Cu")
		(net "I3C_BMC_SWB_SDA")
	)
	(segment
		(start 214.200232 -85.2297)
		(end 214.200232 -83.487006)
		(width 0.11684)
		(layer "In4.Cu")
		(net "I3C_BMC_SWB_SDA")
	)
	(segment
		(start 175.059594 -13.650468)
		(end 173.301914 -11.892788)
		(width 0.11684)
		(layer "In4.Cu")
		(net "I3C_BMC_SWB_SDA")
	)
	(segment
		(start 270.713962 -366.420654)
		(end 269.683992 -365.390684)
		(width 0.11684)
		(layer "In4.Cu")
		(net "I3C_BMC_SWB_SDA")
	)
	(segment
		(start 284.68447 -400.502628)
		(end 284.68447 -397.35633)
		(width 0.11684)
		(layer "In4.Cu")
		(net "I3C_BMC_SWB_SDA")
	)
	(segment
		(start 276.758654 -370.106956)
		(end 273.072352 -366.420654)
		(width 0.11684)
		(layer "In4.Cu")
		(net "I3C_BMC_SWB_SDA")
	)
	(segment
		(start 285.114746 -415.084768)
		(end 285.862522 -414.336992)
		(width 0.11684)
		(layer "In4.Cu")
		(net "I3C_BMC_SWB_SDA")
	)
	(segment
		(start 214.462868 -78.649322)
		(end 214.346028 -78.532482)
		(width 0.11684)
		(layer "In4.Cu")
		(net "I3C_BMC_SWB_SDA")
	)
	(segment
		(start 192.193418 -21.24456)
		(end 192.193418 -18.800572)
		(width 0.11684)
		(layer "In4.Cu")
		(net "I3C_BMC_SWB_SDA")
	)
	(segment
		(start 258.702302 -353.166426)
		(end 258.702302 -330.838048)
		(width 0.11684)
		(layer "In4.Cu")
		(net "I3C_BMC_SWB_SDA")
	)
	(segment
		(start 214.317072 -83.370166)
		(end 215.935306 -83.370166)
		(width 0.11684)
		(layer "In4.Cu")
		(net "I3C_BMC_SWB_SDA")
	)
	(segment
		(start 286.163004 -395.877796)
		(end 286.163004 -388.98068)
		(width 0.11684)
		(layer "In4.Cu")
		(net "I3C_BMC_SWB_SDA")
	)
	(segment
		(start 256.272792 -326.551036)
		(end 258.702302 -324.121526)
		(width 0.11684)
		(layer "In4.Cu")
		(net "I3C_BMC_SWB_SDA")
	)
	(segment
		(start 286.163004 -388.98068)
		(end 284.973268 -387.790944)
		(width 0.11684)
		(layer "In4.Cu")
		(net "I3C_BMC_SWB_SDA")
	)
	(segment
		(start 213.046818 -78.532482)
		(end 212.929978 -78.415642)
		(width 0.11684)
		(layer "In4.Cu")
		(net "I3C_BMC_SWB_SDA")
	)
	(segment
		(start 285.862522 -409.332176)
		(end 286.163004 -409.031694)
		(width 0.11684)
		(layer "In4.Cu")
		(net "I3C_BMC_SWB_SDA")
	)
	(segment
		(start 214.462868 -79.297022)
		(end 214.462868 -78.649322)
		(width 0.11684)
		(layer "In4.Cu")
		(net "I3C_BMC_SWB_SDA")
	)
	(segment
		(start 187.810648 -13.650468)
		(end 186.30773 -13.650468)
		(width 0.11684)
		(layer "In4.Cu")
		(net "I3C_BMC_SWB_SDA")
	)
	(segment
		(start 285.862522 -414.336992)
		(end 285.862522 -409.332176)
		(width 0.11684)
		(layer "In4.Cu")
		(net "I3C_BMC_SWB_SDA")
	)
	(segment
		(start 214.317072 -82.488786)
		(end 214.200232 -82.371946)
		(width 0.11684)
		(layer "In4.Cu")
		(net "I3C_BMC_SWB_SDA")
	)
	(segment
		(start 214.346028 -78.532482)
		(end 213.046818 -78.532482)
		(width 0.11684)
		(layer "In4.Cu")
		(net "I3C_BMC_SWB_SDA")
	)
	(segment
		(start 185.696606 -13.039344)
		(end 176.983136 -13.039344)
		(width 0.11684)
		(layer "In4.Cu")
		(net "I3C_BMC_SWB_SDA")
	)
	(segment
		(start 286.001968 -372.175024)
		(end 283.9339 -370.106956)
		(width 0.11684)
		(layer "In4.Cu")
		(net "I3C_BMC_SWB_SDA")
	)
	(segment
		(start 286.163004 -401.981162)
		(end 284.68447 -400.502628)
		(width 0.11684)
		(layer "In4.Cu")
		(net "I3C_BMC_SWB_SDA")
	)
	(segment
		(start 284.973268 -387.790944)
		(end 284.973268 -382.26365)
		(width 0.11684)
		(layer "In4.Cu")
		(net "I3C_BMC_SWB_SDA")
	)
	(segment
		(start 215.935306 -82.488786)
		(end 214.317072 -82.488786)
		(width 0.11684)
		(layer "In4.Cu")
		(net "I3C_BMC_SWB_SDA")
	)
	(segment
		(start 258.702302 -257.49885)
		(end 249.540268 -248.336816)
		(width 0.11684)
		(layer "In4.Cu")
		(net "I3C_BMC_SWB_SDA")
	)
	(segment
		(start 211.97062 -58.810906)
		(end 211.97062 -45.724572)
		(width 0.11684)
		(layer "In4.Cu")
		(net "I3C_BMC_SWB_SDA")
	)
	(segment
		(start 211.97062 -45.724572)
		(end 193.569336 -27.323288)
		(width 0.11684)
		(layer "In4.Cu")
		(net "I3C_BMC_SWB_SDA")
	)
	(segment
		(start 173.959774 -11.712448)
		(end 173.594014 -11.346688)
		(width 0.10668)
		(layer "F.Cu")
		(net "I3C_BMC_SWB_SCL")
	)
	(segment
		(start 173.959774 -12.489942)
		(end 173.959774 -11.712448)
		(width 0.10668)
		(layer "F.Cu")
		(net "I3C_BMC_SWB_SCL")
	)
	(segment
		(start 173.731682 -10.631678)
		(end 173.891194 -10.631678)
		(width 0.10668)
		(layer "F.Cu")
		(net "I3C_BMC_SWB_SCL")
	)
	(segment
		(start 173.594014 -11.346688)
		(end 173.594014 -10.769346)
		(width 0.10668)
		(layer "F.Cu")
		(net "I3C_BMC_SWB_SCL")
	)
	(segment
		(start 173.594014 -10.769346)
		(end 173.731682 -10.631678)
		(width 0.10668)
		(layer "F.Cu")
		(net "I3C_BMC_SWB_SCL")
	)
	(segment
		(start 174.066962 -13.599922)
		(end 174.066962 -12.59713)
		(width 0.10668)
		(layer "F.Cu")
		(net "I3C_BMC_SWB_SCL")
	)
	(segment
		(start 174.066962 -12.59713)
		(end 173.959774 -12.489942)
		(width 0.10668)
		(layer "F.Cu")
		(net "I3C_BMC_SWB_SCL")
	)
	(via
		(at 173.891194 -10.631678)
		(size 0.508)
		(drill 0.254)
		(layers "F.Cu" "B.Cu")
		(net "I3C_BMC_SWB_SCL")
	)
	(segment
		(start 172.285914 -11.757914)
		(end 172.285914 -13.235178)
		(width 0.10668)
		(layer "B.Cu")
		(net "I3C_BMC_SWB_SCL")
	)
	(segment
		(start 173.856142 -12.525502)
		(end 174.317914 -12.987274)
		(width 0.10668)
		(layer "B.Cu")
		(net "I3C_BMC_SWB_SCL")
	)
	(segment
		(start 174.317914 -12.987274)
		(end 174.317914 -13.362178)
		(width 0.10668)
		(layer "B.Cu")
		(net "I3C_BMC_SWB_SCL")
	)
	(segment
		(start 173.41215 -10.631678)
		(end 172.285914 -11.757914)
		(width 0.10668)
		(layer "B.Cu")
		(net "I3C_BMC_SWB_SCL")
	)
	(segment
		(start 173.891194 -10.631678)
		(end 173.856142 -10.66673)
		(width 0.10668)
		(layer "B.Cu")
		(net "I3C_BMC_SWB_SCL")
	)
	(segment
		(start 173.856142 -10.66673)
		(end 173.856142 -12.525502)
		(width 0.10668)
		(layer "B.Cu")
		(net "I3C_BMC_SWB_SCL")
	)
	(segment
		(start 173.891194 -10.631678)
		(end 173.41215 -10.631678)
		(width 0.10668)
		(layer "B.Cu")
		(net "I3C_BMC_SWB_SCL")
	)
	(via
		(at 289.904424 -425.841668)
		(size 0.508)
		(drill 0.254)
		(layers "F.Cu" "B.Cu")
		(net "I3C_BMC_SWB_BUF_SDA")
	)
	(via
		(at 361.255564 -413.752538)
		(size 0.508)
		(drill 0.254)
		(layers "F.Cu" "B.Cu")
		(net "I3C_BMC_SWB_BUF_SDA")
	)
	(via
		(at 376.678698 -429.375062)
		(size 0.6604)
		(drill 0.3302)
		(layers "F.Cu" "B.Cu")
		(net "I3C_BMC_SWB_BUF_SDA")
	)
	(segment
		(start 362.720128 -414.97885)
		(end 362.720128 -415.877756)
		(width 0.10668)
		(layer "B.Cu")
		(net "I3C_BMC_SWB_BUF_SDA")
	)
	(segment
		(start 380.797308 -424.551856)
		(end 380.797308 -427.467776)
		(width 0.10668)
		(layer "B.Cu")
		(net "I3C_BMC_SWB_BUF_SDA")
	)
	(segment
		(start 376.494548 -429.559212)
		(end 376.678698 -429.375062)
		(width 0.10668)
		(layer "B.Cu")
		(net "I3C_BMC_SWB_BUF_SDA")
	)
	(segment
		(start 362.420662 -422.37914)
		(end 363.520228 -423.478706)
		(width 0.10668)
		(layer "B.Cu")
		(net "I3C_BMC_SWB_BUF_SDA")
	)
	(segment
		(start 383.002536 -423.94251)
		(end 381.406654 -423.94251)
		(width 0.10668)
		(layer "B.Cu")
		(net "I3C_BMC_SWB_BUF_SDA")
	)
	(segment
		(start 365.645192 -429.559212)
		(end 376.494548 -429.559212)
		(width 0.10668)
		(layer "B.Cu")
		(net "I3C_BMC_SWB_BUF_SDA")
	)
	(segment
		(start 362.116116 -417.740084)
		(end 362.420662 -418.04463)
		(width 0.10668)
		(layer "B.Cu")
		(net "I3C_BMC_SWB_BUF_SDA")
	)
	(segment
		(start 363.520228 -427.434248)
		(end 365.645192 -429.559212)
		(width 0.10668)
		(layer "B.Cu")
		(net "I3C_BMC_SWB_BUF_SDA")
	)
	(segment
		(start 378.890022 -429.375062)
		(end 376.678698 -429.375062)
		(width 0.10668)
		(layer "B.Cu")
		(net "I3C_BMC_SWB_BUF_SDA")
	)
	(segment
		(start 289.54095 -426.466)
		(end 289.54095 -426.205142)
		(width 0.10668)
		(layer "B.Cu")
		(net "I3C_BMC_SWB_BUF_SDA")
	)
	(segment
		(start 363.520228 -423.478706)
		(end 363.520228 -427.434248)
		(width 0.10668)
		(layer "B.Cu")
		(net "I3C_BMC_SWB_BUF_SDA")
	)
	(segment
		(start 381.406654 -423.94251)
		(end 380.797308 -424.551856)
		(width 0.10668)
		(layer "B.Cu")
		(net "I3C_BMC_SWB_BUF_SDA")
	)
	(segment
		(start 380.797308 -427.467776)
		(end 378.890022 -429.375062)
		(width 0.10668)
		(layer "B.Cu")
		(net "I3C_BMC_SWB_BUF_SDA")
	)
	(segment
		(start 362.720128 -415.877756)
		(end 362.116116 -416.481768)
		(width 0.10668)
		(layer "B.Cu")
		(net "I3C_BMC_SWB_BUF_SDA")
	)
	(segment
		(start 361.493816 -413.752538)
		(end 362.720128 -414.97885)
		(width 0.10668)
		(layer "B.Cu")
		(net "I3C_BMC_SWB_BUF_SDA")
	)
	(segment
		(start 383.749804 -424.689778)
		(end 383.002536 -423.94251)
		(width 0.10668)
		(layer "B.Cu")
		(net "I3C_BMC_SWB_BUF_SDA")
	)
	(segment
		(start 362.116116 -416.481768)
		(end 362.116116 -417.740084)
		(width 0.10668)
		(layer "B.Cu")
		(net "I3C_BMC_SWB_BUF_SDA")
	)
	(segment
		(start 362.420662 -418.04463)
		(end 362.420662 -422.37914)
		(width 0.10668)
		(layer "B.Cu")
		(net "I3C_BMC_SWB_BUF_SDA")
	)
	(segment
		(start 361.255564 -413.752538)
		(end 361.493816 -413.752538)
		(width 0.10668)
		(layer "B.Cu")
		(net "I3C_BMC_SWB_BUF_SDA")
	)
	(segment
		(start 289.54095 -426.205142)
		(end 289.904424 -425.841668)
		(width 0.10668)
		(layer "B.Cu")
		(net "I3C_BMC_SWB_BUF_SDA")
	)
	(segment
		(start 300.619668 -419.705536)
		(end 292.958012 -419.705536)
		(width 0.11684)
		(layer "In2.Cu")
		(net "I3C_BMC_SWB_BUF_SDA")
	)
	(segment
		(start 304.626518 -417.658042)
		(end 302.667162 -417.658042)
		(width 0.11684)
		(layer "In2.Cu")
		(net "I3C_BMC_SWB_BUF_SDA")
	)
	(segment
		(start 302.667162 -417.658042)
		(end 300.619668 -419.705536)
		(width 0.11684)
		(layer "In2.Cu")
		(net "I3C_BMC_SWB_BUF_SDA")
	)
	(segment
		(start 353.309682 -415.028634)
		(end 352.565462 -414.284414)
		(width 0.11684)
		(layer "In2.Cu")
		(net "I3C_BMC_SWB_BUF_SDA")
	)
	(segment
		(start 310.444642 -415.677096)
		(end 309.388764 -416.732974)
		(width 0.11684)
		(layer "In2.Cu")
		(net "I3C_BMC_SWB_BUF_SDA")
	)
	(segment
		(start 306.56911 -417.338764)
		(end 304.945796 -417.338764)
		(width 0.11684)
		(layer "In2.Cu")
		(net "I3C_BMC_SWB_BUF_SDA")
	)
	(segment
		(start 291.704268 -422.373806)
		(end 291.704268 -425.615862)
		(width 0.11684)
		(layer "In2.Cu")
		(net "I3C_BMC_SWB_BUF_SDA")
	)
	(segment
		(start 307.859176 -417.488624)
		(end 306.71897 -417.488624)
		(width 0.11684)
		(layer "In2.Cu")
		(net "I3C_BMC_SWB_BUF_SDA")
	)
	(segment
		(start 359.979468 -415.028634)
		(end 353.309682 -415.028634)
		(width 0.11684)
		(layer "In2.Cu")
		(net "I3C_BMC_SWB_BUF_SDA")
	)
	(segment
		(start 292.61943 -421.458644)
		(end 291.704268 -422.373806)
		(width 0.11684)
		(layer "In2.Cu")
		(net "I3C_BMC_SWB_BUF_SDA")
	)
	(segment
		(start 352.565462 -414.284414)
		(end 311.100978 -414.284414)
		(width 0.11684)
		(layer "In2.Cu")
		(net "I3C_BMC_SWB_BUF_SDA")
	)
	(segment
		(start 291.478462 -425.841668)
		(end 289.904424 -425.841668)
		(width 0.11684)
		(layer "In2.Cu")
		(net "I3C_BMC_SWB_BUF_SDA")
	)
	(segment
		(start 311.100978 -414.284414)
		(end 310.444642 -414.94075)
		(width 0.11684)
		(layer "In2.Cu")
		(net "I3C_BMC_SWB_BUF_SDA")
	)
	(segment
		(start 304.945796 -417.338764)
		(end 304.626518 -417.658042)
		(width 0.11684)
		(layer "In2.Cu")
		(net "I3C_BMC_SWB_BUF_SDA")
	)
	(segment
		(start 310.444642 -414.94075)
		(end 310.444642 -415.677096)
		(width 0.11684)
		(layer "In2.Cu")
		(net "I3C_BMC_SWB_BUF_SDA")
	)
	(segment
		(start 291.704268 -425.615862)
		(end 291.478462 -425.841668)
		(width 0.11684)
		(layer "In2.Cu")
		(net "I3C_BMC_SWB_BUF_SDA")
	)
	(segment
		(start 292.958012 -419.705536)
		(end 292.61943 -420.044118)
		(width 0.11684)
		(layer "In2.Cu")
		(net "I3C_BMC_SWB_BUF_SDA")
	)
	(segment
		(start 361.255564 -413.752538)
		(end 359.979468 -415.028634)
		(width 0.11684)
		(layer "In2.Cu")
		(net "I3C_BMC_SWB_BUF_SDA")
	)
	(segment
		(start 292.61943 -420.044118)
		(end 292.61943 -421.458644)
		(width 0.11684)
		(layer "In2.Cu")
		(net "I3C_BMC_SWB_BUF_SDA")
	)
	(segment
		(start 308.614826 -416.732974)
		(end 307.859176 -417.488624)
		(width 0.11684)
		(layer "In2.Cu")
		(net "I3C_BMC_SWB_BUF_SDA")
	)
	(segment
		(start 306.71897 -417.488624)
		(end 306.56911 -417.338764)
		(width 0.11684)
		(layer "In2.Cu")
		(net "I3C_BMC_SWB_BUF_SDA")
	)
	(segment
		(start 309.388764 -416.732974)
		(end 308.614826 -416.732974)
		(width 0.11684)
		(layer "In2.Cu")
		(net "I3C_BMC_SWB_BUF_SDA")
	)
	(via
		(at 288.69005 -425.764706)
		(size 0.508)
		(drill 0.254)
		(layers "F.Cu" "B.Cu")
		(net "I3C_BMC_SWB_BUF_SCL")
	)
	(via
		(at 375.009664 -428.995586)
		(size 0.6604)
		(drill 0.3302)
		(layers "F.Cu" "B.Cu")
		(net "I3C_BMC_SWB_BUF_SCL")
	)
	(via
		(at 361.227116 -413.07258)
		(size 0.508)
		(drill 0.254)
		(layers "F.Cu" "B.Cu")
		(net "I3C_BMC_SWB_BUF_SCL")
	)
	(segment
		(start 363.042962 -418.528246)
		(end 363.540802 -418.030406)
		(width 0.10668)
		(layer "B.Cu")
		(net "I3C_BMC_SWB_BUF_SCL")
	)
	(segment
		(start 379.984508 -424.346116)
		(end 379.984508 -427.424088)
		(width 0.10668)
		(layer "B.Cu")
		(net "I3C_BMC_SWB_BUF_SCL")
	)
	(segment
		(start 288.69005 -426.466)
		(end 288.69005 -425.764706)
		(width 0.10668)
		(layer "B.Cu")
		(net "I3C_BMC_SWB_BUF_SCL")
	)
	(segment
		(start 375.009664 -428.995586)
		(end 366.219486 -428.995586)
		(width 0.10668)
		(layer "B.Cu")
		(net "I3C_BMC_SWB_BUF_SCL")
	)
	(segment
		(start 386.356606 -423.296588)
		(end 381.034036 -423.296588)
		(width 0.10668)
		(layer "B.Cu")
		(net "I3C_BMC_SWB_BUF_SCL")
	)
	(segment
		(start 366.219486 -428.995586)
		(end 364.10519 -426.88129)
		(width 0.10668)
		(layer "B.Cu")
		(net "I3C_BMC_SWB_BUF_SCL")
	)
	(segment
		(start 364.10519 -426.88129)
		(end 364.10519 -423.282618)
		(width 0.10668)
		(layer "B.Cu")
		(net "I3C_BMC_SWB_BUF_SCL")
	)
	(segment
		(start 375.335038 -428.995586)
		(end 375.009664 -428.995586)
		(width 0.10668)
		(layer "B.Cu")
		(net "I3C_BMC_SWB_BUF_SCL")
	)
	(segment
		(start 363.540802 -414.992566)
		(end 361.620816 -413.07258)
		(width 0.10668)
		(layer "B.Cu")
		(net "I3C_BMC_SWB_BUF_SCL")
	)
	(segment
		(start 363.540802 -418.030406)
		(end 363.540802 -414.992566)
		(width 0.10668)
		(layer "B.Cu")
		(net "I3C_BMC_SWB_BUF_SCL")
	)
	(segment
		(start 387.749796 -424.689778)
		(end 386.356606 -423.296588)
		(width 0.10668)
		(layer "B.Cu")
		(net "I3C_BMC_SWB_BUF_SCL")
	)
	(segment
		(start 363.042962 -422.22039)
		(end 363.042962 -418.528246)
		(width 0.10668)
		(layer "B.Cu")
		(net "I3C_BMC_SWB_BUF_SCL")
	)
	(segment
		(start 378.607828 -428.800768)
		(end 375.529856 -428.800768)
		(width 0.10668)
		(layer "B.Cu")
		(net "I3C_BMC_SWB_BUF_SCL")
	)
	(segment
		(start 379.984508 -427.424088)
		(end 378.607828 -428.800768)
		(width 0.10668)
		(layer "B.Cu")
		(net "I3C_BMC_SWB_BUF_SCL")
	)
	(segment
		(start 375.529856 -428.800768)
		(end 375.335038 -428.995586)
		(width 0.10668)
		(layer "B.Cu")
		(net "I3C_BMC_SWB_BUF_SCL")
	)
	(segment
		(start 361.620816 -413.07258)
		(end 361.227116 -413.07258)
		(width 0.10668)
		(layer "B.Cu")
		(net "I3C_BMC_SWB_BUF_SCL")
	)
	(segment
		(start 364.10519 -423.282618)
		(end 363.042962 -422.22039)
		(width 0.10668)
		(layer "B.Cu")
		(net "I3C_BMC_SWB_BUF_SCL")
	)
	(segment
		(start 381.034036 -423.296588)
		(end 379.984508 -424.346116)
		(width 0.10668)
		(layer "B.Cu")
		(net "I3C_BMC_SWB_BUF_SCL")
	)
	(segment
		(start 361.08767 -413.07258)
		(end 359.731056 -414.429194)
		(width 0.11684)
		(layer "In2.Cu")
		(net "I3C_BMC_SWB_BUF_SCL")
	)
	(segment
		(start 304.81016 -416.324288)
		(end 303.15281 -416.324288)
		(width 0.11684)
		(layer "In2.Cu")
		(net "I3C_BMC_SWB_BUF_SCL")
	)
	(segment
		(start 292.603682 -419.106096)
		(end 291.95776 -419.752018)
		(width 0.11684)
		(layer "In2.Cu")
		(net "I3C_BMC_SWB_BUF_SCL")
	)
	(segment
		(start 308.728618 -412.541466)
		(end 308.728618 -413.456374)
		(width 0.11684)
		(layer "In2.Cu")
		(net "I3C_BMC_SWB_BUF_SCL")
	)
	(segment
		(start 289.23488 -425.219876)
		(end 288.69005 -425.764706)
		(width 0.11684)
		(layer "In2.Cu")
		(net "I3C_BMC_SWB_BUF_SCL")
	)
	(segment
		(start 359.731056 -414.429194)
		(end 353.748848 -414.429194)
		(width 0.11684)
		(layer "In2.Cu")
		(net "I3C_BMC_SWB_BUF_SCL")
	)
	(segment
		(start 307.289454 -415.73958)
		(end 306.56911 -416.459924)
		(width 0.11684)
		(layer "In2.Cu")
		(net "I3C_BMC_SWB_BUF_SCL")
	)
	(segment
		(start 291.95776 -421.26408)
		(end 291.097462 -422.124378)
		(width 0.11684)
		(layer "In2.Cu")
		(net "I3C_BMC_SWB_BUF_SCL")
	)
	(segment
		(start 351.03689 -411.717236)
		(end 309.552848 -411.717236)
		(width 0.11684)
		(layer "In2.Cu")
		(net "I3C_BMC_SWB_BUF_SCL")
	)
	(segment
		(start 291.95776 -419.752018)
		(end 291.95776 -421.26408)
		(width 0.11684)
		(layer "In2.Cu")
		(net "I3C_BMC_SWB_BUF_SCL")
	)
	(segment
		(start 291.097462 -422.124378)
		(end 291.097462 -425.092876)
		(width 0.11684)
		(layer "In2.Cu")
		(net "I3C_BMC_SWB_BUF_SCL")
	)
	(segment
		(start 309.552848 -411.717236)
		(end 308.728618 -412.541466)
		(width 0.11684)
		(layer "In2.Cu")
		(net "I3C_BMC_SWB_BUF_SCL")
	)
	(segment
		(start 304.945796 -416.459924)
		(end 304.81016 -416.324288)
		(width 0.11684)
		(layer "In2.Cu")
		(net "I3C_BMC_SWB_BUF_SCL")
	)
	(segment
		(start 291.097462 -425.092876)
		(end 290.970462 -425.219876)
		(width 0.11684)
		(layer "In2.Cu")
		(net "I3C_BMC_SWB_BUF_SCL")
	)
	(segment
		(start 303.15281 -416.324288)
		(end 300.371002 -419.106096)
		(width 0.11684)
		(layer "In2.Cu")
		(net "I3C_BMC_SWB_BUF_SCL")
	)
	(segment
		(start 353.748848 -414.429194)
		(end 351.03689 -411.717236)
		(width 0.11684)
		(layer "In2.Cu")
		(net "I3C_BMC_SWB_BUF_SCL")
	)
	(segment
		(start 300.371002 -419.106096)
		(end 292.603682 -419.106096)
		(width 0.11684)
		(layer "In2.Cu")
		(net "I3C_BMC_SWB_BUF_SCL")
	)
	(segment
		(start 307.289454 -414.895538)
		(end 307.289454 -415.73958)
		(width 0.11684)
		(layer "In2.Cu")
		(net "I3C_BMC_SWB_BUF_SCL")
	)
	(segment
		(start 361.227116 -413.07258)
		(end 361.08767 -413.07258)
		(width 0.11684)
		(layer "In2.Cu")
		(net "I3C_BMC_SWB_BUF_SCL")
	)
	(segment
		(start 290.970462 -425.219876)
		(end 289.23488 -425.219876)
		(width 0.11684)
		(layer "In2.Cu")
		(net "I3C_BMC_SWB_BUF_SCL")
	)
	(segment
		(start 308.728618 -413.456374)
		(end 307.289454 -414.895538)
		(width 0.11684)
		(layer "In2.Cu")
		(net "I3C_BMC_SWB_BUF_SCL")
	)
	(segment
		(start 306.56911 -416.459924)
		(end 304.945796 -416.459924)
		(width 0.11684)
		(layer "In2.Cu")
		(net "I3C_BMC_SWB_BUF_SCL")
	)
	(segment
		(start 173.844204 -168.928542)
		(end 171.26077 -169.998644)
		(width 0.10668)
		(layer "F.Cu")
		(net "I3C_1_SPD_DDRGL_CPU1_SDA")
	)
	(segment
		(start 160.147 -193.111374)
		(end 159.957516 -193.300858)
		(width 0.10668)
		(layer "F.Cu")
		(net "I3C_1_SPD_DDRGL_CPU1_SDA")
	)
	(segment
		(start 169.90949 -172.496226)
		(end 160.147 -182.258716)
		(width 0.10668)
		(layer "F.Cu")
		(net "I3C_1_SPD_DDRGL_CPU1_SDA")
	)
	(segment
		(start 159.303974 -196.341746)
		(end 159.9057 -196.943472)
		(width 0.10668)
		(layer "F.Cu")
		(net "I3C_1_SPD_DDRGL_CPU1_SDA")
	)
	(segment
		(start 180.020214 -163.010596)
		(end 181.93512 -163.010596)
		(width 0.10668)
		(layer "F.Cu")
		(net "I3C_1_SPD_DDRGL_CPU1_SDA")
	)
	(segment
		(start 159.303974 -194.878706)
		(end 159.303974 -196.341746)
		(width 0.10668)
		(layer "F.Cu")
		(net "I3C_1_SPD_DDRGL_CPU1_SDA")
	)
	(segment
		(start 182.66283 -163.738306)
		(end 182.66283 -164.121338)
		(width 0.10668)
		(layer "F.Cu")
		(net "I3C_1_SPD_DDRGL_CPU1_SDA")
	)
	(segment
		(start 161.494978 -196.943472)
		(end 162.628834 -195.809616)
		(width 0.10668)
		(layer "F.Cu")
		(net "I3C_1_SPD_DDRGL_CPU1_SDA")
	)
	(segment
		(start 159.957516 -193.300858)
		(end 159.303974 -194.878706)
		(width 0.10668)
		(layer "F.Cu")
		(net "I3C_1_SPD_DDRGL_CPU1_SDA")
	)
	(segment
		(start 179.110132 -163.920678)
		(end 178.852068 -163.920678)
		(width 0.10668)
		(layer "F.Cu")
		(net "I3C_1_SPD_DDRGL_CPU1_SDA")
	)
	(segment
		(start 171.26077 -169.998644)
		(end 169.90949 -171.349924)
		(width 0.10668)
		(layer "F.Cu")
		(net "I3C_1_SPD_DDRGL_CPU1_SDA")
	)
	(segment
		(start 160.147 -182.258716)
		(end 160.147 -193.111374)
		(width 0.10668)
		(layer "F.Cu")
		(net "I3C_1_SPD_DDRGL_CPU1_SDA")
	)
	(segment
		(start 179.110132 -163.920678)
		(end 180.020214 -163.010596)
		(width 0.10668)
		(layer "F.Cu")
		(net "I3C_1_SPD_DDRGL_CPU1_SDA")
	)
	(segment
		(start 169.90949 -171.349924)
		(end 169.90949 -172.496226)
		(width 0.10668)
		(layer "F.Cu")
		(net "I3C_1_SPD_DDRGL_CPU1_SDA")
	)
	(segment
		(start 181.93512 -163.010596)
		(end 182.66283 -163.738306)
		(width 0.10668)
		(layer "F.Cu")
		(net "I3C_1_SPD_DDRGL_CPU1_SDA")
	)
	(segment
		(start 162.628834 -195.809616)
		(end 162.628834 -193.925952)
		(width 0.10668)
		(layer "F.Cu")
		(net "I3C_1_SPD_DDRGL_CPU1_SDA")
	)
	(segment
		(start 159.9057 -196.943472)
		(end 161.494978 -196.943472)
		(width 0.10668)
		(layer "F.Cu")
		(net "I3C_1_SPD_DDRGL_CPU1_SDA")
	)
	(segment
		(start 178.852068 -163.920678)
		(end 173.844204 -168.928542)
		(width 0.10668)
		(layer "F.Cu")
		(net "I3C_1_SPD_DDRGL_CPU1_SDA")
	)
	(via
		(at 162.628834 -193.925952)
		(size 0.508)
		(drill 0.254)
		(layers "F.Cu" "B.Cu")
		(net "I3C_1_SPD_DDRGL_CPU1_SDA")
	)
	(via
		(at 179.110132 -163.920678)
		(size 0.508)
		(drill 0.254)
		(layers "F.Cu" "B.Cu")
		(net "I3C_1_SPD_DDRGL_CPU1_SDA")
	)
	(segment
		(start 162.252914 -193.550032)
		(end 162.628834 -193.925952)
		(width 0.10668)
		(layer "B.Cu")
		(net "I3C_1_SPD_DDRGL_CPU1_SDA")
	)
	(segment
		(start 161.276284 -192.507362)
		(end 162.252914 -193.485008)
		(width 0.10668)
		(layer "B.Cu")
		(net "I3C_1_SPD_DDRGL_CPU1_SDA")
	)
	(segment
		(start 162.252914 -193.485008)
		(end 162.252914 -193.550032)
		(width 0.10668)
		(layer "B.Cu")
		(net "I3C_1_SPD_DDRGL_CPU1_SDA")
	)
	(segment
		(start 160.372044 -193.741548)
		(end 159.84474 -195.014342)
		(width 0.10668)
		(layer "F.Cu")
		(net "I3C_1_SPD_DDRGL_CPU1_SCL")
	)
	(segment
		(start 171.68749 -170.405298)
		(end 170.44797 -171.644818)
		(width 0.10668)
		(layer "F.Cu")
		(net "I3C_1_SPD_DDRGL_CPU1_SCL")
	)
	(segment
		(start 160.68548 -182.501286)
		(end 160.68548 -193.428112)
		(width 0.10668)
		(layer "F.Cu")
		(net "I3C_1_SPD_DDRGL_CPU1_SCL")
	)
	(segment
		(start 159.84474 -195.014342)
		(end 159.84474 -195.862448)
		(width 0.10668)
		(layer "F.Cu")
		(net "I3C_1_SPD_DDRGL_CPU1_SCL")
	)
	(segment
		(start 182.162704 -164.121338)
		(end 181.60873 -163.567364)
		(width 0.10668)
		(layer "F.Cu")
		(net "I3C_1_SPD_DDRGL_CPU1_SCL")
	)
	(segment
		(start 180.225192 -163.567364)
		(end 174.589186 -169.20337)
		(width 0.10668)
		(layer "F.Cu")
		(net "I3C_1_SPD_DDRGL_CPU1_SCL")
	)
	(segment
		(start 170.44797 -172.738796)
		(end 160.68548 -182.501286)
		(width 0.10668)
		(layer "F.Cu")
		(net "I3C_1_SPD_DDRGL_CPU1_SCL")
	)
	(segment
		(start 181.60873 -163.567364)
		(end 180.225192 -163.567364)
		(width 0.10668)
		(layer "F.Cu")
		(net "I3C_1_SPD_DDRGL_CPU1_SCL")
	)
	(segment
		(start 174.589186 -169.20337)
		(end 171.68749 -170.405298)
		(width 0.10668)
		(layer "F.Cu")
		(net "I3C_1_SPD_DDRGL_CPU1_SCL")
	)
	(segment
		(start 159.84474 -195.862448)
		(end 160.415478 -196.433186)
		(width 0.10668)
		(layer "F.Cu")
		(net "I3C_1_SPD_DDRGL_CPU1_SCL")
	)
	(segment
		(start 170.44797 -171.644818)
		(end 170.44797 -172.738796)
		(width 0.10668)
		(layer "F.Cu")
		(net "I3C_1_SPD_DDRGL_CPU1_SCL")
	)
	(segment
		(start 160.68548 -193.428112)
		(end 160.372044 -193.741548)
		(width 0.10668)
		(layer "F.Cu")
		(net "I3C_1_SPD_DDRGL_CPU1_SCL")
	)
	(via
		(at 160.415478 -196.433186)
		(size 0.508)
		(drill 0.254)
		(layers "F.Cu" "B.Cu")
		(net "I3C_1_SPD_DDRGL_CPU1_SCL")
	)
	(via
		(at 158.632398 -194.447414)
		(size 0.6604)
		(drill 0.3302)
		(layers "F.Cu" "B.Cu")
		(net "I3C_1_SPD_DDRGL_CPU1_SCL")
	)
	(segment
		(start 159.615632 -192.748916)
		(end 159.149034 -192.748916)
		(width 0.10668)
		(layer "B.Cu")
		(net "I3C_1_SPD_DDRGL_CPU1_SCL")
	)
	(segment
		(start 159.149034 -192.748916)
		(end 158.632398 -193.265552)
		(width 0.10668)
		(layer "B.Cu")
		(net "I3C_1_SPD_DDRGL_CPU1_SCL")
	)
	(segment
		(start 158.632398 -193.265552)
		(end 158.632398 -194.447414)
		(width 0.10668)
		(layer "B.Cu")
		(net "I3C_1_SPD_DDRGL_CPU1_SCL")
	)
	(segment
		(start 158.632398 -194.447414)
		(end 158.632398 -194.650106)
		(width 0.10668)
		(layer "B.Cu")
		(net "I3C_1_SPD_DDRGL_CPU1_SCL")
	)
	(segment
		(start 158.632398 -194.650106)
		(end 160.415478 -196.433186)
		(width 0.10668)
		(layer "B.Cu")
		(net "I3C_1_SPD_DDRGL_CPU1_SCL")
	)
	(segment
		(start 142.327884 -222.070422)
		(end 142.794736 -221.804484)
		(width 0.10668)
		(layer "F.Cu")
		(net "I3C_1_SPD_DDRGL_CPU1_R_SDA")
	)
	(via
		(at 142.794736 -221.804484)
		(size 0.4064)
		(drill 0.2032)
		(layers "F.Cu" "B.Cu")
		(net "I3C_1_SPD_DDRGL_CPU1_R_SDA")
	)
	(via
		(at 159.895794 -200.418192)
		(size 0.6604)
		(drill 0.3302)
		(layers "F.Cu" "B.Cu")
		(net "I3C_1_SPD_DDRGL_CPU1_R_SDA")
	)
	(segment
		(start 144.598898 -225.517964)
		(end 144.843246 -225.517964)
		(width 0.10668)
		(layer "B.Cu")
		(net "I3C_1_SPD_DDRGL_CPU1_R_SDA")
	)
	(segment
		(start 160.713166 -192.978786)
		(end 160.713166 -191.578484)
		(width 0.10668)
		(layer "B.Cu")
		(net "I3C_1_SPD_DDRGL_CPU1_R_SDA")
	)
	(segment
		(start 162.367722 -195.61556)
		(end 162.298634 -195.684648)
		(width 0.10668)
		(layer "B.Cu")
		(net "I3C_1_SPD_DDRGL_CPU1_R_SDA")
	)
	(segment
		(start 142.057628 -224.62109)
		(end 142.089632 -224.639632)
		(width 0.10668)
		(layer "B.Cu")
		(net "I3C_1_SPD_DDRGL_CPU1_R_SDA")
	)
	(segment
		(start 161.041842 -193.307462)
		(end 160.713166 -192.978786)
		(width 0.10668)
		(layer "B.Cu")
		(net "I3C_1_SPD_DDRGL_CPU1_R_SDA")
	)
	(segment
		(start 162.298634 -195.684648)
		(end 162.298634 -198.015352)
		(width 0.10668)
		(layer "B.Cu")
		(net "I3C_1_SPD_DDRGL_CPU1_R_SDA")
	)
	(segment
		(start 162.298634 -198.015352)
		(end 159.895794 -200.418192)
		(width 0.10668)
		(layer "B.Cu")
		(net "I3C_1_SPD_DDRGL_CPU1_R_SDA")
	)
	(segment
		(start 148.09597 -222.878396)
		(end 159.895794 -211.078572)
		(width 0.10668)
		(layer "B.Cu")
		(net "I3C_1_SPD_DDRGL_CPU1_R_SDA")
	)
	(segment
		(start 145.048986 -225.312224)
		(end 145.46453 -225.312224)
		(width 0.10668)
		(layer "B.Cu")
		(net "I3C_1_SPD_DDRGL_CPU1_R_SDA")
	)
	(segment
		(start 145.46453 -225.312224)
		(end 145.641568 -225.489262)
		(width 0.10668)
		(layer "B.Cu")
		(net "I3C_1_SPD_DDRGL_CPU1_R_SDA")
	)
	(segment
		(start 162.367722 -194.47256)
		(end 162.367722 -195.61556)
		(width 0.10668)
		(layer "B.Cu")
		(net "I3C_1_SPD_DDRGL_CPU1_R_SDA")
	)
	(segment
		(start 144.43964 -225.449384)
		(end 144.598898 -225.517964)
		(width 0.10668)
		(layer "B.Cu")
		(net "I3C_1_SPD_DDRGL_CPU1_R_SDA")
	)
	(segment
		(start 161.755328 -193.786506)
		(end 161.755328 -193.860166)
		(width 0.10668)
		(layer "B.Cu")
		(net "I3C_1_SPD_DDRGL_CPU1_R_SDA")
	)
	(segment
		(start 142.089632 -224.639632)
		(end 142.127732 -224.66173)
		(width 0.10668)
		(layer "B.Cu")
		(net "I3C_1_SPD_DDRGL_CPU1_R_SDA")
	)
	(segment
		(start 161.276284 -193.307462)
		(end 161.755328 -193.786506)
		(width 0.10668)
		(layer "B.Cu")
		(net "I3C_1_SPD_DDRGL_CPU1_R_SDA")
	)
	(segment
		(start 161.755328 -193.860166)
		(end 162.367722 -194.47256)
		(width 0.10668)
		(layer "B.Cu")
		(net "I3C_1_SPD_DDRGL_CPU1_R_SDA")
	)
	(segment
		(start 148.09597 -224.186496)
		(end 148.09597 -222.878396)
		(width 0.10668)
		(layer "B.Cu")
		(net "I3C_1_SPD_DDRGL_CPU1_R_SDA")
	)
	(segment
		(start 161.276284 -193.307462)
		(end 161.041842 -193.307462)
		(width 0.10668)
		(layer "B.Cu")
		(net "I3C_1_SPD_DDRGL_CPU1_R_SDA")
	)
	(segment
		(start 141.854936 -222.744284)
		(end 141.854936 -224.234502)
		(width 0.10668)
		(layer "B.Cu")
		(net "I3C_1_SPD_DDRGL_CPU1_R_SDA")
	)
	(segment
		(start 160.713166 -191.578484)
		(end 160.7312 -191.56045)
		(width 0.10668)
		(layer "B.Cu")
		(net "I3C_1_SPD_DDRGL_CPU1_R_SDA")
	)
	(segment
		(start 142.794736 -221.804484)
		(end 141.854936 -222.744284)
		(width 0.10668)
		(layer "B.Cu")
		(net "I3C_1_SPD_DDRGL_CPU1_R_SDA")
	)
	(segment
		(start 143.029686 -225.449384)
		(end 143.039338 -225.443796)
		(width 0.10668)
		(layer "B.Cu")
		(net "I3C_1_SPD_DDRGL_CPU1_R_SDA")
	)
	(segment
		(start 142.524226 -225.42881)
		(end 142.559786 -225.449384)
		(width 0.10668)
		(layer "B.Cu")
		(net "I3C_1_SPD_DDRGL_CPU1_R_SDA")
	)
	(segment
		(start 159.895794 -211.078572)
		(end 159.895794 -200.418192)
		(width 0.10668)
		(layer "B.Cu")
		(net "I3C_1_SPD_DDRGL_CPU1_R_SDA")
	)
	(segment
		(start 145.641568 -225.489262)
		(end 146.793204 -225.489262)
		(width 0.10668)
		(layer "B.Cu")
		(net "I3C_1_SPD_DDRGL_CPU1_R_SDA")
	)
	(segment
		(start 146.793204 -225.489262)
		(end 148.09597 -224.186496)
		(width 0.10668)
		(layer "B.Cu")
		(net "I3C_1_SPD_DDRGL_CPU1_R_SDA")
	)
	(segment
		(start 144.843246 -225.517964)
		(end 145.048986 -225.312224)
		(width 0.10668)
		(layer "B.Cu")
		(net "I3C_1_SPD_DDRGL_CPU1_R_SDA")
	)
	(arc
		(start 143.49984 -225.449384)
		(mid 143.73479 -225.512617)
		(end 143.96974 -225.449384)
		(width 0.10668)
		(layer "B.Cu")
		(net "I3C_1_SPD_DDRGL_CPU1_R_SDA")
	)
	(arc
		(start 142.127732 -224.66173)
		(mid 142.272689 -224.829228)
		(end 142.324836 -225.044508)
		(width 0.10668)
		(layer "B.Cu")
		(net "I3C_1_SPD_DDRGL_CPU1_R_SDA")
	)
	(arc
		(start 142.324836 -225.044508)
		(mid 142.377642 -225.260993)
		(end 142.524226 -225.42881)
		(width 0.10668)
		(layer "B.Cu")
		(net "I3C_1_SPD_DDRGL_CPU1_R_SDA")
	)
	(arc
		(start 141.854936 -224.234502)
		(mid 141.90869 -224.452742)
		(end 142.057628 -224.62109)
		(width 0.10668)
		(layer "B.Cu")
		(net "I3C_1_SPD_DDRGL_CPU1_R_SDA")
	)
	(arc
		(start 143.039338 -225.443796)
		(mid 143.270323 -225.386095)
		(end 143.49984 -225.449384)
		(width 0.10668)
		(layer "B.Cu")
		(net "I3C_1_SPD_DDRGL_CPU1_R_SDA")
	)
	(arc
		(start 142.559786 -225.449384)
		(mid 142.794736 -225.512617)
		(end 143.029686 -225.449384)
		(width 0.10668)
		(layer "B.Cu")
		(net "I3C_1_SPD_DDRGL_CPU1_R_SDA")
	)
	(arc
		(start 143.96974 -225.449384)
		(mid 144.20469 -225.386185)
		(end 144.43964 -225.449384)
		(width 0.10668)
		(layer "B.Cu")
		(net "I3C_1_SPD_DDRGL_CPU1_R_SDA")
	)
	(segment
		(start 140.447776 -223.690434)
		(end 140.914882 -223.424496)
		(width 0.10668)
		(layer "F.Cu")
		(net "I3C_1_SPD_DDRGL_CPU1_R_SCL")
	)
	(via
		(at 160.649666 -198.52513)
		(size 0.6604)
		(drill 0.3302)
		(layers "F.Cu" "B.Cu")
		(net "I3C_1_SPD_DDRGL_CPU1_R_SCL")
	)
	(via
		(at 140.914882 -223.424496)
		(size 0.4064)
		(drill 0.2032)
		(layers "F.Cu" "B.Cu")
		(net "I3C_1_SPD_DDRGL_CPU1_R_SCL")
	)
	(segment
		(start 142.59306 -223.000316)
		(end 142.559786 -223.01962)
		(width 0.10668)
		(layer "B.Cu")
		(net "I3C_1_SPD_DDRGL_CPU1_R_SCL")
	)
	(segment
		(start 161.043874 -198.130922)
		(end 160.649666 -198.52513)
		(width 0.10668)
		(layer "B.Cu")
		(net "I3C_1_SPD_DDRGL_CPU1_R_SCL")
	)
	(segment
		(start 143.279622 -221.405704)
		(end 143.279622 -221.981522)
		(width 0.10668)
		(layer "B.Cu")
		(net "I3C_1_SPD_DDRGL_CPU1_R_SCL")
	)
	(segment
		(start 159.219138 -199.955658)
		(end 160.649666 -198.52513)
		(width 0.10668)
		(layer "B.Cu")
		(net "I3C_1_SPD_DDRGL_CPU1_R_SCL")
	)
	(segment
		(start 160.16732 -194.592956)
		(end 161.043874 -195.46951)
		(width 0.10668)
		(layer "B.Cu")
		(net "I3C_1_SPD_DDRGL_CPU1_R_SCL")
	)
	(segment
		(start 140.914882 -222.454724)
		(end 142.241016 -221.12859)
		(width 0.10668)
		(layer "B.Cu")
		(net "I3C_1_SPD_DDRGL_CPU1_R_SCL")
	)
	(segment
		(start 147.133818 -222.94088)
		(end 159.219138 -210.85556)
		(width 0.10668)
		(layer "B.Cu")
		(net "I3C_1_SPD_DDRGL_CPU1_R_SCL")
	)
	(segment
		(start 159.7152 -191.997584)
		(end 159.7152 -191.56045)
		(width 0.10668)
		(layer "B.Cu")
		(net "I3C_1_SPD_DDRGL_CPU1_R_SCL")
	)
	(segment
		(start 145.062448 -224.61728)
		(end 146.425412 -224.61728)
		(width 0.10668)
		(layer "B.Cu")
		(net "I3C_1_SPD_DDRGL_CPU1_R_SCL")
	)
	(segment
		(start 140.914882 -223.424496)
		(end 140.914882 -222.454724)
		(width 0.10668)
		(layer "B.Cu")
		(net "I3C_1_SPD_DDRGL_CPU1_R_SCL")
	)
	(segment
		(start 143.279622 -221.981522)
		(end 143.125698 -222.135446)
		(width 0.10668)
		(layer "B.Cu")
		(net "I3C_1_SPD_DDRGL_CPU1_R_SCL")
	)
	(segment
		(start 144.900142 -224.634044)
		(end 144.909794 -224.639632)
		(width 0.10668)
		(layer "B.Cu")
		(net "I3C_1_SPD_DDRGL_CPU1_R_SCL")
	)
	(segment
		(start 142.524226 -223.808798)
		(end 142.559786 -223.829372)
		(width 0.10668)
		(layer "B.Cu")
		(net "I3C_1_SPD_DDRGL_CPU1_R_SCL")
	)
	(segment
		(start 159.615632 -193.549016)
		(end 159.615632 -193.581528)
		(width 0.10668)
		(layer "B.Cu")
		(net "I3C_1_SPD_DDRGL_CPU1_R_SCL")
	)
	(segment
		(start 143.029686 -224.639632)
		(end 143.039338 -224.64522)
		(width 0.10668)
		(layer "B.Cu")
		(net "I3C_1_SPD_DDRGL_CPU1_R_SCL")
	)
	(segment
		(start 143.029686 -222.20936)
		(end 142.996412 -222.228664)
		(width 0.10668)
		(layer "B.Cu")
		(net "I3C_1_SPD_DDRGL_CPU1_R_SCL")
	)
	(segment
		(start 142.241016 -221.12859)
		(end 143.002508 -221.12859)
		(width 0.10668)
		(layer "B.Cu")
		(net "I3C_1_SPD_DDRGL_CPU1_R_SCL")
	)
	(segment
		(start 147.133818 -223.908874)
		(end 147.133818 -222.94088)
		(width 0.10668)
		(layer "B.Cu")
		(net "I3C_1_SPD_DDRGL_CPU1_R_SCL")
	)
	(segment
		(start 142.559786 -223.829372)
		(end 142.59306 -223.848676)
		(width 0.10668)
		(layer "B.Cu")
		(net "I3C_1_SPD_DDRGL_CPU1_R_SCL")
	)
	(segment
		(start 143.0274 -224.638108)
		(end 143.029686 -224.639632)
		(width 0.10668)
		(layer "B.Cu")
		(net "I3C_1_SPD_DDRGL_CPU1_R_SCL")
	)
	(segment
		(start 160.173162 -192.455546)
		(end 159.7152 -191.997584)
		(width 0.10668)
		(layer "B.Cu")
		(net "I3C_1_SPD_DDRGL_CPU1_R_SCL")
	)
	(segment
		(start 160.173162 -192.991486)
		(end 160.173162 -192.455546)
		(width 0.10668)
		(layer "B.Cu")
		(net "I3C_1_SPD_DDRGL_CPU1_R_SCL")
	)
	(segment
		(start 159.219138 -210.85556)
		(end 159.219138 -199.955658)
		(width 0.10668)
		(layer "B.Cu")
		(net "I3C_1_SPD_DDRGL_CPU1_R_SCL")
	)
	(segment
		(start 159.615632 -193.581528)
		(end 160.16732 -194.133216)
		(width 0.10668)
		(layer "B.Cu")
		(net "I3C_1_SPD_DDRGL_CPU1_R_SCL")
	)
	(segment
		(start 146.425412 -224.61728)
		(end 147.133818 -223.908874)
		(width 0.10668)
		(layer "B.Cu")
		(net "I3C_1_SPD_DDRGL_CPU1_R_SCL")
	)
	(segment
		(start 144.909794 -224.639632)
		(end 145.062448 -224.61728)
		(width 0.10668)
		(layer "B.Cu")
		(net "I3C_1_SPD_DDRGL_CPU1_R_SCL")
	)
	(segment
		(start 160.16732 -194.133216)
		(end 160.16732 -194.592956)
		(width 0.10668)
		(layer "B.Cu")
		(net "I3C_1_SPD_DDRGL_CPU1_R_SCL")
	)
	(segment
		(start 161.043874 -195.46951)
		(end 161.043874 -198.130922)
		(width 0.10668)
		(layer "B.Cu")
		(net "I3C_1_SPD_DDRGL_CPU1_R_SCL")
	)
	(segment
		(start 143.002508 -221.12859)
		(end 143.279622 -221.405704)
		(width 0.10668)
		(layer "B.Cu")
		(net "I3C_1_SPD_DDRGL_CPU1_R_SCL")
	)
	(segment
		(start 159.615632 -193.549016)
		(end 160.173162 -192.991486)
		(width 0.10668)
		(layer "B.Cu")
		(net "I3C_1_SPD_DDRGL_CPU1_R_SCL")
	)
	(segment
		(start 142.559786 -223.01962)
		(end 142.524226 -223.040194)
		(width 0.10668)
		(layer "B.Cu")
		(net "I3C_1_SPD_DDRGL_CPU1_R_SCL")
	)
	(arc
		(start 142.794736 -222.61449)
		(mid 142.741276 -222.832168)
		(end 142.59306 -223.000316)
		(width 0.10668)
		(layer "B.Cu")
		(net "I3C_1_SPD_DDRGL_CPU1_R_SCL")
	)
	(arc
		(start 142.59306 -223.848676)
		(mid 142.741276 -224.016824)
		(end 142.794736 -224.234502)
		(width 0.10668)
		(layer "B.Cu")
		(net "I3C_1_SPD_DDRGL_CPU1_R_SCL")
	)
	(arc
		(start 142.794736 -224.234502)
		(mid 142.857146 -224.46737)
		(end 143.0274 -224.638108)
		(width 0.10668)
		(layer "B.Cu")
		(net "I3C_1_SPD_DDRGL_CPU1_R_SCL")
	)
	(arc
		(start 142.996412 -222.228664)
		(mid 142.848196 -222.396812)
		(end 142.794736 -222.61449)
		(width 0.10668)
		(layer "B.Cu")
		(net "I3C_1_SPD_DDRGL_CPU1_R_SCL")
	)
	(arc
		(start 143.96974 -224.639632)
		(mid 144.20469 -224.702831)
		(end 144.43964 -224.639632)
		(width 0.10668)
		(layer "B.Cu")
		(net "I3C_1_SPD_DDRGL_CPU1_R_SCL")
	)
	(arc
		(start 144.43964 -224.639632)
		(mid 144.669157 -224.576306)
		(end 144.900142 -224.634044)
		(width 0.10668)
		(layer "B.Cu")
		(net "I3C_1_SPD_DDRGL_CPU1_R_SCL")
	)
	(arc
		(start 143.49984 -224.639632)
		(mid 143.73479 -224.576399)
		(end 143.96974 -224.639632)
		(width 0.10668)
		(layer "B.Cu")
		(net "I3C_1_SPD_DDRGL_CPU1_R_SCL")
	)
	(arc
		(start 143.039338 -224.64522)
		(mid 143.270323 -224.702921)
		(end 143.49984 -224.639632)
		(width 0.10668)
		(layer "B.Cu")
		(net "I3C_1_SPD_DDRGL_CPU1_R_SCL")
	)
	(arc
		(start 142.524226 -223.040194)
		(mid 142.324882 -223.424496)
		(end 142.524226 -223.808798)
		(width 0.10668)
		(layer "B.Cu")
		(net "I3C_1_SPD_DDRGL_CPU1_R_SCL")
	)
	(arc
		(start 143.125698 -222.135446)
		(mid 143.080104 -222.175537)
		(end 143.029686 -222.20936)
		(width 0.10668)
		(layer "B.Cu")
		(net "I3C_1_SPD_DDRGL_CPU1_R_SCL")
	)
	(segment
		(start 439.45556 -168.466516)
		(end 440.192922 -167.729154)
		(width 0.10668)
		(layer "F.Cu")
		(net "I3C_1_SPD_DDRGL_CPU0_SDA")
	)
	(segment
		(start 440.192922 -167.729154)
		(end 440.192922 -166.901114)
		(width 0.10668)
		(layer "F.Cu")
		(net "I3C_1_SPD_DDRGL_CPU0_SDA")
	)
	(segment
		(start 439.128916 -168.466516)
		(end 439.45556 -168.466516)
		(width 0.10668)
		(layer "F.Cu")
		(net "I3C_1_SPD_DDRGL_CPU0_SDA")
	)
	(via
		(at 440.192922 -166.901114)
		(size 0.508)
		(drill 0.254)
		(layers "F.Cu" "B.Cu")
		(net "I3C_1_SPD_DDRGL_CPU0_SDA")
	)
	(via
		(at 383.076958 -204.085952)
		(size 0.508)
		(drill 0.254)
		(layers "F.Cu" "B.Cu")
		(net "I3C_1_SPD_DDRGL_CPU0_SDA")
	)
	(segment
		(start 383.076958 -204.701902)
		(end 383.076958 -204.085952)
		(width 0.10668)
		(layer "B.Cu")
		(net "I3C_1_SPD_DDRGL_CPU0_SDA")
	)
	(segment
		(start 435.458108 -170.330368)
		(end 437.457088 -170.330368)
		(width 0.11684)
		(layer "In2.Cu")
		(net "I3C_1_SPD_DDRGL_CPU0_SDA")
	)
	(segment
		(start 400.649186 -195.816982)
		(end 413.476694 -182.989474)
		(width 0.11684)
		(layer "In2.Cu")
		(net "I3C_1_SPD_DDRGL_CPU0_SDA")
	)
	(segment
		(start 438.93994 -170.818048)
		(end 439.29681 -170.461178)
		(width 0.11684)
		(layer "In2.Cu")
		(net "I3C_1_SPD_DDRGL_CPU0_SDA")
	)
	(segment
		(start 440.192922 -167.774366)
		(end 440.192922 -166.901114)
		(width 0.11684)
		(layer "In2.Cu")
		(net "I3C_1_SPD_DDRGL_CPU0_SDA")
	)
	(segment
		(start 437.944768 -170.818048)
		(end 438.93994 -170.818048)
		(width 0.11684)
		(layer "In2.Cu")
		(net "I3C_1_SPD_DDRGL_CPU0_SDA")
	)
	(segment
		(start 439.29681 -170.461178)
		(end 439.29681 -168.670478)
		(width 0.11684)
		(layer "In2.Cu")
		(net "I3C_1_SPD_DDRGL_CPU0_SDA")
	)
	(segment
		(start 430.403 -173.94809)
		(end 430.403 -166.624)
		(width 0.11684)
		(layer "In2.Cu")
		(net "I3C_1_SPD_DDRGL_CPU0_SDA")
	)
	(segment
		(start 392.322304 -202.12177)
		(end 398.627092 -195.816982)
		(width 0.11684)
		(layer "In2.Cu")
		(net "I3C_1_SPD_DDRGL_CPU0_SDA")
	)
	(segment
		(start 431.419 -165.608)
		(end 433.07 -165.608)
		(width 0.11684)
		(layer "In2.Cu")
		(net "I3C_1_SPD_DDRGL_CPU0_SDA")
	)
	(segment
		(start 430.403 -166.624)
		(end 431.419 -165.608)
		(width 0.11684)
		(layer "In2.Cu")
		(net "I3C_1_SPD_DDRGL_CPU0_SDA")
	)
	(segment
		(start 413.476694 -182.989474)
		(end 421.361616 -182.989474)
		(width 0.11684)
		(layer "In2.Cu")
		(net "I3C_1_SPD_DDRGL_CPU0_SDA")
	)
	(segment
		(start 439.29681 -168.670478)
		(end 440.192922 -167.774366)
		(width 0.11684)
		(layer "In2.Cu")
		(net "I3C_1_SPD_DDRGL_CPU0_SDA")
	)
	(segment
		(start 434.467 -169.33926)
		(end 435.458108 -170.330368)
		(width 0.11684)
		(layer "In2.Cu")
		(net "I3C_1_SPD_DDRGL_CPU0_SDA")
	)
	(segment
		(start 437.457088 -170.330368)
		(end 437.944768 -170.818048)
		(width 0.11684)
		(layer "In2.Cu")
		(net "I3C_1_SPD_DDRGL_CPU0_SDA")
	)
	(segment
		(start 385.04114 -202.12177)
		(end 392.322304 -202.12177)
		(width 0.11684)
		(layer "In2.Cu")
		(net "I3C_1_SPD_DDRGL_CPU0_SDA")
	)
	(segment
		(start 421.361616 -182.989474)
		(end 430.403 -173.94809)
		(width 0.11684)
		(layer "In2.Cu")
		(net "I3C_1_SPD_DDRGL_CPU0_SDA")
	)
	(segment
		(start 383.076958 -204.085952)
		(end 385.04114 -202.12177)
		(width 0.11684)
		(layer "In2.Cu")
		(net "I3C_1_SPD_DDRGL_CPU0_SDA")
	)
	(segment
		(start 398.627092 -195.816982)
		(end 400.649186 -195.816982)
		(width 0.11684)
		(layer "In2.Cu")
		(net "I3C_1_SPD_DDRGL_CPU0_SDA")
	)
	(segment
		(start 433.07 -165.608)
		(end 434.467 -167.005)
		(width 0.11684)
		(layer "In2.Cu")
		(net "I3C_1_SPD_DDRGL_CPU0_SDA")
	)
	(segment
		(start 434.467 -167.005)
		(end 434.467 -169.33926)
		(width 0.11684)
		(layer "In2.Cu")
		(net "I3C_1_SPD_DDRGL_CPU0_SDA")
	)
	(segment
		(start 439.128916 -167.96639)
		(end 439.43778 -167.657526)
		(width 0.10668)
		(layer "F.Cu")
		(net "I3C_1_SPD_DDRGL_CPU0_SCL")
	)
	(segment
		(start 439.43778 -167.657526)
		(end 439.43778 -165.692328)
		(width 0.10668)
		(layer "F.Cu")
		(net "I3C_1_SPD_DDRGL_CPU0_SCL")
	)
	(segment
		(start 439.43778 -165.692328)
		(end 438.62752 -164.882068)
		(width 0.10668)
		(layer "F.Cu")
		(net "I3C_1_SPD_DDRGL_CPU0_SCL")
	)
	(segment
		(start 438.62752 -164.882068)
		(end 436.8927 -164.882068)
		(width 0.10668)
		(layer "F.Cu")
		(net "I3C_1_SPD_DDRGL_CPU0_SCL")
	)
	(via
		(at 436.8927 -164.882068)
		(size 0.508)
		(drill 0.254)
		(layers "F.Cu" "B.Cu")
		(net "I3C_1_SPD_DDRGL_CPU0_SCL")
	)
	(via
		(at 380.119128 -204.092302)
		(size 0.508)
		(drill 0.254)
		(layers "F.Cu" "B.Cu")
		(net "I3C_1_SPD_DDRGL_CPU0_SCL")
	)
	(segment
		(start 380.282958 -204.256132)
		(end 380.119128 -204.092302)
		(width 0.10668)
		(layer "B.Cu")
		(net "I3C_1_SPD_DDRGL_CPU0_SCL")
	)
	(segment
		(start 380.282958 -204.701902)
		(end 380.282958 -204.256132)
		(width 0.10668)
		(layer "B.Cu")
		(net "I3C_1_SPD_DDRGL_CPU0_SCL")
	)
	(segment
		(start 400.400774 -195.217542)
		(end 398.37868 -195.217542)
		(width 0.11684)
		(layer "In2.Cu")
		(net "I3C_1_SPD_DDRGL_CPU0_SCL")
	)
	(segment
		(start 431.256186 -164.882068)
		(end 429.768 -166.370254)
		(width 0.11684)
		(layer "In2.Cu")
		(net "I3C_1_SPD_DDRGL_CPU0_SCL")
	)
	(segment
		(start 381.507746 -204.724)
		(end 380.750826 -204.724)
		(width 0.11684)
		(layer "In2.Cu")
		(net "I3C_1_SPD_DDRGL_CPU0_SCL")
	)
	(segment
		(start 413.228282 -182.390034)
		(end 400.400774 -195.217542)
		(width 0.11684)
		(layer "In2.Cu")
		(net "I3C_1_SPD_DDRGL_CPU0_SCL")
	)
	(segment
		(start 384.709416 -201.52233)
		(end 381.507746 -204.724)
		(width 0.11684)
		(layer "In2.Cu")
		(net "I3C_1_SPD_DDRGL_CPU0_SCL")
	)
	(segment
		(start 436.8927 -164.882068)
		(end 431.256186 -164.882068)
		(width 0.11684)
		(layer "In2.Cu")
		(net "I3C_1_SPD_DDRGL_CPU0_SCL")
	)
	(segment
		(start 429.768 -173.735238)
		(end 421.113204 -182.390034)
		(width 0.11684)
		(layer "In2.Cu")
		(net "I3C_1_SPD_DDRGL_CPU0_SCL")
	)
	(segment
		(start 429.768 -166.370254)
		(end 429.768 -173.735238)
		(width 0.11684)
		(layer "In2.Cu")
		(net "I3C_1_SPD_DDRGL_CPU0_SCL")
	)
	(segment
		(start 380.750826 -204.724)
		(end 380.119128 -204.092302)
		(width 0.11684)
		(layer "In2.Cu")
		(net "I3C_1_SPD_DDRGL_CPU0_SCL")
	)
	(segment
		(start 392.073892 -201.52233)
		(end 384.709416 -201.52233)
		(width 0.11684)
		(layer "In2.Cu")
		(net "I3C_1_SPD_DDRGL_CPU0_SCL")
	)
	(segment
		(start 398.37868 -195.217542)
		(end 392.073892 -201.52233)
		(width 0.11684)
		(layer "In2.Cu")
		(net "I3C_1_SPD_DDRGL_CPU0_SCL")
	)
	(segment
		(start 421.113204 -182.390034)
		(end 413.228282 -182.390034)
		(width 0.11684)
		(layer "In2.Cu")
		(net "I3C_1_SPD_DDRGL_CPU0_SCL")
	)
	(segment
		(start 390.267952 -221.460314)
		(end 390.267952 -222.070168)
		(width 0.10668)
		(layer "F.Cu")
		(net "I3C_1_SPD_DDRGL_CPU0_R_SDA")
	)
	(segment
		(start 383.606294 -206.911194)
		(end 383.606294 -214.798656)
		(width 0.10668)
		(layer "F.Cu")
		(net "I3C_1_SPD_DDRGL_CPU0_R_SDA")
	)
	(segment
		(start 383.606294 -214.798656)
		(end 390.267952 -221.460314)
		(width 0.10668)
		(layer "F.Cu")
		(net "I3C_1_SPD_DDRGL_CPU0_R_SDA")
	)
	(via
		(at 383.606294 -206.911194)
		(size 0.508)
		(drill 0.254)
		(layers "F.Cu" "B.Cu")
		(net "I3C_1_SPD_DDRGL_CPU0_R_SDA")
	)
	(via
		(at 382.016 -206.41056)
		(size 0.4064)
		(drill 0.2032)
		(layers "F.Cu" "B.Cu")
		(net "I3C_1_SPD_DDRGL_CPU0_R_SDA")
	)
	(segment
		(start 382.016 -205.502002)
		(end 382.016 -206.41056)
		(width 0.10668)
		(layer "B.Cu")
		(net "I3C_1_SPD_DDRGL_CPU0_R_SDA")
	)
	(segment
		(start 382.143 -206.911194)
		(end 383.606294 -206.911194)
		(width 0.10668)
		(layer "B.Cu")
		(net "I3C_1_SPD_DDRGL_CPU0_R_SDA")
	)
	(segment
		(start 383.076958 -205.502002)
		(end 382.016 -205.502002)
		(width 0.10668)
		(layer "B.Cu")
		(net "I3C_1_SPD_DDRGL_CPU0_R_SDA")
	)
	(segment
		(start 382.016 -206.41056)
		(end 382.016 -206.784194)
		(width 0.10668)
		(layer "B.Cu")
		(net "I3C_1_SPD_DDRGL_CPU0_R_SDA")
	)
	(segment
		(start 382.016 -206.784194)
		(end 382.143 -206.911194)
		(width 0.10668)
		(layer "B.Cu")
		(net "I3C_1_SPD_DDRGL_CPU0_R_SDA")
	)
	(segment
		(start 389.306308 -221.26067)
		(end 383.041144 -214.995506)
		(width 0.10668)
		(layer "F.Cu")
		(net "I3C_1_SPD_DDRGL_CPU0_R_SCL")
	)
	(segment
		(start 383.041144 -214.995506)
		(end 383.041144 -207.13573)
		(width 0.10668)
		(layer "F.Cu")
		(net "I3C_1_SPD_DDRGL_CPU0_R_SCL")
	)
	(segment
		(start 381.407416 -205.502002)
		(end 381.127 -205.502002)
		(width 0.10668)
		(layer "F.Cu")
		(net "I3C_1_SPD_DDRGL_CPU0_R_SCL")
	)
	(segment
		(start 389.306308 -223.020382)
		(end 389.306308 -221.26067)
		(width 0.10668)
		(layer "F.Cu")
		(net "I3C_1_SPD_DDRGL_CPU0_R_SCL")
	)
	(segment
		(start 388.387844 -223.69018)
		(end 388.63651 -223.69018)
		(width 0.10668)
		(layer "F.Cu")
		(net "I3C_1_SPD_DDRGL_CPU0_R_SCL")
	)
	(segment
		(start 383.041144 -207.13573)
		(end 381.407416 -205.502002)
		(width 0.10668)
		(layer "F.Cu")
		(net "I3C_1_SPD_DDRGL_CPU0_R_SCL")
	)
	(segment
		(start 388.63651 -223.69018)
		(end 389.306308 -223.020382)
		(width 0.10668)
		(layer "F.Cu")
		(net "I3C_1_SPD_DDRGL_CPU0_R_SCL")
	)
	(via
		(at 381.127 -205.502002)
		(size 0.508)
		(drill 0.254)
		(layers "F.Cu" "B.Cu")
		(net "I3C_1_SPD_DDRGL_CPU0_R_SCL")
	)
	(segment
		(start 380.282958 -205.502002)
		(end 381.127 -205.502002)
		(width 0.10668)
		(layer "B.Cu")
		(net "I3C_1_SPD_DDRGL_CPU0_R_SCL")
	)
	(segment
		(start 380.282958 -205.502002)
		(end 379.266958 -205.502002)
		(width 0.10668)
		(layer "B.Cu")
		(net "I3C_1_SPD_DDRGL_CPU0_R_SCL")
	)
	(segment
		(start 39.42715 -171.73067)
		(end 40.141398 -171.73067)
		(width 0.10668)
		(layer "F.Cu")
		(net "I3C_0_SPD_DDRAF_CPU1_SDA")
	)
	(segment
		(start 40.141398 -171.73067)
		(end 40.458898 -171.41317)
		(width 0.10668)
		(layer "F.Cu")
		(net "I3C_0_SPD_DDRAF_CPU1_SDA")
	)
	(segment
		(start 40.458898 -171.41317)
		(end 40.516302 -171.41317)
		(width 0.10668)
		(layer "F.Cu")
		(net "I3C_0_SPD_DDRAF_CPU1_SDA")
	)
	(segment
		(start 42.27195 -171.831)
		(end 41.85412 -171.41317)
		(width 0.10668)
		(layer "F.Cu")
		(net "I3C_0_SPD_DDRAF_CPU1_SDA")
	)
	(segment
		(start 41.85412 -171.41317)
		(end 40.516302 -171.41317)
		(width 0.10668)
		(layer "F.Cu")
		(net "I3C_0_SPD_DDRAF_CPU1_SDA")
	)
	(via
		(at 40.516302 -171.41317)
		(size 0.508)
		(drill 0.254)
		(layers "F.Cu" "B.Cu")
		(net "I3C_0_SPD_DDRAF_CPU1_SDA")
	)
	(segment
		(start 42.27195 -170.307)
		(end 41.58869 -170.307)
		(width 0.10668)
		(layer "F.Cu")
		(net "I3C_0_SPD_DDRAF_CPU1_SCL")
	)
	(segment
		(start 39.42715 -171.230544)
		(end 39.57955 -171.230544)
		(width 0.10668)
		(layer "F.Cu")
		(net "I3C_0_SPD_DDRAF_CPU1_SCL")
	)
	(segment
		(start 39.57955 -171.230544)
		(end 40.410892 -170.399202)
		(width 0.10668)
		(layer "F.Cu")
		(net "I3C_0_SPD_DDRAF_CPU1_SCL")
	)
	(segment
		(start 41.58869 -170.307)
		(end 41.496488 -170.399202)
		(width 0.10668)
		(layer "F.Cu")
		(net "I3C_0_SPD_DDRAF_CPU1_SCL")
	)
	(segment
		(start 40.410892 -170.399202)
		(end 41.496488 -170.399202)
		(width 0.10668)
		(layer "F.Cu")
		(net "I3C_0_SPD_DDRAF_CPU1_SCL")
	)
	(via
		(at 41.496488 -170.399202)
		(size 0.508)
		(drill 0.254)
		(layers "F.Cu" "B.Cu")
		(net "I3C_0_SPD_DDRAF_CPU1_SCL")
	)
	(segment
		(start 43.07205 -171.494196)
		(end 43.248072 -171.318174)
		(width 0.10668)
		(layer "F.Cu")
		(net "I3C_0_SPD_DDRAF_CPU1_R_SDA")
	)
	(segment
		(start 47.380398 -174.211488)
		(end 47.380398 -172.472858)
		(width 0.10668)
		(layer "F.Cu")
		(net "I3C_0_SPD_DDRAF_CPU1_R_SDA")
	)
	(segment
		(start 64.16294 -192.943988)
		(end 61.436758 -190.217806)
		(width 0.10668)
		(layer "F.Cu")
		(net "I3C_0_SPD_DDRAF_CPU1_R_SDA")
	)
	(segment
		(start 47.03318 -172.12564)
		(end 46.9138 -172.12564)
		(width 0.10668)
		(layer "F.Cu")
		(net "I3C_0_SPD_DDRAF_CPU1_R_SDA")
	)
	(segment
		(start 67.966844 -202.008994)
		(end 63.476378 -197.518528)
		(width 0.10668)
		(layer "F.Cu")
		(net "I3C_0_SPD_DDRAF_CPU1_R_SDA")
	)
	(segment
		(start 54.519322 -181.350412)
		(end 47.380398 -174.211488)
		(width 0.10668)
		(layer "F.Cu")
		(net "I3C_0_SPD_DDRAF_CPU1_R_SDA")
	)
	(segment
		(start 83.272376 -207.514698)
		(end 74.675492 -207.514698)
		(width 0.10668)
		(layer "F.Cu")
		(net "I3C_0_SPD_DDRAF_CPU1_R_SDA")
	)
	(segment
		(start 86.547706 -210.62823)
		(end 83.548728 -207.629252)
		(width 0.10668)
		(layer "F.Cu")
		(net "I3C_0_SPD_DDRAF_CPU1_R_SDA")
	)
	(segment
		(start 80.757776 -221.077536)
		(end 86.547706 -215.287606)
		(width 0.10668)
		(layer "F.Cu")
		(net "I3C_0_SPD_DDRAF_CPU1_R_SDA")
	)
	(segment
		(start 57.895998 -190.217806)
		(end 54.519322 -186.84113)
		(width 0.10668)
		(layer "F.Cu")
		(net "I3C_0_SPD_DDRAF_CPU1_R_SDA")
	)
	(segment
		(start 45.167042 -172.593)
		(end 44.81195 -172.237908)
		(width 0.10668)
		(layer "F.Cu")
		(net "I3C_0_SPD_DDRAF_CPU1_R_SDA")
	)
	(segment
		(start 71.34352 -204.892148)
		(end 69.598032 -203.14666)
		(width 0.10668)
		(layer "F.Cu")
		(net "I3C_0_SPD_DDRAF_CPU1_R_SDA")
	)
	(segment
		(start 72.5551 -205.394306)
		(end 71.34352 -204.892148)
		(width 0.10668)
		(layer "F.Cu")
		(net "I3C_0_SPD_DDRAF_CPU1_R_SDA")
	)
	(segment
		(start 74.675492 -207.514698)
		(end 72.5551 -205.394306)
		(width 0.10668)
		(layer "F.Cu")
		(net "I3C_0_SPD_DDRAF_CPU1_R_SDA")
	)
	(segment
		(start 46.535086 -172.12564)
		(end 46.067726 -172.593)
		(width 0.10668)
		(layer "F.Cu")
		(net "I3C_0_SPD_DDRAF_CPU1_R_SDA")
	)
	(segment
		(start 43.248072 -171.318174)
		(end 44.299124 -171.318174)
		(width 0.10668)
		(layer "F.Cu")
		(net "I3C_0_SPD_DDRAF_CPU1_R_SDA")
	)
	(segment
		(start 69.007228 -202.008994)
		(end 67.966844 -202.008994)
		(width 0.10668)
		(layer "F.Cu")
		(net "I3C_0_SPD_DDRAF_CPU1_R_SDA")
	)
	(segment
		(start 47.380398 -172.472858)
		(end 47.03318 -172.12564)
		(width 0.10668)
		(layer "F.Cu")
		(net "I3C_0_SPD_DDRAF_CPU1_R_SDA")
	)
	(segment
		(start 46.067726 -172.593)
		(end 45.167042 -172.593)
		(width 0.10668)
		(layer "F.Cu")
		(net "I3C_0_SPD_DDRAF_CPU1_R_SDA")
	)
	(segment
		(start 69.598032 -203.14666)
		(end 69.598032 -202.599798)
		(width 0.10668)
		(layer "F.Cu")
		(net "I3C_0_SPD_DDRAF_CPU1_R_SDA")
	)
	(segment
		(start 69.598032 -202.599798)
		(end 69.007228 -202.008994)
		(width 0.10668)
		(layer "F.Cu")
		(net "I3C_0_SPD_DDRAF_CPU1_R_SDA")
	)
	(segment
		(start 63.476378 -197.518528)
		(end 63.476378 -195.738242)
		(width 0.10668)
		(layer "F.Cu")
		(net "I3C_0_SPD_DDRAF_CPU1_R_SDA")
	)
	(segment
		(start 64.16294 -195.05168)
		(end 64.16294 -192.943988)
		(width 0.10668)
		(layer "F.Cu")
		(net "I3C_0_SPD_DDRAF_CPU1_R_SDA")
	)
	(segment
		(start 80.757776 -222.880428)
		(end 80.757776 -221.077536)
		(width 0.10668)
		(layer "F.Cu")
		(net "I3C_0_SPD_DDRAF_CPU1_R_SDA")
	)
	(segment
		(start 83.548728 -207.629252)
		(end 83.272376 -207.514698)
		(width 0.10668)
		(layer "F.Cu")
		(net "I3C_0_SPD_DDRAF_CPU1_R_SDA")
	)
	(segment
		(start 54.519322 -186.84113)
		(end 54.519322 -181.350412)
		(width 0.10668)
		(layer "F.Cu")
		(net "I3C_0_SPD_DDRAF_CPU1_R_SDA")
	)
	(segment
		(start 43.07205 -171.831)
		(end 43.07205 -171.494196)
		(width 0.10668)
		(layer "F.Cu")
		(net "I3C_0_SPD_DDRAF_CPU1_R_SDA")
	)
	(segment
		(start 61.436758 -190.217806)
		(end 57.895998 -190.217806)
		(width 0.10668)
		(layer "F.Cu")
		(net "I3C_0_SPD_DDRAF_CPU1_R_SDA")
	)
	(segment
		(start 46.9138 -172.12564)
		(end 46.535086 -172.12564)
		(width 0.10668)
		(layer "F.Cu")
		(net "I3C_0_SPD_DDRAF_CPU1_R_SDA")
	)
	(segment
		(start 63.476378 -195.738242)
		(end 64.16294 -195.05168)
		(width 0.10668)
		(layer "F.Cu")
		(net "I3C_0_SPD_DDRAF_CPU1_R_SDA")
	)
	(segment
		(start 44.299124 -171.318174)
		(end 44.81195 -171.831)
		(width 0.10668)
		(layer "F.Cu")
		(net "I3C_0_SPD_DDRAF_CPU1_R_SDA")
	)
	(segment
		(start 86.547706 -215.287606)
		(end 86.547706 -210.62823)
		(width 0.10668)
		(layer "F.Cu")
		(net "I3C_0_SPD_DDRAF_CPU1_R_SDA")
	)
	(segment
		(start 44.81195 -172.237908)
		(end 44.81195 -171.831)
		(width 0.10668)
		(layer "F.Cu")
		(net "I3C_0_SPD_DDRAF_CPU1_R_SDA")
	)
	(via
		(at 46.9138 -172.12564)
		(size 0.762)
		(drill 0.381)
		(layers "F.Cu" "B.Cu")
		(net "I3C_0_SPD_DDRAF_CPU1_R_SDA")
	)
	(segment
		(start 44.81195 -170.815)
		(end 44.81195 -170.48861)
		(width 0.10668)
		(layer "F.Cu")
		(net "I3C_0_SPD_DDRAF_CPU1_R_SCL")
	)
	(segment
		(start 72.860408 -204.937868)
		(end 74.898758 -206.976218)
		(width 0.10668)
		(layer "F.Cu")
		(net "I3C_0_SPD_DDRAF_CPU1_R_SCL")
	)
	(segment
		(start 44.543726 -170.815)
		(end 44.81195 -170.815)
		(width 0.10668)
		(layer "F.Cu")
		(net "I3C_0_SPD_DDRAF_CPU1_R_SCL")
	)
	(segment
		(start 83.772756 -207.091534)
		(end 87.086186 -210.404964)
		(width 0.10668)
		(layer "F.Cu")
		(net "I3C_0_SPD_DDRAF_CPU1_R_SCL")
	)
	(segment
		(start 70.142354 -202.382374)
		(end 70.142354 -202.929236)
		(width 0.10668)
		(layer "F.Cu")
		(net "I3C_0_SPD_DDRAF_CPU1_R_SCL")
	)
	(segment
		(start 87.086186 -210.404964)
		(end 87.086186 -215.510872)
		(width 0.10668)
		(layer "F.Cu")
		(net "I3C_0_SPD_DDRAF_CPU1_R_SCL")
	)
	(segment
		(start 87.086186 -215.510872)
		(end 81.22793 -221.369128)
		(width 0.10668)
		(layer "F.Cu")
		(net "I3C_0_SPD_DDRAF_CPU1_R_SCL")
	)
	(segment
		(start 58.11266 -189.672722)
		(end 61.65342 -189.672722)
		(width 0.10668)
		(layer "F.Cu")
		(net "I3C_0_SPD_DDRAF_CPU1_R_SCL")
	)
	(segment
		(start 45.2247 -170.07586)
		(end 46.851824 -170.07586)
		(width 0.10668)
		(layer "F.Cu")
		(net "I3C_0_SPD_DDRAF_CPU1_R_SCL")
	)
	(segment
		(start 71.648828 -204.43571)
		(end 72.860408 -204.937868)
		(width 0.10668)
		(layer "F.Cu")
		(net "I3C_0_SPD_DDRAF_CPU1_R_SCL")
	)
	(segment
		(start 83.494372 -206.976218)
		(end 83.772756 -207.091534)
		(width 0.10668)
		(layer "F.Cu")
		(net "I3C_0_SPD_DDRAF_CPU1_R_SCL")
	)
	(segment
		(start 55.057802 -180.353208)
		(end 55.057802 -186.617864)
		(width 0.10668)
		(layer "F.Cu")
		(net "I3C_0_SPD_DDRAF_CPU1_R_SCL")
	)
	(segment
		(start 61.65342 -189.672722)
		(end 64.73444 -192.753742)
		(width 0.10668)
		(layer "F.Cu")
		(net "I3C_0_SPD_DDRAF_CPU1_R_SCL")
	)
	(segment
		(start 55.057802 -186.617864)
		(end 58.11266 -189.672722)
		(width 0.10668)
		(layer "F.Cu")
		(net "I3C_0_SPD_DDRAF_CPU1_R_SCL")
	)
	(segment
		(start 64.026034 -197.306438)
		(end 68.169028 -201.449432)
		(width 0.10668)
		(layer "F.Cu")
		(net "I3C_0_SPD_DDRAF_CPU1_R_SCL")
	)
	(segment
		(start 44.482512 -170.753786)
		(end 44.543726 -170.815)
		(width 0.10668)
		(layer "F.Cu")
		(net "I3C_0_SPD_DDRAF_CPU1_R_SCL")
	)
	(segment
		(start 68.169028 -201.449432)
		(end 69.209412 -201.449432)
		(width 0.10668)
		(layer "F.Cu")
		(net "I3C_0_SPD_DDRAF_CPU1_R_SCL")
	)
	(segment
		(start 47.350934 -170.57497)
		(end 48.637444 -171.86148)
		(width 0.10668)
		(layer "F.Cu")
		(net "I3C_0_SPD_DDRAF_CPU1_R_SCL")
	)
	(segment
		(start 74.898758 -206.976218)
		(end 83.494372 -206.976218)
		(width 0.10668)
		(layer "F.Cu")
		(net "I3C_0_SPD_DDRAF_CPU1_R_SCL")
	)
	(segment
		(start 64.026034 -195.983606)
		(end 64.026034 -197.306438)
		(width 0.10668)
		(layer "F.Cu")
		(net "I3C_0_SPD_DDRAF_CPU1_R_SCL")
	)
	(segment
		(start 43.222164 -170.753786)
		(end 44.482512 -170.753786)
		(width 0.10668)
		(layer "F.Cu")
		(net "I3C_0_SPD_DDRAF_CPU1_R_SCL")
	)
	(segment
		(start 43.07205 -170.603672)
		(end 43.222164 -170.753786)
		(width 0.10668)
		(layer "F.Cu")
		(net "I3C_0_SPD_DDRAF_CPU1_R_SCL")
	)
	(segment
		(start 64.73444 -195.2752)
		(end 64.026034 -195.983606)
		(width 0.10668)
		(layer "F.Cu")
		(net "I3C_0_SPD_DDRAF_CPU1_R_SCL")
	)
	(segment
		(start 48.637444 -171.86148)
		(end 48.637444 -173.93285)
		(width 0.10668)
		(layer "F.Cu")
		(net "I3C_0_SPD_DDRAF_CPU1_R_SCL")
	)
	(segment
		(start 44.81195 -170.48861)
		(end 45.2247 -170.07586)
		(width 0.10668)
		(layer "F.Cu")
		(net "I3C_0_SPD_DDRAF_CPU1_R_SCL")
	)
	(segment
		(start 48.637444 -173.93285)
		(end 55.057802 -180.353208)
		(width 0.10668)
		(layer "F.Cu")
		(net "I3C_0_SPD_DDRAF_CPU1_R_SCL")
	)
	(segment
		(start 70.142354 -202.929236)
		(end 71.648828 -204.43571)
		(width 0.10668)
		(layer "F.Cu")
		(net "I3C_0_SPD_DDRAF_CPU1_R_SCL")
	)
	(segment
		(start 64.73444 -192.753742)
		(end 64.73444 -195.2752)
		(width 0.10668)
		(layer "F.Cu")
		(net "I3C_0_SPD_DDRAF_CPU1_R_SCL")
	)
	(segment
		(start 81.22793 -221.369128)
		(end 81.22793 -222.070422)
		(width 0.10668)
		(layer "F.Cu")
		(net "I3C_0_SPD_DDRAF_CPU1_R_SCL")
	)
	(segment
		(start 69.209412 -201.449432)
		(end 70.142354 -202.382374)
		(width 0.10668)
		(layer "F.Cu")
		(net "I3C_0_SPD_DDRAF_CPU1_R_SCL")
	)
	(segment
		(start 43.07205 -170.307)
		(end 43.07205 -170.603672)
		(width 0.10668)
		(layer "F.Cu")
		(net "I3C_0_SPD_DDRAF_CPU1_R_SCL")
	)
	(segment
		(start 46.851824 -170.07586)
		(end 47.350934 -170.57497)
		(width 0.10668)
		(layer "F.Cu")
		(net "I3C_0_SPD_DDRAF_CPU1_R_SCL")
	)
	(via
		(at 47.350934 -170.57497)
		(size 0.762)
		(drill 0.381)
		(layers "F.Cu" "B.Cu")
		(net "I3C_0_SPD_DDRAF_CPU1_R_SCL")
	)
	(segment
		(start 311.226708 -171.774612)
		(end 311.226708 -154.384756)
		(width 0.10668)
		(layer "F.Cu")
		(net "I3C_0_SPD_DDRAF_CPU0_SDA")
	)
	(segment
		(start 318.625728 -179.173632)
		(end 311.226708 -171.774612)
		(width 0.10668)
		(layer "F.Cu")
		(net "I3C_0_SPD_DDRAF_CPU0_SDA")
	)
	(segment
		(start 308.569106 -151.727154)
		(end 305.91125 -151.727154)
		(width 0.10668)
		(layer "F.Cu")
		(net "I3C_0_SPD_DDRAF_CPU0_SDA")
	)
	(segment
		(start 318.927988 -193.29781)
		(end 318.625728 -192.99555)
		(width 0.10668)
		(layer "F.Cu")
		(net "I3C_0_SPD_DDRAF_CPU0_SDA")
	)
	(segment
		(start 318.625728 -192.99555)
		(end 318.625728 -179.173632)
		(width 0.10668)
		(layer "F.Cu")
		(net "I3C_0_SPD_DDRAF_CPU0_SDA")
	)
	(segment
		(start 305.91125 -151.727154)
		(end 304.645568 -150.461472)
		(width 0.10668)
		(layer "F.Cu")
		(net "I3C_0_SPD_DDRAF_CPU0_SDA")
	)
	(segment
		(start 302.678338 -147.659852)
		(end 303.487074 -146.851116)
		(width 0.10668)
		(layer "F.Cu")
		(net "I3C_0_SPD_DDRAF_CPU0_SDA")
	)
	(segment
		(start 319.22339 -193.29781)
		(end 318.927988 -193.29781)
		(width 0.10668)
		(layer "F.Cu")
		(net "I3C_0_SPD_DDRAF_CPU0_SDA")
	)
	(segment
		(start 303.487074 -146.851116)
		(end 304.63998 -146.851116)
		(width 0.10668)
		(layer "F.Cu")
		(net "I3C_0_SPD_DDRAF_CPU0_SDA")
	)
	(segment
		(start 311.226708 -154.384756)
		(end 308.569106 -151.727154)
		(width 0.10668)
		(layer "F.Cu")
		(net "I3C_0_SPD_DDRAF_CPU0_SDA")
	)
	(segment
		(start 304.645568 -150.461472)
		(end 304.645568 -149.987)
		(width 0.10668)
		(layer "F.Cu")
		(net "I3C_0_SPD_DDRAF_CPU0_SDA")
	)
	(segment
		(start 302.440848 -147.659852)
		(end 302.678338 -147.659852)
		(width 0.10668)
		(layer "F.Cu")
		(net "I3C_0_SPD_DDRAF_CPU0_SDA")
	)
	(via
		(at 304.63998 -146.851116)
		(size 0.508)
		(drill 0.254)
		(layers "F.Cu" "B.Cu")
		(net "I3C_0_SPD_DDRAF_CPU0_SDA")
	)
	(via
		(at 304.645568 -149.987)
		(size 0.508)
		(drill 0.254)
		(layers "F.Cu" "B.Cu")
		(net "I3C_0_SPD_DDRAF_CPU0_SDA")
	)
	(segment
		(start 304.63998 -146.851116)
		(end 304.63998 -149.981412)
		(width 0.11684)
		(layer "In4.Cu")
		(net "I3C_0_SPD_DDRAF_CPU0_SDA")
	)
	(segment
		(start 304.63998 -149.981412)
		(end 304.645568 -149.987)
		(width 0.11684)
		(layer "In4.Cu")
		(net "I3C_0_SPD_DDRAF_CPU0_SDA")
	)
	(segment
		(start 302.749204 -146.999198)
		(end 302.749204 -145.960592)
		(width 0.10668)
		(layer "F.Cu")
		(net "I3C_0_SPD_DDRAF_CPU0_SCL")
	)
	(segment
		(start 302.749204 -145.960592)
		(end 302.536098 -145.747486)
		(width 0.10668)
		(layer "F.Cu")
		(net "I3C_0_SPD_DDRAF_CPU0_SCL")
	)
	(segment
		(start 302.588676 -147.159726)
		(end 302.749204 -146.999198)
		(width 0.10668)
		(layer "F.Cu")
		(net "I3C_0_SPD_DDRAF_CPU0_SCL")
	)
	(segment
		(start 312.928 -153.556716)
		(end 308.211728 -148.840444)
		(width 0.10668)
		(layer "F.Cu")
		(net "I3C_0_SPD_DDRAF_CPU0_SCL")
	)
	(segment
		(start 320.981324 -193.29781)
		(end 321.316604 -193.29781)
		(width 0.10668)
		(layer "F.Cu")
		(net "I3C_0_SPD_DDRAF_CPU0_SCL")
	)
	(segment
		(start 308.211728 -148.840444)
		(end 307.018182 -148.840444)
		(width 0.10668)
		(layer "F.Cu")
		(net "I3C_0_SPD_DDRAF_CPU0_SCL")
	)
	(segment
		(start 321.316604 -193.29781)
		(end 321.641978 -192.972436)
		(width 0.10668)
		(layer "F.Cu")
		(net "I3C_0_SPD_DDRAF_CPU0_SCL")
	)
	(segment
		(start 321.641978 -192.972436)
		(end 321.641978 -179.782978)
		(width 0.10668)
		(layer "F.Cu")
		(net "I3C_0_SPD_DDRAF_CPU0_SCL")
	)
	(segment
		(start 312.928 -171.069)
		(end 312.928 -153.556716)
		(width 0.10668)
		(layer "F.Cu")
		(net "I3C_0_SPD_DDRAF_CPU0_SCL")
	)
	(segment
		(start 321.641978 -179.782978)
		(end 312.928 -171.069)
		(width 0.10668)
		(layer "F.Cu")
		(net "I3C_0_SPD_DDRAF_CPU0_SCL")
	)
	(segment
		(start 302.440848 -147.159726)
		(end 302.588676 -147.159726)
		(width 0.10668)
		(layer "F.Cu")
		(net "I3C_0_SPD_DDRAF_CPU0_SCL")
	)
	(via
		(at 307.018182 -148.840444)
		(size 0.508)
		(drill 0.254)
		(layers "F.Cu" "B.Cu")
		(net "I3C_0_SPD_DDRAF_CPU0_SCL")
	)
	(via
		(at 302.536098 -145.747486)
		(size 0.508)
		(drill 0.254)
		(layers "F.Cu" "B.Cu")
		(net "I3C_0_SPD_DDRAF_CPU0_SCL")
	)
	(segment
		(start 307.018182 -147.418806)
		(end 307.018182 -148.840444)
		(width 0.10668)
		(layer "B.Cu")
		(net "I3C_0_SPD_DDRAF_CPU0_SCL")
	)
	(segment
		(start 305.346862 -145.747486)
		(end 307.018182 -147.418806)
		(width 0.10668)
		(layer "B.Cu")
		(net "I3C_0_SPD_DDRAF_CPU0_SCL")
	)
	(segment
		(start 302.536098 -145.747486)
		(end 305.346862 -145.747486)
		(width 0.10668)
		(layer "B.Cu")
		(net "I3C_0_SPD_DDRAF_CPU0_SCL")
	)
	(segment
		(start 319.80505 -195.326)
		(end 319.80505 -194.31)
		(width 0.10668)
		(layer "F.Cu")
		(net "I3C_0_SPD_DDRAF_CPU0_R_SDA")
	)
	(segment
		(start 319.22339 -192.49771)
		(end 319.80505 -193.07937)
		(width 0.10668)
		(layer "F.Cu")
		(net "I3C_0_SPD_DDRAF_CPU0_R_SDA")
	)
	(segment
		(start 329.202034 -221.275148)
		(end 329.438 -221.275148)
		(width 0.10668)
		(layer "F.Cu")
		(net "I3C_0_SPD_DDRAF_CPU0_R_SDA")
	)
	(segment
		(start 335.23428 -215.478868)
		(end 335.23428 -210.75523)
		(width 0.10668)
		(layer "F.Cu")
		(net "I3C_0_SPD_DDRAF_CPU0_R_SDA")
	)
	(segment
		(start 319.80505 -193.07937)
		(end 319.80505 -194.31)
		(width 0.10668)
		(layer "F.Cu")
		(net "I3C_0_SPD_DDRAF_CPU0_R_SDA")
	)
	(segment
		(start 328.697844 -222.880174)
		(end 328.697844 -221.779338)
		(width 0.10668)
		(layer "F.Cu")
		(net "I3C_0_SPD_DDRAF_CPU0_R_SDA")
	)
	(segment
		(start 328.697844 -221.779338)
		(end 329.202034 -221.275148)
		(width 0.10668)
		(layer "F.Cu")
		(net "I3C_0_SPD_DDRAF_CPU0_R_SDA")
	)
	(segment
		(start 329.438 -221.275148)
		(end 335.23428 -215.478868)
		(width 0.10668)
		(layer "F.Cu")
		(net "I3C_0_SPD_DDRAF_CPU0_R_SDA")
	)
	(segment
		(start 335.23428 -210.75523)
		(end 319.80505 -195.326)
		(width 0.10668)
		(layer "F.Cu")
		(net "I3C_0_SPD_DDRAF_CPU0_R_SDA")
	)
	(via
		(at 319.80505 -195.326)
		(size 0.762)
		(drill 0.381)
		(layers "F.Cu" "B.Cu")
		(net "I3C_0_SPD_DDRAF_CPU0_R_SDA")
	)
	(segment
		(start 321.28333 -195.934076)
		(end 321.28333 -195.352924)
		(width 0.10668)
		(layer "F.Cu")
		(net "I3C_0_SPD_DDRAF_CPU0_R_SCL")
	)
	(segment
		(start 320.78295 -194.852544)
		(end 320.78295 -194.31)
		(width 0.10668)
		(layer "F.Cu")
		(net "I3C_0_SPD_DDRAF_CPU0_R_SCL")
	)
	(segment
		(start 329.404726 -222.070168)
		(end 335.77276 -215.702134)
		(width 0.10668)
		(layer "F.Cu")
		(net "I3C_0_SPD_DDRAF_CPU0_R_SCL")
	)
	(segment
		(start 320.360802 -193.887852)
		(end 320.78295 -194.31)
		(width 0.10668)
		(layer "F.Cu")
		(net "I3C_0_SPD_DDRAF_CPU0_R_SCL")
	)
	(segment
		(start 320.981324 -192.49771)
		(end 320.360802 -193.118232)
		(width 0.10668)
		(layer "F.Cu")
		(net "I3C_0_SPD_DDRAF_CPU0_R_SCL")
	)
	(segment
		(start 329.167998 -222.070168)
		(end 329.404726 -222.070168)
		(width 0.10668)
		(layer "F.Cu")
		(net "I3C_0_SPD_DDRAF_CPU0_R_SCL")
	)
	(segment
		(start 335.77276 -215.702134)
		(end 335.77276 -210.423506)
		(width 0.10668)
		(layer "F.Cu")
		(net "I3C_0_SPD_DDRAF_CPU0_R_SCL")
	)
	(segment
		(start 335.77276 -210.423506)
		(end 321.28333 -195.934076)
		(width 0.10668)
		(layer "F.Cu")
		(net "I3C_0_SPD_DDRAF_CPU0_R_SCL")
	)
	(segment
		(start 320.360802 -193.118232)
		(end 320.360802 -193.887852)
		(width 0.10668)
		(layer "F.Cu")
		(net "I3C_0_SPD_DDRAF_CPU0_R_SCL")
	)
	(segment
		(start 321.28333 -195.352924)
		(end 320.78295 -194.852544)
		(width 0.10668)
		(layer "F.Cu")
		(net "I3C_0_SPD_DDRAF_CPU0_R_SCL")
	)
	(via
		(at 321.28333 -195.352924)
		(size 0.762)
		(drill 0.381)
		(layers "F.Cu" "B.Cu")
		(net "I3C_0_SPD_DDRAF_CPU0_R_SCL")
	)
	(segment
		(start 183.861964 -15.848838)
		(end 184.328054 -15.382748)
		(width 0.10668)
		(layer "F.Cu")
		(net "FPGA_IO3V3_RSVD_1")
	)
	(segment
		(start 184.328054 -15.382748)
		(end 184.604406 -15.382748)
		(width 0.10668)
		(layer "F.Cu")
		(net "FPGA_IO3V3_RSVD_1")
	)
	(segment
		(start 179.52212 -118.652798)
		(end 179.13223 -119.042688)
		(width 0.10668)
		(layer "F.Cu")
		(net "FPGA_IO3V3_RSVD_1")
	)
	(segment
		(start 183.861964 -16.549878)
		(end 183.861964 -15.848838)
		(width 0.10668)
		(layer "F.Cu")
		(net "FPGA_IO3V3_RSVD_1")
	)
	(via
		(at 184.604406 -15.382748)
		(size 0.508)
		(drill 0.254)
		(layers "F.Cu" "B.Cu")
		(net "FPGA_IO3V3_RSVD_1")
	)
	(via
		(at 175.342042 -122.388376)
		(size 0.6604)
		(drill 0.3302)
		(layers "F.Cu" "B.Cu")
		(net "FPGA_IO3V3_RSVD_1")
	)
	(via
		(at 179.13223 -119.042688)
		(size 0.4572)
		(drill 0.254)
		(layers "F.Cu" "B.Cu")
		(net "FPGA_IO3V3_RSVD_1")
	)
	(segment
		(start 178.72837 -120.073674)
		(end 178.72837 -119.67718)
		(width 0.10668)
		(layer "B.Cu")
		(net "FPGA_IO3V3_RSVD_1")
	)
	(segment
		(start 178.72837 -119.67718)
		(end 179.13223 -119.27332)
		(width 0.10668)
		(layer "B.Cu")
		(net "FPGA_IO3V3_RSVD_1")
	)
	(segment
		(start 179.13223 -119.27332)
		(end 179.13223 -119.042688)
		(width 0.10668)
		(layer "B.Cu")
		(net "FPGA_IO3V3_RSVD_1")
	)
	(segment
		(start 175.342042 -122.388376)
		(end 176.025048 -122.388376)
		(width 0.10668)
		(layer "B.Cu")
		(net "FPGA_IO3V3_RSVD_1")
	)
	(segment
		(start 178.171348 -120.242076)
		(end 178.559968 -120.242076)
		(width 0.10668)
		(layer "B.Cu")
		(net "FPGA_IO3V3_RSVD_1")
	)
	(segment
		(start 176.025048 -122.388376)
		(end 178.171348 -120.242076)
		(width 0.10668)
		(layer "B.Cu")
		(net "FPGA_IO3V3_RSVD_1")
	)
	(segment
		(start 178.559968 -120.242076)
		(end 178.72837 -120.073674)
		(width 0.10668)
		(layer "B.Cu")
		(net "FPGA_IO3V3_RSVD_1")
	)
	(segment
		(start 179.973986 -15.382748)
		(end 184.604406 -15.382748)
		(width 0.11684)
		(layer "In11.Cu")
		(net "FPGA_IO3V3_RSVD_1")
	)
	(segment
		(start 164.84219 -14.678406)
		(end 165.298374 -14.222222)
		(width 0.11684)
		(layer "In11.Cu")
		(net "FPGA_IO3V3_RSVD_1")
	)
	(segment
		(start 175.4886 -117.211348)
		(end 175.4886 -115.0366)
		(width 0.11684)
		(layer "In11.Cu")
		(net "FPGA_IO3V3_RSVD_1")
	)
	(segment
		(start 170.426126 -92.567252)
		(end 172.00372 -90.989658)
		(width 0.11684)
		(layer "In11.Cu")
		(net "FPGA_IO3V3_RSVD_1")
	)
	(segment
		(start 173.316646 -106.905806)
		(end 173.316646 -105.053638)
		(width 0.11684)
		(layer "In11.Cu")
		(net "FPGA_IO3V3_RSVD_1")
	)
	(segment
		(start 164.84219 -19.806666)
		(end 164.84219 -14.678406)
		(width 0.11684)
		(layer "In11.Cu")
		(net "FPGA_IO3V3_RSVD_1")
	)
	(segment
		(start 165.517576 -20.482052)
		(end 164.84219 -19.806666)
		(width 0.11684)
		(layer "In11.Cu")
		(net "FPGA_IO3V3_RSVD_1")
	)
	(segment
		(start 172.00372 -90.989658)
		(end 172.00372 -90.035888)
		(width 0.11684)
		(layer "In11.Cu")
		(net "FPGA_IO3V3_RSVD_1")
	)
	(segment
		(start 174.206662 -107.795822)
		(end 173.316646 -106.905806)
		(width 0.11684)
		(layer "In11.Cu")
		(net "FPGA_IO3V3_RSVD_1")
	)
	(segment
		(start 166.06012 -39.311072)
		(end 166.06012 -25.084024)
		(width 0.11684)
		(layer "In11.Cu")
		(net "FPGA_IO3V3_RSVD_1")
	)
	(segment
		(start 167.18661 -13.36294)
		(end 177.954178 -13.36294)
		(width 0.11684)
		(layer "In11.Cu")
		(net "FPGA_IO3V3_RSVD_1")
	)
	(segment
		(start 171.81703 -102.99573)
		(end 170.01236 -101.19106)
		(width 0.11684)
		(layer "In11.Cu")
		(net "FPGA_IO3V3_RSVD_1")
	)
	(segment
		(start 175.4886 -115.0366)
		(end 174.206662 -113.754662)
		(width 0.11684)
		(layer "In11.Cu")
		(net "FPGA_IO3V3_RSVD_1")
	)
	(segment
		(start 173.162214 -102.99573)
		(end 171.81703 -102.99573)
		(width 0.11684)
		(layer "In11.Cu")
		(net "FPGA_IO3V3_RSVD_1")
	)
	(segment
		(start 165.298374 -14.222222)
		(end 166.327328 -14.222222)
		(width 0.11684)
		(layer "In11.Cu")
		(net "FPGA_IO3V3_RSVD_1")
	)
	(segment
		(start 165.81628 -48.775112)
		(end 168.61536 -45.976032)
		(width 0.11684)
		(layer "In11.Cu")
		(net "FPGA_IO3V3_RSVD_1")
	)
	(segment
		(start 166.327328 -14.222222)
		(end 167.18661 -13.36294)
		(width 0.11684)
		(layer "In11.Cu")
		(net "FPGA_IO3V3_RSVD_1")
	)
	(segment
		(start 173.394624 -88.644984)
		(end 173.394624 -85.1916)
		(width 0.11684)
		(layer "In11.Cu")
		(net "FPGA_IO3V3_RSVD_1")
	)
	(segment
		(start 173.84268 -104.527604)
		(end 173.84268 -103.676196)
		(width 0.11684)
		(layer "In11.Cu")
		(net "FPGA_IO3V3_RSVD_1")
	)
	(segment
		(start 173.394624 -85.1916)
		(end 167.252396 -79.049372)
		(width 0.11684)
		(layer "In11.Cu")
		(net "FPGA_IO3V3_RSVD_1")
	)
	(segment
		(start 178.73599 -118.646448)
		(end 176.4284 -118.646448)
		(width 0.11684)
		(layer "In11.Cu")
		(net "FPGA_IO3V3_RSVD_1")
	)
	(segment
		(start 166.06012 -25.084024)
		(end 165.517576 -24.54148)
		(width 0.11684)
		(layer "In11.Cu")
		(net "FPGA_IO3V3_RSVD_1")
	)
	(segment
		(start 174.206662 -113.754662)
		(end 174.206662 -107.795822)
		(width 0.11684)
		(layer "In11.Cu")
		(net "FPGA_IO3V3_RSVD_1")
	)
	(segment
		(start 173.84268 -103.676196)
		(end 173.162214 -102.99573)
		(width 0.11684)
		(layer "In11.Cu")
		(net "FPGA_IO3V3_RSVD_1")
	)
	(segment
		(start 168.61536 -41.866312)
		(end 166.06012 -39.311072)
		(width 0.11684)
		(layer "In11.Cu")
		(net "FPGA_IO3V3_RSVD_1")
	)
	(segment
		(start 173.316646 -105.053638)
		(end 173.84268 -104.527604)
		(width 0.11684)
		(layer "In11.Cu")
		(net "FPGA_IO3V3_RSVD_1")
	)
	(segment
		(start 168.61536 -45.976032)
		(end 168.61536 -41.866312)
		(width 0.11684)
		(layer "In11.Cu")
		(net "FPGA_IO3V3_RSVD_1")
	)
	(segment
		(start 170.01236 -101.19106)
		(end 170.01236 -99.029774)
		(width 0.11684)
		(layer "In11.Cu")
		(net "FPGA_IO3V3_RSVD_1")
	)
	(segment
		(start 165.517576 -24.54148)
		(end 165.517576 -20.482052)
		(width 0.11684)
		(layer "In11.Cu")
		(net "FPGA_IO3V3_RSVD_1")
	)
	(segment
		(start 172.00372 -90.035888)
		(end 173.394624 -88.644984)
		(width 0.11684)
		(layer "In11.Cu")
		(net "FPGA_IO3V3_RSVD_1")
	)
	(segment
		(start 179.13223 -119.042688)
		(end 178.73599 -118.646448)
		(width 0.11684)
		(layer "In11.Cu")
		(net "FPGA_IO3V3_RSVD_1")
	)
	(segment
		(start 176.1617 -118.379748)
		(end 176.1617 -117.884448)
		(width 0.11684)
		(layer "In11.Cu")
		(net "FPGA_IO3V3_RSVD_1")
	)
	(segment
		(start 170.01236 -99.029774)
		(end 170.426126 -98.616008)
		(width 0.11684)
		(layer "In11.Cu")
		(net "FPGA_IO3V3_RSVD_1")
	)
	(segment
		(start 177.954178 -13.36294)
		(end 179.973986 -15.382748)
		(width 0.11684)
		(layer "In11.Cu")
		(net "FPGA_IO3V3_RSVD_1")
	)
	(segment
		(start 176.4284 -118.646448)
		(end 176.1617 -118.379748)
		(width 0.11684)
		(layer "In11.Cu")
		(net "FPGA_IO3V3_RSVD_1")
	)
	(segment
		(start 167.252396 -55.8546)
		(end 165.81628 -54.418484)
		(width 0.11684)
		(layer "In11.Cu")
		(net "FPGA_IO3V3_RSVD_1")
	)
	(segment
		(start 170.426126 -98.616008)
		(end 170.426126 -92.567252)
		(width 0.11684)
		(layer "In11.Cu")
		(net "FPGA_IO3V3_RSVD_1")
	)
	(segment
		(start 167.252396 -79.049372)
		(end 167.252396 -55.8546)
		(width 0.11684)
		(layer "In11.Cu")
		(net "FPGA_IO3V3_RSVD_1")
	)
	(segment
		(start 165.81628 -54.418484)
		(end 165.81628 -48.775112)
		(width 0.11684)
		(layer "In11.Cu")
		(net "FPGA_IO3V3_RSVD_1")
	)
	(segment
		(start 176.1617 -117.884448)
		(end 175.4886 -117.211348)
		(width 0.11684)
		(layer "In11.Cu")
		(net "FPGA_IO3V3_RSVD_1")
	)
	(segment
		(start 179.611782 -404.500842)
		(end 180.43144 -403.681184)
		(width 0.1524)
		(layer "F.Cu")
		(net "HSC_VTEMP")
	)
	(segment
		(start 179.08905 -405.511)
		(end 179.08905 -404.528782)
		(width 0.1524)
		(layer "F.Cu")
		(net "HSC_VTEMP")
	)
	(segment
		(start 181.088538 -403.681184)
		(end 181.725062 -403.04466)
		(width 0.1524)
		(layer "F.Cu")
		(net "HSC_VTEMP")
	)
	(segment
		(start 180.43144 -403.681184)
		(end 181.088538 -403.681184)
		(width 0.1524)
		(layer "F.Cu")
		(net "HSC_VTEMP")
	)
	(segment
		(start 179.08905 -404.528782)
		(end 179.11699 -404.500842)
		(width 0.1524)
		(layer "F.Cu")
		(net "HSC_VTEMP")
	)
	(segment
		(start 229.303072 -403.170136)
		(end 228.6381 -403.170136)
		(width 0.1524)
		(layer "F.Cu")
		(net "HSC_VTEMP")
	)
	(segment
		(start 218.635072 -403.170136)
		(end 217.9701 -403.170136)
		(width 0.1524)
		(layer "F.Cu")
		(net "HSC_VTEMP")
	)
	(segment
		(start 179.11699 -404.500842)
		(end 179.611782 -404.500842)
		(width 0.1524)
		(layer "F.Cu")
		(net "HSC_VTEMP")
	)
	(segment
		(start 197.299072 -403.170136)
		(end 196.70268 -403.170136)
		(width 0.1524)
		(layer "F.Cu")
		(net "HSC_VTEMP")
	)
	(segment
		(start 207.967072 -403.170136)
		(end 207.3021 -403.170136)
		(width 0.1524)
		(layer "F.Cu")
		(net "HSC_VTEMP")
	)
	(segment
		(start 181.725062 -403.04466)
		(end 182.041038 -403.04466)
		(width 0.1524)
		(layer "F.Cu")
		(net "HSC_VTEMP")
	)
	(via
		(at 228.6381 -403.170136)
		(size 0.508)
		(drill 0.254)
		(layers "F.Cu" "B.Cu")
		(net "HSC_VTEMP")
	)
	(via
		(at 180.43144 -403.681184)
		(size 0.508)
		(drill 0.254)
		(layers "F.Cu" "B.Cu")
		(net "HSC_VTEMP")
	)
	(via
		(at 217.9701 -403.170136)
		(size 0.508)
		(drill 0.254)
		(layers "F.Cu" "B.Cu")
		(net "HSC_VTEMP")
	)
	(via
		(at 207.3021 -403.170136)
		(size 0.508)
		(drill 0.254)
		(layers "F.Cu" "B.Cu")
		(net "HSC_VTEMP")
	)
	(via
		(at 196.70268 -403.170136)
		(size 0.508)
		(drill 0.254)
		(layers "F.Cu" "B.Cu")
		(net "HSC_VTEMP")
	)
	(segment
		(start 196.70268 -403.83968)
		(end 196.70268 -403.170136)
		(width 0.1524)
		(layer "In13.Cu")
		(net "HSC_VTEMP")
	)
	(segment
		(start 207.3021 -403.170136)
		(end 207.3021 -403.012148)
		(width 0.1524)
		(layer "In13.Cu")
		(net "HSC_VTEMP")
	)
	(segment
		(start 216.8525 -407.38806)
		(end 216.8525 -408.89428)
		(width 0.1524)
		(layer "In13.Cu")
		(net "HSC_VTEMP")
	)
	(segment
		(start 217.9701 -406.27046)
		(end 216.8525 -407.38806)
		(width 0.1524)
		(layer "In13.Cu")
		(net "HSC_VTEMP")
	)
	(segment
		(start 215.9635 -401.760182)
		(end 215.2015 -402.522182)
		(width 0.1524)
		(layer "In13.Cu")
		(net "HSC_VTEMP")
	)
	(segment
		(start 213.857332 -402.522182)
		(end 213.45144 -402.928074)
		(width 0.1524)
		(layer "In13.Cu")
		(net "HSC_VTEMP")
	)
	(segment
		(start 227.386134 -401.760182)
		(end 228.6381 -403.012148)
		(width 0.1524)
		(layer "In13.Cu")
		(net "HSC_VTEMP")
	)
	(segment
		(start 180.874416 -406.505156)
		(end 181.26964 -406.90038)
		(width 0.1524)
		(layer "In13.Cu")
		(net "HSC_VTEMP")
	)
	(segment
		(start 206.822802 -409.532582)
		(end 205.99654 -408.70632)
		(width 0.1524)
		(layer "In13.Cu")
		(net "HSC_VTEMP")
	)
	(segment
		(start 216.718134 -401.760182)
		(end 215.9635 -401.760182)
		(width 0.1524)
		(layer "In13.Cu")
		(net "HSC_VTEMP")
	)
	(segment
		(start 185.5216 -409.45816)
		(end 193.2432 -409.45816)
		(width 0.1524)
		(layer "In13.Cu")
		(net "HSC_VTEMP")
	)
	(segment
		(start 180.874416 -404.12416)
		(end 180.874416 -406.505156)
		(width 0.1524)
		(layer "In13.Cu")
		(net "HSC_VTEMP")
	)
	(segment
		(start 224.525332 -402.522182)
		(end 225.8695 -402.522182)
		(width 0.1524)
		(layer "In13.Cu")
		(net "HSC_VTEMP")
	)
	(segment
		(start 228.6381 -403.012148)
		(end 228.6381 -403.170136)
		(width 0.1524)
		(layer "In13.Cu")
		(net "HSC_VTEMP")
	)
	(segment
		(start 205.99654 -408.70632)
		(end 205.99654 -407.57602)
		(width 0.1524)
		(layer "In13.Cu")
		(net "HSC_VTEMP")
	)
	(segment
		(start 196.154802 -409.532582)
		(end 195.5165 -408.89428)
		(width 0.1524)
		(layer "In13.Cu")
		(net "HSC_VTEMP")
	)
	(segment
		(start 202.78344 -408.94508)
		(end 202.195938 -409.532582)
		(width 0.1524)
		(layer "In13.Cu")
		(net "HSC_VTEMP")
	)
	(segment
		(start 207.3021 -406.27046)
		(end 207.3021 -403.170136)
		(width 0.1524)
		(layer "In13.Cu")
		(net "HSC_VTEMP")
	)
	(segment
		(start 226.6315 -401.760182)
		(end 227.386134 -401.760182)
		(width 0.1524)
		(layer "In13.Cu")
		(net "HSC_VTEMP")
	)
	(segment
		(start 203.189332 -402.522182)
		(end 202.78344 -402.928074)
		(width 0.1524)
		(layer "In13.Cu")
		(net "HSC_VTEMP")
	)
	(segment
		(start 217.9701 -403.012148)
		(end 216.718134 -401.760182)
		(width 0.1524)
		(layer "In13.Cu")
		(net "HSC_VTEMP")
	)
	(segment
		(start 204.5335 -402.522182)
		(end 203.189332 -402.522182)
		(width 0.1524)
		(layer "In13.Cu")
		(net "HSC_VTEMP")
	)
	(segment
		(start 205.99654 -407.57602)
		(end 207.3021 -406.27046)
		(width 0.1524)
		(layer "In13.Cu")
		(net "HSC_VTEMP")
	)
	(segment
		(start 194.522344 -401.048982)
		(end 195.169282 -401.048982)
		(width 0.1524)
		(layer "In13.Cu")
		(net "HSC_VTEMP")
	)
	(segment
		(start 217.490802 -409.532582)
		(end 223.531938 -409.532582)
		(width 0.1524)
		(layer "In13.Cu")
		(net "HSC_VTEMP")
	)
	(segment
		(start 193.8274 -401.743926)
		(end 194.522344 -401.048982)
		(width 0.1524)
		(layer "In13.Cu")
		(net "HSC_VTEMP")
	)
	(segment
		(start 223.531938 -409.532582)
		(end 224.11944 -408.94508)
		(width 0.1524)
		(layer "In13.Cu")
		(net "HSC_VTEMP")
	)
	(segment
		(start 213.45144 -402.928074)
		(end 213.45144 -408.94508)
		(width 0.1524)
		(layer "In13.Cu")
		(net "HSC_VTEMP")
	)
	(segment
		(start 205.2955 -401.760182)
		(end 204.5335 -402.522182)
		(width 0.1524)
		(layer "In13.Cu")
		(net "HSC_VTEMP")
	)
	(segment
		(start 212.863938 -409.532582)
		(end 206.822802 -409.532582)
		(width 0.1524)
		(layer "In13.Cu")
		(net "HSC_VTEMP")
	)
	(segment
		(start 207.3021 -403.012148)
		(end 206.050134 -401.760182)
		(width 0.1524)
		(layer "In13.Cu")
		(net "HSC_VTEMP")
	)
	(segment
		(start 217.9701 -403.170136)
		(end 217.9701 -403.012148)
		(width 0.1524)
		(layer "In13.Cu")
		(net "HSC_VTEMP")
	)
	(segment
		(start 195.5165 -405.02586)
		(end 196.70268 -403.83968)
		(width 0.1524)
		(layer "In13.Cu")
		(net "HSC_VTEMP")
	)
	(segment
		(start 202.78344 -402.928074)
		(end 202.78344 -408.94508)
		(width 0.1524)
		(layer "In13.Cu")
		(net "HSC_VTEMP")
	)
	(segment
		(start 181.26964 -406.90038)
		(end 182.96382 -406.90038)
		(width 0.1524)
		(layer "In13.Cu")
		(net "HSC_VTEMP")
	)
	(segment
		(start 216.8525 -408.89428)
		(end 217.490802 -409.532582)
		(width 0.1524)
		(layer "In13.Cu")
		(net "HSC_VTEMP")
	)
	(segment
		(start 196.70268 -402.3487)
		(end 196.70268 -403.170136)
		(width 0.1524)
		(layer "In13.Cu")
		(net "HSC_VTEMP")
	)
	(segment
		(start 180.43144 -403.681184)
		(end 180.874416 -404.12416)
		(width 0.1524)
		(layer "In13.Cu")
		(net "HSC_VTEMP")
	)
	(segment
		(start 195.834762 -401.480782)
		(end 196.70268 -402.3487)
		(width 0.1524)
		(layer "In13.Cu")
		(net "HSC_VTEMP")
	)
	(segment
		(start 225.8695 -402.522182)
		(end 226.6315 -401.760182)
		(width 0.1524)
		(layer "In13.Cu")
		(net "HSC_VTEMP")
	)
	(segment
		(start 215.2015 -402.522182)
		(end 213.857332 -402.522182)
		(width 0.1524)
		(layer "In13.Cu")
		(net "HSC_VTEMP")
	)
	(segment
		(start 202.195938 -409.532582)
		(end 196.154802 -409.532582)
		(width 0.1524)
		(layer "In13.Cu")
		(net "HSC_VTEMP")
	)
	(segment
		(start 224.11944 -402.928074)
		(end 224.525332 -402.522182)
		(width 0.1524)
		(layer "In13.Cu")
		(net "HSC_VTEMP")
	)
	(segment
		(start 182.96382 -406.90038)
		(end 185.5216 -409.45816)
		(width 0.1524)
		(layer "In13.Cu")
		(net "HSC_VTEMP")
	)
	(segment
		(start 217.9701 -403.170136)
		(end 217.9701 -406.27046)
		(width 0.1524)
		(layer "In13.Cu")
		(net "HSC_VTEMP")
	)
	(segment
		(start 193.8274 -408.87396)
		(end 193.8274 -401.743926)
		(width 0.1524)
		(layer "In13.Cu")
		(net "HSC_VTEMP")
	)
	(segment
		(start 213.45144 -408.94508)
		(end 212.863938 -409.532582)
		(width 0.1524)
		(layer "In13.Cu")
		(net "HSC_VTEMP")
	)
	(segment
		(start 195.5165 -408.89428)
		(end 195.5165 -405.02586)
		(width 0.1524)
		(layer "In13.Cu")
		(net "HSC_VTEMP")
	)
	(segment
		(start 195.601082 -401.480782)
		(end 195.834762 -401.480782)
		(width 0.1524)
		(layer "In13.Cu")
		(net "HSC_VTEMP")
	)
	(segment
		(start 195.169282 -401.048982)
		(end 195.601082 -401.480782)
		(width 0.1524)
		(layer "In13.Cu")
		(net "HSC_VTEMP")
	)
	(segment
		(start 193.2432 -409.45816)
		(end 193.8274 -408.87396)
		(width 0.1524)
		(layer "In13.Cu")
		(net "HSC_VTEMP")
	)
	(segment
		(start 206.050134 -401.760182)
		(end 205.2955 -401.760182)
		(width 0.1524)
		(layer "In13.Cu")
		(net "HSC_VTEMP")
	)
	(segment
		(start 224.11944 -408.94508)
		(end 224.11944 -402.928074)
		(width 0.1524)
		(layer "In13.Cu")
		(net "HSC_VTEMP")
	)
	(segment
		(start 184.19445 -407.199846)
		(end 184.5437 -406.850596)
		(width 0.1524)
		(layer "F.Cu")
		(net "HSC_VSENSE")
	)
	(segment
		(start 183.6547 -406.236932)
		(end 184.3786 -405.513032)
		(width 0.1524)
		(layer "F.Cu")
		(net "HSC_VSENSE")
	)
	(segment
		(start 184.19445 -408.110182)
		(end 184.19445 -407.199846)
		(width 0.1524)
		(layer "F.Cu")
		(net "HSC_VSENSE")
	)
	(segment
		(start 184.5437 -406.850596)
		(end 184.5437 -406.236932)
		(width 0.1524)
		(layer "F.Cu")
		(net "HSC_VSENSE")
	)
	(segment
		(start 184.3786 -405.513032)
		(end 184.3786 -404.15718)
		(width 0.1524)
		(layer "F.Cu")
		(net "HSC_VSENSE")
	)
	(segment
		(start 184.5437 -406.236932)
		(end 183.6547 -406.236932)
		(width 0.1524)
		(layer "F.Cu")
		(net "HSC_VSENSE")
	)
	(via
		(at 184.5437 -406.236932)
		(size 0.508)
		(drill 0.254)
		(layers "F.Cu" "B.Cu")
		(net "HSC_VSENSE")
	)
	(segment
		(start 184.5437 -406.236932)
		(end 183.958484 -406.822148)
		(width 0.1524)
		(layer "B.Cu")
		(net "HSC_VSENSE")
	)
	(segment
		(start 183.958484 -406.822148)
		(end 183.36006 -406.822148)
		(width 0.1524)
		(layer "B.Cu")
		(net "HSC_VSENSE")
	)
	(segment
		(start 182.96255 -398.741392)
		(end 183.24576 -399.024602)
		(width 0.10668)
		(layer "F.Cu")
		(net "HSC_VOSEN")
	)
	(segment
		(start 183.478424 -399.257266)
		(end 183.478424 -399.682208)
		(width 0.10668)
		(layer "F.Cu")
		(net "HSC_VOSEN")
	)
	(segment
		(start 182.96255 -397.848582)
		(end 182.96255 -398.741392)
		(width 0.10668)
		(layer "F.Cu")
		(net "HSC_VOSEN")
	)
	(segment
		(start 183.24576 -399.024602)
		(end 183.478424 -399.257266)
		(width 0.10668)
		(layer "F.Cu")
		(net "HSC_VOSEN")
	)
	(via
		(at 183.24576 -399.024602)
		(size 0.508)
		(drill 0.254)
		(layers "F.Cu" "B.Cu")
		(net "HSC_VOSEN")
	)
	(segment
		(start 183.564784 -399.343626)
		(end 183.24576 -399.024602)
		(width 0.10668)
		(layer "B.Cu")
		(net "HSC_VOSEN")
	)
	(segment
		(start 183.564784 -399.867882)
		(end 183.564784 -399.343626)
		(width 0.10668)
		(layer "B.Cu")
		(net "HSC_VOSEN")
	)
	(segment
		(start 183.24576 -399.024602)
		(end 183.24576 -397.975582)
		(width 0.10668)
		(layer "B.Cu")
		(net "HSC_VOSEN")
	)
	(segment
		(start 183.37276 -397.848582)
		(end 183.94045 -397.848582)
		(width 0.10668)
		(layer "B.Cu")
		(net "HSC_VOSEN")
	)
	(segment
		(start 183.24576 -397.975582)
		(end 183.37276 -397.848582)
		(width 0.10668)
		(layer "B.Cu")
		(net "HSC_VOSEN")
	)
	(segment
		(start 179.705 -405.652478)
		(end 180.298344 -405.059134)
		(width 0.10668)
		(layer "F.Cu")
		(net "HSC_VIN_UVW_N")
	)
	(segment
		(start 180.696362 -404.661116)
		(end 180.298344 -405.059134)
		(width 0.10668)
		(layer "F.Cu")
		(net "HSC_VIN_UVW_N")
	)
	(segment
		(start 179.08905 -406.527)
		(end 179.197 -406.527)
		(width 0.10668)
		(layer "F.Cu")
		(net "HSC_VIN_UVW_N")
	)
	(segment
		(start 179.197 -406.527)
		(end 179.705 -406.019)
		(width 0.10668)
		(layer "F.Cu")
		(net "HSC_VIN_UVW_N")
	)
	(segment
		(start 182.041038 -403.494748)
		(end 181.63794 -403.494748)
		(width 0.10668)
		(layer "F.Cu")
		(net "HSC_VIN_UVW_N")
	)
	(segment
		(start 180.696362 -404.436326)
		(end 180.696362 -404.661116)
		(width 0.10668)
		(layer "F.Cu")
		(net "HSC_VIN_UVW_N")
	)
	(segment
		(start 179.705 -406.019)
		(end 179.705 -405.652478)
		(width 0.10668)
		(layer "F.Cu")
		(net "HSC_VIN_UVW_N")
	)
	(segment
		(start 181.63794 -403.494748)
		(end 180.696362 -404.436326)
		(width 0.10668)
		(layer "F.Cu")
		(net "HSC_VIN_UVW_N")
	)
	(via
		(at 180.298344 -405.059134)
		(size 0.762)
		(drill 0.254)
		(layers "F.Cu" "B.Cu")
		(net "HSC_VIN_UVW_N")
	)
	(segment
		(start 227.7745 -401.791932)
		(end 228.047804 -401.791932)
		(width 0.254)
		(layer "F.Cu")
		(net "HSC_VDD_R_4")
	)
	(segment
		(start 228.16947 -401.670266)
		(end 229.303072 -401.670266)
		(width 0.254)
		(layer "F.Cu")
		(net "HSC_VDD_R_4")
	)
	(segment
		(start 227.0887 -402.344382)
		(end 227.64115 -401.791932)
		(width 0.254)
		(layer "F.Cu")
		(net "HSC_VDD_R_4")
	)
	(segment
		(start 228.047804 -401.791932)
		(end 228.16947 -401.670266)
		(width 0.254)
		(layer "F.Cu")
		(net "HSC_VDD_R_4")
	)
	(segment
		(start 227.64115 -401.791932)
		(end 227.7745 -401.791932)
		(width 0.254)
		(layer "F.Cu")
		(net "HSC_VDD_R_4")
	)
	(via
		(at 227.0887 -402.344382)
		(size 0.508)
		(drill 0.254)
		(layers "F.Cu" "B.Cu")
		(net "HSC_VDD_R_4")
	)
	(segment
		(start 227.0887 -402.344382)
		(end 225.9203 -402.344382)
		(width 0.254)
		(layer "B.Cu")
		(net "HSC_VDD_R_4")
	)
	(segment
		(start 217.379804 -401.791932)
		(end 217.1065 -401.791932)
		(width 0.254)
		(layer "F.Cu")
		(net "HSC_VDD_R_3")
	)
	(segment
		(start 218.635072 -401.670266)
		(end 217.50147 -401.670266)
		(width 0.254)
		(layer "F.Cu")
		(net "HSC_VDD_R_3")
	)
	(segment
		(start 216.97315 -401.791932)
		(end 217.1065 -401.791932)
		(width 0.254)
		(layer "F.Cu")
		(net "HSC_VDD_R_3")
	)
	(segment
		(start 217.50147 -401.670266)
		(end 217.379804 -401.791932)
		(width 0.254)
		(layer "F.Cu")
		(net "HSC_VDD_R_3")
	)
	(segment
		(start 216.4207 -402.344382)
		(end 216.97315 -401.791932)
		(width 0.254)
		(layer "F.Cu")
		(net "HSC_VDD_R_3")
	)
	(via
		(at 216.4207 -402.344382)
		(size 0.508)
		(drill 0.254)
		(layers "F.Cu" "B.Cu")
		(net "HSC_VDD_R_3")
	)
	(segment
		(start 216.4207 -402.344382)
		(end 215.2523 -402.344382)
		(width 0.254)
		(layer "B.Cu")
		(net "HSC_VDD_R_3")
	)
	(segment
		(start 207.967072 -401.670266)
		(end 206.83347 -401.670266)
		(width 0.254)
		(layer "F.Cu")
		(net "HSC_VDD_R_2")
	)
	(segment
		(start 205.7527 -402.344382)
		(end 206.30515 -401.791932)
		(width 0.254)
		(layer "F.Cu")
		(net "HSC_VDD_R_2")
	)
	(segment
		(start 206.711804 -401.791932)
		(end 206.4385 -401.791932)
		(width 0.254)
		(layer "F.Cu")
		(net "HSC_VDD_R_2")
	)
	(segment
		(start 206.83347 -401.670266)
		(end 206.711804 -401.791932)
		(width 0.254)
		(layer "F.Cu")
		(net "HSC_VDD_R_2")
	)
	(segment
		(start 206.30515 -401.791932)
		(end 206.4385 -401.791932)
		(width 0.254)
		(layer "F.Cu")
		(net "HSC_VDD_R_2")
	)
	(via
		(at 205.7527 -402.344382)
		(size 0.508)
		(drill 0.254)
		(layers "F.Cu" "B.Cu")
		(net "HSC_VDD_R_2")
	)
	(segment
		(start 205.7527 -402.344382)
		(end 204.5843 -402.344382)
		(width 0.254)
		(layer "B.Cu")
		(net "HSC_VDD_R_2")
	)
	(segment
		(start 195.801234 -401.670266)
		(end 195.6943 -401.563332)
		(width 0.254)
		(layer "F.Cu")
		(net "HSC_VDD_R_1")
	)
	(segment
		(start 194.87515 -401.563332)
		(end 195.6943 -401.563332)
		(width 0.254)
		(layer "F.Cu")
		(net "HSC_VDD_R_1")
	)
	(segment
		(start 194.8053 -401.633182)
		(end 194.87515 -401.563332)
		(width 0.254)
		(layer "F.Cu")
		(net "HSC_VDD_R_1")
	)
	(segment
		(start 197.299072 -401.670266)
		(end 195.801234 -401.670266)
		(width 0.254)
		(layer "F.Cu")
		(net "HSC_VDD_R_1")
	)
	(via
		(at 194.8053 -401.633182)
		(size 0.508)
		(drill 0.254)
		(layers "F.Cu" "B.Cu")
		(net "HSC_VDD_R_1")
	)
	(segment
		(start 194.8053 -401.633182)
		(end 193.6369 -401.633182)
		(width 0.254)
		(layer "B.Cu")
		(net "HSC_VDD_R_1")
	)
	(segment
		(start 179.445158 -402.468842)
		(end 180.166518 -401.747482)
		(width 0.254)
		(layer "F.Cu")
		(net "HSC_VDD_R")
	)
	(segment
		(start 181.858412 -402.144738)
		(end 182.041038 -402.144738)
		(width 0.2032)
		(layer "F.Cu")
		(net "HSC_VDD_R")
	)
	(segment
		(start 180.36032 -401.747482)
		(end 180.66258 -401.747482)
		(width 0.254)
		(layer "F.Cu")
		(net "HSC_VDD_R")
	)
	(segment
		(start 181.126384 -402.211286)
		(end 181.791864 -402.211286)
		(width 0.2032)
		(layer "F.Cu")
		(net "HSC_VDD_R")
	)
	(segment
		(start 179.11699 -402.468842)
		(end 179.445158 -402.468842)
		(width 0.254)
		(layer "F.Cu")
		(net "HSC_VDD_R")
	)
	(segment
		(start 180.66258 -401.747482)
		(end 181.126384 -402.211286)
		(width 0.254)
		(layer "F.Cu")
		(net "HSC_VDD_R")
	)
	(segment
		(start 181.791864 -402.211286)
		(end 181.858412 -402.144738)
		(width 0.2032)
		(layer "F.Cu")
		(net "HSC_VDD_R")
	)
	(segment
		(start 180.166518 -401.747482)
		(end 180.36032 -401.747482)
		(width 0.254)
		(layer "F.Cu")
		(net "HSC_VDD_R")
	)
	(segment
		(start 179.11699 -403.484842)
		(end 179.11699 -402.468842)
		(width 0.254)
		(layer "F.Cu")
		(net "HSC_VDD_R")
	)
	(via
		(at 183.886602 -401.048728)
		(size 0.508)
		(drill 0.254)
		(layers "F.Cu" "B.Cu")
		(net "HSC_VDD_R")
	)
	(via
		(at 180.36032 -401.747482)
		(size 0.508)
		(drill 0.254)
		(layers "F.Cu" "B.Cu")
		(net "HSC_VDD_R")
	)
	(via
		(at 182.870602 -401.048728)
		(size 0.508)
		(drill 0.254)
		(layers "F.Cu" "B.Cu")
		(net "HSC_VDD_R")
	)
	(via
		(at 183.378602 -400.540728)
		(size 0.508)
		(drill 0.254)
		(layers "F.Cu" "B.Cu")
		(net "HSC_VDD_R")
	)
	(segment
		(start 183.3753 -401.518882)
		(end 183.340756 -401.518882)
		(width 0.254)
		(layer "B.Cu")
		(net "HSC_VDD_R")
	)
	(segment
		(start 183.340756 -401.518882)
		(end 182.870602 -401.048728)
		(width 0.254)
		(layer "B.Cu")
		(net "HSC_VDD_R")
	)
	(segment
		(start 180.4797 -400.436842)
		(end 180.84292 -400.436842)
		(width 0.1524)
		(layer "F.Cu")
		(net "HSC_VDD18")
	)
	(segment
		(start 177.673 -395.96695)
		(end 177.673 -395.986)
		(width 0.254)
		(layer "F.Cu")
		(net "HSC_VDD18")
	)
	(segment
		(start 178.28895 -395.351)
		(end 177.673 -395.96695)
		(width 0.254)
		(layer "F.Cu")
		(net "HSC_VDD18")
	)
	(segment
		(start 180.84292 -400.436842)
		(end 181.60492 -401.198842)
		(width 0.1524)
		(layer "F.Cu")
		(net "HSC_VDD18")
	)
	(segment
		(start 179.11699 -400.436842)
		(end 180.4797 -400.436842)
		(width 0.1524)
		(layer "F.Cu")
		(net "HSC_VDD18")
	)
	(segment
		(start 181.60492 -401.198842)
		(end 181.995064 -401.198842)
		(width 0.1524)
		(layer "F.Cu")
		(net "HSC_VDD18")
	)
	(segment
		(start 181.995064 -401.198842)
		(end 182.041038 -401.244816)
		(width 0.1524)
		(layer "F.Cu")
		(net "HSC_VDD18")
	)
	(via
		(at 180.4797 -400.436842)
		(size 0.762)
		(drill 0.254)
		(layers "F.Cu" "B.Cu")
		(net "HSC_VDD18")
	)
	(via
		(at 177.673 -395.986)
		(size 0.508)
		(drill 0.254)
		(layers "F.Cu" "B.Cu")
		(net "HSC_VDD18")
	)
	(segment
		(start 178.689 -397.002)
		(end 178.689 -399.796)
		(width 0.254)
		(layer "B.Cu")
		(net "HSC_VDD18")
	)
	(segment
		(start 177.673 -395.986)
		(end 178.689 -397.002)
		(width 0.254)
		(layer "B.Cu")
		(net "HSC_VDD18")
	)
	(segment
		(start 179.329842 -400.436842)
		(end 180.4797 -400.436842)
		(width 0.254)
		(layer "B.Cu")
		(net "HSC_VDD18")
	)
	(segment
		(start 178.689 -399.796)
		(end 179.329842 -400.436842)
		(width 0.254)
		(layer "B.Cu")
		(net "HSC_VDD18")
	)
	(segment
		(start 177.927 -406.527)
		(end 177.673 -406.273)
		(width 0.254)
		(layer "F.Cu")
		(net "HSC_VDD")
	)
	(segment
		(start 178.28895 -406.527)
		(end 177.927 -406.527)
		(width 0.254)
		(layer "F.Cu")
		(net "HSC_VDD")
	)
	(segment
		(start 177.678842 -403.484842)
		(end 177.673 -403.479)
		(width 0.254)
		(layer "F.Cu")
		(net "HSC_VDD")
	)
	(segment
		(start 178.31689 -403.484842)
		(end 177.678842 -403.484842)
		(width 0.254)
		(layer "F.Cu")
		(net "HSC_VDD")
	)
	(via
		(at 214.5538 -403.144482)
		(size 0.508)
		(drill 0.254)
		(layers "F.Cu" "B.Cu")
		(net "HSC_VDD")
	)
	(via
		(at 191.67729 -404.513034)
		(size 0.508)
		(drill 0.254)
		(layers "F.Cu" "B.Cu")
		(net "HSC_VDD")
	)
	(via
		(at 225.2218 -403.144482)
		(size 0.508)
		(drill 0.254)
		(layers "F.Cu" "B.Cu")
		(net "HSC_VDD")
	)
	(via
		(at 177.673 -406.273)
		(size 0.508)
		(drill 0.254)
		(layers "F.Cu" "B.Cu")
		(net "HSC_VDD")
	)
	(via
		(at 177.673 -403.479)
		(size 0.508)
		(drill 0.254)
		(layers "F.Cu" "B.Cu")
		(net "HSC_VDD")
	)
	(via
		(at 203.8858 -403.144482)
		(size 0.508)
		(drill 0.254)
		(layers "F.Cu" "B.Cu")
		(net "HSC_VDD")
	)
	(segment
		(start 191.67729 -404.513034)
		(end 190.530988 -403.366732)
		(width 0.254)
		(layer "B.Cu")
		(net "HSC_VDD")
	)
	(segment
		(start 190.530988 -401.362672)
		(end 190.783718 -401.109942)
		(width 0.254)
		(layer "B.Cu")
		(net "HSC_VDD")
	)
	(segment
		(start 191.26454 -402.341842)
		(end 191.26454 -401.109942)
		(width 0.254)
		(layer "B.Cu")
		(net "HSC_VDD")
	)
	(segment
		(start 193.86296 -402.659342)
		(end 193.86296 -403.57806)
		(width 0.254)
		(layer "B.Cu")
		(net "HSC_VDD")
	)
	(segment
		(start 190.783718 -401.109942)
		(end 191.26454 -401.109942)
		(width 0.254)
		(layer "B.Cu")
		(net "HSC_VDD")
	)
	(segment
		(start 192.927986 -404.513034)
		(end 191.67729 -404.513034)
		(width 0.254)
		(layer "B.Cu")
		(net "HSC_VDD")
	)
	(segment
		(start 215.2523 -403.144482)
		(end 214.5538 -403.144482)
		(width 0.254)
		(layer "B.Cu")
		(net "HSC_VDD")
	)
	(segment
		(start 204.5843 -403.144482)
		(end 203.8858 -403.144482)
		(width 0.254)
		(layer "B.Cu")
		(net "HSC_VDD")
	)
	(segment
		(start 193.6369 -402.433282)
		(end 193.86296 -402.659342)
		(width 0.254)
		(layer "B.Cu")
		(net "HSC_VDD")
	)
	(segment
		(start 190.530988 -403.366732)
		(end 190.530988 -401.362672)
		(width 0.254)
		(layer "B.Cu")
		(net "HSC_VDD")
	)
	(segment
		(start 225.9203 -403.144482)
		(end 225.2218 -403.144482)
		(width 0.254)
		(layer "B.Cu")
		(net "HSC_VDD")
	)
	(segment
		(start 193.86296 -403.57806)
		(end 192.927986 -404.513034)
		(width 0.254)
		(layer "B.Cu")
		(net "HSC_VDD")
	)
	(segment
		(start 177.673 -406.273)
		(end 178.151536 -406.273)
		(width 0.254)
		(layer "In4.Cu")
		(net "HSC_VDD")
	)
	(segment
		(start 178.382168 -406.042368)
		(end 178.382168 -404.925276)
		(width 0.254)
		(layer "In4.Cu")
		(net "HSC_VDD")
	)
	(segment
		(start 194.761612 -403.951694)
		(end 195.154042 -404.344124)
		(width 0.254)
		(layer "In4.Cu")
		(net "HSC_VDD")
	)
	(segment
		(start 178.151536 -406.273)
		(end 178.382168 -406.042368)
		(width 0.254)
		(layer "In4.Cu")
		(net "HSC_VDD")
	)
	(segment
		(start 177.673 -403.479)
		(end 179.07 -403.479)
		(width 0.254)
		(layer "In4.Cu")
		(net "HSC_VDD")
	)
	(segment
		(start 192.882266 -403.951694)
		(end 194.761612 -403.951694)
		(width 0.254)
		(layer "In4.Cu")
		(net "HSC_VDD")
	)
	(segment
		(start 218.577668 -404.276814)
		(end 217.614246 -405.240236)
		(width 0.254)
		(layer "In4.Cu")
		(net "HSC_VDD")
	)
	(segment
		(start 191.67729 -404.09749)
		(end 191.67729 -404.513034)
		(width 0.254)
		(layer "In4.Cu")
		(net "HSC_VDD")
	)
	(segment
		(start 215.709754 -405.240236)
		(end 214.9983 -404.528782)
		(width 0.254)
		(layer "In4.Cu")
		(net "HSC_VDD")
	)
	(segment
		(start 177.673 -404.216108)
		(end 177.673 -403.479)
		(width 0.254)
		(layer "In4.Cu")
		(net "HSC_VDD")
	)
	(segment
		(start 202.686158 -404.344124)
		(end 203.8858 -403.144482)
		(width 0.254)
		(layer "In4.Cu")
		(net "HSC_VDD")
	)
	(segment
		(start 203.8858 -403.982682)
		(end 205.013306 -405.110188)
		(width 0.254)
		(layer "In4.Cu")
		(net "HSC_VDD")
	)
	(segment
		(start 190.23838 -402.65858)
		(end 191.67729 -404.09749)
		(width 0.254)
		(layer "In4.Cu")
		(net "HSC_VDD")
	)
	(segment
		(start 207.996536 -404.308818)
		(end 213.389464 -404.308818)
		(width 0.254)
		(layer "In4.Cu")
		(net "HSC_VDD")
	)
	(segment
		(start 181.31282 -404.03018)
		(end 188.0362 -404.03018)
		(width 0.254)
		(layer "In4.Cu")
		(net "HSC_VDD")
	)
	(segment
		(start 214.9983 -404.528782)
		(end 214.9983 -403.588982)
		(width 0.254)
		(layer "In4.Cu")
		(net "HSC_VDD")
	)
	(segment
		(start 207.195166 -405.110188)
		(end 207.996536 -404.308818)
		(width 0.254)
		(layer "In4.Cu")
		(net "HSC_VDD")
	)
	(segment
		(start 214.9983 -403.588982)
		(end 214.5538 -403.144482)
		(width 0.254)
		(layer "In4.Cu")
		(net "HSC_VDD")
	)
	(segment
		(start 181.026816 -404.316184)
		(end 181.31282 -404.03018)
		(width 0.254)
		(layer "In4.Cu")
		(net "HSC_VDD")
	)
	(segment
		(start 223.33966 -404.276814)
		(end 218.577668 -404.276814)
		(width 0.254)
		(layer "In4.Cu")
		(net "HSC_VDD")
	)
	(segment
		(start 179.07 -403.479)
		(end 179.907184 -404.316184)
		(width 0.254)
		(layer "In4.Cu")
		(net "HSC_VDD")
	)
	(segment
		(start 217.614246 -405.240236)
		(end 215.709754 -405.240236)
		(width 0.254)
		(layer "In4.Cu")
		(net "HSC_VDD")
	)
	(segment
		(start 225.2218 -403.144482)
		(end 224.471992 -403.144482)
		(width 0.254)
		(layer "In4.Cu")
		(net "HSC_VDD")
	)
	(segment
		(start 203.8858 -403.144482)
		(end 203.8858 -403.982682)
		(width 0.254)
		(layer "In4.Cu")
		(net "HSC_VDD")
	)
	(segment
		(start 213.389464 -404.308818)
		(end 214.5538 -403.144482)
		(width 0.254)
		(layer "In4.Cu")
		(net "HSC_VDD")
	)
	(segment
		(start 189.4078 -402.65858)
		(end 190.23838 -402.65858)
		(width 0.254)
		(layer "In4.Cu")
		(net "HSC_VDD")
	)
	(segment
		(start 224.471992 -403.144482)
		(end 223.33966 -404.276814)
		(width 0.254)
		(layer "In4.Cu")
		(net "HSC_VDD")
	)
	(segment
		(start 195.154042 -404.344124)
		(end 202.686158 -404.344124)
		(width 0.254)
		(layer "In4.Cu")
		(net "HSC_VDD")
	)
	(segment
		(start 188.0362 -404.03018)
		(end 189.4078 -402.65858)
		(width 0.254)
		(layer "In4.Cu")
		(net "HSC_VDD")
	)
	(segment
		(start 178.382168 -404.925276)
		(end 177.673 -404.216108)
		(width 0.254)
		(layer "In4.Cu")
		(net "HSC_VDD")
	)
	(segment
		(start 191.67729 -404.513034)
		(end 192.320926 -404.513034)
		(width 0.254)
		(layer "In4.Cu")
		(net "HSC_VDD")
	)
	(segment
		(start 179.907184 -404.316184)
		(end 181.026816 -404.316184)
		(width 0.254)
		(layer "In4.Cu")
		(net "HSC_VDD")
	)
	(segment
		(start 205.013306 -405.110188)
		(end 207.195166 -405.110188)
		(width 0.254)
		(layer "In4.Cu")
		(net "HSC_VDD")
	)
	(segment
		(start 192.320926 -404.513034)
		(end 192.882266 -403.951694)
		(width 0.254)
		(layer "In4.Cu")
		(net "HSC_VDD")
	)
	(segment
		(start 195.9737 -402.932646)
		(end 196.341746 -402.5646)
		(width 0.1524)
		(layer "F.Cu")
		(net "HSC_SS")
	)
	(segment
		(start 205.16215 -405.036782)
		(end 205.597506 -405.036782)
		(width 0.1524)
		(layer "F.Cu")
		(net "HSC_SS")
	)
	(segment
		(start 215.83015 -405.036782)
		(end 216.265506 -405.036782)
		(width 0.1524)
		(layer "F.Cu")
		(net "HSC_SS")
	)
	(segment
		(start 227.850446 -404.020782)
		(end 227.8507 -404.020528)
		(width 0.1524)
		(layer "F.Cu")
		(net "HSC_SS")
	)
	(segment
		(start 197.125336 -402.670264)
		(end 197.299072 -402.670264)
		(width 0.1524)
		(layer "F.Cu")
		(net "HSC_SS")
	)
	(segment
		(start 194.62115 -403.284182)
		(end 195.385182 -403.284182)
		(width 0.1524)
		(layer "F.Cu")
		(net "HSC_SS")
	)
	(segment
		(start 195.385182 -403.284182)
		(end 195.537582 -403.131782)
		(width 0.1524)
		(layer "F.Cu")
		(net "HSC_SS")
	)
	(segment
		(start 195.9737 -403.131782)
		(end 195.9737 -402.932646)
		(width 0.1524)
		(layer "F.Cu")
		(net "HSC_SS")
	)
	(segment
		(start 178.054 -403.987)
		(end 179.451 -403.987)
		(width 0.1524)
		(layer "F.Cu")
		(net "HSC_SS")
	)
	(segment
		(start 195.537582 -403.131782)
		(end 195.9737 -403.131782)
		(width 0.1524)
		(layer "F.Cu")
		(net "HSC_SS")
	)
	(segment
		(start 217.745564 -402.670264)
		(end 218.635072 -402.670264)
		(width 0.1524)
		(layer "F.Cu")
		(net "HSC_SS")
	)
	(segment
		(start 206.514446 -404.020782)
		(end 206.514446 -403.233382)
		(width 0.1524)
		(layer "F.Cu")
		(net "HSC_SS")
	)
	(segment
		(start 216.265506 -405.036782)
		(end 217.182446 -404.119842)
		(width 0.1524)
		(layer "F.Cu")
		(net "HSC_SS")
	)
	(segment
		(start 227.8507 -404.020528)
		(end 227.8507 -403.233128)
		(width 0.1524)
		(layer "F.Cu")
		(net "HSC_SS")
	)
	(segment
		(start 217.182446 -404.119842)
		(end 217.182446 -404.020782)
		(width 0.1524)
		(layer "F.Cu")
		(net "HSC_SS")
	)
	(segment
		(start 177.94605 -404.09495)
		(end 178.054 -403.987)
		(width 0.1524)
		(layer "F.Cu")
		(net "HSC_SS")
	)
	(segment
		(start 179.832 -403.606)
		(end 179.832 -403.098)
		(width 0.1524)
		(layer "F.Cu")
		(net "HSC_SS")
	)
	(segment
		(start 227.850446 -404.119842)
		(end 227.850446 -404.020782)
		(width 0.1524)
		(layer "F.Cu")
		(net "HSC_SS")
	)
	(segment
		(start 181.732174 -402.594572)
		(end 181.692804 -402.633942)
		(width 0.1524)
		(layer "F.Cu")
		(net "HSC_SS")
	)
	(segment
		(start 226.933506 -405.036782)
		(end 227.850446 -404.119842)
		(width 0.1524)
		(layer "F.Cu")
		(net "HSC_SS")
	)
	(segment
		(start 179.451 -403.987)
		(end 179.832 -403.606)
		(width 0.1524)
		(layer "F.Cu")
		(net "HSC_SS")
	)
	(segment
		(start 197.019672 -402.5646)
		(end 197.125336 -402.670264)
		(width 0.1524)
		(layer "F.Cu")
		(net "HSC_SS")
	)
	(segment
		(start 217.182446 -404.020782)
		(end 217.1827 -404.020528)
		(width 0.1524)
		(layer "F.Cu")
		(net "HSC_SS")
	)
	(segment
		(start 227.8507 -403.233128)
		(end 228.413564 -402.670264)
		(width 0.1524)
		(layer "F.Cu")
		(net "HSC_SS")
	)
	(segment
		(start 177.419 -404.09495)
		(end 177.94605 -404.09495)
		(width 0.1524)
		(layer "F.Cu")
		(net "HSC_SS")
	)
	(segment
		(start 228.413564 -402.670264)
		(end 229.303072 -402.670264)
		(width 0.1524)
		(layer "F.Cu")
		(net "HSC_SS")
	)
	(segment
		(start 205.597506 -405.036782)
		(end 206.514446 -404.119842)
		(width 0.1524)
		(layer "F.Cu")
		(net "HSC_SS")
	)
	(segment
		(start 207.077564 -402.670264)
		(end 207.967072 -402.670264)
		(width 0.1524)
		(layer "F.Cu")
		(net "HSC_SS")
	)
	(segment
		(start 181.692804 -402.633942)
		(end 180.44668 -402.633942)
		(width 0.1524)
		(layer "F.Cu")
		(net "HSC_SS")
	)
	(segment
		(start 180.296058 -402.633942)
		(end 180.44668 -402.633942)
		(width 0.1524)
		(layer "F.Cu")
		(net "HSC_SS")
	)
	(segment
		(start 226.49815 -405.036782)
		(end 226.933506 -405.036782)
		(width 0.1524)
		(layer "F.Cu")
		(net "HSC_SS")
	)
	(segment
		(start 217.1827 -403.233128)
		(end 217.745564 -402.670264)
		(width 0.1524)
		(layer "F.Cu")
		(net "HSC_SS")
	)
	(segment
		(start 179.832 -403.098)
		(end 180.296058 -402.633942)
		(width 0.1524)
		(layer "F.Cu")
		(net "HSC_SS")
	)
	(segment
		(start 206.514446 -403.233382)
		(end 207.077564 -402.670264)
		(width 0.1524)
		(layer "F.Cu")
		(net "HSC_SS")
	)
	(segment
		(start 217.1827 -404.020528)
		(end 217.1827 -403.233128)
		(width 0.1524)
		(layer "F.Cu")
		(net "HSC_SS")
	)
	(segment
		(start 196.341746 -402.5646)
		(end 197.019672 -402.5646)
		(width 0.1524)
		(layer "F.Cu")
		(net "HSC_SS")
	)
	(segment
		(start 182.041038 -402.594572)
		(end 181.732174 -402.594572)
		(width 0.1524)
		(layer "F.Cu")
		(net "HSC_SS")
	)
	(segment
		(start 206.514446 -404.119842)
		(end 206.514446 -404.020782)
		(width 0.1524)
		(layer "F.Cu")
		(net "HSC_SS")
	)
	(via
		(at 227.850446 -404.020782)
		(size 0.508)
		(drill 0.254)
		(layers "F.Cu" "B.Cu")
		(net "HSC_SS")
	)
	(via
		(at 206.514446 -404.020782)
		(size 0.508)
		(drill 0.254)
		(layers "F.Cu" "B.Cu")
		(net "HSC_SS")
	)
	(via
		(at 217.182446 -404.020782)
		(size 0.508)
		(drill 0.254)
		(layers "F.Cu" "B.Cu")
		(net "HSC_SS")
	)
	(via
		(at 180.44668 -402.633942)
		(size 0.762)
		(drill 0.254)
		(layers "F.Cu" "B.Cu")
		(net "HSC_SS")
	)
	(via
		(at 195.9737 -403.131782)
		(size 0.508)
		(drill 0.254)
		(layers "F.Cu" "B.Cu")
		(net "HSC_SS")
	)
	(segment
		(start 194.399154 -404.706328)
		(end 195.9737 -403.131782)
		(width 0.1524)
		(layer "In13.Cu")
		(net "HSC_SS")
	)
	(segment
		(start 204.8002 -410.3497)
		(end 204.9399 -410.21)
		(width 0.1524)
		(layer "In13.Cu")
		(net "HSC_SS")
	)
	(segment
		(start 194.833494 -410.3497)
		(end 204.8002 -410.3497)
		(width 0.1524)
		(layer "In13.Cu")
		(net "HSC_SS")
	)
	(segment
		(start 179.00904 -408.8257)
		(end 179.00904 -409.75534)
		(width 0.1524)
		(layer "In13.Cu")
		(net "HSC_SS")
	)
	(segment
		(start 179.00904 -409.75534)
		(end 179.49926 -410.24556)
		(width 0.1524)
		(layer "In13.Cu")
		(net "HSC_SS")
	)
	(segment
		(start 179.49926 -410.24556)
		(end 194.068954 -410.24556)
		(width 0.1524)
		(layer "In13.Cu")
		(net "HSC_SS")
	)
	(segment
		(start 215.6079 -410.21)
		(end 215.7476 -410.3497)
		(width 0.1524)
		(layer "In13.Cu")
		(net "HSC_SS")
	)
	(segment
		(start 215.4682 -410.3497)
		(end 215.6079 -410.21)
		(width 0.1524)
		(layer "In13.Cu")
		(net "HSC_SS")
	)
	(segment
		(start 226.1362 -410.3497)
		(end 226.2759 -410.21)
		(width 0.1524)
		(layer "In13.Cu")
		(net "HSC_SS")
	)
	(segment
		(start 204.9399 -405.595328)
		(end 206.514446 -404.020782)
		(width 0.1524)
		(layer "In13.Cu")
		(net "HSC_SS")
	)
	(segment
		(start 215.6079 -410.21)
		(end 215.6079 -405.595328)
		(width 0.1524)
		(layer "In13.Cu")
		(net "HSC_SS")
	)
	(segment
		(start 194.068954 -410.24556)
		(end 194.399154 -409.91536)
		(width 0.1524)
		(layer "In13.Cu")
		(net "HSC_SS")
	)
	(segment
		(start 215.7476 -410.3497)
		(end 226.1362 -410.3497)
		(width 0.1524)
		(layer "In13.Cu")
		(net "HSC_SS")
	)
	(segment
		(start 194.399154 -409.91536)
		(end 194.833494 -410.3497)
		(width 0.1524)
		(layer "In13.Cu")
		(net "HSC_SS")
	)
	(segment
		(start 194.399154 -409.91536)
		(end 194.399154 -404.706328)
		(width 0.1524)
		(layer "In13.Cu")
		(net "HSC_SS")
	)
	(segment
		(start 205.0796 -410.3497)
		(end 215.4682 -410.3497)
		(width 0.1524)
		(layer "In13.Cu")
		(net "HSC_SS")
	)
	(segment
		(start 179.49164 -403.588982)
		(end 179.49164 -408.3431)
		(width 0.1524)
		(layer "In13.Cu")
		(net "HSC_SS")
	)
	(segment
		(start 179.49164 -408.3431)
		(end 179.00904 -408.8257)
		(width 0.1524)
		(layer "In13.Cu")
		(net "HSC_SS")
	)
	(segment
		(start 226.2759 -405.595328)
		(end 227.850446 -404.020782)
		(width 0.1524)
		(layer "In13.Cu")
		(net "HSC_SS")
	)
	(segment
		(start 180.44668 -402.633942)
		(end 179.49164 -403.588982)
		(width 0.1524)
		(layer "In13.Cu")
		(net "HSC_SS")
	)
	(segment
		(start 204.9399 -410.21)
		(end 205.0796 -410.3497)
		(width 0.1524)
		(layer "In13.Cu")
		(net "HSC_SS")
	)
	(segment
		(start 215.6079 -405.595328)
		(end 217.182446 -404.020782)
		(width 0.1524)
		(layer "In13.Cu")
		(net "HSC_SS")
	)
	(segment
		(start 226.2759 -410.21)
		(end 226.2759 -405.595328)
		(width 0.1524)
		(layer "In13.Cu")
		(net "HSC_SS")
	)
	(segment
		(start 204.9399 -410.21)
		(end 204.9399 -405.595328)
		(width 0.1524)
		(layer "In13.Cu")
		(net "HSC_SS")
	)
	(segment
		(start 226.49815 -408.084782)
		(end 227.202492 -408.084782)
		(width 0.1524)
		(layer "F.Cu")
		(net "HSC_SCREF_4")
	)
	(segment
		(start 228.7651 -404.808182)
		(end 228.7651 -404.020782)
		(width 0.1524)
		(layer "F.Cu")
		(net "HSC_SCREF_4")
	)
	(segment
		(start 228.10851 -405.464772)
		(end 228.7651 -404.808182)
		(width 0.1524)
		(layer "F.Cu")
		(net "HSC_SCREF_4")
	)
	(segment
		(start 227.839778 -405.733504)
		(end 228.10851 -405.464772)
		(width 0.1524)
		(layer "F.Cu")
		(net "HSC_SCREF_4")
	)
	(segment
		(start 229.11562 -403.670262)
		(end 229.290372 -403.670262)
		(width 0.1524)
		(layer "F.Cu")
		(net "HSC_SCREF_4")
	)
	(segment
		(start 228.7651 -404.020782)
		(end 229.11562 -403.670262)
		(width 0.1524)
		(layer "F.Cu")
		(net "HSC_SCREF_4")
	)
	(segment
		(start 227.202492 -408.084782)
		(end 227.839778 -407.447496)
		(width 0.1524)
		(layer "F.Cu")
		(net "HSC_SCREF_4")
	)
	(segment
		(start 227.839778 -407.447496)
		(end 227.839778 -405.733504)
		(width 0.1524)
		(layer "F.Cu")
		(net "HSC_SCREF_4")
	)
	(via
		(at 228.10851 -405.464772)
		(size 0.762)
		(drill 0.381)
		(layers "F.Cu" "B.Cu")
		(net "HSC_SCREF_4")
	)
	(segment
		(start 216.534492 -408.084782)
		(end 217.171778 -407.447496)
		(width 0.1524)
		(layer "F.Cu")
		(net "HSC_SCREF_3")
	)
	(segment
		(start 218.0971 -404.808182)
		(end 218.0971 -404.020782)
		(width 0.1524)
		(layer "F.Cu")
		(net "HSC_SCREF_3")
	)
	(segment
		(start 217.42781 -405.616664)
		(end 217.42781 -405.477472)
		(width 0.1524)
		(layer "F.Cu")
		(net "HSC_SCREF_3")
	)
	(segment
		(start 217.42781 -405.477472)
		(end 218.0971 -404.808182)
		(width 0.1524)
		(layer "F.Cu")
		(net "HSC_SCREF_3")
	)
	(segment
		(start 217.171778 -407.447496)
		(end 217.171778 -405.872696)
		(width 0.1524)
		(layer "F.Cu")
		(net "HSC_SCREF_3")
	)
	(segment
		(start 215.83015 -408.084782)
		(end 216.534492 -408.084782)
		(width 0.1524)
		(layer "F.Cu")
		(net "HSC_SCREF_3")
	)
	(segment
		(start 217.171778 -405.872696)
		(end 217.42781 -405.616664)
		(width 0.1524)
		(layer "F.Cu")
		(net "HSC_SCREF_3")
	)
	(segment
		(start 218.0971 -404.020782)
		(end 218.44762 -403.670262)
		(width 0.1524)
		(layer "F.Cu")
		(net "HSC_SCREF_3")
	)
	(segment
		(start 218.44762 -403.670262)
		(end 218.622372 -403.670262)
		(width 0.1524)
		(layer "F.Cu")
		(net "HSC_SCREF_3")
	)
	(via
		(at 217.42781 -405.616664)
		(size 0.762)
		(drill 0.381)
		(layers "F.Cu" "B.Cu")
		(net "HSC_SCREF_3")
	)
	(segment
		(start 207.4291 -404.020782)
		(end 207.77962 -403.670262)
		(width 0.1524)
		(layer "F.Cu")
		(net "HSC_SCREF_2")
	)
	(segment
		(start 205.866492 -408.084782)
		(end 206.647034 -407.30424)
		(width 0.1524)
		(layer "F.Cu")
		(net "HSC_SCREF_2")
	)
	(segment
		(start 206.647034 -405.773636)
		(end 206.647034 -405.590248)
		(width 0.1524)
		(layer "F.Cu")
		(net "HSC_SCREF_2")
	)
	(segment
		(start 206.647034 -407.30424)
		(end 206.647034 -405.773636)
		(width 0.1524)
		(layer "F.Cu")
		(net "HSC_SCREF_2")
	)
	(segment
		(start 207.4291 -404.808182)
		(end 207.4291 -404.020782)
		(width 0.1524)
		(layer "F.Cu")
		(net "HSC_SCREF_2")
	)
	(segment
		(start 207.77962 -403.670262)
		(end 207.954372 -403.670262)
		(width 0.1524)
		(layer "F.Cu")
		(net "HSC_SCREF_2")
	)
	(segment
		(start 205.16215 -408.084782)
		(end 205.866492 -408.084782)
		(width 0.1524)
		(layer "F.Cu")
		(net "HSC_SCREF_2")
	)
	(segment
		(start 206.647034 -405.590248)
		(end 207.4291 -404.808182)
		(width 0.1524)
		(layer "F.Cu")
		(net "HSC_SCREF_2")
	)
	(via
		(at 206.647034 -405.773636)
		(size 0.762)
		(drill 0.381)
		(layers "F.Cu" "B.Cu")
		(net "HSC_SCREF_2")
	)
	(segment
		(start 194.62115 -404.300182)
		(end 195.9991 -404.300182)
		(width 0.1524)
		(layer "F.Cu")
		(net "HSC_SCREF_1")
	)
	(segment
		(start 196.459348 -404.300182)
		(end 197.089268 -403.670262)
		(width 0.1524)
		(layer "F.Cu")
		(net "HSC_SCREF_1")
	)
	(segment
		(start 197.089268 -403.670262)
		(end 197.286372 -403.670262)
		(width 0.1524)
		(layer "F.Cu")
		(net "HSC_SCREF_1")
	)
	(segment
		(start 195.9991 -404.300182)
		(end 196.459348 -404.300182)
		(width 0.1524)
		(layer "F.Cu")
		(net "HSC_SCREF_1")
	)
	(via
		(at 195.9991 -404.300182)
		(size 0.762)
		(drill 0.381)
		(layers "F.Cu" "B.Cu")
		(net "HSC_SCREF_1")
	)
	(segment
		(start 193.82105 -404.300182)
		(end 193.324734 -404.300182)
		(width 0.1524)
		(layer "F.Cu")
		(net "HSC_SCREF")
	)
	(segment
		(start 193.172334 -404.452582)
		(end 193.172334 -405.257)
		(width 0.1524)
		(layer "F.Cu")
		(net "HSC_SCREF")
	)
	(segment
		(start 183.92394 -397.007588)
		(end 183.44134 -397.490188)
		(width 0.1524)
		(layer "F.Cu")
		(net "HSC_SCREF")
	)
	(segment
		(start 204.36205 -408.084782)
		(end 203.7461 -408.084782)
		(width 0.1524)
		(layer "F.Cu")
		(net "HSC_SCREF")
	)
	(segment
		(start 215.03005 -408.084782)
		(end 214.4141 -408.084782)
		(width 0.1524)
		(layer "F.Cu")
		(net "HSC_SCREF")
	)
	(segment
		(start 183.928512 -399.123662)
		(end 183.928512 -399.682208)
		(width 0.1524)
		(layer "F.Cu")
		(net "HSC_SCREF")
	)
	(segment
		(start 225.69805 -408.084782)
		(end 225.0821 -408.084782)
		(width 0.1524)
		(layer "F.Cu")
		(net "HSC_SCREF")
	)
	(segment
		(start 193.324734 -404.300182)
		(end 193.172334 -404.452582)
		(width 0.1524)
		(layer "F.Cu")
		(net "HSC_SCREF")
	)
	(segment
		(start 183.44134 -397.490188)
		(end 183.44134 -397.947388)
		(width 0.1524)
		(layer "F.Cu")
		(net "HSC_SCREF")
	)
	(segment
		(start 183.44134 -397.947388)
		(end 183.928512 -399.123662)
		(width 0.1524)
		(layer "F.Cu")
		(net "HSC_SCREF")
	)
	(segment
		(start 183.92394 -396.70355)
		(end 183.92394 -397.007588)
		(width 0.1524)
		(layer "F.Cu")
		(net "HSC_SCREF")
	)
	(via
		(at 214.4141 -408.084782)
		(size 0.508)
		(drill 0.254)
		(layers "F.Cu" "B.Cu")
		(net "HSC_SCREF")
	)
	(via
		(at 193.172334 -405.257)
		(size 0.508)
		(drill 0.254)
		(layers "F.Cu" "B.Cu")
		(net "HSC_SCREF")
	)
	(via
		(at 183.92394 -396.70355)
		(size 0.508)
		(drill 0.254)
		(layers "F.Cu" "B.Cu")
		(net "HSC_SCREF")
	)
	(via
		(at 225.0821 -408.084782)
		(size 0.508)
		(drill 0.254)
		(layers "F.Cu" "B.Cu")
		(net "HSC_SCREF")
	)
	(via
		(at 203.7461 -408.084782)
		(size 0.508)
		(drill 0.254)
		(layers "F.Cu" "B.Cu")
		(net "HSC_SCREF")
	)
	(segment
		(start 214.4141 -410.952442)
		(end 214.4141 -408.084782)
		(width 0.1524)
		(layer "In4.Cu")
		(net "HSC_SCREF")
	)
	(segment
		(start 193.172334 -410.213556)
		(end 194.691 -411.732222)
		(width 0.1524)
		(layer "In4.Cu")
		(net "HSC_SCREF")
	)
	(segment
		(start 202.74026 -411.732222)
		(end 203.7461 -410.726382)
		(width 0.1524)
		(layer "In4.Cu")
		(net "HSC_SCREF")
	)
	(segment
		(start 204.72654 -411.706822)
		(end 213.65972 -411.706822)
		(width 0.1524)
		(layer "In4.Cu")
		(net "HSC_SCREF")
	)
	(segment
		(start 225.0821 -408.084782)
		(end 225.0821 -410.914342)
		(width 0.1524)
		(layer "In4.Cu")
		(net "HSC_SCREF")
	)
	(segment
		(start 193.172334 -405.257)
		(end 193.172334 -410.213556)
		(width 0.1524)
		(layer "In4.Cu")
		(net "HSC_SCREF")
	)
	(segment
		(start 215.19134 -411.729682)
		(end 214.4141 -410.952442)
		(width 0.1524)
		(layer "In4.Cu")
		(net "HSC_SCREF")
	)
	(segment
		(start 224.26676 -411.729682)
		(end 215.19134 -411.729682)
		(width 0.1524)
		(layer "In4.Cu")
		(net "HSC_SCREF")
	)
	(segment
		(start 225.0821 -410.914342)
		(end 224.26676 -411.729682)
		(width 0.1524)
		(layer "In4.Cu")
		(net "HSC_SCREF")
	)
	(segment
		(start 194.691 -411.732222)
		(end 202.74026 -411.732222)
		(width 0.1524)
		(layer "In4.Cu")
		(net "HSC_SCREF")
	)
	(segment
		(start 203.7461 -410.726382)
		(end 204.72654 -411.706822)
		(width 0.1524)
		(layer "In4.Cu")
		(net "HSC_SCREF")
	)
	(segment
		(start 203.7461 -410.726382)
		(end 203.7461 -408.084782)
		(width 0.1524)
		(layer "In4.Cu")
		(net "HSC_SCREF")
	)
	(segment
		(start 213.65972 -411.706822)
		(end 214.4141 -410.952442)
		(width 0.1524)
		(layer "In4.Cu")
		(net "HSC_SCREF")
	)
	(segment
		(start 183.92394 -396.70355)
		(end 183.92394 -399.48866)
		(width 0.1524)
		(layer "In15.Cu")
		(net "HSC_SCREF")
	)
	(segment
		(start 183.92394 -399.48866)
		(end 184.190386 -399.755106)
		(width 0.1524)
		(layer "In15.Cu")
		(net "HSC_SCREF")
	)
	(segment
		(start 190.644018 -399.24609)
		(end 191.070992 -399.673064)
		(width 0.1524)
		(layer "In15.Cu")
		(net "HSC_SCREF")
	)
	(segment
		(start 189.740794 -399.24609)
		(end 190.644018 -399.24609)
		(width 0.1524)
		(layer "In15.Cu")
		(net "HSC_SCREF")
	)
	(segment
		(start 191.070992 -399.673064)
		(end 191.070992 -403.022816)
		(width 0.1524)
		(layer "In15.Cu")
		(net "HSC_SCREF")
	)
	(segment
		(start 184.190386 -399.755106)
		(end 189.231778 -399.755106)
		(width 0.1524)
		(layer "In15.Cu")
		(net "HSC_SCREF")
	)
	(segment
		(start 193.172334 -405.124158)
		(end 193.172334 -405.257)
		(width 0.1524)
		(layer "In15.Cu")
		(net "HSC_SCREF")
	)
	(segment
		(start 189.231778 -399.755106)
		(end 189.740794 -399.24609)
		(width 0.1524)
		(layer "In15.Cu")
		(net "HSC_SCREF")
	)
	(segment
		(start 191.070992 -403.022816)
		(end 193.172334 -405.124158)
		(width 0.1524)
		(layer "In15.Cu")
		(net "HSC_SCREF")
	)
	(segment
		(start 189.80658 -401.325842)
		(end 189.76594 -401.285202)
		(width 0.1524)
		(layer "F.Cu")
		(net "HSC_ON_R")
	)
	(segment
		(start 191.01689 -401.325842)
		(end 189.80658 -401.325842)
		(width 0.1524)
		(layer "F.Cu")
		(net "HSC_ON_R")
	)
	(segment
		(start 189.356492 -401.69465)
		(end 188.516006 -401.69465)
		(width 0.1524)
		(layer "F.Cu")
		(net "HSC_ON_R")
	)
	(segment
		(start 189.76594 -401.285202)
		(end 189.356492 -401.69465)
		(width 0.1524)
		(layer "F.Cu")
		(net "HSC_ON_R")
	)
	(via
		(at 189.76594 -401.285202)
		(size 0.762)
		(drill 0.254)
		(layers "F.Cu" "B.Cu")
		(net "HSC_ON_R")
	)
	(segment
		(start 224.3201 -401.670266)
		(end 224.3201 -403.069044)
		(width 0.1524)
		(layer "F.Cu")
		(net "HSC_ON")
	)
	(segment
		(start 203.935838 -404.020782)
		(end 204.36205 -404.020782)
		(width 0.1524)
		(layer "F.Cu")
		(net "HSC_ON")
	)
	(segment
		(start 213.6521 -401.670266)
		(end 212.442044 -401.670266)
		(width 0.1524)
		(layer "F.Cu")
		(net "HSC_ON")
	)
	(segment
		(start 215.03005 -404.020782)
		(end 214.600282 -404.020782)
		(width 0.1524)
		(layer "F.Cu")
		(net "HSC_ON")
	)
	(segment
		(start 191.81699 -401.325842)
		(end 192.4431 -401.325842)
		(width 0.1524)
		(layer "F.Cu")
		(net "HSC_ON")
	)
	(segment
		(start 233.778044 -401.670266)
		(end 235.1151 -401.670266)
		(width 0.1524)
		(layer "F.Cu")
		(net "HSC_ON")
	)
	(segment
		(start 225.271838 -404.020782)
		(end 225.69805 -404.020782)
		(width 0.1524)
		(layer "F.Cu")
		(net "HSC_ON")
	)
	(segment
		(start 214.600282 -404.020782)
		(end 213.6521 -403.0726)
		(width 0.1524)
		(layer "F.Cu")
		(net "HSC_ON")
	)
	(segment
		(start 201.774044 -401.670266)
		(end 202.9841 -401.670266)
		(width 0.1524)
		(layer "F.Cu")
		(net "HSC_ON")
	)
	(segment
		(start 224.3201 -403.069044)
		(end 225.271838 -404.020782)
		(width 0.1524)
		(layer "F.Cu")
		(net "HSC_ON")
	)
	(segment
		(start 223.110044 -401.670266)
		(end 224.3201 -401.670266)
		(width 0.1524)
		(layer "F.Cu")
		(net "HSC_ON")
	)
	(segment
		(start 235.1151 -401.670266)
		(end 235.332016 -401.887182)
		(width 0.1524)
		(layer "F.Cu")
		(net "HSC_ON")
	)
	(segment
		(start 213.6521 -403.0726)
		(end 213.6521 -401.670266)
		(width 0.1524)
		(layer "F.Cu")
		(net "HSC_ON")
	)
	(segment
		(start 202.9841 -401.670266)
		(end 202.9841 -403.069044)
		(width 0.1524)
		(layer "F.Cu")
		(net "HSC_ON")
	)
	(segment
		(start 235.332016 -401.887182)
		(end 236.36605 -401.887182)
		(width 0.1524)
		(layer "F.Cu")
		(net "HSC_ON")
	)
	(segment
		(start 202.9841 -403.069044)
		(end 203.935838 -404.020782)
		(width 0.1524)
		(layer "F.Cu")
		(net "HSC_ON")
	)
	(via
		(at 192.4431 -401.325842)
		(size 0.508)
		(drill 0.254)
		(layers "F.Cu" "B.Cu")
		(net "HSC_ON")
	)
	(via
		(at 213.6521 -401.670266)
		(size 0.508)
		(drill 0.254)
		(layers "F.Cu" "B.Cu")
		(net "HSC_ON")
	)
	(via
		(at 235.1151 -401.670266)
		(size 0.508)
		(drill 0.254)
		(layers "F.Cu" "B.Cu")
		(net "HSC_ON")
	)
	(via
		(at 202.9841 -401.670266)
		(size 0.508)
		(drill 0.254)
		(layers "F.Cu" "B.Cu")
		(net "HSC_ON")
	)
	(via
		(at 224.3201 -401.670266)
		(size 0.508)
		(drill 0.254)
		(layers "F.Cu" "B.Cu")
		(net "HSC_ON")
	)
	(segment
		(start 233.477816 -400.032982)
		(end 235.1151 -401.670266)
		(width 0.1524)
		(layer "In13.Cu")
		(net "HSC_ON")
	)
	(segment
		(start 192.57264 -401.455382)
		(end 192.4431 -401.325842)
		(width 0.1524)
		(layer "In13.Cu")
		(net "HSC_ON")
	)
	(segment
		(start 201.843386 -399.938748)
		(end 197.474586 -399.938748)
		(width 0.1524)
		(layer "In13.Cu")
		(net "HSC_ON")
	)
	(segment
		(start 211.970874 -399.98904)
		(end 213.6521 -401.670266)
		(width 0.1524)
		(layer "In13.Cu")
		(net "HSC_ON")
	)
	(segment
		(start 193.394838 -401.455382)
		(end 192.57264 -401.455382)
		(width 0.1524)
		(layer "In13.Cu")
		(net "HSC_ON")
	)
	(segment
		(start 202.9841 -401.670266)
		(end 202.9841 -401.079462)
		(width 0.1524)
		(layer "In13.Cu")
		(net "HSC_ON")
	)
	(segment
		(start 226.313492 -401.480782)
		(end 227.761292 -400.032982)
		(width 0.1524)
		(layer "In13.Cu")
		(net "HSC_ON")
	)
	(segment
		(start 213.866984 -401.455382)
		(end 215.726772 -401.455382)
		(width 0.1524)
		(layer "In13.Cu")
		(net "HSC_ON")
	)
	(segment
		(start 224.3201 -401.670266)
		(end 224.509584 -401.480782)
		(width 0.1524)
		(layer "In13.Cu")
		(net "HSC_ON")
	)
	(segment
		(start 205.030324 -401.480782)
		(end 206.522066 -399.98904)
		(width 0.1524)
		(layer "In13.Cu")
		(net "HSC_ON")
	)
	(segment
		(start 202.9841 -401.670266)
		(end 203.173584 -401.480782)
		(width 0.1524)
		(layer "In13.Cu")
		(net "HSC_ON")
	)
	(segment
		(start 217.098372 -400.083782)
		(end 222.733616 -400.083782)
		(width 0.1524)
		(layer "In13.Cu")
		(net "HSC_ON")
	)
	(segment
		(start 213.6521 -401.670266)
		(end 213.866984 -401.455382)
		(width 0.1524)
		(layer "In13.Cu")
		(net "HSC_ON")
	)
	(segment
		(start 206.522066 -399.98904)
		(end 211.970874 -399.98904)
		(width 0.1524)
		(layer "In13.Cu")
		(net "HSC_ON")
	)
	(segment
		(start 203.173584 -401.480782)
		(end 205.030324 -401.480782)
		(width 0.1524)
		(layer "In13.Cu")
		(net "HSC_ON")
	)
	(segment
		(start 195.202048 -399.648172)
		(end 193.394838 -401.455382)
		(width 0.1524)
		(layer "In13.Cu")
		(net "HSC_ON")
	)
	(segment
		(start 197.18401 -399.648172)
		(end 195.202048 -399.648172)
		(width 0.1524)
		(layer "In13.Cu")
		(net "HSC_ON")
	)
	(segment
		(start 202.9841 -401.079462)
		(end 201.843386 -399.938748)
		(width 0.1524)
		(layer "In13.Cu")
		(net "HSC_ON")
	)
	(segment
		(start 222.733616 -400.083782)
		(end 224.3201 -401.670266)
		(width 0.1524)
		(layer "In13.Cu")
		(net "HSC_ON")
	)
	(segment
		(start 197.474586 -399.938748)
		(end 197.18401 -399.648172)
		(width 0.1524)
		(layer "In13.Cu")
		(net "HSC_ON")
	)
	(segment
		(start 224.509584 -401.480782)
		(end 226.313492 -401.480782)
		(width 0.1524)
		(layer "In13.Cu")
		(net "HSC_ON")
	)
	(segment
		(start 215.726772 -401.455382)
		(end 217.098372 -400.083782)
		(width 0.1524)
		(layer "In13.Cu")
		(net "HSC_ON")
	)
	(segment
		(start 227.761292 -400.032982)
		(end 233.477816 -400.032982)
		(width 0.1524)
		(layer "In13.Cu")
		(net "HSC_ON")
	)
	(segment
		(start 206.5401 -398.940782)
		(end 207.76946 -400.170142)
		(width 0.1524)
		(layer "F.Cu")
		(net "HSC_OCREF")
	)
	(segment
		(start 205.16215 -398.940782)
		(end 206.5401 -398.940782)
		(width 0.1524)
		(layer "F.Cu")
		(net "HSC_OCREF")
	)
	(segment
		(start 194.617848 -398.940782)
		(end 194.617848 -398.282922)
		(width 0.1524)
		(layer "F.Cu")
		(net "HSC_OCREF")
	)
	(segment
		(start 181.999636 -399.103342)
		(end 182.578502 -399.682208)
		(width 0.1524)
		(layer "F.Cu")
		(net "HSC_OCREF")
	)
	(segment
		(start 207.76946 -400.170142)
		(end 207.954372 -400.170142)
		(width 0.1524)
		(layer "F.Cu")
		(net "HSC_OCREF")
	)
	(segment
		(start 217.235532 -398.940782)
		(end 217.2081 -398.940782)
		(width 0.1524)
		(layer "F.Cu")
		(net "HSC_OCREF")
	)
	(segment
		(start 194.617848 -398.282922)
		(end 195.82384 -398.282922)
		(width 0.1524)
		(layer "F.Cu")
		(net "HSC_OCREF")
	)
	(segment
		(start 218.622372 -400.170142)
		(end 218.464892 -400.170142)
		(width 0.1524)
		(layer "F.Cu")
		(net "HSC_OCREF")
	)
	(segment
		(start 226.49815 -398.940782)
		(end 227.8761 -398.940782)
		(width 0.1524)
		(layer "F.Cu")
		(net "HSC_OCREF")
	)
	(segment
		(start 196.7611 -399.220182)
		(end 196.7611 -399.764758)
		(width 0.1524)
		(layer "F.Cu")
		(net "HSC_OCREF")
	)
	(segment
		(start 218.464892 -400.170142)
		(end 217.235532 -398.940782)
		(width 0.1524)
		(layer "F.Cu")
		(net "HSC_OCREF")
	)
	(segment
		(start 181.5846 -399.103342)
		(end 181.999636 -399.103342)
		(width 0.1524)
		(layer "F.Cu")
		(net "HSC_OCREF")
	)
	(segment
		(start 217.2081 -398.940782)
		(end 215.83015 -398.940782)
		(width 0.1524)
		(layer "F.Cu")
		(net "HSC_OCREF")
	)
	(segment
		(start 227.903532 -398.940782)
		(end 229.132892 -400.170142)
		(width 0.1524)
		(layer "F.Cu")
		(net "HSC_OCREF")
	)
	(segment
		(start 227.8761 -398.940782)
		(end 227.903532 -398.940782)
		(width 0.1524)
		(layer "F.Cu")
		(net "HSC_OCREF")
	)
	(segment
		(start 196.7611 -399.764758)
		(end 197.166484 -400.170142)
		(width 0.1524)
		(layer "F.Cu")
		(net "HSC_OCREF")
	)
	(segment
		(start 229.132892 -400.170142)
		(end 229.290372 -400.170142)
		(width 0.1524)
		(layer "F.Cu")
		(net "HSC_OCREF")
	)
	(segment
		(start 197.166484 -400.170142)
		(end 197.286372 -400.170142)
		(width 0.1524)
		(layer "F.Cu")
		(net "HSC_OCREF")
	)
	(segment
		(start 195.82384 -398.282922)
		(end 196.7611 -399.220182)
		(width 0.1524)
		(layer "F.Cu")
		(net "HSC_OCREF")
	)
	(via
		(at 227.8761 -398.940782)
		(size 0.508)
		(drill 0.254)
		(layers "F.Cu" "B.Cu")
		(net "HSC_OCREF")
	)
	(via
		(at 206.5401 -398.940782)
		(size 0.508)
		(drill 0.254)
		(layers "F.Cu" "B.Cu")
		(net "HSC_OCREF")
	)
	(via
		(at 194.617848 -398.282922)
		(size 0.508)
		(drill 0.254)
		(layers "F.Cu" "B.Cu")
		(net "HSC_OCREF")
	)
	(via
		(at 217.2081 -398.940782)
		(size 0.508)
		(drill 0.254)
		(layers "F.Cu" "B.Cu")
		(net "HSC_OCREF")
	)
	(via
		(at 181.5846 -399.103342)
		(size 0.508)
		(drill 0.254)
		(layers "F.Cu" "B.Cu")
		(net "HSC_OCREF")
	)
	(segment
		(start 206.88554 -392.500358)
		(end 216.974166 -392.500358)
		(width 0.1524)
		(layer "In4.Cu")
		(net "HSC_OCREF")
	)
	(segment
		(start 194.617848 -392.010138)
		(end 194.34556 -392.010138)
		(width 0.1524)
		(layer "In4.Cu")
		(net "HSC_OCREF")
	)
	(segment
		(start 182.547514 -391.520172)
		(end 181.00802 -393.059666)
		(width 0.1524)
		(layer "In4.Cu")
		(net "HSC_OCREF")
	)
	(segment
		(start 206.5401 -392.845798)
		(end 206.5401 -391.087102)
		(width 0.1524)
		(layer "In4.Cu")
		(net "HSC_OCREF")
	)
	(segment
		(start 195.281804 -390.582658)
		(end 194.617848 -391.246614)
		(width 0.1524)
		(layer "In4.Cu")
		(net "HSC_OCREF")
	)
	(segment
		(start 194.617848 -398.282922)
		(end 194.617848 -392.010138)
		(width 0.1524)
		(layer "In4.Cu")
		(net "HSC_OCREF")
	)
	(segment
		(start 217.2081 -392.734292)
		(end 217.2081 -398.940782)
		(width 0.1524)
		(layer "In4.Cu")
		(net "HSC_OCREF")
	)
	(segment
		(start 206.035656 -390.582658)
		(end 195.281804 -390.582658)
		(width 0.1524)
		(layer "In4.Cu")
		(net "HSC_OCREF")
	)
	(segment
		(start 194.617848 -391.246614)
		(end 194.617848 -392.010138)
		(width 0.1524)
		(layer "In4.Cu")
		(net "HSC_OCREF")
	)
	(segment
		(start 181.00802 -398.330674)
		(end 181.5846 -398.907254)
		(width 0.1524)
		(layer "In4.Cu")
		(net "HSC_OCREF")
	)
	(segment
		(start 181.00802 -393.059666)
		(end 181.00802 -398.330674)
		(width 0.1524)
		(layer "In4.Cu")
		(net "HSC_OCREF")
	)
	(segment
		(start 217.464386 -392.478006)
		(end 226.78771 -392.478006)
		(width 0.1524)
		(layer "In4.Cu")
		(net "HSC_OCREF")
	)
	(segment
		(start 206.5401 -392.845798)
		(end 206.88554 -392.500358)
		(width 0.1524)
		(layer "In4.Cu")
		(net "HSC_OCREF")
	)
	(segment
		(start 217.2081 -392.734292)
		(end 217.464386 -392.478006)
		(width 0.1524)
		(layer "In4.Cu")
		(net "HSC_OCREF")
	)
	(segment
		(start 227.8761 -393.566396)
		(end 227.8761 -398.940782)
		(width 0.1524)
		(layer "In4.Cu")
		(net "HSC_OCREF")
	)
	(segment
		(start 206.5401 -391.087102)
		(end 206.035656 -390.582658)
		(width 0.1524)
		(layer "In4.Cu")
		(net "HSC_OCREF")
	)
	(segment
		(start 181.5846 -398.907254)
		(end 181.5846 -399.103342)
		(width 0.1524)
		(layer "In4.Cu")
		(net "HSC_OCREF")
	)
	(segment
		(start 193.855594 -391.520172)
		(end 182.547514 -391.520172)
		(width 0.1524)
		(layer "In4.Cu")
		(net "HSC_OCREF")
	)
	(segment
		(start 194.34556 -392.010138)
		(end 193.855594 -391.520172)
		(width 0.1524)
		(layer "In4.Cu")
		(net "HSC_OCREF")
	)
	(segment
		(start 216.974166 -392.500358)
		(end 217.2081 -392.734292)
		(width 0.1524)
		(layer "In4.Cu")
		(net "HSC_OCREF")
	)
	(segment
		(start 206.5401 -392.845798)
		(end 206.5401 -398.940782)
		(width 0.1524)
		(layer "In4.Cu")
		(net "HSC_OCREF")
	)
	(segment
		(start 226.78771 -392.478006)
		(end 227.8761 -393.566396)
		(width 0.1524)
		(layer "In4.Cu")
		(net "HSC_OCREF")
	)
	(segment
		(start 233.778044 -403.170136)
		(end 234.259882 -403.170136)
		(width 0.10668)
		(layer "F.Cu")
		(net "HSC_NC1_4")
	)
	(segment
		(start 238.295434 -403.644862)
		(end 238.295434 -404.99411)
		(width 0.10668)
		(layer "F.Cu")
		(net "HSC_NC1_4")
	)
	(segment
		(start 234.809792 -403.720046)
		(end 235.444284 -403.720046)
		(width 0.10668)
		(layer "F.Cu")
		(net "HSC_NC1_4")
	)
	(segment
		(start 235.444284 -403.720046)
		(end 235.76915 -403.39518)
		(width 0.10668)
		(layer "F.Cu")
		(net "HSC_NC1_4")
	)
	(segment
		(start 234.259882 -403.170136)
		(end 234.809792 -403.720046)
		(width 0.10668)
		(layer "F.Cu")
		(net "HSC_NC1_4")
	)
	(segment
		(start 235.76915 -403.39518)
		(end 238.045752 -403.39518)
		(width 0.10668)
		(layer "F.Cu")
		(net "HSC_NC1_4")
	)
	(segment
		(start 238.295434 -404.99411)
		(end 238.18977 -405.099774)
		(width 0.10668)
		(layer "F.Cu")
		(net "HSC_NC1_4")
	)
	(segment
		(start 238.045752 -403.39518)
		(end 238.295434 -403.644862)
		(width 0.10668)
		(layer "F.Cu")
		(net "HSC_NC1_4")
	)
	(via
		(at 238.18977 -405.099774)
		(size 0.762)
		(drill 0.381)
		(layers "F.Cu" "B.Cu")
		(net "HSC_NC1_4")
	)
	(segment
		(start 223.782382 -405.363172)
		(end 224.493074 -406.073864)
		(width 0.10668)
		(layer "F.Cu")
		(net "HSC_NC1_3")
	)
	(segment
		(start 223.258634 -403.170136)
		(end 223.782382 -403.693884)
		(width 0.10668)
		(layer "F.Cu")
		(net "HSC_NC1_3")
	)
	(segment
		(start 223.110044 -403.170136)
		(end 223.258634 -403.170136)
		(width 0.10668)
		(layer "F.Cu")
		(net "HSC_NC1_3")
	)
	(segment
		(start 223.782382 -403.693884)
		(end 223.782382 -405.363172)
		(width 0.10668)
		(layer "F.Cu")
		(net "HSC_NC1_3")
	)
	(via
		(at 224.493074 -406.073864)
		(size 0.762)
		(drill 0.381)
		(layers "F.Cu" "B.Cu")
		(net "HSC_NC1_3")
	)
	(segment
		(start 212.598762 -403.170136)
		(end 212.442044 -403.170136)
		(width 0.10668)
		(layer "F.Cu")
		(net "HSC_NC1_2")
	)
	(segment
		(start 213.830154 -406.083262)
		(end 213.090252 -405.34336)
		(width 0.10668)
		(layer "F.Cu")
		(net "HSC_NC1_2")
	)
	(segment
		(start 213.090252 -405.34336)
		(end 213.090252 -403.661626)
		(width 0.10668)
		(layer "F.Cu")
		(net "HSC_NC1_2")
	)
	(segment
		(start 213.090252 -403.661626)
		(end 212.598762 -403.170136)
		(width 0.10668)
		(layer "F.Cu")
		(net "HSC_NC1_2")
	)
	(via
		(at 213.830154 -406.083262)
		(size 0.762)
		(drill 0.381)
		(layers "F.Cu" "B.Cu")
		(net "HSC_NC1_2")
	)
	(segment
		(start 201.91349 -403.170136)
		(end 202.451208 -403.707854)
		(width 0.10668)
		(layer "F.Cu")
		(net "HSC_NC1_1")
	)
	(segment
		(start 202.451208 -403.707854)
		(end 202.451208 -405.382984)
		(width 0.10668)
		(layer "F.Cu")
		(net "HSC_NC1_1")
	)
	(segment
		(start 202.451208 -405.382984)
		(end 203.14285 -406.074626)
		(width 0.10668)
		(layer "F.Cu")
		(net "HSC_NC1_1")
	)
	(segment
		(start 201.774044 -403.170136)
		(end 201.91349 -403.170136)
		(width 0.10668)
		(layer "F.Cu")
		(net "HSC_NC1_1")
	)
	(via
		(at 203.14285 -406.074626)
		(size 0.762)
		(drill 0.381)
		(layers "F.Cu" "B.Cu")
		(net "HSC_NC1_1")
	)
	(segment
		(start 235.134404 -404.434294)
		(end 235.850938 -404.434294)
		(width 0.1524)
		(layer "F.Cu")
		(net "HSC_MODE_4")
	)
	(segment
		(start 233.996992 -403.670262)
		(end 234.761024 -404.434294)
		(width 0.1524)
		(layer "F.Cu")
		(net "HSC_MODE_4")
	)
	(segment
		(start 235.850938 -404.434294)
		(end 236.36605 -403.919182)
		(width 0.1524)
		(layer "F.Cu")
		(net "HSC_MODE_4")
	)
	(segment
		(start 234.761024 -404.434294)
		(end 235.134404 -404.434294)
		(width 0.1524)
		(layer "F.Cu")
		(net "HSC_MODE_4")
	)
	(segment
		(start 233.790744 -403.670262)
		(end 233.996992 -403.670262)
		(width 0.1524)
		(layer "F.Cu")
		(net "HSC_MODE_4")
	)
	(via
		(at 235.134404 -404.434294)
		(size 0.762)
		(drill 0.381)
		(layers "F.Cu" "B.Cu")
		(net "HSC_MODE_4")
	)
	(segment
		(start 223.398842 -403.822662)
		(end 223.246442 -403.670262)
		(width 0.1524)
		(layer "F.Cu")
		(net "HSC_MODE_3")
	)
	(segment
		(start 225.57105 -407.195782)
		(end 224.697544 -407.195782)
		(width 0.1524)
		(layer "F.Cu")
		(net "HSC_MODE_3")
	)
	(segment
		(start 224.697544 -407.195782)
		(end 224.51187 -407.381456)
		(width 0.1524)
		(layer "F.Cu")
		(net "HSC_MODE_3")
	)
	(segment
		(start 224.51187 -407.381456)
		(end 223.398842 -406.268428)
		(width 0.1524)
		(layer "F.Cu")
		(net "HSC_MODE_3")
	)
	(segment
		(start 225.69805 -407.068782)
		(end 225.57105 -407.195782)
		(width 0.1524)
		(layer "F.Cu")
		(net "HSC_MODE_3")
	)
	(segment
		(start 223.246442 -403.670262)
		(end 223.122744 -403.670262)
		(width 0.1524)
		(layer "F.Cu")
		(net "HSC_MODE_3")
	)
	(segment
		(start 223.398842 -406.268428)
		(end 223.398842 -403.822662)
		(width 0.1524)
		(layer "F.Cu")
		(net "HSC_MODE_3")
	)
	(via
		(at 224.51187 -407.381456)
		(size 0.762)
		(drill 0.381)
		(layers "F.Cu" "B.Cu")
		(net "HSC_MODE_3")
	)
	(segment
		(start 214.03818 -407.195782)
		(end 213.848696 -407.385266)
		(width 0.1524)
		(layer "F.Cu")
		(net "HSC_MODE_2")
	)
	(segment
		(start 215.03005 -407.068782)
		(end 214.90305 -407.195782)
		(width 0.1524)
		(layer "F.Cu")
		(net "HSC_MODE_2")
	)
	(segment
		(start 212.706712 -403.822662)
		(end 212.554312 -403.670262)
		(width 0.1524)
		(layer "F.Cu")
		(net "HSC_MODE_2")
	)
	(segment
		(start 214.90305 -407.195782)
		(end 214.03818 -407.195782)
		(width 0.1524)
		(layer "F.Cu")
		(net "HSC_MODE_2")
	)
	(segment
		(start 212.706712 -406.243282)
		(end 212.706712 -403.822662)
		(width 0.1524)
		(layer "F.Cu")
		(net "HSC_MODE_2")
	)
	(segment
		(start 213.848696 -407.385266)
		(end 212.706712 -406.243282)
		(width 0.1524)
		(layer "F.Cu")
		(net "HSC_MODE_2")
	)
	(segment
		(start 212.554312 -403.670262)
		(end 212.454744 -403.670262)
		(width 0.1524)
		(layer "F.Cu")
		(net "HSC_MODE_2")
	)
	(via
		(at 213.848696 -407.385266)
		(size 0.762)
		(drill 0.381)
		(layers "F.Cu" "B.Cu")
		(net "HSC_MODE_2")
	)
	(segment
		(start 203.349352 -407.195782)
		(end 204.23505 -407.195782)
		(width 0.1524)
		(layer "F.Cu")
		(net "HSC_MODE_1")
	)
	(segment
		(start 204.23505 -407.195782)
		(end 204.36205 -407.068782)
		(width 0.1524)
		(layer "F.Cu")
		(net "HSC_MODE_1")
	)
	(segment
		(start 203.171552 -407.373582)
		(end 203.349352 -407.195782)
		(width 0.1524)
		(layer "F.Cu")
		(net "HSC_MODE_1")
	)
	(segment
		(start 201.786744 -403.670262)
		(end 201.915268 -403.670262)
		(width 0.1524)
		(layer "F.Cu")
		(net "HSC_MODE_1")
	)
	(segment
		(start 201.915268 -403.670262)
		(end 202.067668 -403.822662)
		(width 0.1524)
		(layer "F.Cu")
		(net "HSC_MODE_1")
	)
	(segment
		(start 202.067668 -406.269698)
		(end 203.171552 -407.373582)
		(width 0.1524)
		(layer "F.Cu")
		(net "HSC_MODE_1")
	)
	(segment
		(start 202.067668 -403.822662)
		(end 202.067668 -406.269698)
		(width 0.1524)
		(layer "F.Cu")
		(net "HSC_MODE_1")
	)
	(via
		(at 203.171552 -407.373582)
		(size 0.762)
		(drill 0.381)
		(layers "F.Cu" "B.Cu")
		(net "HSC_MODE_1")
	)
	(segment
		(start 188.874146 -403.04466)
		(end 188.516006 -403.04466)
		(width 0.1524)
		(layer "F.Cu")
		(net "HSC_MODE")
	)
	(segment
		(start 191.01689 -403.611842)
		(end 191.01689 -403.631146)
		(width 0.1524)
		(layer "F.Cu")
		(net "HSC_MODE")
	)
	(segment
		(start 190.288418 -404.359618)
		(end 189.820804 -404.359618)
		(width 0.1524)
		(layer "F.Cu")
		(net "HSC_MODE")
	)
	(segment
		(start 189.05855 -403.229064)
		(end 188.874146 -403.04466)
		(width 0.1524)
		(layer "F.Cu")
		(net "HSC_MODE")
	)
	(segment
		(start 191.01689 -403.631146)
		(end 190.288418 -404.359618)
		(width 0.1524)
		(layer "F.Cu")
		(net "HSC_MODE")
	)
	(segment
		(start 189.820804 -404.359618)
		(end 189.05855 -403.597364)
		(width 0.1524)
		(layer "F.Cu")
		(net "HSC_MODE")
	)
	(segment
		(start 189.05855 -403.597364)
		(end 189.05855 -403.229064)
		(width 0.1524)
		(layer "F.Cu")
		(net "HSC_MODE")
	)
	(via
		(at 190.288418 -404.359618)
		(size 0.508)
		(drill 0.254)
		(layers "F.Cu" "B.Cu")
		(net "HSC_MODE")
	)
	(segment
		(start 206.5401 -401.17014)
		(end 207.967072 -401.17014)
		(width 0.1524)
		(layer "F.Cu")
		(net "HSC_IMON")
	)
	(segment
		(start 226.49815 -401.988782)
		(end 226.707954 -401.988782)
		(width 0.1524)
		(layer "F.Cu")
		(net "HSC_IMON")
	)
	(segment
		(start 194.9069 -400.998182)
		(end 195.2625 -400.642582)
		(width 0.1524)
		(layer "F.Cu")
		(net "HSC_IMON")
	)
	(segment
		(start 179.11699 -397.388842)
		(end 179.11699 -398.404842)
		(width 0.1524)
		(layer "F.Cu")
		(net "HSC_IMON")
	)
	(segment
		(start 217.2081 -401.17014)
		(end 216.858596 -401.17014)
		(width 0.1524)
		(layer "F.Cu")
		(net "HSC_IMON")
	)
	(segment
		(start 196.475858 -401.17014)
		(end 197.299072 -401.17014)
		(width 0.1524)
		(layer "F.Cu")
		(net "HSC_IMON")
	)
	(segment
		(start 195.2625 -400.642582)
		(end 195.9483 -400.642582)
		(width 0.1524)
		(layer "F.Cu")
		(net "HSC_IMON")
	)
	(segment
		(start 205.16215 -401.988782)
		(end 205.295246 -401.988782)
		(width 0.1524)
		(layer "F.Cu")
		(net "HSC_IMON")
	)
	(segment
		(start 206.113888 -401.17014)
		(end 206.5401 -401.17014)
		(width 0.1524)
		(layer "F.Cu")
		(net "HSC_IMON")
	)
	(segment
		(start 180.084476 -398.400778)
		(end 180.76164 -399.077942)
		(width 0.1524)
		(layer "F.Cu")
		(net "HSC_IMON")
	)
	(segment
		(start 227.526596 -401.17014)
		(end 227.8761 -401.17014)
		(width 0.1524)
		(layer "F.Cu")
		(net "HSC_IMON")
	)
	(segment
		(start 216.858596 -401.17014)
		(end 216.039954 -401.988782)
		(width 0.1524)
		(layer "F.Cu")
		(net "HSC_IMON")
	)
	(segment
		(start 226.707954 -401.988782)
		(end 227.526596 -401.17014)
		(width 0.1524)
		(layer "F.Cu")
		(net "HSC_IMON")
	)
	(segment
		(start 181.804818 -400.34464)
		(end 182.041038 -400.34464)
		(width 0.1524)
		(layer "F.Cu")
		(net "HSC_IMON")
	)
	(segment
		(start 180.76164 -399.077942)
		(end 180.76164 -399.301462)
		(width 0.1524)
		(layer "F.Cu")
		(net "HSC_IMON")
	)
	(segment
		(start 195.9483 -400.642582)
		(end 196.475858 -401.17014)
		(width 0.1524)
		(layer "F.Cu")
		(net "HSC_IMON")
	)
	(segment
		(start 180.080412 -398.404842)
		(end 180.084476 -398.400778)
		(width 0.1524)
		(layer "F.Cu")
		(net "HSC_IMON")
	)
	(segment
		(start 205.295246 -401.988782)
		(end 206.113888 -401.17014)
		(width 0.1524)
		(layer "F.Cu")
		(net "HSC_IMON")
	)
	(segment
		(start 179.11699 -398.404842)
		(end 180.080412 -398.404842)
		(width 0.1524)
		(layer "F.Cu")
		(net "HSC_IMON")
	)
	(segment
		(start 216.039954 -401.988782)
		(end 215.83015 -401.988782)
		(width 0.1524)
		(layer "F.Cu")
		(net "HSC_IMON")
	)
	(segment
		(start 227.8761 -401.17014)
		(end 229.303072 -401.17014)
		(width 0.1524)
		(layer "F.Cu")
		(net "HSC_IMON")
	)
	(segment
		(start 180.76164 -399.301462)
		(end 181.804818 -400.34464)
		(width 0.1524)
		(layer "F.Cu")
		(net "HSC_IMON")
	)
	(segment
		(start 194.62115 -400.998182)
		(end 194.9069 -400.998182)
		(width 0.1524)
		(layer "F.Cu")
		(net "HSC_IMON")
	)
	(segment
		(start 218.635072 -401.17014)
		(end 217.2081 -401.17014)
		(width 0.1524)
		(layer "F.Cu")
		(net "HSC_IMON")
	)
	(via
		(at 206.5401 -401.17014)
		(size 0.508)
		(drill 0.254)
		(layers "F.Cu" "B.Cu")
		(net "HSC_IMON")
	)
	(via
		(at 195.9483 -400.642582)
		(size 0.508)
		(drill 0.254)
		(layers "F.Cu" "B.Cu")
		(net "HSC_IMON")
	)
	(via
		(at 217.2081 -401.17014)
		(size 0.508)
		(drill 0.254)
		(layers "F.Cu" "B.Cu")
		(net "HSC_IMON")
	)
	(via
		(at 180.084476 -398.400778)
		(size 0.762)
		(drill 0.254)
		(layers "F.Cu" "B.Cu")
		(net "HSC_IMON")
	)
	(via
		(at 227.8761 -401.17014)
		(size 0.508)
		(drill 0.254)
		(layers "F.Cu" "B.Cu")
		(net "HSC_IMON")
	)
	(segment
		(start 195.9483 -400.642582)
		(end 195.9483 -391.620756)
		(width 0.1524)
		(layer "In4.Cu")
		(net "HSC_IMON")
	)
	(segment
		(start 218.153996 -393.480798)
		(end 226.527614 -393.480798)
		(width 0.1524)
		(layer "In4.Cu")
		(net "HSC_IMON")
	)
	(segment
		(start 180.76164 -399.077942)
		(end 180.084476 -398.400778)
		(width 0.1524)
		(layer "In4.Cu")
		(net "HSC_IMON")
	)
	(segment
		(start 205.74 -399.11782)
		(end 206.5401 -399.91792)
		(width 0.1524)
		(layer "In4.Cu")
		(net "HSC_IMON")
	)
	(segment
		(start 205.74 -398.53616)
		(end 205.74 -399.11782)
		(width 0.1524)
		(layer "In4.Cu")
		(net "HSC_IMON")
	)
	(segment
		(start 205.09992 -397.89608)
		(end 205.74 -398.53616)
		(width 0.1524)
		(layer "In4.Cu")
		(net "HSC_IMON")
	)
	(segment
		(start 196.0753 -391.493756)
		(end 204.97292 -391.493756)
		(width 0.1524)
		(layer "In4.Cu")
		(net "HSC_IMON")
	)
	(segment
		(start 182.404766 -394.01242)
		(end 182.404766 -399.504154)
		(width 0.1524)
		(layer "In4.Cu")
		(net "HSC_IMON")
	)
	(segment
		(start 217.93962 -400.43862)
		(end 217.93962 -393.695174)
		(width 0.1524)
		(layer "In4.Cu")
		(net "HSC_IMON")
	)
	(segment
		(start 215.162384 -393.33043)
		(end 207.575658 -393.33043)
		(width 0.1524)
		(layer "In4.Cu")
		(net "HSC_IMON")
	)
	(segment
		(start 217.2081 -401.17014)
		(end 217.93962 -400.43862)
		(width 0.1524)
		(layer "In4.Cu")
		(net "HSC_IMON")
	)
	(segment
		(start 193.76644 -393.451334)
		(end 193.327274 -393.012168)
		(width 0.1524)
		(layer "In4.Cu")
		(net "HSC_IMON")
	)
	(segment
		(start 180.76164 -399.415254)
		(end 180.76164 -399.077942)
		(width 0.1524)
		(layer "In4.Cu")
		(net "HSC_IMON")
	)
	(segment
		(start 227.8761 -399.83156)
		(end 227.8761 -401.17014)
		(width 0.1524)
		(layer "In4.Cu")
		(net "HSC_IMON")
	)
	(segment
		(start 217.2081 -399.95856)
		(end 215.58885 -398.33931)
		(width 0.1524)
		(layer "In4.Cu")
		(net "HSC_IMON")
	)
	(segment
		(start 193.327274 -393.012168)
		(end 183.405018 -393.012168)
		(width 0.1524)
		(layer "In4.Cu")
		(net "HSC_IMON")
	)
	(segment
		(start 226.527614 -393.480798)
		(end 226.983544 -393.936728)
		(width 0.1524)
		(layer "In4.Cu")
		(net "HSC_IMON")
	)
	(segment
		(start 226.983544 -393.936728)
		(end 226.983544 -398.939004)
		(width 0.1524)
		(layer "In4.Cu")
		(net "HSC_IMON")
	)
	(segment
		(start 207.2386 -393.667488)
		(end 207.2386 -400.47164)
		(width 0.1524)
		(layer "In4.Cu")
		(net "HSC_IMON")
	)
	(segment
		(start 195.9483 -391.620756)
		(end 196.0753 -391.493756)
		(width 0.1524)
		(layer "In4.Cu")
		(net "HSC_IMON")
	)
	(segment
		(start 205.09992 -391.620756)
		(end 205.09992 -397.89608)
		(width 0.1524)
		(layer "In4.Cu")
		(net "HSC_IMON")
	)
	(segment
		(start 215.58885 -398.33931)
		(end 215.58885 -393.756896)
		(width 0.1524)
		(layer "In4.Cu")
		(net "HSC_IMON")
	)
	(segment
		(start 207.2386 -400.47164)
		(end 206.5401 -401.17014)
		(width 0.1524)
		(layer "In4.Cu")
		(net "HSC_IMON")
	)
	(segment
		(start 217.2081 -401.17014)
		(end 217.2081 -399.95856)
		(width 0.1524)
		(layer "In4.Cu")
		(net "HSC_IMON")
	)
	(segment
		(start 206.5401 -399.91792)
		(end 206.5401 -401.17014)
		(width 0.1524)
		(layer "In4.Cu")
		(net "HSC_IMON")
	)
	(segment
		(start 195.9483 -400.642582)
		(end 195.791836 -400.642582)
		(width 0.1524)
		(layer "In4.Cu")
		(net "HSC_IMON")
	)
	(segment
		(start 183.405018 -393.012168)
		(end 182.404766 -394.01242)
		(width 0.1524)
		(layer "In4.Cu")
		(net "HSC_IMON")
	)
	(segment
		(start 204.97292 -391.493756)
		(end 205.09992 -391.620756)
		(width 0.1524)
		(layer "In4.Cu")
		(net "HSC_IMON")
	)
	(segment
		(start 193.76644 -398.617186)
		(end 193.76644 -393.451334)
		(width 0.1524)
		(layer "In4.Cu")
		(net "HSC_IMON")
	)
	(segment
		(start 182.404766 -399.504154)
		(end 182.06212 -399.8468)
		(width 0.1524)
		(layer "In4.Cu")
		(net "HSC_IMON")
	)
	(segment
		(start 195.791836 -400.642582)
		(end 193.76644 -398.617186)
		(width 0.1524)
		(layer "In4.Cu")
		(net "HSC_IMON")
	)
	(segment
		(start 215.58885 -393.756896)
		(end 215.162384 -393.33043)
		(width 0.1524)
		(layer "In4.Cu")
		(net "HSC_IMON")
	)
	(segment
		(start 217.93962 -393.695174)
		(end 218.153996 -393.480798)
		(width 0.1524)
		(layer "In4.Cu")
		(net "HSC_IMON")
	)
	(segment
		(start 181.193186 -399.8468)
		(end 180.76164 -399.415254)
		(width 0.1524)
		(layer "In4.Cu")
		(net "HSC_IMON")
	)
	(segment
		(start 207.575658 -393.33043)
		(end 207.2386 -393.667488)
		(width 0.1524)
		(layer "In4.Cu")
		(net "HSC_IMON")
	)
	(segment
		(start 182.06212 -399.8468)
		(end 181.193186 -399.8468)
		(width 0.1524)
		(layer "In4.Cu")
		(net "HSC_IMON")
	)
	(segment
		(start 226.983544 -398.939004)
		(end 227.8761 -399.83156)
		(width 0.1524)
		(layer "In4.Cu")
		(net "HSC_IMON")
	)
	(segment
		(start 235.2421 -402.903182)
		(end 236.36605 -402.903182)
		(width 0.10668)
		(layer "F.Cu")
		(net "HSC_FLT_TYPE_4")
	)
	(segment
		(start 233.778044 -402.670264)
		(end 234.041188 -402.670264)
		(width 0.10668)
		(layer "F.Cu")
		(net "HSC_FLT_TYPE_4")
	)
	(segment
		(start 235.1151 -403.030182)
		(end 235.2421 -402.903182)
		(width 0.10668)
		(layer "F.Cu")
		(net "HSC_FLT_TYPE_4")
	)
	(segment
		(start 234.126024 -402.7551)
		(end 234.840018 -402.7551)
		(width 0.10668)
		(layer "F.Cu")
		(net "HSC_FLT_TYPE_4")
	)
	(segment
		(start 234.041188 -402.670264)
		(end 234.126024 -402.7551)
		(width 0.10668)
		(layer "F.Cu")
		(net "HSC_FLT_TYPE_4")
	)
	(segment
		(start 234.840018 -402.7551)
		(end 235.1151 -403.030182)
		(width 0.10668)
		(layer "F.Cu")
		(net "HSC_FLT_TYPE_4")
	)
	(via
		(at 235.1151 -403.030182)
		(size 0.762)
		(drill 0.381)
		(layers "F.Cu" "B.Cu")
		(net "HSC_FLT_TYPE_4")
	)
	(segment
		(start 224.502726 -403.898354)
		(end 223.274636 -402.670264)
		(width 0.10668)
		(layer "F.Cu")
		(net "HSC_FLT_TYPE_3")
	)
	(segment
		(start 225.69805 -406.052782)
		(end 225.447606 -406.052782)
		(width 0.10668)
		(layer "F.Cu")
		(net "HSC_FLT_TYPE_3")
	)
	(segment
		(start 225.447606 -406.052782)
		(end 224.502726 -405.107902)
		(width 0.10668)
		(layer "F.Cu")
		(net "HSC_FLT_TYPE_3")
	)
	(segment
		(start 224.502726 -404.273766)
		(end 224.502726 -403.898354)
		(width 0.10668)
		(layer "F.Cu")
		(net "HSC_FLT_TYPE_3")
	)
	(segment
		(start 224.502726 -405.107902)
		(end 224.502726 -404.273766)
		(width 0.10668)
		(layer "F.Cu")
		(net "HSC_FLT_TYPE_3")
	)
	(segment
		(start 223.274636 -402.670264)
		(end 223.110044 -402.670264)
		(width 0.10668)
		(layer "F.Cu")
		(net "HSC_FLT_TYPE_3")
	)
	(via
		(at 224.502726 -404.273766)
		(size 0.762)
		(drill 0.381)
		(layers "F.Cu" "B.Cu")
		(net "HSC_FLT_TYPE_3")
	)
	(segment
		(start 214.779606 -406.052782)
		(end 213.81085 -405.084026)
		(width 0.10668)
		(layer "F.Cu")
		(net "HSC_FLT_TYPE_2")
	)
	(segment
		(start 212.623908 -402.670264)
		(end 212.442044 -402.670264)
		(width 0.10668)
		(layer "F.Cu")
		(net "HSC_FLT_TYPE_2")
	)
	(segment
		(start 213.81085 -404.259796)
		(end 213.81085 -403.857206)
		(width 0.10668)
		(layer "F.Cu")
		(net "HSC_FLT_TYPE_2")
	)
	(segment
		(start 215.03005 -406.052782)
		(end 214.779606 -406.052782)
		(width 0.10668)
		(layer "F.Cu")
		(net "HSC_FLT_TYPE_2")
	)
	(segment
		(start 213.81085 -405.084026)
		(end 213.81085 -404.259796)
		(width 0.10668)
		(layer "F.Cu")
		(net "HSC_FLT_TYPE_2")
	)
	(segment
		(start 213.81085 -403.857206)
		(end 212.623908 -402.670264)
		(width 0.10668)
		(layer "F.Cu")
		(net "HSC_FLT_TYPE_2")
	)
	(via
		(at 213.81085 -404.259796)
		(size 0.762)
		(drill 0.381)
		(layers "F.Cu" "B.Cu")
		(net "HSC_FLT_TYPE_2")
	)
	(segment
		(start 201.774044 -402.670264)
		(end 201.92492 -402.670264)
		(width 0.10668)
		(layer "F.Cu")
		(net "HSC_FLT_TYPE_1")
	)
	(segment
		(start 203.14285 -404.240492)
		(end 203.14285 -405.084026)
		(width 0.10668)
		(layer "F.Cu")
		(net "HSC_FLT_TYPE_1")
	)
	(segment
		(start 203.14285 -405.084026)
		(end 204.111606 -406.052782)
		(width 0.10668)
		(layer "F.Cu")
		(net "HSC_FLT_TYPE_1")
	)
	(segment
		(start 201.92492 -402.670264)
		(end 203.14285 -403.888194)
		(width 0.10668)
		(layer "F.Cu")
		(net "HSC_FLT_TYPE_1")
	)
	(segment
		(start 203.14285 -403.888194)
		(end 203.14285 -404.240492)
		(width 0.10668)
		(layer "F.Cu")
		(net "HSC_FLT_TYPE_1")
	)
	(segment
		(start 204.111606 -406.052782)
		(end 204.36205 -406.052782)
		(width 0.10668)
		(layer "F.Cu")
		(net "HSC_FLT_TYPE_1")
	)
	(via
		(at 203.14285 -404.240492)
		(size 0.762)
		(drill 0.381)
		(layers "F.Cu" "B.Cu")
		(net "HSC_FLT_TYPE_1")
	)
	(segment
		(start 189.77864 -403.294342)
		(end 189.07887 -402.594572)
		(width 0.10668)
		(layer "F.Cu")
		(net "HSC_FLT_TYPE")
	)
	(segment
		(start 226.49815 -406.052782)
		(end 227.1141 -406.052782)
		(width 0.10668)
		(layer "F.Cu")
		(net "HSC_FLT_TYPE")
	)
	(segment
		(start 237.16615 -402.903182)
		(end 237.7821 -402.903182)
		(width 0.10668)
		(layer "F.Cu")
		(net "HSC_FLT_TYPE")
	)
	(segment
		(start 215.83015 -406.052782)
		(end 216.4461 -406.052782)
		(width 0.10668)
		(layer "F.Cu")
		(net "HSC_FLT_TYPE")
	)
	(segment
		(start 205.16215 -406.052782)
		(end 205.7781 -406.052782)
		(width 0.1524)
		(layer "F.Cu")
		(net "HSC_FLT_TYPE")
	)
	(segment
		(start 189.07887 -402.594572)
		(end 188.516006 -402.594572)
		(width 0.10668)
		(layer "F.Cu")
		(net "HSC_FLT_TYPE")
	)
	(via
		(at 205.7781 -406.052782)
		(size 0.508)
		(drill 0.254)
		(layers "F.Cu" "B.Cu")
		(net "HSC_FLT_TYPE")
	)
	(via
		(at 227.1141 -406.052782)
		(size 0.508)
		(drill 0.254)
		(layers "F.Cu" "B.Cu")
		(net "HSC_FLT_TYPE")
	)
	(via
		(at 216.4461 -406.052782)
		(size 0.508)
		(drill 0.254)
		(layers "F.Cu" "B.Cu")
		(net "HSC_FLT_TYPE")
	)
	(via
		(at 189.77864 -403.294342)
		(size 0.762)
		(drill 0.254)
		(layers "F.Cu" "B.Cu")
		(net "HSC_FLT_TYPE")
	)
	(via
		(at 237.7821 -402.903182)
		(size 0.508)
		(drill 0.254)
		(layers "F.Cu" "B.Cu")
		(net "HSC_FLT_TYPE")
	)
	(segment
		(start 224.278952 -407.78557)
		(end 226.01174 -406.052782)
		(width 0.1524)
		(layer "In4.Cu")
		(net "HSC_FLT_TYPE")
	)
	(segment
		(start 192.38722 -405.20112)
		(end 192.938908 -404.649432)
		(width 0.1524)
		(layer "In4.Cu")
		(net "HSC_FLT_TYPE")
	)
	(segment
		(start 195.18376 -411.094682)
		(end 202.01636 -411.094682)
		(width 0.1524)
		(layer "In4.Cu")
		(net "HSC_FLT_TYPE")
	)
	(segment
		(start 203.01458 -410.096462)
		(end 203.01458 -407.604722)
		(width 0.1524)
		(layer "In4.Cu")
		(net "HSC_FLT_TYPE")
	)
	(segment
		(start 224.139252 -411.02407)
		(end 224.278952 -410.88437)
		(width 0.1524)
		(layer "In4.Cu")
		(net "HSC_FLT_TYPE")
	)
	(segment
		(start 216.4461 -406.052782)
		(end 215.37422 -406.052782)
		(width 0.1524)
		(layer "In4.Cu")
		(net "HSC_FLT_TYPE")
	)
	(segment
		(start 189.77864 -403.294342)
		(end 190.132208 -403.294342)
		(width 0.1524)
		(layer "In4.Cu")
		(net "HSC_FLT_TYPE")
	)
	(segment
		(start 236.530642 -404.15464)
		(end 236.530642 -406.805638)
		(width 0.1524)
		(layer "In4.Cu")
		(net "HSC_FLT_TYPE")
	)
	(segment
		(start 204.56652 -406.052782)
		(end 205.7781 -406.052782)
		(width 0.1524)
		(layer "In4.Cu")
		(net "HSC_FLT_TYPE")
	)
	(segment
		(start 203.01458 -407.604722)
		(end 204.56652 -406.052782)
		(width 0.1524)
		(layer "In4.Cu")
		(net "HSC_FLT_TYPE")
	)
	(segment
		(start 224.278952 -410.88437)
		(end 224.278952 -407.78557)
		(width 0.1524)
		(layer "In4.Cu")
		(net "HSC_FLT_TYPE")
	)
	(segment
		(start 193.811906 -404.649432)
		(end 194.09029 -404.927816)
		(width 0.1524)
		(layer "In4.Cu")
		(net "HSC_FLT_TYPE")
	)
	(segment
		(start 205.23454 -409.479242)
		(end 205.23454 -406.596342)
		(width 0.1524)
		(layer "In4.Cu")
		(net "HSC_FLT_TYPE")
	)
	(segment
		(start 190.132208 -403.294342)
		(end 190.93434 -404.096474)
		(width 0.1524)
		(layer "In4.Cu")
		(net "HSC_FLT_TYPE")
	)
	(segment
		(start 202.01636 -411.094682)
		(end 203.01458 -410.096462)
		(width 0.1524)
		(layer "In4.Cu")
		(net "HSC_FLT_TYPE")
	)
	(segment
		(start 192.938908 -404.649432)
		(end 193.811906 -404.649432)
		(width 0.1524)
		(layer "In4.Cu")
		(net "HSC_FLT_TYPE")
	)
	(segment
		(start 194.09029 -404.927816)
		(end 194.09029 -410.001212)
		(width 0.1524)
		(layer "In4.Cu")
		(net "HSC_FLT_TYPE")
	)
	(segment
		(start 236.530642 -406.805638)
		(end 234.311698 -409.024582)
		(width 0.1524)
		(layer "In4.Cu")
		(net "HSC_FLT_TYPE")
	)
	(segment
		(start 213.633558 -407.793444)
		(end 213.633558 -410.838904)
		(width 0.1524)
		(layer "In4.Cu")
		(net "HSC_FLT_TYPE")
	)
	(segment
		(start 215.78824 -409.392882)
		(end 217.419428 -411.02407)
		(width 0.1524)
		(layer "In4.Cu")
		(net "HSC_FLT_TYPE")
	)
	(segment
		(start 213.633558 -410.838904)
		(end 213.2965 -411.175962)
		(width 0.1524)
		(layer "In4.Cu")
		(net "HSC_FLT_TYPE")
	)
	(segment
		(start 191.12738 -405.20112)
		(end 192.38722 -405.20112)
		(width 0.1524)
		(layer "In4.Cu")
		(net "HSC_FLT_TYPE")
	)
	(segment
		(start 206.93126 -411.175962)
		(end 205.23454 -409.479242)
		(width 0.1524)
		(layer "In4.Cu")
		(net "HSC_FLT_TYPE")
	)
	(segment
		(start 217.419428 -411.02407)
		(end 224.139252 -411.02407)
		(width 0.1524)
		(layer "In4.Cu")
		(net "HSC_FLT_TYPE")
	)
	(segment
		(start 226.01174 -406.052782)
		(end 227.1141 -406.052782)
		(width 0.1524)
		(layer "In4.Cu")
		(net "HSC_FLT_TYPE")
	)
	(segment
		(start 190.93434 -404.096474)
		(end 190.93434 -405.00808)
		(width 0.1524)
		(layer "In4.Cu")
		(net "HSC_FLT_TYPE")
	)
	(segment
		(start 194.09029 -410.001212)
		(end 195.18376 -411.094682)
		(width 0.1524)
		(layer "In4.Cu")
		(net "HSC_FLT_TYPE")
	)
	(segment
		(start 227.183442 -409.024582)
		(end 226.45624 -408.29738)
		(width 0.1524)
		(layer "In4.Cu")
		(net "HSC_FLT_TYPE")
	)
	(segment
		(start 213.2965 -411.175962)
		(end 206.93126 -411.175962)
		(width 0.1524)
		(layer "In4.Cu")
		(net "HSC_FLT_TYPE")
	)
	(segment
		(start 234.311698 -409.024582)
		(end 227.183442 -409.024582)
		(width 0.1524)
		(layer "In4.Cu")
		(net "HSC_FLT_TYPE")
	)
	(segment
		(start 205.23454 -406.596342)
		(end 205.7781 -406.052782)
		(width 0.1524)
		(layer "In4.Cu")
		(net "HSC_FLT_TYPE")
	)
	(segment
		(start 226.45624 -406.710642)
		(end 227.1141 -406.052782)
		(width 0.1524)
		(layer "In4.Cu")
		(net "HSC_FLT_TYPE")
	)
	(segment
		(start 190.93434 -405.00808)
		(end 191.12738 -405.20112)
		(width 0.1524)
		(layer "In4.Cu")
		(net "HSC_FLT_TYPE")
	)
	(segment
		(start 237.7821 -402.903182)
		(end 236.530642 -404.15464)
		(width 0.1524)
		(layer "In4.Cu")
		(net "HSC_FLT_TYPE")
	)
	(segment
		(start 215.37422 -406.052782)
		(end 213.633558 -407.793444)
		(width 0.1524)
		(layer "In4.Cu")
		(net "HSC_FLT_TYPE")
	)
	(segment
		(start 215.78824 -406.710642)
		(end 215.78824 -409.392882)
		(width 0.1524)
		(layer "In4.Cu")
		(net "HSC_FLT_TYPE")
	)
	(segment
		(start 226.45624 -408.29738)
		(end 226.45624 -406.710642)
		(width 0.1524)
		(layer "In4.Cu")
		(net "HSC_FLT_TYPE")
	)
	(segment
		(start 216.4461 -406.052782)
		(end 215.78824 -406.710642)
		(width 0.1524)
		(layer "In4.Cu")
		(net "HSC_FLT_TYPE")
	)
	(segment
		(start 189.973204 -402.341842)
		(end 189.7761 -402.144738)
		(width 0.1524)
		(layer "F.Cu")
		(net "HSC_FAULT")
	)
	(segment
		(start 212.442044 -402.170138)
		(end 213.0171 -402.170138)
		(width 0.1524)
		(layer "F.Cu")
		(net "HSC_FAULT")
	)
	(segment
		(start 223.110044 -402.170138)
		(end 223.6851 -402.170138)
		(width 0.1524)
		(layer "F.Cu")
		(net "HSC_FAULT")
	)
	(segment
		(start 191.01689 -402.341842)
		(end 189.973204 -402.341842)
		(width 0.1524)
		(layer "F.Cu")
		(net "HSC_FAULT")
	)
	(segment
		(start 233.778044 -402.170138)
		(end 234.3531 -402.170138)
		(width 0.1524)
		(layer "F.Cu")
		(net "HSC_FAULT")
	)
	(segment
		(start 201.774044 -402.170138)
		(end 202.3491 -402.170138)
		(width 0.1524)
		(layer "F.Cu")
		(net "HSC_FAULT")
	)
	(segment
		(start 189.7761 -402.144738)
		(end 188.516006 -402.144738)
		(width 0.1524)
		(layer "F.Cu")
		(net "HSC_FAULT")
	)
	(via
		(at 234.3531 -402.170138)
		(size 0.508)
		(drill 0.254)
		(layers "F.Cu" "B.Cu")
		(net "HSC_FAULT")
	)
	(via
		(at 189.7761 -402.144738)
		(size 0.508)
		(drill 0.254)
		(layers "F.Cu" "B.Cu")
		(net "HSC_FAULT")
	)
	(via
		(at 213.0171 -402.170138)
		(size 0.508)
		(drill 0.254)
		(layers "F.Cu" "B.Cu")
		(net "HSC_FAULT")
	)
	(via
		(at 223.6851 -402.170138)
		(size 0.508)
		(drill 0.254)
		(layers "F.Cu" "B.Cu")
		(net "HSC_FAULT")
	)
	(via
		(at 202.3491 -402.170138)
		(size 0.508)
		(drill 0.254)
		(layers "F.Cu" "B.Cu")
		(net "HSC_FAULT")
	)
	(segment
		(start 226.0219 -403.100794)
		(end 226.0219 -403.842982)
		(width 0.1524)
		(layer "In4.Cu")
		(net "HSC_FAULT")
	)
	(segment
		(start 215.992456 -404.740618)
		(end 217.387932 -404.740618)
		(width 0.1524)
		(layer "In4.Cu")
		(net "HSC_FAULT")
	)
	(segment
		(start 207.678782 -403.8219)
		(end 206.873094 -404.627588)
		(width 0.1524)
		(layer "In4.Cu")
		(net "HSC_FAULT")
	)
	(segment
		(start 205.385162 -404.627588)
		(end 204.51572 -403.758146)
		(width 0.1524)
		(layer "In4.Cu")
		(net "HSC_FAULT")
	)
	(segment
		(start 224.02292 -402.507958)
		(end 225.429064 -402.507958)
		(width 0.1524)
		(layer "In4.Cu")
		(net "HSC_FAULT")
	)
	(segment
		(start 226.0219 -403.842982)
		(end 226.821746 -404.642828)
		(width 0.1524)
		(layer "In4.Cu")
		(net "HSC_FAULT")
	)
	(segment
		(start 225.429064 -402.507958)
		(end 226.0219 -403.100794)
		(width 0.1524)
		(layer "In4.Cu")
		(net "HSC_FAULT")
	)
	(segment
		(start 202.3491 -403.46503)
		(end 201.992738 -403.821392)
		(width 0.1524)
		(layer "In4.Cu")
		(net "HSC_FAULT")
	)
	(segment
		(start 192.907412 -402.699728)
		(end 192.66408 -402.94306)
		(width 0.1524)
		(layer "In4.Cu")
		(net "HSC_FAULT")
	)
	(segment
		(start 204.51572 -403.758146)
		(end 204.51572 -402.881338)
		(width 0.1524)
		(layer "In4.Cu")
		(net "HSC_FAULT")
	)
	(segment
		(start 233.134154 -403.868382)
		(end 234.3531 -402.649436)
		(width 0.1524)
		(layer "In4.Cu")
		(net "HSC_FAULT")
	)
	(segment
		(start 194.296538 -402.699728)
		(end 192.907412 -402.699728)
		(width 0.1524)
		(layer "In4.Cu")
		(net "HSC_FAULT")
	)
	(segment
		(start 204.51572 -402.881338)
		(end 204.151484 -402.517102)
		(width 0.1524)
		(layer "In4.Cu")
		(net "HSC_FAULT")
	)
	(segment
		(start 217.387932 -404.740618)
		(end 218.322652 -403.805898)
		(width 0.1524)
		(layer "In4.Cu")
		(net "HSC_FAULT")
	)
	(segment
		(start 190.534798 -402.144738)
		(end 189.7761 -402.144738)
		(width 0.1524)
		(layer "In4.Cu")
		(net "HSC_FAULT")
	)
	(segment
		(start 212.423502 -403.8219)
		(end 207.678782 -403.8219)
		(width 0.1524)
		(layer "In4.Cu")
		(net "HSC_FAULT")
	)
	(segment
		(start 228.9175 -403.868382)
		(end 233.134154 -403.868382)
		(width 0.1524)
		(layer "In4.Cu")
		(net "HSC_FAULT")
	)
	(segment
		(start 226.821746 -404.642828)
		(end 228.143054 -404.642828)
		(width 0.1524)
		(layer "In4.Cu")
		(net "HSC_FAULT")
	)
	(segment
		(start 215.535764 -403.186646)
		(end 215.535764 -404.283926)
		(width 0.1524)
		(layer "In4.Cu")
		(net "HSC_FAULT")
	)
	(segment
		(start 223.6851 -402.170138)
		(end 224.02292 -402.507958)
		(width 0.1524)
		(layer "In4.Cu")
		(net "HSC_FAULT")
	)
	(segment
		(start 223.087184 -403.805898)
		(end 223.6851 -403.207982)
		(width 0.1524)
		(layer "In4.Cu")
		(net "HSC_FAULT")
	)
	(segment
		(start 195.418202 -403.821392)
		(end 194.296538 -402.699728)
		(width 0.1524)
		(layer "In4.Cu")
		(net "HSC_FAULT")
	)
	(segment
		(start 214.847932 -402.498814)
		(end 215.535764 -403.186646)
		(width 0.1524)
		(layer "In4.Cu")
		(net "HSC_FAULT")
	)
	(segment
		(start 215.535764 -404.283926)
		(end 215.992456 -404.740618)
		(width 0.1524)
		(layer "In4.Cu")
		(net "HSC_FAULT")
	)
	(segment
		(start 204.151484 -402.517102)
		(end 202.696064 -402.517102)
		(width 0.1524)
		(layer "In4.Cu")
		(net "HSC_FAULT")
	)
	(segment
		(start 213.0171 -402.170138)
		(end 213.0171 -403.228302)
		(width 0.1524)
		(layer "In4.Cu")
		(net "HSC_FAULT")
	)
	(segment
		(start 218.322652 -403.805898)
		(end 223.087184 -403.805898)
		(width 0.1524)
		(layer "In4.Cu")
		(net "HSC_FAULT")
	)
	(segment
		(start 191.33312 -402.94306)
		(end 190.534798 -402.144738)
		(width 0.1524)
		(layer "In4.Cu")
		(net "HSC_FAULT")
	)
	(segment
		(start 234.3531 -402.649436)
		(end 234.3531 -402.170138)
		(width 0.1524)
		(layer "In4.Cu")
		(net "HSC_FAULT")
	)
	(segment
		(start 213.0171 -403.228302)
		(end 212.423502 -403.8219)
		(width 0.1524)
		(layer "In4.Cu")
		(net "HSC_FAULT")
	)
	(segment
		(start 201.992738 -403.821392)
		(end 195.418202 -403.821392)
		(width 0.1524)
		(layer "In4.Cu")
		(net "HSC_FAULT")
	)
	(segment
		(start 228.143054 -404.642828)
		(end 228.9175 -403.868382)
		(width 0.1524)
		(layer "In4.Cu")
		(net "HSC_FAULT")
	)
	(segment
		(start 213.0171 -402.170138)
		(end 213.345776 -402.498814)
		(width 0.1524)
		(layer "In4.Cu")
		(net "HSC_FAULT")
	)
	(segment
		(start 192.66408 -402.94306)
		(end 191.33312 -402.94306)
		(width 0.1524)
		(layer "In4.Cu")
		(net "HSC_FAULT")
	)
	(segment
		(start 223.6851 -403.207982)
		(end 223.6851 -402.170138)
		(width 0.1524)
		(layer "In4.Cu")
		(net "HSC_FAULT")
	)
	(segment
		(start 206.873094 -404.627588)
		(end 205.385162 -404.627588)
		(width 0.1524)
		(layer "In4.Cu")
		(net "HSC_FAULT")
	)
	(segment
		(start 202.3491 -402.170138)
		(end 202.3491 -403.46503)
		(width 0.1524)
		(layer "In4.Cu")
		(net "HSC_FAULT")
	)
	(segment
		(start 202.696064 -402.517102)
		(end 202.3491 -402.170138)
		(width 0.1524)
		(layer "In4.Cu")
		(net "HSC_FAULT")
	)
	(segment
		(start 213.345776 -402.498814)
		(end 214.847932 -402.498814)
		(width 0.1524)
		(layer "In4.Cu")
		(net "HSC_FAULT")
	)
	(segment
		(start 184.52465 -399.108422)
		(end 184.288938 -398.87271)
		(width 0.1524)
		(layer "F.Cu")
		(net "HSC_EN_R")
	)
	(segment
		(start 184.3786 -399.254472)
		(end 184.52465 -399.108422)
		(width 0.1524)
		(layer "F.Cu")
		(net "HSC_EN_R")
	)
	(segment
		(start 184.3786 -399.682208)
		(end 184.3786 -399.254472)
		(width 0.1524)
		(layer "F.Cu")
		(net "HSC_EN_R")
	)
	(segment
		(start 183.94045 -398.031716)
		(end 183.94045 -397.848582)
		(width 0.1524)
		(layer "F.Cu")
		(net "HSC_EN_R")
	)
	(segment
		(start 184.288938 -398.87271)
		(end 183.94045 -398.031716)
		(width 0.1524)
		(layer "F.Cu")
		(net "HSC_EN_R")
	)
	(via
		(at 184.52465 -399.108422)
		(size 0.508)
		(drill 0.254)
		(layers "F.Cu" "B.Cu")
		(net "HSC_EN_R")
	)
	(segment
		(start 184.74055 -397.1036)
		(end 184.74055 -397.848582)
		(width 0.10668)
		(layer "F.Cu")
		(net "HSC_EN")
	)
	(segment
		(start 270.115792 -418.648388)
		(end 270.192754 -418.571426)
		(width 0.10668)
		(layer "F.Cu")
		(net "HSC_EN")
	)
	(segment
		(start 271.295876 -418.57168)
		(end 272.322036 -418.57168)
		(width 0.10668)
		(layer "F.Cu")
		(net "HSC_EN")
	)
	(segment
		(start 267.869924 -418.648388)
		(end 270.115792 -418.648388)
		(width 0.10668)
		(layer "F.Cu")
		(net "HSC_EN")
	)
	(segment
		(start 265.601958 -418.13607)
		(end 267.357606 -418.13607)
		(width 0.10668)
		(layer "F.Cu")
		(net "HSC_EN")
	)
	(segment
		(start 267.357606 -418.13607)
		(end 267.869924 -418.648388)
		(width 0.10668)
		(layer "F.Cu")
		(net "HSC_EN")
	)
	(segment
		(start 270.192754 -418.571426)
		(end 271.295622 -418.571426)
		(width 0.10668)
		(layer "F.Cu")
		(net "HSC_EN")
	)
	(segment
		(start 271.295622 -418.571426)
		(end 271.295876 -418.57168)
		(width 0.10668)
		(layer "F.Cu")
		(net "HSC_EN")
	)
	(segment
		(start 193.779902 -380.660402)
		(end 192.573402 -380.660402)
		(width 0.10668)
		(layer "F.Cu")
		(net "HSC_EN")
	)
	(via
		(at 272.322036 -418.57168)
		(size 0.508)
		(drill 0.254)
		(layers "F.Cu" "B.Cu")
		(net "HSC_EN")
	)
	(via
		(at 184.74055 -397.1036)
		(size 0.508)
		(drill 0.254)
		(layers "F.Cu" "B.Cu")
		(net "HSC_EN")
	)
	(via
		(at 282.372054 -395.89456)
		(size 0.508)
		(drill 0.254)
		(layers "F.Cu" "B.Cu")
		(net "HSC_EN")
	)
	(via
		(at 192.573402 -380.660402)
		(size 0.508)
		(drill 0.254)
		(layers "F.Cu" "B.Cu")
		(net "HSC_EN")
	)
	(segment
		(start 199.0725 -373.47398)
		(end 199.075802 -373.47398)
		(width 0.11684)
		(layer "In2.Cu")
		(net "HSC_EN")
	)
	(segment
		(start 281.45994 -377.15952)
		(end 281.45994 -387.223)
		(width 0.11684)
		(layer "In2.Cu")
		(net "HSC_EN")
	)
	(segment
		(start 200.27392 -372.275862)
		(end 219.070936 -372.275862)
		(width 0.11684)
		(layer "In2.Cu")
		(net "HSC_EN")
	)
	(segment
		(start 196.09562 -376.45086)
		(end 199.0725 -373.47398)
		(width 0.11684)
		(layer "In2.Cu")
		(net "HSC_EN")
	)
	(segment
		(start 280.95194 -388.82828)
		(end 280.95194 -394.474446)
		(width 0.11684)
		(layer "In2.Cu")
		(net "HSC_EN")
	)
	(segment
		(start 281.65044 -388.12978)
		(end 280.95194 -388.82828)
		(width 0.11684)
		(layer "In2.Cu")
		(net "HSC_EN")
	)
	(segment
		(start 219.070936 -372.275862)
		(end 219.93733 -371.409468)
		(width 0.11684)
		(layer "In2.Cu")
		(net "HSC_EN")
	)
	(segment
		(start 196.09562 -378.077476)
		(end 196.09562 -376.45086)
		(width 0.11684)
		(layer "In2.Cu")
		(net "HSC_EN")
	)
	(segment
		(start 281.65044 -387.4135)
		(end 281.65044 -388.12978)
		(width 0.11684)
		(layer "In2.Cu")
		(net "HSC_EN")
	)
	(segment
		(start 199.075802 -373.47398)
		(end 200.27392 -372.275862)
		(width 0.11684)
		(layer "In2.Cu")
		(net "HSC_EN")
	)
	(segment
		(start 224.982786 -372.854474)
		(end 277.154894 -372.854474)
		(width 0.11684)
		(layer "In2.Cu")
		(net "HSC_EN")
	)
	(segment
		(start 280.95194 -394.474446)
		(end 282.372054 -395.89456)
		(width 0.11684)
		(layer "In2.Cu")
		(net "HSC_EN")
	)
	(segment
		(start 219.93733 -371.409468)
		(end 223.53778 -371.409468)
		(width 0.11684)
		(layer "In2.Cu")
		(net "HSC_EN")
	)
	(segment
		(start 193.512694 -380.660402)
		(end 196.09562 -378.077476)
		(width 0.11684)
		(layer "In2.Cu")
		(net "HSC_EN")
	)
	(segment
		(start 277.154894 -372.854474)
		(end 281.45994 -377.15952)
		(width 0.11684)
		(layer "In2.Cu")
		(net "HSC_EN")
	)
	(segment
		(start 223.53778 -371.409468)
		(end 224.982786 -372.854474)
		(width 0.11684)
		(layer "In2.Cu")
		(net "HSC_EN")
	)
	(segment
		(start 281.45994 -387.223)
		(end 281.65044 -387.4135)
		(width 0.11684)
		(layer "In2.Cu")
		(net "HSC_EN")
	)
	(segment
		(start 192.573402 -380.660402)
		(end 193.512694 -380.660402)
		(width 0.11684)
		(layer "In2.Cu")
		(net "HSC_EN")
	)
	(segment
		(start 279.654 -413.26435)
		(end 280.481024 -412.437326)
		(width 0.11684)
		(layer "In4.Cu")
		(net "HSC_EN")
	)
	(segment
		(start 281.237944 -409.548838)
		(end 281.237944 -397.02867)
		(width 0.11684)
		(layer "In4.Cu")
		(net "HSC_EN")
	)
	(segment
		(start 279.654 -416.178746)
		(end 279.654 -413.26435)
		(width 0.11684)
		(layer "In4.Cu")
		(net "HSC_EN")
	)
	(segment
		(start 272.322036 -418.57168)
		(end 272.93189 -418.57168)
		(width 0.11684)
		(layer "In4.Cu")
		(net "HSC_EN")
	)
	(segment
		(start 280.481024 -410.305758)
		(end 281.237944 -409.548838)
		(width 0.11684)
		(layer "In4.Cu")
		(net "HSC_EN")
	)
	(segment
		(start 276.037548 -416.880802)
		(end 278.951944 -416.880802)
		(width 0.11684)
		(layer "In4.Cu")
		(net "HSC_EN")
	)
	(segment
		(start 272.93189 -418.57168)
		(end 273.379184 -418.124386)
		(width 0.11684)
		(layer "In4.Cu")
		(net "HSC_EN")
	)
	(segment
		(start 280.481024 -412.437326)
		(end 280.481024 -410.305758)
		(width 0.11684)
		(layer "In4.Cu")
		(net "HSC_EN")
	)
	(segment
		(start 273.379184 -418.124386)
		(end 274.793964 -418.124386)
		(width 0.11684)
		(layer "In4.Cu")
		(net "HSC_EN")
	)
	(segment
		(start 278.951944 -416.880802)
		(end 279.654 -416.178746)
		(width 0.11684)
		(layer "In4.Cu")
		(net "HSC_EN")
	)
	(segment
		(start 274.793964 -418.124386)
		(end 276.037548 -416.880802)
		(width 0.11684)
		(layer "In4.Cu")
		(net "HSC_EN")
	)
	(segment
		(start 281.237944 -397.02867)
		(end 282.372054 -395.89456)
		(width 0.11684)
		(layer "In4.Cu")
		(net "HSC_EN")
	)
	(segment
		(start 184.174384 -397.669766)
		(end 183.742584 -397.669766)
		(width 0.11684)
		(layer "In6.Cu")
		(net "HSC_EN")
	)
	(segment
		(start 183.049418 -395.085062)
		(end 184.483248 -393.651232)
		(width 0.11684)
		(layer "In6.Cu")
		(net "HSC_EN")
	)
	(segment
		(start 193.729356 -387.90372)
		(end 193.729356 -381.55118)
		(width 0.11684)
		(layer "In6.Cu")
		(net "HSC_EN")
	)
	(segment
		(start 183.049418 -396.9766)
		(end 183.049418 -395.085062)
		(width 0.11684)
		(layer "In6.Cu")
		(net "HSC_EN")
	)
	(segment
		(start 192.838578 -380.660402)
		(end 192.573402 -380.660402)
		(width 0.11684)
		(layer "In6.Cu")
		(net "HSC_EN")
	)
	(segment
		(start 193.20002 -390.2583)
		(end 193.20002 -388.433056)
		(width 0.11684)
		(layer "In6.Cu")
		(net "HSC_EN")
	)
	(segment
		(start 183.742584 -397.669766)
		(end 183.049418 -396.9766)
		(width 0.11684)
		(layer "In6.Cu")
		(net "HSC_EN")
	)
	(segment
		(start 189.807088 -393.651232)
		(end 193.20002 -390.2583)
		(width 0.11684)
		(layer "In6.Cu")
		(net "HSC_EN")
	)
	(segment
		(start 193.729356 -381.55118)
		(end 192.838578 -380.660402)
		(width 0.11684)
		(layer "In6.Cu")
		(net "HSC_EN")
	)
	(segment
		(start 184.74055 -397.1036)
		(end 184.174384 -397.669766)
		(width 0.11684)
		(layer "In6.Cu")
		(net "HSC_EN")
	)
	(segment
		(start 184.483248 -393.651232)
		(end 189.807088 -393.651232)
		(width 0.11684)
		(layer "In6.Cu")
		(net "HSC_EN")
	)
	(segment
		(start 193.20002 -388.433056)
		(end 193.729356 -387.90372)
		(width 0.11684)
		(layer "In6.Cu")
		(net "HSC_EN")
	)
	(segment
		(start 190.97625 -400.269202)
		(end 191.01689 -400.309842)
		(width 0.1524)
		(layer "F.Cu")
		(net "HSC_D_OC_R")
	)
	(segment
		(start 189.765686 -400.420078)
		(end 189.76594 -400.269202)
		(width 0.1524)
		(layer "F.Cu")
		(net "HSC_D_OC_R")
	)
	(segment
		(start 205.16215 -399.956782)
		(end 205.7781 -399.956782)
		(width 0.1524)
		(layer "F.Cu")
		(net "HSC_D_OC_R")
	)
	(segment
		(start 215.83015 -399.956782)
		(end 216.4461 -399.956782)
		(width 0.1524)
		(layer "F.Cu")
		(net "HSC_D_OC_R")
	)
	(segment
		(start 237.16615 -400.871182)
		(end 237.7821 -400.871182)
		(width 0.1524)
		(layer "F.Cu")
		(net "HSC_D_OC_R")
	)
	(segment
		(start 189.76594 -400.269202)
		(end 190.97625 -400.269202)
		(width 0.1524)
		(layer "F.Cu")
		(net "HSC_D_OC_R")
	)
	(segment
		(start 188.940186 -401.244816)
		(end 189.765686 -400.420078)
		(width 0.1524)
		(layer "F.Cu")
		(net "HSC_D_OC_R")
	)
	(segment
		(start 188.516006 -401.244816)
		(end 188.940186 -401.244816)
		(width 0.1524)
		(layer "F.Cu")
		(net "HSC_D_OC_R")
	)
	(segment
		(start 226.49815 -399.956782)
		(end 227.1141 -399.956782)
		(width 0.1524)
		(layer "F.Cu")
		(net "HSC_D_OC_R")
	)
	(via
		(at 216.4461 -399.956782)
		(size 0.508)
		(drill 0.254)
		(layers "F.Cu" "B.Cu")
		(net "HSC_D_OC_R")
	)
	(via
		(at 237.7821 -400.871182)
		(size 0.508)
		(drill 0.254)
		(layers "F.Cu" "B.Cu")
		(net "HSC_D_OC_R")
	)
	(via
		(at 189.76594 -400.269202)
		(size 0.508)
		(drill 0.254)
		(layers "F.Cu" "B.Cu")
		(net "HSC_D_OC_R")
	)
	(via
		(at 227.1141 -399.956782)
		(size 0.508)
		(drill 0.254)
		(layers "F.Cu" "B.Cu")
		(net "HSC_D_OC_R")
	)
	(via
		(at 205.7781 -399.956782)
		(size 0.508)
		(drill 0.254)
		(layers "F.Cu" "B.Cu")
		(net "HSC_D_OC_R")
	)
	(segment
		(start 216.4461 -401.49272)
		(end 216.8144 -401.86102)
		(width 0.1524)
		(layer "In4.Cu")
		(net "HSC_D_OC_R")
	)
	(segment
		(start 228.57714 -401.9804)
		(end 228.96322 -401.59432)
		(width 0.1524)
		(layer "In4.Cu")
		(net "HSC_D_OC_R")
	)
	(segment
		(start 207.1878 -401.89658)
		(end 207.84058 -401.2438)
		(width 0.1524)
		(layer "In4.Cu")
		(net "HSC_D_OC_R")
	)
	(segment
		(start 207.84058 -401.2438)
		(end 207.84058 -400.42338)
		(width 0.1524)
		(layer "In4.Cu")
		(net "HSC_D_OC_R")
	)
	(segment
		(start 228.96322 -401.59432)
		(end 228.96322 -400.36242)
		(width 0.1524)
		(layer "In4.Cu")
		(net "HSC_D_OC_R")
	)
	(segment
		(start 196.83984 -401.02536)
		(end 196.83984 -400.37512)
		(width 0.1524)
		(layer "In4.Cu")
		(net "HSC_D_OC_R")
	)
	(segment
		(start 217.87612 -401.86102)
		(end 218.50604 -401.2311)
		(width 0.1524)
		(layer "In4.Cu")
		(net "HSC_D_OC_R")
	)
	(segment
		(start 227.1141 -399.956782)
		(end 227.1141 -401.516088)
		(width 0.1524)
		(layer "In4.Cu")
		(net "HSC_D_OC_R")
	)
	(segment
		(start 191.9732 -399.44548)
		(end 193.55562 -399.44548)
		(width 0.1524)
		(layer "In4.Cu")
		(net "HSC_D_OC_R")
	)
	(segment
		(start 193.55562 -399.44548)
		(end 195.6689 -401.55876)
		(width 0.1524)
		(layer "In4.Cu")
		(net "HSC_D_OC_R")
	)
	(segment
		(start 205.7781 -401.45208)
		(end 206.2226 -401.89658)
		(width 0.1524)
		(layer "In4.Cu")
		(net "HSC_D_OC_R")
	)
	(segment
		(start 196.83984 -400.37512)
		(end 197.258178 -399.956782)
		(width 0.1524)
		(layer "In4.Cu")
		(net "HSC_D_OC_R")
	)
	(segment
		(start 191.149478 -400.269202)
		(end 191.9732 -399.44548)
		(width 0.1524)
		(layer "In4.Cu")
		(net "HSC_D_OC_R")
	)
	(segment
		(start 196.30644 -401.55876)
		(end 196.83984 -401.02536)
		(width 0.1524)
		(layer "In4.Cu")
		(net "HSC_D_OC_R")
	)
	(segment
		(start 228.96322 -400.36242)
		(end 229.39756 -399.92808)
		(width 0.1524)
		(layer "In4.Cu")
		(net "HSC_D_OC_R")
	)
	(segment
		(start 227.578412 -401.9804)
		(end 228.57714 -401.9804)
		(width 0.1524)
		(layer "In4.Cu")
		(net "HSC_D_OC_R")
	)
	(segment
		(start 236.838998 -399.92808)
		(end 237.7821 -400.871182)
		(width 0.1524)
		(layer "In4.Cu")
		(net "HSC_D_OC_R")
	)
	(segment
		(start 197.258178 -399.956782)
		(end 205.7781 -399.956782)
		(width 0.1524)
		(layer "In4.Cu")
		(net "HSC_D_OC_R")
	)
	(segment
		(start 218.50604 -401.2311)
		(end 218.50604 -400.34718)
		(width 0.1524)
		(layer "In4.Cu")
		(net "HSC_D_OC_R")
	)
	(segment
		(start 208.307178 -399.956782)
		(end 216.4461 -399.956782)
		(width 0.1524)
		(layer "In4.Cu")
		(net "HSC_D_OC_R")
	)
	(segment
		(start 205.7781 -399.956782)
		(end 205.7781 -401.45208)
		(width 0.1524)
		(layer "In4.Cu")
		(net "HSC_D_OC_R")
	)
	(segment
		(start 218.50604 -400.34718)
		(end 218.896438 -399.956782)
		(width 0.1524)
		(layer "In4.Cu")
		(net "HSC_D_OC_R")
	)
	(segment
		(start 218.896438 -399.956782)
		(end 227.1141 -399.956782)
		(width 0.1524)
		(layer "In4.Cu")
		(net "HSC_D_OC_R")
	)
	(segment
		(start 227.1141 -401.516088)
		(end 227.578412 -401.9804)
		(width 0.1524)
		(layer "In4.Cu")
		(net "HSC_D_OC_R")
	)
	(segment
		(start 216.8144 -401.86102)
		(end 217.87612 -401.86102)
		(width 0.1524)
		(layer "In4.Cu")
		(net "HSC_D_OC_R")
	)
	(segment
		(start 216.4461 -399.956782)
		(end 216.4461 -401.49272)
		(width 0.1524)
		(layer "In4.Cu")
		(net "HSC_D_OC_R")
	)
	(segment
		(start 189.76594 -400.269202)
		(end 191.149478 -400.269202)
		(width 0.1524)
		(layer "In4.Cu")
		(net "HSC_D_OC_R")
	)
	(segment
		(start 229.39756 -399.92808)
		(end 236.838998 -399.92808)
		(width 0.1524)
		(layer "In4.Cu")
		(net "HSC_D_OC_R")
	)
	(segment
		(start 206.2226 -401.89658)
		(end 207.1878 -401.89658)
		(width 0.1524)
		(layer "In4.Cu")
		(net "HSC_D_OC_R")
	)
	(segment
		(start 207.84058 -400.42338)
		(end 208.307178 -399.956782)
		(width 0.1524)
		(layer "In4.Cu")
		(net "HSC_D_OC_R")
	)
	(segment
		(start 195.6689 -401.55876)
		(end 196.30644 -401.55876)
		(width 0.1524)
		(layer "In4.Cu")
		(net "HSC_D_OC_R")
	)
	(segment
		(start 234.308142 -401.17014)
		(end 235.1151 -400.363182)
		(width 0.1524)
		(layer "F.Cu")
		(net "HSC_D_OC_4")
	)
	(segment
		(start 235.1151 -400.363182)
		(end 235.6231 -400.871182)
		(width 0.1524)
		(layer "F.Cu")
		(net "HSC_D_OC_4")
	)
	(segment
		(start 235.6231 -400.871182)
		(end 236.36605 -400.871182)
		(width 0.1524)
		(layer "F.Cu")
		(net "HSC_D_OC_4")
	)
	(segment
		(start 233.778044 -401.17014)
		(end 234.308142 -401.17014)
		(width 0.1524)
		(layer "F.Cu")
		(net "HSC_D_OC_4")
	)
	(via
		(at 235.1151 -400.363182)
		(size 0.762)
		(drill 0.381)
		(layers "F.Cu" "B.Cu")
		(net "HSC_D_OC_4")
	)
	(segment
		(start 225.69805 -399.956782)
		(end 224.4725 -399.956782)
		(width 0.1524)
		(layer "F.Cu")
		(net "HSC_D_OC_3")
	)
	(segment
		(start 224.3201 -400.109182)
		(end 224.3201 -400.363182)
		(width 0.1524)
		(layer "F.Cu")
		(net "HSC_D_OC_3")
	)
	(segment
		(start 223.513142 -401.17014)
		(end 223.110044 -401.17014)
		(width 0.1524)
		(layer "F.Cu")
		(net "HSC_D_OC_3")
	)
	(segment
		(start 224.4725 -399.956782)
		(end 224.3201 -400.109182)
		(width 0.1524)
		(layer "F.Cu")
		(net "HSC_D_OC_3")
	)
	(segment
		(start 224.3201 -400.363182)
		(end 223.513142 -401.17014)
		(width 0.1524)
		(layer "F.Cu")
		(net "HSC_D_OC_3")
	)
	(via
		(at 224.3201 -400.109182)
		(size 0.762)
		(drill 0.381)
		(layers "F.Cu" "B.Cu")
		(net "HSC_D_OC_3")
	)
	(segment
		(start 212.442044 -401.17014)
		(end 212.845142 -401.17014)
		(width 0.1524)
		(layer "F.Cu")
		(net "HSC_D_OC_2")
	)
	(segment
		(start 213.8045 -399.956782)
		(end 215.03005 -399.956782)
		(width 0.1524)
		(layer "F.Cu")
		(net "HSC_D_OC_2")
	)
	(segment
		(start 213.6521 -400.109182)
		(end 213.8045 -399.956782)
		(width 0.1524)
		(layer "F.Cu")
		(net "HSC_D_OC_2")
	)
	(segment
		(start 212.845142 -401.17014)
		(end 213.6521 -400.363182)
		(width 0.1524)
		(layer "F.Cu")
		(net "HSC_D_OC_2")
	)
	(segment
		(start 213.6521 -400.363182)
		(end 213.6521 -400.109182)
		(width 0.1524)
		(layer "F.Cu")
		(net "HSC_D_OC_2")
	)
	(via
		(at 213.6521 -400.109182)
		(size 0.762)
		(drill 0.381)
		(layers "F.Cu" "B.Cu")
		(net "HSC_D_OC_2")
	)
	(segment
		(start 202.9841 -400.109182)
		(end 203.1365 -399.956782)
		(width 0.1524)
		(layer "F.Cu")
		(net "HSC_D_OC_1")
	)
	(segment
		(start 202.177142 -401.17014)
		(end 202.9841 -400.363182)
		(width 0.1524)
		(layer "F.Cu")
		(net "HSC_D_OC_1")
	)
	(segment
		(start 201.774044 -401.17014)
		(end 202.177142 -401.17014)
		(width 0.1524)
		(layer "F.Cu")
		(net "HSC_D_OC_1")
	)
	(segment
		(start 202.9841 -400.363182)
		(end 202.9841 -400.109182)
		(width 0.1524)
		(layer "F.Cu")
		(net "HSC_D_OC_1")
	)
	(segment
		(start 203.1365 -399.956782)
		(end 204.36205 -399.956782)
		(width 0.1524)
		(layer "F.Cu")
		(net "HSC_D_OC_1")
	)
	(via
		(at 202.9841 -400.109182)
		(size 0.762)
		(drill 0.381)
		(layers "F.Cu" "B.Cu")
		(net "HSC_D_OC_1")
	)
	(segment
		(start 188.615066 -171.727622)
		(end 188.615066 -172.425106)
		(width 0.1524)
		(layer "F.Cu")
		(net "HSC_D_OC")
	)
	(segment
		(start 163.30295 -114.264948)
		(end 162.306508 -114.264948)
		(width 0.1524)
		(layer "F.Cu")
		(net "HSC_D_OC")
	)
	(segment
		(start 203.725526 -181.456838)
		(end 207.513428 -185.24474)
		(width 0.1524)
		(layer "F.Cu")
		(net "HSC_D_OC")
	)
	(segment
		(start 197.646798 -181.456838)
		(end 203.725526 -181.456838)
		(width 0.1524)
		(layer "F.Cu")
		(net "HSC_D_OC")
	)
	(segment
		(start 209.325972 -189.620652)
		(end 209.325972 -192.69202)
		(width 0.1524)
		(layer "F.Cu")
		(net "HSC_D_OC")
	)
	(segment
		(start 188.615066 -172.425106)
		(end 197.646798 -181.456838)
		(width 0.1524)
		(layer "F.Cu")
		(net "HSC_D_OC")
	)
	(segment
		(start 191.81699 -400.309842)
		(end 192.43294 -400.309842)
		(width 0.1524)
		(layer "F.Cu")
		(net "HSC_D_OC")
	)
	(segment
		(start 209.325972 -192.69202)
		(end 208.935066 -193.082926)
		(width 0.1524)
		(layer "F.Cu")
		(net "HSC_D_OC")
	)
	(segment
		(start 207.513428 -185.24474)
		(end 209.325972 -189.620652)
		(width 0.1524)
		(layer "F.Cu")
		(net "HSC_D_OC")
	)
	(via
		(at 177.165762 -421.978074)
		(size 0.508)
		(drill 0.254)
		(layers "F.Cu" "B.Cu")
		(net "HSC_D_OC")
	)
	(via
		(at 177.653696 -410.623258)
		(size 0.508)
		(drill 0.254)
		(layers "F.Cu" "B.Cu")
		(net "HSC_D_OC")
	)
	(via
		(at 162.306508 -114.264948)
		(size 0.508)
		(drill 0.254)
		(layers "F.Cu" "B.Cu")
		(net "HSC_D_OC")
	)
	(via
		(at 188.615066 -171.727622)
		(size 0.508)
		(drill 0.254)
		(layers "F.Cu" "B.Cu")
		(net "HSC_D_OC")
	)
	(via
		(at 176.869344 -423.718482)
		(size 0.6604)
		(drill 0.3302)
		(layers "F.Cu" "B.Cu")
		(net "HSC_D_OC")
	)
	(via
		(at 192.43294 -400.309842)
		(size 0.508)
		(drill 0.254)
		(layers "F.Cu" "B.Cu")
		(net "HSC_D_OC")
	)
	(via
		(at 202.42657 -377.816872)
		(size 0.508)
		(drill 0.254)
		(layers "F.Cu" "B.Cu")
		(net "HSC_D_OC")
	)
	(via
		(at 208.935066 -193.082926)
		(size 0.508)
		(drill 0.254)
		(layers "F.Cu" "B.Cu")
		(net "HSC_D_OC")
	)
	(via
		(at 164.484304 -126.482856)
		(size 0.508)
		(drill 0.254)
		(layers "F.Cu" "B.Cu")
		(net "HSC_D_OC")
	)
	(segment
		(start 164.484304 -126.929896)
		(end 164.944298 -127.38989)
		(width 0.1524)
		(layer "B.Cu")
		(net "HSC_D_OC")
	)
	(segment
		(start 175.90643 -422.234614)
		(end 175.90643 -421.216836)
		(width 0.1524)
		(layer "B.Cu")
		(net "HSC_D_OC")
	)
	(segment
		(start 180.980842 -395.32179)
		(end 185.345578 -390.957054)
		(width 0.1524)
		(layer "B.Cu")
		(net "HSC_D_OC")
	)
	(segment
		(start 176.207674 -407.70937)
		(end 176.351438 -407.565606)
		(width 0.1524)
		(layer "B.Cu")
		(net "HSC_D_OC")
	)
	(segment
		(start 176.46523 -157.63621)
		(end 176.46523 -166.808912)
		(width 0.1524)
		(layer "B.Cu")
		(net "HSC_D_OC")
	)
	(segment
		(start 175.907192 -421.216074)
		(end 175.908716 -421.217598)
		(width 0.1524)
		(layer "B.Cu")
		(net "HSC_D_OC")
	)
	(segment
		(start 177.220372 -395.32179)
		(end 180.980842 -395.32179)
		(width 0.1524)
		(layer "B.Cu")
		(net "HSC_D_OC")
	)
	(segment
		(start 177.14087 -424.985688)
		(end 177.14087 -423.990008)
		(width 0.1524)
		(layer "B.Cu")
		(net "HSC_D_OC")
	)
	(segment
		(start 164.484304 -126.482856)
		(end 164.484304 -126.929896)
		(width 0.1524)
		(layer "B.Cu")
		(net "HSC_D_OC")
	)
	(segment
		(start 177.653696 -410.623258)
		(end 176.207674 -409.177236)
		(width 0.1524)
		(layer "B.Cu")
		(net "HSC_D_OC")
	)
	(segment
		(start 164.944298 -127.38989)
		(end 164.944298 -127.645414)
		(width 0.1524)
		(layer "B.Cu")
		(net "HSC_D_OC")
	)
	(segment
		(start 176.878234 -421.217598)
		(end 176.878234 -421.690546)
		(width 0.1524)
		(layer "B.Cu")
		(net "HSC_D_OC")
	)
	(segment
		(start 176.351438 -396.190724)
		(end 177.220372 -395.32179)
		(width 0.1524)
		(layer "B.Cu")
		(net "HSC_D_OC")
	)
	(segment
		(start 175.90643 -421.216836)
		(end 175.907192 -421.216074)
		(width 0.1524)
		(layer "B.Cu")
		(net "HSC_D_OC")
	)
	(segment
		(start 164.944298 -127.645414)
		(end 171.14647 -133.847586)
		(width 0.1524)
		(layer "B.Cu")
		(net "HSC_D_OC")
	)
	(segment
		(start 188.615066 -169.916094)
		(end 188.615066 -171.727622)
		(width 0.1524)
		(layer "B.Cu")
		(net "HSC_D_OC")
	)
	(segment
		(start 175.908716 -421.217598)
		(end 176.878234 -421.217598)
		(width 0.1524)
		(layer "B.Cu")
		(net "HSC_D_OC")
	)
	(segment
		(start 177.681128 -168.02481)
		(end 186.723782 -168.02481)
		(width 0.1524)
		(layer "B.Cu")
		(net "HSC_D_OC")
	)
	(segment
		(start 171.14647 -135.127238)
		(end 171.889674 -135.870442)
		(width 0.1524)
		(layer "B.Cu")
		(net "HSC_D_OC")
	)
	(segment
		(start 176.869344 -423.718482)
		(end 175.90643 -422.755568)
		(width 0.1524)
		(layer "B.Cu")
		(net "HSC_D_OC")
	)
	(segment
		(start 178.213004 -424.910758)
		(end 177.997104 -425.126658)
		(width 0.1524)
		(layer "B.Cu")
		(net "HSC_D_OC")
	)
	(segment
		(start 191.26454 -400.309842)
		(end 192.43294 -400.309842)
		(width 0.1524)
		(layer "B.Cu")
		(net "HSC_D_OC")
	)
	(segment
		(start 171.14647 -133.847586)
		(end 171.14647 -135.127238)
		(width 0.1524)
		(layer "B.Cu")
		(net "HSC_D_OC")
	)
	(segment
		(start 177.28184 -425.126658)
		(end 177.14087 -424.985688)
		(width 0.1524)
		(layer "B.Cu")
		(net "HSC_D_OC")
	)
	(segment
		(start 176.878234 -421.690546)
		(end 177.165762 -421.978074)
		(width 0.1524)
		(layer "B.Cu")
		(net "HSC_D_OC")
	)
	(segment
		(start 176.351438 -407.565606)
		(end 176.351438 -396.190724)
		(width 0.1524)
		(layer "B.Cu")
		(net "HSC_D_OC")
	)
	(segment
		(start 194.959478 -390.957054)
		(end 198.067676 -387.848856)
		(width 0.1524)
		(layer "B.Cu")
		(net "HSC_D_OC")
	)
	(segment
		(start 177.997104 -425.126658)
		(end 177.28184 -425.126658)
		(width 0.1524)
		(layer "B.Cu")
		(net "HSC_D_OC")
	)
	(segment
		(start 202.42657 -378.2568)
		(end 202.42657 -377.816872)
		(width 0.1524)
		(layer "B.Cu")
		(net "HSC_D_OC")
	)
	(segment
		(start 178.213004 -424.085004)
		(end 178.213004 -424.910758)
		(width 0.1524)
		(layer "B.Cu")
		(net "HSC_D_OC")
	)
	(segment
		(start 175.90643 -422.755568)
		(end 175.90643 -422.234614)
		(width 0.1524)
		(layer "B.Cu")
		(net "HSC_D_OC")
	)
	(segment
		(start 198.067676 -380.244858)
		(end 198.634604 -379.67793)
		(width 0.1524)
		(layer "B.Cu")
		(net "HSC_D_OC")
	)
	(segment
		(start 186.723782 -168.02481)
		(end 188.615066 -169.916094)
		(width 0.1524)
		(layer "B.Cu")
		(net "HSC_D_OC")
	)
	(segment
		(start 176.207674 -409.177236)
		(end 176.207674 -407.70937)
		(width 0.1524)
		(layer "B.Cu")
		(net "HSC_D_OC")
	)
	(segment
		(start 201.00544 -379.67793)
		(end 202.42657 -378.2568)
		(width 0.1524)
		(layer "B.Cu")
		(net "HSC_D_OC")
	)
	(segment
		(start 185.345578 -390.957054)
		(end 194.959478 -390.957054)
		(width 0.1524)
		(layer "B.Cu")
		(net "HSC_D_OC")
	)
	(segment
		(start 198.634604 -379.67793)
		(end 201.00544 -379.67793)
		(width 0.1524)
		(layer "B.Cu")
		(net "HSC_D_OC")
	)
	(segment
		(start 177.14087 -423.990008)
		(end 176.869344 -423.718482)
		(width 0.1524)
		(layer "B.Cu")
		(net "HSC_D_OC")
	)
	(segment
		(start 171.889674 -135.870442)
		(end 171.889674 -153.060654)
		(width 0.1524)
		(layer "B.Cu")
		(net "HSC_D_OC")
	)
	(segment
		(start 198.067676 -387.848856)
		(end 198.067676 -380.244858)
		(width 0.1524)
		(layer "B.Cu")
		(net "HSC_D_OC")
	)
	(segment
		(start 171.889674 -153.060654)
		(end 176.46523 -157.63621)
		(width 0.1524)
		(layer "B.Cu")
		(net "HSC_D_OC")
	)
	(segment
		(start 176.46523 -166.808912)
		(end 177.681128 -168.02481)
		(width 0.1524)
		(layer "B.Cu")
		(net "HSC_D_OC")
	)
	(segment
		(start 201.56551 -376.955812)
		(end 199.813418 -376.955812)
		(width 0.1524)
		(layer "In6.Cu")
		(net "HSC_D_OC")
	)
	(segment
		(start 202.42657 -377.816872)
		(end 201.56551 -376.955812)
		(width 0.1524)
		(layer "In6.Cu")
		(net "HSC_D_OC")
	)
	(segment
		(start 229.833424 -331.27823)
		(end 218.004136 -319.448942)
		(width 0.1524)
		(layer "In6.Cu")
		(net "HSC_D_OC")
	)
	(segment
		(start 177.653696 -410.623258)
		(end 177.486056 -410.790898)
		(width 0.1524)
		(layer "In6.Cu")
		(net "HSC_D_OC")
	)
	(segment
		(start 202.986132 -377.25731)
		(end 221.108524 -377.25731)
		(width 0.1524)
		(layer "In6.Cu")
		(net "HSC_D_OC")
	)
	(segment
		(start 197.282816 -390.887204)
		(end 192.43294 -395.73708)
		(width 0.1524)
		(layer "In6.Cu")
		(net "HSC_D_OC")
	)
	(segment
		(start 209.13344 -192.884552)
		(end 208.935066 -193.082926)
		(width 0.1524)
		(layer "In6.Cu")
		(net "HSC_D_OC")
	)
	(segment
		(start 202.42657 -377.816872)
		(end 202.986132 -377.25731)
		(width 0.1524)
		(layer "In6.Cu")
		(net "HSC_D_OC")
	)
	(segment
		(start 177.486056 -410.790898)
		(end 177.486056 -421.65778)
		(width 0.1524)
		(layer "In6.Cu")
		(net "HSC_D_OC")
	)
	(segment
		(start 229.833424 -368.53241)
		(end 229.833424 -331.27823)
		(width 0.1524)
		(layer "In6.Cu")
		(net "HSC_D_OC")
	)
	(segment
		(start 218.004136 -201.139044)
		(end 209.749644 -192.884552)
		(width 0.1524)
		(layer "In6.Cu")
		(net "HSC_D_OC")
	)
	(segment
		(start 197.282816 -379.486414)
		(end 197.282816 -390.887204)
		(width 0.1524)
		(layer "In6.Cu")
		(net "HSC_D_OC")
	)
	(segment
		(start 209.749644 -192.884552)
		(end 209.13344 -192.884552)
		(width 0.1524)
		(layer "In6.Cu")
		(net "HSC_D_OC")
	)
	(segment
		(start 221.108524 -377.25731)
		(end 229.833424 -368.53241)
		(width 0.1524)
		(layer "In6.Cu")
		(net "HSC_D_OC")
	)
	(segment
		(start 199.813418 -376.955812)
		(end 197.282816 -379.486414)
		(width 0.1524)
		(layer "In6.Cu")
		(net "HSC_D_OC")
	)
	(segment
		(start 218.004136 -319.448942)
		(end 218.004136 -201.139044)
		(width 0.1524)
		(layer "In6.Cu")
		(net "HSC_D_OC")
	)
	(segment
		(start 192.43294 -395.73708)
		(end 192.43294 -400.309842)
		(width 0.1524)
		(layer "In6.Cu")
		(net "HSC_D_OC")
	)
	(segment
		(start 177.486056 -421.65778)
		(end 177.165762 -421.978074)
		(width 0.1524)
		(layer "In6.Cu")
		(net "HSC_D_OC")
	)
	(segment
		(start 162.306508 -114.264948)
		(end 162.437826 -114.264948)
		(width 0.1524)
		(layer "In11.Cu")
		(net "HSC_D_OC")
	)
	(segment
		(start 162.890708 -122.75947)
		(end 164.438838 -124.3076)
		(width 0.1524)
		(layer "In11.Cu")
		(net "HSC_D_OC")
	)
	(segment
		(start 162.437826 -114.264948)
		(end 162.890708 -114.71783)
		(width 0.1524)
		(layer "In11.Cu")
		(net "HSC_D_OC")
	)
	(segment
		(start 164.438838 -126.43739)
		(end 164.484304 -126.482856)
		(width 0.1524)
		(layer "In11.Cu")
		(net "HSC_D_OC")
	)
	(segment
		(start 162.890708 -114.71783)
		(end 162.890708 -122.75947)
		(width 0.1524)
		(layer "In11.Cu")
		(net "HSC_D_OC")
	)
	(segment
		(start 164.438838 -124.3076)
		(end 164.438838 -126.43739)
		(width 0.1524)
		(layer "In11.Cu")
		(net "HSC_D_OC")
	)
	(segment
		(start 228.818948 -400.670268)
		(end 229.303072 -400.670268)
		(width 0.1524)
		(layer "F.Cu")
		(net "HSC_CS_4")
	)
	(segment
		(start 227.934774 -399.996152)
		(end 228.144832 -399.996152)
		(width 0.1524)
		(layer "F.Cu")
		(net "HSC_CS_4")
	)
	(segment
		(start 226.49815 -400.972782)
		(end 226.958144 -400.972782)
		(width 0.1524)
		(layer "F.Cu")
		(net "HSC_CS_4")
	)
	(segment
		(start 226.958144 -400.972782)
		(end 227.934774 -399.996152)
		(width 0.1524)
		(layer "F.Cu")
		(net "HSC_CS_4")
	)
	(segment
		(start 228.144832 -399.996152)
		(end 228.818948 -400.670268)
		(width 0.1524)
		(layer "F.Cu")
		(net "HSC_CS_4")
	)
	(via
		(at 227.934774 -399.996152)
		(size 0.762)
		(drill 0.381)
		(layers "F.Cu" "B.Cu")
		(net "HSC_CS_4")
	)
	(segment
		(start 216.4715 -400.972782)
		(end 215.83015 -400.972782)
		(width 0.1524)
		(layer "F.Cu")
		(net "HSC_CS_3")
	)
	(segment
		(start 218.635072 -400.670268)
		(end 218.150948 -400.670268)
		(width 0.1524)
		(layer "F.Cu")
		(net "HSC_CS_3")
	)
	(segment
		(start 218.150948 -400.670268)
		(end 217.653362 -400.172682)
		(width 0.1524)
		(layer "F.Cu")
		(net "HSC_CS_3")
	)
	(segment
		(start 217.2716 -400.172682)
		(end 216.4715 -400.972782)
		(width 0.1524)
		(layer "F.Cu")
		(net "HSC_CS_3")
	)
	(segment
		(start 217.653362 -400.172682)
		(end 217.2716 -400.172682)
		(width 0.1524)
		(layer "F.Cu")
		(net "HSC_CS_3")
	)
	(via
		(at 217.2716 -400.172682)
		(size 0.762)
		(drill 0.381)
		(layers "F.Cu" "B.Cu")
		(net "HSC_CS_3")
	)
	(segment
		(start 206.6036 -400.172682)
		(end 206.985362 -400.172682)
		(width 0.1524)
		(layer "F.Cu")
		(net "HSC_CS_2")
	)
	(segment
		(start 205.16215 -400.972782)
		(end 205.4479 -400.972782)
		(width 0.1524)
		(layer "F.Cu")
		(net "HSC_CS_2")
	)
	(segment
		(start 207.482948 -400.670268)
		(end 207.967072 -400.670268)
		(width 0.1524)
		(layer "F.Cu")
		(net "HSC_CS_2")
	)
	(segment
		(start 206.985362 -400.172682)
		(end 207.482948 -400.670268)
		(width 0.1524)
		(layer "F.Cu")
		(net "HSC_CS_2")
	)
	(segment
		(start 205.4479 -400.972782)
		(end 206.248 -400.172682)
		(width 0.1524)
		(layer "F.Cu")
		(net "HSC_CS_2")
	)
	(segment
		(start 206.248 -400.172682)
		(end 206.6036 -400.172682)
		(width 0.1524)
		(layer "F.Cu")
		(net "HSC_CS_2")
	)
	(via
		(at 206.6036 -400.172682)
		(size 0.762)
		(drill 0.381)
		(layers "F.Cu" "B.Cu")
		(net "HSC_CS_2")
	)
	(segment
		(start 194.62115 -399.982182)
		(end 195.133214 -399.470118)
		(width 0.1524)
		(layer "F.Cu")
		(net "HSC_CS_1")
	)
	(segment
		(start 197.184518 -400.670268)
		(end 197.299072 -400.670268)
		(width 0.1524)
		(layer "F.Cu")
		(net "HSC_CS_1")
	)
	(segment
		(start 195.984368 -399.470118)
		(end 197.184518 -400.670268)
		(width 0.1524)
		(layer "F.Cu")
		(net "HSC_CS_1")
	)
	(segment
		(start 195.133214 -399.470118)
		(end 195.984368 -399.470118)
		(width 0.1524)
		(layer "F.Cu")
		(net "HSC_CS_1")
	)
	(via
		(at 195.984368 -399.470118)
		(size 0.762)
		(drill 0.381)
		(layers "F.Cu" "B.Cu")
		(net "HSC_CS_1")
	)
	(segment
		(start 181.713378 -400.794728)
		(end 182.041038 -400.794728)
		(width 0.1524)
		(layer "F.Cu")
		(net "HSC_CS")
	)
	(segment
		(start 179.9844 -399.420842)
		(end 180.3781 -399.814542)
		(width 0.1524)
		(layer "F.Cu")
		(net "HSC_CS")
	)
	(segment
		(start 180.3781 -399.814542)
		(end 180.733192 -399.814542)
		(width 0.1524)
		(layer "F.Cu")
		(net "HSC_CS")
	)
	(segment
		(start 180.733192 -399.814542)
		(end 181.713378 -400.794728)
		(width 0.1524)
		(layer "F.Cu")
		(net "HSC_CS")
	)
	(segment
		(start 179.11699 -399.420842)
		(end 179.9844 -399.420842)
		(width 0.1524)
		(layer "F.Cu")
		(net "HSC_CS")
	)
	(via
		(at 179.9844 -399.420842)
		(size 0.508)
		(drill 0.254)
		(layers "F.Cu" "B.Cu")
		(net "HSC_CS")
	)
	(segment
		(start 180.975 -398.145)
		(end 181.323742 -398.493742)
		(width 0.1524)
		(layer "F.Cu")
		(net "HSC_ADDR")
	)
	(segment
		(start 179.12461 -396.385542)
		(end 179.940458 -396.385542)
		(width 0.1524)
		(layer "F.Cu")
		(net "HSC_ADDR")
	)
	(segment
		(start 179.08905 -395.351)
		(end 179.08905 -396.349982)
		(width 0.1524)
		(layer "F.Cu")
		(net "HSC_ADDR")
	)
	(segment
		(start 179.959 -396.367)
		(end 180.975 -397.383)
		(width 0.1524)
		(layer "F.Cu")
		(net "HSC_ADDR")
	)
	(segment
		(start 182.002176 -398.493742)
		(end 183.02859 -399.520156)
		(width 0.1524)
		(layer "F.Cu")
		(net "HSC_ADDR")
	)
	(segment
		(start 179.08905 -396.349982)
		(end 179.12461 -396.385542)
		(width 0.1524)
		(layer "F.Cu")
		(net "HSC_ADDR")
	)
	(segment
		(start 183.02859 -399.520156)
		(end 183.02859 -399.682208)
		(width 0.1524)
		(layer "F.Cu")
		(net "HSC_ADDR")
	)
	(segment
		(start 179.940458 -396.385542)
		(end 179.959 -396.367)
		(width 0.1524)
		(layer "F.Cu")
		(net "HSC_ADDR")
	)
	(segment
		(start 181.323742 -398.493742)
		(end 182.002176 -398.493742)
		(width 0.1524)
		(layer "F.Cu")
		(net "HSC_ADDR")
	)
	(segment
		(start 180.975 -397.383)
		(end 180.975 -398.145)
		(width 0.1524)
		(layer "F.Cu")
		(net "HSC_ADDR")
	)
	(via
		(at 179.959 -396.367)
		(size 0.508)
		(drill 0.254)
		(layers "F.Cu" "B.Cu")
		(net "HSC_ADDR")
	)
	(segment
		(start 14.382496 -71.860664)
		(end 14.972284 -72.450452)
		(width 0.10668)
		(layer "F.Cu")
		(net "HP_LVC3_OCP_V3_2_PRSNT2_N_R")
	)
	(segment
		(start 13.335 -79.542386)
		(end 13.335 -78.4479)
		(width 0.10668)
		(layer "F.Cu")
		(net "HP_LVC3_OCP_V3_2_PRSNT2_N_R")
	)
	(segment
		(start 17.2847 -72.450452)
		(end 17.7292 -72.894952)
		(width 0.10668)
		(layer "F.Cu")
		(net "HP_LVC3_OCP_V3_2_PRSNT2_N_R")
	)
	(segment
		(start 14.627352 -68.128642)
		(end 13.962126 -68.793868)
		(width 0.10668)
		(layer "F.Cu")
		(net "HP_LVC3_OCP_V3_2_PRSNT2_N_R")
	)
	(segment
		(start 14.733016 -69.743574)
		(end 15.18412 -70.194678)
		(width 0.10668)
		(layer "F.Cu")
		(net "HP_LVC3_OCP_V3_2_PRSNT2_N_R")
	)
	(segment
		(start 14.972284 -72.450452)
		(end 17.2847 -72.450452)
		(width 0.10668)
		(layer "F.Cu")
		(net "HP_LVC3_OCP_V3_2_PRSNT2_N_R")
	)
	(segment
		(start 13.90396 -79.669386)
		(end 13.462 -79.669386)
		(width 0.10668)
		(layer "F.Cu")
		(net "HP_LVC3_OCP_V3_2_PRSNT2_N_R")
	)
	(segment
		(start 17.7292 -77.1398)
		(end 17.145 -77.724)
		(width 0.10668)
		(layer "F.Cu")
		(net "HP_LVC3_OCP_V3_2_PRSNT2_N_R")
	)
	(segment
		(start 16.256 -77.724)
		(end 14.986254 -77.724)
		(width 0.10668)
		(layer "F.Cu")
		(net "HP_LVC3_OCP_V3_2_PRSNT2_N_R")
	)
	(segment
		(start 13.462 -79.669386)
		(end 13.335 -79.542386)
		(width 0.10668)
		(layer "F.Cu")
		(net "HP_LVC3_OCP_V3_2_PRSNT2_N_R")
	)
	(segment
		(start 14.818106 -70.560692)
		(end 15.18412 -70.194678)
		(width 0.10668)
		(layer "F.Cu")
		(net "HP_LVC3_OCP_V3_2_PRSNT2_N_R")
	)
	(segment
		(start 17.145 -77.724)
		(end 16.256 -77.724)
		(width 0.10668)
		(layer "F.Cu")
		(net "HP_LVC3_OCP_V3_2_PRSNT2_N_R")
	)
	(segment
		(start 14.34084 -78.369414)
		(end 13.90396 -78.369414)
		(width 0.10668)
		(layer "F.Cu")
		(net "HP_LVC3_OCP_V3_2_PRSNT2_N_R")
	)
	(segment
		(start 13.263118 -70.687692)
		(end 13.263118 -71.733664)
		(width 0.10668)
		(layer "F.Cu")
		(net "HP_LVC3_OCP_V3_2_PRSNT2_N_R")
	)
	(segment
		(start 17.7292 -72.894952)
		(end 17.7292 -77.1398)
		(width 0.10668)
		(layer "F.Cu")
		(net "HP_LVC3_OCP_V3_2_PRSNT2_N_R")
	)
	(segment
		(start 13.902182 -78.367636)
		(end 13.90396 -78.369414)
		(width 0.10668)
		(layer "F.Cu")
		(net "HP_LVC3_OCP_V3_2_PRSNT2_N_R")
	)
	(segment
		(start 14.294866 -69.743574)
		(end 14.733016 -69.743574)
		(width 0.10668)
		(layer "F.Cu")
		(net "HP_LVC3_OCP_V3_2_PRSNT2_N_R")
	)
	(segment
		(start 13.91412 -70.560692)
		(end 14.818106 -70.560692)
		(width 0.10668)
		(layer "F.Cu")
		(net "HP_LVC3_OCP_V3_2_PRSNT2_N_R")
	)
	(segment
		(start 13.415264 -78.367636)
		(end 13.902182 -78.367636)
		(width 0.10668)
		(layer "F.Cu")
		(net "HP_LVC3_OCP_V3_2_PRSNT2_N_R")
	)
	(segment
		(start 14.986254 -77.724)
		(end 14.34084 -78.369414)
		(width 0.10668)
		(layer "F.Cu")
		(net "HP_LVC3_OCP_V3_2_PRSNT2_N_R")
	)
	(segment
		(start 13.962126 -69.410834)
		(end 14.294866 -69.743574)
		(width 0.10668)
		(layer "F.Cu")
		(net "HP_LVC3_OCP_V3_2_PRSNT2_N_R")
	)
	(segment
		(start 13.390118 -70.560692)
		(end 13.263118 -70.687692)
		(width 0.10668)
		(layer "F.Cu")
		(net "HP_LVC3_OCP_V3_2_PRSNT2_N_R")
	)
	(segment
		(start 13.335 -78.4479)
		(end 13.415264 -78.367636)
		(width 0.10668)
		(layer "F.Cu")
		(net "HP_LVC3_OCP_V3_2_PRSNT2_N_R")
	)
	(segment
		(start 13.91412 -70.560692)
		(end 13.390118 -70.560692)
		(width 0.10668)
		(layer "F.Cu")
		(net "HP_LVC3_OCP_V3_2_PRSNT2_N_R")
	)
	(segment
		(start 15.1511 -68.128642)
		(end 14.627352 -68.128642)
		(width 0.10668)
		(layer "F.Cu")
		(net "HP_LVC3_OCP_V3_2_PRSNT2_N_R")
	)
	(segment
		(start 13.263118 -71.733664)
		(end 13.390118 -71.860664)
		(width 0.10668)
		(layer "F.Cu")
		(net "HP_LVC3_OCP_V3_2_PRSNT2_N_R")
	)
	(segment
		(start 13.390118 -71.860664)
		(end 13.91412 -71.860664)
		(width 0.10668)
		(layer "F.Cu")
		(net "HP_LVC3_OCP_V3_2_PRSNT2_N_R")
	)
	(segment
		(start 13.962126 -68.793868)
		(end 13.962126 -69.410834)
		(width 0.10668)
		(layer "F.Cu")
		(net "HP_LVC3_OCP_V3_2_PRSNT2_N_R")
	)
	(segment
		(start 13.91412 -71.860664)
		(end 14.382496 -71.860664)
		(width 0.10668)
		(layer "F.Cu")
		(net "HP_LVC3_OCP_V3_2_PRSNT2_N_R")
	)
	(via
		(at 16.256 -77.724)
		(size 0.762)
		(drill 0.381)
		(layers "F.Cu" "B.Cu")
		(net "HP_LVC3_OCP_V3_2_PRSNT2_N_R")
	)
	(segment
		(start 33.552384 -75.741276)
		(end 33.552384 -86.96452)
		(width 0.10668)
		(layer "F.Cu")
		(net "HP_LVC3_OCP_V3_2_PRSNT2_PLD_N")
	)
	(segment
		(start 49.341532 -88.959436)
		(end 50.850546 -90.46845)
		(width 0.10668)
		(layer "F.Cu")
		(net "HP_LVC3_OCP_V3_2_PRSNT2_PLD_N")
	)
	(segment
		(start 56.816498 -130.771138)
		(end 56.816498 -132.703062)
		(width 0.10668)
		(layer "F.Cu")
		(net "HP_LVC3_OCP_V3_2_PRSNT2_PLD_N")
	)
	(segment
		(start 15.98422 -69.178678)
		(end 26.989786 -69.178678)
		(width 0.10668)
		(layer "F.Cu")
		(net "HP_LVC3_OCP_V3_2_PRSNT2_PLD_N")
	)
	(segment
		(start 15.98422 -70.194678)
		(end 15.98422 -69.178678)
		(width 0.10668)
		(layer "F.Cu")
		(net "HP_LVC3_OCP_V3_2_PRSNT2_PLD_N")
	)
	(segment
		(start 35.5473 -88.959436)
		(end 49.341532 -88.959436)
		(width 0.10668)
		(layer "F.Cu")
		(net "HP_LVC3_OCP_V3_2_PRSNT2_PLD_N")
	)
	(segment
		(start 33.552384 -86.96452)
		(end 35.5473 -88.959436)
		(width 0.10668)
		(layer "F.Cu")
		(net "HP_LVC3_OCP_V3_2_PRSNT2_PLD_N")
	)
	(segment
		(start 50.850546 -90.46845)
		(end 50.850546 -124.805186)
		(width 0.10668)
		(layer "F.Cu")
		(net "HP_LVC3_OCP_V3_2_PRSNT2_PLD_N")
	)
	(segment
		(start 50.850546 -124.805186)
		(end 56.816498 -130.771138)
		(width 0.10668)
		(layer "F.Cu")
		(net "HP_LVC3_OCP_V3_2_PRSNT2_PLD_N")
	)
	(segment
		(start 26.989786 -69.178678)
		(end 33.552384 -75.741276)
		(width 0.10668)
		(layer "F.Cu")
		(net "HP_LVC3_OCP_V3_2_PRSNT2_PLD_N")
	)
	(via
		(at 56.816498 -132.703062)
		(size 0.508)
		(drill 0.254)
		(layers "F.Cu" "B.Cu")
		(net "HP_LVC3_OCP_V3_2_PRSNT2_PLD_N")
	)
	(segment
		(start 110.38713 -122.853704)
		(end 65.244726 -122.853704)
		(width 0.10668)
		(layer "B.Cu")
		(net "HP_LVC3_OCP_V3_2_PRSNT2_PLD_N")
	)
	(segment
		(start 165.80866 -123.48337)
		(end 158.381192 -123.48337)
		(width 0.10668)
		(layer "B.Cu")
		(net "HP_LVC3_OCP_V3_2_PRSNT2_PLD_N")
	)
	(segment
		(start 170.8023 -121.537222)
		(end 170.482514 -121.857008)
		(width 0.10668)
		(layer "B.Cu")
		(net "HP_LVC3_OCP_V3_2_PRSNT2_PLD_N")
	)
	(segment
		(start 132.102098 -122.853704)
		(end 112.798352 -122.853704)
		(width 0.10668)
		(layer "B.Cu")
		(net "HP_LVC3_OCP_V3_2_PRSNT2_PLD_N")
	)
	(segment
		(start 153.298398 -123.95835)
		(end 152.90165 -124.355098)
		(width 0.10668)
		(layer "B.Cu")
		(net "HP_LVC3_OCP_V3_2_PRSNT2_PLD_N")
	)
	(segment
		(start 135.646668 -119.309134)
		(end 132.102098 -122.853704)
		(width 0.10668)
		(layer "B.Cu")
		(net "HP_LVC3_OCP_V3_2_PRSNT2_PLD_N")
	)
	(segment
		(start 65.244726 -122.853704)
		(end 56.816498 -131.281932)
		(width 0.10668)
		(layer "B.Cu")
		(net "HP_LVC3_OCP_V3_2_PRSNT2_PLD_N")
	)
	(segment
		(start 111.079534 -122.1613)
		(end 110.38713 -122.853704)
		(width 0.10668)
		(layer "B.Cu")
		(net "HP_LVC3_OCP_V3_2_PRSNT2_PLD_N")
	)
	(segment
		(start 56.816498 -131.281932)
		(end 56.816498 -132.703062)
		(width 0.10668)
		(layer "B.Cu")
		(net "HP_LVC3_OCP_V3_2_PRSNT2_PLD_N")
	)
	(segment
		(start 157.906212 -123.95835)
		(end 153.298398 -123.95835)
		(width 0.10668)
		(layer "B.Cu")
		(net "HP_LVC3_OCP_V3_2_PRSNT2_PLD_N")
	)
	(segment
		(start 167.435022 -121.857008)
		(end 165.80866 -123.48337)
		(width 0.10668)
		(layer "B.Cu")
		(net "HP_LVC3_OCP_V3_2_PRSNT2_PLD_N")
	)
	(segment
		(start 170.482514 -121.857008)
		(end 167.435022 -121.857008)
		(width 0.10668)
		(layer "B.Cu")
		(net "HP_LVC3_OCP_V3_2_PRSNT2_PLD_N")
	)
	(segment
		(start 170.8023 -120.233948)
		(end 170.8023 -121.537222)
		(width 0.10668)
		(layer "B.Cu")
		(net "HP_LVC3_OCP_V3_2_PRSNT2_PLD_N")
	)
	(segment
		(start 152.90165 -124.355098)
		(end 148.84781 -124.355098)
		(width 0.10668)
		(layer "B.Cu")
		(net "HP_LVC3_OCP_V3_2_PRSNT2_PLD_N")
	)
	(segment
		(start 112.105948 -122.1613)
		(end 111.079534 -122.1613)
		(width 0.10668)
		(layer "B.Cu")
		(net "HP_LVC3_OCP_V3_2_PRSNT2_PLD_N")
	)
	(segment
		(start 143.801846 -119.309134)
		(end 135.646668 -119.309134)
		(width 0.10668)
		(layer "B.Cu")
		(net "HP_LVC3_OCP_V3_2_PRSNT2_PLD_N")
	)
	(segment
		(start 158.381192 -123.48337)
		(end 157.906212 -123.95835)
		(width 0.10668)
		(layer "B.Cu")
		(net "HP_LVC3_OCP_V3_2_PRSNT2_PLD_N")
	)
	(segment
		(start 148.84781 -124.355098)
		(end 143.801846 -119.309134)
		(width 0.10668)
		(layer "B.Cu")
		(net "HP_LVC3_OCP_V3_2_PRSNT2_PLD_N")
	)
	(segment
		(start 112.798352 -122.853704)
		(end 112.105948 -122.1613)
		(width 0.10668)
		(layer "B.Cu")
		(net "HP_LVC3_OCP_V3_2_PRSNT2_PLD_N")
	)
	(segment
		(start 63.0809 -42.0878)
		(end 61.85662 -43.31208)
		(width 0.10668)
		(layer "F.Cu")
		(net "HP_LVC3_OCP_V3_2_P12V_PWRGD")
	)
	(segment
		(start 65.272412 -28.389834)
		(end 64.484758 -28.389834)
		(width 0.10668)
		(layer "F.Cu")
		(net "HP_LVC3_OCP_V3_2_P12V_PWRGD")
	)
	(segment
		(start 58.801 -37.592)
		(end 59.436 -37.592)
		(width 0.10668)
		(layer "F.Cu")
		(net "HP_LVC3_OCP_V3_2_P12V_PWRGD")
	)
	(segment
		(start 90.91295 -78.105)
		(end 90.91295 -77.236828)
		(width 0.10668)
		(layer "F.Cu")
		(net "HP_LVC3_OCP_V3_2_P12V_PWRGD")
	)
	(segment
		(start 82.219546 -18.742152)
		(end 82.051144 -18.57375)
		(width 0.10668)
		(layer "F.Cu")
		(net "HP_LVC3_OCP_V3_2_P12V_PWRGD")
	)
	(segment
		(start 63.594488 -28.382722)
		(end 64.476122 -28.382722)
		(width 0.10668)
		(layer "F.Cu")
		(net "HP_LVC3_OCP_V3_2_P12V_PWRGD")
	)
	(segment
		(start 153.940256 -34.647632)
		(end 157.28696 -31.300928)
		(width 0.10668)
		(layer "F.Cu")
		(net "HP_LVC3_OCP_V3_2_P12V_PWRGD")
	)
	(segment
		(start 58.297064 -38.603936)
		(end 58.297064 -38.095936)
		(width 0.10668)
		(layer "F.Cu")
		(net "HP_LVC3_OCP_V3_2_P12V_PWRGD")
	)
	(segment
		(start 82.706718 -18.742152)
		(end 82.219546 -18.742152)
		(width 0.10668)
		(layer "F.Cu")
		(net "HP_LVC3_OCP_V3_2_P12V_PWRGD")
	)
	(segment
		(start 64.476122 -28.382722)
		(end 64.483996 -28.390596)
		(width 0.10668)
		(layer "F.Cu")
		(net "HP_LVC3_OCP_V3_2_P12V_PWRGD")
	)
	(segment
		(start 57.00903 -46.67123)
		(end 57.00903 -52.53228)
		(width 0.10668)
		(layer "F.Cu")
		(net "HP_LVC3_OCP_V3_2_P12V_PWRGD")
	)
	(segment
		(start 58.297064 -38.095936)
		(end 58.801 -37.592)
		(width 0.10668)
		(layer "F.Cu")
		(net "HP_LVC3_OCP_V3_2_P12V_PWRGD")
	)
	(segment
		(start 61.85662 -43.31208)
		(end 60.36818 -43.31208)
		(width 0.10668)
		(layer "F.Cu")
		(net "HP_LVC3_OCP_V3_2_P12V_PWRGD")
	)
	(segment
		(start 153.248868 -34.647632)
		(end 153.940256 -34.647632)
		(width 0.10668)
		(layer "F.Cu")
		(net "HP_LVC3_OCP_V3_2_P12V_PWRGD")
	)
	(segment
		(start 82.706718 -17.745202)
		(end 82.706718 -18.742152)
		(width 0.10668)
		(layer "F.Cu")
		(net "HP_LVC3_OCP_V3_2_P12V_PWRGD")
	)
	(segment
		(start 64.484758 -28.389834)
		(end 64.483996 -28.390596)
		(width 0.10668)
		(layer "F.Cu")
		(net "HP_LVC3_OCP_V3_2_P12V_PWRGD")
	)
	(segment
		(start 60.36818 -43.31208)
		(end 57.00903 -46.67123)
		(width 0.10668)
		(layer "F.Cu")
		(net "HP_LVC3_OCP_V3_2_P12V_PWRGD")
	)
	(via
		(at 59.436 -37.592)
		(size 0.508)
		(drill 0.254)
		(layers "F.Cu" "B.Cu")
		(net "HP_LVC3_OCP_V3_2_P12V_PWRGD")
	)
	(via
		(at 90.91295 -77.236828)
		(size 0.508)
		(drill 0.254)
		(layers "F.Cu" "B.Cu")
		(net "HP_LVC3_OCP_V3_2_P12V_PWRGD")
	)
	(via
		(at 64.483996 -28.390596)
		(size 0.508)
		(drill 0.254)
		(layers "F.Cu" "B.Cu")
		(net "HP_LVC3_OCP_V3_2_P12V_PWRGD")
	)
	(via
		(at 157.28696 -31.300928)
		(size 0.508)
		(drill 0.254)
		(layers "F.Cu" "B.Cu")
		(net "HP_LVC3_OCP_V3_2_P12V_PWRGD")
	)
	(via
		(at 86.634828 -14.302232)
		(size 0.508)
		(drill 0.254)
		(layers "F.Cu" "B.Cu")
		(net "HP_LVC3_OCP_V3_2_P12V_PWRGD")
	)
	(via
		(at 99.39274 -57.879234)
		(size 0.508)
		(drill 0.254)
		(layers "F.Cu" "B.Cu")
		(net "HP_LVC3_OCP_V3_2_P12V_PWRGD")
	)
	(via
		(at 63.0809 -42.0878)
		(size 0.508)
		(drill 0.254)
		(layers "F.Cu" "B.Cu")
		(net "HP_LVC3_OCP_V3_2_P12V_PWRGD")
	)
	(via
		(at 82.051144 -18.57375)
		(size 0.508)
		(drill 0.254)
		(layers "F.Cu" "B.Cu")
		(net "HP_LVC3_OCP_V3_2_P12V_PWRGD")
	)
	(segment
		(start 61.46292 -37.592)
		(end 62.44336 -38.57244)
		(width 0.10668)
		(layer "B.Cu")
		(net "HP_LVC3_OCP_V3_2_P12V_PWRGD")
	)
	(segment
		(start 64.476122 -28.382722)
		(end 64.483996 -28.390596)
		(width 0.10668)
		(layer "B.Cu")
		(net "HP_LVC3_OCP_V3_2_P12V_PWRGD")
	)
	(segment
		(start 62.44336 -39.23284)
		(end 63.0809 -39.87038)
		(width 0.10668)
		(layer "B.Cu")
		(net "HP_LVC3_OCP_V3_2_P12V_PWRGD")
	)
	(segment
		(start 63.0809 -39.87038)
		(end 63.0809 -42.0878)
		(width 0.10668)
		(layer "B.Cu")
		(net "HP_LVC3_OCP_V3_2_P12V_PWRGD")
	)
	(segment
		(start 59.436 -37.592)
		(end 61.46292 -37.592)
		(width 0.10668)
		(layer "B.Cu")
		(net "HP_LVC3_OCP_V3_2_P12V_PWRGD")
	)
	(segment
		(start 62.44336 -38.57244)
		(end 62.44336 -39.23284)
		(width 0.10668)
		(layer "B.Cu")
		(net "HP_LVC3_OCP_V3_2_P12V_PWRGD")
	)
	(segment
		(start 63.594488 -28.382722)
		(end 64.476122 -28.382722)
		(width 0.10668)
		(layer "B.Cu")
		(net "HP_LVC3_OCP_V3_2_P12V_PWRGD")
	)
	(segment
		(start 93.263466 -76.602082)
		(end 92.62872 -77.236828)
		(width 0.11684)
		(layer "In2.Cu")
		(net "HP_LVC3_OCP_V3_2_P12V_PWRGD")
	)
	(segment
		(start 94.816676 -72.451976)
		(end 94.816676 -75.958954)
		(width 0.11684)
		(layer "In2.Cu")
		(net "HP_LVC3_OCP_V3_2_P12V_PWRGD")
	)
	(segment
		(start 99.72675 -58.213244)
		(end 99.72675 -62.496954)
		(width 0.11684)
		(layer "In2.Cu")
		(net "HP_LVC3_OCP_V3_2_P12V_PWRGD")
	)
	(segment
		(start 99.39274 -57.879234)
		(end 99.72675 -58.213244)
		(width 0.11684)
		(layer "In2.Cu")
		(net "HP_LVC3_OCP_V3_2_P12V_PWRGD")
	)
	(segment
		(start 62.765432 -35.941508)
		(end 61.11494 -37.592)
		(width 0.11684)
		(layer "In2.Cu")
		(net "HP_LVC3_OCP_V3_2_P12V_PWRGD")
	)
	(segment
		(start 62.765432 -29.49448)
		(end 62.765432 -35.941508)
		(width 0.11684)
		(layer "In2.Cu")
		(net "HP_LVC3_OCP_V3_2_P12V_PWRGD")
	)
	(segment
		(start 94.173548 -76.602082)
		(end 93.263466 -76.602082)
		(width 0.11684)
		(layer "In2.Cu")
		(net "HP_LVC3_OCP_V3_2_P12V_PWRGD")
	)
	(segment
		(start 64.483996 -28.390596)
		(end 63.869316 -28.390596)
		(width 0.11684)
		(layer "In2.Cu")
		(net "HP_LVC3_OCP_V3_2_P12V_PWRGD")
	)
	(segment
		(start 97.455482 -69.81317)
		(end 94.816676 -72.451976)
		(width 0.11684)
		(layer "In2.Cu")
		(net "HP_LVC3_OCP_V3_2_P12V_PWRGD")
	)
	(segment
		(start 61.11494 -37.592)
		(end 59.436 -37.592)
		(width 0.11684)
		(layer "In2.Cu")
		(net "HP_LVC3_OCP_V3_2_P12V_PWRGD")
	)
	(segment
		(start 97.455482 -64.768222)
		(end 97.455482 -69.81317)
		(width 0.11684)
		(layer "In2.Cu")
		(net "HP_LVC3_OCP_V3_2_P12V_PWRGD")
	)
	(segment
		(start 94.816676 -75.958954)
		(end 94.173548 -76.602082)
		(width 0.11684)
		(layer "In2.Cu")
		(net "HP_LVC3_OCP_V3_2_P12V_PWRGD")
	)
	(segment
		(start 63.869316 -28.390596)
		(end 62.765432 -29.49448)
		(width 0.11684)
		(layer "In2.Cu")
		(net "HP_LVC3_OCP_V3_2_P12V_PWRGD")
	)
	(segment
		(start 99.72675 -62.496954)
		(end 97.455482 -64.768222)
		(width 0.11684)
		(layer "In2.Cu")
		(net "HP_LVC3_OCP_V3_2_P12V_PWRGD")
	)
	(segment
		(start 92.62872 -77.236828)
		(end 90.91295 -77.236828)
		(width 0.11684)
		(layer "In2.Cu")
		(net "HP_LVC3_OCP_V3_2_P12V_PWRGD")
	)
	(segment
		(start 74.197464 -24.363426)
		(end 74.295 -24.460962)
		(width 0.11684)
		(layer "In4.Cu")
		(net "HP_LVC3_OCP_V3_2_P12V_PWRGD")
	)
	(segment
		(start 82.051144 -18.57375)
		(end 82.051144 -17.992344)
		(width 0.11684)
		(layer "In4.Cu")
		(net "HP_LVC3_OCP_V3_2_P12V_PWRGD")
	)
	(segment
		(start 74.197464 -22.97938)
		(end 74.197464 -24.363426)
		(width 0.11684)
		(layer "In4.Cu")
		(net "HP_LVC3_OCP_V3_2_P12V_PWRGD")
	)
	(segment
		(start 65.712848 -29.543248)
		(end 64.560196 -28.390596)
		(width 0.11684)
		(layer "In4.Cu")
		(net "HP_LVC3_OCP_V3_2_P12V_PWRGD")
	)
	(segment
		(start 72.770746 -30.8356)
		(end 71.714106 -30.8356)
		(width 0.11684)
		(layer "In4.Cu")
		(net "HP_LVC3_OCP_V3_2_P12V_PWRGD")
	)
	(segment
		(start 64.560196 -28.390596)
		(end 64.483996 -28.390596)
		(width 0.11684)
		(layer "In4.Cu")
		(net "HP_LVC3_OCP_V3_2_P12V_PWRGD")
	)
	(segment
		(start 75.634342 -19.327114)
		(end 75.634342 -21.542502)
		(width 0.11684)
		(layer "In4.Cu")
		(net "HP_LVC3_OCP_V3_2_P12V_PWRGD")
	)
	(segment
		(start 80.50911 -16.45031)
		(end 79.48549 -16.45031)
		(width 0.11684)
		(layer "In4.Cu")
		(net "HP_LVC3_OCP_V3_2_P12V_PWRGD")
	)
	(segment
		(start 74.295 -24.460962)
		(end 74.295 -29.311346)
		(width 0.11684)
		(layer "In4.Cu")
		(net "HP_LVC3_OCP_V3_2_P12V_PWRGD")
	)
	(segment
		(start 77.314298 -17.647158)
		(end 75.634342 -19.327114)
		(width 0.11684)
		(layer "In4.Cu")
		(net "HP_LVC3_OCP_V3_2_P12V_PWRGD")
	)
	(segment
		(start 79.48549 -16.45031)
		(end 78.288642 -17.647158)
		(width 0.11684)
		(layer "In4.Cu")
		(net "HP_LVC3_OCP_V3_2_P12V_PWRGD")
	)
	(segment
		(start 78.288642 -17.647158)
		(end 77.314298 -17.647158)
		(width 0.11684)
		(layer "In4.Cu")
		(net "HP_LVC3_OCP_V3_2_P12V_PWRGD")
	)
	(segment
		(start 82.051144 -17.992344)
		(end 80.50911 -16.45031)
		(width 0.11684)
		(layer "In4.Cu")
		(net "HP_LVC3_OCP_V3_2_P12V_PWRGD")
	)
	(segment
		(start 74.295 -29.311346)
		(end 72.770746 -30.8356)
		(width 0.11684)
		(layer "In4.Cu")
		(net "HP_LVC3_OCP_V3_2_P12V_PWRGD")
	)
	(segment
		(start 70.421754 -29.543248)
		(end 65.712848 -29.543248)
		(width 0.11684)
		(layer "In4.Cu")
		(net "HP_LVC3_OCP_V3_2_P12V_PWRGD")
	)
	(segment
		(start 71.714106 -30.8356)
		(end 70.421754 -29.543248)
		(width 0.11684)
		(layer "In4.Cu")
		(net "HP_LVC3_OCP_V3_2_P12V_PWRGD")
	)
	(segment
		(start 75.634342 -21.542502)
		(end 74.197464 -22.97938)
		(width 0.11684)
		(layer "In4.Cu")
		(net "HP_LVC3_OCP_V3_2_P12V_PWRGD")
	)
	(segment
		(start 129.39014 -17.089882)
		(end 125.572012 -13.271754)
		(width 0.11684)
		(layer "In6.Cu")
		(net "HP_LVC3_OCP_V3_2_P12V_PWRGD")
	)
	(segment
		(start 153.05532 -31.300928)
		(end 142.86357 -21.109178)
		(width 0.11684)
		(layer "In6.Cu")
		(net "HP_LVC3_OCP_V3_2_P12V_PWRGD")
	)
	(segment
		(start 125.572012 -13.271754)
		(end 105.83545 -13.271754)
		(width 0.11684)
		(layer "In6.Cu")
		(net "HP_LVC3_OCP_V3_2_P12V_PWRGD")
	)
	(segment
		(start 142.86357 -21.109178)
		(end 142.86357 -17.473676)
		(width 0.11684)
		(layer "In6.Cu")
		(net "HP_LVC3_OCP_V3_2_P12V_PWRGD")
	)
	(segment
		(start 105.83545 -13.271754)
		(end 104.804972 -14.302232)
		(width 0.11684)
		(layer "In6.Cu")
		(net "HP_LVC3_OCP_V3_2_P12V_PWRGD")
	)
	(segment
		(start 157.28696 -31.300928)
		(end 153.05532 -31.300928)
		(width 0.11684)
		(layer "In6.Cu")
		(net "HP_LVC3_OCP_V3_2_P12V_PWRGD")
	)
	(segment
		(start 104.804972 -14.302232)
		(end 86.634828 -14.302232)
		(width 0.11684)
		(layer "In6.Cu")
		(net "HP_LVC3_OCP_V3_2_P12V_PWRGD")
	)
	(segment
		(start 142.479776 -17.089882)
		(end 129.39014 -17.089882)
		(width 0.11684)
		(layer "In6.Cu")
		(net "HP_LVC3_OCP_V3_2_P12V_PWRGD")
	)
	(segment
		(start 142.86357 -17.473676)
		(end 142.479776 -17.089882)
		(width 0.11684)
		(layer "In6.Cu")
		(net "HP_LVC3_OCP_V3_2_P12V_PWRGD")
	)
	(segment
		(start 99.39274 -57.879234)
		(end 99.39274 -56.73852)
		(width 0.11684)
		(layer "In11.Cu")
		(net "HP_LVC3_OCP_V3_2_P12V_PWRGD")
	)
	(segment
		(start 83.596734 -20.11934)
		(end 82.051144 -18.57375)
		(width 0.11684)
		(layer "In11.Cu")
		(net "HP_LVC3_OCP_V3_2_P12V_PWRGD")
	)
	(segment
		(start 95.25762 -52.6034)
		(end 92.27312 -52.6034)
		(width 0.11684)
		(layer "In11.Cu")
		(net "HP_LVC3_OCP_V3_2_P12V_PWRGD")
	)
	(segment
		(start 85.4075 -20.11934)
		(end 83.596734 -20.11934)
		(width 0.11684)
		(layer "In11.Cu")
		(net "HP_LVC3_OCP_V3_2_P12V_PWRGD")
	)
	(segment
		(start 99.39274 -56.73852)
		(end 95.25762 -52.6034)
		(width 0.11684)
		(layer "In11.Cu")
		(net "HP_LVC3_OCP_V3_2_P12V_PWRGD")
	)
	(segment
		(start 82.051144 -18.57375)
		(end 86.322662 -14.302232)
		(width 0.11684)
		(layer "In11.Cu")
		(net "HP_LVC3_OCP_V3_2_P12V_PWRGD")
	)
	(segment
		(start 86.322662 -14.302232)
		(end 86.634828 -14.302232)
		(width 0.11684)
		(layer "In11.Cu")
		(net "HP_LVC3_OCP_V3_2_P12V_PWRGD")
	)
	(segment
		(start 87.11692 -28.83662)
		(end 87.11692 -21.82876)
		(width 0.11684)
		(layer "In11.Cu")
		(net "HP_LVC3_OCP_V3_2_P12V_PWRGD")
	)
	(segment
		(start 92.27312 -52.6034)
		(end 88.22182 -48.5521)
		(width 0.11684)
		(layer "In11.Cu")
		(net "HP_LVC3_OCP_V3_2_P12V_PWRGD")
	)
	(segment
		(start 87.11692 -21.82876)
		(end 85.4075 -20.11934)
		(width 0.11684)
		(layer "In11.Cu")
		(net "HP_LVC3_OCP_V3_2_P12V_PWRGD")
	)
	(segment
		(start 88.22182 -48.5521)
		(end 88.22182 -29.94152)
		(width 0.11684)
		(layer "In11.Cu")
		(net "HP_LVC3_OCP_V3_2_P12V_PWRGD")
	)
	(segment
		(start 88.22182 -29.94152)
		(end 87.11692 -28.83662)
		(width 0.11684)
		(layer "In11.Cu")
		(net "HP_LVC3_OCP_V3_2_P12V_PWRGD")
	)
	(segment
		(start 459.533498 -108.567728)
		(end 458.634592 -107.668822)
		(width 0.10668)
		(layer "F.Cu")
		(net "HP_LVC3_OCP_V3_1_PRSNT2_N_R")
	)
	(segment
		(start 458.197966 -107.668822)
		(end 458.634592 -107.668822)
		(width 0.10668)
		(layer "F.Cu")
		(net "HP_LVC3_OCP_V3_1_PRSNT2_N_R")
	)
	(segment
		(start 458.15885 -102.996238)
		(end 458.637386 -102.996238)
		(width 0.10668)
		(layer "F.Cu")
		(net "HP_LVC3_OCP_V3_1_PRSNT2_N_R")
	)
	(segment
		(start 459.974696 -108.567728)
		(end 459.533498 -108.567728)
		(width 0.10668)
		(layer "F.Cu")
		(net "HP_LVC3_OCP_V3_1_PRSNT2_N_R")
	)
	(segment
		(start 457.937616 -103.217472)
		(end 458.15885 -102.996238)
		(width 0.10668)
		(layer "F.Cu")
		(net "HP_LVC3_OCP_V3_1_PRSNT2_N_R")
	)
	(segment
		(start 461.193896 -108.567728)
		(end 459.974696 -108.567728)
		(width 0.10668)
		(layer "F.Cu")
		(net "HP_LVC3_OCP_V3_1_PRSNT2_N_R")
	)
	(segment
		(start 461.192118 -109.646212)
		(end 461.193896 -109.644434)
		(width 0.10668)
		(layer "F.Cu")
		(net "HP_LVC3_OCP_V3_1_PRSNT2_N_R")
	)
	(segment
		(start 458.254354 -104.29621)
		(end 457.937616 -103.979472)
		(width 0.10668)
		(layer "F.Cu")
		(net "HP_LVC3_OCP_V3_1_PRSNT2_N_R")
	)
	(segment
		(start 458.634592 -106.36885)
		(end 458.634592 -104.706928)
		(width 0.10668)
		(layer "F.Cu")
		(net "HP_LVC3_OCP_V3_1_PRSNT2_N_R")
	)
	(segment
		(start 461.193896 -109.644434)
		(end 461.193896 -108.567728)
		(width 0.10668)
		(layer "F.Cu")
		(net "HP_LVC3_OCP_V3_1_PRSNT2_N_R")
	)
	(segment
		(start 457.937616 -107.408472)
		(end 458.197966 -107.668822)
		(width 0.10668)
		(layer "F.Cu")
		(net "HP_LVC3_OCP_V3_1_PRSNT2_N_R")
	)
	(segment
		(start 458.088238 -106.36885)
		(end 457.937616 -106.519472)
		(width 0.10668)
		(layer "F.Cu")
		(net "HP_LVC3_OCP_V3_1_PRSNT2_N_R")
	)
	(segment
		(start 458.634592 -104.706928)
		(end 458.637386 -104.704134)
		(width 0.10668)
		(layer "F.Cu")
		(net "HP_LVC3_OCP_V3_1_PRSNT2_N_R")
	)
	(segment
		(start 457.937616 -103.979472)
		(end 457.937616 -103.217472)
		(width 0.10668)
		(layer "F.Cu")
		(net "HP_LVC3_OCP_V3_1_PRSNT2_N_R")
	)
	(segment
		(start 458.637386 -104.29621)
		(end 458.254354 -104.29621)
		(width 0.10668)
		(layer "F.Cu")
		(net "HP_LVC3_OCP_V3_1_PRSNT2_N_R")
	)
	(segment
		(start 458.634592 -106.36885)
		(end 458.088238 -106.36885)
		(width 0.10668)
		(layer "F.Cu")
		(net "HP_LVC3_OCP_V3_1_PRSNT2_N_R")
	)
	(segment
		(start 458.637386 -104.704134)
		(end 458.637386 -104.29621)
		(width 0.10668)
		(layer "F.Cu")
		(net "HP_LVC3_OCP_V3_1_PRSNT2_N_R")
	)
	(segment
		(start 457.937616 -106.519472)
		(end 457.937616 -107.408472)
		(width 0.10668)
		(layer "F.Cu")
		(net "HP_LVC3_OCP_V3_1_PRSNT2_N_R")
	)
	(via
		(at 459.974696 -108.567728)
		(size 0.762)
		(drill 0.381)
		(layers "F.Cu" "B.Cu")
		(net "HP_LVC3_OCP_V3_1_PRSNT2_N_R")
	)
	(segment
		(start 210.946746 -108.097828)
		(end 215.073484 -108.097828)
		(width 0.10668)
		(layer "F.Cu")
		(net "HP_LVC3_OCP_SFF_PRSNT2_PLD_N")
	)
	(segment
		(start 210.499198 -108.545376)
		(end 210.946746 -108.097828)
		(width 0.10668)
		(layer "F.Cu")
		(net "HP_LVC3_OCP_SFF_PRSNT2_PLD_N")
	)
	(segment
		(start 462.971896 -108.567728)
		(end 462.971896 -107.936792)
		(width 0.10668)
		(layer "F.Cu")
		(net "HP_LVC3_OCP_SFF_PRSNT2_PLD_N")
	)
	(segment
		(start 209.294476 -108.545376)
		(end 210.499198 -108.545376)
		(width 0.10668)
		(layer "F.Cu")
		(net "HP_LVC3_OCP_SFF_PRSNT2_PLD_N")
	)
	(segment
		(start 461.993996 -108.567728)
		(end 462.971896 -108.567728)
		(width 0.10668)
		(layer "F.Cu")
		(net "HP_LVC3_OCP_SFF_PRSNT2_PLD_N")
	)
	(segment
		(start 215.073484 -108.097828)
		(end 217.353388 -105.817924)
		(width 0.10668)
		(layer "F.Cu")
		(net "HP_LVC3_OCP_SFF_PRSNT2_PLD_N")
	)
	(via
		(at 313.300872 -106.614468)
		(size 0.508)
		(drill 0.254)
		(layers "F.Cu" "B.Cu")
		(net "HP_LVC3_OCP_SFF_PRSNT2_PLD_N")
	)
	(via
		(at 217.353388 -105.817924)
		(size 0.508)
		(drill 0.254)
		(layers "F.Cu" "B.Cu")
		(net "HP_LVC3_OCP_SFF_PRSNT2_PLD_N")
	)
	(via
		(at 462.971896 -107.936792)
		(size 0.508)
		(drill 0.254)
		(layers "F.Cu" "B.Cu")
		(net "HP_LVC3_OCP_SFF_PRSNT2_PLD_N")
	)
	(segment
		(start 329.89647 -118.684802)
		(end 372.960138 -118.684802)
		(width 0.11684)
		(layer "In2.Cu")
		(net "HP_LVC3_OCP_SFF_PRSNT2_PLD_N")
	)
	(segment
		(start 455.562462 -115.346226)
		(end 462.971896 -107.936792)
		(width 0.11684)
		(layer "In2.Cu")
		(net "HP_LVC3_OCP_SFF_PRSNT2_PLD_N")
	)
	(segment
		(start 376.298714 -115.346226)
		(end 455.562462 -115.346226)
		(width 0.11684)
		(layer "In2.Cu")
		(net "HP_LVC3_OCP_SFF_PRSNT2_PLD_N")
	)
	(segment
		(start 317.826136 -106.614468)
		(end 329.89647 -118.684802)
		(width 0.11684)
		(layer "In2.Cu")
		(net "HP_LVC3_OCP_SFF_PRSNT2_PLD_N")
	)
	(segment
		(start 313.300872 -106.614468)
		(end 317.826136 -106.614468)
		(width 0.11684)
		(layer "In2.Cu")
		(net "HP_LVC3_OCP_SFF_PRSNT2_PLD_N")
	)
	(segment
		(start 372.960138 -118.684802)
		(end 376.298714 -115.346226)
		(width 0.11684)
		(layer "In2.Cu")
		(net "HP_LVC3_OCP_SFF_PRSNT2_PLD_N")
	)
	(segment
		(start 258.274312 -107.247182)
		(end 259.077206 -106.444288)
		(width 0.11684)
		(layer "In6.Cu")
		(net "HP_LVC3_OCP_SFF_PRSNT2_PLD_N")
	)
	(segment
		(start 260.94563 -107.633008)
		(end 275.551646 -107.633008)
		(width 0.11684)
		(layer "In6.Cu")
		(net "HP_LVC3_OCP_SFF_PRSNT2_PLD_N")
	)
	(segment
		(start 218.155266 -106.619802)
		(end 222.111062 -106.619802)
		(width 0.11684)
		(layer "In6.Cu")
		(net "HP_LVC3_OCP_SFF_PRSNT2_PLD_N")
	)
	(segment
		(start 222.738442 -107.247182)
		(end 258.274312 -107.247182)
		(width 0.11684)
		(layer "In6.Cu")
		(net "HP_LVC3_OCP_SFF_PRSNT2_PLD_N")
	)
	(segment
		(start 259.75691 -106.444288)
		(end 260.94563 -107.633008)
		(width 0.11684)
		(layer "In6.Cu")
		(net "HP_LVC3_OCP_SFF_PRSNT2_PLD_N")
	)
	(segment
		(start 275.551646 -107.633008)
		(end 276.712426 -106.472228)
		(width 0.11684)
		(layer "In6.Cu")
		(net "HP_LVC3_OCP_SFF_PRSNT2_PLD_N")
	)
	(segment
		(start 222.111062 -106.619802)
		(end 222.738442 -107.247182)
		(width 0.11684)
		(layer "In6.Cu")
		(net "HP_LVC3_OCP_SFF_PRSNT2_PLD_N")
	)
	(segment
		(start 217.353388 -105.817924)
		(end 218.155266 -106.619802)
		(width 0.11684)
		(layer "In6.Cu")
		(net "HP_LVC3_OCP_SFF_PRSNT2_PLD_N")
	)
	(segment
		(start 259.077206 -106.444288)
		(end 259.75691 -106.444288)
		(width 0.11684)
		(layer "In6.Cu")
		(net "HP_LVC3_OCP_SFF_PRSNT2_PLD_N")
	)
	(segment
		(start 313.158632 -106.472228)
		(end 313.300872 -106.614468)
		(width 0.11684)
		(layer "In6.Cu")
		(net "HP_LVC3_OCP_SFF_PRSNT2_PLD_N")
	)
	(segment
		(start 276.712426 -106.472228)
		(end 313.158632 -106.472228)
		(width 0.11684)
		(layer "In6.Cu")
		(net "HP_LVC3_OCP_SFF_PRSNT2_PLD_N")
	)
	(segment
		(start 439.168794 -28.67533)
		(end 439.15711 -28.687014)
		(width 0.10668)
		(layer "F.Cu")
		(net "HP_LVC3_OCP_V3_1_P12V_PWRGD")
	)
	(segment
		(start 221.28226 -97.70999)
		(end 221.28226 -97.08642)
		(width 0.10668)
		(layer "F.Cu")
		(net "HP_LVC3_OCP_V3_1_P12V_PWRGD")
	)
	(segment
		(start 439.953146 -28.67533)
		(end 439.168794 -28.67533)
		(width 0.10668)
		(layer "F.Cu")
		(net "HP_LVC3_OCP_V3_1_P12V_PWRGD")
	)
	(segment
		(start 454.847452 -18.030698)
		(end 454.847452 -19.027648)
		(width 0.10668)
		(layer "F.Cu")
		(net "HP_LVC3_OCP_V3_1_P12V_PWRGD")
	)
	(segment
		(start 209.239612 -95.600012)
		(end 208.037684 -95.600012)
		(width 0.10668)
		(layer "F.Cu")
		(net "HP_LVC3_OCP_V3_1_P12V_PWRGD")
	)
	(segment
		(start 421.01643 -109.631226)
		(end 421.01643 -110.364524)
		(width 0.10668)
		(layer "F.Cu")
		(net "HP_LVC3_OCP_V3_1_P12V_PWRGD")
	)
	(segment
		(start 208.037684 -95.600012)
		(end 206.567786 -94.130114)
		(width 0.10668)
		(layer "F.Cu")
		(net "HP_LVC3_OCP_V3_1_P12V_PWRGD")
	)
	(segment
		(start 453.169782 -41.357296)
		(end 452.467472 -41.357296)
		(width 0.10668)
		(layer "F.Cu")
		(net "HP_LVC3_OCP_V3_1_P12V_PWRGD")
	)
	(segment
		(start 438.275222 -28.668218)
		(end 439.138314 -28.668218)
		(width 0.10668)
		(layer "F.Cu")
		(net "HP_LVC3_OCP_V3_1_P12V_PWRGD")
	)
	(segment
		(start 454.847452 -19.027648)
		(end 454.2155 -19.027648)
		(width 0.10668)
		(layer "F.Cu")
		(net "HP_LVC3_OCP_V3_1_P12V_PWRGD")
	)
	(segment
		(start 206.567786 -94.130114)
		(end 200.382378 -94.130114)
		(width 0.10668)
		(layer "F.Cu")
		(net "HP_LVC3_OCP_V3_1_P12V_PWRGD")
	)
	(segment
		(start 439.138314 -28.668218)
		(end 439.15711 -28.687014)
		(width 0.10668)
		(layer "F.Cu")
		(net "HP_LVC3_OCP_V3_1_P12V_PWRGD")
	)
	(segment
		(start 412.881318 -71.812912)
		(end 413.508444 -71.812912)
		(width 0.10668)
		(layer "F.Cu")
		(net "HP_LVC3_OCP_V3_1_P12V_PWRGD")
	)
	(segment
		(start 454.2155 -19.027648)
		(end 454.203816 -19.039332)
		(width 0.10668)
		(layer "F.Cu")
		(net "HP_LVC3_OCP_V3_1_P12V_PWRGD")
	)
	(segment
		(start 200.382378 -94.130114)
		(end 198.489824 -96.022668)
		(width 0.10668)
		(layer "F.Cu")
		(net "HP_LVC3_OCP_V3_1_P12V_PWRGD")
	)
	(via
		(at 413.508444 -71.812912)
		(size 0.508)
		(drill 0.254)
		(layers "F.Cu" "B.Cu")
		(net "HP_LVC3_OCP_V3_1_P12V_PWRGD")
	)
	(via
		(at 439.15711 -28.687014)
		(size 0.508)
		(drill 0.254)
		(layers "F.Cu" "B.Cu")
		(net "HP_LVC3_OCP_V3_1_P12V_PWRGD")
	)
	(via
		(at 421.01643 -110.364524)
		(size 0.508)
		(drill 0.254)
		(layers "F.Cu" "B.Cu")
		(net "HP_LVC3_OCP_V3_1_P12V_PWRGD")
	)
	(via
		(at 452.467472 -41.357296)
		(size 0.508)
		(drill 0.254)
		(layers "F.Cu" "B.Cu")
		(net "HP_LVC3_OCP_V3_1_P12V_PWRGD")
	)
	(via
		(at 210.7692 -84.077302)
		(size 0.508)
		(drill 0.254)
		(layers "F.Cu" "B.Cu")
		(net "HP_LVC3_OCP_V3_1_P12V_PWRGD")
	)
	(via
		(at 221.28226 -97.08642)
		(size 0.508)
		(drill 0.254)
		(layers "F.Cu" "B.Cu")
		(net "HP_LVC3_OCP_V3_1_P12V_PWRGD")
	)
	(via
		(at 209.239612 -95.600012)
		(size 0.508)
		(drill 0.254)
		(layers "F.Cu" "B.Cu")
		(net "HP_LVC3_OCP_V3_1_P12V_PWRGD")
	)
	(via
		(at 454.203816 -19.039332)
		(size 0.508)
		(drill 0.254)
		(layers "F.Cu" "B.Cu")
		(net "HP_LVC3_OCP_V3_1_P12V_PWRGD")
	)
	(segment
		(start 416.54222 -53.776626)
		(end 416.54222 -68.779136)
		(width 0.10668)
		(layer "B.Cu")
		(net "HP_LVC3_OCP_V3_1_P12V_PWRGD")
	)
	(segment
		(start 436.346092 -33.170368)
		(end 434.673756 -33.170368)
		(width 0.10668)
		(layer "B.Cu")
		(net "HP_LVC3_OCP_V3_1_P12V_PWRGD")
	)
	(segment
		(start 434.673756 -33.170368)
		(end 431.339498 -36.504626)
		(width 0.10668)
		(layer "B.Cu")
		(net "HP_LVC3_OCP_V3_1_P12V_PWRGD")
	)
	(segment
		(start 437.62041 -30.223714)
		(end 437.62041 -31.89605)
		(width 0.10668)
		(layer "B.Cu")
		(net "HP_LVC3_OCP_V3_1_P12V_PWRGD")
	)
	(segment
		(start 416.54222 -68.779136)
		(end 413.508444 -71.812912)
		(width 0.10668)
		(layer "B.Cu")
		(net "HP_LVC3_OCP_V3_1_P12V_PWRGD")
	)
	(segment
		(start 431.339498 -42.922698)
		(end 430.872138 -43.390058)
		(width 0.10668)
		(layer "B.Cu")
		(net "HP_LVC3_OCP_V3_1_P12V_PWRGD")
	)
	(segment
		(start 439.15711 -28.687014)
		(end 437.62041 -30.223714)
		(width 0.10668)
		(layer "B.Cu")
		(net "HP_LVC3_OCP_V3_1_P12V_PWRGD")
	)
	(segment
		(start 430.872138 -43.390058)
		(end 426.928788 -43.390058)
		(width 0.10668)
		(layer "B.Cu")
		(net "HP_LVC3_OCP_V3_1_P12V_PWRGD")
	)
	(segment
		(start 426.928788 -43.390058)
		(end 416.54222 -53.776626)
		(width 0.10668)
		(layer "B.Cu")
		(net "HP_LVC3_OCP_V3_1_P12V_PWRGD")
	)
	(segment
		(start 437.62041 -31.89605)
		(end 436.346092 -33.170368)
		(width 0.10668)
		(layer "B.Cu")
		(net "HP_LVC3_OCP_V3_1_P12V_PWRGD")
	)
	(segment
		(start 431.339498 -36.504626)
		(end 431.339498 -42.922698)
		(width 0.10668)
		(layer "B.Cu")
		(net "HP_LVC3_OCP_V3_1_P12V_PWRGD")
	)
	(segment
		(start 413.327596 -92.401644)
		(end 413.327596 -102.67569)
		(width 0.11684)
		(layer "In4.Cu")
		(net "HP_LVC3_OCP_V3_1_P12V_PWRGD")
	)
	(segment
		(start 413.7406 -73.31202)
		(end 412.037276 -73.31202)
		(width 0.11684)
		(layer "In4.Cu")
		(net "HP_LVC3_OCP_V3_1_P12V_PWRGD")
	)
	(segment
		(start 454.989438 -36.726622)
		(end 452.467472 -39.248588)
		(width 0.11684)
		(layer "In4.Cu")
		(net "HP_LVC3_OCP_V3_1_P12V_PWRGD")
	)
	(segment
		(start 452.467472 -39.248588)
		(end 452.467472 -41.357296)
		(width 0.11684)
		(layer "In4.Cu")
		(net "HP_LVC3_OCP_V3_1_P12V_PWRGD")
	)
	(segment
		(start 413.327596 -102.67569)
		(end 421.01643 -110.364524)
		(width 0.11684)
		(layer "In4.Cu")
		(net "HP_LVC3_OCP_V3_1_P12V_PWRGD")
	)
	(segment
		(start 210.7692 -84.077302)
		(end 210.7692 -88.475312)
		(width 0.11684)
		(layer "In4.Cu")
		(net "HP_LVC3_OCP_V3_1_P12V_PWRGD")
	)
	(segment
		(start 414.066482 -72.37095)
		(end 414.066482 -72.986138)
		(width 0.11684)
		(layer "In4.Cu")
		(net "HP_LVC3_OCP_V3_1_P12V_PWRGD")
	)
	(segment
		(start 209.239612 -90.0049)
		(end 209.239612 -95.600012)
		(width 0.11684)
		(layer "In4.Cu")
		(net "HP_LVC3_OCP_V3_1_P12V_PWRGD")
	)
	(segment
		(start 210.7692 -88.475312)
		(end 209.239612 -90.0049)
		(width 0.11684)
		(layer "In4.Cu")
		(net "HP_LVC3_OCP_V3_1_P12V_PWRGD")
	)
	(segment
		(start 454.989438 -19.824954)
		(end 454.989438 -36.726622)
		(width 0.11684)
		(layer "In4.Cu")
		(net "HP_LVC3_OCP_V3_1_P12V_PWRGD")
	)
	(segment
		(start 412.037276 -73.31202)
		(end 410.963872 -74.385424)
		(width 0.11684)
		(layer "In4.Cu")
		(net "HP_LVC3_OCP_V3_1_P12V_PWRGD")
	)
	(segment
		(start 413.508444 -71.812912)
		(end 414.066482 -72.37095)
		(width 0.11684)
		(layer "In4.Cu")
		(net "HP_LVC3_OCP_V3_1_P12V_PWRGD")
	)
	(segment
		(start 414.066482 -72.986138)
		(end 413.7406 -73.31202)
		(width 0.11684)
		(layer "In4.Cu")
		(net "HP_LVC3_OCP_V3_1_P12V_PWRGD")
	)
	(segment
		(start 410.963872 -90.03792)
		(end 413.327596 -92.401644)
		(width 0.11684)
		(layer "In4.Cu")
		(net "HP_LVC3_OCP_V3_1_P12V_PWRGD")
	)
	(segment
		(start 410.963872 -74.385424)
		(end 410.963872 -90.03792)
		(width 0.11684)
		(layer "In4.Cu")
		(net "HP_LVC3_OCP_V3_1_P12V_PWRGD")
	)
	(segment
		(start 454.203816 -19.039332)
		(end 454.989438 -19.824954)
		(width 0.11684)
		(layer "In4.Cu")
		(net "HP_LVC3_OCP_V3_1_P12V_PWRGD")
	)
	(segment
		(start 442.461396 -31.9913)
		(end 446.473326 -31.9913)
		(width 0.11684)
		(layer "In6.Cu")
		(net "HP_LVC3_OCP_V3_1_P12V_PWRGD")
	)
	(segment
		(start 378.997718 -50.461418)
		(end 402.405088 -27.054048)
		(width 0.11684)
		(layer "In6.Cu")
		(net "HP_LVC3_OCP_V3_1_P12V_PWRGD")
	)
	(segment
		(start 308.690518 -51.107594)
		(end 309.336694 -50.461418)
		(width 0.11684)
		(layer "In6.Cu")
		(net "HP_LVC3_OCP_V3_1_P12V_PWRGD")
	)
	(segment
		(start 446.473326 -31.9913)
		(end 447.948304 -30.516322)
		(width 0.11684)
		(layer "In6.Cu")
		(net "HP_LVC3_OCP_V3_1_P12V_PWRGD")
	)
	(segment
		(start 246.91594 -79.189326)
		(end 259.846318 -79.189326)
		(width 0.11684)
		(layer "In6.Cu")
		(net "HP_LVC3_OCP_V3_1_P12V_PWRGD")
	)
	(segment
		(start 402.405088 -27.054048)
		(end 437.524144 -27.054048)
		(width 0.11684)
		(layer "In6.Cu")
		(net "HP_LVC3_OCP_V3_1_P12V_PWRGD")
	)
	(segment
		(start 276.926294 -67.066414)
		(end 276.926294 -64.048386)
		(width 0.11684)
		(layer "In6.Cu")
		(net "HP_LVC3_OCP_V3_1_P12V_PWRGD")
	)
	(segment
		(start 274.573238 -69.41947)
		(end 276.926294 -67.066414)
		(width 0.11684)
		(layer "In6.Cu")
		(net "HP_LVC3_OCP_V3_1_P12V_PWRGD")
	)
	(segment
		(start 455.104246 -19.939762)
		(end 454.203816 -19.039332)
		(width 0.11684)
		(layer "In6.Cu")
		(net "HP_LVC3_OCP_V3_1_P12V_PWRGD")
	)
	(segment
		(start 210.872832 -84.18068)
		(end 214.702898 -88.010746)
		(width 0.11684)
		(layer "In6.Cu")
		(net "HP_LVC3_OCP_V3_1_P12V_PWRGD")
	)
	(segment
		(start 276.926294 -64.048386)
		(end 290.60775 -50.36693)
		(width 0.11684)
		(layer "In6.Cu")
		(net "HP_LVC3_OCP_V3_1_P12V_PWRGD")
	)
	(segment
		(start 304.966116 -50.36693)
		(end 305.70678 -51.107594)
		(width 0.11684)
		(layer "In6.Cu")
		(net "HP_LVC3_OCP_V3_1_P12V_PWRGD")
	)
	(segment
		(start 439.15711 -28.687014)
		(end 442.461396 -31.9913)
		(width 0.11684)
		(layer "In6.Cu")
		(net "HP_LVC3_OCP_V3_1_P12V_PWRGD")
	)
	(segment
		(start 447.948304 -30.516322)
		(end 454.210928 -30.516322)
		(width 0.11684)
		(layer "In6.Cu")
		(net "HP_LVC3_OCP_V3_1_P12V_PWRGD")
	)
	(segment
		(start 309.336694 -50.461418)
		(end 378.997718 -50.461418)
		(width 0.11684)
		(layer "In6.Cu")
		(net "HP_LVC3_OCP_V3_1_P12V_PWRGD")
	)
	(segment
		(start 454.210928 -30.516322)
		(end 455.104246 -29.623004)
		(width 0.11684)
		(layer "In6.Cu")
		(net "HP_LVC3_OCP_V3_1_P12V_PWRGD")
	)
	(segment
		(start 269.616174 -69.41947)
		(end 274.573238 -69.41947)
		(width 0.11684)
		(layer "In6.Cu")
		(net "HP_LVC3_OCP_V3_1_P12V_PWRGD")
	)
	(segment
		(start 259.846318 -79.189326)
		(end 269.616174 -69.41947)
		(width 0.11684)
		(layer "In6.Cu")
		(net "HP_LVC3_OCP_V3_1_P12V_PWRGD")
	)
	(segment
		(start 210.7692 -84.077302)
		(end 210.872832 -84.18068)
		(width 0.11684)
		(layer "In6.Cu")
		(net "HP_LVC3_OCP_V3_1_P12V_PWRGD")
	)
	(segment
		(start 290.60775 -50.36693)
		(end 304.966116 -50.36693)
		(width 0.11684)
		(layer "In6.Cu")
		(net "HP_LVC3_OCP_V3_1_P12V_PWRGD")
	)
	(segment
		(start 455.104246 -29.623004)
		(end 455.104246 -19.939762)
		(width 0.11684)
		(layer "In6.Cu")
		(net "HP_LVC3_OCP_V3_1_P12V_PWRGD")
	)
	(segment
		(start 305.70678 -51.107594)
		(end 308.690518 -51.107594)
		(width 0.11684)
		(layer "In6.Cu")
		(net "HP_LVC3_OCP_V3_1_P12V_PWRGD")
	)
	(segment
		(start 238.09452 -88.010746)
		(end 246.91594 -79.189326)
		(width 0.11684)
		(layer "In6.Cu")
		(net "HP_LVC3_OCP_V3_1_P12V_PWRGD")
	)
	(segment
		(start 214.702898 -88.010746)
		(end 238.09452 -88.010746)
		(width 0.11684)
		(layer "In6.Cu")
		(net "HP_LVC3_OCP_V3_1_P12V_PWRGD")
	)
	(segment
		(start 437.524144 -27.054048)
		(end 439.15711 -28.687014)
		(width 0.11684)
		(layer "In6.Cu")
		(net "HP_LVC3_OCP_V3_1_P12V_PWRGD")
	)
	(segment
		(start 220.7514 -97.29724)
		(end 216.7763 -97.29724)
		(width 0.11684)
		(layer "In15.Cu")
		(net "HP_LVC3_OCP_V3_1_P12V_PWRGD")
	)
	(segment
		(start 214.86622 -96.92132)
		(end 214.34806 -96.40316)
		(width 0.11684)
		(layer "In15.Cu")
		(net "HP_LVC3_OCP_V3_1_P12V_PWRGD")
	)
	(segment
		(start 221.28226 -97.08642)
		(end 220.96222 -97.08642)
		(width 0.11684)
		(layer "In15.Cu")
		(net "HP_LVC3_OCP_V3_1_P12V_PWRGD")
	)
	(segment
		(start 209.981292 -95.600012)
		(end 209.239612 -95.600012)
		(width 0.11684)
		(layer "In15.Cu")
		(net "HP_LVC3_OCP_V3_1_P12V_PWRGD")
	)
	(segment
		(start 210.78444 -96.40316)
		(end 209.981292 -95.600012)
		(width 0.11684)
		(layer "In15.Cu")
		(net "HP_LVC3_OCP_V3_1_P12V_PWRGD")
	)
	(segment
		(start 220.96222 -97.08642)
		(end 220.7514 -97.29724)
		(width 0.11684)
		(layer "In15.Cu")
		(net "HP_LVC3_OCP_V3_1_P12V_PWRGD")
	)
	(segment
		(start 214.34806 -96.40316)
		(end 210.78444 -96.40316)
		(width 0.11684)
		(layer "In15.Cu")
		(net "HP_LVC3_OCP_V3_1_P12V_PWRGD")
	)
	(segment
		(start 216.40038 -96.92132)
		(end 214.86622 -96.92132)
		(width 0.11684)
		(layer "In15.Cu")
		(net "HP_LVC3_OCP_V3_1_P12V_PWRGD")
	)
	(segment
		(start 216.7763 -97.29724)
		(end 216.40038 -96.92132)
		(width 0.11684)
		(layer "In15.Cu")
		(net "HP_LVC3_OCP_V3_1_P12V_PWRGD")
	)
	(segment
		(start 170.79595 -112.359948)
		(end 170.18 -112.359948)
		(width 0.10668)
		(layer "F.Cu")
		(net "P3V3_OCP_SFF_EN_R")
	)
	(segment
		(start 164.10305 -112.359948)
		(end 164.51199 -112.359948)
		(width 0.10668)
		(layer "F.Cu")
		(net "P3V3_OCP_SFF_EN_R")
	)
	(segment
		(start 169.02176 -112.867948)
		(end 169.672 -112.867948)
		(width 0.10668)
		(layer "F.Cu")
		(net "P3V3_OCP_SFF_EN_R")
	)
	(segment
		(start 420.06266 -110.199678)
		(end 420.14394 -110.280958)
		(width 0.10668)
		(layer "F.Cu")
		(net "P3V3_OCP_SFF_EN_R")
	)
	(segment
		(start 420.06266 -109.631226)
		(end 420.06266 -110.199678)
		(width 0.10668)
		(layer "F.Cu")
		(net "P3V3_OCP_SFF_EN_R")
	)
	(segment
		(start 454.61301 -42.121836)
		(end 453.99706 -42.121836)
		(width 0.10668)
		(layer "F.Cu")
		(net "P3V3_OCP_SFF_EN_R")
	)
	(segment
		(start 168.251124 -112.097312)
		(end 169.02176 -112.867948)
		(width 0.10668)
		(layer "F.Cu")
		(net "P3V3_OCP_SFF_EN_R")
	)
	(segment
		(start 412.872936 -72.832468)
		(end 413.488886 -72.832468)
		(width 0.10668)
		(layer "F.Cu")
		(net "P3V3_OCP_SFF_EN_R")
	)
	(segment
		(start 164.51199 -112.359948)
		(end 164.774626 -112.097312)
		(width 0.10668)
		(layer "F.Cu")
		(net "P3V3_OCP_SFF_EN_R")
	)
	(segment
		(start 164.774626 -112.097312)
		(end 168.251124 -112.097312)
		(width 0.10668)
		(layer "F.Cu")
		(net "P3V3_OCP_SFF_EN_R")
	)
	(segment
		(start 169.672 -112.867948)
		(end 170.18 -112.359948)
		(width 0.10668)
		(layer "F.Cu")
		(net "P3V3_OCP_SFF_EN_R")
	)
	(via
		(at 453.99706 -42.121836)
		(size 0.508)
		(drill 0.254)
		(layers "F.Cu" "B.Cu")
		(net "P3V3_OCP_SFF_EN_R")
	)
	(via
		(at 413.488886 -72.832468)
		(size 0.508)
		(drill 0.254)
		(layers "F.Cu" "B.Cu")
		(net "P3V3_OCP_SFF_EN_R")
	)
	(via
		(at 170.18 -112.359948)
		(size 0.508)
		(drill 0.254)
		(layers "F.Cu" "B.Cu")
		(net "P3V3_OCP_SFF_EN_R")
	)
	(via
		(at 420.14394 -110.280958)
		(size 0.508)
		(drill 0.254)
		(layers "F.Cu" "B.Cu")
		(net "P3V3_OCP_SFF_EN_R")
	)
	(segment
		(start 453.436482 -41.561258)
		(end 453.436482 -40.049958)
		(width 0.10668)
		(layer "B.Cu")
		(net "P3V3_OCP_SFF_EN_R")
	)
	(segment
		(start 448.325748 -34.939224)
		(end 433.494434 -34.939224)
		(width 0.10668)
		(layer "B.Cu")
		(net "P3V3_OCP_SFF_EN_R")
	)
	(segment
		(start 433.494434 -34.939224)
		(end 431.840894 -36.592764)
		(width 0.10668)
		(layer "B.Cu")
		(net "P3V3_OCP_SFF_EN_R")
	)
	(segment
		(start 431.840894 -43.073066)
		(end 431.022506 -43.891454)
		(width 0.10668)
		(layer "B.Cu")
		(net "P3V3_OCP_SFF_EN_R")
	)
	(segment
		(start 431.022506 -43.891454)
		(end 427.235366 -43.891454)
		(width 0.10668)
		(layer "B.Cu")
		(net "P3V3_OCP_SFF_EN_R")
	)
	(segment
		(start 453.436482 -40.049958)
		(end 448.325748 -34.939224)
		(width 0.10668)
		(layer "B.Cu")
		(net "P3V3_OCP_SFF_EN_R")
	)
	(segment
		(start 453.99706 -42.121836)
		(end 453.436482 -41.561258)
		(width 0.10668)
		(layer "B.Cu")
		(net "P3V3_OCP_SFF_EN_R")
	)
	(segment
		(start 417.609782 -53.517038)
		(end 417.609782 -68.711572)
		(width 0.10668)
		(layer "B.Cu")
		(net "P3V3_OCP_SFF_EN_R")
	)
	(segment
		(start 431.840894 -36.592764)
		(end 431.840894 -43.073066)
		(width 0.10668)
		(layer "B.Cu")
		(net "P3V3_OCP_SFF_EN_R")
	)
	(segment
		(start 417.609782 -68.711572)
		(end 413.488886 -72.832468)
		(width 0.10668)
		(layer "B.Cu")
		(net "P3V3_OCP_SFF_EN_R")
	)
	(segment
		(start 427.235366 -43.891454)
		(end 417.609782 -53.517038)
		(width 0.10668)
		(layer "B.Cu")
		(net "P3V3_OCP_SFF_EN_R")
	)
	(segment
		(start 412.1912 -95.48368)
		(end 412.75508 -94.9198)
		(width 0.11684)
		(layer "In4.Cu")
		(net "P3V3_OCP_SFF_EN_R")
	)
	(segment
		(start 412.75508 -94.9198)
		(end 412.75508 -92.624656)
		(width 0.11684)
		(layer "In4.Cu")
		(net "P3V3_OCP_SFF_EN_R")
	)
	(segment
		(start 412.75508 -92.624656)
		(end 410.521404 -90.39098)
		(width 0.11684)
		(layer "In4.Cu")
		(net "P3V3_OCP_SFF_EN_R")
	)
	(segment
		(start 410.521404 -74.126344)
		(end 411.81528 -72.832468)
		(width 0.11684)
		(layer "In4.Cu")
		(net "P3V3_OCP_SFF_EN_R")
	)
	(segment
		(start 410.521404 -90.39098)
		(end 410.521404 -74.126344)
		(width 0.11684)
		(layer "In4.Cu")
		(net "P3V3_OCP_SFF_EN_R")
	)
	(segment
		(start 412.1912 -102.328218)
		(end 412.1912 -95.48368)
		(width 0.11684)
		(layer "In4.Cu")
		(net "P3V3_OCP_SFF_EN_R")
	)
	(segment
		(start 411.81528 -72.832468)
		(end 413.488886 -72.832468)
		(width 0.11684)
		(layer "In4.Cu")
		(net "P3V3_OCP_SFF_EN_R")
	)
	(segment
		(start 420.14394 -110.280958)
		(end 412.1912 -102.328218)
		(width 0.11684)
		(layer "In4.Cu")
		(net "P3V3_OCP_SFF_EN_R")
	)
	(segment
		(start 166.437056 -99.629722)
		(end 166.437056 -100.50526)
		(width 0.11684)
		(layer "In6.Cu")
		(net "P3V3_OCP_SFF_EN_R")
	)
	(segment
		(start 317.05931 -96.295972)
		(end 315.648086 -94.884748)
		(width 0.11684)
		(layer "In6.Cu")
		(net "P3V3_OCP_SFF_EN_R")
	)
	(segment
		(start 171.13504 -111.844328)
		(end 170.61942 -112.359948)
		(width 0.11684)
		(layer "In6.Cu")
		(net "P3V3_OCP_SFF_EN_R")
	)
	(segment
		(start 218.341702 -95.76435)
		(end 216.723214 -94.145862)
		(width 0.11684)
		(layer "In6.Cu")
		(net "P3V3_OCP_SFF_EN_R")
	)
	(segment
		(start 263.68502 -92.109544)
		(end 263.212072 -92.582492)
		(width 0.11684)
		(layer "In6.Cu")
		(net "P3V3_OCP_SFF_EN_R")
	)
	(segment
		(start 200.819258 -91.76766)
		(end 198.35114 -89.299542)
		(width 0.11684)
		(layer "In6.Cu")
		(net "P3V3_OCP_SFF_EN_R")
	)
	(segment
		(start 167.983916 -105.574084)
		(end 170.069002 -105.574084)
		(width 0.11684)
		(layer "In6.Cu")
		(net "P3V3_OCP_SFF_EN_R")
	)
	(segment
		(start 169.855134 -97.584768)
		(end 169.633646 -97.36328)
		(width 0.11684)
		(layer "In6.Cu")
		(net "P3V3_OCP_SFF_EN_R")
	)
	(segment
		(start 174.77486 -95.889826)
		(end 173.079918 -97.584768)
		(width 0.11684)
		(layer "In6.Cu")
		(net "P3V3_OCP_SFF_EN_R")
	)
	(segment
		(start 169.633646 -97.36328)
		(end 168.703498 -97.36328)
		(width 0.11684)
		(layer "In6.Cu")
		(net "P3V3_OCP_SFF_EN_R")
	)
	(segment
		(start 168.703498 -97.36328)
		(end 166.437056 -99.629722)
		(width 0.11684)
		(layer "In6.Cu")
		(net "P3V3_OCP_SFF_EN_R")
	)
	(segment
		(start 420.14394 -110.280958)
		(end 406.158954 -96.295972)
		(width 0.11684)
		(layer "In6.Cu")
		(net "P3V3_OCP_SFF_EN_R")
	)
	(segment
		(start 315.648086 -94.884748)
		(end 280.921968 -94.884748)
		(width 0.11684)
		(layer "In6.Cu")
		(net "P3V3_OCP_SFF_EN_R")
	)
	(segment
		(start 170.61942 -112.359948)
		(end 170.18 -112.359948)
		(width 0.11684)
		(layer "In6.Cu")
		(net "P3V3_OCP_SFF_EN_R")
	)
	(segment
		(start 263.212072 -92.582492)
		(end 259.801868 -92.582492)
		(width 0.11684)
		(layer "In6.Cu")
		(net "P3V3_OCP_SFF_EN_R")
	)
	(segment
		(start 174.77486 -91.736164)
		(end 174.77486 -95.889826)
		(width 0.11684)
		(layer "In6.Cu")
		(net "P3V3_OCP_SFF_EN_R")
	)
	(segment
		(start 198.35114 -89.299542)
		(end 177.211482 -89.299542)
		(width 0.11684)
		(layer "In6.Cu")
		(net "P3V3_OCP_SFF_EN_R")
	)
	(segment
		(start 177.211482 -89.299542)
		(end 174.77486 -91.736164)
		(width 0.11684)
		(layer "In6.Cu")
		(net "P3V3_OCP_SFF_EN_R")
	)
	(segment
		(start 219.763848 -94.727776)
		(end 218.727274 -95.76435)
		(width 0.11684)
		(layer "In6.Cu")
		(net "P3V3_OCP_SFF_EN_R")
	)
	(segment
		(start 278.619712 -92.582492)
		(end 273.981926 -92.582492)
		(width 0.11684)
		(layer "In6.Cu")
		(net "P3V3_OCP_SFF_EN_R")
	)
	(segment
		(start 167.340788 -104.930956)
		(end 167.983916 -105.574084)
		(width 0.11684)
		(layer "In6.Cu")
		(net "P3V3_OCP_SFF_EN_R")
	)
	(segment
		(start 256.309876 -96.074484)
		(end 233.196892 -96.074484)
		(width 0.11684)
		(layer "In6.Cu")
		(net "P3V3_OCP_SFF_EN_R")
	)
	(segment
		(start 216.723214 -94.145862)
		(end 206.099918 -94.145862)
		(width 0.11684)
		(layer "In6.Cu")
		(net "P3V3_OCP_SFF_EN_R")
	)
	(segment
		(start 167.340788 -101.408992)
		(end 167.340788 -104.930956)
		(width 0.11684)
		(layer "In6.Cu")
		(net "P3V3_OCP_SFF_EN_R")
	)
	(segment
		(start 259.801868 -92.582492)
		(end 256.309876 -96.074484)
		(width 0.11684)
		(layer "In6.Cu")
		(net "P3V3_OCP_SFF_EN_R")
	)
	(segment
		(start 203.721716 -91.76766)
		(end 200.819258 -91.76766)
		(width 0.11684)
		(layer "In6.Cu")
		(net "P3V3_OCP_SFF_EN_R")
	)
	(segment
		(start 171.13504 -106.640122)
		(end 171.13504 -111.844328)
		(width 0.11684)
		(layer "In6.Cu")
		(net "P3V3_OCP_SFF_EN_R")
	)
	(segment
		(start 273.981926 -92.582492)
		(end 273.508978 -92.109544)
		(width 0.11684)
		(layer "In6.Cu")
		(net "P3V3_OCP_SFF_EN_R")
	)
	(segment
		(start 406.158954 -96.295972)
		(end 317.05931 -96.295972)
		(width 0.11684)
		(layer "In6.Cu")
		(net "P3V3_OCP_SFF_EN_R")
	)
	(segment
		(start 218.727274 -95.76435)
		(end 218.341702 -95.76435)
		(width 0.11684)
		(layer "In6.Cu")
		(net "P3V3_OCP_SFF_EN_R")
	)
	(segment
		(start 166.437056 -100.50526)
		(end 167.340788 -101.408992)
		(width 0.11684)
		(layer "In6.Cu")
		(net "P3V3_OCP_SFF_EN_R")
	)
	(segment
		(start 170.069002 -105.574084)
		(end 171.13504 -106.640122)
		(width 0.11684)
		(layer "In6.Cu")
		(net "P3V3_OCP_SFF_EN_R")
	)
	(segment
		(start 273.508978 -92.109544)
		(end 263.68502 -92.109544)
		(width 0.11684)
		(layer "In6.Cu")
		(net "P3V3_OCP_SFF_EN_R")
	)
	(segment
		(start 280.921968 -94.884748)
		(end 278.619712 -92.582492)
		(width 0.11684)
		(layer "In6.Cu")
		(net "P3V3_OCP_SFF_EN_R")
	)
	(segment
		(start 231.850184 -94.727776)
		(end 219.763848 -94.727776)
		(width 0.11684)
		(layer "In6.Cu")
		(net "P3V3_OCP_SFF_EN_R")
	)
	(segment
		(start 173.079918 -97.584768)
		(end 169.855134 -97.584768)
		(width 0.11684)
		(layer "In6.Cu")
		(net "P3V3_OCP_SFF_EN_R")
	)
	(segment
		(start 206.099918 -94.145862)
		(end 203.721716 -91.76766)
		(width 0.11684)
		(layer "In6.Cu")
		(net "P3V3_OCP_SFF_EN_R")
	)
	(segment
		(start 233.196892 -96.074484)
		(end 231.850184 -94.727776)
		(width 0.11684)
		(layer "In6.Cu")
		(net "P3V3_OCP_SFF_EN_R")
	)
	(segment
		(start 250.317 -38.664896)
		(end 251.8029 -38.664896)
		(width 0.10668)
		(layer "F.Cu")
		(net "HP_LVC3_E1S_0_HSC_PWRGD")
	)
	(segment
		(start 251.82195 -38.683946)
		(end 251.82195 -39.218108)
		(width 0.10668)
		(layer "F.Cu")
		(net "HP_LVC3_E1S_0_HSC_PWRGD")
	)
	(segment
		(start 254.35433 -54.819042)
		(end 254.155194 -54.619906)
		(width 0.10668)
		(layer "F.Cu")
		(net "HP_LVC3_E1S_0_HSC_PWRGD")
	)
	(segment
		(start 251.8029 -38.664896)
		(end 251.82195 -38.683946)
		(width 0.10668)
		(layer "F.Cu")
		(net "HP_LVC3_E1S_0_HSC_PWRGD")
	)
	(segment
		(start 251.82195 -39.218108)
		(end 251.607066 -39.432992)
		(width 0.10668)
		(layer "F.Cu")
		(net "HP_LVC3_E1S_0_HSC_PWRGD")
	)
	(segment
		(start 254.155194 -54.619906)
		(end 254.361442 -54.413658)
		(width 0.10668)
		(layer "F.Cu")
		(net "HP_LVC3_E1S_0_HSC_PWRGD")
	)
	(segment
		(start 254.35433 -55.460392)
		(end 254.35433 -54.819042)
		(width 0.10668)
		(layer "F.Cu")
		(net "HP_LVC3_E1S_0_HSC_PWRGD")
	)
	(segment
		(start 254.361442 -54.413658)
		(end 254.361442 -53.782468)
		(width 0.10668)
		(layer "F.Cu")
		(net "HP_LVC3_E1S_0_HSC_PWRGD")
	)
	(via
		(at 251.607066 -39.432992)
		(size 0.508)
		(drill 0.254)
		(layers "F.Cu" "B.Cu")
		(net "HP_LVC3_E1S_0_HSC_PWRGD")
	)
	(via
		(at 243.372132 -114.05108)
		(size 0.508)
		(drill 0.254)
		(layers "F.Cu" "B.Cu")
		(net "HP_LVC3_E1S_0_HSC_PWRGD")
	)
	(via
		(at 254.155194 -54.619906)
		(size 0.508)
		(drill 0.254)
		(layers "F.Cu" "B.Cu")
		(net "HP_LVC3_E1S_0_HSC_PWRGD")
	)
	(via
		(at 198.977758 -114.641376)
		(size 0.508)
		(drill 0.254)
		(layers "F.Cu" "B.Cu")
		(net "HP_LVC3_E1S_0_HSC_PWRGD")
	)
	(segment
		(start 198.977758 -115.083844)
		(end 199.129396 -115.235482)
		(width 0.10668)
		(layer "B.Cu")
		(net "HP_LVC3_E1S_0_HSC_PWRGD")
	)
	(segment
		(start 198.977758 -114.641376)
		(end 198.977758 -115.083844)
		(width 0.10668)
		(layer "B.Cu")
		(net "HP_LVC3_E1S_0_HSC_PWRGD")
	)
	(segment
		(start 199.129396 -115.235482)
		(end 199.129396 -115.773962)
		(width 0.10668)
		(layer "B.Cu")
		(net "HP_LVC3_E1S_0_HSC_PWRGD")
	)
	(segment
		(start 243.8908 -64.938148)
		(end 241.723672 -64.938148)
		(width 0.11684)
		(layer "In11.Cu")
		(net "HP_LVC3_E1S_0_HSC_PWRGD")
	)
	(segment
		(start 250.825 -43.922696)
		(end 250.825 -45.562774)
		(width 0.11684)
		(layer "In11.Cu")
		(net "HP_LVC3_E1S_0_HSC_PWRGD")
	)
	(segment
		(start 251.687584 -39.51351)
		(end 251.687584 -43.060112)
		(width 0.11684)
		(layer "In11.Cu")
		(net "HP_LVC3_E1S_0_HSC_PWRGD")
	)
	(segment
		(start 254.155194 -54.619906)
		(end 254.155194 -54.673754)
		(width 0.11684)
		(layer "In11.Cu")
		(net "HP_LVC3_E1S_0_HSC_PWRGD")
	)
	(segment
		(start 243.372132 -78.996286)
		(end 243.372132 -114.05108)
		(width 0.11684)
		(layer "In11.Cu")
		(net "HP_LVC3_E1S_0_HSC_PWRGD")
	)
	(segment
		(start 240.05286 -75.677014)
		(end 243.372132 -78.996286)
		(width 0.11684)
		(layer "In11.Cu")
		(net "HP_LVC3_E1S_0_HSC_PWRGD")
	)
	(segment
		(start 250.825 -45.562774)
		(end 251.54001 -47.288958)
		(width 0.11684)
		(layer "In11.Cu")
		(net "HP_LVC3_E1S_0_HSC_PWRGD")
	)
	(segment
		(start 254.155194 -54.673754)
		(end 243.8908 -64.938148)
		(width 0.11684)
		(layer "In11.Cu")
		(net "HP_LVC3_E1S_0_HSC_PWRGD")
	)
	(segment
		(start 251.607066 -39.432992)
		(end 251.687584 -39.51351)
		(width 0.11684)
		(layer "In11.Cu")
		(net "HP_LVC3_E1S_0_HSC_PWRGD")
	)
	(segment
		(start 252.476 -48.224948)
		(end 252.476 -52.940712)
		(width 0.11684)
		(layer "In11.Cu")
		(net "HP_LVC3_E1S_0_HSC_PWRGD")
	)
	(segment
		(start 241.723672 -64.938148)
		(end 240.05286 -66.60896)
		(width 0.11684)
		(layer "In11.Cu")
		(net "HP_LVC3_E1S_0_HSC_PWRGD")
	)
	(segment
		(start 251.687584 -43.060112)
		(end 250.825 -43.922696)
		(width 0.11684)
		(layer "In11.Cu")
		(net "HP_LVC3_E1S_0_HSC_PWRGD")
	)
	(segment
		(start 251.54001 -47.288958)
		(end 252.476 -48.224948)
		(width 0.11684)
		(layer "In11.Cu")
		(net "HP_LVC3_E1S_0_HSC_PWRGD")
	)
	(segment
		(start 240.05286 -66.60896)
		(end 240.05286 -75.677014)
		(width 0.11684)
		(layer "In11.Cu")
		(net "HP_LVC3_E1S_0_HSC_PWRGD")
	)
	(segment
		(start 252.476 -52.940712)
		(end 254.155194 -54.619906)
		(width 0.11684)
		(layer "In11.Cu")
		(net "HP_LVC3_E1S_0_HSC_PWRGD")
	)
	(segment
		(start 201.832972 -113.131854)
		(end 208.064354 -113.131854)
		(width 0.11684)
		(layer "In15.Cu")
		(net "HP_LVC3_E1S_0_HSC_PWRGD")
	)
	(segment
		(start 198.977758 -114.576352)
		(end 199.501506 -114.052604)
		(width 0.11684)
		(layer "In15.Cu")
		(net "HP_LVC3_E1S_0_HSC_PWRGD")
	)
	(segment
		(start 239.139476 -113.306352)
		(end 240.968784 -115.13566)
		(width 0.11684)
		(layer "In15.Cu")
		(net "HP_LVC3_E1S_0_HSC_PWRGD")
	)
	(segment
		(start 198.977758 -114.641376)
		(end 198.977758 -114.576352)
		(width 0.11684)
		(layer "In15.Cu")
		(net "HP_LVC3_E1S_0_HSC_PWRGD")
	)
	(segment
		(start 242.287552 -115.13566)
		(end 243.372132 -114.05108)
		(width 0.11684)
		(layer "In15.Cu")
		(net "HP_LVC3_E1S_0_HSC_PWRGD")
	)
	(segment
		(start 221.552516 -112.80521)
		(end 222.053658 -113.306352)
		(width 0.11684)
		(layer "In15.Cu")
		(net "HP_LVC3_E1S_0_HSC_PWRGD")
	)
	(segment
		(start 208.815178 -113.882678)
		(end 209.638392 -113.882678)
		(width 0.11684)
		(layer "In15.Cu")
		(net "HP_LVC3_E1S_0_HSC_PWRGD")
	)
	(segment
		(start 209.638392 -113.882678)
		(end 209.97799 -113.54308)
		(width 0.11684)
		(layer "In15.Cu")
		(net "HP_LVC3_E1S_0_HSC_PWRGD")
	)
	(segment
		(start 240.968784 -115.13566)
		(end 242.287552 -115.13566)
		(width 0.11684)
		(layer "In15.Cu")
		(net "HP_LVC3_E1S_0_HSC_PWRGD")
	)
	(segment
		(start 208.064354 -113.131854)
		(end 208.815178 -113.882678)
		(width 0.11684)
		(layer "In15.Cu")
		(net "HP_LVC3_E1S_0_HSC_PWRGD")
	)
	(segment
		(start 200.912222 -114.052604)
		(end 201.832972 -113.131854)
		(width 0.11684)
		(layer "In15.Cu")
		(net "HP_LVC3_E1S_0_HSC_PWRGD")
	)
	(segment
		(start 209.97799 -113.54308)
		(end 213.126574 -113.54308)
		(width 0.11684)
		(layer "In15.Cu")
		(net "HP_LVC3_E1S_0_HSC_PWRGD")
	)
	(segment
		(start 213.126574 -113.54308)
		(end 213.864444 -112.80521)
		(width 0.11684)
		(layer "In15.Cu")
		(net "HP_LVC3_E1S_0_HSC_PWRGD")
	)
	(segment
		(start 199.501506 -114.052604)
		(end 200.912222 -114.052604)
		(width 0.11684)
		(layer "In15.Cu")
		(net "HP_LVC3_E1S_0_HSC_PWRGD")
	)
	(segment
		(start 222.053658 -113.306352)
		(end 239.139476 -113.306352)
		(width 0.11684)
		(layer "In15.Cu")
		(net "HP_LVC3_E1S_0_HSC_PWRGD")
	)
	(segment
		(start 213.864444 -112.80521)
		(end 221.552516 -112.80521)
		(width 0.11684)
		(layer "In15.Cu")
		(net "HP_LVC3_E1S_0_HSC_PWRGD")
	)
	(segment
		(start 179.52212 -116.252752)
		(end 179.13223 -116.642642)
		(width 0.10668)
		(layer "F.Cu")
		(net "RST_MB_STBY_N")
	)
	(via
		(at 166.125398 -23.683214)
		(size 0.508)
		(drill 0.254)
		(layers "F.Cu" "B.Cu")
		(net "RST_MB_STBY_N")
	)
	(via
		(at 179.13223 -116.642642)
		(size 0.4572)
		(drill 0.254)
		(layers "F.Cu" "B.Cu")
		(net "RST_MB_STBY_N")
	)
	(via
		(at 148.94306 -17.599914)
		(size 0.508)
		(drill 0.254)
		(layers "F.Cu" "B.Cu")
		(net "RST_MB_STBY_N")
	)
	(via
		(at 145.270982 -16.913098)
		(size 0.6604)
		(drill 0.3302)
		(layers "F.Cu" "B.Cu")
		(net "RST_MB_STBY_N")
	)
	(segment
		(start 144.9832 -15.750032)
		(end 144.9832 -14.67104)
		(width 0.10668)
		(layer "B.Cu")
		(net "RST_MB_STBY_N")
	)
	(segment
		(start 144.102582 -16.913098)
		(end 144.102582 -16.63065)
		(width 0.10668)
		(layer "B.Cu")
		(net "RST_MB_STBY_N")
	)
	(segment
		(start 144.102582 -16.63065)
		(end 144.9832 -15.750032)
		(width 0.10668)
		(layer "B.Cu")
		(net "RST_MB_STBY_N")
	)
	(segment
		(start 144.9832 -14.67104)
		(end 144.477232 -14.165072)
		(width 0.10668)
		(layer "B.Cu")
		(net "RST_MB_STBY_N")
	)
	(segment
		(start 144.477232 -14.165072)
		(end 144.3228 -14.165072)
		(width 0.10668)
		(layer "B.Cu")
		(net "RST_MB_STBY_N")
	)
	(segment
		(start 148.256244 -16.913098)
		(end 148.94306 -17.599914)
		(width 0.10668)
		(layer "B.Cu")
		(net "RST_MB_STBY_N")
	)
	(segment
		(start 144.102582 -16.913098)
		(end 145.270982 -16.913098)
		(width 0.10668)
		(layer "B.Cu")
		(net "RST_MB_STBY_N")
	)
	(segment
		(start 145.270982 -16.913098)
		(end 148.256244 -16.913098)
		(width 0.10668)
		(layer "B.Cu")
		(net "RST_MB_STBY_N")
	)
	(segment
		(start 166.093648 -21.977604)
		(end 165.47846 -22.592792)
		(width 0.11684)
		(layer "In6.Cu")
		(net "RST_MB_STBY_N")
	)
	(segment
		(start 165.47846 -23.420324)
		(end 165.74135 -23.683214)
		(width 0.11684)
		(layer "In6.Cu")
		(net "RST_MB_STBY_N")
	)
	(segment
		(start 165.47846 -22.592792)
		(end 165.47846 -23.420324)
		(width 0.11684)
		(layer "In6.Cu")
		(net "RST_MB_STBY_N")
	)
	(segment
		(start 166.093648 -18.200878)
		(end 166.093648 -21.977604)
		(width 0.11684)
		(layer "In6.Cu")
		(net "RST_MB_STBY_N")
	)
	(segment
		(start 164.693346 -16.800576)
		(end 166.093648 -18.200878)
		(width 0.11684)
		(layer "In6.Cu")
		(net "RST_MB_STBY_N")
	)
	(segment
		(start 150.159466 -16.800576)
		(end 164.693346 -16.800576)
		(width 0.11684)
		(layer "In6.Cu")
		(net "RST_MB_STBY_N")
	)
	(segment
		(start 165.74135 -23.683214)
		(end 166.125398 -23.683214)
		(width 0.11684)
		(layer "In6.Cu")
		(net "RST_MB_STBY_N")
	)
	(segment
		(start 149.360128 -17.599914)
		(end 150.159466 -16.800576)
		(width 0.11684)
		(layer "In6.Cu")
		(net "RST_MB_STBY_N")
	)
	(segment
		(start 148.94306 -17.599914)
		(end 149.360128 -17.599914)
		(width 0.11684)
		(layer "In6.Cu")
		(net "RST_MB_STBY_N")
	)
	(segment
		(start 174.249588 -84.85378)
		(end 168.16578 -78.769972)
		(width 0.11684)
		(layer "In11.Cu")
		(net "RST_MB_STBY_N")
	)
	(segment
		(start 166.65956 -49.154588)
		(end 169.55262 -46.261528)
		(width 0.11684)
		(layer "In11.Cu")
		(net "RST_MB_STBY_N")
	)
	(segment
		(start 177.978308 -116.243608)
		(end 175.062642 -113.327942)
		(width 0.11684)
		(layer "In11.Cu")
		(net "RST_MB_STBY_N")
	)
	(segment
		(start 175.539146 -104.449118)
		(end 175.539146 -103.001826)
		(width 0.11684)
		(layer "In11.Cu")
		(net "RST_MB_STBY_N")
	)
	(segment
		(start 178.733196 -116.243608)
		(end 177.978308 -116.243608)
		(width 0.11684)
		(layer "In11.Cu")
		(net "RST_MB_STBY_N")
	)
	(segment
		(start 166.9034 -24.123904)
		(end 166.46271 -23.683214)
		(width 0.11684)
		(layer "In11.Cu")
		(net "RST_MB_STBY_N")
	)
	(segment
		(start 169.55262 -46.261528)
		(end 169.55262 -41.610788)
		(width 0.11684)
		(layer "In11.Cu")
		(net "RST_MB_STBY_N")
	)
	(segment
		(start 172.404532 -91.938602)
		(end 172.847 -91.496134)
		(width 0.11684)
		(layer "In11.Cu")
		(net "RST_MB_STBY_N")
	)
	(segment
		(start 172.847 -90.46972)
		(end 174.249588 -89.067132)
		(width 0.11684)
		(layer "In11.Cu")
		(net "RST_MB_STBY_N")
	)
	(segment
		(start 166.9034 -38.961568)
		(end 166.9034 -24.123904)
		(width 0.11684)
		(layer "In11.Cu")
		(net "RST_MB_STBY_N")
	)
	(segment
		(start 166.65956 -53.760116)
		(end 166.65956 -49.154588)
		(width 0.11684)
		(layer "In11.Cu")
		(net "RST_MB_STBY_N")
	)
	(segment
		(start 175.539146 -103.001826)
		(end 174.652686 -102.115366)
		(width 0.11684)
		(layer "In11.Cu")
		(net "RST_MB_STBY_N")
	)
	(segment
		(start 175.062642 -104.925622)
		(end 175.539146 -104.449118)
		(width 0.11684)
		(layer "In11.Cu")
		(net "RST_MB_STBY_N")
	)
	(segment
		(start 173.098714 -98.16973)
		(end 172.404532 -97.475548)
		(width 0.11684)
		(layer "In11.Cu")
		(net "RST_MB_STBY_N")
	)
	(segment
		(start 179.13223 -116.642642)
		(end 178.733196 -116.243608)
		(width 0.11684)
		(layer "In11.Cu")
		(net "RST_MB_STBY_N")
	)
	(segment
		(start 172.404532 -97.475548)
		(end 172.404532 -91.938602)
		(width 0.11684)
		(layer "In11.Cu")
		(net "RST_MB_STBY_N")
	)
	(segment
		(start 174.652686 -101.00564)
		(end 173.098714 -99.451668)
		(width 0.11684)
		(layer "In11.Cu")
		(net "RST_MB_STBY_N")
	)
	(segment
		(start 168.16578 -55.266336)
		(end 166.65956 -53.760116)
		(width 0.11684)
		(layer "In11.Cu")
		(net "RST_MB_STBY_N")
	)
	(segment
		(start 169.55262 -41.610788)
		(end 166.9034 -38.961568)
		(width 0.11684)
		(layer "In11.Cu")
		(net "RST_MB_STBY_N")
	)
	(segment
		(start 174.249588 -89.067132)
		(end 174.249588 -84.85378)
		(width 0.11684)
		(layer "In11.Cu")
		(net "RST_MB_STBY_N")
	)
	(segment
		(start 168.16578 -78.769972)
		(end 168.16578 -55.266336)
		(width 0.11684)
		(layer "In11.Cu")
		(net "RST_MB_STBY_N")
	)
	(segment
		(start 173.098714 -99.451668)
		(end 173.098714 -98.16973)
		(width 0.11684)
		(layer "In11.Cu")
		(net "RST_MB_STBY_N")
	)
	(segment
		(start 172.847 -91.496134)
		(end 172.847 -90.46972)
		(width 0.11684)
		(layer "In11.Cu")
		(net "RST_MB_STBY_N")
	)
	(segment
		(start 175.062642 -113.327942)
		(end 175.062642 -104.925622)
		(width 0.11684)
		(layer "In11.Cu")
		(net "RST_MB_STBY_N")
	)
	(segment
		(start 174.652686 -102.115366)
		(end 174.652686 -101.00564)
		(width 0.11684)
		(layer "In11.Cu")
		(net "RST_MB_STBY_N")
	)
	(segment
		(start 166.46271 -23.683214)
		(end 166.125398 -23.683214)
		(width 0.11684)
		(layer "In11.Cu")
		(net "RST_MB_STBY_N")
	)
	(segment
		(start 312.499248 -23.92934)
		(end 311.861962 -23.92934)
		(width 0.10668)
		(layer "F.Cu")
		(net "FW_RECOVERY_R")
	)
	(segment
		(start 314.174886 -23.92934)
		(end 312.499248 -23.92934)
		(width 0.10668)
		(layer "F.Cu")
		(net "FW_RECOVERY_R")
	)
	(via
		(at 146.425412 -14.875002)
		(size 0.508)
		(drill 0.254)
		(layers "F.Cu" "B.Cu")
		(net "FW_RECOVERY_R")
	)
	(via
		(at 311.861962 -23.92934)
		(size 0.508)
		(drill 0.254)
		(layers "F.Cu" "B.Cu")
		(net "FW_RECOVERY_R")
	)
	(segment
		(start 146.3548 -14.80439)
		(end 146.425412 -14.875002)
		(width 0.10668)
		(layer "B.Cu")
		(net "FW_RECOVERY_R")
	)
	(segment
		(start 146.3548 -14.172438)
		(end 146.3548 -14.80439)
		(width 0.10668)
		(layer "B.Cu")
		(net "FW_RECOVERY_R")
	)
	(segment
		(start 257.868928 -39.31412)
		(end 260.563614 -39.31412)
		(width 0.11684)
		(layer "In6.Cu")
		(net "FW_RECOVERY_R")
	)
	(segment
		(start 165.669214 -16.05788)
		(end 166.736522 -17.125188)
		(width 0.11684)
		(layer "In6.Cu")
		(net "FW_RECOVERY_R")
	)
	(segment
		(start 185.047636 -18.236184)
		(end 185.29554 -18.484088)
		(width 0.11684)
		(layer "In6.Cu")
		(net "FW_RECOVERY_R")
	)
	(segment
		(start 166.736522 -17.125188)
		(end 170.814238 -17.125188)
		(width 0.11684)
		(layer "In6.Cu")
		(net "FW_RECOVERY_R")
	)
	(segment
		(start 235.73994 -42.05986)
		(end 242.788694 -42.05986)
		(width 0.11684)
		(layer "In6.Cu")
		(net "FW_RECOVERY_R")
	)
	(segment
		(start 232.432606 -40.390064)
		(end 234.070144 -40.390064)
		(width 0.11684)
		(layer "In6.Cu")
		(net "FW_RECOVERY_R")
	)
	(segment
		(start 242.788694 -42.05986)
		(end 246.862092 -37.986462)
		(width 0.11684)
		(layer "In6.Cu")
		(net "FW_RECOVERY_R")
	)
	(segment
		(start 188.759592 -25.133808)
		(end 188.759592 -27.841448)
		(width 0.11684)
		(layer "In6.Cu")
		(net "FW_RECOVERY_R")
	)
	(segment
		(start 171.033948 -16.905478)
		(end 184.912 -16.905478)
		(width 0.11684)
		(layer "In6.Cu")
		(net "FW_RECOVERY_R")
	)
	(segment
		(start 256.54127 -37.986462)
		(end 257.868928 -39.31412)
		(width 0.11684)
		(layer "In6.Cu")
		(net "FW_RECOVERY_R")
	)
	(segment
		(start 278.27605 -36.149788)
		(end 293.77005 -20.655788)
		(width 0.11684)
		(layer "In6.Cu")
		(net "FW_RECOVERY_R")
	)
	(segment
		(start 298.674028 -20.655788)
		(end 300.367446 -18.96237)
		(width 0.11684)
		(layer "In6.Cu")
		(net "FW_RECOVERY_R")
	)
	(segment
		(start 188.759592 -27.841448)
		(end 188.50102 -28.10002)
		(width 0.11684)
		(layer "In6.Cu")
		(net "FW_RECOVERY_R")
	)
	(segment
		(start 234.070144 -40.390064)
		(end 235.73994 -42.05986)
		(width 0.11684)
		(layer "In6.Cu")
		(net "FW_RECOVERY_R")
	)
	(segment
		(start 263.727946 -36.149788)
		(end 278.27605 -36.149788)
		(width 0.11684)
		(layer "In6.Cu")
		(net "FW_RECOVERY_R")
	)
	(segment
		(start 146.906488 -15.442692)
		(end 149.310852 -15.442692)
		(width 0.11684)
		(layer "In6.Cu")
		(net "FW_RECOVERY_R")
	)
	(segment
		(start 220.03385 -32.478472)
		(end 220.03385 -36.345368)
		(width 0.11684)
		(layer "In6.Cu")
		(net "FW_RECOVERY_R")
	)
	(segment
		(start 311.861962 -20.957032)
		(end 311.861962 -23.92934)
		(width 0.11684)
		(layer "In6.Cu")
		(net "FW_RECOVERY_R")
	)
	(segment
		(start 208.108042 -31.116778)
		(end 218.672156 -31.116778)
		(width 0.11684)
		(layer "In6.Cu")
		(net "FW_RECOVERY_R")
	)
	(segment
		(start 170.814238 -17.125188)
		(end 171.033948 -16.905478)
		(width 0.11684)
		(layer "In6.Cu")
		(net "FW_RECOVERY_R")
	)
	(segment
		(start 246.862092 -37.986462)
		(end 256.54127 -37.986462)
		(width 0.11684)
		(layer "In6.Cu")
		(net "FW_RECOVERY_R")
	)
	(segment
		(start 222.362776 -38.674294)
		(end 230.716836 -38.674294)
		(width 0.11684)
		(layer "In6.Cu")
		(net "FW_RECOVERY_R")
	)
	(segment
		(start 146.425412 -14.961616)
		(end 146.906488 -15.442692)
		(width 0.11684)
		(layer "In6.Cu")
		(net "FW_RECOVERY_R")
	)
	(segment
		(start 185.29554 -18.484088)
		(end 185.29554 -19.675348)
		(width 0.11684)
		(layer "In6.Cu")
		(net "FW_RECOVERY_R")
	)
	(segment
		(start 204.786992 -34.437828)
		(end 208.108042 -31.116778)
		(width 0.11684)
		(layer "In6.Cu")
		(net "FW_RECOVERY_R")
	)
	(segment
		(start 185.858912 -20.23872)
		(end 185.858912 -20.545044)
		(width 0.11684)
		(layer "In6.Cu")
		(net "FW_RECOVERY_R")
	)
	(segment
		(start 220.03385 -36.345368)
		(end 222.362776 -38.674294)
		(width 0.11684)
		(layer "In6.Cu")
		(net "FW_RECOVERY_R")
	)
	(segment
		(start 188.50102 -30.757876)
		(end 192.180972 -34.437828)
		(width 0.11684)
		(layer "In6.Cu")
		(net "FW_RECOVERY_R")
	)
	(segment
		(start 218.672156 -31.116778)
		(end 220.03385 -32.478472)
		(width 0.11684)
		(layer "In6.Cu")
		(net "FW_RECOVERY_R")
	)
	(segment
		(start 149.310852 -15.442692)
		(end 149.92604 -16.05788)
		(width 0.11684)
		(layer "In6.Cu")
		(net "FW_RECOVERY_R")
	)
	(segment
		(start 260.563614 -39.31412)
		(end 263.727946 -36.149788)
		(width 0.11684)
		(layer "In6.Cu")
		(net "FW_RECOVERY_R")
	)
	(segment
		(start 309.8673 -18.96237)
		(end 311.861962 -20.957032)
		(width 0.11684)
		(layer "In6.Cu")
		(net "FW_RECOVERY_R")
	)
	(segment
		(start 230.716836 -38.674294)
		(end 232.432606 -40.390064)
		(width 0.11684)
		(layer "In6.Cu")
		(net "FW_RECOVERY_R")
	)
	(segment
		(start 146.425412 -14.875002)
		(end 146.425412 -14.961616)
		(width 0.11684)
		(layer "In6.Cu")
		(net "FW_RECOVERY_R")
	)
	(segment
		(start 187.047632 -21.733764)
		(end 187.047632 -23.421848)
		(width 0.11684)
		(layer "In6.Cu")
		(net "FW_RECOVERY_R")
	)
	(segment
		(start 300.367446 -18.96237)
		(end 309.8673 -18.96237)
		(width 0.11684)
		(layer "In6.Cu")
		(net "FW_RECOVERY_R")
	)
	(segment
		(start 192.180972 -34.437828)
		(end 204.786992 -34.437828)
		(width 0.11684)
		(layer "In6.Cu")
		(net "FW_RECOVERY_R")
	)
	(segment
		(start 185.29554 -19.675348)
		(end 185.858912 -20.23872)
		(width 0.11684)
		(layer "In6.Cu")
		(net "FW_RECOVERY_R")
	)
	(segment
		(start 184.912 -16.905478)
		(end 185.047636 -17.041114)
		(width 0.11684)
		(layer "In6.Cu")
		(net "FW_RECOVERY_R")
	)
	(segment
		(start 293.77005 -20.655788)
		(end 298.674028 -20.655788)
		(width 0.11684)
		(layer "In6.Cu")
		(net "FW_RECOVERY_R")
	)
	(segment
		(start 149.92604 -16.05788)
		(end 165.669214 -16.05788)
		(width 0.11684)
		(layer "In6.Cu")
		(net "FW_RECOVERY_R")
	)
	(segment
		(start 185.047636 -17.041114)
		(end 185.047636 -18.236184)
		(width 0.11684)
		(layer "In6.Cu")
		(net "FW_RECOVERY_R")
	)
	(segment
		(start 188.50102 -28.10002)
		(end 188.50102 -30.757876)
		(width 0.11684)
		(layer "In6.Cu")
		(net "FW_RECOVERY_R")
	)
	(segment
		(start 185.858912 -20.545044)
		(end 187.047632 -21.733764)
		(width 0.11684)
		(layer "In6.Cu")
		(net "FW_RECOVERY_R")
	)
	(segment
		(start 187.047632 -23.421848)
		(end 188.759592 -25.133808)
		(width 0.11684)
		(layer "In6.Cu")
		(net "FW_RECOVERY_R")
	)
	(via
		(at 107.625388 -412.934912)
		(size 0.6604)
		(drill 0.3302)
		(layers "F.Cu" "B.Cu")
		(net "HGX_DETECT_N_ISO")
	)
	(via
		(at 109.642656 -412.582868)
		(size 0.508)
		(drill 0.254)
		(layers "F.Cu" "B.Cu")
		(net "HGX_DETECT_N_ISO")
	)
	(segment
		(start 107.118912 -412.428436)
		(end 106.891074 -412.428436)
		(width 0.10668)
		(layer "B.Cu")
		(net "HGX_DETECT_N_ISO")
	)
	(segment
		(start 108.570014 -414.08604)
		(end 108.777278 -413.878776)
		(width 0.10668)
		(layer "B.Cu")
		(net "HGX_DETECT_N_ISO")
	)
	(segment
		(start 105.700576 -412.428436)
		(end 105.695242 -412.43377)
		(width 0.10668)
		(layer "B.Cu")
		(net "HGX_DETECT_N_ISO")
	)
	(segment
		(start 107.983528 -413.293052)
		(end 107.625388 -412.934912)
		(width 0.10668)
		(layer "B.Cu")
		(net "HGX_DETECT_N_ISO")
	)
	(segment
		(start 108.570014 -414.08604)
		(end 107.983528 -413.499554)
		(width 0.10668)
		(layer "B.Cu")
		(net "HGX_DETECT_N_ISO")
	)
	(segment
		(start 108.777278 -413.878776)
		(end 108.777278 -413.448246)
		(width 0.10668)
		(layer "B.Cu")
		(net "HGX_DETECT_N_ISO")
	)
	(segment
		(start 104.557068 -412.43377)
		(end 104.555544 -412.432246)
		(width 0.10668)
		(layer "B.Cu")
		(net "HGX_DETECT_N_ISO")
	)
	(segment
		(start 105.695242 -412.43377)
		(end 104.557068 -412.43377)
		(width 0.10668)
		(layer "B.Cu")
		(net "HGX_DETECT_N_ISO")
	)
	(segment
		(start 107.625388 -412.934912)
		(end 107.118912 -412.428436)
		(width 0.10668)
		(layer "B.Cu")
		(net "HGX_DETECT_N_ISO")
	)
	(segment
		(start 107.983528 -413.499554)
		(end 107.983528 -413.293052)
		(width 0.10668)
		(layer "B.Cu")
		(net "HGX_DETECT_N_ISO")
	)
	(segment
		(start 106.891074 -412.428436)
		(end 105.700576 -412.428436)
		(width 0.10668)
		(layer "B.Cu")
		(net "HGX_DETECT_N_ISO")
	)
	(segment
		(start 108.777278 -413.448246)
		(end 109.642656 -412.582868)
		(width 0.10668)
		(layer "B.Cu")
		(net "HGX_DETECT_N_ISO")
	)
	(segment
		(start 75.9206 -422.9354)
		(end 74.0664 -424.7896)
		(width 0.11684)
		(layer "In4.Cu")
		(net "HGX_DETECT_N_ISO")
	)
	(segment
		(start 106.033316 -424.379898)
		(end 105.73131 -424.077892)
		(width 0.11684)
		(layer "In4.Cu")
		(net "HGX_DETECT_N_ISO")
	)
	(segment
		(start 105.266998 -424.077892)
		(end 104.570022 -424.774868)
		(width 0.11684)
		(layer "In4.Cu")
		(net "HGX_DETECT_N_ISO")
	)
	(segment
		(start 68.155312 -440.73572)
		(end 67.353688 -440.73572)
		(width 0.11684)
		(layer "In4.Cu")
		(net "HGX_DETECT_N_ISO")
	)
	(segment
		(start 105.73131 -424.077892)
		(end 105.266998 -424.077892)
		(width 0.11684)
		(layer "In4.Cu")
		(net "HGX_DETECT_N_ISO")
	)
	(segment
		(start 110.542578 -414.580578)
		(end 111.500158 -415.538158)
		(width 0.11684)
		(layer "In4.Cu")
		(net "HGX_DETECT_N_ISO")
	)
	(segment
		(start 110.09757 -421.792146)
		(end 110.09757 -421.802052)
		(width 0.11684)
		(layer "In4.Cu")
		(net "HGX_DETECT_N_ISO")
	)
	(segment
		(start 104.570022 -424.774868)
		(end 92.969334 -424.774868)
		(width 0.11684)
		(layer "In4.Cu")
		(net "HGX_DETECT_N_ISO")
	)
	(segment
		(start 111.500158 -415.538158)
		(end 111.500158 -420.389558)
		(width 0.11684)
		(layer "In4.Cu")
		(net "HGX_DETECT_N_ISO")
	)
	(segment
		(start 109.323886 -413.711898)
		(end 110.192566 -414.580578)
		(width 0.11684)
		(layer "In4.Cu")
		(net "HGX_DETECT_N_ISO")
	)
	(segment
		(start 110.09757 -421.802052)
		(end 107.519724 -424.379898)
		(width 0.11684)
		(layer "In4.Cu")
		(net "HGX_DETECT_N_ISO")
	)
	(segment
		(start 110.192566 -414.580578)
		(end 110.542578 -414.580578)
		(width 0.11684)
		(layer "In4.Cu")
		(net "HGX_DETECT_N_ISO")
	)
	(segment
		(start 111.500158 -420.389558)
		(end 110.09757 -421.792146)
		(width 0.11684)
		(layer "In4.Cu")
		(net "HGX_DETECT_N_ISO")
	)
	(segment
		(start 67.353688 -440.73572)
		(end 67.0306 -441.058808)
		(width 0.11684)
		(layer "In4.Cu")
		(net "HGX_DETECT_N_ISO")
	)
	(segment
		(start 109.642656 -412.582868)
		(end 109.323886 -412.901638)
		(width 0.11684)
		(layer "In4.Cu")
		(net "HGX_DETECT_N_ISO")
	)
	(segment
		(start 63.218822 -441.058808)
		(end 62.649862 -440.489848)
		(width 0.11684)
		(layer "In4.Cu")
		(net "HGX_DETECT_N_ISO")
	)
	(segment
		(start 67.0306 -441.058808)
		(end 63.218822 -441.058808)
		(width 0.11684)
		(layer "In4.Cu")
		(net "HGX_DETECT_N_ISO")
	)
	(segment
		(start 107.519724 -424.379898)
		(end 106.033316 -424.379898)
		(width 0.11684)
		(layer "In4.Cu")
		(net "HGX_DETECT_N_ISO")
	)
	(segment
		(start 72.8853 -441.058554)
		(end 68.478146 -441.058554)
		(width 0.11684)
		(layer "In4.Cu")
		(net "HGX_DETECT_N_ISO")
	)
	(segment
		(start 92.969334 -424.774868)
		(end 91.129866 -422.9354)
		(width 0.11684)
		(layer "In4.Cu")
		(net "HGX_DETECT_N_ISO")
	)
	(segment
		(start 68.478146 -441.058554)
		(end 68.155312 -440.73572)
		(width 0.11684)
		(layer "In4.Cu")
		(net "HGX_DETECT_N_ISO")
	)
	(segment
		(start 74.0664 -424.7896)
		(end 74.0664 -439.877454)
		(width 0.11684)
		(layer "In4.Cu")
		(net "HGX_DETECT_N_ISO")
	)
	(segment
		(start 109.323886 -412.901638)
		(end 109.323886 -413.711898)
		(width 0.11684)
		(layer "In4.Cu")
		(net "HGX_DETECT_N_ISO")
	)
	(segment
		(start 74.0664 -439.877454)
		(end 72.8853 -441.058554)
		(width 0.11684)
		(layer "In4.Cu")
		(net "HGX_DETECT_N_ISO")
	)
	(segment
		(start 91.129866 -422.9354)
		(end 75.9206 -422.9354)
		(width 0.11684)
		(layer "In4.Cu")
		(net "HGX_DETECT_N_ISO")
	)
	(segment
		(start 205.559406 -114.249708)
		(end 206.47533 -114.249708)
		(width 0.10668)
		(layer "F.Cu")
		(net "HGX_DETECT_N")
	)
	(via
		(at 102.77856 -415.90595)
		(size 0.508)
		(drill 0.254)
		(layers "F.Cu" "B.Cu")
		(net "HGX_DETECT_N")
	)
	(via
		(at 206.47533 -114.249708)
		(size 0.508)
		(drill 0.254)
		(layers "F.Cu" "B.Cu")
		(net "HGX_DETECT_N")
	)
	(via
		(at 34.427922 -415.81197)
		(size 0.508)
		(drill 0.254)
		(layers "F.Cu" "B.Cu")
		(net "HGX_DETECT_N")
	)
	(via
		(at 206.880206 -141.752828)
		(size 0.508)
		(drill 0.254)
		(layers "F.Cu" "B.Cu")
		(net "HGX_DETECT_N")
	)
	(via
		(at 100.208334 -400.276314)
		(size 0.508)
		(drill 0.254)
		(layers "F.Cu" "B.Cu")
		(net "HGX_DETECT_N")
	)
	(segment
		(start 109.093 -414.607248)
		(end 109.22 -414.480248)
		(width 0.10668)
		(layer "B.Cu")
		(net "HGX_DETECT_N")
	)
	(segment
		(start 103.632 -415.52495)
		(end 104.648 -415.52495)
		(width 0.10668)
		(layer "B.Cu")
		(net "HGX_DETECT_N")
	)
	(segment
		(start 105.565702 -414.607248)
		(end 109.093 -414.607248)
		(width 0.10668)
		(layer "B.Cu")
		(net "HGX_DETECT_N")
	)
	(segment
		(start 104.648 -415.52495)
		(end 105.565702 -414.607248)
		(width 0.10668)
		(layer "B.Cu")
		(net "HGX_DETECT_N")
	)
	(segment
		(start 109.22 -414.480248)
		(end 109.22 -414.08604)
		(width 0.10668)
		(layer "B.Cu")
		(net "HGX_DETECT_N")
	)
	(segment
		(start 103.251 -415.90595)
		(end 102.77856 -415.90595)
		(width 0.10668)
		(layer "B.Cu")
		(net "HGX_DETECT_N")
	)
	(segment
		(start 103.632 -415.52495)
		(end 103.251 -415.90595)
		(width 0.10668)
		(layer "B.Cu")
		(net "HGX_DETECT_N")
	)
	(segment
		(start 43.679364 -399.915634)
		(end 39.49065 -399.915634)
		(width 0.11684)
		(layer "In4.Cu")
		(net "HGX_DETECT_N")
	)
	(segment
		(start 206.361284 -125.229112)
		(end 205.1177 -126.472696)
		(width 0.11684)
		(layer "In4.Cu")
		(net "HGX_DETECT_N")
	)
	(segment
		(start 37.349684 -412.905448)
		(end 37.232844 -413.022288)
		(width 0.11684)
		(layer "In4.Cu")
		(net "HGX_DETECT_N")
	)
	(segment
		(start 97.090738 -400.276314)
		(end 95.324168 -398.509744)
		(width 0.11684)
		(layer "In4.Cu")
		(net "HGX_DETECT_N")
	)
	(segment
		(start 207.18145 -120.953276)
		(end 207.18145 -123.04776)
		(width 0.11684)
		(layer "In4.Cu")
		(net "HGX_DETECT_N")
	)
	(segment
		(start 38.438836 -411.261814)
		(end 37.349684 -412.350966)
		(width 0.11684)
		(layer "In4.Cu")
		(net "HGX_DETECT_N")
	)
	(segment
		(start 206.47533 -114.249708)
		(end 206.381096 -114.249708)
		(width 0.11684)
		(layer "In4.Cu")
		(net "HGX_DETECT_N")
	)
	(segment
		(start 39.49065 -399.915634)
		(end 36.768532 -402.637752)
		(width 0.11684)
		(layer "In4.Cu")
		(net "HGX_DETECT_N")
	)
	(segment
		(start 206.514954 -120.410986)
		(end 206.63916 -120.410986)
		(width 0.11684)
		(layer "In4.Cu")
		(net "HGX_DETECT_N")
	)
	(segment
		(start 206.014066 -119.910098)
		(end 206.514954 -120.410986)
		(width 0.11684)
		(layer "In4.Cu")
		(net "HGX_DETECT_N")
	)
	(segment
		(start 206.63916 -120.410986)
		(end 207.18145 -120.953276)
		(width 0.11684)
		(layer "In4.Cu")
		(net "HGX_DETECT_N")
	)
	(segment
		(start 36.768532 -407.877518)
		(end 38.438836 -409.547822)
		(width 0.11684)
		(layer "In4.Cu")
		(net "HGX_DETECT_N")
	)
	(segment
		(start 205.1177 -132.189982)
		(end 206.425546 -133.497828)
		(width 0.11684)
		(layer "In4.Cu")
		(net "HGX_DETECT_N")
	)
	(segment
		(start 46.923198 -400.984212)
		(end 44.747942 -400.984212)
		(width 0.11684)
		(layer "In4.Cu")
		(net "HGX_DETECT_N")
	)
	(segment
		(start 36.768532 -402.637752)
		(end 36.768532 -407.877518)
		(width 0.11684)
		(layer "In4.Cu")
		(net "HGX_DETECT_N")
	)
	(segment
		(start 206.014066 -114.616738)
		(end 206.014066 -119.910098)
		(width 0.11684)
		(layer "In4.Cu")
		(net "HGX_DETECT_N")
	)
	(segment
		(start 206.82839 -141.752828)
		(end 206.880206 -141.752828)
		(width 0.11684)
		(layer "In4.Cu")
		(net "HGX_DETECT_N")
	)
	(segment
		(start 37.232844 -413.022288)
		(end 37.217604 -413.022288)
		(width 0.11684)
		(layer "In4.Cu")
		(net "HGX_DETECT_N")
	)
	(segment
		(start 49.234344 -398.509744)
		(end 49.117504 -398.626584)
		(width 0.11684)
		(layer "In4.Cu")
		(net "HGX_DETECT_N")
	)
	(segment
		(start 207.142842 -123.627642)
		(end 206.361284 -124.4092)
		(width 0.11684)
		(layer "In4.Cu")
		(net "HGX_DETECT_N")
	)
	(segment
		(start 37.217604 -413.022288)
		(end 34.427922 -415.81197)
		(width 0.11684)
		(layer "In4.Cu")
		(net "HGX_DETECT_N")
	)
	(segment
		(start 207.142842 -123.086368)
		(end 207.142842 -123.627642)
		(width 0.11684)
		(layer "In4.Cu")
		(net "HGX_DETECT_N")
	)
	(segment
		(start 206.361284 -124.4092)
		(end 206.361284 -125.229112)
		(width 0.11684)
		(layer "In4.Cu")
		(net "HGX_DETECT_N")
	)
	(segment
		(start 207.18145 -123.04776)
		(end 207.142842 -123.086368)
		(width 0.11684)
		(layer "In4.Cu")
		(net "HGX_DETECT_N")
	)
	(segment
		(start 95.324168 -398.509744)
		(end 49.234344 -398.509744)
		(width 0.11684)
		(layer "In4.Cu")
		(net "HGX_DETECT_N")
	)
	(segment
		(start 206.425546 -141.349984)
		(end 206.82839 -141.752828)
		(width 0.11684)
		(layer "In4.Cu")
		(net "HGX_DETECT_N")
	)
	(segment
		(start 100.208334 -400.276314)
		(end 97.090738 -400.276314)
		(width 0.11684)
		(layer "In4.Cu")
		(net "HGX_DETECT_N")
	)
	(segment
		(start 37.349684 -412.350966)
		(end 37.349684 -412.905448)
		(width 0.11684)
		(layer "In4.Cu")
		(net "HGX_DETECT_N")
	)
	(segment
		(start 44.747942 -400.984212)
		(end 43.679364 -399.915634)
		(width 0.11684)
		(layer "In4.Cu")
		(net "HGX_DETECT_N")
	)
	(segment
		(start 206.381096 -114.249708)
		(end 206.014066 -114.616738)
		(width 0.11684)
		(layer "In4.Cu")
		(net "HGX_DETECT_N")
	)
	(segment
		(start 49.117504 -398.626584)
		(end 49.117504 -398.789906)
		(width 0.11684)
		(layer "In4.Cu")
		(net "HGX_DETECT_N")
	)
	(segment
		(start 38.438836 -409.547822)
		(end 38.438836 -411.261814)
		(width 0.11684)
		(layer "In4.Cu")
		(net "HGX_DETECT_N")
	)
	(segment
		(start 49.117504 -398.789906)
		(end 46.923198 -400.984212)
		(width 0.11684)
		(layer "In4.Cu")
		(net "HGX_DETECT_N")
	)
	(segment
		(start 205.1177 -126.472696)
		(end 205.1177 -132.189982)
		(width 0.11684)
		(layer "In4.Cu")
		(net "HGX_DETECT_N")
	)
	(segment
		(start 206.425546 -133.497828)
		(end 206.425546 -141.349984)
		(width 0.11684)
		(layer "In4.Cu")
		(net "HGX_DETECT_N")
	)
	(segment
		(start 157.661864 -143.201136)
		(end 150.77821 -136.317482)
		(width 0.11684)
		(layer "In13.Cu")
		(net "HGX_DETECT_N")
	)
	(segment
		(start 93.850714 -136.317482)
		(end 93.491812 -135.95858)
		(width 0.11684)
		(layer "In13.Cu")
		(net "HGX_DETECT_N")
	)
	(segment
		(start 100.208334 -402.511006)
		(end 100.77323 -403.075902)
		(width 0.11684)
		(layer "In13.Cu")
		(net "HGX_DETECT_N")
	)
	(segment
		(start 100.764594 -409.847542)
		(end 102.281736 -411.364684)
		(width 0.11684)
		(layer "In13.Cu")
		(net "HGX_DETECT_N")
	)
	(segment
		(start 176.509934 -143.201136)
		(end 157.661864 -143.201136)
		(width 0.11684)
		(layer "In13.Cu")
		(net "HGX_DETECT_N")
	)
	(segment
		(start 17.26819 -368.620548)
		(end 19.388836 -370.741194)
		(width 0.11684)
		(layer "In13.Cu")
		(net "HGX_DETECT_N")
	)
	(segment
		(start 29.049472 -380.392686)
		(end 31.063946 -382.40716)
		(width 0.11684)
		(layer "In13.Cu")
		(net "HGX_DETECT_N")
	)
	(segment
		(start 4.757166 -357.258366)
		(end 5.504942 -358.006142)
		(width 0.11684)
		(layer "In13.Cu")
		(net "HGX_DETECT_N")
	)
	(segment
		(start 79.071978 -135.95858)
		(end 77.477874 -137.552684)
		(width 0.11684)
		(layer "In13.Cu")
		(net "HGX_DETECT_N")
	)
	(segment
		(start 25.918922 -372.67896)
		(end 29.049472 -375.80951)
		(width 0.11684)
		(layer "In13.Cu")
		(net "HGX_DETECT_N")
	)
	(segment
		(start 6.018022 -335.176876)
		(end 4.757166 -336.437732)
		(width 0.11684)
		(layer "In13.Cu")
		(net "HGX_DETECT_N")
	)
	(segment
		(start 19.388836 -370.741194)
		(end 19.388836 -371.459252)
		(width 0.11684)
		(layer "In13.Cu")
		(net "HGX_DETECT_N")
	)
	(segment
		(start 100.77323 -405.243538)
		(end 100.764594 -405.252174)
		(width 0.11684)
		(layer "In13.Cu")
		(net "HGX_DETECT_N")
	)
	(segment
		(start 31.063946 -382.40716)
		(end 31.063946 -392.226038)
		(width 0.11684)
		(layer "In13.Cu")
		(net "HGX_DETECT_N")
	)
	(segment
		(start 177.132742 -143.823944)
		(end 176.509934 -143.201136)
		(width 0.11684)
		(layer "In13.Cu")
		(net "HGX_DETECT_N")
	)
	(segment
		(start 34.70783 -407.868882)
		(end 33.149794 -409.426918)
		(width 0.11684)
		(layer "In13.Cu")
		(net "HGX_DETECT_N")
	)
	(segment
		(start 33.149794 -409.426918)
		(end 33.149794 -414.533842)
		(width 0.11684)
		(layer "In13.Cu")
		(net "HGX_DETECT_N")
	)
	(segment
		(start 194.37731 -140.892784)
		(end 192.211452 -143.058642)
		(width 0.11684)
		(layer "In13.Cu")
		(net "HGX_DETECT_N")
	)
	(segment
		(start 100.208334 -400.276314)
		(end 100.208334 -402.511006)
		(width 0.11684)
		(layer "In13.Cu")
		(net "HGX_DETECT_N")
	)
	(segment
		(start 200.792334 -143.101822)
		(end 200.144888 -142.454376)
		(width 0.11684)
		(layer "In13.Cu")
		(net "HGX_DETECT_N")
	)
	(segment
		(start 100.764594 -405.252174)
		(end 100.764594 -409.847542)
		(width 0.11684)
		(layer "In13.Cu")
		(net "HGX_DETECT_N")
	)
	(segment
		(start 150.77821 -136.317482)
		(end 93.850714 -136.317482)
		(width 0.11684)
		(layer "In13.Cu")
		(net "HGX_DETECT_N")
	)
	(segment
		(start 102.281736 -412.268416)
		(end 103.421688 -413.408368)
		(width 0.11684)
		(layer "In13.Cu")
		(net "HGX_DETECT_N")
	)
	(segment
		(start 34.70783 -397.15059)
		(end 34.70783 -407.868882)
		(width 0.11684)
		(layer "In13.Cu")
		(net "HGX_DETECT_N")
	)
	(segment
		(start 5.504942 -358.006142)
		(end 5.504942 -365.909606)
		(width 0.11684)
		(layer "In13.Cu")
		(net "HGX_DETECT_N")
	)
	(segment
		(start 206.880206 -141.752828)
		(end 205.531212 -143.101822)
		(width 0.11684)
		(layer "In13.Cu")
		(net "HGX_DETECT_N")
	)
	(segment
		(start 36.019232 -395.046708)
		(end 36.019232 -395.839188)
		(width 0.11684)
		(layer "In13.Cu")
		(net "HGX_DETECT_N")
	)
	(segment
		(start 4.757166 -336.437732)
		(end 4.757166 -357.258366)
		(width 0.11684)
		(layer "In13.Cu")
		(net "HGX_DETECT_N")
	)
	(segment
		(start 185.078624 -143.823944)
		(end 177.132742 -143.823944)
		(width 0.11684)
		(layer "In13.Cu")
		(net "HGX_DETECT_N")
	)
	(segment
		(start 8.215884 -368.620548)
		(end 17.26819 -368.620548)
		(width 0.11684)
		(layer "In13.Cu")
		(net "HGX_DETECT_N")
	)
	(segment
		(start 33.149794 -414.533842)
		(end 34.427922 -415.81197)
		(width 0.11684)
		(layer "In13.Cu")
		(net "HGX_DETECT_N")
	)
	(segment
		(start 31.063946 -392.226038)
		(end 33.50641 -394.668502)
		(width 0.11684)
		(layer "In13.Cu")
		(net "HGX_DETECT_N")
	)
	(segment
		(start 29.049472 -375.80951)
		(end 29.049472 -380.392686)
		(width 0.11684)
		(layer "In13.Cu")
		(net "HGX_DETECT_N")
	)
	(segment
		(start 35.641026 -394.668502)
		(end 36.019232 -395.046708)
		(width 0.11684)
		(layer "In13.Cu")
		(net "HGX_DETECT_N")
	)
	(segment
		(start 5.504942 -365.909606)
		(end 8.215884 -368.620548)
		(width 0.11684)
		(layer "In13.Cu")
		(net "HGX_DETECT_N")
	)
	(segment
		(start 102.281736 -411.364684)
		(end 102.281736 -412.268416)
		(width 0.11684)
		(layer "In13.Cu")
		(net "HGX_DETECT_N")
	)
	(segment
		(start 192.211452 -143.058642)
		(end 185.843926 -143.058642)
		(width 0.11684)
		(layer "In13.Cu")
		(net "HGX_DETECT_N")
	)
	(segment
		(start 103.421688 -413.408368)
		(end 103.421688 -415.262822)
		(width 0.11684)
		(layer "In13.Cu")
		(net "HGX_DETECT_N")
	)
	(segment
		(start 100.77323 -403.075902)
		(end 100.77323 -405.243538)
		(width 0.11684)
		(layer "In13.Cu")
		(net "HGX_DETECT_N")
	)
	(segment
		(start 200.144888 -141.666214)
		(end 199.371458 -140.892784)
		(width 0.11684)
		(layer "In13.Cu")
		(net "HGX_DETECT_N")
	)
	(segment
		(start 33.50641 -394.668502)
		(end 35.641026 -394.668502)
		(width 0.11684)
		(layer "In13.Cu")
		(net "HGX_DETECT_N")
	)
	(segment
		(start 30.470602 -137.552684)
		(end 17.901666 -150.12162)
		(width 0.11684)
		(layer "In13.Cu")
		(net "HGX_DETECT_N")
	)
	(segment
		(start 17.901666 -150.12162)
		(end 17.901666 -174.134526)
		(width 0.11684)
		(layer "In13.Cu")
		(net "HGX_DETECT_N")
	)
	(segment
		(start 20.608544 -372.67896)
		(end 25.918922 -372.67896)
		(width 0.11684)
		(layer "In13.Cu")
		(net "HGX_DETECT_N")
	)
	(segment
		(start 200.144888 -142.454376)
		(end 200.144888 -141.666214)
		(width 0.11684)
		(layer "In13.Cu")
		(net "HGX_DETECT_N")
	)
	(segment
		(start 205.531212 -143.101822)
		(end 200.792334 -143.101822)
		(width 0.11684)
		(layer "In13.Cu")
		(net "HGX_DETECT_N")
	)
	(segment
		(start 6.018022 -186.01817)
		(end 6.018022 -335.176876)
		(width 0.11684)
		(layer "In13.Cu")
		(net "HGX_DETECT_N")
	)
	(segment
		(start 77.477874 -137.552684)
		(end 30.470602 -137.552684)
		(width 0.11684)
		(layer "In13.Cu")
		(net "HGX_DETECT_N")
	)
	(segment
		(start 19.388836 -371.459252)
		(end 20.608544 -372.67896)
		(width 0.11684)
		(layer "In13.Cu")
		(net "HGX_DETECT_N")
	)
	(segment
		(start 103.421688 -415.262822)
		(end 102.77856 -415.90595)
		(width 0.11684)
		(layer "In13.Cu")
		(net "HGX_DETECT_N")
	)
	(segment
		(start 93.491812 -135.95858)
		(end 79.071978 -135.95858)
		(width 0.11684)
		(layer "In13.Cu")
		(net "HGX_DETECT_N")
	)
	(segment
		(start 199.371458 -140.892784)
		(end 194.37731 -140.892784)
		(width 0.11684)
		(layer "In13.Cu")
		(net "HGX_DETECT_N")
	)
	(segment
		(start 17.901666 -174.134526)
		(end 6.018022 -186.01817)
		(width 0.11684)
		(layer "In13.Cu")
		(net "HGX_DETECT_N")
	)
	(segment
		(start 185.843926 -143.058642)
		(end 185.078624 -143.823944)
		(width 0.11684)
		(layer "In13.Cu")
		(net "HGX_DETECT_N")
	)
	(segment
		(start 36.019232 -395.839188)
		(end 34.70783 -397.15059)
		(width 0.11684)
		(layer "In13.Cu")
		(net "HGX_DETECT_N")
	)
	(via
		(at 111.22914 -416.075114)
		(size 0.6604)
		(drill 0.3302)
		(layers "F.Cu" "B.Cu")
		(net "HGX_DETECT")
	)
	(segment
		(start 111.77905 -416.941)
		(end 111.77905 -416.625024)
		(width 0.10668)
		(layer "B.Cu")
		(net "HGX_DETECT")
	)
	(segment
		(start 109.22 -415.98596)
		(end 109.22 -415.510472)
		(width 0.10668)
		(layer "B.Cu")
		(net "HGX_DETECT")
	)
	(segment
		(start 109.364272 -415.3662)
		(end 109.742986 -415.3662)
		(width 0.10668)
		(layer "B.Cu")
		(net "HGX_DETECT")
	)
	(segment
		(start 111.139986 -415.98596)
		(end 111.22914 -416.075114)
		(width 0.10668)
		(layer "B.Cu")
		(net "HGX_DETECT")
	)
	(segment
		(start 109.869986 -415.4932)
		(end 109.869986 -415.98596)
		(width 0.10668)
		(layer "B.Cu")
		(net "HGX_DETECT")
	)
	(segment
		(start 109.22 -415.510472)
		(end 109.364272 -415.3662)
		(width 0.10668)
		(layer "B.Cu")
		(net "HGX_DETECT")
	)
	(segment
		(start 109.742986 -415.3662)
		(end 109.869986 -415.4932)
		(width 0.10668)
		(layer "B.Cu")
		(net "HGX_DETECT")
	)
	(segment
		(start 111.77905 -416.625024)
		(end 111.22914 -416.075114)
		(width 0.10668)
		(layer "B.Cu")
		(net "HGX_DETECT")
	)
	(segment
		(start 109.869986 -415.98596)
		(end 111.139986 -415.98596)
		(width 0.10668)
		(layer "B.Cu")
		(net "HGX_DETECT")
	)
	(segment
		(start 403.282912 -58.2295)
		(end 402.063712 -58.2295)
		(width 0.10668)
		(layer "F.Cu")
		(net "HDT_HDR_TRST_N_R")
	)
	(segment
		(start 403.282912 -58.2295)
		(end 403.282912 -57.2135)
		(width 0.10668)
		(layer "F.Cu")
		(net "HDT_HDR_TRST_N_R")
	)
	(segment
		(start 397.307308 -58.2295)
		(end 402.063712 -58.2295)
		(width 0.10668)
		(layer "F.Cu")
		(net "HDT_HDR_TRST_N_R")
	)
	(via
		(at 402.063712 -58.2295)
		(size 0.762)
		(drill 0.381)
		(layers "F.Cu" "B.Cu")
		(net "HDT_HDR_TRST_N_R")
	)
	(segment
		(start 405.353012 -57.2135)
		(end 405.353012 -57.352184)
		(width 0.10668)
		(layer "F.Cu")
		(net "HDT_HDR_TRST_N")
	)
	(segment
		(start 276.025356 -92.426282)
		(end 272.031714 -96.419924)
		(width 0.10668)
		(layer "F.Cu")
		(net "HDT_HDR_TRST_N")
	)
	(segment
		(start 405.353012 -57.2135)
		(end 404.083012 -57.2135)
		(width 0.10668)
		(layer "F.Cu")
		(net "HDT_HDR_TRST_N")
	)
	(segment
		(start 276.025356 -89.79281)
		(end 276.025356 -92.426282)
		(width 0.10668)
		(layer "F.Cu")
		(net "HDT_HDR_TRST_N")
	)
	(segment
		(start 405.353012 -57.352184)
		(end 406.169114 -58.168286)
		(width 0.10668)
		(layer "F.Cu")
		(net "HDT_HDR_TRST_N")
	)
	(segment
		(start 406.169114 -58.168286)
		(end 406.169114 -59.299348)
		(width 0.10668)
		(layer "F.Cu")
		(net "HDT_HDR_TRST_N")
	)
	(segment
		(start 272.031714 -97.729294)
		(end 271.471644 -98.289364)
		(width 0.10668)
		(layer "F.Cu")
		(net "HDT_HDR_TRST_N")
	)
	(segment
		(start 271.471644 -98.289364)
		(end 270.95069 -98.289364)
		(width 0.10668)
		(layer "F.Cu")
		(net "HDT_HDR_TRST_N")
	)
	(segment
		(start 270.767302 -98.105976)
		(end 269.771622 -98.105976)
		(width 0.10668)
		(layer "F.Cu")
		(net "HDT_HDR_TRST_N")
	)
	(segment
		(start 406.169114 -59.299348)
		(end 405.968962 -59.4995)
		(width 0.10668)
		(layer "F.Cu")
		(net "HDT_HDR_TRST_N")
	)
	(segment
		(start 270.95069 -98.289364)
		(end 270.767302 -98.105976)
		(width 0.10668)
		(layer "F.Cu")
		(net "HDT_HDR_TRST_N")
	)
	(segment
		(start 272.031714 -96.419924)
		(end 272.031714 -97.729294)
		(width 0.10668)
		(layer "F.Cu")
		(net "HDT_HDR_TRST_N")
	)
	(via
		(at 276.025356 -89.79281)
		(size 0.508)
		(drill 0.254)
		(layers "F.Cu" "B.Cu")
		(net "HDT_HDR_TRST_N")
	)
	(via
		(at 405.968962 -59.4995)
		(size 0.508)
		(drill 0.254)
		(layers "F.Cu" "B.Cu")
		(net "HDT_HDR_TRST_N")
	)
	(segment
		(start 276.025356 -89.79281)
		(end 287.63849 -89.79281)
		(width 0.11684)
		(layer "In6.Cu")
		(net "HDT_HDR_TRST_N")
	)
	(segment
		(start 287.63849 -89.79281)
		(end 296.059352 -81.371948)
		(width 0.11684)
		(layer "In6.Cu")
		(net "HDT_HDR_TRST_N")
	)
	(segment
		(start 405.968962 -64.442594)
		(end 405.968962 -59.4995)
		(width 0.11684)
		(layer "In6.Cu")
		(net "HDT_HDR_TRST_N")
	)
	(segment
		(start 296.059352 -81.371948)
		(end 336.043524 -81.371948)
		(width 0.11684)
		(layer "In6.Cu")
		(net "HDT_HDR_TRST_N")
	)
	(segment
		(start 336.043524 -81.371948)
		(end 404.386288 -66.025268)
		(width 0.11684)
		(layer "In6.Cu")
		(net "HDT_HDR_TRST_N")
	)
	(segment
		(start 404.386288 -66.025268)
		(end 405.968962 -64.442594)
		(width 0.11684)
		(layer "In6.Cu")
		(net "HDT_HDR_TRST_N")
	)
	(segment
		(start 271.151096 -65.214246)
		(end 280.001726 -56.363616)
		(width 0.10668)
		(layer "F.Cu")
		(net "HDT_HDR_TMS")
	)
	(segment
		(start 315.608208 -54.947312)
		(end 383.083308 -54.947312)
		(width 0.10668)
		(layer "F.Cu")
		(net "HDT_HDR_TMS")
	)
	(segment
		(start 268.63802 -97.455736)
		(end 268.207236 -97.024952)
		(width 0.10668)
		(layer "F.Cu")
		(net "HDT_HDR_TMS")
	)
	(segment
		(start 383.86512 -54.1655)
		(end 384.465576 -54.1655)
		(width 0.10668)
		(layer "F.Cu")
		(net "HDT_HDR_TMS")
	)
	(segment
		(start 314.191904 -56.363616)
		(end 315.608208 -54.947312)
		(width 0.10668)
		(layer "F.Cu")
		(net "HDT_HDR_TMS")
	)
	(segment
		(start 383.083308 -54.947312)
		(end 383.86512 -54.1655)
		(width 0.10668)
		(layer "F.Cu")
		(net "HDT_HDR_TMS")
	)
	(segment
		(start 269.09141 -66.442844)
		(end 270.320008 -65.214246)
		(width 0.10668)
		(layer "F.Cu")
		(net "HDT_HDR_TMS")
	)
	(segment
		(start 269.771622 -97.455736)
		(end 268.63802 -97.455736)
		(width 0.10668)
		(layer "F.Cu")
		(net "HDT_HDR_TMS")
	)
	(segment
		(start 280.001726 -56.363616)
		(end 314.191904 -56.363616)
		(width 0.10668)
		(layer "F.Cu")
		(net "HDT_HDR_TMS")
	)
	(segment
		(start 267.871702 -66.442844)
		(end 269.09141 -66.442844)
		(width 0.10668)
		(layer "F.Cu")
		(net "HDT_HDR_TMS")
	)
	(segment
		(start 270.320008 -65.214246)
		(end 271.151096 -65.214246)
		(width 0.10668)
		(layer "F.Cu")
		(net "HDT_HDR_TMS")
	)
	(segment
		(start 385.811776 -54.1655)
		(end 384.465576 -54.1655)
		(width 0.10668)
		(layer "F.Cu")
		(net "HDT_HDR_TMS")
	)
	(via
		(at 267.871702 -66.442844)
		(size 0.508)
		(drill 0.254)
		(layers "F.Cu" "B.Cu")
		(net "HDT_HDR_TMS")
	)
	(via
		(at 268.207236 -97.024952)
		(size 0.508)
		(drill 0.254)
		(layers "F.Cu" "B.Cu")
		(net "HDT_HDR_TMS")
	)
	(segment
		(start 268.207236 -97.024952)
		(end 267.871702 -96.689418)
		(width 0.11684)
		(layer "In4.Cu")
		(net "HDT_HDR_TMS")
	)
	(segment
		(start 267.871702 -96.689418)
		(end 267.871702 -66.442844)
		(width 0.11684)
		(layer "In4.Cu")
		(net "HDT_HDR_TMS")
	)
	(segment
		(start 268.607032 -68.091812)
		(end 270.661638 -66.037206)
		(width 0.10668)
		(layer "F.Cu")
		(net "HDT_HDR_TDO")
	)
	(segment
		(start 386.167122 -58.00471)
		(end 385.811776 -58.360056)
		(width 0.10668)
		(layer "F.Cu")
		(net "HDT_HDR_TDO")
	)
	(segment
		(start 390.152636 -58.230262)
		(end 389.927084 -58.00471)
		(width 0.10668)
		(layer "F.Cu")
		(net "HDT_HDR_TDO")
	)
	(segment
		(start 391.322306 -56.9595)
		(end 391.12444 -57.157366)
		(width 0.10668)
		(layer "F.Cu")
		(net "HDT_HDR_TDO")
	)
	(segment
		(start 266.898628 -68.091812)
		(end 268.607032 -68.091812)
		(width 0.10668)
		(layer "F.Cu")
		(net "HDT_HDR_TDO")
	)
	(segment
		(start 391.12444 -57.732168)
		(end 390.626346 -58.230262)
		(width 0.10668)
		(layer "F.Cu")
		(net "HDT_HDR_TDO")
	)
	(segment
		(start 391.12444 -57.157366)
		(end 391.12444 -57.732168)
		(width 0.10668)
		(layer "F.Cu")
		(net "HDT_HDR_TDO")
	)
	(segment
		(start 359.802938 -58.7375)
		(end 385.811776 -58.7375)
		(width 0.10668)
		(layer "F.Cu")
		(net "HDT_HDR_TDO")
	)
	(segment
		(start 271.492472 -66.037206)
		(end 280.343102 -57.186576)
		(width 0.10668)
		(layer "F.Cu")
		(net "HDT_HDR_TDO")
	)
	(segment
		(start 266.560554 -67.753738)
		(end 266.898628 -68.091812)
		(width 0.10668)
		(layer "F.Cu")
		(net "HDT_HDR_TDO")
	)
	(segment
		(start 120.373394 -52.46624)
		(end 120.76049 -52.46624)
		(width 0.10668)
		(layer "F.Cu")
		(net "HDT_HDR_TDO")
	)
	(segment
		(start 119.99722 -52.842414)
		(end 120.373394 -52.46624)
		(width 0.10668)
		(layer "F.Cu")
		(net "HDT_HDR_TDO")
	)
	(segment
		(start 385.811776 -58.360056)
		(end 385.811776 -58.7375)
		(width 0.10668)
		(layer "F.Cu")
		(net "HDT_HDR_TDO")
	)
	(segment
		(start 119.99722 -55.67172)
		(end 119.99722 -52.842414)
		(width 0.10668)
		(layer "F.Cu")
		(net "HDT_HDR_TDO")
	)
	(segment
		(start 390.626346 -58.230262)
		(end 390.152636 -58.230262)
		(width 0.10668)
		(layer "F.Cu")
		(net "HDT_HDR_TDO")
	)
	(segment
		(start 120.97004 -56.64454)
		(end 119.99722 -55.67172)
		(width 0.10668)
		(layer "F.Cu")
		(net "HDT_HDR_TDO")
	)
	(segment
		(start 270.661638 -66.037206)
		(end 271.492472 -66.037206)
		(width 0.10668)
		(layer "F.Cu")
		(net "HDT_HDR_TDO")
	)
	(segment
		(start 120.97004 -67.76466)
		(end 120.97004 -56.64454)
		(width 0.10668)
		(layer "F.Cu")
		(net "HDT_HDR_TDO")
	)
	(segment
		(start 358.252014 -57.186576)
		(end 359.802938 -58.7375)
		(width 0.10668)
		(layer "F.Cu")
		(net "HDT_HDR_TDO")
	)
	(segment
		(start 280.343102 -57.186576)
		(end 358.252014 -57.186576)
		(width 0.10668)
		(layer "F.Cu")
		(net "HDT_HDR_TDO")
	)
	(segment
		(start 389.927084 -58.00471)
		(end 386.167122 -58.00471)
		(width 0.10668)
		(layer "F.Cu")
		(net "HDT_HDR_TDO")
	)
	(segment
		(start 392.58748 -56.9595)
		(end 391.322306 -56.9595)
		(width 0.10668)
		(layer "F.Cu")
		(net "HDT_HDR_TDO")
	)
	(segment
		(start 121.88698 -68.6816)
		(end 120.97004 -67.76466)
		(width 0.10668)
		(layer "F.Cu")
		(net "HDT_HDR_TDO")
	)
	(via
		(at 266.560554 -67.753738)
		(size 0.508)
		(drill 0.254)
		(layers "F.Cu" "B.Cu")
		(net "HDT_HDR_TDO")
	)
	(via
		(at 121.88698 -68.6816)
		(size 0.508)
		(drill 0.254)
		(layers "F.Cu" "B.Cu")
		(net "HDT_HDR_TDO")
	)
	(segment
		(start 260.395466 -74.64044)
		(end 261.79653 -73.239376)
		(width 0.11684)
		(layer "In2.Cu")
		(net "HDT_HDR_TDO")
	)
	(segment
		(start 136.40816 -68.11264)
		(end 159.136334 -68.11264)
		(width 0.11684)
		(layer "In2.Cu")
		(net "HDT_HDR_TDO")
	)
	(segment
		(start 256.16154 -74.140314)
		(end 257.68173 -75.660504)
		(width 0.11684)
		(layer "In2.Cu")
		(net "HDT_HDR_TDO")
	)
	(segment
		(start 266.560554 -70.588886)
		(end 266.560554 -67.753738)
		(width 0.11684)
		(layer "In2.Cu")
		(net "HDT_HDR_TDO")
	)
	(segment
		(start 121.88698 -68.6816)
		(end 122.5042 -69.29882)
		(width 0.11684)
		(layer "In2.Cu")
		(net "HDT_HDR_TDO")
	)
	(segment
		(start 182.627524 -81.697322)
		(end 183.662066 -82.731864)
		(width 0.11684)
		(layer "In2.Cu")
		(net "HDT_HDR_TDO")
	)
	(segment
		(start 258.966462 -75.660504)
		(end 259.986526 -74.64044)
		(width 0.11684)
		(layer "In2.Cu")
		(net "HDT_HDR_TDO")
	)
	(segment
		(start 159.136334 -68.11264)
		(end 172.721016 -81.697322)
		(width 0.11684)
		(layer "In2.Cu")
		(net "HDT_HDR_TDO")
	)
	(segment
		(start 172.721016 -81.697322)
		(end 182.627524 -81.697322)
		(width 0.11684)
		(layer "In2.Cu")
		(net "HDT_HDR_TDO")
	)
	(segment
		(start 122.5042 -69.29882)
		(end 135.22198 -69.29882)
		(width 0.11684)
		(layer "In2.Cu")
		(net "HDT_HDR_TDO")
	)
	(segment
		(start 135.22198 -69.29882)
		(end 136.40816 -68.11264)
		(width 0.11684)
		(layer "In2.Cu")
		(net "HDT_HDR_TDO")
	)
	(segment
		(start 214.195914 -78.946248)
		(end 222.645478 -78.946248)
		(width 0.11684)
		(layer "In2.Cu")
		(net "HDT_HDR_TDO")
	)
	(segment
		(start 265.62558 -71.52386)
		(end 266.560554 -70.588886)
		(width 0.11684)
		(layer "In2.Cu")
		(net "HDT_HDR_TDO")
	)
	(segment
		(start 222.645478 -78.946248)
		(end 234.248452 -74.140314)
		(width 0.11684)
		(layer "In2.Cu")
		(net "HDT_HDR_TDO")
	)
	(segment
		(start 261.79653 -72.33666)
		(end 262.60933 -71.52386)
		(width 0.11684)
		(layer "In2.Cu")
		(net "HDT_HDR_TDO")
	)
	(segment
		(start 183.662066 -82.731864)
		(end 193.161158 -82.731864)
		(width 0.11684)
		(layer "In2.Cu")
		(net "HDT_HDR_TDO")
	)
	(segment
		(start 257.68173 -75.660504)
		(end 258.966462 -75.660504)
		(width 0.11684)
		(layer "In2.Cu")
		(net "HDT_HDR_TDO")
	)
	(segment
		(start 259.986526 -74.64044)
		(end 260.395466 -74.64044)
		(width 0.11684)
		(layer "In2.Cu")
		(net "HDT_HDR_TDO")
	)
	(segment
		(start 234.248452 -74.140314)
		(end 256.16154 -74.140314)
		(width 0.11684)
		(layer "In2.Cu")
		(net "HDT_HDR_TDO")
	)
	(segment
		(start 194.712082 -81.18094)
		(end 211.961222 -81.18094)
		(width 0.11684)
		(layer "In2.Cu")
		(net "HDT_HDR_TDO")
	)
	(segment
		(start 262.60933 -71.52386)
		(end 265.62558 -71.52386)
		(width 0.11684)
		(layer "In2.Cu")
		(net "HDT_HDR_TDO")
	)
	(segment
		(start 261.79653 -73.239376)
		(end 261.79653 -72.33666)
		(width 0.11684)
		(layer "In2.Cu")
		(net "HDT_HDR_TDO")
	)
	(segment
		(start 211.961222 -81.18094)
		(end 214.195914 -78.946248)
		(width 0.11684)
		(layer "In2.Cu")
		(net "HDT_HDR_TDO")
	)
	(segment
		(start 193.161158 -82.731864)
		(end 194.712082 -81.18094)
		(width 0.11684)
		(layer "In2.Cu")
		(net "HDT_HDR_TDO")
	)
	(segment
		(start 121.50598 -57.60974)
		(end 122.227594 -56.888126)
		(width 0.10668)
		(layer "F.Cu")
		(net "HDT_HDR_TDI")
	)
	(segment
		(start 385.811776 -57.2135)
		(end 384.465576 -57.2135)
		(width 0.10668)
		(layer "F.Cu")
		(net "HDT_HDR_TDI")
	)
	(segment
		(start 123.85548 -68.6816)
		(end 121.50598 -66.3321)
		(width 0.10668)
		(layer "F.Cu")
		(net "HDT_HDR_TDI")
	)
	(segment
		(start 266.58951 -66.820288)
		(end 267.345668 -66.820288)
		(width 0.10668)
		(layer "F.Cu")
		(net "HDT_HDR_TDI")
	)
	(segment
		(start 271.321784 -65.625726)
		(end 280.172414 -56.775096)
		(width 0.10668)
		(layer "F.Cu")
		(net "HDT_HDR_TDI")
	)
	(segment
		(start 358.422702 -56.775096)
		(end 358.861106 -57.2135)
		(width 0.10668)
		(layer "F.Cu")
		(net "HDT_HDR_TDI")
	)
	(segment
		(start 358.861106 -57.2135)
		(end 384.465576 -57.2135)
		(width 0.10668)
		(layer "F.Cu")
		(net "HDT_HDR_TDI")
	)
	(segment
		(start 265.781536 -68.532756)
		(end 265.781536 -67.628262)
		(width 0.10668)
		(layer "F.Cu")
		(net "HDT_HDR_TDI")
	)
	(segment
		(start 269.061692 -67.054984)
		(end 270.49095 -65.625726)
		(width 0.10668)
		(layer "F.Cu")
		(net "HDT_HDR_TDI")
	)
	(segment
		(start 267.345668 -66.820288)
		(end 267.580364 -67.054984)
		(width 0.10668)
		(layer "F.Cu")
		(net "HDT_HDR_TDI")
	)
	(segment
		(start 122.227594 -56.888126)
		(end 122.227594 -55.175658)
		(width 0.10668)
		(layer "F.Cu")
		(net "HDT_HDR_TDI")
	)
	(segment
		(start 267.580364 -67.054984)
		(end 269.061692 -67.054984)
		(width 0.10668)
		(layer "F.Cu")
		(net "HDT_HDR_TDI")
	)
	(segment
		(start 270.49095 -65.625726)
		(end 271.321784 -65.625726)
		(width 0.10668)
		(layer "F.Cu")
		(net "HDT_HDR_TDI")
	)
	(segment
		(start 280.172414 -56.775096)
		(end 358.422702 -56.775096)
		(width 0.10668)
		(layer "F.Cu")
		(net "HDT_HDR_TDI")
	)
	(segment
		(start 265.781536 -67.628262)
		(end 266.58951 -66.820288)
		(width 0.10668)
		(layer "F.Cu")
		(net "HDT_HDR_TDI")
	)
	(segment
		(start 385.811776 -57.2135)
		(end 385.811776 -56.1975)
		(width 0.10668)
		(layer "F.Cu")
		(net "HDT_HDR_TDI")
	)
	(segment
		(start 121.50598 -66.3321)
		(end 121.50598 -57.60974)
		(width 0.10668)
		(layer "F.Cu")
		(net "HDT_HDR_TDI")
	)
	(via
		(at 123.85548 -68.6816)
		(size 0.508)
		(drill 0.254)
		(layers "F.Cu" "B.Cu")
		(net "HDT_HDR_TDI")
	)
	(via
		(at 265.781536 -68.532756)
		(size 0.508)
		(drill 0.254)
		(layers "F.Cu" "B.Cu")
		(net "HDT_HDR_TDI")
	)
	(segment
		(start 220.512894 -78.493366)
		(end 232.040176 -73.718674)
		(width 0.11684)
		(layer "In2.Cu")
		(net "HDT_HDR_TDI")
	)
	(segment
		(start 256.336546 -73.718674)
		(end 257.856736 -75.238864)
		(width 0.11684)
		(layer "In2.Cu")
		(net "HDT_HDR_TDI")
	)
	(segment
		(start 214.052404 -78.493366)
		(end 220.512894 -78.493366)
		(width 0.11684)
		(layer "In2.Cu")
		(net "HDT_HDR_TDI")
	)
	(segment
		(start 159.347662 -67.68338)
		(end 172.908722 -81.24444)
		(width 0.11684)
		(layer "In2.Cu")
		(net "HDT_HDR_TDI")
	)
	(segment
		(start 123.85548 -68.6816)
		(end 124.05106 -68.87718)
		(width 0.11684)
		(layer "In2.Cu")
		(net "HDT_HDR_TDI")
	)
	(segment
		(start 135.95858 -67.68338)
		(end 159.347662 -67.68338)
		(width 0.11684)
		(layer "In2.Cu")
		(net "HDT_HDR_TDI")
	)
	(segment
		(start 257.856736 -75.238864)
		(end 258.775454 -75.238864)
		(width 0.11684)
		(layer "In2.Cu")
		(net "HDT_HDR_TDI")
	)
	(segment
		(start 261.37489 -71.93915)
		(end 262.30326 -71.01078)
		(width 0.11684)
		(layer "In2.Cu")
		(net "HDT_HDR_TDI")
	)
	(segment
		(start 183.89346 -82.310224)
		(end 192.942718 -82.310224)
		(width 0.11684)
		(layer "In2.Cu")
		(net "HDT_HDR_TDI")
	)
	(segment
		(start 260.349238 -74.090276)
		(end 261.37489 -73.064624)
		(width 0.11684)
		(layer "In2.Cu")
		(net "HDT_HDR_TDI")
	)
	(segment
		(start 124.05106 -68.87718)
		(end 134.76478 -68.87718)
		(width 0.11684)
		(layer "In2.Cu")
		(net "HDT_HDR_TDI")
	)
	(segment
		(start 182.827676 -81.24444)
		(end 183.89346 -82.310224)
		(width 0.11684)
		(layer "In2.Cu")
		(net "HDT_HDR_TDI")
	)
	(segment
		(start 211.817712 -80.728058)
		(end 214.052404 -78.493366)
		(width 0.11684)
		(layer "In2.Cu")
		(net "HDT_HDR_TDI")
	)
	(segment
		(start 265.1125 -71.01078)
		(end 265.781536 -70.341744)
		(width 0.11684)
		(layer "In2.Cu")
		(net "HDT_HDR_TDI")
	)
	(segment
		(start 261.37489 -73.064624)
		(end 261.37489 -71.93915)
		(width 0.11684)
		(layer "In2.Cu")
		(net "HDT_HDR_TDI")
	)
	(segment
		(start 172.908722 -81.24444)
		(end 182.827676 -81.24444)
		(width 0.11684)
		(layer "In2.Cu")
		(net "HDT_HDR_TDI")
	)
	(segment
		(start 192.942718 -82.310224)
		(end 194.524884 -80.728058)
		(width 0.11684)
		(layer "In2.Cu")
		(net "HDT_HDR_TDI")
	)
	(segment
		(start 194.524884 -80.728058)
		(end 211.817712 -80.728058)
		(width 0.11684)
		(layer "In2.Cu")
		(net "HDT_HDR_TDI")
	)
	(segment
		(start 232.040176 -73.718674)
		(end 256.336546 -73.718674)
		(width 0.11684)
		(layer "In2.Cu")
		(net "HDT_HDR_TDI")
	)
	(segment
		(start 134.76478 -68.87718)
		(end 135.95858 -67.68338)
		(width 0.11684)
		(layer "In2.Cu")
		(net "HDT_HDR_TDI")
	)
	(segment
		(start 259.924042 -74.090276)
		(end 260.349238 -74.090276)
		(width 0.11684)
		(layer "In2.Cu")
		(net "HDT_HDR_TDI")
	)
	(segment
		(start 258.775454 -75.238864)
		(end 259.924042 -74.090276)
		(width 0.11684)
		(layer "In2.Cu")
		(net "HDT_HDR_TDI")
	)
	(segment
		(start 265.781536 -70.341744)
		(end 265.781536 -68.532756)
		(width 0.11684)
		(layer "In2.Cu")
		(net "HDT_HDR_TDI")
	)
	(segment
		(start 262.30326 -71.01078)
		(end 265.1125 -71.01078)
		(width 0.11684)
		(layer "In2.Cu")
		(net "HDT_HDR_TDI")
	)
	(segment
		(start 296.508424 -53.869336)
		(end 294.50665 -55.87111)
		(width 0.10668)
		(layer "F.Cu")
		(net "HDT_HDR_TCK")
	)
	(segment
		(start 270.14932 -64.802766)
		(end 269.121382 -65.830704)
		(width 0.10668)
		(layer "F.Cu")
		(net "HDT_HDR_TCK")
	)
	(segment
		(start 271.308322 -95.10141)
		(end 271.308322 -96.567752)
		(width 0.10668)
		(layer "F.Cu")
		(net "HDT_HDR_TCK")
	)
	(segment
		(start 271.070324 -96.80575)
		(end 271.308322 -96.567752)
		(width 0.10668)
		(layer "F.Cu")
		(net "HDT_HDR_TCK")
	)
	(segment
		(start 387.030976 -51.1175)
		(end 387.030976 -51.5112)
		(width 0.10668)
		(layer "F.Cu")
		(net "HDT_HDR_TCK")
	)
	(segment
		(start 270.980408 -64.802766)
		(end 270.14932 -64.802766)
		(width 0.10668)
		(layer "F.Cu")
		(net "HDT_HDR_TCK")
	)
	(segment
		(start 279.912064 -55.87111)
		(end 270.980408 -64.802766)
		(width 0.10668)
		(layer "F.Cu")
		(net "HDT_HDR_TCK")
	)
	(segment
		(start 315.205364 -53.869336)
		(end 296.508424 -53.869336)
		(width 0.10668)
		(layer "F.Cu")
		(net "HDT_HDR_TCK")
	)
	(segment
		(start 315.5696 -53.5051)
		(end 315.205364 -53.869336)
		(width 0.10668)
		(layer "F.Cu")
		(net "HDT_HDR_TCK")
	)
	(segment
		(start 269.771622 -96.80575)
		(end 271.070324 -96.80575)
		(width 0.10668)
		(layer "F.Cu")
		(net "HDT_HDR_TCK")
	)
	(segment
		(start 271.400524 -95.009208)
		(end 271.308322 -95.10141)
		(width 0.10668)
		(layer "F.Cu")
		(net "HDT_HDR_TCK")
	)
	(segment
		(start 387.030976 -51.5112)
		(end 385.811776 -52.7304)
		(width 0.10668)
		(layer "F.Cu")
		(net "HDT_HDR_TCK")
	)
	(segment
		(start 271.400524 -93.927168)
		(end 271.400524 -95.009208)
		(width 0.10668)
		(layer "F.Cu")
		(net "HDT_HDR_TCK")
	)
	(segment
		(start 294.50665 -55.87111)
		(end 279.912064 -55.87111)
		(width 0.10668)
		(layer "F.Cu")
		(net "HDT_HDR_TCK")
	)
	(segment
		(start 385.811776 -52.7304)
		(end 385.811776 -53.1495)
		(width 0.10668)
		(layer "F.Cu")
		(net "HDT_HDR_TCK")
	)
	(segment
		(start 381.489712 -53.5051)
		(end 315.5696 -53.5051)
		(width 0.10668)
		(layer "F.Cu")
		(net "HDT_HDR_TCK")
	)
	(segment
		(start 387.030976 -51.1175)
		(end 383.877312 -51.1175)
		(width 0.10668)
		(layer "F.Cu")
		(net "HDT_HDR_TCK")
	)
	(segment
		(start 269.121382 -65.830704)
		(end 268.463014 -65.830704)
		(width 0.10668)
		(layer "F.Cu")
		(net "HDT_HDR_TCK")
	)
	(segment
		(start 383.877312 -51.1175)
		(end 381.489712 -53.5051)
		(width 0.10668)
		(layer "F.Cu")
		(net "HDT_HDR_TCK")
	)
	(via
		(at 268.463014 -65.830704)
		(size 0.508)
		(drill 0.254)
		(layers "F.Cu" "B.Cu")
		(net "HDT_HDR_TCK")
	)
	(via
		(at 271.308322 -96.567752)
		(size 0.508)
		(drill 0.254)
		(layers "F.Cu" "B.Cu")
		(net "HDT_HDR_TCK")
	)
	(segment
		(start 271.125696 -69.574156)
		(end 271.125696 -68.493386)
		(width 0.11684)
		(layer "In4.Cu")
		(net "HDT_HDR_TCK")
	)
	(segment
		(start 270.710914 -95.970344)
		(end 270.710914 -69.988938)
		(width 0.11684)
		(layer "In4.Cu")
		(net "HDT_HDR_TCK")
	)
	(segment
		(start 271.308322 -96.567752)
		(end 270.710914 -95.970344)
		(width 0.11684)
		(layer "In4.Cu")
		(net "HDT_HDR_TCK")
	)
	(segment
		(start 270.710914 -69.988938)
		(end 271.125696 -69.574156)
		(width 0.11684)
		(layer "In4.Cu")
		(net "HDT_HDR_TCK")
	)
	(segment
		(start 271.125696 -68.493386)
		(end 268.463014 -65.830704)
		(width 0.11684)
		(layer "In4.Cu")
		(net "HDT_HDR_TCK")
	)
	(segment
		(start 387.577076 -54.1655)
		(end 386.611876 -54.1655)
		(width 0.10668)
		(layer "F.Cu")
		(net "HDT_HDR_R_TMS")
	)
	(segment
		(start 387.831076 -54.4195)
		(end 387.577076 -54.1655)
		(width 0.10668)
		(layer "F.Cu")
		(net "HDT_HDR_R_TMS")
	)
	(segment
		(start 392.58748 -54.4195)
		(end 387.831076 -54.4195)
		(width 0.10668)
		(layer "F.Cu")
		(net "HDT_HDR_R_TMS")
	)
	(via
		(at 387.831076 -54.4195)
		(size 0.762)
		(drill 0.381)
		(layers "F.Cu" "B.Cu")
		(net "HDT_HDR_R_TMS")
	)
	(segment
		(start 386.611876 -56.1975)
		(end 387.831076 -56.1975)
		(width 0.10668)
		(layer "F.Cu")
		(net "HDT_HDR_R_TDI")
	)
	(segment
		(start 392.58748 -55.6895)
		(end 391.027412 -55.6895)
		(width 0.10668)
		(layer "F.Cu")
		(net "HDT_HDR_R_TDI")
	)
	(segment
		(start 391.027412 -55.6895)
		(end 390.519412 -56.1975)
		(width 0.10668)
		(layer "F.Cu")
		(net "HDT_HDR_R_TDI")
	)
	(segment
		(start 390.519412 -56.1975)
		(end 387.831076 -56.1975)
		(width 0.10668)
		(layer "F.Cu")
		(net "HDT_HDR_R_TDI")
	)
	(via
		(at 387.831076 -56.1975)
		(size 0.762)
		(drill 0.381)
		(layers "F.Cu" "B.Cu")
		(net "HDT_HDR_R_TDI")
	)
	(segment
		(start 392.58748 -53.1495)
		(end 387.831076 -53.1495)
		(width 0.10668)
		(layer "F.Cu")
		(net "HDT_HDR_R_TCK")
	)
	(segment
		(start 386.611876 -53.1495)
		(end 387.831076 -53.1495)
		(width 0.10668)
		(layer "F.Cu")
		(net "HDT_HDR_R_TCK")
	)
	(via
		(at 387.831076 -53.1495)
		(size 0.762)
		(drill 0.381)
		(layers "F.Cu" "B.Cu")
		(net "HDT_HDR_R_TCK")
	)
	(segment
		(start 286.057594 -112.585754)
		(end 294.603424 -104.039924)
		(width 0.10668)
		(layer "F.Cu")
		(net "HDT_HDR_RESET_N")
	)
	(segment
		(start 391.319512 -59.4995)
		(end 392.58748 -59.4995)
		(width 0.10668)
		(layer "F.Cu")
		(net "HDT_HDR_RESET_N")
	)
	(segment
		(start 268.958822 -68.904358)
		(end 271.003014 -66.860166)
		(width 0.10668)
		(layer "F.Cu")
		(net "HDT_HDR_RESET_N")
	)
	(segment
		(start 288.90976 -88.499442)
		(end 281.601672 -88.499442)
		(width 0.10668)
		(layer "F.Cu")
		(net "HDT_HDR_RESET_N")
	)
	(segment
		(start 280.420572 -131.078986)
		(end 286.057594 -125.441964)
		(width 0.10668)
		(layer "F.Cu")
		(net "HDT_HDR_RESET_N")
	)
	(segment
		(start 286.057594 -125.441964)
		(end 286.057594 -112.585754)
		(width 0.10668)
		(layer "F.Cu")
		(net "HDT_HDR_RESET_N")
	)
	(segment
		(start 359.359708 -59.806586)
		(end 391.012426 -59.806586)
		(width 0.10668)
		(layer "F.Cu")
		(net "HDT_HDR_RESET_N")
	)
	(segment
		(start 268.958822 -75.856592)
		(end 268.958822 -68.904358)
		(width 0.10668)
		(layer "F.Cu")
		(net "HDT_HDR_RESET_N")
	)
	(segment
		(start 391.012426 -59.806586)
		(end 391.319512 -59.4995)
		(width 0.10668)
		(layer "F.Cu")
		(net "HDT_HDR_RESET_N")
	)
	(segment
		(start 281.032458 -58.009536)
		(end 357.562658 -58.009536)
		(width 0.10668)
		(layer "F.Cu")
		(net "HDT_HDR_RESET_N")
	)
	(segment
		(start 294.603424 -104.039924)
		(end 294.603424 -94.193106)
		(width 0.10668)
		(layer "F.Cu")
		(net "HDT_HDR_RESET_N")
	)
	(segment
		(start 189.103 -134.531354)
		(end 189.208664 -134.637018)
		(width 0.10668)
		(layer "F.Cu")
		(net "HDT_HDR_RESET_N")
	)
	(segment
		(start 294.603424 -94.193106)
		(end 288.90976 -88.499442)
		(width 0.10668)
		(layer "F.Cu")
		(net "HDT_HDR_RESET_N")
	)
	(segment
		(start 269.422626 -131.078986)
		(end 280.420572 -131.078986)
		(width 0.10668)
		(layer "F.Cu")
		(net "HDT_HDR_RESET_N")
	)
	(segment
		(start 357.562658 -58.009536)
		(end 359.359708 -59.806586)
		(width 0.10668)
		(layer "F.Cu")
		(net "HDT_HDR_RESET_N")
	)
	(segment
		(start 272.181828 -66.860166)
		(end 281.032458 -58.009536)
		(width 0.10668)
		(layer "F.Cu")
		(net "HDT_HDR_RESET_N")
	)
	(segment
		(start 189.103 -133.968998)
		(end 189.103 -134.531354)
		(width 0.10668)
		(layer "F.Cu")
		(net "HDT_HDR_RESET_N")
	)
	(segment
		(start 189.208664 -134.637018)
		(end 189.208664 -134.688072)
		(width 0.10668)
		(layer "F.Cu")
		(net "HDT_HDR_RESET_N")
	)
	(segment
		(start 271.003014 -66.860166)
		(end 272.181828 -66.860166)
		(width 0.10668)
		(layer "F.Cu")
		(net "HDT_HDR_RESET_N")
	)
	(segment
		(start 281.601672 -88.499442)
		(end 268.958822 -75.856592)
		(width 0.10668)
		(layer "F.Cu")
		(net "HDT_HDR_RESET_N")
	)
	(via
		(at 189.208664 -134.688072)
		(size 0.508)
		(drill 0.254)
		(layers "F.Cu" "B.Cu")
		(net "HDT_HDR_RESET_N")
	)
	(via
		(at 269.422626 -131.078986)
		(size 0.762)
		(drill 0.254)
		(layers "F.Cu" "B.Cu")
		(net "HDT_HDR_RESET_N")
	)
	(segment
		(start 259.707126 -125.684534)
		(end 262.056372 -125.684534)
		(width 0.11684)
		(layer "In2.Cu")
		(net "HDT_HDR_RESET_N")
	)
	(segment
		(start 252.024896 -128.527302)
		(end 256.864358 -128.527302)
		(width 0.11684)
		(layer "In2.Cu")
		(net "HDT_HDR_RESET_N")
	)
	(segment
		(start 200.201784 -137.974324)
		(end 203.497434 -134.678674)
		(width 0.11684)
		(layer "In2.Cu")
		(net "HDT_HDR_RESET_N")
	)
	(segment
		(start 190.991998 -137.365232)
		(end 191.457326 -137.365232)
		(width 0.11684)
		(layer "In2.Cu")
		(net "HDT_HDR_RESET_N")
	)
	(segment
		(start 262.056372 -125.684534)
		(end 267.616432 -131.244594)
		(width 0.11684)
		(layer "In2.Cu")
		(net "HDT_HDR_RESET_N")
	)
	(segment
		(start 190.63589 -137.009124)
		(end 190.991998 -137.365232)
		(width 0.11684)
		(layer "In2.Cu")
		(net "HDT_HDR_RESET_N")
	)
	(segment
		(start 267.616432 -131.244594)
		(end 269.257018 -131.244594)
		(width 0.11684)
		(layer "In2.Cu")
		(net "HDT_HDR_RESET_N")
	)
	(segment
		(start 203.497434 -134.678674)
		(end 206.754476 -134.678674)
		(width 0.11684)
		(layer "In2.Cu")
		(net "HDT_HDR_RESET_N")
	)
	(segment
		(start 246.49557 -134.056628)
		(end 252.024896 -128.527302)
		(width 0.11684)
		(layer "In2.Cu")
		(net "HDT_HDR_RESET_N")
	)
	(segment
		(start 189.208664 -134.926832)
		(end 189.643004 -135.361172)
		(width 0.11684)
		(layer "In2.Cu")
		(net "HDT_HDR_RESET_N")
	)
	(segment
		(start 189.208664 -134.688072)
		(end 189.208664 -134.926832)
		(width 0.11684)
		(layer "In2.Cu")
		(net "HDT_HDR_RESET_N")
	)
	(segment
		(start 269.257018 -131.244594)
		(end 269.422626 -131.078986)
		(width 0.11684)
		(layer "In2.Cu")
		(net "HDT_HDR_RESET_N")
	)
	(segment
		(start 192.066418 -137.974324)
		(end 200.201784 -137.974324)
		(width 0.11684)
		(layer "In2.Cu")
		(net "HDT_HDR_RESET_N")
	)
	(segment
		(start 256.864358 -128.527302)
		(end 259.707126 -125.684534)
		(width 0.11684)
		(layer "In2.Cu")
		(net "HDT_HDR_RESET_N")
	)
	(segment
		(start 191.457326 -137.365232)
		(end 192.066418 -137.974324)
		(width 0.11684)
		(layer "In2.Cu")
		(net "HDT_HDR_RESET_N")
	)
	(segment
		(start 211.297012 -134.056628)
		(end 246.49557 -134.056628)
		(width 0.11684)
		(layer "In2.Cu")
		(net "HDT_HDR_RESET_N")
	)
	(segment
		(start 190.07201 -135.361172)
		(end 190.63589 -135.925052)
		(width 0.11684)
		(layer "In2.Cu")
		(net "HDT_HDR_RESET_N")
	)
	(segment
		(start 207.414622 -135.33882)
		(end 210.01482 -135.33882)
		(width 0.11684)
		(layer "In2.Cu")
		(net "HDT_HDR_RESET_N")
	)
	(segment
		(start 190.63589 -135.925052)
		(end 190.63589 -137.009124)
		(width 0.11684)
		(layer "In2.Cu")
		(net "HDT_HDR_RESET_N")
	)
	(segment
		(start 206.754476 -134.678674)
		(end 207.414622 -135.33882)
		(width 0.11684)
		(layer "In2.Cu")
		(net "HDT_HDR_RESET_N")
	)
	(segment
		(start 210.01482 -135.33882)
		(end 211.297012 -134.056628)
		(width 0.11684)
		(layer "In2.Cu")
		(net "HDT_HDR_RESET_N")
	)
	(segment
		(start 189.643004 -135.361172)
		(end 190.07201 -135.361172)
		(width 0.11684)
		(layer "In2.Cu")
		(net "HDT_HDR_RESET_N")
	)
	(segment
		(start 285.646114 -112.415066)
		(end 294.191944 -103.869236)
		(width 0.10668)
		(layer "F.Cu")
		(net "HDT_HDR_PWROK")
	)
	(segment
		(start 359.530396 -59.395106)
		(end 390.466326 -59.395106)
		(width 0.10668)
		(layer "F.Cu")
		(net "HDT_HDR_PWROK")
	)
	(segment
		(start 190.119 -134.505192)
		(end 190.069978 -134.554214)
		(width 0.10668)
		(layer "F.Cu")
		(net "HDT_HDR_PWROK")
	)
	(segment
		(start 268.547342 -76.02728)
		(end 268.547342 -68.73367)
		(width 0.10668)
		(layer "F.Cu")
		(net "HDT_HDR_PWROK")
	)
	(segment
		(start 269.422626 -130.139186)
		(end 280.778204 -130.139186)
		(width 0.10668)
		(layer "F.Cu")
		(net "HDT_HDR_PWROK")
	)
	(segment
		(start 285.646114 -125.271276)
		(end 285.646114 -112.415066)
		(width 0.10668)
		(layer "F.Cu")
		(net "HDT_HDR_PWROK")
	)
	(segment
		(start 294.191944 -103.869236)
		(end 294.191944 -94.363794)
		(width 0.10668)
		(layer "F.Cu")
		(net "HDT_HDR_PWROK")
	)
	(segment
		(start 190.069978 -134.64667)
		(end 190.028322 -134.688326)
		(width 0.10668)
		(layer "F.Cu")
		(net "HDT_HDR_PWROK")
	)
	(segment
		(start 357.733346 -57.598056)
		(end 359.530396 -59.395106)
		(width 0.10668)
		(layer "F.Cu")
		(net "HDT_HDR_PWROK")
	)
	(segment
		(start 280.86177 -57.598056)
		(end 357.733346 -57.598056)
		(width 0.10668)
		(layer "F.Cu")
		(net "HDT_HDR_PWROK")
	)
	(segment
		(start 190.069978 -134.554214)
		(end 190.069978 -134.64667)
		(width 0.10668)
		(layer "F.Cu")
		(net "HDT_HDR_PWROK")
	)
	(segment
		(start 190.119 -133.968998)
		(end 190.119 -134.505192)
		(width 0.10668)
		(layer "F.Cu")
		(net "HDT_HDR_PWROK")
	)
	(segment
		(start 294.191944 -94.363794)
		(end 288.739072 -88.910922)
		(width 0.10668)
		(layer "F.Cu")
		(net "HDT_HDR_PWROK")
	)
	(segment
		(start 280.778204 -130.139186)
		(end 285.646114 -125.271276)
		(width 0.10668)
		(layer "F.Cu")
		(net "HDT_HDR_PWROK")
	)
	(segment
		(start 270.832326 -66.448686)
		(end 272.01114 -66.448686)
		(width 0.10668)
		(layer "F.Cu")
		(net "HDT_HDR_PWROK")
	)
	(segment
		(start 391.631932 -58.2295)
		(end 392.58748 -58.2295)
		(width 0.10668)
		(layer "F.Cu")
		(net "HDT_HDR_PWROK")
	)
	(segment
		(start 281.430984 -88.910922)
		(end 268.547342 -76.02728)
		(width 0.10668)
		(layer "F.Cu")
		(net "HDT_HDR_PWROK")
	)
	(segment
		(start 288.739072 -88.910922)
		(end 281.430984 -88.910922)
		(width 0.10668)
		(layer "F.Cu")
		(net "HDT_HDR_PWROK")
	)
	(segment
		(start 390.466326 -59.395106)
		(end 391.631932 -58.2295)
		(width 0.10668)
		(layer "F.Cu")
		(net "HDT_HDR_PWROK")
	)
	(segment
		(start 272.01114 -66.448686)
		(end 280.86177 -57.598056)
		(width 0.10668)
		(layer "F.Cu")
		(net "HDT_HDR_PWROK")
	)
	(segment
		(start 268.547342 -68.73367)
		(end 270.832326 -66.448686)
		(width 0.10668)
		(layer "F.Cu")
		(net "HDT_HDR_PWROK")
	)
	(via
		(at 190.028322 -134.688326)
		(size 0.508)
		(drill 0.254)
		(layers "F.Cu" "B.Cu")
		(net "HDT_HDR_PWROK")
	)
	(via
		(at 269.422626 -130.139186)
		(size 0.508)
		(drill 0.254)
		(layers "F.Cu" "B.Cu")
		(net "HDT_HDR_PWROK")
	)
	(segment
		(start 267.820648 -130.78841)
		(end 262.240776 -125.208538)
		(width 0.11684)
		(layer "In2.Cu")
		(net "HDT_HDR_PWROK")
	)
	(segment
		(start 192.329562 -137.507472)
		(end 191.87922 -137.05713)
		(width 0.11684)
		(layer "In2.Cu")
		(net "HDT_HDR_PWROK")
	)
	(segment
		(start 246.29491 -133.596888)
		(end 203.91882 -133.596888)
		(width 0.11684)
		(layer "In2.Cu")
		(net "HDT_HDR_PWROK")
	)
	(segment
		(start 203.91882 -133.596888)
		(end 200.008236 -137.507472)
		(width 0.11684)
		(layer "In2.Cu")
		(net "HDT_HDR_PWROK")
	)
	(segment
		(start 269.422626 -130.139186)
		(end 268.773402 -130.78841)
		(width 0.11684)
		(layer "In2.Cu")
		(net "HDT_HDR_PWROK")
	)
	(segment
		(start 191.87922 -137.05713)
		(end 191.87922 -136.30021)
		(width 0.11684)
		(layer "In2.Cu")
		(net "HDT_HDR_PWROK")
	)
	(segment
		(start 191.87922 -136.30021)
		(end 190.267336 -134.688326)
		(width 0.11684)
		(layer "In2.Cu")
		(net "HDT_HDR_PWROK")
	)
	(segment
		(start 190.267336 -134.688326)
		(end 190.028322 -134.688326)
		(width 0.11684)
		(layer "In2.Cu")
		(net "HDT_HDR_PWROK")
	)
	(segment
		(start 200.008236 -137.507472)
		(end 192.329562 -137.507472)
		(width 0.11684)
		(layer "In2.Cu")
		(net "HDT_HDR_PWROK")
	)
	(segment
		(start 251.831348 -128.06045)
		(end 246.29491 -133.596888)
		(width 0.11684)
		(layer "In2.Cu")
		(net "HDT_HDR_PWROK")
	)
	(segment
		(start 262.240776 -125.208538)
		(end 259.418074 -125.208538)
		(width 0.11684)
		(layer "In2.Cu")
		(net "HDT_HDR_PWROK")
	)
	(segment
		(start 259.418074 -125.208538)
		(end 256.566162 -128.06045)
		(width 0.11684)
		(layer "In2.Cu")
		(net "HDT_HDR_PWROK")
	)
	(segment
		(start 256.566162 -128.06045)
		(end 251.831348 -128.06045)
		(width 0.11684)
		(layer "In2.Cu")
		(net "HDT_HDR_PWROK")
	)
	(segment
		(start 268.773402 -130.78841)
		(end 267.820648 -130.78841)
		(width 0.11684)
		(layer "In2.Cu")
		(net "HDT_HDR_PWROK")
	)
	(segment
		(start 392.58748 -62.0395)
		(end 387.831076 -62.0395)
		(width 0.10668)
		(layer "F.Cu")
		(net "HDT_HDR_DBREQ_R_N")
	)
	(segment
		(start 386.611876 -62.0395)
		(end 387.831076 -62.0395)
		(width 0.10668)
		(layer "F.Cu")
		(net "HDT_HDR_DBREQ_R_N")
	)
	(segment
		(start 386.611876 -61.640466)
		(end 385.811776 -60.840366)
		(width 0.10668)
		(layer "F.Cu")
		(net "HDT_HDR_DBREQ_R_N")
	)
	(segment
		(start 386.611876 -62.0395)
		(end 386.611876 -61.640466)
		(width 0.10668)
		(layer "F.Cu")
		(net "HDT_HDR_DBREQ_R_N")
	)
	(segment
		(start 385.811776 -60.840366)
		(end 385.811776 -60.456318)
		(width 0.10668)
		(layer "F.Cu")
		(net "HDT_HDR_DBREQ_R_N")
	)
	(via
		(at 387.831076 -62.0395)
		(size 0.762)
		(drill 0.381)
		(layers "F.Cu" "B.Cu")
		(net "HDT_HDR_DBREQ_R_N")
	)
	(segment
		(start 269.926816 -68.80225)
		(end 271.45742 -67.271646)
		(width 0.10668)
		(layer "F.Cu")
		(net "HDT_HDR_DBREQ_N")
	)
	(segment
		(start 384.465576 -60.7822)
		(end 384.465576 -62.5729)
		(width 0.10668)
		(layer "F.Cu")
		(net "HDT_HDR_DBREQ_N")
	)
	(segment
		(start 271.45742 -67.271646)
		(end 272.352516 -67.271646)
		(width 0.10668)
		(layer "F.Cu")
		(net "HDT_HDR_DBREQ_N")
	)
	(segment
		(start 272.352516 -67.271646)
		(end 281.203146 -58.421016)
		(width 0.10668)
		(layer "F.Cu")
		(net "HDT_HDR_DBREQ_N")
	)
	(segment
		(start 383.901442 -60.218066)
		(end 384.465576 -60.7822)
		(width 0.10668)
		(layer "F.Cu")
		(net "HDT_HDR_DBREQ_N")
	)
	(segment
		(start 269.771622 -98.755962)
		(end 269.724632 -98.802952)
		(width 0.10668)
		(layer "F.Cu")
		(net "HDT_HDR_DBREQ_N")
	)
	(segment
		(start 281.203146 -58.421016)
		(end 357.39197 -58.421016)
		(width 0.10668)
		(layer "F.Cu")
		(net "HDT_HDR_DBREQ_N")
	)
	(segment
		(start 385.278376 -62.5729)
		(end 385.811776 -62.0395)
		(width 0.10668)
		(layer "F.Cu")
		(net "HDT_HDR_DBREQ_N")
	)
	(segment
		(start 384.465576 -62.5729)
		(end 385.278376 -62.5729)
		(width 0.10668)
		(layer "F.Cu")
		(net "HDT_HDR_DBREQ_N")
	)
	(segment
		(start 359.18902 -60.218066)
		(end 383.901442 -60.218066)
		(width 0.10668)
		(layer "F.Cu")
		(net "HDT_HDR_DBREQ_N")
	)
	(segment
		(start 357.39197 -58.421016)
		(end 359.18902 -60.218066)
		(width 0.10668)
		(layer "F.Cu")
		(net "HDT_HDR_DBREQ_N")
	)
	(segment
		(start 269.724632 -98.802952)
		(end 268.207236 -98.802952)
		(width 0.10668)
		(layer "F.Cu")
		(net "HDT_HDR_DBREQ_N")
	)
	(via
		(at 268.207236 -98.802952)
		(size 0.508)
		(drill 0.254)
		(layers "F.Cu" "B.Cu")
		(net "HDT_HDR_DBREQ_N")
	)
	(via
		(at 269.926816 -68.80225)
		(size 0.508)
		(drill 0.254)
		(layers "F.Cu" "B.Cu")
		(net "HDT_HDR_DBREQ_N")
	)
	(segment
		(start 268.886686 -69.84238)
		(end 269.926816 -68.80225)
		(width 0.11684)
		(layer "In4.Cu")
		(net "HDT_HDR_DBREQ_N")
	)
	(segment
		(start 268.886686 -98.392742)
		(end 268.886686 -69.84238)
		(width 0.11684)
		(layer "In4.Cu")
		(net "HDT_HDR_DBREQ_N")
	)
	(segment
		(start 268.207236 -98.802952)
		(end 268.476476 -98.802952)
		(width 0.11684)
		(layer "In4.Cu")
		(net "HDT_HDR_DBREQ_N")
	)
	(segment
		(start 268.476476 -98.802952)
		(end 268.886686 -98.392742)
		(width 0.11684)
		(layer "In4.Cu")
		(net "HDT_HDR_DBREQ_N")
	)
	(segment
		(start 397.307308 -60.7695)
		(end 402.063712 -60.7695)
		(width 0.10668)
		(layer "F.Cu")
		(net "HDT_CPU0_XTRIG_L7")
	)
	(segment
		(start 403.282912 -60.7695)
		(end 402.063712 -60.7695)
		(width 0.10668)
		(layer "F.Cu")
		(net "HDT_CPU0_XTRIG_L7")
	)
	(via
		(at 402.063712 -60.7695)
		(size 0.762)
		(drill 0.381)
		(layers "F.Cu" "B.Cu")
		(net "HDT_CPU0_XTRIG_L7")
	)
	(segment
		(start 403.282912 -59.4995)
		(end 402.063712 -59.4995)
		(width 0.10668)
		(layer "F.Cu")
		(net "HDT_CPU0_XTRIG_L6")
	)
	(segment
		(start 397.307308 -59.4995)
		(end 402.063712 -59.4995)
		(width 0.10668)
		(layer "F.Cu")
		(net "HDT_CPU0_XTRIG_L6")
	)
	(via
		(at 402.063712 -59.4995)
		(size 0.762)
		(drill 0.381)
		(layers "F.Cu" "B.Cu")
		(net "HDT_CPU0_XTRIG_L6")
	)
	(segment
		(start 403.282912 -62.0395)
		(end 402.063712 -62.0395)
		(width 0.10668)
		(layer "F.Cu")
		(net "HDT_CPU0_XTRIG_L5")
	)
	(segment
		(start 397.307308 -62.0395)
		(end 402.063712 -62.0395)
		(width 0.10668)
		(layer "F.Cu")
		(net "HDT_CPU0_XTRIG_L5")
	)
	(via
		(at 402.063712 -62.0395)
		(size 0.762)
		(drill 0.381)
		(layers "F.Cu" "B.Cu")
		(net "HDT_CPU0_XTRIG_L5")
	)
	(segment
		(start 392.58748 -63.3095)
		(end 387.831076 -63.3095)
		(width 0.10668)
		(layer "F.Cu")
		(net "HDT_CPU0_HDT_CONN_TESTEN")
	)
	(segment
		(start 386.611876 -64.3255)
		(end 386.611876 -63.3095)
		(width 0.10668)
		(layer "F.Cu")
		(net "HDT_CPU0_HDT_CONN_TESTEN")
	)
	(segment
		(start 386.611876 -63.3095)
		(end 387.831076 -63.3095)
		(width 0.10668)
		(layer "F.Cu")
		(net "HDT_CPU0_HDT_CONN_TESTEN")
	)
	(via
		(at 387.831076 -63.3095)
		(size 0.762)
		(drill 0.381)
		(layers "F.Cu" "B.Cu")
		(net "HDT_CPU0_HDT_CONN_TESTEN")
	)
	(segment
		(start 145.640552 -105.624884)
		(end 146.874992 -105.624884)
		(width 0.10668)
		(layer "F.Cu")
		(net "HDD_ACTIVITY_BUF_N")
	)
	(segment
		(start 148.094192 -105.624884)
		(end 146.874992 -105.624884)
		(width 0.10668)
		(layer "F.Cu")
		(net "HDD_ACTIVITY_BUF_N")
	)
	(segment
		(start 148.094192 -105.624884)
		(end 148.094192 -104.608884)
		(width 0.10668)
		(layer "F.Cu")
		(net "HDD_ACTIVITY_BUF_N")
	)
	(via
		(at 146.874992 -105.624884)
		(size 0.762)
		(drill 0.381)
		(layers "F.Cu" "B.Cu")
		(net "HDD_ACTIVITY_BUF_N")
	)
	(segment
		(start 144.980406 -102.544118)
		(end 144.413986 -103.110538)
		(width 0.10668)
		(layer "F.Cu")
		(net "HDD_ACTIVITY_BUF")
	)
	(segment
		(start 145.740628 -102.544118)
		(end 144.980406 -102.544118)
		(width 0.10668)
		(layer "F.Cu")
		(net "HDD_ACTIVITY_BUF")
	)
	(segment
		(start 144.413986 -103.110538)
		(end 144.413986 -104.758236)
		(width 0.10668)
		(layer "F.Cu")
		(net "HDD_ACTIVITY_BUF")
	)
	(segment
		(start 142.506192 -104.844596)
		(end 141.667992 -104.844596)
		(width 0.10668)
		(layer "F.Cu")
		(net "HDD_ACTIVITY_BUF")
	)
	(segment
		(start 144.197324 -104.974898)
		(end 143.740632 -104.974898)
		(width 0.10668)
		(layer "F.Cu")
		(net "HDD_ACTIVITY_BUF")
	)
	(segment
		(start 144.413986 -104.758236)
		(end 144.197324 -104.974898)
		(width 0.10668)
		(layer "F.Cu")
		(net "HDD_ACTIVITY_BUF")
	)
	(segment
		(start 141.667992 -104.844596)
		(end 141.286992 -105.225596)
		(width 0.10668)
		(layer "F.Cu")
		(net "HDD_ACTIVITY_BUF")
	)
	(segment
		(start 142.636494 -104.974898)
		(end 142.506192 -104.844596)
		(width 0.10668)
		(layer "F.Cu")
		(net "HDD_ACTIVITY_BUF")
	)
	(segment
		(start 143.740632 -104.974898)
		(end 142.636494 -104.974898)
		(width 0.10668)
		(layer "F.Cu")
		(net "HDD_ACTIVITY_BUF")
	)
	(via
		(at 142.506192 -104.844596)
		(size 0.762)
		(drill 0.381)
		(layers "F.Cu" "B.Cu")
		(net "HDD_ACTIVITY_BUF")
	)
	(segment
		(start 439.910982 -434.87721)
		(end 439.072782 -434.87721)
		(width 0.10668)
		(layer "F.Cu")
		(net "GPU_WP_HW_CTRL_N")
	)
	(segment
		(start 438.056782 -434.87721)
		(end 439.072782 -434.87721)
		(width 0.10668)
		(layer "F.Cu")
		(net "GPU_WP_HW_CTRL_N")
	)
	(segment
		(start 441.23356 -434.549296)
		(end 440.238896 -434.549296)
		(width 0.10668)
		(layer "F.Cu")
		(net "GPU_WP_HW_CTRL_N")
	)
	(segment
		(start 440.238896 -434.549296)
		(end 439.910982 -434.87721)
		(width 0.10668)
		(layer "F.Cu")
		(net "GPU_WP_HW_CTRL_N")
	)
	(segment
		(start 437.177688 -434.87721)
		(end 438.056782 -434.87721)
		(width 0.10668)
		(layer "F.Cu")
		(net "GPU_WP_HW_CTRL_N")
	)
	(via
		(at 198.342758 -122.769376)
		(size 0.508)
		(drill 0.254)
		(layers "F.Cu" "B.Cu")
		(net "GPU_WP_HW_CTRL_N")
	)
	(via
		(at 212.994494 -122.954034)
		(size 0.508)
		(drill 0.254)
		(layers "F.Cu" "B.Cu")
		(net "GPU_WP_HW_CTRL_N")
	)
	(via
		(at 437.177688 -434.87721)
		(size 0.508)
		(drill 0.254)
		(layers "F.Cu" "B.Cu")
		(net "GPU_WP_HW_CTRL_N")
	)
	(segment
		(start 198.99757 -123.486926)
		(end 198.342758 -122.832114)
		(width 0.11684)
		(layer "In2.Cu")
		(net "GPU_WP_HW_CTRL_N")
	)
	(segment
		(start 206.883254 -122.501406)
		(end 206.060548 -122.501406)
		(width 0.11684)
		(layer "In2.Cu")
		(net "GPU_WP_HW_CTRL_N")
	)
	(segment
		(start 198.342758 -122.832114)
		(end 198.342758 -122.769376)
		(width 0.11684)
		(layer "In2.Cu")
		(net "GPU_WP_HW_CTRL_N")
	)
	(segment
		(start 212.994494 -122.954034)
		(end 212.033358 -121.992898)
		(width 0.11684)
		(layer "In2.Cu")
		(net "GPU_WP_HW_CTRL_N")
	)
	(segment
		(start 206.060548 -122.501406)
		(end 205.85049 -122.711464)
		(width 0.11684)
		(layer "In2.Cu")
		(net "GPU_WP_HW_CTRL_N")
	)
	(segment
		(start 202.274932 -123.279662)
		(end 202.067668 -123.486926)
		(width 0.11684)
		(layer "In2.Cu")
		(net "GPU_WP_HW_CTRL_N")
	)
	(segment
		(start 205.85049 -122.711464)
		(end 205.847442 -122.711464)
		(width 0.11684)
		(layer "In2.Cu")
		(net "GPU_WP_HW_CTRL_N")
	)
	(segment
		(start 207.391762 -121.992898)
		(end 206.883254 -122.501406)
		(width 0.11684)
		(layer "In2.Cu")
		(net "GPU_WP_HW_CTRL_N")
	)
	(segment
		(start 205.279244 -123.279662)
		(end 202.274932 -123.279662)
		(width 0.11684)
		(layer "In2.Cu")
		(net "GPU_WP_HW_CTRL_N")
	)
	(segment
		(start 205.847442 -122.711464)
		(end 205.279244 -123.279662)
		(width 0.11684)
		(layer "In2.Cu")
		(net "GPU_WP_HW_CTRL_N")
	)
	(segment
		(start 202.067668 -123.486926)
		(end 198.99757 -123.486926)
		(width 0.11684)
		(layer "In2.Cu")
		(net "GPU_WP_HW_CTRL_N")
	)
	(segment
		(start 212.033358 -121.992898)
		(end 207.391762 -121.992898)
		(width 0.11684)
		(layer "In2.Cu")
		(net "GPU_WP_HW_CTRL_N")
	)
	(segment
		(start 453.454516 -358.549956)
		(end 439.969656 -372.034816)
		(width 0.11684)
		(layer "In6.Cu")
		(net "GPU_WP_HW_CTRL_N")
	)
	(segment
		(start 436.424578 -391.324338)
		(end 436.424578 -392.385804)
		(width 0.11684)
		(layer "In6.Cu")
		(net "GPU_WP_HW_CTRL_N")
	)
	(segment
		(start 437.177688 -434.43779)
		(end 437.177688 -434.87721)
		(width 0.11684)
		(layer "In6.Cu")
		(net "GPU_WP_HW_CTRL_N")
	)
	(segment
		(start 400.408394 -126.968758)
		(end 400.987006 -126.390146)
		(width 0.11684)
		(layer "In6.Cu")
		(net "GPU_WP_HW_CTRL_N")
	)
	(segment
		(start 253.795276 -146.221196)
		(end 262.603234 -146.221196)
		(width 0.11684)
		(layer "In6.Cu")
		(net "GPU_WP_HW_CTRL_N")
	)
	(segment
		(start 271.307052 -137.517378)
		(end 289.764216 -137.517378)
		(width 0.11684)
		(layer "In6.Cu")
		(net "GPU_WP_HW_CTRL_N")
	)
	(segment
		(start 435.878986 -416.372548)
		(end 435.878986 -433.369466)
		(width 0.11684)
		(layer "In6.Cu")
		(net "GPU_WP_HW_CTRL_N")
	)
	(segment
		(start 289.764216 -137.517378)
		(end 302.085756 -125.195838)
		(width 0.11684)
		(layer "In6.Cu")
		(net "GPU_WP_HW_CTRL_N")
	)
	(segment
		(start 431.84572 -396.964662)
		(end 431.84572 -400.518884)
		(width 0.11684)
		(layer "In6.Cu")
		(net "GPU_WP_HW_CTRL_N")
	)
	(segment
		(start 437.317642 -414.933892)
		(end 435.878986 -416.372548)
		(width 0.11684)
		(layer "In6.Cu")
		(net "GPU_WP_HW_CTRL_N")
	)
	(segment
		(start 302.085756 -125.195838)
		(end 318.470788 -125.195838)
		(width 0.11684)
		(layer "In6.Cu")
		(net "GPU_WP_HW_CTRL_N")
	)
	(segment
		(start 464.826096 -177.695606)
		(end 464.826096 -331.325474)
		(width 0.11684)
		(layer "In6.Cu")
		(net "GPU_WP_HW_CTRL_N")
	)
	(segment
		(start 219.267786 -123.648724)
		(end 228.571044 -132.951982)
		(width 0.11684)
		(layer "In6.Cu")
		(net "GPU_WP_HW_CTRL_N")
	)
	(segment
		(start 435.911498 -403.51583)
		(end 437.317642 -404.921974)
		(width 0.11684)
		(layer "In6.Cu")
		(net "GPU_WP_HW_CTRL_N")
	)
	(segment
		(start 217.610182 -123.648724)
		(end 219.267786 -123.648724)
		(width 0.11684)
		(layer "In6.Cu")
		(net "GPU_WP_HW_CTRL_N")
	)
	(segment
		(start 434.842666 -403.51583)
		(end 435.911498 -403.51583)
		(width 0.11684)
		(layer "In6.Cu")
		(net "GPU_WP_HW_CTRL_N")
	)
	(segment
		(start 318.470788 -125.195838)
		(end 321.025266 -122.64136)
		(width 0.11684)
		(layer "In6.Cu")
		(net "GPU_WP_HW_CTRL_N")
	)
	(segment
		(start 240.526062 -132.951982)
		(end 253.795276 -146.221196)
		(width 0.11684)
		(layer "In6.Cu")
		(net "GPU_WP_HW_CTRL_N")
	)
	(segment
		(start 431.84572 -400.518884)
		(end 434.842666 -403.51583)
		(width 0.11684)
		(layer "In6.Cu")
		(net "GPU_WP_HW_CTRL_N")
	)
	(segment
		(start 452.235316 -165.104826)
		(end 464.826096 -177.695606)
		(width 0.11684)
		(layer "In6.Cu")
		(net "GPU_WP_HW_CTRL_N")
	)
	(segment
		(start 464.826096 -331.325474)
		(end 453.454516 -342.697054)
		(width 0.11684)
		(layer "In6.Cu")
		(net "GPU_WP_HW_CTRL_N")
	)
	(segment
		(start 436.709566 -433.969668)
		(end 437.177688 -434.43779)
		(width 0.11684)
		(layer "In6.Cu")
		(net "GPU_WP_HW_CTRL_N")
	)
	(segment
		(start 217.403934 -123.854972)
		(end 217.610182 -123.648724)
		(width 0.11684)
		(layer "In6.Cu")
		(net "GPU_WP_HW_CTRL_N")
	)
	(segment
		(start 346.112338 -122.64136)
		(end 350.439736 -126.968758)
		(width 0.11684)
		(layer "In6.Cu")
		(net "GPU_WP_HW_CTRL_N")
	)
	(segment
		(start 213.895432 -123.854972)
		(end 217.403934 -123.854972)
		(width 0.11684)
		(layer "In6.Cu")
		(net "GPU_WP_HW_CTRL_N")
	)
	(segment
		(start 350.439736 -126.968758)
		(end 400.408394 -126.968758)
		(width 0.11684)
		(layer "In6.Cu")
		(net "GPU_WP_HW_CTRL_N")
	)
	(segment
		(start 452.235316 -150.704042)
		(end 452.235316 -165.104826)
		(width 0.11684)
		(layer "In6.Cu")
		(net "GPU_WP_HW_CTRL_N")
	)
	(segment
		(start 400.987006 -126.390146)
		(end 400.987006 -126.210314)
		(width 0.11684)
		(layer "In6.Cu")
		(net "GPU_WP_HW_CTRL_N")
	)
	(segment
		(start 453.454516 -342.697054)
		(end 453.454516 -358.549956)
		(width 0.11684)
		(layer "In6.Cu")
		(net "GPU_WP_HW_CTRL_N")
	)
	(segment
		(start 401.25904 -125.93828)
		(end 427.469554 -125.93828)
		(width 0.11684)
		(layer "In6.Cu")
		(net "GPU_WP_HW_CTRL_N")
	)
	(segment
		(start 427.469554 -125.93828)
		(end 452.235316 -150.704042)
		(width 0.11684)
		(layer "In6.Cu")
		(net "GPU_WP_HW_CTRL_N")
	)
	(segment
		(start 436.424578 -392.385804)
		(end 431.84572 -396.964662)
		(width 0.11684)
		(layer "In6.Cu")
		(net "GPU_WP_HW_CTRL_N")
	)
	(segment
		(start 400.987006 -126.210314)
		(end 401.25904 -125.93828)
		(width 0.11684)
		(layer "In6.Cu")
		(net "GPU_WP_HW_CTRL_N")
	)
	(segment
		(start 437.317642 -404.921974)
		(end 437.317642 -414.933892)
		(width 0.11684)
		(layer "In6.Cu")
		(net "GPU_WP_HW_CTRL_N")
	)
	(segment
		(start 262.603234 -146.221196)
		(end 271.307052 -137.517378)
		(width 0.11684)
		(layer "In6.Cu")
		(net "GPU_WP_HW_CTRL_N")
	)
	(segment
		(start 228.571044 -132.951982)
		(end 240.526062 -132.951982)
		(width 0.11684)
		(layer "In6.Cu")
		(net "GPU_WP_HW_CTRL_N")
	)
	(segment
		(start 436.479188 -433.969668)
		(end 436.709566 -433.969668)
		(width 0.11684)
		(layer "In6.Cu")
		(net "GPU_WP_HW_CTRL_N")
	)
	(segment
		(start 439.969656 -372.034816)
		(end 439.969656 -387.77926)
		(width 0.11684)
		(layer "In6.Cu")
		(net "GPU_WP_HW_CTRL_N")
	)
	(segment
		(start 435.878986 -433.369466)
		(end 436.479188 -433.969668)
		(width 0.11684)
		(layer "In6.Cu")
		(net "GPU_WP_HW_CTRL_N")
	)
	(segment
		(start 212.994494 -122.954034)
		(end 213.895432 -123.854972)
		(width 0.11684)
		(layer "In6.Cu")
		(net "GPU_WP_HW_CTRL_N")
	)
	(segment
		(start 321.025266 -122.64136)
		(end 346.112338 -122.64136)
		(width 0.11684)
		(layer "In6.Cu")
		(net "GPU_WP_HW_CTRL_N")
	)
	(segment
		(start 439.969656 -387.77926)
		(end 436.424578 -391.324338)
		(width 0.11684)
		(layer "In6.Cu")
		(net "GPU_WP_HW_CTRL_N")
	)
	(segment
		(start 444.158116 -435.889654)
		(end 443.154562 -435.889654)
		(width 0.10668)
		(layer "F.Cu")
		(net "GPU_WP_HW_CTRL_ISO")
	)
	(segment
		(start 443.13348 -435.199282)
		(end 443.13348 -435.868572)
		(width 0.10668)
		(layer "F.Cu")
		(net "GPU_WP_HW_CTRL_ISO")
	)
	(segment
		(start 443.13348 -434.549296)
		(end 443.13348 -435.199282)
		(width 0.10668)
		(layer "F.Cu")
		(net "GPU_WP_HW_CTRL_ISO")
	)
	(segment
		(start 444.59652 -435.45125)
		(end 444.158116 -435.889654)
		(width 0.10668)
		(layer "F.Cu")
		(net "GPU_WP_HW_CTRL_ISO")
	)
	(segment
		(start 443.154562 -435.889654)
		(end 443.13348 -435.868572)
		(width 0.10668)
		(layer "F.Cu")
		(net "GPU_WP_HW_CTRL_ISO")
	)
	(segment
		(start 444.59652 -435.199282)
		(end 444.59652 -435.45125)
		(width 0.10668)
		(layer "F.Cu")
		(net "GPU_WP_HW_CTRL_ISO")
	)
	(via
		(at 443.13348 -435.868572)
		(size 0.508)
		(drill 0.254)
		(layers "F.Cu" "B.Cu")
		(net "GPU_WP_HW_CTRL_ISO")
	)
	(segment
		(start 163.338764 -118.78183)
		(end 163.582604 -118.53799)
		(width 0.10668)
		(layer "F.Cu")
		(net "GPU_PRSNT_N_ISO")
	)
	(segment
		(start 163.338764 -119.345202)
		(end 163.338764 -118.78183)
		(width 0.10668)
		(layer "F.Cu")
		(net "GPU_PRSNT_N_ISO")
	)
	(segment
		(start 186.111642 -413.24403)
		(end 186.111642 -412.92907)
		(width 0.10668)
		(layer "F.Cu")
		(net "GPU_PRSNT_N_ISO")
	)
	(segment
		(start 165.248336 -118.348506)
		(end 165.372288 -118.348506)
		(width 0.10668)
		(layer "F.Cu")
		(net "GPU_PRSNT_N_ISO")
	)
	(segment
		(start 186.111642 -412.92907)
		(end 185.584338 -412.401766)
		(width 0.10668)
		(layer "F.Cu")
		(net "GPU_PRSNT_N_ISO")
	)
	(segment
		(start 163.582604 -118.53799)
		(end 165.058852 -118.53799)
		(width 0.10668)
		(layer "F.Cu")
		(net "GPU_PRSNT_N_ISO")
	)
	(segment
		(start 165.058852 -118.53799)
		(end 165.248336 -118.348506)
		(width 0.10668)
		(layer "F.Cu")
		(net "GPU_PRSNT_N_ISO")
	)
	(via
		(at 168.076372 -126.506224)
		(size 0.508)
		(drill 0.254)
		(layers "F.Cu" "B.Cu")
		(net "GPU_PRSNT_N_ISO")
	)
	(via
		(at 169.705782 -412.960312)
		(size 0.508)
		(drill 0.254)
		(layers "F.Cu" "B.Cu")
		(net "GPU_PRSNT_N_ISO")
	)
	(via
		(at 232.032048 -123.632722)
		(size 0.508)
		(drill 0.254)
		(layers "F.Cu" "B.Cu")
		(net "GPU_PRSNT_N_ISO")
	)
	(via
		(at 185.584338 -412.401766)
		(size 0.508)
		(drill 0.254)
		(layers "F.Cu" "B.Cu")
		(net "GPU_PRSNT_N_ISO")
	)
	(via
		(at 192.318894 -430.891696)
		(size 0.508)
		(drill 0.254)
		(layers "F.Cu" "B.Cu")
		(net "GPU_PRSNT_N_ISO")
	)
	(via
		(at 168.076372 -147.302728)
		(size 0.508)
		(drill 0.254)
		(layers "F.Cu" "B.Cu")
		(net "GPU_PRSNT_N_ISO")
	)
	(via
		(at 234.631738 -148.57603)
		(size 0.508)
		(drill 0.254)
		(layers "F.Cu" "B.Cu")
		(net "GPU_PRSNT_N_ISO")
	)
	(via
		(at 39.388034 -392.075416)
		(size 0.508)
		(drill 0.254)
		(layers "F.Cu" "B.Cu")
		(net "GPU_PRSNT_N_ISO")
	)
	(via
		(at 436.671974 -433.504848)
		(size 0.508)
		(drill 0.254)
		(layers "F.Cu" "B.Cu")
		(net "GPU_PRSNT_N_ISO")
	)
	(via
		(at 50.907696 -428.46498)
		(size 0.508)
		(drill 0.254)
		(layers "F.Cu" "B.Cu")
		(net "GPU_PRSNT_N_ISO")
	)
	(via
		(at 165.372288 -118.348506)
		(size 0.508)
		(drill 0.254)
		(layers "F.Cu" "B.Cu")
		(net "GPU_PRSNT_N_ISO")
	)
	(segment
		(start 184.87771 -411.964886)
		(end 185.147458 -411.964886)
		(width 0.10668)
		(layer "B.Cu")
		(net "GPU_PRSNT_N_ISO")
	)
	(segment
		(start 170.03903 -412.960312)
		(end 172.36948 -410.629862)
		(width 0.10668)
		(layer "B.Cu")
		(net "GPU_PRSNT_N_ISO")
	)
	(segment
		(start 52.782978 -428.46498)
		(end 51.766978 -428.46498)
		(width 0.10668)
		(layer "B.Cu")
		(net "GPU_PRSNT_N_ISO")
	)
	(segment
		(start 185.147458 -411.964886)
		(end 185.584338 -412.401766)
		(width 0.10668)
		(layer "B.Cu")
		(net "GPU_PRSNT_N_ISO")
	)
	(segment
		(start 175.968406 -410.629862)
		(end 176.727866 -411.389322)
		(width 0.10668)
		(layer "B.Cu")
		(net "GPU_PRSNT_N_ISO")
	)
	(segment
		(start 179.678838 -410.291026)
		(end 183.204104 -410.291026)
		(width 0.10668)
		(layer "B.Cu")
		(net "GPU_PRSNT_N_ISO")
	)
	(segment
		(start 183.204104 -410.291026)
		(end 183.383428 -410.47035)
		(width 0.10668)
		(layer "B.Cu")
		(net "GPU_PRSNT_N_ISO")
	)
	(segment
		(start 49.6062 -428.46498)
		(end 50.907696 -428.46498)
		(width 0.10668)
		(layer "B.Cu")
		(net "GPU_PRSNT_N_ISO")
	)
	(segment
		(start 50.907696 -428.46498)
		(end 51.766978 -428.46498)
		(width 0.10668)
		(layer "B.Cu")
		(net "GPU_PRSNT_N_ISO")
	)
	(segment
		(start 183.383428 -410.47035)
		(end 183.383428 -410.470604)
		(width 0.10668)
		(layer "B.Cu")
		(net "GPU_PRSNT_N_ISO")
	)
	(segment
		(start 183.383428 -410.470604)
		(end 184.87771 -411.964886)
		(width 0.10668)
		(layer "B.Cu")
		(net "GPU_PRSNT_N_ISO")
	)
	(segment
		(start 172.36948 -410.629862)
		(end 175.968406 -410.629862)
		(width 0.10668)
		(layer "B.Cu")
		(net "GPU_PRSNT_N_ISO")
	)
	(segment
		(start 176.727866 -411.389322)
		(end 178.580542 -411.389322)
		(width 0.10668)
		(layer "B.Cu")
		(net "GPU_PRSNT_N_ISO")
	)
	(segment
		(start 178.580542 -411.389322)
		(end 179.678838 -410.291026)
		(width 0.10668)
		(layer "B.Cu")
		(net "GPU_PRSNT_N_ISO")
	)
	(segment
		(start 169.705782 -412.960312)
		(end 170.03903 -412.960312)
		(width 0.10668)
		(layer "B.Cu")
		(net "GPU_PRSNT_N_ISO")
	)
	(segment
		(start 229.981252 -148.902674)
		(end 217.741246 -148.902674)
		(width 0.11684)
		(layer "In2.Cu")
		(net "GPU_PRSNT_N_ISO")
	)
	(segment
		(start 231.993948 -149.29358)
		(end 230.372158 -149.29358)
		(width 0.11684)
		(layer "In2.Cu")
		(net "GPU_PRSNT_N_ISO")
	)
	(segment
		(start 299.801026 -417.856162)
		(end 302.459898 -415.19729)
		(width 0.11684)
		(layer "In2.Cu")
		(net "GPU_PRSNT_N_ISO")
	)
	(segment
		(start 361.485942 -409.698698)
		(end 362.768896 -408.415744)
		(width 0.11684)
		(layer "In2.Cu")
		(net "GPU_PRSNT_N_ISO")
	)
	(segment
		(start 358.827832 -412.186374)
		(end 359.872788 -411.141418)
		(width 0.11684)
		(layer "In2.Cu")
		(net "GPU_PRSNT_N_ISO")
	)
	(segment
		(start 163.89858 -402.663914)
		(end 165.405054 -404.170388)
		(width 0.11684)
		(layer "In2.Cu")
		(net "GPU_PRSNT_N_ISO")
	)
	(segment
		(start 431.374804 -431.695606)
		(end 432.42992 -432.750722)
		(width 0.11684)
		(layer "In2.Cu")
		(net "GPU_PRSNT_N_ISO")
	)
	(segment
		(start 203.48067 -146.255994)
		(end 203.074778 -146.661886)
		(width 0.11684)
		(layer "In2.Cu")
		(net "GPU_PRSNT_N_ISO")
	)
	(segment
		(start 165.405054 -407.830782)
		(end 168.48963 -410.915358)
		(width 0.11684)
		(layer "In2.Cu")
		(net "GPU_PRSNT_N_ISO")
	)
	(segment
		(start 357.176578 -412.186374)
		(end 358.827832 -412.186374)
		(width 0.11684)
		(layer "In2.Cu")
		(net "GPU_PRSNT_N_ISO")
	)
	(segment
		(start 215.094566 -146.255994)
		(end 203.48067 -146.255994)
		(width 0.11684)
		(layer "In2.Cu")
		(net "GPU_PRSNT_N_ISO")
	)
	(segment
		(start 432.42992 -432.750722)
		(end 435.917848 -432.750722)
		(width 0.11684)
		(layer "In2.Cu")
		(net "GPU_PRSNT_N_ISO")
	)
	(segment
		(start 282.36164 -413.707072)
		(end 285.42869 -410.640022)
		(width 0.11684)
		(layer "In2.Cu")
		(net "GPU_PRSNT_N_ISO")
	)
	(segment
		(start 187.715144 -149.072346)
		(end 184.281064 -149.072346)
		(width 0.11684)
		(layer "In2.Cu")
		(net "GPU_PRSNT_N_ISO")
	)
	(segment
		(start 292.197536 -414.724342)
		(end 295.329356 -417.856162)
		(width 0.11684)
		(layer "In2.Cu")
		(net "GPU_PRSNT_N_ISO")
	)
	(segment
		(start 432.768756 -425.26331)
		(end 431.374804 -426.657262)
		(width 0.11684)
		(layer "In2.Cu")
		(net "GPU_PRSNT_N_ISO")
	)
	(segment
		(start 356.204012 -410.109162)
		(end 356.204012 -411.213808)
		(width 0.11684)
		(layer "In2.Cu")
		(net "GPU_PRSNT_N_ISO")
	)
	(segment
		(start 193.912236 -432.485038)
		(end 193.912236 -433.8828)
		(width 0.11684)
		(layer "In2.Cu")
		(net "GPU_PRSNT_N_ISO")
	)
	(segment
		(start 234.631738 -148.57603)
		(end 232.711498 -148.57603)
		(width 0.11684)
		(layer "In2.Cu")
		(net "GPU_PRSNT_N_ISO")
	)
	(segment
		(start 192.788032 -145.838418)
		(end 189.648592 -147.138898)
		(width 0.11684)
		(layer "In2.Cu")
		(net "GPU_PRSNT_N_ISO")
	)
	(segment
		(start 355.999542 -409.904692)
		(end 356.204012 -410.109162)
		(width 0.11684)
		(layer "In2.Cu")
		(net "GPU_PRSNT_N_ISO")
	)
	(segment
		(start 367.842546 -408.617928)
		(end 428.55642 -408.617928)
		(width 0.11684)
		(layer "In2.Cu")
		(net "GPU_PRSNT_N_ISO")
	)
	(segment
		(start 189.648592 -147.138898)
		(end 187.715144 -149.072346)
		(width 0.11684)
		(layer "In2.Cu")
		(net "GPU_PRSNT_N_ISO")
	)
	(segment
		(start 283.92882 -422.76649)
		(end 282.36164 -421.19931)
		(width 0.11684)
		(layer "In2.Cu")
		(net "GPU_PRSNT_N_ISO")
	)
	(segment
		(start 200.83399 -146.661886)
		(end 200.010522 -145.838418)
		(width 0.11684)
		(layer "In2.Cu")
		(net "GPU_PRSNT_N_ISO")
	)
	(segment
		(start 356.204012 -411.213808)
		(end 357.176578 -412.186374)
		(width 0.11684)
		(layer "In2.Cu")
		(net "GPU_PRSNT_N_ISO")
	)
	(segment
		(start 309.380382 -409.904692)
		(end 355.999542 -409.904692)
		(width 0.11684)
		(layer "In2.Cu")
		(net "GPU_PRSNT_N_ISO")
	)
	(segment
		(start 283.92882 -425.317412)
		(end 283.92882 -422.76649)
		(width 0.11684)
		(layer "In2.Cu")
		(net "GPU_PRSNT_N_ISO")
	)
	(segment
		(start 193.912236 -433.8828)
		(end 198.94677 -438.917334)
		(width 0.11684)
		(layer "In2.Cu")
		(net "GPU_PRSNT_N_ISO")
	)
	(segment
		(start 359.872788 -411.141418)
		(end 359.872788 -410.242512)
		(width 0.11684)
		(layer "In2.Cu")
		(net "GPU_PRSNT_N_ISO")
	)
	(segment
		(start 362.768896 -408.415744)
		(end 367.640362 -408.415744)
		(width 0.11684)
		(layer "In2.Cu")
		(net "GPU_PRSNT_N_ISO")
	)
	(segment
		(start 96.5581 -397.127222)
		(end 98.497898 -399.06702)
		(width 0.11684)
		(layer "In2.Cu")
		(net "GPU_PRSNT_N_ISO")
	)
	(segment
		(start 101.483922 -399.06702)
		(end 105.080816 -402.663914)
		(width 0.11684)
		(layer "In2.Cu")
		(net "GPU_PRSNT_N_ISO")
	)
	(segment
		(start 283.683964 -436.715662)
		(end 283.683964 -425.562268)
		(width 0.11684)
		(layer "In2.Cu")
		(net "GPU_PRSNT_N_ISO")
	)
	(segment
		(start 359.872788 -410.242512)
		(end 360.416602 -409.698698)
		(width 0.11684)
		(layer "In2.Cu")
		(net "GPU_PRSNT_N_ISO")
	)
	(segment
		(start 174.242222 -147.302728)
		(end 168.076372 -147.302728)
		(width 0.11684)
		(layer "In2.Cu")
		(net "GPU_PRSNT_N_ISO")
	)
	(segment
		(start 308.683914 -410.60116)
		(end 309.380382 -409.904692)
		(width 0.11684)
		(layer "In2.Cu")
		(net "GPU_PRSNT_N_ISO")
	)
	(segment
		(start 230.372158 -149.29358)
		(end 229.981252 -148.902674)
		(width 0.11684)
		(layer "In2.Cu")
		(net "GPU_PRSNT_N_ISO")
	)
	(segment
		(start 217.741246 -148.902674)
		(end 215.094566 -146.255994)
		(width 0.11684)
		(layer "In2.Cu")
		(net "GPU_PRSNT_N_ISO")
	)
	(segment
		(start 281.482292 -438.917334)
		(end 283.683964 -436.715662)
		(width 0.11684)
		(layer "In2.Cu")
		(net "GPU_PRSNT_N_ISO")
	)
	(segment
		(start 200.010522 -145.838418)
		(end 192.788032 -145.838418)
		(width 0.11684)
		(layer "In2.Cu")
		(net "GPU_PRSNT_N_ISO")
	)
	(segment
		(start 177.562256 -150.622762)
		(end 174.242222 -147.302728)
		(width 0.11684)
		(layer "In2.Cu")
		(net "GPU_PRSNT_N_ISO")
	)
	(segment
		(start 295.329356 -417.856162)
		(end 299.801026 -417.856162)
		(width 0.11684)
		(layer "In2.Cu")
		(net "GPU_PRSNT_N_ISO")
	)
	(segment
		(start 182.730648 -150.622762)
		(end 177.562256 -150.622762)
		(width 0.11684)
		(layer "In2.Cu")
		(net "GPU_PRSNT_N_ISO")
	)
	(segment
		(start 105.080816 -402.663914)
		(end 163.89858 -402.663914)
		(width 0.11684)
		(layer "In2.Cu")
		(net "GPU_PRSNT_N_ISO")
	)
	(segment
		(start 302.459898 -411.389576)
		(end 303.248314 -410.60116)
		(width 0.11684)
		(layer "In2.Cu")
		(net "GPU_PRSNT_N_ISO")
	)
	(segment
		(start 285.42869 -410.640022)
		(end 289.572954 -410.640022)
		(width 0.11684)
		(layer "In2.Cu")
		(net "GPU_PRSNT_N_ISO")
	)
	(segment
		(start 367.640362 -408.415744)
		(end 367.842546 -408.617928)
		(width 0.11684)
		(layer "In2.Cu")
		(net "GPU_PRSNT_N_ISO")
	)
	(segment
		(start 168.764966 -413.278574)
		(end 169.38752 -413.278574)
		(width 0.11684)
		(layer "In2.Cu")
		(net "GPU_PRSNT_N_ISO")
	)
	(segment
		(start 40.067484 -392.754866)
		(end 44.734734 -392.754866)
		(width 0.11684)
		(layer "In2.Cu")
		(net "GPU_PRSNT_N_ISO")
	)
	(segment
		(start 203.074778 -146.661886)
		(end 200.83399 -146.661886)
		(width 0.11684)
		(layer "In2.Cu")
		(net "GPU_PRSNT_N_ISO")
	)
	(segment
		(start 303.248314 -410.60116)
		(end 308.683914 -410.60116)
		(width 0.11684)
		(layer "In2.Cu")
		(net "GPU_PRSNT_N_ISO")
	)
	(segment
		(start 292.197536 -413.264604)
		(end 292.197536 -414.724342)
		(width 0.11684)
		(layer "In2.Cu")
		(net "GPU_PRSNT_N_ISO")
	)
	(segment
		(start 435.917848 -432.750722)
		(end 436.671974 -433.504848)
		(width 0.11684)
		(layer "In2.Cu")
		(net "GPU_PRSNT_N_ISO")
	)
	(segment
		(start 168.48963 -413.003238)
		(end 168.764966 -413.278574)
		(width 0.11684)
		(layer "In2.Cu")
		(net "GPU_PRSNT_N_ISO")
	)
	(segment
		(start 432.768756 -412.830264)
		(end 432.768756 -425.26331)
		(width 0.11684)
		(layer "In2.Cu")
		(net "GPU_PRSNT_N_ISO")
	)
	(segment
		(start 198.94677 -438.917334)
		(end 281.482292 -438.917334)
		(width 0.11684)
		(layer "In2.Cu")
		(net "GPU_PRSNT_N_ISO")
	)
	(segment
		(start 232.711498 -148.57603)
		(end 231.993948 -149.29358)
		(width 0.11684)
		(layer "In2.Cu")
		(net "GPU_PRSNT_N_ISO")
	)
	(segment
		(start 283.683964 -425.562268)
		(end 283.92882 -425.317412)
		(width 0.11684)
		(layer "In2.Cu")
		(net "GPU_PRSNT_N_ISO")
	)
	(segment
		(start 282.36164 -421.19931)
		(end 282.36164 -413.707072)
		(width 0.11684)
		(layer "In2.Cu")
		(net "GPU_PRSNT_N_ISO")
	)
	(segment
		(start 289.572954 -410.640022)
		(end 292.197536 -413.264604)
		(width 0.11684)
		(layer "In2.Cu")
		(net "GPU_PRSNT_N_ISO")
	)
	(segment
		(start 165.405054 -404.170388)
		(end 165.405054 -407.830782)
		(width 0.11684)
		(layer "In2.Cu")
		(net "GPU_PRSNT_N_ISO")
	)
	(segment
		(start 428.55642 -408.617928)
		(end 432.768756 -412.830264)
		(width 0.11684)
		(layer "In2.Cu")
		(net "GPU_PRSNT_N_ISO")
	)
	(segment
		(start 49.10709 -397.127222)
		(end 96.5581 -397.127222)
		(width 0.11684)
		(layer "In2.Cu")
		(net "GPU_PRSNT_N_ISO")
	)
	(segment
		(start 169.38752 -413.278574)
		(end 169.705782 -412.960312)
		(width 0.11684)
		(layer "In2.Cu")
		(net "GPU_PRSNT_N_ISO")
	)
	(segment
		(start 39.388034 -392.075416)
		(end 40.067484 -392.754866)
		(width 0.11684)
		(layer "In2.Cu")
		(net "GPU_PRSNT_N_ISO")
	)
	(segment
		(start 302.459898 -415.19729)
		(end 302.459898 -411.389576)
		(width 0.11684)
		(layer "In2.Cu")
		(net "GPU_PRSNT_N_ISO")
	)
	(segment
		(start 360.416602 -409.698698)
		(end 361.485942 -409.698698)
		(width 0.11684)
		(layer "In2.Cu")
		(net "GPU_PRSNT_N_ISO")
	)
	(segment
		(start 431.374804 -426.657262)
		(end 431.374804 -431.695606)
		(width 0.11684)
		(layer "In2.Cu")
		(net "GPU_PRSNT_N_ISO")
	)
	(segment
		(start 44.734734 -392.754866)
		(end 49.10709 -397.127222)
		(width 0.11684)
		(layer "In2.Cu")
		(net "GPU_PRSNT_N_ISO")
	)
	(segment
		(start 168.48963 -410.915358)
		(end 168.48963 -413.003238)
		(width 0.11684)
		(layer "In2.Cu")
		(net "GPU_PRSNT_N_ISO")
	)
	(segment
		(start 184.281064 -149.072346)
		(end 182.730648 -150.622762)
		(width 0.11684)
		(layer "In2.Cu")
		(net "GPU_PRSNT_N_ISO")
	)
	(segment
		(start 192.318894 -430.891696)
		(end 193.912236 -432.485038)
		(width 0.11684)
		(layer "In2.Cu")
		(net "GPU_PRSNT_N_ISO")
	)
	(segment
		(start 98.497898 -399.06702)
		(end 101.483922 -399.06702)
		(width 0.11684)
		(layer "In2.Cu")
		(net "GPU_PRSNT_N_ISO")
	)
	(segment
		(start 232.032048 -123.632722)
		(end 232.032048 -139.88288)
		(width 0.11684)
		(layer "In4.Cu")
		(net "GPU_PRSNT_N_ISO")
	)
	(segment
		(start 232.907332 -140.758164)
		(end 232.907332 -146.86534)
		(width 0.11684)
		(layer "In4.Cu")
		(net "GPU_PRSNT_N_ISO")
	)
	(segment
		(start 232.032048 -139.88288)
		(end 232.907332 -140.758164)
		(width 0.11684)
		(layer "In4.Cu")
		(net "GPU_PRSNT_N_ISO")
	)
	(segment
		(start 234.618022 -148.57603)
		(end 234.631738 -148.57603)
		(width 0.11684)
		(layer "In4.Cu")
		(net "GPU_PRSNT_N_ISO")
	)
	(segment
		(start 232.907332 -146.86534)
		(end 234.618022 -148.57603)
		(width 0.11684)
		(layer "In4.Cu")
		(net "GPU_PRSNT_N_ISO")
	)
	(segment
		(start 233.956606 -132.577078)
		(end 240.79454 -132.577078)
		(width 0.11684)
		(layer "In6.Cu")
		(net "GPU_PRSNT_N_ISO")
	)
	(segment
		(start 465.146136 -331.648816)
		(end 453.90943 -342.885522)
		(width 0.11684)
		(layer "In6.Cu")
		(net "GPU_PRSNT_N_ISO")
	)
	(segment
		(start 192.318894 -430.053496)
		(end 192.318894 -430.891696)
		(width 0.11684)
		(layer "In6.Cu")
		(net "GPU_PRSNT_N_ISO")
	)
	(segment
		(start 349.719646 -125.795786)
		(end 400.948906 -125.795786)
		(width 0.11684)
		(layer "In6.Cu")
		(net "GPU_PRSNT_N_ISO")
	)
	(segment
		(start 318.47282 -124.740924)
		(end 320.892424 -122.32132)
		(width 0.11684)
		(layer "In6.Cu")
		(net "GPU_PRSNT_N_ISO")
	)
	(segment
		(start 436.199026 -416.505136)
		(end 436.199026 -433.0319)
		(width 0.11684)
		(layer "In6.Cu")
		(net "GPU_PRSNT_N_ISO")
	)
	(segment
		(start 189.511686 -429.045878)
		(end 191.311276 -429.045878)
		(width 0.11684)
		(layer "In6.Cu")
		(net "GPU_PRSNT_N_ISO")
	)
	(segment
		(start 184.98566 -424.519852)
		(end 189.511686 -429.045878)
		(width 0.11684)
		(layer "In6.Cu")
		(net "GPU_PRSNT_N_ISO")
	)
	(segment
		(start 432.16576 -397.097504)
		(end 432.16576 -400.386296)
		(width 0.11684)
		(layer "In6.Cu")
		(net "GPU_PRSNT_N_ISO")
	)
	(segment
		(start 437.637682 -404.789386)
		(end 437.637682 -415.06648)
		(width 0.11684)
		(layer "In6.Cu")
		(net "GPU_PRSNT_N_ISO")
	)
	(segment
		(start 232.032048 -130.65252)
		(end 233.956606 -132.577078)
		(width 0.11684)
		(layer "In6.Cu")
		(net "GPU_PRSNT_N_ISO")
	)
	(segment
		(start 453.90943 -358.76103)
		(end 440.289696 -372.380764)
		(width 0.11684)
		(layer "In6.Cu")
		(net "GPU_PRSNT_N_ISO")
	)
	(segment
		(start 320.892424 -122.32132)
		(end 346.24518 -122.32132)
		(width 0.11684)
		(layer "In6.Cu")
		(net "GPU_PRSNT_N_ISO")
	)
	(segment
		(start 254.118618 -145.901156)
		(end 262.470392 -145.901156)
		(width 0.11684)
		(layer "In6.Cu")
		(net "GPU_PRSNT_N_ISO")
	)
	(segment
		(start 436.744618 -391.461752)
		(end 436.744618 -392.518646)
		(width 0.11684)
		(layer "In6.Cu")
		(net "GPU_PRSNT_N_ISO")
	)
	(segment
		(start 289.575748 -137.062464)
		(end 301.897288 -124.740924)
		(width 0.11684)
		(layer "In6.Cu")
		(net "GPU_PRSNT_N_ISO")
	)
	(segment
		(start 436.744618 -392.518646)
		(end 432.16576 -397.097504)
		(width 0.11684)
		(layer "In6.Cu")
		(net "GPU_PRSNT_N_ISO")
	)
	(segment
		(start 434.197506 -402.418042)
		(end 435.266338 -402.418042)
		(width 0.11684)
		(layer "In6.Cu")
		(net "GPU_PRSNT_N_ISO")
	)
	(segment
		(start 301.897288 -124.740924)
		(end 318.47282 -124.740924)
		(width 0.11684)
		(layer "In6.Cu")
		(net "GPU_PRSNT_N_ISO")
	)
	(segment
		(start 346.24518 -122.32132)
		(end 349.719646 -125.795786)
		(width 0.11684)
		(layer "In6.Cu")
		(net "GPU_PRSNT_N_ISO")
	)
	(segment
		(start 436.199026 -433.0319)
		(end 436.671974 -433.504848)
		(width 0.11684)
		(layer "In6.Cu")
		(net "GPU_PRSNT_N_ISO")
	)
	(segment
		(start 401.126452 -125.61824)
		(end 427.602142 -125.61824)
		(width 0.11684)
		(layer "In6.Cu")
		(net "GPU_PRSNT_N_ISO")
	)
	(segment
		(start 453.90943 -342.885522)
		(end 453.90943 -358.76103)
		(width 0.11684)
		(layer "In6.Cu")
		(net "GPU_PRSNT_N_ISO")
	)
	(segment
		(start 240.79454 -132.577078)
		(end 254.118618 -145.901156)
		(width 0.11684)
		(layer "In6.Cu")
		(net "GPU_PRSNT_N_ISO")
	)
	(segment
		(start 232.032048 -123.632722)
		(end 232.032048 -130.65252)
		(width 0.11684)
		(layer "In6.Cu")
		(net "GPU_PRSNT_N_ISO")
	)
	(segment
		(start 452.69023 -164.916358)
		(end 465.146136 -177.372264)
		(width 0.11684)
		(layer "In6.Cu")
		(net "GPU_PRSNT_N_ISO")
	)
	(segment
		(start 452.69023 -150.706328)
		(end 452.69023 -164.916358)
		(width 0.11684)
		(layer "In6.Cu")
		(net "GPU_PRSNT_N_ISO")
	)
	(segment
		(start 400.948906 -125.795786)
		(end 401.126452 -125.61824)
		(width 0.11684)
		(layer "In6.Cu")
		(net "GPU_PRSNT_N_ISO")
	)
	(segment
		(start 271.309084 -137.062464)
		(end 289.575748 -137.062464)
		(width 0.11684)
		(layer "In6.Cu")
		(net "GPU_PRSNT_N_ISO")
	)
	(segment
		(start 185.584338 -417.277804)
		(end 184.98566 -417.876482)
		(width 0.11684)
		(layer "In6.Cu")
		(net "GPU_PRSNT_N_ISO")
	)
	(segment
		(start 191.311276 -429.045878)
		(end 192.318894 -430.053496)
		(width 0.11684)
		(layer "In6.Cu")
		(net "GPU_PRSNT_N_ISO")
	)
	(segment
		(start 435.266338 -402.418042)
		(end 437.637682 -404.789386)
		(width 0.11684)
		(layer "In6.Cu")
		(net "GPU_PRSNT_N_ISO")
	)
	(segment
		(start 185.584338 -412.401766)
		(end 185.584338 -417.277804)
		(width 0.11684)
		(layer "In6.Cu")
		(net "GPU_PRSNT_N_ISO")
	)
	(segment
		(start 440.289696 -387.916674)
		(end 436.744618 -391.461752)
		(width 0.11684)
		(layer "In6.Cu")
		(net "GPU_PRSNT_N_ISO")
	)
	(segment
		(start 440.289696 -372.380764)
		(end 440.289696 -387.916674)
		(width 0.11684)
		(layer "In6.Cu")
		(net "GPU_PRSNT_N_ISO")
	)
	(segment
		(start 437.637682 -415.06648)
		(end 436.199026 -416.505136)
		(width 0.11684)
		(layer "In6.Cu")
		(net "GPU_PRSNT_N_ISO")
	)
	(segment
		(start 427.602142 -125.61824)
		(end 452.69023 -150.706328)
		(width 0.11684)
		(layer "In6.Cu")
		(net "GPU_PRSNT_N_ISO")
	)
	(segment
		(start 184.98566 -417.876482)
		(end 184.98566 -424.519852)
		(width 0.11684)
		(layer "In6.Cu")
		(net "GPU_PRSNT_N_ISO")
	)
	(segment
		(start 262.470392 -145.901156)
		(end 271.309084 -137.062464)
		(width 0.11684)
		(layer "In6.Cu")
		(net "GPU_PRSNT_N_ISO")
	)
	(segment
		(start 432.16576 -400.386296)
		(end 434.197506 -402.418042)
		(width 0.11684)
		(layer "In6.Cu")
		(net "GPU_PRSNT_N_ISO")
	)
	(segment
		(start 465.146136 -177.372264)
		(end 465.146136 -331.648816)
		(width 0.11684)
		(layer "In6.Cu")
		(net "GPU_PRSNT_N_ISO")
	)
	(segment
		(start 165.372288 -118.498874)
		(end 166.672006 -119.798592)
		(width 0.11684)
		(layer "In11.Cu")
		(net "GPU_PRSNT_N_ISO")
	)
	(segment
		(start 168.193974 -126.388622)
		(end 168.076372 -126.506224)
		(width 0.11684)
		(layer "In11.Cu")
		(net "GPU_PRSNT_N_ISO")
	)
	(segment
		(start 168.193974 -123.949968)
		(end 168.193974 -126.388622)
		(width 0.11684)
		(layer "In11.Cu")
		(net "GPU_PRSNT_N_ISO")
	)
	(segment
		(start 166.672006 -119.798592)
		(end 166.672006 -122.428)
		(width 0.11684)
		(layer "In11.Cu")
		(net "GPU_PRSNT_N_ISO")
	)
	(segment
		(start 166.672006 -122.428)
		(end 168.193974 -123.949968)
		(width 0.11684)
		(layer "In11.Cu")
		(net "GPU_PRSNT_N_ISO")
	)
	(segment
		(start 165.372288 -118.348506)
		(end 165.372288 -118.498874)
		(width 0.11684)
		(layer "In11.Cu")
		(net "GPU_PRSNT_N_ISO")
	)
	(segment
		(start 46.878748 -424.309032)
		(end 47.067216 -424.309032)
		(width 0.11684)
		(layer "In13.Cu")
		(net "GPU_PRSNT_N_ISO")
	)
	(segment
		(start 47.067216 -424.309032)
		(end 48.393096 -425.634912)
		(width 0.11684)
		(layer "In13.Cu")
		(net "GPU_PRSNT_N_ISO")
	)
	(segment
		(start 49.329848 -425.634912)
		(end 50.907696 -427.21276)
		(width 0.11684)
		(layer "In13.Cu")
		(net "GPU_PRSNT_N_ISO")
	)
	(segment
		(start 34.365946 -410.57195)
		(end 34.365946 -413.574992)
		(width 0.11684)
		(layer "In13.Cu")
		(net "GPU_PRSNT_N_ISO")
	)
	(segment
		(start 37.235384 -397.475964)
		(end 36.120832 -398.590516)
		(width 0.11684)
		(layer "In13.Cu")
		(net "GPU_PRSNT_N_ISO")
	)
	(segment
		(start 50.907696 -427.21276)
		(end 50.907696 -428.46498)
		(width 0.11684)
		(layer "In13.Cu")
		(net "GPU_PRSNT_N_ISO")
	)
	(segment
		(start 36.120832 -398.590516)
		(end 36.120832 -408.817064)
		(width 0.11684)
		(layer "In13.Cu")
		(net "GPU_PRSNT_N_ISO")
	)
	(segment
		(start 36.120832 -408.817064)
		(end 34.365946 -410.57195)
		(width 0.11684)
		(layer "In13.Cu")
		(net "GPU_PRSNT_N_ISO")
	)
	(segment
		(start 37.09924 -414.529524)
		(end 46.878748 -424.309032)
		(width 0.11684)
		(layer "In13.Cu")
		(net "GPU_PRSNT_N_ISO")
	)
	(segment
		(start 35.320478 -414.529524)
		(end 37.09924 -414.529524)
		(width 0.11684)
		(layer "In13.Cu")
		(net "GPU_PRSNT_N_ISO")
	)
	(segment
		(start 39.388034 -392.075416)
		(end 37.235384 -394.227812)
		(width 0.11684)
		(layer "In13.Cu")
		(net "GPU_PRSNT_N_ISO")
	)
	(segment
		(start 37.235384 -394.227812)
		(end 37.235384 -397.475964)
		(width 0.11684)
		(layer "In13.Cu")
		(net "GPU_PRSNT_N_ISO")
	)
	(segment
		(start 48.393096 -425.634912)
		(end 49.329848 -425.634912)
		(width 0.11684)
		(layer "In13.Cu")
		(net "GPU_PRSNT_N_ISO")
	)
	(segment
		(start 34.365946 -413.574992)
		(end 35.320478 -414.529524)
		(width 0.11684)
		(layer "In13.Cu")
		(net "GPU_PRSNT_N_ISO")
	)
	(segment
		(start 168.076372 -147.302728)
		(end 167.820086 -147.046442)
		(width 0.11684)
		(layer "In15.Cu")
		(net "GPU_PRSNT_N_ISO")
	)
	(segment
		(start 167.820086 -147.046442)
		(end 167.820086 -142.479268)
		(width 0.11684)
		(layer "In15.Cu")
		(net "GPU_PRSNT_N_ISO")
	)
	(segment
		(start 167.39997 -142.059152)
		(end 167.39997 -138.134344)
		(width 0.11684)
		(layer "In15.Cu")
		(net "GPU_PRSNT_N_ISO")
	)
	(segment
		(start 166.81831 -127.764286)
		(end 168.076372 -126.506224)
		(width 0.11684)
		(layer "In15.Cu")
		(net "GPU_PRSNT_N_ISO")
	)
	(segment
		(start 167.820086 -142.479268)
		(end 167.39997 -142.059152)
		(width 0.11684)
		(layer "In15.Cu")
		(net "GPU_PRSNT_N_ISO")
	)
	(segment
		(start 167.39997 -138.134344)
		(end 166.81831 -137.552684)
		(width 0.11684)
		(layer "In15.Cu")
		(net "GPU_PRSNT_N_ISO")
	)
	(segment
		(start 166.81831 -137.552684)
		(end 166.81831 -127.764286)
		(width 0.11684)
		(layer "In15.Cu")
		(net "GPU_PRSNT_N_ISO")
	)
	(via
		(at 50.913792 -429.455834)
		(size 0.508)
		(drill 0.254)
		(layers "F.Cu" "B.Cu")
		(net "GPU_PRSNT_N")
	)
	(via
		(at 96.954594 -404.835868)
		(size 0.508)
		(drill 0.254)
		(layers "F.Cu" "B.Cu")
		(net "GPU_PRSNT_N")
	)
	(segment
		(start 93.857572 -420.11981)
		(end 93.857572 -416.853116)
		(width 0.10668)
		(layer "B.Cu")
		(net "GPU_PRSNT_N")
	)
	(segment
		(start 81.445862 -420.894002)
		(end 93.08338 -420.894002)
		(width 0.10668)
		(layer "B.Cu")
		(net "GPU_PRSNT_N")
	)
	(segment
		(start 51.766978 -429.44288)
		(end 52.782978 -429.44288)
		(width 0.10668)
		(layer "B.Cu")
		(net "GPU_PRSNT_N")
	)
	(segment
		(start 77.650086 -424.689778)
		(end 81.445862 -420.894002)
		(width 0.10668)
		(layer "B.Cu")
		(net "GPU_PRSNT_N")
	)
	(segment
		(start 97.576132 -411.974792)
		(end 97.576132 -405.457406)
		(width 0.10668)
		(layer "B.Cu")
		(net "GPU_PRSNT_N")
	)
	(segment
		(start 95.50527 -415.205418)
		(end 95.50527 -414.045654)
		(width 0.10668)
		(layer "B.Cu")
		(net "GPU_PRSNT_N")
	)
	(segment
		(start 50.265076 -429.114966)
		(end 50.605944 -429.455834)
		(width 0.10668)
		(layer "B.Cu")
		(net "GPU_PRSNT_N")
	)
	(segment
		(start 97.576132 -405.457406)
		(end 96.954594 -404.835868)
		(width 0.10668)
		(layer "B.Cu")
		(net "GPU_PRSNT_N")
	)
	(segment
		(start 49.6062 -429.114966)
		(end 50.265076 -429.114966)
		(width 0.10668)
		(layer "B.Cu")
		(net "GPU_PRSNT_N")
	)
	(segment
		(start 95.50527 -414.045654)
		(end 97.576132 -411.974792)
		(width 0.10668)
		(layer "B.Cu")
		(net "GPU_PRSNT_N")
	)
	(segment
		(start 50.97653 -429.455834)
		(end 50.989484 -429.44288)
		(width 0.10668)
		(layer "B.Cu")
		(net "GPU_PRSNT_N")
	)
	(segment
		(start 93.857572 -416.853116)
		(end 95.50527 -415.205418)
		(width 0.10668)
		(layer "B.Cu")
		(net "GPU_PRSNT_N")
	)
	(segment
		(start 50.989484 -429.44288)
		(end 51.766978 -429.44288)
		(width 0.10668)
		(layer "B.Cu")
		(net "GPU_PRSNT_N")
	)
	(segment
		(start 93.08338 -420.894002)
		(end 93.857572 -420.11981)
		(width 0.10668)
		(layer "B.Cu")
		(net "GPU_PRSNT_N")
	)
	(segment
		(start 50.605944 -429.455834)
		(end 50.913792 -429.455834)
		(width 0.10668)
		(layer "B.Cu")
		(net "GPU_PRSNT_N")
	)
	(segment
		(start 50.913792 -429.455834)
		(end 50.97653 -429.455834)
		(width 0.10668)
		(layer "B.Cu")
		(net "GPU_PRSNT_N")
	)
	(segment
		(start 46.223682 -410.025088)
		(end 46.223682 -413.178752)
		(width 0.11684)
		(layer "In4.Cu")
		(net "GPU_PRSNT_N")
	)
	(segment
		(start 47.985934 -408.262836)
		(end 46.223682 -410.025088)
		(width 0.11684)
		(layer "In4.Cu")
		(net "GPU_PRSNT_N")
	)
	(segment
		(start 53.418486 -401.541234)
		(end 51.629564 -403.330156)
		(width 0.11684)
		(layer "In4.Cu")
		(net "GPU_PRSNT_N")
	)
	(segment
		(start 48.9204 -419.81247)
		(end 48.9204 -425.2468)
		(width 0.11684)
		(layer "In4.Cu")
		(net "GPU_PRSNT_N")
	)
	(segment
		(start 96.309688 -404.042372)
		(end 93.80855 -401.541234)
		(width 0.11684)
		(layer "In4.Cu")
		(net "GPU_PRSNT_N")
	)
	(segment
		(start 50.2412 -426.5676)
		(end 50.2412 -428.783242)
		(width 0.11684)
		(layer "In4.Cu")
		(net "GPU_PRSNT_N")
	)
	(segment
		(start 51.629564 -403.330156)
		(end 50.40249 -403.330156)
		(width 0.11684)
		(layer "In4.Cu")
		(net "GPU_PRSNT_N")
	)
	(segment
		(start 50.2412 -428.783242)
		(end 50.913792 -429.455834)
		(width 0.11684)
		(layer "In4.Cu")
		(net "GPU_PRSNT_N")
	)
	(segment
		(start 48.9204 -425.2468)
		(end 50.2412 -426.5676)
		(width 0.11684)
		(layer "In4.Cu")
		(net "GPU_PRSNT_N")
	)
	(segment
		(start 93.80855 -401.541234)
		(end 53.418486 -401.541234)
		(width 0.11684)
		(layer "In4.Cu")
		(net "GPU_PRSNT_N")
	)
	(segment
		(start 49.750726 -403.98192)
		(end 49.750726 -404.939754)
		(width 0.11684)
		(layer "In4.Cu")
		(net "GPU_PRSNT_N")
	)
	(segment
		(start 46.223682 -413.178752)
		(end 48.006 -414.96107)
		(width 0.11684)
		(layer "In4.Cu")
		(net "GPU_PRSNT_N")
	)
	(segment
		(start 96.309688 -404.190962)
		(end 96.309688 -404.042372)
		(width 0.11684)
		(layer "In4.Cu")
		(net "GPU_PRSNT_N")
	)
	(segment
		(start 47.985934 -406.704546)
		(end 47.985934 -408.262836)
		(width 0.11684)
		(layer "In4.Cu")
		(net "GPU_PRSNT_N")
	)
	(segment
		(start 48.006 -414.96107)
		(end 48.006 -418.89807)
		(width 0.11684)
		(layer "In4.Cu")
		(net "GPU_PRSNT_N")
	)
	(segment
		(start 48.006 -418.89807)
		(end 48.9204 -419.81247)
		(width 0.11684)
		(layer "In4.Cu")
		(net "GPU_PRSNT_N")
	)
	(segment
		(start 50.40249 -403.330156)
		(end 49.750726 -403.98192)
		(width 0.11684)
		(layer "In4.Cu")
		(net "GPU_PRSNT_N")
	)
	(segment
		(start 96.954594 -404.835868)
		(end 96.309688 -404.190962)
		(width 0.11684)
		(layer "In4.Cu")
		(net "GPU_PRSNT_N")
	)
	(segment
		(start 49.750726 -404.939754)
		(end 47.985934 -406.704546)
		(width 0.11684)
		(layer "In4.Cu")
		(net "GPU_PRSNT_N")
	)
	(segment
		(start 193.48958 -413.564832)
		(end 192.969642 -413.044894)
		(width 0.10668)
		(layer "F.Cu")
		(net "GPU_PRSNT")
	)
	(via
		(at 102.363016 -401.944078)
		(size 0.508)
		(drill 0.254)
		(layers "F.Cu" "B.Cu")
		(net "GPU_PRSNT")
	)
	(via
		(at 47.011336 -429.764952)
		(size 0.762)
		(drill 0.254)
		(layers "F.Cu" "B.Cu")
		(net "GPU_PRSNT")
	)
	(via
		(at 192.969642 -413.044894)
		(size 0.508)
		(drill 0.254)
		(layers "F.Cu" "B.Cu")
		(net "GPU_PRSNT")
	)
	(via
		(at 165.345364 -411.209236)
		(size 0.508)
		(drill 0.254)
		(layers "F.Cu" "B.Cu")
		(net "GPU_PRSNT")
	)
	(segment
		(start 188.184028 -412.242254)
		(end 192.167002 -412.242254)
		(width 0.10668)
		(layer "B.Cu")
		(net "GPU_PRSNT")
	)
	(segment
		(start 187.870846 -411.929072)
		(end 188.184028 -412.242254)
		(width 0.10668)
		(layer "B.Cu")
		(net "GPU_PRSNT")
	)
	(segment
		(start 179.418488 -410.027374)
		(end 183.630316 -410.027374)
		(width 0.10668)
		(layer "B.Cu")
		(net "GPU_PRSNT")
	)
	(segment
		(start 166.30523 -412.169102)
		(end 168.876726 -412.169102)
		(width 0.10668)
		(layer "B.Cu")
		(net "GPU_PRSNT")
	)
	(segment
		(start 47.011336 -429.764952)
		(end 47.70628 -429.764952)
		(width 0.10668)
		(layer "B.Cu")
		(net "GPU_PRSNT")
	)
	(segment
		(start 165.345364 -411.209236)
		(end 166.30523 -412.169102)
		(width 0.10668)
		(layer "B.Cu")
		(net "GPU_PRSNT")
	)
	(segment
		(start 168.876726 -412.169102)
		(end 170.648884 -410.396944)
		(width 0.10668)
		(layer "B.Cu")
		(net "GPU_PRSNT")
	)
	(segment
		(start 46.359318 -429.764952)
		(end 47.011336 -429.764952)
		(width 0.10668)
		(layer "B.Cu")
		(net "GPU_PRSNT")
	)
	(segment
		(start 176.814988 -411.0863)
		(end 178.359562 -411.0863)
		(width 0.10668)
		(layer "B.Cu")
		(net "GPU_PRSNT")
	)
	(segment
		(start 176.125632 -410.396944)
		(end 176.814988 -411.0863)
		(width 0.10668)
		(layer "B.Cu")
		(net "GPU_PRSNT")
	)
	(segment
		(start 185.532014 -411.929072)
		(end 187.870846 -411.929072)
		(width 0.10668)
		(layer "B.Cu")
		(net "GPU_PRSNT")
	)
	(segment
		(start 170.648884 -410.396944)
		(end 176.125632 -410.396944)
		(width 0.10668)
		(layer "B.Cu")
		(net "GPU_PRSNT")
	)
	(segment
		(start 47.70628 -429.114966)
		(end 47.70628 -429.764952)
		(width 0.10668)
		(layer "B.Cu")
		(net "GPU_PRSNT")
	)
	(segment
		(start 178.359562 -411.0863)
		(end 179.418488 -410.027374)
		(width 0.10668)
		(layer "B.Cu")
		(net "GPU_PRSNT")
	)
	(segment
		(start 192.167002 -412.242254)
		(end 192.969642 -413.044894)
		(width 0.10668)
		(layer "B.Cu")
		(net "GPU_PRSNT")
	)
	(segment
		(start 183.630316 -410.027374)
		(end 185.532014 -411.929072)
		(width 0.10668)
		(layer "B.Cu")
		(net "GPU_PRSNT")
	)
	(segment
		(start 103.781098 -403.36216)
		(end 163.69157 -403.36216)
		(width 0.11684)
		(layer "In2.Cu")
		(net "GPU_PRSNT")
	)
	(segment
		(start 164.764974 -410.628846)
		(end 165.345364 -411.209236)
		(width 0.11684)
		(layer "In2.Cu")
		(net "GPU_PRSNT")
	)
	(segment
		(start 164.764974 -404.435564)
		(end 164.764974 -410.628846)
		(width 0.11684)
		(layer "In2.Cu")
		(net "GPU_PRSNT")
	)
	(segment
		(start 163.69157 -403.36216)
		(end 164.764974 -404.435564)
		(width 0.11684)
		(layer "In2.Cu")
		(net "GPU_PRSNT")
	)
	(segment
		(start 102.363016 -401.944078)
		(end 103.781098 -403.36216)
		(width 0.11684)
		(layer "In2.Cu")
		(net "GPU_PRSNT")
	)
	(segment
		(start 47.752 -426.4152)
		(end 46.7868 -425.45)
		(width 0.11684)
		(layer "In4.Cu")
		(net "GPU_PRSNT")
	)
	(segment
		(start 94.502732 -399.846546)
		(end 98.020378 -403.364192)
		(width 0.11684)
		(layer "In4.Cu")
		(net "GPU_PRSNT")
	)
	(segment
		(start 46.331886 -408.196288)
		(end 46.331886 -403.795484)
		(width 0.11684)
		(layer "In4.Cu")
		(net "GPU_PRSNT")
	)
	(segment
		(start 46.7868 -425.45)
		(end 46.16323 -425.45)
		(width 0.11684)
		(layer "In4.Cu")
		(net "GPU_PRSNT")
	)
	(segment
		(start 44.54017 -409.988004)
		(end 46.331886 -408.196288)
		(width 0.11684)
		(layer "In4.Cu")
		(net "GPU_PRSNT")
	)
	(segment
		(start 98.020378 -403.364192)
		(end 100.942902 -403.364192)
		(width 0.11684)
		(layer "In4.Cu")
		(net "GPU_PRSNT")
	)
	(segment
		(start 46.16323 -425.45)
		(end 44.54017 -423.82694)
		(width 0.11684)
		(layer "In4.Cu")
		(net "GPU_PRSNT")
	)
	(segment
		(start 47.011336 -429.764952)
		(end 47.752 -429.024288)
		(width 0.11684)
		(layer "In4.Cu")
		(net "GPU_PRSNT")
	)
	(segment
		(start 50.280824 -399.846546)
		(end 94.502732 -399.846546)
		(width 0.11684)
		(layer "In4.Cu")
		(net "GPU_PRSNT")
	)
	(segment
		(start 44.54017 -423.82694)
		(end 44.54017 -409.988004)
		(width 0.11684)
		(layer "In4.Cu")
		(net "GPU_PRSNT")
	)
	(segment
		(start 47.752 -429.024288)
		(end 47.752 -426.4152)
		(width 0.11684)
		(layer "In4.Cu")
		(net "GPU_PRSNT")
	)
	(segment
		(start 46.331886 -403.795484)
		(end 50.280824 -399.846546)
		(width 0.11684)
		(layer "In4.Cu")
		(net "GPU_PRSNT")
	)
	(segment
		(start 100.942902 -403.364192)
		(end 102.363016 -401.944078)
		(width 0.11684)
		(layer "In4.Cu")
		(net "GPU_PRSNT")
	)
	(segment
		(start 184.312052 -426.806614)
		(end 184.310528 -426.80509)
		(width 0.10668)
		(layer "F.Cu")
		(net "GPU_PEX_STRAP1")
	)
	(segment
		(start 184.829958 -427.971966)
		(end 184.312052 -427.45406)
		(width 0.10668)
		(layer "F.Cu")
		(net "GPU_PEX_STRAP1")
	)
	(segment
		(start 185.027316 -427.971966)
		(end 184.829958 -427.971966)
		(width 0.10668)
		(layer "F.Cu")
		(net "GPU_PEX_STRAP1")
	)
	(segment
		(start 184.312052 -427.45406)
		(end 184.312052 -426.806614)
		(width 0.10668)
		(layer "F.Cu")
		(net "GPU_PEX_STRAP1")
	)
	(via
		(at 102.403402 -401.156678)
		(size 0.508)
		(drill 0.254)
		(layers "F.Cu" "B.Cu")
		(net "GPU_PEX_STRAP1")
	)
	(via
		(at 92.835222 -420.397178)
		(size 0.508)
		(drill 0.254)
		(layers "F.Cu" "B.Cu")
		(net "GPU_PEX_STRAP1")
	)
	(via
		(at 167.933624 -413.139128)
		(size 0.508)
		(drill 0.254)
		(layers "F.Cu" "B.Cu")
		(net "GPU_PEX_STRAP1")
	)
	(via
		(at 184.312052 -427.45406)
		(size 0.508)
		(drill 0.254)
		(layers "F.Cu" "B.Cu")
		(net "GPU_PEX_STRAP1")
	)
	(segment
		(start 74.837544 -424.335702)
		(end 74.837544 -439.677302)
		(width 0.10668)
		(layer "B.Cu")
		(net "GPU_PEX_STRAP1")
	)
	(segment
		(start 78.776068 -420.397178)
		(end 74.837544 -424.335702)
		(width 0.10668)
		(layer "B.Cu")
		(net "GPU_PEX_STRAP1")
	)
	(segment
		(start 74.837544 -439.677302)
		(end 75.65009 -440.489848)
		(width 0.10668)
		(layer "B.Cu")
		(net "GPU_PEX_STRAP1")
	)
	(segment
		(start 92.835222 -420.397178)
		(end 78.776068 -420.397178)
		(width 0.10668)
		(layer "B.Cu")
		(net "GPU_PEX_STRAP1")
	)
	(segment
		(start 167.646096 -412.8516)
		(end 167.933624 -413.139128)
		(width 0.11684)
		(layer "In2.Cu")
		(net "GPU_PEX_STRAP1")
	)
	(segment
		(start 167.646096 -410.650436)
		(end 167.646096 -412.8516)
		(width 0.11684)
		(layer "In2.Cu")
		(net "GPU_PEX_STRAP1")
	)
	(segment
		(start 165.085014 -408.089354)
		(end 167.646096 -410.650436)
		(width 0.11684)
		(layer "In2.Cu")
		(net "GPU_PEX_STRAP1")
	)
	(segment
		(start 165.085014 -404.302976)
		(end 165.085014 -408.089354)
		(width 0.11684)
		(layer "In2.Cu")
		(net "GPU_PEX_STRAP1")
	)
	(segment
		(start 163.800282 -403.018244)
		(end 165.085014 -404.302976)
		(width 0.11684)
		(layer "In2.Cu")
		(net "GPU_PEX_STRAP1")
	)
	(segment
		(start 104.264968 -403.018244)
		(end 163.800282 -403.018244)
		(width 0.11684)
		(layer "In2.Cu")
		(net "GPU_PEX_STRAP1")
	)
	(segment
		(start 102.403402 -401.156678)
		(end 104.264968 -403.018244)
		(width 0.11684)
		(layer "In2.Cu")
		(net "GPU_PEX_STRAP1")
	)
	(segment
		(start 167.933624 -413.139128)
		(end 167.933624 -413.531304)
		(width 0.11684)
		(layer "In4.Cu")
		(net "GPU_PEX_STRAP1")
	)
	(segment
		(start 178.860958 -421.49268)
		(end 184.312052 -426.944282)
		(width 0.11684)
		(layer "In4.Cu")
		(net "GPU_PEX_STRAP1")
	)
	(segment
		(start 170.708828 -418.810186)
		(end 171.030646 -419.132004)
		(width 0.11684)
		(layer "In4.Cu")
		(net "GPU_PEX_STRAP1")
	)
	(segment
		(start 171.030646 -419.132004)
		(end 173.262798 -419.132004)
		(width 0.11684)
		(layer "In4.Cu")
		(net "GPU_PEX_STRAP1")
	)
	(segment
		(start 184.312052 -426.944282)
		(end 184.312052 -427.45406)
		(width 0.11684)
		(layer "In4.Cu")
		(net "GPU_PEX_STRAP1")
	)
	(segment
		(start 175.623474 -421.49268)
		(end 178.860958 -421.49268)
		(width 0.11684)
		(layer "In4.Cu")
		(net "GPU_PEX_STRAP1")
	)
	(segment
		(start 170.708828 -416.306508)
		(end 170.708828 -418.810186)
		(width 0.11684)
		(layer "In4.Cu")
		(net "GPU_PEX_STRAP1")
	)
	(segment
		(start 167.933624 -413.531304)
		(end 170.708828 -416.306508)
		(width 0.11684)
		(layer "In4.Cu")
		(net "GPU_PEX_STRAP1")
	)
	(segment
		(start 173.262798 -419.132004)
		(end 175.623474 -421.49268)
		(width 0.11684)
		(layer "In4.Cu")
		(net "GPU_PEX_STRAP1")
	)
	(segment
		(start 101.084634 -408.570176)
		(end 101.924358 -409.4099)
		(width 0.11684)
		(layer "In13.Cu")
		(net "GPU_PEX_STRAP1")
	)
	(segment
		(start 103.30942 -411.083252)
		(end 104.541828 -412.31566)
		(width 0.11684)
		(layer "In13.Cu")
		(net "GPU_PEX_STRAP1")
	)
	(segment
		(start 92.835222 -426.470064)
		(end 92.835222 -420.397178)
		(width 0.11684)
		(layer "In13.Cu")
		(net "GPU_PEX_STRAP1")
	)
	(segment
		(start 102.703122 -411.083252)
		(end 103.30942 -411.083252)
		(width 0.11684)
		(layer "In13.Cu")
		(net "GPU_PEX_STRAP1")
	)
	(segment
		(start 101.36505 -402.19503)
		(end 101.36505 -405.86533)
		(width 0.11684)
		(layer "In13.Cu")
		(net "GPU_PEX_STRAP1")
	)
	(segment
		(start 101.924358 -409.4099)
		(end 101.924358 -410.304488)
		(width 0.11684)
		(layer "In13.Cu")
		(net "GPU_PEX_STRAP1")
	)
	(segment
		(start 102.403402 -401.156678)
		(end 101.36505 -402.19503)
		(width 0.11684)
		(layer "In13.Cu")
		(net "GPU_PEX_STRAP1")
	)
	(segment
		(start 104.881172 -423.731944)
		(end 104.881172 -424.792394)
		(width 0.11684)
		(layer "In13.Cu")
		(net "GPU_PEX_STRAP1")
	)
	(segment
		(start 104.541828 -417.2966)
		(end 105.11282 -417.867592)
		(width 0.11684)
		(layer "In13.Cu")
		(net "GPU_PEX_STRAP1")
	)
	(segment
		(start 100.869496 -428.80407)
		(end 95.169228 -428.80407)
		(width 0.11684)
		(layer "In13.Cu")
		(net "GPU_PEX_STRAP1")
	)
	(segment
		(start 104.881172 -424.792394)
		(end 100.869496 -428.80407)
		(width 0.11684)
		(layer "In13.Cu")
		(net "GPU_PEX_STRAP1")
	)
	(segment
		(start 104.541828 -412.31566)
		(end 104.541828 -417.2966)
		(width 0.11684)
		(layer "In13.Cu")
		(net "GPU_PEX_STRAP1")
	)
	(segment
		(start 105.11282 -423.500296)
		(end 104.881172 -423.731944)
		(width 0.11684)
		(layer "In13.Cu")
		(net "GPU_PEX_STRAP1")
	)
	(segment
		(start 101.36505 -405.86533)
		(end 101.084634 -406.145746)
		(width 0.11684)
		(layer "In13.Cu")
		(net "GPU_PEX_STRAP1")
	)
	(segment
		(start 105.11282 -417.867592)
		(end 105.11282 -423.500296)
		(width 0.11684)
		(layer "In13.Cu")
		(net "GPU_PEX_STRAP1")
	)
	(segment
		(start 101.924358 -410.304488)
		(end 102.703122 -411.083252)
		(width 0.11684)
		(layer "In13.Cu")
		(net "GPU_PEX_STRAP1")
	)
	(segment
		(start 101.084634 -406.145746)
		(end 101.084634 -408.570176)
		(width 0.11684)
		(layer "In13.Cu")
		(net "GPU_PEX_STRAP1")
	)
	(segment
		(start 95.169228 -428.80407)
		(end 92.835222 -426.470064)
		(width 0.11684)
		(layer "In13.Cu")
		(net "GPU_PEX_STRAP1")
	)
	(segment
		(start 185.322464 -426.805344)
		(end 185.322464 -427.271434)
		(width 0.10668)
		(layer "F.Cu")
		(net "GPU_PEX_STRAP0")
	)
	(segment
		(start 185.322464 -427.271434)
		(end 185.508138 -427.457108)
		(width 0.10668)
		(layer "F.Cu")
		(net "GPU_PEX_STRAP0")
	)
	(segment
		(start 185.508138 -427.457108)
		(end 186.038236 -427.987206)
		(width 0.10668)
		(layer "F.Cu")
		(net "GPU_PEX_STRAP0")
	)
	(segment
		(start 186.038236 -427.987206)
		(end 186.038236 -428.014892)
		(width 0.10668)
		(layer "F.Cu")
		(net "GPU_PEX_STRAP0")
	)
	(via
		(at 185.508138 -427.457108)
		(size 0.508)
		(drill 0.254)
		(layers "F.Cu" "B.Cu")
		(net "GPU_PEX_STRAP0")
	)
	(via
		(at 102.576376 -423.105326)
		(size 0.508)
		(drill 0.254)
		(layers "F.Cu" "B.Cu")
		(net "GPU_PEX_STRAP0")
	)
	(segment
		(start 98.01352 -422.521126)
		(end 101.992176 -422.521126)
		(width 0.11684)
		(layer "In2.Cu")
		(net "GPU_PEX_STRAP0")
	)
	(segment
		(start 153.60904 -415.261552)
		(end 161.707068 -415.261552)
		(width 0.11684)
		(layer "In2.Cu")
		(net "GPU_PEX_STRAP0")
	)
	(segment
		(start 181.815486 -423.764456)
		(end 185.508138 -427.457108)
		(width 0.11684)
		(layer "In2.Cu")
		(net "GPU_PEX_STRAP0")
	)
	(segment
		(start 117.20449 -416.298888)
		(end 152.571704 -416.298888)
		(width 0.11684)
		(layer "In2.Cu")
		(net "GPU_PEX_STRAP0")
	)
	(segment
		(start 103.160576 -422.521126)
		(end 104.861614 -422.521126)
		(width 0.11684)
		(layer "In2.Cu")
		(net "GPU_PEX_STRAP0")
	)
	(segment
		(start 181.815486 -419.237668)
		(end 181.815486 -423.764456)
		(width 0.11684)
		(layer "In2.Cu")
		(net "GPU_PEX_STRAP0")
	)
	(segment
		(start 178.553364 -415.975546)
		(end 181.815486 -419.237668)
		(width 0.11684)
		(layer "In2.Cu")
		(net "GPU_PEX_STRAP0")
	)
	(segment
		(start 83.650074 -440.489848)
		(end 84.795614 -439.344308)
		(width 0.11684)
		(layer "In2.Cu")
		(net "GPU_PEX_STRAP0")
	)
	(segment
		(start 102.576376 -423.105326)
		(end 103.160576 -422.521126)
		(width 0.11684)
		(layer "In2.Cu")
		(net "GPU_PEX_STRAP0")
	)
	(segment
		(start 96.416876 -423.328084)
		(end 97.206562 -423.328084)
		(width 0.11684)
		(layer "In2.Cu")
		(net "GPU_PEX_STRAP0")
	)
	(segment
		(start 91.785694 -424.593766)
		(end 95.151194 -424.593766)
		(width 0.11684)
		(layer "In2.Cu")
		(net "GPU_PEX_STRAP0")
	)
	(segment
		(start 162.454844 -416.009328)
		(end 166.720774 -416.009328)
		(width 0.11684)
		(layer "In2.Cu")
		(net "GPU_PEX_STRAP0")
	)
	(segment
		(start 115.541298 -417.96208)
		(end 117.20449 -416.298888)
		(width 0.11684)
		(layer "In2.Cu")
		(net "GPU_PEX_STRAP0")
	)
	(segment
		(start 176.439576 -415.454846)
		(end 176.960276 -415.975546)
		(width 0.11684)
		(layer "In2.Cu")
		(net "GPU_PEX_STRAP0")
	)
	(segment
		(start 107.860846 -417.96208)
		(end 115.541298 -417.96208)
		(width 0.11684)
		(layer "In2.Cu")
		(net "GPU_PEX_STRAP0")
	)
	(segment
		(start 104.861614 -422.521126)
		(end 106.417618 -420.965122)
		(width 0.11684)
		(layer "In2.Cu")
		(net "GPU_PEX_STRAP0")
	)
	(segment
		(start 106.417618 -419.405308)
		(end 107.860846 -417.96208)
		(width 0.11684)
		(layer "In2.Cu")
		(net "GPU_PEX_STRAP0")
	)
	(segment
		(start 84.795614 -439.344308)
		(end 84.795614 -424.74007)
		(width 0.11684)
		(layer "In2.Cu")
		(net "GPU_PEX_STRAP0")
	)
	(segment
		(start 170.571414 -415.454846)
		(end 176.439576 -415.454846)
		(width 0.11684)
		(layer "In2.Cu")
		(net "GPU_PEX_STRAP0")
	)
	(segment
		(start 176.960276 -415.975546)
		(end 178.553364 -415.975546)
		(width 0.11684)
		(layer "In2.Cu")
		(net "GPU_PEX_STRAP0")
	)
	(segment
		(start 161.707068 -415.261552)
		(end 162.454844 -416.009328)
		(width 0.11684)
		(layer "In2.Cu")
		(net "GPU_PEX_STRAP0")
	)
	(segment
		(start 85.414612 -424.121072)
		(end 91.313 -424.121072)
		(width 0.11684)
		(layer "In2.Cu")
		(net "GPU_PEX_STRAP0")
	)
	(segment
		(start 106.417618 -420.965122)
		(end 106.417618 -419.405308)
		(width 0.11684)
		(layer "In2.Cu")
		(net "GPU_PEX_STRAP0")
	)
	(segment
		(start 166.720774 -416.009328)
		(end 167.271192 -416.559746)
		(width 0.11684)
		(layer "In2.Cu")
		(net "GPU_PEX_STRAP0")
	)
	(segment
		(start 167.271192 -416.559746)
		(end 169.466514 -416.559746)
		(width 0.11684)
		(layer "In2.Cu")
		(net "GPU_PEX_STRAP0")
	)
	(segment
		(start 169.466514 -416.559746)
		(end 170.571414 -415.454846)
		(width 0.11684)
		(layer "In2.Cu")
		(net "GPU_PEX_STRAP0")
	)
	(segment
		(start 97.206562 -423.328084)
		(end 98.01352 -422.521126)
		(width 0.11684)
		(layer "In2.Cu")
		(net "GPU_PEX_STRAP0")
	)
	(segment
		(start 95.151194 -424.593766)
		(end 96.416876 -423.328084)
		(width 0.11684)
		(layer "In2.Cu")
		(net "GPU_PEX_STRAP0")
	)
	(segment
		(start 84.795614 -424.74007)
		(end 85.414612 -424.121072)
		(width 0.11684)
		(layer "In2.Cu")
		(net "GPU_PEX_STRAP0")
	)
	(segment
		(start 91.313 -424.121072)
		(end 91.785694 -424.593766)
		(width 0.11684)
		(layer "In2.Cu")
		(net "GPU_PEX_STRAP0")
	)
	(segment
		(start 152.571704 -416.298888)
		(end 153.60904 -415.261552)
		(width 0.11684)
		(layer "In2.Cu")
		(net "GPU_PEX_STRAP0")
	)
	(segment
		(start 101.992176 -422.521126)
		(end 102.576376 -423.105326)
		(width 0.11684)
		(layer "In2.Cu")
		(net "GPU_PEX_STRAP0")
	)
	(segment
		(start 105.59796 -422.21404)
		(end 104.535986 -422.21404)
		(width 0.10668)
		(layer "F.Cu")
		(net "GPU_NVS_PWR_BRAKE_N_R")
	)
	(segment
		(start 105.93705 -421.87495)
		(end 105.918 -421.894)
		(width 0.10668)
		(layer "F.Cu")
		(net "GPU_NVS_PWR_BRAKE_N_R")
	)
	(segment
		(start 105.918 -421.894)
		(end 105.59796 -422.21404)
		(width 0.10668)
		(layer "F.Cu")
		(net "GPU_NVS_PWR_BRAKE_N_R")
	)
	(segment
		(start 105.93705 -419.989)
		(end 105.93705 -418.973)
		(width 0.10668)
		(layer "F.Cu")
		(net "GPU_NVS_PWR_BRAKE_N_R")
	)
	(segment
		(start 105.93705 -421.005)
		(end 105.93705 -421.87495)
		(width 0.10668)
		(layer "F.Cu")
		(net "GPU_NVS_PWR_BRAKE_N_R")
	)
	(segment
		(start 105.93705 -421.005)
		(end 105.93705 -419.989)
		(width 0.10668)
		(layer "F.Cu")
		(net "GPU_NVS_PWR_BRAKE_N_R")
	)
	(via
		(at 105.918 -421.894)
		(size 0.762)
		(drill 0.381)
		(layers "F.Cu" "B.Cu")
		(net "GPU_NVS_PWR_BRAKE_N_R")
	)
	(segment
		(start 105.13695 -418.973)
		(end 105.13695 -418.871908)
		(width 0.10668)
		(layer "F.Cu")
		(net "GPU_NVS_PWR_BRAKE_N_BUF")
	)
	(segment
		(start 105.13695 -418.871908)
		(end 104.648 -418.382958)
		(width 0.10668)
		(layer "F.Cu")
		(net "GPU_NVS_PWR_BRAKE_N_BUF")
	)
	(via
		(at 104.648 -418.382958)
		(size 0.508)
		(drill 0.254)
		(layers "F.Cu" "B.Cu")
		(net "GPU_NVS_PWR_BRAKE_N_BUF")
	)
	(segment
		(start 71.049896 -414.069022)
		(end 70.624446 -414.494472)
		(width 0.11684)
		(layer "In4.Cu")
		(net "GPU_NVS_PWR_BRAKE_N_BUF")
	)
	(segment
		(start 70.624446 -414.494472)
		(end 66.23939 -414.494472)
		(width 0.11684)
		(layer "In4.Cu")
		(net "GPU_NVS_PWR_BRAKE_N_BUF")
	)
	(segment
		(start 104.648 -418.382958)
		(end 103.71582 -418.382958)
		(width 0.11684)
		(layer "In4.Cu")
		(net "GPU_NVS_PWR_BRAKE_N_BUF")
	)
	(segment
		(start 66.23939 -414.494472)
		(end 64.649858 -416.084004)
		(width 0.11684)
		(layer "In4.Cu")
		(net "GPU_NVS_PWR_BRAKE_N_BUF")
	)
	(segment
		(start 89.742264 -414.069022)
		(end 71.049896 -414.069022)
		(width 0.11684)
		(layer "In4.Cu")
		(net "GPU_NVS_PWR_BRAKE_N_BUF")
	)
	(segment
		(start 103.71582 -418.382958)
		(end 103.525066 -418.573712)
		(width 0.11684)
		(layer "In4.Cu")
		(net "GPU_NVS_PWR_BRAKE_N_BUF")
	)
	(segment
		(start 103.525066 -418.573712)
		(end 103.525066 -420.570914)
		(width 0.11684)
		(layer "In4.Cu")
		(net "GPU_NVS_PWR_BRAKE_N_BUF")
	)
	(segment
		(start 102.758494 -421.337486)
		(end 97.010728 -421.337486)
		(width 0.11684)
		(layer "In4.Cu")
		(net "GPU_NVS_PWR_BRAKE_N_BUF")
	)
	(segment
		(start 103.525066 -420.570914)
		(end 102.758494 -421.337486)
		(width 0.11684)
		(layer "In4.Cu")
		(net "GPU_NVS_PWR_BRAKE_N_BUF")
	)
	(segment
		(start 97.010728 -421.337486)
		(end 89.742264 -414.069022)
		(width 0.11684)
		(layer "In4.Cu")
		(net "GPU_NVS_PWR_BRAKE_N_BUF")
	)
	(segment
		(start 64.649858 -416.084004)
		(end 64.649858 -417.489894)
		(width 0.11684)
		(layer "In4.Cu")
		(net "GPU_NVS_PWR_BRAKE_N_BUF")
	)
	(segment
		(start 196.977 -99.894898)
		(end 196.948552 -99.86645)
		(width 0.10668)
		(layer "F.Cu")
		(net "GPU_NVS_PWR_BRAKE_N")
	)
	(segment
		(start 104.535986 -424.11396)
		(end 104.535986 -425.699936)
		(width 0.10668)
		(layer "F.Cu")
		(net "GPU_NVS_PWR_BRAKE_N")
	)
	(segment
		(start 213.16823 -173.10989)
		(end 213.202012 -173.143672)
		(width 0.10668)
		(layer "F.Cu")
		(net "GPU_NVS_PWR_BRAKE_N")
	)
	(segment
		(start 218.478608 -199.165718)
		(end 219.485464 -200.172574)
		(width 0.10668)
		(layer "F.Cu")
		(net "GPU_NVS_PWR_BRAKE_N")
	)
	(segment
		(start 105.918 -426.06595)
		(end 105.918 -425.45)
		(width 0.10668)
		(layer "F.Cu")
		(net "GPU_NVS_PWR_BRAKE_N")
	)
	(segment
		(start 218.478608 -185.880756)
		(end 218.478608 -199.165718)
		(width 0.10668)
		(layer "F.Cu")
		(net "GPU_NVS_PWR_BRAKE_N")
	)
	(segment
		(start 219.485464 -200.172574)
		(end 219.828364 -200.172574)
		(width 0.10668)
		(layer "F.Cu")
		(net "GPU_NVS_PWR_BRAKE_N")
	)
	(segment
		(start 104.535986 -425.699936)
		(end 104.902 -426.06595)
		(width 0.10668)
		(layer "F.Cu")
		(net "GPU_NVS_PWR_BRAKE_N")
	)
	(segment
		(start 213.202012 -173.143672)
		(end 218.478608 -185.880756)
		(width 0.10668)
		(layer "F.Cu")
		(net "GPU_NVS_PWR_BRAKE_N")
	)
	(segment
		(start 212.697314 -169.17924)
		(end 213.16823 -169.650156)
		(width 0.10668)
		(layer "F.Cu")
		(net "GPU_NVS_PWR_BRAKE_N")
	)
	(segment
		(start 213.16823 -169.650156)
		(end 213.16823 -173.10989)
		(width 0.10668)
		(layer "F.Cu")
		(net "GPU_NVS_PWR_BRAKE_N")
	)
	(segment
		(start 212.697314 -167.59428)
		(end 212.697314 -169.17924)
		(width 0.10668)
		(layer "F.Cu")
		(net "GPU_NVS_PWR_BRAKE_N")
	)
	(segment
		(start 104.902 -426.06595)
		(end 105.918 -426.06595)
		(width 0.10668)
		(layer "F.Cu")
		(net "GPU_NVS_PWR_BRAKE_N")
	)
	(segment
		(start 196.948552 -99.86645)
		(end 196.948552 -99.278948)
		(width 0.10668)
		(layer "F.Cu")
		(net "GPU_NVS_PWR_BRAKE_N")
	)
	(via
		(at 219.828364 -200.172574)
		(size 0.508)
		(drill 0.254)
		(layers "F.Cu" "B.Cu")
		(net "GPU_NVS_PWR_BRAKE_N")
	)
	(via
		(at 105.918 -425.45)
		(size 0.508)
		(drill 0.254)
		(layers "F.Cu" "B.Cu")
		(net "GPU_NVS_PWR_BRAKE_N")
	)
	(via
		(at 169.31894 -399.18132)
		(size 0.508)
		(drill 0.254)
		(layers "F.Cu" "B.Cu")
		(net "GPU_NVS_PWR_BRAKE_N")
	)
	(via
		(at 196.948552 -99.278948)
		(size 0.508)
		(drill 0.254)
		(layers "F.Cu" "B.Cu")
		(net "GPU_NVS_PWR_BRAKE_N")
	)
	(via
		(at 221.189804 -107.549442)
		(size 0.508)
		(drill 0.254)
		(layers "F.Cu" "B.Cu")
		(net "GPU_NVS_PWR_BRAKE_N")
	)
	(via
		(at 212.697314 -167.59428)
		(size 0.508)
		(drill 0.254)
		(layers "F.Cu" "B.Cu")
		(net "GPU_NVS_PWR_BRAKE_N")
	)
	(via
		(at 170.451272 -419.307772)
		(size 0.508)
		(drill 0.254)
		(layers "F.Cu" "B.Cu")
		(net "GPU_NVS_PWR_BRAKE_N")
	)
	(segment
		(start 117.743224 -421.081454)
		(end 117.149626 -421.081454)
		(width 0.11684)
		(layer "In2.Cu")
		(net "GPU_NVS_PWR_BRAKE_N")
	)
	(segment
		(start 210.876642 -100.673916)
		(end 208.207102 -98.004376)
		(width 0.11684)
		(layer "In2.Cu")
		(net "GPU_NVS_PWR_BRAKE_N")
	)
	(segment
		(start 169.620692 -419.307772)
		(end 169.27068 -418.95776)
		(width 0.11684)
		(layer "In2.Cu")
		(net "GPU_NVS_PWR_BRAKE_N")
	)
	(segment
		(start 162.616134 -419.582854)
		(end 161.200338 -418.167058)
		(width 0.11684)
		(layer "In2.Cu")
		(net "GPU_NVS_PWR_BRAKE_N")
	)
	(segment
		(start 115.974114 -420.476172)
		(end 109.187488 -420.476172)
		(width 0.11684)
		(layer "In2.Cu")
		(net "GPU_NVS_PWR_BRAKE_N")
	)
	(segment
		(start 107.24388 -422.41978)
		(end 107.24388 -424.12412)
		(width 0.11684)
		(layer "In2.Cu")
		(net "GPU_NVS_PWR_BRAKE_N")
	)
	(segment
		(start 167.879014 -419.347904)
		(end 165.780466 -419.347904)
		(width 0.11684)
		(layer "In2.Cu")
		(net "GPU_NVS_PWR_BRAKE_N")
	)
	(segment
		(start 221.189804 -105.401872)
		(end 216.990168 -101.202236)
		(width 0.11684)
		(layer "In2.Cu")
		(net "GPU_NVS_PWR_BRAKE_N")
	)
	(segment
		(start 116.835428 -420.767256)
		(end 116.265198 -420.767256)
		(width 0.11684)
		(layer "In2.Cu")
		(net "GPU_NVS_PWR_BRAKE_N")
	)
	(segment
		(start 205.04023 -98.004376)
		(end 204.038962 -99.005644)
		(width 0.11684)
		(layer "In2.Cu")
		(net "GPU_NVS_PWR_BRAKE_N")
	)
	(segment
		(start 163.721288 -419.74008)
		(end 163.564062 -419.582854)
		(width 0.11684)
		(layer "In2.Cu")
		(net "GPU_NVS_PWR_BRAKE_N")
	)
	(segment
		(start 203.611734 -99.005644)
		(end 203.172568 -98.566478)
		(width 0.11684)
		(layer "In2.Cu")
		(net "GPU_NVS_PWR_BRAKE_N")
	)
	(segment
		(start 221.189804 -107.549442)
		(end 221.189804 -105.401872)
		(width 0.11684)
		(layer "In2.Cu")
		(net "GPU_NVS_PWR_BRAKE_N")
	)
	(segment
		(start 117.952774 -420.871904)
		(end 117.743224 -421.081454)
		(width 0.11684)
		(layer "In2.Cu")
		(net "GPU_NVS_PWR_BRAKE_N")
	)
	(segment
		(start 163.564062 -419.582854)
		(end 162.616134 -419.582854)
		(width 0.11684)
		(layer "In2.Cu")
		(net "GPU_NVS_PWR_BRAKE_N")
	)
	(segment
		(start 204.038962 -99.005644)
		(end 203.611734 -99.005644)
		(width 0.11684)
		(layer "In2.Cu")
		(net "GPU_NVS_PWR_BRAKE_N")
	)
	(segment
		(start 213.889844 -101.202236)
		(end 213.361524 -100.673916)
		(width 0.11684)
		(layer "In2.Cu")
		(net "GPU_NVS_PWR_BRAKE_N")
	)
	(segment
		(start 122.718068 -418.167058)
		(end 120.013222 -420.871904)
		(width 0.11684)
		(layer "In2.Cu")
		(net "GPU_NVS_PWR_BRAKE_N")
	)
	(segment
		(start 208.207102 -98.004376)
		(end 205.04023 -98.004376)
		(width 0.11684)
		(layer "In2.Cu")
		(net "GPU_NVS_PWR_BRAKE_N")
	)
	(segment
		(start 169.27068 -418.95776)
		(end 168.269158 -418.95776)
		(width 0.11684)
		(layer "In2.Cu")
		(net "GPU_NVS_PWR_BRAKE_N")
	)
	(segment
		(start 213.361524 -100.673916)
		(end 210.876642 -100.673916)
		(width 0.11684)
		(layer "In2.Cu")
		(net "GPU_NVS_PWR_BRAKE_N")
	)
	(segment
		(start 117.149626 -421.081454)
		(end 116.835428 -420.767256)
		(width 0.11684)
		(layer "In2.Cu")
		(net "GPU_NVS_PWR_BRAKE_N")
	)
	(segment
		(start 165.780466 -419.347904)
		(end 165.38829 -419.74008)
		(width 0.11684)
		(layer "In2.Cu")
		(net "GPU_NVS_PWR_BRAKE_N")
	)
	(segment
		(start 116.265198 -420.767256)
		(end 115.974114 -420.476172)
		(width 0.11684)
		(layer "In2.Cu")
		(net "GPU_NVS_PWR_BRAKE_N")
	)
	(segment
		(start 197.661022 -98.566478)
		(end 196.948552 -99.278948)
		(width 0.11684)
		(layer "In2.Cu")
		(net "GPU_NVS_PWR_BRAKE_N")
	)
	(segment
		(start 168.269158 -418.95776)
		(end 167.879014 -419.347904)
		(width 0.11684)
		(layer "In2.Cu")
		(net "GPU_NVS_PWR_BRAKE_N")
	)
	(segment
		(start 170.451272 -419.307772)
		(end 169.620692 -419.307772)
		(width 0.11684)
		(layer "In2.Cu")
		(net "GPU_NVS_PWR_BRAKE_N")
	)
	(segment
		(start 216.990168 -101.202236)
		(end 213.889844 -101.202236)
		(width 0.11684)
		(layer "In2.Cu")
		(net "GPU_NVS_PWR_BRAKE_N")
	)
	(segment
		(start 165.38829 -419.74008)
		(end 163.721288 -419.74008)
		(width 0.11684)
		(layer "In2.Cu")
		(net "GPU_NVS_PWR_BRAKE_N")
	)
	(segment
		(start 107.24388 -424.12412)
		(end 105.918 -425.45)
		(width 0.11684)
		(layer "In2.Cu")
		(net "GPU_NVS_PWR_BRAKE_N")
	)
	(segment
		(start 109.187488 -420.476172)
		(end 107.24388 -422.41978)
		(width 0.11684)
		(layer "In2.Cu")
		(net "GPU_NVS_PWR_BRAKE_N")
	)
	(segment
		(start 161.200338 -418.167058)
		(end 122.718068 -418.167058)
		(width 0.11684)
		(layer "In2.Cu")
		(net "GPU_NVS_PWR_BRAKE_N")
	)
	(segment
		(start 203.172568 -98.566478)
		(end 197.661022 -98.566478)
		(width 0.11684)
		(layer "In2.Cu")
		(net "GPU_NVS_PWR_BRAKE_N")
	)
	(segment
		(start 120.013222 -420.871904)
		(end 117.952774 -420.871904)
		(width 0.11684)
		(layer "In2.Cu")
		(net "GPU_NVS_PWR_BRAKE_N")
	)
	(segment
		(start 212.779102 -167.512492)
		(end 212.697314 -167.59428)
		(width 0.11684)
		(layer "In4.Cu")
		(net "GPU_NVS_PWR_BRAKE_N")
	)
	(segment
		(start 221.831408 -107.996736)
		(end 221.831408 -113.046764)
		(width 0.11684)
		(layer "In4.Cu")
		(net "GPU_NVS_PWR_BRAKE_N")
	)
	(segment
		(start 215.00084 -167.512492)
		(end 212.779102 -167.512492)
		(width 0.11684)
		(layer "In4.Cu")
		(net "GPU_NVS_PWR_BRAKE_N")
	)
	(segment
		(start 221.352618 -113.525554)
		(end 221.352618 -135.458454)
		(width 0.11684)
		(layer "In4.Cu")
		(net "GPU_NVS_PWR_BRAKE_N")
	)
	(segment
		(start 218.37269 -138.438382)
		(end 218.37269 -164.140642)
		(width 0.11684)
		(layer "In4.Cu")
		(net "GPU_NVS_PWR_BRAKE_N")
	)
	(segment
		(start 221.189804 -107.549442)
		(end 221.384114 -107.549442)
		(width 0.11684)
		(layer "In4.Cu")
		(net "GPU_NVS_PWR_BRAKE_N")
	)
	(segment
		(start 221.831408 -113.046764)
		(end 221.352618 -113.525554)
		(width 0.11684)
		(layer "In4.Cu")
		(net "GPU_NVS_PWR_BRAKE_N")
	)
	(segment
		(start 221.384114 -107.549442)
		(end 221.831408 -107.996736)
		(width 0.11684)
		(layer "In4.Cu")
		(net "GPU_NVS_PWR_BRAKE_N")
	)
	(segment
		(start 221.352618 -135.458454)
		(end 218.37269 -138.438382)
		(width 0.11684)
		(layer "In4.Cu")
		(net "GPU_NVS_PWR_BRAKE_N")
	)
	(segment
		(start 218.37269 -164.140642)
		(end 215.00084 -167.512492)
		(width 0.11684)
		(layer "In4.Cu")
		(net "GPU_NVS_PWR_BRAKE_N")
	)
	(segment
		(start 165.45433 -401.977352)
		(end 165.45433 -407.861008)
		(width 0.11684)
		(layer "In13.Cu")
		(net "GPU_NVS_PWR_BRAKE_N")
	)
	(segment
		(start 167.312848 -416.287712)
		(end 167.740838 -416.715702)
		(width 0.11684)
		(layer "In13.Cu")
		(net "GPU_NVS_PWR_BRAKE_N")
	)
	(segment
		(start 168.250362 -399.18132)
		(end 165.45433 -401.977352)
		(width 0.11684)
		(layer "In13.Cu")
		(net "GPU_NVS_PWR_BRAKE_N")
	)
	(segment
		(start 168.976294 -418.060378)
		(end 170.223688 -419.307772)
		(width 0.11684)
		(layer "In13.Cu")
		(net "GPU_NVS_PWR_BRAKE_N")
	)
	(segment
		(start 167.740838 -416.715702)
		(end 167.740838 -416.824922)
		(width 0.11684)
		(layer "In13.Cu")
		(net "GPU_NVS_PWR_BRAKE_N")
	)
	(segment
		(start 167.312848 -415.90214)
		(end 167.312848 -416.287712)
		(width 0.11684)
		(layer "In13.Cu")
		(net "GPU_NVS_PWR_BRAKE_N")
	)
	(segment
		(start 169.31894 -399.18132)
		(end 168.250362 -399.18132)
		(width 0.11684)
		(layer "In13.Cu")
		(net "GPU_NVS_PWR_BRAKE_N")
	)
	(segment
		(start 165.45433 -407.861008)
		(end 167.470328 -409.877006)
		(width 0.11684)
		(layer "In13.Cu")
		(net "GPU_NVS_PWR_BRAKE_N")
	)
	(segment
		(start 168.70426 -417.5633)
		(end 168.976294 -417.835334)
		(width 0.11684)
		(layer "In13.Cu")
		(net "GPU_NVS_PWR_BRAKE_N")
	)
	(segment
		(start 167.470328 -409.877006)
		(end 167.470328 -412.944818)
		(width 0.11684)
		(layer "In13.Cu")
		(net "GPU_NVS_PWR_BRAKE_N")
	)
	(segment
		(start 168.479216 -417.5633)
		(end 168.70426 -417.5633)
		(width 0.11684)
		(layer "In13.Cu")
		(net "GPU_NVS_PWR_BRAKE_N")
	)
	(segment
		(start 167.468804 -415.746184)
		(end 167.312848 -415.90214)
		(width 0.11684)
		(layer "In13.Cu")
		(net "GPU_NVS_PWR_BRAKE_N")
	)
	(segment
		(start 167.468804 -412.946342)
		(end 167.468804 -415.746184)
		(width 0.11684)
		(layer "In13.Cu")
		(net "GPU_NVS_PWR_BRAKE_N")
	)
	(segment
		(start 168.976294 -417.835334)
		(end 168.976294 -418.060378)
		(width 0.11684)
		(layer "In13.Cu")
		(net "GPU_NVS_PWR_BRAKE_N")
	)
	(segment
		(start 170.223688 -419.307772)
		(end 170.451272 -419.307772)
		(width 0.11684)
		(layer "In13.Cu")
		(net "GPU_NVS_PWR_BRAKE_N")
	)
	(segment
		(start 167.740838 -416.824922)
		(end 168.479216 -417.5633)
		(width 0.11684)
		(layer "In13.Cu")
		(net "GPU_NVS_PWR_BRAKE_N")
	)
	(segment
		(start 167.470328 -412.944818)
		(end 167.468804 -412.946342)
		(width 0.11684)
		(layer "In13.Cu")
		(net "GPU_NVS_PWR_BRAKE_N")
	)
	(segment
		(start 173.44009 -395.688312)
		(end 174.321724 -394.806678)
		(width 0.11684)
		(layer "In15.Cu")
		(net "GPU_NVS_PWR_BRAKE_N")
	)
	(segment
		(start 216.532206 -200.172574)
		(end 219.828364 -200.172574)
		(width 0.11684)
		(layer "In15.Cu")
		(net "GPU_NVS_PWR_BRAKE_N")
	)
	(segment
		(start 213.627462 -319.282318)
		(end 213.627462 -203.077318)
		(width 0.11684)
		(layer "In15.Cu")
		(net "GPU_NVS_PWR_BRAKE_N")
	)
	(segment
		(start 174.321724 -394.806678)
		(end 174.321724 -393.47394)
		(width 0.11684)
		(layer "In15.Cu")
		(net "GPU_NVS_PWR_BRAKE_N")
	)
	(segment
		(start 174.321724 -393.47394)
		(end 187.131706 -380.663958)
		(width 0.11684)
		(layer "In15.Cu")
		(net "GPU_NVS_PWR_BRAKE_N")
	)
	(segment
		(start 169.84726 -398.653)
		(end 172.795946 -398.653)
		(width 0.11684)
		(layer "In15.Cu")
		(net "GPU_NVS_PWR_BRAKE_N")
	)
	(segment
		(start 187.131706 -372.208044)
		(end 190.256922 -369.082828)
		(width 0.11684)
		(layer "In15.Cu")
		(net "GPU_NVS_PWR_BRAKE_N")
	)
	(segment
		(start 172.795946 -398.653)
		(end 173.44009 -398.008856)
		(width 0.11684)
		(layer "In15.Cu")
		(net "GPU_NVS_PWR_BRAKE_N")
	)
	(segment
		(start 190.256922 -369.082828)
		(end 193.505582 -369.082828)
		(width 0.11684)
		(layer "In15.Cu")
		(net "GPU_NVS_PWR_BRAKE_N")
	)
	(segment
		(start 169.31894 -399.18132)
		(end 169.84726 -398.653)
		(width 0.11684)
		(layer "In15.Cu")
		(net "GPU_NVS_PWR_BRAKE_N")
	)
	(segment
		(start 219.852494 -342.735916)
		(end 219.852494 -325.50735)
		(width 0.11684)
		(layer "In15.Cu")
		(net "GPU_NVS_PWR_BRAKE_N")
	)
	(segment
		(start 187.131706 -380.663958)
		(end 187.131706 -372.208044)
		(width 0.11684)
		(layer "In15.Cu")
		(net "GPU_NVS_PWR_BRAKE_N")
	)
	(segment
		(start 219.852494 -325.50735)
		(end 213.627462 -319.282318)
		(width 0.11684)
		(layer "In15.Cu")
		(net "GPU_NVS_PWR_BRAKE_N")
	)
	(segment
		(start 173.44009 -398.008856)
		(end 173.44009 -395.688312)
		(width 0.11684)
		(layer "In15.Cu")
		(net "GPU_NVS_PWR_BRAKE_N")
	)
	(segment
		(start 213.627462 -203.077318)
		(end 216.532206 -200.172574)
		(width 0.11684)
		(layer "In15.Cu")
		(net "GPU_NVS_PWR_BRAKE_N")
	)
	(segment
		(start 193.505582 -369.082828)
		(end 219.852494 -342.735916)
		(width 0.11684)
		(layer "In15.Cu")
		(net "GPU_NVS_PWR_BRAKE_N")
	)
	(segment
		(start 119.99595 -419.881304)
		(end 119.99595 -420.497)
		(width 0.10668)
		(layer "F.Cu")
		(net "GPU_HMC_PRSNT_N")
	)
	(segment
		(start 120.142 -419.28796)
		(end 120.142 -419.735254)
		(width 0.10668)
		(layer "F.Cu")
		(net "GPU_HMC_PRSNT_N")
	)
	(segment
		(start 119.99595 -421.513)
		(end 119.99595 -420.497)
		(width 0.10668)
		(layer "F.Cu")
		(net "GPU_HMC_PRSNT_N")
	)
	(segment
		(start 120.142 -419.735254)
		(end 119.99595 -419.881304)
		(width 0.10668)
		(layer "F.Cu")
		(net "GPU_HMC_PRSNT_N")
	)
	(segment
		(start 119.99595 -421.513)
		(end 119.99595 -422.00195)
		(width 0.10668)
		(layer "F.Cu")
		(net "GPU_HMC_PRSNT_N")
	)
	(segment
		(start 119.99595 -422.00195)
		(end 120.269 -422.275)
		(width 0.10668)
		(layer "F.Cu")
		(net "GPU_HMC_PRSNT_N")
	)
	(via
		(at 120.269 -422.275)
		(size 0.508)
		(drill 0.254)
		(layers "F.Cu" "B.Cu")
		(net "GPU_HMC_PRSNT_N")
	)
	(segment
		(start 128.893824 -439.633868)
		(end 129.749804 -440.489848)
		(width 0.10668)
		(layer "B.Cu")
		(net "GPU_HMC_PRSNT_N")
	)
	(segment
		(start 126.745746 -422.656)
		(end 128.893824 -424.804078)
		(width 0.10668)
		(layer "B.Cu")
		(net "GPU_HMC_PRSNT_N")
	)
	(segment
		(start 120.65 -422.656)
		(end 126.745746 -422.656)
		(width 0.10668)
		(layer "B.Cu")
		(net "GPU_HMC_PRSNT_N")
	)
	(segment
		(start 120.269 -422.275)
		(end 120.65 -422.656)
		(width 0.10668)
		(layer "B.Cu")
		(net "GPU_HMC_PRSNT_N")
	)
	(segment
		(start 128.893824 -424.804078)
		(end 128.893824 -439.633868)
		(width 0.10668)
		(layer "B.Cu")
		(net "GPU_HMC_PRSNT_N")
	)
	(segment
		(start 207.7466 -165.343586)
		(end 207.7466 -164.849048)
		(width 0.10668)
		(layer "F.Cu")
		(net "GPU_HMC_PRSNT_ISO_N")
	)
	(segment
		(start 217.173048 -200.408794)
		(end 217.173048 -186.43854)
		(width 0.10668)
		(layer "F.Cu")
		(net "GPU_HMC_PRSNT_ISO_N")
	)
	(segment
		(start 119.492014 -419.28796)
		(end 119.492014 -419.896036)
		(width 0.10668)
		(layer "F.Cu")
		(net "GPU_HMC_PRSNT_ISO_N")
	)
	(segment
		(start 208.923128 -166.520114)
		(end 207.7466 -165.343586)
		(width 0.10668)
		(layer "F.Cu")
		(net "GPU_HMC_PRSNT_ISO_N")
	)
	(segment
		(start 219.476828 -202.712574)
		(end 217.173048 -200.408794)
		(width 0.10668)
		(layer "F.Cu")
		(net "GPU_HMC_PRSNT_ISO_N")
	)
	(segment
		(start 118.89105 -421.513)
		(end 118.89105 -422.275)
		(width 0.10668)
		(layer "F.Cu")
		(net "GPU_HMC_PRSNT_ISO_N")
	)
	(segment
		(start 217.173048 -186.43854)
		(end 208.923128 -166.520114)
		(width 0.10668)
		(layer "F.Cu")
		(net "GPU_HMC_PRSNT_ISO_N")
	)
	(segment
		(start 118.89105 -421.513)
		(end 118.89105 -420.497)
		(width 0.10668)
		(layer "F.Cu")
		(net "GPU_HMC_PRSNT_ISO_N")
	)
	(segment
		(start 119.492014 -419.896036)
		(end 118.89105 -420.497)
		(width 0.10668)
		(layer "F.Cu")
		(net "GPU_HMC_PRSNT_ISO_N")
	)
	(segment
		(start 209.278982 -117.748812)
		(end 210.502754 -117.748812)
		(width 0.10668)
		(layer "F.Cu")
		(net "GPU_HMC_PRSNT_ISO_N")
	)
	(segment
		(start 219.828364 -202.712574)
		(end 219.476828 -202.712574)
		(width 0.10668)
		(layer "F.Cu")
		(net "GPU_HMC_PRSNT_ISO_N")
	)
	(via
		(at 118.89105 -422.275)
		(size 0.508)
		(drill 0.254)
		(layers "F.Cu" "B.Cu")
		(net "GPU_HMC_PRSNT_ISO_N")
	)
	(via
		(at 177.934112 -422.012872)
		(size 0.508)
		(drill 0.254)
		(layers "F.Cu" "B.Cu")
		(net "GPU_HMC_PRSNT_ISO_N")
	)
	(via
		(at 207.7466 -164.849048)
		(size 0.508)
		(drill 0.254)
		(layers "F.Cu" "B.Cu")
		(net "GPU_HMC_PRSNT_ISO_N")
	)
	(via
		(at 210.502754 -117.748812)
		(size 0.508)
		(drill 0.254)
		(layers "F.Cu" "B.Cu")
		(net "GPU_HMC_PRSNT_ISO_N")
	)
	(via
		(at 219.828364 -202.712574)
		(size 0.508)
		(drill 0.254)
		(layers "F.Cu" "B.Cu")
		(net "GPU_HMC_PRSNT_ISO_N")
	)
	(segment
		(start 118.89105 -422.275)
		(end 119.536718 -422.920668)
		(width 0.11684)
		(layer "In2.Cu")
		(net "GPU_HMC_PRSNT_ISO_N")
	)
	(segment
		(start 160.602676 -419.018466)
		(end 161.259266 -419.675056)
		(width 0.11684)
		(layer "In2.Cu")
		(net "GPU_HMC_PRSNT_ISO_N")
	)
	(segment
		(start 125.824488 -419.018466)
		(end 160.602676 -419.018466)
		(width 0.11684)
		(layer "In2.Cu")
		(net "GPU_HMC_PRSNT_ISO_N")
	)
	(segment
		(start 176.711864 -422.467024)
		(end 177.47996 -422.467024)
		(width 0.11684)
		(layer "In2.Cu")
		(net "GPU_HMC_PRSNT_ISO_N")
	)
	(segment
		(start 161.259266 -420.357554)
		(end 162.325812 -421.4241)
		(width 0.11684)
		(layer "In2.Cu")
		(net "GPU_HMC_PRSNT_ISO_N")
	)
	(segment
		(start 175.66894 -421.4241)
		(end 176.711864 -422.467024)
		(width 0.11684)
		(layer "In2.Cu")
		(net "GPU_HMC_PRSNT_ISO_N")
	)
	(segment
		(start 122.253756 -422.589198)
		(end 125.824488 -419.018466)
		(width 0.11684)
		(layer "In2.Cu")
		(net "GPU_HMC_PRSNT_ISO_N")
	)
	(segment
		(start 121.543572 -422.589198)
		(end 122.253756 -422.589198)
		(width 0.11684)
		(layer "In2.Cu")
		(net "GPU_HMC_PRSNT_ISO_N")
	)
	(segment
		(start 177.47996 -422.467024)
		(end 177.934112 -422.012872)
		(width 0.11684)
		(layer "In2.Cu")
		(net "GPU_HMC_PRSNT_ISO_N")
	)
	(segment
		(start 161.259266 -419.675056)
		(end 161.259266 -420.357554)
		(width 0.11684)
		(layer "In2.Cu")
		(net "GPU_HMC_PRSNT_ISO_N")
	)
	(segment
		(start 121.212102 -422.920668)
		(end 121.543572 -422.589198)
		(width 0.11684)
		(layer "In2.Cu")
		(net "GPU_HMC_PRSNT_ISO_N")
	)
	(segment
		(start 162.325812 -421.4241)
		(end 175.66894 -421.4241)
		(width 0.11684)
		(layer "In2.Cu")
		(net "GPU_HMC_PRSNT_ISO_N")
	)
	(segment
		(start 119.536718 -422.920668)
		(end 121.212102 -422.920668)
		(width 0.11684)
		(layer "In2.Cu")
		(net "GPU_HMC_PRSNT_ISO_N")
	)
	(segment
		(start 210.992466 -117.748812)
		(end 210.502754 -117.748812)
		(width 0.11684)
		(layer "In4.Cu")
		(net "GPU_HMC_PRSNT_ISO_N")
	)
	(segment
		(start 207.7466 -164.849048)
		(end 211.70392 -160.891728)
		(width 0.11684)
		(layer "In4.Cu")
		(net "GPU_HMC_PRSNT_ISO_N")
	)
	(segment
		(start 212.439758 -132.528818)
		(end 212.439758 -124.58827)
		(width 0.11684)
		(layer "In4.Cu")
		(net "GPU_HMC_PRSNT_ISO_N")
	)
	(segment
		(start 213.819994 -120.57634)
		(end 210.992466 -117.748812)
		(width 0.11684)
		(layer "In4.Cu")
		(net "GPU_HMC_PRSNT_ISO_N")
	)
	(segment
		(start 212.439758 -124.58827)
		(end 213.819994 -123.208034)
		(width 0.11684)
		(layer "In4.Cu")
		(net "GPU_HMC_PRSNT_ISO_N")
	)
	(segment
		(start 211.70392 -133.264656)
		(end 212.439758 -132.528818)
		(width 0.11684)
		(layer "In4.Cu")
		(net "GPU_HMC_PRSNT_ISO_N")
	)
	(segment
		(start 211.70392 -160.891728)
		(end 211.70392 -133.264656)
		(width 0.11684)
		(layer "In4.Cu")
		(net "GPU_HMC_PRSNT_ISO_N")
	)
	(segment
		(start 213.819994 -123.208034)
		(end 213.819994 -120.57634)
		(width 0.11684)
		(layer "In4.Cu")
		(net "GPU_HMC_PRSNT_ISO_N")
	)
	(segment
		(start 179.133246 -393.493752)
		(end 179.397914 -393.75842)
		(width 0.11684)
		(layer "In15.Cu")
		(net "GPU_HMC_PRSNT_ISO_N")
	)
	(segment
		(start 221.437454 -324.751192)
		(end 215.212422 -318.52616)
		(width 0.11684)
		(layer "In15.Cu")
		(net "GPU_HMC_PRSNT_ISO_N")
	)
	(segment
		(start 175.321214 -409.878022)
		(end 175.321214 -396.233396)
		(width 0.11684)
		(layer "In15.Cu")
		(net "GPU_HMC_PRSNT_ISO_N")
	)
	(segment
		(start 179.783486 -393.75842)
		(end 182.94604 -390.595866)
		(width 0.11684)
		(layer "In15.Cu")
		(net "GPU_HMC_PRSNT_ISO_N")
	)
	(segment
		(start 216.23401 -202.712574)
		(end 219.828364 -202.712574)
		(width 0.11684)
		(layer "In15.Cu")
		(net "GPU_HMC_PRSNT_ISO_N")
	)
	(segment
		(start 174.020226 -411.17901)
		(end 175.321214 -409.878022)
		(width 0.11684)
		(layer "In15.Cu")
		(net "GPU_HMC_PRSNT_ISO_N")
	)
	(segment
		(start 215.212422 -203.734162)
		(end 216.23401 -202.712574)
		(width 0.11684)
		(layer "In15.Cu")
		(net "GPU_HMC_PRSNT_ISO_N")
	)
	(segment
		(start 174.020226 -414.295844)
		(end 174.020226 -411.17901)
		(width 0.11684)
		(layer "In15.Cu")
		(net "GPU_HMC_PRSNT_ISO_N")
	)
	(segment
		(start 182.94604 -387.091428)
		(end 188.890148 -381.14732)
		(width 0.11684)
		(layer "In15.Cu")
		(net "GPU_HMC_PRSNT_ISO_N")
	)
	(segment
		(start 221.437454 -343.39276)
		(end 221.437454 -324.751192)
		(width 0.11684)
		(layer "In15.Cu")
		(net "GPU_HMC_PRSNT_ISO_N")
	)
	(segment
		(start 193.3321 -371.498114)
		(end 221.437454 -343.39276)
		(width 0.11684)
		(layer "In15.Cu")
		(net "GPU_HMC_PRSNT_ISO_N")
	)
	(segment
		(start 177.934112 -421.338248)
		(end 175.229012 -418.633148)
		(width 0.11684)
		(layer "In15.Cu")
		(net "GPU_HMC_PRSNT_ISO_N")
	)
	(segment
		(start 179.397914 -393.75842)
		(end 179.783486 -393.75842)
		(width 0.11684)
		(layer "In15.Cu")
		(net "GPU_HMC_PRSNT_ISO_N")
	)
	(segment
		(start 175.321214 -396.233396)
		(end 178.060858 -393.493752)
		(width 0.11684)
		(layer "In15.Cu")
		(net "GPU_HMC_PRSNT_ISO_N")
	)
	(segment
		(start 188.890148 -381.14732)
		(end 188.890148 -374.15724)
		(width 0.11684)
		(layer "In15.Cu")
		(net "GPU_HMC_PRSNT_ISO_N")
	)
	(segment
		(start 178.060858 -393.493752)
		(end 179.133246 -393.493752)
		(width 0.11684)
		(layer "In15.Cu")
		(net "GPU_HMC_PRSNT_ISO_N")
	)
	(segment
		(start 182.94604 -390.595866)
		(end 182.94604 -387.091428)
		(width 0.11684)
		(layer "In15.Cu")
		(net "GPU_HMC_PRSNT_ISO_N")
	)
	(segment
		(start 177.934112 -422.012872)
		(end 177.934112 -421.338248)
		(width 0.11684)
		(layer "In15.Cu")
		(net "GPU_HMC_PRSNT_ISO_N")
	)
	(segment
		(start 175.229012 -418.633148)
		(end 175.229012 -415.50463)
		(width 0.11684)
		(layer "In15.Cu")
		(net "GPU_HMC_PRSNT_ISO_N")
	)
	(segment
		(start 215.212422 -318.52616)
		(end 215.212422 -203.734162)
		(width 0.11684)
		(layer "In15.Cu")
		(net "GPU_HMC_PRSNT_ISO_N")
	)
	(segment
		(start 188.890148 -374.15724)
		(end 191.549274 -371.498114)
		(width 0.11684)
		(layer "In15.Cu")
		(net "GPU_HMC_PRSNT_ISO_N")
	)
	(segment
		(start 175.229012 -415.50463)
		(end 174.020226 -414.295844)
		(width 0.11684)
		(layer "In15.Cu")
		(net "GPU_HMC_PRSNT_ISO_N")
	)
	(segment
		(start 191.549274 -371.498114)
		(end 193.3321 -371.498114)
		(width 0.11684)
		(layer "In15.Cu")
		(net "GPU_HMC_PRSNT_ISO_N")
	)
	(segment
		(start 118.11 -418.44595)
		(end 118.11 -417.576)
		(width 0.10668)
		(layer "F.Cu")
		(net "GPU_HMC_PRSNT")
	)
	(segment
		(start 120.791986 -417.815014)
		(end 120.65 -417.957)
		(width 0.10668)
		(layer "F.Cu")
		(net "GPU_HMC_PRSNT")
	)
	(segment
		(start 120.269 -417.957)
		(end 120.142 -417.83)
		(width 0.10668)
		(layer "F.Cu")
		(net "GPU_HMC_PRSNT")
	)
	(segment
		(start 120.791986 -417.38804)
		(end 120.791986 -417.815014)
		(width 0.10668)
		(layer "F.Cu")
		(net "GPU_HMC_PRSNT")
	)
	(segment
		(start 118.11 -418.44595)
		(end 119.52605 -418.44595)
		(width 0.10668)
		(layer "F.Cu")
		(net "GPU_HMC_PRSNT")
	)
	(segment
		(start 119.52605 -418.44595)
		(end 120.142 -417.83)
		(width 0.10668)
		(layer "F.Cu")
		(net "GPU_HMC_PRSNT")
	)
	(segment
		(start 120.142 -417.83)
		(end 120.142 -417.38804)
		(width 0.10668)
		(layer "F.Cu")
		(net "GPU_HMC_PRSNT")
	)
	(segment
		(start 120.65 -417.957)
		(end 120.269 -417.957)
		(width 0.10668)
		(layer "F.Cu")
		(net "GPU_HMC_PRSNT")
	)
	(via
		(at 118.11 -417.576)
		(size 0.762)
		(drill 0.381)
		(layers "F.Cu" "B.Cu")
		(net "GPU_HMC_PRSNT")
	)
	(via
		(at 50.921412 -432.246532)
		(size 0.508)
		(drill 0.254)
		(layers "F.Cu" "B.Cu")
		(net "GPU_FPGA_THERM_OVERT_N")
	)
	(segment
		(start 66.763138 -415.603182)
		(end 56.698388 -415.603182)
		(width 0.10668)
		(layer "B.Cu")
		(net "GPU_FPGA_THERM_OVERT_N")
	)
	(segment
		(start 54.515004 -417.786566)
		(end 54.515004 -432.42357)
		(width 0.10668)
		(layer "B.Cu")
		(net "GPU_FPGA_THERM_OVERT_N")
	)
	(segment
		(start 53.728874 -432.59375)
		(end 53.039772 -433.282852)
		(width 0.10668)
		(layer "B.Cu")
		(net "GPU_FPGA_THERM_OVERT_N")
	)
	(segment
		(start 51.766978 -433.092098)
		(end 50.921412 -432.246532)
		(width 0.10668)
		(layer "B.Cu")
		(net "GPU_FPGA_THERM_OVERT_N")
	)
	(segment
		(start 51.766978 -433.282852)
		(end 52.782978 -433.282852)
		(width 0.10668)
		(layer "B.Cu")
		(net "GPU_FPGA_THERM_OVERT_N")
	)
	(segment
		(start 53.039772 -433.282852)
		(end 52.782978 -433.282852)
		(width 0.10668)
		(layer "B.Cu")
		(net "GPU_FPGA_THERM_OVERT_N")
	)
	(segment
		(start 49.783492 -432.954938)
		(end 50.491898 -432.246532)
		(width 0.10668)
		(layer "B.Cu")
		(net "GPU_FPGA_THERM_OVERT_N")
	)
	(segment
		(start 56.698388 -415.603182)
		(end 54.515004 -417.786566)
		(width 0.10668)
		(layer "B.Cu")
		(net "GPU_FPGA_THERM_OVERT_N")
	)
	(segment
		(start 50.491898 -432.246532)
		(end 50.921412 -432.246532)
		(width 0.10668)
		(layer "B.Cu")
		(net "GPU_FPGA_THERM_OVERT_N")
	)
	(segment
		(start 51.766978 -433.282852)
		(end 51.766978 -433.092098)
		(width 0.10668)
		(layer "B.Cu")
		(net "GPU_FPGA_THERM_OVERT_N")
	)
	(segment
		(start 49.6062 -432.954938)
		(end 49.783492 -432.954938)
		(width 0.10668)
		(layer "B.Cu")
		(net "GPU_FPGA_THERM_OVERT_N")
	)
	(segment
		(start 54.515004 -432.42357)
		(end 54.344824 -432.59375)
		(width 0.10668)
		(layer "B.Cu")
		(net "GPU_FPGA_THERM_OVERT_N")
	)
	(segment
		(start 68.64985 -417.489894)
		(end 66.763138 -415.603182)
		(width 0.10668)
		(layer "B.Cu")
		(net "GPU_FPGA_THERM_OVERT_N")
	)
	(segment
		(start 54.344824 -432.59375)
		(end 53.728874 -432.59375)
		(width 0.10668)
		(layer "B.Cu")
		(net "GPU_FPGA_THERM_OVERT_N")
	)
	(via
		(at 199.623426 -142.15364)
		(size 0.508)
		(drill 0.254)
		(layers "F.Cu" "B.Cu")
		(net "GPU_FPGA_THERM_OVERT_ISO_N")
	)
	(via
		(at 198.312786 -121.753376)
		(size 0.508)
		(drill 0.254)
		(layers "F.Cu" "B.Cu")
		(net "GPU_FPGA_THERM_OVERT_ISO_N")
	)
	(via
		(at 50.23612 -431.031142)
		(size 0.508)
		(drill 0.254)
		(layers "F.Cu" "B.Cu")
		(net "GPU_FPGA_THERM_OVERT_ISO_N")
	)
	(segment
		(start 50.23612 -431.031142)
		(end 50.493168 -431.031142)
		(width 0.10668)
		(layer "B.Cu")
		(net "GPU_FPGA_THERM_OVERT_ISO_N")
	)
	(segment
		(start 50.23612 -431.675032)
		(end 50.23612 -431.031142)
		(width 0.10668)
		(layer "B.Cu")
		(net "GPU_FPGA_THERM_OVERT_ISO_N")
	)
	(segment
		(start 197.669658 -121.753376)
		(end 198.312786 -121.753376)
		(width 0.10668)
		(layer "B.Cu")
		(net "GPU_FPGA_THERM_OVERT_ISO_N")
	)
	(segment
		(start 51.766978 -432.304952)
		(end 52.782978 -432.304952)
		(width 0.10668)
		(layer "B.Cu")
		(net "GPU_FPGA_THERM_OVERT_ISO_N")
	)
	(segment
		(start 50.493168 -431.031142)
		(end 51.766978 -432.304952)
		(width 0.10668)
		(layer "B.Cu")
		(net "GPU_FPGA_THERM_OVERT_ISO_N")
	)
	(segment
		(start 49.6062 -432.304952)
		(end 50.23612 -431.675032)
		(width 0.10668)
		(layer "B.Cu")
		(net "GPU_FPGA_THERM_OVERT_ISO_N")
	)
	(segment
		(start 199.92213 -141.854936)
		(end 199.623426 -142.15364)
		(width 0.11684)
		(layer "In4.Cu")
		(net "GPU_FPGA_THERM_OVERT_ISO_N")
	)
	(segment
		(start 199.055736 -122.602752)
		(end 199.055736 -125.00102)
		(width 0.11684)
		(layer "In4.Cu")
		(net "GPU_FPGA_THERM_OVERT_ISO_N")
	)
	(segment
		(start 199.148192 -129.160524)
		(end 199.92213 -129.934462)
		(width 0.11684)
		(layer "In4.Cu")
		(net "GPU_FPGA_THERM_OVERT_ISO_N")
	)
	(segment
		(start 199.148192 -127.75692)
		(end 199.148192 -129.160524)
		(width 0.11684)
		(layer "In4.Cu")
		(net "GPU_FPGA_THERM_OVERT_ISO_N")
	)
	(segment
		(start 198.312786 -121.859802)
		(end 199.055736 -122.602752)
		(width 0.11684)
		(layer "In4.Cu")
		(net "GPU_FPGA_THERM_OVERT_ISO_N")
	)
	(segment
		(start 199.92213 -129.934462)
		(end 199.92213 -141.854936)
		(width 0.11684)
		(layer "In4.Cu")
		(net "GPU_FPGA_THERM_OVERT_ISO_N")
	)
	(segment
		(start 199.055736 -125.00102)
		(end 198.4121 -125.644656)
		(width 0.11684)
		(layer "In4.Cu")
		(net "GPU_FPGA_THERM_OVERT_ISO_N")
	)
	(segment
		(start 198.4121 -125.644656)
		(end 198.4121 -127.020828)
		(width 0.11684)
		(layer "In4.Cu")
		(net "GPU_FPGA_THERM_OVERT_ISO_N")
	)
	(segment
		(start 198.4121 -127.020828)
		(end 199.148192 -127.75692)
		(width 0.11684)
		(layer "In4.Cu")
		(net "GPU_FPGA_THERM_OVERT_ISO_N")
	)
	(segment
		(start 198.312786 -121.753376)
		(end 198.312786 -121.859802)
		(width 0.11684)
		(layer "In4.Cu")
		(net "GPU_FPGA_THERM_OVERT_ISO_N")
	)
	(segment
		(start 33.35909 -394.068554)
		(end 31.383986 -392.09345)
		(width 0.11684)
		(layer "In13.Cu")
		(net "GPU_FPGA_THERM_OVERT_ISO_N")
	)
	(segment
		(start 29.369512 -380.001272)
		(end 29.369512 -375.529094)
		(width 0.11684)
		(layer "In13.Cu")
		(net "GPU_FPGA_THERM_OVERT_ISO_N")
	)
	(segment
		(start 176.945798 -144.143984)
		(end 185.216292 -144.143984)
		(width 0.11684)
		(layer "In13.Cu")
		(net "GPU_FPGA_THERM_OVERT_ISO_N")
	)
	(segment
		(start 194.519042 -141.23416)
		(end 198.703946 -141.23416)
		(width 0.11684)
		(layer "In13.Cu")
		(net "GPU_FPGA_THERM_OVERT_ISO_N")
	)
	(segment
		(start 31.383986 -392.09345)
		(end 31.383986 -382.015746)
		(width 0.11684)
		(layer "In13.Cu")
		(net "GPU_FPGA_THERM_OVERT_ISO_N")
	)
	(segment
		(start 36.339272 -395.971776)
		(end 36.339272 -394.530834)
		(width 0.11684)
		(layer "In13.Cu")
		(net "GPU_FPGA_THERM_OVERT_ISO_N")
	)
	(segment
		(start 30.60319 -137.872724)
		(end 77.610462 -137.872724)
		(width 0.11684)
		(layer "In13.Cu")
		(net "GPU_FPGA_THERM_OVERT_ISO_N")
	)
	(segment
		(start 35.876992 -394.068554)
		(end 33.35909 -394.068554)
		(width 0.11684)
		(layer "In13.Cu")
		(net "GPU_FPGA_THERM_OVERT_ISO_N")
	)
	(segment
		(start 192.37452 -143.378682)
		(end 194.519042 -141.23416)
		(width 0.11684)
		(layer "In13.Cu")
		(net "GPU_FPGA_THERM_OVERT_ISO_N")
	)
	(segment
		(start 77.610462 -137.872724)
		(end 79.204566 -136.27862)
		(width 0.11684)
		(layer "In13.Cu")
		(net "GPU_FPGA_THERM_OVERT_ISO_N")
	)
	(segment
		(start 43.177206 -422.69283)
		(end 43.177206 -421.843454)
		(width 0.11684)
		(layer "In13.Cu")
		(net "GPU_FPGA_THERM_OVERT_ISO_N")
	)
	(segment
		(start 33.469834 -409.559506)
		(end 35.02787 -408.00147)
		(width 0.11684)
		(layer "In13.Cu")
		(net "GPU_FPGA_THERM_OVERT_ISO_N")
	)
	(segment
		(start 15.692882 -345.515946)
		(end 6.44144 -336.264504)
		(width 0.11684)
		(layer "In13.Cu")
		(net "GPU_FPGA_THERM_OVERT_ISO_N")
	)
	(segment
		(start 34.901378 -415.588958)
		(end 33.469834 -414.157414)
		(width 0.11684)
		(layer "In13.Cu")
		(net "GPU_FPGA_THERM_OVERT_ISO_N")
	)
	(segment
		(start 43.177206 -421.843454)
		(end 36.92271 -415.588958)
		(width 0.11684)
		(layer "In13.Cu")
		(net "GPU_FPGA_THERM_OVERT_ISO_N")
	)
	(segment
		(start 35.02787 -397.283178)
		(end 36.339272 -395.971776)
		(width 0.11684)
		(layer "In13.Cu")
		(net "GPU_FPGA_THERM_OVERT_ISO_N")
	)
	(segment
		(start 49.367694 -431.031142)
		(end 47.9044 -429.567848)
		(width 0.11684)
		(layer "In13.Cu")
		(net "GPU_FPGA_THERM_OVERT_ISO_N")
	)
	(segment
		(start 185.981594 -143.378682)
		(end 192.37452 -143.378682)
		(width 0.11684)
		(layer "In13.Cu")
		(net "GPU_FPGA_THERM_OVERT_ISO_N")
	)
	(segment
		(start 185.216292 -144.143984)
		(end 185.981594 -143.378682)
		(width 0.11684)
		(layer "In13.Cu")
		(net "GPU_FPGA_THERM_OVERT_ISO_N")
	)
	(segment
		(start 6.44144 -186.04738)
		(end 18.221706 -174.267114)
		(width 0.11684)
		(layer "In13.Cu")
		(net "GPU_FPGA_THERM_OVERT_ISO_N")
	)
	(segment
		(start 47.9044 -429.567848)
		(end 47.9044 -426.40631)
		(width 0.11684)
		(layer "In13.Cu")
		(net "GPU_FPGA_THERM_OVERT_ISO_N")
	)
	(segment
		(start 46.683676 -425.185586)
		(end 45.669962 -425.185586)
		(width 0.11684)
		(layer "In13.Cu")
		(net "GPU_FPGA_THERM_OVERT_ISO_N")
	)
	(segment
		(start 45.669962 -425.185586)
		(end 43.177206 -422.69283)
		(width 0.11684)
		(layer "In13.Cu")
		(net "GPU_FPGA_THERM_OVERT_ISO_N")
	)
	(segment
		(start 15.692882 -354.829618)
		(end 15.692882 -345.515946)
		(width 0.11684)
		(layer "In13.Cu")
		(net "GPU_FPGA_THERM_OVERT_ISO_N")
	)
	(segment
		(start 6.44144 -336.264504)
		(end 6.44144 -186.04738)
		(width 0.11684)
		(layer "In13.Cu")
		(net "GPU_FPGA_THERM_OVERT_ISO_N")
	)
	(segment
		(start 198.703946 -141.23416)
		(end 199.623426 -142.15364)
		(width 0.11684)
		(layer "In13.Cu")
		(net "GPU_FPGA_THERM_OVERT_ISO_N")
	)
	(segment
		(start 36.92271 -415.588958)
		(end 34.901378 -415.588958)
		(width 0.11684)
		(layer "In13.Cu")
		(net "GPU_FPGA_THERM_OVERT_ISO_N")
	)
	(segment
		(start 18.221706 -150.254208)
		(end 30.60319 -137.872724)
		(width 0.11684)
		(layer "In13.Cu")
		(net "GPU_FPGA_THERM_OVERT_ISO_N")
	)
	(segment
		(start 93.35897 -136.27862)
		(end 93.717872 -136.637522)
		(width 0.11684)
		(layer "In13.Cu")
		(net "GPU_FPGA_THERM_OVERT_ISO_N")
	)
	(segment
		(start 79.204566 -136.27862)
		(end 93.35897 -136.27862)
		(width 0.11684)
		(layer "In13.Cu")
		(net "GPU_FPGA_THERM_OVERT_ISO_N")
	)
	(segment
		(start 50.23612 -431.031142)
		(end 49.367694 -431.031142)
		(width 0.11684)
		(layer "In13.Cu")
		(net "GPU_FPGA_THERM_OVERT_ISO_N")
	)
	(segment
		(start 17.24279 -368.14252)
		(end 17.24279 -356.379526)
		(width 0.11684)
		(layer "In13.Cu")
		(net "GPU_FPGA_THERM_OVERT_ISO_N")
	)
	(segment
		(start 35.02787 -408.00147)
		(end 35.02787 -397.283178)
		(width 0.11684)
		(layer "In13.Cu")
		(net "GPU_FPGA_THERM_OVERT_ISO_N")
	)
	(segment
		(start 18.221706 -174.267114)
		(end 18.221706 -150.254208)
		(width 0.11684)
		(layer "In13.Cu")
		(net "GPU_FPGA_THERM_OVERT_ISO_N")
	)
	(segment
		(start 93.717872 -136.637522)
		(end 150.645622 -136.637522)
		(width 0.11684)
		(layer "In13.Cu")
		(net "GPU_FPGA_THERM_OVERT_ISO_N")
	)
	(segment
		(start 17.24279 -356.379526)
		(end 15.692882 -354.829618)
		(width 0.11684)
		(layer "In13.Cu")
		(net "GPU_FPGA_THERM_OVERT_ISO_N")
	)
	(segment
		(start 29.369512 -375.529094)
		(end 24.675846 -370.835428)
		(width 0.11684)
		(layer "In13.Cu")
		(net "GPU_FPGA_THERM_OVERT_ISO_N")
	)
	(segment
		(start 33.469834 -414.157414)
		(end 33.469834 -409.559506)
		(width 0.11684)
		(layer "In13.Cu")
		(net "GPU_FPGA_THERM_OVERT_ISO_N")
	)
	(segment
		(start 31.383986 -382.015746)
		(end 29.369512 -380.001272)
		(width 0.11684)
		(layer "In13.Cu")
		(net "GPU_FPGA_THERM_OVERT_ISO_N")
	)
	(segment
		(start 19.935698 -370.835428)
		(end 17.24279 -368.14252)
		(width 0.11684)
		(layer "In13.Cu")
		(net "GPU_FPGA_THERM_OVERT_ISO_N")
	)
	(segment
		(start 150.645622 -136.637522)
		(end 157.550358 -143.542258)
		(width 0.11684)
		(layer "In13.Cu")
		(net "GPU_FPGA_THERM_OVERT_ISO_N")
	)
	(segment
		(start 47.9044 -426.40631)
		(end 46.683676 -425.185586)
		(width 0.11684)
		(layer "In13.Cu")
		(net "GPU_FPGA_THERM_OVERT_ISO_N")
	)
	(segment
		(start 24.675846 -370.835428)
		(end 19.935698 -370.835428)
		(width 0.11684)
		(layer "In13.Cu")
		(net "GPU_FPGA_THERM_OVERT_ISO_N")
	)
	(segment
		(start 157.550358 -143.542258)
		(end 176.344072 -143.542258)
		(width 0.11684)
		(layer "In13.Cu")
		(net "GPU_FPGA_THERM_OVERT_ISO_N")
	)
	(segment
		(start 36.339272 -394.530834)
		(end 35.876992 -394.068554)
		(width 0.11684)
		(layer "In13.Cu")
		(net "GPU_FPGA_THERM_OVERT_ISO_N")
	)
	(segment
		(start 176.344072 -143.542258)
		(end 176.945798 -144.143984)
		(width 0.11684)
		(layer "In13.Cu")
		(net "GPU_FPGA_THERM_OVERT_ISO_N")
	)
	(via
		(at 47.021496 -432.270154)
		(size 0.762)
		(drill 0.254)
		(layers "F.Cu" "B.Cu")
		(net "GPU_FPGA_THERM_OVERT")
	)
	(segment
		(start 47.70628 -433.604924)
		(end 47.70628 -432.954938)
		(width 0.10668)
		(layer "B.Cu")
		(net "GPU_FPGA_THERM_OVERT")
	)
	(segment
		(start 47.021496 -432.270154)
		(end 47.021496 -432.620166)
		(width 0.10668)
		(layer "B.Cu")
		(net "GPU_FPGA_THERM_OVERT")
	)
	(segment
		(start 46.359318 -432.385724)
		(end 46.491398 -432.253644)
		(width 0.10668)
		(layer "B.Cu")
		(net "GPU_FPGA_THERM_OVERT")
	)
	(segment
		(start 47.021496 -432.620166)
		(end 47.356268 -432.954938)
		(width 0.10668)
		(layer "B.Cu")
		(net "GPU_FPGA_THERM_OVERT")
	)
	(segment
		(start 47.004986 -432.253644)
		(end 47.021496 -432.270154)
		(width 0.10668)
		(layer "B.Cu")
		(net "GPU_FPGA_THERM_OVERT")
	)
	(segment
		(start 47.356268 -432.954938)
		(end 47.70628 -432.954938)
		(width 0.10668)
		(layer "B.Cu")
		(net "GPU_FPGA_THERM_OVERT")
	)
	(segment
		(start 46.491398 -432.253644)
		(end 47.004986 -432.253644)
		(width 0.10668)
		(layer "B.Cu")
		(net "GPU_FPGA_THERM_OVERT")
	)
	(segment
		(start 45.30979 -435.722014)
		(end 46.16704 -435.722014)
		(width 0.10668)
		(layer "F.Cu")
		(net "GPU_FPGA_RST_R_N")
	)
	(segment
		(start 209.294476 -114.249708)
		(end 210.560666 -114.249708)
		(width 0.10668)
		(layer "F.Cu")
		(net "GPU_FPGA_RST_R_N")
	)
	(segment
		(start 44.581064 -435.722014)
		(end 45.30979 -435.722014)
		(width 0.10668)
		(layer "F.Cu")
		(net "GPU_FPGA_RST_R_N")
	)
	(segment
		(start 44.46905 -435.61)
		(end 44.581064 -435.722014)
		(width 0.10668)
		(layer "F.Cu")
		(net "GPU_FPGA_RST_R_N")
	)
	(segment
		(start 44.46905 -435.61)
		(end 44.46905 -434.594)
		(width 0.10668)
		(layer "F.Cu")
		(net "GPU_FPGA_RST_R_N")
	)
	(via
		(at 210.560666 -114.249708)
		(size 0.508)
		(drill 0.254)
		(layers "F.Cu" "B.Cu")
		(net "GPU_FPGA_RST_R_N")
	)
	(via
		(at 209.388964 -140.320776)
		(size 0.508)
		(drill 0.254)
		(layers "F.Cu" "B.Cu")
		(net "GPU_FPGA_RST_R_N")
	)
	(via
		(at 45.30979 -435.722014)
		(size 0.508)
		(drill 0.254)
		(layers "F.Cu" "B.Cu")
		(net "GPU_FPGA_RST_R_N")
	)
	(segment
		(start 210.821016 -125.492002)
		(end 210.821016 -123.886976)
		(width 0.11684)
		(layer "In4.Cu")
		(net "GPU_FPGA_RST_R_N")
	)
	(segment
		(start 210.393534 -123.459494)
		(end 210.393534 -122.384058)
		(width 0.11684)
		(layer "In4.Cu")
		(net "GPU_FPGA_RST_R_N")
	)
	(segment
		(start 210.91017 -118.295166)
		(end 210.202272 -118.295166)
		(width 0.11684)
		(layer "In4.Cu")
		(net "GPU_FPGA_RST_R_N")
	)
	(segment
		(start 208.912968 -139.286996)
		(end 208.912968 -136.718802)
		(width 0.11684)
		(layer "In4.Cu")
		(net "GPU_FPGA_RST_R_N")
	)
	(segment
		(start 211.063586 -118.448582)
		(end 210.91017 -118.295166)
		(width 0.11684)
		(layer "In4.Cu")
		(net "GPU_FPGA_RST_R_N")
	)
	(segment
		(start 209.388964 -140.320776)
		(end 209.388964 -139.762992)
		(width 0.11684)
		(layer "In4.Cu")
		(net "GPU_FPGA_RST_R_N")
	)
	(segment
		(start 209.394806 -132.876036)
		(end 208.29143 -131.77266)
		(width 0.11684)
		(layer "In4.Cu")
		(net "GPU_FPGA_RST_R_N")
	)
	(segment
		(start 210.821016 -123.886976)
		(end 210.393534 -123.459494)
		(width 0.11684)
		(layer "In4.Cu")
		(net "GPU_FPGA_RST_R_N")
	)
	(segment
		(start 208.912968 -136.718802)
		(end 209.394806 -136.236964)
		(width 0.11684)
		(layer "In4.Cu")
		(net "GPU_FPGA_RST_R_N")
	)
	(segment
		(start 209.394806 -136.236964)
		(end 209.394806 -132.876036)
		(width 0.11684)
		(layer "In4.Cu")
		(net "GPU_FPGA_RST_R_N")
	)
	(segment
		(start 210.519772 -114.249708)
		(end 210.560666 -114.249708)
		(width 0.11684)
		(layer "In4.Cu")
		(net "GPU_FPGA_RST_R_N")
	)
	(segment
		(start 210.022186 -119.238268)
		(end 210.851242 -119.238268)
		(width 0.11684)
		(layer "In4.Cu")
		(net "GPU_FPGA_RST_R_N")
	)
	(segment
		(start 211.063586 -119.025924)
		(end 211.063586 -118.448582)
		(width 0.11684)
		(layer "In4.Cu")
		(net "GPU_FPGA_RST_R_N")
	)
	(segment
		(start 209.53349 -115.23599)
		(end 210.519772 -114.249708)
		(width 0.11684)
		(layer "In4.Cu")
		(net "GPU_FPGA_RST_R_N")
	)
	(segment
		(start 209.388964 -139.762992)
		(end 208.912968 -139.286996)
		(width 0.11684)
		(layer "In4.Cu")
		(net "GPU_FPGA_RST_R_N")
	)
	(segment
		(start 210.851242 -119.238268)
		(end 211.063586 -119.025924)
		(width 0.11684)
		(layer "In4.Cu")
		(net "GPU_FPGA_RST_R_N")
	)
	(segment
		(start 208.29143 -131.77266)
		(end 208.29143 -128.021588)
		(width 0.11684)
		(layer "In4.Cu")
		(net "GPU_FPGA_RST_R_N")
	)
	(segment
		(start 208.29143 -128.021588)
		(end 210.821016 -125.492002)
		(width 0.11684)
		(layer "In4.Cu")
		(net "GPU_FPGA_RST_R_N")
	)
	(segment
		(start 209.51063 -121.501154)
		(end 209.51063 -119.749824)
		(width 0.11684)
		(layer "In4.Cu")
		(net "GPU_FPGA_RST_R_N")
	)
	(segment
		(start 209.53349 -117.626384)
		(end 209.53349 -115.23599)
		(width 0.11684)
		(layer "In4.Cu")
		(net "GPU_FPGA_RST_R_N")
	)
	(segment
		(start 210.202272 -118.295166)
		(end 209.53349 -117.626384)
		(width 0.11684)
		(layer "In4.Cu")
		(net "GPU_FPGA_RST_R_N")
	)
	(segment
		(start 210.393534 -122.384058)
		(end 209.51063 -121.501154)
		(width 0.11684)
		(layer "In4.Cu")
		(net "GPU_FPGA_RST_R_N")
	)
	(segment
		(start 209.51063 -119.749824)
		(end 210.022186 -119.238268)
		(width 0.11684)
		(layer "In4.Cu")
		(net "GPU_FPGA_RST_R_N")
	)
	(segment
		(start 10.309606 -388.655306)
		(end 10.309606 -392.09726)
		(width 0.11684)
		(layer "In13.Cu")
		(net "GPU_FPGA_RST_R_N")
	)
	(segment
		(start 7.583678 -406.91689)
		(end 8.366252 -408.806396)
		(width 0.11684)
		(layer "In13.Cu")
		(net "GPU_FPGA_RST_R_N")
	)
	(segment
		(start 36.596574 -434.965602)
		(end 37.16147 -434.400706)
		(width 0.11684)
		(layer "In13.Cu")
		(net "GPU_FPGA_RST_R_N")
	)
	(segment
		(start 208.761076 -139.1666)
		(end 187.403232 -139.1666)
		(width 0.11684)
		(layer "In13.Cu")
		(net "GPU_FPGA_RST_R_N")
	)
	(segment
		(start 10.418826 -429.172116)
		(end 15.331694 -429.172116)
		(width 0.11684)
		(layer "In13.Cu")
		(net "GPU_FPGA_RST_R_N")
	)
	(segment
		(start 209.388964 -140.320776)
		(end 209.388964 -139.794488)
		(width 0.11684)
		(layer "In13.Cu")
		(net "GPU_FPGA_RST_R_N")
	)
	(segment
		(start 43.349164 -435.100222)
		(end 44.687998 -435.100222)
		(width 0.11684)
		(layer "In13.Cu")
		(net "GPU_FPGA_RST_R_N")
	)
	(segment
		(start 42.649648 -434.400706)
		(end 43.349164 -435.100222)
		(width 0.11684)
		(layer "In13.Cu")
		(net "GPU_FPGA_RST_R_N")
	)
	(segment
		(start 158.201106 -141.487652)
		(end 151.445976 -134.732522)
		(width 0.11684)
		(layer "In13.Cu")
		(net "GPU_FPGA_RST_R_N")
	)
	(segment
		(start 3.172206 -335.750154)
		(end 3.172206 -363.58195)
		(width 0.11684)
		(layer "In13.Cu")
		(net "GPU_FPGA_RST_R_N")
	)
	(segment
		(start 177.175668 -141.487652)
		(end 158.201106 -141.487652)
		(width 0.11684)
		(layer "In13.Cu")
		(net "GPU_FPGA_RST_R_N")
	)
	(segment
		(start 16.309086 -173.485048)
		(end 4.411472 -185.382662)
		(width 0.11684)
		(layer "In13.Cu")
		(net "GPU_FPGA_RST_R_N")
	)
	(segment
		(start 177.927 -142.238984)
		(end 177.175668 -141.487652)
		(width 0.11684)
		(layer "In13.Cu")
		(net "GPU_FPGA_RST_R_N")
	)
	(segment
		(start 6.213602 -396.193264)
		(end 6.213602 -405.546814)
		(width 0.11684)
		(layer "In13.Cu")
		(net "GPU_FPGA_RST_R_N")
	)
	(segment
		(start 6.213602 -405.546814)
		(end 7.583678 -406.91689)
		(width 0.11684)
		(layer "In13.Cu")
		(net "GPU_FPGA_RST_R_N")
	)
	(segment
		(start 34.901632 -434.239162)
		(end 35.628072 -434.965602)
		(width 0.11684)
		(layer "In13.Cu")
		(net "GPU_FPGA_RST_R_N")
	)
	(segment
		(start 6.565138 -386.485892)
		(end 8.140192 -386.485892)
		(width 0.11684)
		(layer "In13.Cu")
		(net "GPU_FPGA_RST_R_N")
	)
	(segment
		(start 8.366252 -420.811452)
		(end 9.33323 -421.77843)
		(width 0.11684)
		(layer "In13.Cu")
		(net "GPU_FPGA_RST_R_N")
	)
	(segment
		(start 35.628072 -434.965602)
		(end 36.596574 -434.965602)
		(width 0.11684)
		(layer "In13.Cu")
		(net "GPU_FPGA_RST_R_N")
	)
	(segment
		(start 4.411472 -185.382662)
		(end 4.411472 -334.510888)
		(width 0.11684)
		(layer "In13.Cu")
		(net "GPU_FPGA_RST_R_N")
	)
	(segment
		(start 187.403232 -139.1666)
		(end 184.330848 -142.238984)
		(width 0.11684)
		(layer "In13.Cu")
		(net "GPU_FPGA_RST_R_N")
	)
	(segment
		(start 20.39874 -434.239162)
		(end 34.901632 -434.239162)
		(width 0.11684)
		(layer "In13.Cu")
		(net "GPU_FPGA_RST_R_N")
	)
	(segment
		(start 9.33323 -428.08652)
		(end 10.418826 -429.172116)
		(width 0.11684)
		(layer "In13.Cu")
		(net "GPU_FPGA_RST_R_N")
	)
	(segment
		(start 3.172206 -363.58195)
		(end 3.749548 -364.159292)
		(width 0.11684)
		(layer "In13.Cu")
		(net "GPU_FPGA_RST_R_N")
	)
	(segment
		(start 94.507812 -134.732522)
		(end 94.14891 -134.37362)
		(width 0.11684)
		(layer "In13.Cu")
		(net "GPU_FPGA_RST_R_N")
	)
	(segment
		(start 15.331694 -429.172116)
		(end 20.39874 -434.239162)
		(width 0.11684)
		(layer "In13.Cu")
		(net "GPU_FPGA_RST_R_N")
	)
	(segment
		(start 16.309086 -149.461474)
		(end 16.309086 -173.485048)
		(width 0.11684)
		(layer "In13.Cu")
		(net "GPU_FPGA_RST_R_N")
	)
	(segment
		(start 8.366252 -408.806396)
		(end 8.366252 -420.811452)
		(width 0.11684)
		(layer "In13.Cu")
		(net "GPU_FPGA_RST_R_N")
	)
	(segment
		(start 44.687998 -435.100222)
		(end 45.30979 -435.722014)
		(width 0.11684)
		(layer "In13.Cu")
		(net "GPU_FPGA_RST_R_N")
	)
	(segment
		(start 10.309606 -392.09726)
		(end 6.213602 -396.193264)
		(width 0.11684)
		(layer "In13.Cu")
		(net "GPU_FPGA_RST_R_N")
	)
	(segment
		(start 4.411472 -334.510888)
		(end 3.172206 -335.750154)
		(width 0.11684)
		(layer "In13.Cu")
		(net "GPU_FPGA_RST_R_N")
	)
	(segment
		(start 76.817728 -135.960104)
		(end 29.810456 -135.960104)
		(width 0.11684)
		(layer "In13.Cu")
		(net "GPU_FPGA_RST_R_N")
	)
	(segment
		(start 37.16147 -434.400706)
		(end 42.649648 -434.400706)
		(width 0.11684)
		(layer "In13.Cu")
		(net "GPU_FPGA_RST_R_N")
	)
	(segment
		(start 209.388964 -139.794488)
		(end 208.761076 -139.1666)
		(width 0.11684)
		(layer "In13.Cu")
		(net "GPU_FPGA_RST_R_N")
	)
	(segment
		(start 151.445976 -134.732522)
		(end 94.507812 -134.732522)
		(width 0.11684)
		(layer "In13.Cu")
		(net "GPU_FPGA_RST_R_N")
	)
	(segment
		(start 8.140192 -386.485892)
		(end 10.309606 -388.655306)
		(width 0.11684)
		(layer "In13.Cu")
		(net "GPU_FPGA_RST_R_N")
	)
	(segment
		(start 78.404212 -134.37362)
		(end 76.817728 -135.960104)
		(width 0.11684)
		(layer "In13.Cu")
		(net "GPU_FPGA_RST_R_N")
	)
	(segment
		(start 184.330848 -142.238984)
		(end 177.927 -142.238984)
		(width 0.11684)
		(layer "In13.Cu")
		(net "GPU_FPGA_RST_R_N")
	)
	(segment
		(start 3.749548 -383.670302)
		(end 6.565138 -386.485892)
		(width 0.11684)
		(layer "In13.Cu")
		(net "GPU_FPGA_RST_R_N")
	)
	(segment
		(start 94.14891 -134.37362)
		(end 78.404212 -134.37362)
		(width 0.11684)
		(layer "In13.Cu")
		(net "GPU_FPGA_RST_R_N")
	)
	(segment
		(start 29.810456 -135.960104)
		(end 16.309086 -149.461474)
		(width 0.11684)
		(layer "In13.Cu")
		(net "GPU_FPGA_RST_R_N")
	)
	(segment
		(start 3.749548 -364.159292)
		(end 3.749548 -383.670302)
		(width 0.11684)
		(layer "In13.Cu")
		(net "GPU_FPGA_RST_R_N")
	)
	(segment
		(start 9.33323 -421.77843)
		(end 9.33323 -428.08652)
		(width 0.11684)
		(layer "In13.Cu")
		(net "GPU_FPGA_RST_R_N")
	)
	(segment
		(start 48.19904 -433.726336)
		(end 48.75403 -434.281326)
		(width 0.10668)
		(layer "F.Cu")
		(net "GPU_FPGA_RST_R_BUF_N")
	)
	(segment
		(start 48.19904 -433.657502)
		(end 48.19904 -433.726336)
		(width 0.10668)
		(layer "F.Cu")
		(net "GPU_FPGA_RST_R_BUF_N")
	)
	(segment
		(start 48.75403 -434.281326)
		(end 49.091596 -434.281326)
		(width 0.10668)
		(layer "F.Cu")
		(net "GPU_FPGA_RST_R_BUF_N")
	)
	(via
		(at 99.82327 -404.445216)
		(size 0.508)
		(drill 0.254)
		(layers "F.Cu" "B.Cu")
		(net "GPU_FPGA_RST_R_BUF_N")
	)
	(via
		(at 49.091596 -434.281326)
		(size 0.508)
		(drill 0.254)
		(layers "F.Cu" "B.Cu")
		(net "GPU_FPGA_RST_R_BUF_N")
	)
	(segment
		(start 99.492308 -412.422086)
		(end 99.492308 -406.400254)
		(width 0.10668)
		(layer "B.Cu")
		(net "GPU_FPGA_RST_R_BUF_N")
	)
	(segment
		(start 96.295972 -421.426894)
		(end 96.295972 -414.357566)
		(width 0.10668)
		(layer "B.Cu")
		(net "GPU_FPGA_RST_R_BUF_N")
	)
	(segment
		(start 99.492308 -406.400254)
		(end 99.82327 -406.069292)
		(width 0.10668)
		(layer "B.Cu")
		(net "GPU_FPGA_RST_R_BUF_N")
	)
	(segment
		(start 86.83752 -424.694604)
		(end 87.638382 -423.893742)
		(width 0.10668)
		(layer "B.Cu")
		(net "GPU_FPGA_RST_R_BUF_N")
	)
	(segment
		(start 87.650066 -440.489848)
		(end 86.83752 -439.677302)
		(width 0.10668)
		(layer "B.Cu")
		(net "GPU_FPGA_RST_R_BUF_N")
	)
	(segment
		(start 99.219766 -412.694628)
		(end 99.492308 -412.422086)
		(width 0.10668)
		(layer "B.Cu")
		(net "GPU_FPGA_RST_R_BUF_N")
	)
	(segment
		(start 99.82327 -406.069292)
		(end 99.82327 -404.445216)
		(width 0.10668)
		(layer "B.Cu")
		(net "GPU_FPGA_RST_R_BUF_N")
	)
	(segment
		(start 87.638382 -423.893742)
		(end 93.829124 -423.893742)
		(width 0.10668)
		(layer "B.Cu")
		(net "GPU_FPGA_RST_R_BUF_N")
	)
	(segment
		(start 96.295972 -414.357566)
		(end 97.95891 -412.694628)
		(width 0.10668)
		(layer "B.Cu")
		(net "GPU_FPGA_RST_R_BUF_N")
	)
	(segment
		(start 86.83752 -439.677302)
		(end 86.83752 -424.694604)
		(width 0.10668)
		(layer "B.Cu")
		(net "GPU_FPGA_RST_R_BUF_N")
	)
	(segment
		(start 97.95891 -412.694628)
		(end 99.219766 -412.694628)
		(width 0.10668)
		(layer "B.Cu")
		(net "GPU_FPGA_RST_R_BUF_N")
	)
	(segment
		(start 93.829124 -423.893742)
		(end 96.295972 -421.426894)
		(width 0.10668)
		(layer "B.Cu")
		(net "GPU_FPGA_RST_R_BUF_N")
	)
	(segment
		(start 45.677836 -413.27959)
		(end 45.677836 -409.946094)
		(width 0.11684)
		(layer "In4.Cu")
		(net "GPU_FPGA_RST_R_BUF_N")
	)
	(segment
		(start 45.677836 -409.946094)
		(end 46.775878 -408.848052)
		(width 0.11684)
		(layer "In4.Cu")
		(net "GPU_FPGA_RST_R_BUF_N")
	)
	(segment
		(start 49.4792 -433.893722)
		(end 49.4792 -431.419)
		(width 0.11684)
		(layer "In4.Cu")
		(net "GPU_FPGA_RST_R_BUF_N")
	)
	(segment
		(start 52.884324 -401.01774)
		(end 95.04934 -401.01774)
		(width 0.11684)
		(layer "In4.Cu")
		(net "GPU_FPGA_RST_R_BUF_N")
	)
	(segment
		(start 46.775878 -403.998684)
		(end 48.137064 -402.637498)
		(width 0.11684)
		(layer "In4.Cu")
		(net "GPU_FPGA_RST_R_BUF_N")
	)
	(segment
		(start 46.775878 -408.848052)
		(end 46.775878 -403.998684)
		(width 0.11684)
		(layer "In4.Cu")
		(net "GPU_FPGA_RST_R_BUF_N")
	)
	(segment
		(start 48.137064 -402.637498)
		(end 51.264566 -402.637498)
		(width 0.11684)
		(layer "In4.Cu")
		(net "GPU_FPGA_RST_R_BUF_N")
	)
	(segment
		(start 48.9204 -426.4914)
		(end 47.5488 -425.1198)
		(width 0.11684)
		(layer "In4.Cu")
		(net "GPU_FPGA_RST_R_BUF_N")
	)
	(segment
		(start 98.476816 -404.445216)
		(end 99.82327 -404.445216)
		(width 0.11684)
		(layer "In4.Cu")
		(net "GPU_FPGA_RST_R_BUF_N")
	)
	(segment
		(start 49.4792 -431.419)
		(end 48.9204 -430.8602)
		(width 0.11684)
		(layer "In4.Cu")
		(net "GPU_FPGA_RST_R_BUF_N")
	)
	(segment
		(start 47.5488 -415.150554)
		(end 45.677836 -413.27959)
		(width 0.11684)
		(layer "In4.Cu")
		(net "GPU_FPGA_RST_R_BUF_N")
	)
	(segment
		(start 47.5488 -425.1198)
		(end 47.5488 -415.150554)
		(width 0.11684)
		(layer "In4.Cu")
		(net "GPU_FPGA_RST_R_BUF_N")
	)
	(segment
		(start 49.091596 -434.281326)
		(end 49.4792 -433.893722)
		(width 0.11684)
		(layer "In4.Cu")
		(net "GPU_FPGA_RST_R_BUF_N")
	)
	(segment
		(start 51.264566 -402.637498)
		(end 52.884324 -401.01774)
		(width 0.11684)
		(layer "In4.Cu")
		(net "GPU_FPGA_RST_R_BUF_N")
	)
	(segment
		(start 95.04934 -401.01774)
		(end 98.476816 -404.445216)
		(width 0.11684)
		(layer "In4.Cu")
		(net "GPU_FPGA_RST_R_BUF_N")
	)
	(segment
		(start 48.9204 -430.8602)
		(end 48.9204 -426.4914)
		(width 0.11684)
		(layer "In4.Cu")
		(net "GPU_FPGA_RST_R_BUF_N")
	)
	(segment
		(start 48.19904 -435.117494)
		(end 48.19904 -434.457602)
		(width 0.10668)
		(layer "F.Cu")
		(net "GPU_FPGA_RST_R1_BUF_N")
	)
	(segment
		(start 47.18304 -434.457602)
		(end 46.16704 -434.457602)
		(width 0.10668)
		(layer "F.Cu")
		(net "GPU_FPGA_RST_R1_BUF_N")
	)
	(segment
		(start 48.06696 -435.722014)
		(end 48.19904 -435.589934)
		(width 0.10668)
		(layer "F.Cu")
		(net "GPU_FPGA_RST_R1_BUF_N")
	)
	(segment
		(start 48.19904 -435.589934)
		(end 48.19904 -435.117494)
		(width 0.10668)
		(layer "F.Cu")
		(net "GPU_FPGA_RST_R1_BUF_N")
	)
	(segment
		(start 47.18304 -434.457602)
		(end 48.19904 -434.457602)
		(width 0.10668)
		(layer "F.Cu")
		(net "GPU_FPGA_RST_R1_BUF_N")
	)
	(via
		(at 48.19904 -435.117494)
		(size 0.508)
		(drill 0.254)
		(layers "F.Cu" "B.Cu")
		(net "GPU_FPGA_RST_R1_BUF_N")
	)
	(segment
		(start 36.720018 -132.587238)
		(end 37.333428 -132.587238)
		(width 0.10668)
		(layer "F.Cu")
		(net "GPU_FPGA_READY_N")
	)
	(via
		(at 37.333428 -132.587238)
		(size 0.508)
		(drill 0.254)
		(layers "F.Cu" "B.Cu")
		(net "GPU_FPGA_READY_N")
	)
	(via
		(at 37.931852 -433.223162)
		(size 0.508)
		(drill 0.254)
		(layers "F.Cu" "B.Cu")
		(net "GPU_FPGA_READY_N")
	)
	(segment
		(start 46.451774 -422.110662)
		(end 46.434502 -422.127934)
		(width 0.10668)
		(layer "B.Cu")
		(net "GPU_FPGA_READY_N")
	)
	(segment
		(start 41.385744 -433.784248)
		(end 38.492938 -433.784248)
		(width 0.10668)
		(layer "B.Cu")
		(net "GPU_FPGA_READY_N")
	)
	(segment
		(start 48.250856 -421.93972)
		(end 48.250856 -421.56253)
		(width 0.10668)
		(layer "B.Cu")
		(net "GPU_FPGA_READY_N")
	)
	(segment
		(start 38.492938 -433.784248)
		(end 37.931852 -433.223162)
		(width 0.10668)
		(layer "B.Cu")
		(net "GPU_FPGA_READY_N")
	)
	(segment
		(start 45.122592 -430.0474)
		(end 41.385744 -433.784248)
		(width 0.10668)
		(layer "B.Cu")
		(net "GPU_FPGA_READY_N")
	)
	(segment
		(start 47.668942 -422.110662)
		(end 48.079914 -422.110662)
		(width 0.10668)
		(layer "B.Cu")
		(net "GPU_FPGA_READY_N")
	)
	(segment
		(start 47.668942 -422.110662)
		(end 46.451774 -422.110662)
		(width 0.10668)
		(layer "B.Cu")
		(net "GPU_FPGA_READY_N")
	)
	(segment
		(start 45.122592 -423.439844)
		(end 45.122592 -430.0474)
		(width 0.10668)
		(layer "B.Cu")
		(net "GPU_FPGA_READY_N")
	)
	(segment
		(start 48.079914 -422.110662)
		(end 48.250856 -421.93972)
		(width 0.10668)
		(layer "B.Cu")
		(net "GPU_FPGA_READY_N")
	)
	(segment
		(start 48.250856 -421.56253)
		(end 48.149002 -421.460676)
		(width 0.10668)
		(layer "B.Cu")
		(net "GPU_FPGA_READY_N")
	)
	(segment
		(start 48.149002 -421.460676)
		(end 47.668942 -421.460676)
		(width 0.10668)
		(layer "B.Cu")
		(net "GPU_FPGA_READY_N")
	)
	(segment
		(start 46.434502 -422.127934)
		(end 45.122592 -423.439844)
		(width 0.10668)
		(layer "B.Cu")
		(net "GPU_FPGA_READY_N")
	)
	(segment
		(start 31.484824 -392.14679)
		(end 31.484824 -379.723396)
		(width 0.11684)
		(layer "In11.Cu")
		(net "GPU_FPGA_READY_N")
	)
	(segment
		(start 36.094162 -432.544474)
		(end 35.767264 -432.217576)
		(width 0.11684)
		(layer "In11.Cu")
		(net "GPU_FPGA_READY_N")
	)
	(segment
		(start 35.767264 -432.217576)
		(end 35.767264 -431.735484)
		(width 0.11684)
		(layer "In11.Cu")
		(net "GPU_FPGA_READY_N")
	)
	(segment
		(start 37.910516 -426.473874)
		(end 37.910516 -422.498266)
		(width 0.11684)
		(layer "In11.Cu")
		(net "GPU_FPGA_READY_N")
	)
	(segment
		(start 38.853618 -430.845976)
		(end 38.853618 -427.416976)
		(width 0.11684)
		(layer "In11.Cu")
		(net "GPU_FPGA_READY_N")
	)
	(segment
		(start 22.30247 -365.268764)
		(end 20.448524 -365.268764)
		(width 0.11684)
		(layer "In11.Cu")
		(net "GPU_FPGA_READY_N")
	)
	(segment
		(start 30.163008 -373.450358)
		(end 30.163008 -372.16461)
		(width 0.11684)
		(layer "In11.Cu")
		(net "GPU_FPGA_READY_N")
	)
	(segment
		(start 39.978838 -420.429944)
		(end 39.978838 -415.843466)
		(width 0.11684)
		(layer "In11.Cu")
		(net "GPU_FPGA_READY_N")
	)
	(segment
		(start 36.067238 -431.43551)
		(end 38.264084 -431.43551)
		(width 0.11684)
		(layer "In11.Cu")
		(net "GPU_FPGA_READY_N")
	)
	(segment
		(start 37.253164 -432.544474)
		(end 36.094162 -432.544474)
		(width 0.11684)
		(layer "In11.Cu")
		(net "GPU_FPGA_READY_N")
	)
	(segment
		(start 30.655768 -373.943118)
		(end 30.163008 -373.450358)
		(width 0.11684)
		(layer "In11.Cu")
		(net "GPU_FPGA_READY_N")
	)
	(segment
		(start 30.163008 -372.16461)
		(end 26.936954 -368.938556)
		(width 0.11684)
		(layer "In11.Cu")
		(net "GPU_FPGA_READY_N")
	)
	(segment
		(start 27.27071 -134.314184)
		(end 35.606482 -134.314184)
		(width 0.11684)
		(layer "In11.Cu")
		(net "GPU_FPGA_READY_N")
	)
	(segment
		(start 35.767264 -431.735484)
		(end 36.067238 -431.43551)
		(width 0.11684)
		(layer "In11.Cu")
		(net "GPU_FPGA_READY_N")
	)
	(segment
		(start 37.910516 -422.498266)
		(end 39.978838 -420.429944)
		(width 0.11684)
		(layer "In11.Cu")
		(net "GPU_FPGA_READY_N")
	)
	(segment
		(start 4.595622 -363.314742)
		(end 4.595622 -352.699828)
		(width 0.11684)
		(layer "In11.Cu")
		(net "GPU_FPGA_READY_N")
	)
	(segment
		(start 38.264084 -431.43551)
		(end 38.853618 -430.845976)
		(width 0.11684)
		(layer "In11.Cu")
		(net "GPU_FPGA_READY_N")
	)
	(segment
		(start 19.994118 -364.814358)
		(end 18.969736 -364.390178)
		(width 0.11684)
		(layer "In11.Cu")
		(net "GPU_FPGA_READY_N")
	)
	(segment
		(start 37.931852 -433.223162)
		(end 37.253164 -432.544474)
		(width 0.11684)
		(layer "In11.Cu")
		(net "GPU_FPGA_READY_N")
	)
	(segment
		(start 4.058666 -352.162872)
		(end 4.058666 -344.416634)
		(width 0.11684)
		(layer "In11.Cu")
		(net "GPU_FPGA_READY_N")
	)
	(segment
		(start 34.863278 -395.525244)
		(end 31.484824 -392.14679)
		(width 0.11684)
		(layer "In11.Cu")
		(net "GPU_FPGA_READY_N")
	)
	(segment
		(start 4.595622 -352.699828)
		(end 4.058666 -352.162872)
		(width 0.11684)
		(layer "In11.Cu")
		(net "GPU_FPGA_READY_N")
	)
	(segment
		(start 35.606482 -134.314184)
		(end 37.333428 -132.587238)
		(width 0.11684)
		(layer "In11.Cu")
		(net "GPU_FPGA_READY_N")
	)
	(segment
		(start 5.671058 -364.390178)
		(end 4.595622 -363.314742)
		(width 0.11684)
		(layer "In11.Cu")
		(net "GPU_FPGA_READY_N")
	)
	(segment
		(start 38.853618 -427.416976)
		(end 37.910516 -426.473874)
		(width 0.11684)
		(layer "In11.Cu")
		(net "GPU_FPGA_READY_N")
	)
	(segment
		(start 26.936954 -368.938556)
		(end 26.936954 -367.532158)
		(width 0.11684)
		(layer "In11.Cu")
		(net "GPU_FPGA_READY_N")
	)
	(segment
		(start 30.655768 -378.89434)
		(end 30.655768 -373.943118)
		(width 0.11684)
		(layer "In11.Cu")
		(net "GPU_FPGA_READY_N")
	)
	(segment
		(start 4.765548 -156.819346)
		(end 27.27071 -134.314184)
		(width 0.11684)
		(layer "In11.Cu")
		(net "GPU_FPGA_READY_N")
	)
	(segment
		(start 20.448524 -365.268764)
		(end 19.994118 -364.814358)
		(width 0.11684)
		(layer "In11.Cu")
		(net "GPU_FPGA_READY_N")
	)
	(segment
		(start 37.899848 -412.296102)
		(end 34.863278 -409.259532)
		(width 0.11684)
		(layer "In11.Cu")
		(net "GPU_FPGA_READY_N")
	)
	(segment
		(start 31.484824 -379.723396)
		(end 30.655768 -378.89434)
		(width 0.11684)
		(layer "In11.Cu")
		(net "GPU_FPGA_READY_N")
	)
	(segment
		(start 39.978838 -415.843466)
		(end 37.899848 -413.764476)
		(width 0.11684)
		(layer "In11.Cu")
		(net "GPU_FPGA_READY_N")
	)
	(segment
		(start 34.863278 -409.259532)
		(end 34.863278 -395.525244)
		(width 0.11684)
		(layer "In11.Cu")
		(net "GPU_FPGA_READY_N")
	)
	(segment
		(start 4.058666 -344.416634)
		(end 4.765548 -343.709752)
		(width 0.11684)
		(layer "In11.Cu")
		(net "GPU_FPGA_READY_N")
	)
	(segment
		(start 26.936954 -367.532158)
		(end 25.632664 -366.227868)
		(width 0.11684)
		(layer "In11.Cu")
		(net "GPU_FPGA_READY_N")
	)
	(segment
		(start 4.765548 -343.709752)
		(end 4.765548 -156.819346)
		(width 0.11684)
		(layer "In11.Cu")
		(net "GPU_FPGA_READY_N")
	)
	(segment
		(start 37.899848 -413.764476)
		(end 37.899848 -412.296102)
		(width 0.11684)
		(layer "In11.Cu")
		(net "GPU_FPGA_READY_N")
	)
	(segment
		(start 18.969736 -364.390178)
		(end 5.671058 -364.390178)
		(width 0.11684)
		(layer "In11.Cu")
		(net "GPU_FPGA_READY_N")
	)
	(segment
		(start 25.632664 -366.227868)
		(end 23.261574 -366.227868)
		(width 0.11684)
		(layer "In11.Cu")
		(net "GPU_FPGA_READY_N")
	)
	(segment
		(start 23.261574 -366.227868)
		(end 22.30247 -365.268764)
		(width 0.11684)
		(layer "In11.Cu")
		(net "GPU_FPGA_READY_N")
	)
	(segment
		(start 202.039982 -123.356116)
		(end 203.312268 -123.356116)
		(width 0.10668)
		(layer "F.Cu")
		(net "GPU_FPGA_READY_ISO")
	)
	(segment
		(start 205.97114 -122.878088)
		(end 206.248 -123.154948)
		(width 0.10668)
		(layer "F.Cu")
		(net "GPU_FPGA_READY_ISO")
	)
	(segment
		(start 203.790296 -122.878088)
		(end 205.97114 -122.878088)
		(width 0.10668)
		(layer "F.Cu")
		(net "GPU_FPGA_READY_ISO")
	)
	(segment
		(start 206.248 -123.154948)
		(end 206.502 -123.154948)
		(width 0.10668)
		(layer "F.Cu")
		(net "GPU_FPGA_READY_ISO")
	)
	(segment
		(start 203.312268 -123.356116)
		(end 203.790296 -122.878088)
		(width 0.10668)
		(layer "F.Cu")
		(net "GPU_FPGA_READY_ISO")
	)
	(segment
		(start 201.482198 -122.798332)
		(end 202.039982 -123.356116)
		(width 0.10668)
		(layer "F.Cu")
		(net "GPU_FPGA_READY_ISO")
	)
	(via
		(at 34.896044 -413.108648)
		(size 0.508)
		(drill 0.254)
		(layers "F.Cu" "B.Cu")
		(net "GPU_FPGA_READY_ISO")
	)
	(via
		(at 206.502 -123.154948)
		(size 0.508)
		(drill 0.254)
		(layers "F.Cu" "B.Cu")
		(net "GPU_FPGA_READY_ISO")
	)
	(via
		(at 52.524152 -421.88384)
		(size 0.508)
		(drill 0.254)
		(layers "F.Cu" "B.Cu")
		(net "GPU_FPGA_READY_ISO")
	)
	(via
		(at 72.140572 -132.6642)
		(size 0.508)
		(drill 0.254)
		(layers "F.Cu" "B.Cu")
		(net "GPU_FPGA_READY_ISO")
	)
	(segment
		(start 50.724562 -421.61079)
		(end 51.379882 -421.61079)
		(width 0.10668)
		(layer "B.Cu")
		(net "GPU_FPGA_READY_ISO")
	)
	(segment
		(start 52.751482 -421.180768)
		(end 52.751482 -421.65651)
		(width 0.10668)
		(layer "B.Cu")
		(net "GPU_FPGA_READY_ISO")
	)
	(segment
		(start 52.751482 -421.65651)
		(end 52.524152 -421.88384)
		(width 0.10668)
		(layer "B.Cu")
		(net "GPU_FPGA_READY_ISO")
	)
	(segment
		(start 51.379882 -421.61079)
		(end 51.815492 -421.17518)
		(width 0.10668)
		(layer "B.Cu")
		(net "GPU_FPGA_READY_ISO")
	)
	(segment
		(start 49.899062 -420.78529)
		(end 50.724562 -421.61079)
		(width 0.10668)
		(layer "B.Cu")
		(net "GPU_FPGA_READY_ISO")
	)
	(segment
		(start 51.815492 -421.17518)
		(end 52.751482 -421.180768)
		(width 0.10668)
		(layer "B.Cu")
		(net "GPU_FPGA_READY_ISO")
	)
	(segment
		(start 49.568862 -420.81069)
		(end 49.899062 -420.78529)
		(width 0.10668)
		(layer "B.Cu")
		(net "GPU_FPGA_READY_ISO")
	)
	(segment
		(start 18.37182 -368.429286)
		(end 15.669006 -365.726472)
		(width 0.11684)
		(layer "In4.Cu")
		(net "GPU_FPGA_READY_ISO")
	)
	(segment
		(start 16.168878 -162.990022)
		(end 16.168878 -153.905966)
		(width 0.11684)
		(layer "In4.Cu")
		(net "GPU_FPGA_READY_ISO")
	)
	(segment
		(start 5.533136 -167.78097)
		(end 6.979158 -166.334948)
		(width 0.11684)
		(layer "In4.Cu")
		(net "GPU_FPGA_READY_ISO")
	)
	(segment
		(start 33.098486 -136.976358)
		(end 67.828414 -136.976358)
		(width 0.11684)
		(layer "In4.Cu")
		(net "GPU_FPGA_READY_ISO")
	)
	(segment
		(start 34.896044 -413.108648)
		(end 35.42792 -412.576772)
		(width 0.11684)
		(layer "In4.Cu")
		(net "GPU_FPGA_READY_ISO")
	)
	(segment
		(start 16.168878 -153.905966)
		(end 33.098486 -136.976358)
		(width 0.11684)
		(layer "In4.Cu")
		(net "GPU_FPGA_READY_ISO")
	)
	(segment
		(start 32.23514 -392.99388)
		(end 31.67634 -391.644378)
		(width 0.11684)
		(layer "In4.Cu")
		(net "GPU_FPGA_READY_ISO")
	)
	(segment
		(start 6.979158 -166.334948)
		(end 12.823952 -166.334948)
		(width 0.11684)
		(layer "In4.Cu")
		(net "GPU_FPGA_READY_ISO")
	)
	(segment
		(start 5.533136 -335.3562)
		(end 5.533136 -167.78097)
		(width 0.11684)
		(layer "In4.Cu")
		(net "GPU_FPGA_READY_ISO")
	)
	(segment
		(start 15.669006 -365.726472)
		(end 15.669006 -345.49207)
		(width 0.11684)
		(layer "In4.Cu")
		(net "GPU_FPGA_READY_ISO")
	)
	(segment
		(start 31.67634 -391.644378)
		(end 31.539688 -390.957816)
		(width 0.11684)
		(layer "In4.Cu")
		(net "GPU_FPGA_READY_ISO")
	)
	(segment
		(start 35.42792 -396.18666)
		(end 32.23514 -392.99388)
		(width 0.11684)
		(layer "In4.Cu")
		(net "GPU_FPGA_READY_ISO")
	)
	(segment
		(start 15.669006 -345.49207)
		(end 5.533136 -335.3562)
		(width 0.11684)
		(layer "In4.Cu")
		(net "GPU_FPGA_READY_ISO")
	)
	(segment
		(start 31.539688 -390.957816)
		(end 31.539688 -379.33122)
		(width 0.11684)
		(layer "In4.Cu")
		(net "GPU_FPGA_READY_ISO")
	)
	(segment
		(start 12.823952 -166.334948)
		(end 16.168878 -162.990022)
		(width 0.11684)
		(layer "In4.Cu")
		(net "GPU_FPGA_READY_ISO")
	)
	(segment
		(start 67.828414 -136.976358)
		(end 72.140572 -132.6642)
		(width 0.11684)
		(layer "In4.Cu")
		(net "GPU_FPGA_READY_ISO")
	)
	(segment
		(start 23.311612 -368.429286)
		(end 18.37182 -368.429286)
		(width 0.11684)
		(layer "In4.Cu")
		(net "GPU_FPGA_READY_ISO")
	)
	(segment
		(start 31.539688 -379.33122)
		(end 29.649166 -374.76684)
		(width 0.11684)
		(layer "In4.Cu")
		(net "GPU_FPGA_READY_ISO")
	)
	(segment
		(start 35.42792 -412.576772)
		(end 35.42792 -396.18666)
		(width 0.11684)
		(layer "In4.Cu")
		(net "GPU_FPGA_READY_ISO")
	)
	(segment
		(start 29.649166 -374.76684)
		(end 23.311612 -368.429286)
		(width 0.11684)
		(layer "In4.Cu")
		(net "GPU_FPGA_READY_ISO")
	)
	(segment
		(start 77.202792 -127.60198)
		(end 108.74248 -127.60198)
		(width 0.11684)
		(layer "In6.Cu")
		(net "GPU_FPGA_READY_ISO")
	)
	(segment
		(start 190.666116 -134.396226)
		(end 191.100202 -133.96214)
		(width 0.11684)
		(layer "In6.Cu")
		(net "GPU_FPGA_READY_ISO")
	)
	(segment
		(start 114.173508 -129.971546)
		(end 114.173508 -130.016758)
		(width 0.11684)
		(layer "In6.Cu")
		(net "GPU_FPGA_READY_ISO")
	)
	(segment
		(start 114.173508 -130.016758)
		(end 115.274852 -131.118102)
		(width 0.11684)
		(layer "In6.Cu")
		(net "GPU_FPGA_READY_ISO")
	)
	(segment
		(start 113.13414 -128.932178)
		(end 114.173508 -129.971546)
		(width 0.11684)
		(layer "In6.Cu")
		(net "GPU_FPGA_READY_ISO")
	)
	(segment
		(start 154.889454 -131.118102)
		(end 156.704284 -132.932932)
		(width 0.11684)
		(layer "In6.Cu")
		(net "GPU_FPGA_READY_ISO")
	)
	(segment
		(start 172.491654 -137.086594)
		(end 190.17996 -137.086594)
		(width 0.11684)
		(layer "In6.Cu")
		(net "GPU_FPGA_READY_ISO")
	)
	(segment
		(start 156.704284 -132.932932)
		(end 162.341052 -132.932932)
		(width 0.11684)
		(layer "In6.Cu")
		(net "GPU_FPGA_READY_ISO")
	)
	(segment
		(start 202.27036 -127.941832)
		(end 206.502 -123.710192)
		(width 0.11684)
		(layer "In6.Cu")
		(net "GPU_FPGA_READY_ISO")
	)
	(segment
		(start 72.140572 -132.6642)
		(end 77.202792 -127.60198)
		(width 0.11684)
		(layer "In6.Cu")
		(net "GPU_FPGA_READY_ISO")
	)
	(segment
		(start 110.072678 -128.932178)
		(end 113.13414 -128.932178)
		(width 0.11684)
		(layer "In6.Cu")
		(net "GPU_FPGA_READY_ISO")
	)
	(segment
		(start 202.27036 -128.4351)
		(end 202.27036 -127.941832)
		(width 0.11684)
		(layer "In6.Cu")
		(net "GPU_FPGA_READY_ISO")
	)
	(segment
		(start 206.502 -123.710192)
		(end 206.502 -123.154948)
		(width 0.11684)
		(layer "In6.Cu")
		(net "GPU_FPGA_READY_ISO")
	)
	(segment
		(start 191.100202 -133.96214)
		(end 196.74332 -133.96214)
		(width 0.11684)
		(layer "In6.Cu")
		(net "GPU_FPGA_READY_ISO")
	)
	(segment
		(start 169.691304 -134.286244)
		(end 172.491654 -137.086594)
		(width 0.11684)
		(layer "In6.Cu")
		(net "GPU_FPGA_READY_ISO")
	)
	(segment
		(start 163.694364 -134.286244)
		(end 169.691304 -134.286244)
		(width 0.11684)
		(layer "In6.Cu")
		(net "GPU_FPGA_READY_ISO")
	)
	(segment
		(start 190.17996 -137.086594)
		(end 190.666116 -136.600438)
		(width 0.11684)
		(layer "In6.Cu")
		(net "GPU_FPGA_READY_ISO")
	)
	(segment
		(start 190.666116 -136.600438)
		(end 190.666116 -134.396226)
		(width 0.11684)
		(layer "In6.Cu")
		(net "GPU_FPGA_READY_ISO")
	)
	(segment
		(start 162.341052 -132.932932)
		(end 163.694364 -134.286244)
		(width 0.11684)
		(layer "In6.Cu")
		(net "GPU_FPGA_READY_ISO")
	)
	(segment
		(start 108.74248 -127.60198)
		(end 110.072678 -128.932178)
		(width 0.11684)
		(layer "In6.Cu")
		(net "GPU_FPGA_READY_ISO")
	)
	(segment
		(start 196.74332 -133.96214)
		(end 202.27036 -128.4351)
		(width 0.11684)
		(layer "In6.Cu")
		(net "GPU_FPGA_READY_ISO")
	)
	(segment
		(start 115.274852 -131.118102)
		(end 154.889454 -131.118102)
		(width 0.11684)
		(layer "In6.Cu")
		(net "GPU_FPGA_READY_ISO")
	)
	(segment
		(start 52.210208 -421.569896)
		(end 49.39538 -421.569896)
		(width 0.11684)
		(layer "In13.Cu")
		(net "GPU_FPGA_READY_ISO")
	)
	(segment
		(start 35.327844 -413.540448)
		(end 34.896044 -413.108648)
		(width 0.11684)
		(layer "In13.Cu")
		(net "GPU_FPGA_READY_ISO")
	)
	(segment
		(start 52.524152 -421.88384)
		(end 52.210208 -421.569896)
		(width 0.11684)
		(layer "In13.Cu")
		(net "GPU_FPGA_READY_ISO")
	)
	(segment
		(start 45.738542 -422.528238)
		(end 36.750752 -413.540448)
		(width 0.11684)
		(layer "In13.Cu")
		(net "GPU_FPGA_READY_ISO")
	)
	(segment
		(start 49.39538 -421.569896)
		(end 48.437038 -422.528238)
		(width 0.11684)
		(layer "In13.Cu")
		(net "GPU_FPGA_READY_ISO")
	)
	(segment
		(start 48.437038 -422.528238)
		(end 45.738542 -422.528238)
		(width 0.11684)
		(layer "In13.Cu")
		(net "GPU_FPGA_READY_ISO")
	)
	(segment
		(start 36.750752 -413.540448)
		(end 35.327844 -413.540448)
		(width 0.11684)
		(layer "In13.Cu")
		(net "GPU_FPGA_READY_ISO")
	)
	(via
		(at 50.469292 -422.20261)
		(size 0.762)
		(drill 0.254)
		(layers "F.Cu" "B.Cu")
		(net "GPU_FPGA_READY")
	)
	(segment
		(start 50.469292 -421.875966)
		(end 50.469292 -422.20261)
		(width 0.10668)
		(layer "B.Cu")
		(net "GPU_FPGA_READY")
	)
	(segment
		(start 50.469292 -422.20261)
		(end 51.153568 -422.20261)
		(width 0.10668)
		(layer "B.Cu")
		(net "GPU_FPGA_READY")
	)
	(segment
		(start 49.568862 -421.460676)
		(end 50.054002 -421.460676)
		(width 0.10668)
		(layer "B.Cu")
		(net "GPU_FPGA_READY")
	)
	(segment
		(start 50.054002 -421.460676)
		(end 50.469292 -421.875966)
		(width 0.10668)
		(layer "B.Cu")
		(net "GPU_FPGA_READY")
	)
	(segment
		(start 51.153568 -422.20261)
		(end 51.728624 -422.777666)
		(width 0.10668)
		(layer "B.Cu")
		(net "GPU_FPGA_READY")
	)
	(segment
		(start 51.728624 -422.777666)
		(end 52.69357 -422.777666)
		(width 0.10668)
		(layer "B.Cu")
		(net "GPU_FPGA_READY")
	)
	(segment
		(start 50.469292 -422.20261)
		(end 50.469292 -421.41394)
		(width 0.11684)
		(layer "In2.Cu")
		(net "GPU_FPGA_READY")
	)
	(segment
		(start 48.427386 -419.372034)
		(end 48.427386 -416.21202)
		(width 0.11684)
		(layer "In2.Cu")
		(net "GPU_FPGA_READY")
	)
	(segment
		(start 50.469292 -421.41394)
		(end 48.427386 -419.372034)
		(width 0.11684)
		(layer "In2.Cu")
		(net "GPU_FPGA_READY")
	)
	(segment
		(start 48.72609 -415.913316)
		(end 60.10148 -415.913316)
		(width 0.11684)
		(layer "In2.Cu")
		(net "GPU_FPGA_READY")
	)
	(segment
		(start 60.649866 -416.461702)
		(end 60.649866 -417.489894)
		(width 0.11684)
		(layer "In2.Cu")
		(net "GPU_FPGA_READY")
	)
	(segment
		(start 48.427386 -416.21202)
		(end 48.72609 -415.913316)
		(width 0.11684)
		(layer "In2.Cu")
		(net "GPU_FPGA_READY")
	)
	(segment
		(start 60.10148 -415.913316)
		(end 60.649866 -416.461702)
		(width 0.11684)
		(layer "In2.Cu")
		(net "GPU_FPGA_READY")
	)
	(segment
		(start 309.521352 -434.342794)
		(end 308.420516 -434.342794)
		(width 0.10668)
		(layer "F.Cu")
		(net "GPU_FPGA_OVERT_N")
	)
	(segment
		(start 305.243738 -434.264308)
		(end 305.322224 -434.342794)
		(width 0.10668)
		(layer "F.Cu")
		(net "GPU_FPGA_OVERT_N")
	)
	(segment
		(start 309.813452 -434.050694)
		(end 309.521352 -434.342794)
		(width 0.10668)
		(layer "F.Cu")
		(net "GPU_FPGA_OVERT_N")
	)
	(segment
		(start 305.322224 -434.342794)
		(end 307.404516 -434.342794)
		(width 0.10668)
		(layer "F.Cu")
		(net "GPU_FPGA_OVERT_N")
	)
	(segment
		(start 307.404516 -434.342794)
		(end 308.420516 -434.342794)
		(width 0.10668)
		(layer "F.Cu")
		(net "GPU_FPGA_OVERT_N")
	)
	(via
		(at 309.813452 -434.050694)
		(size 0.508)
		(drill 0.254)
		(layers "F.Cu" "B.Cu")
		(net "GPU_FPGA_OVERT_N")
	)
	(segment
		(start 326.28205 -440.489848)
		(end 325.825612 -440.03341)
		(width 0.11684)
		(layer "In2.Cu")
		(net "GPU_FPGA_OVERT_N")
	)
	(segment
		(start 325.825612 -440.03341)
		(end 325.825612 -424.018456)
		(width 0.11684)
		(layer "In2.Cu")
		(net "GPU_FPGA_OVERT_N")
	)
	(segment
		(start 311.539382 -432.324764)
		(end 309.813452 -434.050694)
		(width 0.11684)
		(layer "In2.Cu")
		(net "GPU_FPGA_OVERT_N")
	)
	(segment
		(start 326.649588 -440.489848)
		(end 326.28205 -440.489848)
		(width 0.11684)
		(layer "In2.Cu")
		(net "GPU_FPGA_OVERT_N")
	)
	(segment
		(start 311.539382 -424.41876)
		(end 311.539382 -432.324764)
		(width 0.11684)
		(layer "In2.Cu")
		(net "GPU_FPGA_OVERT_N")
	)
	(segment
		(start 325.825612 -424.018456)
		(end 325.593964 -423.786808)
		(width 0.11684)
		(layer "In2.Cu")
		(net "GPU_FPGA_OVERT_N")
	)
	(segment
		(start 312.171334 -423.786808)
		(end 311.539382 -424.41876)
		(width 0.11684)
		(layer "In2.Cu")
		(net "GPU_FPGA_OVERT_N")
	)
	(segment
		(start 325.593964 -423.786808)
		(end 312.171334 -423.786808)
		(width 0.11684)
		(layer "In2.Cu")
		(net "GPU_FPGA_OVERT_N")
	)
	(segment
		(start 309.813452 -435.320694)
		(end 308.420516 -435.320694)
		(width 0.10668)
		(layer "F.Cu")
		(net "GPU_FPGA_OVERT_ISO_N")
	)
	(segment
		(start 305.650138 -435.320694)
		(end 305.243738 -434.914294)
		(width 0.10668)
		(layer "F.Cu")
		(net "GPU_FPGA_OVERT_ISO_N")
	)
	(segment
		(start 308.420516 -435.320694)
		(end 307.404516 -435.320694)
		(width 0.10668)
		(layer "F.Cu")
		(net "GPU_FPGA_OVERT_ISO_N")
	)
	(segment
		(start 307.404516 -435.320694)
		(end 305.650138 -435.320694)
		(width 0.10668)
		(layer "F.Cu")
		(net "GPU_FPGA_OVERT_ISO_N")
	)
	(via
		(at 293.045896 -371.52453)
		(size 0.508)
		(drill 0.254)
		(layers "F.Cu" "B.Cu")
		(net "GPU_FPGA_OVERT_ISO_N")
	)
	(via
		(at 405.311864 -363.692694)
		(size 0.508)
		(drill 0.254)
		(layers "F.Cu" "B.Cu")
		(net "GPU_FPGA_OVERT_ISO_N")
	)
	(via
		(at 309.813452 -435.320694)
		(size 0.508)
		(drill 0.254)
		(layers "F.Cu" "B.Cu")
		(net "GPU_FPGA_OVERT_ISO_N")
	)
	(via
		(at 202.520804 -122.769376)
		(size 0.508)
		(drill 0.254)
		(layers "F.Cu" "B.Cu")
		(net "GPU_FPGA_OVERT_ISO_N")
	)
	(segment
		(start 400.004788 -368.99977)
		(end 405.311864 -363.692694)
		(width 0.10668)
		(layer "B.Cu")
		(net "GPU_FPGA_OVERT_ISO_N")
	)
	(segment
		(start 301.064168 -367.558574)
		(end 302.505364 -368.99977)
		(width 0.10668)
		(layer "B.Cu")
		(net "GPU_FPGA_OVERT_ISO_N")
	)
	(segment
		(start 293.045896 -371.52453)
		(end 293.045896 -369.857274)
		(width 0.10668)
		(layer "B.Cu")
		(net "GPU_FPGA_OVERT_ISO_N")
	)
	(segment
		(start 297.102276 -367.558574)
		(end 301.064168 -367.558574)
		(width 0.10668)
		(layer "B.Cu")
		(net "GPU_FPGA_OVERT_ISO_N")
	)
	(segment
		(start 296.182796 -368.478054)
		(end 297.102276 -367.558574)
		(width 0.10668)
		(layer "B.Cu")
		(net "GPU_FPGA_OVERT_ISO_N")
	)
	(segment
		(start 294.425116 -368.478054)
		(end 296.182796 -368.478054)
		(width 0.10668)
		(layer "B.Cu")
		(net "GPU_FPGA_OVERT_ISO_N")
	)
	(segment
		(start 201.352658 -122.769376)
		(end 202.520804 -122.769376)
		(width 0.10668)
		(layer "B.Cu")
		(net "GPU_FPGA_OVERT_ISO_N")
	)
	(segment
		(start 302.505364 -368.99977)
		(end 400.004788 -368.99977)
		(width 0.10668)
		(layer "B.Cu")
		(net "GPU_FPGA_OVERT_ISO_N")
	)
	(segment
		(start 293.045896 -369.857274)
		(end 294.425116 -368.478054)
		(width 0.10668)
		(layer "B.Cu")
		(net "GPU_FPGA_OVERT_ISO_N")
	)
	(segment
		(start 303.435766 -430.166272)
		(end 297.568112 -424.298618)
		(width 0.11684)
		(layer "In4.Cu")
		(net "GPU_FPGA_OVERT_ISO_N")
	)
	(segment
		(start 293.758112 -403.359366)
		(end 294.901112 -402.216366)
		(width 0.11684)
		(layer "In4.Cu")
		(net "GPU_FPGA_OVERT_ISO_N")
	)
	(segment
		(start 296.541698 -376.767852)
		(end 293.936166 -374.16232)
		(width 0.11684)
		(layer "In4.Cu")
		(net "GPU_FPGA_OVERT_ISO_N")
	)
	(segment
		(start 294.901112 -402.216366)
		(end 294.901112 -400.66976)
		(width 0.11684)
		(layer "In4.Cu")
		(net "GPU_FPGA_OVERT_ISO_N")
	)
	(segment
		(start 296.541698 -380.555754)
		(end 296.541698 -376.767852)
		(width 0.11684)
		(layer "In4.Cu")
		(net "GPU_FPGA_OVERT_ISO_N")
	)
	(segment
		(start 294.901112 -400.66976)
		(end 298.619164 -396.951708)
		(width 0.11684)
		(layer "In4.Cu")
		(net "GPU_FPGA_OVERT_ISO_N")
	)
	(segment
		(start 293.936166 -374.16232)
		(end 293.936166 -372.4148)
		(width 0.11684)
		(layer "In4.Cu")
		(net "GPU_FPGA_OVERT_ISO_N")
	)
	(segment
		(start 298.619164 -392.041888)
		(end 301.547276 -389.113776)
		(width 0.11684)
		(layer "In4.Cu")
		(net "GPU_FPGA_OVERT_ISO_N")
	)
	(segment
		(start 293.936166 -372.4148)
		(end 293.045896 -371.52453)
		(width 0.11684)
		(layer "In4.Cu")
		(net "GPU_FPGA_OVERT_ISO_N")
	)
	(segment
		(start 297.568112 -424.298618)
		(end 297.568112 -420.628572)
		(width 0.11684)
		(layer "In4.Cu")
		(net "GPU_FPGA_OVERT_ISO_N")
	)
	(segment
		(start 299.927264 -383.94132)
		(end 296.541698 -380.555754)
		(width 0.11684)
		(layer "In4.Cu")
		(net "GPU_FPGA_OVERT_ISO_N")
	)
	(segment
		(start 292.921944 -415.982404)
		(end 292.921944 -406.000966)
		(width 0.11684)
		(layer "In4.Cu")
		(net "GPU_FPGA_OVERT_ISO_N")
	)
	(segment
		(start 309.813452 -435.320694)
		(end 310.278272 -434.855874)
		(width 0.11684)
		(layer "In4.Cu")
		(net "GPU_FPGA_OVERT_ISO_N")
	)
	(segment
		(start 293.758112 -405.164798)
		(end 293.758112 -403.359366)
		(width 0.11684)
		(layer "In4.Cu")
		(net "GPU_FPGA_OVERT_ISO_N")
	)
	(segment
		(start 300.775624 -383.94132)
		(end 299.927264 -383.94132)
		(width 0.11684)
		(layer "In4.Cu")
		(net "GPU_FPGA_OVERT_ISO_N")
	)
	(segment
		(start 301.547276 -389.113776)
		(end 301.547276 -384.712972)
		(width 0.11684)
		(layer "In4.Cu")
		(net "GPU_FPGA_OVERT_ISO_N")
	)
	(segment
		(start 292.921944 -406.000966)
		(end 293.758112 -405.164798)
		(width 0.11684)
		(layer "In4.Cu")
		(net "GPU_FPGA_OVERT_ISO_N")
	)
	(segment
		(start 310.278272 -432.909472)
		(end 307.535072 -430.166272)
		(width 0.11684)
		(layer "In4.Cu")
		(net "GPU_FPGA_OVERT_ISO_N")
	)
	(segment
		(start 297.568112 -420.628572)
		(end 292.921944 -415.982404)
		(width 0.11684)
		(layer "In4.Cu")
		(net "GPU_FPGA_OVERT_ISO_N")
	)
	(segment
		(start 310.278272 -434.855874)
		(end 310.278272 -432.909472)
		(width 0.11684)
		(layer "In4.Cu")
		(net "GPU_FPGA_OVERT_ISO_N")
	)
	(segment
		(start 301.547276 -384.712972)
		(end 300.775624 -383.94132)
		(width 0.11684)
		(layer "In4.Cu")
		(net "GPU_FPGA_OVERT_ISO_N")
	)
	(segment
		(start 307.535072 -430.166272)
		(end 303.435766 -430.166272)
		(width 0.11684)
		(layer "In4.Cu")
		(net "GPU_FPGA_OVERT_ISO_N")
	)
	(segment
		(start 298.619164 -396.951708)
		(end 298.619164 -392.041888)
		(width 0.11684)
		(layer "In4.Cu")
		(net "GPU_FPGA_OVERT_ISO_N")
	)
	(segment
		(start 461.963008 -172.615352)
		(end 461.963008 -319.356486)
		(width 0.11684)
		(layer "In15.Cu")
		(net "GPU_FPGA_OVERT_ISO_N")
	)
	(segment
		(start 258.202684 -124.89942)
		(end 258.602734 -125.29947)
		(width 0.11684)
		(layer "In15.Cu")
		(net "GPU_FPGA_OVERT_ISO_N")
	)
	(segment
		(start 406.999694 -362.004864)
		(end 405.311864 -363.692694)
		(width 0.11684)
		(layer "In15.Cu")
		(net "GPU_FPGA_OVERT_ISO_N")
	)
	(segment
		(start 265.897614 -126.327408)
		(end 271.681956 -126.327408)
		(width 0.11684)
		(layer "In15.Cu")
		(net "GPU_FPGA_OVERT_ISO_N")
	)
	(segment
		(start 407.901394 -332.478634)
		(end 407.23566 -333.144368)
		(width 0.11684)
		(layer "In15.Cu")
		(net "GPU_FPGA_OVERT_ISO_N")
	)
	(segment
		(start 396.36573 -331.1525)
		(end 395.53134 -331.98689)
		(width 0.11684)
		(layer "In15.Cu")
		(net "GPU_FPGA_OVERT_ISO_N")
	)
	(segment
		(start 398.045432 -331.1525)
		(end 396.36573 -331.1525)
		(width 0.11684)
		(layer "In15.Cu")
		(net "GPU_FPGA_OVERT_ISO_N")
	)
	(segment
		(start 454.815448 -326.504046)
		(end 415.276284 -326.504046)
		(width 0.11684)
		(layer "In15.Cu")
		(net "GPU_FPGA_OVERT_ISO_N")
	)
	(segment
		(start 258.602734 -125.29947)
		(end 264.869676 -125.29947)
		(width 0.11684)
		(layer "In15.Cu")
		(net "GPU_FPGA_OVERT_ISO_N")
	)
	(segment
		(start 406.999694 -346.324428)
		(end 406.999694 -362.004864)
		(width 0.11684)
		(layer "In15.Cu")
		(net "GPU_FPGA_OVERT_ISO_N")
	)
	(segment
		(start 272.992342 -127.637794)
		(end 286.728408 -127.637794)
		(width 0.11684)
		(layer "In15.Cu")
		(net "GPU_FPGA_OVERT_ISO_N")
	)
	(segment
		(start 415.276284 -326.504046)
		(end 409.301696 -332.478634)
		(width 0.11684)
		(layer "In15.Cu")
		(net "GPU_FPGA_OVERT_ISO_N")
	)
	(segment
		(start 264.869676 -125.29947)
		(end 265.897614 -126.327408)
		(width 0.11684)
		(layer "In15.Cu")
		(net "GPU_FPGA_OVERT_ISO_N")
	)
	(segment
		(start 409.301696 -332.478634)
		(end 407.901394 -332.478634)
		(width 0.11684)
		(layer "In15.Cu")
		(net "GPU_FPGA_OVERT_ISO_N")
	)
	(segment
		(start 286.728408 -127.637794)
		(end 288.873692 -129.783078)
		(width 0.11684)
		(layer "In15.Cu")
		(net "GPU_FPGA_OVERT_ISO_N")
	)
	(segment
		(start 297.92422 -125.20422)
		(end 371.409468 -125.20422)
		(width 0.11684)
		(layer "In15.Cu")
		(net "GPU_FPGA_OVERT_ISO_N")
	)
	(segment
		(start 455.494898 -151.462232)
		(end 454.621138 -152.335992)
		(width 0.11684)
		(layer "In15.Cu")
		(net "GPU_FPGA_OVERT_ISO_N")
	)
	(segment
		(start 288.873692 -129.783078)
		(end 293.345362 -129.783078)
		(width 0.11684)
		(layer "In15.Cu")
		(net "GPU_FPGA_OVERT_ISO_N")
	)
	(segment
		(start 455.494898 -136.968484)
		(end 455.494898 -151.462232)
		(width 0.11684)
		(layer "In15.Cu")
		(net "GPU_FPGA_OVERT_ISO_N")
	)
	(segment
		(start 454.621138 -152.335992)
		(end 454.621138 -165.273482)
		(width 0.11684)
		(layer "In15.Cu")
		(net "GPU_FPGA_OVERT_ISO_N")
	)
	(segment
		(start 371.409468 -125.20422)
		(end 374.448578 -128.24333)
		(width 0.11684)
		(layer "In15.Cu")
		(net "GPU_FPGA_OVERT_ISO_N")
	)
	(segment
		(start 395.53134 -331.98689)
		(end 395.53134 -334.856074)
		(width 0.11684)
		(layer "In15.Cu")
		(net "GPU_FPGA_OVERT_ISO_N")
	)
	(segment
		(start 407.23566 -333.144368)
		(end 400.0373 -333.144368)
		(width 0.11684)
		(layer "In15.Cu")
		(net "GPU_FPGA_OVERT_ISO_N")
	)
	(segment
		(start 202.846432 -122.443748)
		(end 213.535514 -122.443748)
		(width 0.11684)
		(layer "In15.Cu")
		(net "GPU_FPGA_OVERT_ISO_N")
	)
	(segment
		(start 446.769744 -128.24333)
		(end 455.494898 -136.968484)
		(width 0.11684)
		(layer "In15.Cu")
		(net "GPU_FPGA_OVERT_ISO_N")
	)
	(segment
		(start 253.603506 -124.89942)
		(end 258.202684 -124.89942)
		(width 0.11684)
		(layer "In15.Cu")
		(net "GPU_FPGA_OVERT_ISO_N")
	)
	(segment
		(start 215.73871 -122.925332)
		(end 216.3572 -123.543822)
		(width 0.11684)
		(layer "In15.Cu")
		(net "GPU_FPGA_OVERT_ISO_N")
	)
	(segment
		(start 214.017098 -122.925332)
		(end 215.73871 -122.925332)
		(width 0.11684)
		(layer "In15.Cu")
		(net "GPU_FPGA_OVERT_ISO_N")
	)
	(segment
		(start 226.090734 -125.297946)
		(end 246.825516 -125.297946)
		(width 0.11684)
		(layer "In15.Cu")
		(net "GPU_FPGA_OVERT_ISO_N")
	)
	(segment
		(start 271.681956 -126.327408)
		(end 272.992342 -127.637794)
		(width 0.11684)
		(layer "In15.Cu")
		(net "GPU_FPGA_OVERT_ISO_N")
	)
	(segment
		(start 202.520804 -122.769376)
		(end 202.846432 -122.443748)
		(width 0.11684)
		(layer "In15.Cu")
		(net "GPU_FPGA_OVERT_ISO_N")
	)
	(segment
		(start 216.3572 -123.543822)
		(end 224.33661 -123.543822)
		(width 0.11684)
		(layer "In15.Cu")
		(net "GPU_FPGA_OVERT_ISO_N")
	)
	(segment
		(start 461.963008 -319.356486)
		(end 454.815448 -326.504046)
		(width 0.11684)
		(layer "In15.Cu")
		(net "GPU_FPGA_OVERT_ISO_N")
	)
	(segment
		(start 293.345362 -129.783078)
		(end 297.92422 -125.20422)
		(width 0.11684)
		(layer "In15.Cu")
		(net "GPU_FPGA_OVERT_ISO_N")
	)
	(segment
		(start 213.535514 -122.443748)
		(end 214.017098 -122.925332)
		(width 0.11684)
		(layer "In15.Cu")
		(net "GPU_FPGA_OVERT_ISO_N")
	)
	(segment
		(start 246.825516 -125.297946)
		(end 247.547638 -124.575824)
		(width 0.11684)
		(layer "In15.Cu")
		(net "GPU_FPGA_OVERT_ISO_N")
	)
	(segment
		(start 454.621138 -165.273482)
		(end 461.963008 -172.615352)
		(width 0.11684)
		(layer "In15.Cu")
		(net "GPU_FPGA_OVERT_ISO_N")
	)
	(segment
		(start 224.33661 -123.543822)
		(end 226.090734 -125.297946)
		(width 0.11684)
		(layer "In15.Cu")
		(net "GPU_FPGA_OVERT_ISO_N")
	)
	(segment
		(start 374.448578 -128.24333)
		(end 446.769744 -128.24333)
		(width 0.11684)
		(layer "In15.Cu")
		(net "GPU_FPGA_OVERT_ISO_N")
	)
	(segment
		(start 400.0373 -333.144368)
		(end 398.045432 -331.1525)
		(width 0.11684)
		(layer "In15.Cu")
		(net "GPU_FPGA_OVERT_ISO_N")
	)
	(segment
		(start 395.53134 -334.856074)
		(end 406.999694 -346.324428)
		(width 0.11684)
		(layer "In15.Cu")
		(net "GPU_FPGA_OVERT_ISO_N")
	)
	(segment
		(start 247.547638 -124.575824)
		(end 253.27991 -124.575824)
		(width 0.11684)
		(layer "In15.Cu")
		(net "GPU_FPGA_OVERT_ISO_N")
	)
	(segment
		(start 253.27991 -124.575824)
		(end 253.603506 -124.89942)
		(width 0.11684)
		(layer "In15.Cu")
		(net "GPU_FPGA_OVERT_ISO_N")
	)
	(segment
		(start 303.343818 -433.614322)
		(end 302.109378 -433.614322)
		(width 0.10668)
		(layer "F.Cu")
		(net "GPU_FPGA_OVERT")
	)
	(segment
		(start 303.343818 -434.264308)
		(end 303.343818 -433.614322)
		(width 0.10668)
		(layer "F.Cu")
		(net "GPU_FPGA_OVERT")
	)
	(segment
		(start 302.109378 -434.833522)
		(end 302.109378 -433.614322)
		(width 0.10668)
		(layer "F.Cu")
		(net "GPU_FPGA_OVERT")
	)
	(via
		(at 302.109378 -433.614322)
		(size 0.762)
		(drill 0.381)
		(layers "F.Cu" "B.Cu")
		(net "GPU_FPGA_OVERT")
	)
	(segment
		(start 201.352658 -110.577376)
		(end 202.268582 -110.577376)
		(width 0.10668)
		(layer "F.Cu")
		(net "GPU_FPGA_EROT_RST_N")
	)
	(segment
		(start 219.495624 -199.537574)
		(end 218.839288 -198.881238)
		(width 0.10668)
		(layer "F.Cu")
		(net "GPU_FPGA_EROT_RST_N")
	)
	(segment
		(start 212.682836 -166.31412)
		(end 206.814928 -160.446212)
		(width 0.10668)
		(layer "F.Cu")
		(net "GPU_FPGA_EROT_RST_N")
	)
	(segment
		(start 218.839288 -181.17566)
		(end 212.682836 -166.31412)
		(width 0.10668)
		(layer "F.Cu")
		(net "GPU_FPGA_EROT_RST_N")
	)
	(segment
		(start 206.49819 -160.446212)
		(end 204.5081 -158.456122)
		(width 0.10668)
		(layer "F.Cu")
		(net "GPU_FPGA_EROT_RST_N")
	)
	(segment
		(start 103.236014 -424.11396)
		(end 103.236014 -424.800014)
		(width 0.10668)
		(layer "F.Cu")
		(net "GPU_FPGA_EROT_RST_N")
	)
	(segment
		(start 102.87 -426.06595)
		(end 102.87 -425.45)
		(width 0.10668)
		(layer "F.Cu")
		(net "GPU_FPGA_EROT_RST_N")
	)
	(segment
		(start 102.87 -426.06595)
		(end 103.886 -426.06595)
		(width 0.10668)
		(layer "F.Cu")
		(net "GPU_FPGA_EROT_RST_N")
	)
	(segment
		(start 103.236014 -424.800014)
		(end 103.886 -425.45)
		(width 0.10668)
		(layer "F.Cu")
		(net "GPU_FPGA_EROT_RST_N")
	)
	(segment
		(start 219.828364 -199.537574)
		(end 219.495624 -199.537574)
		(width 0.10668)
		(layer "F.Cu")
		(net "GPU_FPGA_EROT_RST_N")
	)
	(segment
		(start 103.886 -425.45)
		(end 103.886 -426.06595)
		(width 0.10668)
		(layer "F.Cu")
		(net "GPU_FPGA_EROT_RST_N")
	)
	(segment
		(start 206.814928 -160.446212)
		(end 206.49819 -160.446212)
		(width 0.10668)
		(layer "F.Cu")
		(net "GPU_FPGA_EROT_RST_N")
	)
	(segment
		(start 218.839288 -198.881238)
		(end 218.839288 -181.17566)
		(width 0.10668)
		(layer "F.Cu")
		(net "GPU_FPGA_EROT_RST_N")
	)
	(via
		(at 102.87 -425.45)
		(size 0.508)
		(drill 0.254)
		(layers "F.Cu" "B.Cu")
		(net "GPU_FPGA_EROT_RST_N")
	)
	(via
		(at 204.5081 -158.456122)
		(size 0.508)
		(drill 0.254)
		(layers "F.Cu" "B.Cu")
		(net "GPU_FPGA_EROT_RST_N")
	)
	(via
		(at 202.268582 -110.577376)
		(size 0.508)
		(drill 0.254)
		(layers "F.Cu" "B.Cu")
		(net "GPU_FPGA_EROT_RST_N")
	)
	(via
		(at 172.3009 -398.1196)
		(size 0.508)
		(drill 0.254)
		(layers "F.Cu" "B.Cu")
		(net "GPU_FPGA_EROT_RST_N")
	)
	(via
		(at 219.828364 -199.537574)
		(size 0.508)
		(drill 0.254)
		(layers "F.Cu" "B.Cu")
		(net "GPU_FPGA_EROT_RST_N")
	)
	(via
		(at 170.383962 -420.269924)
		(size 0.508)
		(drill 0.254)
		(layers "F.Cu" "B.Cu")
		(net "GPU_FPGA_EROT_RST_N")
	)
	(segment
		(start 103.503476 -426.083476)
		(end 102.87 -425.45)
		(width 0.11684)
		(layer "In2.Cu")
		(net "GPU_FPGA_EROT_RST_N")
	)
	(segment
		(start 124.438156 -418.588698)
		(end 121.642632 -421.384222)
		(width 0.11684)
		(layer "In2.Cu")
		(net "GPU_FPGA_EROT_RST_N")
	)
	(segment
		(start 121.642632 -421.384222)
		(end 118.173754 -421.384222)
		(width 0.11684)
		(layer "In2.Cu")
		(net "GPU_FPGA_EROT_RST_N")
	)
	(segment
		(start 170.383962 -420.269924)
		(end 169.79138 -420.862506)
		(width 0.11684)
		(layer "In2.Cu")
		(net "GPU_FPGA_EROT_RST_N")
	)
	(segment
		(start 107.72775 -424.636692)
		(end 106.280966 -426.083476)
		(width 0.11684)
		(layer "In2.Cu")
		(net "GPU_FPGA_EROT_RST_N")
	)
	(segment
		(start 109.504226 -420.904416)
		(end 107.72775 -422.680892)
		(width 0.11684)
		(layer "In2.Cu")
		(net "GPU_FPGA_EROT_RST_N")
	)
	(segment
		(start 117.52199 -422.035986)
		(end 116.474494 -422.035986)
		(width 0.11684)
		(layer "In2.Cu")
		(net "GPU_FPGA_EROT_RST_N")
	)
	(segment
		(start 107.72775 -422.680892)
		(end 107.72775 -424.636692)
		(width 0.11684)
		(layer "In2.Cu")
		(net "GPU_FPGA_EROT_RST_N")
	)
	(segment
		(start 169.79138 -420.862506)
		(end 163.261294 -420.862506)
		(width 0.11684)
		(layer "In2.Cu")
		(net "GPU_FPGA_EROT_RST_N")
	)
	(segment
		(start 160.987486 -418.588698)
		(end 124.438156 -418.588698)
		(width 0.11684)
		(layer "In2.Cu")
		(net "GPU_FPGA_EROT_RST_N")
	)
	(segment
		(start 163.261294 -420.862506)
		(end 160.987486 -418.588698)
		(width 0.11684)
		(layer "In2.Cu")
		(net "GPU_FPGA_EROT_RST_N")
	)
	(segment
		(start 115.342924 -420.904416)
		(end 109.504226 -420.904416)
		(width 0.11684)
		(layer "In2.Cu")
		(net "GPU_FPGA_EROT_RST_N")
	)
	(segment
		(start 116.474494 -422.035986)
		(end 115.342924 -420.904416)
		(width 0.11684)
		(layer "In2.Cu")
		(net "GPU_FPGA_EROT_RST_N")
	)
	(segment
		(start 118.173754 -421.384222)
		(end 117.52199 -422.035986)
		(width 0.11684)
		(layer "In2.Cu")
		(net "GPU_FPGA_EROT_RST_N")
	)
	(segment
		(start 106.280966 -426.083476)
		(end 103.503476 -426.083476)
		(width 0.11684)
		(layer "In2.Cu")
		(net "GPU_FPGA_EROT_RST_N")
	)
	(segment
		(start 202.268582 -110.935516)
		(end 201.417682 -111.786416)
		(width 0.11684)
		(layer "In4.Cu")
		(net "GPU_FPGA_EROT_RST_N")
	)
	(segment
		(start 202.268582 -110.577376)
		(end 202.268582 -110.935516)
		(width 0.11684)
		(layer "In4.Cu")
		(net "GPU_FPGA_EROT_RST_N")
	)
	(segment
		(start 201.18705 -128.318768)
		(end 201.18705 -131.844288)
		(width 0.11684)
		(layer "In4.Cu")
		(net "GPU_FPGA_EROT_RST_N")
	)
	(segment
		(start 203.119228 -123.941586)
		(end 201.803508 -125.257306)
		(width 0.11684)
		(layer "In4.Cu")
		(net "GPU_FPGA_EROT_RST_N")
	)
	(segment
		(start 201.18705 -131.844288)
		(end 202.44054 -133.097778)
		(width 0.11684)
		(layer "In4.Cu")
		(net "GPU_FPGA_EROT_RST_N")
	)
	(segment
		(start 203.586334 -157.534356)
		(end 204.5081 -158.456122)
		(width 0.11684)
		(layer "In4.Cu")
		(net "GPU_FPGA_EROT_RST_N")
	)
	(segment
		(start 202.129898 -120.370854)
		(end 202.743562 -120.370854)
		(width 0.11684)
		(layer "In4.Cu")
		(net "GPU_FPGA_EROT_RST_N")
	)
	(segment
		(start 203.119228 -120.74652)
		(end 203.119228 -123.941586)
		(width 0.11684)
		(layer "In4.Cu")
		(net "GPU_FPGA_EROT_RST_N")
	)
	(segment
		(start 202.44054 -138.160252)
		(end 203.586334 -139.306046)
		(width 0.11684)
		(layer "In4.Cu")
		(net "GPU_FPGA_EROT_RST_N")
	)
	(segment
		(start 201.417682 -119.658638)
		(end 202.129898 -120.370854)
		(width 0.11684)
		(layer "In4.Cu")
		(net "GPU_FPGA_EROT_RST_N")
	)
	(segment
		(start 202.44054 -133.097778)
		(end 202.44054 -138.160252)
		(width 0.11684)
		(layer "In4.Cu")
		(net "GPU_FPGA_EROT_RST_N")
	)
	(segment
		(start 201.417682 -111.786416)
		(end 201.417682 -119.658638)
		(width 0.11684)
		(layer "In4.Cu")
		(net "GPU_FPGA_EROT_RST_N")
	)
	(segment
		(start 203.586334 -139.306046)
		(end 203.586334 -157.534356)
		(width 0.11684)
		(layer "In4.Cu")
		(net "GPU_FPGA_EROT_RST_N")
	)
	(segment
		(start 201.803508 -127.70231)
		(end 201.18705 -128.318768)
		(width 0.11684)
		(layer "In4.Cu")
		(net "GPU_FPGA_EROT_RST_N")
	)
	(segment
		(start 202.743562 -120.370854)
		(end 203.119228 -120.74652)
		(width 0.11684)
		(layer "In4.Cu")
		(net "GPU_FPGA_EROT_RST_N")
	)
	(segment
		(start 201.803508 -125.257306)
		(end 201.803508 -127.70231)
		(width 0.11684)
		(layer "In4.Cu")
		(net "GPU_FPGA_EROT_RST_N")
	)
	(segment
		(start 168.91 -419.228778)
		(end 169.306494 -419.228778)
		(width 0.11684)
		(layer "In13.Cu")
		(net "GPU_FPGA_EROT_RST_N")
	)
	(segment
		(start 165.009068 -408.030426)
		(end 166.206424 -409.227782)
		(width 0.11684)
		(layer "In13.Cu")
		(net "GPU_FPGA_EROT_RST_N")
	)
	(segment
		(start 166.206424 -416.525202)
		(end 168.91 -419.228778)
		(width 0.11684)
		(layer "In13.Cu")
		(net "GPU_FPGA_EROT_RST_N")
	)
	(segment
		(start 169.360596 -419.246558)
		(end 170.383962 -420.269924)
		(width 0.11684)
		(layer "In13.Cu")
		(net "GPU_FPGA_EROT_RST_N")
	)
	(segment
		(start 165.009068 -401.719034)
		(end 165.009068 -408.030426)
		(width 0.11684)
		(layer "In13.Cu")
		(net "GPU_FPGA_EROT_RST_N")
	)
	(segment
		(start 168.608502 -398.1196)
		(end 165.009068 -401.719034)
		(width 0.11684)
		(layer "In13.Cu")
		(net "GPU_FPGA_EROT_RST_N")
	)
	(segment
		(start 172.3009 -398.1196)
		(end 168.608502 -398.1196)
		(width 0.11684)
		(layer "In13.Cu")
		(net "GPU_FPGA_EROT_RST_N")
	)
	(segment
		(start 169.324274 -419.246558)
		(end 169.360596 -419.246558)
		(width 0.11684)
		(layer "In13.Cu")
		(net "GPU_FPGA_EROT_RST_N")
	)
	(segment
		(start 166.206424 -409.227782)
		(end 166.206424 -416.525202)
		(width 0.11684)
		(layer "In13.Cu")
		(net "GPU_FPGA_EROT_RST_N")
	)
	(segment
		(start 169.306494 -419.228778)
		(end 169.324274 -419.246558)
		(width 0.11684)
		(layer "In13.Cu")
		(net "GPU_FPGA_EROT_RST_N")
	)
	(segment
		(start 172.927518 -395.553438)
		(end 173.900084 -394.580872)
		(width 0.11684)
		(layer "In15.Cu")
		(net "GPU_FPGA_EROT_RST_N")
	)
	(segment
		(start 213.205822 -319.457324)
		(end 213.205822 -202.902566)
		(width 0.11684)
		(layer "In15.Cu")
		(net "GPU_FPGA_EROT_RST_N")
	)
	(segment
		(start 186.702192 -370.88699)
		(end 189.272672 -368.31651)
		(width 0.11684)
		(layer "In15.Cu")
		(net "GPU_FPGA_EROT_RST_N")
	)
	(segment
		(start 213.205822 -202.902566)
		(end 216.570814 -199.537574)
		(width 0.11684)
		(layer "In15.Cu")
		(net "GPU_FPGA_EROT_RST_N")
	)
	(segment
		(start 216.570814 -199.537574)
		(end 219.828364 -199.537574)
		(width 0.11684)
		(layer "In15.Cu")
		(net "GPU_FPGA_EROT_RST_N")
	)
	(segment
		(start 219.430854 -325.682356)
		(end 213.205822 -319.457324)
		(width 0.11684)
		(layer "In15.Cu")
		(net "GPU_FPGA_EROT_RST_N")
	)
	(segment
		(start 172.927518 -397.700246)
		(end 172.927518 -395.553438)
		(width 0.11684)
		(layer "In15.Cu")
		(net "GPU_FPGA_EROT_RST_N")
	)
	(segment
		(start 173.900084 -393.299188)
		(end 186.702192 -380.49708)
		(width 0.11684)
		(layer "In15.Cu")
		(net "GPU_FPGA_EROT_RST_N")
	)
	(segment
		(start 172.508164 -398.1196)
		(end 172.927518 -397.700246)
		(width 0.11684)
		(layer "In15.Cu")
		(net "GPU_FPGA_EROT_RST_N")
	)
	(segment
		(start 186.702192 -380.49708)
		(end 186.702192 -370.88699)
		(width 0.11684)
		(layer "In15.Cu")
		(net "GPU_FPGA_EROT_RST_N")
	)
	(segment
		(start 173.900084 -394.580872)
		(end 173.900084 -393.299188)
		(width 0.11684)
		(layer "In15.Cu")
		(net "GPU_FPGA_EROT_RST_N")
	)
	(segment
		(start 219.430854 -342.561164)
		(end 219.430854 -325.682356)
		(width 0.11684)
		(layer "In15.Cu")
		(net "GPU_FPGA_EROT_RST_N")
	)
	(segment
		(start 189.272672 -368.31651)
		(end 193.675508 -368.31651)
		(width 0.11684)
		(layer "In15.Cu")
		(net "GPU_FPGA_EROT_RST_N")
	)
	(segment
		(start 193.675508 -368.31651)
		(end 219.430854 -342.561164)
		(width 0.11684)
		(layer "In15.Cu")
		(net "GPU_FPGA_EROT_RST_N")
	)
	(segment
		(start 172.3009 -398.1196)
		(end 172.508164 -398.1196)
		(width 0.11684)
		(layer "In15.Cu")
		(net "GPU_FPGA_EROT_RST_N")
	)
	(segment
		(start 103.10495 -418.973)
		(end 103.10495 -419.989)
		(width 0.10668)
		(layer "F.Cu")
		(net "GPU_FPGA_EROT_RST_BUF_R_N")
	)
	(segment
		(start 103.10495 -419.989)
		(end 103.10495 -420.746936)
		(width 0.10668)
		(layer "F.Cu")
		(net "GPU_FPGA_EROT_RST_BUF_R_N")
	)
	(segment
		(start 103.236014 -422.21404)
		(end 103.236014 -420.878)
		(width 0.10668)
		(layer "F.Cu")
		(net "GPU_FPGA_EROT_RST_BUF_R_N")
	)
	(segment
		(start 103.10495 -418.973)
		(end 103.10495 -417.957)
		(width 0.10668)
		(layer "F.Cu")
		(net "GPU_FPGA_EROT_RST_BUF_R_N")
	)
	(segment
		(start 103.10495 -420.746936)
		(end 103.236014 -420.878)
		(width 0.10668)
		(layer "F.Cu")
		(net "GPU_FPGA_EROT_RST_BUF_R_N")
	)
	(via
		(at 103.236014 -420.878)
		(size 0.762)
		(drill 0.381)
		(layers "F.Cu" "B.Cu")
		(net "GPU_FPGA_EROT_RST_BUF_R_N")
	)
	(segment
		(start 104.778556 -417.703)
		(end 104.15905 -417.703)
		(width 0.10668)
		(layer "F.Cu")
		(net "GPU_FPGA_EROT_RST_BUF_N")
	)
	(segment
		(start 107.569 -419.735)
		(end 106.34091 -418.50691)
		(width 0.10668)
		(layer "F.Cu")
		(net "GPU_FPGA_EROT_RST_BUF_N")
	)
	(segment
		(start 104.15905 -417.703)
		(end 103.90505 -417.957)
		(width 0.10668)
		(layer "F.Cu")
		(net "GPU_FPGA_EROT_RST_BUF_N")
	)
	(segment
		(start 105.582466 -418.50691)
		(end 104.778556 -417.703)
		(width 0.10668)
		(layer "F.Cu")
		(net "GPU_FPGA_EROT_RST_BUF_N")
	)
	(segment
		(start 106.34091 -418.50691)
		(end 105.582466 -418.50691)
		(width 0.10668)
		(layer "F.Cu")
		(net "GPU_FPGA_EROT_RST_BUF_N")
	)
	(via
		(at 107.569 -419.735)
		(size 0.508)
		(drill 0.254)
		(layers "F.Cu" "B.Cu")
		(net "GPU_FPGA_EROT_RST_BUF_N")
	)
	(segment
		(start 139.749784 -424.689778)
		(end 135.750808 -420.690802)
		(width 0.10668)
		(layer "B.Cu")
		(net "GPU_FPGA_EROT_RST_BUF_N")
	)
	(segment
		(start 117.856 -420.116)
		(end 117.475 -419.735)
		(width 0.10668)
		(layer "B.Cu")
		(net "GPU_FPGA_EROT_RST_BUF_N")
	)
	(segment
		(start 135.750808 -420.690802)
		(end 122.494802 -420.690802)
		(width 0.10668)
		(layer "B.Cu")
		(net "GPU_FPGA_EROT_RST_BUF_N")
	)
	(segment
		(start 121.816876 -420.012876)
		(end 120.626124 -420.012876)
		(width 0.10668)
		(layer "B.Cu")
		(net "GPU_FPGA_EROT_RST_BUF_N")
	)
	(segment
		(start 122.494802 -420.690802)
		(end 121.816876 -420.012876)
		(width 0.10668)
		(layer "B.Cu")
		(net "GPU_FPGA_EROT_RST_BUF_N")
	)
	(segment
		(start 120.523 -420.116)
		(end 117.856 -420.116)
		(width 0.10668)
		(layer "B.Cu")
		(net "GPU_FPGA_EROT_RST_BUF_N")
	)
	(segment
		(start 117.475 -419.735)
		(end 107.569 -419.735)
		(width 0.10668)
		(layer "B.Cu")
		(net "GPU_FPGA_EROT_RST_BUF_N")
	)
	(segment
		(start 120.626124 -420.012876)
		(end 120.523 -420.116)
		(width 0.10668)
		(layer "B.Cu")
		(net "GPU_FPGA_EROT_RST_BUF_N")
	)
	(segment
		(start 206.482696 -110.649512)
		(end 206.554832 -110.577376)
		(width 0.10668)
		(layer "F.Cu")
		(net "GPU_FPGA_EROT_RECOV_N")
	)
	(segment
		(start 218.255088 -186.034172)
		(end 208.8261 -163.272724)
		(width 0.10668)
		(layer "F.Cu")
		(net "GPU_FPGA_EROT_RECOV_N")
	)
	(segment
		(start 205.634336 -110.649512)
		(end 206.482696 -110.649512)
		(width 0.10668)
		(layer "F.Cu")
		(net "GPU_FPGA_EROT_RECOV_N")
	)
	(segment
		(start 208.8261 -163.272724)
		(end 208.436718 -162.883342)
		(width 0.10668)
		(layer "F.Cu")
		(net "GPU_FPGA_EROT_RECOV_N")
	)
	(segment
		(start 218.255088 -199.56145)
		(end 218.255088 -186.034172)
		(width 0.10668)
		(layer "F.Cu")
		(net "GPU_FPGA_EROT_RECOV_N")
	)
	(segment
		(start 120.023636 -439.547)
		(end 120.023636 -438.793382)
		(width 0.10668)
		(layer "F.Cu")
		(net "GPU_FPGA_EROT_RECOV_N")
	)
	(segment
		(start 119.99595 -440.309)
		(end 119.99595 -439.574686)
		(width 0.10668)
		(layer "F.Cu")
		(net "GPU_FPGA_EROT_RECOV_N")
	)
	(segment
		(start 219.501212 -200.807574)
		(end 218.255088 -199.56145)
		(width 0.10668)
		(layer "F.Cu")
		(net "GPU_FPGA_EROT_RECOV_N")
	)
	(segment
		(start 119.99595 -439.574686)
		(end 120.023636 -439.547)
		(width 0.10668)
		(layer "F.Cu")
		(net "GPU_FPGA_EROT_RECOV_N")
	)
	(segment
		(start 219.828364 -200.807574)
		(end 219.501212 -200.807574)
		(width 0.10668)
		(layer "F.Cu")
		(net "GPU_FPGA_EROT_RECOV_N")
	)
	(segment
		(start 119.01805 -440.309)
		(end 119.99595 -440.309)
		(width 0.10668)
		(layer "F.Cu")
		(net "GPU_FPGA_EROT_RECOV_N")
	)
	(segment
		(start 119.01805 -440.309)
		(end 119.01805 -439.674)
		(width 0.10668)
		(layer "F.Cu")
		(net "GPU_FPGA_EROT_RECOV_N")
	)
	(via
		(at 206.554832 -110.577376)
		(size 0.508)
		(drill 0.254)
		(layers "F.Cu" "B.Cu")
		(net "GPU_FPGA_EROT_RECOV_N")
	)
	(via
		(at 119.01805 -439.674)
		(size 0.508)
		(drill 0.254)
		(layers "F.Cu" "B.Cu")
		(net "GPU_FPGA_EROT_RECOV_N")
	)
	(via
		(at 208.436718 -162.883342)
		(size 0.508)
		(drill 0.254)
		(layers "F.Cu" "B.Cu")
		(net "GPU_FPGA_EROT_RECOV_N")
	)
	(via
		(at 170.89374 -399.17624)
		(size 0.508)
		(drill 0.254)
		(layers "F.Cu" "B.Cu")
		(net "GPU_FPGA_EROT_RECOV_N")
	)
	(via
		(at 219.828364 -200.807574)
		(size 0.508)
		(drill 0.254)
		(layers "F.Cu" "B.Cu")
		(net "GPU_FPGA_EROT_RECOV_N")
	)
	(via
		(at 174.179738 -424.002962)
		(size 0.508)
		(drill 0.254)
		(layers "F.Cu" "B.Cu")
		(net "GPU_FPGA_EROT_RECOV_N")
	)
	(segment
		(start 163.856416 -423.902124)
		(end 164.535612 -424.58132)
		(width 0.11684)
		(layer "In2.Cu")
		(net "GPU_FPGA_EROT_RECOV_N")
	)
	(segment
		(start 163.080192 -423.331386)
		(end 163.127182 -423.28465)
		(width 0.11684)
		(layer "In2.Cu")
		(net "GPU_FPGA_EROT_RECOV_N")
	)
	(segment
		(start 118.53418 -434.72227)
		(end 118.53418 -428.432214)
		(width 0.11684)
		(layer "In2.Cu")
		(net "GPU_FPGA_EROT_RECOV_N")
	)
	(segment
		(start 164.535612 -424.58132)
		(end 173.60138 -424.58132)
		(width 0.11684)
		(layer "In2.Cu")
		(net "GPU_FPGA_EROT_RECOV_N")
	)
	(segment
		(start 162.988752 -423.422826)
		(end 163.080192 -423.331386)
		(width 0.11684)
		(layer "In2.Cu")
		(net "GPU_FPGA_EROT_RECOV_N")
	)
	(segment
		(start 162.38855 -423.422826)
		(end 162.988752 -423.422826)
		(width 0.11684)
		(layer "In2.Cu")
		(net "GPU_FPGA_EROT_RECOV_N")
	)
	(segment
		(start 126.049278 -421.405812)
		(end 160.371536 -421.405812)
		(width 0.11684)
		(layer "In2.Cu")
		(net "GPU_FPGA_EROT_RECOV_N")
	)
	(segment
		(start 163.55441 -423.28465)
		(end 163.856416 -423.586656)
		(width 0.11684)
		(layer "In2.Cu")
		(net "GPU_FPGA_EROT_RECOV_N")
	)
	(segment
		(start 121.209054 -425.75734)
		(end 121.69775 -425.75734)
		(width 0.11684)
		(layer "In2.Cu")
		(net "GPU_FPGA_EROT_RECOV_N")
	)
	(segment
		(start 163.856416 -423.586656)
		(end 163.856416 -423.902124)
		(width 0.11684)
		(layer "In2.Cu")
		(net "GPU_FPGA_EROT_RECOV_N")
	)
	(segment
		(start 118.87962 -435.06771)
		(end 118.53418 -434.72227)
		(width 0.11684)
		(layer "In2.Cu")
		(net "GPU_FPGA_EROT_RECOV_N")
	)
	(segment
		(start 118.87962 -436.014622)
		(end 118.87962 -435.06771)
		(width 0.11684)
		(layer "In2.Cu")
		(net "GPU_FPGA_EROT_RECOV_N")
	)
	(segment
		(start 118.53418 -428.432214)
		(end 121.209054 -425.75734)
		(width 0.11684)
		(layer "In2.Cu")
		(net "GPU_FPGA_EROT_RECOV_N")
	)
	(segment
		(start 118.258844 -438.914794)
		(end 118.258844 -436.635398)
		(width 0.11684)
		(layer "In2.Cu")
		(net "GPU_FPGA_EROT_RECOV_N")
	)
	(segment
		(start 118.258844 -436.635398)
		(end 118.87962 -436.014622)
		(width 0.11684)
		(layer "In2.Cu")
		(net "GPU_FPGA_EROT_RECOV_N")
	)
	(segment
		(start 163.127182 -423.28465)
		(end 163.55441 -423.28465)
		(width 0.11684)
		(layer "In2.Cu")
		(net "GPU_FPGA_EROT_RECOV_N")
	)
	(segment
		(start 173.60138 -424.58132)
		(end 174.179738 -424.002962)
		(width 0.11684)
		(layer "In2.Cu")
		(net "GPU_FPGA_EROT_RECOV_N")
	)
	(segment
		(start 119.01805 -439.674)
		(end 118.258844 -438.914794)
		(width 0.11684)
		(layer "In2.Cu")
		(net "GPU_FPGA_EROT_RECOV_N")
	)
	(segment
		(start 121.69775 -425.75734)
		(end 126.049278 -421.405812)
		(width 0.11684)
		(layer "In2.Cu")
		(net "GPU_FPGA_EROT_RECOV_N")
	)
	(segment
		(start 160.371536 -421.405812)
		(end 162.38855 -423.422826)
		(width 0.11684)
		(layer "In2.Cu")
		(net "GPU_FPGA_EROT_RECOV_N")
	)
	(segment
		(start 206.210916 -132.090414)
		(end 207.268826 -133.148324)
		(width 0.11684)
		(layer "In4.Cu")
		(net "GPU_FPGA_EROT_RECOV_N")
	)
	(segment
		(start 207.268826 -133.148324)
		(end 207.268826 -140.654532)
		(width 0.11684)
		(layer "In4.Cu")
		(net "GPU_FPGA_EROT_RECOV_N")
	)
	(segment
		(start 208.16316 -123.007628)
		(end 208.541112 -123.38558)
		(width 0.11684)
		(layer "In4.Cu")
		(net "GPU_FPGA_EROT_RECOV_N")
	)
	(segment
		(start 207.068674 -110.063534)
		(end 207.72247 -110.063534)
		(width 0.11684)
		(layer "In4.Cu")
		(net "GPU_FPGA_EROT_RECOV_N")
	)
	(segment
		(start 207.72247 -110.063534)
		(end 208.16316 -110.504224)
		(width 0.11684)
		(layer "In4.Cu")
		(net "GPU_FPGA_EROT_RECOV_N")
	)
	(segment
		(start 206.8576 -129.935224)
		(end 206.210916 -130.581908)
		(width 0.11684)
		(layer "In4.Cu")
		(net "GPU_FPGA_EROT_RECOV_N")
	)
	(segment
		(start 206.8576 -127.66548)
		(end 206.8576 -129.935224)
		(width 0.11684)
		(layer "In4.Cu")
		(net "GPU_FPGA_EROT_RECOV_N")
	)
	(segment
		(start 208.16316 -110.504224)
		(end 208.16316 -123.007628)
		(width 0.11684)
		(layer "In4.Cu")
		(net "GPU_FPGA_EROT_RECOV_N")
	)
	(segment
		(start 208.541112 -123.38558)
		(end 208.541112 -125.981968)
		(width 0.11684)
		(layer "In4.Cu")
		(net "GPU_FPGA_EROT_RECOV_N")
	)
	(segment
		(start 206.210916 -130.581908)
		(end 206.210916 -132.090414)
		(width 0.11684)
		(layer "In4.Cu")
		(net "GPU_FPGA_EROT_RECOV_N")
	)
	(segment
		(start 207.268826 -140.654532)
		(end 208.436718 -141.822424)
		(width 0.11684)
		(layer "In4.Cu")
		(net "GPU_FPGA_EROT_RECOV_N")
	)
	(segment
		(start 208.541112 -125.981968)
		(end 206.8576 -127.66548)
		(width 0.11684)
		(layer "In4.Cu")
		(net "GPU_FPGA_EROT_RECOV_N")
	)
	(segment
		(start 208.436718 -141.822424)
		(end 208.436718 -162.883342)
		(width 0.11684)
		(layer "In4.Cu")
		(net "GPU_FPGA_EROT_RECOV_N")
	)
	(segment
		(start 206.554832 -110.577376)
		(end 207.068674 -110.063534)
		(width 0.11684)
		(layer "In4.Cu")
		(net "GPU_FPGA_EROT_RECOV_N")
	)
	(segment
		(start 167.790368 -412.248858)
		(end 172.137324 -416.595814)
		(width 0.11684)
		(layer "In13.Cu")
		(net "GPU_FPGA_EROT_RECOV_N")
	)
	(segment
		(start 165.778942 -402.349716)
		(end 165.778942 -407.732992)
		(width 0.11684)
		(layer "In13.Cu")
		(net "GPU_FPGA_EROT_RECOV_N")
	)
	(segment
		(start 170.0657 -399.17624)
		(end 169.54754 -399.6944)
		(width 0.11684)
		(layer "In13.Cu")
		(net "GPU_FPGA_EROT_RECOV_N")
	)
	(segment
		(start 174.77867 -420.661846)
		(end 174.77867 -423.40403)
		(width 0.11684)
		(layer "In13.Cu")
		(net "GPU_FPGA_EROT_RECOV_N")
	)
	(segment
		(start 168.434258 -399.6944)
		(end 165.778942 -402.349716)
		(width 0.11684)
		(layer "In13.Cu")
		(net "GPU_FPGA_EROT_RECOV_N")
	)
	(segment
		(start 172.137324 -416.595814)
		(end 172.137324 -418.0205)
		(width 0.11684)
		(layer "In13.Cu")
		(net "GPU_FPGA_EROT_RECOV_N")
	)
	(segment
		(start 170.89374 -399.17624)
		(end 170.0657 -399.17624)
		(width 0.11684)
		(layer "In13.Cu")
		(net "GPU_FPGA_EROT_RECOV_N")
	)
	(segment
		(start 169.54754 -399.6944)
		(end 168.434258 -399.6944)
		(width 0.11684)
		(layer "In13.Cu")
		(net "GPU_FPGA_EROT_RECOV_N")
	)
	(segment
		(start 174.77867 -423.40403)
		(end 174.179738 -424.002962)
		(width 0.11684)
		(layer "In13.Cu")
		(net "GPU_FPGA_EROT_RECOV_N")
	)
	(segment
		(start 167.790368 -409.744418)
		(end 167.790368 -412.248858)
		(width 0.11684)
		(layer "In13.Cu")
		(net "GPU_FPGA_EROT_RECOV_N")
	)
	(segment
		(start 172.137324 -418.0205)
		(end 174.77867 -420.661846)
		(width 0.11684)
		(layer "In13.Cu")
		(net "GPU_FPGA_EROT_RECOV_N")
	)
	(segment
		(start 165.778942 -407.732992)
		(end 167.790368 -409.744418)
		(width 0.11684)
		(layer "In13.Cu")
		(net "GPU_FPGA_EROT_RECOV_N")
	)
	(segment
		(start 213.947502 -319.14973)
		(end 213.947502 -203.209906)
		(width 0.11684)
		(layer "In15.Cu")
		(net "GPU_FPGA_EROT_RECOV_N")
	)
	(segment
		(start 170.89374 -399.17624)
		(end 172.87494 -399.17624)
		(width 0.11684)
		(layer "In15.Cu")
		(net "GPU_FPGA_EROT_RECOV_N")
	)
	(segment
		(start 175.027336 -394.738098)
		(end 175.027336 -394.273024)
		(width 0.11684)
		(layer "In15.Cu")
		(net "GPU_FPGA_EROT_RECOV_N")
	)
	(segment
		(start 213.947502 -203.209906)
		(end 216.349834 -200.807574)
		(width 0.11684)
		(layer "In15.Cu")
		(net "GPU_FPGA_EROT_RECOV_N")
	)
	(segment
		(start 216.349834 -200.807574)
		(end 219.828364 -200.807574)
		(width 0.11684)
		(layer "In15.Cu")
		(net "GPU_FPGA_EROT_RECOV_N")
	)
	(segment
		(start 193.424048 -369.61699)
		(end 220.172534 -342.868504)
		(width 0.11684)
		(layer "In15.Cu")
		(net "GPU_FPGA_EROT_RECOV_N")
	)
	(segment
		(start 220.172534 -325.374762)
		(end 213.947502 -319.14973)
		(width 0.11684)
		(layer "In15.Cu")
		(net "GPU_FPGA_EROT_RECOV_N")
	)
	(segment
		(start 180.101494 -388.146798)
		(end 187.532264 -380.716028)
		(width 0.11684)
		(layer "In15.Cu")
		(net "GPU_FPGA_EROT_RECOV_N")
	)
	(segment
		(start 175.027336 -394.273024)
		(end 180.101494 -389.198866)
		(width 0.11684)
		(layer "In15.Cu")
		(net "GPU_FPGA_EROT_RECOV_N")
	)
	(segment
		(start 173.980094 -398.071086)
		(end 173.980094 -395.78534)
		(width 0.11684)
		(layer "In15.Cu")
		(net "GPU_FPGA_EROT_RECOV_N")
	)
	(segment
		(start 220.172534 -342.868504)
		(end 220.172534 -325.374762)
		(width 0.11684)
		(layer "In15.Cu")
		(net "GPU_FPGA_EROT_RECOV_N")
	)
	(segment
		(start 173.980094 -395.78534)
		(end 175.027336 -394.738098)
		(width 0.11684)
		(layer "In15.Cu")
		(net "GPU_FPGA_EROT_RECOV_N")
	)
	(segment
		(start 190.299086 -369.61699)
		(end 193.424048 -369.61699)
		(width 0.11684)
		(layer "In15.Cu")
		(net "GPU_FPGA_EROT_RECOV_N")
	)
	(segment
		(start 180.101494 -389.198866)
		(end 180.101494 -388.146798)
		(width 0.11684)
		(layer "In15.Cu")
		(net "GPU_FPGA_EROT_RECOV_N")
	)
	(segment
		(start 187.532264 -372.383812)
		(end 190.299086 -369.61699)
		(width 0.11684)
		(layer "In15.Cu")
		(net "GPU_FPGA_EROT_RECOV_N")
	)
	(segment
		(start 187.532264 -380.716028)
		(end 187.532264 -372.383812)
		(width 0.11684)
		(layer "In15.Cu")
		(net "GPU_FPGA_EROT_RECOV_N")
	)
	(segment
		(start 172.87494 -399.17624)
		(end 173.980094 -398.071086)
		(width 0.11684)
		(layer "In15.Cu")
		(net "GPU_FPGA_EROT_RECOV_N")
	)
	(segment
		(start 120.023636 -436.893462)
		(end 120.023636 -435.510686)
		(width 0.10668)
		(layer "F.Cu")
		(net "GPU_FPGA_EROT_RECOV_BUF_R_N")
	)
	(segment
		(start 119.99595 -435.483)
		(end 119.99595 -434.467)
		(width 0.10668)
		(layer "F.Cu")
		(net "GPU_FPGA_EROT_RECOV_BUF_R_N")
	)
	(segment
		(start 119.99595 -434.467)
		(end 119.99595 -433.451)
		(width 0.10668)
		(layer "F.Cu")
		(net "GPU_FPGA_EROT_RECOV_BUF_R_N")
	)
	(segment
		(start 119.99595 -433.451)
		(end 118.364 -433.451)
		(width 0.10668)
		(layer "F.Cu")
		(net "GPU_FPGA_EROT_RECOV_BUF_R_N")
	)
	(segment
		(start 118.364 -433.451)
		(end 118.11 -433.197)
		(width 0.10668)
		(layer "F.Cu")
		(net "GPU_FPGA_EROT_RECOV_BUF_R_N")
	)
	(segment
		(start 120.023636 -435.510686)
		(end 119.99595 -435.483)
		(width 0.10668)
		(layer "F.Cu")
		(net "GPU_FPGA_EROT_RECOV_BUF_R_N")
	)
	(via
		(at 118.11 -433.197)
		(size 0.762)
		(drill 0.381)
		(layers "F.Cu" "B.Cu")
		(net "GPU_FPGA_EROT_RECOV_BUF_R_N")
	)
	(segment
		(start 123.19 -437.930036)
		(end 125.749812 -440.489848)
		(width 0.10668)
		(layer "F.Cu")
		(net "GPU_FPGA_EROT_RECOV_BUF_N")
	)
	(segment
		(start 121.666 -433.451)
		(end 123.19 -434.975)
		(width 0.10668)
		(layer "F.Cu")
		(net "GPU_FPGA_EROT_RECOV_BUF_N")
	)
	(segment
		(start 120.79605 -433.451)
		(end 121.666 -433.451)
		(width 0.10668)
		(layer "F.Cu")
		(net "GPU_FPGA_EROT_RECOV_BUF_N")
	)
	(segment
		(start 123.19 -434.975)
		(end 123.19 -437.930036)
		(width 0.10668)
		(layer "F.Cu")
		(net "GPU_FPGA_EROT_RECOV_BUF_N")
	)
	(via
		(at 121.666 -433.451)
		(size 0.762)
		(drill 0.381)
		(layers "F.Cu" "B.Cu")
		(net "GPU_FPGA_EROT_RECOV_BUF_N")
	)
	(via
		(at 138.175238 -420.243)
		(size 0.6604)
		(drill 0.3302)
		(layers "F.Cu" "B.Cu")
		(net "GPU_FPGA_EROT_FATALERR_N")
	)
	(segment
		(start 119.888 -419.608)
		(end 122.047 -419.608)
		(width 0.10668)
		(layer "B.Cu")
		(net "GPU_FPGA_EROT_FATALERR_N")
	)
	(segment
		(start 116.05895 -417.576)
		(end 116.078 -417.55695)
		(width 0.10668)
		(layer "B.Cu")
		(net "GPU_FPGA_EROT_FATALERR_N")
	)
	(segment
		(start 114.86896 -417.576)
		(end 116.05895 -417.576)
		(width 0.10668)
		(layer "B.Cu")
		(net "GPU_FPGA_EROT_FATALERR_N")
	)
	(segment
		(start 117.83695 -417.55695)
		(end 119.888 -419.608)
		(width 0.10668)
		(layer "B.Cu")
		(net "GPU_FPGA_EROT_FATALERR_N")
	)
	(segment
		(start 122.047 -419.608)
		(end 122.682 -420.243)
		(width 0.10668)
		(layer "B.Cu")
		(net "GPU_FPGA_EROT_FATALERR_N")
	)
	(segment
		(start 140.30325 -420.243)
		(end 144.750028 -424.689778)
		(width 0.10668)
		(layer "B.Cu")
		(net "GPU_FPGA_EROT_FATALERR_N")
	)
	(segment
		(start 117.094 -417.55695)
		(end 117.83695 -417.55695)
		(width 0.10668)
		(layer "B.Cu")
		(net "GPU_FPGA_EROT_FATALERR_N")
	)
	(segment
		(start 116.078 -417.55695)
		(end 117.094 -417.55695)
		(width 0.10668)
		(layer "B.Cu")
		(net "GPU_FPGA_EROT_FATALERR_N")
	)
	(segment
		(start 138.175238 -420.243)
		(end 140.30325 -420.243)
		(width 0.10668)
		(layer "B.Cu")
		(net "GPU_FPGA_EROT_FATALERR_N")
	)
	(segment
		(start 122.682 -420.243)
		(end 138.175238 -420.243)
		(width 0.10668)
		(layer "B.Cu")
		(net "GPU_FPGA_EROT_FATALERR_N")
	)
	(segment
		(start 209.278982 -118.762272)
		(end 210.502754 -118.762272)
		(width 0.10668)
		(layer "F.Cu")
		(net "GPU_FPGA_EROT_FATALERR_ISO_N")
	)
	(via
		(at 113.330228 -412.89097)
		(size 0.508)
		(drill 0.254)
		(layers "F.Cu" "B.Cu")
		(net "GPU_FPGA_EROT_FATALERR_ISO_N")
	)
	(via
		(at 39.526972 -393.530074)
		(size 0.508)
		(drill 0.254)
		(layers "F.Cu" "B.Cu")
		(net "GPU_FPGA_EROT_FATALERR_ISO_N")
	)
	(via
		(at 35.509708 -395.257782)
		(size 0.508)
		(drill 0.254)
		(layers "F.Cu" "B.Cu")
		(net "GPU_FPGA_EROT_FATALERR_ISO_N")
	)
	(via
		(at 208.43748 -139.914884)
		(size 0.508)
		(drill 0.254)
		(layers "F.Cu" "B.Cu")
		(net "GPU_FPGA_EROT_FATALERR_ISO_N")
	)
	(via
		(at 210.502754 -118.762272)
		(size 0.508)
		(drill 0.254)
		(layers "F.Cu" "B.Cu")
		(net "GPU_FPGA_EROT_FATALERR_ISO_N")
	)
	(segment
		(start 117.270022 -414.416494)
		(end 114.855752 -414.416494)
		(width 0.10668)
		(layer "B.Cu")
		(net "GPU_FPGA_EROT_FATALERR_ISO_N")
	)
	(segment
		(start 117.827552 -415.626042)
		(end 117.827552 -414.974024)
		(width 0.10668)
		(layer "B.Cu")
		(net "GPU_FPGA_EROT_FATALERR_ISO_N")
	)
	(segment
		(start 116.116354 -416.310318)
		(end 117.139212 -416.310318)
		(width 0.10668)
		(layer "B.Cu")
		(net "GPU_FPGA_EROT_FATALERR_ISO_N")
	)
	(segment
		(start 116.116354 -416.310318)
		(end 115.927632 -416.310318)
		(width 0.10668)
		(layer "B.Cu")
		(net "GPU_FPGA_EROT_FATALERR_ISO_N")
	)
	(segment
		(start 117.827552 -414.974024)
		(end 117.270022 -414.416494)
		(width 0.10668)
		(layer "B.Cu")
		(net "GPU_FPGA_EROT_FATALERR_ISO_N")
	)
	(segment
		(start 115.311936 -416.926014)
		(end 114.86896 -416.926014)
		(width 0.10668)
		(layer "B.Cu")
		(net "GPU_FPGA_EROT_FATALERR_ISO_N")
	)
	(segment
		(start 115.927632 -416.310318)
		(end 115.311936 -416.926014)
		(width 0.10668)
		(layer "B.Cu")
		(net "GPU_FPGA_EROT_FATALERR_ISO_N")
	)
	(segment
		(start 117.139212 -416.310318)
		(end 117.141244 -416.31235)
		(width 0.10668)
		(layer "B.Cu")
		(net "GPU_FPGA_EROT_FATALERR_ISO_N")
	)
	(segment
		(start 117.141244 -416.31235)
		(end 117.827552 -415.626042)
		(width 0.10668)
		(layer "B.Cu")
		(net "GPU_FPGA_EROT_FATALERR_ISO_N")
	)
	(segment
		(start 114.855752 -414.416494)
		(end 113.330228 -412.89097)
		(width 0.10668)
		(layer "B.Cu")
		(net "GPU_FPGA_EROT_FATALERR_ISO_N")
	)
	(segment
		(start 103.259382 -403.380448)
		(end 102.217474 -403.380448)
		(width 0.11684)
		(layer "In2.Cu")
		(net "GPU_FPGA_EROT_FATALERR_ISO_N")
	)
	(segment
		(start 113.330228 -412.89097)
		(end 113.330228 -409.64358)
		(width 0.11684)
		(layer "In2.Cu")
		(net "GPU_FPGA_EROT_FATALERR_ISO_N")
	)
	(segment
		(start 113.330228 -409.64358)
		(end 110.723934 -407.037286)
		(width 0.11684)
		(layer "In2.Cu")
		(net "GPU_FPGA_EROT_FATALERR_ISO_N")
	)
	(segment
		(start 96.930464 -398.093438)
		(end 49.50841 -398.093438)
		(width 0.11684)
		(layer "In2.Cu")
		(net "GPU_FPGA_EROT_FATALERR_ISO_N")
	)
	(segment
		(start 44.518326 -393.103354)
		(end 39.953692 -393.103354)
		(width 0.11684)
		(layer "In2.Cu")
		(net "GPU_FPGA_EROT_FATALERR_ISO_N")
	)
	(segment
		(start 109.506512 -403.968204)
		(end 103.847138 -403.968204)
		(width 0.11684)
		(layer "In2.Cu")
		(net "GPU_FPGA_EROT_FATALERR_ISO_N")
	)
	(segment
		(start 110.723934 -407.037286)
		(end 110.723934 -405.185626)
		(width 0.11684)
		(layer "In2.Cu")
		(net "GPU_FPGA_EROT_FATALERR_ISO_N")
	)
	(segment
		(start 102.217474 -403.380448)
		(end 96.930464 -398.093438)
		(width 0.11684)
		(layer "In2.Cu")
		(net "GPU_FPGA_EROT_FATALERR_ISO_N")
	)
	(segment
		(start 110.723934 -405.185626)
		(end 109.506512 -403.968204)
		(width 0.11684)
		(layer "In2.Cu")
		(net "GPU_FPGA_EROT_FATALERR_ISO_N")
	)
	(segment
		(start 39.953692 -393.103354)
		(end 39.526972 -393.530074)
		(width 0.11684)
		(layer "In2.Cu")
		(net "GPU_FPGA_EROT_FATALERR_ISO_N")
	)
	(segment
		(start 103.847138 -403.968204)
		(end 103.259382 -403.380448)
		(width 0.11684)
		(layer "In2.Cu")
		(net "GPU_FPGA_EROT_FATALERR_ISO_N")
	)
	(segment
		(start 49.50841 -398.093438)
		(end 44.518326 -393.103354)
		(width 0.11684)
		(layer "In2.Cu")
		(net "GPU_FPGA_EROT_FATALERR_ISO_N")
	)
	(segment
		(start 209.086196 -122.565414)
		(end 209.086196 -119.208804)
		(width 0.11684)
		(layer "In4.Cu")
		(net "GPU_FPGA_EROT_FATALERR_ISO_N")
	)
	(segment
		(start 209.418428 -126.297944)
		(end 209.418428 -122.897646)
		(width 0.11684)
		(layer "In4.Cu")
		(net "GPU_FPGA_EROT_FATALERR_ISO_N")
	)
	(segment
		(start 207.146398 -131.832858)
		(end 207.146398 -131.212336)
		(width 0.11684)
		(layer "In4.Cu")
		(net "GPU_FPGA_EROT_FATALERR_ISO_N")
	)
	(segment
		(start 207.76946 -130.589274)
		(end 207.76946 -127.946912)
		(width 0.11684)
		(layer "In4.Cu")
		(net "GPU_FPGA_EROT_FATALERR_ISO_N")
	)
	(segment
		(start 207.146398 -131.212336)
		(end 207.76946 -130.589274)
		(width 0.11684)
		(layer "In4.Cu")
		(net "GPU_FPGA_EROT_FATALERR_ISO_N")
	)
	(segment
		(start 37.237416 -393.530074)
		(end 39.526972 -393.530074)
		(width 0.11684)
		(layer "In4.Cu")
		(net "GPU_FPGA_EROT_FATALERR_ISO_N")
	)
	(segment
		(start 208.43748 -133.12394)
		(end 207.146398 -131.832858)
		(width 0.11684)
		(layer "In4.Cu")
		(net "GPU_FPGA_EROT_FATALERR_ISO_N")
	)
	(segment
		(start 209.532728 -118.762272)
		(end 210.502754 -118.762272)
		(width 0.11684)
		(layer "In4.Cu")
		(net "GPU_FPGA_EROT_FATALERR_ISO_N")
	)
	(segment
		(start 208.43748 -139.914884)
		(end 208.43748 -133.12394)
		(width 0.11684)
		(layer "In4.Cu")
		(net "GPU_FPGA_EROT_FATALERR_ISO_N")
	)
	(segment
		(start 209.418428 -122.897646)
		(end 209.086196 -122.565414)
		(width 0.11684)
		(layer "In4.Cu")
		(net "GPU_FPGA_EROT_FATALERR_ISO_N")
	)
	(segment
		(start 35.509708 -395.257782)
		(end 37.237416 -393.530074)
		(width 0.11684)
		(layer "In4.Cu")
		(net "GPU_FPGA_EROT_FATALERR_ISO_N")
	)
	(segment
		(start 207.76946 -127.946912)
		(end 209.418428 -126.297944)
		(width 0.11684)
		(layer "In4.Cu")
		(net "GPU_FPGA_EROT_FATALERR_ISO_N")
	)
	(segment
		(start 209.086196 -119.208804)
		(end 209.532728 -118.762272)
		(width 0.11684)
		(layer "In4.Cu")
		(net "GPU_FPGA_EROT_FATALERR_ISO_N")
	)
	(segment
		(start 28.704286 -380.535688)
		(end 30.743906 -382.575308)
		(width 0.11684)
		(layer "In13.Cu")
		(net "GPU_FPGA_EROT_FATALERR_ISO_N")
	)
	(segment
		(start 5.676392 -185.907172)
		(end 5.676392 -335.035144)
		(width 0.11684)
		(layer "In13.Cu")
		(net "GPU_FPGA_EROT_FATALERR_ISO_N")
	)
	(segment
		(start 192.065402 -142.715996)
		(end 185.693304 -142.715996)
		(width 0.11684)
		(layer "In13.Cu")
		(net "GPU_FPGA_EROT_FATALERR_ISO_N")
	)
	(segment
		(start 17.581626 -149.989032)
		(end 17.581626 -174.001938)
		(width 0.11684)
		(layer "In13.Cu")
		(net "GPU_FPGA_EROT_FATALERR_ISO_N")
	)
	(segment
		(start 205.038706 -142.72133)
		(end 200.86447 -142.72133)
		(width 0.11684)
		(layer "In13.Cu")
		(net "GPU_FPGA_EROT_FATALERR_ISO_N")
	)
	(segment
		(start 207.471264 -140.8811)
		(end 206.878936 -140.8811)
		(width 0.11684)
		(layer "In13.Cu")
		(net "GPU_FPGA_EROT_FATALERR_ISO_N")
	)
	(segment
		(start 17.581626 -174.001938)
		(end 5.676392 -185.907172)
		(width 0.11684)
		(layer "In13.Cu")
		(net "GPU_FPGA_EROT_FATALERR_ISO_N")
	)
	(segment
		(start 184.905396 -143.503904)
		(end 177.31232 -143.503904)
		(width 0.11684)
		(layer "In13.Cu")
		(net "GPU_FPGA_EROT_FATALERR_ISO_N")
	)
	(segment
		(start 33.55975 -395.257782)
		(end 35.509708 -395.257782)
		(width 0.11684)
		(layer "In13.Cu")
		(net "GPU_FPGA_EROT_FATALERR_ISO_N")
	)
	(segment
		(start 208.43748 -139.914884)
		(end 207.471264 -140.8811)
		(width 0.11684)
		(layer "In13.Cu")
		(net "GPU_FPGA_EROT_FATALERR_ISO_N")
	)
	(segment
		(start 4.437126 -336.27441)
		(end 4.437126 -357.471726)
		(width 0.11684)
		(layer "In13.Cu")
		(net "GPU_FPGA_EROT_FATALERR_ISO_N")
	)
	(segment
		(start 30.743906 -382.575308)
		(end 30.743906 -392.441938)
		(width 0.11684)
		(layer "In13.Cu")
		(net "GPU_FPGA_EROT_FATALERR_ISO_N")
	)
	(segment
		(start 176.657 -142.848584)
		(end 157.76194 -142.848584)
		(width 0.11684)
		(layer "In13.Cu")
		(net "GPU_FPGA_EROT_FATALERR_ISO_N")
	)
	(segment
		(start 200.464928 -142.321788)
		(end 200.464928 -141.533626)
		(width 0.11684)
		(layer "In13.Cu")
		(net "GPU_FPGA_EROT_FATALERR_ISO_N")
	)
	(segment
		(start 77.345286 -137.232644)
		(end 30.338014 -137.232644)
		(width 0.11684)
		(layer "In13.Cu")
		(net "GPU_FPGA_EROT_FATALERR_ISO_N")
	)
	(segment
		(start 5.159756 -366.052608)
		(end 8.072882 -368.965734)
		(width 0.11684)
		(layer "In13.Cu")
		(net "GPU_FPGA_EROT_FATALERR_ISO_N")
	)
	(segment
		(start 19.017996 -371.54104)
		(end 20.501102 -373.024146)
		(width 0.11684)
		(layer "In13.Cu")
		(net "GPU_FPGA_EROT_FATALERR_ISO_N")
	)
	(segment
		(start 200.86447 -142.72133)
		(end 200.464928 -142.321788)
		(width 0.11684)
		(layer "In13.Cu")
		(net "GPU_FPGA_EROT_FATALERR_ISO_N")
	)
	(segment
		(start 20.501102 -373.024146)
		(end 25.66416 -373.024146)
		(width 0.11684)
		(layer "In13.Cu")
		(net "GPU_FPGA_EROT_FATALERR_ISO_N")
	)
	(segment
		(start 4.437126 -357.471726)
		(end 5.159756 -358.194356)
		(width 0.11684)
		(layer "In13.Cu")
		(net "GPU_FPGA_EROT_FATALERR_ISO_N")
	)
	(segment
		(start 93.983302 -135.997442)
		(end 93.6244 -135.63854)
		(width 0.11684)
		(layer "In13.Cu")
		(net "GPU_FPGA_EROT_FATALERR_ISO_N")
	)
	(segment
		(start 206.878936 -140.8811)
		(end 205.038706 -142.72133)
		(width 0.11684)
		(layer "In13.Cu")
		(net "GPU_FPGA_EROT_FATALERR_ISO_N")
	)
	(segment
		(start 200.464928 -141.533626)
		(end 199.456294 -140.524992)
		(width 0.11684)
		(layer "In13.Cu")
		(net "GPU_FPGA_EROT_FATALERR_ISO_N")
	)
	(segment
		(start 194.256406 -140.524992)
		(end 192.065402 -142.715996)
		(width 0.11684)
		(layer "In13.Cu")
		(net "GPU_FPGA_EROT_FATALERR_ISO_N")
	)
	(segment
		(start 28.704286 -376.064272)
		(end 28.704286 -380.535688)
		(width 0.11684)
		(layer "In13.Cu")
		(net "GPU_FPGA_EROT_FATALERR_ISO_N")
	)
	(segment
		(start 5.676392 -335.035144)
		(end 4.437126 -336.27441)
		(width 0.11684)
		(layer "In13.Cu")
		(net "GPU_FPGA_EROT_FATALERR_ISO_N")
	)
	(segment
		(start 30.743906 -392.441938)
		(end 33.55975 -395.257782)
		(width 0.11684)
		(layer "In13.Cu")
		(net "GPU_FPGA_EROT_FATALERR_ISO_N")
	)
	(segment
		(start 185.693304 -142.715996)
		(end 184.905396 -143.503904)
		(width 0.11684)
		(layer "In13.Cu")
		(net "GPU_FPGA_EROT_FATALERR_ISO_N")
	)
	(segment
		(start 157.76194 -142.848584)
		(end 150.910798 -135.997442)
		(width 0.11684)
		(layer "In13.Cu")
		(net "GPU_FPGA_EROT_FATALERR_ISO_N")
	)
	(segment
		(start 78.93939 -135.63854)
		(end 77.345286 -137.232644)
		(width 0.11684)
		(layer "In13.Cu")
		(net "GPU_FPGA_EROT_FATALERR_ISO_N")
	)
	(segment
		(start 177.31232 -143.503904)
		(end 176.657 -142.848584)
		(width 0.11684)
		(layer "In13.Cu")
		(net "GPU_FPGA_EROT_FATALERR_ISO_N")
	)
	(segment
		(start 93.6244 -135.63854)
		(end 78.93939 -135.63854)
		(width 0.11684)
		(layer "In13.Cu")
		(net "GPU_FPGA_EROT_FATALERR_ISO_N")
	)
	(segment
		(start 199.456294 -140.524992)
		(end 194.256406 -140.524992)
		(width 0.11684)
		(layer "In13.Cu")
		(net "GPU_FPGA_EROT_FATALERR_ISO_N")
	)
	(segment
		(start 8.072882 -368.965734)
		(end 17.125188 -368.965734)
		(width 0.11684)
		(layer "In13.Cu")
		(net "GPU_FPGA_EROT_FATALERR_ISO_N")
	)
	(segment
		(start 150.910798 -135.997442)
		(end 93.983302 -135.997442)
		(width 0.11684)
		(layer "In13.Cu")
		(net "GPU_FPGA_EROT_FATALERR_ISO_N")
	)
	(segment
		(start 17.125188 -368.965734)
		(end 19.017996 -370.858542)
		(width 0.11684)
		(layer "In13.Cu")
		(net "GPU_FPGA_EROT_FATALERR_ISO_N")
	)
	(segment
		(start 5.159756 -358.194356)
		(end 5.159756 -366.052608)
		(width 0.11684)
		(layer "In13.Cu")
		(net "GPU_FPGA_EROT_FATALERR_ISO_N")
	)
	(segment
		(start 30.338014 -137.232644)
		(end 17.581626 -149.989032)
		(width 0.11684)
		(layer "In13.Cu")
		(net "GPU_FPGA_EROT_FATALERR_ISO_N")
	)
	(segment
		(start 25.66416 -373.024146)
		(end 28.704286 -376.064272)
		(width 0.11684)
		(layer "In13.Cu")
		(net "GPU_FPGA_EROT_FATALERR_ISO_N")
	)
	(segment
		(start 19.017996 -370.858542)
		(end 19.017996 -371.54104)
		(width 0.11684)
		(layer "In13.Cu")
		(net "GPU_FPGA_EROT_FATALERR_ISO_N")
	)
	(via
		(at 111.77905 -419.118542)
		(size 0.6604)
		(drill 0.3302)
		(layers "F.Cu" "B.Cu")
		(net "GPU_FPGA_EROT_FATALERR")
	)
	(segment
		(start 112.076484 -419.118542)
		(end 111.77905 -419.118542)
		(width 0.10668)
		(layer "B.Cu")
		(net "GPU_FPGA_EROT_FATALERR")
	)
	(segment
		(start 112.96904 -418.225986)
		(end 112.96904 -417.576)
		(width 0.10668)
		(layer "B.Cu")
		(net "GPU_FPGA_EROT_FATALERR")
	)
	(segment
		(start 111.77905 -419.118542)
		(end 111.77905 -418.211)
		(width 0.10668)
		(layer "B.Cu")
		(net "GPU_FPGA_EROT_FATALERR")
	)
	(segment
		(start 112.96904 -418.225986)
		(end 112.076484 -419.118542)
		(width 0.10668)
		(layer "B.Cu")
		(net "GPU_FPGA_EROT_FATALERR")
	)
	(segment
		(start 120.79605 -425.704)
		(end 120.79605 -424.688)
		(width 0.10668)
		(layer "F.Cu")
		(net "GPU_FPGA_BOOT_EN_BUF_R")
	)
	(segment
		(start 120.868186 -427.923452)
		(end 120.108472 -427.923452)
		(width 0.10668)
		(layer "F.Cu")
		(net "GPU_FPGA_BOOT_EN_BUF_R")
	)
	(segment
		(start 121.375424 -426.283374)
		(end 121.375424 -427.416214)
		(width 0.10668)
		(layer "F.Cu")
		(net "GPU_FPGA_BOOT_EN_BUF_R")
	)
	(segment
		(start 121.375424 -427.416214)
		(end 120.868186 -427.923452)
		(width 0.10668)
		(layer "F.Cu")
		(net "GPU_FPGA_BOOT_EN_BUF_R")
	)
	(segment
		(start 120.79605 -424.688)
		(end 120.79605 -423.672)
		(width 0.10668)
		(layer "F.Cu")
		(net "GPU_FPGA_BOOT_EN_BUF_R")
	)
	(segment
		(start 120.79605 -425.704)
		(end 121.375424 -426.283374)
		(width 0.10668)
		(layer "F.Cu")
		(net "GPU_FPGA_BOOT_EN_BUF_R")
	)
	(via
		(at 121.375424 -427.416214)
		(size 0.762)
		(drill 0.381)
		(layers "F.Cu" "B.Cu")
		(net "GPU_FPGA_BOOT_EN_BUF_R")
	)
	(segment
		(start 121.158 -423.291)
		(end 121.031 -423.164)
		(width 0.10668)
		(layer "F.Cu")
		(net "GPU_FPGA_BOOT_EN_BUF")
	)
	(segment
		(start 121.793 -423.291)
		(end 121.158 -423.291)
		(width 0.10668)
		(layer "F.Cu")
		(net "GPU_FPGA_BOOT_EN_BUF")
	)
	(segment
		(start 121.031 -423.164)
		(end 120.12295 -423.164)
		(width 0.10668)
		(layer "F.Cu")
		(net "GPU_FPGA_BOOT_EN_BUF")
	)
	(segment
		(start 120.12295 -423.164)
		(end 119.99595 -423.291)
		(width 0.10668)
		(layer "F.Cu")
		(net "GPU_FPGA_BOOT_EN_BUF")
	)
	(segment
		(start 119.99595 -423.291)
		(end 119.99595 -423.672)
		(width 0.10668)
		(layer "F.Cu")
		(net "GPU_FPGA_BOOT_EN_BUF")
	)
	(via
		(at 121.793 -423.291)
		(size 0.508)
		(drill 0.254)
		(layers "F.Cu" "B.Cu")
		(net "GPU_FPGA_BOOT_EN_BUF")
	)
	(segment
		(start 121.793 -423.291)
		(end 126.35103 -423.291)
		(width 0.10668)
		(layer "B.Cu")
		(net "GPU_FPGA_BOOT_EN_BUF")
	)
	(segment
		(start 126.35103 -423.291)
		(end 127.749808 -424.689778)
		(width 0.10668)
		(layer "B.Cu")
		(net "GPU_FPGA_BOOT_EN_BUF")
	)
	(segment
		(start 219.828364 -202.077574)
		(end 219.581476 -202.077574)
		(width 0.10668)
		(layer "F.Cu")
		(net "GPU_FPGA_BOOT_EN")
	)
	(segment
		(start 119.99595 -432.054)
		(end 119.99595 -432.41595)
		(width 0.10668)
		(layer "F.Cu")
		(net "GPU_FPGA_BOOT_EN")
	)
	(segment
		(start 219.581476 -202.077574)
		(end 217.533728 -200.029826)
		(width 0.10668)
		(layer "F.Cu")
		(net "GPU_FPGA_BOOT_EN")
	)
	(segment
		(start 204.80401 -160.47339)
		(end 200.048114 -160.47339)
		(width 0.10668)
		(layer "F.Cu")
		(net "GPU_FPGA_BOOT_EN")
	)
	(segment
		(start 208.263236 -163.932616)
		(end 204.80401 -160.47339)
		(width 0.10668)
		(layer "F.Cu")
		(net "GPU_FPGA_BOOT_EN")
	)
	(segment
		(start 120.108472 -429.823372)
		(end 120.108472 -430.436782)
		(width 0.10668)
		(layer "F.Cu")
		(net "GPU_FPGA_BOOT_EN")
	)
	(segment
		(start 217.533728 -186.312048)
		(end 208.263236 -163.932616)
		(width 0.10668)
		(layer "F.Cu")
		(net "GPU_FPGA_BOOT_EN")
	)
	(segment
		(start 120.108472 -430.436782)
		(end 119.99595 -430.549304)
		(width 0.10668)
		(layer "F.Cu")
		(net "GPU_FPGA_BOOT_EN")
	)
	(segment
		(start 119.99595 -430.549304)
		(end 119.99595 -431.038)
		(width 0.10668)
		(layer "F.Cu")
		(net "GPU_FPGA_BOOT_EN")
	)
	(segment
		(start 217.533728 -200.029826)
		(end 217.533728 -186.312048)
		(width 0.10668)
		(layer "F.Cu")
		(net "GPU_FPGA_BOOT_EN")
	)
	(segment
		(start 119.99595 -432.41595)
		(end 120.396 -432.816)
		(width 0.10668)
		(layer "F.Cu")
		(net "GPU_FPGA_BOOT_EN")
	)
	(segment
		(start 194.183 -133.968998)
		(end 194.183 -134.584948)
		(width 0.10668)
		(layer "F.Cu")
		(net "GPU_FPGA_BOOT_EN")
	)
	(segment
		(start 119.99595 -432.054)
		(end 119.99595 -431.038)
		(width 0.10668)
		(layer "F.Cu")
		(net "GPU_FPGA_BOOT_EN")
	)
	(via
		(at 194.183 -134.584948)
		(size 0.508)
		(drill 0.254)
		(layers "F.Cu" "B.Cu")
		(net "GPU_FPGA_BOOT_EN")
	)
	(via
		(at 120.396 -432.816)
		(size 0.508)
		(drill 0.254)
		(layers "F.Cu" "B.Cu")
		(net "GPU_FPGA_BOOT_EN")
	)
	(via
		(at 173.75632 -400.431)
		(size 0.508)
		(drill 0.254)
		(layers "F.Cu" "B.Cu")
		(net "GPU_FPGA_BOOT_EN")
	)
	(via
		(at 219.828364 -202.077574)
		(size 0.508)
		(drill 0.254)
		(layers "F.Cu" "B.Cu")
		(net "GPU_FPGA_BOOT_EN")
	)
	(via
		(at 174.15129 -425.52874)
		(size 0.508)
		(drill 0.254)
		(layers "F.Cu" "B.Cu")
		(net "GPU_FPGA_BOOT_EN")
	)
	(via
		(at 200.048114 -160.47339)
		(size 0.508)
		(drill 0.254)
		(layers "F.Cu" "B.Cu")
		(net "GPU_FPGA_BOOT_EN")
	)
	(segment
		(start 159.75584 -422.249092)
		(end 162.122358 -424.61561)
		(width 0.11684)
		(layer "In2.Cu")
		(net "GPU_FPGA_BOOT_EN")
	)
	(segment
		(start 173.37786 -426.30217)
		(end 174.15129 -425.52874)
		(width 0.11684)
		(layer "In2.Cu")
		(net "GPU_FPGA_BOOT_EN")
	)
	(segment
		(start 162.122358 -425.468034)
		(end 162.956494 -426.30217)
		(width 0.11684)
		(layer "In2.Cu")
		(net "GPU_FPGA_BOOT_EN")
	)
	(segment
		(start 162.956494 -426.30217)
		(end 173.37786 -426.30217)
		(width 0.11684)
		(layer "In2.Cu")
		(net "GPU_FPGA_BOOT_EN")
	)
	(segment
		(start 127.487426 -422.249092)
		(end 159.75584 -422.249092)
		(width 0.11684)
		(layer "In2.Cu")
		(net "GPU_FPGA_BOOT_EN")
	)
	(segment
		(start 120.396 -432.816)
		(end 120.396 -429.340518)
		(width 0.11684)
		(layer "In2.Cu")
		(net "GPU_FPGA_BOOT_EN")
	)
	(segment
		(start 162.122358 -424.61561)
		(end 162.122358 -425.468034)
		(width 0.11684)
		(layer "In2.Cu")
		(net "GPU_FPGA_BOOT_EN")
	)
	(segment
		(start 120.396 -429.340518)
		(end 127.487426 -422.249092)
		(width 0.11684)
		(layer "In2.Cu")
		(net "GPU_FPGA_BOOT_EN")
	)
	(segment
		(start 201.202036 -150.44166)
		(end 201.202036 -159.319468)
		(width 0.11684)
		(layer "In4.Cu")
		(net "GPU_FPGA_BOOT_EN")
	)
	(segment
		(start 194.683126 -135.085074)
		(end 194.683126 -137.275316)
		(width 0.11684)
		(layer "In4.Cu")
		(net "GPU_FPGA_BOOT_EN")
	)
	(segment
		(start 195.62318 -138.21537)
		(end 195.62318 -144.862804)
		(width 0.11684)
		(layer "In4.Cu")
		(net "GPU_FPGA_BOOT_EN")
	)
	(segment
		(start 195.62318 -144.862804)
		(end 201.202036 -150.44166)
		(width 0.11684)
		(layer "In4.Cu")
		(net "GPU_FPGA_BOOT_EN")
	)
	(segment
		(start 194.683126 -137.275316)
		(end 195.62318 -138.21537)
		(width 0.11684)
		(layer "In4.Cu")
		(net "GPU_FPGA_BOOT_EN")
	)
	(segment
		(start 201.202036 -159.319468)
		(end 200.048114 -160.47339)
		(width 0.11684)
		(layer "In4.Cu")
		(net "GPU_FPGA_BOOT_EN")
	)
	(segment
		(start 194.183 -134.584948)
		(end 194.683126 -135.085074)
		(width 0.11684)
		(layer "In4.Cu")
		(net "GPU_FPGA_BOOT_EN")
	)
	(segment
		(start 171.89069 -412.040578)
		(end 171.89069 -414.143952)
		(width 0.11684)
		(layer "In13.Cu")
		(net "GPU_FPGA_BOOT_EN")
	)
	(segment
		(start 173.021752 -415.275014)
		(end 173.021752 -417.68268)
		(width 0.11684)
		(layer "In13.Cu")
		(net "GPU_FPGA_BOOT_EN")
	)
	(segment
		(start 172.85208 -400.304)
		(end 170.1673 -400.304)
		(width 0.11684)
		(layer "In13.Cu")
		(net "GPU_FPGA_BOOT_EN")
	)
	(segment
		(start 170.1673 -400.304)
		(end 169.90822 -400.56308)
		(width 0.11684)
		(layer "In13.Cu")
		(net "GPU_FPGA_BOOT_EN")
	)
	(segment
		(start 169.90822 -400.56308)
		(end 168.895522 -400.56308)
		(width 0.11684)
		(layer "In13.Cu")
		(net "GPU_FPGA_BOOT_EN")
	)
	(segment
		(start 175.862234 -423.817796)
		(end 174.15129 -425.52874)
		(width 0.11684)
		(layer "In13.Cu")
		(net "GPU_FPGA_BOOT_EN")
	)
	(segment
		(start 166.669974 -402.788628)
		(end 166.669974 -406.819862)
		(width 0.11684)
		(layer "In13.Cu")
		(net "GPU_FPGA_BOOT_EN")
	)
	(segment
		(start 168.895522 -400.56308)
		(end 166.669974 -402.788628)
		(width 0.11684)
		(layer "In13.Cu")
		(net "GPU_FPGA_BOOT_EN")
	)
	(segment
		(start 175.862234 -420.523162)
		(end 175.862234 -423.817796)
		(width 0.11684)
		(layer "In13.Cu")
		(net "GPU_FPGA_BOOT_EN")
	)
	(segment
		(start 173.021752 -417.68268)
		(end 175.862234 -420.523162)
		(width 0.11684)
		(layer "In13.Cu")
		(net "GPU_FPGA_BOOT_EN")
	)
	(segment
		(start 171.89069 -414.143952)
		(end 173.021752 -415.275014)
		(width 0.11684)
		(layer "In13.Cu")
		(net "GPU_FPGA_BOOT_EN")
	)
	(segment
		(start 166.669974 -406.819862)
		(end 171.89069 -412.040578)
		(width 0.11684)
		(layer "In13.Cu")
		(net "GPU_FPGA_BOOT_EN")
	)
	(segment
		(start 172.97908 -400.431)
		(end 172.85208 -400.304)
		(width 0.11684)
		(layer "In13.Cu")
		(net "GPU_FPGA_BOOT_EN")
	)
	(segment
		(start 173.75632 -400.431)
		(end 172.97908 -400.431)
		(width 0.11684)
		(layer "In13.Cu")
		(net "GPU_FPGA_BOOT_EN")
	)
	(segment
		(start 190.64732 -370.801392)
		(end 193.43243 -370.801392)
		(width 0.11684)
		(layer "In15.Cu")
		(net "GPU_FPGA_BOOT_EN")
	)
	(segment
		(start 188.408818 -381.032258)
		(end 188.408818 -373.039894)
		(width 0.11684)
		(layer "In15.Cu")
		(net "GPU_FPGA_BOOT_EN")
	)
	(segment
		(start 173.75632 -400.431)
		(end 174.831248 -399.356072)
		(width 0.11684)
		(layer "In15.Cu")
		(net "GPU_FPGA_BOOT_EN")
	)
	(segment
		(start 214.790782 -203.55941)
		(end 216.272618 -202.077574)
		(width 0.11684)
		(layer "In15.Cu")
		(net "GPU_FPGA_BOOT_EN")
	)
	(segment
		(start 177.954432 -393.003786)
		(end 179.222908 -393.003786)
		(width 0.11684)
		(layer "In15.Cu")
		(net "GPU_FPGA_BOOT_EN")
	)
	(segment
		(start 182.5244 -389.30199)
		(end 182.5244 -386.916676)
		(width 0.11684)
		(layer "In15.Cu")
		(net "GPU_FPGA_BOOT_EN")
	)
	(segment
		(start 214.790782 -318.701166)
		(end 214.790782 -203.55941)
		(width 0.11684)
		(layer "In15.Cu")
		(net "GPU_FPGA_BOOT_EN")
	)
	(segment
		(start 182.5244 -386.916676)
		(end 188.408818 -381.032258)
		(width 0.11684)
		(layer "In15.Cu")
		(net "GPU_FPGA_BOOT_EN")
	)
	(segment
		(start 180.38064 -391.846054)
		(end 180.38064 -391.44575)
		(width 0.11684)
		(layer "In15.Cu")
		(net "GPU_FPGA_BOOT_EN")
	)
	(segment
		(start 188.408818 -373.039894)
		(end 190.64732 -370.801392)
		(width 0.11684)
		(layer "In15.Cu")
		(net "GPU_FPGA_BOOT_EN")
	)
	(segment
		(start 221.015814 -324.926198)
		(end 214.790782 -318.701166)
		(width 0.11684)
		(layer "In15.Cu")
		(net "GPU_FPGA_BOOT_EN")
	)
	(segment
		(start 221.015814 -343.218008)
		(end 221.015814 -324.926198)
		(width 0.11684)
		(layer "In15.Cu")
		(net "GPU_FPGA_BOOT_EN")
	)
	(segment
		(start 193.43243 -370.801392)
		(end 221.015814 -343.218008)
		(width 0.11684)
		(layer "In15.Cu")
		(net "GPU_FPGA_BOOT_EN")
	)
	(segment
		(start 180.38064 -391.44575)
		(end 182.5244 -389.30199)
		(width 0.11684)
		(layer "In15.Cu")
		(net "GPU_FPGA_BOOT_EN")
	)
	(segment
		(start 174.831248 -399.356072)
		(end 174.831248 -396.12697)
		(width 0.11684)
		(layer "In15.Cu")
		(net "GPU_FPGA_BOOT_EN")
	)
	(segment
		(start 216.272618 -202.077574)
		(end 219.828364 -202.077574)
		(width 0.11684)
		(layer "In15.Cu")
		(net "GPU_FPGA_BOOT_EN")
	)
	(segment
		(start 174.831248 -396.12697)
		(end 177.954432 -393.003786)
		(width 0.11684)
		(layer "In15.Cu")
		(net "GPU_FPGA_BOOT_EN")
	)
	(segment
		(start 179.222908 -393.003786)
		(end 180.38064 -391.846054)
		(width 0.11684)
		(layer "In15.Cu")
		(net "GPU_FPGA_BOOT_EN")
	)
	(segment
		(start 355.58476 -416.522662)
		(end 355.660452 -416.44697)
		(width 0.10668)
		(layer "F.Cu")
		(net "PRSNT_CABLE_GPU_A1")
	)
	(segment
		(start 356.234746 -416.570414)
		(end 356.234746 -417.095178)
		(width 0.10668)
		(layer "F.Cu")
		(net "PRSNT_CABLE_GPU_A1")
	)
	(segment
		(start 356.111302 -416.44697)
		(end 356.234746 -416.570414)
		(width 0.10668)
		(layer "F.Cu")
		(net "PRSNT_CABLE_GPU_A1")
	)
	(segment
		(start 356.80396 -418.329618)
		(end 355.58476 -418.329618)
		(width 0.10668)
		(layer "F.Cu")
		(net "PRSNT_CABLE_GPU_A1")
	)
	(segment
		(start 355.58476 -417.095178)
		(end 355.58476 -416.522662)
		(width 0.10668)
		(layer "F.Cu")
		(net "PRSNT_CABLE_GPU_A1")
	)
	(segment
		(start 355.660452 -416.44697)
		(end 356.111302 -416.44697)
		(width 0.10668)
		(layer "F.Cu")
		(net "PRSNT_CABLE_GPU_A1")
	)
	(segment
		(start 355.58476 -417.095178)
		(end 355.58476 -418.329618)
		(width 0.10668)
		(layer "F.Cu")
		(net "PRSNT_CABLE_GPU_A1")
	)
	(via
		(at 355.58476 -418.329618)
		(size 0.762)
		(drill 0.381)
		(layers "F.Cu" "B.Cu")
		(net "PRSNT_CABLE_GPU_A1")
	)
	(segment
		(start 356.234746 -415.195258)
		(end 356.234746 -414.212532)
		(width 0.10668)
		(layer "F.Cu")
		(net "PRSNT_CABLE_GPU_A1_N")
	)
	(segment
		(start 355.906832 -412.030418)
		(end 355.906832 -413.046418)
		(width 0.10668)
		(layer "F.Cu")
		(net "PRSNT_CABLE_GPU_A1_N")
	)
	(segment
		(start 355.906832 -410.71165)
		(end 355.906832 -412.030418)
		(width 0.10668)
		(layer "F.Cu")
		(net "PRSNT_CABLE_GPU_A1_N")
	)
	(segment
		(start 356.234746 -414.212532)
		(end 356.084632 -414.062418)
		(width 0.10668)
		(layer "F.Cu")
		(net "PRSNT_CABLE_GPU_A1_N")
	)
	(segment
		(start 355.906832 -413.884618)
		(end 356.084632 -414.062418)
		(width 0.10668)
		(layer "F.Cu")
		(net "PRSNT_CABLE_GPU_A1_N")
	)
	(segment
		(start 355.607366 -410.412184)
		(end 355.906832 -410.71165)
		(width 0.10668)
		(layer "F.Cu")
		(net "PRSNT_CABLE_GPU_A1_N")
	)
	(segment
		(start 355.906832 -413.046418)
		(end 355.906832 -413.884618)
		(width 0.10668)
		(layer "F.Cu")
		(net "PRSNT_CABLE_GPU_A1_N")
	)
	(via
		(at 369.202462 -428.470568)
		(size 0.508)
		(drill 0.254)
		(layers "F.Cu" "B.Cu")
		(net "PRSNT_CABLE_GPU_A1_N")
	)
	(via
		(at 355.607366 -410.412184)
		(size 0.508)
		(drill 0.254)
		(layers "F.Cu" "B.Cu")
		(net "PRSNT_CABLE_GPU_A1_N")
	)
	(segment
		(start 373.26443 -427.099222)
		(end 371.025166 -427.099222)
		(width 0.11684)
		(layer "In2.Cu")
		(net "PRSNT_CABLE_GPU_A1_N")
	)
	(segment
		(start 392.94308 -439.687462)
		(end 392.94308 -424.14571)
		(width 0.11684)
		(layer "In2.Cu")
		(net "PRSNT_CABLE_GPU_A1_N")
	)
	(segment
		(start 392.016234 -423.218864)
		(end 377.144788 -423.218864)
		(width 0.11684)
		(layer "In2.Cu")
		(net "PRSNT_CABLE_GPU_A1_N")
	)
	(segment
		(start 393.745466 -440.489848)
		(end 392.94308 -439.687462)
		(width 0.11684)
		(layer "In2.Cu")
		(net "PRSNT_CABLE_GPU_A1_N")
	)
	(segment
		(start 377.144788 -423.218864)
		(end 373.26443 -427.099222)
		(width 0.11684)
		(layer "In2.Cu")
		(net "PRSNT_CABLE_GPU_A1_N")
	)
	(segment
		(start 371.025166 -427.099222)
		(end 369.65382 -428.470568)
		(width 0.11684)
		(layer "In2.Cu")
		(net "PRSNT_CABLE_GPU_A1_N")
	)
	(segment
		(start 392.94308 -424.14571)
		(end 392.016234 -423.218864)
		(width 0.11684)
		(layer "In2.Cu")
		(net "PRSNT_CABLE_GPU_A1_N")
	)
	(segment
		(start 369.65382 -428.470568)
		(end 369.202462 -428.470568)
		(width 0.11684)
		(layer "In2.Cu")
		(net "PRSNT_CABLE_GPU_A1_N")
	)
	(segment
		(start 393.749784 -440.489848)
		(end 393.745466 -440.489848)
		(width 0.11684)
		(layer "In2.Cu")
		(net "PRSNT_CABLE_GPU_A1_N")
	)
	(segment
		(start 365.28248 -429.190912)
		(end 362.316522 -426.224954)
		(width 0.11684)
		(layer "In4.Cu")
		(net "PRSNT_CABLE_GPU_A1_N")
	)
	(segment
		(start 359.416604 -421.43045)
		(end 358.973374 -420.98722)
		(width 0.11684)
		(layer "In4.Cu")
		(net "PRSNT_CABLE_GPU_A1_N")
	)
	(segment
		(start 360.011472 -421.43045)
		(end 359.416604 -421.43045)
		(width 0.11684)
		(layer "In4.Cu")
		(net "PRSNT_CABLE_GPU_A1_N")
	)
	(segment
		(start 358.973374 -418.335206)
		(end 357.890318 -417.25215)
		(width 0.11684)
		(layer "In4.Cu")
		(net "PRSNT_CABLE_GPU_A1_N")
	)
	(segment
		(start 357.890318 -417.25215)
		(end 356.4763 -417.25215)
		(width 0.11684)
		(layer "In4.Cu")
		(net "PRSNT_CABLE_GPU_A1_N")
	)
	(segment
		(start 358.973374 -420.98722)
		(end 358.973374 -418.335206)
		(width 0.11684)
		(layer "In4.Cu")
		(net "PRSNT_CABLE_GPU_A1_N")
	)
	(segment
		(start 362.316522 -423.7355)
		(end 360.011472 -421.43045)
		(width 0.11684)
		(layer "In4.Cu")
		(net "PRSNT_CABLE_GPU_A1_N")
	)
	(segment
		(start 362.316522 -426.224954)
		(end 362.316522 -423.7355)
		(width 0.11684)
		(layer "In4.Cu")
		(net "PRSNT_CABLE_GPU_A1_N")
	)
	(segment
		(start 368.482118 -429.190912)
		(end 365.28248 -429.190912)
		(width 0.11684)
		(layer "In4.Cu")
		(net "PRSNT_CABLE_GPU_A1_N")
	)
	(segment
		(start 369.202462 -428.470568)
		(end 368.482118 -429.190912)
		(width 0.11684)
		(layer "In4.Cu")
		(net "PRSNT_CABLE_GPU_A1_N")
	)
	(segment
		(start 356.107238 -410.912056)
		(end 355.607366 -410.412184)
		(width 0.11684)
		(layer "In4.Cu")
		(net "PRSNT_CABLE_GPU_A1_N")
	)
	(segment
		(start 356.4763 -417.25215)
		(end 356.107238 -416.883088)
		(width 0.11684)
		(layer "In4.Cu")
		(net "PRSNT_CABLE_GPU_A1_N")
	)
	(segment
		(start 356.107238 -416.883088)
		(end 356.107238 -410.912056)
		(width 0.11684)
		(layer "In4.Cu")
		(net "PRSNT_CABLE_GPU_A1_N")
	)
	(segment
		(start 118.8085 -427.488096)
		(end 118.8085 -427.923452)
		(width 0.10668)
		(layer "F.Cu")
		(net "GPU_BASE_STBY_EN_BUF_R")
	)
	(segment
		(start 117.983 -425.81195)
		(end 117.983 -426.662596)
		(width 0.10668)
		(layer "F.Cu")
		(net "GPU_BASE_STBY_EN_BUF_R")
	)
	(segment
		(start 117.983 -426.662596)
		(end 118.8085 -427.488096)
		(width 0.10668)
		(layer "F.Cu")
		(net "GPU_BASE_STBY_EN_BUF_R")
	)
	(segment
		(start 118.09095 -425.704)
		(end 117.983 -425.81195)
		(width 0.10668)
		(layer "F.Cu")
		(net "GPU_BASE_STBY_EN_BUF_R")
	)
	(segment
		(start 118.09095 -424.688)
		(end 118.09095 -425.704)
		(width 0.10668)
		(layer "F.Cu")
		(net "GPU_BASE_STBY_EN_BUF_R")
	)
	(segment
		(start 118.09095 -423.672)
		(end 118.09095 -424.688)
		(width 0.10668)
		(layer "F.Cu")
		(net "GPU_BASE_STBY_EN_BUF_R")
	)
	(via
		(at 117.983 -426.662596)
		(size 0.762)
		(drill 0.381)
		(layers "F.Cu" "B.Cu")
		(net "GPU_BASE_STBY_EN_BUF_R")
	)
	(segment
		(start 121.84126 -422.656)
		(end 122.809 -421.68826)
		(width 0.10668)
		(layer "F.Cu")
		(net "GPU_BASE_STBY_EN_BUF")
	)
	(segment
		(start 118.89105 -423.672)
		(end 119.78005 -422.783)
		(width 0.10668)
		(layer "F.Cu")
		(net "GPU_BASE_STBY_EN_BUF")
	)
	(segment
		(start 119.78005 -422.783)
		(end 121.031 -422.783)
		(width 0.10668)
		(layer "F.Cu")
		(net "GPU_BASE_STBY_EN_BUF")
	)
	(segment
		(start 121.031 -422.783)
		(end 121.158 -422.656)
		(width 0.10668)
		(layer "F.Cu")
		(net "GPU_BASE_STBY_EN_BUF")
	)
	(segment
		(start 121.158 -422.656)
		(end 121.84126 -422.656)
		(width 0.10668)
		(layer "F.Cu")
		(net "GPU_BASE_STBY_EN_BUF")
	)
	(segment
		(start 122.809 -421.68826)
		(end 122.809 -421.259)
		(width 0.10668)
		(layer "F.Cu")
		(net "GPU_BASE_STBY_EN_BUF")
	)
	(via
		(at 122.809 -421.259)
		(size 0.508)
		(drill 0.254)
		(layers "F.Cu" "B.Cu")
		(net "GPU_BASE_STBY_EN_BUF")
	)
	(segment
		(start 136.937242 -440.035696)
		(end 136.937242 -423.857928)
		(width 0.10668)
		(layer "B.Cu")
		(net "GPU_BASE_STBY_EN_BUF")
	)
	(segment
		(start 137.391394 -440.489848)
		(end 136.937242 -440.035696)
		(width 0.10668)
		(layer "B.Cu")
		(net "GPU_BASE_STBY_EN_BUF")
	)
	(segment
		(start 136.937242 -423.857928)
		(end 134.338314 -421.259)
		(width 0.10668)
		(layer "B.Cu")
		(net "GPU_BASE_STBY_EN_BUF")
	)
	(segment
		(start 134.338314 -421.259)
		(end 122.809 -421.259)
		(width 0.10668)
		(layer "B.Cu")
		(net "GPU_BASE_STBY_EN_BUF")
	)
	(segment
		(start 137.749788 -440.489848)
		(end 137.391394 -440.489848)
		(width 0.10668)
		(layer "B.Cu")
		(net "GPU_BASE_STBY_EN_BUF")
	)
	(segment
		(start 199.892666 -126.806452)
		(end 199.968866 -126.806452)
		(width 0.10668)
		(layer "F.Cu")
		(net "GPU_BASE_STBY_EN")
	)
	(segment
		(start 206.401924 -161.171128)
		(end 204.435202 -159.204406)
		(width 0.10668)
		(layer "F.Cu")
		(net "GPU_BASE_STBY_EN")
	)
	(segment
		(start 119.01805 -430.549304)
		(end 119.01805 -431.038)
		(width 0.10668)
		(layer "F.Cu")
		(net "GPU_BASE_STBY_EN")
	)
	(segment
		(start 118.8085 -429.823372)
		(end 118.8085 -430.339754)
		(width 0.10668)
		(layer "F.Cu")
		(net "GPU_BASE_STBY_EN")
	)
	(segment
		(start 206.401924 -161.551366)
		(end 206.401924 -161.171128)
		(width 0.10668)
		(layer "F.Cu")
		(net "GPU_BASE_STBY_EN")
	)
	(segment
		(start 217.894408 -186.239658)
		(end 208.562194 -163.711636)
		(width 0.10668)
		(layer "F.Cu")
		(net "GPU_BASE_STBY_EN")
	)
	(segment
		(start 197.955154 -125.817376)
		(end 198.463154 -126.325376)
		(width 0.10668)
		(layer "F.Cu")
		(net "GPU_BASE_STBY_EN")
	)
	(segment
		(start 219.51696 -201.442574)
		(end 217.894408 -199.820022)
		(width 0.10668)
		(layer "F.Cu")
		(net "GPU_BASE_STBY_EN")
	)
	(segment
		(start 208.562194 -163.711636)
		(end 206.401924 -161.551366)
		(width 0.10668)
		(layer "F.Cu")
		(net "GPU_BASE_STBY_EN")
	)
	(segment
		(start 197.669658 -125.817376)
		(end 197.955154 -125.817376)
		(width 0.10668)
		(layer "F.Cu")
		(net "GPU_BASE_STBY_EN")
	)
	(segment
		(start 219.828364 -201.442574)
		(end 219.51696 -201.442574)
		(width 0.10668)
		(layer "F.Cu")
		(net "GPU_BASE_STBY_EN")
	)
	(segment
		(start 119.01805 -432.054)
		(end 119.01805 -432.816)
		(width 0.10668)
		(layer "F.Cu")
		(net "GPU_BASE_STBY_EN")
	)
	(segment
		(start 199.41159 -126.325376)
		(end 199.892666 -126.806452)
		(width 0.10668)
		(layer "F.Cu")
		(net "GPU_BASE_STBY_EN")
	)
	(segment
		(start 217.894408 -199.820022)
		(end 217.894408 -186.239658)
		(width 0.10668)
		(layer "F.Cu")
		(net "GPU_BASE_STBY_EN")
	)
	(segment
		(start 119.01805 -431.038)
		(end 119.01805 -432.054)
		(width 0.10668)
		(layer "F.Cu")
		(net "GPU_BASE_STBY_EN")
	)
	(segment
		(start 198.463154 -126.325376)
		(end 199.41159 -126.325376)
		(width 0.10668)
		(layer "F.Cu")
		(net "GPU_BASE_STBY_EN")
	)
	(segment
		(start 118.8085 -430.339754)
		(end 119.01805 -430.549304)
		(width 0.10668)
		(layer "F.Cu")
		(net "GPU_BASE_STBY_EN")
	)
	(via
		(at 173.17212 -399.86712)
		(size 0.508)
		(drill 0.254)
		(layers "F.Cu" "B.Cu")
		(net "GPU_BASE_STBY_EN")
	)
	(via
		(at 204.435202 -159.204406)
		(size 0.508)
		(drill 0.254)
		(layers "F.Cu" "B.Cu")
		(net "GPU_BASE_STBY_EN")
	)
	(via
		(at 199.968866 -126.806452)
		(size 0.508)
		(drill 0.254)
		(layers "F.Cu" "B.Cu")
		(net "GPU_BASE_STBY_EN")
	)
	(via
		(at 119.01805 -432.816)
		(size 0.508)
		(drill 0.254)
		(layers "F.Cu" "B.Cu")
		(net "GPU_BASE_STBY_EN")
	)
	(via
		(at 174.172626 -424.787314)
		(size 0.508)
		(drill 0.254)
		(layers "F.Cu" "B.Cu")
		(net "GPU_BASE_STBY_EN")
	)
	(via
		(at 219.828364 -201.442574)
		(size 0.508)
		(drill 0.254)
		(layers "F.Cu" "B.Cu")
		(net "GPU_BASE_STBY_EN")
	)
	(segment
		(start 163.590986 -424.93565)
		(end 164.00018 -425.344844)
		(width 0.11684)
		(layer "In2.Cu")
		(net "GPU_BASE_STBY_EN")
	)
	(segment
		(start 160.196784 -421.827452)
		(end 163.304982 -424.93565)
		(width 0.11684)
		(layer "In2.Cu")
		(net "GPU_BASE_STBY_EN")
	)
	(segment
		(start 164.00018 -425.344844)
		(end 164.00018 -425.593256)
		(width 0.11684)
		(layer "In2.Cu")
		(net "GPU_BASE_STBY_EN")
	)
	(segment
		(start 119.01805 -432.816)
		(end 119.01805 -430.122076)
		(width 0.11684)
		(layer "In2.Cu")
		(net "GPU_BASE_STBY_EN")
	)
	(segment
		(start 164.00018 -425.593256)
		(end 164.287454 -425.88053)
		(width 0.11684)
		(layer "In2.Cu")
		(net "GPU_BASE_STBY_EN")
	)
	(segment
		(start 163.304982 -424.93565)
		(end 163.590986 -424.93565)
		(width 0.11684)
		(layer "In2.Cu")
		(net "GPU_BASE_STBY_EN")
	)
	(segment
		(start 119.01805 -430.122076)
		(end 127.312674 -421.827452)
		(width 0.11684)
		(layer "In2.Cu")
		(net "GPU_BASE_STBY_EN")
	)
	(segment
		(start 127.312674 -421.827452)
		(end 160.196784 -421.827452)
		(width 0.11684)
		(layer "In2.Cu")
		(net "GPU_BASE_STBY_EN")
	)
	(segment
		(start 173.07941 -425.88053)
		(end 174.172626 -424.787314)
		(width 0.11684)
		(layer "In2.Cu")
		(net "GPU_BASE_STBY_EN")
	)
	(segment
		(start 164.287454 -425.88053)
		(end 173.07941 -425.88053)
		(width 0.11684)
		(layer "In2.Cu")
		(net "GPU_BASE_STBY_EN")
	)
	(segment
		(start 200.34377 -132.193792)
		(end 200.95337 -132.803392)
		(width 0.11684)
		(layer "In4.Cu")
		(net "GPU_BASE_STBY_EN")
	)
	(segment
		(start 200.480422 -146.46021)
		(end 203.153772 -149.13356)
		(width 0.11684)
		(layer "In4.Cu")
		(net "GPU_BASE_STBY_EN")
	)
	(segment
		(start 199.968866 -126.806452)
		(end 199.968866 -127.376682)
		(width 0.11684)
		(layer "In4.Cu")
		(net "GPU_BASE_STBY_EN")
	)
	(segment
		(start 200.34377 -129.608326)
		(end 200.34377 -132.193792)
		(width 0.11684)
		(layer "In4.Cu")
		(net "GPU_BASE_STBY_EN")
	)
	(segment
		(start 199.968866 -127.376682)
		(end 200.134728 -127.542544)
		(width 0.11684)
		(layer "In4.Cu")
		(net "GPU_BASE_STBY_EN")
	)
	(segment
		(start 200.745598 -137.306304)
		(end 200.745598 -141.877796)
		(width 0.11684)
		(layer "In4.Cu")
		(net "GPU_BASE_STBY_EN")
	)
	(segment
		(start 200.480422 -142.142972)
		(end 200.480422 -146.46021)
		(width 0.11684)
		(layer "In4.Cu")
		(net "GPU_BASE_STBY_EN")
	)
	(segment
		(start 200.134728 -129.399284)
		(end 200.34377 -129.608326)
		(width 0.11684)
		(layer "In4.Cu")
		(net "GPU_BASE_STBY_EN")
	)
	(segment
		(start 200.95337 -137.098532)
		(end 200.745598 -137.306304)
		(width 0.11684)
		(layer "In4.Cu")
		(net "GPU_BASE_STBY_EN")
	)
	(segment
		(start 203.153772 -157.922976)
		(end 204.435202 -159.204406)
		(width 0.11684)
		(layer "In4.Cu")
		(net "GPU_BASE_STBY_EN")
	)
	(segment
		(start 203.153772 -149.13356)
		(end 203.153772 -157.922976)
		(width 0.11684)
		(layer "In4.Cu")
		(net "GPU_BASE_STBY_EN")
	)
	(segment
		(start 200.134728 -127.542544)
		(end 200.134728 -129.399284)
		(width 0.11684)
		(layer "In4.Cu")
		(net "GPU_BASE_STBY_EN")
	)
	(segment
		(start 200.95337 -132.803392)
		(end 200.95337 -137.098532)
		(width 0.11684)
		(layer "In4.Cu")
		(net "GPU_BASE_STBY_EN")
	)
	(segment
		(start 200.745598 -141.877796)
		(end 200.480422 -142.142972)
		(width 0.11684)
		(layer "In4.Cu")
		(net "GPU_BASE_STBY_EN")
	)
	(segment
		(start 175.419766 -420.69766)
		(end 175.419766 -423.540174)
		(width 0.11684)
		(layer "In13.Cu")
		(net "GPU_BASE_STBY_EN")
	)
	(segment
		(start 171.83862 -399.86712)
		(end 171.83354 -399.86204)
		(width 0.11684)
		(layer "In13.Cu")
		(net "GPU_BASE_STBY_EN")
	)
	(segment
		(start 172.591222 -417.869116)
		(end 175.419766 -420.69766)
		(width 0.11684)
		(layer "In13.Cu")
		(net "GPU_BASE_STBY_EN")
	)
	(segment
		(start 175.419766 -423.540174)
		(end 174.172626 -424.787314)
		(width 0.11684)
		(layer "In13.Cu")
		(net "GPU_BASE_STBY_EN")
	)
	(segment
		(start 169.645838 -412.495492)
		(end 169.898568 -412.495492)
		(width 0.11684)
		(layer "In13.Cu")
		(net "GPU_BASE_STBY_EN")
	)
	(segment
		(start 170.958256 -413.969454)
		(end 171.23029 -414.241488)
		(width 0.11684)
		(layer "In13.Cu")
		(net "GPU_BASE_STBY_EN")
	)
	(segment
		(start 166.22141 -407.579068)
		(end 168.212008 -409.569666)
		(width 0.11684)
		(layer "In13.Cu")
		(net "GPU_BASE_STBY_EN")
	)
	(segment
		(start 168.73093 -400.13128)
		(end 166.22141 -402.6408)
		(width 0.11684)
		(layer "In13.Cu")
		(net "GPU_BASE_STBY_EN")
	)
	(segment
		(start 169.74058 -400.13128)
		(end 168.73093 -400.13128)
		(width 0.11684)
		(layer "In13.Cu")
		(net "GPU_BASE_STBY_EN")
	)
	(segment
		(start 171.391834 -414.241488)
		(end 172.591222 -415.440876)
		(width 0.11684)
		(layer "In13.Cu")
		(net "GPU_BASE_STBY_EN")
	)
	(segment
		(start 173.17212 -399.86712)
		(end 171.83862 -399.86712)
		(width 0.11684)
		(layer "In13.Cu")
		(net "GPU_BASE_STBY_EN")
	)
	(segment
		(start 170.00982 -399.86204)
		(end 169.74058 -400.13128)
		(width 0.11684)
		(layer "In13.Cu")
		(net "GPU_BASE_STBY_EN")
	)
	(segment
		(start 171.23029 -414.241488)
		(end 171.391834 -414.241488)
		(width 0.11684)
		(layer "In13.Cu")
		(net "GPU_BASE_STBY_EN")
	)
	(segment
		(start 169.898568 -412.495492)
		(end 170.170602 -412.767526)
		(width 0.11684)
		(layer "In13.Cu")
		(net "GPU_BASE_STBY_EN")
	)
	(segment
		(start 172.591222 -415.440876)
		(end 172.591222 -417.869116)
		(width 0.11684)
		(layer "In13.Cu")
		(net "GPU_BASE_STBY_EN")
	)
	(segment
		(start 166.22141 -402.6408)
		(end 166.22141 -407.579068)
		(width 0.11684)
		(layer "In13.Cu")
		(net "GPU_BASE_STBY_EN")
	)
	(segment
		(start 170.958256 -413.80791)
		(end 170.958256 -413.969454)
		(width 0.11684)
		(layer "In13.Cu")
		(net "GPU_BASE_STBY_EN")
	)
	(segment
		(start 168.212008 -409.569666)
		(end 168.212008 -411.061662)
		(width 0.11684)
		(layer "In13.Cu")
		(net "GPU_BASE_STBY_EN")
	)
	(segment
		(start 171.83354 -399.86204)
		(end 170.00982 -399.86204)
		(width 0.11684)
		(layer "In13.Cu")
		(net "GPU_BASE_STBY_EN")
	)
	(segment
		(start 170.170602 -412.767526)
		(end 170.170602 -413.020256)
		(width 0.11684)
		(layer "In13.Cu")
		(net "GPU_BASE_STBY_EN")
	)
	(segment
		(start 170.170602 -413.020256)
		(end 170.958256 -413.80791)
		(width 0.11684)
		(layer "In13.Cu")
		(net "GPU_BASE_STBY_EN")
	)
	(segment
		(start 168.212008 -411.061662)
		(end 169.645838 -412.495492)
		(width 0.11684)
		(layer "In13.Cu")
		(net "GPU_BASE_STBY_EN")
	)
	(segment
		(start 214.369142 -318.974978)
		(end 214.369142 -203.384658)
		(width 0.11684)
		(layer "In15.Cu")
		(net "GPU_BASE_STBY_EN")
	)
	(segment
		(start 178.371246 -391.99058)
		(end 178.371246 -391.714482)
		(width 0.11684)
		(layer "In15.Cu")
		(net "GPU_BASE_STBY_EN")
	)
	(segment
		(start 180.58892 -390.498584)
		(end 180.58892 -388.255764)
		(width 0.11684)
		(layer "In15.Cu")
		(net "GPU_BASE_STBY_EN")
	)
	(segment
		(start 178.935634 -391.150094)
		(end 179.93741 -391.150094)
		(width 0.11684)
		(layer "In15.Cu")
		(net "GPU_BASE_STBY_EN")
	)
	(segment
		(start 216.311226 -201.442574)
		(end 219.828364 -201.442574)
		(width 0.11684)
		(layer "In15.Cu")
		(net "GPU_BASE_STBY_EN")
	)
	(segment
		(start 193.416682 -370.220748)
		(end 220.594174 -343.043256)
		(width 0.11684)
		(layer "In15.Cu")
		(net "GPU_BASE_STBY_EN")
	)
	(segment
		(start 178.371246 -391.714482)
		(end 178.935634 -391.150094)
		(width 0.11684)
		(layer "In15.Cu")
		(net "GPU_BASE_STBY_EN")
	)
	(segment
		(start 174.401734 -395.960092)
		(end 178.371246 -391.99058)
		(width 0.11684)
		(layer "In15.Cu")
		(net "GPU_BASE_STBY_EN")
	)
	(segment
		(start 187.966604 -372.669308)
		(end 190.415164 -370.220748)
		(width 0.11684)
		(layer "In15.Cu")
		(net "GPU_BASE_STBY_EN")
	)
	(segment
		(start 214.369142 -203.384658)
		(end 216.311226 -201.442574)
		(width 0.11684)
		(layer "In15.Cu")
		(net "GPU_BASE_STBY_EN")
	)
	(segment
		(start 180.58892 -388.255764)
		(end 187.966604 -380.87808)
		(width 0.11684)
		(layer "In15.Cu")
		(net "GPU_BASE_STBY_EN")
	)
	(segment
		(start 174.401734 -398.637506)
		(end 174.401734 -395.960092)
		(width 0.11684)
		(layer "In15.Cu")
		(net "GPU_BASE_STBY_EN")
	)
	(segment
		(start 187.966604 -380.87808)
		(end 187.966604 -372.669308)
		(width 0.11684)
		(layer "In15.Cu")
		(net "GPU_BASE_STBY_EN")
	)
	(segment
		(start 179.93741 -391.150094)
		(end 180.58892 -390.498584)
		(width 0.11684)
		(layer "In15.Cu")
		(net "GPU_BASE_STBY_EN")
	)
	(segment
		(start 220.594174 -343.043256)
		(end 220.594174 -325.20001)
		(width 0.11684)
		(layer "In15.Cu")
		(net "GPU_BASE_STBY_EN")
	)
	(segment
		(start 173.17212 -399.86712)
		(end 174.401734 -398.637506)
		(width 0.11684)
		(layer "In15.Cu")
		(net "GPU_BASE_STBY_EN")
	)
	(segment
		(start 190.415164 -370.220748)
		(end 193.416682 -370.220748)
		(width 0.11684)
		(layer "In15.Cu")
		(net "GPU_BASE_STBY_EN")
	)
	(segment
		(start 220.594174 -325.20001)
		(end 214.369142 -318.974978)
		(width 0.11684)
		(layer "In15.Cu")
		(net "GPU_BASE_STBY_EN")
	)
	(segment
		(start 186.144408 -430.708054)
		(end 186.684158 -430.168304)
		(width 0.10668)
		(layer "F.Cu")
		(net "GPU_BASE_ID1")
	)
	(segment
		(start 187.316872 -427.655482)
		(end 187.316618 -427.655228)
		(width 0.10668)
		(layer "F.Cu")
		(net "GPU_BASE_ID1")
	)
	(segment
		(start 186.684158 -430.168304)
		(end 186.684158 -429.163226)
		(width 0.10668)
		(layer "F.Cu")
		(net "GPU_BASE_ID1")
	)
	(segment
		(start 187.316872 -428.530512)
		(end 187.316872 -427.655482)
		(width 0.10668)
		(layer "F.Cu")
		(net "GPU_BASE_ID1")
	)
	(segment
		(start 186.684158 -429.163226)
		(end 187.316872 -428.530512)
		(width 0.10668)
		(layer "F.Cu")
		(net "GPU_BASE_ID1")
	)
	(via
		(at 186.144408 -430.708054)
		(size 0.508)
		(drill 0.254)
		(layers "F.Cu" "B.Cu")
		(net "GPU_BASE_ID1")
	)
	(segment
		(start 175.58893 -418.754306)
		(end 175.431196 -418.91204)
		(width 0.11684)
		(layer "In2.Cu")
		(net "GPU_BASE_ID1")
	)
	(segment
		(start 169.517822 -417.545774)
		(end 161.81705 -417.545774)
		(width 0.11684)
		(layer "In2.Cu")
		(net "GPU_BASE_ID1")
	)
	(segment
		(start 99.292664 -423.972482)
		(end 98.173032 -425.092114)
		(width 0.11684)
		(layer "In2.Cu")
		(net "GPU_BASE_ID1")
	)
	(segment
		(start 108.664502 -419.673024)
		(end 104.365044 -423.972482)
		(width 0.11684)
		(layer "In2.Cu")
		(net "GPU_BASE_ID1")
	)
	(segment
		(start 170.592242 -417.730178)
		(end 169.702226 -417.730178)
		(width 0.11684)
		(layer "In2.Cu")
		(net "GPU_BASE_ID1")
	)
	(segment
		(start 173.601888 -418.91204)
		(end 171.872402 -417.182554)
		(width 0.11684)
		(layer "In2.Cu")
		(net "GPU_BASE_ID1")
	)
	(segment
		(start 98.173032 -425.092114)
		(end 90.052398 -425.092114)
		(width 0.11684)
		(layer "In2.Cu")
		(net "GPU_BASE_ID1")
	)
	(segment
		(start 175.431196 -418.91204)
		(end 173.601888 -418.91204)
		(width 0.11684)
		(layer "In2.Cu")
		(net "GPU_BASE_ID1")
	)
	(segment
		(start 169.702226 -417.730178)
		(end 169.517822 -417.545774)
		(width 0.11684)
		(layer "In2.Cu")
		(net "GPU_BASE_ID1")
	)
	(segment
		(start 119.90832 -418.695124)
		(end 118.558056 -418.695124)
		(width 0.11684)
		(layer "In2.Cu")
		(net "GPU_BASE_ID1")
	)
	(segment
		(start 180.77434 -424.687238)
		(end 180.77434 -420.186358)
		(width 0.11684)
		(layer "In2.Cu")
		(net "GPU_BASE_ID1")
	)
	(segment
		(start 121.112534 -417.49091)
		(end 119.90832 -418.695124)
		(width 0.11684)
		(layer "In2.Cu")
		(net "GPU_BASE_ID1")
	)
	(segment
		(start 118.558056 -418.695124)
		(end 117.580156 -419.673024)
		(width 0.11684)
		(layer "In2.Cu")
		(net "GPU_BASE_ID1")
	)
	(segment
		(start 104.365044 -423.972482)
		(end 99.292664 -423.972482)
		(width 0.11684)
		(layer "In2.Cu")
		(net "GPU_BASE_ID1")
	)
	(segment
		(start 186.144408 -430.708054)
		(end 185.69305 -430.708054)
		(width 0.11684)
		(layer "In2.Cu")
		(net "GPU_BASE_ID1")
	)
	(segment
		(start 185.69305 -430.708054)
		(end 184.272682 -429.287686)
		(width 0.11684)
		(layer "In2.Cu")
		(net "GPU_BASE_ID1")
	)
	(segment
		(start 184.272682 -428.18558)
		(end 180.77434 -424.687238)
		(width 0.11684)
		(layer "In2.Cu")
		(net "GPU_BASE_ID1")
	)
	(segment
		(start 171.872402 -417.182554)
		(end 171.139866 -417.182554)
		(width 0.11684)
		(layer "In2.Cu")
		(net "GPU_BASE_ID1")
	)
	(segment
		(start 184.272682 -429.287686)
		(end 184.272682 -428.18558)
		(width 0.11684)
		(layer "In2.Cu")
		(net "GPU_BASE_ID1")
	)
	(segment
		(start 161.81705 -417.545774)
		(end 161.762186 -417.49091)
		(width 0.11684)
		(layer "In2.Cu")
		(net "GPU_BASE_ID1")
	)
	(segment
		(start 90.052398 -425.092114)
		(end 89.650062 -424.689778)
		(width 0.11684)
		(layer "In2.Cu")
		(net "GPU_BASE_ID1")
	)
	(segment
		(start 180.77434 -420.186358)
		(end 179.342288 -418.754306)
		(width 0.11684)
		(layer "In2.Cu")
		(net "GPU_BASE_ID1")
	)
	(segment
		(start 179.342288 -418.754306)
		(end 175.58893 -418.754306)
		(width 0.11684)
		(layer "In2.Cu")
		(net "GPU_BASE_ID1")
	)
	(segment
		(start 117.580156 -419.673024)
		(end 108.664502 -419.673024)
		(width 0.11684)
		(layer "In2.Cu")
		(net "GPU_BASE_ID1")
	)
	(segment
		(start 171.139866 -417.182554)
		(end 170.592242 -417.730178)
		(width 0.11684)
		(layer "In2.Cu")
		(net "GPU_BASE_ID1")
	)
	(segment
		(start 161.762186 -417.49091)
		(end 121.112534 -417.49091)
		(width 0.11684)
		(layer "In2.Cu")
		(net "GPU_BASE_ID1")
	)
	(segment
		(start 188.751464 -429.923956)
		(end 188.751464 -428.036228)
		(width 0.10668)
		(layer "F.Cu")
		(net "GPU_BASE_ID0")
	)
	(segment
		(start 189.678564 -430.793144)
		(end 189.620652 -430.793144)
		(width 0.10668)
		(layer "F.Cu")
		(net "GPU_BASE_ID0")
	)
	(segment
		(start 189.620652 -430.793144)
		(end 188.751464 -429.923956)
		(width 0.10668)
		(layer "F.Cu")
		(net "GPU_BASE_ID0")
	)
	(segment
		(start 188.384434 -427.669198)
		(end 188.296804 -427.669198)
		(width 0.10668)
		(layer "F.Cu")
		(net "GPU_BASE_ID0")
	)
	(segment
		(start 188.296804 -427.669198)
		(end 188.296804 -426.753528)
		(width 0.10668)
		(layer "F.Cu")
		(net "GPU_BASE_ID0")
	)
	(segment
		(start 188.751464 -428.036228)
		(end 188.384434 -427.669198)
		(width 0.10668)
		(layer "F.Cu")
		(net "GPU_BASE_ID0")
	)
	(via
		(at 189.678564 -430.793144)
		(size 0.508)
		(drill 0.254)
		(layers "F.Cu" "B.Cu")
		(net "GPU_BASE_ID0")
	)
	(segment
		(start 189.620652 -430.793144)
		(end 189.317122 -430.489614)
		(width 0.11684)
		(layer "In2.Cu")
		(net "GPU_BASE_ID0")
	)
	(segment
		(start 80.704944 -424.830748)
		(end 80.704944 -439.434986)
		(width 0.11684)
		(layer "In2.Cu")
		(net "GPU_BASE_ID0")
	)
	(segment
		(start 173.999906 -414.277048)
		(end 170.968416 -414.277048)
		(width 0.11684)
		(layer "In2.Cu")
		(net "GPU_BASE_ID0")
	)
	(segment
		(start 164.216334 -415.421064)
		(end 163.736782 -414.941512)
		(width 0.11684)
		(layer "In2.Cu")
		(net "GPU_BASE_ID0")
	)
	(segment
		(start 107.5817 -417.461446)
		(end 105.800652 -419.242494)
		(width 0.11684)
		(layer "In2.Cu")
		(net "GPU_BASE_ID0")
	)
	(segment
		(start 182.813452 -419.783006)
		(end 178.578002 -415.547556)
		(width 0.11684)
		(layer "In2.Cu")
		(net "GPU_BASE_ID0")
	)
	(segment
		(start 189.678564 -430.793144)
		(end 189.620652 -430.793144)
		(width 0.11684)
		(layer "In2.Cu")
		(net "GPU_BASE_ID0")
	)
	(segment
		(start 167.780208 -415.421064)
		(end 164.216334 -415.421064)
		(width 0.11684)
		(layer "In2.Cu")
		(net "GPU_BASE_ID0")
	)
	(segment
		(start 168.187624 -415.82848)
		(end 167.780208 -415.421064)
		(width 0.11684)
		(layer "In2.Cu")
		(net "GPU_BASE_ID0")
	)
	(segment
		(start 92.06738 -424.273726)
		(end 91.594686 -423.801032)
		(width 0.11684)
		(layer "In2.Cu")
		(net "GPU_BASE_ID0")
	)
	(segment
		(start 115.440206 -417.461446)
		(end 107.5817 -417.461446)
		(width 0.11684)
		(layer "In2.Cu")
		(net "GPU_BASE_ID0")
	)
	(segment
		(start 174.700438 -414.97758)
		(end 173.999906 -414.277048)
		(width 0.11684)
		(layer "In2.Cu")
		(net "GPU_BASE_ID0")
	)
	(segment
		(start 105.800652 -419.242494)
		(end 105.800652 -420.895272)
		(width 0.11684)
		(layer "In2.Cu")
		(net "GPU_BASE_ID0")
	)
	(segment
		(start 81.73466 -423.801032)
		(end 80.704944 -424.830748)
		(width 0.11684)
		(layer "In2.Cu")
		(net "GPU_BASE_ID0")
	)
	(segment
		(start 170.27906 -414.966404)
		(end 169.435272 -414.966404)
		(width 0.11684)
		(layer "In2.Cu")
		(net "GPU_BASE_ID0")
	)
	(segment
		(start 95.018606 -424.273726)
		(end 92.06738 -424.273726)
		(width 0.11684)
		(layer "In2.Cu")
		(net "GPU_BASE_ID0")
	)
	(segment
		(start 98.006154 -422.024556)
		(end 97.305876 -422.724834)
		(width 0.11684)
		(layer "In2.Cu")
		(net "GPU_BASE_ID0")
	)
	(segment
		(start 104.671368 -422.024556)
		(end 98.006154 -422.024556)
		(width 0.11684)
		(layer "In2.Cu")
		(net "GPU_BASE_ID0")
	)
	(segment
		(start 91.594686 -423.801032)
		(end 81.73466 -423.801032)
		(width 0.11684)
		(layer "In2.Cu")
		(net "GPU_BASE_ID0")
	)
	(segment
		(start 182.813452 -423.684446)
		(end 182.813452 -419.783006)
		(width 0.11684)
		(layer "In2.Cu")
		(net "GPU_BASE_ID0")
	)
	(segment
		(start 153.450798 -414.941512)
		(end 152.518872 -415.873438)
		(width 0.11684)
		(layer "In2.Cu")
		(net "GPU_BASE_ID0")
	)
	(segment
		(start 178.578002 -415.547556)
		(end 177.066702 -415.547556)
		(width 0.11684)
		(layer "In2.Cu")
		(net "GPU_BASE_ID0")
	)
	(segment
		(start 96.567498 -422.724834)
		(end 95.018606 -424.273726)
		(width 0.11684)
		(layer "In2.Cu")
		(net "GPU_BASE_ID0")
	)
	(segment
		(start 177.066702 -415.547556)
		(end 176.496726 -414.97758)
		(width 0.11684)
		(layer "In2.Cu")
		(net "GPU_BASE_ID0")
	)
	(segment
		(start 170.968416 -414.277048)
		(end 170.27906 -414.966404)
		(width 0.11684)
		(layer "In2.Cu")
		(net "GPU_BASE_ID0")
	)
	(segment
		(start 152.518872 -415.873438)
		(end 117.028214 -415.873438)
		(width 0.11684)
		(layer "In2.Cu")
		(net "GPU_BASE_ID0")
	)
	(segment
		(start 189.317122 -430.188116)
		(end 182.813452 -423.684446)
		(width 0.11684)
		(layer "In2.Cu")
		(net "GPU_BASE_ID0")
	)
	(segment
		(start 80.704944 -439.434986)
		(end 79.650082 -440.489848)
		(width 0.11684)
		(layer "In2.Cu")
		(net "GPU_BASE_ID0")
	)
	(segment
		(start 105.800652 -420.895272)
		(end 104.671368 -422.024556)
		(width 0.11684)
		(layer "In2.Cu")
		(net "GPU_BASE_ID0")
	)
	(segment
		(start 97.305876 -422.724834)
		(end 96.567498 -422.724834)
		(width 0.11684)
		(layer "In2.Cu")
		(net "GPU_BASE_ID0")
	)
	(segment
		(start 189.317122 -430.489614)
		(end 189.317122 -430.188116)
		(width 0.11684)
		(layer "In2.Cu")
		(net "GPU_BASE_ID0")
	)
	(segment
		(start 176.496726 -414.97758)
		(end 174.700438 -414.97758)
		(width 0.11684)
		(layer "In2.Cu")
		(net "GPU_BASE_ID0")
	)
	(segment
		(start 163.736782 -414.941512)
		(end 153.450798 -414.941512)
		(width 0.11684)
		(layer "In2.Cu")
		(net "GPU_BASE_ID0")
	)
	(segment
		(start 168.573196 -415.82848)
		(end 168.187624 -415.82848)
		(width 0.11684)
		(layer "In2.Cu")
		(net "GPU_BASE_ID0")
	)
	(segment
		(start 117.028214 -415.873438)
		(end 115.440206 -417.461446)
		(width 0.11684)
		(layer "In2.Cu")
		(net "GPU_BASE_ID0")
	)
	(segment
		(start 169.435272 -414.966404)
		(end 168.573196 -415.82848)
		(width 0.11684)
		(layer "In2.Cu")
		(net "GPU_BASE_ID0")
	)
	(segment
		(start 170.06697 -437.778906)
		(end 170.41368 -437.432196)
		(width 0.10668)
		(layer "F.Cu")
		(net "GPU_BASE_HMC_READY_N")
	)
	(segment
		(start 168.821862 -436.78221)
		(end 168.821862 -437.432196)
		(width 0.10668)
		(layer "F.Cu")
		(net "GPU_BASE_HMC_READY_N")
	)
	(segment
		(start 170.41368 -437.432196)
		(end 170.970702 -437.432196)
		(width 0.10668)
		(layer "F.Cu")
		(net "GPU_BASE_HMC_READY_N")
	)
	(segment
		(start 168.821862 -437.432196)
		(end 169.168572 -437.778906)
		(width 0.10668)
		(layer "F.Cu")
		(net "GPU_BASE_HMC_READY_N")
	)
	(segment
		(start 169.168572 -437.778906)
		(end 170.06697 -437.778906)
		(width 0.10668)
		(layer "F.Cu")
		(net "GPU_BASE_HMC_READY_N")
	)
	(via
		(at 170.06697 -437.778906)
		(size 0.762)
		(drill 0.381)
		(layers "F.Cu" "B.Cu")
		(net "GPU_BASE_HMC_READY_N")
	)
	(segment
		(start 209.56905 -183.96204)
		(end 211.685632 -189.071758)
		(width 0.10668)
		(layer "F.Cu")
		(net "GPU_BASE_HMC_READY_ISO")
	)
	(segment
		(start 195.596002 -171.72305)
		(end 197.33006 -171.72305)
		(width 0.10668)
		(layer "F.Cu")
		(net "GPU_BASE_HMC_READY_ISO")
	)
	(segment
		(start 163.82365 -436.153052)
		(end 164.80155 -436.153052)
		(width 0.10668)
		(layer "F.Cu")
		(net "GPU_BASE_HMC_READY_ISO")
	)
	(segment
		(start 197.33006 -171.72305)
		(end 209.56905 -183.96204)
		(width 0.10668)
		(layer "F.Cu")
		(net "GPU_BASE_HMC_READY_ISO")
	)
	(segment
		(start 195.21551 -172.103542)
		(end 195.596002 -171.72305)
		(width 0.10668)
		(layer "F.Cu")
		(net "GPU_BASE_HMC_READY_ISO")
	)
	(segment
		(start 165.298882 -435.65572)
		(end 164.80155 -436.153052)
		(width 0.10668)
		(layer "F.Cu")
		(net "GPU_BASE_HMC_READY_ISO")
	)
	(segment
		(start 209.094324 -198.122794)
		(end 209.012282 -198.204836)
		(width 0.10668)
		(layer "F.Cu")
		(net "GPU_BASE_HMC_READY_ISO")
	)
	(segment
		(start 209.182716 -198.122794)
		(end 209.094324 -198.122794)
		(width 0.10668)
		(layer "F.Cu")
		(net "GPU_BASE_HMC_READY_ISO")
	)
	(segment
		(start 211.685632 -189.071758)
		(end 211.685632 -195.619878)
		(width 0.10668)
		(layer "F.Cu")
		(net "GPU_BASE_HMC_READY_ISO")
	)
	(segment
		(start 205.581758 -117.748812)
		(end 206.497682 -117.748812)
		(width 0.10668)
		(layer "F.Cu")
		(net "GPU_BASE_HMC_READY_ISO")
	)
	(segment
		(start 211.685632 -195.619878)
		(end 209.182716 -198.122794)
		(width 0.10668)
		(layer "F.Cu")
		(net "GPU_BASE_HMC_READY_ISO")
	)
	(segment
		(start 166.921942 -436.132224)
		(end 166.638986 -436.132224)
		(width 0.10668)
		(layer "F.Cu")
		(net "GPU_BASE_HMC_READY_ISO")
	)
	(segment
		(start 166.921942 -436.132224)
		(end 167.527478 -435.526688)
		(width 0.10668)
		(layer "F.Cu")
		(net "GPU_BASE_HMC_READY_ISO")
	)
	(segment
		(start 166.162482 -435.65572)
		(end 165.298882 -435.65572)
		(width 0.10668)
		(layer "F.Cu")
		(net "GPU_BASE_HMC_READY_ISO")
	)
	(segment
		(start 166.638986 -436.132224)
		(end 166.162482 -435.65572)
		(width 0.10668)
		(layer "F.Cu")
		(net "GPU_BASE_HMC_READY_ISO")
	)
	(via
		(at 209.012282 -198.204836)
		(size 0.508)
		(drill 0.254)
		(layers "F.Cu" "B.Cu")
		(net "GPU_BASE_HMC_READY_ISO")
	)
	(via
		(at 167.527478 -435.526688)
		(size 0.508)
		(drill 0.254)
		(layers "F.Cu" "B.Cu")
		(net "GPU_BASE_HMC_READY_ISO")
	)
	(via
		(at 206.497682 -117.748812)
		(size 0.508)
		(drill 0.254)
		(layers "F.Cu" "B.Cu")
		(net "GPU_BASE_HMC_READY_ISO")
	)
	(via
		(at 195.21551 -172.103542)
		(size 0.508)
		(drill 0.254)
		(layers "F.Cu" "B.Cu")
		(net "GPU_BASE_HMC_READY_ISO")
	)
	(segment
		(start 179.493672 -383.053844)
		(end 191.699388 -370.848128)
		(width 0.11684)
		(layer "In6.Cu")
		(net "GPU_BASE_HMC_READY_ISO")
	)
	(segment
		(start 169.240962 -412.767526)
		(end 169.4942 -412.514288)
		(width 0.11684)
		(layer "In6.Cu")
		(net "GPU_BASE_HMC_READY_ISO")
	)
	(segment
		(start 223.717866 -364.485174)
		(end 223.717866 -363.700822)
		(width 0.11684)
		(layer "In6.Cu")
		(net "GPU_BASE_HMC_READY_ISO")
	)
	(segment
		(start 169.4942 -409.669234)
		(end 166.669974 -406.845008)
		(width 0.11684)
		(layer "In6.Cu")
		(net "GPU_BASE_HMC_READY_ISO")
	)
	(segment
		(start 225.57486 -331.779626)
		(end 225.275394 -331.48016)
		(width 0.11684)
		(layer "In6.Cu")
		(net "GPU_BASE_HMC_READY_ISO")
	)
	(segment
		(start 161.940494 -431.783744)
		(end 162.867848 -430.85639)
		(width 0.11684)
		(layer "In6.Cu")
		(net "GPU_BASE_HMC_READY_ISO")
	)
	(segment
		(start 191.699388 -370.848128)
		(end 219.70238 -370.848128)
		(width 0.11684)
		(layer "In6.Cu")
		(net "GPU_BASE_HMC_READY_ISO")
	)
	(segment
		(start 166.669974 -406.845008)
		(end 166.669974 -401.014946)
		(width 0.11684)
		(layer "In6.Cu")
		(net "GPU_BASE_HMC_READY_ISO")
	)
	(segment
		(start 167.023542 -425.604432)
		(end 168.57726 -424.050714)
		(width 0.11684)
		(layer "In6.Cu")
		(net "GPU_BASE_HMC_READY_ISO")
	)
	(segment
		(start 168.57726 -424.050714)
		(end 168.57726 -421.677846)
		(width 0.11684)
		(layer "In6.Cu")
		(net "GPU_BASE_HMC_READY_ISO")
	)
	(segment
		(start 168.22039 -419.5953)
		(end 168.976294 -418.839396)
		(width 0.11684)
		(layer "In6.Cu")
		(net "GPU_BASE_HMC_READY_ISO")
	)
	(segment
		(start 168.57726 -421.677846)
		(end 168.22039 -421.320976)
		(width 0.11684)
		(layer "In6.Cu")
		(net "GPU_BASE_HMC_READY_ISO")
	)
	(segment
		(start 169.240962 -414.679892)
		(end 169.240962 -412.767526)
		(width 0.11684)
		(layer "In6.Cu")
		(net "GPU_BASE_HMC_READY_ISO")
	)
	(segment
		(start 164.831776 -435.526688)
		(end 161.940494 -432.635406)
		(width 0.11684)
		(layer "In6.Cu")
		(net "GPU_BASE_HMC_READY_ISO")
	)
	(segment
		(start 170.380152 -398.27708)
		(end 174.169324 -394.487908)
		(width 0.11684)
		(layer "In6.Cu")
		(net "GPU_BASE_HMC_READY_ISO")
	)
	(segment
		(start 225.275394 -332.72984)
		(end 225.57486 -332.430374)
		(width 0.11684)
		(layer "In6.Cu")
		(net "GPU_BASE_HMC_READY_ISO")
	)
	(segment
		(start 168.976294 -418.839396)
		(end 168.976294 -414.94456)
		(width 0.11684)
		(layer "In6.Cu")
		(net "GPU_BASE_HMC_READY_ISO")
	)
	(segment
		(start 179.493672 -385.185158)
		(end 179.493672 -383.053844)
		(width 0.11684)
		(layer "In6.Cu")
		(net "GPU_BASE_HMC_READY_ISO")
	)
	(segment
		(start 166.669974 -401.014946)
		(end 169.40784 -398.27708)
		(width 0.11684)
		(layer "In6.Cu")
		(net "GPU_BASE_HMC_READY_ISO")
	)
	(segment
		(start 169.40784 -398.27708)
		(end 170.380152 -398.27708)
		(width 0.11684)
		(layer "In6.Cu")
		(net "GPU_BASE_HMC_READY_ISO")
	)
	(segment
		(start 225.275394 -362.143294)
		(end 225.275394 -332.72984)
		(width 0.11684)
		(layer "In6.Cu")
		(net "GPU_BASE_HMC_READY_ISO")
	)
	(segment
		(start 225.275394 -330.94168)
		(end 214.810848 -320.477134)
		(width 0.11684)
		(layer "In6.Cu")
		(net "GPU_BASE_HMC_READY_ISO")
	)
	(segment
		(start 161.940494 -432.635406)
		(end 161.940494 -431.783744)
		(width 0.11684)
		(layer "In6.Cu")
		(net "GPU_BASE_HMC_READY_ISO")
	)
	(segment
		(start 214.810848 -320.477134)
		(end 214.810848 -203.563982)
		(width 0.11684)
		(layer "In6.Cu")
		(net "GPU_BASE_HMC_READY_ISO")
	)
	(segment
		(start 225.57486 -332.430374)
		(end 225.57486 -331.779626)
		(width 0.11684)
		(layer "In6.Cu")
		(net "GPU_BASE_HMC_READY_ISO")
	)
	(segment
		(start 222.595948 -367.506504)
		(end 223.585024 -366.517428)
		(width 0.11684)
		(layer "In6.Cu")
		(net "GPU_BASE_HMC_READY_ISO")
	)
	(segment
		(start 214.810848 -203.563982)
		(end 209.451702 -198.204836)
		(width 0.11684)
		(layer "In6.Cu")
		(net "GPU_BASE_HMC_READY_ISO")
	)
	(segment
		(start 223.585024 -364.618016)
		(end 223.717866 -364.485174)
		(width 0.11684)
		(layer "In6.Cu")
		(net "GPU_BASE_HMC_READY_ISO")
	)
	(segment
		(start 174.169324 -390.509506)
		(end 179.493672 -385.185158)
		(width 0.11684)
		(layer "In6.Cu")
		(net "GPU_BASE_HMC_READY_ISO")
	)
	(segment
		(start 169.4942 -412.514288)
		(end 169.4942 -409.669234)
		(width 0.11684)
		(layer "In6.Cu")
		(net "GPU_BASE_HMC_READY_ISO")
	)
	(segment
		(start 225.275394 -331.48016)
		(end 225.275394 -330.94168)
		(width 0.11684)
		(layer "In6.Cu")
		(net "GPU_BASE_HMC_READY_ISO")
	)
	(segment
		(start 164.39642 -430.85639)
		(end 167.023542 -428.229268)
		(width 0.11684)
		(layer "In6.Cu")
		(net "GPU_BASE_HMC_READY_ISO")
	)
	(segment
		(start 222.595948 -367.95456)
		(end 222.595948 -367.506504)
		(width 0.11684)
		(layer "In6.Cu")
		(net "GPU_BASE_HMC_READY_ISO")
	)
	(segment
		(start 168.976294 -414.94456)
		(end 169.240962 -414.679892)
		(width 0.11684)
		(layer "In6.Cu")
		(net "GPU_BASE_HMC_READY_ISO")
	)
	(segment
		(start 223.585024 -366.517428)
		(end 223.585024 -364.618016)
		(width 0.11684)
		(layer "In6.Cu")
		(net "GPU_BASE_HMC_READY_ISO")
	)
	(segment
		(start 223.717866 -363.700822)
		(end 225.275394 -362.143294)
		(width 0.11684)
		(layer "In6.Cu")
		(net "GPU_BASE_HMC_READY_ISO")
	)
	(segment
		(start 167.527478 -435.526688)
		(end 164.831776 -435.526688)
		(width 0.11684)
		(layer "In6.Cu")
		(net "GPU_BASE_HMC_READY_ISO")
	)
	(segment
		(start 168.22039 -421.320976)
		(end 168.22039 -419.5953)
		(width 0.11684)
		(layer "In6.Cu")
		(net "GPU_BASE_HMC_READY_ISO")
	)
	(segment
		(start 174.169324 -394.487908)
		(end 174.169324 -390.509506)
		(width 0.11684)
		(layer "In6.Cu")
		(net "GPU_BASE_HMC_READY_ISO")
	)
	(segment
		(start 162.867848 -430.85639)
		(end 164.39642 -430.85639)
		(width 0.11684)
		(layer "In6.Cu")
		(net "GPU_BASE_HMC_READY_ISO")
	)
	(segment
		(start 209.451702 -198.204836)
		(end 209.012282 -198.204836)
		(width 0.11684)
		(layer "In6.Cu")
		(net "GPU_BASE_HMC_READY_ISO")
	)
	(segment
		(start 167.023542 -428.229268)
		(end 167.023542 -425.604432)
		(width 0.11684)
		(layer "In6.Cu")
		(net "GPU_BASE_HMC_READY_ISO")
	)
	(segment
		(start 219.70238 -370.848128)
		(end 222.595948 -367.95456)
		(width 0.11684)
		(layer "In6.Cu")
		(net "GPU_BASE_HMC_READY_ISO")
	)
	(segment
		(start 202.613768 -156.1592)
		(end 202.613768 -139.764516)
		(width 0.11684)
		(layer "In11.Cu")
		(net "GPU_BASE_HMC_READY_ISO")
	)
	(segment
		(start 202.127358 -165.191694)
		(end 202.127358 -156.64561)
		(width 0.11684)
		(layer "In11.Cu")
		(net "GPU_BASE_HMC_READY_ISO")
	)
	(segment
		(start 206.892652 -127.852678)
		(end 206.015336 -126.975362)
		(width 0.11684)
		(layer "In11.Cu")
		(net "GPU_BASE_HMC_READY_ISO")
	)
	(segment
		(start 206.709772 -129.830068)
		(end 206.892652 -129.647188)
		(width 0.11684)
		(layer "In11.Cu")
		(net "GPU_BASE_HMC_READY_ISO")
	)
	(segment
		(start 202.613768 -139.764516)
		(end 206.709772 -135.668512)
		(width 0.11684)
		(layer "In11.Cu")
		(net "GPU_BASE_HMC_READY_ISO")
	)
	(segment
		(start 195.21551 -172.103542)
		(end 202.127358 -165.191694)
		(width 0.11684)
		(layer "In11.Cu")
		(net "GPU_BASE_HMC_READY_ISO")
	)
	(segment
		(start 206.892652 -129.647188)
		(end 206.892652 -127.852678)
		(width 0.11684)
		(layer "In11.Cu")
		(net "GPU_BASE_HMC_READY_ISO")
	)
	(segment
		(start 206.497682 -118.920768)
		(end 206.497682 -117.748812)
		(width 0.11684)
		(layer "In11.Cu")
		(net "GPU_BASE_HMC_READY_ISO")
	)
	(segment
		(start 206.015336 -126.975362)
		(end 206.015336 -119.403114)
		(width 0.11684)
		(layer "In11.Cu")
		(net "GPU_BASE_HMC_READY_ISO")
	)
	(segment
		(start 206.015336 -119.403114)
		(end 206.497682 -118.920768)
		(width 0.11684)
		(layer "In11.Cu")
		(net "GPU_BASE_HMC_READY_ISO")
	)
	(segment
		(start 202.127358 -156.64561)
		(end 202.613768 -156.1592)
		(width 0.11684)
		(layer "In11.Cu")
		(net "GPU_BASE_HMC_READY_ISO")
	)
	(segment
		(start 206.709772 -135.668512)
		(end 206.709772 -129.830068)
		(width 0.11684)
		(layer "In11.Cu")
		(net "GPU_BASE_HMC_READY_ISO")
	)
	(segment
		(start 166.921942 -436.78221)
		(end 166.773606 -436.930546)
		(width 0.10668)
		(layer "F.Cu")
		(net "GPU_BASE_HMC_READY")
	)
	(segment
		(start 166.773606 -436.930546)
		(end 165.294056 -436.930546)
		(width 0.10668)
		(layer "F.Cu")
		(net "GPU_BASE_HMC_READY")
	)
	(segment
		(start 166.921942 -436.78221)
		(end 167.978074 -436.78221)
		(width 0.10668)
		(layer "F.Cu")
		(net "GPU_BASE_HMC_READY")
	)
	(segment
		(start 165.294056 -436.930546)
		(end 164.80155 -437.423052)
		(width 0.10668)
		(layer "F.Cu")
		(net "GPU_BASE_HMC_READY")
	)
	(segment
		(start 164.80155 -437.423052)
		(end 163.82365 -437.423052)
		(width 0.10668)
		(layer "F.Cu")
		(net "GPU_BASE_HMC_READY")
	)
	(segment
		(start 167.978074 -436.78221)
		(end 168.17848 -436.982616)
		(width 0.10668)
		(layer "F.Cu")
		(net "GPU_BASE_HMC_READY")
	)
	(via
		(at 168.17848 -436.982616)
		(size 0.508)
		(drill 0.254)
		(layers "F.Cu" "B.Cu")
		(net "GPU_BASE_HMC_READY")
	)
	(segment
		(start 161.547048 -424.636692)
		(end 159.581088 -422.670732)
		(width 0.11684)
		(layer "In2.Cu")
		(net "GPU_BASE_HMC_READY")
	)
	(segment
		(start 159.581088 -422.670732)
		(end 136.964674 -422.670732)
		(width 0.11684)
		(layer "In2.Cu")
		(net "GPU_BASE_HMC_READY")
	)
	(segment
		(start 171.152312 -434.008784)
		(end 171.152312 -430.84877)
		(width 0.11684)
		(layer "In2.Cu")
		(net "GPU_BASE_HMC_READY")
	)
	(segment
		(start 164.245544 -429.023018)
		(end 162.867594 -427.645068)
		(width 0.11684)
		(layer "In2.Cu")
		(net "GPU_BASE_HMC_READY")
	)
	(segment
		(start 161.547048 -426.005752)
		(end 161.547048 -424.636692)
		(width 0.11684)
		(layer "In2.Cu")
		(net "GPU_BASE_HMC_READY")
	)
	(segment
		(start 168.17848 -436.982616)
		(end 171.152312 -434.008784)
		(width 0.11684)
		(layer "In2.Cu")
		(net "GPU_BASE_HMC_READY")
	)
	(segment
		(start 169.825162 -429.52162)
		(end 165.68674 -429.52162)
		(width 0.11684)
		(layer "In2.Cu")
		(net "GPU_BASE_HMC_READY")
	)
	(segment
		(start 134.898892 -424.736514)
		(end 134.898892 -439.340752)
		(width 0.11684)
		(layer "In2.Cu")
		(net "GPU_BASE_HMC_READY")
	)
	(segment
		(start 171.152312 -430.84877)
		(end 169.825162 -429.52162)
		(width 0.11684)
		(layer "In2.Cu")
		(net "GPU_BASE_HMC_READY")
	)
	(segment
		(start 136.964674 -422.670732)
		(end 134.898892 -424.736514)
		(width 0.11684)
		(layer "In2.Cu")
		(net "GPU_BASE_HMC_READY")
	)
	(segment
		(start 162.867594 -427.645068)
		(end 162.867594 -427.326298)
		(width 0.11684)
		(layer "In2.Cu")
		(net "GPU_BASE_HMC_READY")
	)
	(segment
		(start 162.867594 -427.326298)
		(end 161.547048 -426.005752)
		(width 0.11684)
		(layer "In2.Cu")
		(net "GPU_BASE_HMC_READY")
	)
	(segment
		(start 134.898892 -439.340752)
		(end 133.749796 -440.489848)
		(width 0.11684)
		(layer "In2.Cu")
		(net "GPU_BASE_HMC_READY")
	)
	(segment
		(start 165.68674 -429.52162)
		(end 165.188138 -429.023018)
		(width 0.11684)
		(layer "In2.Cu")
		(net "GPU_BASE_HMC_READY")
	)
	(segment
		(start 165.188138 -429.023018)
		(end 164.245544 -429.023018)
		(width 0.11684)
		(layer "In2.Cu")
		(net "GPU_BASE_HMC_READY")
	)
	(segment
		(start 303.355756 -437.820308)
		(end 303.355756 -437.170322)
		(width 0.10668)
		(layer "F.Cu")
		(net "GPU_3V3IO_RSVD5_FFU_N")
	)
	(segment
		(start 304.775108 -439.877962)
		(end 303.403508 -439.877962)
		(width 0.10668)
		(layer "F.Cu")
		(net "GPU_3V3IO_RSVD5_FFU_N")
	)
	(segment
		(start 302.121316 -438.59577)
		(end 302.121316 -437.820308)
		(width 0.10668)
		(layer "F.Cu")
		(net "GPU_3V3IO_RSVD5_FFU_N")
	)
	(segment
		(start 303.403508 -439.877962)
		(end 302.121316 -438.59577)
		(width 0.10668)
		(layer "F.Cu")
		(net "GPU_3V3IO_RSVD5_FFU_N")
	)
	(segment
		(start 302.121316 -437.820308)
		(end 303.355756 -437.820308)
		(width 0.10668)
		(layer "F.Cu")
		(net "GPU_3V3IO_RSVD5_FFU_N")
	)
	(via
		(at 302.121316 -437.820308)
		(size 0.762)
		(drill 0.381)
		(layers "F.Cu" "B.Cu")
		(net "GPU_3V3IO_RSVD5_FFU_N")
	)
	(segment
		(start 201.352658 -117.689376)
		(end 202.519788 -117.689376)
		(width 0.10668)
		(layer "F.Cu")
		(net "GPU_3V3IO_RSVD5_FFU_ISO")
	)
	(segment
		(start 308.420516 -438.876694)
		(end 307.404516 -438.876694)
		(width 0.10668)
		(layer "F.Cu")
		(net "GPU_3V3IO_RSVD5_FFU_ISO")
	)
	(segment
		(start 309.813452 -438.876694)
		(end 308.420516 -438.876694)
		(width 0.10668)
		(layer "F.Cu")
		(net "GPU_3V3IO_RSVD5_FFU_ISO")
	)
	(segment
		(start 305.662076 -438.876694)
		(end 305.255676 -438.470294)
		(width 0.10668)
		(layer "F.Cu")
		(net "GPU_3V3IO_RSVD5_FFU_ISO")
	)
	(segment
		(start 307.404516 -438.876694)
		(end 306.388516 -438.876694)
		(width 0.10668)
		(layer "F.Cu")
		(net "GPU_3V3IO_RSVD5_FFU_ISO")
	)
	(segment
		(start 306.388516 -438.876694)
		(end 305.662076 -438.876694)
		(width 0.10668)
		(layer "F.Cu")
		(net "GPU_3V3IO_RSVD5_FFU_ISO")
	)
	(via
		(at 294.457882 -373.667528)
		(size 0.508)
		(drill 0.254)
		(layers "F.Cu" "B.Cu")
		(net "GPU_3V3IO_RSVD5_FFU_ISO")
	)
	(via
		(at 202.519788 -117.689376)
		(size 0.508)
		(drill 0.254)
		(layers "F.Cu" "B.Cu")
		(net "GPU_3V3IO_RSVD5_FFU_ISO")
	)
	(via
		(at 309.813452 -438.876694)
		(size 0.508)
		(drill 0.254)
		(layers "F.Cu" "B.Cu")
		(net "GPU_3V3IO_RSVD5_FFU_ISO")
	)
	(via
		(at 407.106628 -364.72368)
		(size 0.508)
		(drill 0.254)
		(layers "F.Cu" "B.Cu")
		(net "GPU_3V3IO_RSVD5_FFU_ISO")
	)
	(segment
		(start 401.616672 -369.70081)
		(end 301.765208 -369.70081)
		(width 0.10668)
		(layer "B.Cu")
		(net "GPU_3V3IO_RSVD5_FFU_ISO")
	)
	(segment
		(start 296.29735 -370.76888)
		(end 296.29735 -371.82806)
		(width 0.10668)
		(layer "B.Cu")
		(net "GPU_3V3IO_RSVD5_FFU_ISO")
	)
	(segment
		(start 407.106628 -364.72368)
		(end 405.282908 -366.5474)
		(width 0.10668)
		(layer "B.Cu")
		(net "GPU_3V3IO_RSVD5_FFU_ISO")
	)
	(segment
		(start 405.282908 -366.5474)
		(end 404.770082 -366.5474)
		(width 0.10668)
		(layer "B.Cu")
		(net "GPU_3V3IO_RSVD5_FFU_ISO")
	)
	(segment
		(start 301.765208 -369.70081)
		(end 300.821598 -368.7572)
		(width 0.10668)
		(layer "B.Cu")
		(net "GPU_3V3IO_RSVD5_FFU_ISO")
	)
	(segment
		(start 404.770082 -366.5474)
		(end 401.616672 -369.70081)
		(width 0.10668)
		(layer "B.Cu")
		(net "GPU_3V3IO_RSVD5_FFU_ISO")
	)
	(segment
		(start 300.821598 -368.7572)
		(end 298.30903 -368.7572)
		(width 0.10668)
		(layer "B.Cu")
		(net "GPU_3V3IO_RSVD5_FFU_ISO")
	)
	(segment
		(start 298.30903 -368.7572)
		(end 296.29735 -370.76888)
		(width 0.10668)
		(layer "B.Cu")
		(net "GPU_3V3IO_RSVD5_FFU_ISO")
	)
	(segment
		(start 296.29735 -371.82806)
		(end 294.457882 -373.667528)
		(width 0.10668)
		(layer "B.Cu")
		(net "GPU_3V3IO_RSVD5_FFU_ISO")
	)
	(segment
		(start 295.245028 -400.97329)
		(end 298.947078 -397.27124)
		(width 0.11684)
		(layer "In4.Cu")
		(net "GPU_3V3IO_RSVD5_FFU_ISO")
	)
	(segment
		(start 310.598312 -438.091834)
		(end 310.598312 -432.776884)
		(width 0.11684)
		(layer "In4.Cu")
		(net "GPU_3V3IO_RSVD5_FFU_ISO")
	)
	(segment
		(start 305.230276 -429.082454)
		(end 304.4698 -428.321978)
		(width 0.11684)
		(layer "In4.Cu")
		(net "GPU_3V3IO_RSVD5_FFU_ISO")
	)
	(segment
		(start 297.947334 -424.090084)
		(end 297.947334 -420.509192)
		(width 0.11684)
		(layer "In4.Cu")
		(net "GPU_3V3IO_RSVD5_FFU_ISO")
	)
	(segment
		(start 297.089322 -380.300992)
		(end 297.089322 -374.429782)
		(width 0.11684)
		(layer "In4.Cu")
		(net "GPU_3V3IO_RSVD5_FFU_ISO")
	)
	(segment
		(start 293.241984 -406.5778)
		(end 295.245028 -404.574756)
		(width 0.11684)
		(layer "In4.Cu")
		(net "GPU_3V3IO_RSVD5_FFU_ISO")
	)
	(segment
		(start 296.327068 -373.667528)
		(end 294.457882 -373.667528)
		(width 0.11684)
		(layer "In4.Cu")
		(net "GPU_3V3IO_RSVD5_FFU_ISO")
	)
	(segment
		(start 310.598312 -432.776884)
		(end 306.903882 -429.082454)
		(width 0.11684)
		(layer "In4.Cu")
		(net "GPU_3V3IO_RSVD5_FFU_ISO")
	)
	(segment
		(start 302.136556 -384.361944)
		(end 301.244762 -383.47015)
		(width 0.11684)
		(layer "In4.Cu")
		(net "GPU_3V3IO_RSVD5_FFU_ISO")
	)
	(segment
		(start 309.813452 -438.876694)
		(end 310.598312 -438.091834)
		(width 0.11684)
		(layer "In4.Cu")
		(net "GPU_3V3IO_RSVD5_FFU_ISO")
	)
	(segment
		(start 298.947078 -392.456924)
		(end 302.136556 -389.267446)
		(width 0.11684)
		(layer "In4.Cu")
		(net "GPU_3V3IO_RSVD5_FFU_ISO")
	)
	(segment
		(start 301.244762 -383.47015)
		(end 300.25848 -383.47015)
		(width 0.11684)
		(layer "In4.Cu")
		(net "GPU_3V3IO_RSVD5_FFU_ISO")
	)
	(segment
		(start 298.947078 -397.27124)
		(end 298.947078 -392.456924)
		(width 0.11684)
		(layer "In4.Cu")
		(net "GPU_3V3IO_RSVD5_FFU_ISO")
	)
	(segment
		(start 302.136556 -389.267446)
		(end 302.136556 -384.361944)
		(width 0.11684)
		(layer "In4.Cu")
		(net "GPU_3V3IO_RSVD5_FFU_ISO")
	)
	(segment
		(start 295.245028 -404.574756)
		(end 295.245028 -400.97329)
		(width 0.11684)
		(layer "In4.Cu")
		(net "GPU_3V3IO_RSVD5_FFU_ISO")
	)
	(segment
		(start 297.947334 -420.509192)
		(end 293.241984 -415.803842)
		(width 0.11684)
		(layer "In4.Cu")
		(net "GPU_3V3IO_RSVD5_FFU_ISO")
	)
	(segment
		(start 302.179228 -428.321978)
		(end 297.947334 -424.090084)
		(width 0.11684)
		(layer "In4.Cu")
		(net "GPU_3V3IO_RSVD5_FFU_ISO")
	)
	(segment
		(start 304.4698 -428.321978)
		(end 302.179228 -428.321978)
		(width 0.11684)
		(layer "In4.Cu")
		(net "GPU_3V3IO_RSVD5_FFU_ISO")
	)
	(segment
		(start 300.25848 -383.47015)
		(end 297.089322 -380.300992)
		(width 0.11684)
		(layer "In4.Cu")
		(net "GPU_3V3IO_RSVD5_FFU_ISO")
	)
	(segment
		(start 297.089322 -374.429782)
		(end 296.327068 -373.667528)
		(width 0.11684)
		(layer "In4.Cu")
		(net "GPU_3V3IO_RSVD5_FFU_ISO")
	)
	(segment
		(start 293.241984 -415.803842)
		(end 293.241984 -406.5778)
		(width 0.11684)
		(layer "In4.Cu")
		(net "GPU_3V3IO_RSVD5_FFU_ISO")
	)
	(segment
		(start 306.903882 -429.082454)
		(end 305.230276 -429.082454)
		(width 0.11684)
		(layer "In4.Cu")
		(net "GPU_3V3IO_RSVD5_FFU_ISO")
	)
	(segment
		(start 456.455018 -136.57072)
		(end 447.046604 -127.162306)
		(width 0.11684)
		(layer "In15.Cu")
		(net "GPU_3V3IO_RSVD5_FFU_ISO")
	)
	(segment
		(start 274.03679 -126.154434)
		(end 272.580608 -124.698252)
		(width 0.11684)
		(layer "In15.Cu")
		(net "GPU_3V3IO_RSVD5_FFU_ISO")
	)
	(segment
		(start 304.056034 -123.281694)
		(end 297.748706 -123.281694)
		(width 0.11684)
		(layer "In15.Cu")
		(net "GPU_3V3IO_RSVD5_FFU_ISO")
	)
	(segment
		(start 456.455018 -152.1079)
		(end 456.455018 -136.57072)
		(width 0.11684)
		(layer "In15.Cu")
		(net "GPU_3V3IO_RSVD5_FFU_ISO")
	)
	(segment
		(start 378.24283 -127.162306)
		(end 374.461532 -123.381008)
		(width 0.11684)
		(layer "In15.Cu")
		(net "GPU_3V3IO_RSVD5_FFU_ISO")
	)
	(segment
		(start 254.4318 -118.242842)
		(end 253.34976 -118.242842)
		(width 0.11684)
		(layer "In15.Cu")
		(net "GPU_3V3IO_RSVD5_FFU_ISO")
	)
	(segment
		(start 407.106628 -364.72368)
		(end 407.959814 -363.870494)
		(width 0.11684)
		(layer "In15.Cu")
		(net "GPU_3V3IO_RSVD5_FFU_ISO")
	)
	(segment
		(start 287.343088 -126.154434)
		(end 274.03679 -126.154434)
		(width 0.11684)
		(layer "In15.Cu")
		(net "GPU_3V3IO_RSVD5_FFU_ISO")
	)
	(segment
		(start 396.49146 -333.643224)
		(end 396.49146 -332.384654)
		(width 0.11684)
		(layer "In15.Cu")
		(net "GPU_3V3IO_RSVD5_FFU_ISO")
	)
	(segment
		(start 216.120218 -119.31142)
		(end 211.961222 -119.31142)
		(width 0.11684)
		(layer "In15.Cu")
		(net "GPU_3V3IO_RSVD5_FFU_ISO")
	)
	(segment
		(start 455.581258 -152.98166)
		(end 456.455018 -152.1079)
		(width 0.11684)
		(layer "In15.Cu")
		(net "GPU_3V3IO_RSVD5_FFU_ISO")
	)
	(segment
		(start 289.488372 -128.299718)
		(end 287.343088 -126.154434)
		(width 0.11684)
		(layer "In15.Cu")
		(net "GPU_3V3IO_RSVD5_FFU_ISO")
	)
	(segment
		(start 462.923128 -171.969684)
		(end 455.581258 -164.627814)
		(width 0.11684)
		(layer "In15.Cu")
		(net "GPU_3V3IO_RSVD5_FFU_ISO")
	)
	(segment
		(start 374.461532 -123.381008)
		(end 352.303334 -123.381008)
		(width 0.11684)
		(layer "In15.Cu")
		(net "GPU_3V3IO_RSVD5_FFU_ISO")
	)
	(segment
		(start 249.387106 -117.72519)
		(end 247.387618 -119.724678)
		(width 0.11684)
		(layer "In15.Cu")
		(net "GPU_3V3IO_RSVD5_FFU_ISO")
	)
	(segment
		(start 304.4952 -123.72086)
		(end 304.056034 -123.281694)
		(width 0.11684)
		(layer "In15.Cu")
		(net "GPU_3V3IO_RSVD5_FFU_ISO")
	)
	(segment
		(start 455.038206 -327.639172)
		(end 462.923128 -319.75425)
		(width 0.11684)
		(layer "In15.Cu")
		(net "GPU_3V3IO_RSVD5_FFU_ISO")
	)
	(segment
		(start 407.959814 -345.111578)
		(end 396.49146 -333.643224)
		(width 0.11684)
		(layer "In15.Cu")
		(net "GPU_3V3IO_RSVD5_FFU_ISO")
	)
	(segment
		(start 396.49146 -332.384654)
		(end 396.763494 -332.11262)
		(width 0.11684)
		(layer "In15.Cu")
		(net "GPU_3V3IO_RSVD5_FFU_ISO")
	)
	(segment
		(start 415.746946 -327.639172)
		(end 455.038206 -327.639172)
		(width 0.11684)
		(layer "In15.Cu")
		(net "GPU_3V3IO_RSVD5_FFU_ISO")
	)
	(segment
		(start 292.730682 -128.299718)
		(end 289.488372 -128.299718)
		(width 0.11684)
		(layer "In15.Cu")
		(net "GPU_3V3IO_RSVD5_FFU_ISO")
	)
	(segment
		(start 407.959814 -363.870494)
		(end 407.959814 -345.111578)
		(width 0.11684)
		(layer "In15.Cu")
		(net "GPU_3V3IO_RSVD5_FFU_ISO")
	)
	(segment
		(start 259.08508 -121.402856)
		(end 258.219194 -120.53697)
		(width 0.11684)
		(layer "In15.Cu")
		(net "GPU_3V3IO_RSVD5_FFU_ISO")
	)
	(segment
		(start 447.046604 -127.162306)
		(end 378.24283 -127.162306)
		(width 0.11684)
		(layer "In15.Cu")
		(net "GPU_3V3IO_RSVD5_FFU_ISO")
	)
	(segment
		(start 352.303334 -123.381008)
		(end 351.597976 -122.67565)
		(width 0.11684)
		(layer "In15.Cu")
		(net "GPU_3V3IO_RSVD5_FFU_ISO")
	)
	(segment
		(start 398.768062 -334.355186)
		(end 409.030932 -334.355186)
		(width 0.11684)
		(layer "In15.Cu")
		(net "GPU_3V3IO_RSVD5_FFU_ISO")
	)
	(segment
		(start 211.961222 -119.31142)
		(end 210.921092 -118.27129)
		(width 0.11684)
		(layer "In15.Cu")
		(net "GPU_3V3IO_RSVD5_FFU_ISO")
	)
	(segment
		(start 462.923128 -319.75425)
		(end 462.923128 -171.969684)
		(width 0.11684)
		(layer "In15.Cu")
		(net "GPU_3V3IO_RSVD5_FFU_ISO")
	)
	(segment
		(start 216.276174 -119.155464)
		(end 216.120218 -119.31142)
		(width 0.11684)
		(layer "In15.Cu")
		(net "GPU_3V3IO_RSVD5_FFU_ISO")
	)
	(segment
		(start 409.030932 -334.355186)
		(end 415.746946 -327.639172)
		(width 0.11684)
		(layer "In15.Cu")
		(net "GPU_3V3IO_RSVD5_FFU_ISO")
	)
	(segment
		(start 347.91269 -123.72086)
		(end 304.4952 -123.72086)
		(width 0.11684)
		(layer "In15.Cu")
		(net "GPU_3V3IO_RSVD5_FFU_ISO")
	)
	(segment
		(start 203.101702 -118.27129)
		(end 202.519788 -117.689376)
		(width 0.11684)
		(layer "In15.Cu")
		(net "GPU_3V3IO_RSVD5_FFU_ISO")
	)
	(segment
		(start 219.295472 -119.724678)
		(end 218.726258 -119.155464)
		(width 0.11684)
		(layer "In15.Cu")
		(net "GPU_3V3IO_RSVD5_FFU_ISO")
	)
	(segment
		(start 270.638524 -123.576334)
		(end 265.093704 -123.576334)
		(width 0.11684)
		(layer "In15.Cu")
		(net "GPU_3V3IO_RSVD5_FFU_ISO")
	)
	(segment
		(start 271.760442 -124.698252)
		(end 270.638524 -123.576334)
		(width 0.11684)
		(layer "In15.Cu")
		(net "GPU_3V3IO_RSVD5_FFU_ISO")
	)
	(segment
		(start 262.920226 -121.402856)
		(end 259.08508 -121.402856)
		(width 0.11684)
		(layer "In15.Cu")
		(net "GPU_3V3IO_RSVD5_FFU_ISO")
	)
	(segment
		(start 297.748706 -123.281694)
		(end 292.730682 -128.299718)
		(width 0.11684)
		(layer "In15.Cu")
		(net "GPU_3V3IO_RSVD5_FFU_ISO")
	)
	(segment
		(start 210.921092 -118.27129)
		(end 203.101702 -118.27129)
		(width 0.11684)
		(layer "In15.Cu")
		(net "GPU_3V3IO_RSVD5_FFU_ISO")
	)
	(segment
		(start 258.219194 -120.53697)
		(end 256.725928 -120.53697)
		(width 0.11684)
		(layer "In15.Cu")
		(net "GPU_3V3IO_RSVD5_FFU_ISO")
	)
	(segment
		(start 256.725928 -120.53697)
		(end 254.4318 -118.242842)
		(width 0.11684)
		(layer "In15.Cu")
		(net "GPU_3V3IO_RSVD5_FFU_ISO")
	)
	(segment
		(start 247.387618 -119.724678)
		(end 219.295472 -119.724678)
		(width 0.11684)
		(layer "In15.Cu")
		(net "GPU_3V3IO_RSVD5_FFU_ISO")
	)
	(segment
		(start 272.580608 -124.698252)
		(end 271.760442 -124.698252)
		(width 0.11684)
		(layer "In15.Cu")
		(net "GPU_3V3IO_RSVD5_FFU_ISO")
	)
	(segment
		(start 253.34976 -118.242842)
		(end 252.832108 -117.72519)
		(width 0.11684)
		(layer "In15.Cu")
		(net "GPU_3V3IO_RSVD5_FFU_ISO")
	)
	(segment
		(start 218.726258 -119.155464)
		(end 216.276174 -119.155464)
		(width 0.11684)
		(layer "In15.Cu")
		(net "GPU_3V3IO_RSVD5_FFU_ISO")
	)
	(segment
		(start 348.9579 -122.67565)
		(end 347.91269 -123.72086)
		(width 0.11684)
		(layer "In15.Cu")
		(net "GPU_3V3IO_RSVD5_FFU_ISO")
	)
	(segment
		(start 455.581258 -164.627814)
		(end 455.581258 -152.98166)
		(width 0.11684)
		(layer "In15.Cu")
		(net "GPU_3V3IO_RSVD5_FFU_ISO")
	)
	(segment
		(start 397.149066 -332.11262)
		(end 397.4211 -332.384654)
		(width 0.11684)
		(layer "In15.Cu")
		(net "GPU_3V3IO_RSVD5_FFU_ISO")
	)
	(segment
		(start 265.093704 -123.576334)
		(end 262.920226 -121.402856)
		(width 0.11684)
		(layer "In15.Cu")
		(net "GPU_3V3IO_RSVD5_FFU_ISO")
	)
	(segment
		(start 351.597976 -122.67565)
		(end 348.9579 -122.67565)
		(width 0.11684)
		(layer "In15.Cu")
		(net "GPU_3V3IO_RSVD5_FFU_ISO")
	)
	(segment
		(start 252.832108 -117.72519)
		(end 249.387106 -117.72519)
		(width 0.11684)
		(layer "In15.Cu")
		(net "GPU_3V3IO_RSVD5_FFU_ISO")
	)
	(segment
		(start 397.4211 -332.384654)
		(end 397.4211 -333.008224)
		(width 0.11684)
		(layer "In15.Cu")
		(net "GPU_3V3IO_RSVD5_FFU_ISO")
	)
	(segment
		(start 396.763494 -332.11262)
		(end 397.149066 -332.11262)
		(width 0.11684)
		(layer "In15.Cu")
		(net "GPU_3V3IO_RSVD5_FFU_ISO")
	)
	(segment
		(start 397.4211 -333.008224)
		(end 398.768062 -334.355186)
		(width 0.11684)
		(layer "In15.Cu")
		(net "GPU_3V3IO_RSVD5_FFU_ISO")
	)
	(segment
		(start 309.813452 -437.606694)
		(end 309.521352 -437.898794)
		(width 0.10668)
		(layer "F.Cu")
		(net "GPU_3V3IO_RSVD5_FFU")
	)
	(segment
		(start 308.420516 -437.898794)
		(end 307.404516 -437.898794)
		(width 0.10668)
		(layer "F.Cu")
		(net "GPU_3V3IO_RSVD5_FFU")
	)
	(segment
		(start 306.750212 -438.076594)
		(end 306.388516 -438.076594)
		(width 0.10668)
		(layer "F.Cu")
		(net "GPU_3V3IO_RSVD5_FFU")
	)
	(segment
		(start 306.13223 -437.820308)
		(end 306.388516 -438.076594)
		(width 0.10668)
		(layer "F.Cu")
		(net "GPU_3V3IO_RSVD5_FFU")
	)
	(segment
		(start 305.255676 -437.820308)
		(end 306.13223 -437.820308)
		(width 0.10668)
		(layer "F.Cu")
		(net "GPU_3V3IO_RSVD5_FFU")
	)
	(segment
		(start 307.404516 -437.898794)
		(end 306.928012 -437.898794)
		(width 0.10668)
		(layer "F.Cu")
		(net "GPU_3V3IO_RSVD5_FFU")
	)
	(segment
		(start 309.521352 -437.898794)
		(end 308.420516 -437.898794)
		(width 0.10668)
		(layer "F.Cu")
		(net "GPU_3V3IO_RSVD5_FFU")
	)
	(segment
		(start 306.928012 -437.898794)
		(end 306.750212 -438.076594)
		(width 0.10668)
		(layer "F.Cu")
		(net "GPU_3V3IO_RSVD5_FFU")
	)
	(via
		(at 309.813452 -437.606694)
		(size 0.508)
		(drill 0.254)
		(layers "F.Cu" "B.Cu")
		(net "GPU_3V3IO_RSVD5_FFU")
	)
	(segment
		(start 321.803776 -424.382438)
		(end 321.54241 -424.121072)
		(width 0.11684)
		(layer "In2.Cu")
		(net "GPU_3V3IO_RSVD5_FFU")
	)
	(segment
		(start 322.405756 -440.489848)
		(end 321.803776 -439.887868)
		(width 0.11684)
		(layer "In2.Cu")
		(net "GPU_3V3IO_RSVD5_FFU")
	)
	(segment
		(start 312.121804 -424.782742)
		(end 312.121804 -435.298342)
		(width 0.11684)
		(layer "In2.Cu")
		(net "GPU_3V3IO_RSVD5_FFU")
	)
	(segment
		(start 321.803776 -439.887868)
		(end 321.803776 -424.382438)
		(width 0.11684)
		(layer "In2.Cu")
		(net "GPU_3V3IO_RSVD5_FFU")
	)
	(segment
		(start 321.54241 -424.121072)
		(end 312.783474 -424.121072)
		(width 0.11684)
		(layer "In2.Cu")
		(net "GPU_3V3IO_RSVD5_FFU")
	)
	(segment
		(start 322.649596 -440.489848)
		(end 322.405756 -440.489848)
		(width 0.11684)
		(layer "In2.Cu")
		(net "GPU_3V3IO_RSVD5_FFU")
	)
	(segment
		(start 312.783474 -424.121072)
		(end 312.121804 -424.782742)
		(width 0.11684)
		(layer "In2.Cu")
		(net "GPU_3V3IO_RSVD5_FFU")
	)
	(segment
		(start 312.121804 -435.298342)
		(end 309.813452 -437.606694)
		(width 0.11684)
		(layer "In2.Cu")
		(net "GPU_3V3IO_RSVD5_FFU")
	)
	(segment
		(start 444.36792 -437.828182)
		(end 444.36792 -439.047382)
		(width 0.10668)
		(layer "F.Cu")
		(net "GPU_3V3IO_RSVD4_N")
	)
	(segment
		(start 443.13348 -438.397396)
		(end 443.13348 -439.047382)
		(width 0.10668)
		(layer "F.Cu")
		(net "GPU_3V3IO_RSVD4_N")
	)
	(segment
		(start 444.36792 -439.047382)
		(end 443.13348 -439.047382)
		(width 0.10668)
		(layer "F.Cu")
		(net "GPU_3V3IO_RSVD4_N")
	)
	(via
		(at 444.36792 -439.047382)
		(size 0.762)
		(drill 0.381)
		(layers "F.Cu" "B.Cu")
		(net "GPU_3V3IO_RSVD4_N")
	)
	(segment
		(start 201.352658 -114.641376)
		(end 202.502008 -114.641376)
		(width 0.10668)
		(layer "F.Cu")
		(net "GPU_3V3IO_RSVD4_ISO")
	)
	(segment
		(start 440.088782 -437.74741)
		(end 439.072782 -437.74741)
		(width 0.10668)
		(layer "F.Cu")
		(net "GPU_3V3IO_RSVD4_ISO")
	)
	(segment
		(start 438.056782 -437.74741)
		(end 439.072782 -437.74741)
		(width 0.10668)
		(layer "F.Cu")
		(net "GPU_3V3IO_RSVD4_ISO")
	)
	(segment
		(start 441.23356 -437.74741)
		(end 440.088782 -437.74741)
		(width 0.10668)
		(layer "F.Cu")
		(net "GPU_3V3IO_RSVD4_ISO")
	)
	(segment
		(start 436.663592 -437.26862)
		(end 437.142382 -437.74741)
		(width 0.10668)
		(layer "F.Cu")
		(net "GPU_3V3IO_RSVD4_ISO")
	)
	(segment
		(start 437.142382 -437.74741)
		(end 438.056782 -437.74741)
		(width 0.10668)
		(layer "F.Cu")
		(net "GPU_3V3IO_RSVD4_ISO")
	)
	(via
		(at 436.663592 -437.26862)
		(size 0.508)
		(drill 0.254)
		(layers "F.Cu" "B.Cu")
		(net "GPU_3V3IO_RSVD4_ISO")
	)
	(via
		(at 243.39677 -118.315994)
		(size 0.508)
		(drill 0.254)
		(layers "F.Cu" "B.Cu")
		(net "GPU_3V3IO_RSVD4_ISO")
	)
	(via
		(at 202.502008 -114.641376)
		(size 0.508)
		(drill 0.254)
		(layers "F.Cu" "B.Cu")
		(net "GPU_3V3IO_RSVD4_ISO")
	)
	(via
		(at 243.853716 -131.313428)
		(size 0.508)
		(drill 0.254)
		(layers "F.Cu" "B.Cu")
		(net "GPU_3V3IO_RSVD4_ISO")
	)
	(segment
		(start 437.957722 -404.656798)
		(end 437.957722 -415.414206)
		(width 0.11684)
		(layer "In6.Cu")
		(net "GPU_3V3IO_RSVD4_ISO")
	)
	(segment
		(start 427.73473 -125.2982)
		(end 453.090534 -150.654004)
		(width 0.11684)
		(layer "In6.Cu")
		(net "GPU_3V3IO_RSVD4_ISO")
	)
	(segment
		(start 437.064658 -391.625074)
		(end 437.064658 -392.651488)
		(width 0.11684)
		(layer "In6.Cu")
		(net "GPU_3V3IO_RSVD4_ISO")
	)
	(segment
		(start 243.853716 -131.313428)
		(end 243.86286 -131.322572)
		(width 0.11684)
		(layer "In6.Cu")
		(net "GPU_3V3IO_RSVD4_ISO")
	)
	(segment
		(start 453.090534 -164.750496)
		(end 465.466176 -177.126138)
		(width 0.11684)
		(layer "In6.Cu")
		(net "GPU_3V3IO_RSVD4_ISO")
	)
	(segment
		(start 320.759836 -122.00128)
		(end 346.377768 -122.00128)
		(width 0.11684)
		(layer "In6.Cu")
		(net "GPU_3V3IO_RSVD4_ISO")
	)
	(segment
		(start 435.398926 -402.098002)
		(end 437.957722 -404.656798)
		(width 0.11684)
		(layer "In6.Cu")
		(net "GPU_3V3IO_RSVD4_ISO")
	)
	(segment
		(start 440.609736 -372.805706)
		(end 440.609736 -388.079996)
		(width 0.11684)
		(layer "In6.Cu")
		(net "GPU_3V3IO_RSVD4_ISO")
	)
	(segment
		(start 454.309734 -359.105708)
		(end 440.609736 -372.805706)
		(width 0.11684)
		(layer "In6.Cu")
		(net "GPU_3V3IO_RSVD4_ISO")
	)
	(segment
		(start 262.33755 -145.581116)
		(end 271.256506 -136.66216)
		(width 0.11684)
		(layer "In6.Cu")
		(net "GPU_3V3IO_RSVD4_ISO")
	)
	(segment
		(start 400.993864 -125.2982)
		(end 427.73473 -125.2982)
		(width 0.11684)
		(layer "In6.Cu")
		(net "GPU_3V3IO_RSVD4_ISO")
	)
	(segment
		(start 454.309734 -343.051384)
		(end 454.309734 -359.105708)
		(width 0.11684)
		(layer "In6.Cu")
		(net "GPU_3V3IO_RSVD4_ISO")
	)
	(segment
		(start 440.609736 -388.079996)
		(end 437.064658 -391.625074)
		(width 0.11684)
		(layer "In6.Cu")
		(net "GPU_3V3IO_RSVD4_ISO")
	)
	(segment
		(start 436.663592 -436.98033)
		(end 436.663592 -437.26862)
		(width 0.11684)
		(layer "In6.Cu")
		(net "GPU_3V3IO_RSVD4_ISO")
	)
	(segment
		(start 432.4858 -400.253708)
		(end 434.330094 -402.098002)
		(width 0.11684)
		(layer "In6.Cu")
		(net "GPU_3V3IO_RSVD4_ISO")
	)
	(segment
		(start 436.62981 -429.447706)
		(end 437.890666 -430.708562)
		(width 0.11684)
		(layer "In6.Cu")
		(net "GPU_3V3IO_RSVD4_ISO")
	)
	(segment
		(start 271.256506 -136.66216)
		(end 289.409886 -136.66216)
		(width 0.11684)
		(layer "In6.Cu")
		(net "GPU_3V3IO_RSVD4_ISO")
	)
	(segment
		(start 301.731426 -124.34062)
		(end 318.420496 -124.34062)
		(width 0.11684)
		(layer "In6.Cu")
		(net "GPU_3V3IO_RSVD4_ISO")
	)
	(segment
		(start 437.249316 -436.394606)
		(end 436.663592 -436.98033)
		(width 0.11684)
		(layer "In6.Cu")
		(net "GPU_3V3IO_RSVD4_ISO")
	)
	(segment
		(start 289.409886 -136.66216)
		(end 301.731426 -124.34062)
		(width 0.11684)
		(layer "In6.Cu")
		(net "GPU_3V3IO_RSVD4_ISO")
	)
	(segment
		(start 257.457448 -145.581116)
		(end 262.33755 -145.581116)
		(width 0.11684)
		(layer "In6.Cu")
		(net "GPU_3V3IO_RSVD4_ISO")
	)
	(segment
		(start 437.957722 -415.414206)
		(end 436.62981 -416.742118)
		(width 0.11684)
		(layer "In6.Cu")
		(net "GPU_3V3IO_RSVD4_ISO")
	)
	(segment
		(start 437.064658 -392.651488)
		(end 432.4858 -397.230346)
		(width 0.11684)
		(layer "In6.Cu")
		(net "GPU_3V3IO_RSVD4_ISO")
	)
	(segment
		(start 243.86286 -131.322572)
		(end 243.86286 -131.986528)
		(width 0.11684)
		(layer "In6.Cu")
		(net "GPU_3V3IO_RSVD4_ISO")
	)
	(segment
		(start 465.466176 -177.126138)
		(end 465.466176 -331.894942)
		(width 0.11684)
		(layer "In6.Cu")
		(net "GPU_3V3IO_RSVD4_ISO")
	)
	(segment
		(start 437.366156 -436.394606)
		(end 437.249316 -436.394606)
		(width 0.11684)
		(layer "In6.Cu")
		(net "GPU_3V3IO_RSVD4_ISO")
	)
	(segment
		(start 465.466176 -331.894942)
		(end 454.309734 -343.051384)
		(width 0.11684)
		(layer "In6.Cu")
		(net "GPU_3V3IO_RSVD4_ISO")
	)
	(segment
		(start 346.377768 -122.00128)
		(end 349.852234 -125.475746)
		(width 0.11684)
		(layer "In6.Cu")
		(net "GPU_3V3IO_RSVD4_ISO")
	)
	(segment
		(start 453.090534 -150.654004)
		(end 453.090534 -164.750496)
		(width 0.11684)
		(layer "In6.Cu")
		(net "GPU_3V3IO_RSVD4_ISO")
	)
	(segment
		(start 243.86286 -131.986528)
		(end 257.457448 -145.581116)
		(width 0.11684)
		(layer "In6.Cu")
		(net "GPU_3V3IO_RSVD4_ISO")
	)
	(segment
		(start 434.330094 -402.098002)
		(end 435.398926 -402.098002)
		(width 0.11684)
		(layer "In6.Cu")
		(net "GPU_3V3IO_RSVD4_ISO")
	)
	(segment
		(start 437.890666 -435.870096)
		(end 437.366156 -436.394606)
		(width 0.11684)
		(layer "In6.Cu")
		(net "GPU_3V3IO_RSVD4_ISO")
	)
	(segment
		(start 349.852234 -125.475746)
		(end 400.816318 -125.475746)
		(width 0.11684)
		(layer "In6.Cu")
		(net "GPU_3V3IO_RSVD4_ISO")
	)
	(segment
		(start 432.4858 -397.230346)
		(end 432.4858 -400.253708)
		(width 0.11684)
		(layer "In6.Cu")
		(net "GPU_3V3IO_RSVD4_ISO")
	)
	(segment
		(start 436.62981 -416.742118)
		(end 436.62981 -429.447706)
		(width 0.11684)
		(layer "In6.Cu")
		(net "GPU_3V3IO_RSVD4_ISO")
	)
	(segment
		(start 318.420496 -124.34062)
		(end 320.759836 -122.00128)
		(width 0.11684)
		(layer "In6.Cu")
		(net "GPU_3V3IO_RSVD4_ISO")
	)
	(segment
		(start 400.816318 -125.475746)
		(end 400.993864 -125.2982)
		(width 0.11684)
		(layer "In6.Cu")
		(net "GPU_3V3IO_RSVD4_ISO")
	)
	(segment
		(start 437.890666 -430.708562)
		(end 437.890666 -435.870096)
		(width 0.11684)
		(layer "In6.Cu")
		(net "GPU_3V3IO_RSVD4_ISO")
	)
	(segment
		(start 243.39677 -118.315994)
		(end 243.39677 -122.496072)
		(width 0.11684)
		(layer "In11.Cu")
		(net "GPU_3V3IO_RSVD4_ISO")
	)
	(segment
		(start 244.337332 -130.829812)
		(end 243.853716 -131.313428)
		(width 0.11684)
		(layer "In11.Cu")
		(net "GPU_3V3IO_RSVD4_ISO")
	)
	(segment
		(start 244.337332 -123.436634)
		(end 244.337332 -130.829812)
		(width 0.11684)
		(layer "In11.Cu")
		(net "GPU_3V3IO_RSVD4_ISO")
	)
	(segment
		(start 243.39677 -122.496072)
		(end 244.337332 -123.436634)
		(width 0.11684)
		(layer "In11.Cu")
		(net "GPU_3V3IO_RSVD4_ISO")
	)
	(segment
		(start 202.502008 -114.641376)
		(end 202.589892 -114.72926)
		(width 0.11684)
		(layer "In15.Cu")
		(net "GPU_3V3IO_RSVD4_ISO")
	)
	(segment
		(start 219.935044 -116.162328)
		(end 220.666564 -116.893848)
		(width 0.11684)
		(layer "In15.Cu")
		(net "GPU_3V3IO_RSVD4_ISO")
	)
	(segment
		(start 211.523072 -116.2558)
		(end 212.402928 -116.2558)
		(width 0.11684)
		(layer "In15.Cu")
		(net "GPU_3V3IO_RSVD4_ISO")
	)
	(segment
		(start 207.657446 -114.945668)
		(end 208.874106 -116.162328)
		(width 0.11684)
		(layer "In15.Cu")
		(net "GPU_3V3IO_RSVD4_ISO")
	)
	(segment
		(start 212.402928 -116.2558)
		(end 212.4964 -116.162328)
		(width 0.11684)
		(layer "In15.Cu")
		(net "GPU_3V3IO_RSVD4_ISO")
	)
	(segment
		(start 220.666564 -116.893848)
		(end 241.974624 -116.893848)
		(width 0.11684)
		(layer "In15.Cu")
		(net "GPU_3V3IO_RSVD4_ISO")
	)
	(segment
		(start 212.4964 -116.162328)
		(end 219.935044 -116.162328)
		(width 0.11684)
		(layer "In15.Cu")
		(net "GPU_3V3IO_RSVD4_ISO")
	)
	(segment
		(start 211.4296 -116.162328)
		(end 211.523072 -116.2558)
		(width 0.11684)
		(layer "In15.Cu")
		(net "GPU_3V3IO_RSVD4_ISO")
	)
	(segment
		(start 241.974624 -116.893848)
		(end 243.39677 -118.315994)
		(width 0.11684)
		(layer "In15.Cu")
		(net "GPU_3V3IO_RSVD4_ISO")
	)
	(segment
		(start 205.931516 -114.72926)
		(end 206.147924 -114.945668)
		(width 0.11684)
		(layer "In15.Cu")
		(net "GPU_3V3IO_RSVD4_ISO")
	)
	(segment
		(start 208.874106 -116.162328)
		(end 211.4296 -116.162328)
		(width 0.11684)
		(layer "In15.Cu")
		(net "GPU_3V3IO_RSVD4_ISO")
	)
	(segment
		(start 202.589892 -114.72926)
		(end 205.931516 -114.72926)
		(width 0.11684)
		(layer "In15.Cu")
		(net "GPU_3V3IO_RSVD4_ISO")
	)
	(segment
		(start 206.147924 -114.945668)
		(end 207.657446 -114.945668)
		(width 0.11684)
		(layer "In15.Cu")
		(net "GPU_3V3IO_RSVD4_ISO")
	)
	(segment
		(start 308.120288 -426.191426)
		(end 308.120288 -424.956986)
		(width 0.10668)
		(layer "F.Cu")
		(net "PRSNT_CABLE_GPU_A2")
	)
	(segment
		(start 306.901088 -424.956986)
		(end 308.120288 -424.956986)
		(width 0.10668)
		(layer "F.Cu")
		(net "PRSNT_CABLE_GPU_A2")
	)
	(segment
		(start 307.470302 -426.191426)
		(end 308.120288 -426.191426)
		(width 0.10668)
		(layer "F.Cu")
		(net "PRSNT_CABLE_GPU_A2")
	)
	(via
		(at 308.120288 -424.956986)
		(size 0.762)
		(drill 0.381)
		(layers "F.Cu" "B.Cu")
		(net "PRSNT_CABLE_GPU_A2")
	)
	(segment
		(start 307.798216 -429.401986)
		(end 307.620416 -429.224186)
		(width 0.10668)
		(layer "F.Cu")
		(net "PRSNT_CABLE_GPU_A2_N")
	)
	(segment
		(start 307.470302 -429.074072)
		(end 307.620416 -429.224186)
		(width 0.10668)
		(layer "F.Cu")
		(net "PRSNT_CABLE_GPU_A2_N")
	)
	(segment
		(start 308.090316 -432.649122)
		(end 307.910484 -432.46929)
		(width 0.10668)
		(layer "F.Cu")
		(net "PRSNT_CABLE_GPU_A2_N")
	)
	(segment
		(start 307.798216 -430.240186)
		(end 307.798216 -429.401986)
		(width 0.10668)
		(layer "F.Cu")
		(net "PRSNT_CABLE_GPU_A2_N")
	)
	(segment
		(start 307.910484 -432.46929)
		(end 307.910484 -431.368454)
		(width 0.10668)
		(layer "F.Cu")
		(net "PRSNT_CABLE_GPU_A2_N")
	)
	(segment
		(start 307.910484 -431.368454)
		(end 307.798216 -431.256186)
		(width 0.10668)
		(layer "F.Cu")
		(net "PRSNT_CABLE_GPU_A2_N")
	)
	(segment
		(start 307.798216 -431.256186)
		(end 307.798216 -430.240186)
		(width 0.10668)
		(layer "F.Cu")
		(net "PRSNT_CABLE_GPU_A2_N")
	)
	(segment
		(start 307.470302 -428.091346)
		(end 307.470302 -429.074072)
		(width 0.10668)
		(layer "F.Cu")
		(net "PRSNT_CABLE_GPU_A2_N")
	)
	(via
		(at 308.090316 -432.649122)
		(size 0.508)
		(drill 0.254)
		(layers "F.Cu" "B.Cu")
		(net "PRSNT_CABLE_GPU_A2_N")
	)
	(segment
		(start 310.345836 -423.993564)
		(end 311.085484 -423.253916)
		(width 0.10668)
		(layer "B.Cu")
		(net "PRSNT_CABLE_GPU_A2_N")
	)
	(segment
		(start 310.345836 -430.911)
		(end 310.345836 -423.993564)
		(width 0.10668)
		(layer "B.Cu")
		(net "PRSNT_CABLE_GPU_A2_N")
	)
	(segment
		(start 308.607714 -432.649122)
		(end 310.345836 -430.911)
		(width 0.10668)
		(layer "B.Cu")
		(net "PRSNT_CABLE_GPU_A2_N")
	)
	(segment
		(start 317.85433 -424.363896)
		(end 317.85433 -440.160918)
		(width 0.10668)
		(layer "B.Cu")
		(net "PRSNT_CABLE_GPU_A2_N")
	)
	(segment
		(start 311.085484 -423.253916)
		(end 316.74435 -423.253916)
		(width 0.10668)
		(layer "B.Cu")
		(net "PRSNT_CABLE_GPU_A2_N")
	)
	(segment
		(start 318.18326 -440.489848)
		(end 318.649604 -440.489848)
		(width 0.10668)
		(layer "B.Cu")
		(net "PRSNT_CABLE_GPU_A2_N")
	)
	(segment
		(start 317.85433 -440.160918)
		(end 318.18326 -440.489848)
		(width 0.10668)
		(layer "B.Cu")
		(net "PRSNT_CABLE_GPU_A2_N")
	)
	(segment
		(start 308.090316 -432.649122)
		(end 308.607714 -432.649122)
		(width 0.10668)
		(layer "B.Cu")
		(net "PRSNT_CABLE_GPU_A2_N")
	)
	(segment
		(start 316.74435 -423.253916)
		(end 317.85433 -424.363896)
		(width 0.10668)
		(layer "B.Cu")
		(net "PRSNT_CABLE_GPU_A2_N")
	)
	(segment
		(start 439.910982 -438.72531)
		(end 440.088782 -438.54751)
		(width 0.10668)
		(layer "F.Cu")
		(net "GPU_3V3IO_RSVD4")
	)
	(segment
		(start 439.072782 -438.72531)
		(end 439.910982 -438.72531)
		(width 0.10668)
		(layer "F.Cu")
		(net "GPU_3V3IO_RSVD4")
	)
	(segment
		(start 438.056782 -438.72531)
		(end 436.681372 -438.72531)
		(width 0.10668)
		(layer "F.Cu")
		(net "GPU_3V3IO_RSVD4")
	)
	(segment
		(start 440.238896 -438.397396)
		(end 440.088782 -438.54751)
		(width 0.10668)
		(layer "F.Cu")
		(net "GPU_3V3IO_RSVD4")
	)
	(segment
		(start 439.072782 -438.72531)
		(end 438.056782 -438.72531)
		(width 0.10668)
		(layer "F.Cu")
		(net "GPU_3V3IO_RSVD4")
	)
	(segment
		(start 441.23356 -438.397396)
		(end 440.238896 -438.397396)
		(width 0.10668)
		(layer "F.Cu")
		(net "GPU_3V3IO_RSVD4")
	)
	(via
		(at 436.681372 -438.72531)
		(size 0.508)
		(drill 0.254)
		(layers "F.Cu" "B.Cu")
		(net "GPU_3V3IO_RSVD4")
	)
	(segment
		(start 413.69869 -423.08272)
		(end 416.446462 -425.830492)
		(width 0.10668)
		(layer "B.Cu")
		(net "GPU_3V3IO_RSVD4")
	)
	(segment
		(start 436.094886 -436.049928)
		(end 436.094886 -438.138824)
		(width 0.10668)
		(layer "B.Cu")
		(net "GPU_3V3IO_RSVD4")
	)
	(segment
		(start 398.750028 -440.489848)
		(end 399.165572 -440.489848)
		(width 0.10668)
		(layer "B.Cu")
		(net "GPU_3V3IO_RSVD4")
	)
	(segment
		(start 416.446462 -425.830492)
		(end 416.446462 -428.888398)
		(width 0.10668)
		(layer "B.Cu")
		(net "GPU_3V3IO_RSVD4")
	)
	(segment
		(start 399.165572 -440.489848)
		(end 399.78584 -439.86958)
		(width 0.10668)
		(layer "B.Cu")
		(net "GPU_3V3IO_RSVD4")
	)
	(segment
		(start 428.360078 -433.480972)
		(end 433.52593 -433.480972)
		(width 0.10668)
		(layer "B.Cu")
		(net "GPU_3V3IO_RSVD4")
	)
	(segment
		(start 399.78584 -439.86958)
		(end 399.78584 -424.480228)
		(width 0.10668)
		(layer "B.Cu")
		(net "GPU_3V3IO_RSVD4")
	)
	(segment
		(start 425.23918 -433.192174)
		(end 428.07128 -433.192174)
		(width 0.10668)
		(layer "B.Cu")
		(net "GPU_3V3IO_RSVD4")
	)
	(segment
		(start 401.183348 -423.08272)
		(end 413.69869 -423.08272)
		(width 0.10668)
		(layer "B.Cu")
		(net "GPU_3V3IO_RSVD4")
	)
	(segment
		(start 428.07128 -433.192174)
		(end 428.360078 -433.480972)
		(width 0.10668)
		(layer "B.Cu")
		(net "GPU_3V3IO_RSVD4")
	)
	(segment
		(start 399.78584 -424.480228)
		(end 401.183348 -423.08272)
		(width 0.10668)
		(layer "B.Cu")
		(net "GPU_3V3IO_RSVD4")
	)
	(segment
		(start 418.677852 -431.119788)
		(end 423.166794 -431.119788)
		(width 0.10668)
		(layer "B.Cu")
		(net "GPU_3V3IO_RSVD4")
	)
	(segment
		(start 423.166794 -431.119788)
		(end 425.23918 -433.192174)
		(width 0.10668)
		(layer "B.Cu")
		(net "GPU_3V3IO_RSVD4")
	)
	(segment
		(start 416.446462 -428.888398)
		(end 418.677852 -431.119788)
		(width 0.10668)
		(layer "B.Cu")
		(net "GPU_3V3IO_RSVD4")
	)
	(segment
		(start 436.094886 -438.138824)
		(end 436.681372 -438.72531)
		(width 0.10668)
		(layer "B.Cu")
		(net "GPU_3V3IO_RSVD4")
	)
	(segment
		(start 433.52593 -433.480972)
		(end 436.094886 -436.049928)
		(width 0.10668)
		(layer "B.Cu")
		(net "GPU_3V3IO_RSVD4")
	)
	(via
		(at 434.38318 -436.616602)
		(size 0.6604)
		(drill 0.3302)
		(layers "F.Cu" "B.Cu")
		(net "GPU_3V3IO_RSVD3_N")
	)
	(segment
		(start 433.162964 -436.493666)
		(end 433.16398 -436.49265)
		(width 0.10668)
		(layer "B.Cu")
		(net "GPU_3V3IO_RSVD3_N")
	)
	(segment
		(start 432.512216 -436.599076)
		(end 432.617626 -436.493666)
		(width 0.10668)
		(layer "B.Cu")
		(net "GPU_3V3IO_RSVD3_N")
	)
	(segment
		(start 434.38318 -436.616602)
		(end 434.39842 -436.631842)
		(width 0.10668)
		(layer "B.Cu")
		(net "GPU_3V3IO_RSVD3_N")
	)
	(segment
		(start 434.39842 -436.631842)
		(end 434.39842 -437.71185)
		(width 0.10668)
		(layer "B.Cu")
		(net "GPU_3V3IO_RSVD3_N")
	)
	(segment
		(start 432.587908 -437.142636)
		(end 432.512216 -437.066944)
		(width 0.10668)
		(layer "B.Cu")
		(net "GPU_3V3IO_RSVD3_N")
	)
	(segment
		(start 434.259228 -436.49265)
		(end 434.38318 -436.616602)
		(width 0.10668)
		(layer "B.Cu")
		(net "GPU_3V3IO_RSVD3_N")
	)
	(segment
		(start 433.16398 -436.49265)
		(end 434.259228 -436.49265)
		(width 0.10668)
		(layer "B.Cu")
		(net "GPU_3V3IO_RSVD3_N")
	)
	(segment
		(start 432.617626 -436.493666)
		(end 433.162964 -436.493666)
		(width 0.10668)
		(layer "B.Cu")
		(net "GPU_3V3IO_RSVD3_N")
	)
	(segment
		(start 432.512216 -437.066944)
		(end 432.512216 -436.599076)
		(width 0.10668)
		(layer "B.Cu")
		(net "GPU_3V3IO_RSVD3_N")
	)
	(segment
		(start 433.16398 -437.142636)
		(end 432.587908 -437.142636)
		(width 0.10668)
		(layer "B.Cu")
		(net "GPU_3V3IO_RSVD3_N")
	)
	(segment
		(start 197.669658 -115.657376)
		(end 198.342758 -115.657376)
		(width 0.10668)
		(layer "F.Cu")
		(net "GPU_3V3IO_RSVD3_ISO")
	)
	(via
		(at 198.342758 -115.657376)
		(size 0.508)
		(drill 0.254)
		(layers "F.Cu" "B.Cu")
		(net "GPU_3V3IO_RSVD3_ISO")
	)
	(via
		(at 218.51112 -124.113544)
		(size 0.508)
		(drill 0.254)
		(layers "F.Cu" "B.Cu")
		(net "GPU_3V3IO_RSVD3_ISO")
	)
	(via
		(at 426.942758 -437.792622)
		(size 0.508)
		(drill 0.254)
		(layers "F.Cu" "B.Cu")
		(net "GPU_3V3IO_RSVD3_ISO")
	)
	(segment
		(start 429.103282 -437.792622)
		(end 430.119282 -437.792622)
		(width 0.10668)
		(layer "B.Cu")
		(net "GPU_3V3IO_RSVD3_ISO")
	)
	(segment
		(start 430.119282 -437.792622)
		(end 431.26406 -437.792622)
		(width 0.10668)
		(layer "B.Cu")
		(net "GPU_3V3IO_RSVD3_ISO")
	)
	(segment
		(start 428.087282 -437.792622)
		(end 429.103282 -437.792622)
		(width 0.10668)
		(layer "B.Cu")
		(net "GPU_3V3IO_RSVD3_ISO")
	)
	(segment
		(start 428.087282 -437.792622)
		(end 426.942758 -437.792622)
		(width 0.10668)
		(layer "B.Cu")
		(net "GPU_3V3IO_RSVD3_ISO")
	)
	(segment
		(start 212.894418 -119.241824)
		(end 213.388194 -119.7356)
		(width 0.11684)
		(layer "In2.Cu")
		(net "GPU_3V3IO_RSVD3_ISO")
	)
	(segment
		(start 213.388194 -119.7356)
		(end 215.474296 -119.7356)
		(width 0.11684)
		(layer "In2.Cu")
		(net "GPU_3V3IO_RSVD3_ISO")
	)
	(segment
		(start 204.180694 -117.210586)
		(end 206.211932 -119.241824)
		(width 0.11684)
		(layer "In2.Cu")
		(net "GPU_3V3IO_RSVD3_ISO")
	)
	(segment
		(start 215.474296 -119.7356)
		(end 218.51112 -122.772424)
		(width 0.11684)
		(layer "In2.Cu")
		(net "GPU_3V3IO_RSVD3_ISO")
	)
	(segment
		(start 198.342758 -115.657376)
		(end 199.129396 -115.657376)
		(width 0.11684)
		(layer "In2.Cu")
		(net "GPU_3V3IO_RSVD3_ISO")
	)
	(segment
		(start 218.51112 -122.772424)
		(end 218.51112 -124.113544)
		(width 0.11684)
		(layer "In2.Cu")
		(net "GPU_3V3IO_RSVD3_ISO")
	)
	(segment
		(start 200.370186 -116.180362)
		(end 201.40041 -117.210586)
		(width 0.11684)
		(layer "In2.Cu")
		(net "GPU_3V3IO_RSVD3_ISO")
	)
	(segment
		(start 199.652382 -116.180362)
		(end 200.370186 -116.180362)
		(width 0.11684)
		(layer "In2.Cu")
		(net "GPU_3V3IO_RSVD3_ISO")
	)
	(segment
		(start 201.40041 -117.210586)
		(end 204.180694 -117.210586)
		(width 0.11684)
		(layer "In2.Cu")
		(net "GPU_3V3IO_RSVD3_ISO")
	)
	(segment
		(start 199.129396 -115.657376)
		(end 199.652382 -116.180362)
		(width 0.11684)
		(layer "In2.Cu")
		(net "GPU_3V3IO_RSVD3_ISO")
	)
	(segment
		(start 206.211932 -119.241824)
		(end 212.894418 -119.241824)
		(width 0.11684)
		(layer "In2.Cu")
		(net "GPU_3V3IO_RSVD3_ISO")
	)
	(segment
		(start 289.952684 -137.972292)
		(end 302.274224 -125.650752)
		(width 0.11684)
		(layer "In6.Cu")
		(net "GPU_3V3IO_RSVD3_ISO")
	)
	(segment
		(start 345.979496 -122.9614)
		(end 350.306894 -127.288798)
		(width 0.11684)
		(layer "In6.Cu")
		(net "GPU_3V3IO_RSVD3_ISO")
	)
	(segment
		(start 451.780402 -150.701756)
		(end 451.780402 -165.293294)
		(width 0.11684)
		(layer "In6.Cu")
		(net "GPU_3V3IO_RSVD3_ISO")
	)
	(segment
		(start 253.471934 -146.541236)
		(end 262.736076 -146.541236)
		(width 0.11684)
		(layer "In6.Cu")
		(net "GPU_3V3IO_RSVD3_ISO")
	)
	(segment
		(start 228.431344 -133.389116)
		(end 240.319814 -133.389116)
		(width 0.11684)
		(layer "In6.Cu")
		(net "GPU_3V3IO_RSVD3_ISO")
	)
	(segment
		(start 464.506056 -178.018948)
		(end 464.506056 -331.002132)
		(width 0.11684)
		(layer "In6.Cu")
		(net "GPU_3V3IO_RSVD3_ISO")
	)
	(segment
		(start 436.250842 -415.548064)
		(end 434.973984 -416.824922)
		(width 0.11684)
		(layer "In6.Cu")
		(net "GPU_3V3IO_RSVD3_ISO")
	)
	(segment
		(start 452.999602 -342.508586)
		(end 452.999602 -358.299512)
		(width 0.11684)
		(layer "In6.Cu")
		(net "GPU_3V3IO_RSVD3_ISO")
	)
	(segment
		(start 350.306894 -127.288798)
		(end 428.367444 -127.288798)
		(width 0.11684)
		(layer "In6.Cu")
		(net "GPU_3V3IO_RSVD3_ISO")
	)
	(segment
		(start 434.973984 -416.824922)
		(end 434.973984 -433.70246)
		(width 0.11684)
		(layer "In6.Cu")
		(net "GPU_3V3IO_RSVD3_ISO")
	)
	(segment
		(start 271.30502 -137.972292)
		(end 289.952684 -137.972292)
		(width 0.11684)
		(layer "In6.Cu")
		(net "GPU_3V3IO_RSVD3_ISO")
	)
	(segment
		(start 434.973984 -433.70246)
		(end 430.883822 -437.792622)
		(width 0.11684)
		(layer "In6.Cu")
		(net "GPU_3V3IO_RSVD3_ISO")
	)
	(segment
		(start 439.649616 -387.615938)
		(end 436.104538 -391.161016)
		(width 0.11684)
		(layer "In6.Cu")
		(net "GPU_3V3IO_RSVD3_ISO")
	)
	(segment
		(start 452.999602 -358.299512)
		(end 439.649616 -371.649498)
		(width 0.11684)
		(layer "In6.Cu")
		(net "GPU_3V3IO_RSVD3_ISO")
	)
	(segment
		(start 218.51112 -124.113544)
		(end 219.155772 -124.113544)
		(width 0.11684)
		(layer "In6.Cu")
		(net "GPU_3V3IO_RSVD3_ISO")
	)
	(segment
		(start 436.104538 -391.161016)
		(end 436.104538 -392.252962)
		(width 0.11684)
		(layer "In6.Cu")
		(net "GPU_3V3IO_RSVD3_ISO")
	)
	(segment
		(start 428.367444 -127.288798)
		(end 451.780402 -150.701756)
		(width 0.11684)
		(layer "In6.Cu")
		(net "GPU_3V3IO_RSVD3_ISO")
	)
	(segment
		(start 431.52568 -396.83182)
		(end 431.52568 -400.768312)
		(width 0.11684)
		(layer "In6.Cu")
		(net "GPU_3V3IO_RSVD3_ISO")
	)
	(segment
		(start 302.274224 -125.650752)
		(end 318.468756 -125.650752)
		(width 0.11684)
		(layer "In6.Cu")
		(net "GPU_3V3IO_RSVD3_ISO")
	)
	(segment
		(start 219.155772 -124.113544)
		(end 228.431344 -133.389116)
		(width 0.11684)
		(layer "In6.Cu")
		(net "GPU_3V3IO_RSVD3_ISO")
	)
	(segment
		(start 439.649616 -371.649498)
		(end 439.649616 -387.615938)
		(width 0.11684)
		(layer "In6.Cu")
		(net "GPU_3V3IO_RSVD3_ISO")
	)
	(segment
		(start 321.158108 -122.9614)
		(end 345.979496 -122.9614)
		(width 0.11684)
		(layer "In6.Cu")
		(net "GPU_3V3IO_RSVD3_ISO")
	)
	(segment
		(start 451.780402 -165.293294)
		(end 464.506056 -178.018948)
		(width 0.11684)
		(layer "In6.Cu")
		(net "GPU_3V3IO_RSVD3_ISO")
	)
	(segment
		(start 240.319814 -133.389116)
		(end 253.471934 -146.541236)
		(width 0.11684)
		(layer "In6.Cu")
		(net "GPU_3V3IO_RSVD3_ISO")
	)
	(segment
		(start 430.883822 -437.792622)
		(end 426.942758 -437.792622)
		(width 0.11684)
		(layer "In6.Cu")
		(net "GPU_3V3IO_RSVD3_ISO")
	)
	(segment
		(start 436.104538 -392.252962)
		(end 431.52568 -396.83182)
		(width 0.11684)
		(layer "In6.Cu")
		(net "GPU_3V3IO_RSVD3_ISO")
	)
	(segment
		(start 436.250842 -405.493474)
		(end 436.250842 -415.548064)
		(width 0.11684)
		(layer "In6.Cu")
		(net "GPU_3V3IO_RSVD3_ISO")
	)
	(segment
		(start 262.736076 -146.541236)
		(end 271.30502 -137.972292)
		(width 0.11684)
		(layer "In6.Cu")
		(net "GPU_3V3IO_RSVD3_ISO")
	)
	(segment
		(start 318.468756 -125.650752)
		(end 321.158108 -122.9614)
		(width 0.11684)
		(layer "In6.Cu")
		(net "GPU_3V3IO_RSVD3_ISO")
	)
	(segment
		(start 464.506056 -331.002132)
		(end 452.999602 -342.508586)
		(width 0.11684)
		(layer "In6.Cu")
		(net "GPU_3V3IO_RSVD3_ISO")
	)
	(segment
		(start 431.52568 -400.768312)
		(end 436.250842 -405.493474)
		(width 0.11684)
		(layer "In6.Cu")
		(net "GPU_3V3IO_RSVD3_ISO")
	)
	(segment
		(start 303.573434 -426.18914)
		(end 304.22342 -426.18914)
		(width 0.10668)
		(layer "F.Cu")
		(net "GPU_3V3IO_RSVD3_FFU_N")
	)
	(segment
		(start 304.22342 -425.983908)
		(end 304.034952 -425.79544)
		(width 0.10668)
		(layer "F.Cu")
		(net "GPU_3V3IO_RSVD3_FFU_N")
	)
	(segment
		(start 304.034952 -424.9547)
		(end 303.00422 -424.9547)
		(width 0.10668)
		(layer "F.Cu")
		(net "GPU_3V3IO_RSVD3_FFU_N")
	)
	(segment
		(start 304.034952 -425.79544)
		(end 304.034952 -424.9547)
		(width 0.10668)
		(layer "F.Cu")
		(net "GPU_3V3IO_RSVD3_FFU_N")
	)
	(segment
		(start 304.22342 -426.18914)
		(end 304.22342 -425.983908)
		(width 0.10668)
		(layer "F.Cu")
		(net "GPU_3V3IO_RSVD3_FFU_N")
	)
	(via
		(at 304.034952 -424.9547)
		(size 0.762)
		(drill 0.381)
		(layers "F.Cu" "B.Cu")
		(net "GPU_3V3IO_RSVD3_FFU_N")
	)
	(segment
		(start 205.643734 -121.960386)
		(end 206.497682 -121.960386)
		(width 0.10668)
		(layer "F.Cu")
		(net "GPU_3V3IO_RSVD3_FFU_ISO")
	)
	(segment
		(start 302.923448 -432.646836)
		(end 302.7172 -432.440588)
		(width 0.10668)
		(layer "F.Cu")
		(net "GPU_3V3IO_RSVD3_FFU_ISO")
	)
	(segment
		(start 302.7172 -431.460148)
		(end 302.923448 -431.2539)
		(width 0.10668)
		(layer "F.Cu")
		(net "GPU_3V3IO_RSVD3_FFU_ISO")
	)
	(segment
		(start 302.923448 -428.08906)
		(end 302.923448 -429.2219)
		(width 0.10668)
		(layer "F.Cu")
		(net "GPU_3V3IO_RSVD3_FFU_ISO")
	)
	(segment
		(start 302.923448 -430.2379)
		(end 302.923448 -429.2219)
		(width 0.10668)
		(layer "F.Cu")
		(net "GPU_3V3IO_RSVD3_FFU_ISO")
	)
	(segment
		(start 302.923448 -431.2539)
		(end 302.923448 -430.2379)
		(width 0.10668)
		(layer "F.Cu")
		(net "GPU_3V3IO_RSVD3_FFU_ISO")
	)
	(segment
		(start 302.7172 -432.440588)
		(end 302.7172 -431.460148)
		(width 0.10668)
		(layer "F.Cu")
		(net "GPU_3V3IO_RSVD3_FFU_ISO")
	)
	(via
		(at 302.923448 -432.646836)
		(size 0.508)
		(drill 0.254)
		(layers "F.Cu" "B.Cu")
		(net "GPU_3V3IO_RSVD3_FFU_ISO")
	)
	(via
		(at 405.889968 -364.028482)
		(size 0.508)
		(drill 0.254)
		(layers "F.Cu" "B.Cu")
		(net "GPU_3V3IO_RSVD3_FFU_ISO")
	)
	(via
		(at 206.497682 -121.960386)
		(size 0.508)
		(drill 0.254)
		(layers "F.Cu" "B.Cu")
		(net "GPU_3V3IO_RSVD3_FFU_ISO")
	)
	(via
		(at 292.282372 -371.549168)
		(size 0.508)
		(drill 0.254)
		(layers "F.Cu" "B.Cu")
		(net "GPU_3V3IO_RSVD3_FFU_ISO")
	)
	(segment
		(start 405.889968 -364.028482)
		(end 400.685 -369.23345)
		(width 0.10668)
		(layer "B.Cu")
		(net "GPU_3V3IO_RSVD3_FFU_ISO")
	)
	(segment
		(start 302.201326 -369.23345)
		(end 300.912276 -367.9444)
		(width 0.10668)
		(layer "B.Cu")
		(net "GPU_3V3IO_RSVD3_FFU_ISO")
	)
	(segment
		(start 294.729154 -368.781838)
		(end 293.555166 -369.955826)
		(width 0.10668)
		(layer "B.Cu")
		(net "GPU_3V3IO_RSVD3_FFU_ISO")
	)
	(segment
		(start 293.555166 -369.955826)
		(end 293.555166 -371.746272)
		(width 0.10668)
		(layer "B.Cu")
		(net "GPU_3V3IO_RSVD3_FFU_ISO")
	)
	(segment
		(start 300.912276 -367.9444)
		(end 297.28287 -367.9444)
		(width 0.10668)
		(layer "B.Cu")
		(net "GPU_3V3IO_RSVD3_FFU_ISO")
	)
	(segment
		(start 296.445432 -368.781838)
		(end 294.729154 -368.781838)
		(width 0.10668)
		(layer "B.Cu")
		(net "GPU_3V3IO_RSVD3_FFU_ISO")
	)
	(segment
		(start 400.685 -369.23345)
		(end 302.201326 -369.23345)
		(width 0.10668)
		(layer "B.Cu")
		(net "GPU_3V3IO_RSVD3_FFU_ISO")
	)
	(segment
		(start 297.28287 -367.9444)
		(end 296.445432 -368.781838)
		(width 0.10668)
		(layer "B.Cu")
		(net "GPU_3V3IO_RSVD3_FFU_ISO")
	)
	(segment
		(start 293.555166 -371.746272)
		(end 293.251382 -372.050056)
		(width 0.10668)
		(layer "B.Cu")
		(net "GPU_3V3IO_RSVD3_FFU_ISO")
	)
	(segment
		(start 292.78326 -372.050056)
		(end 292.282372 -371.549168)
		(width 0.10668)
		(layer "B.Cu")
		(net "GPU_3V3IO_RSVD3_FFU_ISO")
	)
	(segment
		(start 293.251382 -372.050056)
		(end 292.78326 -372.050056)
		(width 0.10668)
		(layer "B.Cu")
		(net "GPU_3V3IO_RSVD3_FFU_ISO")
	)
	(segment
		(start 293.118032 -404.83155)
		(end 292.281864 -405.667718)
		(width 0.11684)
		(layer "In4.Cu")
		(net "GPU_3V3IO_RSVD3_FFU_ISO")
	)
	(segment
		(start 292.281864 -416.816286)
		(end 294.708834 -419.243256)
		(width 0.11684)
		(layer "In4.Cu")
		(net "GPU_3V3IO_RSVD3_FFU_ISO")
	)
	(segment
		(start 295.594786 -394.79347)
		(end 294.175942 -396.212314)
		(width 0.11684)
		(layer "In4.Cu")
		(net "GPU_3V3IO_RSVD3_FFU_ISO")
	)
	(segment
		(start 295.594786 -393.986766)
		(end 295.594786 -394.79347)
		(width 0.11684)
		(layer "In4.Cu")
		(net "GPU_3V3IO_RSVD3_FFU_ISO")
	)
	(segment
		(start 300.43501 -432.646836)
		(end 302.923448 -432.646836)
		(width 0.11684)
		(layer "In4.Cu")
		(net "GPU_3V3IO_RSVD3_FFU_ISO")
	)
	(segment
		(start 294.175942 -396.212314)
		(end 294.175942 -401.325842)
		(width 0.11684)
		(layer "In4.Cu")
		(net "GPU_3V3IO_RSVD3_FFU_ISO")
	)
	(segment
		(start 294.175942 -401.325842)
		(end 293.118032 -402.383752)
		(width 0.11684)
		(layer "In4.Cu")
		(net "GPU_3V3IO_RSVD3_FFU_ISO")
	)
	(segment
		(start 292.282372 -371.549168)
		(end 292.282372 -373.363744)
		(width 0.11684)
		(layer "In4.Cu")
		(net "GPU_3V3IO_RSVD3_FFU_ISO")
	)
	(segment
		(start 292.610794 -373.692166)
		(end 292.610794 -374.874536)
		(width 0.11684)
		(layer "In4.Cu")
		(net "GPU_3V3IO_RSVD3_FFU_ISO")
	)
	(segment
		(start 292.281864 -405.667718)
		(end 292.281864 -416.816286)
		(width 0.11684)
		(layer "In4.Cu")
		(net "GPU_3V3IO_RSVD3_FFU_ISO")
	)
	(segment
		(start 297.593258 -386.544312)
		(end 297.146472 -386.544312)
		(width 0.11684)
		(layer "In4.Cu")
		(net "GPU_3V3IO_RSVD3_FFU_ISO")
	)
	(segment
		(start 298.555664 -385.581906)
		(end 297.593258 -386.544312)
		(width 0.11684)
		(layer "In4.Cu")
		(net "GPU_3V3IO_RSVD3_FFU_ISO")
	)
	(segment
		(start 292.610794 -374.874536)
		(end 295.30421 -377.567952)
		(width 0.11684)
		(layer "In4.Cu")
		(net "GPU_3V3IO_RSVD3_FFU_ISO")
	)
	(segment
		(start 295.74744 -427.959266)
		(end 300.43501 -432.646836)
		(width 0.11684)
		(layer "In4.Cu")
		(net "GPU_3V3IO_RSVD3_FFU_ISO")
	)
	(segment
		(start 295.30421 -377.567952)
		(end 295.30421 -380.659132)
		(width 0.11684)
		(layer "In4.Cu")
		(net "GPU_3V3IO_RSVD3_FFU_ISO")
	)
	(segment
		(start 296.256202 -393.32535)
		(end 295.594786 -393.986766)
		(width 0.11684)
		(layer "In4.Cu")
		(net "GPU_3V3IO_RSVD3_FFU_ISO")
	)
	(segment
		(start 295.30421 -380.659132)
		(end 298.555664 -383.910586)
		(width 0.11684)
		(layer "In4.Cu")
		(net "GPU_3V3IO_RSVD3_FFU_ISO")
	)
	(segment
		(start 295.74744 -423.01287)
		(end 295.74744 -427.959266)
		(width 0.11684)
		(layer "In4.Cu")
		(net "GPU_3V3IO_RSVD3_FFU_ISO")
	)
	(segment
		(start 296.256202 -387.604)
		(end 296.256202 -393.32535)
		(width 0.11684)
		(layer "In4.Cu")
		(net "GPU_3V3IO_RSVD3_FFU_ISO")
	)
	(segment
		(start 294.708834 -419.243256)
		(end 294.708834 -421.974264)
		(width 0.11684)
		(layer "In4.Cu")
		(net "GPU_3V3IO_RSVD3_FFU_ISO")
	)
	(segment
		(start 292.282372 -373.363744)
		(end 292.610794 -373.692166)
		(width 0.11684)
		(layer "In4.Cu")
		(net "GPU_3V3IO_RSVD3_FFU_ISO")
	)
	(segment
		(start 298.555664 -383.910586)
		(end 298.555664 -385.581906)
		(width 0.11684)
		(layer "In4.Cu")
		(net "GPU_3V3IO_RSVD3_FFU_ISO")
	)
	(segment
		(start 294.708834 -421.974264)
		(end 295.74744 -423.01287)
		(width 0.11684)
		(layer "In4.Cu")
		(net "GPU_3V3IO_RSVD3_FFU_ISO")
	)
	(segment
		(start 296.37609 -387.314694)
		(end 296.256202 -387.604)
		(width 0.11684)
		(layer "In4.Cu")
		(net "GPU_3V3IO_RSVD3_FFU_ISO")
	)
	(segment
		(start 293.118032 -402.383752)
		(end 293.118032 -404.83155)
		(width 0.11684)
		(layer "In4.Cu")
		(net "GPU_3V3IO_RSVD3_FFU_ISO")
	)
	(segment
		(start 297.146472 -386.544312)
		(end 296.37609 -387.314694)
		(width 0.11684)
		(layer "In4.Cu")
		(net "GPU_3V3IO_RSVD3_FFU_ISO")
	)
	(segment
		(start 206.497682 -121.960386)
		(end 215.601042 -121.960386)
		(width 0.11684)
		(layer "In15.Cu")
		(net "GPU_3V3IO_RSVD3_FFU_ISO")
	)
	(segment
		(start 399.87728 -333.464408)
		(end 397.885412 -331.47254)
		(width 0.11684)
		(layer "In15.Cu")
		(net "GPU_3V3IO_RSVD3_FFU_ISO")
	)
	(segment
		(start 396.498318 -331.47254)
		(end 395.85138 -332.119478)
		(width 0.11684)
		(layer "In15.Cu")
		(net "GPU_3V3IO_RSVD3_FFU_ISO")
	)
	(segment
		(start 289.00628 -129.463038)
		(end 293.212774 -129.463038)
		(width 0.11684)
		(layer "In15.Cu")
		(net "GPU_3V3IO_RSVD3_FFU_ISO")
	)
	(segment
		(start 247.41505 -124.255784)
		(end 253.67107 -124.255784)
		(width 0.11684)
		(layer "In15.Cu")
		(net "GPU_3V3IO_RSVD3_FFU_ISO")
	)
	(segment
		(start 224.494852 -123.16206)
		(end 226.310698 -124.977906)
		(width 0.11684)
		(layer "In15.Cu")
		(net "GPU_3V3IO_RSVD3_FFU_ISO")
	)
	(segment
		(start 407.64333 -333.464408)
		(end 399.87728 -333.464408)
		(width 0.11684)
		(layer "In15.Cu")
		(net "GPU_3V3IO_RSVD3_FFU_ISO")
	)
	(segment
		(start 371.542056 -124.88418)
		(end 374.573546 -127.91567)
		(width 0.11684)
		(layer "In15.Cu")
		(net "GPU_3V3IO_RSVD3_FFU_ISO")
	)
	(segment
		(start 455.814938 -136.835896)
		(end 455.814938 -151.682196)
		(width 0.11684)
		(layer "In15.Cu")
		(net "GPU_3V3IO_RSVD3_FFU_ISO")
	)
	(segment
		(start 253.67107 -124.255784)
		(end 254.276606 -123.650248)
		(width 0.11684)
		(layer "In15.Cu")
		(net "GPU_3V3IO_RSVD3_FFU_ISO")
	)
	(segment
		(start 265.022838 -124.912628)
		(end 266.056364 -125.946154)
		(width 0.11684)
		(layer "In15.Cu")
		(net "GPU_3V3IO_RSVD3_FFU_ISO")
	)
	(segment
		(start 246.692928 -124.977906)
		(end 247.41505 -124.255784)
		(width 0.11684)
		(layer "In15.Cu")
		(net "GPU_3V3IO_RSVD3_FFU_ISO")
	)
	(segment
		(start 258.844796 -124.912628)
		(end 265.022838 -124.912628)
		(width 0.11684)
		(layer "In15.Cu")
		(net "GPU_3V3IO_RSVD3_FFU_ISO")
	)
	(segment
		(start 397.885412 -331.47254)
		(end 396.498318 -331.47254)
		(width 0.11684)
		(layer "In15.Cu")
		(net "GPU_3V3IO_RSVD3_FFU_ISO")
	)
	(segment
		(start 374.573546 -127.91567)
		(end 446.894712 -127.91567)
		(width 0.11684)
		(layer "In15.Cu")
		(net "GPU_3V3IO_RSVD3_FFU_ISO")
	)
	(segment
		(start 454.941178 -152.555956)
		(end 454.941178 -165.053518)
		(width 0.11684)
		(layer "In15.Cu")
		(net "GPU_3V3IO_RSVD3_FFU_ISO")
	)
	(segment
		(start 455.814938 -151.682196)
		(end 454.941178 -152.555956)
		(width 0.11684)
		(layer "In15.Cu")
		(net "GPU_3V3IO_RSVD3_FFU_ISO")
	)
	(segment
		(start 254.276606 -123.650248)
		(end 257.582416 -123.650248)
		(width 0.11684)
		(layer "In15.Cu")
		(net "GPU_3V3IO_RSVD3_FFU_ISO")
	)
	(segment
		(start 215.601042 -121.960386)
		(end 216.802716 -123.16206)
		(width 0.11684)
		(layer "In15.Cu")
		(net "GPU_3V3IO_RSVD3_FFU_ISO")
	)
	(segment
		(start 257.582416 -123.650248)
		(end 258.844796 -124.912628)
		(width 0.11684)
		(layer "In15.Cu")
		(net "GPU_3V3IO_RSVD3_FFU_ISO")
	)
	(segment
		(start 409.321762 -332.998572)
		(end 408.109166 -332.998572)
		(width 0.11684)
		(layer "In15.Cu")
		(net "GPU_3V3IO_RSVD3_FFU_ISO")
	)
	(segment
		(start 415.434526 -326.885808)
		(end 409.321762 -332.998572)
		(width 0.11684)
		(layer "In15.Cu")
		(net "GPU_3V3IO_RSVD3_FFU_ISO")
	)
	(segment
		(start 446.894712 -127.91567)
		(end 455.814938 -136.835896)
		(width 0.11684)
		(layer "In15.Cu")
		(net "GPU_3V3IO_RSVD3_FFU_ISO")
	)
	(segment
		(start 462.283048 -319.489074)
		(end 454.886314 -326.885808)
		(width 0.11684)
		(layer "In15.Cu")
		(net "GPU_3V3IO_RSVD3_FFU_ISO")
	)
	(segment
		(start 462.283048 -172.395388)
		(end 462.283048 -319.489074)
		(width 0.11684)
		(layer "In15.Cu")
		(net "GPU_3V3IO_RSVD3_FFU_ISO")
	)
	(segment
		(start 266.056364 -125.946154)
		(end 271.858232 -125.946154)
		(width 0.11684)
		(layer "In15.Cu")
		(net "GPU_3V3IO_RSVD3_FFU_ISO")
	)
	(segment
		(start 216.802716 -123.16206)
		(end 224.494852 -123.16206)
		(width 0.11684)
		(layer "In15.Cu")
		(net "GPU_3V3IO_RSVD3_FFU_ISO")
	)
	(segment
		(start 226.310698 -124.977906)
		(end 246.692928 -124.977906)
		(width 0.11684)
		(layer "In15.Cu")
		(net "GPU_3V3IO_RSVD3_FFU_ISO")
	)
	(segment
		(start 297.791632 -124.88418)
		(end 371.542056 -124.88418)
		(width 0.11684)
		(layer "In15.Cu")
		(net "GPU_3V3IO_RSVD3_FFU_ISO")
	)
	(segment
		(start 271.858232 -125.946154)
		(end 273.229832 -127.317754)
		(width 0.11684)
		(layer "In15.Cu")
		(net "GPU_3V3IO_RSVD3_FFU_ISO")
	)
	(segment
		(start 407.319734 -362.598716)
		(end 405.889968 -364.028482)
		(width 0.11684)
		(layer "In15.Cu")
		(net "GPU_3V3IO_RSVD3_FFU_ISO")
	)
	(segment
		(start 407.319734 -345.805252)
		(end 407.319734 -362.598716)
		(width 0.11684)
		(layer "In15.Cu")
		(net "GPU_3V3IO_RSVD3_FFU_ISO")
	)
	(segment
		(start 293.212774 -129.463038)
		(end 297.791632 -124.88418)
		(width 0.11684)
		(layer "In15.Cu")
		(net "GPU_3V3IO_RSVD3_FFU_ISO")
	)
	(segment
		(start 286.860996 -127.317754)
		(end 289.00628 -129.463038)
		(width 0.11684)
		(layer "In15.Cu")
		(net "GPU_3V3IO_RSVD3_FFU_ISO")
	)
	(segment
		(start 273.229832 -127.317754)
		(end 286.860996 -127.317754)
		(width 0.11684)
		(layer "In15.Cu")
		(net "GPU_3V3IO_RSVD3_FFU_ISO")
	)
	(segment
		(start 454.886314 -326.885808)
		(end 415.434526 -326.885808)
		(width 0.11684)
		(layer "In15.Cu")
		(net "GPU_3V3IO_RSVD3_FFU_ISO")
	)
	(segment
		(start 454.941178 -165.053518)
		(end 462.283048 -172.395388)
		(width 0.11684)
		(layer "In15.Cu")
		(net "GPU_3V3IO_RSVD3_FFU_ISO")
	)
	(segment
		(start 395.85138 -332.119478)
		(end 395.85138 -334.336898)
		(width 0.11684)
		(layer "In15.Cu")
		(net "GPU_3V3IO_RSVD3_FFU_ISO")
	)
	(segment
		(start 395.85138 -334.336898)
		(end 407.319734 -345.805252)
		(width 0.11684)
		(layer "In15.Cu")
		(net "GPU_3V3IO_RSVD3_FFU_ISO")
	)
	(segment
		(start 408.109166 -332.998572)
		(end 407.64333 -333.464408)
		(width 0.11684)
		(layer "In15.Cu")
		(net "GPU_3V3IO_RSVD3_FFU_ISO")
	)
	(segment
		(start 303.901348 -429.3997)
		(end 303.723548 -429.2219)
		(width 0.10668)
		(layer "F.Cu")
		(net "GPU_3V3IO_RSVD3_FFU")
	)
	(segment
		(start 304.193448 -432.646836)
		(end 304.138584 -432.591972)
		(width 0.10668)
		(layer "F.Cu")
		(net "GPU_3V3IO_RSVD3_FFU")
	)
	(segment
		(start 304.138584 -432.591972)
		(end 304.138584 -431.491136)
		(width 0.10668)
		(layer "F.Cu")
		(net "GPU_3V3IO_RSVD3_FFU")
	)
	(segment
		(start 303.901348 -430.2379)
		(end 303.901348 -429.3997)
		(width 0.10668)
		(layer "F.Cu")
		(net "GPU_3V3IO_RSVD3_FFU")
	)
	(segment
		(start 304.138584 -431.491136)
		(end 303.901348 -431.2539)
		(width 0.10668)
		(layer "F.Cu")
		(net "GPU_3V3IO_RSVD3_FFU")
	)
	(segment
		(start 303.573434 -428.08906)
		(end 303.573434 -429.071786)
		(width 0.10668)
		(layer "F.Cu")
		(net "GPU_3V3IO_RSVD3_FFU")
	)
	(segment
		(start 303.901348 -431.2539)
		(end 303.901348 -430.2379)
		(width 0.10668)
		(layer "F.Cu")
		(net "GPU_3V3IO_RSVD3_FFU")
	)
	(segment
		(start 303.573434 -429.071786)
		(end 303.723548 -429.2219)
		(width 0.10668)
		(layer "F.Cu")
		(net "GPU_3V3IO_RSVD3_FFU")
	)
	(via
		(at 304.193448 -432.646836)
		(size 0.508)
		(drill 0.254)
		(layers "F.Cu" "B.Cu")
		(net "GPU_3V3IO_RSVD3_FFU")
	)
	(segment
		(start 305.283108 -436.887874)
		(end 305.283108 -433.736496)
		(width 0.10668)
		(layer "B.Cu")
		(net "GPU_3V3IO_RSVD3_FFU")
	)
	(segment
		(start 308.885082 -440.489848)
		(end 305.283108 -436.887874)
		(width 0.10668)
		(layer "B.Cu")
		(net "GPU_3V3IO_RSVD3_FFU")
	)
	(segment
		(start 305.283108 -433.736496)
		(end 304.193448 -432.646836)
		(width 0.10668)
		(layer "B.Cu")
		(net "GPU_3V3IO_RSVD3_FFU")
	)
	(segment
		(start 314.649612 -440.489848)
		(end 308.885082 -440.489848)
		(width 0.10668)
		(layer "B.Cu")
		(net "GPU_3V3IO_RSVD3_FFU")
	)
	(via
		(at 424.285918 -436.466742)
		(size 0.6604)
		(drill 0.3302)
		(layers "F.Cu" "B.Cu")
		(net "GPU_3V3IO_RSVD3")
	)
	(segment
		(start 415.343594 -425.752006)
		(end 413.344868 -423.75328)
		(width 0.10668)
		(layer "B.Cu")
		(net "GPU_3V3IO_RSVD3")
	)
	(segment
		(start 430.269396 -437.142636)
		(end 430.119282 -436.992522)
		(width 0.10668)
		(layer "B.Cu")
		(net "GPU_3V3IO_RSVD3")
	)
	(segment
		(start 424.36542 -436.546244)
		(end 424.285918 -436.466742)
		(width 0.10668)
		(layer "B.Cu")
		(net "GPU_3V3IO_RSVD3")
	)
	(segment
		(start 420.564056 -435.02199)
		(end 415.343594 -429.801528)
		(width 0.10668)
		(layer "B.Cu")
		(net "GPU_3V3IO_RSVD3")
	)
	(segment
		(start 408.8892 -423.75328)
		(end 407.930096 -424.712384)
		(width 0.10668)
		(layer "B.Cu")
		(net "GPU_3V3IO_RSVD3")
	)
	(segment
		(start 431.26406 -437.142636)
		(end 430.269396 -437.142636)
		(width 0.10668)
		(layer "B.Cu")
		(net "GPU_3V3IO_RSVD3")
	)
	(segment
		(start 426.328586 -436.546244)
		(end 424.36542 -436.546244)
		(width 0.10668)
		(layer "B.Cu")
		(net "GPU_3V3IO_RSVD3")
	)
	(segment
		(start 429.281082 -436.992522)
		(end 429.103282 -436.814722)
		(width 0.10668)
		(layer "B.Cu")
		(net "GPU_3V3IO_RSVD3")
	)
	(segment
		(start 428.087282 -436.814722)
		(end 427.898052 -437.003952)
		(width 0.10668)
		(layer "B.Cu")
		(net "GPU_3V3IO_RSVD3")
	)
	(segment
		(start 424.285918 -436.466742)
		(end 422.841166 -435.02199)
		(width 0.10668)
		(layer "B.Cu")
		(net "GPU_3V3IO_RSVD3")
	)
	(segment
		(start 427.898052 -437.003952)
		(end 426.786294 -437.003952)
		(width 0.10668)
		(layer "B.Cu")
		(net "GPU_3V3IO_RSVD3")
	)
	(segment
		(start 426.786294 -437.003952)
		(end 426.328586 -436.546244)
		(width 0.10668)
		(layer "B.Cu")
		(net "GPU_3V3IO_RSVD3")
	)
	(segment
		(start 415.343594 -429.801528)
		(end 415.343594 -425.752006)
		(width 0.10668)
		(layer "B.Cu")
		(net "GPU_3V3IO_RSVD3")
	)
	(segment
		(start 407.109676 -440.489848)
		(end 406.750012 -440.489848)
		(width 0.10668)
		(layer "B.Cu")
		(net "GPU_3V3IO_RSVD3")
	)
	(segment
		(start 429.103282 -436.814722)
		(end 428.087282 -436.814722)
		(width 0.10668)
		(layer "B.Cu")
		(net "GPU_3V3IO_RSVD3")
	)
	(segment
		(start 422.841166 -435.02199)
		(end 420.564056 -435.02199)
		(width 0.10668)
		(layer "B.Cu")
		(net "GPU_3V3IO_RSVD3")
	)
	(segment
		(start 430.119282 -436.992522)
		(end 429.281082 -436.992522)
		(width 0.10668)
		(layer "B.Cu")
		(net "GPU_3V3IO_RSVD3")
	)
	(segment
		(start 407.930096 -439.669428)
		(end 407.109676 -440.489848)
		(width 0.10668)
		(layer "B.Cu")
		(net "GPU_3V3IO_RSVD3")
	)
	(segment
		(start 407.930096 -424.712384)
		(end 407.930096 -439.669428)
		(width 0.10668)
		(layer "B.Cu")
		(net "GPU_3V3IO_RSVD3")
	)
	(segment
		(start 413.344868 -423.75328)
		(end 408.8892 -423.75328)
		(width 0.10668)
		(layer "B.Cu")
		(net "GPU_3V3IO_RSVD3")
	)
	(via
		(at 169.625518 -434.451506)
		(size 0.6604)
		(drill 0.3302)
		(layers "F.Cu" "B.Cu")
		(net "PRSNT_CABLE_GPU_B3")
	)
	(segment
		(start 169.297858 -435.451758)
		(end 169.686732 -435.451758)
		(width 0.10668)
		(layer "B.Cu")
		(net "PRSNT_CABLE_GPU_B3")
	)
	(segment
		(start 169.625518 -434.451506)
		(end 169.625518 -435.390544)
		(width 0.10668)
		(layer "B.Cu")
		(net "PRSNT_CABLE_GPU_B3")
	)
	(segment
		(start 168.452292 -434.232558)
		(end 169.40657 -434.232558)
		(width 0.10668)
		(layer "B.Cu")
		(net "PRSNT_CABLE_GPU_B3")
	)
	(segment
		(start 168.452292 -434.882544)
		(end 168.728644 -434.882544)
		(width 0.10668)
		(layer "B.Cu")
		(net "PRSNT_CABLE_GPU_B3")
	)
	(segment
		(start 169.625518 -435.390544)
		(end 169.686732 -435.451758)
		(width 0.10668)
		(layer "B.Cu")
		(net "PRSNT_CABLE_GPU_B3")
	)
	(segment
		(start 168.728644 -434.882544)
		(end 169.297858 -435.451758)
		(width 0.10668)
		(layer "B.Cu")
		(net "PRSNT_CABLE_GPU_B3")
	)
	(segment
		(start 169.40657 -434.232558)
		(end 169.625518 -434.451506)
		(width 0.10668)
		(layer "B.Cu")
		(net "PRSNT_CABLE_GPU_B3")
	)
	(via
		(at 161.409888 -434.799232)
		(size 0.508)
		(drill 0.254)
		(layers "F.Cu" "B.Cu")
		(net "PRSNT_CABLE_GPU_B3_N")
	)
	(segment
		(start 164.403532 -434.55463)
		(end 163.387532 -434.55463)
		(width 0.10668)
		(layer "B.Cu")
		(net "PRSNT_CABLE_GPU_B3_N")
	)
	(segment
		(start 162.726624 -434.55463)
		(end 163.387532 -434.55463)
		(width 0.10668)
		(layer "B.Cu")
		(net "PRSNT_CABLE_GPU_B3_N")
	)
	(segment
		(start 162.482022 -434.799232)
		(end 162.726624 -434.55463)
		(width 0.10668)
		(layer "B.Cu")
		(net "PRSNT_CABLE_GPU_B3_N")
	)
	(segment
		(start 166.552372 -434.882544)
		(end 165.569646 -434.882544)
		(width 0.10668)
		(layer "B.Cu")
		(net "PRSNT_CABLE_GPU_B3_N")
	)
	(segment
		(start 164.653468 -434.73243)
		(end 164.475668 -434.55463)
		(width 0.10668)
		(layer "B.Cu")
		(net "PRSNT_CABLE_GPU_B3_N")
	)
	(segment
		(start 165.419532 -434.73243)
		(end 164.653468 -434.73243)
		(width 0.10668)
		(layer "B.Cu")
		(net "PRSNT_CABLE_GPU_B3_N")
	)
	(segment
		(start 165.569646 -434.882544)
		(end 165.419532 -434.73243)
		(width 0.10668)
		(layer "B.Cu")
		(net "PRSNT_CABLE_GPU_B3_N")
	)
	(segment
		(start 161.409888 -434.799232)
		(end 162.482022 -434.799232)
		(width 0.10668)
		(layer "B.Cu")
		(net "PRSNT_CABLE_GPU_B3_N")
	)
	(segment
		(start 164.475668 -434.55463)
		(end 164.403532 -434.55463)
		(width 0.10668)
		(layer "B.Cu")
		(net "PRSNT_CABLE_GPU_B3_N")
	)
	(segment
		(start 160.402524 -428.342298)
		(end 160.402524 -433.791868)
		(width 0.11684)
		(layer "In4.Cu")
		(net "PRSNT_CABLE_GPU_B3_N")
	)
	(segment
		(start 156.750004 -424.689778)
		(end 160.402524 -428.342298)
		(width 0.11684)
		(layer "In4.Cu")
		(net "PRSNT_CABLE_GPU_B3_N")
	)
	(segment
		(start 160.402524 -433.791868)
		(end 161.409888 -434.799232)
		(width 0.11684)
		(layer "In4.Cu")
		(net "PRSNT_CABLE_GPU_B3_N")
	)
	(segment
		(start 424.307 -436.086758)
		(end 425.54144 -436.086758)
		(width 0.10668)
		(layer "F.Cu")
		(net "GPU_3V3IO_RSVD1_N")
	)
	(segment
		(start 424.307 -435.436772)
		(end 424.307 -436.086758)
		(width 0.10668)
		(layer "F.Cu")
		(net "GPU_3V3IO_RSVD1_N")
	)
	(segment
		(start 425.54144 -434.867558)
		(end 425.54144 -436.086758)
		(width 0.10668)
		(layer "F.Cu")
		(net "GPU_3V3IO_RSVD1_N")
	)
	(via
		(at 425.54144 -436.086758)
		(size 0.762)
		(drill 0.381)
		(layers "F.Cu" "B.Cu")
		(net "GPU_3V3IO_RSVD1_N")
	)
	(segment
		(start 421.262302 -434.786786)
		(end 420.246302 -434.786786)
		(width 0.10668)
		(layer "F.Cu")
		(net "GPU_3V3IO_RSVD1_ISO")
	)
	(segment
		(start 420.246302 -434.786786)
		(end 419.230302 -434.786786)
		(width 0.10668)
		(layer "F.Cu")
		(net "GPU_3V3IO_RSVD1_ISO")
	)
	(segment
		(start 417.837366 -434.494686)
		(end 418.129466 -434.786786)
		(width 0.10668)
		(layer "F.Cu")
		(net "GPU_3V3IO_RSVD1_ISO")
	)
	(segment
		(start 422.40708 -434.786786)
		(end 421.262302 -434.786786)
		(width 0.10668)
		(layer "F.Cu")
		(net "GPU_3V3IO_RSVD1_ISO")
	)
	(segment
		(start 418.129466 -434.786786)
		(end 419.230302 -434.786786)
		(width 0.10668)
		(layer "F.Cu")
		(net "GPU_3V3IO_RSVD1_ISO")
	)
	(via
		(at 417.837366 -434.494686)
		(size 0.508)
		(drill 0.254)
		(layers "F.Cu" "B.Cu")
		(net "GPU_3V3IO_RSVD1_ISO")
	)
	(via
		(at 198.342758 -117.689376)
		(size 0.508)
		(drill 0.254)
		(layers "F.Cu" "B.Cu")
		(net "GPU_3V3IO_RSVD1_ISO")
	)
	(via
		(at 218.569032 -126.434088)
		(size 0.508)
		(drill 0.254)
		(layers "F.Cu" "B.Cu")
		(net "GPU_3V3IO_RSVD1_ISO")
	)
	(segment
		(start 197.669658 -117.689376)
		(end 198.342758 -117.689376)
		(width 0.10668)
		(layer "B.Cu")
		(net "GPU_3V3IO_RSVD1_ISO")
	)
	(segment
		(start 215.559132 -120.27408)
		(end 217.630248 -122.345196)
		(width 0.11684)
		(layer "In2.Cu")
		(net "GPU_3V3IO_RSVD1_ISO")
	)
	(segment
		(start 198.342758 -117.689376)
		(end 201.33691 -117.689376)
		(width 0.11684)
		(layer "In2.Cu")
		(net "GPU_3V3IO_RSVD1_ISO")
	)
	(segment
		(start 202.099164 -118.45163)
		(end 204.40269 -118.45163)
		(width 0.11684)
		(layer "In2.Cu")
		(net "GPU_3V3IO_RSVD1_ISO")
	)
	(segment
		(start 217.630248 -125.495304)
		(end 218.569032 -126.434088)
		(width 0.11684)
		(layer "In2.Cu")
		(net "GPU_3V3IO_RSVD1_ISO")
	)
	(segment
		(start 206.22514 -120.27408)
		(end 215.559132 -120.27408)
		(width 0.11684)
		(layer "In2.Cu")
		(net "GPU_3V3IO_RSVD1_ISO")
	)
	(segment
		(start 204.40269 -118.45163)
		(end 206.22514 -120.27408)
		(width 0.11684)
		(layer "In2.Cu")
		(net "GPU_3V3IO_RSVD1_ISO")
	)
	(segment
		(start 217.630248 -122.345196)
		(end 217.630248 -125.495304)
		(width 0.11684)
		(layer "In2.Cu")
		(net "GPU_3V3IO_RSVD1_ISO")
	)
	(segment
		(start 201.33691 -117.689376)
		(end 202.099164 -118.45163)
		(width 0.11684)
		(layer "In2.Cu")
		(net "GPU_3V3IO_RSVD1_ISO")
	)
	(segment
		(start 290.548822 -139.409678)
		(end 302.870108 -127.088392)
		(width 0.11684)
		(layer "In6.Cu")
		(net "GPU_3V3IO_RSVD1_ISO")
	)
	(segment
		(start 434.845206 -391.503408)
		(end 429.739298 -396.609316)
		(width 0.11684)
		(layer "In6.Cu")
		(net "GPU_3V3IO_RSVD1_ISO")
	)
	(segment
		(start 433.810664 -405.866092)
		(end 433.810664 -431.288444)
		(width 0.11684)
		(layer "In6.Cu")
		(net "GPU_3V3IO_RSVD1_ISO")
	)
	(segment
		(start 302.870108 -127.088392)
		(end 318.677036 -127.088392)
		(width 0.11684)
		(layer "In6.Cu")
		(net "GPU_3V3IO_RSVD1_ISO")
	)
	(segment
		(start 451.561962 -357.782622)
		(end 438.486296 -370.858288)
		(width 0.11684)
		(layer "In6.Cu")
		(net "GPU_3V3IO_RSVD1_ISO")
	)
	(segment
		(start 438.486296 -370.858288)
		(end 438.486296 -387.133592)
		(width 0.11684)
		(layer "In6.Cu")
		(net "GPU_3V3IO_RSVD1_ISO")
	)
	(segment
		(start 429.739298 -396.609316)
		(end 429.440086 -396.609316)
		(width 0.11684)
		(layer "In6.Cu")
		(net "GPU_3V3IO_RSVD1_ISO")
	)
	(segment
		(start 227.031296 -134.896352)
		(end 239.793526 -134.896352)
		(width 0.11684)
		(layer "In6.Cu")
		(net "GPU_3V3IO_RSVD1_ISO")
	)
	(segment
		(start 429.106584 -397.699992)
		(end 429.959008 -398.552416)
		(width 0.11684)
		(layer "In6.Cu")
		(net "GPU_3V3IO_RSVD1_ISO")
	)
	(segment
		(start 434.845206 -390.774682)
		(end 434.845206 -391.503408)
		(width 0.11684)
		(layer "In6.Cu")
		(net "GPU_3V3IO_RSVD1_ISO")
	)
	(segment
		(start 463.342736 -330.131928)
		(end 451.561962 -341.912702)
		(width 0.11684)
		(layer "In6.Cu")
		(net "GPU_3V3IO_RSVD1_ISO")
	)
	(segment
		(start 424.557952 -432.917854)
		(end 422.9735 -434.502306)
		(width 0.11684)
		(layer "In6.Cu")
		(net "GPU_3V3IO_RSVD1_ISO")
	)
	(segment
		(start 438.486296 -387.133592)
		(end 434.845206 -390.774682)
		(width 0.11684)
		(layer "In6.Cu")
		(net "GPU_3V3IO_RSVD1_ISO")
	)
	(segment
		(start 450.342762 -150.909528)
		(end 450.342762 -165.889178)
		(width 0.11684)
		(layer "In6.Cu")
		(net "GPU_3V3IO_RSVD1_ISO")
	)
	(segment
		(start 218.569032 -126.434088)
		(end 227.031296 -134.896352)
		(width 0.11684)
		(layer "In6.Cu")
		(net "GPU_3V3IO_RSVD1_ISO")
	)
	(segment
		(start 429.959008 -402.014436)
		(end 433.810664 -405.866092)
		(width 0.11684)
		(layer "In6.Cu")
		(net "GPU_3V3IO_RSVD1_ISO")
	)
	(segment
		(start 252.60173 -147.704556)
		(end 263.218676 -147.704556)
		(width 0.11684)
		(layer "In6.Cu")
		(net "GPU_3V3IO_RSVD1_ISO")
	)
	(segment
		(start 463.342736 -178.889152)
		(end 463.342736 -330.131928)
		(width 0.11684)
		(layer "In6.Cu")
		(net "GPU_3V3IO_RSVD1_ISO")
	)
	(segment
		(start 417.844986 -434.502306)
		(end 417.837366 -434.494686)
		(width 0.11684)
		(layer "In6.Cu")
		(net "GPU_3V3IO_RSVD1_ISO")
	)
	(segment
		(start 345.496896 -124.12472)
		(end 349.824294 -128.452118)
		(width 0.11684)
		(layer "In6.Cu")
		(net "GPU_3V3IO_RSVD1_ISO")
	)
	(segment
		(start 321.640708 -124.12472)
		(end 345.496896 -124.12472)
		(width 0.11684)
		(layer "In6.Cu")
		(net "GPU_3V3IO_RSVD1_ISO")
	)
	(segment
		(start 422.9735 -434.502306)
		(end 417.844986 -434.502306)
		(width 0.11684)
		(layer "In6.Cu")
		(net "GPU_3V3IO_RSVD1_ISO")
	)
	(segment
		(start 239.793526 -134.896352)
		(end 252.60173 -147.704556)
		(width 0.11684)
		(layer "In6.Cu")
		(net "GPU_3V3IO_RSVD1_ISO")
	)
	(segment
		(start 318.677036 -127.088392)
		(end 321.640708 -124.12472)
		(width 0.11684)
		(layer "In6.Cu")
		(net "GPU_3V3IO_RSVD1_ISO")
	)
	(segment
		(start 451.561962 -341.912702)
		(end 451.561962 -357.782622)
		(width 0.11684)
		(layer "In6.Cu")
		(net "GPU_3V3IO_RSVD1_ISO")
	)
	(segment
		(start 427.885352 -128.452118)
		(end 450.342762 -150.909528)
		(width 0.11684)
		(layer "In6.Cu")
		(net "GPU_3V3IO_RSVD1_ISO")
	)
	(segment
		(start 432.181254 -432.917854)
		(end 424.557952 -432.917854)
		(width 0.11684)
		(layer "In6.Cu")
		(net "GPU_3V3IO_RSVD1_ISO")
	)
	(segment
		(start 271.513554 -139.409678)
		(end 290.548822 -139.409678)
		(width 0.11684)
		(layer "In6.Cu")
		(net "GPU_3V3IO_RSVD1_ISO")
	)
	(segment
		(start 429.106584 -396.942818)
		(end 429.106584 -397.699992)
		(width 0.11684)
		(layer "In6.Cu")
		(net "GPU_3V3IO_RSVD1_ISO")
	)
	(segment
		(start 429.959008 -398.552416)
		(end 429.959008 -402.014436)
		(width 0.11684)
		(layer "In6.Cu")
		(net "GPU_3V3IO_RSVD1_ISO")
	)
	(segment
		(start 433.810664 -431.288444)
		(end 432.181254 -432.917854)
		(width 0.11684)
		(layer "In6.Cu")
		(net "GPU_3V3IO_RSVD1_ISO")
	)
	(segment
		(start 429.440086 -396.609316)
		(end 429.106584 -396.942818)
		(width 0.11684)
		(layer "In6.Cu")
		(net "GPU_3V3IO_RSVD1_ISO")
	)
	(segment
		(start 349.824294 -128.452118)
		(end 427.885352 -128.452118)
		(width 0.11684)
		(layer "In6.Cu")
		(net "GPU_3V3IO_RSVD1_ISO")
	)
	(segment
		(start 450.342762 -165.889178)
		(end 463.342736 -178.889152)
		(width 0.11684)
		(layer "In6.Cu")
		(net "GPU_3V3IO_RSVD1_ISO")
	)
	(segment
		(start 263.218676 -147.704556)
		(end 271.513554 -139.409678)
		(width 0.11684)
		(layer "In6.Cu")
		(net "GPU_3V3IO_RSVD1_ISO")
	)
	(via
		(at 169.634408 -430.676558)
		(size 0.6604)
		(drill 0.3302)
		(layers "F.Cu" "B.Cu")
		(net "GPU_3V3IO_RSVD1_FFU_N")
	)
	(segment
		(start 168.452292 -431.326544)
		(end 168.85031 -431.326544)
		(width 0.10668)
		(layer "B.Cu")
		(net "GPU_3V3IO_RSVD1_FFU_N")
	)
	(segment
		(start 169.72915 -430.7713)
		(end 169.634408 -430.676558)
		(width 0.10668)
		(layer "B.Cu")
		(net "GPU_3V3IO_RSVD1_FFU_N")
	)
	(segment
		(start 168.452292 -430.676558)
		(end 169.634408 -430.676558)
		(width 0.10668)
		(layer "B.Cu")
		(net "GPU_3V3IO_RSVD1_FFU_N")
	)
	(segment
		(start 169.72915 -431.841656)
		(end 169.72915 -430.7713)
		(width 0.10668)
		(layer "B.Cu")
		(net "GPU_3V3IO_RSVD1_FFU_N")
	)
	(segment
		(start 168.85031 -431.326544)
		(end 169.365422 -431.841656)
		(width 0.10668)
		(layer "B.Cu")
		(net "GPU_3V3IO_RSVD1_FFU_N")
	)
	(segment
		(start 169.365422 -431.841656)
		(end 169.72915 -431.841656)
		(width 0.10668)
		(layer "B.Cu")
		(net "GPU_3V3IO_RSVD1_FFU_N")
	)
	(segment
		(start 209.379312 -184.088532)
		(end 211.462112 -189.116716)
		(width 0.10668)
		(layer "F.Cu")
		(net "GPU_3V3IO_RSVD1_FFU_ISO")
	)
	(segment
		(start 211.462112 -195.280534)
		(end 209.254852 -197.487794)
		(width 0.10668)
		(layer "F.Cu")
		(net "GPU_3V3IO_RSVD1_FFU_ISO")
	)
	(segment
		(start 209.254852 -197.487794)
		(end 208.989676 -197.487794)
		(width 0.10668)
		(layer "F.Cu")
		(net "GPU_3V3IO_RSVD1_FFU_ISO")
	)
	(segment
		(start 195.974462 -172.202602)
		(end 197.493382 -172.202602)
		(width 0.10668)
		(layer "F.Cu")
		(net "GPU_3V3IO_RSVD1_FFU_ISO")
	)
	(segment
		(start 197.493382 -172.202602)
		(end 209.379312 -184.088532)
		(width 0.10668)
		(layer "F.Cu")
		(net "GPU_3V3IO_RSVD1_FFU_ISO")
	)
	(segment
		(start 205.643734 -120.944386)
		(end 206.497682 -120.944386)
		(width 0.10668)
		(layer "F.Cu")
		(net "GPU_3V3IO_RSVD1_FFU_ISO")
	)
	(segment
		(start 211.462112 -189.116716)
		(end 211.462112 -195.280534)
		(width 0.10668)
		(layer "F.Cu")
		(net "GPU_3V3IO_RSVD1_FFU_ISO")
	)
	(via
		(at 195.974462 -172.202602)
		(size 0.508)
		(drill 0.254)
		(layers "F.Cu" "B.Cu")
		(net "GPU_3V3IO_RSVD1_FFU_ISO")
	)
	(via
		(at 208.989676 -197.487794)
		(size 0.508)
		(drill 0.254)
		(layers "F.Cu" "B.Cu")
		(net "GPU_3V3IO_RSVD1_FFU_ISO")
	)
	(via
		(at 162.405314 -431.97653)
		(size 0.508)
		(drill 0.254)
		(layers "F.Cu" "B.Cu")
		(net "GPU_3V3IO_RSVD1_FFU_ISO")
	)
	(via
		(at 206.497682 -120.944386)
		(size 0.508)
		(drill 0.254)
		(layers "F.Cu" "B.Cu")
		(net "GPU_3V3IO_RSVD1_FFU_ISO")
	)
	(segment
		(start 166.552372 -431.97653)
		(end 165.419532 -431.97653)
		(width 0.10668)
		(layer "B.Cu")
		(net "GPU_3V3IO_RSVD1_FFU_ISO")
	)
	(segment
		(start 163.387532 -431.97653)
		(end 164.403532 -431.97653)
		(width 0.10668)
		(layer "B.Cu")
		(net "GPU_3V3IO_RSVD1_FFU_ISO")
	)
	(segment
		(start 163.387532 -431.97653)
		(end 162.405314 -431.97653)
		(width 0.10668)
		(layer "B.Cu")
		(net "GPU_3V3IO_RSVD1_FFU_ISO")
	)
	(segment
		(start 164.403532 -431.97653)
		(end 165.419532 -431.97653)
		(width 0.10668)
		(layer "B.Cu")
		(net "GPU_3V3IO_RSVD1_FFU_ISO")
	)
	(segment
		(start 170.269408 -419.783514)
		(end 169.506392 -419.020498)
		(width 0.11684)
		(layer "In6.Cu")
		(net "GPU_3V3IO_RSVD1_FFU_ISO")
	)
	(segment
		(start 222.99676 -368.006376)
		(end 222.99676 -367.74628)
		(width 0.11684)
		(layer "In6.Cu")
		(net "GPU_3V3IO_RSVD1_FFU_ISO")
	)
	(segment
		(start 169.928286 -411.506416)
		(end 170.71594 -410.718762)
		(width 0.11684)
		(layer "In6.Cu")
		(net "GPU_3V3IO_RSVD1_FFU_ISO")
	)
	(segment
		(start 169.199814 -422.801542)
		(end 170.848782 -421.152574)
		(width 0.11684)
		(layer "In6.Cu")
		(net "GPU_3V3IO_RSVD1_FFU_ISO")
	)
	(segment
		(start 209.429096 -197.487794)
		(end 208.989676 -197.487794)
		(width 0.11684)
		(layer "In6.Cu")
		(net "GPU_3V3IO_RSVD1_FFU_ISO")
	)
	(segment
		(start 170.848782 -421.152574)
		(end 170.848782 -420.077138)
		(width 0.11684)
		(layer "In6.Cu")
		(net "GPU_3V3IO_RSVD1_FFU_ISO")
	)
	(segment
		(start 165.006528 -431.97653)
		(end 167.772334 -429.210724)
		(width 0.11684)
		(layer "In6.Cu")
		(net "GPU_3V3IO_RSVD1_FFU_ISO")
	)
	(segment
		(start 174.489618 -390.64184)
		(end 179.813712 -385.317746)
		(width 0.11684)
		(layer "In6.Cu")
		(net "GPU_3V3IO_RSVD1_FFU_ISO")
	)
	(segment
		(start 226.05238 -338.556346)
		(end 226.05238 -331.266038)
		(width 0.11684)
		(layer "In6.Cu")
		(net "GPU_3V3IO_RSVD1_FFU_ISO")
	)
	(segment
		(start 169.928286 -411.891988)
		(end 169.928286 -411.506416)
		(width 0.11684)
		(layer "In6.Cu")
		(net "GPU_3V3IO_RSVD1_FFU_ISO")
	)
	(segment
		(start 175.321214 -401.674076)
		(end 174.489618 -400.84248)
		(width 0.11684)
		(layer "In6.Cu")
		(net "GPU_3V3IO_RSVD1_FFU_ISO")
	)
	(segment
		(start 179.813712 -383.186432)
		(end 191.13881 -371.861334)
		(width 0.11684)
		(layer "In6.Cu")
		(net "GPU_3V3IO_RSVD1_FFU_ISO")
	)
	(segment
		(start 222.99676 -367.74628)
		(end 223.940116 -366.802924)
		(width 0.11684)
		(layer "In6.Cu")
		(net "GPU_3V3IO_RSVD1_FFU_ISO")
	)
	(segment
		(start 167.772334 -429.108108)
		(end 169.199814 -427.680628)
		(width 0.11684)
		(layer "In6.Cu")
		(net "GPU_3V3IO_RSVD1_FFU_ISO")
	)
	(segment
		(start 175.321214 -406.584658)
		(end 175.321214 -401.674076)
		(width 0.11684)
		(layer "In6.Cu")
		(net "GPU_3V3IO_RSVD1_FFU_ISO")
	)
	(segment
		(start 223.940116 -365.322104)
		(end 226.6823 -362.57992)
		(width 0.11684)
		(layer "In6.Cu")
		(net "GPU_3V3IO_RSVD1_FFU_ISO")
	)
	(segment
		(start 171.18711 -410.718762)
		(end 175.321214 -406.584658)
		(width 0.11684)
		(layer "In6.Cu")
		(net "GPU_3V3IO_RSVD1_FFU_ISO")
	)
	(segment
		(start 169.199814 -427.680628)
		(end 169.199814 -422.801542)
		(width 0.11684)
		(layer "In6.Cu")
		(net "GPU_3V3IO_RSVD1_FFU_ISO")
	)
	(segment
		(start 169.506392 -419.020498)
		(end 169.506392 -414.86709)
		(width 0.11684)
		(layer "In6.Cu")
		(net "GPU_3V3IO_RSVD1_FFU_ISO")
	)
	(segment
		(start 174.489618 -400.84248)
		(end 174.489618 -390.64184)
		(width 0.11684)
		(layer "In6.Cu")
		(net "GPU_3V3IO_RSVD1_FFU_ISO")
	)
	(segment
		(start 191.13881 -371.861334)
		(end 219.141802 -371.861334)
		(width 0.11684)
		(layer "In6.Cu")
		(net "GPU_3V3IO_RSVD1_FFU_ISO")
	)
	(segment
		(start 179.813712 -385.317746)
		(end 179.813712 -383.186432)
		(width 0.11684)
		(layer "In6.Cu")
		(net "GPU_3V3IO_RSVD1_FFU_ISO")
	)
	(segment
		(start 170.71594 -410.718762)
		(end 171.18711 -410.718762)
		(width 0.11684)
		(layer "In6.Cu")
		(net "GPU_3V3IO_RSVD1_FFU_ISO")
	)
	(segment
		(start 170.848782 -420.077138)
		(end 170.555158 -419.783514)
		(width 0.11684)
		(layer "In6.Cu")
		(net "GPU_3V3IO_RSVD1_FFU_ISO")
	)
	(segment
		(start 170.555158 -419.783514)
		(end 170.269408 -419.783514)
		(width 0.11684)
		(layer "In6.Cu")
		(net "GPU_3V3IO_RSVD1_FFU_ISO")
	)
	(segment
		(start 226.6823 -339.186266)
		(end 226.05238 -338.556346)
		(width 0.11684)
		(layer "In6.Cu")
		(net "GPU_3V3IO_RSVD1_FFU_ISO")
	)
	(segment
		(start 170.170602 -412.134304)
		(end 169.928286 -411.891988)
		(width 0.11684)
		(layer "In6.Cu")
		(net "GPU_3V3IO_RSVD1_FFU_ISO")
	)
	(segment
		(start 167.772334 -429.210724)
		(end 167.772334 -429.108108)
		(width 0.11684)
		(layer "In6.Cu")
		(net "GPU_3V3IO_RSVD1_FFU_ISO")
	)
	(segment
		(start 223.940116 -366.802924)
		(end 223.940116 -365.322104)
		(width 0.11684)
		(layer "In6.Cu")
		(net "GPU_3V3IO_RSVD1_FFU_ISO")
	)
	(segment
		(start 215.130888 -320.344546)
		(end 215.130888 -203.189586)
		(width 0.11684)
		(layer "In6.Cu")
		(net "GPU_3V3IO_RSVD1_FFU_ISO")
	)
	(segment
		(start 226.6823 -362.57992)
		(end 226.6823 -339.186266)
		(width 0.11684)
		(layer "In6.Cu")
		(net "GPU_3V3IO_RSVD1_FFU_ISO")
	)
	(segment
		(start 226.05238 -331.266038)
		(end 215.130888 -320.344546)
		(width 0.11684)
		(layer "In6.Cu")
		(net "GPU_3V3IO_RSVD1_FFU_ISO")
	)
	(segment
		(start 215.130888 -203.189586)
		(end 209.429096 -197.487794)
		(width 0.11684)
		(layer "In6.Cu")
		(net "GPU_3V3IO_RSVD1_FFU_ISO")
	)
	(segment
		(start 170.170602 -414.20288)
		(end 170.170602 -412.134304)
		(width 0.11684)
		(layer "In6.Cu")
		(net "GPU_3V3IO_RSVD1_FFU_ISO")
	)
	(segment
		(start 162.405314 -431.97653)
		(end 165.006528 -431.97653)
		(width 0.11684)
		(layer "In6.Cu")
		(net "GPU_3V3IO_RSVD1_FFU_ISO")
	)
	(segment
		(start 169.506392 -414.86709)
		(end 170.170602 -414.20288)
		(width 0.11684)
		(layer "In6.Cu")
		(net "GPU_3V3IO_RSVD1_FFU_ISO")
	)
	(segment
		(start 219.141802 -371.861334)
		(end 222.99676 -368.006376)
		(width 0.11684)
		(layer "In6.Cu")
		(net "GPU_3V3IO_RSVD1_FFU_ISO")
	)
	(segment
		(start 207.091026 -130.912108)
		(end 207.091026 -135.810752)
		(width 0.11684)
		(layer "In11.Cu")
		(net "GPU_3V3IO_RSVD1_FFU_ISO")
	)
	(segment
		(start 207.558386 -127.130048)
		(end 207.558386 -130.444748)
		(width 0.11684)
		(layer "In11.Cu")
		(net "GPU_3V3IO_RSVD1_FFU_ISO")
	)
	(segment
		(start 207.091026 -123.400312)
		(end 207.091026 -126.662688)
		(width 0.11684)
		(layer "In11.Cu")
		(net "GPU_3V3IO_RSVD1_FFU_ISO")
	)
	(segment
		(start 207.558386 -130.444748)
		(end 207.091026 -130.912108)
		(width 0.11684)
		(layer "In11.Cu")
		(net "GPU_3V3IO_RSVD1_FFU_ISO")
	)
	(segment
		(start 202.983084 -156.247084)
		(end 202.508104 -156.722064)
		(width 0.11684)
		(layer "In11.Cu")
		(net "GPU_3V3IO_RSVD1_FFU_ISO")
	)
	(segment
		(start 207.185768 -123.30557)
		(end 207.091026 -123.400312)
		(width 0.11684)
		(layer "In11.Cu")
		(net "GPU_3V3IO_RSVD1_FFU_ISO")
	)
	(segment
		(start 202.983084 -139.918694)
		(end 202.983084 -156.247084)
		(width 0.11684)
		(layer "In11.Cu")
		(net "GPU_3V3IO_RSVD1_FFU_ISO")
	)
	(segment
		(start 207.091026 -126.662688)
		(end 207.558386 -127.130048)
		(width 0.11684)
		(layer "In11.Cu")
		(net "GPU_3V3IO_RSVD1_FFU_ISO")
	)
	(segment
		(start 202.508104 -156.722064)
		(end 202.508104 -165.66896)
		(width 0.11684)
		(layer "In11.Cu")
		(net "GPU_3V3IO_RSVD1_FFU_ISO")
	)
	(segment
		(start 206.99476 -120.944386)
		(end 207.185768 -121.135394)
		(width 0.11684)
		(layer "In11.Cu")
		(net "GPU_3V3IO_RSVD1_FFU_ISO")
	)
	(segment
		(start 202.508104 -165.66896)
		(end 195.974462 -172.202602)
		(width 0.11684)
		(layer "In11.Cu")
		(net "GPU_3V3IO_RSVD1_FFU_ISO")
	)
	(segment
		(start 206.497682 -120.944386)
		(end 206.99476 -120.944386)
		(width 0.11684)
		(layer "In11.Cu")
		(net "GPU_3V3IO_RSVD1_FFU_ISO")
	)
	(segment
		(start 207.091026 -135.810752)
		(end 202.983084 -139.918694)
		(width 0.11684)
		(layer "In11.Cu")
		(net "GPU_3V3IO_RSVD1_FFU_ISO")
	)
	(segment
		(start 207.185768 -121.135394)
		(end 207.185768 -123.30557)
		(width 0.11684)
		(layer "In11.Cu")
		(net "GPU_3V3IO_RSVD1_FFU_ISO")
	)
	(via
		(at 161.414714 -430.99863)
		(size 0.508)
		(drill 0.254)
		(layers "F.Cu" "B.Cu")
		(net "GPU_3V3IO_RSVD1_FFU")
	)
	(segment
		(start 163.387532 -430.99863)
		(end 164.403532 -430.99863)
		(width 0.10668)
		(layer "B.Cu")
		(net "GPU_3V3IO_RSVD1_FFU")
	)
	(segment
		(start 166.552372 -431.326544)
		(end 165.569646 -431.326544)
		(width 0.10668)
		(layer "B.Cu")
		(net "GPU_3V3IO_RSVD1_FFU")
	)
	(segment
		(start 161.414714 -430.99863)
		(end 163.387532 -430.99863)
		(width 0.10668)
		(layer "B.Cu")
		(net "GPU_3V3IO_RSVD1_FFU")
	)
	(segment
		(start 165.241732 -430.99863)
		(end 165.419532 -431.17643)
		(width 0.10668)
		(layer "B.Cu")
		(net "GPU_3V3IO_RSVD1_FFU")
	)
	(segment
		(start 165.569646 -431.326544)
		(end 165.419532 -431.17643)
		(width 0.10668)
		(layer "B.Cu")
		(net "GPU_3V3IO_RSVD1_FFU")
	)
	(segment
		(start 164.403532 -430.99863)
		(end 165.241732 -430.99863)
		(width 0.10668)
		(layer "B.Cu")
		(net "GPU_3V3IO_RSVD1_FFU")
	)
	(segment
		(start 153.318464 -424.121072)
		(end 157.262322 -424.121072)
		(width 0.11684)
		(layer "In4.Cu")
		(net "GPU_3V3IO_RSVD1_FFU")
	)
	(segment
		(start 157.262322 -424.121072)
		(end 161.414714 -428.273464)
		(width 0.11684)
		(layer "In4.Cu")
		(net "GPU_3V3IO_RSVD1_FFU")
	)
	(segment
		(start 152.750012 -424.689778)
		(end 153.318464 -424.121072)
		(width 0.11684)
		(layer "In4.Cu")
		(net "GPU_3V3IO_RSVD1_FFU")
	)
	(segment
		(start 161.414714 -428.273464)
		(end 161.414714 -430.99863)
		(width 0.11684)
		(layer "In4.Cu")
		(net "GPU_3V3IO_RSVD1_FFU")
	)
	(segment
		(start 420.246302 -435.764686)
		(end 419.230302 -435.764686)
		(width 0.10668)
		(layer "F.Cu")
		(net "GPU_3V3IO_RSVD1")
	)
	(segment
		(start 422.40708 -435.436772)
		(end 421.412416 -435.436772)
		(width 0.10668)
		(layer "F.Cu")
		(net "GPU_3V3IO_RSVD1")
	)
	(segment
		(start 419.230302 -435.764686)
		(end 417.837366 -435.764686)
		(width 0.10668)
		(layer "F.Cu")
		(net "GPU_3V3IO_RSVD1")
	)
	(segment
		(start 421.412416 -435.436772)
		(end 421.262302 -435.586886)
		(width 0.10668)
		(layer "F.Cu")
		(net "GPU_3V3IO_RSVD1")
	)
	(segment
		(start 420.246302 -435.764686)
		(end 421.084502 -435.764686)
		(width 0.10668)
		(layer "F.Cu")
		(net "GPU_3V3IO_RSVD1")
	)
	(segment
		(start 421.084502 -435.764686)
		(end 421.262302 -435.586886)
		(width 0.10668)
		(layer "F.Cu")
		(net "GPU_3V3IO_RSVD1")
	)
	(via
		(at 417.837366 -435.764686)
		(size 0.508)
		(drill 0.254)
		(layers "F.Cu" "B.Cu")
		(net "GPU_3V3IO_RSVD1")
	)
	(segment
		(start 410.750004 -440.489848)
		(end 410.750004 -440.462162)
		(width 0.10668)
		(layer "B.Cu")
		(net "GPU_3V3IO_RSVD1")
	)
	(segment
		(start 412.057342 -423.9768)
		(end 413.095186 -423.9768)
		(width 0.10668)
		(layer "B.Cu")
		(net "GPU_3V3IO_RSVD1")
	)
	(segment
		(start 410.750004 -440.462162)
		(end 411.760924 -439.451242)
		(width 0.10668)
		(layer "B.Cu")
		(net "GPU_3V3IO_RSVD1")
	)
	(segment
		(start 411.760924 -424.273218)
		(end 412.057342 -423.9768)
		(width 0.10668)
		(layer "B.Cu")
		(net "GPU_3V3IO_RSVD1")
	)
	(segment
		(start 413.095186 -423.9768)
		(end 414.930844 -425.812458)
		(width 0.10668)
		(layer "B.Cu")
		(net "GPU_3V3IO_RSVD1")
	)
	(segment
		(start 414.930844 -432.858164)
		(end 417.837366 -435.764686)
		(width 0.10668)
		(layer "B.Cu")
		(net "GPU_3V3IO_RSVD1")
	)
	(segment
		(start 411.760924 -439.451242)
		(end 411.760924 -424.273218)
		(width 0.10668)
		(layer "B.Cu")
		(net "GPU_3V3IO_RSVD1")
	)
	(segment
		(start 414.930844 -425.812458)
		(end 414.930844 -432.858164)
		(width 0.10668)
		(layer "B.Cu")
		(net "GPU_3V3IO_RSVD1")
	)
	(via
		(at 163.91128 -414.84804)
		(size 0.6604)
		(drill 0.3302)
		(layers "F.Cu" "B.Cu")
		(net "GPU_3V3IO_RSVD0_FFU_N")
	)
	(segment
		(start 163.415218 -415.344102)
		(end 163.91128 -414.84804)
		(width 0.10668)
		(layer "B.Cu")
		(net "GPU_3V3IO_RSVD0_FFU_N")
	)
	(segment
		(start 165.677596 -412.897828)
		(end 166.327582 -412.897828)
		(width 0.10668)
		(layer "B.Cu")
		(net "GPU_3V3IO_RSVD0_FFU_N")
	)
	(segment
		(start 163.91128 -414.84804)
		(end 164.831522 -413.927798)
		(width 0.10668)
		(layer "B.Cu")
		(net "GPU_3V3IO_RSVD0_FFU_N")
	)
	(segment
		(start 163.415218 -415.75101)
		(end 163.415218 -415.344102)
		(width 0.10668)
		(layer "B.Cu")
		(net "GPU_3V3IO_RSVD0_FFU_N")
	)
	(segment
		(start 164.831522 -413.927798)
		(end 165.090602 -413.927798)
		(width 0.10668)
		(layer "B.Cu")
		(net "GPU_3V3IO_RSVD0_FFU_N")
	)
	(segment
		(start 165.677596 -413.340804)
		(end 165.677596 -412.897828)
		(width 0.10668)
		(layer "B.Cu")
		(net "GPU_3V3IO_RSVD0_FFU_N")
	)
	(segment
		(start 165.090602 -413.927798)
		(end 165.677596 -413.340804)
		(width 0.10668)
		(layer "B.Cu")
		(net "GPU_3V3IO_RSVD0_FFU_N")
	)
	(segment
		(start 208.577942 -184.623964)
		(end 210.517232 -189.305692)
		(width 0.10668)
		(layer "F.Cu")
		(net "GPU_3V3IO_RSVD0_FFU_ISO")
	)
	(segment
		(start 204.219556 -180.265578)
		(end 208.577942 -184.623964)
		(width 0.10668)
		(layer "F.Cu")
		(net "GPU_3V3IO_RSVD0_FFU_ISO")
	)
	(segment
		(start 192.261744 -172.462952)
		(end 200.06437 -180.265578)
		(width 0.10668)
		(layer "F.Cu")
		(net "GPU_3V3IO_RSVD0_FFU_ISO")
	)
	(segment
		(start 192.261744 -171.785026)
		(end 192.261744 -172.462952)
		(width 0.10668)
		(layer "F.Cu")
		(net "GPU_3V3IO_RSVD0_FFU_ISO")
	)
	(segment
		(start 200.06437 -180.265578)
		(end 204.219556 -180.265578)
		(width 0.10668)
		(layer "F.Cu")
		(net "GPU_3V3IO_RSVD0_FFU_ISO")
	)
	(segment
		(start 210.517232 -194.716908)
		(end 209.64906 -195.58508)
		(width 0.10668)
		(layer "F.Cu")
		(net "GPU_3V3IO_RSVD0_FFU_ISO")
	)
	(segment
		(start 210.517232 -189.305692)
		(end 210.517232 -194.716908)
		(width 0.10668)
		(layer "F.Cu")
		(net "GPU_3V3IO_RSVD0_FFU_ISO")
	)
	(via
		(at 203.134468 -159.761682)
		(size 0.508)
		(drill 0.254)
		(layers "F.Cu" "B.Cu")
		(net "GPU_3V3IO_RSVD0_FFU_ISO")
	)
	(via
		(at 198.342758 -120.737376)
		(size 0.508)
		(drill 0.254)
		(layers "F.Cu" "B.Cu")
		(net "GPU_3V3IO_RSVD0_FFU_ISO")
	)
	(via
		(at 209.64906 -195.58508)
		(size 0.508)
		(drill 0.254)
		(layers "F.Cu" "B.Cu")
		(net "GPU_3V3IO_RSVD0_FFU_ISO")
	)
	(via
		(at 192.261744 -171.785026)
		(size 0.508)
		(drill 0.254)
		(layers "F.Cu" "B.Cu")
		(net "GPU_3V3IO_RSVD0_FFU_ISO")
	)
	(via
		(at 174.485046 -412.786576)
		(size 0.508)
		(drill 0.254)
		(layers "F.Cu" "B.Cu")
		(net "GPU_3V3IO_RSVD0_FFU_ISO")
	)
	(segment
		(start 203.586588 -160.213802)
		(end 203.134468 -159.761682)
		(width 0.10668)
		(layer "B.Cu")
		(net "GPU_3V3IO_RSVD0_FFU_ISO")
	)
	(segment
		(start 197.669658 -120.737376)
		(end 198.342758 -120.737376)
		(width 0.10668)
		(layer "B.Cu")
		(net "GPU_3V3IO_RSVD0_FFU_ISO")
	)
	(segment
		(start 197.423024 -173.777402)
		(end 203.586588 -167.613838)
		(width 0.10668)
		(layer "B.Cu")
		(net "GPU_3V3IO_RSVD0_FFU_ISO")
	)
	(segment
		(start 171.38015 -412.786576)
		(end 174.485046 -412.786576)
		(width 0.10668)
		(layer "B.Cu")
		(net "GPU_3V3IO_RSVD0_FFU_ISO")
	)
	(segment
		(start 166.977568 -415.930588)
		(end 166.977568 -414.797748)
		(width 0.10668)
		(layer "B.Cu")
		(net "GPU_3V3IO_RSVD0_FFU_ISO")
	)
	(segment
		(start 166.977568 -415.930588)
		(end 166.977568 -416.946588)
		(width 0.10668)
		(layer "B.Cu")
		(net "GPU_3V3IO_RSVD0_FFU_ISO")
	)
	(segment
		(start 192.261744 -172.45076)
		(end 193.588386 -173.777402)
		(width 0.10668)
		(layer "B.Cu")
		(net "GPU_3V3IO_RSVD0_FFU_ISO")
	)
	(segment
		(start 203.586588 -167.613838)
		(end 203.586588 -160.213802)
		(width 0.10668)
		(layer "B.Cu")
		(net "GPU_3V3IO_RSVD0_FFU_ISO")
	)
	(segment
		(start 166.977568 -417.962588)
		(end 166.977568 -416.946588)
		(width 0.10668)
		(layer "B.Cu")
		(net "GPU_3V3IO_RSVD0_FFU_ISO")
	)
	(segment
		(start 192.261744 -171.785026)
		(end 192.261744 -172.45076)
		(width 0.10668)
		(layer "B.Cu")
		(net "GPU_3V3IO_RSVD0_FFU_ISO")
	)
	(segment
		(start 166.977568 -414.797748)
		(end 169.368978 -414.797748)
		(width 0.10668)
		(layer "B.Cu")
		(net "GPU_3V3IO_RSVD0_FFU_ISO")
	)
	(segment
		(start 169.368978 -414.797748)
		(end 171.38015 -412.786576)
		(width 0.10668)
		(layer "B.Cu")
		(net "GPU_3V3IO_RSVD0_FFU_ISO")
	)
	(segment
		(start 193.588386 -173.777402)
		(end 197.423024 -173.777402)
		(width 0.10668)
		(layer "B.Cu")
		(net "GPU_3V3IO_RSVD0_FFU_ISO")
	)
	(segment
		(start 197.347078 -126.504446)
		(end 198.767192 -127.92456)
		(width 0.11684)
		(layer "In4.Cu")
		(net "GPU_3V3IO_RSVD0_FFU_ISO")
	)
	(segment
		(start 198.877936 -142.150338)
		(end 198.877936 -143.285464)
		(width 0.11684)
		(layer "In4.Cu")
		(net "GPU_3V3IO_RSVD0_FFU_ISO")
	)
	(segment
		(start 197.347078 -121.407936)
		(end 197.347078 -126.504446)
		(width 0.11684)
		(layer "In4.Cu")
		(net "GPU_3V3IO_RSVD0_FFU_ISO")
	)
	(segment
		(start 202.68184 -159.309054)
		(end 203.134468 -159.761682)
		(width 0.11684)
		(layer "In4.Cu")
		(net "GPU_3V3IO_RSVD0_FFU_ISO")
	)
	(segment
		(start 199.984614 -146.649694)
		(end 202.68184 -149.34692)
		(width 0.11684)
		(layer "In4.Cu")
		(net "GPU_3V3IO_RSVD0_FFU_ISO")
	)
	(segment
		(start 199.516492 -141.511782)
		(end 198.877936 -142.150338)
		(width 0.11684)
		(layer "In4.Cu")
		(net "GPU_3V3IO_RSVD0_FFU_ISO")
	)
	(segment
		(start 199.984614 -144.392142)
		(end 199.984614 -146.649694)
		(width 0.11684)
		(layer "In4.Cu")
		(net "GPU_3V3IO_RSVD0_FFU_ISO")
	)
	(segment
		(start 198.017638 -120.737376)
		(end 197.347078 -121.407936)
		(width 0.11684)
		(layer "In4.Cu")
		(net "GPU_3V3IO_RSVD0_FFU_ISO")
	)
	(segment
		(start 198.767192 -129.337562)
		(end 199.516492 -130.086862)
		(width 0.11684)
		(layer "In4.Cu")
		(net "GPU_3V3IO_RSVD0_FFU_ISO")
	)
	(segment
		(start 202.68184 -149.34692)
		(end 202.68184 -159.309054)
		(width 0.11684)
		(layer "In4.Cu")
		(net "GPU_3V3IO_RSVD0_FFU_ISO")
	)
	(segment
		(start 198.767192 -127.92456)
		(end 198.767192 -129.337562)
		(width 0.11684)
		(layer "In4.Cu")
		(net "GPU_3V3IO_RSVD0_FFU_ISO")
	)
	(segment
		(start 198.877936 -143.285464)
		(end 199.984614 -144.392142)
		(width 0.11684)
		(layer "In4.Cu")
		(net "GPU_3V3IO_RSVD0_FFU_ISO")
	)
	(segment
		(start 198.342758 -120.737376)
		(end 198.017638 -120.737376)
		(width 0.11684)
		(layer "In4.Cu")
		(net "GPU_3V3IO_RSVD0_FFU_ISO")
	)
	(segment
		(start 199.516492 -130.086862)
		(end 199.516492 -141.511782)
		(width 0.11684)
		(layer "In4.Cu")
		(net "GPU_3V3IO_RSVD0_FFU_ISO")
	)
	(segment
		(start 216.294208 -319.862454)
		(end 228.123496 -331.691742)
		(width 0.11684)
		(layer "In6.Cu")
		(net "GPU_3V3IO_RSVD0_FFU_ISO")
	)
	(segment
		(start 220.966284 -373.560594)
		(end 193.401696 -373.560594)
		(width 0.11684)
		(layer "In6.Cu")
		(net "GPU_3V3IO_RSVD0_FFU_ISO")
	)
	(segment
		(start 181.84368 -383.542032)
		(end 181.84368 -386.00634)
		(width 0.11684)
		(layer "In6.Cu")
		(net "GPU_3V3IO_RSVD0_FFU_ISO")
	)
	(segment
		(start 228.123496 -331.691742)
		(end 228.123496 -363.24159)
		(width 0.11684)
		(layer "In6.Cu")
		(net "GPU_3V3IO_RSVD0_FFU_ISO")
	)
	(segment
		(start 209.64906 -195.58508)
		(end 209.755232 -195.58508)
		(width 0.11684)
		(layer "In6.Cu")
		(net "GPU_3V3IO_RSVD0_FFU_ISO")
	)
	(segment
		(start 216.294208 -202.124056)
		(end 216.294208 -319.862454)
		(width 0.11684)
		(layer "In6.Cu")
		(net "GPU_3V3IO_RSVD0_FFU_ISO")
	)
	(segment
		(start 174.227236 -412.528766)
		(end 174.485046 -412.786576)
		(width 0.11684)
		(layer "In6.Cu")
		(net "GPU_3V3IO_RSVD0_FFU_ISO")
	)
	(segment
		(start 191.665098 -375.297192)
		(end 190.08852 -375.297192)
		(width 0.11684)
		(layer "In6.Cu")
		(net "GPU_3V3IO_RSVD0_FFU_ISO")
	)
	(segment
		(start 227.073968 -367.45291)
		(end 220.966284 -373.560594)
		(width 0.11684)
		(layer "In6.Cu")
		(net "GPU_3V3IO_RSVD0_FFU_ISO")
	)
	(segment
		(start 193.401696 -373.560594)
		(end 191.665098 -375.297192)
		(width 0.11684)
		(layer "In6.Cu")
		(net "GPU_3V3IO_RSVD0_FFU_ISO")
	)
	(segment
		(start 190.08852 -375.297192)
		(end 181.84368 -383.542032)
		(width 0.11684)
		(layer "In6.Cu")
		(net "GPU_3V3IO_RSVD0_FFU_ISO")
	)
	(segment
		(start 227.073968 -364.291118)
		(end 227.073968 -367.45291)
		(width 0.11684)
		(layer "In6.Cu")
		(net "GPU_3V3IO_RSVD0_FFU_ISO")
	)
	(segment
		(start 177.035206 -401.0025)
		(end 177.035206 -407.684986)
		(width 0.11684)
		(layer "In6.Cu")
		(net "GPU_3V3IO_RSVD0_FFU_ISO")
	)
	(segment
		(start 181.84368 -386.00634)
		(end 176.219358 -391.630662)
		(width 0.11684)
		(layer "In6.Cu")
		(net "GPU_3V3IO_RSVD0_FFU_ISO")
	)
	(segment
		(start 176.219358 -400.186652)
		(end 177.035206 -401.0025)
		(width 0.11684)
		(layer "In6.Cu")
		(net "GPU_3V3IO_RSVD0_FFU_ISO")
	)
	(segment
		(start 228.123496 -363.24159)
		(end 227.073968 -364.291118)
		(width 0.11684)
		(layer "In6.Cu")
		(net "GPU_3V3IO_RSVD0_FFU_ISO")
	)
	(segment
		(start 209.755232 -195.58508)
		(end 216.294208 -202.124056)
		(width 0.11684)
		(layer "In6.Cu")
		(net "GPU_3V3IO_RSVD0_FFU_ISO")
	)
	(segment
		(start 174.227236 -410.492956)
		(end 174.227236 -412.528766)
		(width 0.11684)
		(layer "In6.Cu")
		(net "GPU_3V3IO_RSVD0_FFU_ISO")
	)
	(segment
		(start 176.219358 -391.630662)
		(end 176.219358 -400.186652)
		(width 0.11684)
		(layer "In6.Cu")
		(net "GPU_3V3IO_RSVD0_FFU_ISO")
	)
	(segment
		(start 177.035206 -407.684986)
		(end 174.227236 -410.492956)
		(width 0.11684)
		(layer "In6.Cu")
		(net "GPU_3V3IO_RSVD0_FFU_ISO")
	)
	(via
		(at 165.999668 -418.860986)
		(size 0.508)
		(drill 0.254)
		(layers "F.Cu" "B.Cu")
		(net "GPU_3V3IO_RSVD0_FFU")
	)
	(segment
		(start 165.999668 -416.108388)
		(end 166.177468 -415.930588)
		(width 0.10668)
		(layer "B.Cu")
		(net "GPU_3V3IO_RSVD0_FFU")
	)
	(segment
		(start 165.999668 -417.962588)
		(end 165.999668 -416.946588)
		(width 0.10668)
		(layer "B.Cu")
		(net "GPU_3V3IO_RSVD0_FFU")
	)
	(segment
		(start 165.999668 -416.946588)
		(end 165.999668 -416.108388)
		(width 0.10668)
		(layer "B.Cu")
		(net "GPU_3V3IO_RSVD0_FFU")
	)
	(segment
		(start 165.999668 -417.962588)
		(end 165.999668 -418.860986)
		(width 0.10668)
		(layer "B.Cu")
		(net "GPU_3V3IO_RSVD0_FFU")
	)
	(segment
		(start 166.177468 -415.930588)
		(end 166.177468 -415.32937)
		(width 0.10668)
		(layer "B.Cu")
		(net "GPU_3V3IO_RSVD0_FFU")
	)
	(segment
		(start 166.327582 -415.179256)
		(end 166.327582 -414.797748)
		(width 0.10668)
		(layer "B.Cu")
		(net "GPU_3V3IO_RSVD0_FFU")
	)
	(segment
		(start 166.177468 -415.32937)
		(end 166.327582 -415.179256)
		(width 0.10668)
		(layer "B.Cu")
		(net "GPU_3V3IO_RSVD0_FFU")
	)
	(segment
		(start 165.999668 -418.860986)
		(end 165.260782 -419.599872)
		(width 0.11684)
		(layer "In4.Cu")
		(net "GPU_3V3IO_RSVD0_FFU")
	)
	(segment
		(start 161.309558 -419.599872)
		(end 159.678624 -421.230806)
		(width 0.11684)
		(layer "In4.Cu")
		(net "GPU_3V3IO_RSVD0_FFU")
	)
	(segment
		(start 159.678624 -421.230806)
		(end 159.678624 -421.942514)
		(width 0.11684)
		(layer "In4.Cu")
		(net "GPU_3V3IO_RSVD0_FFU")
	)
	(segment
		(start 149.638766 -423.801032)
		(end 148.75002 -424.689778)
		(width 0.11684)
		(layer "In4.Cu")
		(net "GPU_3V3IO_RSVD0_FFU")
	)
	(segment
		(start 157.820106 -423.801032)
		(end 149.638766 -423.801032)
		(width 0.11684)
		(layer "In4.Cu")
		(net "GPU_3V3IO_RSVD0_FFU")
	)
	(segment
		(start 165.260782 -419.599872)
		(end 161.309558 -419.599872)
		(width 0.11684)
		(layer "In4.Cu")
		(net "GPU_3V3IO_RSVD0_FFU")
	)
	(segment
		(start 159.678624 -421.942514)
		(end 157.820106 -423.801032)
		(width 0.11684)
		(layer "In4.Cu")
		(net "GPU_3V3IO_RSVD0_FFU")
	)
	(segment
		(start 122.962416 -384.617722)
		(end 123.570492 -384.617722)
		(width 0.254)
		(layer "F.Cu")
		(net "GND")
	)
	(segment
		(start 382.748028 -243.13007)
		(end 383.21488 -242.864132)
		(width 0.350012)
		(layer "F.Cu")
		(net "GND")
	)
	(segment
		(start 94.36481 -179.610512)
		(end 94.333822 -179.610512)
		(width 0.2286)
		(layer "F.Cu")
		(net "GND")
	)
	(segment
		(start 341.687912 -290.83)
		(end 341.22106 -291.095938)
		(width 0.350012)
		(layer "F.Cu")
		(net "GND")
	)
	(segment
		(start 22.112732 -422.437052)
		(end 22.724364 -422.437052)
		(width 0.4572)
		(layer "F.Cu")
		(net "GND")
	)
	(segment
		(start 83.439254 -338.043774)
		(end 83.470242 -338.043774)
		(width 0.2286)
		(layer "F.Cu")
		(net "GND")
	)
	(segment
		(start 85.990176 -384.617722)
		(end 85.398356 -384.617722)
		(width 0.254)
		(layer "F.Cu")
		(net "GND")
	)
	(segment
		(start 364.417864 -240.700052)
		(end 364.884716 -240.434114)
		(width 0.350012)
		(layer "F.Cu")
		(net "GND")
	)
	(segment
		(start 317.270384 -396.520924)
		(end 316.718188 -396.710662)
		(width 0.254)
		(layer "F.Cu")
		(net "GND")
	)
	(segment
		(start 108.317792 -275.440394)
		(end 107.85094 -275.706332)
		(width 0.350012)
		(layer "F.Cu")
		(net "GND")
	)
	(segment
		(start 346.087954 -254.470154)
		(end 345.621102 -254.204216)
		(width 0.350012)
		(layer "F.Cu")
		(net "GND")
	)
	(segment
		(start 341.387938 -241.510058)
		(end 340.921086 -241.24412)
		(width 0.350012)
		(layer "F.Cu")
		(net "GND")
	)
	(segment
		(start 130.77063 -388.138924)
		(end 130.218434 -388.328662)
		(width 0.254)
		(layer "F.Cu")
		(net "GND")
	)
	(segment
		(start 134.80796 -238.270288)
		(end 135.274812 -238.00435)
		(width 0.350012)
		(layer "F.Cu")
		(net "GND")
	)
	(segment
		(start 77.467968 -243.130324)
		(end 76.812902 -243.130324)
		(width 0.350012)
		(layer "F.Cu")
		(net "GND")
	)
	(segment
		(start 387.61797 -391.333482)
		(end 387.716522 -391.23493)
		(width 0.254)
		(layer "F.Cu")
		(net "GND")
	)
	(segment
		(start 374.11787 -281.920188)
		(end 374.584722 -282.186126)
		(width 0.350012)
		(layer "F.Cu")
		(net "GND")
	)
	(segment
		(start 117.41785 -226.120452)
		(end 117.884702 -225.854514)
		(width 0.350012)
		(layer "F.Cu")
		(net "GND")
	)
	(segment
		(start 156.96819 -99.155758)
		(end 156.30779 -99.155758)
		(width 0.4064)
		(layer "F.Cu")
		(net "GND")
	)
	(segment
		(start 75.68311 -337.395312)
		(end 75.617832 -337.553046)
		(width 0.2286)
		(layer "F.Cu")
		(net "GND")
	)
	(segment
		(start 434.565044 -20.880832)
		(end 434.796692 -20.649184)
		(width 0.3556)
		(layer "F.Cu")
		(net "GND")
	)
	(segment
		(start 373.817896 -229.360222)
		(end 374.284748 -229.094284)
		(width 0.350012)
		(layer "F.Cu")
		(net "GND")
	)
	(segment
		(start 164.427916 -203.285344)
		(end 165.812216 -203.285344)
		(width 0.4572)
		(layer "F.Cu")
		(net "GND")
	)
	(segment
		(start 133.328664 -151.319484)
		(end 132.740654 -151.319484)
		(width 0.381)
		(layer "F.Cu")
		(net "GND")
	)
	(segment
		(start 307.4162 -402.259038)
		(end 307.4162 -403.10562)
		(width 0.381)
		(layer "F.Cu")
		(net "GND")
	)
	(segment
		(start 131.617974 -391.281158)
		(end 131.917948 -390.761474)
		(width 0.254)
		(layer "F.Cu")
		(net "GND")
	)
	(segment
		(start 124.233178 -50.169064)
		(end 123.617228 -50.169064)
		(width 0.4572)
		(layer "F.Cu")
		(net "GND")
	)
	(segment
		(start 360.957876 -272.200116)
		(end 361.424728 -272.466054)
		(width 0.350012)
		(layer "F.Cu")
		(net "GND")
	)
	(segment
		(start 77.613002 -174.560484)
		(end 77.143356 -175.03013)
		(width 0.2286)
		(layer "F.Cu")
		(net "GND")
	)
	(segment
		(start 355.881432 -395.613128)
		(end 355.71938 -395.451076)
		(width 0.254)
		(layer "F.Cu")
		(net "GND")
	)
	(segment
		(start 84.047838 -238.270288)
		(end 83.580986 -238.00435)
		(width 0.350012)
		(layer "F.Cu")
		(net "GND")
	)
	(segment
		(start 96.267778 -225.310446)
		(end 95.800926 -225.044508)
		(width 0.350012)
		(layer "F.Cu")
		(net "GND")
	)
	(segment
		(start 355.71938 -395.451076)
		(end 355.00437 -395.451076)
		(width 0.254)
		(layer "F.Cu")
		(net "GND")
	)
	(segment
		(start 142.797784 -234.220258)
		(end 143.264636 -233.95432)
		(width 0.350012)
		(layer "F.Cu")
		(net "GND")
	)
	(segment
		(start 353.137978 -240.700052)
		(end 352.671126 -240.434114)
		(width 0.350012)
		(layer "F.Cu")
		(net "GND")
	)
	(segment
		(start 312.11774 -392.004296)
		(end 312.417714 -392.30427)
		(width 0.254)
		(layer "F.Cu")
		(net "GND")
	)
	(segment
		(start 435.000146 -212.635084)
		(end 436.384446 -212.635084)
		(width 0.4572)
		(layer "F.Cu")
		(net "GND")
	)
	(segment
		(start 329.808586 -33.921192)
		(end 329.760072 -33.969706)
		(width 0.3556)
		(layer "F.Cu")
		(net "GND")
	)
	(segment
		(start 110.367826 -230.170228)
		(end 109.900974 -229.90429)
		(width 0.350012)
		(layer "F.Cu")
		(net "GND")
	)
	(segment
		(start 109.728 -266.530328)
		(end 109.261148 -266.796266)
		(width 0.350012)
		(layer "F.Cu")
		(net "GND")
	)
	(segment
		(start 265.54811 -221.985078)
		(end 266.93241 -221.985078)
		(width 0.4572)
		(layer "F.Cu")
		(net "GND")
	)
	(segment
		(start 113.017808 -281.920442)
		(end 113.48466 -282.18638)
		(width 0.350012)
		(layer "F.Cu")
		(net "GND")
	)
	(segment
		(start 458.244194 -45.864526)
		(end 458.244194 -45.233082)
		(width 0.381)
		(layer "F.Cu")
		(net "GND")
	)
	(segment
		(start 86.868 -238.270288)
		(end 86.401148 -238.00435)
		(width 0.350012)
		(layer "F.Cu")
		(net "GND")
	)
	(segment
		(start 372.407942 -256.090166)
		(end 372.874794 -255.824228)
		(width 0.350012)
		(layer "F.Cu")
		(net "GND")
	)
	(segment
		(start 89.218008 -222.880428)
		(end 89.218008 -223.40697)
		(width 0.350012)
		(layer "F.Cu")
		(net "GND")
	)
	(segment
		(start 128.52781 -284.35046)
		(end 128.994662 -284.616398)
		(width 0.350012)
		(layer "F.Cu")
		(net "GND")
	)
	(segment
		(start 392.61796 -226.120198)
		(end 393.084812 -225.85426)
		(width 0.350012)
		(layer "F.Cu")
		(net "GND")
	)
	(segment
		(start 100.027994 -235.030264)
		(end 99.561142 -234.764326)
		(width 0.350012)
		(layer "F.Cu")
		(net "GND")
	)
	(segment
		(start 113.594896 -391.304272)
		(end 113.61801 -391.281158)
		(width 0.254)
		(layer "F.Cu")
		(net "GND")
	)
	(segment
		(start 348.737936 -260.860032)
		(end 348.271084 -261.12597)
		(width 0.350012)
		(layer "F.Cu")
		(net "GND")
	)
	(segment
		(start 91.568016 -249.610372)
		(end 91.10091 -249.344434)
		(width 0.350012)
		(layer "F.Cu")
		(net "GND")
	)
	(segment
		(start 153.645616 -390.761474)
		(end 153.698194 -390.160002)
		(width 0.254)
		(layer "F.Cu")
		(net "GND")
	)
	(segment
		(start 138.098022 -255.280414)
		(end 138.564874 -255.014476)
		(width 0.350012)
		(layer "F.Cu")
		(net "GND")
	)
	(segment
		(start 371.467888 -228.550216)
		(end 371.93474 -228.284278)
		(width 0.350012)
		(layer "F.Cu")
		(net "GND")
	)
	(segment
		(start 412.098236 -392.999722)
		(end 412.045658 -392.30427)
		(width 0.254)
		(layer "F.Cu")
		(net "GND")
	)
	(segment
		(start 334.808068 -252.850142)
		(end 334.341216 -252.584204)
		(width 0.350012)
		(layer "F.Cu")
		(net "GND")
	)
	(segment
		(start 77.767942 -263.290304)
		(end 77.112876 -263.290304)
		(width 0.350012)
		(layer "F.Cu")
		(net "GND")
	)
	(segment
		(start 165.942518 -387.831076)
		(end 165.146228 -388.328662)
		(width 0.254)
		(layer "F.Cu")
		(net "GND")
	)
	(segment
		(start 336.987896 -274.630134)
		(end 336.521044 -274.896072)
		(width 0.350012)
		(layer "F.Cu")
		(net "GND")
	)
	(segment
		(start 412.367984 -240.685066)
		(end 413.752284 -240.685066)
		(width 0.4572)
		(layer "F.Cu")
		(net "GND")
	)
	(segment
		(start 320.318384 -396.710662)
		(end 319.67043 -396.520924)
		(width 0.254)
		(layer "F.Cu")
		(net "GND")
	)
	(segment
		(start 21.70811 -293.38524)
		(end 20.32381 -293.38524)
		(width 0.4572)
		(layer "F.Cu")
		(net "GND")
	)
	(segment
		(start 54.070504 -386.6388)
		(end 53.378608 -386.449062)
		(width 0.254)
		(layer "F.Cu")
		(net "GND")
	)
	(segment
		(start 333.697834 -264.100056)
		(end 333.230982 -264.365994)
		(width 0.350012)
		(layer "F.Cu")
		(net "GND")
	)
	(segment
		(start 381.638048 -265.720068)
		(end 382.1049 -265.986006)
		(width 0.350012)
		(layer "F.Cu")
		(net "GND")
	)
	(segment
		(start 323.619876 -337.066128)
		(end 323.87286 -336.813144)
		(width 0.2286)
		(layer "F.Cu")
		(net "GND")
	)
	(segment
		(start 87.3379 -230.980234)
		(end 86.871048 -230.71455)
		(width 0.350012)
		(layer "F.Cu")
		(net "GND")
	)
	(segment
		(start 90.627962 -228.55047)
		(end 90.16111 -228.284532)
		(width 0.350012)
		(layer "F.Cu")
		(net "GND")
	)
	(segment
		(start 107.377992 -285.160466)
		(end 106.91114 -285.426404)
		(width 0.350012)
		(layer "F.Cu")
		(net "GND")
	)
	(segment
		(start 84.040726 -337.056476)
		(end 84.29371 -336.803492)
		(width 0.2286)
		(layer "F.Cu")
		(net "GND")
	)
	(segment
		(start 21.938996 -391.349484)
		(end 22.1361 -391.349484)
		(width 0.2032)
		(layer "F.Cu")
		(net "GND")
	)
	(segment
		(start 96.737932 -230.980234)
		(end 96.27108 -230.71455)
		(width 0.350012)
		(layer "F.Cu")
		(net "GND")
	)
	(segment
		(start 389.327898 -254.470154)
		(end 389.79475 -254.204216)
		(width 0.350012)
		(layer "F.Cu")
		(net "GND")
	)
	(segment
		(start 372.878604 -394.831062)
		(end 372.370604 -395.0208)
		(width 0.254)
		(layer "F.Cu")
		(net "GND")
	)
	(segment
		(start 56.21655 -391.830814)
		(end 56.21655 -391.37971)
		(width 0.254)
		(layer "F.Cu")
		(net "GND")
	)
	(segment
		(start 401.128484 -402.282152)
		(end 400.315684 -402.282152)
		(width 0.254)
		(layer "F.Cu")
		(net "GND")
	)
	(segment
		(start 362.837984 -293.260018)
		(end 363.304582 -293.525956)
		(width 0.350012)
		(layer "F.Cu")
		(net "GND")
	)
	(segment
		(start 101.737922 -291.64026)
		(end 101.27107 -291.906198)
		(width 0.350012)
		(layer "F.Cu")
		(net "GND")
	)
	(segment
		(start 280.635964 -221.985078)
		(end 282.020264 -221.985078)
		(width 0.4572)
		(layer "F.Cu")
		(net "GND")
	)
	(segment
		(start 464.219544 -41.755822)
		(end 463.578194 -41.755822)
		(width 0.4572)
		(layer "F.Cu")
		(net "GND")
	)
	(segment
		(start 376.167904 -249.610118)
		(end 376.634756 -249.34418)
		(width 0.350012)
		(layer "F.Cu")
		(net "GND")
	)
	(segment
		(start 25.152096 -200.735438)
		(end 26.536396 -200.735438)
		(width 0.4572)
		(layer "F.Cu")
		(net "GND")
	)
	(segment
		(start 98.147886 -225.310446)
		(end 97.681034 -225.044508)
		(width 0.350012)
		(layer "F.Cu")
		(net "GND")
	)
	(segment
		(start 266.919964 -420.648384)
		(end 266.919964 -421.525192)
		(width 0.381)
		(layer "F.Cu")
		(net "GND")
	)
	(segment
		(start 381.970534 -396.520924)
		(end 381.418338 -396.710662)
		(width 0.254)
		(layer "F.Cu")
		(net "GND")
	)
	(segment
		(start 68.43776 -147.82673)
		(end 69.359526 -147.82673)
		(width 0.254)
		(layer "F.Cu")
		(net "GND")
	)
	(segment
		(start 118.187978 -290.830254)
		(end 118.65483 -291.096192)
		(width 0.350012)
		(layer "F.Cu")
		(net "GND")
	)
	(segment
		(start 381.291338 -398.542002)
		(end 380.770638 -398.542002)
		(width 0.254)
		(layer "F.Cu")
		(net "GND")
	)
	(segment
		(start 338.097876 -247.1801)
		(end 337.631024 -246.914162)
		(width 0.350012)
		(layer "F.Cu")
		(net "GND")
	)
	(segment
		(start 129.31648 -391.830814)
		(end 129.31648 -391.37971)
		(width 0.254)
		(layer "F.Cu")
		(net "GND")
	)
	(segment
		(start 135.577834 -293.260272)
		(end 136.044686 -293.52621)
		(width 0.350012)
		(layer "F.Cu")
		(net "GND")
	)
	(segment
		(start 347.497908 -243.940076)
		(end 347.031056 -243.674138)
		(width 0.350012)
		(layer "F.Cu")
		(net "GND")
	)
	(segment
		(start 379.75794 -267.34008)
		(end 380.224792 -267.606018)
		(width 0.350012)
		(layer "F.Cu")
		(net "GND")
	)
	(segment
		(start 322.53428 -396.213076)
		(end 322.834254 -396.51305)
		(width 0.254)
		(layer "F.Cu")
		(net "GND")
	)
	(segment
		(start 101.902514 -180.868066)
		(end 101.474016 -180.868066)
		(width 0.2286)
		(layer "F.Cu")
		(net "GND")
	)
	(segment
		(start 429.566832 -11.26998)
		(end 429.566832 -10.16635)
		(width 0.3556)
		(layer "F.Cu")
		(net "GND")
	)
	(segment
		(start 114.817906 -382.951482)
		(end 114.916458 -382.85293)
		(width 0.254)
		(layer "F.Cu")
		(net "GND")
	)
	(segment
		(start 402.046948 -10.16635)
		(end 402.045678 -10.16508)
		(width 0.3556)
		(layer "F.Cu")
		(net "GND")
	)
	(segment
		(start 421.69842 -395.369034)
		(end 421.69842 -395.0208)
		(width 0.254)
		(layer "F.Cu")
		(net "GND")
	)
	(segment
		(start 66.534538 -388.431024)
		(end 66.314828 -388.431024)
		(width 0.254)
		(layer "F.Cu")
		(net "GND")
	)
	(segment
		(start 289.012884 -369.918742)
		(end 289.012884 -369.185698)
		(width 0.4572)
		(layer "F.Cu")
		(net "GND")
	)
	(segment
		(start 382.562354 -392.999722)
		(end 383.17043 -392.999722)
		(width 0.254)
		(layer "F.Cu")
		(net "GND")
	)
	(segment
		(start 280.635964 -240.685066)
		(end 282.020264 -240.685066)
		(width 0.4572)
		(layer "F.Cu")
		(net "GND")
	)
	(segment
		(start 381.970534 -392.999722)
		(end 382.562354 -392.999722)
		(width 0.254)
		(layer "F.Cu")
		(net "GND")
	)
	(segment
		(start 396.648178 -12.374118)
		(end 396.646908 -12.372848)
		(width 0.3556)
		(layer "F.Cu")
		(net "GND")
	)
	(segment
		(start 159.698182 -388.138924)
		(end 159.14624 -388.328662)
		(width 0.254)
		(layer "F.Cu")
		(net "GND")
	)
	(segment
		(start 277.192232 -211.784946)
		(end 275.807932 -211.784946)
		(width 0.4572)
		(layer "F.Cu")
		(net "GND")
	)
	(segment
		(start 127.58801 -294.070278)
		(end 128.054862 -294.336216)
		(width 0.350012)
		(layer "F.Cu")
		(net "GND")
	)
	(segment
		(start 185.922158 -116.252752)
		(end 186.312048 -116.642642)
		(width 0.254)
		(layer "F.Cu")
		(net "GND")
	)
	(segment
		(start 120.537986 -281.920442)
		(end 121.004838 -282.18638)
		(width 0.350012)
		(layer "F.Cu")
		(net "GND")
	)
	(segment
		(start 69.179694 -30.541722)
		(end 69.2023 -30.519116)
		(width 0.254)
		(layer "F.Cu")
		(net "GND")
	)
	(segment
		(start 347.968062 -236.650022)
		(end 347.50121 -236.384084)
		(width 0.350012)
		(layer "F.Cu")
		(net "GND")
	)
	(segment
		(start 143.098012 -281.920442)
		(end 143.56461 -282.18638)
		(width 0.350012)
		(layer "F.Cu")
		(net "GND")
	)
	(segment
		(start 83.877912 -270.580358)
		(end 83.41106 -270.846296)
		(width 0.350012)
		(layer "F.Cu")
		(net "GND")
	)
	(segment
		(start 333.697834 -285.160212)
		(end 333.230982 -285.42615)
		(width 0.350012)
		(layer "F.Cu")
		(net "GND")
	)
	(segment
		(start 330.108052 -236.650022)
		(end 329.6412 -236.384084)
		(width 0.350012)
		(layer "F.Cu")
		(net "GND")
	)
	(segment
		(start 25.746964 -12.372848)
		(end 25.746964 -11.26998)
		(width 0.3556)
		(layer "F.Cu")
		(net "GND")
	)
	(segment
		(start 124.162312 -384.617722)
		(end 123.570492 -384.617722)
		(width 0.254)
		(layer "F.Cu")
		(net "GND")
	)
	(segment
		(start 328.697844 -256.900172)
		(end 328.231246 -256.634234)
		(width 0.350012)
		(layer "F.Cu")
		(net "GND")
	)
	(segment
		(start 347.045534 -391.333482)
		(end 347.144086 -391.23493)
		(width 0.254)
		(layer "F.Cu")
		(net "GND")
	)
	(segment
		(start 133.170676 -390.160002)
		(end 132.491226 -390.160002)
		(width 0.254)
		(layer "F.Cu")
		(net "GND")
	)
	(segment
		(start 374.11787 -277.060152)
		(end 374.584722 -277.32609)
		(width 0.350012)
		(layer "F.Cu")
		(net "GND")
	)
	(segment
		(start 43.85818 -12.374118)
		(end 43.85691 -12.372848)
		(width 0.3556)
		(layer "F.Cu")
		(net "GND")
	)
	(segment
		(start 4.150868 -131.305554)
		(end 4.764278 -131.305554)
		(width 0.3556)
		(layer "F.Cu")
		(net "GND")
	)
	(segment
		(start 389.627872 -271.39011)
		(end 390.094724 -271.656048)
		(width 0.350012)
		(layer "F.Cu")
		(net "GND")
	)
	(segment
		(start 197.673976 -106.543856)
		(end 197.77583 -106.64571)
		(width 0.4572)
		(layer "F.Cu")
		(net "GND")
	)
	(segment
		(start 126.817882 -383.402586)
		(end 126.817882 -382.951482)
		(width 0.254)
		(layer "F.Cu")
		(net "GND")
	)
	(segment
		(start 137.457942 -294.880284)
		(end 137.924794 -295.146222)
		(width 0.350012)
		(layer "F.Cu")
		(net "GND")
	)
	(segment
		(start 284.736032 -312.084974)
		(end 283.351732 -312.084974)
		(width 0.4572)
		(layer "F.Cu")
		(net "GND")
	)
	(segment
		(start 138.397996 -286.780478)
		(end 138.864848 -287.046416)
		(width 0.350012)
		(layer "F.Cu")
		(net "GND")
	)
	(segment
		(start 370.225066 -424.838622)
		(end 370.040408 -425.02328)
		(width 0.381)
		(layer "F.Cu")
		(net "GND")
	)
	(segment
		(start 94.1959 -416.635184)
		(end 94.567502 -417.006786)
		(width 0.254)
		(layer "F.Cu")
		(net "GND")
	)
	(segment
		(start 386.03809 -256.900172)
		(end 386.504942 -256.634234)
		(width 0.350012)
		(layer "F.Cu")
		(net "GND")
	)
	(segment
		(start 124.282454 -159.980884)
		(end 124.212604 -160.050734)
		(width 0.381)
		(layer "F.Cu")
		(net "GND")
	)
	(segment
		(start 77.467968 -254.470408)
		(end 76.812902 -254.470408)
		(width 0.350012)
		(layer "F.Cu")
		(net "GND")
	)
	(segment
		(start 313.118246 -396.710662)
		(end 312.470292 -396.520924)
		(width 0.254)
		(layer "F.Cu")
		(net "GND")
	)
	(segment
		(start 340.277958 -280.300176)
		(end 339.811106 -280.566114)
		(width 0.350012)
		(layer "F.Cu")
		(net "GND")
	)
	(segment
		(start 98.44786 -261.670292)
		(end 97.981008 -261.93623)
		(width 0.350012)
		(layer "F.Cu")
		(net "GND")
	)
	(segment
		(start 145.617946 -224.50044)
		(end 146.084798 -224.234502)
		(width 0.350012)
		(layer "F.Cu")
		(net "GND")
	)
	(segment
		(start 113.61801 -382.957578)
		(end 113.56848 -382.908048)
		(width 0.254)
		(layer "F.Cu")
		(net "GND")
	)
	(segment
		(start 143.098012 -260.860286)
		(end 143.564864 -261.126224)
		(width 0.350012)
		(layer "F.Cu")
		(net "GND")
	)
	(segment
		(start 77.767942 -266.530328)
		(end 77.112876 -266.530328)
		(width 0.350012)
		(layer "F.Cu")
		(net "GND")
	)
	(segment
		(start 388.916418 -399.76171)
		(end 388.817866 -399.663158)
		(width 0.254)
		(layer "F.Cu")
		(net "GND")
	)
	(segment
		(start 302.494696 -400.15795)
		(end 302.494696 -399.686272)
		(width 0.254)
		(layer "F.Cu")
		(net "GND")
	)
	(segment
		(start 72.499728 -171.2341)
		(end 73.109328 -171.2341)
		(width 0.4572)
		(layer "F.Cu")
		(net "GND")
	)
	(segment
		(start 132.927852 -226.930458)
		(end 133.394704 -226.66452)
		(width 0.350012)
		(layer "F.Cu")
		(net "GND")
	)
	(segment
		(start 125.970538 -386.6388)
		(end 125.278388 -386.449062)
		(width 0.254)
		(layer "F.Cu")
		(net "GND")
	)
	(segment
		(start 64.63538 -394.52296)
		(end 64.63538 -393.946634)
		(width 0.3048)
		(layer "F.Cu")
		(net "GND")
	)
	(segment
		(start 280.635964 -219.435172)
		(end 282.020264 -219.435172)
		(width 0.4572)
		(layer "F.Cu")
		(net "GND")
	)
	(segment
		(start 361.128056 -230.169974)
		(end 361.594908 -229.904036)
		(width 0.350012)
		(layer "F.Cu")
		(net "GND")
	)
	(segment
		(start 97.97796 -293.260272)
		(end 97.511108 -293.52621)
		(width 0.350012)
		(layer "F.Cu")
		(net "GND")
	)
	(segment
		(start 295.724072 -228.785166)
		(end 297.108372 -228.785166)
		(width 0.4572)
		(layer "F.Cu")
		(net "GND")
	)
	(segment
		(start 317.270384 -398.542002)
		(end 316.590934 -398.542002)
		(width 0.254)
		(layer "F.Cu")
		(net "GND")
	)
	(segment
		(start 132.610352 -52.68849)
		(end 131.973066 -52.68849)
		(width 0.381)
		(layer "F.Cu")
		(net "GND")
	)
	(segment
		(start 105.66781 -241.510312)
		(end 105.200958 -241.244374)
		(width 0.350012)
		(layer "F.Cu")
		(net "GND")
	)
	(segment
		(start 366.597946 -275.44014)
		(end 367.064798 -275.706078)
		(width 0.350012)
		(layer "F.Cu")
		(net "GND")
	)
	(segment
		(start 103.185722 -28.156154)
		(end 103.052372 -28.022804)
		(width 0.254)
		(layer "F.Cu")
		(net "GND")
	)
	(segment
		(start 143.567912 -266.530328)
		(end 144.034764 -266.796266)
		(width 0.350012)
		(layer "F.Cu")
		(net "GND")
	)
	(segment
		(start 164.427916 -238.135414)
		(end 165.812216 -238.135414)
		(width 0.4572)
		(layer "F.Cu")
		(net "GND")
	)
	(segment
		(start 338.39785 -278.680164)
		(end 337.930998 -278.946102)
		(width 0.350012)
		(layer "F.Cu")
		(net "GND")
	)
	(segment
		(start 49.270666 -388.138924)
		(end 49.91862 -388.328662)
		(width 0.254)
		(layer "F.Cu")
		(net "GND")
	)
	(segment
		(start 326.81799 -253.660148)
		(end 326.351138 -253.39421)
		(width 0.350012)
		(layer "F.Cu")
		(net "GND")
	)
	(segment
		(start 92.245688 -383.622296)
		(end 92.545662 -383.92227)
		(width 0.254)
		(layer "F.Cu")
		(net "GND")
	)
	(segment
		(start 455.750168 -47.456598)
		(end 455.750168 -48.191928)
		(width 0.254)
		(layer "F.Cu")
		(net "GND")
	)
	(segment
		(start 129.217928 -391.281158)
		(end 129.517902 -390.761474)
		(width 0.254)
		(layer "F.Cu")
		(net "GND")
	)
	(segment
		(start 370.057934 -229.360222)
		(end 370.524786 -229.094284)
		(width 0.350012)
		(layer "F.Cu")
		(net "GND")
	)
	(segment
		(start 370.828062 -264.910062)
		(end 371.294914 -265.176)
		(width 0.350012)
		(layer "F.Cu")
		(net "GND")
	)
	(segment
		(start 87.637874 -273.820382)
		(end 87.171022 -274.08632)
		(width 0.350012)
		(layer "F.Cu")
		(net "GND")
	)
	(segment
		(start 265.54811 -200.735184)
		(end 266.93241 -200.735184)
		(width 0.4572)
		(layer "F.Cu")
		(net "GND")
	)
	(segment
		(start 94.387924 -223.690434)
		(end 93.921072 -223.424496)
		(width 0.350012)
		(layer "F.Cu")
		(net "GND")
	)
	(segment
		(start 87.44585 -383.402586)
		(end 87.44585 -383.622296)
		(width 0.254)
		(layer "F.Cu")
		(net "GND")
	)
	(segment
		(start 126.647956 -274.630388)
		(end 127.114808 -274.896326)
		(width 0.350012)
		(layer "F.Cu")
		(net "GND")
	)
	(segment
		(start 374.718072 -399.143474)
		(end 374.417844 -399.663158)
		(width 0.254)
		(layer "F.Cu")
		(net "GND")
	)
	(segment
		(start 356.42804 -244.750082)
		(end 355.961188 -244.484144)
		(width 0.350012)
		(layer "F.Cu")
		(net "GND")
	)
	(segment
		(start 348.24543 -399.663158)
		(end 348.545404 -399.143474)
		(width 0.254)
		(layer "F.Cu")
		(net "GND")
	)
	(segment
		(start 300.048422 -351.927922)
		(end 300.118272 -351.858072)
		(width 0.381)
		(layer "F.Cu")
		(net "GND")
	)
	(segment
		(start 330.108052 -238.270034)
		(end 329.6412 -238.004096)
		(width 0.350012)
		(layer "F.Cu")
		(net "GND")
	)
	(segment
		(start 368.478054 -281.920188)
		(end 368.944906 -282.186126)
		(width 0.350012)
		(layer "F.Cu")
		(net "GND")
	)
	(segment
		(start 414.756854 -10.16635)
		(end 414.755584 -10.16508)
		(width 0.3556)
		(layer "F.Cu")
		(net "GND")
	)
	(segment
		(start 410.545788 -391.333482)
		(end 410.64434 -391.23493)
		(width 0.254)
		(layer "F.Cu")
		(net "GND")
	)
	(segment
		(start 373.217948 -391.784586)
		(end 373.217948 -391.333482)
		(width 0.254)
		(layer "F.Cu")
		(net "GND")
	)
	(segment
		(start 350.14789 -261.670038)
		(end 349.681038 -261.935976)
		(width 0.350012)
		(layer "F.Cu")
		(net "GND")
	)
	(segment
		(start 137.154158 -255.824736)
		(end 137.154412 -255.824736)
		(width 0.350012)
		(layer "F.Cu")
		(net "GND")
	)
	(segment
		(start 161.406332 -386.449062)
		(end 160.898332 -386.6388)
		(width 0.254)
		(layer "F.Cu")
		(net "GND")
	)
	(segment
		(start 80.757776 -250.420378)
		(end 80.291178 -250.15444)
		(width 0.350012)
		(layer "F.Cu")
		(net "GND")
	)
	(segment
		(start 133.398006 -234.220258)
		(end 133.864858 -233.95432)
		(width 0.350012)
		(layer "F.Cu")
		(net "GND")
	)
	(segment
		(start 335.195418 -21.256498)
		(end 335.195418 -22.247098)
		(width 0.4572)
		(layer "F.Cu")
		(net "GND")
	)
	(segment
		(start 366.63249 -392.1252)
		(end 367.16589 -392.1252)
		(width 0.254)
		(layer "F.Cu")
		(net "GND")
	)
	(segment
		(start 129.63779 -245.560342)
		(end 130.104642 -245.294404)
		(width 0.350012)
		(layer "F.Cu")
		(net "GND")
	)
	(segment
		(start 100.327968 -269.770352)
		(end 99.861116 -270.03629)
		(width 0.350012)
		(layer "F.Cu")
		(net "GND")
	)
	(segment
		(start 427.765718 -7.215886)
		(end 427.766988 -7.217156)
		(width 0.3556)
		(layer "F.Cu")
		(net "GND")
	)
	(segment
		(start 101.82987 -406.03424)
		(end 101.82987 -405.407114)
		(width 0.3048)
		(layer "F.Cu")
		(net "GND")
	)
	(segment
		(start 55.328058 -231.335326)
		(end 56.712358 -231.335326)
		(width 0.4572)
		(layer "F.Cu")
		(net "GND")
	)
	(segment
		(start 344.678 -252.040136)
		(end 344.211148 -251.774198)
		(width 0.350012)
		(layer "F.Cu")
		(net "GND")
	)
	(segment
		(start 252.827282 -74.44105)
		(end 252.20041 -73.814178)
		(width 0.3556)
		(layer "F.Cu")
		(net "GND")
	)
	(segment
		(start 57.618122 -383.92227)
		(end 57.6707 -384.617722)
		(width 0.254)
		(layer "F.Cu")
		(net "GND")
	)
	(segment
		(start 107.692952 -24.552656)
		(end 107.537504 -24.552656)
		(width 0.381)
		(layer "F.Cu")
		(net "GND")
	)
	(segment
		(start 98.842576 -387.831076)
		(end 99.062286 -387.831076)
		(width 0.254)
		(layer "F.Cu")
		(net "GND")
	)
	(segment
		(start 350.618044 -280.300176)
		(end 350.151192 -280.566114)
		(width 0.350012)
		(layer "F.Cu")
		(net "GND")
	)
	(segment
		(start 333.697834 -268.960092)
		(end 333.230982 -269.22603)
		(width 0.350012)
		(layer "F.Cu")
		(net "GND")
	)
	(segment
		(start 349.378016 -222.880174)
		(end 348.911164 -222.614236)
		(width 0.350012)
		(layer "F.Cu")
		(net "GND")
	)
	(segment
		(start 143.267938 -252.850396)
		(end 143.73479 -252.584458)
		(width 0.350012)
		(layer "F.Cu")
		(net "GND")
	)
	(segment
		(start 366.597946 -286.780224)
		(end 367.064798 -287.045908)
		(width 0.350012)
		(layer "F.Cu")
		(net "GND")
	)
	(segment
		(start 328.998072 -291.640006)
		(end 328.53122 -291.905944)
		(width 0.350012)
		(layer "F.Cu")
		(net "GND")
	)
	(segment
		(start 392.61796 -232.599992)
		(end 393.084812 -232.334054)
		(width 0.350012)
		(layer "F.Cu")
		(net "GND")
	)
	(segment
		(start 151.044148 -391.830814)
		(end 151.044148 -391.37971)
		(width 0.254)
		(layer "F.Cu")
		(net "GND")
	)
	(segment
		(start 99.55784 -234.220258)
		(end 99.090988 -233.95432)
		(width 0.350012)
		(layer "F.Cu")
		(net "GND")
	)
	(segment
		(start 156.945584 -383.402586)
		(end 156.945584 -382.951482)
		(width 0.254)
		(layer "F.Cu")
		(net "GND")
	)
	(segment
		(start 125.970538 -390.160002)
		(end 125.91796 -390.761474)
		(width 0.254)
		(layer "F.Cu")
		(net "GND")
	)
	(segment
		(start 97.037906 -262.480298)
		(end 96.571054 -262.746236)
		(width 0.350012)
		(layer "F.Cu")
		(net "GND")
	)
	(segment
		(start 17.608042 -284.885384)
		(end 18.992342 -284.885384)
		(width 0.4572)
		(layer "F.Cu")
		(net "GND")
	)
	(segment
		(start 389.170672 -398.542002)
		(end 388.491222 -398.542002)
		(width 0.254)
		(layer "F.Cu")
		(net "GND")
	)
	(segment
		(start 140.27785 -291.64026)
		(end 140.744702 -291.906198)
		(width 0.350012)
		(layer "F.Cu")
		(net "GND")
	)
	(segment
		(start 374.11787 -273.820128)
		(end 374.584722 -274.086066)
		(width 0.350012)
		(layer "F.Cu")
		(net "GND")
	)
	(segment
		(start 106.437938 -285.160466)
		(end 105.971086 -285.426404)
		(width 0.350012)
		(layer "F.Cu")
		(net "GND")
	)
	(segment
		(start 102.155498 -180.31079)
		(end 102.155498 -180.615082)
		(width 0.2286)
		(layer "F.Cu")
		(net "GND")
	)
	(segment
		(start 25.519126 -348.79915)
		(end 25.77211 -348.546166)
		(width 0.2286)
		(layer "F.Cu")
		(net "GND")
	)
	(segment
		(start 118.187978 -271.390364)
		(end 118.65483 -271.656302)
		(width 0.350012)
		(layer "F.Cu")
		(net "GND")
	)
	(segment
		(start 27.548332 -12.37488)
		(end 27.548332 -12.374118)
		(width 0.3556)
		(layer "F.Cu")
		(net "GND")
	)
	(segment
		(start 97.04578 -383.402586)
		(end 97.04578 -383.622296)
		(width 0.254)
		(layer "F.Cu")
		(net "GND")
	)
	(segment
		(start 148.644356 -391.37971)
		(end 148.545804 -391.281158)
		(width 0.254)
		(layer "F.Cu")
		(net "GND")
	)
	(segment
		(start 328.227944 -238.270034)
		(end 327.761092 -238.004096)
		(width 0.350012)
		(layer "F.Cu")
		(net "GND")
	)
	(segment
		(start 371.117876 -399.143474)
		(end 370.817902 -399.663158)
		(width 0.254)
		(layer "F.Cu")
		(net "GND")
	)
	(segment
		(start 64.818006 -390.761474)
		(end 64.870584 -390.160002)
		(width 0.254)
		(layer "F.Cu")
		(net "GND")
	)
	(segment
		(start 130.516376 -391.37971)
		(end 130.417824 -391.281158)
		(width 0.254)
		(layer "F.Cu")
		(net "GND")
	)
	(segment
		(start 386.338064 -280.300176)
		(end 386.804916 -280.566114)
		(width 0.350012)
		(layer "F.Cu")
		(net "GND")
	)
	(segment
		(start 202.147932 -287.43529)
		(end 203.532232 -287.43529)
		(width 0.4572)
		(layer "F.Cu")
		(net "GND")
	)
	(segment
		(start 277.192232 -293.384986)
		(end 275.807932 -293.384986)
		(width 0.4572)
		(layer "F.Cu")
		(net "GND")
	)
	(segment
		(start 393.048236 -12.374118)
		(end 393.046966 -12.372848)
		(width 0.3556)
		(layer "F.Cu")
		(net "GND")
	)
	(segment
		(start 427.766988 -11.26998)
		(end 427.766988 -10.16635)
		(width 0.3556)
		(layer "F.Cu")
		(net "GND")
	)
	(segment
		(start 295.724072 -278.085042)
		(end 297.108372 -278.085042)
		(width 0.4572)
		(layer "F.Cu")
		(net "GND")
	)
	(segment
		(start 165.698424 -386.6388)
		(end 165.006274 -386.449062)
		(width 0.254)
		(layer "F.Cu")
		(net "GND")
	)
	(segment
		(start 299.543724 -393.97559)
		(end 299.532294 -393.96416)
		(width 0.254)
		(layer "F.Cu")
		(net "GND")
	)
	(segment
		(start 87.167974 -261.670292)
		(end 86.701122 -261.93623)
		(width 0.350012)
		(layer "F.Cu")
		(net "GND")
	)
	(segment
		(start 351.65538 -433.841652)
		(end 351.03943 -433.841652)
		(width 0.381)
		(layer "F.Cu")
		(net "GND")
	)
	(segment
		(start 361.42803 -269.770098)
		(end 361.894882 -270.036036)
		(width 0.350012)
		(layer "F.Cu")
		(net "GND")
	)
	(segment
		(start 374.417844 -391.333482)
		(end 374.516396 -391.23493)
		(width 0.2032)
		(layer "F.Cu")
		(net "GND")
	)
	(segment
		(start 392.61796 -230.97998)
		(end 393.084812 -230.714296)
		(width 0.350012)
		(layer "F.Cu")
		(net "GND")
	)
	(segment
		(start 89.047828 -274.630388)
		(end 88.580976 -274.896326)
		(width 0.350012)
		(layer "F.Cu")
		(net "GND")
	)
	(segment
		(start 121.477786 -268.960346)
		(end 121.944638 -269.226284)
		(width 0.350012)
		(layer "F.Cu")
		(net "GND")
	)
	(segment
		(start 196.71919 -72.419464)
		(end 196.536564 -72.236838)
		(width 0.3556)
		(layer "F.Cu")
		(net "GND")
	)
	(segment
		(start 370.539518 -32.573468)
		(end 371.155468 -32.573468)
		(width 0.4572)
		(layer "F.Cu")
		(net "GND")
	)
	(segment
		(start 326.992488 -395.22273)
		(end 326.749156 -395.466062)
		(width 0.381)
		(layer "F.Cu")
		(net "GND")
	)
	(segment
		(start 331.987906 -228.550216)
		(end 331.521054 -228.284278)
		(width 0.350012)
		(layer "F.Cu")
		(net "GND")
	)
	(segment
		(start 356.25786 -265.720068)
		(end 355.791008 -265.986006)
		(width 0.350012)
		(layer "F.Cu")
		(net "GND")
	)
	(segment
		(start 51.317906 -382.951482)
		(end 51.416458 -382.85293)
		(width 0.2032)
		(layer "F.Cu")
		(net "GND")
	)
	(segment
		(start 454.61301 -41.105836)
		(end 453.99706 -41.105836)
		(width 0.4572)
		(layer "F.Cu")
		(net "GND")
	)
	(segment
		(start 120.707912 -244.750336)
		(end 121.174764 -244.484398)
		(width 0.350012)
		(layer "F.Cu")
		(net "GND")
	)
	(segment
		(start 123.997974 -256.900426)
		(end 124.464826 -256.634488)
		(width 0.350012)
		(layer "F.Cu")
		(net "GND")
	)
	(segment
		(start 137.627868 -225.310446)
		(end 138.09472 -225.044508)
		(width 0.350012)
		(layer "F.Cu")
		(net "GND")
	)
	(segment
		(start 204.902054 -338.807552)
		(end 205.089506 -338.995004)
		(width 0.4572)
		(layer "F.Cu")
		(net "GND")
	)
	(segment
		(start 301.73295 -354.711)
		(end 300.99 -354.711)
		(width 0.381)
		(layer "F.Cu")
		(net "GND")
	)
	(segment
		(start 381.638048 -286.780224)
		(end 382.1049 -287.046162)
		(width 0.350012)
		(layer "F.Cu")
		(net "GND")
	)
	(segment
		(start 335.108042 -289.209988)
		(end 334.64119 -289.475926)
		(width 0.350012)
		(layer "F.Cu")
		(net "GND")
	)
	(segment
		(start 87.637874 -283.540454)
		(end 87.171022 -283.806392)
		(width 0.350012)
		(layer "F.Cu")
		(net "GND")
	)
	(segment
		(start 140.27785 -262.480298)
		(end 140.744702 -262.746236)
		(width 0.350012)
		(layer "F.Cu")
		(net "GND")
	)
	(segment
		(start 21.70811 -286.585406)
		(end 20.32381 -286.585406)
		(width 0.4572)
		(layer "F.Cu")
		(net "GND")
	)
	(segment
		(start 423.9514 -32.197548)
		(end 424.9674 -32.197548)
		(width 0.4572)
		(layer "F.Cu")
		(net "GND")
	)
	(segment
		(start 369.72113 -397.412972)
		(end 369.72113 -396.712948)
		(width 0.254)
		(layer "F.Cu")
		(net "GND")
	)
	(segment
		(start 92.80779 -295.69029)
		(end 92.340938 -295.956228)
		(width 0.350012)
		(layer "F.Cu")
		(net "GND")
	)
	(segment
		(start 89.218008 -223.40697)
		(end 89.22131 -223.410272)
		(width 0.350012)
		(layer "F.Cu")
		(net "GND")
	)
	(segment
		(start 90.457782 -262.480298)
		(end 89.99093 -262.746236)
		(width 0.350012)
		(layer "F.Cu")
		(net "GND")
	)
	(segment
		(start 330.938632 -411.985714)
		(end 331.165454 -412.212536)
		(width 0.381)
		(layer "F.Cu")
		(net "GND")
	)
	(segment
		(start 350.618044 -275.44014)
		(end 350.151192 -275.706078)
		(width 0.350012)
		(layer "F.Cu")
		(net "GND")
	)
	(segment
		(start 236.599984 -51.565048)
		(end 237.616238 -51.565048)
		(width 0.4572)
		(layer "F.Cu")
		(net "GND")
	)
	(segment
		(start 382.748028 -223.69018)
		(end 383.21488 -223.424242)
		(width 0.350012)
		(layer "F.Cu")
		(net "GND")
	)
	(segment
		(start 409.050744 -140.900658)
		(end 409.050744 -142.009368)
		(width 0.381)
		(layer "F.Cu")
		(net "GND")
	)
	(segment
		(start 368.89309 -396.74673)
		(end 368.682016 -396.813024)
		(width 0.254)
		(layer "F.Cu")
		(net "GND")
	)
	(segment
		(start 345.1479 -243.13007)
		(end 344.681048 -242.864132)
		(width 0.350012)
		(layer "F.Cu")
		(net "GND")
	)
	(segment
		(start 316.718188 -396.710662)
		(end 316.070234 -396.520924)
		(width 0.254)
		(layer "F.Cu")
		(net "GND")
	)
	(segment
		(start 118.357904 -245.560342)
		(end 118.824756 -245.294404)
		(width 0.350012)
		(layer "F.Cu")
		(net "GND")
	)
	(segment
		(start 368.947954 -271.39011)
		(end 369.414806 -271.656048)
		(width 0.350012)
		(layer "F.Cu")
		(net "GND")
	)
	(segment
		(start 104.257856 -229.360476)
		(end 103.791004 -229.094538)
		(width 0.350012)
		(layer "F.Cu")
		(net "GND")
	)
	(segment
		(start 427.456092 -275.535136)
		(end 428.840392 -275.535136)
		(width 0.4572)
		(layer "F.Cu")
		(net "GND")
	)
	(segment
		(start 94.645734 -382.951482)
		(end 94.744286 -382.85293)
		(width 0.254)
		(layer "F.Cu")
		(net "GND")
	)
	(segment
		(start 389.627872 -285.970218)
		(end 390.094724 -286.236156)
		(width 0.350012)
		(layer "F.Cu")
		(net "GND")
	)
	(segment
		(start 146.087846 -225.310446)
		(end 146.554698 -225.044508)
		(width 0.350012)
		(layer "F.Cu")
		(net "GND")
	)
	(segment
		(start 299.82414 -295.935146)
		(end 298.43984 -295.935146)
		(width 0.4572)
		(layer "F.Cu")
		(net "GND")
	)
	(segment
		(start 370.491004 -398.613122)
		(end 369.72113 -398.613122)
		(width 0.254)
		(layer "F.Cu")
		(net "GND")
	)
	(segment
		(start 164.427916 -303.585372)
		(end 165.812216 -303.585372)
		(width 0.4572)
		(layer "F.Cu")
		(net "GND")
	)
	(segment
		(start 183.878982 -35.195002)
		(end 183.878982 -35.836098)
		(width 0.4572)
		(layer "F.Cu")
		(net "GND")
	)
	(segment
		(start 138.397996 -278.680418)
		(end 138.864848 -278.946356)
		(width 0.350012)
		(layer "F.Cu")
		(net "GND")
	)
	(segment
		(start 390.737852 -235.840016)
		(end 391.204704 -235.574078)
		(width 0.350012)
		(layer "F.Cu")
		(net "GND")
	)
	(segment
		(start 431.55616 -211.784946)
		(end 430.17186 -211.784946)
		(width 0.4572)
		(layer "F.Cu")
		(net "GND")
	)
	(segment
		(start 230.026972 -292.961822)
		(end 229.507796 -292.961822)
		(width 0.1778)
		(layer "F.Cu")
		(net "GND")
	)
	(segment
		(start 388.217918 -281.920188)
		(end 388.68477 -282.186126)
		(width 0.350012)
		(layer "F.Cu")
		(net "GND")
	)
	(segment
		(start 392.61796 -235.840016)
		(end 393.084812 -235.574078)
		(width 0.350012)
		(layer "F.Cu")
		(net "GND")
	)
	(segment
		(start 68.42887 -147.81784)
		(end 68.43776 -147.82673)
		(width 0.254)
		(layer "F.Cu")
		(net "GND")
	)
	(segment
		(start 334.109568 -395.613128)
		(end 333.632556 -395.42974)
		(width 0.254)
		(layer "F.Cu")
		(net "GND")
	)
	(segment
		(start 351.805494 -437.875172)
		(end 351.805494 -437.240172)
		(width 0.381)
		(layer "F.Cu")
		(net "GND")
	)
	(segment
		(start 52.870608 -384.617722)
		(end 52.81803 -383.92227)
		(width 0.254)
		(layer "F.Cu")
		(net "GND")
	)
	(segment
		(start 32.695896 -278.085296)
		(end 34.080196 -278.085296)
		(width 0.4572)
		(layer "F.Cu")
		(net "GND")
	)
	(segment
		(start 265.09218 -103.272844)
		(end 264.386314 -103.272844)
		(width 0.381)
		(layer "F.Cu")
		(net "GND")
	)
	(segment
		(start 120.238012 -232.600246)
		(end 120.70461 -232.334308)
		(width 0.350012)
		(layer "F.Cu")
		(net "GND")
	)
	(segment
		(start 103.277162 -387.084062)
		(end 102.793546 -387.084062)
		(width 0.381)
		(layer "F.Cu")
		(net "GND")
	)
	(segment
		(start 90.719148 -390.160002)
		(end 91.398344 -390.160002)
		(width 0.254)
		(layer "F.Cu")
		(net "GND")
	)
	(segment
		(start 279.632156 -99.269296)
		(end 278.666194 -99.269296)
		(width 0.3556)
		(layer "F.Cu")
		(net "GND")
	)
	(segment
		(start 153.698194 -386.6388)
		(end 153.006298 -386.449062)
		(width 0.254)
		(layer "F.Cu")
		(net "GND")
	)
	(segment
		(start 79.34579 -383.92227)
		(end 79.398368 -383.974848)
		(width 0.254)
		(layer "F.Cu")
		(net "GND")
	)
	(segment
		(start 86.88705 -72.39)
		(end 86.88705 -73.13295)
		(width 0.381)
		(layer "F.Cu")
		(net "GND")
	)
	(segment
		(start 348.24543 -391.784586)
		(end 348.24543 -391.333482)
		(width 0.254)
		(layer "F.Cu")
		(net "GND")
	)
	(segment
		(start 402.498306 -392.999722)
		(end 403.090126 -392.999722)
		(width 0.254)
		(layer "F.Cu")
		(net "GND")
	)
	(segment
		(start 104.257856 -226.120452)
		(end 103.791004 -225.854514)
		(width 0.350012)
		(layer "F.Cu")
		(net "GND")
	)
	(segment
		(start 342.158066 -262.480044)
		(end 341.691214 -262.745982)
		(width 0.350012)
		(layer "F.Cu")
		(net "GND")
	)
	(segment
		(start 431.55616 -312.084974)
		(end 430.17186 -312.084974)
		(width 0.4572)
		(layer "F.Cu")
		(net "GND")
	)
	(segment
		(start 50.461926 -349.09379)
		(end 50.461926 -348.79915)
		(width 0.2286)
		(layer "F.Cu")
		(net "GND")
	)
	(segment
		(start 97.97796 -280.30043)
		(end 97.511108 -280.566368)
		(width 0.350012)
		(layer "F.Cu")
		(net "GND")
	)
	(segment
		(start 144.977866 -293.260272)
		(end 145.444718 -293.52621)
		(width 0.350012)
		(layer "F.Cu")
		(net "GND")
	)
	(segment
		(start 338.097876 -234.220004)
		(end 337.631024 -233.954066)
		(width 0.350012)
		(layer "F.Cu")
		(net "GND")
	)
	(segment
		(start 93.445838 -391.281158)
		(end 93.745812 -390.761474)
		(width 0.254)
		(layer "F.Cu")
		(net "GND")
	)
	(segment
		(start 117.517926 -390.761474)
		(end 117.570504 -390.160002)
		(width 0.254)
		(layer "F.Cu")
		(net "GND")
	)
	(segment
		(start 367.645442 -172.62094)
		(end 367.538254 -172.513752)
		(width 0.381)
		(layer "F.Cu")
		(net "GND")
	)
	(segment
		(start 194.604132 -303.585372)
		(end 195.988432 -303.585372)
		(width 0.4572)
		(layer "F.Cu")
		(net "GND")
	)
	(segment
		(start 431.55616 -277.235158)
		(end 430.17186 -277.235158)
		(width 0.4572)
		(layer "F.Cu")
		(net "GND")
	)
	(segment
		(start 87.745824 -390.761474)
		(end 87.798402 -390.160002)
		(width 0.254)
		(layer "F.Cu")
		(net "GND")
	)
	(segment
		(start 340.277958 -273.820128)
		(end 339.811106 -274.086066)
		(width 0.350012)
		(layer "F.Cu")
		(net "GND")
	)
	(segment
		(start 51.642518 -36.820348)
		(end 49.78273 -36.820348)
		(width 0.4572)
		(layer "F.Cu")
		(net "GND")
	)
	(segment
		(start 114.428016 -279.490424)
		(end 114.894614 -279.756362)
		(width 0.350012)
		(layer "F.Cu")
		(net "GND")
	)
	(segment
		(start 374.11787 -264.100056)
		(end 374.584722 -264.365994)
		(width 0.350012)
		(layer "F.Cu")
		(net "GND")
	)
	(segment
		(start 75.112626 -338.058252)
		(end 75.081638 -338.058252)
		(width 0.2286)
		(layer "F.Cu")
		(net "GND")
	)
	(segment
		(start 123.357894 -260.860286)
		(end 123.824746 -261.126224)
		(width 0.350012)
		(layer "F.Cu")
		(net "GND")
	)
	(segment
		(start 85.757766 -280.30043)
		(end 85.290914 -280.566368)
		(width 0.350012)
		(layer "F.Cu")
		(net "GND")
	)
	(segment
		(start 318.47028 -398.542002)
		(end 317.791084 -398.542002)
		(width 0.254)
		(layer "F.Cu")
		(net "GND")
	)
	(segment
		(start 126.347982 -247.99036)
		(end 126.814834 -247.724422)
		(width 0.350012)
		(layer "F.Cu")
		(net "GND")
	)
	(segment
		(start 23.916132 -333.038704)
		(end 23.80361 -333.151226)
		(width 0.254)
		(layer "F.Cu")
		(net "GND")
	)
	(segment
		(start 319.67043 -395.0208)
		(end 318.97828 -394.831062)
		(width 0.254)
		(layer "F.Cu")
		(net "GND")
	)
	(segment
		(start 419.912038 -294.235124)
		(end 421.296338 -294.235124)
		(width 0.4572)
		(layer "F.Cu")
		(net "GND")
	)
	(segment
		(start 122.117866 -256.900426)
		(end 122.584718 -256.634488)
		(width 0.350012)
		(layer "F.Cu")
		(net "GND")
	)
	(segment
		(start 380.71806 -392.30427)
		(end 380.770638 -392.999722)
		(width 0.254)
		(layer "F.Cu")
		(net "GND")
	)
	(segment
		(start 343.56802 -294.070024)
		(end 343.101168 -294.335962)
		(width 0.350012)
		(layer "F.Cu")
		(net "GND")
	)
	(segment
		(start 305.418998 -47.037498)
		(end 304.803048 -47.037498)
		(width 0.381)
		(layer "F.Cu")
		(net "GND")
	)
	(segment
		(start 103.147876 -290.830254)
		(end 102.681024 -291.096192)
		(width 0.350012)
		(layer "F.Cu")
		(net "GND")
	)
	(segment
		(start 88.747854 -230.170228)
		(end 88.281002 -229.90429)
		(width 0.350012)
		(layer "F.Cu")
		(net "GND")
	)
	(segment
		(start 417.861242 -158.617412)
		(end 418.023802 -158.779972)
		(width 0.381)
		(layer "F.Cu")
		(net "GND")
	)
	(segment
		(start 374.28805 -243.13007)
		(end 374.754902 -242.864132)
		(width 0.350012)
		(layer "F.Cu")
		(net "GND")
	)
	(segment
		(start 348.268036 -282.730194)
		(end 347.801184 -282.996132)
		(width 0.350012)
		(layer "F.Cu")
		(net "GND")
	)
	(segment
		(start 129.938018 -273.820382)
		(end 130.40487 -274.08632)
		(width 0.350012)
		(layer "F.Cu")
		(net "GND")
	)
	(segment
		(start 147.82419 -96.412558)
		(end 147.16379 -96.412558)
		(width 0.4064)
		(layer "F.Cu")
		(net "GND")
	)
	(segment
		(start 164.427916 -221.985332)
		(end 165.812216 -221.985332)
		(width 0.4572)
		(layer "F.Cu")
		(net "GND")
	)
	(segment
		(start 176.072038 -274.685252)
		(end 174.687738 -274.685252)
		(width 0.4572)
		(layer "F.Cu")
		(net "GND")
	)
	(segment
		(start 387.831076 -51.1175)
		(end 388.462266 -51.1175)
		(width 0.4572)
		(layer "F.Cu")
		(net "GND")
	)
	(segment
		(start 80.757776 -235.84027)
		(end 80.291178 -235.574332)
		(width 0.350012)
		(layer "F.Cu")
		(net "GND")
	)
	(segment
		(start 124.297948 -278.680418)
		(end 124.7648 -278.946356)
		(width 0.350012)
		(layer "F.Cu")
		(net "GND")
	)
	(segment
		(start 335.577942 -291.640006)
		(end 335.11109 -291.905944)
		(width 0.350012)
		(layer "F.Cu")
		(net "GND")
	)
	(segment
		(start 117.888004 -247.99036)
		(end 118.354856 -247.724422)
		(width 0.350012)
		(layer "F.Cu")
		(net "GND")
	)
	(segment
		(start 89.987882 -268.15034)
		(end 89.52103 -268.416278)
		(width 0.350012)
		(layer "F.Cu")
		(net "GND")
	)
	(segment
		(start 62.216538 -391.37971)
		(end 62.117986 -391.281158)
		(width 0.254)
		(layer "F.Cu")
		(net "GND")
	)
	(segment
		(start 106.168698 -19.990562)
		(end 107.821222 -19.990562)
		(width 0.381)
		(layer "F.Cu")
		(net "GND")
	)
	(segment
		(start 378.347986 -276.250146)
		(end 378.814838 -276.516084)
		(width 0.350012)
		(layer "F.Cu")
		(net "GND")
	)
	(segment
		(start 77.143356 -175.03013)
		(end 77.042518 -175.273462)
		(width 0.2286)
		(layer "F.Cu")
		(net "GND")
	)
	(segment
		(start 354.378006 -285.160212)
		(end 353.911154 -285.42615)
		(width 0.350012)
		(layer "F.Cu")
		(net "GND")
	)
	(segment
		(start 379.457966 -229.360222)
		(end 379.924818 -229.094284)
		(width 0.350012)
		(layer "F.Cu")
		(net "GND")
	)
	(segment
		(start 341.398098 -398.542002)
		(end 340.718902 -398.542002)
		(width 0.254)
		(layer "F.Cu")
		(net "GND")
	)
	(segment
		(start 137.954004 -167.57015)
		(end 138.013948 -167.510206)
		(width 0.4572)
		(layer "F.Cu")
		(net "GND")
	)
	(segment
		(start 77.767942 -281.110436)
		(end 77.112876 -281.110436)
		(width 0.350012)
		(layer "F.Cu")
		(net "GND")
	)
	(segment
		(start 349.847916 -256.090166)
		(end 349.381064 -255.824228)
		(width 0.350012)
		(layer "F.Cu")
		(net "GND")
	)
	(segment
		(start 454.188068 -314.635134)
		(end 452.803768 -314.635134)
		(width 0.4572)
		(layer "F.Cu")
		(net "GND")
	)
	(segment
		(start 139.977876 -242.320318)
		(end 140.444728 -242.05438)
		(width 0.350012)
		(layer "F.Cu")
		(net "GND")
	)
	(segment
		(start 53.816504 -391.37971)
		(end 53.717952 -391.281158)
		(width 0.254)
		(layer "F.Cu")
		(net "GND")
	)
	(segment
		(start 118.767098 -169.845482)
		(end 118.514114 -170.098466)
		(width 0.2286)
		(layer "F.Cu")
		(net "GND")
	)
	(segment
		(start 363.778038 -278.680164)
		(end 364.24489 -278.946102)
		(width 0.350012)
		(layer "F.Cu")
		(net "GND")
	)
	(segment
		(start 353.137978 -239.08004)
		(end 352.671126 -238.814102)
		(width 0.350012)
		(layer "F.Cu")
		(net "GND")
	)
	(segment
		(start 137.186924 -166.96055)
		(end 137.186924 -167.57015)
		(width 0.381)
		(layer "F.Cu")
		(net "GND")
	)
	(segment
		(start 80.245712 -391.281158)
		(end 80.344264 -391.37971)
		(width 0.254)
		(layer "F.Cu")
		(net "GND")
	)
	(segment
		(start 305.862228 -392.999722)
		(end 305.270408 -392.999722)
		(width 0.254)
		(layer "F.Cu")
		(net "GND")
	)
	(segment
		(start 363.00791 -239.890046)
		(end 363.474762 -239.624108)
		(width 0.350012)
		(layer "F.Cu")
		(net "GND")
	)
	(segment
		(start 139.507976 -236.650276)
		(end 139.974828 -236.384338)
		(width 0.350012)
		(layer "F.Cu")
		(net "GND")
	)
	(segment
		(start 351.087944 -289.209988)
		(end 350.621092 -289.475926)
		(width 0.350012)
		(layer "F.Cu")
		(net "GND")
	)
	(segment
		(start 136.217914 -253.660402)
		(end 136.684766 -253.394464)
		(width 0.350012)
		(layer "F.Cu")
		(net "GND")
	)
	(segment
		(start 169.263568 -429.798734)
		(end 168.963848 -429.499014)
		(width 0.381)
		(layer "F.Cu")
		(net "GND")
	)
	(segment
		(start 388.217918 -283.5402)
		(end 388.68477 -283.806138)
		(width 0.350012)
		(layer "F.Cu")
		(net "GND")
	)
	(segment
		(start 328.697844 -239.08004)
		(end 328.231246 -238.814102)
		(width 0.350012)
		(layer "F.Cu")
		(net "GND")
	)
	(segment
		(start 368.0079 -292.450012)
		(end 368.474752 -292.71595)
		(width 0.350012)
		(layer "F.Cu")
		(net "GND")
	)
	(segment
		(start 422.162224 -396.813024)
		(end 421.942514 -396.813024)
		(width 0.254)
		(layer "F.Cu")
		(net "GND")
	)
	(segment
		(start 332.071472 -394.800074)
		(end 332.071472 -393.97559)
		(width 0.254)
		(layer "F.Cu")
		(net "GND")
	)
	(segment
		(start 117.094 -418.35705)
		(end 117.094 -419.1)
		(width 0.381)
		(layer "F.Cu")
		(net "GND")
	)
	(segment
		(start 47.875444 -421.231314)
		(end 48.321468 -420.78529)
		(width 0.381)
		(layer "F.Cu")
		(net "GND")
	)
	(segment
		(start 49.666906 -12.372848)
		(end 49.666906 -11.26998)
		(width 0.3556)
		(layer "F.Cu")
		(net "GND")
	)
	(segment
		(start 372.407942 -252.850142)
		(end 372.874794 -252.584204)
		(width 0.350012)
		(layer "F.Cu")
		(net "GND")
	)
	(segment
		(start 416.558222 -12.37488)
		(end 416.558222 -12.374118)
		(width 0.3556)
		(layer "F.Cu")
		(net "GND")
	)
	(segment
		(start 307.317648 -391.784586)
		(end 307.317648 -392.004042)
		(width 0.2032)
		(layer "F.Cu")
		(net "GND")
	)
	(segment
		(start 43.85691 -8.320024)
		(end 43.85691 -9.423654)
		(width 0.3556)
		(layer "F.Cu")
		(net "GND")
	)
	(segment
		(start 146.087846 -235.030264)
		(end 146.742912 -235.030264)
		(width 0.350012)
		(layer "F.Cu")
		(net "GND")
	)
	(segment
		(start 18.54581 -7.215124)
		(end 18.54581 -7.215886)
		(width 0.3556)
		(layer "F.Cu")
		(net "GND")
	)
	(segment
		(start 141.687804 -273.010376)
		(end 142.154656 -273.276314)
		(width 0.350012)
		(layer "F.Cu")
		(net "GND")
	)
	(segment
		(start 13.796518 -133.789166)
		(end 13.546582 -134.039102)
		(width 0.254)
		(layer "F.Cu")
		(net "GND")
	)
	(segment
		(start 336.218022 -250.420124)
		(end 335.75117 -250.154186)
		(width 0.350012)
		(layer "F.Cu")
		(net "GND")
	)
	(segment
		(start 325.736712 -395.466062)
		(end 326.26554 -395.466062)
		(width 0.381)
		(layer "F.Cu")
		(net "GND")
	)
	(segment
		(start 168.394634 -428.452788)
		(end 168.963848 -429.022002)
		(width 0.381)
		(layer "F.Cu")
		(net "GND")
	)
	(segment
		(start 415.090102 -392.999722)
		(end 415.698178 -392.999722)
		(width 0.254)
		(layer "F.Cu")
		(net "GND")
	)
	(segment
		(start 360.657902 -242.320064)
		(end 361.124754 -242.054126)
		(width 0.350012)
		(layer "F.Cu")
		(net "GND")
	)
	(segment
		(start 392.61796 -255.28016)
		(end 393.084812 -255.014222)
		(width 0.350012)
		(layer "F.Cu")
		(net "GND")
	)
	(segment
		(start 307.368194 -209.23504)
		(end 305.983894 -209.23504)
		(width 0.4572)
		(layer "F.Cu")
		(net "GND")
	)
	(segment
		(start 118.187978 -273.010376)
		(end 118.65483 -273.276314)
		(width 0.350012)
		(layer "F.Cu")
		(net "GND")
	)
	(segment
		(start 126.647956 -269.770352)
		(end 127.114808 -270.03629)
		(width 0.350012)
		(layer "F.Cu")
		(net "GND")
	)
	(segment
		(start 389.327898 -251.23013)
		(end 389.79475 -250.964192)
		(width 0.350012)
		(layer "F.Cu")
		(net "GND")
	)
	(segment
		(start 370.828062 -292.450012)
		(end 371.294914 -292.71595)
		(width 0.350012)
		(layer "F.Cu")
		(net "GND")
	)
	(segment
		(start 44.340018 -284.035246)
		(end 42.955718 -284.035246)
		(width 0.4572)
		(layer "F.Cu")
		(net "GND")
	)
	(segment
		(start 329.023472 -390.652)
		(end 329.297792 -390.92632)
		(width 0.254)
		(layer "F.Cu")
		(net "GND")
	)
	(segment
		(start 100.497894 -252.04039)
		(end 100.031042 -251.774452)
		(width 0.350012)
		(layer "F.Cu")
		(net "GND")
	)
	(segment
		(start 92.33789 -290.020248)
		(end 91.871038 -290.286186)
		(width 0.350012)
		(layer "F.Cu")
		(net "GND")
	)
	(segment
		(start 394.84808 -12.374118)
		(end 394.84681 -12.372848)
		(width 0.3556)
		(layer "F.Cu")
		(net "GND")
	)
	(segment
		(start 48.478694 -32.677608)
		(end 47.821088 -32.677608)
		(width 0.4572)
		(layer "F.Cu")
		(net "GND")
	)
	(segment
		(start 346.557854 -247.1801)
		(end 346.091002 -246.914162)
		(width 0.350012)
		(layer "F.Cu")
		(net "GND")
	)
	(segment
		(start 69.2023 -30.519116)
		(end 69.2023 -29.319728)
		(width 0.254)
		(layer "F.Cu")
		(net "GND")
	)
	(segment
		(start 405.490172 -392.999722)
		(end 406.098248 -392.999722)
		(width 0.254)
		(layer "F.Cu")
		(net "GND")
	)
	(segment
		(start 330.408026 -263.29005)
		(end 329.941174 -263.555988)
		(width 0.350012)
		(layer "F.Cu")
		(net "GND")
	)
	(segment
		(start 320.870326 -392.999722)
		(end 320.26225 -392.999722)
		(width 0.254)
		(layer "F.Cu")
		(net "GND")
	)
	(segment
		(start 303.268126 -219.435172)
		(end 304.652426 -219.435172)
		(width 0.4572)
		(layer "F.Cu")
		(net "GND")
	)
	(segment
		(start 345.447874 -284.350206)
		(end 344.981022 -284.616144)
		(width 0.350012)
		(layer "F.Cu")
		(net "GND")
	)
	(segment
		(start 392.917934 -290.019994)
		(end 393.384786 -290.285932)
		(width 0.350012)
		(layer "F.Cu")
		(net "GND")
	)
	(segment
		(start 87.190072 -384.617722)
		(end 86.598252 -384.617722)
		(width 0.254)
		(layer "F.Cu")
		(net "GND")
	)
	(segment
		(start 126.647956 -264.910316)
		(end 127.114808 -265.176254)
		(width 0.350012)
		(layer "F.Cu")
		(net "GND")
	)
	(segment
		(start 321.51828 -396.710662)
		(end 320.870326 -396.520924)
		(width 0.254)
		(layer "F.Cu")
		(net "GND")
	)
	(segment
		(start 334.808068 -251.23013)
		(end 334.341216 -250.964192)
		(width 0.350012)
		(layer "F.Cu")
		(net "GND")
	)
	(segment
		(start 124.467874 -251.230384)
		(end 124.934726 -250.964446)
		(width 0.350012)
		(layer "F.Cu")
		(net "GND")
	)
	(segment
		(start 114.491008 -390.231122)
		(end 113.721134 -390.231122)
		(width 0.254)
		(layer "F.Cu")
		(net "GND")
	)
	(segment
		(start 84.347812 -269.770352)
		(end 83.88096 -270.03629)
		(width 0.350012)
		(layer "F.Cu")
		(net "GND")
	)
	(segment
		(start 346.858082 -270.580104)
		(end 346.39123 -270.846042)
		(width 0.350012)
		(layer "F.Cu")
		(net "GND")
	)
	(segment
		(start 420.156894 -12.372848)
		(end 420.156894 -11.26998)
		(width 0.3556)
		(layer "F.Cu")
		(net "GND")
	)
	(segment
		(start 147.018756 -390.231122)
		(end 146.248882 -390.231122)
		(width 0.254)
		(layer "F.Cu")
		(net "GND")
	)
	(segment
		(start 146.248882 -390.231122)
		(end 146.248882 -390.564624)
		(width 0.254)
		(layer "F.Cu")
		(net "GND")
	)
	(segment
		(start 341.857838 -240.700052)
		(end 341.390986 -240.434114)
		(width 0.350012)
		(layer "F.Cu")
		(net "GND")
	)
	(segment
		(start 405.745696 -391.784586)
		(end 405.745696 -391.333482)
		(width 0.254)
		(layer "F.Cu")
		(net "GND")
	)
	(segment
		(start 82.467958 -273.010376)
		(end 82.001106 -273.276314)
		(width 0.350012)
		(layer "F.Cu")
		(net "GND")
	)
	(segment
		(start 405.64689 -10.16635)
		(end 405.64562 -10.16508)
		(width 0.3556)
		(layer "F.Cu")
		(net "GND")
	)
	(segment
		(start 273.092164 -203.28509)
		(end 274.476464 -203.28509)
		(width 0.4572)
		(layer "F.Cu")
		(net "GND")
	)
	(segment
		(start 370.357908 -281.920188)
		(end 370.82476 -282.186126)
		(width 0.350012)
		(layer "F.Cu")
		(net "GND")
	)
	(segment
		(start 343.56802 -269.770098)
		(end 343.101168 -270.036036)
		(width 0.350012)
		(layer "F.Cu")
		(net "GND")
	)
	(segment
		(start 55.065676 -7.215124)
		(end 55.065676 -7.215886)
		(width 0.3556)
		(layer "F.Cu")
		(net "GND")
	)
	(segment
		(start 120.537986 -288.400236)
		(end 121.004838 -288.666174)
		(width 0.350012)
		(layer "F.Cu")
		(net "GND")
	)
	(segment
		(start 106.437938 -265.720322)
		(end 105.971086 -265.98626)
		(width 0.350012)
		(layer "F.Cu")
		(net "GND")
	)
	(segment
		(start 373.17807 -260.860032)
		(end 373.644922 -261.12597)
		(width 0.350012)
		(layer "F.Cu")
		(net "GND")
	)
	(segment
		(start 339.845396 -391.333482)
		(end 339.943948 -391.23493)
		(width 0.2032)
		(layer "F.Cu")
		(net "GND")
	)
	(segment
		(start 115.067842 -230.170228)
		(end 115.534694 -229.90429)
		(width 0.350012)
		(layer "F.Cu")
		(net "GND")
	)
	(segment
		(start 410.722318 -142.287498)
		(end 410.365702 -142.644114)
		(width 0.1778)
		(layer "F.Cu")
		(net "GND")
	)
	(segment
		(start 389.71474 -392.913108)
		(end 389.414766 -393.213082)
		(width 0.254)
		(layer "F.Cu")
		(net "GND")
	)
	(segment
		(start 340.277958 -272.200116)
		(end 339.811106 -272.466054)
		(width 0.350012)
		(layer "F.Cu")
		(net "GND")
	)
	(segment
		(start 375.057924 -286.780224)
		(end 375.524776 -287.045908)
		(width 0.350012)
		(layer "F.Cu")
		(net "GND")
	)
	(segment
		(start 112.717834 -232.600246)
		(end 113.184686 -232.334308)
		(width 0.350012)
		(layer "F.Cu")
		(net "GND")
	)
	(segment
		(start 63.670688 -384.617722)
		(end 64.262508 -384.617722)
		(width 0.254)
		(layer "F.Cu")
		(net "GND")
	)
	(segment
		(start 90.457782 -270.580358)
		(end 89.99093 -270.846296)
		(width 0.350012)
		(layer "F.Cu")
		(net "GND")
	)
	(segment
		(start 149.7457 -382.951482)
		(end 149.844252 -382.85293)
		(width 0.254)
		(layer "F.Cu")
		(net "GND")
	)
	(segment
		(start 141.38783 -252.850396)
		(end 141.854682 -252.584458)
		(width 0.350012)
		(layer "F.Cu")
		(net "GND")
	)
	(segment
		(start 304.917856 -391.784586)
		(end 304.917856 -392.004296)
		(width 0.254)
		(layer "F.Cu")
		(net "GND")
	)
	(segment
		(start 283.386022 -351.927922)
		(end 283.455872 -351.858072)
		(width 0.381)
		(layer "F.Cu")
		(net "GND")
	)
	(segment
		(start 302.620934 -398.01292)
		(end 302.620934 -397.412972)
		(width 0.254)
		(layer "F.Cu")
		(net "GND")
	)
	(segment
		(start 124.937774 -247.180354)
		(end 125.404626 -246.914416)
		(width 0.350012)
		(layer "F.Cu")
		(net "GND")
	)
	(segment
		(start 238.452152 -69.17436)
		(end 239.461802 -69.17436)
		(width 0.3556)
		(layer "F.Cu")
		(net "GND")
	)
	(segment
		(start 90.457782 -268.960346)
		(end 89.99093 -269.226284)
		(width 0.350012)
		(layer "F.Cu")
		(net "GND")
	)
	(segment
		(start 206.248 -305.285394)
		(end 204.8637 -305.285394)
		(width 0.4572)
		(layer "F.Cu")
		(net "GND")
	)
	(segment
		(start 389.627872 -277.870158)
		(end 390.094724 -278.136096)
		(width 0.350012)
		(layer "F.Cu")
		(net "GND")
	)
	(segment
		(start 138.098022 -252.04039)
		(end 138.564874 -251.774452)
		(width 0.350012)
		(layer "F.Cu")
		(net "GND")
	)
	(segment
		(start 332.28788 -289.209988)
		(end 331.821028 -289.475926)
		(width 0.350012)
		(layer "F.Cu")
		(net "GND")
	)
	(segment
		(start 304.01895 -363.982)
		(end 303.276 -363.982)
		(width 0.381)
		(layer "F.Cu")
		(net "GND")
	)
	(segment
		(start 381.638048 -278.680164)
		(end 382.1049 -278.946102)
		(width 0.350012)
		(layer "F.Cu")
		(net "GND")
	)
	(segment
		(start 146.029426 -387.231128)
		(end 146.248882 -387.231128)
		(width 0.254)
		(layer "F.Cu")
		(net "GND")
	)
	(segment
		(start 194.604132 -315.485272)
		(end 195.988432 -315.485272)
		(width 0.4572)
		(layer "F.Cu")
		(net "GND")
	)
	(segment
		(start 456.250294 -47.769272)
		(end 456.250294 -48.191928)
		(width 0.254)
		(layer "F.Cu")
		(net "GND")
	)
	(segment
		(start 83.577938 -243.94033)
		(end 83.111086 -243.674392)
		(width 0.350012)
		(layer "F.Cu")
		(net "GND")
	)
	(segment
		(start 104.596438 -20.084542)
		(end 106.074718 -20.084542)
		(width 0.381)
		(layer "F.Cu")
		(net "GND")
	)
	(segment
		(start 353.045522 -391.784586)
		(end 353.045522 -391.333482)
		(width 0.254)
		(layer "F.Cu")
		(net "GND")
	)
	(segment
		(start 303.268126 -240.685066)
		(end 304.652426 -240.685066)
		(width 0.4572)
		(layer "F.Cu")
		(net "GND")
	)
	(segment
		(start 99.88169 -387.231128)
		(end 99.719638 -387.069076)
		(width 0.254)
		(layer "F.Cu")
		(net "GND")
	)
	(segment
		(start 414.758124 -12.374118)
		(end 414.756854 -12.372848)
		(width 0.3556)
		(layer "F.Cu")
		(net "GND")
	)
	(segment
		(start 335.148682 -398.01292)
		(end 335.148682 -397.412972)
		(width 0.254)
		(layer "F.Cu")
		(net "GND")
	)
	(segment
		(start 310.917844 -391.784586)
		(end 310.917844 -391.333482)
		(width 0.254)
		(layer "F.Cu")
		(net "GND")
	)
	(segment
		(start 97.04578 -383.622296)
		(end 97.345754 -383.92227)
		(width 0.254)
		(layer "F.Cu")
		(net "GND")
	)
	(segment
		(start 424.012106 -221.13494)
		(end 422.627806 -221.13494)
		(width 0.4572)
		(layer "F.Cu")
		(net "GND")
	)
	(segment
		(start 411.745684 -391.333482)
		(end 411.844236 -391.23493)
		(width 0.254)
		(layer "F.Cu")
		(net "GND")
	)
	(segment
		(start 102.207822 -295.69029)
		(end 101.74097 -295.956228)
		(width 0.350012)
		(layer "F.Cu")
		(net "GND")
	)
	(segment
		(start 350.31807 -250.420124)
		(end 349.851218 -250.154186)
		(width 0.350012)
		(layer "F.Cu")
		(net "GND")
	)
	(segment
		(start 80.287876 -252.850396)
		(end 79.821024 -252.584458)
		(width 0.350012)
		(layer "F.Cu")
		(net "GND")
	)
	(segment
		(start 368.17808 -240.700052)
		(end 368.644678 -240.434114)
		(width 0.350012)
		(layer "F.Cu")
		(net "GND")
	)
	(segment
		(start 456.737466 -103.646224)
		(end 456.051666 -103.646224)
		(width 0.3556)
		(layer "F.Cu")
		(net "GND")
	)
	(segment
		(start 343.56802 -273.010122)
		(end 343.101168 -273.27606)
		(width 0.350012)
		(layer "F.Cu")
		(net "GND")
	)
	(segment
		(start 277.192232 -284.034992)
		(end 275.807932 -284.034992)
		(width 0.4572)
		(layer "F.Cu")
		(net "GND")
	)
	(segment
		(start 377.878086 -277.060152)
		(end 378.344938 -277.32609)
		(width 0.350012)
		(layer "F.Cu")
		(net "GND")
	)
	(segment
		(start 345.447874 -271.39011)
		(end 344.981022 -271.656048)
		(width 0.350012)
		(layer "F.Cu")
		(net "GND")
	)
	(segment
		(start 119.418354 -388.328662)
		(end 118.770654 -388.138924)
		(width 0.254)
		(layer "F.Cu")
		(net "GND")
	)
	(segment
		(start 362.334302 -414.779206)
		(end 362.334302 -415.130742)
		(width 0.381)
		(layer "F.Cu")
		(net "GND")
	)
	(segment
		(start 354.245418 -391.784586)
		(end 354.34397 -391.686034)
		(width 0.254)
		(layer "F.Cu")
		(net "GND")
	)
	(segment
		(start 233.523536 -140.855192)
		(end 232.30205 -142.076678)
		(width 0.4572)
		(layer "F.Cu")
		(net "GND")
	)
	(segment
		(start 386.770626 -398.542002)
		(end 386.091176 -398.542002)
		(width 0.254)
		(layer "F.Cu")
		(net "GND")
	)
	(segment
		(start 421.729154 -392.999722)
		(end 421.729154 -392.387836)
		(width 0.254)
		(layer "F.Cu")
		(net "GND")
	)
	(segment
		(start 353.907852 -269.770098)
		(end 353.441 -270.036036)
		(width 0.350012)
		(layer "F.Cu")
		(net "GND")
	)
	(segment
		(start 58.138568 -351.10547)
		(end 58.138568 -351.736406)
		(width 0.381)
		(layer "F.Cu")
		(net "GND")
	)
	(segment
		(start 416.468052 -239.835182)
		(end 415.083752 -239.835182)
		(width 0.4572)
		(layer "F.Cu")
		(net "GND")
	)
	(segment
		(start 113.017808 -270.580358)
		(end 113.48466 -270.846296)
		(width 0.350012)
		(layer "F.Cu")
		(net "GND")
	)
	(segment
		(start 99.4664 -31.259272)
		(end 99.4664 -30.779212)
		(width 0.381)
		(layer "F.Cu")
		(net "GND")
	)
	(segment
		(start 343.118694 -398.542002)
		(end 342.597994 -398.542002)
		(width 0.254)
		(layer "F.Cu")
		(net "GND")
	)
	(segment
		(start 32.695896 -210.085432)
		(end 34.080196 -210.085432)
		(width 0.4572)
		(layer "F.Cu")
		(net "GND")
	)
	(segment
		(start 117.41785 -235.84027)
		(end 117.884702 -235.574332)
		(width 0.350012)
		(layer "F.Cu")
		(net "GND")
	)
	(segment
		(start 87.3379 -248.800366)
		(end 86.871048 -248.534428)
		(width 0.350012)
		(layer "F.Cu")
		(net "GND")
	)
	(segment
		(start 328.227944 -251.23013)
		(end 327.761092 -250.964192)
		(width 0.350012)
		(layer "F.Cu")
		(net "GND")
	)
	(segment
		(start 344.99804 -392.999722)
		(end 344.945462 -392.30427)
		(width 0.254)
		(layer "F.Cu")
		(net "GND")
	)
	(segment
		(start 51.884072 -312.085228)
		(end 50.499772 -312.085228)
		(width 0.4572)
		(layer "F.Cu")
		(net "GND")
	)
	(segment
		(start 344.678 -227.74021)
		(end 344.211148 -227.474272)
		(width 0.350012)
		(layer "F.Cu")
		(net "GND")
	)
	(segment
		(start 404.346156 -396.710662)
		(end 403.698202 -396.520924)
		(width 0.254)
		(layer "F.Cu")
		(net "GND")
	)
	(segment
		(start 376.167904 -231.789986)
		(end 376.634756 -231.524048)
		(width 0.350012)
		(layer "F.Cu")
		(net "GND")
	)
	(segment
		(start 101.437948 -235.84027)
		(end 100.971096 -235.574332)
		(width 0.350012)
		(layer "F.Cu")
		(net "GND")
	)
	(segment
		(start 163.465002 -353.052888)
		(end 163.465002 -353.715574)
		(width 0.381)
		(layer "F.Cu")
		(net "GND")
	)
	(segment
		(start 40.23995 -294.235378)
		(end 41.62425 -294.235378)
		(width 0.4572)
		(layer "F.Cu")
		(net "GND")
	)
	(segment
		(start 442.5442 -219.435172)
		(end 443.9285 -219.435172)
		(width 0.4572)
		(layer "F.Cu")
		(net "GND")
	)
	(segment
		(start 141.687804 -285.970472)
		(end 142.154656 -286.23641)
		(width 0.350012)
		(layer "F.Cu")
		(net "GND")
	)
	(segment
		(start 52.870608 -386.6388)
		(end 52.178458 -386.449062)
		(width 0.254)
		(layer "F.Cu")
		(net "GND")
	)
	(segment
		(start 117.888004 -235.030264)
		(end 118.354856 -234.764326)
		(width 0.350012)
		(layer "F.Cu")
		(net "GND")
	)
	(segment
		(start 139.83716 -387.83514)
		(end 139.83716 -387.622796)
		(width 0.254)
		(layer "F.Cu")
		(net "GND")
	)
	(segment
		(start 412.367984 -287.435036)
		(end 413.752284 -287.435036)
		(width 0.4572)
		(layer "F.Cu")
		(net "GND")
	)
	(segment
		(start 129.217928 -383.402586)
		(end 129.217928 -383.622296)
		(width 0.254)
		(layer "F.Cu")
		(net "GND")
	)
	(segment
		(start 280.635964 -296.78503)
		(end 282.020264 -296.78503)
		(width 0.4572)
		(layer "F.Cu")
		(net "GND")
	)
	(segment
		(start 382.748028 -231.789986)
		(end 383.21488 -231.524048)
		(width 0.350012)
		(layer "F.Cu")
		(net "GND")
	)
	(segment
		(start 85.457792 -232.600246)
		(end 84.99094 -232.334308)
		(width 0.350012)
		(layer "F.Cu")
		(net "GND")
	)
	(segment
		(start 372.238016 -273.820128)
		(end 372.704868 -274.086066)
		(width 0.350012)
		(layer "F.Cu")
		(net "GND")
	)
	(segment
		(start 187.461906 -16.549878)
		(end 187.463176 -16.551148)
		(width 0.3556)
		(layer "F.Cu")
		(net "GND")
	)
	(segment
		(start 131.87299 -112.268)
		(end 132.364226 -112.268)
		(width 0.381)
		(layer "F.Cu")
		(net "GND")
	)
	(segment
		(start 299.532294 -392.1252)
		(end 300.065694 -392.1252)
		(width 0.254)
		(layer "F.Cu")
		(net "GND")
	)
	(segment
		(start 125.68174 -26.916126)
		(end 123.84786 -26.916126)
		(width 0.3556)
		(layer "F.Cu")
		(net "GND")
	)
	(segment
		(start 348.437962 -255.28016)
		(end 347.97111 -255.014222)
		(width 0.350012)
		(layer "F.Cu")
		(net "GND")
	)
	(segment
		(start 347.968062 -247.990106)
		(end 347.50121 -247.724168)
		(width 0.350012)
		(layer "F.Cu")
		(net "GND")
	)
	(segment
		(start 353.437952 -277.060152)
		(end 352.9711 -277.32609)
		(width 0.350012)
		(layer "F.Cu")
		(net "GND")
	)
	(segment
		(start 348.437962 -247.1801)
		(end 347.97111 -246.914162)
		(width 0.350012)
		(layer "F.Cu")
		(net "GND")
	)
	(segment
		(start 115.537996 -240.700306)
		(end 116.004848 -240.434368)
		(width 0.350012)
		(layer "F.Cu")
		(net "GND")
	)
	(segment
		(start 113.187988 -249.610372)
		(end 113.65484 -249.344434)
		(width 0.350012)
		(layer "F.Cu")
		(net "GND")
	)
	(segment
		(start 353.437952 -286.780224)
		(end 352.9711 -287.045908)
		(width 0.350012)
		(layer "F.Cu")
		(net "GND")
	)
	(segment
		(start 105.44556 -66.58991)
		(end 104.82961 -66.58991)
		(width 0.381)
		(layer "F.Cu")
		(net "GND")
	)
	(segment
		(start 380.86792 -238.270034)
		(end 381.334772 -238.004096)
		(width 0.350012)
		(layer "F.Cu")
		(net "GND")
	)
	(segment
		(start 9.949942 -53.904896)
		(end 11.512042 -53.904896)
		(width 0.4572)
		(layer "F.Cu")
		(net "GND")
	)
	(segment
		(start 87.637874 -291.64026)
		(end 87.171022 -291.906198)
		(width 0.350012)
		(layer "F.Cu")
		(net "GND")
	)
	(segment
		(start 284.736032 -227.935028)
		(end 283.351732 -227.935028)
		(width 0.4572)
		(layer "F.Cu")
		(net "GND")
	)
	(segment
		(start 340.198202 -395.0208)
		(end 339.506052 -394.831062)
		(width 0.254)
		(layer "F.Cu")
		(net "GND")
	)
	(segment
		(start 51.416458 -394.705078)
		(end 51.416458 -393.877038)
		(width 0.381)
		(layer "F.Cu")
		(net "GND")
	)
	(segment
		(start 115.537996 -234.220258)
		(end 116.004848 -233.95432)
		(width 0.350012)
		(layer "F.Cu")
		(net "GND")
	)
	(segment
		(start 127.117856 -275.440394)
		(end 127.584708 -275.706332)
		(width 0.350012)
		(layer "F.Cu")
		(net "GND")
	)
	(segment
		(start 348.343982 -399.76171)
		(end 348.24543 -399.663158)
		(width 0.254)
		(layer "F.Cu")
		(net "GND")
	)
	(segment
		(start 377.878086 -260.860032)
		(end 378.344938 -261.12597)
		(width 0.350012)
		(layer "F.Cu")
		(net "GND")
	)
	(segment
		(start 357.197914 -291.640006)
		(end 356.731062 -291.905944)
		(width 0.350012)
		(layer "F.Cu")
		(net "GND")
	)
	(segment
		(start 419.912038 -278.085042)
		(end 421.296338 -278.085042)
		(width 0.4572)
		(layer "F.Cu")
		(net "GND")
	)
	(segment
		(start 136.188958 -62.68212)
		(end 135.406638 -62.68212)
		(width 0.4572)
		(layer "F.Cu")
		(net "GND")
	)
	(segment
		(start 463.062574 -98.564954)
		(end 462.446624 -98.564954)
		(width 0.4572)
		(layer "F.Cu")
		(net "GND")
	)
	(segment
		(start 299.532294 -393.96416)
		(end 300.065694 -393.96416)
		(width 0.254)
		(layer "F.Cu")
		(net "GND")
	)
	(segment
		(start 80.757776 -226.120452)
		(end 80.291178 -225.854514)
		(width 0.350012)
		(layer "F.Cu")
		(net "GND")
	)
	(segment
		(start 313.062112 -392.999722)
		(end 312.470292 -392.999722)
		(width 0.254)
		(layer "F.Cu")
		(net "GND")
	)
	(segment
		(start 387.917944 -239.08004)
		(end 388.384796 -238.814102)
		(width 0.350012)
		(layer "F.Cu")
		(net "GND")
	)
	(segment
		(start 386.338064 -262.480044)
		(end 386.804916 -262.745982)
		(width 0.350012)
		(layer "F.Cu")
		(net "GND")
	)
	(segment
		(start 113.187988 -251.230384)
		(end 113.65484 -250.964446)
		(width 0.350012)
		(layer "F.Cu")
		(net "GND")
	)
	(segment
		(start 380.516384 -399.76171)
		(end 380.417832 -399.663158)
		(width 0.254)
		(layer "F.Cu")
		(net "GND")
	)
	(segment
		(start 394.027914 -228.550216)
		(end 394.494766 -228.284278)
		(width 0.350012)
		(layer "F.Cu")
		(net "GND")
	)
	(segment
		(start 371.938042 -248.800112)
		(end 372.404894 -248.534174)
		(width 0.350012)
		(layer "F.Cu")
		(net "GND")
	)
	(segment
		(start 86.344252 -391.830814)
		(end 86.344252 -391.37971)
		(width 0.254)
		(layer "F.Cu")
		(net "GND")
	)
	(segment
		(start 176.072038 -295.9354)
		(end 174.687738 -295.9354)
		(width 0.4572)
		(layer "F.Cu")
		(net "GND")
	)
	(segment
		(start 98.617786 -229.360476)
		(end 98.150934 -229.094538)
		(width 0.350012)
		(layer "F.Cu")
		(net "GND")
	)
	(segment
		(start 343.56802 -284.350206)
		(end 343.101168 -284.616144)
		(width 0.350012)
		(layer "F.Cu")
		(net "GND")
	)
	(segment
		(start 307.368194 -293.384986)
		(end 305.983894 -293.384986)
		(width 0.4572)
		(layer "F.Cu")
		(net "GND")
	)
	(segment
		(start 342.158066 -281.920188)
		(end 341.691214 -282.186126)
		(width 0.350012)
		(layer "F.Cu")
		(net "GND")
	)
	(segment
		(start 147.345654 -391.281158)
		(end 147.444206 -391.37971)
		(width 0.254)
		(layer "F.Cu")
		(net "GND")
	)
	(segment
		(start 370.057934 -224.500186)
		(end 370.524786 -224.234248)
		(width 0.350012)
		(layer "F.Cu")
		(net "GND")
	)
	(segment
		(start 306.470304 -395.0208)
		(end 305.778408 -394.831062)
		(width 0.254)
		(layer "F.Cu")
		(net "GND")
	)
	(segment
		(start 134.80796 -243.130324)
		(end 135.274812 -242.864386)
		(width 0.350012)
		(layer "F.Cu")
		(net "GND")
	)
	(segment
		(start 377.577858 -224.500186)
		(end 378.04471 -224.234248)
		(width 0.350012)
		(layer "F.Cu")
		(net "GND")
	)
	(segment
		(start 367.504726 -27.504644)
		(end 367.504726 -26.702766)
		(width 0.4572)
		(layer "F.Cu")
		(net "GND")
	)
	(segment
		(start 236.599984 -58.764932)
		(end 237.616238 -58.764932)
		(width 0.381)
		(layer "F.Cu")
		(net "GND")
	)
	(segment
		(start 342.158066 -273.820128)
		(end 341.691214 -274.086066)
		(width 0.350012)
		(layer "F.Cu")
		(net "GND")
	)
	(segment
		(start 308.379622 -351.927922)
		(end 308.449472 -351.858072)
		(width 0.381)
		(layer "F.Cu")
		(net "GND")
	)
	(segment
		(start 187.060078 -296.785284)
		(end 188.444378 -296.785284)
		(width 0.4572)
		(layer "F.Cu")
		(net "GND")
	)
	(segment
		(start 338.56803 -233.409998)
		(end 338.101178 -233.14406)
		(width 0.350012)
		(layer "F.Cu")
		(net "GND")
	)
	(segment
		(start 417.406328 -394.831062)
		(end 416.898328 -395.0208)
		(width 0.254)
		(layer "F.Cu")
		(net "GND")
	)
	(segment
		(start 144.908016 -57.676034)
		(end 144.527016 -58.057034)
		(width 0.1778)
		(layer "F.Cu")
		(net "GND")
	)
	(segment
		(start 358.307894 -223.69018)
		(end 357.841042 -223.424242)
		(width 0.350012)
		(layer "F.Cu")
		(net "GND")
	)
	(segment
		(start 36.795964 -221.135194)
		(end 35.411664 -221.135194)
		(width 0.4572)
		(layer "F.Cu")
		(net "GND")
	)
	(segment
		(start 98.842576 -387.231128)
		(end 98.842576 -387.831076)
		(width 0.254)
		(layer "F.Cu")
		(net "GND")
	)
	(segment
		(start 384.927856 -271.39011)
		(end 385.394708 -271.656048)
		(width 0.350012)
		(layer "F.Cu")
		(net "GND")
	)
	(segment
		(start 178.289458 -51.299872)
		(end 177.108358 -51.299872)
		(width 0.254)
		(layer "F.Cu")
		(net "GND")
	)
	(segment
		(start 129.217928 -383.402586)
		(end 129.217928 -382.951482)
		(width 0.254)
		(layer "F.Cu")
		(net "GND")
	)
	(segment
		(start 356.728014 -287.59023)
		(end 356.261162 -287.856168)
		(width 0.350012)
		(layer "F.Cu")
		(net "GND")
	)
	(segment
		(start 341.687912 -274.630134)
		(end 341.22106 -274.896072)
		(width 0.350012)
		(layer "F.Cu")
		(net "GND")
	)
	(segment
		(start 115.11788 -390.761474)
		(end 114.817906 -391.281158)
		(width 0.254)
		(layer "F.Cu")
		(net "GND")
	)
	(segment
		(start 290.605972 -367.280698)
		(end 290.605972 -368.205512)
		(width 0.381)
		(layer "F.Cu")
		(net "GND")
	)
	(segment
		(start 288.180018 -296.78503)
		(end 289.564318 -296.78503)
		(width 0.4572)
		(layer "F.Cu")
		(net "GND")
	)
	(segment
		(start 5.229098 -133.08838)
		(end 5.403088 -132.91439)
		(width 0.3556)
		(layer "F.Cu")
		(net "GND")
	)
	(segment
		(start 114.428016 -276.2504)
		(end 114.894614 -276.516338)
		(width 0.350012)
		(layer "F.Cu")
		(net "GND")
	)
	(segment
		(start 88.747854 -241.510312)
		(end 88.281002 -241.244374)
		(width 0.350012)
		(layer "F.Cu")
		(net "GND")
	)
	(segment
		(start 85.345778 -390.761474)
		(end 85.045804 -391.281158)
		(width 0.254)
		(layer "F.Cu")
		(net "GND")
	)
	(segment
		(start 116.477796 -250.420378)
		(end 116.944648 -250.15444)
		(width 0.350012)
		(layer "F.Cu")
		(net "GND")
	)
	(segment
		(start 80.58785 -261.670292)
		(end 80.120998 -261.93623)
		(width 0.350012)
		(layer "F.Cu")
		(net "GND")
	)
	(segment
		(start 372.238016 -281.920188)
		(end 372.704868 -282.186126)
		(width 0.350012)
		(layer "F.Cu")
		(net "GND")
	)
	(segment
		(start 110.83798 -222.880428)
		(end 110.371128 -222.61449)
		(width 0.350012)
		(layer "F.Cu")
		(net "GND")
	)
	(segment
		(start 337.627976 -225.310192)
		(end 337.161124 -225.044254)
		(width 0.350012)
		(layer "F.Cu")
		(net "GND")
	)
	(segment
		(start 181.122066 -107.452922)
		(end 180.732176 -107.063032)
		(width 0.254)
		(layer "F.Cu")
		(net "GND")
	)
	(segment
		(start 138.098022 -235.84027)
		(end 138.564874 -235.574332)
		(width 0.350012)
		(layer "F.Cu")
		(net "GND")
	)
	(segment
		(start 338.868004 -285.970218)
		(end 338.401152 -286.236156)
		(width 0.350012)
		(layer "F.Cu")
		(net "GND")
	)
	(segment
		(start 105.66781 -246.370348)
		(end 105.200958 -246.10441)
		(width 0.350012)
		(layer "F.Cu")
		(net "GND")
	)
	(segment
		(start 130.77063 -384.617722)
		(end 130.718052 -383.92227)
		(width 0.254)
		(layer "F.Cu")
		(net "GND")
	)
	(segment
		(start 381.167894 -266.530074)
		(end 381.634746 -266.796012)
		(width 0.350012)
		(layer "F.Cu")
		(net "GND")
	)
	(segment
		(start 102.348284 -139.751816)
		(end 102.348284 -140.18641)
		(width 0.381)
		(layer "F.Cu")
		(net "GND")
	)
	(segment
		(start 187.060078 -221.985332)
		(end 188.444378 -221.985332)
		(width 0.4572)
		(layer "F.Cu")
		(net "GND")
	)
	(segment
		(start 13.206984 -395.248638)
		(end 12.863068 -395.592554)
		(width 0.254)
		(layer "F.Cu")
		(net "GND")
	)
	(segment
		(start 26.484326 -394.733526)
		(end 26.135584 -395.082268)
		(width 0.4572)
		(layer "F.Cu")
		(net "GND")
	)
	(segment
		(start 348.737936 -270.580104)
		(end 348.271084 -270.846042)
		(width 0.350012)
		(layer "F.Cu")
		(net "GND")
	)
	(segment
		(start 382.748028 -235.03001)
		(end 383.21488 -234.764072)
		(width 0.350012)
		(layer "F.Cu")
		(net "GND")
	)
	(segment
		(start 120.707912 -236.650276)
		(end 121.174764 -236.384338)
		(width 0.350012)
		(layer "F.Cu")
		(net "GND")
	)
	(segment
		(start 421.942514 -393.213082)
		(end 421.729154 -392.999722)
		(width 0.254)
		(layer "F.Cu")
		(net "GND")
	)
	(segment
		(start 348.597982 -395.0208)
		(end 347.906086 -394.831062)
		(width 0.254)
		(layer "F.Cu")
		(net "GND")
	)
	(segment
		(start 319.67043 -396.520924)
		(end 319.118234 -396.710662)
		(width 0.254)
		(layer "F.Cu")
		(net "GND")
	)
	(segment
		(start 378.347986 -290.83)
		(end 378.814838 -291.095938)
		(width 0.350012)
		(layer "F.Cu")
		(net "GND")
	)
	(segment
		(start 339.845396 -399.663158)
		(end 340.145624 -399.143474)
		(width 0.254)
		(layer "F.Cu")
		(net "GND")
	)
	(segment
		(start 394.027914 -233.409998)
		(end 394.68298 -233.409998)
		(width 0.350012)
		(layer "F.Cu")
		(net "GND")
	)
	(segment
		(start 82.467958 -285.970472)
		(end 82.001106 -286.23641)
		(width 0.350012)
		(layer "F.Cu")
		(net "GND")
	)
	(segment
		(start 51.467004 -8.320024)
		(end 51.467004 -9.423654)
		(width 0.3556)
		(layer "F.Cu")
		(net "GND")
	)
	(segment
		(start 122.117866 -252.04039)
		(end 122.584718 -251.774452)
		(width 0.350012)
		(layer "F.Cu")
		(net "GND")
	)
	(segment
		(start 385.217924 -392.004296)
		(end 385.517898 -392.30427)
		(width 0.254)
		(layer "F.Cu")
		(net "GND")
	)
	(segment
		(start 123.52782 -247.99036)
		(end 123.994672 -247.724422)
		(width 0.350012)
		(layer "F.Cu")
		(net "GND")
	)
	(segment
		(start 351.007172 -424.279314)
		(end 351.007172 -423.648378)
		(width 0.381)
		(layer "F.Cu")
		(net "GND")
	)
	(segment
		(start 87.167974 -266.530328)
		(end 86.701122 -266.796266)
		(width 0.350012)
		(layer "F.Cu")
		(net "GND")
	)
	(segment
		(start 95.627952 -261.670292)
		(end 95.1611 -261.93623)
		(width 0.350012)
		(layer "F.Cu")
		(net "GND")
	)
	(segment
		(start 93.79839 -388.138924)
		(end 93.246194 -388.328662)
		(width 0.254)
		(layer "F.Cu")
		(net "GND")
	)
	(segment
		(start 11.533124 -52.639214)
		(end 11.537442 -52.634896)
		(width 0.4572)
		(layer "F.Cu")
		(net "GND")
	)
	(segment
		(start 49.778666 -28.707588)
		(end 49.778666 -27.803348)
		(width 0.4572)
		(layer "F.Cu")
		(net "GND")
	)
	(segment
		(start 108.09097 -20.26031)
		(end 108.09097 -20.831556)
		(width 0.381)
		(layer "F.Cu")
		(net "GND")
	)
	(segment
		(start 315.462158 -392.999722)
		(end 316.070234 -392.999722)
		(width 0.254)
		(layer "F.Cu")
		(net "GND")
	)
	(segment
		(start 115.367816 -274.630388)
		(end 115.834668 -274.896326)
		(width 0.350012)
		(layer "F.Cu")
		(net "GND")
	)
	(segment
		(start 239.13592 -292.988238)
		(end 239.13592 -291.863526)
		(width 0.4572)
		(layer "F.Cu")
		(net "GND")
	)
	(segment
		(start 52.770532 -402.878036)
		(end 53.723032 -403.830536)
		(width 0.381)
		(layer "F.Cu")
		(net "GND")
	)
	(segment
		(start 360.957876 -273.820128)
		(end 361.424728 -274.086066)
		(width 0.350012)
		(layer "F.Cu")
		(net "GND")
	)
	(segment
		(start 49.02454 -394.65758)
		(end 49.016412 -394.649452)
		(width 0.381)
		(layer "F.Cu")
		(net "GND")
	)
	(segment
		(start 26.430478 -431.502058)
		(end 26.042366 -431.502058)
		(width 0.3556)
		(layer "F.Cu")
		(net "GND")
	)
	(segment
		(start 112.16005 -407.4668)
		(end 112.808512 -407.4668)
		(width 0.381)
		(layer "F.Cu")
		(net "GND")
	)
	(segment
		(start 318.117728 -391.333482)
		(end 318.21628 -391.23493)
		(width 0.254)
		(layer "F.Cu")
		(net "GND")
	)
	(segment
		(start 138.397996 -275.440394)
		(end 138.864848 -275.706332)
		(width 0.350012)
		(layer "F.Cu")
		(net "GND")
	)
	(segment
		(start 343.268046 -239.890046)
		(end 342.801194 -239.624108)
		(width 0.350012)
		(layer "F.Cu")
		(net "GND")
	)
	(segment
		(start 340.74989 -62.634876)
		(end 339.15604 -62.634876)
		(width 0.4572)
		(layer "F.Cu")
		(net "GND")
	)
	(segment
		(start 386.718048 -392.30427)
		(end 386.41782 -392.004042)
		(width 0.254)
		(layer "F.Cu")
		(net "GND")
	)
	(segment
		(start 308.598316 -431.256186)
		(end 308.598316 -431.887122)
		(width 0.381)
		(layer "F.Cu")
		(net "GND")
	)
	(segment
		(start 133.41477 -384.831082)
		(end 133.41477 -385.21132)
		(width 0.254)
		(layer "F.Cu")
		(net "GND")
	)
	(segment
		(start 56.867044 -7.217156)
		(end 56.867044 -8.320024)
		(width 0.3556)
		(layer "F.Cu")
		(net "GND")
	)
	(segment
		(start 277.192232 -274.684998)
		(end 275.807932 -274.684998)
		(width 0.4572)
		(layer "F.Cu")
		(net "GND")
	)
	(segment
		(start 391.50798 -289.209988)
		(end 391.974832 -289.475926)
		(width 0.350012)
		(layer "F.Cu")
		(net "GND")
	)
	(segment
		(start 338.56803 -236.650022)
		(end 338.101178 -236.384084)
		(width 0.350012)
		(layer "F.Cu")
		(net "GND")
	)
	(segment
		(start 103.147876 -281.110436)
		(end 102.681024 -281.376374)
		(width 0.350012)
		(layer "F.Cu")
		(net "GND")
	)
	(segment
		(start 347.797882 -283.5402)
		(end 347.33103 -283.806138)
		(width 0.350012)
		(layer "F.Cu")
		(net "GND")
	)
	(segment
		(start 131.817872 -285.160466)
		(end 132.284724 -285.426404)
		(width 0.350012)
		(layer "F.Cu")
		(net "GND")
	)
	(segment
		(start 115.367816 -276.2504)
		(end 115.834668 -276.516338)
		(width 0.350012)
		(layer "F.Cu")
		(net "GND")
	)
	(segment
		(start 384.457956 -281.920188)
		(end 384.924808 -282.186126)
		(width 0.350012)
		(layer "F.Cu")
		(net "GND")
	)
	(segment
		(start 371.938042 -240.700052)
		(end 372.404894 -240.434114)
		(width 0.350012)
		(layer "F.Cu")
		(net "GND")
	)
	(segment
		(start 294.821102 -122.349514)
		(end 295.430702 -122.349514)
		(width 0.3556)
		(layer "F.Cu")
		(net "GND")
	)
	(segment
		(start 307.368194 -230.485188)
		(end 305.983894 -230.485188)
		(width 0.4572)
		(layer "F.Cu")
		(net "GND")
	)
	(segment
		(start 332.28788 -264.910062)
		(end 331.821028 -265.176)
		(width 0.350012)
		(layer "F.Cu")
		(net "GND")
	)
	(segment
		(start 55.328058 -312.935366)
		(end 56.712358 -312.935366)
		(width 0.4572)
		(layer "F.Cu")
		(net "GND")
	)
	(segment
		(start 330.408026 -284.350206)
		(end 329.941174 -284.616144)
		(width 0.350012)
		(layer "F.Cu")
		(net "GND")
	)
	(segment
		(start 47.784004 -275.53539)
		(end 49.168304 -275.53539)
		(width 0.4572)
		(layer "F.Cu")
		(net "GND")
	)
	(segment
		(start 161.490152 -384.617722)
		(end 160.898332 -384.617722)
		(width 0.254)
		(layer "F.Cu")
		(net "GND")
	)
	(segment
		(start 218.96705 -100.457)
		(end 218.96705 -101.228398)
		(width 0.381)
		(layer "F.Cu")
		(net "GND")
	)
	(segment
		(start 90.157808 -250.420378)
		(end 89.690956 -250.15444)
		(width 0.350012)
		(layer "F.Cu")
		(net "GND")
	)
	(segment
		(start 337.24596 -396.710662)
		(end 336.598006 -396.520924)
		(width 0.254)
		(layer "F.Cu")
		(net "GND")
	)
	(segment
		(start 305.270408 -395.0208)
		(end 304.578258 -394.831062)
		(width 0.254)
		(layer "F.Cu")
		(net "GND")
	)
	(segment
		(start 381.638048 -264.100056)
		(end 382.1049 -264.365994)
		(width 0.350012)
		(layer "F.Cu")
		(net "GND")
	)
	(segment
		(start 89.047828 -287.590484)
		(end 88.580976 -287.856422)
		(width 0.350012)
		(layer "F.Cu")
		(net "GND")
	)
	(segment
		(start 288.180018 -278.085042)
		(end 289.564318 -278.085042)
		(width 0.4572)
		(layer "F.Cu")
		(net "GND")
	)
	(segment
		(start 93.445838 -383.402586)
		(end 93.445838 -383.622296)
		(width 0.254)
		(layer "F.Cu")
		(net "GND")
	)
	(segment
		(start 81.058004 -267.340334)
		(end 80.591152 -267.606272)
		(width 0.350012)
		(layer "F.Cu")
		(net "GND")
	)
	(segment
		(start 429.649382 -399.72488)
		(end 429.22952 -399.305018)
		(width 0.254)
		(layer "F.Cu")
		(net "GND")
	)
	(segment
		(start 90.927936 -284.35046)
		(end 90.461084 -284.616398)
		(width 0.350012)
		(layer "F.Cu")
		(net "GND")
	)
	(segment
		(start 81.058004 -288.400236)
		(end 80.591152 -288.666174)
		(width 0.350012)
		(layer "F.Cu")
		(net "GND")
	)
	(segment
		(start 386.03809 -222.880174)
		(end 386.504942 -222.614236)
		(width 0.350012)
		(layer "F.Cu")
		(net "GND")
	)
	(segment
		(start 150.102316 -58.236358)
		(end 149.492716 -58.236358)
		(width 0.4572)
		(layer "F.Cu")
		(net "GND")
	)
	(segment
		(start 86.22792 -268.15034)
		(end 85.761068 -268.416278)
		(width 0.350012)
		(layer "F.Cu")
		(net "GND")
	)
	(segment
		(start 107.377992 -281.920442)
		(end 106.91114 -282.18638)
		(width 0.350012)
		(layer "F.Cu")
		(net "GND")
	)
	(segment
		(start 120.707912 -233.410252)
		(end 121.174764 -233.144314)
		(width 0.350012)
		(layer "F.Cu")
		(net "GND")
	)
	(segment
		(start 108.017818 -247.180354)
		(end 107.550966 -246.914416)
		(width 0.350012)
		(layer "F.Cu")
		(net "GND")
	)
	(segment
		(start 12.780772 -411.712918)
		(end 12.342622 -411.712918)
		(width 0.1778)
		(layer "F.Cu")
		(net "GND")
	)
	(segment
		(start 132.715 -109.07395)
		(end 134.38505 -109.07395)
		(width 0.381)
		(layer "F.Cu")
		(net "GND")
	)
	(segment
		(start 418.690044 -392.999722)
		(end 418.098224 -392.999722)
		(width 0.254)
		(layer "F.Cu")
		(net "GND")
	)
	(segment
		(start 284.736032 -293.384986)
		(end 283.351732 -293.384986)
		(width 0.4572)
		(layer "F.Cu")
		(net "GND")
	)
	(segment
		(start 119.71655 -391.830814)
		(end 119.71655 -391.37971)
		(width 0.254)
		(layer "F.Cu")
		(net "GND")
	)
	(segment
		(start 163.867084 -16.549878)
		(end 163.82238 -16.594582)
		(width 0.3556)
		(layer "F.Cu")
		(net "GND")
	)
	(segment
		(start 382.748028 -225.310192)
		(end 383.21488 -225.044254)
		(width 0.350012)
		(layer "F.Cu")
		(net "GND")
	)
	(segment
		(start 375.970546 -395.0208)
		(end 375.278396 -394.831062)
		(width 0.254)
		(layer "F.Cu")
		(net "GND")
	)
	(segment
		(start 142.797784 -240.700306)
		(end 143.264636 -240.434368)
		(width 0.350012)
		(layer "F.Cu")
		(net "GND")
	)
	(segment
		(start 390.28243 -77.423264)
		(end 390.891268 -77.423264)
		(width 0.4572)
		(layer "F.Cu")
		(net "GND")
	)
	(segment
		(start 113.017808 -286.780478)
		(end 113.48466 -287.046162)
		(width 0.350012)
		(layer "F.Cu")
		(net "GND")
	)
	(segment
		(start 194.604132 -212.635338)
		(end 195.988432 -212.635338)
		(width 0.4572)
		(layer "F.Cu")
		(net "GND")
	)
	(segment
		(start 394.027914 -231.789986)
		(end 394.68298 -231.789986)
		(width 0.350012)
		(layer "F.Cu")
		(net "GND")
	)
	(segment
		(start 288.180018 -203.28509)
		(end 289.564318 -203.28509)
		(width 0.4572)
		(layer "F.Cu")
		(net "GND")
	)
	(segment
		(start 85.457792 -229.360476)
		(end 84.99094 -229.094538)
		(width 0.350012)
		(layer "F.Cu")
		(net "GND")
	)
	(segment
		(start 58.191654 -349.786448)
		(end 58.222642 -349.786448)
		(width 0.2286)
		(layer "F.Cu")
		(net "GND")
	)
	(segment
		(start 265.54811 -203.28509)
		(end 266.93241 -203.28509)
		(width 0.4572)
		(layer "F.Cu")
		(net "GND")
	)
	(segment
		(start 184.322212 -117.052852)
		(end 183.932322 -117.442742)
		(width 0.254)
		(layer "F.Cu")
		(net "GND")
	)
	(segment
		(start 133.227826 -285.970472)
		(end 133.694678 -286.23641)
		(width 0.350012)
		(layer "F.Cu")
		(net "GND")
	)
	(segment
		(start 206.248 -202.435206)
		(end 204.8637 -202.435206)
		(width 0.4572)
		(layer "F.Cu")
		(net "GND")
	)
	(segment
		(start 344.678 -253.660148)
		(end 344.211148 -253.39421)
		(width 0.350012)
		(layer "F.Cu")
		(net "GND")
	)
	(segment
		(start 342.158066 -277.060152)
		(end 341.691214 -277.32609)
		(width 0.350012)
		(layer "F.Cu")
		(net "GND")
	)
	(segment
		(start 84.047838 -247.99036)
		(end 83.580986 -247.724422)
		(width 0.350012)
		(layer "F.Cu")
		(net "GND")
	)
	(segment
		(start 313.317636 -392.004042)
		(end 313.317636 -391.784586)
		(width 0.254)
		(layer "F.Cu")
		(net "GND")
	)
	(segment
		(start 353.907852 -268.150086)
		(end 353.441 -268.416024)
		(width 0.350012)
		(layer "F.Cu")
		(net "GND")
	)
	(segment
		(start 149.377146 -65.194434)
		(end 149.13356 -65.43802)
		(width 0.4572)
		(layer "F.Cu")
		(net "GND")
	)
	(segment
		(start 373.217948 -391.333482)
		(end 373.3165 -391.23493)
		(width 0.254)
		(layer "F.Cu")
		(net "GND")
	)
	(segment
		(start 269.648178 -218.585034)
		(end 268.263878 -218.585034)
		(width 0.4572)
		(layer "F.Cu")
		(net "GND")
	)
	(segment
		(start 387.917944 -227.74021)
		(end 388.384796 -227.474272)
		(width 0.350012)
		(layer "F.Cu")
		(net "GND")
	)
	(segment
		(start 357.684832 -411.81147)
		(end 358.05364 -411.442662)
		(width 0.381)
		(layer "F.Cu")
		(net "GND")
	)
	(segment
		(start 306.25034 -403.11578)
		(end 306.216304 -403.081744)
		(width 0.381)
		(layer "F.Cu")
		(net "GND")
	)
	(segment
		(start 90.457782 -291.64026)
		(end 89.99093 -291.906198)
		(width 0.350012)
		(layer "F.Cu")
		(net "GND")
	)
	(segment
		(start 347.398086 -395.0208)
		(end 346.705936 -394.831062)
		(width 0.254)
		(layer "F.Cu")
		(net "GND")
	)
	(segment
		(start 11.533124 -51.369214)
		(end 11.537442 -51.364896)
		(width 0.4572)
		(layer "F.Cu")
		(net "GND")
	)
	(segment
		(start 376.167904 -254.470154)
		(end 376.634756 -254.204216)
		(width 0.350012)
		(layer "F.Cu")
		(net "GND")
	)
	(segment
		(start 79.177896 -293.260272)
		(end 78.711044 -293.52621)
		(width 0.350012)
		(layer "F.Cu")
		(net "GND")
	)
	(segment
		(start 357.36784 -249.610118)
		(end 356.901242 -249.34418)
		(width 0.350012)
		(layer "F.Cu")
		(net "GND")
	)
	(segment
		(start 153.146252 -388.328662)
		(end 152.498298 -388.138924)
		(width 0.254)
		(layer "F.Cu")
		(net "GND")
	)
	(segment
		(start 446.644268 -284.034992)
		(end 445.259968 -284.034992)
		(width 0.4572)
		(layer "F.Cu")
		(net "GND")
	)
	(segment
		(start 53.22697 -351.932748)
		(end 53.29682 -351.862898)
		(width 0.381)
		(layer "F.Cu")
		(net "GND")
	)
	(segment
		(start 361.42803 -281.110182)
		(end 361.894882 -281.37612)
		(width 0.350012)
		(layer "F.Cu")
		(net "GND")
	)
	(segment
		(start 46.621192 -386.030978)
		(end 46.621192 -386.630926)
		(width 0.254)
		(layer "F.Cu")
		(net "GND")
	)
	(segment
		(start 321.816222 -400.212814)
		(end 321.816222 -399.76171)
		(width 0.254)
		(layer "F.Cu")
		(net "GND")
	)
	(segment
		(start 129.938018 -283.540454)
		(end 130.40487 -283.806392)
		(width 0.350012)
		(layer "F.Cu")
		(net "GND")
	)
	(segment
		(start 331.518006 -232.599992)
		(end 331.051154 -232.334054)
		(width 0.350012)
		(layer "F.Cu")
		(net "GND")
	)
	(segment
		(start 364.717838 -270.580104)
		(end 365.18469 -270.846042)
		(width 0.350012)
		(layer "F.Cu")
		(net "GND")
	)
	(segment
		(start 25.747726 -394.410184)
		(end 25.754584 -394.403326)
		(width 0.4572)
		(layer "F.Cu")
		(net "GND")
	)
	(segment
		(start 102.804722 -124.580904)
		(end 102.804722 -125.590554)
		(width 0.3048)
		(layer "F.Cu")
		(net "GND")
	)
	(segment
		(start 98.147886 -254.470408)
		(end 97.681034 -254.20447)
		(width 0.350012)
		(layer "F.Cu")
		(net "GND")
	)
	(segment
		(start 40.494458 -429.390048)
		(end 40.494458 -428.712122)
		(width 0.381)
		(layer "F.Cu")
		(net "GND")
	)
	(segment
		(start 31.147004 -9.423654)
		(end 31.148274 -9.424924)
		(width 0.3556)
		(layer "F.Cu")
		(net "GND")
	)
	(segment
		(start 299.82414 -314.635134)
		(end 298.43984 -314.635134)
		(width 0.4572)
		(layer "F.Cu")
		(net "GND")
	)
	(segment
		(start 154.668474 -104.648)
		(end 155.17749 -104.138984)
		(width 0.381)
		(layer "F.Cu")
		(net "GND")
	)
	(segment
		(start 95.327978 -233.410252)
		(end 94.861126 -233.144314)
		(width 0.350012)
		(layer "F.Cu")
		(net "GND")
	)
	(segment
		(start 347.975174 -344.604594)
		(end 347.706188 -344.87358)
		(width 0.381)
		(layer "F.Cu")
		(net "GND")
	)
	(segment
		(start 412.690056 -392.999722)
		(end 413.298386 -392.999722)
		(width 0.254)
		(layer "F.Cu")
		(net "GND")
	)
	(segment
		(start 384.157982 -255.28016)
		(end 384.624834 -255.014222)
		(width 0.350012)
		(layer "F.Cu")
		(net "GND")
	)
	(segment
		(start 91.398344 -386.6388)
		(end 90.706194 -386.449062)
		(width 0.254)
		(layer "F.Cu")
		(net "GND")
	)
	(segment
		(start 438.629552 -427.09211)
		(end 437.962802 -427.09211)
		(width 0.4572)
		(layer "F.Cu")
		(net "GND")
	)
	(segment
		(start 61.791342 -390.160002)
		(end 62.470538 -390.160002)
		(width 0.254)
		(layer "F.Cu")
		(net "GND")
	)
	(segment
		(start 307.368194 -218.585034)
		(end 305.983894 -218.585034)
		(width 0.4572)
		(layer "F.Cu")
		(net "GND")
	)
	(segment
		(start 59.428126 -202.435206)
		(end 58.043826 -202.435206)
		(width 0.4572)
		(layer "F.Cu")
		(net "GND")
	)
	(segment
		(start 265.54811 -296.78503)
		(end 266.93241 -296.78503)
		(width 0.4572)
		(layer "F.Cu")
		(net "GND")
	)
	(segment
		(start 24.917654 -349.786448)
		(end 24.948642 -349.786448)
		(width 0.2286)
		(layer "F.Cu")
		(net "GND")
	)
	(segment
		(start 103.617776 -281.920442)
		(end 103.151178 -282.18638)
		(width 0.350012)
		(layer "F.Cu")
		(net "GND")
	)
	(segment
		(start 93.277944 -268.960346)
		(end 92.811092 -269.226284)
		(width 0.350012)
		(layer "F.Cu")
		(net "GND")
	)
	(segment
		(start 325.408036 -251.23013)
		(end 324.75297 -251.23013)
		(width 0.350012)
		(layer "F.Cu")
		(net "GND")
	)
	(segment
		(start 163.298378 -388.138924)
		(end 162.746182 -388.328662)
		(width 0.254)
		(layer "F.Cu")
		(net "GND")
	)
	(segment
		(start 133.41477 -387.231128)
		(end 133.41477 -387.831076)
		(width 0.254)
		(layer "F.Cu")
		(net "GND")
	)
	(segment
		(start 307.317648 -399.663158)
		(end 307.4162 -399.76171)
		(width 0.254)
		(layer "F.Cu")
		(net "GND")
	)
	(segment
		(start 77.767942 -261.670292)
		(end 77.112876 -261.670292)
		(width 0.350012)
		(layer "F.Cu")
		(net "GND")
	)
	(segment
		(start 440.221116 -389.9535)
		(end 441.446666 -389.9535)
		(width 0.254)
		(layer "F.Cu")
		(net "GND")
	)
	(segment
		(start 392.448034 -268.150086)
		(end 392.914886 -268.416024)
		(width 0.350012)
		(layer "F.Cu")
		(net "GND")
	)
	(segment
		(start 124.091192 -390.160002)
		(end 123.570492 -390.160002)
		(width 0.254)
		(layer "F.Cu")
		(net "GND")
	)
	(segment
		(start 368.478054 -267.34008)
		(end 368.944906 -267.606018)
		(width 0.350012)
		(layer "F.Cu")
		(net "GND")
	)
	(segment
		(start 288.180018 -240.685066)
		(end 289.564318 -240.685066)
		(width 0.4572)
		(layer "F.Cu")
		(net "GND")
	)
	(segment
		(start 99.004628 -387.069076)
		(end 98.842576 -387.231128)
		(width 0.254)
		(layer "F.Cu")
		(net "GND")
	)
	(segment
		(start 307.404516 -439.676794)
		(end 306.77358 -439.676794)
		(width 0.381)
		(layer "F.Cu")
		(net "GND")
	)
	(segment
		(start 366.128046 -273.010122)
		(end 366.594898 -273.27606)
		(width 0.350012)
		(layer "F.Cu")
		(net "GND")
	)
	(segment
		(start 161.62147 -76.781406)
		(end 160.98647 -76.781406)
		(width 0.4572)
		(layer "F.Cu")
		(net "GND")
	)
	(segment
		(start 386.338064 -277.060152)
		(end 386.804916 -277.32609)
		(width 0.350012)
		(layer "F.Cu")
		(net "GND")
	)
	(segment
		(start 101.437948 -247.180354)
		(end 100.971096 -246.914416)
		(width 0.350012)
		(layer "F.Cu")
		(net "GND")
	)
	(segment
		(start 77.042518 -175.547782)
		(end 76.789534 -175.800766)
		(width 0.2286)
		(layer "F.Cu")
		(net "GND")
	)
	(segment
		(start 372.707916 -263.29005)
		(end 373.174768 -263.555988)
		(width 0.350012)
		(layer "F.Cu")
		(net "GND")
	)
	(segment
		(start 136.948164 -16.551148)
		(end 136.948164 -17.654778)
		(width 0.3556)
		(layer "F.Cu")
		(net "GND")
	)
	(segment
		(start 394.327888 -274.630134)
		(end 394.982954 -274.630134)
		(width 0.350012)
		(layer "F.Cu")
		(net "GND")
	)
	(segment
		(start 371.938042 -239.08004)
		(end 372.404894 -238.814102)
		(width 0.350012)
		(layer "F.Cu")
		(net "GND")
	)
	(segment
		(start 442.5442 -203.28509)
		(end 443.9285 -203.28509)
		(width 0.4572)
		(layer "F.Cu")
		(net "GND")
	)
	(segment
		(start 202.147932 -294.235378)
		(end 203.532232 -294.235378)
		(width 0.4572)
		(layer "F.Cu")
		(net "GND")
	)
	(segment
		(start 125.362462 -384.617722)
		(end 125.970538 -384.617722)
		(width 0.254)
		(layer "F.Cu")
		(net "GND")
	)
	(segment
		(start 325.70801 -285.970218)
		(end 325.052944 -285.970218)
		(width 0.350012)
		(layer "F.Cu")
		(net "GND")
	)
	(segment
		(start 442.5442 -275.535136)
		(end 443.9285 -275.535136)
		(width 0.4572)
		(layer "F.Cu")
		(net "GND")
	)
	(segment
		(start 380.417832 -391.333482)
		(end 380.516384 -391.23493)
		(width 0.254)
		(layer "F.Cu")
		(net "GND")
	)
	(segment
		(start 382.817878 -392.004296)
		(end 383.117852 -392.30427)
		(width 0.254)
		(layer "F.Cu")
		(net "GND")
	)
	(segment
		(start 92.33789 -265.720322)
		(end 91.871038 -265.98626)
		(width 0.350012)
		(layer "F.Cu")
		(net "GND")
	)
	(segment
		(start 409.090114 -392.999722)
		(end 409.69819 -392.999722)
		(width 0.254)
		(layer "F.Cu")
		(net "GND")
	)
	(segment
		(start 350.78797 -226.930204)
		(end 350.321118 -226.664266)
		(width 0.350012)
		(layer "F.Cu")
		(net "GND")
	)
	(segment
		(start 130.516376 -391.830814)
		(end 130.516376 -391.37971)
		(width 0.254)
		(layer "F.Cu")
		(net "GND")
	)
	(segment
		(start 44.32935 -105.8164)
		(end 43.71848 -105.8164)
		(width 0.381)
		(layer "F.Cu")
		(net "GND")
	)
	(segment
		(start 445.361822 -11.26998)
		(end 445.361822 -12.372848)
		(width 0.3556)
		(layer "F.Cu")
		(net "GND")
	)
	(segment
		(start 46.518068 -383.402586)
		(end 46.518068 -382.957578)
		(width 0.254)
		(layer "F.Cu")
		(net "GND")
	)
	(segment
		(start 97.207832 -241.510312)
		(end 96.74098 -241.244374)
		(width 0.350012)
		(layer "F.Cu")
		(net "GND")
	)
	(segment
		(start 93.763338 -180.309774)
		(end 93.763338 -180.570378)
		(width 0.2286)
		(layer "F.Cu")
		(net "GND")
	)
	(segment
		(start 352.668078 -223.69018)
		(end 352.201226 -223.424242)
		(width 0.350012)
		(layer "F.Cu")
		(net "GND")
	)
	(segment
		(start 264.17143 -99.405948)
		(end 261.75335 -99.405948)
		(width 0.381)
		(layer "F.Cu")
		(net "GND")
	)
	(segment
		(start 143.098012 -264.10031)
		(end 143.56461 -264.366248)
		(width 0.350012)
		(layer "F.Cu")
		(net "GND")
	)
	(segment
		(start 377.577858 -235.840016)
		(end 378.04471 -235.574078)
		(width 0.350012)
		(layer "F.Cu")
		(net "GND")
	)
	(segment
		(start 355.78796 -294.070024)
		(end 355.321108 -294.335962)
		(width 0.350012)
		(layer "F.Cu")
		(net "GND")
	)
	(segment
		(start 447.419476 -422.134538)
		(end 447.419476 -422.263062)
		(width 0.1778)
		(layer "F.Cu")
		(net "GND")
	)
	(segment
		(start 295.724072 -200.735184)
		(end 297.108372 -200.735184)
		(width 0.4572)
		(layer "F.Cu")
		(net "GND")
	)
	(segment
		(start 129.63779 -255.280414)
		(end 130.104642 -255.014476)
		(width 0.350012)
		(layer "F.Cu")
		(net "GND")
	)
	(segment
		(start 144.677892 -230.980234)
		(end 145.144744 -230.71455)
		(width 0.350012)
		(layer "F.Cu")
		(net "GND")
	)
	(segment
		(start 131.517898 -224.50044)
		(end 131.98475 -224.234502)
		(width 0.350012)
		(layer "F.Cu")
		(net "GND")
	)
	(segment
		(start 152.498298 -386.6388)
		(end 151.806148 -386.449062)
		(width 0.254)
		(layer "F.Cu")
		(net "GND")
	)
	(segment
		(start 373.517922 -399.143474)
		(end 373.5705 -398.542002)
		(width 0.254)
		(layer "F.Cu")
		(net "GND")
	)
	(segment
		(start 100.797868 -273.820382)
		(end 100.331016 -274.08632)
		(width 0.350012)
		(layer "F.Cu")
		(net "GND")
	)
	(segment
		(start 348.04604 -396.710662)
		(end 347.398086 -396.520924)
		(width 0.254)
		(layer "F.Cu")
		(net "GND")
	)
	(segment
		(start 78.707996 -294.070278)
		(end 78.241144 -294.336216)
		(width 0.350012)
		(layer "F.Cu")
		(net "GND")
	)
	(segment
		(start 330.408026 -271.39011)
		(end 329.941174 -271.656048)
		(width 0.350012)
		(layer "F.Cu")
		(net "GND")
	)
	(segment
		(start 84.047838 -252.850396)
		(end 83.580986 -252.584458)
		(width 0.350012)
		(layer "F.Cu")
		(net "GND")
	)
	(segment
		(start 353.437952 -293.260018)
		(end 352.9711 -293.525956)
		(width 0.350012)
		(layer "F.Cu")
		(net "GND")
	)
	(segment
		(start 382.748028 -247.990106)
		(end 383.21488 -247.724168)
		(width 0.350012)
		(layer "F.Cu")
		(net "GND")
	)
	(segment
		(start 381.338074 -230.97998)
		(end 381.804926 -230.714042)
		(width 0.350012)
		(layer "F.Cu")
		(net "GND")
	)
	(segment
		(start 79.817976 -250.420378)
		(end 79.351124 -250.15444)
		(width 0.350012)
		(layer "F.Cu")
		(net "GND")
	)
	(segment
		(start 339.977984 -226.120198)
		(end 339.511132 -225.85426)
		(width 0.350012)
		(layer "F.Cu")
		(net "GND")
	)
	(segment
		(start 282.798012 -351.927922)
		(end 283.386022 -351.927922)
		(width 0.381)
		(layer "F.Cu")
		(net "GND")
	)
	(segment
		(start 412.367984 -284.88513)
		(end 413.752284 -284.88513)
		(width 0.4572)
		(layer "F.Cu")
		(net "GND")
	)
	(segment
		(start 411.745684 -399.663158)
		(end 411.844236 -399.76171)
		(width 0.254)
		(layer "F.Cu")
		(net "GND")
	)
	(segment
		(start 9.277096 -100.417884)
		(end 9.963404 -100.417884)
		(width 0.3556)
		(layer "F.Cu")
		(net "GND")
	)
	(segment
		(start 386.338064 -260.860032)
		(end 386.804916 -261.12597)
		(width 0.350012)
		(layer "F.Cu")
		(net "GND")
	)
	(segment
		(start 412.367984 -212.635084)
		(end 413.752284 -212.635084)
		(width 0.4572)
		(layer "F.Cu")
		(net "GND")
	)
	(segment
		(start 331.262482 -142.284196)
		(end 331.262482 -141.36243)
		(width 0.254)
		(layer "F.Cu")
		(net "GND")
	)
	(segment
		(start 114.817906 -383.402586)
		(end 114.817906 -383.622296)
		(width 0.254)
		(layer "F.Cu")
		(net "GND")
	)
	(segment
		(start 371.678454 -394.831062)
		(end 371.170454 -395.0208)
		(width 0.254)
		(layer "F.Cu")
		(net "GND")
	)
	(segment
		(start 314.870338 -398.542002)
		(end 314.191142 -398.542002)
		(width 0.254)
		(layer "F.Cu")
		(net "GND")
	)
	(segment
		(start 419.912038 -312.935112)
		(end 421.296338 -312.935112)
		(width 0.4572)
		(layer "F.Cu")
		(net "GND")
	)
	(segment
		(start 288.180018 -231.335072)
		(end 289.564318 -231.335072)
		(width 0.4572)
		(layer "F.Cu")
		(net "GND")
	)
	(segment
		(start 379.75794 -288.399982)
		(end 380.224792 -288.66592)
		(width 0.350012)
		(layer "F.Cu")
		(net "GND")
	)
	(segment
		(start 102.378002 -239.080294)
		(end 101.91115 -238.814356)
		(width 0.350012)
		(layer "F.Cu")
		(net "GND")
	)
	(segment
		(start 363.778038 -273.820128)
		(end 364.24489 -274.086066)
		(width 0.350012)
		(layer "F.Cu")
		(net "GND")
	)
	(segment
		(start 277.192232 -295.935146)
		(end 275.807932 -295.935146)
		(width 0.4572)
		(layer "F.Cu")
		(net "GND")
	)
	(segment
		(start 337.798156 -398.542002)
		(end 337.118706 -398.542002)
		(width 0.254)
		(layer "F.Cu")
		(net "GND")
	)
	(segment
		(start 354.078032 -237.460028)
		(end 353.61118 -237.19409)
		(width 0.350012)
		(layer "F.Cu")
		(net "GND")
	)
	(segment
		(start 158.445708 -390.761474)
		(end 158.498286 -390.160002)
		(width 0.254)
		(layer "F.Cu")
		(net "GND")
	)
	(segment
		(start 114.986816 -403.013418)
		(end 114.678968 -403.013418)
		(width 0.3302)
		(layer "F.Cu")
		(net "GND")
	)
	(segment
		(start 198.7042 -221.135194)
		(end 197.3199 -221.135194)
		(width 0.4572)
		(layer "F.Cu")
		(net "GND")
	)
	(segment
		(start 144.207992 -225.310446)
		(end 144.674844 -225.044508)
		(width 0.350012)
		(layer "F.Cu")
		(net "GND")
	)
	(segment
		(start 401.729448 -395.313154)
		(end 402.029422 -395.613128)
		(width 0.254)
		(layer "F.Cu")
		(net "GND")
	)
	(segment
		(start 130.71729 -53.974492)
		(end 131.438142 -53.974492)
		(width 0.1778)
		(layer "F.Cu")
		(net "GND")
	)
	(segment
		(start 433.166774 -8.320024)
		(end 433.166774 -9.425432)
		(width 0.3556)
		(layer "F.Cu")
		(net "GND")
	)
	(segment
		(start 121.691146 -390.160002)
		(end 121.170446 -390.160002)
		(width 0.254)
		(layer "F.Cu")
		(net "GND")
	)
	(segment
		(start 288.180018 -294.235124)
		(end 289.564318 -294.235124)
		(width 0.4572)
		(layer "F.Cu")
		(net "GND")
	)
	(segment
		(start 320.097658 -104.426512)
		(end 320.09842 -104.42575)
		(width 0.4572)
		(layer "F.Cu")
		(net "GND")
	)
	(segment
		(start 366.297972 -229.360222)
		(end 366.764824 -229.094284)
		(width 0.350012)
		(layer "F.Cu")
		(net "GND")
	)
	(segment
		(start 105.19791 -230.980234)
		(end 104.731058 -230.71455)
		(width 0.350012)
		(layer "F.Cu")
		(net "GND")
	)
	(segment
		(start 177.922174 -111.452914)
		(end 177.532284 -111.063024)
		(width 0.254)
		(layer "F.Cu")
		(net "GND")
	)
	(segment
		(start 83.646264 -388.328662)
		(end 84.19846 -388.138924)
		(width 0.254)
		(layer "F.Cu")
		(net "GND")
	)
	(segment
		(start 329.760072 -37.017706)
		(end 330.369672 -37.017706)
		(width 0.3556)
		(layer "F.Cu")
		(net "GND")
	)
	(segment
		(start 358.307894 -247.990106)
		(end 357.841042 -247.724168)
		(width 0.350012)
		(layer "F.Cu")
		(net "GND")
	)
	(segment
		(start 89.047828 -284.35046)
		(end 88.580976 -284.616398)
		(width 0.350012)
		(layer "F.Cu")
		(net "GND")
	)
	(segment
		(start 405.64689 -7.217156)
		(end 405.64689 -8.320024)
		(width 0.3556)
		(layer "F.Cu")
		(net "GND")
	)
	(segment
		(start 87.167974 -271.390364)
		(end 86.701122 -271.656302)
		(width 0.350012)
		(layer "F.Cu")
		(net "GND")
	)
	(segment
		(start 61.270642 -390.160002)
		(end 60.591192 -390.160002)
		(width 0.254)
		(layer "F.Cu")
		(net "GND")
	)
	(segment
		(start 129.938018 -260.860286)
		(end 130.40487 -261.126224)
		(width 0.350012)
		(layer "F.Cu")
		(net "GND")
	)
	(segment
		(start 356.728014 -279.49017)
		(end 356.261162 -279.756108)
		(width 0.350012)
		(layer "F.Cu")
		(net "GND")
	)
	(segment
		(start 424.01871 -362.79963)
		(end 424.01871 -363.773974)
		(width 0.3556)
		(layer "F.Cu")
		(net "GND")
	)
	(segment
		(start 24.629364 -39.574978)
		(end 25.337516 -39.574978)
		(width 0.2286)
		(layer "F.Cu")
		(net "GND")
	)
	(segment
		(start 85.757766 -288.400236)
		(end 85.290914 -288.666174)
		(width 0.350012)
		(layer "F.Cu")
		(net "GND")
	)
	(segment
		(start 376.167904 -241.510058)
		(end 376.634756 -241.24412)
		(width 0.350012)
		(layer "F.Cu")
		(net "GND")
	)
	(segment
		(start 273.092164 -212.635084)
		(end 274.476464 -212.635084)
		(width 0.4572)
		(layer "F.Cu")
		(net "GND")
	)
	(segment
		(start 131.418584 -388.328662)
		(end 130.77063 -388.138924)
		(width 0.254)
		(layer "F.Cu")
		(net "GND")
	)
	(segment
		(start 77.467968 -252.850396)
		(end 76.812902 -252.850396)
		(width 0.350012)
		(layer "F.Cu")
		(net "GND")
	)
	(segment
		(start 280.635964 -287.435036)
		(end 282.020264 -287.435036)
		(width 0.4572)
		(layer "F.Cu")
		(net "GND")
	)
	(segment
		(start 269.648178 -237.285022)
		(end 268.263878 -237.285022)
		(width 0.4572)
		(layer "F.Cu")
		(net "GND")
	)
	(segment
		(start 335.277968 -224.500186)
		(end 334.811116 -224.234248)
		(width 0.350012)
		(layer "F.Cu")
		(net "GND")
	)
	(segment
		(start 99.36226 -385.131056)
		(end 99.36226 -384.531108)
		(width 0.254)
		(layer "F.Cu")
		(net "GND")
	)
	(segment
		(start 284.736032 -284.034992)
		(end 283.351732 -284.034992)
		(width 0.4572)
		(layer "F.Cu")
		(net "GND")
	)
	(segment
		(start 402.248878 -394.412978)
		(end 402.248878 -395.012926)
		(width 0.254)
		(layer "F.Cu")
		(net "GND")
	)
	(segment
		(start 81.544414 -391.830814)
		(end 81.544414 -391.37971)
		(width 0.254)
		(layer "F.Cu")
		(net "GND")
	)
	(segment
		(start 58.666888 -12.372848)
		(end 58.666888 -11.26998)
		(width 0.3556)
		(layer "F.Cu")
		(net "GND")
	)
	(segment
		(start 137.627868 -223.690434)
		(end 138.09472 -223.424496)
		(width 0.350012)
		(layer "F.Cu")
		(net "GND")
	)
	(segment
		(start 85.398356 -384.617722)
		(end 85.345778 -383.92227)
		(width 0.254)
		(layer "F.Cu")
		(net "GND")
	)
	(segment
		(start 354.378006 -280.300176)
		(end 353.911154 -280.566114)
		(width 0.350012)
		(layer "F.Cu")
		(net "GND")
	)
	(segment
		(start 310.662066 -392.999722)
		(end 311.270396 -392.999722)
		(width 0.254)
		(layer "F.Cu")
		(net "GND")
	)
	(segment
		(start 97.037906 -293.260272)
		(end 96.571054 -293.52621)
		(width 0.350012)
		(layer "F.Cu")
		(net "GND")
	)
	(segment
		(start 374.28805 -230.169974)
		(end 374.754902 -229.904036)
		(width 0.350012)
		(layer "F.Cu")
		(net "GND")
	)
	(segment
		(start 123.997974 -248.800366)
		(end 124.464826 -248.534428)
		(width 0.350012)
		(layer "F.Cu")
		(net "GND")
	)
	(segment
		(start 144.977866 -268.960346)
		(end 145.444718 -269.226284)
		(width 0.350012)
		(layer "F.Cu")
		(net "GND")
	)
	(segment
		(start 141.687804 -281.110436)
		(end 142.154656 -281.376374)
		(width 0.350012)
		(layer "F.Cu")
		(net "GND")
	)
	(segment
		(start 384.627882 -223.69018)
		(end 385.094734 -223.424242)
		(width 0.350012)
		(layer "F.Cu")
		(net "GND")
	)
	(segment
		(start 327.117964 -280.300176)
		(end 326.651112 -280.566114)
		(width 0.350012)
		(layer "F.Cu")
		(net "GND")
	)
	(segment
		(start 310.917844 -399.663158)
		(end 311.217818 -399.143474)
		(width 0.254)
		(layer "F.Cu")
		(net "GND")
	)
	(segment
		(start 149.535642 -107.683046)
		(end 148.894292 -107.683046)
		(width 0.4064)
		(layer "F.Cu")
		(net "GND")
	)
	(segment
		(start 371.170454 -395.0208)
		(end 370.478558 -394.831062)
		(width 0.254)
		(layer "F.Cu")
		(net "GND")
	)
	(segment
		(start 134.80796 -228.55047)
		(end 135.274812 -228.284532)
		(width 0.350012)
		(layer "F.Cu")
		(net "GND")
	)
	(segment
		(start 188.164978 -353.81565)
		(end 187.594494 -354.386134)
		(width 0.2286)
		(layer "F.Cu")
		(net "GND")
	)
	(segment
		(start 363.778038 -270.580104)
		(end 364.24489 -270.846042)
		(width 0.350012)
		(layer "F.Cu")
		(net "GND")
	)
	(segment
		(start 148.971 -116.31295)
		(end 148.21027 -116.31295)
		(width 0.381)
		(layer "F.Cu")
		(net "GND")
	)
	(segment
		(start 110.77702 -173.19498)
		(end 110.77702 -173.553374)
		(width 0.3048)
		(layer "F.Cu")
		(net "GND")
	)
	(segment
		(start 113.017808 -265.720322)
		(end 113.48466 -265.98626)
		(width 0.350012)
		(layer "F.Cu")
		(net "GND")
	)
	(segment
		(start 313.617864 -392.30427)
		(end 313.317636 -392.004042)
		(width 0.254)
		(layer "F.Cu")
		(net "GND")
	)
	(segment
		(start 424.012106 -305.28514)
		(end 422.627806 -305.28514)
		(width 0.4572)
		(layer "F.Cu")
		(net "GND")
	)
	(segment
		(start 381.338074 -253.660148)
		(end 381.804926 -253.39421)
		(width 0.350012)
		(layer "F.Cu")
		(net "GND")
	)
	(segment
		(start 112.68202 -387.231128)
		(end 112.205008 -387.04774)
		(width 0.254)
		(layer "F.Cu")
		(net "GND")
	)
	(segment
		(start 78.877922 -232.600246)
		(end 78.41107 -232.334308)
		(width 0.350012)
		(layer "F.Cu")
		(net "GND")
	)
	(segment
		(start 328.527918 -264.910062)
		(end 328.061066 -265.176)
		(width 0.350012)
		(layer "F.Cu")
		(net "GND")
	)
	(segment
		(start 141.38783 -228.55047)
		(end 141.854682 -228.284532)
		(width 0.350012)
		(layer "F.Cu")
		(net "GND")
	)
	(segment
		(start 161.546286 -388.328662)
		(end 160.898332 -388.138924)
		(width 0.254)
		(layer "F.Cu")
		(net "GND")
	)
	(segment
		(start 138.303 -111.77143)
		(end 138.390376 -111.684054)
		(width 0.381)
		(layer "F.Cu")
		(net "GND")
	)
	(segment
		(start 388.562342 -392.999722)
		(end 389.201406 -392.999722)
		(width 0.254)
		(layer "F.Cu")
		(net "GND")
	)
	(segment
		(start 140.748004 -295.69029)
		(end 141.214856 -295.956228)
		(width 0.350012)
		(layer "F.Cu")
		(net "GND")
	)
	(segment
		(start 350.998028 -396.520924)
		(end 350.446086 -396.710662)
		(width 0.254)
		(layer "F.Cu")
		(net "GND")
	)
	(segment
		(start 38.45814 -12.37488)
		(end 38.45814 -12.374118)
		(width 0.3556)
		(layer "F.Cu")
		(net "GND")
	)
	(segment
		(start 133.398006 -237.460282)
		(end 133.864858 -237.194344)
		(width 0.350012)
		(layer "F.Cu")
		(net "GND")
	)
	(segment
		(start 117.717824 -281.920442)
		(end 118.184676 -282.18638)
		(width 0.350012)
		(layer "F.Cu")
		(net "GND")
	)
	(segment
		(start 391.677906 -250.420124)
		(end 392.144758 -250.154186)
		(width 0.350012)
		(layer "F.Cu")
		(net "GND")
	)
	(segment
		(start 108.017818 -240.700306)
		(end 107.550966 -240.434368)
		(width 0.350012)
		(layer "F.Cu")
		(net "GND")
	)
	(segment
		(start 58.518044 -383.402586)
		(end 58.518044 -382.951482)
		(width 0.254)
		(layer "F.Cu")
		(net "GND")
	)
	(segment
		(start 97.97796 -270.580358)
		(end 97.511108 -270.846296)
		(width 0.350012)
		(layer "F.Cu")
		(net "GND")
	)
	(segment
		(start 356.42804 -228.550216)
		(end 355.961188 -228.284278)
		(width 0.350012)
		(layer "F.Cu")
		(net "GND")
	)
	(segment
		(start 110.83798 -235.84027)
		(end 110.371128 -235.574332)
		(width 0.350012)
		(layer "F.Cu")
		(net "GND")
	)
	(segment
		(start 303.268126 -306.135024)
		(end 304.652426 -306.135024)
		(width 0.4572)
		(layer "F.Cu")
		(net "GND")
	)
	(segment
		(start 126.404878 -50.169064)
		(end 125.788928 -50.169064)
		(width 0.4572)
		(layer "F.Cu")
		(net "GND")
	)
	(segment
		(start 407.298398 -392.999722)
		(end 407.24582 -392.30427)
		(width 0.254)
		(layer "F.Cu")
		(net "GND")
	)
	(segment
		(start 31.017718 -51.369214)
		(end 32.605218 -51.369214)
		(width 0.4572)
		(layer "F.Cu")
		(net "GND")
	)
	(segment
		(start 343.56802 -289.209988)
		(end 343.101168 -289.475926)
		(width 0.350012)
		(layer "F.Cu")
		(net "GND")
	)
	(segment
		(start 105.497884 -293.260272)
		(end 105.031032 -293.52621)
		(width 0.350012)
		(layer "F.Cu")
		(net "GND")
	)
	(segment
		(start 338.389976 -392.999722)
		(end 337.798156 -392.999722)
		(width 0.254)
		(layer "F.Cu")
		(net "GND")
	)
	(segment
		(start 166.81958 -387.069076)
		(end 166.10457 -387.069076)
		(width 0.254)
		(layer "F.Cu")
		(net "GND")
	)
	(segment
		(start 389.327898 -247.990106)
		(end 389.79475 -247.724168)
		(width 0.350012)
		(layer "F.Cu")
		(net "GND")
	)
	(segment
		(start 103.317802 -224.50044)
		(end 102.85095 -224.234502)
		(width 0.350012)
		(layer "F.Cu")
		(net "GND")
	)
	(segment
		(start 149.490176 -384.617722)
		(end 148.898356 -384.617722)
		(width 0.254)
		(layer "F.Cu")
		(net "GND")
	)
	(segment
		(start 135.14705 -17.652746)
		(end 135.14832 -17.654016)
		(width 0.3556)
		(layer "F.Cu")
		(net "GND")
	)
	(segment
		(start 422.2115 -394.831062)
		(end 421.69842 -395.0208)
		(width 0.254)
		(layer "F.Cu")
		(net "GND")
	)
	(segment
		(start 38.45687 -8.320024)
		(end 38.45687 -9.423654)
		(width 0.3556)
		(layer "F.Cu")
		(net "GND")
	)
	(segment
		(start 165.44417 -391.830814)
		(end 165.44417 -391.37971)
		(width 0.254)
		(layer "F.Cu")
		(net "GND")
	)
	(segment
		(start 123.52782 -228.55047)
		(end 123.994672 -228.284532)
		(width 0.350012)
		(layer "F.Cu")
		(net "GND")
	)
	(segment
		(start 391.97788 -293.260018)
		(end 392.444732 -293.525956)
		(width 0.350012)
		(layer "F.Cu")
		(net "GND")
	)
	(segment
		(start 60.578492 -386.449062)
		(end 60.070492 -386.6388)
		(width 0.254)
		(layer "F.Cu")
		(net "GND")
	)
	(segment
		(start 56.867044 -11.26998)
		(end 56.867044 -10.16635)
		(width 0.3556)
		(layer "F.Cu")
		(net "GND")
	)
	(segment
		(start 330.108052 -235.03001)
		(end 329.6412 -234.764072)
		(width 0.350012)
		(layer "F.Cu")
		(net "GND")
	)
	(segment
		(start 343.56802 -274.630134)
		(end 343.101168 -274.896072)
		(width 0.350012)
		(layer "F.Cu")
		(net "GND")
	)
	(segment
		(start 116.94795 -249.610372)
		(end 117.414802 -249.344434)
		(width 0.350012)
		(layer "F.Cu")
		(net "GND")
	)
	(segment
		(start 364.717838 -281.920188)
		(end 365.18469 -282.186126)
		(width 0.350012)
		(layer "F.Cu")
		(net "GND")
	)
	(segment
		(start 425.96562 -7.215124)
		(end 425.96562 -7.215886)
		(width 0.3556)
		(layer "F.Cu")
		(net "GND")
	)
	(segment
		(start 122.41784 -265.720322)
		(end 122.884692 -265.98626)
		(width 0.350012)
		(layer "F.Cu")
		(net "GND")
	)
	(segment
		(start 156.60624 -386.449062)
		(end 156.09824 -386.6388)
		(width 0.254)
		(layer "F.Cu")
		(net "GND")
	)
	(segment
		(start 323.049392 -338.053426)
		(end 323.619876 -337.482942)
		(width 0.2286)
		(layer "F.Cu")
		(net "GND")
	)
	(segment
		(start 349.847916 -222.070168)
		(end 349.381064 -221.80423)
		(width 0.350012)
		(layer "F.Cu")
		(net "GND")
	)
	(segment
		(start 446.644268 -305.28514)
		(end 445.259968 -305.28514)
		(width 0.4572)
		(layer "F.Cu")
		(net "GND")
	)
	(segment
		(start 89.518998 -390.160002)
		(end 90.198448 -390.160002)
		(width 0.254)
		(layer "F.Cu")
		(net "GND")
	)
	(segment
		(start 344.03792 -268.960092)
		(end 343.571068 -269.22603)
		(width 0.350012)
		(layer "F.Cu")
		(net "GND")
	)
	(segment
		(start 42.105326 -349.215964)
		(end 42.105326 -348.79915)
		(width 0.2286)
		(layer "F.Cu")
		(net "GND")
	)
	(segment
		(start 162.098228 -384.617722)
		(end 162.04565 -383.92227)
		(width 0.254)
		(layer "F.Cu")
		(net "GND")
	)
	(segment
		(start 77.467968 -238.270288)
		(end 76.812902 -238.270288)
		(width 0.350012)
		(layer "F.Cu")
		(net "GND")
	)
	(segment
		(start 380.218442 -396.710662)
		(end 379.570488 -396.520924)
		(width 0.254)
		(layer "F.Cu")
		(net "GND")
	)
	(segment
		(start 49.668176 -12.374118)
		(end 49.666906 -12.372848)
		(width 0.3556)
		(layer "F.Cu")
		(net "GND")
	)
	(segment
		(start 354.078032 -243.940076)
		(end 353.61118 -243.674138)
		(width 0.350012)
		(layer "F.Cu")
		(net "GND")
	)
	(segment
		(start 108.09097 -24.154638)
		(end 107.692952 -24.552656)
		(width 0.381)
		(layer "F.Cu")
		(net "GND")
	)
	(segment
		(start 439.100214 -239.835182)
		(end 437.715914 -239.835182)
		(width 0.4572)
		(layer "F.Cu")
		(net "GND")
	)
	(segment
		(start 79.14894 -386.030978)
		(end 79.14894 -385.43103)
		(width 0.254)
		(layer "F.Cu")
		(net "GND")
	)
	(segment
		(start 384.157982 -234.220004)
		(end 384.624834 -233.954066)
		(width 0.350012)
		(layer "F.Cu")
		(net "GND")
	)
	(segment
		(start 405.64689 -9.423654)
		(end 405.64816 -9.424924)
		(width 0.3556)
		(layer "F.Cu")
		(net "GND")
	)
	(segment
		(start 376.467878 -284.350206)
		(end 376.93473 -284.616144)
		(width 0.350012)
		(layer "F.Cu")
		(net "GND")
	)
	(segment
		(start 385.570476 -398.542002)
		(end 384.89128 -398.542002)
		(width 0.254)
		(layer "F.Cu")
		(net "GND")
	)
	(segment
		(start 97.037906 -272.20037)
		(end 96.571054 -272.466308)
		(width 0.350012)
		(layer "F.Cu")
		(net "GND")
	)
	(segment
		(start 156.09824 -386.6388)
		(end 155.406344 -386.449062)
		(width 0.254)
		(layer "F.Cu")
		(net "GND")
	)
	(segment
		(start 363.00791 -233.409998)
		(end 363.474762 -233.14406)
		(width 0.350012)
		(layer "F.Cu")
		(net "GND")
	)
	(segment
		(start 408.498294 -395.0208)
		(end 407.806144 -394.831062)
		(width 0.254)
		(layer "F.Cu")
		(net "GND")
	)
	(segment
		(start 108.017818 -234.220258)
		(end 107.550966 -233.95432)
		(width 0.350012)
		(layer "F.Cu")
		(net "GND")
	)
	(segment
		(start 374.11787 -270.580104)
		(end 374.584722 -270.846042)
		(width 0.350012)
		(layer "F.Cu")
		(net "GND")
	)
	(segment
		(start 375.057924 -290.019994)
		(end 375.524776 -290.285932)
		(width 0.350012)
		(layer "F.Cu")
		(net "GND")
	)
	(segment
		(start 454.188068 -295.935146)
		(end 452.803768 -295.935146)
		(width 0.4572)
		(layer "F.Cu")
		(net "GND")
	)
	(segment
		(start 128.962404 -384.617722)
		(end 128.370584 -384.617722)
		(width 0.254)
		(layer "F.Cu")
		(net "GND")
	)
	(segment
		(start 373.3165 -399.76171)
		(end 373.217948 -399.663158)
		(width 0.254)
		(layer "F.Cu")
		(net "GND")
	)
	(segment
		(start 347.045534 -391.784586)
		(end 347.045534 -391.333482)
		(width 0.254)
		(layer "F.Cu")
		(net "GND")
	)
	(segment
		(start 64.171576 -403.830536)
		(end 64.171576 -402.931122)
		(width 0.381)
		(layer "F.Cu")
		(net "GND")
	)
	(segment
		(start 125.91796 -390.761474)
		(end 125.617986 -391.281158)
		(width 0.254)
		(layer "F.Cu")
		(net "GND")
	)
	(segment
		(start 363.478064 -243.940076)
		(end 363.944916 -243.674138)
		(width 0.350012)
		(layer "F.Cu")
		(net "GND")
	)
	(segment
		(start 194.604132 -200.735438)
		(end 195.988432 -200.735438)
		(width 0.4572)
		(layer "F.Cu")
		(net "GND")
	)
	(segment
		(start 87.8078 -223.690434)
		(end 87.340948 -223.424496)
		(width 0.350012)
		(layer "F.Cu")
		(net "GND")
	)
	(segment
		(start 386.03809 -239.08004)
		(end 386.504942 -238.814102)
		(width 0.350012)
		(layer "F.Cu")
		(net "GND")
	)
	(segment
		(start 421.942514 -393.213082)
		(end 421.942514 -393.59332)
		(width 0.254)
		(layer "F.Cu")
		(net "GND")
	)
	(segment
		(start 393.849352 -395.466062)
		(end 393.365736 -395.466062)
		(width 0.381)
		(layer "F.Cu")
		(net "GND")
	)
	(segment
		(start 115.067842 -246.370348)
		(end 115.534694 -246.10441)
		(width 0.350012)
		(layer "F.Cu")
		(net "GND")
	)
	(segment
		(start 55.218076 -390.761474)
		(end 55.270654 -390.160002)
		(width 0.254)
		(layer "F.Cu")
		(net "GND")
	)
	(segment
		(start 466.119464 -40.45585)
		(end 466.760814 -40.45585)
		(width 0.4572)
		(layer "F.Cu")
		(net "GND")
	)
	(segment
		(start 75.702922 -340.250526)
		(end 75.449684 -340.503764)
		(width 0.381)
		(layer "F.Cu")
		(net "GND")
	)
	(segment
		(start 319.317624 -391.333482)
		(end 319.416176 -391.23493)
		(width 0.254)
		(layer "F.Cu")
		(net "GND")
	)
	(segment
		(start 269.648178 -302.73498)
		(end 268.263878 -302.73498)
		(width 0.4572)
		(layer "F.Cu")
		(net "GND")
	)
	(segment
		(start 369.72113 -396.214092)
		(end 369.72113 -395.613128)
		(width 0.254)
		(layer "F.Cu")
		(net "GND")
	)
	(segment
		(start 322.834254 -396.51305)
		(end 322.53428 -396.813024)
		(width 0.254)
		(layer "F.Cu")
		(net "GND")
	)
	(segment
		(start 346.557854 -232.599992)
		(end 346.091002 -232.334054)
		(width 0.350012)
		(layer "F.Cu")
		(net "GND")
	)
	(segment
		(start 416.468052 -202.434952)
		(end 415.083752 -202.434952)
		(width 0.4572)
		(layer "F.Cu")
		(net "GND")
	)
	(segment
		(start 97.507806 -277.870412)
		(end 97.040954 -278.13635)
		(width 0.350012)
		(layer "F.Cu")
		(net "GND")
	)
	(segment
		(start 96.737932 -239.080294)
		(end 96.27108 -238.814356)
		(width 0.350012)
		(layer "F.Cu")
		(net "GND")
	)
	(segment
		(start 344.645488 -391.784586)
		(end 344.645488 -391.333482)
		(width 0.254)
		(layer "F.Cu")
		(net "GND")
	)
	(segment
		(start 145.209768 -388.431024)
		(end 144.732756 -388.29615)
		(width 0.254)
		(layer "F.Cu")
		(net "GND")
	)
	(segment
		(start 445.361822 -8.320024)
		(end 445.360552 -8.318754)
		(width 0.3556)
		(layer "F.Cu")
		(net "GND")
	)
	(segment
		(start 129.74701 -12.497054)
		(end 129.74574 -12.495784)
		(width 0.3556)
		(layer "F.Cu")
		(net "GND")
	)
	(segment
		(start 388.217918 -277.060152)
		(end 388.68477 -277.32609)
		(width 0.350012)
		(layer "F.Cu")
		(net "GND")
	)
	(segment
		(start 97.207832 -244.750336)
		(end 96.74098 -244.484398)
		(width 0.350012)
		(layer "F.Cu")
		(net "GND")
	)
	(segment
		(start 375.528078 -294.070024)
		(end 375.99493 -294.335962)
		(width 0.350012)
		(layer "F.Cu")
		(net "GND")
	)
	(segment
		(start 409.229306 -166.21252)
		(end 409.229306 -166.54018)
		(width 0.2286)
		(layer "F.Cu")
		(net "GND")
	)
	(segment
		(start 362.067856 -233.409998)
		(end 362.534708 -233.14406)
		(width 0.350012)
		(layer "F.Cu")
		(net "GND")
	)
	(segment
		(start 189.262004 -12.4968)
		(end 189.226952 -12.461748)
		(width 0.3556)
		(layer "F.Cu")
		(net "GND")
	)
	(segment
		(start 29.252164 -199.8853)
		(end 27.867864 -199.8853)
		(width 0.4572)
		(layer "F.Cu")
		(net "GND")
	)
	(segment
		(start 102.677976 -285.160466)
		(end 102.211124 -285.426404)
		(width 0.350012)
		(layer "F.Cu")
		(net "GND")
	)
	(segment
		(start 382.748028 -241.510058)
		(end 383.21488 -241.24412)
		(width 0.350012)
		(layer "F.Cu")
		(net "GND")
	)
	(segment
		(start 370.357908 -265.720068)
		(end 370.82476 -265.986006)
		(width 0.350012)
		(layer "F.Cu")
		(net "GND")
	)
	(segment
		(start 128.227836 -256.09042)
		(end 128.694688 -255.824482)
		(width 0.350012)
		(layer "F.Cu")
		(net "GND")
	)
	(segment
		(start 371.170454 -396.520924)
		(end 370.618512 -396.710662)
		(width 0.254)
		(layer "F.Cu")
		(net "GND")
	)
	(segment
		(start 361.128056 -241.510058)
		(end 361.594908 -241.24412)
		(width 0.350012)
		(layer "F.Cu")
		(net "GND")
	)
	(segment
		(start 348.268036 -269.770098)
		(end 347.801184 -270.036036)
		(width 0.350012)
		(layer "F.Cu")
		(net "GND")
	)
	(segment
		(start 295.724072 -294.235124)
		(end 297.108372 -294.235124)
		(width 0.4572)
		(layer "F.Cu")
		(net "GND")
	)
	(segment
		(start 311.270396 -398.542002)
		(end 310.590946 -398.542002)
		(width 0.254)
		(layer "F.Cu")
		(net "GND")
	)
	(segment
		(start 350.618044 -293.260018)
		(end 350.151192 -293.525956)
		(width 0.350012)
		(layer "F.Cu")
		(net "GND")
	)
	(segment
		(start 66.101468 -384.005836)
		(end 66.101468 -384.617722)
		(width 0.254)
		(layer "F.Cu")
		(net "GND")
	)
	(segment
		(start 105.058464 -387.602984)
		(end 104.866948 -387.7945)
		(width 0.254)
		(layer "F.Cu")
		(net "GND")
	)
	(segment
		(start 381.970534 -398.542002)
		(end 381.917956 -399.143474)
		(width 0.254)
		(layer "F.Cu")
		(net "GND")
	)
	(segment
		(start 105.44556 -68.62191)
		(end 104.82961 -68.62191)
		(width 0.381)
		(layer "F.Cu")
		(net "GND")
	)
	(segment
		(start 171.666916 -13.599922)
		(end 171.666916 -12.496292)
		(width 0.3556)
		(layer "F.Cu")
		(net "GND")
	)
	(segment
		(start 165.345618 -383.402586)
		(end 165.44417 -383.304034)
		(width 0.254)
		(layer "F.Cu")
		(net "GND")
	)
	(segment
		(start 412.367984 -221.985078)
		(end 413.752284 -221.985078)
		(width 0.4572)
		(layer "F.Cu")
		(net "GND")
	)
	(segment
		(start 159.14624 -388.328662)
		(end 158.498286 -388.138924)
		(width 0.254)
		(layer "F.Cu")
		(net "GND")
	)
	(segment
		(start 361.128056 -233.409998)
		(end 361.594908 -233.14406)
		(width 0.350012)
		(layer "F.Cu")
		(net "GND")
	)
	(segment
		(start 384.159506 -180.353208)
		(end 384.159506 -180.665882)
		(width 0.2286)
		(layer "F.Cu")
		(net "GND")
	)
	(segment
		(start 135.107934 -282.730448)
		(end 135.574786 -282.996386)
		(width 0.350012)
		(layer "F.Cu")
		(net "GND")
	)
	(segment
		(start 164.333936 -128.899666)
		(end 164.343588 -128.890014)
		(width 0.381)
		(layer "F.Cu")
		(net "GND")
	)
	(segment
		(start 386.338064 -291.640006)
		(end 386.804916 -291.905944)
		(width 0.350012)
		(layer "F.Cu")
		(net "GND")
	)
	(segment
		(start 82.74431 -391.830814)
		(end 82.74431 -391.37971)
		(width 0.254)
		(layer "F.Cu")
		(net "GND")
	)
	(segment
		(start 136.987788 -289.210242)
		(end 137.45464 -289.47618)
		(width 0.350012)
		(layer "F.Cu")
		(net "GND")
	)
	(segment
		(start 352.197924 -243.940076)
		(end 351.731072 -243.674138)
		(width 0.350012)
		(layer "F.Cu")
		(net "GND")
	)
	(segment
		(start 427.768258 -12.37488)
		(end 427.768258 -12.374118)
		(width 0.3556)
		(layer "F.Cu")
		(net "GND")
	)
	(segment
		(start 302.022002 -22.12975)
		(end 302.637952 -22.12975)
		(width 0.4064)
		(layer "F.Cu")
		(net "GND")
	)
	(segment
		(start 333.39786 -248.800112)
		(end 332.931008 -248.534174)
		(width 0.350012)
		(layer "F.Cu")
		(net "GND")
	)
	(segment
		(start 163.334446 -116.296186)
		(end 163.305744 -116.267484)
		(width 0.4572)
		(layer "F.Cu")
		(net "GND")
	)
	(segment
		(start 124.297948 -283.540454)
		(end 124.7648 -283.806392)
		(width 0.350012)
		(layer "F.Cu")
		(net "GND")
	)
	(segment
		(start 389.627872 -287.59023)
		(end 390.094724 -287.856168)
		(width 0.350012)
		(layer "F.Cu")
		(net "GND")
	)
	(segment
		(start 188.84646 -353.145852)
		(end 188.417962 -353.145852)
		(width 0.2286)
		(layer "F.Cu")
		(net "GND")
	)
	(segment
		(start 129.63779 -239.080294)
		(end 130.104642 -238.814356)
		(width 0.350012)
		(layer "F.Cu")
		(net "GND")
	)
	(segment
		(start 338.39785 -280.300176)
		(end 337.930998 -280.566114)
		(width 0.350012)
		(layer "F.Cu")
		(net "GND")
	)
	(segment
		(start 100.327968 -263.290304)
		(end 99.861116 -263.556242)
		(width 0.350012)
		(layer "F.Cu")
		(net "GND")
	)
	(segment
		(start 361.42803 -273.010122)
		(end 361.894882 -273.27606)
		(width 0.350012)
		(layer "F.Cu")
		(net "GND")
	)
	(segment
		(start 400.315684 -401.30476)
		(end 400.469862 -401.150582)
		(width 0.254)
		(layer "F.Cu")
		(net "GND")
	)
	(segment
		(start 227.19157 -292.988238)
		(end 227.19157 -293.42207)
		(width 0.4572)
		(layer "F.Cu")
		(net "GND")
	)
	(segment
		(start 372.238016 -275.44014)
		(end 372.704868 -275.706078)
		(width 0.350012)
		(layer "F.Cu")
		(net "GND")
	)
	(segment
		(start 400.24685 -8.320024)
		(end 400.24685 -9.423654)
		(width 0.3556)
		(layer "F.Cu")
		(net "GND")
	)
	(segment
		(start 187.060078 -240.68532)
		(end 188.444378 -240.68532)
		(width 0.4572)
		(layer "F.Cu")
		(net "GND")
	)
	(segment
		(start 23.240746 -389.329168)
		(end 22.85746 -389.329168)
		(width 0.2032)
		(layer "F.Cu")
		(net "GND")
	)
	(segment
		(start 367.238026 -235.840016)
		(end 367.704878 -235.574078)
		(width 0.350012)
		(layer "F.Cu")
		(net "GND")
	)
	(segment
		(start 424.5356 -423.997882)
		(end 424.315636 -424.217846)
		(width 0.254)
		(layer "F.Cu")
		(net "GND")
	)
	(segment
		(start 118.417848 -383.622042)
		(end 118.718076 -383.92227)
		(width 0.2032)
		(layer "F.Cu")
		(net "GND")
	)
	(segment
		(start 101.767894 -177.43551)
		(end 102.07752 -177.125884)
		(width 0.381)
		(layer "F.Cu")
		(net "GND")
	)
	(segment
		(start 26.393394 -423.509694)
		(end 26.393394 -424.525694)
		(width 0.4572)
		(layer "F.Cu")
		(net "GND")
	)
	(segment
		(start 408.841702 -163.336224)
		(end 408.841702 -162.974782)
		(width 0.381)
		(layer "F.Cu")
		(net "GND")
	)
	(segment
		(start 143.567912 -271.390364)
		(end 144.034764 -271.656302)
		(width 0.350012)
		(layer "F.Cu")
		(net "GND")
	)
	(segment
		(start 330.63307 -21.047964)
		(end 331.112876 -21.047964)
		(width 0.381)
		(layer "F.Cu")
		(net "GND")
	)
	(segment
		(start 121.177812 -232.600246)
		(end 121.644664 -232.334308)
		(width 0.350012)
		(layer "F.Cu")
		(net "GND")
	)
	(segment
		(start 375.41835 -396.710662)
		(end 374.77065 -396.520924)
		(width 0.254)
		(layer "F.Cu")
		(net "GND")
	)
	(segment
		(start 122.41784 -280.30043)
		(end 122.884692 -280.566368)
		(width 0.350012)
		(layer "F.Cu")
		(net "GND")
	)
	(segment
		(start 123.570492 -384.617722)
		(end 123.517914 -383.92227)
		(width 0.254)
		(layer "F.Cu")
		(net "GND")
	)
	(segment
		(start 387.448044 -233.409998)
		(end 387.914896 -233.14406)
		(width 0.350012)
		(layer "F.Cu")
		(net "GND")
	)
	(segment
		(start 121.170446 -386.6388)
		(end 120.47855 -386.449062)
		(width 0.254)
		(layer "F.Cu")
		(net "GND")
	)
	(segment
		(start 346.858082 -293.260018)
		(end 346.39123 -293.525956)
		(width 0.350012)
		(layer "F.Cu")
		(net "GND")
	)
	(segment
		(start 162.690048 -384.617722)
		(end 162.098228 -384.617722)
		(width 0.254)
		(layer "F.Cu")
		(net "GND")
	)
	(segment
		(start 102.378002 -250.420378)
		(end 101.91115 -250.15444)
		(width 0.350012)
		(layer "F.Cu")
		(net "GND")
	)
	(segment
		(start 168.527984 -277.235412)
		(end 167.143684 -277.235412)
		(width 0.4572)
		(layer "F.Cu")
		(net "GND")
	)
	(segment
		(start 160.362646 -37.139372)
		(end 159.35706 -38.144958)
		(width 0.4572)
		(layer "F.Cu")
		(net "GND")
	)
	(segment
		(start 356.728014 -271.39011)
		(end 356.261162 -271.656048)
		(width 0.350012)
		(layer "F.Cu")
		(net "GND")
	)
	(segment
		(start 375.278396 -394.831062)
		(end 374.77065 -395.0208)
		(width 0.254)
		(layer "F.Cu")
		(net "GND")
	)
	(segment
		(start 112.68202 -387.231128)
		(end 113.201704 -386.931154)
		(width 0.254)
		(layer "F.Cu")
		(net "GND")
	)
	(segment
		(start 350.645476 -391.333482)
		(end 350.744028 -391.23493)
		(width 0.254)
		(layer "F.Cu")
		(net "GND")
	)
	(segment
		(start 43.543982 -388.297674)
		(end 44.19092 -388.297674)
		(width 0.254)
		(layer "F.Cu")
		(net "GND")
	)
	(segment
		(start 378.01804 -399.663158)
		(end 378.318014 -399.143474)
		(width 0.254)
		(layer "F.Cu")
		(net "GND")
	)
	(segment
		(start 153.698194 -390.160002)
		(end 153.018998 -390.160002)
		(width 0.254)
		(layer "F.Cu")
		(net "GND")
	)
	(segment
		(start 66.314828 -387.231128)
		(end 66.070734 -386.987034)
		(width 0.254)
		(layer "F.Cu")
		(net "GND")
	)
	(segment
		(start 439.100214 -305.28514)
		(end 437.715914 -305.28514)
		(width 0.4572)
		(layer "F.Cu")
		(net "GND")
	)
	(segment
		(start 131.517898 -248.800366)
		(end 131.98475 -248.534428)
		(width 0.350012)
		(layer "F.Cu")
		(net "GND")
	)
	(segment
		(start 326.81799 -235.840016)
		(end 326.351138 -235.574078)
		(width 0.350012)
		(layer "F.Cu")
		(net "GND")
	)
	(segment
		(start 57.317894 -383.402586)
		(end 57.317894 -382.951482)
		(width 0.254)
		(layer "F.Cu")
		(net "GND")
	)
	(segment
		(start 133.69798 -285.160466)
		(end 134.164832 -285.426404)
		(width 0.350012)
		(layer "F.Cu")
		(net "GND")
	)
	(segment
		(start 90.457782 -285.160466)
		(end 89.99093 -285.426404)
		(width 0.350012)
		(layer "F.Cu")
		(net "GND")
	)
	(segment
		(start 348.58452 -342.01354)
		(end 348.83852 -341.75954)
		(width 0.2286)
		(layer "F.Cu")
		(net "GND")
	)
	(segment
		(start 104.257856 -243.94033)
		(end 103.791004 -243.674392)
		(width 0.350012)
		(layer "F.Cu")
		(net "GND")
	)
	(segment
		(start 332.060042 -392.1252)
		(end 332.593442 -392.1252)
		(width 0.254)
		(layer "F.Cu")
		(net "GND")
	)
	(segment
		(start 296.215562 -18.847308)
		(end 296.846498 -18.847308)
		(width 0.4064)
		(layer "F.Cu")
		(net "GND")
	)
	(segment
		(start 368.64798 -252.850142)
		(end 369.114832 -252.584204)
		(width 0.350012)
		(layer "F.Cu")
		(net "GND")
	)
	(segment
		(start 386.338064 -288.399982)
		(end 386.804916 -288.66592)
		(width 0.350012)
		(layer "F.Cu")
		(net "GND")
	)
	(segment
		(start 113.501678 -387.231128)
		(end 113.721134 -387.231128)
		(width 0.254)
		(layer "F.Cu")
		(net "GND")
	)
	(segment
		(start 80.58785 -284.35046)
		(end 80.120998 -284.616398)
		(width 0.350012)
		(layer "F.Cu")
		(net "GND")
	)
	(segment
		(start 127.818388 -388.328662)
		(end 127.170434 -388.138924)
		(width 0.254)
		(layer "F.Cu")
		(net "GND")
	)
	(segment
		(start 304.718212 -396.710662)
		(end 304.070258 -396.520924)
		(width 0.254)
		(layer "F.Cu")
		(net "GND")
	)
	(segment
		(start 394.84554 -7.215124)
		(end 394.84554 -7.215886)
		(width 0.3556)
		(layer "F.Cu")
		(net "GND")
	)
	(segment
		(start 419.819074 -398.542002)
		(end 419.298374 -398.542002)
		(width 0.254)
		(layer "F.Cu")
		(net "GND")
	)
	(segment
		(start 384.37058 -396.520924)
		(end 383.818384 -396.710662)
		(width 0.254)
		(layer "F.Cu")
		(net "GND")
	)
	(segment
		(start 359.078022 -293.260018)
		(end 358.61117 -293.525956)
		(width 0.350012)
		(layer "F.Cu")
		(net "GND")
	)
	(segment
		(start 382.491234 -398.542002)
		(end 381.970534 -398.542002)
		(width 0.254)
		(layer "F.Cu")
		(net "GND")
	)
	(segment
		(start 134.189216 -53.574188)
		(end 134.94512 -53.574188)
		(width 0.4572)
		(layer "F.Cu")
		(net "GND")
	)
	(segment
		(start 85.34781 -177.48631)
		(end 85.60562 -177.2285)
		(width 0.381)
		(layer "F.Cu")
		(net "GND")
	)
	(segment
		(start 90.927936 -271.390364)
		(end 90.461084 -271.656302)
		(width 0.350012)
		(layer "F.Cu")
		(net "GND")
	)
	(segment
		(start 381.338074 -226.120198)
		(end 381.804926 -225.85426)
		(width 0.350012)
		(layer "F.Cu")
		(net "GND")
	)
	(segment
		(start 388.384796 -222.614236)
		(end 388.857998 -222.880174)
		(width 0.350012)
		(layer "F.Cu")
		(net "GND")
	)
	(segment
		(start 317.270384 -395.0208)
		(end 316.578234 -394.831062)
		(width 0.254)
		(layer "F.Cu")
		(net "GND")
	)
	(segment
		(start 25.90673 -351.978722)
		(end 25.90673 -352.614738)
		(width 0.381)
		(layer "F.Cu")
		(net "GND")
	)
	(segment
		(start 112.717834 -248.800366)
		(end 113.184686 -248.534428)
		(width 0.350012)
		(layer "F.Cu")
		(net "GND")
	)
	(segment
		(start 303.268126 -200.735184)
		(end 304.652426 -200.735184)
		(width 0.4572)
		(layer "F.Cu")
		(net "GND")
	)
	(segment
		(start 113.487962 -287.590484)
		(end 113.954814 -287.856422)
		(width 0.350012)
		(layer "F.Cu")
		(net "GND")
	)
	(segment
		(start 162.690048 -384.617722)
		(end 163.298378 -384.617722)
		(width 0.254)
		(layer "F.Cu")
		(net "GND")
	)
	(segment
		(start 331.81798 -293.260018)
		(end 331.351128 -293.525956)
		(width 0.350012)
		(layer "F.Cu")
		(net "GND")
	)
	(segment
		(start 312.11774 -391.784586)
		(end 312.11774 -391.333482)
		(width 0.254)
		(layer "F.Cu")
		(net "GND")
	)
	(segment
		(start 381.167894 -294.070024)
		(end 381.634746 -294.335962)
		(width 0.350012)
		(layer "F.Cu")
		(net "GND")
	)
	(segment
		(start 136.217914 -239.080294)
		(end 136.684766 -238.814356)
		(width 0.350012)
		(layer "F.Cu")
		(net "GND")
	)
	(segment
		(start 141.687804 -268.15034)
		(end 142.154656 -268.416278)
		(width 0.350012)
		(layer "F.Cu")
		(net "GND")
	)
	(segment
		(start 153.018998 -390.160002)
		(end 152.498298 -390.160002)
		(width 0.254)
		(layer "F.Cu")
		(net "GND")
	)
	(segment
		(start 126.7206 -41.014396)
		(end 126.223522 -40.517318)
		(width 0.381)
		(layer "F.Cu")
		(net "GND")
	)
	(segment
		(start 97.745296 -423.284904)
		(end 97.917508 -423.457116)
		(width 0.381)
		(layer "F.Cu")
		(net "GND")
	)
	(segment
		(start 391.03808 -281.920188)
		(end 391.504678 -282.186126)
		(width 0.350012)
		(layer "F.Cu")
		(net "GND")
	)
	(segment
		(start 403.846792 -10.16635)
		(end 403.845522 -10.16508)
		(width 0.3556)
		(layer "F.Cu")
		(net "GND")
	)
	(segment
		(start 410.545788 -399.663158)
		(end 410.845762 -399.143474)
		(width 0.254)
		(layer "F.Cu")
		(net "GND")
	)
	(segment
		(start 356.728014 -290.83)
		(end 356.261162 -291.095938)
		(width 0.350012)
		(layer "F.Cu")
		(net "GND")
	)
	(segment
		(start 45.582078 -387.231128)
		(end 46.101762 -386.931154)
		(width 0.254)
		(layer "F.Cu")
		(net "GND")
	)
	(segment
		(start 339.977984 -229.360222)
		(end 339.511132 -229.094284)
		(width 0.350012)
		(layer "F.Cu")
		(net "GND")
	)
	(segment
		(start 117.41785 -232.600246)
		(end 117.884702 -232.334308)
		(width 0.350012)
		(layer "F.Cu")
		(net "GND")
	)
	(segment
		(start 347.968062 -251.23013)
		(end 347.50121 -250.964192)
		(width 0.350012)
		(layer "F.Cu")
		(net "GND")
	)
	(segment
		(start 98.918014 -265.720322)
		(end 98.451162 -265.98626)
		(width 0.350012)
		(layer "F.Cu")
		(net "GND")
	)
	(segment
		(start 98.950272 -36.305998)
		(end 98.950272 -36.97859)
		(width 0.3556)
		(layer "F.Cu")
		(net "GND")
	)
	(segment
		(start 146.145758 -383.402586)
		(end 146.145758 -382.958086)
		(width 0.254)
		(layer "F.Cu")
		(net "GND")
	)
	(segment
		(start 306.991004 -398.542002)
		(end 306.470304 -398.542002)
		(width 0.254)
		(layer "F.Cu")
		(net "GND")
	)
	(segment
		(start 90.157808 -224.50044)
		(end 89.690956 -224.234502)
		(width 0.350012)
		(layer "F.Cu")
		(net "GND")
	)
	(segment
		(start 158.395416 -58.109104)
		(end 158.39567 -58.109358)
		(width 0.4572)
		(layer "F.Cu")
		(net "GND")
	)
	(segment
		(start 389.327898 -236.650022)
		(end 389.79475 -236.384084)
		(width 0.350012)
		(layer "F.Cu")
		(net "GND")
	)
	(segment
		(start 139.507976 -226.930458)
		(end 139.974828 -226.66452)
		(width 0.350012)
		(layer "F.Cu")
		(net "GND")
	)
	(segment
		(start 146.38782 -264.910316)
		(end 147.042886 -264.910316)
		(width 0.350012)
		(layer "F.Cu")
		(net "GND")
	)
	(segment
		(start 338.56803 -249.610118)
		(end 338.101178 -249.34418)
		(width 0.350012)
		(layer "F.Cu")
		(net "GND")
	)
	(segment
		(start 48.070516 -388.138924)
		(end 48.71847 -388.328662)
		(width 0.254)
		(layer "F.Cu")
		(net "GND")
	)
	(segment
		(start 32.695896 -231.335326)
		(end 34.080196 -231.335326)
		(width 0.4572)
		(layer "F.Cu")
		(net "GND")
	)
	(segment
		(start 93.19006 -384.617722)
		(end 92.59824 -384.617722)
		(width 0.254)
		(layer "F.Cu")
		(net "GND")
	)
	(segment
		(start 84.706206 -386.449062)
		(end 84.19846 -386.6388)
		(width 0.254)
		(layer "F.Cu")
		(net "GND")
	)
	(segment
		(start 139.80795 -261.670292)
		(end 140.274802 -261.93623)
		(width 0.350012)
		(layer "F.Cu")
		(net "GND")
	)
	(segment
		(start 207.813148 -123.569984)
		(end 207.626204 -123.756928)
		(width 0.3556)
		(layer "F.Cu")
		(net "GND")
	)
	(segment
		(start 303.268126 -275.535136)
		(end 304.652426 -275.535136)
		(width 0.4572)
		(layer "F.Cu")
		(net "GND")
	)
	(segment
		(start 366.597946 -278.680164)
		(end 367.064798 -278.946102)
		(width 0.350012)
		(layer "F.Cu")
		(net "GND")
	)
	(segment
		(start 332.45806 -224.500186)
		(end 331.991208 -224.234248)
		(width 0.350012)
		(layer "F.Cu")
		(net "GND")
	)
	(segment
		(start 341.857838 -253.660148)
		(end 341.390986 -253.39421)
		(width 0.350012)
		(layer "F.Cu")
		(net "GND")
	)
	(segment
		(start 121.177812 -239.080294)
		(end 121.644664 -238.814356)
		(width 0.350012)
		(layer "F.Cu")
		(net "GND")
	)
	(segment
		(start 348.597982 -398.542002)
		(end 347.918786 -398.542002)
		(width 0.254)
		(layer "F.Cu")
		(net "GND")
	)
	(segment
		(start 295.724072 -303.585118)
		(end 297.108372 -303.585118)
		(width 0.4572)
		(layer "F.Cu")
		(net "GND")
	)
	(segment
		(start 11.533124 -53.909214)
		(end 11.537442 -53.904896)
		(width 0.4572)
		(layer "F.Cu")
		(net "GND")
	)
	(segment
		(start 18.828258 -428.589948)
		(end 18.828258 -427.980348)
		(width 0.3556)
		(layer "F.Cu")
		(net "GND")
	)
	(segment
		(start 193.35623 -43.849544)
		(end 192.560194 -43.849544)
		(width 0.3556)
		(layer "F.Cu")
		(net "GND")
	)
	(segment
		(start 312.216292 -399.76171)
		(end 312.11774 -399.663158)
		(width 0.254)
		(layer "F.Cu")
		(net "GND")
	)
	(segment
		(start 165.090094 -384.617722)
		(end 165.729158 -384.617722)
		(width 0.254)
		(layer "F.Cu")
		(net "GND")
	)
	(segment
		(start 360.657902 -240.700052)
		(end 361.124754 -240.434114)
		(width 0.350012)
		(layer "F.Cu")
		(net "GND")
	)
	(segment
		(start 394.327888 -277.870158)
		(end 394.982954 -277.870158)
		(width 0.350012)
		(layer "F.Cu")
		(net "GND")
	)
	(segment
		(start 215.922352 -25.311354)
		(end 217.062812 -25.311354)
		(width 0.4572)
		(layer "F.Cu")
		(net "GND")
	)
	(segment
		(start 362.067856 -244.750082)
		(end 362.534708 -244.484144)
		(width 0.350012)
		(layer "F.Cu")
		(net "GND")
	)
	(segment
		(start 27.26817 -40.180514)
		(end 27.414474 -40.326818)
		(width 0.4572)
		(layer "F.Cu")
		(net "GND")
	)
	(segment
		(start 363.778038 -281.920188)
		(end 364.24489 -282.186126)
		(width 0.350012)
		(layer "F.Cu")
		(net "GND")
	)
	(segment
		(start 325.408036 -252.850142)
		(end 324.75297 -252.850142)
		(width 0.350012)
		(layer "F.Cu")
		(net "GND")
	)
	(segment
		(start 318.47028 -392.999722)
		(end 317.862204 -392.999722)
		(width 0.254)
		(layer "F.Cu")
		(net "GND")
	)
	(segment
		(start 124.467874 -223.690434)
		(end 124.934726 -223.424496)
		(width 0.350012)
		(layer "F.Cu")
		(net "GND")
	)
	(segment
		(start 353.907852 -276.250146)
		(end 353.441 -276.516084)
		(width 0.350012)
		(layer "F.Cu")
		(net "GND")
	)
	(segment
		(start 133.63448 -387.831076)
		(end 133.934454 -388.13105)
		(width 0.254)
		(layer "F.Cu")
		(net "GND")
	)
	(segment
		(start 131.517898 -247.180354)
		(end 131.98475 -246.914416)
		(width 0.350012)
		(layer "F.Cu")
		(net "GND")
	)
	(segment
		(start 85.457792 -230.980234)
		(end 84.99094 -230.714296)
		(width 0.350012)
		(layer "F.Cu")
		(net "GND")
	)
	(segment
		(start 376.167904 -256.090166)
		(end 376.634756 -255.824228)
		(width 0.350012)
		(layer "F.Cu")
		(net "GND")
	)
	(segment
		(start 140.3096 -402.755608)
		(end 140.277342 -402.755608)
		(width 0.381)
		(layer "F.Cu")
		(net "GND")
	)
	(segment
		(start 324.00748 -340.2457)
		(end 323.639688 -340.2457)
		(width 0.381)
		(layer "F.Cu")
		(net "GND")
	)
	(segment
		(start 389.627872 -264.910062)
		(end 390.094724 -265.176)
		(width 0.350012)
		(layer "F.Cu")
		(net "GND")
	)
	(segment
		(start 36.795964 -295.9354)
		(end 35.411664 -295.9354)
		(width 0.4572)
		(layer "F.Cu")
		(net "GND")
	)
	(segment
		(start 157.245812 -383.92227)
		(end 156.945584 -383.622042)
		(width 0.254)
		(layer "F.Cu")
		(net "GND")
	)
	(segment
		(start 410.8196 -77.913484)
		(end 411.456886 -77.913484)
		(width 0.4064)
		(layer "F.Cu")
		(net "GND")
	)
	(segment
		(start 31.147004 -11.26998)
		(end 31.147004 -10.16635)
		(width 0.3556)
		(layer "F.Cu")
		(net "GND")
	)
	(segment
		(start 351.557844 -293.260018)
		(end 351.091246 -293.525956)
		(width 0.350012)
		(layer "F.Cu")
		(net "GND")
	)
	(segment
		(start 351.518728 -398.542002)
		(end 350.998028 -398.542002)
		(width 0.254)
		(layer "F.Cu")
		(net "GND")
	)
	(segment
		(start 165.729158 -384.617722)
		(end 165.729158 -384.005836)
		(width 0.254)
		(layer "F.Cu")
		(net "GND")
	)
	(segment
		(start 315.517276 -336.820256)
		(end 315.945774 -336.820256)
		(width 0.2286)
		(layer "F.Cu")
		(net "GND")
	)
	(segment
		(start 302.620934 -398.613122)
		(end 302.620934 -398.01292)
		(width 0.254)
		(layer "F.Cu")
		(net "GND")
	)
	(segment
		(start 124.233178 -51.185064)
		(end 123.778264 -51.185064)
		(width 0.4572)
		(layer "F.Cu")
		(net "GND")
	)
	(segment
		(start 109.427772 -247.99036)
		(end 108.961174 -247.724422)
		(width 0.350012)
		(layer "F.Cu")
		(net "GND")
	)
	(segment
		(start 90.14587 -383.92227)
		(end 89.845642 -383.622042)
		(width 0.254)
		(layer "F.Cu")
		(net "GND")
	)
	(segment
		(start 79.347822 -251.230384)
		(end 78.88097 -250.964446)
		(width 0.350012)
		(layer "F.Cu")
		(net "GND")
	)
	(segment
		(start 366.297972 -247.1801)
		(end 366.764824 -246.914162)
		(width 0.350012)
		(layer "F.Cu")
		(net "GND")
	)
	(segment
		(start 164.45103 -353.058984)
		(end 164.45103 -353.72167)
		(width 0.381)
		(layer "F.Cu")
		(net "GND")
	)
	(segment
		(start 83.59013 -384.617722)
		(end 84.19846 -384.617722)
		(width 0.254)
		(layer "F.Cu")
		(net "GND")
	)
	(segment
		(start 309.816246 -399.76171)
		(end 309.717694 -399.663158)
		(width 0.254)
		(layer "F.Cu")
		(net "GND")
	)
	(segment
		(start 106.437938 -291.64026)
		(end 105.971086 -291.906198)
		(width 0.350012)
		(layer "F.Cu")
		(net "GND")
	)
	(segment
		(start 166.10457 -387.069076)
		(end 165.942518 -387.231128)
		(width 0.254)
		(layer "F.Cu")
		(net "GND")
	)
	(segment
		(start 414.756854 -7.217156)
		(end 414.756854 -8.320024)
		(width 0.3556)
		(layer "F.Cu")
		(net "GND")
	)
	(segment
		(start 108.940346 -57.20207)
		(end 110.013496 -57.20207)
		(width 0.4064)
		(layer "F.Cu")
		(net "GND")
	)
	(segment
		(start 173.625002 -390.53008)
		(end 173.232064 -390.923018)
		(width 0.254)
		(layer "F.Cu")
		(net "GND")
	)
	(segment
		(start 140.27785 -277.060406)
		(end 140.744702 -277.326344)
		(width 0.350012)
		(layer "F.Cu")
		(net "GND")
	)
	(segment
		(start 159.698182 -384.617722)
		(end 159.645604 -383.92227)
		(width 0.254)
		(layer "F.Cu")
		(net "GND")
	)
	(segment
		(start 331.518006 -252.040136)
		(end 331.051154 -251.774198)
		(width 0.350012)
		(layer "F.Cu")
		(net "GND")
	)
	(segment
		(start 392.61796 -240.700052)
		(end 393.084812 -240.434114)
		(width 0.350012)
		(layer "F.Cu")
		(net "GND")
	)
	(segment
		(start 83.877912 -265.720322)
		(end 83.41106 -265.98626)
		(width 0.350012)
		(layer "F.Cu")
		(net "GND")
	)
	(segment
		(start 128.52781 -263.290304)
		(end 128.994662 -263.556242)
		(width 0.350012)
		(layer "F.Cu")
		(net "GND")
	)
	(segment
		(start 191.522096 -115.452906)
		(end 191.911986 -115.842796)
		(width 0.254)
		(layer "F.Cu")
		(net "GND")
	)
	(segment
		(start 400.24685 -7.217156)
		(end 400.24685 -8.320024)
		(width 0.3556)
		(layer "F.Cu")
		(net "GND")
	)
	(segment
		(start 346.145612 -392.30427)
		(end 345.845384 -392.004042)
		(width 0.254)
		(layer "F.Cu")
		(net "GND")
	)
	(segment
		(start 65.81648 -383.304034)
		(end 65.81648 -382.85293)
		(width 0.254)
		(layer "F.Cu")
		(net "GND")
	)
	(segment
		(start 350.31807 -242.320064)
		(end 349.851218 -242.054126)
		(width 0.350012)
		(layer "F.Cu")
		(net "GND")
	)
	(segment
		(start 100.901754 -341.764366)
		(end 101.329236 -341.764366)
		(width 0.2286)
		(layer "F.Cu")
		(net "GND")
	)
	(segment
		(start 360.657902 -235.840016)
		(end 361.124754 -235.574078)
		(width 0.350012)
		(layer "F.Cu")
		(net "GND")
	)
	(segment
		(start 454.188068 -284.034992)
		(end 452.803768 -284.034992)
		(width 0.4572)
		(layer "F.Cu")
		(net "GND")
	)
	(segment
		(start 325.408036 -254.470154)
		(end 324.75297 -254.470154)
		(width 0.350012)
		(layer "F.Cu")
		(net "GND")
	)
	(segment
		(start 132.17398 -27.25928)
		(end 132.44068 -27.52598)
		(width 0.254)
		(layer "F.Cu")
		(net "GND")
	)
	(segment
		(start 318.47028 -395.0208)
		(end 317.778384 -394.831062)
		(width 0.254)
		(layer "F.Cu")
		(net "GND")
	)
	(segment
		(start 102.824788 -345.150948)
		(end 103.412798 -345.150948)
		(width 0.381)
		(layer "F.Cu")
		(net "GND")
	)
	(segment
		(start 124.297948 -265.720322)
		(end 124.7648 -265.98626)
		(width 0.350012)
		(layer "F.Cu")
		(net "GND")
	)
	(segment
		(start 134.80796 -247.99036)
		(end 135.274812 -247.724422)
		(width 0.350012)
		(layer "F.Cu")
		(net "GND")
	)
	(segment
		(start 211.149692 -26.468324)
		(end 211.992464 -26.468324)
		(width 0.3556)
		(layer "F.Cu")
		(net "GND")
	)
	(segment
		(start 187.522104 -117.052852)
		(end 187.911994 -117.442742)
		(width 0.254)
		(layer "F.Cu")
		(net "GND")
	)
	(segment
		(start 85.757766 -286.780478)
		(end 85.291422 -287.045908)
		(width 0.350012)
		(layer "F.Cu")
		(net "GND")
	)
	(segment
		(start 279.113742 -123.035314)
		(end 278.504142 -123.035314)
		(width 0.381)
		(layer "F.Cu")
		(net "GND")
	)
	(segment
		(start 338.097876 -255.28016)
		(end 337.631024 -255.014222)
		(width 0.350012)
		(layer "F.Cu")
		(net "GND")
	)
	(segment
		(start 124.417836 -391.281158)
		(end 124.718064 -390.761474)
		(width 0.254)
		(layer "F.Cu")
		(net "GND")
	)
	(segment
		(start 336.245454 -391.784586)
		(end 336.245454 -391.333482)
		(width 0.254)
		(layer "F.Cu")
		(net "GND")
	)
	(segment
		(start 394.84681 -11.26998)
		(end 394.84554 -10.16508)
		(width 0.3556)
		(layer "F.Cu")
		(net "GND")
	)
	(segment
		(start 168.06799 -347.289882)
		(end 167.342566 -347.289882)
		(width 0.381)
		(layer "F.Cu")
		(net "GND")
	)
	(segment
		(start 133.227826 -279.490424)
		(end 133.694678 -279.756362)
		(width 0.350012)
		(layer "F.Cu")
		(net "GND")
	)
	(segment
		(start 319.317624 -392.004042)
		(end 319.317624 -391.784586)
		(width 0.254)
		(layer "F.Cu")
		(net "GND")
	)
	(segment
		(start 110.83798 -243.94033)
		(end 110.371128 -243.674392)
		(width 0.350012)
		(layer "F.Cu")
		(net "GND")
	)
	(segment
		(start 137.157968 -222.880428)
		(end 137.62482 -222.61449)
		(width 0.350012)
		(layer "F.Cu")
		(net "GND")
	)
	(segment
		(start 135.107934 -264.910316)
		(end 135.574786 -265.176254)
		(width 0.350012)
		(layer "F.Cu")
		(net "GND")
	)
	(segment
		(start 387.748018 -266.530074)
		(end 388.21487 -266.796012)
		(width 0.350012)
		(layer "F.Cu")
		(net "GND")
	)
	(segment
		(start 95.327978 -223.690434)
		(end 94.861126 -223.424496)
		(width 0.350012)
		(layer "F.Cu")
		(net "GND")
	)
	(segment
		(start 126.404878 -48.137064)
		(end 125.788928 -48.137064)
		(width 0.4572)
		(layer "F.Cu")
		(net "GND")
	)
	(segment
		(start 183.522112 -117.052852)
		(end 183.132222 -117.442742)
		(width 0.254)
		(layer "F.Cu")
		(net "GND")
	)
	(segment
		(start 377.878086 -281.920188)
		(end 378.344938 -282.186126)
		(width 0.350012)
		(layer "F.Cu")
		(net "GND")
	)
	(segment
		(start 107.078018 -247.180354)
		(end 106.611166 -246.914416)
		(width 0.350012)
		(layer "F.Cu")
		(net "GND")
	)
	(segment
		(start 103.617776 -285.160466)
		(end 103.151178 -285.426404)
		(width 0.350012)
		(layer "F.Cu")
		(net "GND")
	)
	(segment
		(start 369.588034 -222.070168)
		(end 370.054886 -221.80423)
		(width 0.350012)
		(layer "F.Cu")
		(net "GND")
	)
	(segment
		(start 192.419478 -428.693326)
		(end 192.419478 -427.848776)
		(width 0.381)
		(layer "F.Cu")
		(net "GND")
	)
	(segment
		(start 91.608656 -73.110852)
		(end 91.372436 -73.347072)
		(width 0.2286)
		(layer "F.Cu")
		(net "GND")
	)
	(segment
		(start 62.117986 -383.622296)
		(end 62.41796 -383.92227)
		(width 0.254)
		(layer "F.Cu")
		(net "GND")
	)
	(segment
		(start 328.554842 -390.652)
		(end 329.023472 -390.652)
		(width 0.254)
		(layer "F.Cu")
		(net "GND")
	)
	(segment
		(start 320.616326 -402.890736)
		(end 320.612262 -402.8948)
		(width 0.3048)
		(layer "F.Cu")
		(net "GND")
	)
	(segment
		(start 363.478064 -239.08004)
		(end 363.944916 -238.814102)
		(width 0.350012)
		(layer "F.Cu")
		(net "GND")
	)
	(segment
		(start 345.447874 -274.630134)
		(end 344.981022 -274.896072)
		(width 0.350012)
		(layer "F.Cu")
		(net "GND")
	)
	(segment
		(start 66.666364 -151.149812)
		(end 67.3354 -151.149812)
		(width 0.381)
		(layer "F.Cu")
		(net "GND")
	)
	(segment
		(start 404.898352 -395.0208)
		(end 404.206202 -394.831062)
		(width 0.254)
		(layer "F.Cu")
		(net "GND")
	)
	(segment
		(start 378.347986 -271.39011)
		(end 378.814838 -271.656048)
		(width 0.350012)
		(layer "F.Cu")
		(net "GND")
	)
	(segment
		(start 29.299662 -430.769014)
		(end 29.299662 -430.159414)
		(width 0.3556)
		(layer "F.Cu")
		(net "GND")
	)
	(segment
		(start 77.767942 -268.15034)
		(end 77.112876 -268.15034)
		(width 0.350012)
		(layer "F.Cu")
		(net "GND")
	)
	(segment
		(start 112.717834 -224.50044)
		(end 113.184686 -224.234502)
		(width 0.350012)
		(layer "F.Cu")
		(net "GND")
	)
	(segment
		(start 239.800384 -290.741862)
		(end 239.893856 -290.741862)
		(width 0.4572)
		(layer "F.Cu")
		(net "GND")
	)
	(segment
		(start 189.861952 -13.599922)
		(end 189.861952 -12.461748)
		(width 0.3556)
		(layer "F.Cu")
		(net "GND")
	)
	(segment
		(start 391.50798 -290.83)
		(end 391.974832 -291.095938)
		(width 0.350012)
		(layer "F.Cu")
		(net "GND")
	)
	(segment
		(start 310.917844 -392.004296)
		(end 311.217818 -392.30427)
		(width 0.254)
		(layer "F.Cu")
		(net "GND")
	)
	(segment
		(start 384.927856 -274.630134)
		(end 385.394708 -274.896072)
		(width 0.350012)
		(layer "F.Cu")
		(net "GND")
	)
	(segment
		(start 134.63778 -268.960346)
		(end 135.104632 -269.226284)
		(width 0.350012)
		(layer "F.Cu")
		(net "GND")
	)
	(segment
		(start 431.654204 -356.35184)
		(end 431.724054 -356.28199)
		(width 0.3556)
		(layer "F.Cu")
		(net "GND")
	)
	(segment
		(start 381.338074 -227.74021)
		(end 381.804926 -227.474272)
		(width 0.350012)
		(layer "F.Cu")
		(net "GND")
	)
	(segment
		(start 68.790566 -393.510262)
		(end 68.790566 -394.080746)
		(width 0.254)
		(layer "F.Cu")
		(net "GND")
	)
	(segment
		(start 48.71847 -388.328662)
		(end 49.270666 -388.138924)
		(width 0.254)
		(layer "F.Cu")
		(net "GND")
	)
	(segment
		(start 179.516024 -210.085432)
		(end 180.900324 -210.085432)
		(width 0.4572)
		(layer "F.Cu")
		(net "GND")
	)
	(segment
		(start 297.30319 -351.973896)
		(end 297.049952 -352.227134)
		(width 0.381)
		(layer "F.Cu")
		(net "GND")
	)
	(segment
		(start 123.997974 -230.980234)
		(end 124.464826 -230.714296)
		(width 0.350012)
		(layer "F.Cu")
		(net "GND")
	)
	(segment
		(start 59.428126 -209.235294)
		(end 58.043826 -209.235294)
		(width 0.4572)
		(layer "F.Cu")
		(net "GND")
	)
	(segment
		(start 110.584996 -399.736056)
		(end 111.286544 -400.437604)
		(width 0.3048)
		(layer "F.Cu")
		(net "GND")
	)
	(segment
		(start 99.857814 -278.680418)
		(end 99.390962 -278.946356)
		(width 0.350012)
		(layer "F.Cu")
		(net "GND")
	)
	(segment
		(start 334.320642 -396.74673)
		(end 334.109568 -396.813024)
		(width 0.254)
		(layer "F.Cu")
		(net "GND")
	)
	(segment
		(start 327.117964 -273.820128)
		(end 326.651112 -274.086066)
		(width 0.350012)
		(layer "F.Cu")
		(net "GND")
	)
	(segment
		(start 121.007886 -282.730448)
		(end 121.474738 -282.996386)
		(width 0.350012)
		(layer "F.Cu")
		(net "GND")
	)
	(segment
		(start 389.627872 -281.110182)
		(end 390.094724 -281.37612)
		(width 0.350012)
		(layer "F.Cu")
		(net "GND")
	)
	(segment
		(start 120.49125 -390.160002)
		(end 119.97055 -390.160002)
		(width 0.254)
		(layer "F.Cu")
		(net "GND")
	)
	(segment
		(start 375.22785 -222.070168)
		(end 375.694702 -221.80423)
		(width 0.350012)
		(layer "F.Cu")
		(net "GND")
	)
	(segment
		(start 425.96689 -11.26998)
		(end 425.96689 -10.16635)
		(width 0.3556)
		(layer "F.Cu")
		(net "GND")
	)
	(segment
		(start 105.082848 -382.27)
		(end 105.302558 -382.27)
		(width 0.254)
		(layer "F.Cu")
		(net "GND")
	)
	(segment
		(start 336.517996 -294.88003)
		(end 336.051144 -295.145968)
		(width 0.350012)
		(layer "F.Cu")
		(net "GND")
	)
	(segment
		(start 54.662324 -384.617722)
		(end 55.270654 -384.617722)
		(width 0.254)
		(layer "F.Cu")
		(net "GND")
	)
	(segment
		(start 431.55616 -218.585034)
		(end 430.17186 -218.585034)
		(width 0.4572)
		(layer "F.Cu")
		(net "GND")
	)
	(segment
		(start 212.376258 -15.920974)
		(end 211.972398 -15.517114)
		(width 0.3556)
		(layer "F.Cu")
		(net "GND")
	)
	(segment
		(start 92.037916 -247.180354)
		(end 91.571064 -246.914416)
		(width 0.350012)
		(layer "F.Cu")
		(net "GND")
	)
	(segment
		(start 179.639722 -31.209488)
		(end 179.194206 -30.763972)
		(width 0.254)
		(layer "F.Cu")
		(net "GND")
	)
	(segment
		(start 343.56802 -277.870158)
		(end 343.101168 -278.136096)
		(width 0.350012)
		(layer "F.Cu")
		(net "GND")
	)
	(segment
		(start 87.167974 -294.070278)
		(end 86.701122 -294.336216)
		(width 0.350012)
		(layer "F.Cu")
		(net "GND")
	)
	(segment
		(start 380.162308 -392.999722)
		(end 379.570488 -392.999722)
		(width 0.254)
		(layer "F.Cu")
		(net "GND")
	)
	(segment
		(start 15.094458 -418.290248)
		(end 15.094458 -417.68014)
		(width 0.381)
		(layer "F.Cu")
		(net "GND")
	)
	(segment
		(start 392.61796 -229.360222)
		(end 393.084812 -229.094284)
		(width 0.350012)
		(layer "F.Cu")
		(net "GND")
	)
	(segment
		(start 439.100214 -302.73498)
		(end 437.715914 -302.73498)
		(width 0.4572)
		(layer "F.Cu")
		(net "GND")
	)
	(segment
		(start 374.28805 -247.990106)
		(end 374.754902 -247.724168)
		(width 0.350012)
		(layer "F.Cu")
		(net "GND")
	)
	(segment
		(start 277.192232 -286.585152)
		(end 275.807932 -286.585152)
		(width 0.4572)
		(layer "F.Cu")
		(net "GND")
	)
	(segment
		(start 290.603178 -423.834814)
		(end 290.603178 -424.463972)
		(width 0.381)
		(layer "F.Cu")
		(net "GND")
	)
	(segment
		(start 370.817902 -391.784586)
		(end 370.817902 -392.004296)
		(width 0.254)
		(layer "F.Cu")
		(net "GND")
	)
	(segment
		(start 331.518006 -250.420124)
		(end 331.051154 -250.154186)
		(width 0.350012)
		(layer "F.Cu")
		(net "GND")
	)
	(segment
		(start 119.297958 -229.360476)
		(end 119.76481 -229.094538)
		(width 0.350012)
		(layer "F.Cu")
		(net "GND")
	)
	(segment
		(start 372.370604 -398.542002)
		(end 371.691154 -398.542002)
		(width 0.254)
		(layer "F.Cu")
		(net "GND")
	)
	(segment
		(start 339.845396 -392.004042)
		(end 340.145624 -392.30427)
		(width 0.2032)
		(layer "F.Cu")
		(net "GND")
	)
	(segment
		(start 78.877922 -226.120452)
		(end 78.41107 -225.854514)
		(width 0.350012)
		(layer "F.Cu")
		(net "GND")
	)
	(segment
		(start 121.477786 -278.680418)
		(end 121.944638 -278.946356)
		(width 0.350012)
		(layer "F.Cu")
		(net "GND")
	)
	(segment
		(start 380.86792 -228.550216)
		(end 381.334772 -228.284278)
		(width 0.350012)
		(layer "F.Cu")
		(net "GND")
	)
	(segment
		(start 90.927936 -292.450266)
		(end 90.461084 -292.716204)
		(width 0.350012)
		(layer "F.Cu")
		(net "GND")
	)
	(segment
		(start 344.977974 -286.780224)
		(end 344.511122 -287.045908)
		(width 0.350012)
		(layer "F.Cu")
		(net "GND")
	)
	(segment
		(start 131.817872 -291.64026)
		(end 132.284724 -291.906198)
		(width 0.350012)
		(layer "F.Cu")
		(net "GND")
	)
	(segment
		(start 269.648178 -305.28514)
		(end 268.263878 -305.28514)
		(width 0.4572)
		(layer "F.Cu")
		(net "GND")
	)
	(segment
		(start 205.6511 -107.362498)
		(end 206.54645 -107.362498)
		(width 0.4572)
		(layer "F.Cu")
		(net "GND")
	)
	(segment
		(start 427.456092 -203.28509)
		(end 428.840392 -203.28509)
		(width 0.4572)
		(layer "F.Cu")
		(net "GND")
	)
	(segment
		(start 29.252164 -209.235294)
		(end 27.867864 -209.235294)
		(width 0.4572)
		(layer "F.Cu")
		(net "GND")
	)
	(segment
		(start 126.177802 -288.400236)
		(end 126.644654 -288.666174)
		(width 0.350012)
		(layer "F.Cu")
		(net "GND")
	)
	(segment
		(start 429.566832 -8.320024)
		(end 429.566832 -9.423654)
		(width 0.3556)
		(layer "F.Cu")
		(net "GND")
	)
	(segment
		(start 357.318056 -402.284946)
		(end 357.318056 -401.892262)
		(width 0.254)
		(layer "F.Cu")
		(net "GND")
	)
	(segment
		(start 58.665618 -7.215886)
		(end 58.666888 -7.217156)
		(width 0.3556)
		(layer "F.Cu")
		(net "GND")
	)
	(segment
		(start 362.067856 -230.169974)
		(end 362.534708 -229.904036)
		(width 0.350012)
		(layer "F.Cu")
		(net "GND")
	)
	(segment
		(start 358.307894 -244.750082)
		(end 357.841042 -244.484144)
		(width 0.350012)
		(layer "F.Cu")
		(net "GND")
	)
	(segment
		(start 37.61105 -363.093)
		(end 38.3286 -363.093)
		(width 0.381)
		(layer "F.Cu")
		(net "GND")
	)
	(segment
		(start 412.958026 -12.374118)
		(end 412.956756 -12.372848)
		(width 0.3556)
		(layer "F.Cu")
		(net "GND")
	)
	(segment
		(start 113.017808 -267.340334)
		(end 113.48466 -267.606272)
		(width 0.350012)
		(layer "F.Cu")
		(net "GND")
	)
	(segment
		(start 379.75794 -275.44014)
		(end 380.224792 -275.706078)
		(width 0.350012)
		(layer "F.Cu")
		(net "GND")
	)
	(segment
		(start 133.398006 -253.660402)
		(end 133.864858 -253.394464)
		(width 0.350012)
		(layer "F.Cu")
		(net "GND")
	)
	(segment
		(start 131.517898 -230.980234)
		(end 131.98475 -230.71455)
		(width 0.350012)
		(layer "F.Cu")
		(net "GND")
	)
	(segment
		(start 113.201704 -388.13105)
		(end 112.893094 -388.36473)
		(width 0.254)
		(layer "F.Cu")
		(net "GND")
	)
	(segment
		(start 82.167984 -235.030264)
		(end 81.701132 -234.764326)
		(width 0.350012)
		(layer "F.Cu")
		(net "GND")
	)
	(segment
		(start 5.229098 -134.328154)
		(end 5.229098 -134.288022)
		(width 0.3556)
		(layer "F.Cu")
		(net "GND")
	)
	(segment
		(start 92.037916 -252.04039)
		(end 91.571064 -251.774452)
		(width 0.350012)
		(layer "F.Cu")
		(net "GND")
	)
	(segment
		(start 386.01269 -412.212536)
		(end 386.01269 -411.332426)
		(width 0.381)
		(layer "F.Cu")
		(net "GND")
	)
	(segment
		(start 100.027994 -241.510312)
		(end 99.561142 -241.244374)
		(width 0.350012)
		(layer "F.Cu")
		(net "GND")
	)
	(segment
		(start 82.467958 -279.490424)
		(end 82.001106 -279.756362)
		(width 0.350012)
		(layer "F.Cu")
		(net "GND")
	)
	(segment
		(start 378.318014 -392.30427)
		(end 378.370592 -392.999722)
		(width 0.254)
		(layer "F.Cu")
		(net "GND")
	)
	(segment
		(start 216.38133 -41.341548)
		(end 216.38133 -40.675814)
		(width 0.4572)
		(layer "F.Cu")
		(net "GND")
	)
	(segment
		(start 359.078022 -278.680164)
		(end 358.61117 -278.946102)
		(width 0.350012)
		(layer "F.Cu")
		(net "GND")
	)
	(segment
		(start 363.778038 -280.300176)
		(end 364.24489 -280.566114)
		(width 0.350012)
		(layer "F.Cu")
		(net "GND")
	)
	(segment
		(start 358.778048 -242.320064)
		(end 358.311196 -242.054126)
		(width 0.350012)
		(layer "F.Cu")
		(net "GND")
	)
	(segment
		(start 103.147876 -285.970472)
		(end 102.681024 -286.23641)
		(width 0.350012)
		(layer "F.Cu")
		(net "GND")
	)
	(segment
		(start 405.745696 -399.663158)
		(end 406.04567 -399.143474)
		(width 0.254)
		(layer "F.Cu")
		(net "GND")
	)
	(segment
		(start 114.897916 -265.720322)
		(end 115.364768 -265.98626)
		(width 0.350012)
		(layer "F.Cu")
		(net "GND")
	)
	(segment
		(start 118.357904 -239.080294)
		(end 118.824756 -238.814356)
		(width 0.350012)
		(layer "F.Cu")
		(net "GND")
	)
	(segment
		(start 166.462202 -385.131056)
		(end 166.462202 -384.531108)
		(width 0.254)
		(layer "F.Cu")
		(net "GND")
	)
	(segment
		(start 93.747844 -289.210242)
		(end 93.280992 -289.47618)
		(width 0.350012)
		(layer "F.Cu")
		(net "GND")
	)
	(segment
		(start 374.77065 -398.542002)
		(end 374.718072 -399.143474)
		(width 0.254)
		(layer "F.Cu")
		(net "GND")
	)
	(segment
		(start 133.69798 -288.400236)
		(end 134.164832 -288.666174)
		(width 0.350012)
		(layer "F.Cu")
		(net "GND")
	)
	(segment
		(start 85.757766 -272.20037)
		(end 85.290914 -272.466308)
		(width 0.350012)
		(layer "F.Cu")
		(net "GND")
	)
	(segment
		(start 128.52781 -282.730448)
		(end 128.994662 -282.996386)
		(width 0.350012)
		(layer "F.Cu")
		(net "GND")
	)
	(segment
		(start 303.268126 -278.085042)
		(end 304.652426 -278.085042)
		(width 0.4572)
		(layer "F.Cu")
		(net "GND")
	)
	(segment
		(start 335.747868 -249.610118)
		(end 335.281016 -249.34418)
		(width 0.350012)
		(layer "F.Cu")
		(net "GND")
	)
	(segment
		(start 105.497884 -286.780478)
		(end 105.031032 -287.046162)
		(width 0.350012)
		(layer "F.Cu")
		(net "GND")
	)
	(segment
		(start 47.784004 -306.135278)
		(end 49.168304 -306.135278)
		(width 0.4572)
		(layer "F.Cu")
		(net "GND")
	)
	(segment
		(start 359.078022 -288.399982)
		(end 358.61117 -288.66592)
		(width 0.350012)
		(layer "F.Cu")
		(net "GND")
	)
	(segment
		(start 126.347982 -243.130324)
		(end 126.814834 -242.864386)
		(width 0.350012)
		(layer "F.Cu")
		(net "GND")
	)
	(segment
		(start 50.991262 -390.160002)
		(end 50.470562 -390.160002)
		(width 0.254)
		(layer "F.Cu")
		(net "GND")
	)
	(segment
		(start 420.158164 -12.37488)
		(end 420.158164 -12.374118)
		(width 0.3556)
		(layer "F.Cu")
		(net "GND")
	)
	(segment
		(start 31.017718 -50.099214)
		(end 32.605218 -50.099214)
		(width 0.4572)
		(layer "F.Cu")
		(net "GND")
	)
	(segment
		(start 87.167974 -289.210242)
		(end 86.701122 -289.47618)
		(width 0.350012)
		(layer "F.Cu")
		(net "GND")
	)
	(segment
		(start 172.14342 -418.551868)
		(end 171.319444 -418.551868)
		(width 0.381)
		(layer "F.Cu")
		(net "GND")
	)
	(segment
		(start 318.417702 -399.143474)
		(end 318.47028 -398.542002)
		(width 0.254)
		(layer "F.Cu")
		(net "GND")
	)
	(segment
		(start 112.717834 -226.120452)
		(end 113.184686 -225.854514)
		(width 0.350012)
		(layer "F.Cu")
		(net "GND")
	)
	(segment
		(start 380.39802 -224.500186)
		(end 380.864872 -224.234248)
		(width 0.350012)
		(layer "F.Cu")
		(net "GND")
	)
	(segment
		(start 139.25804 -112.81791)
		(end 139.25804 -112.026192)
		(width 0.381)
		(layer "F.Cu")
		(net "GND")
	)
	(segment
		(start 104.55783 -281.920442)
		(end 104.090978 -282.18638)
		(width 0.350012)
		(layer "F.Cu")
		(net "GND")
	)
	(segment
		(start 88.645746 -383.402586)
		(end 88.645746 -383.622296)
		(width 0.254)
		(layer "F.Cu")
		(net "GND")
	)
	(segment
		(start 351.087944 -285.970218)
		(end 350.621092 -286.236156)
		(width 0.350012)
		(layer "F.Cu")
		(net "GND")
	)
	(segment
		(start 344.645488 -392.004296)
		(end 344.945462 -392.30427)
		(width 0.254)
		(layer "F.Cu")
		(net "GND")
	)
	(segment
		(start 159.34563 -391.281158)
		(end 159.645604 -390.761474)
		(width 0.254)
		(layer "F.Cu")
		(net "GND")
	)
	(segment
		(start 88.308942 -31.12135)
		(end 87.131144 -31.12135)
		(width 0.3556)
		(layer "F.Cu")
		(net "GND")
	)
	(segment
		(start 101.421946 -55.282084)
		(end 101.076252 -55.282084)
		(width 0.4572)
		(layer "F.Cu")
		(net "GND")
	)
	(segment
		(start 366.128046 -281.110182)
		(end 366.594898 -281.37612)
		(width 0.350012)
		(layer "F.Cu")
		(net "GND")
	)
	(segment
		(start 93.44787 -236.650276)
		(end 92.981018 -236.384338)
		(width 0.350012)
		(layer "F.Cu")
		(net "GND")
	)
	(segment
		(start 107.078018 -240.700306)
		(end 106.611166 -240.434368)
		(width 0.350012)
		(layer "F.Cu")
		(net "GND")
	)
	(segment
		(start 306.470304 -398.542002)
		(end 305.791108 -398.542002)
		(width 0.254)
		(layer "F.Cu")
		(net "GND")
	)
	(segment
		(start 136.517888 -291.64026)
		(end 136.98474 -291.906198)
		(width 0.350012)
		(layer "F.Cu")
		(net "GND")
	)
	(segment
		(start 117.316504 -391.37971)
		(end 117.217952 -391.281158)
		(width 0.254)
		(layer "F.Cu")
		(net "GND")
	)
	(segment
		(start 295.724072 -212.635084)
		(end 297.108372 -212.635084)
		(width 0.4572)
		(layer "F.Cu")
		(net "GND")
	)
	(segment
		(start 122.878596 -386.449062)
		(end 122.370596 -386.6388)
		(width 0.254)
		(layer "F.Cu")
		(net "GND")
	)
	(segment
		(start 378.048012 -247.990106)
		(end 378.514864 -247.724168)
		(width 0.350012)
		(layer "F.Cu")
		(net "GND")
	)
	(segment
		(start 368.947954 -284.350206)
		(end 369.414806 -284.616144)
		(width 0.350012)
		(layer "F.Cu")
		(net "GND")
	)
	(segment
		(start 354.046028 -396.710662)
		(end 353.398074 -396.520924)
		(width 0.254)
		(layer "F.Cu")
		(net "GND")
	)
	(segment
		(start 402.048218 -12.374118)
		(end 402.046948 -12.372848)
		(width 0.3556)
		(layer "F.Cu")
		(net "GND")
	)
	(segment
		(start 49.668176 -12.37488)
		(end 49.668176 -12.374118)
		(width 0.3556)
		(layer "F.Cu")
		(net "GND")
	)
	(segment
		(start 138.098022 -248.800366)
		(end 138.564874 -248.534428)
		(width 0.350012)
		(layer "F.Cu")
		(net "GND")
	)
	(segment
		(start 121.007886 -289.210242)
		(end 121.474738 -289.47618)
		(width 0.350012)
		(layer "F.Cu")
		(net "GND")
	)
	(segment
		(start 425.96689 -12.372848)
		(end 425.96689 -11.26998)
		(width 0.3556)
		(layer "F.Cu")
		(net "GND")
	)
	(segment
		(start 316.070234 -396.520924)
		(end 315.518292 -396.710662)
		(width 0.254)
		(layer "F.Cu")
		(net "GND")
	)
	(segment
		(start 163.298378 -386.6388)
		(end 162.606228 -386.449062)
		(width 0.254)
		(layer "F.Cu")
		(net "GND")
	)
	(segment
		(start 360.657902 -230.97998)
		(end 361.124754 -230.714296)
		(width 0.350012)
		(layer "F.Cu")
		(net "GND")
	)
	(segment
		(start 345.845384 -391.333482)
		(end 345.943936 -391.23493)
		(width 0.254)
		(layer "F.Cu")
		(net "GND")
	)
	(segment
		(start 445.021716 -402.81987)
		(end 445.637666 -402.81987)
		(width 0.254)
		(layer "F.Cu")
		(net "GND")
	)
	(segment
		(start 388.817866 -399.663158)
		(end 389.11784 -399.143474)
		(width 0.254)
		(layer "F.Cu")
		(net "GND")
	)
	(segment
		(start 280.635964 -238.13516)
		(end 282.020264 -238.13516)
		(width 0.4572)
		(layer "F.Cu")
		(net "GND")
	)
	(segment
		(start 127.170434 -386.6388)
		(end 126.478538 -386.449062)
		(width 0.254)
		(layer "F.Cu")
		(net "GND")
	)
	(segment
		(start 49.891442 -349.786448)
		(end 50.375566 -349.302324)
		(width 0.2286)
		(layer "F.Cu")
		(net "GND")
	)
	(segment
		(start 228.783642 -291.224462)
		(end 228.921056 -291.361876)
		(width 0.1778)
		(layer "F.Cu")
		(net "GND")
	)
	(segment
		(start 353.607878 -249.610118)
		(end 353.141026 -249.34418)
		(width 0.350012)
		(layer "F.Cu")
		(net "GND")
	)
	(segment
		(start 99.55784 -230.980234)
		(end 99.090988 -230.71455)
		(width 0.350012)
		(layer "F.Cu")
		(net "GND")
	)
	(segment
		(start 124.467874 -256.09042)
		(end 124.934726 -255.824482)
		(width 0.350012)
		(layer "F.Cu")
		(net "GND")
	)
	(segment
		(start 165.146228 -388.328662)
		(end 164.498274 -388.138924)
		(width 0.254)
		(layer "F.Cu")
		(net "GND")
	)
	(segment
		(start 71.2343 -381.064262)
		(end 71.277734 -381.020828)
		(width 0.254)
		(layer "F.Cu")
		(net "GND")
	)
	(segment
		(start 138.567922 -249.610372)
		(end 139.034774 -249.344434)
		(width 0.350012)
		(layer "F.Cu")
		(net "GND")
	)
	(segment
		(start 308.61635 -400.212814)
		(end 308.61635 -399.76171)
		(width 0.254)
		(layer "F.Cu")
		(net "GND")
	)
	(segment
		(start 310.578246 -394.831062)
		(end 310.070246 -395.0208)
		(width 0.254)
		(layer "F.Cu")
		(net "GND")
	)
	(segment
		(start 160.644332 -391.830814)
		(end 160.644332 -391.37971)
		(width 0.254)
		(layer "F.Cu")
		(net "GND")
	)
	(segment
		(start 33.691322 -434.173884)
		(end 33.691322 -434.808884)
		(width 0.3556)
		(layer "F.Cu")
		(net "GND")
	)
	(segment
		(start 380.22784 -294.070024)
		(end 380.694946 -294.335962)
		(width 0.350012)
		(layer "F.Cu")
		(net "GND")
	)
	(segment
		(start 95.327978 -230.170228)
		(end 94.861126 -229.90429)
		(width 0.350012)
		(layer "F.Cu")
		(net "GND")
	)
	(segment
		(start 103.787956 -249.610372)
		(end 103.321104 -249.344434)
		(width 0.350012)
		(layer "F.Cu")
		(net "GND")
	)
	(segment
		(start 387.748018 -269.770098)
		(end 388.21487 -270.036036)
		(width 0.350012)
		(layer "F.Cu")
		(net "GND")
	)
	(segment
		(start 422.739566 -356.32644)
		(end 423.327576 -356.32644)
		(width 0.3556)
		(layer "F.Cu")
		(net "GND")
	)
	(segment
		(start 122.018044 -383.622296)
		(end 122.318018 -383.92227)
		(width 0.254)
		(layer "F.Cu")
		(net "GND")
	)
	(segment
		(start 29.252164 -277.235412)
		(end 27.867864 -277.235412)
		(width 0.4572)
		(layer "F.Cu")
		(net "GND")
	)
	(segment
		(start 121.94794 -294.070278)
		(end 122.414792 -294.336216)
		(width 0.350012)
		(layer "F.Cu")
		(net "GND")
	)
	(segment
		(start 305.772058 -411.295596)
		(end 304.855118 -412.212536)
		(width 0.381)
		(layer "F.Cu")
		(net "GND")
	)
	(segment
		(start 59.347862 -41.166796)
		(end 59.336686 -41.15562)
		(width 0.4572)
		(layer "F.Cu")
		(net "GND")
	)
	(segment
		(start 90.457782 -260.860286)
		(end 89.99093 -261.126224)
		(width 0.350012)
		(layer "F.Cu")
		(net "GND")
	)
	(segment
		(start 40.23995 -200.735438)
		(end 41.62425 -200.735438)
		(width 0.4572)
		(layer "F.Cu")
		(net "GND")
	)
	(segment
		(start 402.046948 -8.320024)
		(end 402.046948 -9.423654)
		(width 0.3556)
		(layer "F.Cu")
		(net "GND")
	)
	(segment
		(start 176.911 -133.968998)
		(end 176.911 -134.584948)
		(width 0.4572)
		(layer "F.Cu")
		(net "GND")
	)
	(segment
		(start 128.844294 -38.07333)
		(end 127.802894 -38.07333)
		(width 0.1778)
		(layer "F.Cu")
		(net "GND")
	)
	(segment
		(start 383.048002 -268.150086)
		(end 383.514854 -268.416024)
		(width 0.350012)
		(layer "F.Cu")
		(net "GND")
	)
	(segment
		(start 351.943924 -400.212814)
		(end 351.943924 -399.76171)
		(width 0.254)
		(layer "F.Cu")
		(net "GND")
	)
	(segment
		(start 303.164494 -394.25753)
		(end 303.009046 -394.412978)
		(width 0.254)
		(layer "F.Cu")
		(net "GND")
	)
	(segment
		(start 419.04412 -399.76171)
		(end 418.945568 -399.663158)
		(width 0.254)
		(layer "F.Cu")
		(net "GND")
	)
	(segment
		(start 121.477786 -280.30043)
		(end 121.944638 -280.566368)
		(width 0.350012)
		(layer "F.Cu")
		(net "GND")
	)
	(segment
		(start 101.437948 -256.900426)
		(end 100.971096 -256.634488)
		(width 0.350012)
		(layer "F.Cu")
		(net "GND")
	)
	(segment
		(start 296.681906 -349.781622)
		(end 296.712894 -349.781622)
		(width 0.2286)
		(layer "F.Cu")
		(net "GND")
	)
	(segment
		(start 114.127788 -233.410252)
		(end 114.59464 -233.144314)
		(width 0.350012)
		(layer "F.Cu")
		(net "GND")
	)
	(segment
		(start 411.745684 -391.784586)
		(end 411.745684 -392.004296)
		(width 0.254)
		(layer "F.Cu")
		(net "GND")
	)
	(segment
		(start 102.378002 -243.94033)
		(end 101.91115 -243.674392)
		(width 0.350012)
		(layer "F.Cu")
		(net "GND")
	)
	(segment
		(start 194.604132 -231.335326)
		(end 195.988432 -231.335326)
		(width 0.4572)
		(layer "F.Cu")
		(net "GND")
	)
	(segment
		(start 143.737838 -250.420378)
		(end 144.20469 -250.15444)
		(width 0.350012)
		(layer "F.Cu")
		(net "GND")
	)
	(segment
		(start 372.238016 -277.060152)
		(end 372.704868 -277.32609)
		(width 0.350012)
		(layer "F.Cu")
		(net "GND")
	)
	(segment
		(start 120.537986 -293.260272)
		(end 121.004838 -293.52621)
		(width 0.350012)
		(layer "F.Cu")
		(net "GND")
	)
	(segment
		(start 79.177896 -272.20037)
		(end 78.711044 -272.466308)
		(width 0.350012)
		(layer "F.Cu")
		(net "GND")
	)
	(segment
		(start 116.77777 -288.400236)
		(end 117.244622 -288.666174)
		(width 0.350012)
		(layer "F.Cu")
		(net "GND")
	)
	(segment
		(start 122.927618 -53.40477)
		(end 122.800618 -53.27777)
		(width 0.1778)
		(layer "F.Cu")
		(net "GND")
	)
	(segment
		(start 131.817872 -281.920442)
		(end 132.284724 -282.18638)
		(width 0.350012)
		(layer "F.Cu")
		(net "GND")
	)
	(segment
		(start 55.068216 -12.37488)
		(end 55.068216 -12.374118)
		(width 0.3556)
		(layer "F.Cu")
		(net "GND")
	)
	(segment
		(start 169.267124 -16.549878)
		(end 169.19956 -16.617442)
		(width 0.3556)
		(layer "F.Cu")
		(net "GND")
	)
	(segment
		(start 316.213236 -361.279948)
		(end 316.213236 -360.300016)
		(width 0.381)
		(layer "F.Cu")
		(net "GND")
	)
	(segment
		(start 255.312926 -65.588388)
		(end 255.947926 -65.588388)
		(width 0.4572)
		(layer "F.Cu")
		(net "GND")
	)
	(segment
		(start 123.827794 -281.110436)
		(end 124.294646 -281.376374)
		(width 0.350012)
		(layer "F.Cu")
		(net "GND")
	)
	(segment
		(start 384.157982 -224.500186)
		(end 384.624834 -224.234248)
		(width 0.350012)
		(layer "F.Cu")
		(net "GND")
	)
	(segment
		(start 165.0365 -419.25494)
		(end 164.913564 -419.132004)
		(width 0.3048)
		(layer "F.Cu")
		(net "GND")
	)
	(segment
		(start 349.44558 -391.333482)
		(end 349.544132 -391.23493)
		(width 0.254)
		(layer "F.Cu")
		(net "GND")
	)
	(segment
		(start 143.567912 -276.2504)
		(end 144.034764 -276.516338)
		(width 0.350012)
		(layer "F.Cu")
		(net "GND")
	)
	(segment
		(start 136.687814 -241.510312)
		(end 137.154666 -241.244374)
		(width 0.350012)
		(layer "F.Cu")
		(net "GND")
	)
	(segment
		(start 116.018056 -383.622296)
		(end 116.31803 -383.92227)
		(width 0.254)
		(layer "F.Cu")
		(net "GND")
	)
	(segment
		(start 50.52695 -433.127658)
		(end 50.684938 -432.96967)
		(width 0.381)
		(layer "F.Cu")
		(net "GND")
	)
	(segment
		(start 48.070516 -390.160002)
		(end 48.591216 -390.160002)
		(width 0.254)
		(layer "F.Cu")
		(net "GND")
	)
	(segment
		(start 331.518006 -229.360222)
		(end 331.051154 -229.094284)
		(width 0.350012)
		(layer "F.Cu")
		(net "GND")
	)
	(segment
		(start 146.38782 -289.210242)
		(end 147.042886 -289.210242)
		(width 0.350012)
		(layer "F.Cu")
		(net "GND")
	)
	(segment
		(start 107.847892 -294.070278)
		(end 107.38104 -294.336216)
		(width 0.350012)
		(layer "F.Cu")
		(net "GND")
	)
	(segment
		(start 87.190072 -384.617722)
		(end 87.798402 -384.617722)
		(width 0.254)
		(layer "F.Cu")
		(net "GND")
	)
	(segment
		(start 239.98428 -293.654226)
		(end 241.461798 -292.961822)
		(width 0.1778)
		(layer "F.Cu")
		(net "GND")
	)
	(segment
		(start 353.137978 -230.97998)
		(end 352.671126 -230.714296)
		(width 0.350012)
		(layer "F.Cu")
		(net "GND")
	)
	(segment
		(start 107.821222 -19.990562)
		(end 108.09097 -20.26031)
		(width 0.381)
		(layer "F.Cu")
		(net "GND")
	)
	(segment
		(start 37.61105 -365.125)
		(end 38.15969 -365.125)
		(width 0.381)
		(layer "F.Cu")
		(net "GND")
	)
	(segment
		(start 417.844224 -400.212814)
		(end 417.844224 -399.76171)
		(width 0.254)
		(layer "F.Cu")
		(net "GND")
	)
	(segment
		(start 26.626566 -40.180514)
		(end 27.26817 -40.180514)
		(width 0.4572)
		(layer "F.Cu")
		(net "GND")
	)
	(segment
		(start 389.327898 -239.890046)
		(end 389.79475 -239.624108)
		(width 0.350012)
		(layer "F.Cu")
		(net "GND")
	)
	(segment
		(start 96.145858 -390.761474)
		(end 96.198436 -390.160002)
		(width 0.254)
		(layer "F.Cu")
		(net "GND")
	)
	(segment
		(start 90.627962 -238.270288)
		(end 90.16111 -238.00435)
		(width 0.350012)
		(layer "F.Cu")
		(net "GND")
	)
	(segment
		(start 442.5442 -312.935112)
		(end 443.9285 -312.935112)
		(width 0.4572)
		(layer "F.Cu")
		(net "GND")
	)
	(segment
		(start 98.344228 -391.37971)
		(end 98.245676 -391.281158)
		(width 0.254)
		(layer "F.Cu")
		(net "GND")
	)
	(segment
		(start 131.817872 -273.820382)
		(end 132.284724 -274.08632)
		(width 0.350012)
		(layer "F.Cu")
		(net "GND")
	)
	(segment
		(start 59.336686 -41.15562)
		(end 58.804556 -41.15562)
		(width 0.4572)
		(layer "F.Cu")
		(net "GND")
	)
	(segment
		(start 420.145718 -391.333482)
		(end 420.24427 -391.23493)
		(width 0.254)
		(layer "F.Cu")
		(net "GND")
	)
	(segment
		(start 387.41858 -396.710662)
		(end 386.770626 -396.520924)
		(width 0.254)
		(layer "F.Cu")
		(net "GND")
	)
	(segment
		(start 120.238012 -235.84027)
		(end 120.70461 -235.574332)
		(width 0.350012)
		(layer "F.Cu")
		(net "GND")
	)
	(segment
		(start 68.651374 -150.932642)
		(end 68.651374 -150.551642)
		(width 0.1778)
		(layer "F.Cu")
		(net "GND")
	)
	(segment
		(start 19.400012 -357.90632)
		(end 19.400012 -357.281988)
		(width 0.381)
		(layer "F.Cu")
		(net "GND")
	)
	(segment
		(start 139.80795 -294.070278)
		(end 140.274802 -294.336216)
		(width 0.350012)
		(layer "F.Cu")
		(net "GND")
	)
	(segment
		(start 341.218012 -268.960092)
		(end 340.75116 -269.22603)
		(width 0.350012)
		(layer "F.Cu")
		(net "GND")
	)
	(segment
		(start 257.894836 -74.774044)
		(end 258.53898 -74.774044)
		(width 0.4572)
		(layer "F.Cu")
		(net "GND")
	)
	(segment
		(start 120.707912 -243.130324)
		(end 121.174764 -242.864386)
		(width 0.350012)
		(layer "F.Cu")
		(net "GND")
	)
	(segment
		(start 335.277968 -240.700052)
		(end 334.811116 -240.434114)
		(width 0.350012)
		(layer "F.Cu")
		(net "GND")
	)
	(segment
		(start 382.817878 -391.784586)
		(end 382.817878 -392.004296)
		(width 0.254)
		(layer "F.Cu")
		(net "GND")
	)
	(segment
		(start 135.107934 -284.35046)
		(end 135.574786 -284.616398)
		(width 0.350012)
		(layer "F.Cu")
		(net "GND")
	)
	(segment
		(start 141.687804 -261.670292)
		(end 142.154656 -261.93623)
		(width 0.350012)
		(layer "F.Cu")
		(net "GND")
	)
	(segment
		(start 59.428126 -274.685252)
		(end 58.043826 -274.685252)
		(width 0.4572)
		(layer "F.Cu")
		(net "GND")
	)
	(segment
		(start 384.465576 -56.048148)
		(end 384.702304 -55.81142)
		(width 0.4572)
		(layer "F.Cu")
		(net "GND")
	)
	(segment
		(start 168.527984 -293.38524)
		(end 167.143684 -293.38524)
		(width 0.4572)
		(layer "F.Cu")
		(net "GND")
	)
	(segment
		(start 353.045522 -391.784586)
		(end 353.045522 -392.004296)
		(width 0.254)
		(layer "F.Cu")
		(net "GND")
	)
	(segment
		(start 136.517888 -278.680418)
		(end 136.98474 -278.946356)
		(width 0.350012)
		(layer "F.Cu")
		(net "GND")
	)
	(segment
		(start 383.17043 -395.0208)
		(end 382.478534 -394.831062)
		(width 0.254)
		(layer "F.Cu")
		(net "GND")
	)
	(segment
		(start 413.890206 -392.999722)
		(end 414.498282 -392.999722)
		(width 0.254)
		(layer "F.Cu")
		(net "GND")
	)
	(segment
		(start 352.968052 -294.070024)
		(end 352.5012 -294.335962)
		(width 0.350012)
		(layer "F.Cu")
		(net "GND")
	)
	(segment
		(start 390.267952 -249.610118)
		(end 390.734804 -249.34418)
		(width 0.350012)
		(layer "F.Cu")
		(net "GND")
	)
	(segment
		(start 117.717824 -288.400236)
		(end 118.184676 -288.666174)
		(width 0.350012)
		(layer "F.Cu")
		(net "GND")
	)
	(segment
		(start 90.927936 -261.670292)
		(end 90.461084 -261.93623)
		(width 0.350012)
		(layer "F.Cu")
		(net "GND")
	)
	(segment
		(start 344.678 -234.220004)
		(end 344.211148 -233.954066)
		(width 0.350012)
		(layer "F.Cu")
		(net "GND")
	)
	(segment
		(start 350.618044 -278.680164)
		(end 350.151192 -278.946102)
		(width 0.350012)
		(layer "F.Cu")
		(net "GND")
	)
	(segment
		(start 78.84795 -61.214)
		(end 78.84795 -61.95695)
		(width 0.381)
		(layer "F.Cu")
		(net "GND")
	)
	(segment
		(start 118.187978 -285.970472)
		(end 118.65483 -286.23641)
		(width 0.350012)
		(layer "F.Cu")
		(net "GND")
	)
	(segment
		(start 36.795964 -286.585406)
		(end 35.411664 -286.585406)
		(width 0.4572)
		(layer "F.Cu")
		(net "GND")
	)
	(segment
		(start 160.54578 -382.951482)
		(end 160.644332 -382.85293)
		(width 0.254)
		(layer "F.Cu")
		(net "GND")
	)
	(segment
		(start 114.197638 -394.954506)
		(end 114.197638 -394.862558)
		(width 0.254)
		(layer "F.Cu")
		(net "GND")
	)
	(segment
		(start 350.618044 -277.060152)
		(end 350.151192 -277.32609)
		(width 0.350012)
		(layer "F.Cu")
		(net "GND")
	)
	(segment
		(start 364.417864 -232.599992)
		(end 364.884716 -232.334054)
		(width 0.350012)
		(layer "F.Cu")
		(net "GND")
	)
	(segment
		(start 419.912038 -238.13516)
		(end 421.296338 -238.13516)
		(width 0.4572)
		(layer "F.Cu")
		(net "GND")
	)
	(segment
		(start 43.85564 -7.215886)
		(end 43.85691 -7.217156)
		(width 0.3556)
		(layer "F.Cu")
		(net "GND")
	)
	(segment
		(start 115.367816 -287.590484)
		(end 115.834668 -287.856422)
		(width 0.350012)
		(layer "F.Cu")
		(net "GND")
	)
	(segment
		(start 334.864202 -357.703628)
		(end 334.864202 -358.496616)
		(width 0.4572)
		(layer "F.Cu")
		(net "GND")
	)
	(segment
		(start 131.517898 -227.740464)
		(end 131.98475 -227.474526)
		(width 0.350012)
		(layer "F.Cu")
		(net "GND")
	)
	(segment
		(start 390.281668 -77.424026)
		(end 390.28243 -77.423264)
		(width 0.4572)
		(layer "F.Cu")
		(net "GND")
	)
	(segment
		(start 421.69842 -398.542002)
		(end 422.373044 -398.542002)
		(width 0.254)
		(layer "F.Cu")
		(net "GND")
	)
	(segment
		(start 355.957886 -248.800112)
		(end 355.491034 -248.534174)
		(width 0.350012)
		(layer "F.Cu")
		(net "GND")
	)
	(segment
		(start 349.189802 -392.999722)
		(end 349.798132 -392.999722)
		(width 0.254)
		(layer "F.Cu")
		(net "GND")
	)
	(segment
		(start 359.078022 -275.44014)
		(end 358.61117 -275.706078)
		(width 0.350012)
		(layer "F.Cu")
		(net "GND")
	)
	(segment
		(start 338.097876 -248.800112)
		(end 337.631024 -248.534174)
		(width 0.350012)
		(layer "F.Cu")
		(net "GND")
	)
	(segment
		(start 365.828072 -241.510058)
		(end 366.294924 -241.24412)
		(width 0.350012)
		(layer "F.Cu")
		(net "GND")
	)
	(segment
		(start 350.31807 -248.800112)
		(end 349.851218 -248.534174)
		(width 0.350012)
		(layer "F.Cu")
		(net "GND")
	)
	(segment
		(start 335.577942 -272.200116)
		(end 335.11109 -272.466054)
		(width 0.350012)
		(layer "F.Cu")
		(net "GND")
	)
	(segment
		(start 90.927936 -273.010376)
		(end 90.461084 -273.276314)
		(width 0.350012)
		(layer "F.Cu")
		(net "GND")
	)
	(segment
		(start 127.170434 -390.160002)
		(end 126.491238 -390.160002)
		(width 0.254)
		(layer "F.Cu")
		(net "GND")
	)
	(segment
		(start 63.416434 -391.830814)
		(end 63.416434 -391.37971)
		(width 0.254)
		(layer "F.Cu")
		(net "GND")
	)
	(segment
		(start 230.967534 -56.965088)
		(end 232.000044 -56.965088)
		(width 0.381)
		(layer "F.Cu")
		(net "GND")
	)
	(segment
		(start 161.971736 -115.405408)
		(end 161.926016 -115.405408)
		(width 0.4572)
		(layer "F.Cu")
		(net "GND")
	)
	(segment
		(start 425.96816 -12.37488)
		(end 425.96816 -12.374118)
		(width 0.3556)
		(layer "F.Cu")
		(net "GND")
	)
	(segment
		(start 79.177896 -278.680418)
		(end 78.711044 -278.946356)
		(width 0.350012)
		(layer "F.Cu")
		(net "GND")
	)
	(segment
		(start 90.157808 -226.120452)
		(end 89.690956 -225.854514)
		(width 0.350012)
		(layer "F.Cu")
		(net "GND")
	)
	(segment
		(start 117.717824 -277.060406)
		(end 118.184676 -277.326344)
		(width 0.350012)
		(layer "F.Cu")
		(net "GND")
	)
	(segment
		(start 165.0365 -419.7096)
		(end 164.918136 -419.827964)
		(width 0.3048)
		(layer "F.Cu")
		(net "GND")
	)
	(segment
		(start 251.16409 -48.155606)
		(end 251.102622 -48.094138)
		(width 0.4572)
		(layer "F.Cu")
		(net "GND")
	)
	(segment
		(start 407.819098 -398.542002)
		(end 407.298398 -398.542002)
		(width 0.254)
		(layer "F.Cu")
		(net "GND")
	)
	(segment
		(start 371.938042 -245.560088)
		(end 372.404894 -245.29415)
		(width 0.350012)
		(layer "F.Cu")
		(net "GND")
	)
	(segment
		(start 222.07093 -42.255948)
		(end 222.07093 -41.620948)
		(width 0.381)
		(layer "F.Cu")
		(net "GND")
	)
	(segment
		(start 338.945474 -399.143474)
		(end 338.998052 -398.542002)
		(width 0.254)
		(layer "F.Cu")
		(net "GND")
	)
	(segment
		(start 155.546298 -388.328662)
		(end 154.898344 -388.138924)
		(width 0.254)
		(layer "F.Cu")
		(net "GND")
	)
	(segment
		(start 83.877912 -280.30043)
		(end 83.41106 -280.566368)
		(width 0.350012)
		(layer "F.Cu")
		(net "GND")
	)
	(segment
		(start 25.152096 -210.085432)
		(end 26.536396 -210.085432)
		(width 0.4572)
		(layer "F.Cu")
		(net "GND")
	)
	(segment
		(start 133.69798 -291.64026)
		(end 134.164832 -291.906198)
		(width 0.350012)
		(layer "F.Cu")
		(net "GND")
	)
	(segment
		(start 310.070246 -398.542002)
		(end 309.39105 -398.542002)
		(width 0.254)
		(layer "F.Cu")
		(net "GND")
	)
	(segment
		(start 26.393394 -426.609256)
		(end 25.63241 -426.609256)
		(width 0.4572)
		(layer "F.Cu")
		(net "GND")
	)
	(segment
		(start 316.23 -366.79505)
		(end 315.214 -366.79505)
		(width 0.381)
		(layer "F.Cu")
		(net "GND")
	)
	(segment
		(start 141.857984 -224.50044)
		(end 142.324836 -224.234502)
		(width 0.350012)
		(layer "F.Cu")
		(net "GND")
	)
	(segment
		(start 94.217998 -286.780478)
		(end 93.751146 -287.046162)
		(width 0.350012)
		(layer "F.Cu")
		(net "GND")
	)
	(segment
		(start 306.978304 -394.831062)
		(end 306.470304 -395.0208)
		(width 0.254)
		(layer "F.Cu")
		(net "GND")
	)
	(segment
		(start 39.30396 -433.68595)
		(end 38.81501 -433.197)
		(width 0.381)
		(layer "F.Cu")
		(net "GND")
	)
	(segment
		(start 370.916454 -399.76171)
		(end 370.916454 -400.212814)
		(width 0.254)
		(layer "F.Cu")
		(net "GND")
	)
	(segment
		(start 328.697844 -250.420124)
		(end 328.231246 -250.154186)
		(width 0.350012)
		(layer "F.Cu")
		(net "GND")
	)
	(segment
		(start 93.854524 -180.08981)
		(end 93.763338 -180.309774)
		(width 0.2286)
		(layer "F.Cu")
		(net "GND")
	)
	(segment
		(start 126.177802 -264.10031)
		(end 126.644654 -264.366248)
		(width 0.350012)
		(layer "F.Cu")
		(net "GND")
	)
	(segment
		(start 135.14705 -16.549878)
		(end 135.14705 -17.652746)
		(width 0.3556)
		(layer "F.Cu")
		(net "GND")
	)
	(segment
		(start 146.474688 -57.92597)
		(end 146.474688 -58.392822)
		(width 0.1778)
		(layer "F.Cu")
		(net "GND")
	)
	(segment
		(start 378.370592 -395.0208)
		(end 377.678442 -394.831062)
		(width 0.254)
		(layer "F.Cu")
		(net "GND")
	)
	(segment
		(start 383.688082 -249.610118)
		(end 384.154934 -249.34418)
		(width 0.350012)
		(layer "F.Cu")
		(net "GND")
	)
	(segment
		(start 398.445482 -7.215886)
		(end 398.446752 -7.217156)
		(width 0.3556)
		(layer "F.Cu")
		(net "GND")
	)
	(segment
		(start 317.221108 -118.910608)
		(end 317.221108 -119.566182)
		(width 0.3556)
		(layer "F.Cu")
		(net "GND")
	)
	(segment
		(start 84.347812 -279.490424)
		(end 83.88096 -279.756362)
		(width 0.350012)
		(layer "F.Cu")
		(net "GND")
	)
	(segment
		(start 141.38783 -244.750336)
		(end 141.854682 -244.484398)
		(width 0.350012)
		(layer "F.Cu")
		(net "GND")
	)
	(segment
		(start 350.14789 -294.070024)
		(end 349.681038 -294.335962)
		(width 0.350012)
		(layer "F.Cu")
		(net "GND")
	)
	(segment
		(start 355.957886 -230.97998)
		(end 355.491034 -230.714042)
		(width 0.350012)
		(layer "F.Cu")
		(net "GND")
	)
	(segment
		(start 88.747854 -252.850396)
		(end 88.281002 -252.584458)
		(width 0.350012)
		(layer "F.Cu")
		(net "GND")
	)
	(segment
		(start 339.977984 -232.599992)
		(end 339.511132 -232.334054)
		(width 0.350012)
		(layer "F.Cu")
		(net "GND")
	)
	(segment
		(start 108.957872 -224.50044)
		(end 108.49102 -224.234502)
		(width 0.350012)
		(layer "F.Cu")
		(net "GND")
	)
	(segment
		(start 125.238002 -260.860286)
		(end 125.704854 -261.126224)
		(width 0.350012)
		(layer "F.Cu")
		(net "GND")
	)
	(segment
		(start 417.844224 -399.76171)
		(end 417.745672 -399.663158)
		(width 0.254)
		(layer "F.Cu")
		(net "GND")
	)
	(segment
		(start 335.045558 -391.340086)
		(end 334.996028 -391.290556)
		(width 0.254)
		(layer "F.Cu")
		(net "GND")
	)
	(segment
		(start 51.884072 -227.935282)
		(end 50.499772 -227.935282)
		(width 0.4572)
		(layer "F.Cu")
		(net "GND")
	)
	(segment
		(start 353.907852 -281.110182)
		(end 353.441 -281.37612)
		(width 0.350012)
		(layer "F.Cu")
		(net "GND")
	)
	(segment
		(start 384.318002 -399.143474)
		(end 384.018028 -399.663158)
		(width 0.254)
		(layer "F.Cu")
		(net "GND")
	)
	(segment
		(start 379.75794 -278.680164)
		(end 380.224792 -278.946102)
		(width 0.350012)
		(layer "F.Cu")
		(net "GND")
	)
	(segment
		(start 29.252164 -293.38524)
		(end 27.867864 -293.38524)
		(width 0.4572)
		(layer "F.Cu")
		(net "GND")
	)
	(segment
		(start 347.968062 -235.03001)
		(end 347.50121 -234.764072)
		(width 0.350012)
		(layer "F.Cu")
		(net "GND")
	)
	(segment
		(start 81.69783 -222.880428)
		(end 81.230978 -222.61449)
		(width 0.350012)
		(layer "F.Cu")
		(net "GND")
	)
	(segment
		(start 333.697834 -277.060152)
		(end 333.230982 -277.32609)
		(width 0.350012)
		(layer "F.Cu")
		(net "GND")
	)
	(segment
		(start 380.86792 -251.23013)
		(end 381.334772 -250.964192)
		(width 0.350012)
		(layer "F.Cu")
		(net "GND")
	)
	(segment
		(start 157.044136 -391.830814)
		(end 157.044136 -391.37971)
		(width 0.254)
		(layer "F.Cu")
		(net "GND")
	)
	(segment
		(start 314.174886 -22.97938)
		(end 313.600338 -22.97938)
		(width 0.4572)
		(layer "F.Cu")
		(net "GND")
	)
	(segment
		(start 138.334242 -381.064262)
		(end 138.377676 -381.020828)
		(width 0.254)
		(layer "F.Cu")
		(net "GND")
	)
	(segment
		(start 316.662054 -392.999722)
		(end 316.070234 -392.999722)
		(width 0.254)
		(layer "F.Cu")
		(net "GND")
	)
	(segment
		(start 348.24543 -392.004296)
		(end 348.545404 -392.30427)
		(width 0.254)
		(layer "F.Cu")
		(net "GND")
	)
	(segment
		(start 353.607878 -238.270034)
		(end 353.141026 -238.004096)
		(width 0.350012)
		(layer "F.Cu")
		(net "GND")
	)
	(segment
		(start 336.687922 -228.550216)
		(end 336.22107 -228.284278)
		(width 0.350012)
		(layer "F.Cu")
		(net "GND")
	)
	(segment
		(start 88.747854 -225.310446)
		(end 88.281002 -225.044508)
		(width 0.350012)
		(layer "F.Cu")
		(net "GND")
	)
	(segment
		(start 101.737922 -277.060406)
		(end 101.27107 -277.326344)
		(width 0.350012)
		(layer "F.Cu")
		(net "GND")
	)
	(segment
		(start 128.018032 -383.622296)
		(end 128.318006 -383.92227)
		(width 0.254)
		(layer "F.Cu")
		(net "GND")
	)
	(segment
		(start 353.137978 -243.940076)
		(end 352.671126 -243.674138)
		(width 0.350012)
		(layer "F.Cu")
		(net "GND")
	)
	(segment
		(start 89.047828 -263.290304)
		(end 88.580976 -263.556242)
		(width 0.350012)
		(layer "F.Cu")
		(net "GND")
	)
	(segment
		(start 62.117986 -382.951482)
		(end 62.216538 -382.85293)
		(width 0.254)
		(layer "F.Cu")
		(net "GND")
	)
	(segment
		(start 385.098036 -222.880174)
		(end 385.564888 -222.614236)
		(width 0.350012)
		(layer "F.Cu")
		(net "GND")
	)
	(segment
		(start 371.938042 -253.660148)
		(end 372.404894 -253.39421)
		(width 0.350012)
		(layer "F.Cu")
		(net "GND")
	)
	(segment
		(start 138.098022 -229.360476)
		(end 138.564874 -229.094538)
		(width 0.350012)
		(layer "F.Cu")
		(net "GND")
	)
	(segment
		(start 191.160146 -211.7852)
		(end 189.775846 -211.7852)
		(width 0.4572)
		(layer "F.Cu")
		(net "GND")
	)
	(segment
		(start 166.242492 -384.531108)
		(end 165.942518 -384.831082)
		(width 0.254)
		(layer "F.Cu")
		(net "GND")
	)
	(segment
		(start 368.947954 -273.010122)
		(end 369.414806 -273.27606)
		(width 0.350012)
		(layer "F.Cu")
		(net "GND")
	)
	(segment
		(start 379.457966 -242.320064)
		(end 379.924818 -242.054126)
		(width 0.350012)
		(layer "F.Cu")
		(net "GND")
	)
	(segment
		(start 109.35208 -63.187072)
		(end 107.831128 -63.187072)
		(width 0.381)
		(layer "F.Cu")
		(net "GND")
	)
	(segment
		(start 418.098224 -395.0208)
		(end 417.406328 -394.831062)
		(width 0.254)
		(layer "F.Cu")
		(net "GND")
	)
	(segment
		(start 297.820842 -399.034)
		(end 297.820842 -399.6055)
		(width 0.254)
		(layer "F.Cu")
		(net "GND")
	)
	(segment
		(start 383.048002 -294.070024)
		(end 383.514854 -294.335962)
		(width 0.350012)
		(layer "F.Cu")
		(net "GND")
	)
	(segment
		(start 336.987896 -292.450012)
		(end 336.521044 -292.71595)
		(width 0.350012)
		(layer "F.Cu")
		(net "GND")
	)
	(segment
		(start 117.888004 -243.130324)
		(end 118.354856 -242.864386)
		(width 0.350012)
		(layer "F.Cu")
		(net "GND")
	)
	(segment
		(start 374.28805 -236.650022)
		(end 374.754902 -236.384084)
		(width 0.350012)
		(layer "F.Cu")
		(net "GND")
	)
	(segment
		(start 165.44417 -391.37971)
		(end 165.345618 -391.281158)
		(width 0.254)
		(layer "F.Cu")
		(net "GND")
	)
	(segment
		(start 374.28805 -256.090166)
		(end 374.754902 -255.824228)
		(width 0.350012)
		(layer "F.Cu")
		(net "GND")
	)
	(segment
		(start 92.245688 -382.951482)
		(end 92.34424 -382.85293)
		(width 0.254)
		(layer "F.Cu")
		(net "GND")
	)
	(segment
		(start 405.419052 -398.542002)
		(end 404.898352 -398.542002)
		(width 0.254)
		(layer "F.Cu")
		(net "GND")
	)
	(segment
		(start 110.83798 -240.700306)
		(end 110.371128 -240.434368)
		(width 0.350012)
		(layer "F.Cu")
		(net "GND")
	)
	(segment
		(start 374.588024 -289.209988)
		(end 375.054876 -289.475926)
		(width 0.350012)
		(layer "F.Cu")
		(net "GND")
	)
	(segment
		(start 23.948136 -12.37488)
		(end 23.948136 -12.374118)
		(width 0.3556)
		(layer "F.Cu")
		(net "GND")
	)
	(segment
		(start 117.957346 -61.554868)
		(end 117.526562 -61.554868)
		(width 0.4572)
		(layer "F.Cu")
		(net "GND")
	)
	(segment
		(start 125.617986 -383.622296)
		(end 125.91796 -383.92227)
		(width 0.254)
		(layer "F.Cu")
		(net "GND")
	)
	(segment
		(start 335.577942 -273.820128)
		(end 335.11109 -274.086066)
		(width 0.350012)
		(layer "F.Cu")
		(net "GND")
	)
	(segment
		(start 55.328058 -238.135414)
		(end 56.712358 -238.135414)
		(width 0.4572)
		(layer "F.Cu")
		(net "GND")
	)
	(segment
		(start 338.39785 -288.399982)
		(end 337.930998 -288.66592)
		(width 0.350012)
		(layer "F.Cu")
		(net "GND")
	)
	(segment
		(start 84.347812 -281.110436)
		(end 83.88096 -281.376374)
		(width 0.350012)
		(layer "F.Cu")
		(net "GND")
	)
	(segment
		(start 384.9624 -392.999722)
		(end 384.37058 -392.999722)
		(width 0.254)
		(layer "F.Cu")
		(net "GND")
	)
	(segment
		(start 289.179762 -348.54134)
		(end 289.60826 -348.54134)
		(width 0.2286)
		(layer "F.Cu")
		(net "GND")
	)
	(segment
		(start 377.878086 -283.5402)
		(end 378.344938 -283.806138)
		(width 0.350012)
		(layer "F.Cu")
		(net "GND")
	)
	(segment
		(start 55.328058 -294.235378)
		(end 56.712358 -294.235378)
		(width 0.4572)
		(layer "F.Cu")
		(net "GND")
	)
	(segment
		(start 350.31807 -230.97998)
		(end 349.851218 -230.714296)
		(width 0.350012)
		(layer "F.Cu")
		(net "GND")
	)
	(segment
		(start 374.417844 -392.004042)
		(end 374.718072 -392.30427)
		(width 0.2032)
		(layer "F.Cu")
		(net "GND")
	)
	(segment
		(start 420.156894 -7.217156)
		(end 420.156894 -8.320024)
		(width 0.3556)
		(layer "F.Cu")
		(net "GND")
	)
	(segment
		(start 58.616596 -391.830814)
		(end 58.616596 -391.37971)
		(width 0.254)
		(layer "F.Cu")
		(net "GND")
	)
	(segment
		(start 354.245418 -399.663158)
		(end 354.545392 -399.143474)
		(width 0.254)
		(layer "F.Cu")
		(net "GND")
	)
	(segment
		(start 14.057884 -107.631484)
		(end 14.486128 -107.631484)
		(width 0.3556)
		(layer "F.Cu")
		(net "GND")
	)
	(segment
		(start 152.145746 -382.951482)
		(end 152.244298 -382.85293)
		(width 0.2032)
		(layer "F.Cu")
		(net "GND")
	)
	(segment
		(start 344.977974 -268.960092)
		(end 344.511122 -269.22603)
		(width 0.350012)
		(layer "F.Cu")
		(net "GND")
	)
	(segment
		(start 408.498294 -396.520924)
		(end 407.946098 -396.710662)
		(width 0.254)
		(layer "F.Cu")
		(net "GND")
	)
	(segment
		(start 122.318018 -383.92227)
		(end 122.370596 -384.617722)
		(width 0.254)
		(layer "F.Cu")
		(net "GND")
	)
	(segment
		(start 371.170454 -392.999722)
		(end 371.117876 -392.30427)
		(width 0.254)
		(layer "F.Cu")
		(net "GND")
	)
	(segment
		(start 187.060078 -203.285344)
		(end 188.444378 -203.285344)
		(width 0.4572)
		(layer "F.Cu")
		(net "GND")
	)
	(segment
		(start 77.467968 -236.650276)
		(end 76.812902 -236.650276)
		(width 0.350012)
		(layer "F.Cu")
		(net "GND")
	)
	(segment
		(start 15.527782 -416.457892)
		(end 15.073122 -416.912552)
		(width 0.381)
		(layer "F.Cu")
		(net "GND")
	)
	(segment
		(start 345.51874 -398.542002)
		(end 344.99804 -398.542002)
		(width 0.254)
		(layer "F.Cu")
		(net "GND")
	)
	(segment
		(start 53.518562 -388.328662)
		(end 54.070504 -388.138924)
		(width 0.254)
		(layer "F.Cu")
		(net "GND")
	)
	(segment
		(start 377.170442 -395.0208)
		(end 376.478546 -394.831062)
		(width 0.254)
		(layer "F.Cu")
		(net "GND")
	)
	(segment
		(start 118.864634 -169.331132)
		(end 118.767098 -169.56659)
		(width 0.2286)
		(layer "F.Cu")
		(net "GND")
	)
	(segment
		(start 387.291326 -398.542002)
		(end 386.770626 -398.542002)
		(width 0.254)
		(layer "F.Cu")
		(net "GND")
	)
	(segment
		(start 358.607868 -281.110182)
		(end 358.141016 -281.37612)
		(width 0.350012)
		(layer "F.Cu")
		(net "GND")
	)
	(segment
		(start 47.784004 -315.485272)
		(end 49.168304 -315.485272)
		(width 0.4572)
		(layer "F.Cu")
		(net "GND")
	)
	(segment
		(start 84.347812 -263.290304)
		(end 83.88096 -263.556242)
		(width 0.350012)
		(layer "F.Cu")
		(net "GND")
	)
	(segment
		(start 119.36857 -168.858184)
		(end 119.337582 -168.858184)
		(width 0.2286)
		(layer "F.Cu")
		(net "GND")
	)
	(segment
		(start 355.018086 -235.840016)
		(end 354.551234 -235.574078)
		(width 0.350012)
		(layer "F.Cu")
		(net "GND")
	)
	(segment
		(start 363.00791 -241.510058)
		(end 363.474762 -241.24412)
		(width 0.350012)
		(layer "F.Cu")
		(net "GND")
	)
	(segment
		(start 391.97788 -268.960092)
		(end 392.444732 -269.22603)
		(width 0.350012)
		(layer "F.Cu")
		(net "GND")
	)
	(segment
		(start 338.56803 -223.69018)
		(end 338.101178 -223.424242)
		(width 0.350012)
		(layer "F.Cu")
		(net "GND")
	)
	(segment
		(start 87.44585 -383.622296)
		(end 87.745824 -383.92227)
		(width 0.254)
		(layer "F.Cu")
		(net "GND")
	)
	(segment
		(start 141.38783 -246.370348)
		(end 141.854682 -246.10441)
		(width 0.350012)
		(layer "F.Cu")
		(net "GND")
	)
	(segment
		(start 97.230438 -400.640296)
		(end 97.452942 -400.417792)
		(width 0.3302)
		(layer "F.Cu")
		(net "GND")
	)
	(segment
		(start 333.697834 -270.580104)
		(end 333.230982 -270.846042)
		(width 0.350012)
		(layer "F.Cu")
		(net "GND")
	)
	(segment
		(start 319.67043 -392.999722)
		(end 319.617852 -392.30427)
		(width 0.254)
		(layer "F.Cu")
		(net "GND")
	)
	(segment
		(start 25.152096 -315.485272)
		(end 26.536396 -315.485272)
		(width 0.4572)
		(layer "F.Cu")
		(net "GND")
	)
	(segment
		(start 308.517798 -399.663158)
		(end 308.817772 -399.143474)
		(width 0.254)
		(layer "F.Cu")
		(net "GND")
	)
	(segment
		(start 439.100214 -274.684998)
		(end 437.715914 -274.684998)
		(width 0.4572)
		(layer "F.Cu")
		(net "GND")
	)
	(segment
		(start 108.487972 -228.55047)
		(end 108.02112 -228.284532)
		(width 0.350012)
		(layer "F.Cu")
		(net "GND")
	)
	(segment
		(start 143.71701 -117.475)
		(end 144.552416 -117.475)
		(width 0.381)
		(layer "F.Cu")
		(net "GND")
	)
	(segment
		(start 335.148682 -395.012926)
		(end 335.148682 -395.613128)
		(width 0.254)
		(layer "F.Cu")
		(net "GND")
	)
	(segment
		(start 45.582078 -388.431024)
		(end 45.105066 -388.29615)
		(width 0.254)
		(layer "F.Cu")
		(net "GND")
	)
	(segment
		(start 132.927852 -251.230384)
		(end 133.394704 -250.964446)
		(width 0.350012)
		(layer "F.Cu")
		(net "GND")
	)
	(segment
		(start 136.987788 -281.110436)
		(end 137.45464 -281.376374)
		(width 0.350012)
		(layer "F.Cu")
		(net "GND")
	)
	(segment
		(start 140.54709 -16.549878)
		(end 140.54836 -16.551148)
		(width 0.3556)
		(layer "F.Cu")
		(net "GND")
	)
	(segment
		(start 136.687814 -256.09042)
		(end 137.154158 -255.824736)
		(width 0.350012)
		(layer "F.Cu")
		(net "GND")
	)
	(segment
		(start 171.246546 -382.30429)
		(end 171.246546 -381.90805)
		(width 0.254)
		(layer "F.Cu")
		(net "GND")
	)
	(segment
		(start 93.745812 -390.761474)
		(end 93.79839 -390.160002)
		(width 0.254)
		(layer "F.Cu")
		(net "GND")
	)
	(segment
		(start 329.446128 -137.575036)
		(end 329.065128 -137.194036)
		(width 0.381)
		(layer "F.Cu")
		(net "GND")
	)
	(segment
		(start 287.581086 -424.696382)
		(end 287.581086 -424.90898)
		(width 0.381)
		(layer "F.Cu")
		(net "GND")
	)
	(segment
		(start 152.145746 -383.402586)
		(end 152.145746 -383.622296)
		(width 0.2032)
		(layer "F.Cu")
		(net "GND")
	)
	(segment
		(start 372.877842 -224.500186)
		(end 373.344694 -224.234248)
		(width 0.350012)
		(layer "F.Cu")
		(net "GND")
	)
	(segment
		(start 384.018028 -391.784586)
		(end 384.018028 -391.333482)
		(width 0.254)
		(layer "F.Cu")
		(net "GND")
	)
	(segment
		(start 357.36784 -247.990106)
		(end 356.901242 -247.724168)
		(width 0.350012)
		(layer "F.Cu")
		(net "GND")
	)
	(segment
		(start 351.25787 -229.360222)
		(end 350.791018 -229.094284)
		(width 0.350012)
		(layer "F.Cu")
		(net "GND")
	)
	(segment
		(start 367.238026 -240.700052)
		(end 367.704878 -240.434114)
		(width 0.350012)
		(layer "F.Cu")
		(net "GND")
	)
	(segment
		(start 98.617786 -252.04039)
		(end 98.150934 -251.774452)
		(width 0.350012)
		(layer "F.Cu")
		(net "GND")
	)
	(segment
		(start 59.908694 -180.746908)
		(end 60.34659 -180.746908)
		(width 0.381)
		(layer "F.Cu")
		(net "GND")
	)
	(segment
		(start 119.97055 -384.617722)
		(end 119.917972 -383.92227)
		(width 0.254)
		(layer "F.Cu")
		(net "GND")
	)
	(segment
		(start 121.647966 -222.070422)
		(end 122.114818 -221.804484)
		(width 0.350012)
		(layer "F.Cu")
		(net "GND")
	)
	(segment
		(start 118.287546 -72.51319)
		(end 118.287546 -71.839582)
		(width 0.254)
		(layer "F.Cu")
		(net "GND")
	)
	(segment
		(start 121.177812 -240.700306)
		(end 121.644664 -240.434368)
		(width 0.350012)
		(layer "F.Cu")
		(net "GND")
	)
	(segment
		(start 97.207832 -233.410252)
		(end 96.74098 -233.144314)
		(width 0.350012)
		(layer "F.Cu")
		(net "GND")
	)
	(segment
		(start 138.098022 -250.420378)
		(end 138.564874 -250.15444)
		(width 0.350012)
		(layer "F.Cu")
		(net "GND")
	)
	(segment
		(start 139.977876 -243.94033)
		(end 140.444728 -243.674392)
		(width 0.350012)
		(layer "F.Cu")
		(net "GND")
	)
	(segment
		(start 29.252164 -227.935282)
		(end 27.867864 -227.935282)
		(width 0.4572)
		(layer "F.Cu")
		(net "GND")
	)
	(segment
		(start 253.413006 -74.44105)
		(end 252.827282 -74.44105)
		(width 0.3556)
		(layer "F.Cu")
		(net "GND")
	)
	(segment
		(start 206.248 -293.38524)
		(end 204.8637 -293.38524)
		(width 0.4572)
		(layer "F.Cu")
		(net "GND")
	)
	(segment
		(start 273.092164 -312.935112)
		(end 274.476464 -312.935112)
		(width 0.4572)
		(layer "F.Cu")
		(net "GND")
	)
	(segment
		(start 392.61796 -227.74021)
		(end 393.084812 -227.474272)
		(width 0.350012)
		(layer "F.Cu")
		(net "GND")
	)
	(segment
		(start 46.494954 -391.77595)
		(end 46.494954 -391.304272)
		(width 0.254)
		(layer "F.Cu")
		(net "GND")
	)
	(segment
		(start 400.24685 -11.26998)
		(end 400.24685 -10.16635)
		(width 0.3556)
		(layer "F.Cu")
		(net "GND")
	)
	(segment
		(start 126.491238 -390.160002)
		(end 125.970538 -390.160002)
		(width 0.254)
		(layer "F.Cu")
		(net "GND")
	)
	(segment
		(start 356.69601 -402.4757)
		(end 356.69601 -402.163788)
		(width 0.254)
		(layer "F.Cu")
		(net "GND")
	)
	(segment
		(start 153.345642 -383.402586)
		(end 153.345642 -383.622296)
		(width 0.254)
		(layer "F.Cu")
		(net "GND")
	)
	(segment
		(start 191.160146 -209.235294)
		(end 189.775846 -209.235294)
		(width 0.4572)
		(layer "F.Cu")
		(net "GND")
	)
	(segment
		(start 17.608042 -315.485272)
		(end 18.992342 -315.485272)
		(width 0.4572)
		(layer "F.Cu")
		(net "GND")
	)
	(segment
		(start 413.044132 -400.212814)
		(end 413.044132 -399.76171)
		(width 0.254)
		(layer "F.Cu")
		(net "GND")
	)
	(segment
		(start 355.957886 -235.840016)
		(end 355.491034 -235.574078)
		(width 0.350012)
		(layer "F.Cu")
		(net "GND")
	)
	(segment
		(start 98.147886 -249.610372)
		(end 97.681034 -249.344434)
		(width 0.350012)
		(layer "F.Cu")
		(net "GND")
	)
	(segment
		(start 361.128056 -236.650022)
		(end 361.594908 -236.384084)
		(width 0.350012)
		(layer "F.Cu")
		(net "GND")
	)
	(segment
		(start 338.39785 -260.860032)
		(end 337.930998 -261.12597)
		(width 0.350012)
		(layer "F.Cu")
		(net "GND")
	)
	(segment
		(start 49.860454 -349.786448)
		(end 49.891442 -349.786448)
		(width 0.2286)
		(layer "F.Cu")
		(net "GND")
	)
	(segment
		(start 366.202214 -151.457914)
		(end 365.564928 -151.457914)
		(width 0.381)
		(layer "F.Cu")
		(net "GND")
	)
	(segment
		(start 108.787946 -276.2504)
		(end 108.321094 -276.516338)
		(width 0.350012)
		(layer "F.Cu")
		(net "GND")
	)
	(segment
		(start 90.627962 -243.130324)
		(end 90.16111 -242.864386)
		(width 0.350012)
		(layer "F.Cu")
		(net "GND")
	)
	(segment
		(start 95.327978 -243.130324)
		(end 94.861126 -242.864386)
		(width 0.350012)
		(layer "F.Cu")
		(net "GND")
	)
	(segment
		(start 97.207832 -230.170228)
		(end 96.74098 -229.90429)
		(width 0.350012)
		(layer "F.Cu")
		(net "GND")
	)
	(segment
		(start 124.770642 -384.617722)
		(end 124.162312 -384.617722)
		(width 0.254)
		(layer "F.Cu")
		(net "GND")
	)
	(segment
		(start 139.507976 -233.410252)
		(end 139.974828 -233.144314)
		(width 0.350012)
		(layer "F.Cu")
		(net "GND")
	)
	(segment
		(start 168.963848 -429.499014)
		(end 168.963848 -429.022002)
		(width 0.381)
		(layer "F.Cu")
		(net "GND")
	)
	(segment
		(start 330.108052 -243.13007)
		(end 329.6412 -242.864132)
		(width 0.350012)
		(layer "F.Cu")
		(net "GND")
	)
	(segment
		(start 369.11788 -224.500186)
		(end 369.584732 -224.234248)
		(width 0.350012)
		(layer "F.Cu")
		(net "GND")
	)
	(segment
		(start 155.745688 -383.402586)
		(end 155.745688 -383.622296)
		(width 0.254)
		(layer "F.Cu")
		(net "GND")
	)
	(segment
		(start 91.919044 -390.160002)
		(end 92.59824 -390.160002)
		(width 0.254)
		(layer "F.Cu")
		(net "GND")
	)
	(segment
		(start 167.79621 -393.781788)
		(end 168.242996 -393.335002)
		(width 0.254)
		(layer "F.Cu")
		(net "GND")
	)
	(segment
		(start 350.618044 -267.34008)
		(end 350.151192 -267.606018)
		(width 0.350012)
		(layer "F.Cu")
		(net "GND")
	)
	(segment
		(start 431.55616 -286.585152)
		(end 430.17186 -286.585152)
		(width 0.4572)
		(layer "F.Cu")
		(net "GND")
	)
	(segment
		(start 303.268126 -296.78503)
		(end 304.652426 -296.78503)
		(width 0.4572)
		(layer "F.Cu")
		(net "GND")
	)
	(segment
		(start 419.298374 -396.520924)
		(end 418.746178 -396.710662)
		(width 0.254)
		(layer "F.Cu")
		(net "GND")
	)
	(segment
		(start 91.801442 -338.094574)
		(end 92.253816 -337.6422)
		(width 0.2286)
		(layer "F.Cu")
		(net "GND")
	)
	(segment
		(start 371.467888 -226.930204)
		(end 371.93474 -226.664266)
		(width 0.350012)
		(layer "F.Cu")
		(net "GND")
	)
	(segment
		(start 122.370596 -390.160002)
		(end 121.691146 -390.160002)
		(width 0.254)
		(layer "F.Cu")
		(net "GND")
	)
	(segment
		(start 377.878086 -291.640006)
		(end 378.344938 -291.905944)
		(width 0.350012)
		(layer "F.Cu")
		(net "GND")
	)
	(segment
		(start 154.474926 -113.60404)
		(end 155.694126 -113.60404)
		(width 0.381)
		(layer "F.Cu")
		(net "GND")
	)
	(segment
		(start 30.569662 -418.239448)
		(end 30.569662 -418.849048)
		(width 0.3556)
		(layer "F.Cu")
		(net "GND")
	)
	(segment
		(start 104.55783 -285.160466)
		(end 104.090978 -285.426404)
		(width 0.350012)
		(layer "F.Cu")
		(net "GND")
	)
	(segment
		(start 95.327978 -228.55047)
		(end 94.861126 -228.284532)
		(width 0.350012)
		(layer "F.Cu")
		(net "GND")
	)
	(segment
		(start 68.729098 -166.850568)
		(end 68.476114 -167.103552)
		(width 0.2286)
		(layer "F.Cu")
		(net "GND")
	)
	(segment
		(start 101.696266 -405.27351)
		(end 101.82987 -405.407114)
		(width 0.381)
		(layer "F.Cu")
		(net "GND")
	)
	(segment
		(start 418.618924 -398.542002)
		(end 418.098224 -398.542002)
		(width 0.254)
		(layer "F.Cu")
		(net "GND")
	)
	(segment
		(start 340.277958 -265.720068)
		(end 339.811106 -265.986006)
		(width 0.350012)
		(layer "F.Cu")
		(net "GND")
	)
	(segment
		(start 417.611306 -161.403792)
		(end 417.611306 -161.684716)
		(width 0.2286)
		(layer "F.Cu")
		(net "GND")
	)
	(segment
		(start 29.346906 -10.16635)
		(end 29.345636 -10.16508)
		(width 0.3556)
		(layer "F.Cu")
		(net "GND")
	)
	(segment
		(start 163.890198 -384.617722)
		(end 163.298378 -384.617722)
		(width 0.254)
		(layer "F.Cu")
		(net "GND")
	)
	(segment
		(start 99.55784 -242.320318)
		(end 99.090988 -242.05438)
		(width 0.350012)
		(layer "F.Cu")
		(net "GND")
	)
	(segment
		(start 374.75795 -248.800112)
		(end 375.224802 -248.534174)
		(width 0.350012)
		(layer "F.Cu")
		(net "GND")
	)
	(segment
		(start 172.066966 -415.503868)
		(end 171.191428 -416.379406)
		(width 0.381)
		(layer "F.Cu")
		(net "GND")
	)
	(segment
		(start 107.831128 -63.187072)
		(end 107.62742 -63.39078)
		(width 0.381)
		(layer "F.Cu")
		(net "GND")
	)
	(segment
		(start 315.518292 -396.710662)
		(end 314.870338 -396.520924)
		(width 0.254)
		(layer "F.Cu")
		(net "GND")
	)
	(segment
		(start 113.187988 -244.750336)
		(end 113.65484 -244.484398)
		(width 0.350012)
		(layer "F.Cu")
		(net "GND")
	)
	(segment
		(start 350.14789 -264.910062)
		(end 349.681038 -265.176)
		(width 0.350012)
		(layer "F.Cu")
		(net "GND")
	)
	(segment
		(start 171.97197 -306.135278)
		(end 173.35627 -306.135278)
		(width 0.4572)
		(layer "F.Cu")
		(net "GND")
	)
	(segment
		(start 422.981628 -395.613128)
		(end 422.819576 -395.451076)
		(width 0.254)
		(layer "F.Cu")
		(net "GND")
	)
	(segment
		(start 277.192232 -221.13494)
		(end 275.807932 -221.13494)
		(width 0.4572)
		(layer "F.Cu")
		(net "GND")
	)
	(segment
		(start 342.545416 -399.143474)
		(end 342.597994 -398.542002)
		(width 0.254)
		(layer "F.Cu")
		(net "GND")
	)
	(segment
		(start 119.617998 -383.622296)
		(end 119.917972 -383.92227)
		(width 0.2032)
		(layer "F.Cu")
		(net "GND")
	)
	(segment
		(start 378.347986 -269.770098)
		(end 378.814838 -270.036036)
		(width 0.350012)
		(layer "F.Cu")
		(net "GND")
	)
	(segment
		(start 305.243738 -433.614322)
		(end 305.929538 -433.614322)
		(width 0.4318)
		(layer "F.Cu")
		(net "GND")
	)
	(segment
		(start 121.177812 -234.220258)
		(end 121.644664 -233.95432)
		(width 0.350012)
		(layer "F.Cu")
		(net "GND")
	)
	(segment
		(start 58.870596 -388.138924)
		(end 58.3184 -388.328662)
		(width 0.254)
		(layer "F.Cu")
		(net "GND")
	)
	(segment
		(start 153.256996 -16.549878)
		(end 153.258266 -16.551148)
		(width 0.3556)
		(layer "F.Cu")
		(net "GND")
	)
	(segment
		(start 115.067842 -233.410252)
		(end 115.534694 -233.144314)
		(width 0.350012)
		(layer "F.Cu")
		(net "GND")
	)
	(segment
		(start 83.107784 -225.310446)
		(end 82.640932 -225.044508)
		(width 0.350012)
		(layer "F.Cu")
		(net "GND")
	)
	(segment
		(start 420.156894 -10.16635)
		(end 420.155624 -10.16508)
		(width 0.3556)
		(layer "F.Cu")
		(net "GND")
	)
	(segment
		(start 387.917944 -256.900172)
		(end 388.384796 -256.634234)
		(width 0.350012)
		(layer "F.Cu")
		(net "GND")
	)
	(segment
		(start 133.398006 -235.84027)
		(end 133.864858 -235.574332)
		(width 0.350012)
		(layer "F.Cu")
		(net "GND")
	)
	(segment
		(start 92.037916 -235.84027)
		(end 91.571064 -235.574332)
		(width 0.350012)
		(layer "F.Cu")
		(net "GND")
	)
	(segment
		(start 126.647956 -268.15034)
		(end 127.114808 -268.416278)
		(width 0.350012)
		(layer "F.Cu")
		(net "GND")
	)
	(segment
		(start 286.380936 -101.09708)
		(end 286.380936 -102.122732)
		(width 0.4572)
		(layer "F.Cu")
		(net "GND")
	)
	(segment
		(start 101.437948 -240.700306)
		(end 100.971096 -240.434368)
		(width 0.350012)
		(layer "F.Cu")
		(net "GND")
	)
	(segment
		(start 104.55783 -267.340334)
		(end 104.090978 -267.606272)
		(width 0.350012)
		(layer "F.Cu")
		(net "GND")
	)
	(segment
		(start 147.345654 -383.402586)
		(end 147.345654 -383.622296)
		(width 0.254)
		(layer "F.Cu")
		(net "GND")
	)
	(segment
		(start 454.188068 -305.28514)
		(end 452.803768 -305.28514)
		(width 0.4572)
		(layer "F.Cu")
		(net "GND")
	)
	(segment
		(start 209.422492 -36.17214)
		(end 209.422492 -36.880038)
		(width 0.254)
		(layer "F.Cu")
		(net "GND")
	)
	(segment
		(start 414.445704 -399.143474)
		(end 414.498282 -398.542002)
		(width 0.254)
		(layer "F.Cu")
		(net "GND")
	)
	(segment
		(start 100.327968 -264.910316)
		(end 99.861116 -265.176254)
		(width 0.350012)
		(layer "F.Cu")
		(net "GND")
	)
	(segment
		(start 42.35831 -348.546166)
		(end 42.786808 -348.546166)
		(width 0.2286)
		(layer "F.Cu")
		(net "GND")
	)
	(segment
		(start 385.570476 -392.999722)
		(end 384.9624 -392.999722)
		(width 0.254)
		(layer "F.Cu")
		(net "GND")
	)
	(segment
		(start 150.098252 -388.138924)
		(end 149.54631 -388.328662)
		(width 0.254)
		(layer "F.Cu")
		(net "GND")
	)
	(segment
		(start 23.946866 -11.26998)
		(end 23.946866 -10.16635)
		(width 0.3556)
		(layer "F.Cu")
		(net "GND")
	)
	(segment
		(start 194.759326 -36.433252)
		(end 195.598542 -36.433252)
		(width 0.4572)
		(layer "F.Cu")
		(net "GND")
	)
	(segment
		(start 131.517898 -232.600246)
		(end 131.98475 -232.334308)
		(width 0.350012)
		(layer "F.Cu")
		(net "GND")
	)
	(segment
		(start 118.357904 -230.980234)
		(end 118.824756 -230.71455)
		(width 0.350012)
		(layer "F.Cu")
		(net "GND")
	)
	(segment
		(start 355.487986 -251.23013)
		(end 355.021134 -250.964192)
		(width 0.350012)
		(layer "F.Cu")
		(net "GND")
	)
	(segment
		(start 387.61797 -391.784586)
		(end 387.61797 -392.004296)
		(width 0.254)
		(layer "F.Cu")
		(net "GND")
	)
	(segment
		(start 313.670442 -395.0208)
		(end 312.978292 -394.831062)
		(width 0.254)
		(layer "F.Cu")
		(net "GND")
	)
	(segment
		(start 385.567936 -223.69018)
		(end 386.034788 -223.424242)
		(width 0.350012)
		(layer "F.Cu")
		(net "GND")
	)
	(segment
		(start 138.098022 -243.94033)
		(end 138.564874 -243.674392)
		(width 0.350012)
		(layer "F.Cu")
		(net "GND")
	)
	(segment
		(start 343.096088 -171.346622)
		(end 343.057988 -171.308522)
		(width 0.254)
		(layer "F.Cu")
		(net "GND")
	)
	(segment
		(start 29.252164 -239.835436)
		(end 27.867864 -239.835436)
		(width 0.4572)
		(layer "F.Cu")
		(net "GND")
	)
	(segment
		(start 424.165522 -7.215886)
		(end 424.166792 -7.217156)
		(width 0.3556)
		(layer "F.Cu")
		(net "GND")
	)
	(segment
		(start 307.368194 -221.13494)
		(end 305.983894 -221.13494)
		(width 0.4572)
		(layer "F.Cu")
		(net "GND")
	)
	(segment
		(start 330.108052 -247.990106)
		(end 329.6412 -247.724168)
		(width 0.350012)
		(layer "F.Cu")
		(net "GND")
	)
	(segment
		(start 3.579368 -73.694798)
		(end 4.392168 -73.694798)
		(width 0.4572)
		(layer "F.Cu")
		(net "GND")
	)
	(segment
		(start 346.858082 -280.300176)
		(end 346.39123 -280.566114)
		(width 0.350012)
		(layer "F.Cu")
		(net "GND")
	)
	(segment
		(start 99.55784 -227.740464)
		(end 99.090988 -227.474526)
		(width 0.350012)
		(layer "F.Cu")
		(net "GND")
	)
	(segment
		(start 311.791096 -398.542002)
		(end 311.270396 -398.542002)
		(width 0.254)
		(layer "F.Cu")
		(net "GND")
	)
	(segment
		(start 411.870144 -140.383006)
		(end 411.092142 -140.383006)
		(width 0.1778)
		(layer "F.Cu")
		(net "GND")
	)
	(segment
		(start 85.757766 -267.340334)
		(end 85.290914 -267.606272)
		(width 0.350012)
		(layer "F.Cu")
		(net "GND")
	)
	(segment
		(start 78.3209 -388.36473)
		(end 78.109826 -388.431024)
		(width 0.254)
		(layer "F.Cu")
		(net "GND")
	)
	(segment
		(start 369.91798 -392.30427)
		(end 369.970558 -392.356848)
		(width 0.254)
		(layer "F.Cu")
		(net "GND")
	)
	(segment
		(start 320.616326 -400.212814)
		(end 320.616326 -399.76171)
		(width 0.254)
		(layer "F.Cu")
		(net "GND")
	)
	(segment
		(start 211.972398 -15.517114)
		(end 211.972398 -14.892528)
		(width 0.3556)
		(layer "F.Cu")
		(net "GND")
	)
	(segment
		(start 131.517898 -237.460282)
		(end 131.98475 -237.194344)
		(width 0.350012)
		(layer "F.Cu")
		(net "GND")
	)
	(segment
		(start 119.597932 -291.64026)
		(end 120.064784 -291.906198)
		(width 0.350012)
		(layer "F.Cu")
		(net "GND")
	)
	(segment
		(start 349.67799 -260.860032)
		(end 349.211138 -261.12597)
		(width 0.350012)
		(layer "F.Cu")
		(net "GND")
	)
	(segment
		(start 345.918028 -293.260018)
		(end 345.451176 -293.525956)
		(width 0.350012)
		(layer "F.Cu")
		(net "GND")
	)
	(segment
		(start 32.695896 -219.435426)
		(end 34.080196 -219.435426)
		(width 0.4572)
		(layer "F.Cu")
		(net "GND")
	)
	(segment
		(start 54.578504 -386.449062)
		(end 54.070504 -386.6388)
		(width 0.254)
		(layer "F.Cu")
		(net "GND")
	)
	(segment
		(start 335.277968 -243.940076)
		(end 334.811116 -243.674138)
		(width 0.350012)
		(layer "F.Cu")
		(net "GND")
	)
	(segment
		(start 379.316488 -400.212814)
		(end 379.316488 -399.76171)
		(width 0.254)
		(layer "F.Cu")
		(net "GND")
	)
	(segment
		(start 110.6678 -276.2504)
		(end 110.200948 -276.516338)
		(width 0.350012)
		(layer "F.Cu")
		(net "GND")
	)
	(segment
		(start 74.865484 -172.414184)
		(end 74.277474 -172.414184)
		(width 0.381)
		(layer "F.Cu")
		(net "GND")
	)
	(segment
		(start 392.917934 -283.5402)
		(end 393.384786 -283.806138)
		(width 0.350012)
		(layer "F.Cu")
		(net "GND")
	)
	(segment
		(start 405.64689 -8.320024)
		(end 405.64689 -9.423654)
		(width 0.3556)
		(layer "F.Cu")
		(net "GND")
	)
	(segment
		(start 140.27785 -290.020248)
		(end 140.744702 -290.286186)
		(width 0.350012)
		(layer "F.Cu")
		(net "GND")
	)
	(segment
		(start 142.074392 -403.639274)
		(end 142.265654 -403.830536)
		(width 0.381)
		(layer "F.Cu")
		(net "GND")
	)
	(segment
		(start 102.07752 -177.125884)
		(end 102.07752 -176.83988)
		(width 0.381)
		(layer "F.Cu")
		(net "GND")
	)
	(segment
		(start 21.70811 -221.135194)
		(end 20.32381 -221.135194)
		(width 0.4572)
		(layer "F.Cu")
		(net "GND")
	)
	(segment
		(start 50.470562 -388.138924)
		(end 51.118516 -388.328662)
		(width 0.254)
		(layer "F.Cu")
		(net "GND")
	)
	(segment
		(start 97.507806 -281.110436)
		(end 97.040954 -281.376374)
		(width 0.350012)
		(layer "F.Cu")
		(net "GND")
	)
	(segment
		(start 456.620626 -47.39894)
		(end 456.250294 -47.769272)
		(width 0.254)
		(layer "F.Cu")
		(net "GND")
	)
	(segment
		(start 301.73295 -356.997)
		(end 300.99 -356.997)
		(width 0.381)
		(layer "F.Cu")
		(net "GND")
	)
	(segment
		(start 341.045546 -391.784586)
		(end 341.045546 -391.333482)
		(width 0.2032)
		(layer "F.Cu")
		(net "GND")
	)
	(segment
		(start 217.481912 -67.324478)
		(end 216.8652 -67.324478)
		(width 0.4572)
		(layer "F.Cu")
		(net "GND")
	)
	(segment
		(start 382.748028 -256.090166)
		(end 383.21488 -255.824228)
		(width 0.350012)
		(layer "F.Cu")
		(net "GND")
	)
	(segment
		(start 410.365702 -142.644114)
		(end 409.883102 -142.644114)
		(width 0.1778)
		(layer "F.Cu")
		(net "GND")
	)
	(segment
		(start 328.527918 -281.110182)
		(end 328.061066 -281.37612)
		(width 0.350012)
		(layer "F.Cu")
		(net "GND")
	)
	(segment
		(start 386.338064 -272.200116)
		(end 386.804916 -272.466054)
		(width 0.350012)
		(layer "F.Cu")
		(net "GND")
	)
	(segment
		(start 135.107934 -276.2504)
		(end 135.574786 -276.516338)
		(width 0.350012)
		(layer "F.Cu")
		(net "GND")
	)
	(segment
		(start 127.117856 -283.540454)
		(end 127.584708 -283.806392)
		(width 0.350012)
		(layer "F.Cu")
		(net "GND")
	)
	(segment
		(start 340.308692 -337.519264)
		(end 340.308692 -337.10245)
		(width 0.2286)
		(layer "F.Cu")
		(net "GND")
	)
	(segment
		(start 164.427916 -228.78542)
		(end 165.812216 -228.78542)
		(width 0.4572)
		(layer "F.Cu")
		(net "GND")
	)
	(segment
		(start 126.347982 -256.09042)
		(end 126.814834 -255.824482)
		(width 0.350012)
		(layer "F.Cu")
		(net "GND")
	)
	(segment
		(start 427.456092 -212.635084)
		(end 428.840392 -212.635084)
		(width 0.4572)
		(layer "F.Cu")
		(net "GND")
	)
	(segment
		(start 445.252602 -417.44011)
		(end 445.709802 -416.98291)
		(width 0.381)
		(layer "F.Cu")
		(net "GND")
	)
	(segment
		(start 264.26795 -108.472986)
		(end 265.4554 -108.472986)
		(width 0.3556)
		(layer "F.Cu")
		(net "GND")
	)
	(segment
		(start 131.817872 -267.340334)
		(end 132.284724 -267.606272)
		(width 0.350012)
		(layer "F.Cu")
		(net "GND")
	)
	(segment
		(start 162.098228 -386.6388)
		(end 161.406332 -386.449062)
		(width 0.254)
		(layer "F.Cu")
		(net "GND")
	)
	(segment
		(start 329.937872 -293.260018)
		(end 329.47102 -293.525956)
		(width 0.350012)
		(layer "F.Cu")
		(net "GND")
	)
	(segment
		(start 347.028008 -225.310192)
		(end 346.561156 -225.044254)
		(width 0.350012)
		(layer "F.Cu")
		(net "GND")
	)
	(segment
		(start 88.747854 -254.470408)
		(end 88.281002 -254.20447)
		(width 0.350012)
		(layer "F.Cu")
		(net "GND")
	)
	(segment
		(start 123.827794 -274.630388)
		(end 124.294646 -274.896326)
		(width 0.350012)
		(layer "F.Cu")
		(net "GND")
	)
	(segment
		(start 416.898328 -395.0208)
		(end 416.206178 -394.831062)
		(width 0.254)
		(layer "F.Cu")
		(net "GND")
	)
	(segment
		(start 99.719638 -387.069076)
		(end 99.004628 -387.069076)
		(width 0.254)
		(layer "F.Cu")
		(net "GND")
	)
	(segment
		(start 373.5705 -395.0208)
		(end 372.878604 -394.831062)
		(width 0.254)
		(layer "F.Cu")
		(net "GND")
	)
	(segment
		(start 22.85746 -389.329168)
		(end 22.41423 -388.885938)
		(width 0.2032)
		(layer "F.Cu")
		(net "GND")
	)
	(segment
		(start 101.437948 -229.360476)
		(end 100.971096 -229.094538)
		(width 0.350012)
		(layer "F.Cu")
		(net "GND")
	)
	(segment
		(start 420.49827 -395.0208)
		(end 419.806374 -394.831062)
		(width 0.254)
		(layer "F.Cu")
		(net "GND")
	)
	(segment
		(start 82.167984 -225.310446)
		(end 81.701132 -225.044508)
		(width 0.350012)
		(layer "F.Cu")
		(net "GND")
	)
	(segment
		(start 127.287782 -225.310446)
		(end 127.754634 -225.044508)
		(width 0.350012)
		(layer "F.Cu")
		(net "GND")
	)
	(segment
		(start 370.828062 -268.150086)
		(end 371.294914 -268.416024)
		(width 0.350012)
		(layer "F.Cu")
		(net "GND")
	)
	(segment
		(start 50.11801 -383.402586)
		(end 50.11801 -382.951482)
		(width 0.254)
		(layer "F.Cu")
		(net "GND")
	)
	(segment
		(start 155.419044 -390.160002)
		(end 154.898344 -390.160002)
		(width 0.254)
		(layer "F.Cu")
		(net "GND")
	)
	(segment
		(start 366.128046 -285.970218)
		(end 366.594898 -286.236156)
		(width 0.350012)
		(layer "F.Cu")
		(net "GND")
	)
	(segment
		(start 333.39786 -242.320064)
		(end 332.931008 -242.054126)
		(width 0.350012)
		(layer "F.Cu")
		(net "GND")
	)
	(segment
		(start 92.33789 -267.340334)
		(end 91.871038 -267.606272)
		(width 0.350012)
		(layer "F.Cu")
		(net "GND")
	)
	(segment
		(start 46.621192 -385.43103)
		(end 46.621192 -384.86715)
		(width 0.254)
		(layer "F.Cu")
		(net "GND")
	)
	(segment
		(start 136.517888 -273.820382)
		(end 136.98474 -274.08632)
		(width 0.350012)
		(layer "F.Cu")
		(net "GND")
	)
	(segment
		(start 126.647956 -277.870412)
		(end 127.114808 -278.13635)
		(width 0.350012)
		(layer "F.Cu")
		(net "GND")
	)
	(segment
		(start 102.677976 -275.440394)
		(end 102.211124 -275.706332)
		(width 0.350012)
		(layer "F.Cu")
		(net "GND")
	)
	(segment
		(start 409.146248 -396.710662)
		(end 408.498294 -396.520924)
		(width 0.254)
		(layer "F.Cu")
		(net "GND")
	)
	(segment
		(start 98.842576 -384.831082)
		(end 98.842576 -385.21132)
		(width 0.254)
		(layer "F.Cu")
		(net "GND")
	)
	(segment
		(start 412.94558 -391.784586)
		(end 412.94558 -391.333482)
		(width 0.254)
		(layer "F.Cu")
		(net "GND")
	)
	(segment
		(start 76.184252 -403.590252)
		(end 76.424536 -403.830536)
		(width 0.381)
		(layer "F.Cu")
		(net "GND")
	)
	(segment
		(start 92.037916 -230.980234)
		(end 91.571064 -230.71455)
		(width 0.350012)
		(layer "F.Cu")
		(net "GND")
	)
	(segment
		(start 125.238002 -273.820382)
		(end 125.704854 -274.08632)
		(width 0.350012)
		(layer "F.Cu")
		(net "GND")
	)
	(segment
		(start 32.948372 -12.374118)
		(end 32.947102 -12.372848)
		(width 0.3556)
		(layer "F.Cu")
		(net "GND")
	)
	(segment
		(start 167.329358 -350.239838)
		(end 167.329358 -349.265494)
		(width 0.381)
		(layer "F.Cu")
		(net "GND")
	)
	(segment
		(start 83.577938 -235.84027)
		(end 83.111086 -235.574332)
		(width 0.350012)
		(layer "F.Cu")
		(net "GND")
	)
	(segment
		(start 126.177802 -273.820382)
		(end 126.644654 -274.08632)
		(width 0.350012)
		(layer "F.Cu")
		(net "GND")
	)
	(segment
		(start 64.191388 -390.160002)
		(end 63.670688 -390.160002)
		(width 0.254)
		(layer "F.Cu")
		(net "GND")
	)
	(segment
		(start 373.817896 -237.460028)
		(end 374.284748 -237.19409)
		(width 0.350012)
		(layer "F.Cu")
		(net "GND")
	)
	(segment
		(start 353.607878 -233.409998)
		(end 353.141026 -233.14406)
		(width 0.350012)
		(layer "F.Cu")
		(net "GND")
	)
	(segment
		(start 137.186924 -167.57015)
		(end 137.954004 -167.57015)
		(width 0.4572)
		(layer "F.Cu")
		(net "GND")
	)
	(segment
		(start 370.491004 -398.542002)
		(end 370.491004 -398.613122)
		(width 0.254)
		(layer "F.Cu")
		(net "GND")
	)
	(segment
		(start 168.33596 -94.151958)
		(end 168.33596 -95.31096)
		(width 0.381)
		(layer "F.Cu")
		(net "GND")
	)
	(segment
		(start 331.987906 -247.990106)
		(end 331.521054 -247.724168)
		(width 0.350012)
		(layer "F.Cu")
		(net "GND")
	)
	(segment
		(start 386.162296 -392.999722)
		(end 386.770626 -392.999722)
		(width 0.254)
		(layer "F.Cu")
		(net "GND")
	)
	(segment
		(start 391.83945 -139.024614)
		(end 391.83945 -138.142472)
		(width 0.254)
		(layer "F.Cu")
		(net "GND")
	)
	(segment
		(start 63.317882 -382.951482)
		(end 63.416434 -382.85293)
		(width 0.254)
		(layer "F.Cu")
		(net "GND")
	)
	(segment
		(start 137.955274 -31.30677)
		(end 138.604244 -30.6578)
		(width 0.381)
		(layer "F.Cu")
		(net "GND")
	)
	(segment
		(start 289.589718 -423.856658)
		(end 289.589718 -424.540934)
		(width 0.381)
		(layer "F.Cu")
		(net "GND")
	)
	(segment
		(start 469.357964 -41.105836)
		(end 469.357964 -40.417496)
		(width 0.4572)
		(layer "F.Cu")
		(net "GND")
	)
	(segment
		(start 133.69798 -272.20037)
		(end 134.164832 -272.466308)
		(width 0.350012)
		(layer "F.Cu")
		(net "GND")
	)
	(segment
		(start 455.054208 -403.12467)
		(end 454.705466 -403.473412)
		(width 0.4572)
		(layer "F.Cu")
		(net "GND")
	)
	(segment
		(start 121.177812 -229.360476)
		(end 121.644664 -229.094538)
		(width 0.350012)
		(layer "F.Cu")
		(net "GND")
	)
	(segment
		(start 298.451016 -23.763224)
		(end 299.066966 -23.763224)
		(width 0.4064)
		(layer "F.Cu")
		(net "GND")
	)
	(segment
		(start 84.29371 -336.803492)
		(end 84.722208 -336.803492)
		(width 0.2286)
		(layer "F.Cu")
		(net "GND")
	)
	(segment
		(start 139.507976 -235.030264)
		(end 139.974828 -234.764326)
		(width 0.350012)
		(layer "F.Cu")
		(net "GND")
	)
	(segment
		(start 106.137964 -243.94033)
		(end 105.671112 -243.674392)
		(width 0.350012)
		(layer "F.Cu")
		(net "GND")
	)
	(segment
		(start 79.177896 -281.920442)
		(end 78.711044 -282.18638)
		(width 0.350012)
		(layer "F.Cu")
		(net "GND")
	)
	(segment
		(start 331.518006 -245.560088)
		(end 331.051154 -245.29415)
		(width 0.350012)
		(layer "F.Cu")
		(net "GND")
	)
	(segment
		(start 438.056782 -435.67731)
		(end 437.425846 -435.67731)
		(width 0.381)
		(layer "F.Cu")
		(net "GND")
	)
	(segment
		(start 122.117866 -250.420378)
		(end 122.584718 -250.15444)
		(width 0.350012)
		(layer "F.Cu")
		(net "GND")
	)
	(segment
		(start 147.698206 -390.160002)
		(end 147.645628 -390.761474)
		(width 0.254)
		(layer "F.Cu")
		(net "GND")
	)
	(segment
		(start 131.517898 -245.560342)
		(end 131.98475 -245.294404)
		(width 0.350012)
		(layer "F.Cu")
		(net "GND")
	)
	(segment
		(start 308.318154 -396.710662)
		(end 307.670454 -396.520924)
		(width 0.254)
		(layer "F.Cu")
		(net "GND")
	)
	(segment
		(start 336.987896 -282.730194)
		(end 336.521044 -282.996132)
		(width 0.350012)
		(layer "F.Cu")
		(net "GND")
	)
	(segment
		(start 123.05792 -224.50044)
		(end 123.524772 -224.234502)
		(width 0.350012)
		(layer "F.Cu")
		(net "GND")
	)
	(segment
		(start 123.05792 -243.94033)
		(end 123.524772 -243.674392)
		(width 0.350012)
		(layer "F.Cu")
		(net "GND")
	)
	(segment
		(start 301.73295 -358.14)
		(end 300.7614 -358.14)
		(width 0.381)
		(layer "F.Cu")
		(net "GND")
	)
	(segment
		(start 295.724072 -287.435036)
		(end 297.108372 -287.435036)
		(width 0.4572)
		(layer "F.Cu")
		(net "GND")
	)
	(segment
		(start 418.21354 -109.631226)
		(end 418.21354 -110.128558)
		(width 0.3556)
		(layer "F.Cu")
		(net "GND")
	)
	(segment
		(start 56.47055 -384.617722)
		(end 56.417972 -383.92227)
		(width 0.254)
		(layer "F.Cu")
		(net "GND")
	)
	(segment
		(start 398.446752 -10.16635)
		(end 398.445482 -10.16508)
		(width 0.3556)
		(layer "F.Cu")
		(net "GND")
	)
	(segment
		(start 351.845372 -392.004042)
		(end 351.845372 -391.784586)
		(width 0.254)
		(layer "F.Cu")
		(net "GND")
	)
	(segment
		(start 386.338064 -268.960092)
		(end 386.804916 -269.22603)
		(width 0.350012)
		(layer "F.Cu")
		(net "GND")
	)
	(segment
		(start 97.04578 -391.281158)
		(end 97.345754 -390.761474)
		(width 0.254)
		(layer "F.Cu")
		(net "GND")
	)
	(segment
		(start 390.291828 -395.451076)
		(end 389.576818 -395.451076)
		(width 0.254)
		(layer "F.Cu")
		(net "GND")
	)
	(segment
		(start 320.340228 -43.700954)
		(end 320.949828 -43.700954)
		(width 0.3556)
		(layer "F.Cu")
		(net "GND")
	)
	(segment
		(start 366.244378 -13.444982)
		(end 366.049814 -13.639546)
		(width 0.4572)
		(layer "F.Cu")
		(net "GND")
	)
	(segment
		(start 44.340018 -286.585406)
		(end 42.955718 -286.585406)
		(width 0.4572)
		(layer "F.Cu")
		(net "GND")
	)
	(segment
		(start 100.327968 -277.870412)
		(end 99.861116 -278.13635)
		(width 0.350012)
		(layer "F.Cu")
		(net "GND")
	)
	(segment
		(start 20.348194 -12.37488)
		(end 20.348194 -12.374118)
		(width 0.3556)
		(layer "F.Cu")
		(net "GND")
	)
	(segment
		(start 92.33789 -264.10031)
		(end 91.871038 -264.366248)
		(width 0.350012)
		(layer "F.Cu")
		(net "GND")
	)
	(segment
		(start 132.81787 -391.281158)
		(end 133.117844 -390.761474)
		(width 0.254)
		(layer "F.Cu")
		(net "GND")
	)
	(segment
		(start 356.89794 -226.120198)
		(end 356.431088 -225.85426)
		(width 0.350012)
		(layer "F.Cu")
		(net "GND")
	)
	(segment
		(start 17.608042 -203.285344)
		(end 18.992342 -203.285344)
		(width 0.4572)
		(layer "F.Cu")
		(net "GND")
	)
	(segment
		(start 69.33057 -165.86327)
		(end 69.299582 -165.86327)
		(width 0.2286)
		(layer "F.Cu")
		(net "GND")
	)
	(segment
		(start 411.745684 -391.784586)
		(end 411.745684 -391.333482)
		(width 0.254)
		(layer "F.Cu")
		(net "GND")
	)
	(segment
		(start 317.778384 -394.831062)
		(end 317.270384 -395.0208)
		(width 0.254)
		(layer "F.Cu")
		(net "GND")
	)
	(segment
		(start 146.087846 -252.850396)
		(end 146.742912 -252.850396)
		(width 0.350012)
		(layer "F.Cu")
		(net "GND")
	)
	(segment
		(start 116.477796 -243.94033)
		(end 116.944648 -243.674392)
		(width 0.350012)
		(layer "F.Cu")
		(net "GND")
	)
	(segment
		(start 130.107944 -256.09042)
		(end 130.574796 -255.824482)
		(width 0.350012)
		(layer "F.Cu")
		(net "GND")
	)
	(segment
		(start 146.087846 -244.750336)
		(end 146.742912 -244.750336)
		(width 0.350012)
		(layer "F.Cu")
		(net "GND")
	)
	(segment
		(start 328.998072 -268.960092)
		(end 328.53122 -269.22603)
		(width 0.350012)
		(layer "F.Cu")
		(net "GND")
	)
	(segment
		(start 101.907848 -252.850396)
		(end 101.440996 -252.584458)
		(width 0.350012)
		(layer "F.Cu")
		(net "GND")
	)
	(segment
		(start 373.5705 -396.520924)
		(end 373.018558 -396.710662)
		(width 0.254)
		(layer "F.Cu")
		(net "GND")
	)
	(segment
		(start 392.917934 -277.060152)
		(end 393.384786 -277.32609)
		(width 0.350012)
		(layer "F.Cu")
		(net "GND")
	)
	(segment
		(start 287.996884 -369.918742)
		(end 289.012884 -369.918742)
		(width 0.4572)
		(layer "F.Cu")
		(net "GND")
	)
	(segment
		(start 338.868004 -289.209988)
		(end 338.401152 -289.475926)
		(width 0.350012)
		(layer "F.Cu")
		(net "GND")
	)
	(segment
		(start 338.39785 -283.5402)
		(end 337.930998 -283.806138)
		(width 0.350012)
		(layer "F.Cu")
		(net "GND")
	)
	(segment
		(start 183.616092 -277.235412)
		(end 182.231792 -277.235412)
		(width 0.4572)
		(layer "F.Cu")
		(net "GND")
	)
	(segment
		(start 118.657878 -286.780478)
		(end 119.12473 -287.046162)
		(width 0.350012)
		(layer "F.Cu")
		(net "GND")
	)
	(segment
		(start 60.662312 -384.617722)
		(end 60.070492 -384.617722)
		(width 0.254)
		(layer "F.Cu")
		(net "GND")
	)
	(segment
		(start 389.627872 -290.83)
		(end 390.094724 -291.095938)
		(width 0.350012)
		(layer "F.Cu")
		(net "GND")
	)
	(segment
		(start 346.858082 -260.860032)
		(end 346.39123 -261.12597)
		(width 0.350012)
		(layer "F.Cu")
		(net "GND")
	)
	(segment
		(start 405.64689 -12.372848)
		(end 405.64689 -11.26998)
		(width 0.3556)
		(layer "F.Cu")
		(net "GND")
	)
	(segment
		(start 94.998286 -386.6388)
		(end 95.506286 -386.449062)
		(width 0.254)
		(layer "F.Cu")
		(net "GND")
	)
	(segment
		(start 339.977984 -253.660148)
		(end 339.511132 -253.39421)
		(width 0.350012)
		(layer "F.Cu")
		(net "GND")
	)
	(segment
		(start 108.487972 -233.410252)
		(end 108.02112 -233.144314)
		(width 0.350012)
		(layer "F.Cu")
		(net "GND")
	)
	(segment
		(start 146.248882 -385.43103)
		(end 146.248882 -384.86715)
		(width 0.254)
		(layer "F.Cu")
		(net "GND")
	)
	(segment
		(start 346.087954 -251.23013)
		(end 345.621102 -250.964192)
		(width 0.350012)
		(layer "F.Cu")
		(net "GND")
	)
	(segment
		(start 120.707912 -235.030264)
		(end 121.174764 -234.764326)
		(width 0.350012)
		(layer "F.Cu")
		(net "GND")
	)
	(segment
		(start 50.20818 -394.7414)
		(end 50.216562 -394.733018)
		(width 0.381)
		(layer "F.Cu")
		(net "GND")
	)
	(segment
		(start 361.625388 -408.588464)
		(end 360.992928 -407.956004)
		(width 0.381)
		(layer "F.Cu")
		(net "GND")
	)
	(segment
		(start 131.517898 -235.84027)
		(end 131.98475 -235.574332)
		(width 0.350012)
		(layer "F.Cu")
		(net "GND")
	)
	(segment
		(start 114.428016 -273.010376)
		(end 114.894614 -273.276314)
		(width 0.350012)
		(layer "F.Cu")
		(net "GND")
	)
	(segment
		(start 411.546294 -396.710662)
		(end 410.89834 -396.520924)
		(width 0.254)
		(layer "F.Cu")
		(net "GND")
	)
	(segment
		(start 380.770638 -392.999722)
		(end 380.162308 -392.999722)
		(width 0.254)
		(layer "F.Cu")
		(net "GND")
	)
	(segment
		(start 380.86792 -254.470154)
		(end 381.334772 -254.204216)
		(width 0.350012)
		(layer "F.Cu")
		(net "GND")
	)
	(segment
		(start 407.24582 -399.143474)
		(end 407.298398 -398.542002)
		(width 0.254)
		(layer "F.Cu")
		(net "GND")
	)
	(segment
		(start 113.187988 -230.170228)
		(end 113.65484 -229.90429)
		(width 0.350012)
		(layer "F.Cu")
		(net "GND")
	)
	(segment
		(start 388.217918 -291.640006)
		(end 388.68477 -291.905944)
		(width 0.350012)
		(layer "F.Cu")
		(net "GND")
	)
	(segment
		(start 430.555908 -430.891188)
		(end 430.555908 -431.532538)
		(width 0.381)
		(layer "F.Cu")
		(net "GND")
	)
	(segment
		(start 98.918014 -293.260272)
		(end 98.451162 -293.52621)
		(width 0.350012)
		(layer "F.Cu")
		(net "GND")
	)
	(segment
		(start 420.419784 -356.372414)
		(end 420.312596 -356.265226)
		(width 0.3556)
		(layer "F.Cu")
		(net "GND")
	)
	(segment
		(start 368.64798 -233.409998)
		(end 369.114832 -233.14406)
		(width 0.350012)
		(layer "F.Cu")
		(net "GND")
	)
	(segment
		(start 330.408026 -279.49017)
		(end 329.941174 -279.756108)
		(width 0.350012)
		(layer "F.Cu")
		(net "GND")
	)
	(segment
		(start 101.737922 -270.580358)
		(end 101.27107 -270.846296)
		(width 0.350012)
		(layer "F.Cu")
		(net "GND")
	)
	(segment
		(start 17.658842 -106.498898)
		(end 17.658842 -105.937812)
		(width 0.3556)
		(layer "F.Cu")
		(net "GND")
	)
	(segment
		(start 121.007886 -263.290304)
		(end 121.474738 -263.556242)
		(width 0.350012)
		(layer "F.Cu")
		(net "GND")
	)
	(segment
		(start 57.618122 -383.92227)
		(end 57.317894 -383.622042)
		(width 0.254)
		(layer "F.Cu")
		(net "GND")
	)
	(segment
		(start 462.357978 -94.317566)
		(end 462.357978 -94.952566)
		(width 0.3556)
		(layer "F.Cu")
		(net "GND")
	)
	(segment
		(start 46.818042 -383.92227)
		(end 46.87062 -383.974848)
		(width 0.254)
		(layer "F.Cu")
		(net "GND")
	)
	(segment
		(start 66.070734 -386.987034)
		(end 66.070734 -386.6388)
		(width 0.254)
		(layer "F.Cu")
		(net "GND")
	)
	(segment
		(start 77.467968 -247.99036)
		(end 76.812902 -247.99036)
		(width 0.350012)
		(layer "F.Cu")
		(net "GND")
	)
	(segment
		(start 48.591216 -390.160002)
		(end 49.270666 -390.160002)
		(width 0.254)
		(layer "F.Cu")
		(net "GND")
	)
	(segment
		(start 418.356796 -11.26998)
		(end 418.355526 -11.26871)
		(width 0.3556)
		(layer "F.Cu")
		(net "GND")
	)
	(segment
		(start 339.977984 -230.97998)
		(end 339.511132 -230.714296)
		(width 0.350012)
		(layer "F.Cu")
		(net "GND")
	)
	(segment
		(start 329.17384 -411.14091)
		(end 328.102214 -412.212536)
		(width 0.381)
		(layer "F.Cu")
		(net "GND")
	)
	(segment
		(start 421.942514 -395.613128)
		(end 421.69842 -395.369034)
		(width 0.254)
		(layer "F.Cu")
		(net "GND")
	)
	(segment
		(start 142.797784 -226.120452)
		(end 143.264636 -225.854514)
		(width 0.350012)
		(layer "F.Cu")
		(net "GND")
	)
	(segment
		(start 354.078032 -250.420124)
		(end 353.61118 -250.154186)
		(width 0.350012)
		(layer "F.Cu")
		(net "GND")
	)
	(segment
		(start 280.67 -426.61205)
		(end 280.67 -427.261528)
		(width 0.381)
		(layer "F.Cu")
		(net "GND")
	)
	(segment
		(start 332.53299 -19.747992)
		(end 332.53299 -18.985992)
		(width 0.381)
		(layer "F.Cu")
		(net "GND")
	)
	(segment
		(start 384.157982 -240.700052)
		(end 384.624834 -240.434114)
		(width 0.350012)
		(layer "F.Cu")
		(net "GND")
	)
	(segment
		(start 352.197924 -247.1801)
		(end 351.731072 -246.914162)
		(width 0.350012)
		(layer "F.Cu")
		(net "GND")
	)
	(segment
		(start 79.14894 -389.63092)
		(end 79.14894 -389.030972)
		(width 0.254)
		(layer "F.Cu")
		(net "GND")
	)
	(segment
		(start 94.233746 -34.329878)
		(end 93.185996 -34.329878)
		(width 0.3556)
		(layer "F.Cu")
		(net "GND")
	)
	(segment
		(start 420.158164 -12.374118)
		(end 420.156894 -12.372848)
		(width 0.3556)
		(layer "F.Cu")
		(net "GND")
	)
	(segment
		(start 46.621192 -387.832092)
		(end 46.621192 -387.231128)
		(width 0.254)
		(layer "F.Cu")
		(net "GND")
	)
	(segment
		(start 144.677892 -232.600246)
		(end 145.144744 -232.334308)
		(width 0.350012)
		(layer "F.Cu")
		(net "GND")
	)
	(segment
		(start 27.547062 -8.320024)
		(end 27.547062 -9.423654)
		(width 0.3556)
		(layer "F.Cu")
		(net "GND")
	)
	(segment
		(start 87.106252 -386.449062)
		(end 86.598252 -386.6388)
		(width 0.254)
		(layer "F.Cu")
		(net "GND")
	)
	(segment
		(start 168.527984 -218.585288)
		(end 167.143684 -218.585288)
		(width 0.4572)
		(layer "F.Cu")
		(net "GND")
	)
	(segment
		(start 178.764946 -413.414972)
		(end 179.431696 -413.414972)
		(width 0.381)
		(layer "F.Cu")
		(net "GND")
	)
	(segment
		(start 319.99809 -34.938462)
		(end 318.81445 -34.938462)
		(width 0.3556)
		(layer "F.Cu")
		(net "GND")
	)
	(segment
		(start 130.107944 -226.930458)
		(end 130.574796 -226.66452)
		(width 0.350012)
		(layer "F.Cu")
		(net "GND")
	)
	(segment
		(start 170.568112 -101.018594)
		(end 170.625262 -101.075744)
		(width 0.4572)
		(layer "F.Cu")
		(net "GND")
	)
	(segment
		(start 95.327978 -231.79024)
		(end 94.861126 -231.524302)
		(width 0.350012)
		(layer "F.Cu")
		(net "GND")
	)
	(segment
		(start 341.857838 -256.900172)
		(end 341.390986 -256.634234)
		(width 0.350012)
		(layer "F.Cu")
		(net "GND")
	)
	(segment
		(start 346.557854 -222.880174)
		(end 346.091002 -222.614236)
		(width 0.350012)
		(layer "F.Cu")
		(net "GND")
	)
	(segment
		(start 136.946894 -12.496292)
		(end 136.945624 -12.495022)
		(width 0.4572)
		(layer "F.Cu")
		(net "GND")
	)
	(segment
		(start 345.58986 -392.999722)
		(end 346.19819 -392.999722)
		(width 0.254)
		(layer "F.Cu")
		(net "GND")
	)
	(segment
		(start 345.1479 -241.510058)
		(end 344.681048 -241.24412)
		(width 0.350012)
		(layer "F.Cu")
		(net "GND")
	)
	(segment
		(start 342.597994 -392.999722)
		(end 342.545416 -392.30427)
		(width 0.254)
		(layer "F.Cu")
		(net "GND")
	)
	(segment
		(start 387.917944 -392.30427)
		(end 387.970522 -392.999722)
		(width 0.254)
		(layer "F.Cu")
		(net "GND")
	)
	(segment
		(start 387.448044 -254.470154)
		(end 387.914896 -254.204216)
		(width 0.350012)
		(layer "F.Cu")
		(net "GND")
	)
	(segment
		(start 349.847916 -252.850142)
		(end 349.381064 -252.584204)
		(width 0.350012)
		(layer "F.Cu")
		(net "GND")
	)
	(segment
		(start 442.5442 -303.585118)
		(end 443.9285 -303.585118)
		(width 0.4572)
		(layer "F.Cu")
		(net "GND")
	)
	(segment
		(start 44.340018 -302.735234)
		(end 42.955718 -302.735234)
		(width 0.4572)
		(layer "F.Cu")
		(net "GND")
	)
	(segment
		(start 123.05792 -229.360476)
		(end 123.524772 -229.094538)
		(width 0.350012)
		(layer "F.Cu")
		(net "GND")
	)
	(segment
		(start 21.70811 -199.8853)
		(end 20.32381 -199.8853)
		(width 0.4572)
		(layer "F.Cu")
		(net "GND")
	)
	(segment
		(start 412.955486 -7.215886)
		(end 412.956756 -7.217156)
		(width 0.3556)
		(layer "F.Cu")
		(net "GND")
	)
	(segment
		(start 100.327968 -274.630388)
		(end 99.861116 -274.896326)
		(width 0.350012)
		(layer "F.Cu")
		(net "GND")
	)
	(segment
		(start 302.620934 -395.012926)
		(end 302.620934 -395.613128)
		(width 0.254)
		(layer "F.Cu")
		(net "GND")
	)
	(segment
		(start 117.888004 -246.370348)
		(end 118.354856 -246.10441)
		(width 0.350012)
		(layer "F.Cu")
		(net "GND")
	)
	(segment
		(start 374.588024 -277.870158)
		(end 375.054876 -278.136096)
		(width 0.350012)
		(layer "F.Cu")
		(net "GND")
	)
	(segment
		(start 428.586138 -365.825532)
		(end 428.588678 -365.828072)
		(width 0.508)
		(layer "F.Cu")
		(net "GND")
	)
	(segment
		(start 85.757766 -278.680418)
		(end 85.290914 -278.946356)
		(width 0.350012)
		(layer "F.Cu")
		(net "GND")
	)
	(segment
		(start 356.42804 -247.990106)
		(end 355.961188 -247.724168)
		(width 0.350012)
		(layer "F.Cu")
		(net "GND")
	)
	(segment
		(start 429.276764 -356.397814)
		(end 428.908972 -356.397814)
		(width 0.381)
		(layer "F.Cu")
		(net "GND")
	)
	(segment
		(start 309.925212 -43.78833)
		(end 308.744112 -43.78833)
		(width 0.3556)
		(layer "F.Cu")
		(net "GND")
	)
	(segment
		(start 94.645734 -383.402586)
		(end 94.645734 -383.622296)
		(width 0.254)
		(layer "F.Cu")
		(net "GND")
	)
	(segment
		(start 59.462416 -384.617722)
		(end 60.070492 -384.617722)
		(width 0.254)
		(layer "F.Cu")
		(net "GND")
	)
	(segment
		(start 171.97197 -315.485272)
		(end 173.35627 -315.485272)
		(width 0.4572)
		(layer "F.Cu")
		(net "GND")
	)
	(segment
		(start 129.63779 -234.220258)
		(end 130.104642 -233.95432)
		(width 0.350012)
		(layer "F.Cu")
		(net "GND")
	)
	(segment
		(start 374.588024 -271.39011)
		(end 375.054876 -271.656048)
		(width 0.350012)
		(layer "F.Cu")
		(net "GND")
	)
	(segment
		(start 366.128046 -274.630134)
		(end 366.594898 -274.896072)
		(width 0.350012)
		(layer "F.Cu")
		(net "GND")
	)
	(segment
		(start 336.687922 -252.850142)
		(end 336.22107 -252.584204)
		(width 0.350012)
		(layer "F.Cu")
		(net "GND")
	)
	(segment
		(start 394.027914 -241.510058)
		(end 394.68298 -241.510058)
		(width 0.350012)
		(layer "F.Cu")
		(net "GND")
	)
	(segment
		(start 346.387928 -263.29005)
		(end 345.921076 -263.555988)
		(width 0.350012)
		(layer "F.Cu")
		(net "GND")
	)
	(segment
		(start 80.58785 -289.210242)
		(end 80.120998 -289.47618)
		(width 0.350012)
		(layer "F.Cu")
		(net "GND")
	)
	(segment
		(start 87.637874 -286.780478)
		(end 87.171022 -287.046162)
		(width 0.350012)
		(layer "F.Cu")
		(net "GND")
	)
	(segment
		(start 103.317802 -240.700306)
		(end 102.85095 -240.434368)
		(width 0.350012)
		(layer "F.Cu")
		(net "GND")
	)
	(segment
		(start 373.17807 -281.920188)
		(end 373.644922 -282.186126)
		(width 0.350012)
		(layer "F.Cu")
		(net "GND")
	)
	(segment
		(start 269.423134 -333.744316)
		(end 269.423134 -333.045562)
		(width 0.4572)
		(layer "F.Cu")
		(net "GND")
	)
	(segment
		(start 202.147932 -212.635338)
		(end 203.532232 -212.635338)
		(width 0.4572)
		(layer "F.Cu")
		(net "GND")
	)
	(segment
		(start 339.03793 -250.420124)
		(end 338.571078 -250.154186)
		(width 0.350012)
		(layer "F.Cu")
		(net "GND")
	)
	(segment
		(start 360.957876 -277.060152)
		(end 361.424728 -277.32609)
		(width 0.350012)
		(layer "F.Cu")
		(net "GND")
	)
	(segment
		(start 379.457966 -255.28016)
		(end 379.924818 -255.014222)
		(width 0.350012)
		(layer "F.Cu")
		(net "GND")
	)
	(segment
		(start 355.78796 -295.690036)
		(end 355.321108 -295.955974)
		(width 0.350012)
		(layer "F.Cu")
		(net "GND")
	)
	(segment
		(start 150.045674 -390.761474)
		(end 150.098252 -390.160002)
		(width 0.254)
		(layer "F.Cu")
		(net "GND")
	)
	(segment
		(start 185.122058 -113.85296)
		(end 184.732168 -113.46307)
		(width 0.254)
		(layer "F.Cu")
		(net "GND")
	)
	(segment
		(start 345.1479 -239.890046)
		(end 344.681048 -239.624108)
		(width 0.350012)
		(layer "F.Cu")
		(net "GND")
	)
	(segment
		(start 328.227944 -243.13007)
		(end 327.761092 -242.864132)
		(width 0.350012)
		(layer "F.Cu")
		(net "GND")
	)
	(segment
		(start 126.562358 -384.617722)
		(end 127.170434 -384.617722)
		(width 0.254)
		(layer "F.Cu")
		(net "GND")
	)
	(segment
		(start 88.747854 -233.410252)
		(end 88.281002 -233.144314)
		(width 0.350012)
		(layer "F.Cu")
		(net "GND")
	)
	(segment
		(start 372.238016 -272.200116)
		(end 372.704868 -272.466054)
		(width 0.350012)
		(layer "F.Cu")
		(net "GND")
	)
	(segment
		(start 80.757776 -234.220258)
		(end 80.291178 -233.95432)
		(width 0.350012)
		(layer "F.Cu")
		(net "GND")
	)
	(segment
		(start 370.562378 -392.999722)
		(end 371.170454 -392.999722)
		(width 0.254)
		(layer "F.Cu")
		(net "GND")
	)
	(segment
		(start 83.40725 -140.308838)
		(end 83.40725 -139.349734)
		(width 0.3556)
		(layer "F.Cu")
		(net "GND")
	)
	(segment
		(start 82.167984 -228.55047)
		(end 81.701132 -228.284532)
		(width 0.350012)
		(layer "F.Cu")
		(net "GND")
	)
	(segment
		(start 344.678 -248.800112)
		(end 344.211148 -248.534174)
		(width 0.350012)
		(layer "F.Cu")
		(net "GND")
	)
	(segment
		(start 183.616092 -286.585406)
		(end 182.231792 -286.585406)
		(width 0.4572)
		(layer "F.Cu")
		(net "GND")
	)
	(segment
		(start 34.18713 -351.978722)
		(end 33.819338 -351.978722)
		(width 0.381)
		(layer "F.Cu")
		(net "GND")
	)
	(segment
		(start 372.018052 -391.784586)
		(end 372.018052 -391.333482)
		(width 0.254)
		(layer "F.Cu")
		(net "GND")
	)
	(segment
		(start 366.767872 -249.610118)
		(end 367.234724 -249.34418)
		(width 0.350012)
		(layer "F.Cu")
		(net "GND")
	)
	(segment
		(start 306.417726 -399.143474)
		(end 306.470304 -398.542002)
		(width 0.254)
		(layer "F.Cu")
		(net "GND")
	)
	(segment
		(start 350.78797 -236.650022)
		(end 350.321118 -236.384084)
		(width 0.350012)
		(layer "F.Cu")
		(net "GND")
	)
	(segment
		(start 274.460208 -100.046028)
		(end 274.79371 -100.37953)
		(width 0.3556)
		(layer "F.Cu")
		(net "GND")
	)
	(segment
		(start 61.53277 -41.277794)
		(end 61.531754 -41.27881)
		(width 0.4572)
		(layer "F.Cu")
		(net "GND")
	)
	(segment
		(start 292.280086 -302.73498)
		(end 290.895786 -302.73498)
		(width 0.4572)
		(layer "F.Cu")
		(net "GND")
	)
	(segment
		(start 454.188068 -199.885046)
		(end 452.803768 -199.885046)
		(width 0.4572)
		(layer "F.Cu")
		(net "GND")
	)
	(segment
		(start 100.027994 -251.230384)
		(end 99.561142 -250.964446)
		(width 0.350012)
		(layer "F.Cu")
		(net "GND")
	)
	(segment
		(start 369.72113 -398.613122)
		(end 369.72113 -398.01292)
		(width 0.254)
		(layer "F.Cu")
		(net "GND")
	)
	(segment
		(start 115.067842 -228.55047)
		(end 115.534694 -228.284532)
		(width 0.350012)
		(layer "F.Cu")
		(net "GND")
	)
	(segment
		(start 116.30787 -294.070278)
		(end 116.774722 -294.336216)
		(width 0.350012)
		(layer "F.Cu")
		(net "GND")
	)
	(segment
		(start 333.697834 -273.820128)
		(end 333.230982 -274.086066)
		(width 0.350012)
		(layer "F.Cu")
		(net "GND")
	)
	(segment
		(start 366.415066 -424.403012)
		(end 366.415066 -425.018962)
		(width 0.381)
		(layer "F.Cu")
		(net "GND")
	)
	(segment
		(start 77.767942 -290.830254)
		(end 77.112876 -290.830254)
		(width 0.350012)
		(layer "F.Cu")
		(net "GND")
	)
	(segment
		(start 398.446752 -7.217156)
		(end 398.446752 -8.320024)
		(width 0.3556)
		(layer "F.Cu")
		(net "GND")
	)
	(segment
		(start 319.317624 -399.663158)
		(end 319.617852 -399.143474)
		(width 0.254)
		(layer "F.Cu")
		(net "GND")
	)
	(segment
		(start 358.26446 -395.466062)
		(end 358.793288 -395.466062)
		(width 0.381)
		(layer "F.Cu")
		(net "GND")
	)
	(segment
		(start 43.543982 -386.418074)
		(end 43.543982 -385.59359)
		(width 0.254)
		(layer "F.Cu")
		(net "GND")
	)
	(segment
		(start 8.42772 -76.544678)
		(end 9.065006 -76.544678)
		(width 0.4064)
		(layer "F.Cu")
		(net "GND")
	)
	(segment
		(start 122.117866 -224.50044)
		(end 122.584718 -224.234502)
		(width 0.350012)
		(layer "F.Cu")
		(net "GND")
	)
	(segment
		(start 142.797784 -253.660402)
		(end 143.264636 -253.394464)
		(width 0.350012)
		(layer "F.Cu")
		(net "GND")
	)
	(segment
		(start 355.31806 -273.820128)
		(end 354.851208 -274.086066)
		(width 0.350012)
		(layer "F.Cu")
		(net "GND")
	)
	(segment
		(start 383.048002 -271.39011)
		(end 383.514854 -271.656048)
		(width 0.350012)
		(layer "F.Cu")
		(net "GND")
	)
	(segment
		(start 343.56802 -285.970218)
		(end 343.101168 -286.236156)
		(width 0.350012)
		(layer "F.Cu")
		(net "GND")
	)
	(segment
		(start 25.77211 -348.546166)
		(end 26.200608 -348.546166)
		(width 0.2286)
		(layer "F.Cu")
		(net "GND")
	)
	(segment
		(start 146.087846 -226.930458)
		(end 146.554698 -226.66452)
		(width 0.350012)
		(layer "F.Cu")
		(net "GND")
	)
	(segment
		(start 363.00791 -246.370094)
		(end 363.474762 -246.104156)
		(width 0.350012)
		(layer "F.Cu")
		(net "GND")
	)
	(segment
		(start 133.69798 -283.540454)
		(end 134.164832 -283.806392)
		(width 0.350012)
		(layer "F.Cu")
		(net "GND")
	)
	(segment
		(start 288.180018 -275.535136)
		(end 289.564318 -275.535136)
		(width 0.4572)
		(layer "F.Cu")
		(net "GND")
	)
	(segment
		(start 74.357738 -402.773388)
		(end 74.357738 -402.834094)
		(width 0.381)
		(layer "F.Cu")
		(net "GND")
	)
	(segment
		(start 102.378002 -245.560342)
		(end 101.91115 -245.294404)
		(width 0.350012)
		(layer "F.Cu")
		(net "GND")
	)
	(segment
		(start 368.64798 -246.370094)
		(end 369.114832 -246.104156)
		(width 0.350012)
		(layer "F.Cu")
		(net "GND")
	)
	(segment
		(start 83.50631 -386.449062)
		(end 82.99831 -386.6388)
		(width 0.254)
		(layer "F.Cu")
		(net "GND")
	)
	(segment
		(start 308.61635 -403.14245)
		(end 308.61635 -402.309838)
		(width 0.381)
		(layer "F.Cu")
		(net "GND")
	)
	(segment
		(start 413.298386 -398.542002)
		(end 412.618936 -398.542002)
		(width 0.254)
		(layer "F.Cu")
		(net "GND")
	)
	(segment
		(start 42.057066 -10.16635)
		(end 42.055796 -10.16508)
		(width 0.3556)
		(layer "F.Cu")
		(net "GND")
	)
	(segment
		(start 265.54811 -284.88513)
		(end 266.93241 -284.88513)
		(width 0.4572)
		(layer "F.Cu")
		(net "GND")
	)
	(segment
		(start 115.537996 -235.84027)
		(end 116.004848 -235.574332)
		(width 0.350012)
		(layer "F.Cu")
		(net "GND")
	)
	(segment
		(start 257.125724 -134.605268)
		(end 257.379724 -134.351268)
		(width 0.3556)
		(layer "F.Cu")
		(net "GND")
	)
	(segment
		(start 288.463736 -394.719048)
		(end 288.300922 -394.556234)
		(width 0.254)
		(layer "F.Cu")
		(net "GND")
	)
	(segment
		(start 433.166774 -7.217156)
		(end 433.166774 -8.320024)
		(width 0.3556)
		(layer "F.Cu")
		(net "GND")
	)
	(segment
		(start 126.647956 -284.35046)
		(end 127.114808 -284.616398)
		(width 0.350012)
		(layer "F.Cu")
		(net "GND")
	)
	(segment
		(start 119.2784 -386.449062)
		(end 118.770654 -386.6388)
		(width 0.254)
		(layer "F.Cu")
		(net "GND")
	)
	(segment
		(start 338.868004 -273.010122)
		(end 338.401152 -273.27606)
		(width 0.350012)
		(layer "F.Cu")
		(net "GND")
	)
	(segment
		(start 303.717706 -391.333482)
		(end 303.816258 -391.23493)
		(width 0.254)
		(layer "F.Cu")
		(net "GND")
	)
	(segment
		(start 302.620934 -398.613122)
		(end 302.620934 -398.946624)
		(width 0.254)
		(layer "F.Cu")
		(net "GND")
	)
	(segment
		(start 18.232628 -40.942514)
		(end 18.231866 -40.943276)
		(width 0.4572)
		(layer "F.Cu")
		(net "GND")
	)
	(segment
		(start 232.30205 -142.076678)
		(end 232.30205 -142.246858)
		(width 0.4572)
		(layer "F.Cu")
		(net "GND")
	)
	(segment
		(start 22.148292 -12.37488)
		(end 22.148292 -12.374118)
		(width 0.3556)
		(layer "F.Cu")
		(net "GND")
	)
	(segment
		(start 328.697844 -255.28016)
		(end 328.231246 -255.014222)
		(width 0.350012)
		(layer "F.Cu")
		(net "GND")
	)
	(segment
		(start 88.747854 -238.270288)
		(end 88.281002 -238.00435)
		(width 0.350012)
		(layer "F.Cu")
		(net "GND")
	)
	(segment
		(start 124.467874 -254.470408)
		(end 124.934726 -254.20447)
		(width 0.350012)
		(layer "F.Cu")
		(net "GND")
	)
	(segment
		(start 375.22785 -225.310192)
		(end 375.694702 -225.044254)
		(width 0.350012)
		(layer "F.Cu")
		(net "GND")
	)
	(segment
		(start 343.798144 -395.0208)
		(end 343.105994 -394.831062)
		(width 0.254)
		(layer "F.Cu")
		(net "GND")
	)
	(segment
		(start 162.945572 -383.622042)
		(end 162.945572 -383.402586)
		(width 0.254)
		(layer "F.Cu")
		(net "GND")
	)
	(segment
		(start 131.970526 -384.617722)
		(end 132.562346 -384.617722)
		(width 0.254)
		(layer "F.Cu")
		(net "GND")
	)
	(segment
		(start 301.58182 -395.613128)
		(end 301.104808 -395.42974)
		(width 0.254)
		(layer "F.Cu")
		(net "GND")
	)
	(segment
		(start 59.849512 -403.830536)
		(end 59.849512 -402.882354)
		(width 0.381)
		(layer "F.Cu")
		(net "GND")
	)
	(segment
		(start 94.333822 -179.610512)
		(end 93.854524 -180.08981)
		(width 0.2286)
		(layer "F.Cu")
		(net "GND")
	)
	(segment
		(start 372.018052 -391.333482)
		(end 372.116604 -391.23493)
		(width 0.254)
		(layer "F.Cu")
		(net "GND")
	)
	(segment
		(start 80.57896 -65.158112)
		(end 80.57896 -64.25438)
		(width 0.381)
		(layer "F.Cu")
		(net "GND")
	)
	(segment
		(start 113.187988 -233.410252)
		(end 113.65484 -233.144314)
		(width 0.350012)
		(layer "F.Cu")
		(net "GND")
	)
	(segment
		(start 304.917856 -399.663158)
		(end 305.016408 -399.76171)
		(width 0.254)
		(layer "F.Cu")
		(net "GND")
	)
	(segment
		(start 454.188068 -221.13494)
		(end 452.803768 -221.13494)
		(width 0.4572)
		(layer "F.Cu")
		(net "GND")
	)
	(segment
		(start 345.447874 -277.870158)
		(end 344.981022 -278.136096)
		(width 0.350012)
		(layer "F.Cu")
		(net "GND")
	)
	(segment
		(start 273.092164 -238.13516)
		(end 274.476464 -238.13516)
		(width 0.4572)
		(layer "F.Cu")
		(net "GND")
	)
	(segment
		(start 379.75794 -268.960092)
		(end 380.224792 -269.22603)
		(width 0.350012)
		(layer "F.Cu")
		(net "GND")
	)
	(segment
		(start 90.157808 -242.320318)
		(end 89.690956 -242.05438)
		(width 0.350012)
		(layer "F.Cu")
		(net "GND")
	)
	(segment
		(start 338.39785 -268.960092)
		(end 337.930998 -269.22603)
		(width 0.350012)
		(layer "F.Cu")
		(net "GND")
	)
	(segment
		(start 80.58785 -290.830254)
		(end 80.120998 -291.096192)
		(width 0.350012)
		(layer "F.Cu")
		(net "GND")
	)
	(segment
		(start 145.374868 -57.676034)
		(end 144.908016 -57.676034)
		(width 0.1778)
		(layer "F.Cu")
		(net "GND")
	)
	(segment
		(start 111.286544 -400.437604)
		(end 111.974884 -400.437604)
		(width 0.3048)
		(layer "F.Cu")
		(net "GND")
	)
	(segment
		(start 171.97197 -210.085432)
		(end 173.35627 -210.085432)
		(width 0.4572)
		(layer "F.Cu")
		(net "GND")
	)
	(segment
		(start 95.627952 -285.970472)
		(end 95.1611 -286.23641)
		(width 0.350012)
		(layer "F.Cu")
		(net "GND")
	)
	(segment
		(start 330.408026 -274.630134)
		(end 329.941174 -274.896072)
		(width 0.350012)
		(layer "F.Cu")
		(net "GND")
	)
	(segment
		(start 331.987906 -246.370094)
		(end 331.521054 -246.104156)
		(width 0.350012)
		(layer "F.Cu")
		(net "GND")
	)
	(segment
		(start 159.698182 -390.160002)
		(end 159.018986 -390.160002)
		(width 0.254)
		(layer "F.Cu")
		(net "GND")
	)
	(segment
		(start 108.487972 -244.750336)
		(end 108.02112 -244.484398)
		(width 0.350012)
		(layer "F.Cu")
		(net "GND")
	)
	(segment
		(start 350.618044 -281.920188)
		(end 350.151192 -282.186126)
		(width 0.350012)
		(layer "F.Cu")
		(net "GND")
	)
	(segment
		(start 110.6678 -269.770352)
		(end 110.200948 -270.03629)
		(width 0.350012)
		(layer "F.Cu")
		(net "GND")
	)
	(segment
		(start 47.717964 -383.402586)
		(end 47.717964 -383.622296)
		(width 0.254)
		(layer "F.Cu")
		(net "GND")
	)
	(segment
		(start 288.926778 -349.211138)
		(end 288.926778 -348.794324)
		(width 0.2286)
		(layer "F.Cu")
		(net "GND")
	)
	(segment
		(start 366.767872 -251.23013)
		(end 367.234724 -250.964192)
		(width 0.350012)
		(layer "F.Cu")
		(net "GND")
	)
	(segment
		(start 121.007886 -271.390364)
		(end 121.474738 -271.656302)
		(width 0.350012)
		(layer "F.Cu")
		(net "GND")
	)
	(segment
		(start 310.017668 -392.30427)
		(end 310.070246 -392.999722)
		(width 0.254)
		(layer "F.Cu")
		(net "GND")
	)
	(segment
		(start 315.378338 -394.831062)
		(end 314.870338 -395.0208)
		(width 0.254)
		(layer "F.Cu")
		(net "GND")
	)
	(segment
		(start 69.50456 -340.211664)
		(end 70.09257 -340.211664)
		(width 0.381)
		(layer "F.Cu")
		(net "GND")
	)
	(segment
		(start 368.474752 -292.71595)
		(end 368.478054 -293.260018)
		(width 0.350012)
		(layer "F.Cu")
		(net "GND")
	)
	(segment
		(start 118.187978 -287.590484)
		(end 118.65483 -287.856422)
		(width 0.350012)
		(layer "F.Cu")
		(net "GND")
	)
	(segment
		(start 120.47855 -386.449062)
		(end 119.97055 -386.6388)
		(width 0.254)
		(layer "F.Cu")
		(net "GND")
	)
	(segment
		(start 324.024244 -38.10762)
		(end 324.640194 -38.10762)
		(width 0.3556)
		(layer "F.Cu")
		(net "GND")
	)
	(segment
		(start 418.045646 -399.143474)
		(end 418.098224 -398.542002)
		(width 0.254)
		(layer "F.Cu")
		(net "GND")
	)
	(segment
		(start 334.808068 -225.310192)
		(end 334.341216 -225.044254)
		(width 0.350012)
		(layer "F.Cu")
		(net "GND")
	)
	(segment
		(start 350.78797 -235.03001)
		(end 350.321118 -234.764072)
		(width 0.350012)
		(layer "F.Cu")
		(net "GND")
	)
	(segment
		(start 345.845384 -399.663158)
		(end 346.145612 -399.143474)
		(width 0.254)
		(layer "F.Cu")
		(net "GND")
	)
	(segment
		(start 313.317636 -399.663158)
		(end 313.617864 -399.143474)
		(width 0.254)
		(layer "F.Cu")
		(net "GND")
	)
	(segment
		(start 419.912038 -275.535136)
		(end 421.296338 -275.535136)
		(width 0.4572)
		(layer "F.Cu")
		(net "GND")
	)
	(segment
		(start 157.245812 -390.761474)
		(end 157.29839 -390.160002)
		(width 0.254)
		(layer "F.Cu")
		(net "GND")
	)
	(segment
		(start 133.934454 -385.731004)
		(end 133.683756 -386.449062)
		(width 0.254)
		(layer "F.Cu")
		(net "GND")
	)
	(segment
		(start 218.360752 -44.788328)
		(end 219.325952 -44.788328)
		(width 0.3556)
		(layer "F.Cu")
		(net "GND")
	)
	(segment
		(start 8.447278 -136.65835)
		(end 8.447278 -137.25398)
		(width 0.3556)
		(layer "F.Cu")
		(net "GND")
	)
	(segment
		(start 165.44417 -383.304034)
		(end 165.44417 -382.85293)
		(width 0.254)
		(layer "F.Cu")
		(net "GND")
	)
	(segment
		(start 310.017668 -399.143474)
		(end 310.070246 -398.542002)
		(width 0.254)
		(layer "F.Cu")
		(net "GND")
	)
	(segment
		(start 314.517786 -391.333482)
		(end 314.616338 -391.23493)
		(width 0.254)
		(layer "F.Cu")
		(net "GND")
	)
	(segment
		(start 123.827794 -290.830254)
		(end 124.294646 -291.096192)
		(width 0.350012)
		(layer "F.Cu")
		(net "GND")
	)
	(segment
		(start 332.071472 -396.679674)
		(end 332.71841 -396.679674)
		(width 0.254)
		(layer "F.Cu")
		(net "GND")
	)
	(segment
		(start 302.344836 -423.234104)
		(end 302.997362 -423.234104)
		(width 0.381)
		(layer "F.Cu")
		(net "GND")
	)
	(segment
		(start 354.078032 -240.700052)
		(end 353.61118 -240.434114)
		(width 0.350012)
		(layer "F.Cu")
		(net "GND")
	)
	(segment
		(start 54.918102 -383.402586)
		(end 54.918102 -383.622296)
		(width 0.254)
		(layer "F.Cu")
		(net "GND")
	)
	(segment
		(start 389.627872 -261.670038)
		(end 390.094724 -261.935976)
		(width 0.350012)
		(layer "F.Cu")
		(net "GND")
	)
	(segment
		(start 389.845296 -398.542002)
		(end 389.170672 -398.542002)
		(width 0.254)
		(layer "F.Cu")
		(net "GND")
	)
	(segment
		(start 354.842318 -396.213076)
		(end 354.046028 -396.710662)
		(width 0.254)
		(layer "F.Cu")
		(net "GND")
	)
	(segment
		(start 350.645476 -391.784586)
		(end 350.645476 -392.004296)
		(width 0.254)
		(layer "F.Cu")
		(net "GND")
	)
	(segment
		(start 377.878086 -293.260018)
		(end 378.344938 -293.525956)
		(width 0.350012)
		(layer "F.Cu")
		(net "GND")
	)
	(segment
		(start 308.262274 -392.999722)
		(end 307.670454 -392.999722)
		(width 0.254)
		(layer "F.Cu")
		(net "GND")
	)
	(segment
		(start 125.970538 -384.617722)
		(end 126.562358 -384.617722)
		(width 0.254)
		(layer "F.Cu")
		(net "GND")
	)
	(segment
		(start 273.092164 -200.735184)
		(end 274.476464 -200.735184)
		(width 0.4572)
		(layer "F.Cu")
		(net "GND")
	)
	(segment
		(start 164.427916 -315.485272)
		(end 165.812216 -315.485272)
		(width 0.4572)
		(layer "F.Cu")
		(net "GND")
	)
	(segment
		(start 179.639722 -31.482284)
		(end 179.639722 -31.209488)
		(width 0.254)
		(layer "F.Cu")
		(net "GND")
	)
	(segment
		(start 136.517888 -293.260272)
		(end 136.98474 -293.52621)
		(width 0.350012)
		(layer "F.Cu")
		(net "GND")
	)
	(segment
		(start 109.431074 -224.234502)
		(end 109.897926 -224.50044)
		(width 0.350012)
		(layer "F.Cu")
		(net "GND")
	)
	(segment
		(start 396.648178 -12.37488)
		(end 396.648178 -12.374118)
		(width 0.3556)
		(layer "F.Cu")
		(net "GND")
	)
	(segment
		(start 352.497898 -285.160212)
		(end 352.031046 -285.42615)
		(width 0.350012)
		(layer "F.Cu")
		(net "GND")
	)
	(segment
		(start 397.307308 -56.9595)
		(end 395.32687 -56.9595)
		(width 0.4572)
		(layer "F.Cu")
		(net "GND")
	)
	(segment
		(start 101.555296 -422.83253)
		(end 101.555296 -423.44848)
		(width 0.381)
		(layer "F.Cu")
		(net "GND")
	)
	(segment
		(start 178.82108 -31.140908)
		(end 178.852576 -31.140908)
		(width 0.254)
		(layer "F.Cu")
		(net "GND")
	)
	(segment
		(start 366.767872 -223.69018)
		(end 367.234724 -223.424242)
		(width 0.350012)
		(layer "F.Cu")
		(net "GND")
	)
	(segment
		(start 435.000146 -240.685066)
		(end 436.384446 -240.685066)
		(width 0.4572)
		(layer "F.Cu")
		(net "GND")
	)
	(segment
		(start 115.367816 -268.15034)
		(end 115.834668 -268.416278)
		(width 0.350012)
		(layer "F.Cu")
		(net "GND")
	)
	(segment
		(start 123.21794 -382.951482)
		(end 123.316492 -382.85293)
		(width 0.254)
		(layer "F.Cu")
		(net "GND")
	)
	(segment
		(start 402.145754 -391.784586)
		(end 402.145754 -392.004296)
		(width 0.254)
		(layer "F.Cu")
		(net "GND")
	)
	(segment
		(start 70.861936 -7.217156)
		(end 70.860666 -7.215886)
		(width 0.3556)
		(layer "F.Cu")
		(net "GND")
	)
	(segment
		(start 9.277096 -100.417884)
		(end 9.277096 -101.095302)
		(width 0.3556)
		(layer "F.Cu")
		(net "GND")
	)
	(segment
		(start 387.748018 -273.010122)
		(end 388.21487 -273.27606)
		(width 0.350012)
		(layer "F.Cu")
		(net "GND")
	)
	(segment
		(start 372.321328 -136.608058)
		(end 372.321328 -135.97382)
		(width 0.4572)
		(layer "F.Cu")
		(net "GND")
	)
	(segment
		(start 347.968062 -233.409998)
		(end 347.50121 -233.14406)
		(width 0.350012)
		(layer "F.Cu")
		(net "GND")
	)
	(segment
		(start 361.128056 -223.69018)
		(end 361.594908 -223.424242)
		(width 0.350012)
		(layer "F.Cu")
		(net "GND")
	)
	(segment
		(start 339.943948 -400.212814)
		(end 339.943948 -399.76171)
		(width 0.254)
		(layer "F.Cu")
		(net "GND")
	)
	(segment
		(start 373.817896 -256.900172)
		(end 374.284748 -256.634234)
		(width 0.350012)
		(layer "F.Cu")
		(net "GND")
	)
	(segment
		(start 92.371926 -337.357212)
		(end 92.371926 -337.107276)
		(width 0.2286)
		(layer "F.Cu")
		(net "GND")
	)
	(segment
		(start 375.057924 -278.680164)
		(end 375.524776 -278.946102)
		(width 0.350012)
		(layer "F.Cu")
		(net "GND")
	)
	(segment
		(start 356.25786 -280.300176)
		(end 355.791008 -280.566114)
		(width 0.350012)
		(layer "F.Cu")
		(net "GND")
	)
	(segment
		(start 303.53 -360.426)
		(end 303.276 -360.172)
		(width 0.381)
		(layer "F.Cu")
		(net "GND")
	)
	(segment
		(start 102.847902 -233.410252)
		(end 102.38105 -233.144314)
		(width 0.350012)
		(layer "F.Cu")
		(net "GND")
	)
	(segment
		(start 326.81799 -252.040136)
		(end 326.351138 -251.774198)
		(width 0.350012)
		(layer "F.Cu")
		(net "GND")
	)
	(segment
		(start 81.445862 -383.622296)
		(end 81.745836 -383.92227)
		(width 0.254)
		(layer "F.Cu")
		(net "GND")
	)
	(segment
		(start 64.870584 -384.617722)
		(end 65.462404 -384.617722)
		(width 0.254)
		(layer "F.Cu")
		(net "GND")
	)
	(segment
		(start 341.144098 -399.76171)
		(end 341.144098 -400.212814)
		(width 0.254)
		(layer "F.Cu")
		(net "GND")
	)
	(segment
		(start 79.177896 -286.780478)
		(end 78.711044 -287.046162)
		(width 0.350012)
		(layer "F.Cu")
		(net "GND")
	)
	(segment
		(start 87.3379 -224.50044)
		(end 86.871048 -224.234502)
		(width 0.350012)
		(layer "F.Cu")
		(net "GND")
	)
	(segment
		(start 57.06237 -384.617722)
		(end 56.47055 -384.617722)
		(width 0.254)
		(layer "F.Cu")
		(net "GND")
	)
	(segment
		(start 332.28788 -276.250146)
		(end 331.821028 -276.516084)
		(width 0.350012)
		(layer "F.Cu")
		(net "GND")
	)
	(segment
		(start 123.84786 -26.916126)
		(end 123.30176 -26.916126)
		(width 0.3556)
		(layer "F.Cu")
		(net "GND")
	)
	(segment
		(start 416.555682 -7.215124)
		(end 416.555682 -7.215886)
		(width 0.3556)
		(layer "F.Cu")
		(net "GND")
	)
	(segment
		(start 355.362002 -394.113004)
		(end 355.111304 -394.831062)
		(width 0.254)
		(layer "F.Cu")
		(net "GND")
	)
	(segment
		(start 392.61796 -224.500186)
		(end 393.084812 -224.234248)
		(width 0.350012)
		(layer "F.Cu")
		(net "GND")
	)
	(segment
		(start 205.089506 -340.553548)
		(end 205.089506 -341.010748)
		(width 0.4572)
		(layer "F.Cu")
		(net "GND")
	)
	(segment
		(start 17.422368 -106.735372)
		(end 17.658842 -106.498898)
		(width 0.3556)
		(layer "F.Cu")
		(net "GND")
	)
	(segment
		(start 339.03793 -224.500186)
		(end 338.571078 -224.234248)
		(width 0.350012)
		(layer "F.Cu")
		(net "GND")
	)
	(segment
		(start 31.147004 -12.372848)
		(end 31.147004 -11.26998)
		(width 0.3556)
		(layer "F.Cu")
		(net "GND")
	)
	(segment
		(start 93.91777 -250.420378)
		(end 93.450918 -250.15444)
		(width 0.350012)
		(layer "F.Cu")
		(net "GND")
	)
	(segment
		(start 121.007886 -281.110436)
		(end 121.474738 -281.376374)
		(width 0.350012)
		(layer "F.Cu")
		(net "GND")
	)
	(segment
		(start 375.057924 -283.5402)
		(end 375.524776 -283.806138)
		(width 0.350012)
		(layer "F.Cu")
		(net "GND")
	)
	(segment
		(start 144.677892 -226.120452)
		(end 145.144744 -225.854514)
		(width 0.350012)
		(layer "F.Cu")
		(net "GND")
	)
	(segment
		(start 105.66781 -235.030264)
		(end 105.200958 -234.764326)
		(width 0.350012)
		(layer "F.Cu")
		(net "GND")
	)
	(segment
		(start 343.981278 -171.64431)
		(end 343.68359 -171.346622)
		(width 0.254)
		(layer "F.Cu")
		(net "GND")
	)
	(segment
		(start 131.517898 -250.420378)
		(end 131.98475 -250.15444)
		(width 0.350012)
		(layer "F.Cu")
		(net "GND")
	)
	(segment
		(start 183.616092 -284.035246)
		(end 182.231792 -284.035246)
		(width 0.4572)
		(layer "F.Cu")
		(net "GND")
	)
	(segment
		(start 22.145752 -7.215124)
		(end 22.145752 -7.215886)
		(width 0.3556)
		(layer "F.Cu")
		(net "GND")
	)
	(segment
		(start 102.87 -426.86605)
		(end 102.87 -427.609)
		(width 0.381)
		(layer "F.Cu")
		(net "GND")
	)
	(segment
		(start 95.506286 -386.449062)
		(end 96.198436 -386.6388)
		(width 0.254)
		(layer "F.Cu")
		(net "GND")
	)
	(segment
		(start 129.938018 -281.920442)
		(end 130.40487 -282.18638)
		(width 0.350012)
		(layer "F.Cu")
		(net "GND")
	)
	(segment
		(start 55.328058 -212.635338)
		(end 56.712358 -212.635338)
		(width 0.4572)
		(layer "F.Cu")
		(net "GND")
	)
	(segment
		(start 350.78797 -228.550216)
		(end 350.321118 -228.284278)
		(width 0.350012)
		(layer "F.Cu")
		(net "GND")
	)
	(segment
		(start 182.710836 -91.701112)
		(end 182.753 -91.658948)
		(width 0.4572)
		(layer "F.Cu")
		(net "GND")
	)
	(segment
		(start 394.327888 -271.39011)
		(end 394.982954 -271.39011)
		(width 0.350012)
		(layer "F.Cu")
		(net "GND")
	)
	(segment
		(start 12.987782 -415.663634)
		(end 12.987782 -416.762184)
		(width 0.4572)
		(layer "F.Cu")
		(net "GND")
	)
	(segment
		(start 98.617786 -237.460282)
		(end 98.150934 -237.194344)
		(width 0.350012)
		(layer "F.Cu")
		(net "GND")
	)
	(segment
		(start 348.24543 -391.333482)
		(end 348.343982 -391.23493)
		(width 0.254)
		(layer "F.Cu")
		(net "GND")
	)
	(segment
		(start 265.54811 -275.535136)
		(end 266.93241 -275.535136)
		(width 0.4572)
		(layer "F.Cu")
		(net "GND")
	)
	(segment
		(start 80.58785 -279.490424)
		(end 80.120998 -279.756362)
		(width 0.350012)
		(layer "F.Cu")
		(net "GND")
	)
	(segment
		(start 79.14894 -386.030978)
		(end 79.14894 -386.630926)
		(width 0.254)
		(layer "F.Cu")
		(net "GND")
	)
	(segment
		(start 38.45687 -10.16635)
		(end 38.4556 -10.16508)
		(width 0.3556)
		(layer "F.Cu")
		(net "GND")
	)
	(segment
		(start 61.270642 -390.160002)
		(end 61.791342 -390.160002)
		(width 0.254)
		(layer "F.Cu")
		(net "GND")
	)
	(segment
		(start 325.408036 -243.13007)
		(end 324.75297 -243.13007)
		(width 0.350012)
		(layer "F.Cu")
		(net "GND")
	)
	(segment
		(start 146.087846 -239.8903)
		(end 146.742912 -239.8903)
		(width 0.350012)
		(layer "F.Cu")
		(net "GND")
	)
	(segment
		(start 84.047838 -236.650276)
		(end 83.580986 -236.384338)
		(width 0.350012)
		(layer "F.Cu")
		(net "GND")
	)
	(segment
		(start 115.537996 -227.740464)
		(end 116.004848 -227.474526)
		(width 0.350012)
		(layer "F.Cu")
		(net "GND")
	)
	(segment
		(start 439.100214 -202.434952)
		(end 437.715914 -202.434952)
		(width 0.4572)
		(layer "F.Cu")
		(net "GND")
	)
	(segment
		(start 137.457942 -268.960346)
		(end 137.924794 -269.226284)
		(width 0.350012)
		(layer "F.Cu")
		(net "GND")
	)
	(segment
		(start 97.677986 -224.50044)
		(end 97.211134 -224.234502)
		(width 0.350012)
		(layer "F.Cu")
		(net "GND")
	)
	(segment
		(start 334.167988 -295.690036)
		(end 333.701136 -295.955974)
		(width 0.350012)
		(layer "F.Cu")
		(net "GND")
	)
	(segment
		(start 120.740932 -14.00429)
		(end 121.653046 -14.00429)
		(width 0.4572)
		(layer "F.Cu")
		(net "GND")
	)
	(segment
		(start 95.84563 -382.951482)
		(end 95.944182 -382.85293)
		(width 0.254)
		(layer "F.Cu")
		(net "GND")
	)
	(segment
		(start 81.058004 -283.540454)
		(end 80.591152 -283.806392)
		(width 0.350012)
		(layer "F.Cu")
		(net "GND")
	)
	(segment
		(start 101.50475 -122.705876)
		(end 101.50475 -121.696226)
		(width 0.3048)
		(layer "F.Cu")
		(net "GND")
	)
	(segment
		(start 131.817872 -286.780478)
		(end 132.284724 -287.046162)
		(width 0.350012)
		(layer "F.Cu")
		(net "GND")
	)
	(segment
		(start 376.467878 -294.070024)
		(end 376.93473 -294.335962)
		(width 0.350012)
		(layer "F.Cu")
		(net "GND")
	)
	(segment
		(start 364.247938 -294.070024)
		(end 364.71479 -294.335962)
		(width 0.350012)
		(layer "F.Cu")
		(net "GND")
	)
	(segment
		(start 183.860694 -13.598652)
		(end 183.860694 -12.817348)
		(width 0.3556)
		(layer "F.Cu")
		(net "GND")
	)
	(segment
		(start 202.147932 -303.585372)
		(end 203.532232 -303.585372)
		(width 0.4572)
		(layer "F.Cu")
		(net "GND")
	)
	(segment
		(start 84.832952 -150.807166)
		(end 84.832952 -150.020782)
		(width 0.4064)
		(layer "F.Cu")
		(net "GND")
	)
	(segment
		(start 93.747844 -281.110436)
		(end 93.280992 -281.376374)
		(width 0.350012)
		(layer "F.Cu")
		(net "GND")
	)
	(segment
		(start 327.117964 -265.720068)
		(end 326.651112 -265.986006)
		(width 0.350012)
		(layer "F.Cu")
		(net "GND")
	)
	(segment
		(start 340.277958 -288.399982)
		(end 339.811106 -288.66592)
		(width 0.350012)
		(layer "F.Cu")
		(net "GND")
	)
	(segment
		(start 202.147932 -306.135278)
		(end 203.532232 -306.135278)
		(width 0.4572)
		(layer "F.Cu")
		(net "GND")
	)
	(segment
		(start 368.947954 -287.59023)
		(end 369.414806 -287.856168)
		(width 0.350012)
		(layer "F.Cu")
		(net "GND")
	)
	(segment
		(start 442.5442 -231.335072)
		(end 443.9285 -231.335072)
		(width 0.4572)
		(layer "F.Cu")
		(net "GND")
	)
	(segment
		(start 115.367816 -271.390364)
		(end 115.834668 -271.656302)
		(width 0.350012)
		(layer "F.Cu")
		(net "GND")
	)
	(segment
		(start 17.608042 -312.935366)
		(end 18.992342 -312.935366)
		(width 0.4572)
		(layer "F.Cu")
		(net "GND")
	)
	(segment
		(start 102.677976 -264.10031)
		(end 102.211124 -264.366248)
		(width 0.350012)
		(layer "F.Cu")
		(net "GND")
	)
	(segment
		(start 383.771902 -177.48631)
		(end 384.141218 -177.48631)
		(width 0.381)
		(layer "F.Cu")
		(net "GND")
	)
	(segment
		(start 278.254206 -430.791366)
		(end 277.61692 -430.791366)
		(width 0.381)
		(layer "F.Cu")
		(net "GND")
	)
	(segment
		(start 369.417854 -288.399982)
		(end 369.884706 -288.66592)
		(width 0.350012)
		(layer "F.Cu")
		(net "GND")
	)
	(segment
		(start 17.608042 -296.785284)
		(end 18.992342 -296.785284)
		(width 0.4572)
		(layer "F.Cu")
		(net "GND")
	)
	(segment
		(start 357.837994 -224.500186)
		(end 357.371142 -224.234248)
		(width 0.350012)
		(layer "F.Cu")
		(net "GND")
	)
	(segment
		(start 350.809306 -158.737808)
		(end 350.809306 -159.061404)
		(width 0.2286)
		(layer "F.Cu")
		(net "GND")
	)
	(segment
		(start 126.817882 -245.560342)
		(end 127.284734 -245.294404)
		(width 0.350012)
		(layer "F.Cu")
		(net "GND")
	)
	(segment
		(start 405.844248 -399.76171)
		(end 405.745696 -399.663158)
		(width 0.254)
		(layer "F.Cu")
		(net "GND")
	)
	(segment
		(start 255.693926 -52.38242)
		(end 255.261618 -52.38242)
		(width 0.254)
		(layer "F.Cu")
		(net "GND")
	)
	(segment
		(start 95.627952 -273.010376)
		(end 95.1611 -273.276314)
		(width 0.350012)
		(layer "F.Cu")
		(net "GND")
	)
	(segment
		(start 55.328058 -200.735438)
		(end 56.712358 -200.735438)
		(width 0.4572)
		(layer "F.Cu")
		(net "GND")
	)
	(segment
		(start 350.31807 -227.74021)
		(end 349.851218 -227.474272)
		(width 0.350012)
		(layer "F.Cu")
		(net "GND")
	)
	(segment
		(start 354.547932 -222.070168)
		(end 354.08108 -221.80423)
		(width 0.350012)
		(layer "F.Cu")
		(net "GND")
	)
	(segment
		(start 371.938042 -230.97998)
		(end 372.404894 -230.714042)
		(width 0.350012)
		(layer "F.Cu")
		(net "GND")
	)
	(segment
		(start 333.39786 -237.460028)
		(end 332.931008 -237.19409)
		(width 0.350012)
		(layer "F.Cu")
		(net "GND")
	)
	(segment
		(start 91.770454 -338.094574)
		(end 91.801442 -338.094574)
		(width 0.2286)
		(layer "F.Cu")
		(net "GND")
	)
	(segment
		(start 146.776186 -54.513734)
		(end 146.776186 -53.897784)
		(width 0.4572)
		(layer "F.Cu")
		(net "GND")
	)
	(segment
		(start 327.117964 -270.580104)
		(end 326.651112 -270.846042)
		(width 0.350012)
		(layer "F.Cu")
		(net "GND")
	)
	(segment
		(start 120.79605 -432.054)
		(end 121.539 -432.054)
		(width 0.381)
		(layer "F.Cu")
		(net "GND")
	)
	(segment
		(start 144.677892 -255.280414)
		(end 145.144744 -255.014476)
		(width 0.350012)
		(layer "F.Cu")
		(net "GND")
	)
	(segment
		(start 80.58785 -285.970472)
		(end 80.120998 -286.23641)
		(width 0.350012)
		(layer "F.Cu")
		(net "GND")
	)
	(segment
		(start 121.007886 -266.530328)
		(end 121.474738 -266.796266)
		(width 0.350012)
		(layer "F.Cu")
		(net "GND")
	)
	(segment
		(start 376.467878 -273.010122)
		(end 376.93473 -273.27606)
		(width 0.350012)
		(layer "F.Cu")
		(net "GND")
	)
	(segment
		(start 54.662324 -384.617722)
		(end 54.070504 -384.617722)
		(width 0.254)
		(layer "F.Cu")
		(net "GND")
	)
	(segment
		(start 123.997974 -229.360476)
		(end 124.464826 -229.094538)
		(width 0.350012)
		(layer "F.Cu")
		(net "GND")
	)
	(segment
		(start 138.604244 -30.6578)
		(end 138.7856 -30.6578)
		(width 0.381)
		(layer "F.Cu")
		(net "GND")
	)
	(segment
		(start 11.512042 -51.364896)
		(end 11.51636 -51.369214)
		(width 0.4572)
		(layer "F.Cu")
		(net "GND")
	)
	(segment
		(start 93.747844 -261.670292)
		(end 93.280992 -261.93623)
		(width 0.350012)
		(layer "F.Cu")
		(net "GND")
	)
	(segment
		(start 391.03808 -262.480044)
		(end 391.504678 -262.745982)
		(width 0.350012)
		(layer "F.Cu")
		(net "GND")
	)
	(segment
		(start 351.845372 -391.784586)
		(end 351.845372 -391.333482)
		(width 0.254)
		(layer "F.Cu")
		(net "GND")
	)
	(segment
		(start 191.160146 -286.585406)
		(end 189.775846 -286.585406)
		(width 0.4572)
		(layer "F.Cu")
		(net "GND")
	)
	(segment
		(start 392.836908 -395.466062)
		(end 393.365736 -395.466062)
		(width 0.381)
		(layer "F.Cu")
		(net "GND")
	)
	(segment
		(start 44.340018 -211.7852)
		(end 42.955718 -211.7852)
		(width 0.4572)
		(layer "F.Cu")
		(net "GND")
	)
	(segment
		(start 373.817896 -243.940076)
		(end 374.284748 -243.674138)
		(width 0.350012)
		(layer "F.Cu")
		(net "GND")
	)
	(segment
		(start 96.198436 -384.617722)
		(end 96.145858 -383.92227)
		(width 0.254)
		(layer "F.Cu")
		(net "GND")
	)
	(segment
		(start 154.545792 -391.281158)
		(end 154.845766 -390.761474)
		(width 0.254)
		(layer "F.Cu")
		(net "GND")
	)
	(segment
		(start 13.257784 -388.205726)
		(end 13.613384 -388.561326)
		(width 0.2032)
		(layer "F.Cu")
		(net "GND")
	)
	(segment
		(start 141.687804 -289.210242)
		(end 142.154656 -289.47618)
		(width 0.350012)
		(layer "F.Cu")
		(net "GND")
	)
	(segment
		(start 133.227826 -274.630388)
		(end 133.694678 -274.896326)
		(width 0.350012)
		(layer "F.Cu")
		(net "GND")
	)
	(segment
		(start 343.268046 -249.610118)
		(end 342.801194 -249.34418)
		(width 0.350012)
		(layer "F.Cu")
		(net "GND")
	)
	(segment
		(start 85.757766 -270.580358)
		(end 85.290914 -270.846296)
		(width 0.350012)
		(layer "F.Cu")
		(net "GND")
	)
	(segment
		(start 350.875346 -158.57855)
		(end 350.809306 -158.737808)
		(width 0.2286)
		(layer "F.Cu")
		(net "GND")
	)
	(segment
		(start 306.417726 -392.30427)
		(end 306.470304 -392.999722)
		(width 0.254)
		(layer "F.Cu")
		(net "GND")
	)
	(segment
		(start 403.848062 -12.374118)
		(end 403.846792 -12.372848)
		(width 0.3556)
		(layer "F.Cu")
		(net "GND")
	)
	(segment
		(start 114.109246 -386.030978)
		(end 113.721134 -386.030978)
		(width 0.254)
		(layer "F.Cu")
		(net "GND")
	)
	(segment
		(start 100.027994 -236.650276)
		(end 99.561142 -236.384338)
		(width 0.350012)
		(layer "F.Cu")
		(net "GND")
	)
	(segment
		(start 159.444182 -391.830814)
		(end 159.444182 -391.37971)
		(width 0.254)
		(layer "F.Cu")
		(net "GND")
	)
	(segment
		(start 373.17807 -288.399982)
		(end 373.644922 -288.66592)
		(width 0.350012)
		(layer "F.Cu")
		(net "GND")
	)
	(segment
		(start 102.154736 -128.803654)
		(end 102.154736 -128.187704)
		(width 0.4064)
		(layer "F.Cu")
		(net "GND")
	)
	(segment
		(start 118.162324 -384.617722)
		(end 117.570504 -384.617722)
		(width 0.254)
		(layer "F.Cu")
		(net "GND")
	)
	(segment
		(start 64.518032 -383.622296)
		(end 64.818006 -383.92227)
		(width 0.254)
		(layer "F.Cu")
		(net "GND")
	)
	(segment
		(start 14.445996 -106.506264)
		(end 14.265402 -106.32567)
		(width 0.3556)
		(layer "F.Cu")
		(net "GND")
	)
	(segment
		(start 346.087954 -222.070168)
		(end 345.621102 -221.80423)
		(width 0.350012)
		(layer "F.Cu")
		(net "GND")
	)
	(segment
		(start 207.630014 -132.27304)
		(end 207.630014 -131.557014)
		(width 0.381)
		(layer "F.Cu")
		(net "GND")
	)
	(segment
		(start 370.357908 -280.300176)
		(end 370.82476 -280.566114)
		(width 0.350012)
		(layer "F.Cu")
		(net "GND")
	)
	(segment
		(start 353.137978 -248.800112)
		(end 352.671126 -248.534174)
		(width 0.350012)
		(layer "F.Cu")
		(net "GND")
	)
	(segment
		(start 387.748018 -268.150086)
		(end 388.21487 -268.416024)
		(width 0.350012)
		(layer "F.Cu")
		(net "GND")
	)
	(segment
		(start 388.217918 -280.300176)
		(end 388.68477 -280.566114)
		(width 0.350012)
		(layer "F.Cu")
		(net "GND")
	)
	(segment
		(start 100.797868 -285.160466)
		(end 100.331016 -285.426404)
		(width 0.350012)
		(layer "F.Cu")
		(net "GND")
	)
	(segment
		(start 389.634476 -396.213076)
		(end 389.93445 -396.51305)
		(width 0.254)
		(layer "F.Cu")
		(net "GND")
	)
	(segment
		(start 86.868 -251.230384)
		(end 86.401148 -250.964446)
		(width 0.350012)
		(layer "F.Cu")
		(net "GND")
	)
	(segment
		(start 107.078018 -237.460282)
		(end 106.611166 -237.194344)
		(width 0.350012)
		(layer "F.Cu")
		(net "GND")
	)
	(segment
		(start 388.217918 -272.200116)
		(end 388.68477 -272.466054)
		(width 0.350012)
		(layer "F.Cu")
		(net "GND")
	)
	(segment
		(start 336.687922 -256.090166)
		(end 336.22107 -255.824228)
		(width 0.350012)
		(layer "F.Cu")
		(net "GND")
	)
	(segment
		(start 99.36226 -384.531108)
		(end 99.14255 -384.531108)
		(width 0.254)
		(layer "F.Cu")
		(net "GND")
	)
	(segment
		(start 381.617982 -391.784586)
		(end 381.617982 -391.333482)
		(width 0.254)
		(layer "F.Cu")
		(net "GND")
	)
	(segment
		(start 113.487962 -268.15034)
		(end 113.954814 -268.416278)
		(width 0.350012)
		(layer "F.Cu")
		(net "GND")
	)
	(segment
		(start 235.768896 -67.074288)
		(end 235.068872 -67.074288)
		(width 0.4064)
		(layer "F.Cu")
		(net "GND")
	)
	(segment
		(start 131.817872 -260.860286)
		(end 132.284724 -261.126224)
		(width 0.350012)
		(layer "F.Cu")
		(net "GND")
	)
	(segment
		(start 318.47028 -392.999722)
		(end 319.0621 -392.999722)
		(width 0.254)
		(layer "F.Cu")
		(net "GND")
	)
	(segment
		(start 381.638048 -270.580104)
		(end 382.1049 -270.846042)
		(width 0.350012)
		(layer "F.Cu")
		(net "GND")
	)
	(segment
		(start 105.497884 -270.580358)
		(end 105.031032 -270.846296)
		(width 0.350012)
		(layer "F.Cu")
		(net "GND")
	)
	(segment
		(start 424.012106 -230.485188)
		(end 422.627806 -230.485188)
		(width 0.4572)
		(layer "F.Cu")
		(net "GND")
	)
	(segment
		(start 176.072038 -230.485442)
		(end 174.687738 -230.485442)
		(width 0.4572)
		(layer "F.Cu")
		(net "GND")
	)
	(segment
		(start 309.717694 -399.663158)
		(end 310.017668 -399.143474)
		(width 0.254)
		(layer "F.Cu")
		(net "GND")
	)
	(segment
		(start 124.767848 -264.910316)
		(end 125.2347 -265.176254)
		(width 0.350012)
		(layer "F.Cu")
		(net "GND")
	)
	(segment
		(start 85.457792 -253.660402)
		(end 84.99094 -253.394464)
		(width 0.350012)
		(layer "F.Cu")
		(net "GND")
	)
	(segment
		(start 296.62882 -351.100644)
		(end 296.62882 -351.73158)
		(width 0.381)
		(layer "F.Cu")
		(net "GND")
	)
	(segment
		(start 51.884072 -239.835436)
		(end 50.499772 -239.835436)
		(width 0.4572)
		(layer "F.Cu")
		(net "GND")
	)
	(segment
		(start 72.660764 -7.215886)
		(end 72.660764 -7.215124)
		(width 0.3556)
		(layer "F.Cu")
		(net "GND")
	)
	(segment
		(start 351.845372 -399.663158)
		(end 352.1456 -399.143474)
		(width 0.254)
		(layer "F.Cu")
		(net "GND")
	)
	(segment
		(start 42.058336 -12.374118)
		(end 42.057066 -12.372848)
		(width 0.3556)
		(layer "F.Cu")
		(net "GND")
	)
	(segment
		(start 331.987906 -241.510058)
		(end 331.521054 -241.24412)
		(width 0.350012)
		(layer "F.Cu")
		(net "GND")
	)
	(segment
		(start 32.695896 -294.235378)
		(end 34.080196 -294.235378)
		(width 0.4572)
		(layer "F.Cu")
		(net "GND")
	)
	(segment
		(start 389.93445 -396.51305)
		(end 389.634476 -396.813024)
		(width 0.254)
		(layer "F.Cu")
		(net "GND")
	)
	(segment
		(start 102.207822 -263.290304)
		(end 101.74097 -263.556242)
		(width 0.350012)
		(layer "F.Cu")
		(net "GND")
	)
	(segment
		(start 334.808068 -238.270034)
		(end 334.341216 -238.004096)
		(width 0.350012)
		(layer "F.Cu")
		(net "GND")
	)
	(segment
		(start 369.417854 -268.960092)
		(end 369.884706 -269.22603)
		(width 0.350012)
		(layer "F.Cu")
		(net "GND")
	)
	(segment
		(start 410.21889 -398.542002)
		(end 409.69819 -398.542002)
		(width 0.254)
		(layer "F.Cu")
		(net "GND")
	)
	(segment
		(start 273.092164 -287.435036)
		(end 274.476464 -287.435036)
		(width 0.4572)
		(layer "F.Cu")
		(net "GND")
	)
	(segment
		(start 420.682166 -175.938688)
		(end 419.597586 -175.938688)
		(width 0.254)
		(layer "F.Cu")
		(net "GND")
	)
	(segment
		(start 355.957886 -252.040136)
		(end 355.491034 -251.774198)
		(width 0.350012)
		(layer "F.Cu")
		(net "GND")
	)
	(segment
		(start 111.137954 -283.540454)
		(end 110.671102 -283.806392)
		(width 0.350012)
		(layer "F.Cu")
		(net "GND")
	)
	(segment
		(start 332.92796 -222.070168)
		(end 332.461108 -221.80423)
		(width 0.350012)
		(layer "F.Cu")
		(net "GND")
	)
	(segment
		(start 369.72113 -393.24915)
		(end 369.970558 -392.999722)
		(width 0.254)
		(layer "F.Cu")
		(net "GND")
	)
	(segment
		(start 381.338074 -229.360222)
		(end 381.804926 -229.094284)
		(width 0.350012)
		(layer "F.Cu")
		(net "GND")
	)
	(segment
		(start 363.307884 -279.49017)
		(end 363.774736 -279.756108)
		(width 0.350012)
		(layer "F.Cu")
		(net "GND")
	)
	(segment
		(start 93.54439 -391.37971)
		(end 93.445838 -391.281158)
		(width 0.254)
		(layer "F.Cu")
		(net "GND")
	)
	(segment
		(start 302.620934 -396.712948)
		(end 302.301402 -396.712948)
		(width 0.254)
		(layer "F.Cu")
		(net "GND")
	)
	(segment
		(start 348.268036 -277.870158)
		(end 347.801184 -278.136096)
		(width 0.350012)
		(layer "F.Cu")
		(net "GND")
	)
	(segment
		(start 391.208006 -238.270034)
		(end 391.674858 -238.004096)
		(width 0.350012)
		(layer "F.Cu")
		(net "GND")
	)
	(segment
		(start 344.99804 -395.0208)
		(end 344.306144 -394.831062)
		(width 0.254)
		(layer "F.Cu")
		(net "GND")
	)
	(segment
		(start 347.327982 -294.070024)
		(end 346.86113 -294.335962)
		(width 0.350012)
		(layer "F.Cu")
		(net "GND")
	)
	(segment
		(start 108.487972 -246.370348)
		(end 108.02112 -246.10441)
		(width 0.350012)
		(layer "F.Cu")
		(net "GND")
	)
	(segment
		(start 187.522104 -116.252752)
		(end 187.911994 -116.642642)
		(width 0.254)
		(layer "F.Cu")
		(net "GND")
	)
	(segment
		(start 186.722004 -113.05286)
		(end 187.111894 -112.66297)
		(width 0.254)
		(layer "F.Cu")
		(net "GND")
	)
	(segment
		(start 372.194328 -176.59731)
		(end 372.683278 -176.59731)
		(width 0.381)
		(layer "F.Cu")
		(net "GND")
	)
	(segment
		(start 381.338074 -252.040136)
		(end 381.804926 -251.774198)
		(width 0.350012)
		(layer "F.Cu")
		(net "GND")
	)
	(segment
		(start 355.31806 -277.060152)
		(end 354.851208 -277.32609)
		(width 0.350012)
		(layer "F.Cu")
		(net "GND")
	)
	(segment
		(start 131.716526 -391.37971)
		(end 131.617974 -391.281158)
		(width 0.254)
		(layer "F.Cu")
		(net "GND")
	)
	(segment
		(start 123.570492 -390.160002)
		(end 122.891296 -390.160002)
		(width 0.254)
		(layer "F.Cu")
		(net "GND")
	)
	(segment
		(start 353.144074 -400.212814)
		(end 353.144074 -399.76171)
		(width 0.254)
		(layer "F.Cu")
		(net "GND")
	)
	(segment
		(start 50.48504 -435.61)
		(end 51.188874 -435.61)
		(width 0.381)
		(layer "F.Cu")
		(net "GND")
	)
	(segment
		(start 77.767942 -271.390364)
		(end 77.112876 -271.390364)
		(width 0.350012)
		(layer "F.Cu")
		(net "GND")
	)
	(segment
		(start 341.857838 -229.360222)
		(end 341.390986 -229.094284)
		(width 0.350012)
		(layer "F.Cu")
		(net "GND")
	)
	(segment
		(start 346.087954 -252.850142)
		(end 345.621102 -252.584204)
		(width 0.350012)
		(layer "F.Cu")
		(net "GND")
	)
	(segment
		(start 305.791108 -398.542002)
		(end 305.270408 -398.542002)
		(width 0.254)
		(layer "F.Cu")
		(net "GND")
	)
	(segment
		(start 109.427772 -244.750336)
		(end 108.961174 -244.484398)
		(width 0.350012)
		(layer "F.Cu")
		(net "GND")
	)
	(segment
		(start 187.51042 -355.705156)
		(end 187.51042 -356.336092)
		(width 0.381)
		(layer "F.Cu")
		(net "GND")
	)
	(segment
		(start 124.297948 -285.160466)
		(end 124.7648 -285.426404)
		(width 0.350012)
		(layer "F.Cu")
		(net "GND")
	)
	(segment
		(start 83.577938 -239.080294)
		(end 83.111086 -238.814356)
		(width 0.350012)
		(layer "F.Cu")
		(net "GND")
	)
	(segment
		(start 372.877842 -240.700052)
		(end 373.344694 -240.434114)
		(width 0.350012)
		(layer "F.Cu")
		(net "GND")
	)
	(segment
		(start 58.518044 -382.951482)
		(end 58.616596 -382.85293)
		(width 0.254)
		(layer "F.Cu")
		(net "GND")
	)
	(segment
		(start 412.94558 -391.333482)
		(end 413.044132 -391.23493)
		(width 0.254)
		(layer "F.Cu")
		(net "GND")
	)
	(segment
		(start 123.357894 -280.30043)
		(end 123.824746 -280.566368)
		(width 0.350012)
		(layer "F.Cu")
		(net "GND")
	)
	(segment
		(start 184.070244 -409.281122)
		(end 183.610504 -409.281122)
		(width 0.3556)
		(layer "F.Cu")
		(net "GND")
	)
	(segment
		(start 84.347812 -261.670292)
		(end 83.88096 -261.93623)
		(width 0.350012)
		(layer "F.Cu")
		(net "GND")
	)
	(segment
		(start 454.705466 -403.473412)
		(end 454.502266 -403.473412)
		(width 0.4572)
		(layer "F.Cu")
		(net "GND")
	)
	(segment
		(start 371.297962 -280.300176)
		(end 371.764814 -280.566114)
		(width 0.350012)
		(layer "F.Cu")
		(net "GND")
	)
	(segment
		(start 314.262262 -392.999722)
		(end 313.670442 -392.999722)
		(width 0.254)
		(layer "F.Cu")
		(net "GND")
	)
	(segment
		(start 127.617982 -162.127184)
		(end 127.145034 -162.600132)
		(width 0.2286)
		(layer "F.Cu")
		(net "GND")
	)
	(segment
		(start 118.357904 -232.600246)
		(end 118.824756 -232.334308)
		(width 0.350012)
		(layer "F.Cu")
		(net "GND")
	)
	(segment
		(start 128.227836 -251.230384)
		(end 128.694688 -250.964446)
		(width 0.350012)
		(layer "F.Cu")
		(net "GND")
	)
	(segment
		(start 37.681662 -418.239448)
		(end 37.681662 -418.849048)
		(width 0.3556)
		(layer "F.Cu")
		(net "GND")
	)
	(segment
		(start 99.857814 -293.260272)
		(end 99.390962 -293.52621)
		(width 0.350012)
		(layer "F.Cu")
		(net "GND")
	)
	(segment
		(start 120.537986 -285.160466)
		(end 121.004838 -285.426404)
		(width 0.350012)
		(layer "F.Cu")
		(net "GND")
	)
	(segment
		(start 418.356796 -9.423654)
		(end 418.358066 -9.424924)
		(width 0.3556)
		(layer "F.Cu")
		(net "GND")
	)
	(segment
		(start 85.457792 -227.740464)
		(end 84.99094 -227.474526)
		(width 0.350012)
		(layer "F.Cu")
		(net "GND")
	)
	(segment
		(start 56.868314 -12.37488)
		(end 56.868314 -12.374118)
		(width 0.3556)
		(layer "F.Cu")
		(net "GND")
	)
	(segment
		(start 196.308218 -79.123794)
		(end 196.308218 -78.42377)
		(width 0.3556)
		(layer "F.Cu")
		(net "GND")
	)
	(segment
		(start 162.606228 -386.449062)
		(end 162.098228 -386.6388)
		(width 0.254)
		(layer "F.Cu")
		(net "GND")
	)
	(segment
		(start 435.000146 -278.085042)
		(end 436.384446 -278.085042)
		(width 0.4572)
		(layer "F.Cu")
		(net "GND")
	)
	(segment
		(start 454.188068 -202.434952)
		(end 452.803768 -202.434952)
		(width 0.4572)
		(layer "F.Cu")
		(net "GND")
	)
	(segment
		(start 402.498306 -396.46352)
		(end 402.248878 -396.712948)
		(width 0.254)
		(layer "F.Cu")
		(net "GND")
	)
	(segment
		(start 98.918014 -264.10031)
		(end 98.451162 -264.366248)
		(width 0.350012)
		(layer "F.Cu")
		(net "GND")
	)
	(segment
		(start 163.806378 -386.449062)
		(end 163.298378 -386.6388)
		(width 0.254)
		(layer "F.Cu")
		(net "GND")
	)
	(segment
		(start 98.44786 -266.530328)
		(end 97.981008 -266.796266)
		(width 0.350012)
		(layer "F.Cu")
		(net "GND")
	)
	(segment
		(start 370.357908 -291.640006)
		(end 370.82476 -291.905944)
		(width 0.350012)
		(layer "F.Cu")
		(net "GND")
	)
	(segment
		(start 389.627872 -263.29005)
		(end 390.094724 -263.555988)
		(width 0.350012)
		(layer "F.Cu")
		(net "GND")
	)
	(segment
		(start 363.307884 -281.110182)
		(end 363.774736 -281.37612)
		(width 0.350012)
		(layer "F.Cu")
		(net "GND")
	)
	(segment
		(start 384.760978 -179.678584)
		(end 384.72999 -179.678584)
		(width 0.2286)
		(layer "F.Cu")
		(net "GND")
	)
	(segment
		(start 329.477878 -137.575036)
		(end 329.446128 -137.575036)
		(width 0.381)
		(layer "F.Cu")
		(net "GND")
	)
	(segment
		(start 141.687804 -277.870412)
		(end 142.154656 -278.13635)
		(width 0.350012)
		(layer "F.Cu")
		(net "GND")
	)
	(segment
		(start 331.518006 -253.660148)
		(end 331.051154 -253.39421)
		(width 0.350012)
		(layer "F.Cu")
		(net "GND")
	)
	(segment
		(start 124.767848 -294.070278)
		(end 125.2347 -294.336216)
		(width 0.350012)
		(layer "F.Cu")
		(net "GND")
	)
	(segment
		(start 378.048012 -252.850142)
		(end 378.514864 -252.584204)
		(width 0.350012)
		(layer "F.Cu")
		(net "GND")
	)
	(segment
		(start 331.518006 -248.800112)
		(end 331.051154 -248.534174)
		(width 0.350012)
		(layer "F.Cu")
		(net "GND")
	)
	(segment
		(start 131.347972 -268.15034)
		(end 131.814824 -268.416278)
		(width 0.350012)
		(layer "F.Cu")
		(net "GND")
	)
	(segment
		(start 109.136942 -19.58975)
		(end 109.347 -19.379692)
		(width 0.381)
		(layer "F.Cu")
		(net "GND")
	)
	(segment
		(start 86.868 -233.410252)
		(end 86.401148 -233.144314)
		(width 0.350012)
		(layer "F.Cu")
		(net "GND")
	)
	(segment
		(start 380.86792 -249.610118)
		(end 381.334772 -249.34418)
		(width 0.350012)
		(layer "F.Cu")
		(net "GND")
	)
	(segment
		(start 336.987896 -284.350206)
		(end 336.521044 -284.616144)
		(width 0.350012)
		(layer "F.Cu")
		(net "GND")
	)
	(segment
		(start 351.25787 -247.1801)
		(end 350.791018 -246.914162)
		(width 0.350012)
		(layer "F.Cu")
		(net "GND")
	)
	(segment
		(start 371.297962 -288.399982)
		(end 371.764814 -288.66592)
		(width 0.350012)
		(layer "F.Cu")
		(net "GND")
	)
	(segment
		(start 187.060078 -312.935366)
		(end 188.444378 -312.935366)
		(width 0.4572)
		(layer "F.Cu")
		(net "GND")
	)
	(segment
		(start 308.87035 -398.542002)
		(end 308.191154 -398.542002)
		(width 0.254)
		(layer "F.Cu")
		(net "GND")
	)
	(segment
		(start 187.060078 -212.635338)
		(end 188.444378 -212.635338)
		(width 0.4572)
		(layer "F.Cu")
		(net "GND")
	)
	(segment
		(start 414.756854 -11.26998)
		(end 414.756854 -10.16635)
		(width 0.3556)
		(layer "F.Cu")
		(net "GND")
	)
	(segment
		(start 118.657878 -281.920442)
		(end 119.12473 -282.18638)
		(width 0.350012)
		(layer "F.Cu")
		(net "GND")
	)
	(segment
		(start 70.09257 -340.211664)
		(end 70.16242 -340.141814)
		(width 0.381)
		(layer "F.Cu")
		(net "GND")
	)
	(segment
		(start 383.17043 -396.520924)
		(end 382.618488 -396.710662)
		(width 0.254)
		(layer "F.Cu")
		(net "GND")
	)
	(segment
		(start 357.668068 -279.49017)
		(end 357.201216 -279.756108)
		(width 0.350012)
		(layer "F.Cu")
		(net "GND")
	)
	(segment
		(start 336.598006 -398.542002)
		(end 335.918556 -398.542002)
		(width 0.254)
		(layer "F.Cu")
		(net "GND")
	)
	(segment
		(start 371.297962 -270.580104)
		(end 371.764814 -270.846042)
		(width 0.350012)
		(layer "F.Cu")
		(net "GND")
	)
	(segment
		(start 136.987788 -276.2504)
		(end 137.45464 -276.516338)
		(width 0.350012)
		(layer "F.Cu")
		(net "GND")
	)
	(segment
		(start 272.340578 -349.211138)
		(end 272.340578 -348.794324)
		(width 0.2286)
		(layer "F.Cu")
		(net "GND")
	)
	(segment
		(start 308.805834 -411.295596)
		(end 309.722774 -412.212536)
		(width 0.381)
		(layer "F.Cu")
		(net "GND")
	)
	(segment
		(start 381.638048 -277.060152)
		(end 382.1049 -277.32609)
		(width 0.350012)
		(layer "F.Cu")
		(net "GND")
	)
	(segment
		(start 82.167984 -226.930458)
		(end 81.701132 -226.66452)
		(width 0.350012)
		(layer "F.Cu")
		(net "GND")
	)
	(segment
		(start 369.91798 -399.143474)
		(end 369.618006 -399.663158)
		(width 0.254)
		(layer "F.Cu")
		(net "GND")
	)
	(segment
		(start 104.08793 -266.530328)
		(end 103.621078 -266.796266)
		(width 0.350012)
		(layer "F.Cu")
		(net "GND")
	)
	(segment
		(start 119.97055 -388.138924)
		(end 119.418354 -388.328662)
		(width 0.254)
		(layer "F.Cu")
		(net "GND")
	)
	(segment
		(start 144.677892 -234.220258)
		(end 145.144744 -233.95432)
		(width 0.350012)
		(layer "F.Cu")
		(net "GND")
	)
	(segment
		(start 368.947954 -268.150086)
		(end 369.414806 -268.416024)
		(width 0.350012)
		(layer "F.Cu")
		(net "GND")
	)
	(segment
		(start 98.918014 -294.880284)
		(end 98.451162 -295.146222)
		(width 0.350012)
		(layer "F.Cu")
		(net "GND")
	)
	(segment
		(start 63.43269 -39.381176)
		(end 63.43269 -38.784276)
		(width 0.3556)
		(layer "F.Cu")
		(net "GND")
	)
	(segment
		(start 370.997988 -237.460028)
		(end 371.46484 -237.19409)
		(width 0.350012)
		(layer "F.Cu")
		(net "GND")
	)
	(segment
		(start 115.170458 -384.617722)
		(end 115.762278 -384.617722)
		(width 0.254)
		(layer "F.Cu")
		(net "GND")
	)
	(segment
		(start 408.145742 -399.663158)
		(end 408.244294 -399.76171)
		(width 0.254)
		(layer "F.Cu")
		(net "GND")
	)
	(segment
		(start 280.635964 -275.535136)
		(end 282.020264 -275.535136)
		(width 0.4572)
		(layer "F.Cu")
		(net "GND")
	)
	(segment
		(start 129.63779 -230.980234)
		(end 130.104642 -230.71455)
		(width 0.350012)
		(layer "F.Cu")
		(net "GND")
	)
	(segment
		(start 129.63779 -226.120452)
		(end 130.104642 -225.854514)
		(width 0.350012)
		(layer "F.Cu")
		(net "GND")
	)
	(segment
		(start 344.678 -239.08004)
		(end 344.211148 -238.814102)
		(width 0.350012)
		(layer "F.Cu")
		(net "GND")
	)
	(segment
		(start 334.82915 -396.712948)
		(end 334.629252 -396.51305)
		(width 0.254)
		(layer "F.Cu")
		(net "GND")
	)
	(segment
		(start 113.487962 -269.770352)
		(end 113.954814 -270.03629)
		(width 0.350012)
		(layer "F.Cu")
		(net "GND")
	)
	(segment
		(start 341.857838 -250.420124)
		(end 341.390986 -250.154186)
		(width 0.350012)
		(layer "F.Cu")
		(net "GND")
	)
	(segment
		(start 341.398098 -395.0208)
		(end 340.705948 -394.831062)
		(width 0.254)
		(layer "F.Cu")
		(net "GND")
	)
	(segment
		(start 119.297958 -235.84027)
		(end 119.76481 -235.574332)
		(width 0.350012)
		(layer "F.Cu")
		(net "GND")
	)
	(segment
		(start 82.167984 -249.610372)
		(end 81.701132 -249.344434)
		(width 0.350012)
		(layer "F.Cu")
		(net "GND")
	)
	(segment
		(start 202.830176 -339.455252)
		(end 204.241146 -338.79409)
		(width 0.1778)
		(layer "F.Cu")
		(net "GND")
	)
	(segment
		(start 214.757 -99.172014)
		(end 213.832948 -99.172014)
		(width 0.381)
		(layer "F.Cu")
		(net "GND")
	)
	(segment
		(start 373.17807 -273.820128)
		(end 373.644922 -274.086066)
		(width 0.350012)
		(layer "F.Cu")
		(net "GND")
	)
	(segment
		(start 372.370604 -396.520924)
		(end 371.818408 -396.710662)
		(width 0.254)
		(layer "F.Cu")
		(net "GND")
	)
	(segment
		(start 58.870596 -390.160002)
		(end 59.391296 -390.160002)
		(width 0.254)
		(layer "F.Cu")
		(net "GND")
	)
	(segment
		(start 82.167984 -230.170228)
		(end 81.701132 -229.90429)
		(width 0.350012)
		(layer "F.Cu")
		(net "GND")
	)
	(segment
		(start 59.428126 -211.7852)
		(end 58.043826 -211.7852)
		(width 0.4572)
		(layer "F.Cu")
		(net "GND")
	)
	(segment
		(start 216.46896 -118.688104)
		(end 216.46896 -119.620284)
		(width 0.381)
		(layer "F.Cu")
		(net "GND")
	)
	(segment
		(start 341.387938 -251.23013)
		(end 340.921086 -250.964192)
		(width 0.350012)
		(layer "F.Cu")
		(net "GND")
	)
	(segment
		(start 64.818006 -383.92227)
		(end 64.870584 -384.617722)
		(width 0.254)
		(layer "F.Cu")
		(net "GND")
	)
	(segment
		(start 92.860622 -157.891988)
		(end 93.397578 -157.355032)
		(width 0.4572)
		(layer "F.Cu")
		(net "GND")
	)
	(segment
		(start 338.56803 -241.510058)
		(end 338.101178 -241.24412)
		(width 0.350012)
		(layer "F.Cu")
		(net "GND")
	)
	(segment
		(start 344.74404 -399.76171)
		(end 344.74404 -400.212814)
		(width 0.254)
		(layer "F.Cu")
		(net "GND")
	)
	(segment
		(start 143.267938 -231.79024)
		(end 143.73479 -231.524302)
		(width 0.350012)
		(layer "F.Cu")
		(net "GND")
	)
	(segment
		(start 49.666906 -9.423654)
		(end 49.668176 -9.424924)
		(width 0.3556)
		(layer "F.Cu")
		(net "GND")
	)
	(segment
		(start 206.248 -227.935282)
		(end 204.8637 -227.935282)
		(width 0.4572)
		(layer "F.Cu")
		(net "GND")
	)
	(segment
		(start 60.070492 -384.617722)
		(end 60.017914 -383.92227)
		(width 0.254)
		(layer "F.Cu")
		(net "GND")
	)
	(segment
		(start 384.390392 -65.141602)
		(end 384.390392 -64.504316)
		(width 0.4572)
		(layer "F.Cu")
		(net "GND")
	)
	(segment
		(start 419.912038 -212.635084)
		(end 421.296338 -212.635084)
		(width 0.4572)
		(layer "F.Cu")
		(net "GND")
	)
	(segment
		(start 126.916434 -391.37971)
		(end 126.817882 -391.281158)
		(width 0.254)
		(layer "F.Cu")
		(net "GND")
	)
	(segment
		(start 97.677986 -235.84027)
		(end 97.211134 -235.574332)
		(width 0.350012)
		(layer "F.Cu")
		(net "GND")
	)
	(segment
		(start 92.33789 -278.680418)
		(end 91.871038 -278.946356)
		(width 0.350012)
		(layer "F.Cu")
		(net "GND")
	)
	(segment
		(start 335.114646 -403.336506)
		(end 335.114646 -402.734018)
		(width 0.254)
		(layer "F.Cu")
		(net "GND")
	)
	(segment
		(start 32.695896 -287.43529)
		(end 34.080196 -287.43529)
		(width 0.4572)
		(layer "F.Cu")
		(net "GND")
	)
	(segment
		(start 344.99804 -398.542002)
		(end 344.318844 -398.542002)
		(width 0.254)
		(layer "F.Cu")
		(net "GND")
	)
	(segment
		(start 350.78797 -243.13007)
		(end 350.321118 -242.864132)
		(width 0.350012)
		(layer "F.Cu")
		(net "GND")
	)
	(segment
		(start 308.87035 -396.520924)
		(end 308.318154 -396.710662)
		(width 0.254)
		(layer "F.Cu")
		(net "GND")
	)
	(segment
		(start 365.828072 -231.789986)
		(end 366.294924 -231.524048)
		(width 0.350012)
		(layer "F.Cu")
		(net "GND")
	)
	(segment
		(start 335.148682 -394.412978)
		(end 335.148682 -393.81303)
		(width 0.254)
		(layer "F.Cu")
		(net "GND")
	)
	(segment
		(start 339.977984 -242.320064)
		(end 339.511132 -242.054126)
		(width 0.350012)
		(layer "F.Cu")
		(net "GND")
	)
	(segment
		(start 356.25786 -277.060152)
		(end 355.791008 -277.32609)
		(width 0.350012)
		(layer "F.Cu")
		(net "GND")
	)
	(segment
		(start 414.846262 -158.556198)
		(end 414.776412 -158.626048)
		(width 0.381)
		(layer "F.Cu")
		(net "GND")
	)
	(segment
		(start 161.745676 -382.951482)
		(end 161.844228 -382.85293)
		(width 0.254)
		(layer "F.Cu")
		(net "GND")
	)
	(segment
		(start 84.047838 -239.8903)
		(end 83.580986 -239.624362)
		(width 0.350012)
		(layer "F.Cu")
		(net "GND")
	)
	(segment
		(start 76.07173 -386.418074)
		(end 76.07173 -385.59359)
		(width 0.254)
		(layer "F.Cu")
		(net "GND")
	)
	(segment
		(start 89.944194 -391.830814)
		(end 89.944194 -391.37971)
		(width 0.254)
		(layer "F.Cu")
		(net "GND")
	)
	(segment
		(start 307.670454 -392.999722)
		(end 307.617876 -392.30427)
		(width 0.254)
		(layer "F.Cu")
		(net "GND")
	)
	(segment
		(start 280.635964 -203.28509)
		(end 282.020264 -203.28509)
		(width 0.4572)
		(layer "F.Cu")
		(net "GND")
	)
	(segment
		(start 310.590946 -398.542002)
		(end 310.070246 -398.542002)
		(width 0.254)
		(layer "F.Cu")
		(net "GND")
	)
	(segment
		(start 114.897916 -267.340334)
		(end 115.364768 -267.606272)
		(width 0.350012)
		(layer "F.Cu")
		(net "GND")
	)
	(segment
		(start 332.28788 -269.770098)
		(end 331.821028 -270.036036)
		(width 0.350012)
		(layer "F.Cu")
		(net "GND")
	)
	(segment
		(start 82.467958 -263.290304)
		(end 82.001106 -263.556242)
		(width 0.350012)
		(layer "F.Cu")
		(net "GND")
	)
	(segment
		(start 348.737936 -293.260018)
		(end 348.271084 -293.525956)
		(width 0.350012)
		(layer "F.Cu")
		(net "GND")
	)
	(segment
		(start 85.045804 -383.402586)
		(end 85.045804 -382.951482)
		(width 0.2032)
		(layer "F.Cu")
		(net "GND")
	)
	(segment
		(start 53.391308 -390.160002)
		(end 52.870608 -390.160002)
		(width 0.254)
		(layer "F.Cu")
		(net "GND")
	)
	(segment
		(start 356.53726 -326.69226)
		(end 357.42626 -326.69226)
		(width 0.4572)
		(layer "F.Cu")
		(net "GND")
	)
	(segment
		(start 41.8211 -391.795)
		(end 41.8211 -391.2235)
		(width 0.254)
		(layer "F.Cu")
		(net "GND")
	)
	(segment
		(start 81.544414 -391.37971)
		(end 81.445862 -391.281158)
		(width 0.254)
		(layer "F.Cu")
		(net "GND")
	)
	(segment
		(start 50.216816 -437.642)
		(end 49.5681 -437.642)
		(width 0.381)
		(layer "F.Cu")
		(net "GND")
	)
	(segment
		(start 78.877922 -242.320318)
		(end 78.41107 -242.05438)
		(width 0.350012)
		(layer "F.Cu")
		(net "GND")
	)
	(segment
		(start 334.808068 -233.409998)
		(end 334.341216 -233.14406)
		(width 0.350012)
		(layer "F.Cu")
		(net "GND")
	)
	(segment
		(start 119.362474 -384.617722)
		(end 118.770654 -384.617722)
		(width 0.254)
		(layer "F.Cu")
		(net "GND")
	)
	(segment
		(start 68.341494 -163.670996)
		(end 68.871846 -163.670996)
		(width 0.381)
		(layer "F.Cu")
		(net "GND")
	)
	(segment
		(start 46.518068 -383.402586)
		(end 46.518068 -383.622296)
		(width 0.254)
		(layer "F.Cu")
		(net "GND")
	)
	(segment
		(start 114.490246 -399.060416)
		(end 113.059972 -399.060416)
		(width 0.3302)
		(layer "F.Cu")
		(net "GND")
	)
	(segment
		(start 308.120288 -428.091346)
		(end 308.120288 -427.456346)
		(width 0.4318)
		(layer "F.Cu")
		(net "GND")
	)
	(segment
		(start 100.046282 -343.004648)
		(end 100.07727 -343.004648)
		(width 0.2286)
		(layer "F.Cu")
		(net "GND")
	)
	(segment
		(start 424.5356 -423.5069)
		(end 424.5356 -423.997882)
		(width 0.254)
		(layer "F.Cu")
		(net "GND")
	)
	(segment
		(start 157.29839 -386.6388)
		(end 156.60624 -386.449062)
		(width 0.254)
		(layer "F.Cu")
		(net "GND")
	)
	(segment
		(start 53.717952 -382.951482)
		(end 53.816504 -382.85293)
		(width 0.254)
		(layer "F.Cu")
		(net "GND")
	)
	(segment
		(start 105.66781 -228.55047)
		(end 105.200958 -228.284532)
		(width 0.350012)
		(layer "F.Cu")
		(net "GND")
	)
	(segment
		(start 407.298398 -396.520924)
		(end 406.746202 -396.710662)
		(width 0.254)
		(layer "F.Cu")
		(net "GND")
	)
	(segment
		(start 204.425042 -341.675212)
		(end 204.33157 -341.675212)
		(width 0.4572)
		(layer "F.Cu")
		(net "GND")
	)
	(segment
		(start 90.927936 -281.110436)
		(end 90.461084 -281.376374)
		(width 0.350012)
		(layer "F.Cu")
		(net "GND")
	)
	(segment
		(start 390.737852 -248.800112)
		(end 391.204704 -248.534174)
		(width 0.350012)
		(layer "F.Cu")
		(net "GND")
	)
	(segment
		(start 78.877922 -243.94033)
		(end 78.41107 -243.674392)
		(width 0.350012)
		(layer "F.Cu")
		(net "GND")
	)
	(segment
		(start 446.644268 -221.13494)
		(end 445.259968 -221.13494)
		(width 0.4572)
		(layer "F.Cu")
		(net "GND")
	)
	(segment
		(start 99.978464 -177.481484)
		(end 99.390454 -177.481484)
		(width 0.381)
		(layer "F.Cu")
		(net "GND")
	)
	(segment
		(start 328.697844 -226.120198)
		(end 328.231246 -225.85426)
		(width 0.350012)
		(layer "F.Cu")
		(net "GND")
	)
	(segment
		(start 134.80796 -226.930458)
		(end 135.274812 -226.66452)
		(width 0.350012)
		(layer "F.Cu")
		(net "GND")
	)
	(segment
		(start 330.408026 -285.970218)
		(end 329.941174 -286.236156)
		(width 0.350012)
		(layer "F.Cu")
		(net "GND")
	)
	(segment
		(start 51.670712 -390.160002)
		(end 51.618134 -390.761474)
		(width 0.254)
		(layer "F.Cu")
		(net "GND")
	)
	(segment
		(start 100.027994 -233.410252)
		(end 99.561142 -233.144314)
		(width 0.350012)
		(layer "F.Cu")
		(net "GND")
	)
	(segment
		(start 107.847892 -268.15034)
		(end 107.38104 -268.416278)
		(width 0.350012)
		(layer "F.Cu")
		(net "GND")
	)
	(segment
		(start 383.048002 -266.530074)
		(end 383.514854 -266.796012)
		(width 0.350012)
		(layer "F.Cu")
		(net "GND")
	)
	(segment
		(start 409.645612 -399.143474)
		(end 409.69819 -398.542002)
		(width 0.254)
		(layer "F.Cu")
		(net "GND")
	)
	(segment
		(start 77.767942 -277.870412)
		(end 77.112876 -277.870412)
		(width 0.350012)
		(layer "F.Cu")
		(net "GND")
	)
	(segment
		(start 348.437962 -253.660148)
		(end 347.97111 -253.39421)
		(width 0.350012)
		(layer "F.Cu")
		(net "GND")
	)
	(segment
		(start 374.77065 -395.0208)
		(end 374.0785 -394.831062)
		(width 0.254)
		(layer "F.Cu")
		(net "GND")
	)
	(segment
		(start 122.587766 -251.230384)
		(end 123.054618 -250.964446)
		(width 0.350012)
		(layer "F.Cu")
		(net "GND")
	)
	(segment
		(start 136.517888 -268.960346)
		(end 136.98474 -269.226284)
		(width 0.350012)
		(layer "F.Cu")
		(net "GND")
	)
	(segment
		(start 354.378006 -293.260018)
		(end 353.911154 -293.525956)
		(width 0.350012)
		(layer "F.Cu")
		(net "GND")
	)
	(segment
		(start 93.91777 -230.980234)
		(end 93.450918 -230.714296)
		(width 0.350012)
		(layer "F.Cu")
		(net "GND")
	)
	(segment
		(start 291.544502 -124.414026)
		(end 291.544502 -125.049026)
		(width 0.3556)
		(layer "F.Cu")
		(net "GND")
	)
	(segment
		(start 307.317648 -391.333482)
		(end 307.4162 -391.23493)
		(width 0.2032)
		(layer "F.Cu")
		(net "GND")
	)
	(segment
		(start 18.54581 -7.215886)
		(end 18.54708 -7.217156)
		(width 0.3556)
		(layer "F.Cu")
		(net "GND")
	)
	(segment
		(start 339.977984 -256.900172)
		(end 339.511132 -256.634234)
		(width 0.350012)
		(layer "F.Cu")
		(net "GND")
	)
	(segment
		(start 46.621192 -389.030972)
		(end 46.621192 -388.330948)
		(width 0.254)
		(layer "F.Cu")
		(net "GND")
	)
	(segment
		(start 348.737936 -280.300176)
		(end 348.271084 -280.566114)
		(width 0.350012)
		(layer "F.Cu")
		(net "GND")
	)
	(segment
		(start 331.518006 -227.74021)
		(end 331.051154 -227.474272)
		(width 0.350012)
		(layer "F.Cu")
		(net "GND")
	)
	(segment
		(start 368.478054 -277.060152)
		(end 368.944906 -277.32609)
		(width 0.350012)
		(layer "F.Cu")
		(net "GND")
	)
	(segment
		(start 419.806374 -394.831062)
		(end 419.298374 -395.0208)
		(width 0.254)
		(layer "F.Cu")
		(net "GND")
	)
	(segment
		(start 350.446086 -396.710662)
		(end 349.798132 -396.520924)
		(width 0.254)
		(layer "F.Cu")
		(net "GND")
	)
	(segment
		(start 32.695896 -200.735438)
		(end 34.080196 -200.735438)
		(width 0.4572)
		(layer "F.Cu")
		(net "GND")
	)
	(segment
		(start 196.581776 -79.397352)
		(end 196.308218 -79.123794)
		(width 0.3556)
		(layer "F.Cu")
		(net "GND")
	)
	(segment
		(start 138.746992 -16.549878)
		(end 138.748262 -16.551148)
		(width 0.3556)
		(layer "F.Cu")
		(net "GND")
	)
	(segment
		(start 92.33789 -270.580358)
		(end 91.871038 -270.846296)
		(width 0.350012)
		(layer "F.Cu")
		(net "GND")
	)
	(segment
		(start 331.81798 -270.580104)
		(end 331.351128 -270.846042)
		(width 0.350012)
		(layer "F.Cu")
		(net "GND")
	)
	(segment
		(start 353.906074 -394.831062)
		(end 353.398074 -395.0208)
		(width 0.254)
		(layer "F.Cu")
		(net "GND")
	)
	(segment
		(start 130.107944 -233.410252)
		(end 130.574796 -233.144314)
		(width 0.350012)
		(layer "F.Cu")
		(net "GND")
	)
	(segment
		(start 97.398332 -390.160002)
		(end 97.919032 -390.160002)
		(width 0.254)
		(layer "F.Cu")
		(net "GND")
	)
	(segment
		(start 389.627872 -279.49017)
		(end 390.094724 -279.756108)
		(width 0.350012)
		(layer "F.Cu")
		(net "GND")
	)
	(segment
		(start 111.91494 -393.40917)
		(end 111.437928 -392.932158)
		(width 0.254)
		(layer "F.Cu")
		(net "GND")
	)
	(segment
		(start 121.007886 -268.15034)
		(end 121.474738 -268.416278)
		(width 0.350012)
		(layer "F.Cu")
		(net "GND")
	)
	(segment
		(start 85.398356 -388.138924)
		(end 84.84616 -388.328662)
		(width 0.254)
		(layer "F.Cu")
		(net "GND")
	)
	(segment
		(start 59.816492 -391.37971)
		(end 59.71794 -391.281158)
		(width 0.254)
		(layer "F.Cu")
		(net "GND")
	)
	(segment
		(start 123.52782 -230.170228)
		(end 123.994672 -229.90429)
		(width 0.350012)
		(layer "F.Cu")
		(net "GND")
	)
	(segment
		(start 360.957876 -293.260018)
		(end 361.424728 -293.525956)
		(width 0.350012)
		(layer "F.Cu")
		(net "GND")
	)
	(segment
		(start 119.297958 -224.50044)
		(end 119.76481 -224.234502)
		(width 0.350012)
		(layer "F.Cu")
		(net "GND")
	)
	(segment
		(start 374.588024 -285.970218)
		(end 375.054876 -286.236156)
		(width 0.350012)
		(layer "F.Cu")
		(net "GND")
	)
	(segment
		(start 387.271514 -412.212536)
		(end 387.271514 -411.313122)
		(width 0.381)
		(layer "F.Cu")
		(net "GND")
	)
	(segment
		(start 107.377992 -273.820382)
		(end 106.91114 -274.08632)
		(width 0.350012)
		(layer "F.Cu")
		(net "GND")
	)
	(segment
		(start 108.317792 -293.260272)
		(end 107.85094 -293.52621)
		(width 0.350012)
		(layer "F.Cu")
		(net "GND")
	)
	(segment
		(start 140.27785 -267.340334)
		(end 140.744702 -267.606272)
		(width 0.350012)
		(layer "F.Cu")
		(net "GND")
	)
	(segment
		(start 389.327898 -246.370094)
		(end 389.79475 -246.104156)
		(width 0.350012)
		(layer "F.Cu")
		(net "GND")
	)
	(segment
		(start 178.72202 -114.652806)
		(end 178.33213 -114.262916)
		(width 0.254)
		(layer "F.Cu")
		(net "GND")
	)
	(segment
		(start 135.107934 -274.630388)
		(end 135.574786 -274.896326)
		(width 0.350012)
		(layer "F.Cu")
		(net "GND")
	)
	(segment
		(start 384.627882 -231.789986)
		(end 385.094734 -231.524048)
		(width 0.350012)
		(layer "F.Cu")
		(net "GND")
	)
	(segment
		(start 168.527984 -239.835436)
		(end 167.143684 -239.835436)
		(width 0.4572)
		(layer "F.Cu")
		(net "GND")
	)
	(segment
		(start 403.698202 -398.542002)
		(end 403.018752 -398.542002)
		(width 0.254)
		(layer "F.Cu")
		(net "GND")
	)
	(segment
		(start 171.97197 -284.885384)
		(end 173.35627 -284.885384)
		(width 0.4572)
		(layer "F.Cu")
		(net "GND")
	)
	(segment
		(start 348.343982 -400.212814)
		(end 348.343982 -399.76171)
		(width 0.254)
		(layer "F.Cu")
		(net "GND")
	)
	(segment
		(start 87.544402 -391.830814)
		(end 87.544402 -391.37971)
		(width 0.254)
		(layer "F.Cu")
		(net "GND")
	)
	(segment
		(start 335.345532 -392.30427)
		(end 335.39811 -392.356848)
		(width 0.254)
		(layer "F.Cu")
		(net "GND")
	)
	(segment
		(start 140.27785 -283.540454)
		(end 140.744702 -283.806392)
		(width 0.350012)
		(layer "F.Cu")
		(net "GND")
	)
	(segment
		(start 138.098022 -247.180354)
		(end 138.564874 -246.914416)
		(width 0.350012)
		(layer "F.Cu")
		(net "GND")
	)
	(segment
		(start 338.744052 -400.212814)
		(end 338.744052 -399.76171)
		(width 0.254)
		(layer "F.Cu")
		(net "GND")
	)
	(segment
		(start 339.845396 -391.784586)
		(end 339.845396 -392.004042)
		(width 0.2032)
		(layer "F.Cu")
		(net "GND")
	)
	(segment
		(start 348.268036 -276.250146)
		(end 347.801184 -276.516084)
		(width 0.350012)
		(layer "F.Cu")
		(net "GND")
	)
	(segment
		(start 90.627962 -230.170228)
		(end 90.16111 -229.90429)
		(width 0.350012)
		(layer "F.Cu")
		(net "GND")
	)
	(segment
		(start 392.917934 -262.480044)
		(end 393.384786 -262.745982)
		(width 0.350012)
		(layer "F.Cu")
		(net "GND")
	)
	(segment
		(start 61.270642 -386.6388)
		(end 60.578492 -386.449062)
		(width 0.254)
		(layer "F.Cu")
		(net "GND")
	)
	(segment
		(start 351.087944 -277.870158)
		(end 350.621092 -278.136096)
		(width 0.350012)
		(layer "F.Cu")
		(net "GND")
	)
	(segment
		(start 284.736032 -199.885046)
		(end 283.351732 -199.885046)
		(width 0.4572)
		(layer "F.Cu")
		(net "GND")
	)
	(segment
		(start 69.647054 -147.187666)
		(end 69.647054 -147.187412)
		(width 0.254)
		(layer "F.Cu")
		(net "GND")
	)
	(segment
		(start 403.645624 -399.143474)
		(end 403.34565 -399.663158)
		(width 0.254)
		(layer "F.Cu")
		(net "GND")
	)
	(segment
		(start 98.617786 -232.600246)
		(end 98.150934 -232.334308)
		(width 0.350012)
		(layer "F.Cu")
		(net "GND")
	)
	(segment
		(start 389.634476 -396.813024)
		(end 389.414766 -396.813024)
		(width 0.254)
		(layer "F.Cu")
		(net "GND")
	)
	(segment
		(start 303.355756 -438.470294)
		(end 303.990756 -438.470294)
		(width 0.4318)
		(layer "F.Cu")
		(net "GND")
	)
	(segment
		(start 301.792894 -396.74673)
		(end 301.58182 -396.813024)
		(width 0.254)
		(layer "F.Cu")
		(net "GND")
	)
	(segment
		(start 108.787946 -287.590484)
		(end 108.321094 -287.856422)
		(width 0.350012)
		(layer "F.Cu")
		(net "GND")
	)
	(segment
		(start 129.938018 -286.780478)
		(end 130.40487 -287.046416)
		(width 0.350012)
		(layer "F.Cu")
		(net "GND")
	)
	(segment
		(start 93.91777 -235.84027)
		(end 93.450918 -235.574332)
		(width 0.350012)
		(layer "F.Cu")
		(net "GND")
	)
	(segment
		(start 367.067846 -294.070024)
		(end 367.534698 -294.335962)
		(width 0.350012)
		(layer "F.Cu")
		(net "GND")
	)
	(segment
		(start 64.518032 -391.281158)
		(end 64.818006 -390.761474)
		(width 0.254)
		(layer "F.Cu")
		(net "GND")
	)
	(segment
		(start 433.168044 -12.374118)
		(end 433.168044 -12.37488)
		(width 0.3556)
		(layer "F.Cu")
		(net "GND")
	)
	(segment
		(start 303.717706 -399.663158)
		(end 303.816258 -399.76171)
		(width 0.254)
		(layer "F.Cu")
		(net "GND")
	)
	(segment
		(start 415.090102 -392.999722)
		(end 414.498282 -392.999722)
		(width 0.254)
		(layer "F.Cu")
		(net "GND")
	)
	(segment
		(start 343.737946 -222.880174)
		(end 343.271094 -222.614236)
		(width 0.350012)
		(layer "F.Cu")
		(net "GND")
	)
	(segment
		(start 425.232068 -389.535416)
		(end 425.10202 -389.405368)
		(width 0.254)
		(layer "F.Cu")
		(net "GND")
	)
	(segment
		(start 348.737936 -262.480044)
		(end 348.271084 -262.745982)
		(width 0.350012)
		(layer "F.Cu")
		(net "GND")
	)
	(segment
		(start 88.390222 -384.617722)
		(end 88.998298 -384.617722)
		(width 0.254)
		(layer "F.Cu")
		(net "GND")
	)
	(segment
		(start 105.967784 -269.770352)
		(end 105.500932 -270.03629)
		(width 0.350012)
		(layer "F.Cu")
		(net "GND")
	)
	(segment
		(start 380.86792 -222.070168)
		(end 381.334772 -221.80423)
		(width 0.350012)
		(layer "F.Cu")
		(net "GND")
	)
	(segment
		(start 374.588024 -269.770098)
		(end 375.054876 -270.036036)
		(width 0.350012)
		(layer "F.Cu")
		(net "GND")
	)
	(segment
		(start 97.207832 -239.8903)
		(end 96.74098 -239.624362)
		(width 0.350012)
		(layer "F.Cu")
		(net "GND")
	)
	(segment
		(start 18.54835 -12.374118)
		(end 18.54708 -12.372848)
		(width 0.3556)
		(layer "F.Cu")
		(net "GND")
	)
	(segment
		(start 341.387938 -247.990106)
		(end 340.921086 -247.724168)
		(width 0.350012)
		(layer "F.Cu")
		(net "GND")
	)
	(segment
		(start 29.345636 -7.215886)
		(end 29.346906 -7.217156)
		(width 0.3556)
		(layer "F.Cu")
		(net "GND")
	)
	(segment
		(start 32.948372 -12.37488)
		(end 32.948372 -12.374118)
		(width 0.3556)
		(layer "F.Cu")
		(net "GND")
	)
	(segment
		(start 144.037812 -293.260272)
		(end 144.504664 -293.52621)
		(width 0.350012)
		(layer "F.Cu")
		(net "GND")
	)
	(segment
		(start 395.794738 -395.8209)
		(end 395.439138 -396.1765)
		(width 0.254)
		(layer "F.Cu")
		(net "GND")
	)
	(segment
		(start 381.167894 -285.970218)
		(end 381.634746 -286.236156)
		(width 0.350012)
		(layer "F.Cu")
		(net "GND")
	)
	(segment
		(start 340.277958 -260.860032)
		(end 339.811106 -261.12597)
		(width 0.350012)
		(layer "F.Cu")
		(net "GND")
	)
	(segment
		(start 98.046286 -388.328662)
		(end 97.398332 -388.138924)
		(width 0.254)
		(layer "F.Cu")
		(net "GND")
	)
	(segment
		(start 58.222642 -349.786448)
		(end 58.662316 -349.346774)
		(width 0.2286)
		(layer "F.Cu")
		(net "GND")
	)
	(segment
		(start 202.484482 -71.582788)
		(end 202.588876 -71.687182)
		(width 0.381)
		(layer "F.Cu")
		(net "GND")
	)
	(segment
		(start 328.227944 -226.930204)
		(end 327.761092 -226.664266)
		(width 0.350012)
		(layer "F.Cu")
		(net "GND")
	)
	(segment
		(start 12.11072 -412.112968)
		(end 12.090908 -412.093156)
		(width 0.1778)
		(layer "F.Cu")
		(net "GND")
	)
	(segment
		(start 63.317882 -391.281158)
		(end 63.61811 -390.761474)
		(width 0.254)
		(layer "F.Cu")
		(net "GND")
	)
	(segment
		(start 316.23 -363.23905)
		(end 317.246 -363.23905)
		(width 0.381)
		(layer "F.Cu")
		(net "GND")
	)
	(segment
		(start 106.437938 -281.920442)
		(end 105.971086 -282.18638)
		(width 0.350012)
		(layer "F.Cu")
		(net "GND")
	)
	(segment
		(start 394.027914 -246.370094)
		(end 394.68298 -246.370094)
		(width 0.350012)
		(layer "F.Cu")
		(net "GND")
	)
	(segment
		(start 347.497908 -229.360222)
		(end 347.031056 -229.094284)
		(width 0.350012)
		(layer "F.Cu")
		(net "GND")
	)
	(segment
		(start 79.177896 -268.960346)
		(end 78.711044 -269.226284)
		(width 0.350012)
		(layer "F.Cu")
		(net "GND")
	)
	(segment
		(start 93.19006 -384.617722)
		(end 93.79839 -384.617722)
		(width 0.254)
		(layer "F.Cu")
		(net "GND")
	)
	(segment
		(start 381.338074 -256.900172)
		(end 381.804926 -256.634234)
		(width 0.350012)
		(layer "F.Cu")
		(net "GND")
	)
	(segment
		(start 391.50798 -276.250146)
		(end 391.974832 -276.516084)
		(width 0.350012)
		(layer "F.Cu")
		(net "GND")
	)
	(segment
		(start 124.417836 -383.402586)
		(end 124.417836 -382.951482)
		(width 0.254)
		(layer "F.Cu")
		(net "GND")
	)
	(segment
		(start 393.045696 -7.215886)
		(end 393.046966 -7.217156)
		(width 0.3556)
		(layer "F.Cu")
		(net "GND")
	)
	(segment
		(start 404.644352 -399.76171)
		(end 404.5458 -399.663158)
		(width 0.254)
		(layer "F.Cu")
		(net "GND")
	)
	(segment
		(start 105.659936 -128.784096)
		(end 105.659936 -128.168146)
		(width 0.4064)
		(layer "F.Cu")
		(net "GND")
	)
	(segment
		(start 83.877912 -293.260272)
		(end 83.41106 -293.52621)
		(width 0.350012)
		(layer "F.Cu")
		(net "GND")
	)
	(segment
		(start 22.806406 -390.679178)
		(end 23.240746 -390.679178)
		(width 0.2032)
		(layer "F.Cu")
		(net "GND")
	)
	(segment
		(start 400.24685 -10.16635)
		(end 400.24558 -10.16508)
		(width 0.3556)
		(layer "F.Cu")
		(net "GND")
	)
	(segment
		(start 144.977866 -283.540454)
		(end 145.444718 -283.806392)
		(width 0.350012)
		(layer "F.Cu")
		(net "GND")
	)
	(segment
		(start 387.448044 -236.650022)
		(end 387.914896 -236.384084)
		(width 0.350012)
		(layer "F.Cu")
		(net "GND")
	)
	(segment
		(start 376.167904 -226.930204)
		(end 376.634756 -226.664266)
		(width 0.350012)
		(layer "F.Cu")
		(net "GND")
	)
	(segment
		(start 334.808068 -236.650022)
		(end 334.341216 -236.384084)
		(width 0.350012)
		(layer "F.Cu")
		(net "GND")
	)
	(segment
		(start 67.184778 -340.257638)
		(end 67.07759 -340.15045)
		(width 0.381)
		(layer "F.Cu")
		(net "GND")
	)
	(segment
		(start 97.037906 -268.960346)
		(end 96.571054 -269.226284)
		(width 0.350012)
		(layer "F.Cu")
		(net "GND")
	)
	(segment
		(start 359.115106 -167.11295)
		(end 359.115106 -167.418004)
		(width 0.2286)
		(layer "F.Cu")
		(net "GND")
	)
	(segment
		(start 422.40708 -439.934858)
		(end 423.04208 -439.934858)
		(width 0.4318)
		(layer "F.Cu")
		(net "GND")
	)
	(segment
		(start 346.858082 -273.820128)
		(end 346.39123 -274.086066)
		(width 0.350012)
		(layer "F.Cu")
		(net "GND")
	)
	(segment
		(start 98.98507 -55.04053)
		(end 97.6884 -56.3372)
		(width 0.508)
		(layer "F.Cu")
		(net "GND")
	)
	(segment
		(start 187.060078 -219.435426)
		(end 188.444378 -219.435426)
		(width 0.4572)
		(layer "F.Cu")
		(net "GND")
	)
	(segment
		(start 124.297948 -280.30043)
		(end 124.7648 -280.566368)
		(width 0.350012)
		(layer "F.Cu")
		(net "GND")
	)
	(segment
		(start 391.03808 -268.960092)
		(end 391.504678 -269.22603)
		(width 0.350012)
		(layer "F.Cu")
		(net "GND")
	)
	(segment
		(start 304.070258 -396.520924)
		(end 303.518316 -396.710662)
		(width 0.254)
		(layer "F.Cu")
		(net "GND")
	)
	(segment
		(start 325.408036 -238.270034)
		(end 324.75297 -238.270034)
		(width 0.350012)
		(layer "F.Cu")
		(net "GND")
	)
	(segment
		(start 378.370592 -396.520924)
		(end 379.018546 -396.710662)
		(width 0.254)
		(layer "F.Cu")
		(net "GND")
	)
	(segment
		(start 77.467968 -256.09042)
		(end 76.812902 -256.09042)
		(width 0.350012)
		(layer "F.Cu")
		(net "GND")
	)
	(segment
		(start 371.297962 -281.920188)
		(end 371.764814 -282.186126)
		(width 0.350012)
		(layer "F.Cu")
		(net "GND")
	)
	(segment
		(start 135.648446 -151.27351)
		(end 135.755634 -151.380698)
		(width 0.381)
		(layer "F.Cu")
		(net "GND")
	)
	(segment
		(start 76.789534 -175.800766)
		(end 76.361036 -175.800766)
		(width 0.2286)
		(layer "F.Cu")
		(net "GND")
	)
	(segment
		(start 382.577848 -268.960092)
		(end 383.0447 -269.22603)
		(width 0.350012)
		(layer "F.Cu")
		(net "GND")
	)
	(segment
		(start 142.074392 -402.773896)
		(end 142.074392 -403.639274)
		(width 0.381)
		(layer "F.Cu")
		(net "GND")
	)
	(segment
		(start 185.027316 -428.772066)
		(end 185.027316 -429.384714)
		(width 0.381)
		(layer "F.Cu")
		(net "GND")
	)
	(segment
		(start 162.434016 -130.199638)
		(end 161.699956 -130.199638)
		(width 0.381)
		(layer "F.Cu")
		(net "GND")
	)
	(segment
		(start 376.478546 -394.831062)
		(end 375.970546 -395.0208)
		(width 0.254)
		(layer "F.Cu")
		(net "GND")
	)
	(segment
		(start 85.457792 -247.180354)
		(end 84.99094 -246.914416)
		(width 0.350012)
		(layer "F.Cu")
		(net "GND")
	)
	(segment
		(start 146.38782 -266.530328)
		(end 147.042886 -266.530328)
		(width 0.350012)
		(layer "F.Cu")
		(net "GND")
	)
	(segment
		(start 98.245676 -383.402586)
		(end 98.344228 -383.304034)
		(width 0.254)
		(layer "F.Cu")
		(net "GND")
	)
	(segment
		(start 97.398332 -384.617722)
		(end 96.790256 -384.617722)
		(width 0.254)
		(layer "F.Cu")
		(net "GND")
	)
	(segment
		(start 367.238026 -247.1801)
		(end 367.704878 -246.914162)
		(width 0.350012)
		(layer "F.Cu")
		(net "GND")
	)
	(segment
		(start 79.647796 -268.15034)
		(end 79.180944 -268.416278)
		(width 0.350012)
		(layer "F.Cu")
		(net "GND")
	)
	(segment
		(start 123.997974 -227.740464)
		(end 124.464826 -227.474526)
		(width 0.350012)
		(layer "F.Cu")
		(net "GND")
	)
	(segment
		(start 116.477796 -222.880428)
		(end 116.944648 -222.61449)
		(width 0.350012)
		(layer "F.Cu")
		(net "GND")
	)
	(segment
		(start 348.597982 -396.520924)
		(end 348.04604 -396.710662)
		(width 0.254)
		(layer "F.Cu")
		(net "GND")
	)
	(segment
		(start 317.270384 -398.542002)
		(end 317.217806 -399.143474)
		(width 0.254)
		(layer "F.Cu")
		(net "GND")
	)
	(segment
		(start 125.877828 -237.460282)
		(end 126.34468 -237.194344)
		(width 0.350012)
		(layer "F.Cu")
		(net "GND")
	)
	(segment
		(start 342.343994 -400.212814)
		(end 342.343994 -399.76171)
		(width 0.254)
		(layer "F.Cu")
		(net "GND")
	)
	(segment
		(start 59.428126 -237.285276)
		(end 58.043826 -237.285276)
		(width 0.4572)
		(layer "F.Cu")
		(net "GND")
	)
	(segment
		(start 144.977866 -264.10031)
		(end 145.444718 -264.366248)
		(width 0.350012)
		(layer "F.Cu")
		(net "GND")
	)
	(segment
		(start 353.607878 -228.550216)
		(end 353.141026 -228.284278)
		(width 0.350012)
		(layer "F.Cu")
		(net "GND")
	)
	(segment
		(start 259.89788 -48.659542)
		(end 259.898134 -48.659796)
		(width 0.4572)
		(layer "F.Cu")
		(net "GND")
	)
	(segment
		(start 312.470292 -395.0208)
		(end 311.778396 -394.831062)
		(width 0.254)
		(layer "F.Cu")
		(net "GND")
	)
	(segment
		(start 106.437938 -273.820382)
		(end 105.971086 -274.08632)
		(width 0.350012)
		(layer "F.Cu")
		(net "GND")
	)
	(segment
		(start 336.687922 -235.03001)
		(end 336.22107 -234.764072)
		(width 0.350012)
		(layer "F.Cu")
		(net "GND")
	)
	(segment
		(start 369.618006 -392.004296)
		(end 369.91798 -392.30427)
		(width 0.254)
		(layer "F.Cu")
		(net "GND")
	)
	(segment
		(start 95.157798 -293.260272)
		(end 94.690946 -293.52621)
		(width 0.350012)
		(layer "F.Cu")
		(net "GND")
	)
	(segment
		(start 83.577938 -227.740464)
		(end 83.111086 -227.474526)
		(width 0.350012)
		(layer "F.Cu")
		(net "GND")
	)
	(segment
		(start 86.21776 -340.190074)
		(end 86.80577 -340.190074)
		(width 0.381)
		(layer "F.Cu")
		(net "GND")
	)
	(segment
		(start 94.945708 -390.761474)
		(end 94.998286 -390.160002)
		(width 0.254)
		(layer "F.Cu")
		(net "GND")
	)
	(segment
		(start 93.747844 -279.490424)
		(end 93.280992 -279.756362)
		(width 0.350012)
		(layer "F.Cu")
		(net "GND")
	)
	(segment
		(start 365.218472 -172.559726)
		(end 364.630462 -172.559726)
		(width 0.381)
		(layer "F.Cu")
		(net "GND")
	)
	(segment
		(start 89.845642 -383.402586)
		(end 89.845642 -382.951482)
		(width 0.254)
		(layer "F.Cu")
		(net "GND")
	)
	(segment
		(start 111.137954 -272.20037)
		(end 110.671102 -272.466308)
		(width 0.350012)
		(layer "F.Cu")
		(net "GND")
	)
	(segment
		(start 62.470538 -384.617722)
		(end 63.062358 -384.617722)
		(width 0.254)
		(layer "F.Cu")
		(net "GND")
	)
	(segment
		(start 419.912038 -306.135024)
		(end 421.296338 -306.135024)
		(width 0.4572)
		(layer "F.Cu")
		(net "GND")
	)
	(segment
		(start 191.160146 -221.135194)
		(end 189.775846 -221.135194)
		(width 0.4572)
		(layer "F.Cu")
		(net "GND")
	)
	(segment
		(start 394.092684 -395.22273)
		(end 393.849352 -395.466062)
		(width 0.381)
		(layer "F.Cu")
		(net "GND")
	)
	(segment
		(start 344.977974 -290.019994)
		(end 344.511122 -290.285932)
		(width 0.350012)
		(layer "F.Cu")
		(net "GND")
	)
	(segment
		(start 325.408036 -235.03001)
		(end 324.75297 -235.03001)
		(width 0.350012)
		(layer "F.Cu")
		(net "GND")
	)
	(segment
		(start 359.68559 -166.430706)
		(end 359.1941 -166.922196)
		(width 0.2286)
		(layer "F.Cu")
		(net "GND")
	)
	(segment
		(start 110.556548 -13.974064)
		(end 109.701584 -13.974064)
		(width 0.4572)
		(layer "F.Cu")
		(net "GND")
	)
	(segment
		(start 117.217952 -383.622296)
		(end 117.517926 -383.92227)
		(width 0.254)
		(layer "F.Cu")
		(net "GND")
	)
	(segment
		(start 98.344228 -383.304034)
		(end 98.344228 -382.85293)
		(width 0.254)
		(layer "F.Cu")
		(net "GND")
	)
	(segment
		(start 160.54578 -383.622296)
		(end 160.845754 -383.92227)
		(width 0.254)
		(layer "F.Cu")
		(net "GND")
	)
	(segment
		(start 78.877922 -256.900426)
		(end 78.41107 -256.634488)
		(width 0.350012)
		(layer "F.Cu")
		(net "GND")
	)
	(segment
		(start 348.268036 -271.39011)
		(end 347.801184 -271.656048)
		(width 0.350012)
		(layer "F.Cu")
		(net "GND")
	)
	(segment
		(start 89.517982 -268.960346)
		(end 89.05113 -269.226284)
		(width 0.350012)
		(layer "F.Cu")
		(net "GND")
	)
	(segment
		(start 109.427772 -238.270288)
		(end 108.961174 -238.00435)
		(width 0.350012)
		(layer "F.Cu")
		(net "GND")
	)
	(segment
		(start 121.477786 -290.020248)
		(end 121.944638 -290.286186)
		(width 0.350012)
		(layer "F.Cu")
		(net "GND")
	)
	(segment
		(start 346.79001 -392.999722)
		(end 347.398086 -392.999722)
		(width 0.254)
		(layer "F.Cu")
		(net "GND")
	)
	(segment
		(start 85.457792 -255.280414)
		(end 84.99094 -255.014476)
		(width 0.350012)
		(layer "F.Cu")
		(net "GND")
	)
	(segment
		(start 347.497908 -230.97998)
		(end 347.031056 -230.714296)
		(width 0.350012)
		(layer "F.Cu")
		(net "GND")
	)
	(segment
		(start 306.002182 -351.973896)
		(end 305.63439 -351.973896)
		(width 0.381)
		(layer "F.Cu")
		(net "GND")
	)
	(segment
		(start 375.970546 -396.520924)
		(end 375.41835 -396.710662)
		(width 0.254)
		(layer "F.Cu")
		(net "GND")
	)
	(segment
		(start 366.297972 -252.040136)
		(end 366.764824 -251.774198)
		(width 0.350012)
		(layer "F.Cu")
		(net "GND")
	)
	(segment
		(start 90.457782 -286.780478)
		(end 89.991438 -287.045908)
		(width 0.350012)
		(layer "F.Cu")
		(net "GND")
	)
	(segment
		(start 340.308692 -337.10245)
		(end 340.561676 -336.849466)
		(width 0.2286)
		(layer "F.Cu")
		(net "GND")
	)
	(segment
		(start 140.27785 -293.260272)
		(end 140.744702 -293.52621)
		(width 0.350012)
		(layer "F.Cu")
		(net "GND")
	)
	(segment
		(start 379.018546 -396.710662)
		(end 379.570488 -396.520924)
		(width 0.254)
		(layer "F.Cu")
		(net "GND")
	)
	(segment
		(start 135.593074 -153.948892)
		(end 135.593074 -154.365706)
		(width 0.2286)
		(layer "F.Cu")
		(net "GND")
	)
	(segment
		(start 53.717952 -383.622296)
		(end 54.017926 -383.92227)
		(width 0.254)
		(layer "F.Cu")
		(net "GND")
	)
	(segment
		(start 15.527782 -416.451034)
		(end 15.527782 -416.457892)
		(width 0.381)
		(layer "F.Cu")
		(net "GND")
	)
	(segment
		(start 363.478064 -245.560088)
		(end 363.944916 -245.29415)
		(width 0.350012)
		(layer "F.Cu")
		(net "GND")
	)
	(segment
		(start 346.387928 -261.670038)
		(end 345.921076 -261.935976)
		(width 0.350012)
		(layer "F.Cu")
		(net "GND")
	)
	(segment
		(start 322.31457 -396.213076)
		(end 321.51828 -396.710662)
		(width 0.254)
		(layer "F.Cu")
		(net "GND")
	)
	(segment
		(start 383.048002 -274.630134)
		(end 383.514854 -274.896072)
		(width 0.350012)
		(layer "F.Cu")
		(net "GND")
	)
	(segment
		(start 146.087846 -243.130324)
		(end 146.742912 -243.130324)
		(width 0.350012)
		(layer "F.Cu")
		(net "GND")
	)
	(segment
		(start 97.207832 -236.650276)
		(end 96.74098 -236.384338)
		(width 0.350012)
		(layer "F.Cu")
		(net "GND")
	)
	(segment
		(start 348.268036 -287.59023)
		(end 347.801184 -287.856168)
		(width 0.350012)
		(layer "F.Cu")
		(net "GND")
	)
	(segment
		(start 99.857814 -270.580358)
		(end 99.390962 -270.846296)
		(width 0.350012)
		(layer "F.Cu")
		(net "GND")
	)
	(segment
		(start 348.972124 -345.192096)
		(end 348.341188 -345.192096)
		(width 0.381)
		(layer "F.Cu")
		(net "GND")
	)
	(segment
		(start 182.722012 -112.25276)
		(end 182.332122 -111.86287)
		(width 0.254)
		(layer "F.Cu")
		(net "GND")
	)
	(segment
		(start 123.357894 -285.160466)
		(end 123.824746 -285.426404)
		(width 0.350012)
		(layer "F.Cu")
		(net "GND")
	)
	(segment
		(start 372.116604 -399.76171)
		(end 372.116604 -400.212814)
		(width 0.254)
		(layer "F.Cu")
		(net "GND")
	)
	(segment
		(start 121.177812 -224.50044)
		(end 121.644664 -224.234502)
		(width 0.350012)
		(layer "F.Cu")
		(net "GND")
	)
	(segment
		(start 58.793126 -349.031306)
		(end 58.793126 -348.79915)
		(width 0.2286)
		(layer "F.Cu")
		(net "GND")
	)
	(segment
		(start 84.347812 -273.010376)
		(end 83.88096 -273.276314)
		(width 0.350012)
		(layer "F.Cu")
		(net "GND")
	)
	(segment
		(start 60.718446 -388.328662)
		(end 61.270642 -388.138924)
		(width 0.254)
		(layer "F.Cu")
		(net "GND")
	)
	(segment
		(start 391.082022 -136.661652)
		(end 391.082022 -135.943848)
		(width 0.4572)
		(layer "F.Cu")
		(net "GND")
	)
	(segment
		(start 314.870338 -395.0208)
		(end 314.178188 -394.831062)
		(width 0.254)
		(layer "F.Cu")
		(net "GND")
	)
	(segment
		(start 74.422 -55.73395)
		(end 74.422 -54.991)
		(width 0.381)
		(layer "F.Cu")
		(net "GND")
	)
	(segment
		(start 88.747854 -239.8903)
		(end 88.281002 -239.624362)
		(width 0.350012)
		(layer "F.Cu")
		(net "GND")
	)
	(segment
		(start 333.39786 -245.560088)
		(end 332.931008 -245.29415)
		(width 0.350012)
		(layer "F.Cu")
		(net "GND")
	)
	(segment
		(start 333.697834 -293.260018)
		(end 333.230982 -293.525956)
		(width 0.350012)
		(layer "F.Cu")
		(net "GND")
	)
	(segment
		(start 450.088 -219.435172)
		(end 451.4723 -219.435172)
		(width 0.4572)
		(layer "F.Cu")
		(net "GND")
	)
	(segment
		(start 376.467878 -290.83)
		(end 376.93473 -291.095938)
		(width 0.350012)
		(layer "F.Cu")
		(net "GND")
	)
	(segment
		(start 127.145034 -162.600132)
		(end 127.047498 -162.83559)
		(width 0.2286)
		(layer "F.Cu")
		(net "GND")
	)
	(segment
		(start 100.327968 -287.590484)
		(end 99.861116 -287.856422)
		(width 0.350012)
		(layer "F.Cu")
		(net "GND")
	)
	(segment
		(start 77.767942 -292.450266)
		(end 77.112876 -292.450266)
		(width 0.350012)
		(layer "F.Cu")
		(net "GND")
	)
	(segment
		(start 150.746206 -388.328662)
		(end 150.098252 -388.138924)
		(width 0.254)
		(layer "F.Cu")
		(net "GND")
	)
	(segment
		(start 390.737852 -226.120198)
		(end 391.204704 -225.85426)
		(width 0.350012)
		(layer "F.Cu")
		(net "GND")
	)
	(segment
		(start 342.597994 -396.520924)
		(end 342.046052 -396.710662)
		(width 0.254)
		(layer "F.Cu")
		(net "GND")
	)
	(segment
		(start 36.795964 -211.7852)
		(end 35.411664 -211.7852)
		(width 0.4572)
		(layer "F.Cu")
		(net "GND")
	)
	(segment
		(start 110.367826 -241.510312)
		(end 109.900974 -241.244374)
		(width 0.350012)
		(layer "F.Cu")
		(net "GND")
	)
	(segment
		(start 171.97197 -219.435426)
		(end 173.35627 -219.435426)
		(width 0.4572)
		(layer "F.Cu")
		(net "GND")
	)
	(segment
		(start 352.197924 -250.420124)
		(end 351.731072 -250.154186)
		(width 0.350012)
		(layer "F.Cu")
		(net "GND")
	)
	(segment
		(start 351.087944 -282.730194)
		(end 350.621092 -282.996132)
		(width 0.350012)
		(layer "F.Cu")
		(net "GND")
	)
	(segment
		(start 265.54811 -231.335072)
		(end 266.93241 -231.335072)
		(width 0.4572)
		(layer "F.Cu")
		(net "GND")
	)
	(segment
		(start 146.248882 -387.832092)
		(end 146.248882 -387.231128)
		(width 0.254)
		(layer "F.Cu")
		(net "GND")
	)
	(segment
		(start 413.931862 -363.790992)
		(end 413.931862 -364.781592)
		(width 0.3556)
		(layer "F.Cu")
		(net "GND")
	)
	(segment
		(start 66.834512 -384.531108)
		(end 66.614802 -384.531108)
		(width 0.254)
		(layer "F.Cu")
		(net "GND")
	)
	(segment
		(start 303.268126 -315.485018)
		(end 304.652426 -315.485018)
		(width 0.4572)
		(layer "F.Cu")
		(net "GND")
	)
	(segment
		(start 49.270666 -384.617722)
		(end 48.662336 -384.617722)
		(width 0.254)
		(layer "F.Cu")
		(net "GND")
	)
	(segment
		(start 94.217998 -288.400236)
		(end 93.751146 -288.666174)
		(width 0.350012)
		(layer "F.Cu")
		(net "GND")
	)
	(segment
		(start 369.72113 -394.412978)
		(end 369.72113 -395.012926)
		(width 0.254)
		(layer "F.Cu")
		(net "GND")
	)
	(segment
		(start 146.087846 -254.470408)
		(end 146.742912 -254.470408)
		(width 0.350012)
		(layer "F.Cu")
		(net "GND")
	)
	(segment
		(start 95.627952 -284.35046)
		(end 95.1611 -284.616398)
		(width 0.350012)
		(layer "F.Cu")
		(net "GND")
	)
	(segment
		(start 211.102956 -29.876242)
		(end 211.102956 -29.266896)
		(width 0.4572)
		(layer "F.Cu")
		(net "GND")
	)
	(segment
		(start 136.687814 -223.690434)
		(end 137.154666 -223.424496)
		(width 0.350012)
		(layer "F.Cu")
		(net "GND")
	)
	(segment
		(start 125.877828 -256.900426)
		(end 126.34468 -256.634488)
		(width 0.350012)
		(layer "F.Cu")
		(net "GND")
	)
	(segment
		(start 269.648178 -202.434952)
		(end 268.263878 -202.434952)
		(width 0.4572)
		(layer "F.Cu")
		(net "GND")
	)
	(segment
		(start 52.191412 -390.160002)
		(end 52.870608 -390.160002)
		(width 0.254)
		(layer "F.Cu")
		(net "GND")
	)
	(segment
		(start 153.345642 -383.402586)
		(end 153.345642 -382.951482)
		(width 0.254)
		(layer "F.Cu")
		(net "GND")
	)
	(segment
		(start 340.74989 -61.364876)
		(end 339.15604 -61.364876)
		(width 0.4572)
		(layer "F.Cu")
		(net "GND")
	)
	(segment
		(start 99.36226 -388.13105)
		(end 99.062286 -388.431024)
		(width 0.254)
		(layer "F.Cu")
		(net "GND")
	)
	(segment
		(start 309.717694 -391.333482)
		(end 309.816246 -391.23493)
		(width 0.254)
		(layer "F.Cu")
		(net "GND")
	)
	(segment
		(start 80.287876 -228.55047)
		(end 79.821024 -228.284532)
		(width 0.350012)
		(layer "F.Cu")
		(net "GND")
	)
	(segment
		(start 161.745676 -383.402586)
		(end 161.745676 -382.951482)
		(width 0.254)
		(layer "F.Cu")
		(net "GND")
	)
	(segment
		(start 202.147932 -221.985332)
		(end 203.532232 -221.985332)
		(width 0.4572)
		(layer "F.Cu")
		(net "GND")
	)
	(segment
		(start 43.532552 -383.7432)
		(end 44.065952 -383.7432)
		(width 0.254)
		(layer "F.Cu")
		(net "GND")
	)
	(segment
		(start 342.158066 -264.100056)
		(end 341.691214 -264.365994)
		(width 0.350012)
		(layer "F.Cu")
		(net "GND")
	)
	(segment
		(start 421.444166 -391.686034)
		(end 421.444166 -391.23493)
		(width 0.254)
		(layer "F.Cu")
		(net "GND")
	)
	(segment
		(start 115.367816 -284.35046)
		(end 115.834668 -284.616398)
		(width 0.350012)
		(layer "F.Cu")
		(net "GND")
	)
	(segment
		(start 349.847916 -249.610118)
		(end 349.381064 -249.34418)
		(width 0.350012)
		(layer "F.Cu")
		(net "GND")
	)
	(segment
		(start 78.877922 -255.280414)
		(end 78.41107 -255.014476)
		(width 0.350012)
		(layer "F.Cu")
		(net "GND")
	)
	(segment
		(start 17.608042 -278.085296)
		(end 18.992342 -278.085296)
		(width 0.4572)
		(layer "F.Cu")
		(net "GND")
	)
	(segment
		(start 138.397996 -291.64026)
		(end 138.864848 -291.906198)
		(width 0.350012)
		(layer "F.Cu")
		(net "GND")
	)
	(segment
		(start 338.6455 -392.004296)
		(end 338.945474 -392.30427)
		(width 0.254)
		(layer "F.Cu")
		(net "GND")
	)
	(segment
		(start 374.75795 -242.320064)
		(end 375.224802 -242.054126)
		(width 0.350012)
		(layer "F.Cu")
		(net "GND")
	)
	(segment
		(start 82.467958 -289.210242)
		(end 82.001106 -289.47618)
		(width 0.350012)
		(layer "F.Cu")
		(net "GND")
	)
	(segment
		(start 43.85564 -7.215124)
		(end 43.85564 -7.215886)
		(width 0.3556)
		(layer "F.Cu")
		(net "GND")
	)
	(segment
		(start 308.757574 -22.585934)
		(end 308.757574 -23.201884)
		(width 0.4572)
		(layer "F.Cu")
		(net "GND")
	)
	(segment
		(start 87.44585 -382.951482)
		(end 87.544402 -382.85293)
		(width 0.254)
		(layer "F.Cu")
		(net "GND")
	)
	(segment
		(start 317.441326 -340.206838)
		(end 318.029336 -340.206838)
		(width 0.381)
		(layer "F.Cu")
		(net "GND")
	)
	(segment
		(start 38.0746 -435.048914)
		(end 37.408358 -435.048914)
		(width 0.381)
		(layer "F.Cu")
		(net "GND")
	)
	(segment
		(start 146.122644 -391.304272)
		(end 146.145758 -391.281158)
		(width 0.254)
		(layer "F.Cu")
		(net "GND")
	)
	(segment
		(start 97.507806 -274.630388)
		(end 97.040954 -274.896326)
		(width 0.350012)
		(layer "F.Cu")
		(net "GND")
	)
	(segment
		(start 116.77777 -267.340334)
		(end 117.244622 -267.606272)
		(width 0.350012)
		(layer "F.Cu")
		(net "GND")
	)
	(segment
		(start 198.7042 -239.835436)
		(end 197.3199 -239.835436)
		(width 0.4572)
		(layer "F.Cu")
		(net "GND")
	)
	(segment
		(start 316.202568 -360.289348)
		(end 316.552326 -359.93959)
		(width 0.381)
		(layer "F.Cu")
		(net "GND")
	)
	(segment
		(start 131.617974 -383.402586)
		(end 131.617974 -382.951482)
		(width 0.254)
		(layer "F.Cu")
		(net "GND")
	)
	(segment
		(start 408.145742 -392.004296)
		(end 408.445716 -392.30427)
		(width 0.2032)
		(layer "F.Cu")
		(net "GND")
	)
	(segment
		(start 125.617986 -391.281158)
		(end 125.716538 -391.37971)
		(width 0.254)
		(layer "F.Cu")
		(net "GND")
	)
	(segment
		(start 83.877912 -277.060406)
		(end 83.41106 -277.326344)
		(width 0.350012)
		(layer "F.Cu")
		(net "GND")
	)
	(segment
		(start 47.46244 -384.617722)
		(end 48.070516 -384.617722)
		(width 0.254)
		(layer "F.Cu")
		(net "GND")
	)
	(segment
		(start 123.21794 -383.402586)
		(end 123.21794 -383.622296)
		(width 0.254)
		(layer "F.Cu")
		(net "GND")
	)
	(segment
		(start 144.507966 -268.15034)
		(end 144.974818 -268.416278)
		(width 0.350012)
		(layer "F.Cu")
		(net "GND")
	)
	(segment
		(start 51.416458 -391.37971)
		(end 51.416458 -391.830814)
		(width 0.254)
		(layer "F.Cu")
		(net "GND")
	)
	(segment
		(start 25.152096 -306.135278)
		(end 26.536396 -306.135278)
		(width 0.4572)
		(layer "F.Cu")
		(net "GND")
	)
	(segment
		(start 133.170676 -386.6388)
		(end 132.478526 -386.449062)
		(width 0.254)
		(layer "F.Cu")
		(net "GND")
	)
	(segment
		(start 138.397996 -272.20037)
		(end 138.864848 -272.466308)
		(width 0.350012)
		(layer "F.Cu")
		(net "GND")
	)
	(segment
		(start 427.922182 -430.892458)
		(end 427.922182 -431.533808)
		(width 0.381)
		(layer "F.Cu")
		(net "GND")
	)
	(segment
		(start 352.706178 -394.831062)
		(end 352.198178 -395.0208)
		(width 0.254)
		(layer "F.Cu")
		(net "GND")
	)
	(segment
		(start 92.33789 -288.400236)
		(end 91.871038 -288.666174)
		(width 0.350012)
		(layer "F.Cu")
		(net "GND")
	)
	(segment
		(start 180.80863 -149.261068)
		(end 181.504082 -149.261068)
		(width 0.4572)
		(layer "F.Cu")
		(net "GND")
	)
	(segment
		(start 392.61796 -234.220004)
		(end 393.084812 -233.954066)
		(width 0.350012)
		(layer "F.Cu")
		(net "GND")
	)
	(segment
		(start 374.75795 -245.560088)
		(end 375.224802 -245.29415)
		(width 0.350012)
		(layer "F.Cu")
		(net "GND")
	)
	(segment
		(start 138.098022 -256.900426)
		(end 138.564874 -256.634488)
		(width 0.350012)
		(layer "F.Cu")
		(net "GND")
	)
	(segment
		(start 384.457956 -288.399982)
		(end 384.924808 -288.66592)
		(width 0.350012)
		(layer "F.Cu")
		(net "GND")
	)
	(segment
		(start 101.437948 -243.94033)
		(end 100.971096 -243.674392)
		(width 0.350012)
		(layer "F.Cu")
		(net "GND")
	)
	(segment
		(start 390.098026 -293.260018)
		(end 390.564878 -293.525956)
		(width 0.350012)
		(layer "F.Cu")
		(net "GND")
	)
	(segment
		(start 392.917934 -285.160212)
		(end 393.384786 -285.42615)
		(width 0.350012)
		(layer "F.Cu")
		(net "GND")
	)
	(segment
		(start 378.891292 -398.542002)
		(end 378.370592 -398.542002)
		(width 0.254)
		(layer "F.Cu")
		(net "GND")
	)
	(segment
		(start 335.277968 -250.420124)
		(end 334.811116 -250.154186)
		(width 0.350012)
		(layer "F.Cu")
		(net "GND")
	)
	(segment
		(start 30.484064 -75.634088)
		(end 30.484064 -76.366116)
		(width 0.4572)
		(layer "F.Cu")
		(net "GND")
	)
	(segment
		(start 383.818384 -396.710662)
		(end 383.17043 -396.520924)
		(width 0.254)
		(layer "F.Cu")
		(net "GND")
	)
	(segment
		(start 182.015384 -356.507034)
		(end 182.603394 -356.507034)
		(width 0.381)
		(layer "F.Cu")
		(net "GND")
	)
	(segment
		(start 340.198202 -398.542002)
		(end 339.518752 -398.542002)
		(width 0.254)
		(layer "F.Cu")
		(net "GND")
	)
	(segment
		(start 88.277954 -224.50044)
		(end 87.811102 -224.234502)
		(width 0.350012)
		(layer "F.Cu")
		(net "GND")
	)
	(segment
		(start 439.072782 -436.94731)
		(end 439.703718 -436.94731)
		(width 0.381)
		(layer "F.Cu")
		(net "GND")
	)
	(segment
		(start 369.72113 -393.81303)
		(end 369.72113 -393.24915)
		(width 0.254)
		(layer "F.Cu")
		(net "GND")
	)
	(segment
		(start 82.167984 -252.850396)
		(end 81.701132 -252.584458)
		(width 0.350012)
		(layer "F.Cu")
		(net "GND")
	)
	(segment
		(start 386.516372 -400.212814)
		(end 386.516372 -399.76171)
		(width 0.254)
		(layer "F.Cu")
		(net "GND")
	)
	(segment
		(start 232.000044 -49.76495)
		(end 230.961692 -49.76495)
		(width 0.381)
		(layer "F.Cu")
		(net "GND")
	)
	(segment
		(start 306.216304 -403.081744)
		(end 306.216304 -402.309838)
		(width 0.381)
		(layer "F.Cu")
		(net "GND")
	)
	(segment
		(start 32.695896 -303.585372)
		(end 34.080196 -303.585372)
		(width 0.4572)
		(layer "F.Cu")
		(net "GND")
	)
	(segment
		(start 91.045792 -391.281158)
		(end 91.345766 -390.761474)
		(width 0.254)
		(layer "F.Cu")
		(net "GND")
	)
	(segment
		(start 405.745696 -391.784586)
		(end 405.745696 -392.004296)
		(width 0.254)
		(layer "F.Cu")
		(net "GND")
	)
	(segment
		(start 83.40725 -139.349734)
		(end 83.557364 -139.19962)
		(width 0.3556)
		(layer "F.Cu")
		(net "GND")
	)
	(segment
		(start 115.537996 -245.560342)
		(end 116.004848 -245.294404)
		(width 0.350012)
		(layer "F.Cu")
		(net "GND")
	)
	(segment
		(start 132.916422 -391.37971)
		(end 132.81787 -391.281158)
		(width 0.254)
		(layer "F.Cu")
		(net "GND")
	)
	(segment
		(start 151.19604 -41.44137)
		(end 150.86965 -41.76776)
		(width 0.381)
		(layer "F.Cu")
		(net "GND")
	)
	(segment
		(start 133.227826 -264.910316)
		(end 133.694678 -265.176254)
		(width 0.350012)
		(layer "F.Cu")
		(net "GND")
	)
	(segment
		(start 371.767862 -289.209988)
		(end 372.234714 -289.475926)
		(width 0.350012)
		(layer "F.Cu")
		(net "GND")
	)
	(segment
		(start 377.878086 -262.480044)
		(end 378.344938 -262.745982)
		(width 0.350012)
		(layer "F.Cu")
		(net "GND")
	)
	(segment
		(start 209.890106 -107.467146)
		(end 209.97291 -107.54995)
		(width 0.381)
		(layer "F.Cu")
		(net "GND")
	)
	(segment
		(start 347.797882 -288.399982)
		(end 347.33103 -288.66592)
		(width 0.350012)
		(layer "F.Cu")
		(net "GND")
	)
	(segment
		(start 47.816516 -394.310616)
		(end 47.816516 -393.902438)
		(width 0.381)
		(layer "F.Cu")
		(net "GND")
	)
	(segment
		(start 105.967784 -271.390364)
		(end 105.500932 -271.656302)
		(width 0.350012)
		(layer "F.Cu")
		(net "GND")
	)
	(segment
		(start 192.199768 -70.185788)
		(end 192.199768 -70.851268)
		(width 0.3556)
		(layer "F.Cu")
		(net "GND")
	)
	(segment
		(start 366.64392 -393.97559)
		(end 366.63249 -393.96416)
		(width 0.254)
		(layer "F.Cu")
		(net "GND")
	)
	(segment
		(start 205.63205 -128.016)
		(end 206.375 -128.016)
		(width 0.381)
		(layer "F.Cu")
		(net "GND")
	)
	(segment
		(start 67.19189 -387.069076)
		(end 66.47688 -387.069076)
		(width 0.254)
		(layer "F.Cu")
		(net "GND")
	)
	(segment
		(start 409.000706 -166.76878)
		(end 408.547824 -166.76878)
		(width 0.2286)
		(layer "F.Cu")
		(net "GND")
	)
	(segment
		(start 338.56803 -243.13007)
		(end 338.101178 -242.864132)
		(width 0.350012)
		(layer "F.Cu")
		(net "GND")
	)
	(segment
		(start 194.604132 -210.085432)
		(end 195.988432 -210.085432)
		(width 0.4572)
		(layer "F.Cu")
		(net "GND")
	)
	(segment
		(start 84.79028 -384.617722)
		(end 85.398356 -384.617722)
		(width 0.254)
		(layer "F.Cu")
		(net "GND")
	)
	(segment
		(start 447.792602 -418.56406)
		(end 446.522602 -418.56406)
		(width 0.4572)
		(layer "F.Cu")
		(net "GND")
	)
	(segment
		(start 143.267938 -228.55047)
		(end 143.73479 -228.284532)
		(width 0.350012)
		(layer "F.Cu")
		(net "GND")
	)
	(segment
		(start 429.136302 -433.986686)
		(end 429.767238 -433.986686)
		(width 0.381)
		(layer "F.Cu")
		(net "GND")
	)
	(segment
		(start 131.970526 -386.6388)
		(end 131.27863 -386.449062)
		(width 0.254)
		(layer "F.Cu")
		(net "GND")
	)
	(segment
		(start 99.08794 -225.310446)
		(end 98.621088 -225.044508)
		(width 0.350012)
		(layer "F.Cu")
		(net "GND")
	)
	(segment
		(start 141.38783 -256.09042)
		(end 141.854682 -255.824482)
		(width 0.350012)
		(layer "F.Cu")
		(net "GND")
	)
	(segment
		(start 371.467888 -233.409998)
		(end 371.93474 -233.14406)
		(width 0.350012)
		(layer "F.Cu")
		(net "GND")
	)
	(segment
		(start 384.157982 -243.940076)
		(end 384.624834 -243.674138)
		(width 0.350012)
		(layer "F.Cu")
		(net "GND")
	)
	(segment
		(start 369.417854 -273.820128)
		(end 369.884706 -274.086066)
		(width 0.350012)
		(layer "F.Cu")
		(net "GND")
	)
	(segment
		(start 340.277958 -268.960092)
		(end 339.811106 -269.22603)
		(width 0.350012)
		(layer "F.Cu")
		(net "GND")
	)
	(segment
		(start 139.507976 -244.750336)
		(end 139.974828 -244.484398)
		(width 0.350012)
		(layer "F.Cu")
		(net "GND")
	)
	(segment
		(start 367.067846 -268.150086)
		(end 367.534698 -268.416024)
		(width 0.350012)
		(layer "F.Cu")
		(net "GND")
	)
	(segment
		(start 95.627952 -276.2504)
		(end 95.1611 -276.516338)
		(width 0.350012)
		(layer "F.Cu")
		(net "GND")
	)
	(segment
		(start 305.270408 -398.542002)
		(end 304.590958 -398.542002)
		(width 0.254)
		(layer "F.Cu")
		(net "GND")
	)
	(segment
		(start 164.427916 -284.885384)
		(end 165.812216 -284.885384)
		(width 0.4572)
		(layer "F.Cu")
		(net "GND")
	)
	(segment
		(start 381.167894 -261.670038)
		(end 381.634746 -261.935976)
		(width 0.350012)
		(layer "F.Cu")
		(net "GND")
	)
	(segment
		(start 122.927618 -54.125622)
		(end 122.927618 -53.40477)
		(width 0.1778)
		(layer "F.Cu")
		(net "GND")
	)
	(segment
		(start 81.445862 -383.402586)
		(end 81.445862 -383.622296)
		(width 0.254)
		(layer "F.Cu")
		(net "GND")
	)
	(segment
		(start 127.305054 -54.17439)
		(end 126.689104 -54.17439)
		(width 0.4572)
		(layer "F.Cu")
		(net "GND")
	)
	(segment
		(start 352.198178 -395.0208)
		(end 351.506028 -394.831062)
		(width 0.254)
		(layer "F.Cu")
		(net "GND")
	)
	(segment
		(start 439.100214 -209.23504)
		(end 437.715914 -209.23504)
		(width 0.4572)
		(layer "F.Cu")
		(net "GND")
	)
	(segment
		(start 118.657878 -285.160466)
		(end 119.12473 -285.426404)
		(width 0.350012)
		(layer "F.Cu")
		(net "GND")
	)
	(segment
		(start 431.36693 -9.423654)
		(end 431.3682 -9.424924)
		(width 0.3556)
		(layer "F.Cu")
		(net "GND")
	)
	(segment
		(start 358.021128 -395.22273)
		(end 358.26446 -395.466062)
		(width 0.381)
		(layer "F.Cu")
		(net "GND")
	)
	(segment
		(start 325.408036 -246.370094)
		(end 324.75297 -246.370094)
		(width 0.350012)
		(layer "F.Cu")
		(net "GND")
	)
	(segment
		(start 72.662034 -7.217156)
		(end 72.660764 -7.215886)
		(width 0.3556)
		(layer "F.Cu")
		(net "GND")
	)
	(segment
		(start 353.137978 -234.220004)
		(end 352.671126 -233.954066)
		(width 0.350012)
		(layer "F.Cu")
		(net "GND")
	)
	(segment
		(start 409.050744 -142.414498)
		(end 409.050744 -142.009368)
		(width 0.381)
		(layer "F.Cu")
		(net "GND")
	)
	(segment
		(start 331.37602 -338.038948)
		(end 331.407008 -338.038948)
		(width 0.2286)
		(layer "F.Cu")
		(net "GND")
	)
	(segment
		(start 373.817896 -253.660148)
		(end 374.284748 -253.39421)
		(width 0.350012)
		(layer "F.Cu")
		(net "GND")
	)
	(segment
		(start 302.494696 -399.686272)
		(end 302.51781 -399.663158)
		(width 0.254)
		(layer "F.Cu")
		(net "GND")
	)
	(segment
		(start 309.39105 -398.542002)
		(end 308.87035 -398.542002)
		(width 0.254)
		(layer "F.Cu")
		(net "GND")
	)
	(segment
		(start 53.594 -434.82895)
		(end 53.594 -434.109114)
		(width 0.381)
		(layer "F.Cu")
		(net "GND")
	)
	(segment
		(start 335.577942 -264.100056)
		(end 335.11109 -264.365994)
		(width 0.350012)
		(layer "F.Cu")
		(net "GND")
	)
	(segment
		(start 138.397996 -285.160466)
		(end 138.864848 -285.426404)
		(width 0.350012)
		(layer "F.Cu")
		(net "GND")
	)
	(segment
		(start 388.217918 -265.720068)
		(end 388.68477 -265.986006)
		(width 0.350012)
		(layer "F.Cu")
		(net "GND")
	)
	(segment
		(start 240.163096 -291.011102)
		(end 239.893856 -290.741862)
		(width 0.4572)
		(layer "F.Cu")
		(net "GND")
	)
	(segment
		(start 341.387938 -243.13007)
		(end 340.921086 -242.864132)
		(width 0.350012)
		(layer "F.Cu")
		(net "GND")
	)
	(segment
		(start 365.828072 -244.750082)
		(end 366.294924 -244.484144)
		(width 0.350012)
		(layer "F.Cu")
		(net "GND")
	)
	(segment
		(start 350.31807 -237.460028)
		(end 349.851218 -237.19409)
		(width 0.350012)
		(layer "F.Cu")
		(net "GND")
	)
	(segment
		(start 377.577858 -243.940076)
		(end 378.04471 -243.674138)
		(width 0.350012)
		(layer "F.Cu")
		(net "GND")
	)
	(segment
		(start 109.728 -281.110436)
		(end 109.261148 -281.376374)
		(width 0.350012)
		(layer "F.Cu")
		(net "GND")
	)
	(segment
		(start 135.107934 -266.530328)
		(end 135.574786 -266.796266)
		(width 0.350012)
		(layer "F.Cu")
		(net "GND")
	)
	(segment
		(start 118.417848 -383.402586)
		(end 118.417848 -382.951482)
		(width 0.2032)
		(layer "F.Cu")
		(net "GND")
	)
	(segment
		(start 208.054956 -29.266896)
		(end 208.05521 -29.266642)
		(width 0.4572)
		(layer "F.Cu")
		(net "GND")
	)
	(segment
		(start 126.347982 -228.55047)
		(end 126.814834 -228.284532)
		(width 0.350012)
		(layer "F.Cu")
		(net "GND")
	)
	(segment
		(start 134.80796 -252.850396)
		(end 135.274812 -252.584458)
		(width 0.350012)
		(layer "F.Cu")
		(net "GND")
	)
	(segment
		(start 113.187988 -241.510312)
		(end 113.65484 -241.244374)
		(width 0.350012)
		(layer "F.Cu")
		(net "GND")
	)
	(segment
		(start 315.264292 -337.490054)
		(end 315.264292 -337.07324)
		(width 0.2286)
		(layer "F.Cu")
		(net "GND")
	)
	(segment
		(start 394.327888 -261.670038)
		(end 394.982954 -261.670038)
		(width 0.350012)
		(layer "F.Cu")
		(net "GND")
	)
	(segment
		(start 344.318844 -398.542002)
		(end 343.798144 -398.542002)
		(width 0.254)
		(layer "F.Cu")
		(net "GND")
	)
	(segment
		(start 104.318054 -25.183592)
		(end 103.99014 -24.855678)
		(width 0.381)
		(layer "F.Cu")
		(net "GND")
	)
	(segment
		(start 338.39785 -264.100056)
		(end 337.930998 -264.365994)
		(width 0.350012)
		(layer "F.Cu")
		(net "GND")
	)
	(segment
		(start 95.327978 -254.470408)
		(end 94.861126 -254.20447)
		(width 0.350012)
		(layer "F.Cu")
		(net "GND")
	)
	(segment
		(start 344.645488 -399.663158)
		(end 344.74404 -399.76171)
		(width 0.254)
		(layer "F.Cu")
		(net "GND")
	)
	(segment
		(start 119.362474 -384.617722)
		(end 119.97055 -384.617722)
		(width 0.254)
		(layer "F.Cu")
		(net "GND")
	)
	(segment
		(start 111.137954 -280.30043)
		(end 110.671102 -280.566368)
		(width 0.350012)
		(layer "F.Cu")
		(net "GND")
	)
	(segment
		(start 162.676586 -108.09605)
		(end 162.93846 -107.834176)
		(width 0.381)
		(layer "F.Cu")
		(net "GND")
	)
	(segment
		(start 36.795964 -230.485442)
		(end 35.411664 -230.485442)
		(width 0.4572)
		(layer "F.Cu")
		(net "GND")
	)
	(segment
		(start 20.346924 -11.26998)
		(end 20.345654 -10.16508)
		(width 0.3556)
		(layer "F.Cu")
		(net "GND")
	)
	(segment
		(start 129.16789 -249.610372)
		(end 129.634742 -249.344434)
		(width 0.350012)
		(layer "F.Cu")
		(net "GND")
	)
	(segment
		(start 372.707916 -264.910062)
		(end 373.174768 -265.176)
		(width 0.350012)
		(layer "F.Cu")
		(net "GND")
	)
	(segment
		(start 406.153112 -57.2135)
		(end 406.97658 -58.036968)
		(width 0.508)
		(layer "F.Cu")
		(net "GND")
	)
	(segment
		(start 309.717694 -391.784586)
		(end 309.717694 -392.004296)
		(width 0.254)
		(layer "F.Cu")
		(net "GND")
	)
	(segment
		(start 59.71794 -391.281158)
		(end 60.017914 -390.761474)
		(width 0.254)
		(layer "F.Cu")
		(net "GND")
	)
	(segment
		(start 316.23 -365.01705)
		(end 315.595 -365.01705)
		(width 0.381)
		(layer "F.Cu")
		(net "GND")
	)
	(segment
		(start 110.367826 -223.690434)
		(end 109.900974 -223.424496)
		(width 0.350012)
		(layer "F.Cu")
		(net "GND")
	)
	(segment
		(start 314.616338 -399.76171)
		(end 314.616338 -400.212814)
		(width 0.254)
		(layer "F.Cu")
		(net "GND")
	)
	(segment
		(start 139.507976 -254.470408)
		(end 139.974828 -254.20447)
		(width 0.350012)
		(layer "F.Cu")
		(net "GND")
	)
	(segment
		(start 394.027914 -244.750082)
		(end 394.68298 -244.750082)
		(width 0.350012)
		(layer "F.Cu")
		(net "GND")
	)
	(segment
		(start 330.108052 -231.789986)
		(end 329.6412 -231.524048)
		(width 0.350012)
		(layer "F.Cu")
		(net "GND")
	)
	(segment
		(start 428.318676 -354.20554)
		(end 428.287688 -354.20554)
		(width 0.2286)
		(layer "F.Cu")
		(net "GND")
	)
	(segment
		(start 94.217998 -293.260272)
		(end 93.751146 -293.52621)
		(width 0.350012)
		(layer "F.Cu")
		(net "GND")
	)
	(segment
		(start 85.757766 -273.820382)
		(end 85.290914 -274.08632)
		(width 0.350012)
		(layer "F.Cu")
		(net "GND")
	)
	(segment
		(start 343.56802 -264.910062)
		(end 343.101168 -265.176)
		(width 0.350012)
		(layer "F.Cu")
		(net "GND")
	)
	(segment
		(start 129.217928 -382.951482)
		(end 129.31648 -382.85293)
		(width 0.254)
		(layer "F.Cu")
		(net "GND")
	)
	(segment
		(start 53.717952 -391.281158)
		(end 54.017926 -390.761474)
		(width 0.254)
		(layer "F.Cu")
		(net "GND")
	)
	(segment
		(start 412.367984 -294.235124)
		(end 413.752284 -294.235124)
		(width 0.4572)
		(layer "F.Cu")
		(net "GND")
	)
	(segment
		(start 377.577858 -234.220004)
		(end 378.04471 -233.954066)
		(width 0.350012)
		(layer "F.Cu")
		(net "GND")
	)
	(segment
		(start 378.116592 -399.76171)
		(end 378.01804 -399.663158)
		(width 0.254)
		(layer "F.Cu")
		(net "GND")
	)
	(segment
		(start 346.557854 -243.940076)
		(end 346.091002 -243.674138)
		(width 0.350012)
		(layer "F.Cu")
		(net "GND")
	)
	(segment
		(start 93.44787 -246.370348)
		(end 92.981018 -246.10441)
		(width 0.350012)
		(layer "F.Cu")
		(net "GND")
	)
	(segment
		(start 102.378002 -232.600246)
		(end 101.91115 -232.334308)
		(width 0.350012)
		(layer "F.Cu")
		(net "GND")
	)
	(segment
		(start 418.356796 -8.320024)
		(end 418.356796 -9.423654)
		(width 0.3556)
		(layer "F.Cu")
		(net "GND")
	)
	(segment
		(start 122.117866 -222.880428)
		(end 122.584718 -222.61449)
		(width 0.350012)
		(layer "F.Cu")
		(net "GND")
	)
	(segment
		(start 151.298402 -384.617722)
		(end 151.245824 -383.92227)
		(width 0.254)
		(layer "F.Cu")
		(net "GND")
	)
	(segment
		(start 135.14832 -17.654016)
		(end 135.14832 -17.654778)
		(width 0.3556)
		(layer "F.Cu")
		(net "GND")
	)
	(segment
		(start 84.047838 -249.610372)
		(end 83.580986 -249.344434)
		(width 0.350012)
		(layer "F.Cu")
		(net "GND")
	)
	(segment
		(start 365.828072 -246.370094)
		(end 366.294924 -246.104156)
		(width 0.350012)
		(layer "F.Cu")
		(net "GND")
	)
	(segment
		(start 391.268458 -402.4757)
		(end 391.268458 -402.163788)
		(width 0.254)
		(layer "F.Cu")
		(net "GND")
	)
	(segment
		(start 416.468052 -293.384986)
		(end 415.083752 -293.384986)
		(width 0.4572)
		(layer "F.Cu")
		(net "GND")
	)
	(segment
		(start 115.067842 -236.650276)
		(end 115.534694 -236.384338)
		(width 0.350012)
		(layer "F.Cu")
		(net "GND")
	)
	(segment
		(start 82.645758 -383.402586)
		(end 82.645758 -382.951482)
		(width 0.254)
		(layer "F.Cu")
		(net "GND")
	)
	(segment
		(start 398.012412 -411.064456)
		(end 398.376394 -411.064456)
		(width 0.381)
		(layer "F.Cu")
		(net "GND")
	)
	(segment
		(start 365.828072 -239.890046)
		(end 366.294924 -239.624108)
		(width 0.350012)
		(layer "F.Cu")
		(net "GND")
	)
	(segment
		(start 365.187992 -266.530074)
		(end 365.654844 -266.796012)
		(width 0.350012)
		(layer "F.Cu")
		(net "GND")
	)
	(segment
		(start 407.890218 -392.999722)
		(end 408.498294 -392.999722)
		(width 0.254)
		(layer "F.Cu")
		(net "GND")
	)
	(segment
		(start 20.345654 -7.215124)
		(end 20.345654 -7.215886)
		(width 0.3556)
		(layer "F.Cu")
		(net "GND")
	)
	(segment
		(start 394.027914 -238.270034)
		(end 394.68298 -238.270034)
		(width 0.350012)
		(layer "F.Cu")
		(net "GND")
	)
	(segment
		(start 403.34565 -392.004296)
		(end 403.645624 -392.30427)
		(width 0.254)
		(layer "F.Cu")
		(net "GND")
	)
	(segment
		(start 380.86792 -231.789986)
		(end 381.334772 -231.524048)
		(width 0.350012)
		(layer "F.Cu")
		(net "GND")
	)
	(segment
		(start 92.037916 -240.700306)
		(end 91.571064 -240.434368)
		(width 0.350012)
		(layer "F.Cu")
		(net "GND")
	)
	(segment
		(start 377.577858 -240.700052)
		(end 378.04471 -240.434114)
		(width 0.350012)
		(layer "F.Cu")
		(net "GND")
	)
	(segment
		(start 76.184252 -402.814536)
		(end 77.212952 -402.814536)
		(width 0.381)
		(layer "F.Cu")
		(net "GND")
	)
	(segment
		(start 128.52781 -289.210242)
		(end 128.994662 -289.47618)
		(width 0.350012)
		(layer "F.Cu")
		(net "GND")
	)
	(segment
		(start 302.817784 -392.30427)
		(end 302.870362 -392.356848)
		(width 0.254)
		(layer "F.Cu")
		(net "GND")
	)
	(segment
		(start 396.679166 -76.055728)
		(end 397.387318 -76.055728)
		(width 0.2286)
		(layer "F.Cu")
		(net "GND")
	)
	(segment
		(start 416.545776 -391.784586)
		(end 416.545776 -392.004296)
		(width 0.254)
		(layer "F.Cu")
		(net "GND")
	)
	(segment
		(start 86.598252 -388.138924)
		(end 86.04631 -388.328662)
		(width 0.254)
		(layer "F.Cu")
		(net "GND")
	)
	(segment
		(start 201.352658 -116.673376)
		(end 202.502008 -116.673376)
		(width 0.4064)
		(layer "F.Cu")
		(net "GND")
	)
	(segment
		(start 132.81787 -383.402586)
		(end 132.916422 -383.304034)
		(width 0.254)
		(layer "F.Cu")
		(net "GND")
	)
	(segment
		(start 379.75794 -285.160212)
		(end 380.224792 -285.42615)
		(width 0.350012)
		(layer "F.Cu")
		(net "GND")
	)
	(segment
		(start 80.287876 -226.930458)
		(end 79.821024 -226.66452)
		(width 0.350012)
		(layer "F.Cu")
		(net "GND")
	)
	(segment
		(start 118.187978 -269.770352)
		(end 118.65483 -270.03629)
		(width 0.350012)
		(layer "F.Cu")
		(net "GND")
	)
	(segment
		(start 122.018044 -383.402586)
		(end 122.018044 -382.951482)
		(width 0.254)
		(layer "F.Cu")
		(net "GND")
	)
	(segment
		(start 408.841702 -162.974782)
		(end 408.59456 -162.72764)
		(width 0.381)
		(layer "F.Cu")
		(net "GND")
	)
	(segment
		(start 377.577858 -226.120198)
		(end 378.04471 -225.85426)
		(width 0.350012)
		(layer "F.Cu")
		(net "GND")
	)
	(segment
		(start 135.107934 -285.970472)
		(end 135.574786 -286.23641)
		(width 0.350012)
		(layer "F.Cu")
		(net "GND")
	)
	(segment
		(start 301.841408 -113.843308)
		(end 301.231808 -113.843308)
		(width 0.381)
		(layer "F.Cu")
		(net "GND")
	)
	(segment
		(start 119.118634 -58.868056)
		(end 119.728234 -58.868056)
		(width 0.4572)
		(layer "F.Cu")
		(net "GND")
	)
	(segment
		(start 447.167762 -422.514776)
		(end 446.729612 -422.514776)
		(width 0.1778)
		(layer "F.Cu")
		(net "GND")
	)
	(segment
		(start 386.97789 -250.420124)
		(end 387.444742 -250.154186)
		(width 0.350012)
		(layer "F.Cu")
		(net "GND")
	)
	(segment
		(start 151.181562 -44.585636)
		(end 152.318212 -44.585636)
		(width 0.3556)
		(layer "F.Cu")
		(net "GND")
	)
	(segment
		(start 43.66895 -434.594)
		(end 43.66895 -433.940712)
		(width 0.381)
		(layer "F.Cu")
		(net "GND")
	)
	(segment
		(start 335.108042 -269.770098)
		(end 334.64119 -270.036036)
		(width 0.350012)
		(layer "F.Cu")
		(net "GND")
	)
	(segment
		(start 338.868004 -271.39011)
		(end 338.401152 -271.656048)
		(width 0.350012)
		(layer "F.Cu")
		(net "GND")
	)
	(segment
		(start 381.638048 -272.200116)
		(end 382.1049 -272.466054)
		(width 0.350012)
		(layer "F.Cu")
		(net "GND")
	)
	(segment
		(start 94.217998 -272.20037)
		(end 93.751146 -272.466308)
		(width 0.350012)
		(layer "F.Cu")
		(net "GND")
	)
	(segment
		(start 138.397996 -290.020248)
		(end 138.864848 -290.286186)
		(width 0.350012)
		(layer "F.Cu")
		(net "GND")
	)
	(segment
		(start 386.03809 -255.28016)
		(end 386.504942 -255.014222)
		(width 0.350012)
		(layer "F.Cu")
		(net "GND")
	)
	(segment
		(start 95.13697 -340.240874)
		(end 95.20682 -340.171024)
		(width 0.381)
		(layer "F.Cu")
		(net "GND")
	)
	(segment
		(start 39.453312 -424.202098)
		(end 38.843712 -424.202098)
		(width 0.3556)
		(layer "F.Cu")
		(net "GND")
	)
	(segment
		(start 79.177896 -273.820382)
		(end 78.711044 -274.08632)
		(width 0.350012)
		(layer "F.Cu")
		(net "GND")
	)
	(segment
		(start 62.912752 -403.830536)
		(end 62.912752 -402.950426)
		(width 0.381)
		(layer "F.Cu")
		(net "GND")
	)
	(segment
		(start 100.497894 -250.420378)
		(end 100.031042 -250.15444)
		(width 0.350012)
		(layer "F.Cu")
		(net "GND")
	)
	(segment
		(start 350.78797 -231.789986)
		(end 350.321118 -231.524048)
		(width 0.350012)
		(layer "F.Cu")
		(net "GND")
	)
	(segment
		(start 416.644328 -399.76171)
		(end 416.545776 -399.663158)
		(width 0.254)
		(layer "F.Cu")
		(net "GND")
	)
	(segment
		(start 84.347812 -294.070278)
		(end 83.88096 -294.336216)
		(width 0.350012)
		(layer "F.Cu")
		(net "GND")
	)
	(segment
		(start 85.757766 -294.880284)
		(end 85.290914 -295.146222)
		(width 0.350012)
		(layer "F.Cu")
		(net "GND")
	)
	(segment
		(start 78.877922 -230.980234)
		(end 78.41107 -230.71455)
		(width 0.350012)
		(layer "F.Cu")
		(net "GND")
	)
	(segment
		(start 369.417854 -272.200116)
		(end 369.884706 -272.466054)
		(width 0.350012)
		(layer "F.Cu")
		(net "GND")
	)
	(segment
		(start 118.21795 -432.054)
		(end 117.475 -432.054)
		(width 0.381)
		(layer "F.Cu")
		(net "GND")
	)
	(segment
		(start 292.280086 -227.935028)
		(end 290.895786 -227.935028)
		(width 0.4572)
		(layer "F.Cu")
		(net "GND")
	)
	(segment
		(start 89.590118 -384.617722)
		(end 90.198448 -384.617722)
		(width 0.254)
		(layer "F.Cu")
		(net "GND")
	)
	(segment
		(start 350.31807 -240.700052)
		(end 349.851218 -240.434114)
		(width 0.350012)
		(layer "F.Cu")
		(net "GND")
	)
	(segment
		(start 340.790022 -392.999722)
		(end 341.398098 -392.999722)
		(width 0.254)
		(layer "F.Cu")
		(net "GND")
	)
	(segment
		(start 144.977866 -272.20037)
		(end 145.444718 -272.466308)
		(width 0.350012)
		(layer "F.Cu")
		(net "GND")
	)
	(segment
		(start 370.109242 -394.412978)
		(end 369.72113 -394.412978)
		(width 0.254)
		(layer "F.Cu")
		(net "GND")
	)
	(segment
		(start 97.579942 -399.888202)
		(end 97.452942 -400.015202)
		(width 0.3302)
		(layer "F.Cu")
		(net "GND")
	)
	(segment
		(start 89.047828 -289.210242)
		(end 88.580976 -289.47618)
		(width 0.350012)
		(layer "F.Cu")
		(net "GND")
	)
	(segment
		(start 134.80796 -235.030264)
		(end 135.274812 -234.764326)
		(width 0.350012)
		(layer "F.Cu")
		(net "GND")
	)
	(segment
		(start 137.457942 -293.260272)
		(end 137.924794 -293.52621)
		(width 0.350012)
		(layer "F.Cu")
		(net "GND")
	)
	(segment
		(start 330.375514 -140.414502)
		(end 330.375514 -140.826998)
		(width 0.254)
		(layer "F.Cu")
		(net "GND")
	)
	(segment
		(start 379.457966 -252.040136)
		(end 379.924818 -251.774198)
		(width 0.350012)
		(layer "F.Cu")
		(net "GND")
	)
	(segment
		(start 89.687908 -225.310446)
		(end 89.221056 -225.044508)
		(width 0.350012)
		(layer "F.Cu")
		(net "GND")
	)
	(segment
		(start 445.361822 -12.372848)
		(end 445.363092 -12.374118)
		(width 0.3556)
		(layer "F.Cu")
		(net "GND")
	)
	(segment
		(start 368.64798 -235.03001)
		(end 369.114832 -234.764072)
		(width 0.350012)
		(layer "F.Cu")
		(net "GND")
	)
	(segment
		(start 87.3379 -250.420378)
		(end 86.871048 -250.15444)
		(width 0.350012)
		(layer "F.Cu")
		(net "GND")
	)
	(segment
		(start 328.227944 -233.409998)
		(end 327.761092 -233.14406)
		(width 0.350012)
		(layer "F.Cu")
		(net "GND")
	)
	(segment
		(start 345.918028 -285.160212)
		(end 345.451176 -285.42615)
		(width 0.350012)
		(layer "F.Cu")
		(net "GND")
	)
	(segment
		(start 98.918014 -260.860286)
		(end 98.451162 -261.126224)
		(width 0.350012)
		(layer "F.Cu")
		(net "GND")
	)
	(segment
		(start 388.217918 -288.399982)
		(end 388.68477 -288.66592)
		(width 0.350012)
		(layer "F.Cu")
		(net "GND")
	)
	(segment
		(start 420.145718 -399.663158)
		(end 420.445692 -399.143474)
		(width 0.254)
		(layer "F.Cu")
		(net "GND")
	)
	(segment
		(start 394.327888 -284.350206)
		(end 394.982954 -284.350206)
		(width 0.350012)
		(layer "F.Cu")
		(net "GND")
	)
	(segment
		(start 380.091188 -398.542002)
		(end 379.570488 -398.542002)
		(width 0.254)
		(layer "F.Cu")
		(net "GND")
	)
	(segment
		(start 105.222548 -387.0579)
		(end 105.222548 -387.206998)
		(width 0.254)
		(layer "F.Cu")
		(net "GND")
	)
	(segment
		(start 402.498306 -392.356848)
		(end 402.498306 -392.999722)
		(width 0.254)
		(layer "F.Cu")
		(net "GND")
	)
	(segment
		(start 124.937774 -243.94033)
		(end 125.404626 -243.674392)
		(width 0.350012)
		(layer "F.Cu")
		(net "GND")
	)
	(segment
		(start 273.092164 -210.085178)
		(end 274.476464 -210.085178)
		(width 0.4572)
		(layer "F.Cu")
		(net "GND")
	)
	(segment
		(start 403.846792 -11.26998)
		(end 403.846792 -10.16635)
		(width 0.3556)
		(layer "F.Cu")
		(net "GND")
	)
	(segment
		(start 340.277958 -294.88003)
		(end 339.811106 -295.145968)
		(width 0.350012)
		(layer "F.Cu")
		(net "GND")
	)
	(segment
		(start 347.797882 -285.160212)
		(end 347.33103 -285.42615)
		(width 0.350012)
		(layer "F.Cu")
		(net "GND")
	)
	(segment
		(start 413.766 -100.60305)
		(end 414.255458 -101.092508)
		(width 0.4572)
		(layer "F.Cu")
		(net "GND")
	)
	(segment
		(start 61.016642 -391.37971)
		(end 61.016642 -391.830814)
		(width 0.254)
		(layer "F.Cu")
		(net "GND")
	)
	(segment
		(start 273.092164 -315.485018)
		(end 274.476464 -315.485018)
		(width 0.4572)
		(layer "F.Cu")
		(net "GND")
	)
	(segment
		(start 90.927936 -269.770352)
		(end 90.461084 -270.03629)
		(width 0.350012)
		(layer "F.Cu")
		(net "GND")
	)
	(segment
		(start 162.90417 -428.02048)
		(end 162.378136 -427.494446)
		(width 0.3048)
		(layer "F.Cu")
		(net "GND")
	)
	(segment
		(start 206.248 -237.285276)
		(end 204.8637 -237.285276)
		(width 0.4572)
		(layer "F.Cu")
		(net "GND")
	)
	(segment
		(start 416.898328 -398.542002)
		(end 416.218878 -398.542002)
		(width 0.254)
		(layer "F.Cu")
		(net "GND")
	)
	(segment
		(start 100.497894 -232.600246)
		(end 100.031042 -232.334308)
		(width 0.350012)
		(layer "F.Cu")
		(net "GND")
	)
	(segment
		(start 9.332468 -138.13917)
		(end 8.447278 -137.25398)
		(width 0.3556)
		(layer "F.Cu")
		(net "GND")
	)
	(segment
		(start 143.267938 -226.930458)
		(end 143.73479 -226.66452)
		(width 0.350012)
		(layer "F.Cu")
		(net "GND")
	)
	(segment
		(start 327.117964 -281.920188)
		(end 326.651112 -282.186126)
		(width 0.350012)
		(layer "F.Cu")
		(net "GND")
	)
	(segment
		(start 370.357908 -273.820128)
		(end 370.82476 -274.086066)
		(width 0.350012)
		(layer "F.Cu")
		(net "GND")
	)
	(segment
		(start 98.617786 -240.700306)
		(end 98.150934 -240.434368)
		(width 0.350012)
		(layer "F.Cu")
		(net "GND")
	)
	(segment
		(start 323.619876 -337.482942)
		(end 323.619876 -337.066128)
		(width 0.2286)
		(layer "F.Cu")
		(net "GND")
	)
	(segment
		(start 136.217914 -229.360476)
		(end 136.684766 -229.094538)
		(width 0.350012)
		(layer "F.Cu")
		(net "GND")
	)
	(segment
		(start 87.798402 -384.617722)
		(end 87.745824 -383.92227)
		(width 0.254)
		(layer "F.Cu")
		(net "GND")
	)
	(segment
		(start 127.117856 -286.780478)
		(end 127.584708 -287.046162)
		(width 0.350012)
		(layer "F.Cu")
		(net "GND")
	)
	(segment
		(start 144.977866 -277.060406)
		(end 145.444718 -277.326344)
		(width 0.350012)
		(layer "F.Cu")
		(net "GND")
	)
	(segment
		(start 103.99014 -20.69084)
		(end 104.596438 -20.084542)
		(width 0.381)
		(layer "F.Cu")
		(net "GND")
	)
	(segment
		(start 51.884072 -209.235294)
		(end 50.499772 -209.235294)
		(width 0.4572)
		(layer "F.Cu")
		(net "GND")
	)
	(segment
		(start 36.795964 -209.235294)
		(end 35.411664 -209.235294)
		(width 0.4572)
		(layer "F.Cu")
		(net "GND")
	)
	(segment
		(start 339.654134 -339.40877)
		(end 339.654134 -340.039706)
		(width 0.381)
		(layer "F.Cu")
		(net "GND")
	)
	(segment
		(start 146.145758 -383.402586)
		(end 146.145758 -383.622296)
		(width 0.254)
		(layer "F.Cu")
		(net "GND")
	)
	(segment
		(start 384.11658 -399.76171)
		(end 384.11658 -400.212814)
		(width 0.254)
		(layer "F.Cu")
		(net "GND")
	)
	(segment
		(start 61.862462 -384.617722)
		(end 61.270642 -384.617722)
		(width 0.254)
		(layer "F.Cu")
		(net "GND")
	)
	(segment
		(start 27.037792 -430.894744)
		(end 26.430478 -431.502058)
		(width 0.3556)
		(layer "F.Cu")
		(net "GND")
	)
	(segment
		(start 377.577858 -239.08004)
		(end 378.04471 -238.814102)
		(width 0.350012)
		(layer "F.Cu")
		(net "GND")
	)
	(segment
		(start 343.268046 -225.310192)
		(end 342.801194 -225.044254)
		(width 0.350012)
		(layer "F.Cu")
		(net "GND")
	)
	(segment
		(start 99.015296 -422.83253)
		(end 99.015296 -423.44848)
		(width 0.381)
		(layer "F.Cu")
		(net "GND")
	)
	(segment
		(start 365.828072 -247.990106)
		(end 366.294924 -247.724168)
		(width 0.350012)
		(layer "F.Cu")
		(net "GND")
	)
	(segment
		(start 320.171318 -412.212536)
		(end 320.171318 -411.313122)
		(width 0.381)
		(layer "F.Cu")
		(net "GND")
	)
	(segment
		(start 372.018052 -391.784586)
		(end 372.018052 -392.004296)
		(width 0.254)
		(layer "F.Cu")
		(net "GND")
	)
	(segment
		(start 102.677976 -283.540454)
		(end 102.211124 -283.806392)
		(width 0.350012)
		(layer "F.Cu")
		(net "GND")
	)
	(segment
		(start 314.178188 -394.831062)
		(end 313.670442 -395.0208)
		(width 0.254)
		(layer "F.Cu")
		(net "GND")
	)
	(segment
		(start 108.09097 -23.371556)
		(end 108.09097 -20.831556)
		(width 0.381)
		(layer "F.Cu")
		(net "GND")
	)
	(segment
		(start 357.53421 -326.58431)
		(end 357.53421 -326.037702)
		(width 0.4572)
		(layer "F.Cu")
		(net "GND")
	)
	(segment
		(start 58.666888 -7.217156)
		(end 58.666888 -8.320024)
		(width 0.3556)
		(layer "F.Cu")
		(net "GND")
	)
	(segment
		(start 92.245688 -383.402586)
		(end 92.245688 -382.951482)
		(width 0.254)
		(layer "F.Cu")
		(net "GND")
	)
	(segment
		(start 29.252164 -237.285276)
		(end 27.867864 -237.285276)
		(width 0.4572)
		(layer "F.Cu")
		(net "GND")
	)
	(segment
		(start 96.097852 -294.880284)
		(end 95.631 -295.146222)
		(width 0.350012)
		(layer "F.Cu")
		(net "GND")
	)
	(segment
		(start 135.107934 -268.15034)
		(end 135.574786 -268.416278)
		(width 0.350012)
		(layer "F.Cu")
		(net "GND")
	)
	(segment
		(start 93.159834 -33.06191)
		(end 93.159834 -32.42691)
		(width 0.3556)
		(layer "F.Cu")
		(net "GND")
	)
	(segment
		(start 87.637874 -264.10031)
		(end 87.171022 -264.366248)
		(width 0.350012)
		(layer "F.Cu")
		(net "GND")
	)
	(segment
		(start 384.927856 -269.770098)
		(end 385.394708 -270.036036)
		(width 0.350012)
		(layer "F.Cu")
		(net "GND")
	)
	(segment
		(start 123.997974 -243.94033)
		(end 124.464826 -243.674392)
		(width 0.350012)
		(layer "F.Cu")
		(net "GND")
	)
	(segment
		(start 86.397846 -222.880428)
		(end 86.397846 -223.40697)
		(width 0.350012)
		(layer "F.Cu")
		(net "GND")
	)
	(segment
		(start 431.3682 -12.374118)
		(end 431.36693 -12.372848)
		(width 0.3556)
		(layer "F.Cu")
		(net "GND")
	)
	(segment
		(start 353.437952 -270.580104)
		(end 352.9711 -270.846042)
		(width 0.350012)
		(layer "F.Cu")
		(net "GND")
	)
	(segment
		(start 312.216292 -400.212814)
		(end 312.216292 -399.76171)
		(width 0.254)
		(layer "F.Cu")
		(net "GND")
	)
	(segment
		(start 330.108052 -241.510058)
		(end 329.6412 -241.24412)
		(width 0.350012)
		(layer "F.Cu")
		(net "GND")
	)
	(segment
		(start 115.537996 -237.460282)
		(end 116.004848 -237.194344)
		(width 0.350012)
		(layer "F.Cu")
		(net "GND")
	)
	(segment
		(start 118.607078 -166.66591)
		(end 118.834916 -166.893748)
		(width 0.381)
		(layer "F.Cu")
		(net "GND")
	)
	(segment
		(start 376.938032 -293.260018)
		(end 377.404884 -293.525956)
		(width 0.350012)
		(layer "F.Cu")
		(net "GND")
	)
	(segment
		(start 148.34616 -388.328662)
		(end 147.698206 -388.138924)
		(width 0.254)
		(layer "F.Cu")
		(net "GND")
	)
	(segment
		(start 77.212952 -402.814536)
		(end 78.228952 -403.830536)
		(width 0.381)
		(layer "F.Cu")
		(net "GND")
	)
	(segment
		(start 120.817894 -391.281158)
		(end 121.117868 -390.761474)
		(width 0.254)
		(layer "F.Cu")
		(net "GND")
	)
	(segment
		(start 178.69408 -31.013908)
		(end 178.82108 -31.140908)
		(width 0.254)
		(layer "F.Cu")
		(net "GND")
	)
	(segment
		(start 125.877828 -243.94033)
		(end 126.34468 -243.674392)
		(width 0.350012)
		(layer "F.Cu")
		(net "GND")
	)
	(segment
		(start 391.03808 -267.34008)
		(end 391.504678 -267.606018)
		(width 0.350012)
		(layer "F.Cu")
		(net "GND")
	)
	(segment
		(start 105.967784 -277.870412)
		(end 105.500932 -278.13635)
		(width 0.350012)
		(layer "F.Cu")
		(net "GND")
	)
	(segment
		(start 450.088 -228.785166)
		(end 451.4723 -228.785166)
		(width 0.4572)
		(layer "F.Cu")
		(net "GND")
	)
	(segment
		(start 322.31457 -393.59332)
		(end 322.834254 -394.113004)
		(width 0.254)
		(layer "F.Cu")
		(net "GND")
	)
	(segment
		(start 330.108052 -256.090166)
		(end 329.6412 -255.824228)
		(width 0.350012)
		(layer "F.Cu")
		(net "GND")
	)
	(segment
		(start 381.167894 -277.870158)
		(end 381.634746 -278.136096)
		(width 0.350012)
		(layer "F.Cu")
		(net "GND")
	)
	(segment
		(start 126.22911 -27.463496)
		(end 125.68174 -26.916126)
		(width 0.3556)
		(layer "F.Cu")
		(net "GND")
	)
	(segment
		(start 87.637874 -278.680418)
		(end 87.171022 -278.946356)
		(width 0.350012)
		(layer "F.Cu")
		(net "GND")
	)
	(segment
		(start 335.148682 -398.613122)
		(end 335.148682 -398.946624)
		(width 0.254)
		(layer "F.Cu")
		(net "GND")
	)
	(segment
		(start 143.098012 -294.880284)
		(end 143.56461 -295.146222)
		(width 0.350012)
		(layer "F.Cu")
		(net "GND")
	)
	(segment
		(start 77.467968 -244.750336)
		(end 76.812902 -244.750336)
		(width 0.350012)
		(layer "F.Cu")
		(net "GND")
	)
	(segment
		(start 353.918774 -398.542002)
		(end 354.598224 -398.542002)
		(width 0.254)
		(layer "F.Cu")
		(net "GND")
	)
	(segment
		(start 376.467878 -285.970218)
		(end 376.93473 -286.236156)
		(width 0.350012)
		(layer "F.Cu")
		(net "GND")
	)
	(segment
		(start 105.19791 -232.600246)
		(end 104.731058 -232.334308)
		(width 0.350012)
		(layer "F.Cu")
		(net "GND")
	)
	(segment
		(start 134.23646 -394.08608)
		(end 134.23138 -394.081)
		(width 0.3048)
		(layer "F.Cu")
		(net "GND")
	)
	(segment
		(start 375.057924 -280.300176)
		(end 375.524776 -280.566114)
		(width 0.350012)
		(layer "F.Cu")
		(net "GND")
	)
	(segment
		(start 381.167894 -279.49017)
		(end 381.634746 -279.756108)
		(width 0.350012)
		(layer "F.Cu")
		(net "GND")
	)
	(segment
		(start 302.870362 -392.999722)
		(end 303.462182 -392.999722)
		(width 0.254)
		(layer "F.Cu")
		(net "GND")
	)
	(segment
		(start 332.28788 -266.530074)
		(end 331.821028 -266.796012)
		(width 0.350012)
		(layer "F.Cu")
		(net "GND")
	)
	(segment
		(start 406.945592 -391.784586)
		(end 406.945592 -391.333482)
		(width 0.2032)
		(layer "F.Cu")
		(net "GND")
	)
	(segment
		(start 134.80796 -223.690434)
		(end 135.274812 -223.424496)
		(width 0.350012)
		(layer "F.Cu")
		(net "GND")
	)
	(segment
		(start 95.627952 -269.770352)
		(end 95.1611 -270.03629)
		(width 0.350012)
		(layer "F.Cu")
		(net "GND")
	)
	(segment
		(start 401.209764 -396.813024)
		(end 400.732752 -396.67815)
		(width 0.254)
		(layer "F.Cu")
		(net "GND")
	)
	(segment
		(start 176.322736 -92.493084)
		(end 176.49698 -92.493084)
		(width 0.381)
		(layer "F.Cu")
		(net "GND")
	)
	(segment
		(start 176.072038 -227.935282)
		(end 174.687738 -227.935282)
		(width 0.4572)
		(layer "F.Cu")
		(net "GND")
	)
	(segment
		(start 425.96689 -9.423654)
		(end 425.96816 -9.424924)
		(width 0.3556)
		(layer "F.Cu")
		(net "GND")
	)
	(segment
		(start 349.67799 -281.920188)
		(end 349.211138 -282.186126)
		(width 0.350012)
		(layer "F.Cu")
		(net "GND")
	)
	(segment
		(start 109.427772 -251.230384)
		(end 108.961174 -250.964446)
		(width 0.350012)
		(layer "F.Cu")
		(net "GND")
	)
	(segment
		(start 365.657892 -291.640006)
		(end 366.124744 -291.905944)
		(width 0.350012)
		(layer "F.Cu")
		(net "GND")
	)
	(segment
		(start 354.598224 -398.542002)
		(end 355.272848 -398.542002)
		(width 0.254)
		(layer "F.Cu")
		(net "GND")
	)
	(segment
		(start 118.770654 -384.617722)
		(end 118.718076 -383.92227)
		(width 0.254)
		(layer "F.Cu")
		(net "GND")
	)
	(segment
		(start 95.327978 -252.850396)
		(end 94.861126 -252.584458)
		(width 0.350012)
		(layer "F.Cu")
		(net "GND")
	)
	(segment
		(start 76.105512 -40.310308)
		(end 76.104496 -40.311324)
		(width 0.4572)
		(layer "F.Cu")
		(net "GND")
	)
	(segment
		(start 94.645734 -383.622296)
		(end 94.945708 -383.92227)
		(width 0.254)
		(layer "F.Cu")
		(net "GND")
	)
	(segment
		(start 97.919032 -390.160002)
		(end 98.598482 -390.160002)
		(width 0.254)
		(layer "F.Cu")
		(net "GND")
	)
	(segment
		(start 373.817896 -232.599992)
		(end 374.284748 -232.334054)
		(width 0.350012)
		(layer "F.Cu")
		(net "GND")
	)
	(segment
		(start 125.617986 -382.951482)
		(end 125.716538 -382.85293)
		(width 0.254)
		(layer "F.Cu")
		(net "GND")
	)
	(segment
		(start 392.61796 -256.900172)
		(end 393.084812 -256.634234)
		(width 0.350012)
		(layer "F.Cu")
		(net "GND")
	)
	(segment
		(start 126.817882 -242.320318)
		(end 127.284734 -242.05438)
		(width 0.350012)
		(layer "F.Cu")
		(net "GND")
	)
	(segment
		(start 105.44556 -64.55791)
		(end 104.82961 -64.55791)
		(width 0.381)
		(layer "F.Cu")
		(net "GND")
	)
	(segment
		(start 370.057934 -240.700052)
		(end 370.524786 -240.434114)
		(width 0.350012)
		(layer "F.Cu")
		(net "GND")
	)
	(segment
		(start 353.989894 -392.999722)
		(end 354.628958 -392.999722)
		(width 0.254)
		(layer "F.Cu")
		(net "GND")
	)
	(segment
		(start 269.648178 -312.084974)
		(end 268.263878 -312.084974)
		(width 0.4572)
		(layer "F.Cu")
		(net "GND")
	)
	(segment
		(start 386.091176 -398.542002)
		(end 385.570476 -398.542002)
		(width 0.254)
		(layer "F.Cu")
		(net "GND")
	)
	(segment
		(start 22.147022 -7.217156)
		(end 22.147022 -8.320024)
		(width 0.3556)
		(layer "F.Cu")
		(net "GND")
	)
	(segment
		(start 398.376394 -411.064456)
		(end 399.524474 -412.212536)
		(width 0.381)
		(layer "F.Cu")
		(net "GND")
	)
	(segment
		(start 403.845522 -7.215124)
		(end 403.845522 -7.215886)
		(width 0.3556)
		(layer "F.Cu")
		(net "GND")
	)
	(segment
		(start 108.317792 -285.160466)
		(end 107.85094 -285.426404)
		(width 0.350012)
		(layer "F.Cu")
		(net "GND")
	)
	(segment
		(start 51.465734 -7.215886)
		(end 51.467004 -7.217156)
		(width 0.3556)
		(layer "F.Cu")
		(net "GND")
	)
	(segment
		(start 157.89021 -384.617722)
		(end 157.29839 -384.617722)
		(width 0.254)
		(layer "F.Cu")
		(net "GND")
	)
	(segment
		(start 121.94794 -261.670292)
		(end 122.414792 -261.93623)
		(width 0.350012)
		(layer "F.Cu")
		(net "GND")
	)
	(segment
		(start 85.457792 -250.420378)
		(end 84.99094 -250.15444)
		(width 0.350012)
		(layer "F.Cu")
		(net "GND")
	)
	(segment
		(start 390.334754 -412.212536)
		(end 390.334754 -411.305502)
		(width 0.381)
		(layer "F.Cu")
		(net "GND")
	)
	(segment
		(start 190.721996 -107.452922)
		(end 191.111886 -107.063032)
		(width 0.254)
		(layer "F.Cu")
		(net "GND")
	)
	(segment
		(start 299.82414 -211.784946)
		(end 298.43984 -211.784946)
		(width 0.4572)
		(layer "F.Cu")
		(net "GND")
	)
	(segment
		(start 392.490706 -180.665882)
		(end 392.237722 -180.918866)
		(width 0.2286)
		(layer "F.Cu")
		(net "GND")
	)
	(segment
		(start 391.208006 -256.090166)
		(end 391.674858 -255.824228)
		(width 0.350012)
		(layer "F.Cu")
		(net "GND")
	)
	(segment
		(start 156.09824 -390.160002)
		(end 156.045662 -390.761474)
		(width 0.254)
		(layer "F.Cu")
		(net "GND")
	)
	(segment
		(start 138.397996 -270.580358)
		(end 138.864848 -270.846296)
		(width 0.350012)
		(layer "F.Cu")
		(net "GND")
	)
	(segment
		(start 144.977866 -291.64026)
		(end 145.444718 -291.906198)
		(width 0.350012)
		(layer "F.Cu")
		(net "GND")
	)
	(segment
		(start 58.665618 -7.215124)
		(end 58.665618 -7.215886)
		(width 0.3556)
		(layer "F.Cu")
		(net "GND")
	)
	(segment
		(start 86.04631 -388.328662)
		(end 85.398356 -388.138924)
		(width 0.254)
		(layer "F.Cu")
		(net "GND")
	)
	(segment
		(start 171.97197 -303.585372)
		(end 173.35627 -303.585372)
		(width 0.4572)
		(layer "F.Cu")
		(net "GND")
	)
	(segment
		(start 170.594274 -429.459644)
		(end 170.255184 -429.798734)
		(width 0.381)
		(layer "F.Cu")
		(net "GND")
	)
	(segment
		(start 228.481128 -291.011102)
		(end 228.783642 -291.224462)
		(width 0.4572)
		(layer "F.Cu")
		(net "GND")
	)
	(segment
		(start 164.427916 -294.235378)
		(end 165.812216 -294.235378)
		(width 0.4572)
		(layer "F.Cu")
		(net "GND")
	)
	(segment
		(start 50.978562 -386.449062)
		(end 50.470562 -386.6388)
		(width 0.254)
		(layer "F.Cu")
		(net "GND")
	)
	(segment
		(start 123.52782 -243.130324)
		(end 123.994672 -242.864386)
		(width 0.350012)
		(layer "F.Cu")
		(net "GND")
	)
	(segment
		(start 325.408036 -230.169974)
		(end 324.75297 -230.169974)
		(width 0.350012)
		(layer "F.Cu")
		(net "GND")
	)
	(segment
		(start 338.56803 -247.990106)
		(end 338.101178 -247.724168)
		(width 0.350012)
		(layer "F.Cu")
		(net "GND")
	)
	(segment
		(start 82.467958 -284.35046)
		(end 82.001106 -284.616398)
		(width 0.350012)
		(layer "F.Cu")
		(net "GND")
	)
	(segment
		(start 66.834512 -388.13105)
		(end 66.534538 -388.431024)
		(width 0.254)
		(layer "F.Cu")
		(net "GND")
	)
	(segment
		(start 394.327888 -269.770098)
		(end 394.982954 -269.770098)
		(width 0.350012)
		(layer "F.Cu")
		(net "GND")
	)
	(segment
		(start 382.748028 -238.270034)
		(end 383.21488 -238.004096)
		(width 0.350012)
		(layer "F.Cu")
		(net "GND")
	)
	(segment
		(start 105.497884 -275.440394)
		(end 105.031032 -275.706332)
		(width 0.350012)
		(layer "F.Cu")
		(net "GND")
	)
	(segment
		(start 326.81799 -255.28016)
		(end 326.351138 -255.014222)
		(width 0.350012)
		(layer "F.Cu")
		(net "GND")
	)
	(segment
		(start 315.717682 -391.784586)
		(end 315.717682 -392.004296)
		(width 0.254)
		(layer "F.Cu")
		(net "GND")
	)
	(segment
		(start 136.687814 -231.79024)
		(end 137.154666 -231.524302)
		(width 0.350012)
		(layer "F.Cu")
		(net "GND")
	)
	(segment
		(start 141.687804 -263.290304)
		(end 142.154656 -263.556242)
		(width 0.350012)
		(layer "F.Cu")
		(net "GND")
	)
	(segment
		(start 395.654784 -390.652)
		(end 396.123668 -390.652)
		(width 0.254)
		(layer "F.Cu")
		(net "GND")
	)
	(segment
		(start 360.957876 -288.399982)
		(end 361.424728 -288.66592)
		(width 0.350012)
		(layer "F.Cu")
		(net "GND")
	)
	(segment
		(start 105.497884 -272.20037)
		(end 105.031032 -272.466308)
		(width 0.350012)
		(layer "F.Cu")
		(net "GND")
	)
	(segment
		(start 83.557364 -138.562334)
		(end 83.557364 -137.925048)
		(width 0.4572)
		(layer "F.Cu")
		(net "GND")
	)
	(segment
		(start 120.707912 -249.610372)
		(end 121.174764 -249.344434)
		(width 0.350012)
		(layer "F.Cu")
		(net "GND")
	)
	(segment
		(start 391.03808 -294.88003)
		(end 391.504678 -295.145968)
		(width 0.350012)
		(layer "F.Cu")
		(net "GND")
	)
	(segment
		(start 335.577942 -294.88003)
		(end 335.11109 -295.145968)
		(width 0.350012)
		(layer "F.Cu")
		(net "GND")
	)
	(segment
		(start 100.327968 -289.210242)
		(end 99.861116 -289.47618)
		(width 0.350012)
		(layer "F.Cu")
		(net "GND")
	)
	(segment
		(start 425.96689 -10.16635)
		(end 425.96562 -10.16508)
		(width 0.3556)
		(layer "F.Cu")
		(net "GND")
	)
	(segment
		(start 374.11787 -267.34008)
		(end 374.584722 -267.606018)
		(width 0.350012)
		(layer "F.Cu")
		(net "GND")
	)
	(segment
		(start 278.254206 -434.655976)
		(end 278.254206 -433.963826)
		(width 0.4318)
		(layer "F.Cu")
		(net "GND")
	)
	(segment
		(start 387.748018 -264.910062)
		(end 388.21487 -265.176)
		(width 0.350012)
		(layer "F.Cu")
		(net "GND")
	)
	(segment
		(start 143.098012 -273.820382)
		(end 143.56461 -274.08632)
		(width 0.350012)
		(layer "F.Cu")
		(net "GND")
	)
	(segment
		(start 40.256968 -12.372848)
		(end 40.256968 -11.26998)
		(width 0.3556)
		(layer "F.Cu")
		(net "GND")
	)
	(segment
		(start 144.977866 -273.820382)
		(end 145.444718 -274.08632)
		(width 0.350012)
		(layer "F.Cu")
		(net "GND")
	)
	(segment
		(start 415.444178 -400.212814)
		(end 415.444178 -399.76171)
		(width 0.254)
		(layer "F.Cu")
		(net "GND")
	)
	(segment
		(start 422.819576 -395.451076)
		(end 422.104566 -395.451076)
		(width 0.254)
		(layer "F.Cu")
		(net "GND")
	)
	(segment
		(start 126.347982 -252.850396)
		(end 126.814834 -252.584458)
		(width 0.350012)
		(layer "F.Cu")
		(net "GND")
	)
	(segment
		(start 98.629216 -384.617722)
		(end 98.629216 -384.005836)
		(width 0.254)
		(layer "F.Cu")
		(net "GND")
	)
	(segment
		(start 371.467888 -247.990106)
		(end 371.93474 -247.724168)
		(width 0.350012)
		(layer "F.Cu")
		(net "GND")
	)
	(segment
		(start 122.318018 -390.761474)
		(end 122.370596 -390.160002)
		(width 0.254)
		(layer "F.Cu")
		(net "GND")
	)
	(segment
		(start 325.408036 -226.930204)
		(end 324.941184 -226.664266)
		(width 0.350012)
		(layer "F.Cu")
		(net "GND")
	)
	(segment
		(start 239.368076 -293.654226)
		(end 239.98428 -293.654226)
		(width 0.4572)
		(layer "F.Cu")
		(net "GND")
	)
	(segment
		(start 340.198202 -396.520924)
		(end 339.646006 -396.710662)
		(width 0.254)
		(layer "F.Cu")
		(net "GND")
	)
	(segment
		(start 335.577942 -288.399982)
		(end 335.11109 -288.66592)
		(width 0.350012)
		(layer "F.Cu")
		(net "GND")
	)
	(segment
		(start 87.167974 -264.910316)
		(end 86.701122 -265.176254)
		(width 0.350012)
		(layer "F.Cu")
		(net "GND")
	)
	(segment
		(start 380.86792 -236.650022)
		(end 381.334772 -236.384084)
		(width 0.350012)
		(layer "F.Cu")
		(net "GND")
	)
	(segment
		(start 95.627952 -279.490424)
		(end 95.1611 -279.756362)
		(width 0.350012)
		(layer "F.Cu")
		(net "GND")
	)
	(segment
		(start 118.657878 -265.720322)
		(end 119.12473 -265.98626)
		(width 0.350012)
		(layer "F.Cu")
		(net "GND")
	)
	(segment
		(start 117.570504 -390.160002)
		(end 116.891308 -390.160002)
		(width 0.254)
		(layer "F.Cu")
		(net "GND")
	)
	(segment
		(start 392.917934 -288.399982)
		(end 393.384786 -288.66592)
		(width 0.350012)
		(layer "F.Cu")
		(net "GND")
	)
	(segment
		(start 396.258796 -411.15615)
		(end 395.20241 -412.212536)
		(width 0.381)
		(layer "F.Cu")
		(net "GND")
	)
	(segment
		(start 337.544156 -399.76171)
		(end 337.445604 -399.663158)
		(width 0.254)
		(layer "F.Cu")
		(net "GND")
	)
	(segment
		(start 130.407918 -294.070278)
		(end 130.87477 -294.336216)
		(width 0.350012)
		(layer "F.Cu")
		(net "GND")
	)
	(segment
		(start 384.37058 -398.542002)
		(end 384.318002 -399.143474)
		(width 0.254)
		(layer "F.Cu")
		(net "GND")
	)
	(segment
		(start 164.427916 -278.085296)
		(end 165.812216 -278.085296)
		(width 0.4572)
		(layer "F.Cu")
		(net "GND")
	)
	(segment
		(start 338.868004 -261.670038)
		(end 338.401152 -261.935976)
		(width 0.350012)
		(layer "F.Cu")
		(net "GND")
	)
	(segment
		(start 352.497898 -294.88003)
		(end 352.031046 -295.145968)
		(width 0.350012)
		(layer "F.Cu")
		(net "GND")
	)
	(segment
		(start 8.343138 -136.55421)
		(end 8.447278 -136.65835)
		(width 0.3556)
		(layer "F.Cu")
		(net "GND")
	)
	(segment
		(start 87.3379 -229.360476)
		(end 86.871048 -229.094538)
		(width 0.350012)
		(layer "F.Cu")
		(net "GND")
	)
	(segment
		(start 351.645982 -396.710662)
		(end 350.998028 -396.520924)
		(width 0.254)
		(layer "F.Cu")
		(net "GND")
	)
	(segment
		(start 381.638048 -285.160212)
		(end 382.1049 -285.42615)
		(width 0.350012)
		(layer "F.Cu")
		(net "GND")
	)
	(segment
		(start 369.417854 -278.680164)
		(end 369.884706 -278.946102)
		(width 0.350012)
		(layer "F.Cu")
		(net "GND")
	)
	(segment
		(start 53.267102 -9.423654)
		(end 53.268372 -9.424924)
		(width 0.3556)
		(layer "F.Cu")
		(net "GND")
	)
	(segment
		(start 338.39785 -285.160212)
		(end 337.930998 -285.42615)
		(width 0.350012)
		(layer "F.Cu")
		(net "GND")
	)
	(segment
		(start 355.018086 -226.120198)
		(end 354.551234 -225.85426)
		(width 0.350012)
		(layer "F.Cu")
		(net "GND")
	)
	(segment
		(start 17.445482 -107.631484)
		(end 17.422368 -107.60837)
		(width 0.3556)
		(layer "F.Cu")
		(net "GND")
	)
	(segment
		(start 115.83797 -277.060406)
		(end 116.304822 -277.326344)
		(width 0.350012)
		(layer "F.Cu")
		(net "GND")
	)
	(segment
		(start 353.907852 -282.730194)
		(end 353.441 -282.996132)
		(width 0.350012)
		(layer "F.Cu")
		(net "GND")
	)
	(segment
		(start 353.907852 -284.350206)
		(end 353.441 -284.616144)
		(width 0.350012)
		(layer "F.Cu")
		(net "GND")
	)
	(segment
		(start 176.072038 -314.635388)
		(end 174.687738 -314.635388)
		(width 0.4572)
		(layer "F.Cu")
		(net "GND")
	)
	(segment
		(start 6.829298 -136.48817)
		(end 6.829298 -137.61847)
		(width 0.3556)
		(layer "F.Cu")
		(net "GND")
	)
	(segment
		(start 79.14894 -384.86715)
		(end 79.398368 -384.617722)
		(width 0.254)
		(layer "F.Cu")
		(net "GND")
	)
	(segment
		(start 423.740072 -424.217846)
		(end 424.315636 -424.217846)
		(width 0.254)
		(layer "F.Cu")
		(net "GND")
	)
	(segment
		(start 77.467968 -231.79024)
		(end 76.812902 -231.79024)
		(width 0.350012)
		(layer "F.Cu")
		(net "GND")
	)
	(segment
		(start 374.28805 -241.510058)
		(end 374.754902 -241.24412)
		(width 0.350012)
		(layer "F.Cu")
		(net "GND")
	)
	(segment
		(start 305.016408 -399.76171)
		(end 305.016408 -400.212814)
		(width 0.254)
		(layer "F.Cu")
		(net "GND")
	)
	(segment
		(start 127.117856 -260.860286)
		(end 127.584708 -261.126224)
		(width 0.350012)
		(layer "F.Cu")
		(net "GND")
	)
	(segment
		(start 358.778048 -227.74021)
		(end 358.311196 -227.474272)
		(width 0.350012)
		(layer "F.Cu")
		(net "GND")
	)
	(segment
		(start 269.648178 -284.034992)
		(end 268.263878 -284.034992)
		(width 0.4572)
		(layer "F.Cu")
		(net "GND")
	)
	(segment
		(start 348.268036 -273.010122)
		(end 347.801184 -273.27606)
		(width 0.350012)
		(layer "F.Cu")
		(net "GND")
	)
	(segment
		(start 382.748028 -244.750082)
		(end 383.21488 -244.484144)
		(width 0.350012)
		(layer "F.Cu")
		(net "GND")
	)
	(segment
		(start 407.445718 -7.215886)
		(end 407.446988 -7.217156)
		(width 0.3556)
		(layer "F.Cu")
		(net "GND")
	)
	(segment
		(start 97.345754 -390.761474)
		(end 97.398332 -390.160002)
		(width 0.254)
		(layer "F.Cu")
		(net "GND")
	)
	(segment
		(start 288.180018 -238.13516)
		(end 289.564318 -238.13516)
		(width 0.4572)
		(layer "F.Cu")
		(net "GND")
	)
	(segment
		(start 52.518056 -382.951482)
		(end 52.616608 -382.85293)
		(width 0.2032)
		(layer "F.Cu")
		(net "GND")
	)
	(segment
		(start 309.518304 -396.710662)
		(end 308.87035 -396.520924)
		(width 0.254)
		(layer "F.Cu")
		(net "GND")
	)
	(segment
		(start 83.877912 -278.680418)
		(end 83.41106 -278.946356)
		(width 0.350012)
		(layer "F.Cu")
		(net "GND")
	)
	(segment
		(start 108.017818 -250.420378)
		(end 107.550966 -250.15444)
		(width 0.350012)
		(layer "F.Cu")
		(net "GND")
	)
	(segment
		(start 139.86764 -387.130798)
		(end 139.794742 -387.0579)
		(width 0.254)
		(layer "F.Cu")
		(net "GND")
	)
	(segment
		(start 125.238002 -285.160466)
		(end 125.704854 -285.426404)
		(width 0.350012)
		(layer "F.Cu")
		(net "GND")
	)
	(segment
		(start 345.618054 -247.1801)
		(end 345.151202 -246.914162)
		(width 0.350012)
		(layer "F.Cu")
		(net "GND")
	)
	(segment
		(start 14.257782 -416.569652)
		(end 13.830046 -416.997388)
		(width 0.381)
		(layer "F.Cu")
		(net "GND")
	)
	(segment
		(start 167.527986 -352.66376)
		(end 167.527986 -353.320858)
		(width 0.381)
		(layer "F.Cu")
		(net "GND")
	)
	(segment
		(start 375.997978 -268.960092)
		(end 376.46483 -269.22603)
		(width 0.350012)
		(layer "F.Cu")
		(net "GND")
	)
	(segment
		(start 391.268458 -402.163788)
		(end 391.715244 -401.717002)
		(width 0.254)
		(layer "F.Cu")
		(net "GND")
	)
	(segment
		(start 196.71919 -72.867266)
		(end 196.71919 -72.419464)
		(width 0.3556)
		(layer "F.Cu")
		(net "GND")
	)
	(segment
		(start 179.431696 -413.414972)
		(end 179.496974 -413.349694)
		(width 0.381)
		(layer "F.Cu")
		(net "GND")
	)
	(segment
		(start 57.416446 -391.37971)
		(end 57.317894 -391.281158)
		(width 0.254)
		(layer "F.Cu")
		(net "GND")
	)
	(segment
		(start 298.950888 -21.205952)
		(end 298.950888 -22.044152)
		(width 0.4064)
		(layer "F.Cu")
		(net "GND")
	)
	(segment
		(start 46.621192 -389.63092)
		(end 46.621192 -389.030972)
		(width 0.254)
		(layer "F.Cu")
		(net "GND")
	)
	(segment
		(start 367.538 -285.160212)
		(end 368.004852 -285.42615)
		(width 0.350012)
		(layer "F.Cu")
		(net "GND")
	)
	(segment
		(start 171.97197 -238.135414)
		(end 173.35627 -238.135414)
		(width 0.4572)
		(layer "F.Cu")
		(net "GND")
	)
	(segment
		(start 141.38783 -243.130324)
		(end 141.854682 -242.864386)
		(width 0.350012)
		(layer "F.Cu")
		(net "GND")
	)
	(segment
		(start 361.128056 -247.990106)
		(end 361.594908 -247.724168)
		(width 0.350012)
		(layer "F.Cu")
		(net "GND")
	)
	(segment
		(start 333.39786 -227.74021)
		(end 332.931008 -227.474272)
		(width 0.350012)
		(layer "F.Cu")
		(net "GND")
	)
	(segment
		(start 124.218446 -388.328662)
		(end 123.570492 -388.138924)
		(width 0.254)
		(layer "F.Cu")
		(net "GND")
	)
	(segment
		(start 177.295556 -92.493846)
		(end 177.296318 -92.493084)
		(width 0.381)
		(layer "F.Cu")
		(net "GND")
	)
	(segment
		(start 371.938042 -256.900172)
		(end 372.404894 -256.634234)
		(width 0.350012)
		(layer "F.Cu")
		(net "GND")
	)
	(segment
		(start 350.618044 -272.200116)
		(end 350.151192 -272.466054)
		(width 0.350012)
		(layer "F.Cu")
		(net "GND")
	)
	(segment
		(start 117.888004 -226.930458)
		(end 118.354856 -226.66452)
		(width 0.350012)
		(layer "F.Cu")
		(net "GND")
	)
	(segment
		(start 107.772454 -172.960284)
		(end 107.702604 -173.030134)
		(width 0.381)
		(layer "F.Cu")
		(net "GND")
	)
	(segment
		(start 306.117752 -392.004296)
		(end 306.417726 -392.30427)
		(width 0.254)
		(layer "F.Cu")
		(net "GND")
	)
	(segment
		(start 160.898332 -384.617722)
		(end 160.845754 -383.92227)
		(width 0.254)
		(layer "F.Cu")
		(net "GND")
	)
	(segment
		(start 120.758712 -15.247366)
		(end 121.653046 -15.247366)
		(width 0.4572)
		(layer "F.Cu")
		(net "GND")
	)
	(segment
		(start 146.38782 -273.010376)
		(end 147.042886 -273.010376)
		(width 0.350012)
		(layer "F.Cu")
		(net "GND")
	)
	(segment
		(start 160.898332 -390.160002)
		(end 160.218882 -390.160002)
		(width 0.254)
		(layer "F.Cu")
		(net "GND")
	)
	(segment
		(start 128.227836 -249.610372)
		(end 128.694688 -249.344434)
		(width 0.350012)
		(layer "F.Cu")
		(net "GND")
	)
	(segment
		(start 439.100214 -295.935146)
		(end 437.715914 -295.935146)
		(width 0.4572)
		(layer "F.Cu")
		(net "GND")
	)
	(segment
		(start 187.463176 -16.551148)
		(end 187.463176 -18.167604)
		(width 0.3556)
		(layer "F.Cu")
		(net "GND")
	)
	(segment
		(start 358.607868 -269.770098)
		(end 358.141016 -270.036036)
		(width 0.350012)
		(layer "F.Cu")
		(net "GND")
	)
	(segment
		(start 98.918014 -291.64026)
		(end 98.451162 -291.906198)
		(width 0.350012)
		(layer "F.Cu")
		(net "GND")
	)
	(segment
		(start 133.69798 -262.480298)
		(end 134.164832 -262.746236)
		(width 0.350012)
		(layer "F.Cu")
		(net "GND")
	)
	(segment
		(start 336.687922 -249.610118)
		(end 336.22107 -249.34418)
		(width 0.350012)
		(layer "F.Cu")
		(net "GND")
	)
	(segment
		(start 367.142522 -175.946308)
		(end 366.714024 -175.946308)
		(width 0.2286)
		(layer "F.Cu")
		(net "GND")
	)
	(segment
		(start 330.408026 -261.670038)
		(end 329.941174 -261.935976)
		(width 0.350012)
		(layer "F.Cu")
		(net "GND")
	)
	(segment
		(start 105.19791 -237.460282)
		(end 104.731058 -237.194344)
		(width 0.350012)
		(layer "F.Cu")
		(net "GND")
	)
	(segment
		(start 132.927852 -252.850396)
		(end 133.394704 -252.584458)
		(width 0.350012)
		(layer "F.Cu")
		(net "GND")
	)
	(segment
		(start 336.987896 -264.910062)
		(end 336.521044 -265.176)
		(width 0.350012)
		(layer "F.Cu")
		(net "GND")
	)
	(segment
		(start 162.945572 -391.281158)
		(end 163.2458 -390.761474)
		(width 0.254)
		(layer "F.Cu")
		(net "GND")
	)
	(segment
		(start 113.61801 -383.622296)
		(end 113.917984 -383.92227)
		(width 0.254)
		(layer "F.Cu")
		(net "GND")
	)
	(segment
		(start 338.868004 -269.770098)
		(end 338.401152 -270.036036)
		(width 0.350012)
		(layer "F.Cu")
		(net "GND")
	)
	(segment
		(start 416.545776 -391.333482)
		(end 416.644328 -391.23493)
		(width 0.254)
		(layer "F.Cu")
		(net "GND")
	)
	(segment
		(start 159.090106 -384.617722)
		(end 158.498286 -384.617722)
		(width 0.254)
		(layer "F.Cu")
		(net "GND")
	)
	(segment
		(start 391.03808 -264.100056)
		(end 391.504678 -264.365994)
		(width 0.350012)
		(layer "F.Cu")
		(net "GND")
	)
	(segment
		(start 86.69782 -268.960346)
		(end 86.230968 -269.226284)
		(width 0.350012)
		(layer "F.Cu")
		(net "GND")
	)
	(segment
		(start 85.113114 -180.918866)
		(end 84.684616 -180.918866)
		(width 0.2286)
		(layer "F.Cu")
		(net "GND")
	)
	(segment
		(start 384.157982 -245.560088)
		(end 384.624834 -245.29415)
		(width 0.350012)
		(layer "F.Cu")
		(net "GND")
	)
	(segment
		(start 375.29135 -398.542002)
		(end 374.77065 -398.542002)
		(width 0.254)
		(layer "F.Cu")
		(net "GND")
	)
	(segment
		(start 83.408012 -294.070278)
		(end 82.940906 -294.336216)
		(width 0.350012)
		(layer "F.Cu")
		(net "GND")
	)
	(segment
		(start 77.767942 -273.010376)
		(end 77.112876 -273.010376)
		(width 0.350012)
		(layer "F.Cu")
		(net "GND")
	)
	(segment
		(start 45.655738 -7.215886)
		(end 45.657008 -7.217156)
		(width 0.3556)
		(layer "F.Cu")
		(net "GND")
	)
	(segment
		(start 158.145734 -383.402586)
		(end 158.145734 -383.622296)
		(width 0.254)
		(layer "F.Cu")
		(net "GND")
	)
	(segment
		(start 374.28805 -235.03001)
		(end 374.754902 -234.764072)
		(width 0.350012)
		(layer "F.Cu")
		(net "GND")
	)
	(segment
		(start 336.687922 -225.310192)
		(end 336.22107 -225.044254)
		(width 0.350012)
		(layer "F.Cu")
		(net "GND")
	)
	(segment
		(start 133.398006 -240.700306)
		(end 133.864858 -240.434368)
		(width 0.350012)
		(layer "F.Cu")
		(net "GND")
	)
	(segment
		(start 131.27863 -386.449062)
		(end 130.77063 -386.6388)
		(width 0.254)
		(layer "F.Cu")
		(net "GND")
	)
	(segment
		(start 270.192754 -419.371526)
		(end 270.192754 -420.073836)
		(width 0.381)
		(layer "F.Cu")
		(net "GND")
	)
	(segment
		(start 337.544156 -400.212814)
		(end 337.544156 -399.76171)
		(width 0.254)
		(layer "F.Cu")
		(net "GND")
	)
	(segment
		(start 110.632494 -384.66268)
		(end 111.165894 -384.66268)
		(width 0.254)
		(layer "F.Cu")
		(net "GND")
	)
	(segment
		(start 133.398006 -226.120452)
		(end 133.864858 -225.854514)
		(width 0.350012)
		(layer "F.Cu")
		(net "GND")
	)
	(segment
		(start 343.56802 -271.39011)
		(end 343.101168 -271.656048)
		(width 0.350012)
		(layer "F.Cu")
		(net "GND")
	)
	(segment
		(start 138.098022 -240.700306)
		(end 138.564874 -240.434368)
		(width 0.350012)
		(layer "F.Cu")
		(net "GND")
	)
	(segment
		(start 80.712818 -176.40935)
		(end 81.192878 -176.88941)
		(width 0.4572)
		(layer "F.Cu")
		(net "GND")
	)
	(segment
		(start 22.8981 -333.151226)
		(end 22.8981 -333.89824)
		(width 0.254)
		(layer "F.Cu")
		(net "GND")
	)
	(segment
		(start 121.477786 -285.160466)
		(end 121.944638 -285.426404)
		(width 0.350012)
		(layer "F.Cu")
		(net "GND")
	)
	(segment
		(start 155.17749 -104.138984)
		(end 156.30779 -104.138984)
		(width 0.4064)
		(layer "F.Cu")
		(net "GND")
	)
	(segment
		(start 101.035358 -345.196922)
		(end 100.505006 -345.196922)
		(width 0.381)
		(layer "F.Cu")
		(net "GND")
	)
	(segment
		(start 115.83797 -280.30043)
		(end 116.304822 -280.566368)
		(width 0.350012)
		(layer "F.Cu")
		(net "GND")
	)
	(segment
		(start 325.70801 -294.070024)
		(end 325.052944 -294.070024)
		(width 0.350012)
		(layer "F.Cu")
		(net "GND")
	)
	(segment
		(start 83.877912 -294.880284)
		(end 83.41106 -295.146222)
		(width 0.350012)
		(layer "F.Cu")
		(net "GND")
	)
	(segment
		(start 384.157982 -226.120198)
		(end 384.624834 -225.85426)
		(width 0.350012)
		(layer "F.Cu")
		(net "GND")
	)
	(segment
		(start 165.698424 -386.987034)
		(end 165.698424 -386.6388)
		(width 0.254)
		(layer "F.Cu")
		(net "GND")
	)
	(segment
		(start 96.198436 -390.160002)
		(end 96.719136 -390.160002)
		(width 0.254)
		(layer "F.Cu")
		(net "GND")
	)
	(segment
		(start 101.737922 -280.30043)
		(end 101.27107 -280.566368)
		(width 0.350012)
		(layer "F.Cu")
		(net "GND")
	)
	(segment
		(start 358.778048 -230.97998)
		(end 358.311196 -230.714296)
		(width 0.350012)
		(layer "F.Cu")
		(net "GND")
	)
	(segment
		(start 389.201406 -392.387836)
		(end 389.11784 -392.30427)
		(width 0.254)
		(layer "F.Cu")
		(net "GND")
	)
	(segment
		(start 59.428126 -302.735234)
		(end 58.043826 -302.735234)
		(width 0.4572)
		(layer "F.Cu")
		(net "GND")
	)
	(segment
		(start 394.027914 -249.610118)
		(end 394.68298 -249.610118)
		(width 0.350012)
		(layer "F.Cu")
		(net "GND")
	)
	(segment
		(start 418.098224 -392.999722)
		(end 418.045646 -392.30427)
		(width 0.254)
		(layer "F.Cu")
		(net "GND")
	)
	(segment
		(start 97.677986 -232.600246)
		(end 97.211134 -232.334308)
		(width 0.350012)
		(layer "F.Cu")
		(net "GND")
	)
	(segment
		(start 117.018562 -388.328662)
		(end 116.370608 -388.138924)
		(width 0.254)
		(layer "F.Cu")
		(net "GND")
	)
	(segment
		(start 87.637874 -272.20037)
		(end 87.171022 -272.466308)
		(width 0.350012)
		(layer "F.Cu")
		(net "GND")
	)
	(segment
		(start 191.160146 -284.035246)
		(end 189.775846 -284.035246)
		(width 0.4572)
		(layer "F.Cu")
		(net "GND")
	)
	(segment
		(start 333.376524 -23.882858)
		(end 332.305914 -23.882858)
		(width 0.508)
		(layer "F.Cu")
		(net "GND")
	)
	(segment
		(start 336.987896 -279.49017)
		(end 336.521044 -279.756108)
		(width 0.350012)
		(layer "F.Cu")
		(net "GND")
	)
	(segment
		(start 25.152096 -221.985332)
		(end 26.536396 -221.985332)
		(width 0.4572)
		(layer "F.Cu")
		(net "GND")
	)
	(segment
		(start 107.10037 -23.371556)
		(end 108.09097 -23.371556)
		(width 0.381)
		(layer "F.Cu")
		(net "GND")
	)
	(segment
		(start 343.798144 -398.542002)
		(end 343.118694 -398.542002)
		(width 0.254)
		(layer "F.Cu")
		(net "GND")
	)
	(segment
		(start 126.177802 -265.720322)
		(end 126.644654 -265.98626)
		(width 0.350012)
		(layer "F.Cu")
		(net "GND")
	)
	(segment
		(start 68.16852 -393.781788)
		(end 68.615306 -393.335002)
		(width 0.254)
		(layer "F.Cu")
		(net "GND")
	)
	(segment
		(start 336.987896 -273.010122)
		(end 336.521044 -273.27606)
		(width 0.350012)
		(layer "F.Cu")
		(net "GND")
	)
	(segment
		(start 110.6678 -284.35046)
		(end 110.200948 -284.616398)
		(width 0.350012)
		(layer "F.Cu")
		(net "GND")
	)
	(segment
		(start 191.160146 -202.435206)
		(end 189.775846 -202.435206)
		(width 0.4572)
		(layer "F.Cu")
		(net "GND")
	)
	(segment
		(start 103.617776 -277.060406)
		(end 103.151178 -277.326344)
		(width 0.350012)
		(layer "F.Cu")
		(net "GND")
	)
	(segment
		(start 276.081744 -94.789498)
		(end 276.081744 -94.115128)
		(width 0.3556)
		(layer "F.Cu")
		(net "GND")
	)
	(segment
		(start 141.38783 -241.510312)
		(end 141.854682 -241.244374)
		(width 0.350012)
		(layer "F.Cu")
		(net "GND")
	)
	(segment
		(start 47.518574 -388.328662)
		(end 48.070516 -388.138924)
		(width 0.254)
		(layer "F.Cu")
		(net "GND")
	)
	(segment
		(start 52.011072 -402.878036)
		(end 52.011072 -403.73808)
		(width 0.381)
		(layer "F.Cu")
		(net "GND")
	)
	(segment
		(start 139.80795 -279.490424)
		(end 140.274802 -279.756362)
		(width 0.350012)
		(layer "F.Cu")
		(net "GND")
	)
	(segment
		(start 93.79839 -386.6388)
		(end 93.10624 -386.449062)
		(width 0.254)
		(layer "F.Cu")
		(net "GND")
	)
	(segment
		(start 378.048012 -256.090166)
		(end 378.514864 -255.824228)
		(width 0.350012)
		(layer "F.Cu")
		(net "GND")
	)
	(segment
		(start 345.618054 -224.500186)
		(end 345.151202 -224.234248)
		(width 0.350012)
		(layer "F.Cu")
		(net "GND")
	)
	(segment
		(start 330.408026 -289.209988)
		(end 329.941174 -289.475926)
		(width 0.350012)
		(layer "F.Cu")
		(net "GND")
	)
	(segment
		(start 346.557854 -235.840016)
		(end 346.091002 -235.574078)
		(width 0.350012)
		(layer "F.Cu")
		(net "GND")
	)
	(segment
		(start 217.062812 -23.292308)
		(end 217.062812 -25.311354)
		(width 0.3556)
		(layer "F.Cu")
		(net "GND")
	)
	(segment
		(start 371.767862 -277.870158)
		(end 372.234714 -278.136096)
		(width 0.350012)
		(layer "F.Cu")
		(net "GND")
	)
	(segment
		(start 86.397846 -223.40697)
		(end 86.401148 -223.410272)
		(width 0.350012)
		(layer "F.Cu")
		(net "GND")
	)
	(segment
		(start 372.238016 -286.780224)
		(end 372.704868 -287.045908)
		(width 0.350012)
		(layer "F.Cu")
		(net "GND")
	)
	(segment
		(start 381.167894 -273.010122)
		(end 381.634746 -273.27606)
		(width 0.350012)
		(layer "F.Cu")
		(net "GND")
	)
	(segment
		(start 462.316576 -100.470208)
		(end 462.316576 -101.105208)
		(width 0.3556)
		(layer "F.Cu")
		(net "GND")
	)
	(segment
		(start 168.527984 -305.285394)
		(end 167.143684 -305.285394)
		(width 0.4572)
		(layer "F.Cu")
		(net "GND")
	)
	(segment
		(start 299.82414 -293.384986)
		(end 298.43984 -293.384986)
		(width 0.4572)
		(layer "F.Cu")
		(net "GND")
	)
	(segment
		(start 143.160242 -384.66268)
		(end 143.693642 -384.66268)
		(width 0.254)
		(layer "F.Cu")
		(net "GND")
	)
	(segment
		(start 367.238026 -226.120198)
		(end 367.704878 -225.85426)
		(width 0.350012)
		(layer "F.Cu")
		(net "GND")
	)
	(segment
		(start 381.638048 -288.399982)
		(end 382.1049 -288.66592)
		(width 0.350012)
		(layer "F.Cu")
		(net "GND")
	)
	(segment
		(start 55.218076 -383.92227)
		(end 55.270654 -384.617722)
		(width 0.254)
		(layer "F.Cu")
		(net "GND")
	)
	(segment
		(start 449.072508 -93.509592)
		(end 449.71208 -93.509592)
		(width 0.3556)
		(layer "F.Cu")
		(net "GND")
	)
	(segment
		(start 350.78797 -239.890046)
		(end 350.321118 -239.624108)
		(width 0.350012)
		(layer "F.Cu")
		(net "GND")
	)
	(segment
		(start 124.770642 -390.160002)
		(end 124.091192 -390.160002)
		(width 0.254)
		(layer "F.Cu")
		(net "GND")
	)
	(segment
		(start 368.947954 -276.250146)
		(end 369.414806 -276.516084)
		(width 0.350012)
		(layer "F.Cu")
		(net "GND")
	)
	(segment
		(start 20.346924 -8.320024)
		(end 20.348194 -9.424924)
		(width 0.3556)
		(layer "F.Cu")
		(net "GND")
	)
	(segment
		(start 378.048012 -226.930204)
		(end 378.514864 -226.664266)
		(width 0.350012)
		(layer "F.Cu")
		(net "GND")
	)
	(segment
		(start 101.437948 -232.600246)
		(end 100.971096 -232.334308)
		(width 0.350012)
		(layer "F.Cu")
		(net "GND")
	)
	(segment
		(start 84.19846 -384.617722)
		(end 84.145882 -383.92227)
		(width 0.254)
		(layer "F.Cu")
		(net "GND")
	)
	(segment
		(start 379.75794 -281.920188)
		(end 380.224792 -282.186126)
		(width 0.350012)
		(layer "F.Cu")
		(net "GND")
	)
	(segment
		(start 351.557844 -273.820128)
		(end 351.091246 -274.086066)
		(width 0.350012)
		(layer "F.Cu")
		(net "GND")
	)
	(segment
		(start 146.38782 -279.490424)
		(end 147.042886 -279.490424)
		(width 0.350012)
		(layer "F.Cu")
		(net "GND")
	)
	(segment
		(start 135.27786 -224.50044)
		(end 135.744712 -224.234502)
		(width 0.350012)
		(layer "F.Cu")
		(net "GND")
	)
	(segment
		(start 17.608042 -212.635338)
		(end 18.992342 -212.635338)
		(width 0.4572)
		(layer "F.Cu")
		(net "GND")
	)
	(segment
		(start 367.238026 -224.500186)
		(end 367.704878 -224.234248)
		(width 0.350012)
		(layer "F.Cu")
		(net "GND")
	)
	(segment
		(start 325.70801 -290.83)
		(end 325.052944 -290.83)
		(width 0.350012)
		(layer "F.Cu")
		(net "GND")
	)
	(segment
		(start 42.057066 -12.372848)
		(end 42.057066 -11.26998)
		(width 0.3556)
		(layer "F.Cu")
		(net "GND")
	)
	(segment
		(start 415.39795 -96.901)
		(end 414.655 -96.901)
		(width 0.4572)
		(layer "F.Cu")
		(net "GND")
	)
	(segment
		(start 382.478534 -394.831062)
		(end 381.970534 -395.0208)
		(width 0.254)
		(layer "F.Cu")
		(net "GND")
	)
	(segment
		(start 313.416188 -400.212814)
		(end 313.416188 -399.76171)
		(width 0.254)
		(layer "F.Cu")
		(net "GND")
	)
	(segment
		(start 91.045792 -383.622296)
		(end 91.345766 -383.92227)
		(width 0.254)
		(layer "F.Cu")
		(net "GND")
	)
	(segment
		(start 79.045816 -383.622296)
		(end 79.34579 -383.92227)
		(width 0.254)
		(layer "F.Cu")
		(net "GND")
	)
	(segment
		(start 93.747844 -276.2504)
		(end 93.280992 -276.516338)
		(width 0.350012)
		(layer "F.Cu")
		(net "GND")
	)
	(segment
		(start 314.517786 -391.784586)
		(end 314.517786 -391.333482)
		(width 0.254)
		(layer "F.Cu")
		(net "GND")
	)
	(segment
		(start 63.61811 -383.92227)
		(end 63.317882 -383.622042)
		(width 0.254)
		(layer "F.Cu")
		(net "GND")
	)
	(segment
		(start 421.919654 -425.685458)
		(end 421.919654 -424.594274)
		(width 0.381)
		(layer "F.Cu")
		(net "GND")
	)
	(segment
		(start 364.417864 -222.880174)
		(end 364.884716 -222.614236)
		(width 0.350012)
		(layer "F.Cu")
		(net "GND")
	)
	(segment
		(start 408.145742 -391.784586)
		(end 408.145742 -391.333482)
		(width 0.2032)
		(layer "F.Cu")
		(net "GND")
	)
	(segment
		(start 355.018086 -222.880174)
		(end 354.551234 -222.614236)
		(width 0.350012)
		(layer "F.Cu")
		(net "GND")
	)
	(segment
		(start 442.199014 -399.070322)
		(end 442.731906 -399.070322)
		(width 0.2286)
		(layer "F.Cu")
		(net "GND")
	)
	(segment
		(start 198.7042 -237.285276)
		(end 197.3199 -237.285276)
		(width 0.4572)
		(layer "F.Cu")
		(net "GND")
	)
	(segment
		(start 331.518006 -226.120198)
		(end 331.051154 -225.85426)
		(width 0.350012)
		(layer "F.Cu")
		(net "GND")
	)
	(segment
		(start 350.31807 -229.360222)
		(end 349.851218 -229.094284)
		(width 0.350012)
		(layer "F.Cu")
		(net "GND")
	)
	(segment
		(start 134.80796 -244.750336)
		(end 135.274812 -244.484398)
		(width 0.350012)
		(layer "F.Cu")
		(net "GND")
	)
	(segment
		(start 113.017808 -294.880284)
		(end 113.48466 -295.146222)
		(width 0.350012)
		(layer "F.Cu")
		(net "GND")
	)
	(segment
		(start 98.40976 -135.229092)
		(end 98.40976 -133.389116)
		(width 0.4572)
		(layer "F.Cu")
		(net "GND")
	)
	(segment
		(start 292.280086 -314.635134)
		(end 290.895786 -314.635134)
		(width 0.4572)
		(layer "F.Cu")
		(net "GND")
	)
	(segment
		(start 379.457966 -245.560088)
		(end 379.924818 -245.29415)
		(width 0.350012)
		(layer "F.Cu")
		(net "GND")
	)
	(segment
		(start 155.490164 -384.617722)
		(end 154.898344 -384.617722)
		(width 0.254)
		(layer "F.Cu")
		(net "GND")
	)
	(segment
		(start 97.507806 -282.730448)
		(end 97.040954 -282.996386)
		(width 0.350012)
		(layer "F.Cu")
		(net "GND")
	)
	(segment
		(start 110.6678 -281.110436)
		(end 110.200948 -281.376374)
		(width 0.350012)
		(layer "F.Cu")
		(net "GND")
	)
	(segment
		(start 417.546282 -396.710662)
		(end 416.898328 -396.520924)
		(width 0.254)
		(layer "F.Cu")
		(net "GND")
	)
	(segment
		(start 387.748018 -281.110182)
		(end 388.21487 -281.37612)
		(width 0.350012)
		(layer "F.Cu")
		(net "GND")
	)
	(segment
		(start 130.577844 -222.880428)
		(end 131.044696 -222.61449)
		(width 0.350012)
		(layer "F.Cu")
		(net "GND")
	)
	(segment
		(start 376.6185 -396.710662)
		(end 375.970546 -396.520924)
		(width 0.254)
		(layer "F.Cu")
		(net "GND")
	)
	(segment
		(start 389.93445 -392.913108)
		(end 389.71474 -392.913108)
		(width 0.254)
		(layer "F.Cu")
		(net "GND")
	)
	(segment
		(start 110.367826 -233.410252)
		(end 109.900974 -233.144314)
		(width 0.350012)
		(layer "F.Cu")
		(net "GND")
	)
	(segment
		(start 412.367984 -228.785166)
		(end 413.752284 -228.785166)
		(width 0.4572)
		(layer "F.Cu")
		(net "GND")
	)
	(segment
		(start 139.977876 -229.360476)
		(end 140.444728 -229.094538)
		(width 0.350012)
		(layer "F.Cu")
		(net "GND")
	)
	(segment
		(start 375.617994 -392.004296)
		(end 375.917968 -392.30427)
		(width 0.2032)
		(layer "F.Cu")
		(net "GND")
	)
	(segment
		(start 105.19791 -247.180354)
		(end 104.731058 -246.914416)
		(width 0.350012)
		(layer "F.Cu")
		(net "GND")
	)
	(segment
		(start 32.695896 -284.885384)
		(end 34.080196 -284.885384)
		(width 0.4572)
		(layer "F.Cu")
		(net "GND")
	)
	(segment
		(start 78.877922 -237.460282)
		(end 78.41107 -237.194344)
		(width 0.350012)
		(layer "F.Cu")
		(net "GND")
	)
	(segment
		(start 355.31806 -288.399982)
		(end 354.851208 -288.66592)
		(width 0.350012)
		(layer "F.Cu")
		(net "GND")
	)
	(segment
		(start 357.36784 -233.409998)
		(end 356.901242 -233.14406)
		(width 0.350012)
		(layer "F.Cu")
		(net "GND")
	)
	(segment
		(start 51.884072 -302.735234)
		(end 50.499772 -302.735234)
		(width 0.4572)
		(layer "F.Cu")
		(net "GND")
	)
	(segment
		(start 20.348194 -12.374118)
		(end 20.346924 -12.372848)
		(width 0.3556)
		(layer "F.Cu")
		(net "GND")
	)
	(segment
		(start 392.917934 -265.720068)
		(end 393.384786 -265.986006)
		(width 0.350012)
		(layer "F.Cu")
		(net "GND")
	)
	(segment
		(start 168.499028 -131.13004)
		(end 167.487092 -131.13004)
		(width 0.381)
		(layer "F.Cu")
		(net "GND")
	)
	(segment
		(start 192.577466 -376.440446)
		(end 195.88988 -376.440446)
		(width 0.4572)
		(layer "F.Cu")
		(net "GND")
	)
	(segment
		(start 159.34563 -383.402586)
		(end 159.34563 -382.951482)
		(width 0.254)
		(layer "F.Cu")
		(net "GND")
	)
	(segment
		(start 84.047838 -243.130324)
		(end 83.580986 -242.864386)
		(width 0.350012)
		(layer "F.Cu")
		(net "GND")
	)
	(segment
		(start 52.318412 -388.328662)
		(end 52.870608 -388.138924)
		(width 0.254)
		(layer "F.Cu")
		(net "GND")
	)
	(segment
		(start 396.258796 -411.15615)
		(end 396.258796 -412.010098)
		(width 0.381)
		(layer "F.Cu")
		(net "GND")
	)
	(segment
		(start 93.747844 -285.970472)
		(end 93.280992 -286.23641)
		(width 0.350012)
		(layer "F.Cu")
		(net "GND")
	)
	(segment
		(start 173.467014 -16.549878)
		(end 173.467014 -17.774158)
		(width 0.3556)
		(layer "F.Cu")
		(net "GND")
	)
	(segment
		(start 322.10121 -392.387836)
		(end 322.017644 -392.30427)
		(width 0.254)
		(layer "F.Cu")
		(net "GND")
	)
	(segment
		(start 90.457782 -275.440394)
		(end 89.99093 -275.706332)
		(width 0.350012)
		(layer "F.Cu")
		(net "GND")
	)
	(segment
		(start 93.44787 -241.510312)
		(end 92.981018 -241.244374)
		(width 0.350012)
		(layer "F.Cu")
		(net "GND")
	)
	(segment
		(start 147.698206 -386.6388)
		(end 147.00631 -386.449062)
		(width 0.254)
		(layer "F.Cu")
		(net "GND")
	)
	(segment
		(start 335.108042 -290.83)
		(end 334.64119 -291.095938)
		(width 0.350012)
		(layer "F.Cu")
		(net "GND")
	)
	(segment
		(start 36.795964 -237.285276)
		(end 35.411664 -237.285276)
		(width 0.4572)
		(layer "F.Cu")
		(net "GND")
	)
	(segment
		(start 42.057066 -9.423654)
		(end 42.058336 -9.424924)
		(width 0.3556)
		(layer "F.Cu")
		(net "GND")
	)
	(segment
		(start 191.403986 -55.94096)
		(end 192.045082 -55.94096)
		(width 0.381)
		(layer "F.Cu")
		(net "GND")
	)
	(segment
		(start 100.696268 -394.0937)
		(end 100.696268 -393.781788)
		(width 0.254)
		(layer "F.Cu")
		(net "GND")
	)
	(segment
		(start 302.800258 -45.005498)
		(end 302.190658 -45.005498)
		(width 0.3556)
		(layer "F.Cu")
		(net "GND")
	)
	(segment
		(start 70.861936 -11.26998)
		(end 70.861936 -12.372848)
		(width 0.3556)
		(layer "F.Cu")
		(net "GND")
	)
	(segment
		(start 45.657008 -9.423654)
		(end 45.658278 -9.424924)
		(width 0.3556)
		(layer "F.Cu")
		(net "GND")
	)
	(segment
		(start 407.052272 -163.382198)
		(end 406.464262 -163.382198)
		(width 0.381)
		(layer "F.Cu")
		(net "GND")
	)
	(segment
		(start 133.398006 -252.04039)
		(end 133.864858 -251.774452)
		(width 0.350012)
		(layer "F.Cu")
		(net "GND")
	)
	(segment
		(start 76.105512 -38.532562)
		(end 76.105512 -37.897562)
		(width 0.3556)
		(layer "F.Cu")
		(net "GND")
	)
	(segment
		(start 322.834254 -393.513056)
		(end 322.834254 -392.913108)
		(width 0.254)
		(layer "F.Cu")
		(net "GND")
	)
	(segment
		(start 127.42545 -27.463496)
		(end 126.58979 -27.463496)
		(width 0.3556)
		(layer "F.Cu")
		(net "GND")
	)
	(segment
		(start 112.769904 -399.642584)
		(end 111.974884 -400.437604)
		(width 0.3302)
		(layer "F.Cu")
		(net "GND")
	)
	(segment
		(start 149.7457 -383.402586)
		(end 149.7457 -383.622296)
		(width 0.254)
		(layer "F.Cu")
		(net "GND")
	)
	(segment
		(start 100.797868 -281.920442)
		(end 100.331016 -282.18638)
		(width 0.350012)
		(layer "F.Cu")
		(net "GND")
	)
	(segment
		(start 91.144344 -391.37971)
		(end 91.045792 -391.281158)
		(width 0.254)
		(layer "F.Cu")
		(net "GND")
	)
	(segment
		(start 95.627952 -281.110436)
		(end 95.1611 -281.376374)
		(width 0.350012)
		(layer "F.Cu")
		(net "GND")
	)
	(segment
		(start 33.229042 -349.786448)
		(end 33.799526 -349.215964)
		(width 0.2286)
		(layer "F.Cu")
		(net "GND")
	)
	(segment
		(start 412.367984 -219.435172)
		(end 413.752284 -219.435172)
		(width 0.4572)
		(layer "F.Cu")
		(net "GND")
	)
	(segment
		(start 391.50798 -279.49017)
		(end 391.974832 -279.756108)
		(width 0.350012)
		(layer "F.Cu")
		(net "GND")
	)
	(segment
		(start 66.070734 -386.6388)
		(end 65.378584 -386.449062)
		(width 0.254)
		(layer "F.Cu")
		(net "GND")
	)
	(segment
		(start 103.147876 -271.390364)
		(end 102.681024 -271.656302)
		(width 0.350012)
		(layer "F.Cu")
		(net "GND")
	)
	(segment
		(start 346.557854 -237.460028)
		(end 346.091002 -237.19409)
		(width 0.350012)
		(layer "F.Cu")
		(net "GND")
	)
	(segment
		(start 106.137964 -250.420378)
		(end 105.671112 -250.15444)
		(width 0.350012)
		(layer "F.Cu")
		(net "GND")
	)
	(segment
		(start 52.877466 -28.707588)
		(end 54.383178 -28.707588)
		(width 0.4572)
		(layer "F.Cu")
		(net "GND")
	)
	(segment
		(start 369.72113 -398.946624)
		(end 369.91798 -399.143474)
		(width 0.254)
		(layer "F.Cu")
		(net "GND")
	)
	(segment
		(start 59.71794 -383.402586)
		(end 59.71794 -382.951482)
		(width 0.254)
		(layer "F.Cu")
		(net "GND")
	)
	(segment
		(start 183.752744 -164.761418)
		(end 184.645808 -164.761418)
		(width 0.3556)
		(layer "F.Cu")
		(net "GND")
	)
	(segment
		(start 142.157958 -293.260272)
		(end 142.62481 -293.52621)
		(width 0.350012)
		(layer "F.Cu")
		(net "GND")
	)
	(segment
		(start 155.745688 -391.281158)
		(end 155.84424 -391.37971)
		(width 0.254)
		(layer "F.Cu")
		(net "GND")
	)
	(segment
		(start 126.817882 -391.281158)
		(end 127.117856 -390.761474)
		(width 0.254)
		(layer "F.Cu")
		(net "GND")
	)
	(segment
		(start 108.317792 -267.340334)
		(end 107.85094 -267.606272)
		(width 0.350012)
		(layer "F.Cu")
		(net "GND")
	)
	(segment
		(start 18.841466 -39.926514)
		(end 18.232628 -39.926514)
		(width 0.4572)
		(layer "F.Cu")
		(net "GND")
	)
	(segment
		(start 123.827794 -276.2504)
		(end 124.294646 -276.516338)
		(width 0.350012)
		(layer "F.Cu")
		(net "GND")
	)
	(segment
		(start 163.334446 -117.310662)
		(end 163.334446 -116.296186)
		(width 0.4572)
		(layer "F.Cu")
		(net "GND")
	)
	(segment
		(start 131.970526 -390.160002)
		(end 131.29133 -390.160002)
		(width 0.254)
		(layer "F.Cu")
		(net "GND")
	)
	(segment
		(start 328.998072 -293.260018)
		(end 328.53122 -293.525956)
		(width 0.350012)
		(layer "F.Cu")
		(net "GND")
	)
	(segment
		(start 236.58957 -157.289754)
		(end 235.490258 -157.289754)
		(width 0.381)
		(layer "F.Cu")
		(net "GND")
	)
	(segment
		(start 59.04611 -348.546166)
		(end 59.474608 -348.546166)
		(width 0.2286)
		(layer "F.Cu")
		(net "GND")
	)
	(segment
		(start 106.074718 -20.084542)
		(end 105.400602 -20.758658)
		(width 0.381)
		(layer "F.Cu")
		(net "GND")
	)
	(segment
		(start 426.974 -364.08995)
		(end 427.631098 -364.08995)
		(width 0.3556)
		(layer "F.Cu")
		(net "GND")
	)
	(segment
		(start 171.97197 -212.635338)
		(end 173.35627 -212.635338)
		(width 0.4572)
		(layer "F.Cu")
		(net "GND")
	)
	(segment
		(start 341.687912 -284.350206)
		(end 341.22106 -284.616144)
		(width 0.350012)
		(layer "F.Cu")
		(net "GND")
	)
	(segment
		(start 338.39785 -270.580104)
		(end 337.930998 -270.846042)
		(width 0.350012)
		(layer "F.Cu")
		(net "GND")
	)
	(segment
		(start 291.691822 -351.927922)
		(end 291.761672 -351.858072)
		(width 0.381)
		(layer "F.Cu")
		(net "GND")
	)
	(segment
		(start 354.378006 -267.34008)
		(end 353.911154 -267.606018)
		(width 0.350012)
		(layer "F.Cu")
		(net "GND")
	)
	(segment
		(start 120.817894 -383.402586)
		(end 120.817894 -382.951482)
		(width 0.254)
		(layer "F.Cu")
		(net "GND")
	)
	(segment
		(start 320.517774 -391.784586)
		(end 320.517774 -391.333482)
		(width 0.254)
		(layer "F.Cu")
		(net "GND")
	)
	(segment
		(start 288.66592 -96.655382)
		(end 289.3568 -96.655382)
		(width 0.4572)
		(layer "F.Cu")
		(net "GND")
	)
	(segment
		(start 392.237722 -180.918866)
		(end 391.809224 -180.918866)
		(width 0.2286)
		(layer "F.Cu")
		(net "GND")
	)
	(segment
		(start 346.19819 -392.999722)
		(end 346.145612 -392.30427)
		(width 0.254)
		(layer "F.Cu")
		(net "GND")
	)
	(segment
		(start 288.356294 -349.781622)
		(end 288.926778 -349.211138)
		(width 0.2286)
		(layer "F.Cu")
		(net "GND")
	)
	(segment
		(start 295.30421 -404.155402)
		(end 294.647874 -404.155402)
		(width 0.254)
		(layer "F.Cu")
		(net "GND")
	)
	(segment
		(start 344.977974 -267.34008)
		(end 344.511122 -267.606018)
		(width 0.350012)
		(layer "F.Cu")
		(net "GND")
	)
	(segment
		(start 342.597994 -398.542002)
		(end 341.918798 -398.542002)
		(width 0.254)
		(layer "F.Cu")
		(net "GND")
	)
	(segment
		(start 391.03808 -272.200116)
		(end 391.504678 -272.466054)
		(width 0.350012)
		(layer "F.Cu")
		(net "GND")
	)
	(segment
		(start 350.618044 -268.960092)
		(end 350.151192 -269.22603)
		(width 0.350012)
		(layer "F.Cu")
		(net "GND")
	)
	(segment
		(start 92.037916 -226.120452)
		(end 91.571064 -225.854514)
		(width 0.350012)
		(layer "F.Cu")
		(net "GND")
	)
	(segment
		(start 128.227836 -243.130324)
		(end 128.694688 -242.864386)
		(width 0.350012)
		(layer "F.Cu")
		(net "GND")
	)
	(segment
		(start 87.3379 -226.120452)
		(end 86.871048 -225.854514)
		(width 0.350012)
		(layer "F.Cu")
		(net "GND")
	)
	(segment
		(start 416.84575 -399.143474)
		(end 416.898328 -398.542002)
		(width 0.254)
		(layer "F.Cu")
		(net "GND")
	)
	(segment
		(start 40.23995 -306.135278)
		(end 41.62425 -306.135278)
		(width 0.4572)
		(layer "F.Cu")
		(net "GND")
	)
	(segment
		(start 374.11787 -285.160212)
		(end 374.584722 -285.42615)
		(width 0.350012)
		(layer "F.Cu")
		(net "GND")
	)
	(segment
		(start 369.687094 -403.336506)
		(end 369.687094 -402.734018)
		(width 0.254)
		(layer "F.Cu")
		(net "GND")
	)
	(segment
		(start 375.716546 -399.76171)
		(end 375.617994 -399.663158)
		(width 0.254)
		(layer "F.Cu")
		(net "GND")
	)
	(segment
		(start 351.557844 -281.920188)
		(end 351.091246 -282.186126)
		(width 0.350012)
		(layer "F.Cu")
		(net "GND")
	)
	(segment
		(start 427.456092 -284.88513)
		(end 428.840392 -284.88513)
		(width 0.4572)
		(layer "F.Cu")
		(net "GND")
	)
	(segment
		(start 326.38492 -340.199726)
		(end 326.45477 -340.129876)
		(width 0.381)
		(layer "F.Cu")
		(net "GND")
	)
	(segment
		(start 82.467958 -268.15034)
		(end 82.001106 -268.416278)
		(width 0.350012)
		(layer "F.Cu")
		(net "GND")
	)
	(segment
		(start 289.314382 -351.973896)
		(end 288.94659 -351.973896)
		(width 0.381)
		(layer "F.Cu")
		(net "GND")
	)
	(segment
		(start 280.620978 -349.211138)
		(end 280.620978 -348.794324)
		(width 0.2286)
		(layer "F.Cu")
		(net "GND")
	)
	(segment
		(start 79.14894 -390.231122)
		(end 79.14894 -390.564624)
		(width 0.254)
		(layer "F.Cu")
		(net "GND")
	)
	(segment
		(start 331.81798 -286.780224)
		(end 331.351128 -287.045908)
		(width 0.350012)
		(layer "F.Cu")
		(net "GND")
	)
	(segment
		(start 93.44787 -231.79024)
		(end 92.981018 -231.524302)
		(width 0.350012)
		(layer "F.Cu")
		(net "GND")
	)
	(segment
		(start 381.167894 -287.59023)
		(end 381.634746 -287.856168)
		(width 0.350012)
		(layer "F.Cu")
		(net "GND")
	)
	(segment
		(start 321.378326 -394.831062)
		(end 320.870326 -395.0208)
		(width 0.254)
		(layer "F.Cu")
		(net "GND")
	)
	(segment
		(start 338.998052 -392.999722)
		(end 338.945474 -392.30427)
		(width 0.254)
		(layer "F.Cu")
		(net "GND")
	)
	(segment
		(start 119.97055 -386.6388)
		(end 119.2784 -386.449062)
		(width 0.254)
		(layer "F.Cu")
		(net "GND")
	)
	(segment
		(start 457.994766 -92.022422)
		(end 458.487526 -92.515182)
		(width 0.3556)
		(layer "F.Cu")
		(net "GND")
	)
	(segment
		(start 308.321964 -115.665504)
		(end 309.337964 -115.665504)
		(width 0.3556)
		(layer "F.Cu")
		(net "GND")
	)
	(segment
		(start 143.567912 -289.210242)
		(end 144.034764 -289.47618)
		(width 0.350012)
		(layer "F.Cu")
		(net "GND")
	)
	(segment
		(start 80.245712 -382.951482)
		(end 80.344264 -382.85293)
		(width 0.254)
		(layer "F.Cu")
		(net "GND")
	)
	(segment
		(start 80.545686 -390.761474)
		(end 80.245712 -391.281158)
		(width 0.254)
		(layer "F.Cu")
		(net "GND")
	)
	(segment
		(start 140.27785 -286.780478)
		(end 140.744702 -287.046162)
		(width 0.350012)
		(layer "F.Cu")
		(net "GND")
	)
	(segment
		(start 387.917944 -248.800112)
		(end 388.384796 -248.534174)
		(width 0.350012)
		(layer "F.Cu")
		(net "GND")
	)
	(segment
		(start 416.468052 -286.585152)
		(end 415.083752 -286.585152)
		(width 0.4572)
		(layer "F.Cu")
		(net "GND")
	)
	(segment
		(start 165.60165 -438.912)
		(end 166.245032 -438.912)
		(width 0.381)
		(layer "F.Cu")
		(net "GND")
	)
	(segment
		(start 125.238002 -281.920442)
		(end 125.704854 -282.18638)
		(width 0.350012)
		(layer "F.Cu")
		(net "GND")
	)
	(segment
		(start 372.962424 -392.999722)
		(end 372.370604 -392.999722)
		(width 0.254)
		(layer "F.Cu")
		(net "GND")
	)
	(segment
		(start 58.668158 -12.37488)
		(end 58.668158 -12.374118)
		(width 0.3556)
		(layer "F.Cu")
		(net "GND")
	)
	(segment
		(start 341.906098 -394.831062)
		(end 341.398098 -395.0208)
		(width 0.254)
		(layer "F.Cu")
		(net "GND")
	)
	(segment
		(start 304.01768 -399.143474)
		(end 303.717706 -399.663158)
		(width 0.254)
		(layer "F.Cu")
		(net "GND")
	)
	(segment
		(start 376.467878 -281.110182)
		(end 376.93473 -281.37612)
		(width 0.350012)
		(layer "F.Cu")
		(net "GND")
	)
	(segment
		(start 427.456092 -278.085042)
		(end 428.840392 -278.085042)
		(width 0.4572)
		(layer "F.Cu")
		(net "GND")
	)
	(segment
		(start 86.545674 -390.761474)
		(end 86.598252 -390.160002)
		(width 0.254)
		(layer "F.Cu")
		(net "GND")
	)
	(segment
		(start 350.618044 -264.100056)
		(end 350.151192 -264.365994)
		(width 0.350012)
		(layer "F.Cu")
		(net "GND")
	)
	(segment
		(start 353.437952 -288.399982)
		(end 352.9711 -288.66592)
		(width 0.350012)
		(layer "F.Cu")
		(net "GND")
	)
	(segment
		(start 417.703762 -161.180526)
		(end 417.611306 -161.403792)
		(width 0.2286)
		(layer "F.Cu")
		(net "GND")
	)
	(segment
		(start 68.476114 -167.103552)
		(end 68.047616 -167.103552)
		(width 0.2286)
		(layer "F.Cu")
		(net "GND")
	)
	(segment
		(start 125.238002 -291.64026)
		(end 125.704854 -291.906198)
		(width 0.350012)
		(layer "F.Cu")
		(net "GND")
	)
	(segment
		(start 92.34424 -391.37971)
		(end 92.245688 -391.281158)
		(width 0.254)
		(layer "F.Cu")
		(net "GND")
	)
	(segment
		(start 101.907848 -254.470408)
		(end 101.440996 -254.20447)
		(width 0.350012)
		(layer "F.Cu")
		(net "GND")
	)
	(segment
		(start 347.797882 -273.820128)
		(end 347.33103 -274.086066)
		(width 0.350012)
		(layer "F.Cu")
		(net "GND")
	)
	(segment
		(start 363.778038 -290.019994)
		(end 364.24489 -290.285932)
		(width 0.350012)
		(layer "F.Cu")
		(net "GND")
	)
	(segment
		(start 191.160146 -218.585288)
		(end 189.775846 -218.585288)
		(width 0.4572)
		(layer "F.Cu")
		(net "GND")
	)
	(segment
		(start 305.21783 -399.143474)
		(end 304.917856 -399.663158)
		(width 0.254)
		(layer "F.Cu")
		(net "GND")
	)
	(segment
		(start 109.897926 -224.50044)
		(end 110.024418 -224.373948)
		(width 0.350012)
		(layer "F.Cu")
		(net "GND")
	)
	(segment
		(start 92.245688 -391.281158)
		(end 92.545662 -390.761474)
		(width 0.254)
		(layer "F.Cu")
		(net "GND")
	)
	(segment
		(start 133.867906 -225.310446)
		(end 134.334758 -225.044508)
		(width 0.350012)
		(layer "F.Cu")
		(net "GND")
	)
	(segment
		(start 99.55784 -247.180354)
		(end 99.090988 -246.914416)
		(width 0.350012)
		(layer "F.Cu")
		(net "GND")
	)
	(segment
		(start 338.868004 -281.110182)
		(end 338.401152 -281.37612)
		(width 0.350012)
		(layer "F.Cu")
		(net "GND")
	)
	(segment
		(start 94.744286 -391.37971)
		(end 94.645734 -391.281158)
		(width 0.254)
		(layer "F.Cu")
		(net "GND")
	)
	(segment
		(start 170.869356 -125.751336)
		(end 170.266106 -125.751336)
		(width 0.4572)
		(layer "F.Cu")
		(net "GND")
	)
	(segment
		(start 376.167904 -251.23013)
		(end 376.634756 -250.964192)
		(width 0.350012)
		(layer "F.Cu")
		(net "GND")
	)
	(segment
		(start 377.577858 -229.360222)
		(end 378.04471 -229.094284)
		(width 0.350012)
		(layer "F.Cu")
		(net "GND")
	)
	(segment
		(start 379.457966 -250.420124)
		(end 379.924818 -250.154186)
		(width 0.350012)
		(layer "F.Cu")
		(net "GND")
	)
	(segment
		(start 141.687804 -266.530328)
		(end 142.154656 -266.796266)
		(width 0.350012)
		(layer "F.Cu")
		(net "GND")
	)
	(segment
		(start 34.05251 -348.546166)
		(end 34.481008 -348.546166)
		(width 0.2286)
		(layer "F.Cu")
		(net "GND")
	)
	(segment
		(start 82.319114 -390.160002)
		(end 82.99831 -390.160002)
		(width 0.254)
		(layer "F.Cu")
		(net "GND")
	)
	(segment
		(start 324.790308 -402.462746)
		(end 324.981062 -402.6535)
		(width 0.254)
		(layer "F.Cu")
		(net "GND")
	)
	(segment
		(start 328.697844 -248.800112)
		(end 328.231246 -248.534174)
		(width 0.350012)
		(layer "F.Cu")
		(net "GND")
	)
	(segment
		(start 82.390234 -384.617722)
		(end 82.99831 -384.617722)
		(width 0.254)
		(layer "F.Cu")
		(net "GND")
	)
	(segment
		(start 336.598006 -392.999722)
		(end 336.545428 -392.30427)
		(width 0.254)
		(layer "F.Cu")
		(net "GND")
	)
	(segment
		(start 123.997974 -240.700306)
		(end 124.464826 -240.434368)
		(width 0.350012)
		(layer "F.Cu")
		(net "GND")
	)
	(segment
		(start 350.31807 -239.08004)
		(end 349.851218 -238.814102)
		(width 0.350012)
		(layer "F.Cu")
		(net "GND")
	)
	(segment
		(start 424.609006 -402.4757)
		(end 424.418252 -402.284946)
		(width 0.254)
		(layer "F.Cu")
		(net "GND")
	)
	(segment
		(start 366.297972 -243.940076)
		(end 366.764824 -243.674138)
		(width 0.350012)
		(layer "F.Cu")
		(net "GND")
	)
	(segment
		(start 342.158066 -268.960092)
		(end 341.691214 -269.22603)
		(width 0.350012)
		(layer "F.Cu")
		(net "GND")
	)
	(segment
		(start 123.517914 -390.761474)
		(end 123.570492 -390.160002)
		(width 0.254)
		(layer "F.Cu")
		(net "GND")
	)
	(segment
		(start 94.54896 -340.240874)
		(end 95.13697 -340.240874)
		(width 0.381)
		(layer "F.Cu")
		(net "GND")
	)
	(segment
		(start 83.845654 -391.281158)
		(end 84.145882 -390.761474)
		(width 0.254)
		(layer "F.Cu")
		(net "GND")
	)
	(segment
		(start 343.56802 -268.150086)
		(end 343.101168 -268.416024)
		(width 0.350012)
		(layer "F.Cu")
		(net "GND")
	)
	(segment
		(start 108.317792 -283.540454)
		(end 107.85094 -283.806392)
		(width 0.350012)
		(layer "F.Cu")
		(net "GND")
	)
	(segment
		(start 66.314828 -384.831082)
		(end 66.101468 -384.617722)
		(width 0.254)
		(layer "F.Cu")
		(net "GND")
	)
	(segment
		(start 315.370972 -31.429706)
		(end 314.761372 -31.429706)
		(width 0.3556)
		(layer "F.Cu")
		(net "GND")
	)
	(segment
		(start 431.55616 -202.434952)
		(end 430.17186 -202.434952)
		(width 0.4572)
		(layer "F.Cu")
		(net "GND")
	)
	(segment
		(start 365.828072 -226.930204)
		(end 366.294924 -226.664266)
		(width 0.350012)
		(layer "F.Cu")
		(net "GND")
	)
	(segment
		(start 50.470562 -384.617722)
		(end 49.862486 -384.617722)
		(width 0.254)
		(layer "F.Cu")
		(net "GND")
	)
	(segment
		(start 325.408036 -241.510058)
		(end 324.75297 -241.510058)
		(width 0.350012)
		(layer "F.Cu")
		(net "GND")
	)
	(segment
		(start 134.80796 -233.410252)
		(end 135.274812 -233.144314)
		(width 0.350012)
		(layer "F.Cu")
		(net "GND")
	)
	(segment
		(start 356.25786 -275.44014)
		(end 355.791008 -275.706078)
		(width 0.350012)
		(layer "F.Cu")
		(net "GND")
	)
	(segment
		(start 102.378002 -230.980234)
		(end 101.91115 -230.714296)
		(width 0.350012)
		(layer "F.Cu")
		(net "GND")
	)
	(segment
		(start 443.13348 -437.74741)
		(end 442.49848 -437.74741)
		(width 0.4318)
		(layer "F.Cu")
		(net "GND")
	)
	(segment
		(start 364.193328 -171.64431)
		(end 364.682278 -171.64431)
		(width 0.381)
		(layer "F.Cu")
		(net "GND")
	)
	(segment
		(start 265.54811 -315.485018)
		(end 266.93241 -315.485018)
		(width 0.4572)
		(layer "F.Cu")
		(net "GND")
	)
	(segment
		(start 336.987896 -287.59023)
		(end 336.521044 -287.856168)
		(width 0.350012)
		(layer "F.Cu")
		(net "GND")
	)
	(segment
		(start 149.377146 -64.437514)
		(end 149.377146 -65.194434)
		(width 0.4572)
		(layer "F.Cu")
		(net "GND")
	)
	(segment
		(start 287.570672 -412.34106)
		(end 287.570672 -411.69844)
		(width 0.381)
		(layer "F.Cu")
		(net "GND")
	)
	(segment
		(start 104.55783 -277.060406)
		(end 104.090978 -277.326344)
		(width 0.350012)
		(layer "F.Cu")
		(net "GND")
	)
	(segment
		(start 138.098022 -230.980234)
		(end 138.564874 -230.714296)
		(width 0.350012)
		(layer "F.Cu")
		(net "GND")
	)
	(segment
		(start 90.157808 -245.560342)
		(end 89.690956 -245.294404)
		(width 0.350012)
		(layer "F.Cu")
		(net "GND")
	)
	(segment
		(start 87.3379 -253.660402)
		(end 86.871048 -253.394464)
		(width 0.350012)
		(layer "F.Cu")
		(net "GND")
	)
	(segment
		(start 150.85568 -13.598652)
		(end 150.85568 -12.495022)
		(width 0.3556)
		(layer "F.Cu")
		(net "GND")
	)
	(segment
		(start 88.747854 -231.79024)
		(end 88.281002 -231.524302)
		(width 0.350012)
		(layer "F.Cu")
		(net "GND")
	)
	(segment
		(start 391.03808 -286.780224)
		(end 391.504678 -287.045908)
		(width 0.350012)
		(layer "F.Cu")
		(net "GND")
	)
	(segment
		(start 327.28789 -225.310192)
		(end 326.821038 -225.044254)
		(width 0.350012)
		(layer "F.Cu")
		(net "GND")
	)
	(segment
		(start 314.517786 -391.784586)
		(end 314.517786 -392.004296)
		(width 0.254)
		(layer "F.Cu")
		(net "GND")
	)
	(segment
		(start 114.428016 -269.770352)
		(end 114.894614 -270.03629)
		(width 0.350012)
		(layer "F.Cu")
		(net "GND")
	)
	(segment
		(start 431.55616 -302.73498)
		(end 430.17186 -302.73498)
		(width 0.4572)
		(layer "F.Cu")
		(net "GND")
	)
	(segment
		(start 384.157982 -235.840016)
		(end 384.624834 -235.574078)
		(width 0.350012)
		(layer "F.Cu")
		(net "GND")
	)
	(segment
		(start 119.97055 -390.160002)
		(end 119.291354 -390.160002)
		(width 0.254)
		(layer "F.Cu")
		(net "GND")
	)
	(segment
		(start 364.717838 -288.399982)
		(end 365.18469 -288.66592)
		(width 0.350012)
		(layer "F.Cu")
		(net "GND")
	)
	(segment
		(start 345.447874 -269.770098)
		(end 344.981022 -270.036036)
		(width 0.350012)
		(layer "F.Cu")
		(net "GND")
	)
	(segment
		(start 100.797868 -293.260272)
		(end 100.331016 -293.52621)
		(width 0.350012)
		(layer "F.Cu")
		(net "GND")
	)
	(segment
		(start 410.545788 -391.784586)
		(end 410.545788 -392.004296)
		(width 0.254)
		(layer "F.Cu")
		(net "GND")
	)
	(segment
		(start 27.69616 -351.932748)
		(end 28.28417 -351.932748)
		(width 0.381)
		(layer "F.Cu")
		(net "GND")
	)
	(segment
		(start 325.408036 -239.890046)
		(end 324.75297 -239.890046)
		(width 0.350012)
		(layer "F.Cu")
		(net "GND")
	)
	(segment
		(start 322.31457 -395.613128)
		(end 322.070476 -395.369034)
		(width 0.254)
		(layer "F.Cu")
		(net "GND")
	)
	(segment
		(start 164.498274 -388.138924)
		(end 163.946332 -388.328662)
		(width 0.254)
		(layer "F.Cu")
		(net "GND")
	)
	(segment
		(start 84.347812 -277.870412)
		(end 83.88096 -278.13635)
		(width 0.350012)
		(layer "F.Cu")
		(net "GND")
	)
	(segment
		(start 114.562382 -384.617722)
		(end 115.170458 -384.617722)
		(width 0.254)
		(layer "F.Cu")
		(net "GND")
	)
	(segment
		(start 53.462428 -384.617722)
		(end 54.070504 -384.617722)
		(width 0.254)
		(layer "F.Cu")
		(net "GND")
	)
	(segment
		(start 79.14894 -385.43103)
		(end 79.14894 -384.86715)
		(width 0.254)
		(layer "F.Cu")
		(net "GND")
	)
	(segment
		(start 356.728014 -289.209988)
		(end 356.261162 -289.475926)
		(width 0.350012)
		(layer "F.Cu")
		(net "GND")
	)
	(segment
		(start 81.058004 -281.920442)
		(end 80.591152 -282.18638)
		(width 0.350012)
		(layer "F.Cu")
		(net "GND")
	)
	(segment
		(start 79.347822 -225.310446)
		(end 78.88097 -225.044508)
		(width 0.350012)
		(layer "F.Cu")
		(net "GND")
	)
	(segment
		(start 66.552064 -163.71697)
		(end 66.482214 -163.78682)
		(width 0.381)
		(layer "F.Cu")
		(net "GND")
	)
	(segment
		(start 384.465576 -56.4134)
		(end 384.465576 -56.048148)
		(width 0.4572)
		(layer "F.Cu")
		(net "GND")
	)
	(segment
		(start 63.61811 -390.761474)
		(end 63.670688 -390.160002)
		(width 0.254)
		(layer "F.Cu")
		(net "GND")
	)
	(segment
		(start 347.797882 -275.44014)
		(end 347.33103 -275.706078)
		(width 0.350012)
		(layer "F.Cu")
		(net "GND")
	)
	(segment
		(start 80.757776 -248.800366)
		(end 80.291178 -248.534428)
		(width 0.350012)
		(layer "F.Cu")
		(net "GND")
	)
	(segment
		(start 76.0603 -383.7432)
		(end 76.5937 -383.7432)
		(width 0.254)
		(layer "F.Cu")
		(net "GND")
	)
	(segment
		(start 29.252164 -302.735234)
		(end 27.867864 -302.735234)
		(width 0.4572)
		(layer "F.Cu")
		(net "GND")
	)
	(segment
		(start 343.56802 -263.29005)
		(end 343.101168 -263.555988)
		(width 0.350012)
		(layer "F.Cu")
		(net "GND")
	)
	(segment
		(start 403.963378 -134.931404)
		(end 404.676356 -134.931404)
		(width 0.4572)
		(layer "F.Cu")
		(net "GND")
	)
	(segment
		(start 406.746202 -396.710662)
		(end 406.098248 -396.520924)
		(width 0.254)
		(layer "F.Cu")
		(net "GND")
	)
	(segment
		(start 393.046966 -7.217156)
		(end 393.046966 -8.320024)
		(width 0.3556)
		(layer "F.Cu")
		(net "GND")
	)
	(segment
		(start 115.170458 -388.138924)
		(end 114.618516 -388.328662)
		(width 0.254)
		(layer "F.Cu")
		(net "GND")
	)
	(segment
		(start 131.817872 -290.020248)
		(end 132.284724 -290.286186)
		(width 0.350012)
		(layer "F.Cu")
		(net "GND")
	)
	(segment
		(start 338.868004 -294.070024)
		(end 338.401152 -294.335962)
		(width 0.350012)
		(layer "F.Cu")
		(net "GND")
	)
	(segment
		(start 334.337914 -222.880174)
		(end 333.871062 -222.614236)
		(width 0.350012)
		(layer "F.Cu")
		(net "GND")
	)
	(segment
		(start 85.757766 -268.960346)
		(end 85.290914 -269.226284)
		(width 0.350012)
		(layer "F.Cu")
		(net "GND")
	)
	(segment
		(start 369.594892 -400.15795)
		(end 369.594892 -399.686272)
		(width 0.254)
		(layer "F.Cu")
		(net "GND")
	)
	(segment
		(start 392.963146 -321.632834)
		(end 392.963146 -320.637154)
		(width 0.508)
		(layer "F.Cu")
		(net "GND")
	)
	(segment
		(start 105.497884 -288.400236)
		(end 105.031032 -288.666174)
		(width 0.350012)
		(layer "F.Cu")
		(net "GND")
	)
	(segment
		(start 190.94958 -413.564832)
		(end 190.312294 -413.564832)
		(width 0.381)
		(layer "F.Cu")
		(net "GND")
	)
	(segment
		(start 152.145746 -391.281158)
		(end 152.244298 -391.37971)
		(width 0.254)
		(layer "F.Cu")
		(net "GND")
	)
	(segment
		(start 419.58514 -59.197748)
		(end 420.222426 -59.197748)
		(width 0.4572)
		(layer "F.Cu")
		(net "GND")
	)
	(segment
		(start 113.487962 -266.530328)
		(end 113.954814 -266.796266)
		(width 0.350012)
		(layer "F.Cu")
		(net "GND")
	)
	(segment
		(start 365.657892 -288.399982)
		(end 366.124744 -288.66592)
		(width 0.350012)
		(layer "F.Cu")
		(net "GND")
	)
	(segment
		(start 141.687804 -276.2504)
		(end 142.154656 -276.516338)
		(width 0.350012)
		(layer "F.Cu")
		(net "GND")
	)
	(segment
		(start 101.437948 -226.120452)
		(end 100.971096 -225.854514)
		(width 0.350012)
		(layer "F.Cu")
		(net "GND")
	)
	(segment
		(start 417.490148 -392.999722)
		(end 416.898328 -392.999722)
		(width 0.254)
		(layer "F.Cu")
		(net "GND")
	)
	(segment
		(start 79.918814 -390.160002)
		(end 80.598264 -390.160002)
		(width 0.254)
		(layer "F.Cu")
		(net "GND")
	)
	(segment
		(start 86.868 -241.510312)
		(end 86.401148 -241.244374)
		(width 0.350012)
		(layer "F.Cu")
		(net "GND")
	)
	(segment
		(start 113.721134 -390.231122)
		(end 113.721134 -389.63092)
		(width 0.254)
		(layer "F.Cu")
		(net "GND")
	)
	(segment
		(start 144.977866 -285.160466)
		(end 145.444718 -285.426404)
		(width 0.350012)
		(layer "F.Cu")
		(net "GND")
	)
	(segment
		(start 349.67799 -294.88003)
		(end 349.211138 -295.145968)
		(width 0.350012)
		(layer "F.Cu")
		(net "GND")
	)
	(segment
		(start 61.55817 -351.932748)
		(end 61.62802 -351.862898)
		(width 0.381)
		(layer "F.Cu")
		(net "GND")
	)
	(segment
		(start 328.227944 -241.510058)
		(end 327.761092 -241.24412)
		(width 0.350012)
		(layer "F.Cu")
		(net "GND")
	)
	(segment
		(start 338.868004 -287.59023)
		(end 338.401152 -287.856168)
		(width 0.350012)
		(layer "F.Cu")
		(net "GND")
	)
	(segment
		(start 139.507976 -230.170228)
		(end 139.974828 -229.90429)
		(width 0.350012)
		(layer "F.Cu")
		(net "GND")
	)
	(segment
		(start 44.340018 -230.485442)
		(end 42.955718 -230.485442)
		(width 0.4572)
		(layer "F.Cu")
		(net "GND")
	)
	(segment
		(start 183.616092 -211.7852)
		(end 182.231792 -211.7852)
		(width 0.4572)
		(layer "F.Cu")
		(net "GND")
	)
	(segment
		(start 97.207832 -246.370348)
		(end 96.74098 -246.10441)
		(width 0.350012)
		(layer "F.Cu")
		(net "GND")
	)
	(segment
		(start 447.16192 -11.26998)
		(end 447.16192 -12.372848)
		(width 0.3556)
		(layer "F.Cu")
		(net "GND")
	)
	(segment
		(start 141.687804 -279.490424)
		(end 142.154656 -279.756362)
		(width 0.350012)
		(layer "F.Cu")
		(net "GND")
	)
	(segment
		(start 228.921056 -291.361876)
		(end 230.026972 -291.361876)
		(width 0.1778)
		(layer "F.Cu")
		(net "GND")
	)
	(segment
		(start 299.543724 -394.800074)
		(end 299.543724 -393.97559)
		(width 0.254)
		(layer "F.Cu")
		(net "GND")
	)
	(segment
		(start 100.797868 -280.30043)
		(end 100.331016 -280.566368)
		(width 0.350012)
		(layer "F.Cu")
		(net "GND")
	)
	(segment
		(start 353.607878 -235.03001)
		(end 353.141026 -234.764072)
		(width 0.350012)
		(layer "F.Cu")
		(net "GND")
	)
	(segment
		(start 58.26252 -384.617722)
		(end 57.6707 -384.617722)
		(width 0.254)
		(layer "F.Cu")
		(net "GND")
	)
	(segment
		(start 377.762262 -392.999722)
		(end 378.370592 -392.999722)
		(width 0.254)
		(layer "F.Cu")
		(net "GND")
	)
	(segment
		(start 132.927852 -233.410252)
		(end 133.394704 -233.144314)
		(width 0.350012)
		(layer "F.Cu")
		(net "GND")
	)
	(segment
		(start 402.248878 -398.946624)
		(end 402.445728 -399.143474)
		(width 0.254)
		(layer "F.Cu")
		(net "GND")
	)
	(segment
		(start 447.919602 -429.01616)
		(end 447.919602 -429.63211)
		(width 0.4572)
		(layer "F.Cu")
		(net "GND")
	)
	(segment
		(start 424.012106 -237.285022)
		(end 422.627806 -237.285022)
		(width 0.4572)
		(layer "F.Cu")
		(net "GND")
	)
	(segment
		(start 150.606252 -386.449062)
		(end 150.098252 -386.6388)
		(width 0.254)
		(layer "F.Cu")
		(net "GND")
	)
	(segment
		(start 347.918786 -398.542002)
		(end 347.398086 -398.542002)
		(width 0.254)
		(layer "F.Cu")
		(net "GND")
	)
	(segment
		(start 124.467874 -252.850396)
		(end 124.934726 -252.584458)
		(width 0.350012)
		(layer "F.Cu")
		(net "GND")
	)
	(segment
		(start 462.120996 -103.614728)
		(end 462.120996 -104.249728)
		(width 0.3556)
		(layer "F.Cu")
		(net "GND")
	)
	(segment
		(start 343.057988 -171.308522)
		(end 341.96909 -171.308522)
		(width 0.254)
		(layer "F.Cu")
		(net "GND")
	)
	(segment
		(start 362.837984 -291.640006)
		(end 363.304836 -291.905944)
		(width 0.350012)
		(layer "F.Cu")
		(net "GND")
	)
	(segment
		(start 435.000146 -303.585118)
		(end 436.384446 -303.585118)
		(width 0.4572)
		(layer "F.Cu")
		(net "GND")
	)
	(segment
		(start 330.910946 -141.36243)
		(end 331.262482 -141.36243)
		(width 0.254)
		(layer "F.Cu")
		(net "GND")
	)
	(segment
		(start 305.016154 -403.143466)
		(end 305.016154 -402.284438)
		(width 0.381)
		(layer "F.Cu")
		(net "GND")
	)
	(segment
		(start 60.491624 -180.891942)
		(end 60.920122 -180.891942)
		(width 0.381)
		(layer "F.Cu")
		(net "GND")
	)
	(segment
		(start 280.635964 -294.235124)
		(end 282.020264 -294.235124)
		(width 0.4572)
		(layer "F.Cu")
		(net "GND")
	)
	(segment
		(start 118.357904 -240.700306)
		(end 118.824756 -240.434368)
		(width 0.350012)
		(layer "F.Cu")
		(net "GND")
	)
	(segment
		(start 98.617786 -222.880428)
		(end 98.150934 -222.61449)
		(width 0.350012)
		(layer "F.Cu")
		(net "GND")
	)
	(segment
		(start 131.29133 -390.160002)
		(end 130.77063 -390.160002)
		(width 0.254)
		(layer "F.Cu")
		(net "GND")
	)
	(segment
		(start 320.19113 -398.542002)
		(end 319.67043 -398.542002)
		(width 0.254)
		(layer "F.Cu")
		(net "GND")
	)
	(segment
		(start 378.048012 -243.13007)
		(end 378.514864 -242.864132)
		(width 0.350012)
		(layer "F.Cu")
		(net "GND")
	)
	(segment
		(start 164.225224 -428.90567)
		(end 164.041328 -428.721774)
		(width 0.3048)
		(layer "F.Cu")
		(net "GND")
	)
	(segment
		(start 362.53801 -226.120198)
		(end 363.004862 -225.85426)
		(width 0.350012)
		(layer "F.Cu")
		(net "GND")
	)
	(segment
		(start 182.603394 -356.507034)
		(end 182.673244 -356.437184)
		(width 0.381)
		(layer "F.Cu")
		(net "GND")
	)
	(segment
		(start 131.817872 -277.060406)
		(end 132.284724 -277.326344)
		(width 0.350012)
		(layer "F.Cu")
		(net "GND")
	)
	(segment
		(start 136.687814 -228.55047)
		(end 137.154666 -228.284532)
		(width 0.350012)
		(layer "F.Cu")
		(net "GND")
	)
	(segment
		(start 429.566832 -7.217156)
		(end 429.566832 -8.320024)
		(width 0.3556)
		(layer "F.Cu")
		(net "GND")
	)
	(segment
		(start 116.30787 -292.450266)
		(end 116.774722 -292.716204)
		(width 0.350012)
		(layer "F.Cu")
		(net "GND")
	)
	(segment
		(start 392.917934 -270.580104)
		(end 393.384786 -270.846042)
		(width 0.350012)
		(layer "F.Cu")
		(net "GND")
	)
	(segment
		(start 130.407918 -290.830254)
		(end 130.87477 -291.096192)
		(width 0.350012)
		(layer "F.Cu")
		(net "GND")
	)
	(segment
		(start 372.707916 -266.530074)
		(end 373.174768 -266.796012)
		(width 0.350012)
		(layer "F.Cu")
		(net "GND")
	)
	(segment
		(start 125.707902 -292.450266)
		(end 126.174754 -292.716204)
		(width 0.350012)
		(layer "F.Cu")
		(net "GND")
	)
	(segment
		(start 97.990152 -384.617722)
		(end 98.629216 -384.617722)
		(width 0.254)
		(layer "F.Cu")
		(net "GND")
	)
	(segment
		(start 197.999858 -388.160514)
		(end 199.206358 -388.160514)
		(width 0.4572)
		(layer "F.Cu")
		(net "GND")
	)
	(segment
		(start 407.044144 -399.76171)
		(end 406.945592 -399.663158)
		(width 0.254)
		(layer "F.Cu")
		(net "GND")
	)
	(segment
		(start 297.536362 -348.54134)
		(end 297.96486 -348.54134)
		(width 0.2286)
		(layer "F.Cu")
		(net "GND")
	)
	(segment
		(start 355.062028 -396.813024)
		(end 354.842318 -396.813024)
		(width 0.254)
		(layer "F.Cu")
		(net "GND")
	)
	(segment
		(start 322.31457 -393.213082)
		(end 322.31457 -393.59332)
		(width 0.254)
		(layer "F.Cu")
		(net "GND")
	)
	(segment
		(start 345.618054 -243.940076)
		(end 345.151202 -243.674138)
		(width 0.350012)
		(layer "F.Cu")
		(net "GND")
	)
	(segment
		(start 93.11894 -390.160002)
		(end 93.79839 -390.160002)
		(width 0.254)
		(layer "F.Cu")
		(net "GND")
	)
	(segment
		(start 237.527846 -149.923754)
		(end 237.654846 -150.050754)
		(width 0.3556)
		(layer "F.Cu")
		(net "GND")
	)
	(segment
		(start 82.467958 -274.630388)
		(end 82.001106 -274.896326)
		(width 0.350012)
		(layer "F.Cu")
		(net "GND")
	)
	(segment
		(start 335.577942 -277.060152)
		(end 335.11109 -277.32609)
		(width 0.350012)
		(layer "F.Cu")
		(net "GND")
	)
	(segment
		(start 368.64798 -251.23013)
		(end 369.114832 -250.964192)
		(width 0.350012)
		(layer "F.Cu")
		(net "GND")
	)
	(segment
		(start 379.75794 -262.480044)
		(end 380.224792 -262.745982)
		(width 0.350012)
		(layer "F.Cu")
		(net "GND")
	)
	(segment
		(start 341.687912 -261.670038)
		(end 341.22106 -261.935976)
		(width 0.350012)
		(layer "F.Cu")
		(net "GND")
	)
	(segment
		(start 84.047838 -233.410252)
		(end 83.580986 -233.144314)
		(width 0.350012)
		(layer "F.Cu")
		(net "GND")
	)
	(segment
		(start 297.670982 -351.973896)
		(end 297.30319 -351.973896)
		(width 0.381)
		(layer "F.Cu")
		(net "GND")
	)
	(segment
		(start 339.977984 -255.28016)
		(end 339.511132 -255.014222)
		(width 0.350012)
		(layer "F.Cu")
		(net "GND")
	)
	(segment
		(start 123.52782 -246.370348)
		(end 123.994672 -246.10441)
		(width 0.350012)
		(layer "F.Cu")
		(net "GND")
	)
	(segment
		(start 340.145624 -399.143474)
		(end 340.198202 -398.542002)
		(width 0.254)
		(layer "F.Cu")
		(net "GND")
	)
	(segment
		(start 439.100214 -199.885046)
		(end 437.715914 -199.885046)
		(width 0.4572)
		(layer "F.Cu")
		(net "GND")
	)
	(segment
		(start 392.61796 -243.940076)
		(end 393.084812 -243.674138)
		(width 0.350012)
		(layer "F.Cu")
		(net "GND")
	)
	(segment
		(start 43.85818 -12.37488)
		(end 43.85818 -12.374118)
		(width 0.3556)
		(layer "F.Cu")
		(net "GND")
	)
	(segment
		(start 108.044996 -404.061422)
		(end 107.654598 -404.45182)
		(width 0.381)
		(layer "F.Cu")
		(net "GND")
	)
	(segment
		(start 53.265832 -7.215124)
		(end 53.265832 -7.215886)
		(width 0.3556)
		(layer "F.Cu")
		(net "GND")
	)
	(segment
		(start 317.791084 -398.542002)
		(end 317.270384 -398.542002)
		(width 0.254)
		(layer "F.Cu")
		(net "GND")
	)
	(segment
		(start 302.401478 -395.613128)
		(end 302.620934 -395.613128)
		(width 0.254)
		(layer "F.Cu")
		(net "GND")
	)
	(segment
		(start 284.736032 -218.585034)
		(end 283.351732 -218.585034)
		(width 0.4572)
		(layer "F.Cu")
		(net "GND")
	)
	(segment
		(start 350.618044 -265.720068)
		(end 350.151192 -265.986006)
		(width 0.350012)
		(layer "F.Cu")
		(net "GND")
	)
	(segment
		(start 394.027914 -223.69018)
		(end 394.494766 -223.424242)
		(width 0.350012)
		(layer "F.Cu")
		(net "GND")
	)
	(segment
		(start 366.297972 -234.220004)
		(end 366.764824 -233.954066)
		(width 0.350012)
		(layer "F.Cu")
		(net "GND")
	)
	(segment
		(start 25.748234 -12.374118)
		(end 25.746964 -12.372848)
		(width 0.3556)
		(layer "F.Cu")
		(net "GND")
	)
	(segment
		(start 96.198436 -388.138924)
		(end 96.84639 -388.328662)
		(width 0.254)
		(layer "F.Cu")
		(net "GND")
	)
	(segment
		(start 360.957876 -290.019994)
		(end 361.424728 -290.285932)
		(width 0.350012)
		(layer "F.Cu")
		(net "GND")
	)
	(segment
		(start 277.192232 -218.585034)
		(end 275.807932 -218.585034)
		(width 0.4572)
		(layer "F.Cu")
		(net "GND")
	)
	(segment
		(start 133.398006 -243.94033)
		(end 133.864858 -243.674392)
		(width 0.350012)
		(layer "F.Cu")
		(net "GND")
	)
	(segment
		(start 429.622458 -398.91208)
		(end 429.22952 -399.305018)
		(width 0.254)
		(layer "F.Cu")
		(net "GND")
	)
	(segment
		(start 100.797868 -265.720322)
		(end 100.331016 -265.98626)
		(width 0.350012)
		(layer "F.Cu")
		(net "GND")
	)
	(segment
		(start 118.657878 -270.580358)
		(end 119.12473 -270.846296)
		(width 0.350012)
		(layer "F.Cu")
		(net "GND")
	)
	(segment
		(start 356.25786 -293.260018)
		(end 355.791008 -293.525956)
		(width 0.350012)
		(layer "F.Cu")
		(net "GND")
	)
	(segment
		(start 402.445728 -399.143474)
		(end 402.145754 -399.663158)
		(width 0.254)
		(layer "F.Cu")
		(net "GND")
	)
	(segment
		(start 345.1479 -233.409998)
		(end 344.681048 -233.14406)
		(width 0.350012)
		(layer "F.Cu")
		(net "GND")
	)
	(segment
		(start 389.414766 -395.613128)
		(end 389.414766 -396.213076)
		(width 0.254)
		(layer "F.Cu")
		(net "GND")
	)
	(segment
		(start 79.045816 -383.402586)
		(end 79.045816 -383.622296)
		(width 0.254)
		(layer "F.Cu")
		(net "GND")
	)
	(segment
		(start 362.837984 -267.34008)
		(end 363.304836 -267.606018)
		(width 0.350012)
		(layer "F.Cu")
		(net "GND")
	)
	(segment
		(start 78.877922 -250.420378)
		(end 78.41107 -250.15444)
		(width 0.350012)
		(layer "F.Cu")
		(net "GND")
	)
	(segment
		(start 409.792678 -139.762992)
		(end 409.034742 -140.520928)
		(width 0.3556)
		(layer "F.Cu")
		(net "GND")
	)
	(segment
		(start 149.7457 -383.622296)
		(end 150.045674 -383.92227)
		(width 0.254)
		(layer "F.Cu")
		(net "GND")
	)
	(segment
		(start 143.267938 -246.370348)
		(end 143.73479 -246.10441)
		(width 0.350012)
		(layer "F.Cu")
		(net "GND")
	)
	(segment
		(start 344.977974 -275.44014)
		(end 344.511122 -275.706078)
		(width 0.350012)
		(layer "F.Cu")
		(net "GND")
	)
	(segment
		(start 311.862216 -392.999722)
		(end 312.470292 -392.999722)
		(width 0.254)
		(layer "F.Cu")
		(net "GND")
	)
	(segment
		(start 366.297972 -245.560088)
		(end 366.764824 -245.29415)
		(width 0.350012)
		(layer "F.Cu")
		(net "GND")
	)
	(segment
		(start 338.097876 -226.120198)
		(end 337.631024 -225.85426)
		(width 0.350012)
		(layer "F.Cu")
		(net "GND")
	)
	(segment
		(start 125.970538 -388.138924)
		(end 125.418342 -388.328662)
		(width 0.254)
		(layer "F.Cu")
		(net "GND")
	)
	(segment
		(start 421.942514 -396.213076)
		(end 421.146224 -396.710662)
		(width 0.254)
		(layer "F.Cu")
		(net "GND")
	)
	(segment
		(start 345.8337 -16.399256)
		(end 345.8337 -17.085056)
		(width 0.4572)
		(layer "F.Cu")
		(net "GND")
	)
	(segment
		(start 366.297972 -239.08004)
		(end 366.764824 -238.814102)
		(width 0.350012)
		(layer "F.Cu")
		(net "GND")
	)
	(segment
		(start 328.527918 -274.630134)
		(end 328.061066 -274.896072)
		(width 0.350012)
		(layer "F.Cu")
		(net "GND")
	)
	(segment
		(start 130.77063 -390.160002)
		(end 130.09118 -390.160002)
		(width 0.254)
		(layer "F.Cu")
		(net "GND")
	)
	(segment
		(start 77.467968 -249.610372)
		(end 76.812902 -249.610372)
		(width 0.350012)
		(layer "F.Cu")
		(net "GND")
	)
	(segment
		(start 393.387834 -294.070024)
		(end 393.854686 -294.335962)
		(width 0.350012)
		(layer "F.Cu")
		(net "GND")
	)
	(segment
		(start 126.817882 -227.740464)
		(end 127.284734 -227.474526)
		(width 0.350012)
		(layer "F.Cu")
		(net "GND")
	)
	(segment
		(start 123.778264 -51.185064)
		(end 123.5964 -51.0032)
		(width 0.4572)
		(layer "F.Cu")
		(net "GND")
	)
	(segment
		(start 425.96689 -8.320024)
		(end 425.96689 -9.423654)
		(width 0.3556)
		(layer "F.Cu")
		(net "GND")
	)
	(segment
		(start 82.645758 -383.622296)
		(end 82.945732 -383.92227)
		(width 0.254)
		(layer "F.Cu")
		(net "GND")
	)
	(segment
		(start 55.328058 -296.785284)
		(end 56.712358 -296.785284)
		(width 0.4572)
		(layer "F.Cu")
		(net "GND")
	)
	(segment
		(start 375.617994 -391.784586)
		(end 375.617994 -392.004296)
		(width 0.2032)
		(layer "F.Cu")
		(net "GND")
	)
	(segment
		(start 155.745688 -383.622296)
		(end 156.045662 -383.92227)
		(width 0.254)
		(layer "F.Cu")
		(net "GND")
	)
	(segment
		(start 366.128046 -282.730194)
		(end 366.594898 -282.996132)
		(width 0.350012)
		(layer "F.Cu")
		(net "GND")
	)
	(segment
		(start 59.71794 -382.951482)
		(end 59.816492 -382.85293)
		(width 0.254)
		(layer "F.Cu")
		(net "GND")
	)
	(segment
		(start 447.16192 -7.217156)
		(end 447.16065 -7.215886)
		(width 0.3556)
		(layer "F.Cu")
		(net "GND")
	)
	(segment
		(start 384.157982 -230.97998)
		(end 384.624834 -230.714296)
		(width 0.350012)
		(layer "F.Cu")
		(net "GND")
	)
	(segment
		(start 230.244142 -294.936926)
		(end 230.244142 -294.277796)
		(width 0.381)
		(layer "F.Cu")
		(net "GND")
	)
	(segment
		(start 450.088 -306.135024)
		(end 451.4723 -306.135024)
		(width 0.4572)
		(layer "F.Cu")
		(net "GND")
	)
	(segment
		(start 230.96728 -56.964834)
		(end 230.967534 -56.965088)
		(width 0.381)
		(layer "F.Cu")
		(net "GND")
	)
	(segment
		(start 90.457782 -278.680418)
		(end 89.99093 -278.946356)
		(width 0.350012)
		(layer "F.Cu")
		(net "GND")
	)
	(segment
		(start 79.14894 -386.630926)
		(end 79.906368 -386.449062)
		(width 0.254)
		(layer "F.Cu")
		(net "GND")
	)
	(segment
		(start 382.817878 -399.663158)
		(end 383.117852 -399.143474)
		(width 0.254)
		(layer "F.Cu")
		(net "GND")
	)
	(segment
		(start 339.977984 -240.700052)
		(end 339.511132 -240.434114)
		(width 0.350012)
		(layer "F.Cu")
		(net "GND")
	)
	(segment
		(start 394.027914 -236.650022)
		(end 394.68298 -236.650022)
		(width 0.350012)
		(layer "F.Cu")
		(net "GND")
	)
	(segment
		(start 77.767942 -282.730448)
		(end 77.112876 -282.730448)
		(width 0.350012)
		(layer "F.Cu")
		(net "GND")
	)
	(segment
		(start 93.445838 -383.622296)
		(end 93.745812 -383.92227)
		(width 0.254)
		(layer "F.Cu")
		(net "GND")
	)
	(segment
		(start 414.14573 -399.663158)
		(end 414.445704 -399.143474)
		(width 0.254)
		(layer "F.Cu")
		(net "GND")
	)
	(segment
		(start 389.627872 -274.630134)
		(end 390.094724 -274.896072)
		(width 0.350012)
		(layer "F.Cu")
		(net "GND")
	)
	(segment
		(start 361.08259 -390.652)
		(end 361.3023 -390.652)
		(width 0.254)
		(layer "F.Cu")
		(net "GND")
	)
	(segment
		(start 15.42161 -133.789166)
		(end 13.796518 -133.789166)
		(width 0.2286)
		(layer "F.Cu")
		(net "GND")
	)
	(segment
		(start 11.895836 -92.287598)
		(end 11.895836 -91.658948)
		(width 0.3556)
		(layer "F.Cu")
		(net "GND")
	)
	(segment
		(start 382.748028 -236.650022)
		(end 383.21488 -236.384084)
		(width 0.350012)
		(layer "F.Cu")
		(net "GND")
	)
	(segment
		(start 79.906368 -386.449062)
		(end 80.598264 -386.6388)
		(width 0.254)
		(layer "F.Cu")
		(net "GND")
	)
	(segment
		(start 96.737932 -248.800366)
		(end 96.27108 -248.534428)
		(width 0.350012)
		(layer "F.Cu")
		(net "GND")
	)
	(segment
		(start 366.597946 -281.920188)
		(end 367.064798 -282.186126)
		(width 0.350012)
		(layer "F.Cu")
		(net "GND")
	)
	(segment
		(start 187.522104 -113.85296)
		(end 187.911994 -113.46307)
		(width 0.254)
		(layer "F.Cu")
		(net "GND")
	)
	(segment
		(start 25.152096 -278.085296)
		(end 26.536396 -278.085296)
		(width 0.4572)
		(layer "F.Cu")
		(net "GND")
	)
	(segment
		(start 180.32222 -120.252744)
		(end 179.93233 -120.642634)
		(width 0.254)
		(layer "F.Cu")
		(net "GND")
	)
	(segment
		(start 104.731058 -224.234502)
		(end 105.19791 -224.50044)
		(width 0.350012)
		(layer "F.Cu")
		(net "GND")
	)
	(segment
		(start 421.180006 -432.876198)
		(end 421.777414 -432.876198)
		(width 0.381)
		(layer "F.Cu")
		(net "GND")
	)
	(segment
		(start 331.81798 -275.44014)
		(end 331.351128 -275.706078)
		(width 0.350012)
		(layer "F.Cu")
		(net "GND")
	)
	(segment
		(start 46.621192 -390.231122)
		(end 46.621192 -390.564624)
		(width 0.254)
		(layer "F.Cu")
		(net "GND")
	)
	(segment
		(start 108.787946 -269.770352)
		(end 108.321094 -270.03629)
		(width 0.350012)
		(layer "F.Cu")
		(net "GND")
	)
	(segment
		(start 79.14894 -389.030972)
		(end 79.14894 -388.330948)
		(width 0.254)
		(layer "F.Cu")
		(net "GND")
	)
	(segment
		(start 348.83852 -341.75954)
		(end 349.266002 -341.75954)
		(width 0.2286)
		(layer "F.Cu")
		(net "GND")
	)
	(segment
		(start 146.248882 -386.030978)
		(end 146.248882 -386.630926)
		(width 0.254)
		(layer "F.Cu")
		(net "GND")
	)
	(segment
		(start 50.461926 -348.79915)
		(end 50.71491 -348.546166)
		(width 0.2286)
		(layer "F.Cu")
		(net "GND")
	)
	(segment
		(start 278.006556 -435.823614)
		(end 277.37562 -435.823614)
		(width 0.381)
		(layer "F.Cu")
		(net "GND")
	)
	(segment
		(start 105.918 -426.86605)
		(end 105.918 -427.609)
		(width 0.381)
		(layer "F.Cu")
		(net "GND")
	)
	(segment
		(start 384.627882 -243.13007)
		(end 385.094734 -242.864132)
		(width 0.350012)
		(layer "F.Cu")
		(net "GND")
	)
	(segment
		(start 136.987788 -271.390364)
		(end 137.45464 -271.656302)
		(width 0.350012)
		(layer "F.Cu")
		(net "GND")
	)
	(segment
		(start 58.666888 -9.423654)
		(end 58.668158 -9.424924)
		(width 0.3556)
		(layer "F.Cu")
		(net "GND")
	)
	(segment
		(start 11.3284 -71.210678)
		(end 12.0142 -71.210678)
		(width 0.4064)
		(layer "F.Cu")
		(net "GND")
	)
	(segment
		(start 143.740632 -95.612458)
		(end 142.800832 -95.612458)
		(width 0.3556)
		(layer "F.Cu")
		(net "GND")
	)
	(segment
		(start 43.85691 -7.217156)
		(end 43.85691 -8.320024)
		(width 0.3556)
		(layer "F.Cu")
		(net "GND")
	)
	(segment
		(start 409.050744 -142.009368)
		(end 408.713178 -142.009368)
		(width 0.381)
		(layer "F.Cu")
		(net "GND")
	)
	(segment
		(start 141.687804 -290.830254)
		(end 142.154656 -291.096192)
		(width 0.350012)
		(layer "F.Cu")
		(net "GND")
	)
	(segment
		(start 239.13592 -291.863526)
		(end 239.13592 -291.406326)
		(width 0.4572)
		(layer "F.Cu")
		(net "GND")
	)
	(segment
		(start 111.137954 -286.780478)
		(end 110.671102 -287.046162)
		(width 0.350012)
		(layer "F.Cu")
		(net "GND")
	)
	(segment
		(start 445.363092 -12.374118)
		(end 445.363092 -12.37488)
		(width 0.3556)
		(layer "F.Cu")
		(net "GND")
	)
	(segment
		(start 93.44787 -233.410252)
		(end 92.981018 -233.144314)
		(width 0.350012)
		(layer "F.Cu")
		(net "GND")
	)
	(segment
		(start 295.724072 -203.28509)
		(end 297.108372 -203.28509)
		(width 0.4572)
		(layer "F.Cu")
		(net "GND")
	)
	(segment
		(start 118.187978 -274.630388)
		(end 118.65483 -274.896326)
		(width 0.350012)
		(layer "F.Cu")
		(net "GND")
	)
	(segment
		(start 384.927856 -266.530074)
		(end 385.394708 -266.796012)
		(width 0.350012)
		(layer "F.Cu")
		(net "GND")
	)
	(segment
		(start 118.357904 -247.180354)
		(end 118.824756 -246.914416)
		(width 0.350012)
		(layer "F.Cu")
		(net "GND")
	)
	(segment
		(start 77.042518 -175.273462)
		(end 77.042518 -175.547782)
		(width 0.2286)
		(layer "F.Cu")
		(net "GND")
	)
	(segment
		(start 411.844236 -399.76171)
		(end 411.844236 -400.212814)
		(width 0.254)
		(layer "F.Cu")
		(net "GND")
	)
	(segment
		(start 66.757042 -338.065364)
		(end 67.237356 -337.58505)
		(width 0.2286)
		(layer "F.Cu")
		(net "GND")
	)
	(segment
		(start 100.797868 -262.480298)
		(end 100.331016 -262.746236)
		(width 0.350012)
		(layer "F.Cu")
		(net "GND")
	)
	(segment
		(start 32.695896 -228.78542)
		(end 34.080196 -228.78542)
		(width 0.4572)
		(layer "F.Cu")
		(net "GND")
	)
	(segment
		(start 192.577466 -389.880602)
		(end 195.88988 -389.880602)
		(width 0.4572)
		(layer "F.Cu")
		(net "GND")
	)
	(segment
		(start 451.810628 -397.720312)
		(end 451.427342 -397.720312)
		(width 0.2032)
		(layer "F.Cu")
		(net "GND")
	)
	(segment
		(start 335.577942 -293.260018)
		(end 335.11109 -293.525956)
		(width 0.350012)
		(layer "F.Cu")
		(net "GND")
	)
	(segment
		(start 394.027914 -252.850142)
		(end 394.68298 -252.850142)
		(width 0.350012)
		(layer "F.Cu")
		(net "GND")
	)
	(segment
		(start 351.25787 -240.700052)
		(end 350.791018 -240.434114)
		(width 0.350012)
		(layer "F.Cu")
		(net "GND")
	)
	(segment
		(start 392.14806 -222.070168)
		(end 392.614912 -221.80423)
		(width 0.350012)
		(layer "F.Cu")
		(net "GND")
	)
	(segment
		(start 381.638048 -293.260018)
		(end 382.1049 -293.525956)
		(width 0.350012)
		(layer "F.Cu")
		(net "GND")
	)
	(segment
		(start 103.520494 -386.84073)
		(end 103.277162 -387.084062)
		(width 0.381)
		(layer "F.Cu")
		(net "GND")
	)
	(segment
		(start 343.268046 -241.510058)
		(end 342.801194 -241.24412)
		(width 0.350012)
		(layer "F.Cu")
		(net "GND")
	)
	(segment
		(start 389.327898 -256.090166)
		(end 389.79475 -255.824228)
		(width 0.350012)
		(layer "F.Cu")
		(net "GND")
	)
	(segment
		(start 221.49308 -104.42448)
		(end 221.199456 -104.130856)
		(width 0.381)
		(layer "F.Cu")
		(net "GND")
	)
	(segment
		(start 347.497908 -235.840016)
		(end 347.031056 -235.574078)
		(width 0.350012)
		(layer "F.Cu")
		(net "GND")
	)
	(segment
		(start 385.517898 -399.143474)
		(end 385.570476 -398.542002)
		(width 0.254)
		(layer "F.Cu")
		(net "GND")
	)
	(segment
		(start 392.917934 -293.260018)
		(end 393.384786 -293.525956)
		(width 0.350012)
		(layer "F.Cu")
		(net "GND")
	)
	(segment
		(start 100.797868 -264.10031)
		(end 100.331016 -264.366248)
		(width 0.350012)
		(layer "F.Cu")
		(net "GND")
	)
	(segment
		(start 331.81798 -277.060152)
		(end 331.351128 -277.32609)
		(width 0.350012)
		(layer "F.Cu")
		(net "GND")
	)
	(segment
		(start 85.463634 -180.151532)
		(end 85.366098 -180.38699)
		(width 0.2286)
		(layer "F.Cu")
		(net "GND")
	)
	(segment
		(start 90.380312 -74.92111)
		(end 90.380312 -75.654154)
		(width 0.4572)
		(layer "F.Cu")
		(net "GND")
	)
	(segment
		(start 82.74431 -391.37971)
		(end 82.645758 -391.281158)
		(width 0.254)
		(layer "F.Cu")
		(net "GND")
	)
	(segment
		(start 280.635964 -200.735184)
		(end 282.020264 -200.735184)
		(width 0.4572)
		(layer "F.Cu")
		(net "GND")
	)
	(segment
		(start 344.977974 -264.100056)
		(end 344.511122 -264.365994)
		(width 0.350012)
		(layer "F.Cu")
		(net "GND")
	)
	(segment
		(start 402.248878 -394.412978)
		(end 402.248878 -393.81303)
		(width 0.254)
		(layer "F.Cu")
		(net "GND")
	)
	(segment
		(start 357.36784 -244.750082)
		(end 356.901242 -244.484144)
		(width 0.350012)
		(layer "F.Cu")
		(net "GND")
	)
	(segment
		(start 442.5442 -240.685066)
		(end 443.9285 -240.685066)
		(width 0.4572)
		(layer "F.Cu")
		(net "GND")
	)
	(segment
		(start 150.945596 -391.281158)
		(end 151.245824 -390.761474)
		(width 0.254)
		(layer "F.Cu")
		(net "GND")
	)
	(segment
		(start 91.906344 -386.449062)
		(end 92.59824 -386.6388)
		(width 0.254)
		(layer "F.Cu")
		(net "GND")
	)
	(segment
		(start 334.028288 -402.282152)
		(end 333.215488 -402.282152)
		(width 0.254)
		(layer "F.Cu")
		(net "GND")
	)
	(segment
		(start 59.428126 -221.135194)
		(end 58.043826 -221.135194)
		(width 0.4572)
		(layer "F.Cu")
		(net "GND")
	)
	(segment
		(start 89.991438 -287.045908)
		(end 89.991184 -287.04667)
		(width 0.350012)
		(layer "F.Cu")
		(net "GND")
	)
	(segment
		(start 435.000146 -284.88513)
		(end 436.384446 -284.88513)
		(width 0.4572)
		(layer "F.Cu")
		(net "GND")
	)
	(segment
		(start 378.370592 -396.520924)
		(end 377.818396 -396.710662)
		(width 0.254)
		(layer "F.Cu")
		(net "GND")
	)
	(segment
		(start 117.717824 -293.260272)
		(end 118.184676 -293.52621)
		(width 0.350012)
		(layer "F.Cu")
		(net "GND")
	)
	(segment
		(start 379.457966 -230.97998)
		(end 379.924818 -230.714296)
		(width 0.350012)
		(layer "F.Cu")
		(net "GND")
	)
	(segment
		(start 330.408026 -269.770098)
		(end 329.941174 -270.036036)
		(width 0.350012)
		(layer "F.Cu")
		(net "GND")
	)
	(segment
		(start 320.870326 -395.0208)
		(end 320.17843 -394.831062)
		(width 0.254)
		(layer "F.Cu")
		(net "GND")
	)
	(segment
		(start 194.604132 -221.985332)
		(end 195.988432 -221.985332)
		(width 0.4572)
		(layer "F.Cu")
		(net "GND")
	)
	(segment
		(start 350.744028 -399.76171)
		(end 350.645476 -399.663158)
		(width 0.254)
		(layer "F.Cu")
		(net "GND")
	)
	(segment
		(start 56.867044 -9.423654)
		(end 56.868314 -9.424924)
		(width 0.3556)
		(layer "F.Cu")
		(net "GND")
	)
	(segment
		(start 115.537996 -248.800366)
		(end 116.004848 -248.534428)
		(width 0.350012)
		(layer "F.Cu")
		(net "GND")
	)
	(segment
		(start 101.907848 -249.610372)
		(end 101.440996 -249.344434)
		(width 0.350012)
		(layer "F.Cu")
		(net "GND")
	)
	(segment
		(start 146.248882 -390.564624)
		(end 146.445732 -390.761474)
		(width 0.254)
		(layer "F.Cu")
		(net "GND")
	)
	(segment
		(start 128.52781 -290.830254)
		(end 128.994662 -291.096192)
		(width 0.350012)
		(layer "F.Cu")
		(net "GND")
	)
	(segment
		(start 216.56675 -101.92512)
		(end 215.8365 -101.92512)
		(width 0.381)
		(layer "F.Cu")
		(net "GND")
	)
	(segment
		(start 152.44572 -390.761474)
		(end 152.145746 -391.281158)
		(width 0.254)
		(layer "F.Cu")
		(net "GND")
	)
	(segment
		(start 161.999676 -437.27243)
		(end 161.34334 -437.27243)
		(width 0.381)
		(layer "F.Cu")
		(net "GND")
	)
	(segment
		(start 120.238012 -224.50044)
		(end 120.70461 -224.234502)
		(width 0.350012)
		(layer "F.Cu")
		(net "GND")
	)
	(segment
		(start 123.127516 -57.537858)
		(end 123.835414 -57.537858)
		(width 0.4572)
		(layer "F.Cu")
		(net "GND")
	)
	(segment
		(start 29.348176 -12.374118)
		(end 29.346906 -12.372848)
		(width 0.3556)
		(layer "F.Cu")
		(net "GND")
	)
	(segment
		(start 348.545404 -399.143474)
		(end 348.597982 -398.542002)
		(width 0.254)
		(layer "F.Cu")
		(net "GND")
	)
	(segment
		(start 311.217818 -399.143474)
		(end 311.270396 -398.542002)
		(width 0.254)
		(layer "F.Cu")
		(net "GND")
	)
	(segment
		(start 211.102956 -29.266896)
		(end 211.10321 -29.266642)
		(width 0.4572)
		(layer "F.Cu")
		(net "GND")
	)
	(segment
		(start 144.315688 -393.900152)
		(end 144.315688 -392.92276)
		(width 0.254)
		(layer "F.Cu")
		(net "GND")
	)
	(segment
		(start 335.108042 -271.39011)
		(end 334.64119 -271.656048)
		(width 0.350012)
		(layer "F.Cu")
		(net "GND")
	)
	(segment
		(start 303.717706 -391.784586)
		(end 303.717706 -392.004296)
		(width 0.254)
		(layer "F.Cu")
		(net "GND")
	)
	(segment
		(start 113.017808 -283.540454)
		(end 113.48466 -283.806392)
		(width 0.350012)
		(layer "F.Cu")
		(net "GND")
	)
	(segment
		(start 419.912038 -240.685066)
		(end 421.296338 -240.685066)
		(width 0.4572)
		(layer "F.Cu")
		(net "GND")
	)
	(segment
		(start 83.59013 -384.617722)
		(end 82.99831 -384.617722)
		(width 0.254)
		(layer "F.Cu")
		(net "GND")
	)
	(segment
		(start 125.240288 -43.59275)
		(end 125.812042 -43.59275)
		(width 0.381)
		(layer "F.Cu")
		(net "GND")
	)
	(segment
		(start 348.299786 -25.529286)
		(end 348.299786 -24.892)
		(width 0.4572)
		(layer "F.Cu")
		(net "GND")
	)
	(segment
		(start 360.957876 -294.88003)
		(end 361.424728 -295.145968)
		(width 0.350012)
		(layer "F.Cu")
		(net "GND")
	)
	(segment
		(start 416.898328 -396.520924)
		(end 416.346132 -396.710662)
		(width 0.254)
		(layer "F.Cu")
		(net "GND")
	)
	(segment
		(start 427.766988 -9.423654)
		(end 427.768258 -9.424924)
		(width 0.3556)
		(layer "F.Cu")
		(net "GND")
	)
	(segment
		(start 407.445718 -7.215124)
		(end 407.445718 -7.215886)
		(width 0.3556)
		(layer "F.Cu")
		(net "GND")
	)
	(segment
		(start 438.277 -96.757998)
		(end 438.277 -97.450148)
		(width 0.3556)
		(layer "F.Cu")
		(net "GND")
	)
	(segment
		(start 139.80795 -274.630388)
		(end 140.274802 -274.896326)
		(width 0.350012)
		(layer "F.Cu")
		(net "GND")
	)
	(segment
		(start 146.38782 -287.590484)
		(end 147.042886 -287.590484)
		(width 0.350012)
		(layer "F.Cu")
		(net "GND")
	)
	(segment
		(start 146.087846 -230.170228)
		(end 146.742912 -230.170228)
		(width 0.350012)
		(layer "F.Cu")
		(net "GND")
	)
	(segment
		(start 375.73839 -177.48631)
		(end 375.9962 -177.2285)
		(width 0.381)
		(layer "F.Cu")
		(net "GND")
	)
	(segment
		(start 341.857838 -230.97998)
		(end 341.390986 -230.714042)
		(width 0.350012)
		(layer "F.Cu")
		(net "GND")
	)
	(segment
		(start 105.66781 -233.410252)
		(end 105.200958 -233.144314)
		(width 0.350012)
		(layer "F.Cu")
		(net "GND")
	)
	(segment
		(start 353.137978 -229.360222)
		(end 352.671126 -229.094284)
		(width 0.350012)
		(layer "F.Cu")
		(net "GND")
	)
	(segment
		(start 144.677892 -253.660402)
		(end 145.144744 -253.394464)
		(width 0.350012)
		(layer "F.Cu")
		(net "GND")
	)
	(segment
		(start 24.36495 -365.76)
		(end 23.622 -365.76)
		(width 0.381)
		(layer "F.Cu")
		(net "GND")
	)
	(segment
		(start 133.69798 -275.440394)
		(end 134.164832 -275.706332)
		(width 0.350012)
		(layer "F.Cu")
		(net "GND")
	)
	(segment
		(start 225.820478 -268.232382)
		(end 225.820478 -267.495782)
		(width 0.381)
		(layer "F.Cu")
		(net "GND")
	)
	(segment
		(start 90.927936 -290.830254)
		(end 90.461084 -291.096192)
		(width 0.350012)
		(layer "F.Cu")
		(net "GND")
	)
	(segment
		(start 367.238026 -243.940076)
		(end 367.704878 -243.674138)
		(width 0.350012)
		(layer "F.Cu")
		(net "GND")
	)
	(segment
		(start 400.893026 -175.01362)
		(end 400.893026 -174.649892)
		(width 0.2286)
		(layer "F.Cu")
		(net "GND")
	)
	(segment
		(start 185.922158 -113.05286)
		(end 186.312048 -112.66297)
		(width 0.254)
		(layer "F.Cu")
		(net "GND")
	)
	(segment
		(start 398.446752 -9.423654)
		(end 398.448022 -9.424924)
		(width 0.3556)
		(layer "F.Cu")
		(net "GND")
	)
	(segment
		(start 88.747854 -243.130324)
		(end 88.281002 -242.864386)
		(width 0.350012)
		(layer "F.Cu")
		(net "GND")
	)
	(segment
		(start 90.157808 -256.900426)
		(end 89.690956 -256.634488)
		(width 0.350012)
		(layer "F.Cu")
		(net "GND")
	)
	(segment
		(start 379.457966 -227.74021)
		(end 379.924818 -227.474272)
		(width 0.350012)
		(layer "F.Cu")
		(net "GND")
	)
	(segment
		(start 158.498286 -384.617722)
		(end 158.445708 -383.92227)
		(width 0.254)
		(layer "F.Cu")
		(net "GND")
	)
	(segment
		(start 327.28789 -251.23013)
		(end 326.821038 -250.964192)
		(width 0.350012)
		(layer "F.Cu")
		(net "GND")
	)
	(segment
		(start 279.96642 -351.100644)
		(end 279.96642 -351.73158)
		(width 0.381)
		(layer "F.Cu")
		(net "GND")
	)
	(segment
		(start 347.968062 -243.13007)
		(end 347.50121 -242.864132)
		(width 0.350012)
		(layer "F.Cu")
		(net "GND")
	)
	(segment
		(start 80.287876 -243.130324)
		(end 79.821024 -242.864386)
		(width 0.350012)
		(layer "F.Cu")
		(net "GND")
	)
	(segment
		(start 120.817894 -382.951482)
		(end 120.916446 -382.85293)
		(width 0.254)
		(layer "F.Cu")
		(net "GND")
	)
	(segment
		(start 301.856648 -118.179088)
		(end 301.169578 -118.179088)
		(width 0.3556)
		(layer "F.Cu")
		(net "GND")
	)
	(segment
		(start 108.487972 -247.99036)
		(end 108.02112 -247.724422)
		(width 0.350012)
		(layer "F.Cu")
		(net "GND")
	)
	(segment
		(start 454.188068 -209.23504)
		(end 452.803768 -209.23504)
		(width 0.4572)
		(layer "F.Cu")
		(net "GND")
	)
	(segment
		(start 144.381982 -105.624884)
		(end 143.740632 -105.624884)
		(width 0.4064)
		(layer "F.Cu")
		(net "GND")
	)
	(segment
		(start 376.167904 -239.890046)
		(end 376.634756 -239.624108)
		(width 0.350012)
		(layer "F.Cu")
		(net "GND")
	)
	(segment
		(start 374.11787 -291.640006)
		(end 374.584722 -291.905944)
		(width 0.350012)
		(layer "F.Cu")
		(net "GND")
	)
	(segment
		(start 94.39021 -384.617722)
		(end 93.79839 -384.617722)
		(width 0.254)
		(layer "F.Cu")
		(net "GND")
	)
	(segment
		(start 311.270396 -396.520924)
		(end 310.7182 -396.710662)
		(width 0.254)
		(layer "F.Cu")
		(net "GND")
	)
	(segment
		(start 141.38783 -230.170228)
		(end 141.854682 -229.90429)
		(width 0.350012)
		(layer "F.Cu")
		(net "GND")
	)
	(segment
		(start 338.39785 -291.640006)
		(end 337.930998 -291.905944)
		(width 0.350012)
		(layer "F.Cu")
		(net "GND")
	)
	(segment
		(start 399.359882 -76.661264)
		(end 398.676368 -76.661264)
		(width 0.4572)
		(layer "F.Cu")
		(net "GND")
	)
	(segment
		(start 29.553662 -418.239448)
		(end 29.553662 -418.849048)
		(width 0.3556)
		(layer "F.Cu")
		(net "GND")
	)
	(segment
		(start 99.55784 -239.080294)
		(end 99.090988 -238.814356)
		(width 0.350012)
		(layer "F.Cu")
		(net "GND")
	)
	(segment
		(start 433.165504 -7.215124)
		(end 433.165504 -7.215886)
		(width 0.3556)
		(layer "F.Cu")
		(net "GND")
	)
	(segment
		(start 304.070258 -392.999722)
		(end 304.662078 -392.999722)
		(width 0.254)
		(layer "F.Cu")
		(net "GND")
	)
	(segment
		(start 121.477786 -275.440394)
		(end 121.944638 -275.706332)
		(width 0.350012)
		(layer "F.Cu")
		(net "GND")
	)
	(segment
		(start 36.73094 -108.49737)
		(end 36.73094 -109.10824)
		(width 0.381)
		(layer "F.Cu")
		(net "GND")
	)
	(segment
		(start 338.39785 -267.34008)
		(end 337.930998 -267.606018)
		(width 0.350012)
		(layer "F.Cu")
		(net "GND")
	)
	(segment
		(start 341.387938 -228.550216)
		(end 340.921086 -228.284278)
		(width 0.350012)
		(layer "F.Cu")
		(net "GND")
	)
	(segment
		(start 319.537588 -118.426738)
		(end 319.537588 -117.950488)
		(width 0.3556)
		(layer "F.Cu")
		(net "GND")
	)
	(segment
		(start 19.915124 -407.471626)
		(end 20.4216 -406.96515)
		(width 0.381)
		(layer "F.Cu")
		(net "GND")
	)
	(segment
		(start 337.189826 -392.999722)
		(end 337.798156 -392.999722)
		(width 0.254)
		(layer "F.Cu")
		(net "GND")
	)
	(segment
		(start 308.002432 -411.295596)
		(end 308.805834 -411.295596)
		(width 0.381)
		(layer "F.Cu")
		(net "GND")
	)
	(segment
		(start 371.767862 -282.730194)
		(end 372.234714 -282.996132)
		(width 0.350012)
		(layer "F.Cu")
		(net "GND")
	)
	(segment
		(start 116.018056 -391.281158)
		(end 116.116608 -391.37971)
		(width 0.254)
		(layer "F.Cu")
		(net "GND")
	)
	(segment
		(start 111.137954 -288.400236)
		(end 110.671102 -288.666174)
		(width 0.350012)
		(layer "F.Cu")
		(net "GND")
	)
	(segment
		(start 115.367816 -269.770352)
		(end 115.834668 -270.03629)
		(width 0.350012)
		(layer "F.Cu")
		(net "GND")
	)
	(segment
		(start 83.577938 -226.120452)
		(end 83.111086 -225.854514)
		(width 0.350012)
		(layer "F.Cu")
		(net "GND")
	)
	(segment
		(start 272.728182 -351.973896)
		(end 272.728182 -352.602292)
		(width 0.381)
		(layer "F.Cu")
		(net "GND")
	)
	(segment
		(start 381.338074 -239.08004)
		(end 381.804926 -238.814102)
		(width 0.350012)
		(layer "F.Cu")
		(net "GND")
	)
	(segment
		(start 201.000614 -71.582788)
		(end 202.484482 -71.582788)
		(width 0.381)
		(layer "F.Cu")
		(net "GND")
	)
	(segment
		(start 138.098022 -239.080294)
		(end 138.564874 -238.814356)
		(width 0.350012)
		(layer "F.Cu")
		(net "GND")
	)
	(segment
		(start 165.60165 -436.153052)
		(end 165.972744 -436.153052)
		(width 0.381)
		(layer "F.Cu")
		(net "GND")
	)
	(segment
		(start 133.227826 -294.070278)
		(end 133.694678 -294.336216)
		(width 0.350012)
		(layer "F.Cu")
		(net "GND")
	)
	(segment
		(start 133.398006 -232.600246)
		(end 133.864858 -232.334308)
		(width 0.350012)
		(layer "F.Cu")
		(net "GND")
	)
	(segment
		(start 119.617998 -383.402586)
		(end 119.617998 -383.622296)
		(width 0.2032)
		(layer "F.Cu")
		(net "GND")
	)
	(segment
		(start 80.287876 -231.79024)
		(end 79.821024 -231.524302)
		(width 0.350012)
		(layer "F.Cu")
		(net "GND")
	)
	(segment
		(start 187.060078 -303.585372)
		(end 188.444378 -303.585372)
		(width 0.4572)
		(layer "F.Cu")
		(net "GND")
	)
	(segment
		(start 164.225224 -429.807624)
		(end 164.225224 -428.90567)
		(width 0.3048)
		(layer "F.Cu")
		(net "GND")
	)
	(segment
		(start 398.448022 -12.37488)
		(end 398.448022 -12.374118)
		(width 0.3556)
		(layer "F.Cu")
		(net "GND")
	)
	(segment
		(start 318.99098 -398.542002)
		(end 318.47028 -398.542002)
		(width 0.254)
		(layer "F.Cu")
		(net "GND")
	)
	(segment
		(start 107.851448 -287.045908)
		(end 107.851194 -287.04667)
		(width 0.350012)
		(layer "F.Cu")
		(net "GND")
	)
	(segment
		(start 394.027914 -225.310192)
		(end 394.494766 -225.044254)
		(width 0.350012)
		(layer "F.Cu")
		(net "GND")
	)
	(segment
		(start 388.688072 -295.690036)
		(end 389.154924 -295.955974)
		(width 0.350012)
		(layer "F.Cu")
		(net "GND")
	)
	(segment
		(start 83.577938 -229.360476)
		(end 83.111086 -229.094538)
		(width 0.350012)
		(layer "F.Cu")
		(net "GND")
	)
	(segment
		(start 6.829298 -136.448038)
		(end 6.829298 -136.48817)
		(width 0.3556)
		(layer "F.Cu")
		(net "GND")
	)
	(segment
		(start 314.262262 -392.999722)
		(end 314.870338 -392.999722)
		(width 0.254)
		(layer "F.Cu")
		(net "GND")
	)
	(segment
		(start 309.717694 -391.784586)
		(end 309.717694 -391.333482)
		(width 0.254)
		(layer "F.Cu")
		(net "GND")
	)
	(segment
		(start 441.758324 -403.21992)
		(end 441.091066 -403.21992)
		(width 0.254)
		(layer "F.Cu")
		(net "GND")
	)
	(segment
		(start 57.317894 -382.951482)
		(end 57.416446 -382.85293)
		(width 0.254)
		(layer "F.Cu")
		(net "GND")
	)
	(segment
		(start 332.28788 -295.690036)
		(end 331.821028 -295.955974)
		(width 0.350012)
		(layer "F.Cu")
		(net "GND")
	)
	(segment
		(start 187.594494 -354.386134)
		(end 187.563506 -354.386134)
		(width 0.2286)
		(layer "F.Cu")
		(net "GND")
	)
	(segment
		(start 90.432128 -139.372594)
		(end 90.6399 -139.164822)
		(width 0.4572)
		(layer "F.Cu")
		(net "GND")
	)
	(segment
		(start 131.987798 -249.610372)
		(end 132.45465 -249.344434)
		(width 0.350012)
		(layer "F.Cu")
		(net "GND")
	)
	(segment
		(start 92.33789 -277.060406)
		(end 91.871038 -277.326344)
		(width 0.350012)
		(layer "F.Cu")
		(net "GND")
	)
	(segment
		(start 179.482242 -422.402254)
		(end 178.682142 -422.402254)
		(width 0.381)
		(layer "F.Cu")
		(net "GND")
	)
	(segment
		(start 90.157808 -230.980234)
		(end 89.690956 -230.714296)
		(width 0.350012)
		(layer "F.Cu")
		(net "GND")
	)
	(segment
		(start 115.83797 -281.920442)
		(end 116.304822 -282.18638)
		(width 0.350012)
		(layer "F.Cu")
		(net "GND")
	)
	(segment
		(start 42.545 -435.71795)
		(end 42.545 -435.067456)
		(width 0.381)
		(layer "F.Cu")
		(net "GND")
	)
	(segment
		(start 139.977876 -232.600246)
		(end 140.444728 -232.334308)
		(width 0.350012)
		(layer "F.Cu")
		(net "GND")
	)
	(segment
		(start 431.36693 -10.16635)
		(end 431.36566 -10.16508)
		(width 0.3556)
		(layer "F.Cu")
		(net "GND")
	)
	(segment
		(start 348.437962 -243.940076)
		(end 347.97111 -243.674138)
		(width 0.350012)
		(layer "F.Cu")
		(net "GND")
	)
	(segment
		(start 188.417962 -353.145852)
		(end 188.164978 -353.398836)
		(width 0.2286)
		(layer "F.Cu")
		(net "GND")
	)
	(segment
		(start 360.657902 -232.599992)
		(end 361.124754 -232.334054)
		(width 0.350012)
		(layer "F.Cu")
		(net "GND")
	)
	(segment
		(start 117.517926 -383.92227)
		(end 117.570504 -384.617722)
		(width 0.254)
		(layer "F.Cu")
		(net "GND")
	)
	(segment
		(start 85.366098 -180.665882)
		(end 85.113114 -180.918866)
		(width 0.2286)
		(layer "F.Cu")
		(net "GND")
	)
	(segment
		(start 143.567912 -261.670292)
		(end 144.034764 -261.93623)
		(width 0.350012)
		(layer "F.Cu")
		(net "GND")
	)
	(segment
		(start 49.270666 -390.160002)
		(end 49.218088 -390.761474)
		(width 0.254)
		(layer "F.Cu")
		(net "GND")
	)
	(segment
		(start 359.078022 -277.060152)
		(end 358.61117 -277.32609)
		(width 0.350012)
		(layer "F.Cu")
		(net "GND")
	)
	(segment
		(start 99.55784 -243.94033)
		(end 99.090988 -243.674392)
		(width 0.350012)
		(layer "F.Cu")
		(net "GND")
	)
	(segment
		(start 116.477796 -252.04039)
		(end 116.944648 -251.774452)
		(width 0.350012)
		(layer "F.Cu")
		(net "GND")
	)
	(segment
		(start 119.127778 -268.15034)
		(end 119.59463 -268.416278)
		(width 0.350012)
		(layer "F.Cu")
		(net "GND")
	)
	(segment
		(start 116.77777 -280.30043)
		(end 117.244622 -280.566368)
		(width 0.350012)
		(layer "F.Cu")
		(net "GND")
	)
	(segment
		(start 357.668068 -276.250146)
		(end 357.201216 -276.516084)
		(width 0.350012)
		(layer "F.Cu")
		(net "GND")
	)
	(segment
		(start 364.247938 -292.450012)
		(end 364.71479 -292.71595)
		(width 0.350012)
		(layer "F.Cu")
		(net "GND")
	)
	(segment
		(start 420.145718 -391.784586)
		(end 420.145718 -392.004296)
		(width 0.254)
		(layer "F.Cu")
		(net "GND")
	)
	(segment
		(start 82.467958 -290.830254)
		(end 82.001106 -291.096192)
		(width 0.350012)
		(layer "F.Cu")
		(net "GND")
	)
	(segment
		(start 325.70801 -263.29005)
		(end 325.052944 -263.29005)
		(width 0.350012)
		(layer "F.Cu")
		(net "GND")
	)
	(segment
		(start 189.262004 -16.549878)
		(end 189.263274 -16.551148)
		(width 0.3556)
		(layer "F.Cu")
		(net "GND")
	)
	(segment
		(start 369.970558 -396.46352)
		(end 369.72113 -396.712948)
		(width 0.254)
		(layer "F.Cu")
		(net "GND")
	)
	(segment
		(start 256.442972 -101.34346)
		(end 256.442972 -100.61575)
		(width 0.4572)
		(layer "F.Cu")
		(net "GND")
	)
	(segment
		(start 138.371834 -49.595024)
		(end 138.987784 -49.595024)
		(width 0.4572)
		(layer "F.Cu")
		(net "GND")
	)
	(segment
		(start 115.170458 -384.617722)
		(end 115.11788 -383.92227)
		(width 0.254)
		(layer "F.Cu")
		(net "GND")
	)
	(segment
		(start 84.347812 -295.69029)
		(end 83.88096 -295.956228)
		(width 0.350012)
		(layer "F.Cu")
		(net "GND")
	)
	(segment
		(start 418.356796 -7.217156)
		(end 418.356796 -8.320024)
		(width 0.3556)
		(layer "F.Cu")
		(net "GND")
	)
	(segment
		(start 43.85691 -9.423654)
		(end 43.85818 -9.424924)
		(width 0.3556)
		(layer "F.Cu")
		(net "GND")
	)
	(segment
		(start 303.390808 -398.542002)
		(end 303.390808 -398.613122)
		(width 0.254)
		(layer "F.Cu")
		(net "GND")
	)
	(segment
		(start 414.498282 -398.542002)
		(end 413.819086 -398.542002)
		(width 0.254)
		(layer "F.Cu")
		(net "GND")
	)
	(segment
		(start 106.137964 -226.120452)
		(end 105.671112 -225.854514)
		(width 0.350012)
		(layer "F.Cu")
		(net "GND")
	)
	(segment
		(start 450.088 -275.535136)
		(end 451.4723 -275.535136)
		(width 0.4572)
		(layer "F.Cu")
		(net "GND")
	)
	(segment
		(start 83.877912 -290.020248)
		(end 83.41106 -290.286186)
		(width 0.350012)
		(layer "F.Cu")
		(net "GND")
	)
	(segment
		(start 93.44787 -225.310446)
		(end 92.981018 -225.044508)
		(width 0.350012)
		(layer "F.Cu")
		(net "GND")
	)
	(segment
		(start 420.246302 -433.986686)
		(end 420.877238 -433.986686)
		(width 0.381)
		(layer "F.Cu")
		(net "GND")
	)
	(segment
		(start 394.84681 -7.217156)
		(end 394.84681 -8.320024)
		(width 0.3556)
		(layer "F.Cu")
		(net "GND")
	)
	(segment
		(start 146.087846 -251.230384)
		(end 146.742912 -251.230384)
		(width 0.350012)
		(layer "F.Cu")
		(net "GND")
	)
	(segment
		(start 82.99831 -386.6388)
		(end 82.306414 -386.449062)
		(width 0.254)
		(layer "F.Cu")
		(net "GND")
	)
	(segment
		(start 89.047828 -276.2504)
		(end 88.580976 -276.516338)
		(width 0.350012)
		(layer "F.Cu")
		(net "GND")
	)
	(segment
		(start 381.167894 -276.250146)
		(end 381.634746 -276.516084)
		(width 0.350012)
		(layer "F.Cu")
		(net "GND")
	)
	(segment
		(start 389.327898 -249.610118)
		(end 389.79475 -249.34418)
		(width 0.350012)
		(layer "F.Cu")
		(net "GND")
	)
	(segment
		(start 390.28243 -76.407264)
		(end 390.891268 -76.407264)
		(width 0.4572)
		(layer "F.Cu")
		(net "GND")
	)
	(segment
		(start 135.107934 -287.590484)
		(end 135.574786 -287.856422)
		(width 0.350012)
		(layer "F.Cu")
		(net "GND")
	)
	(segment
		(start 394.027914 -230.169974)
		(end 394.68298 -230.169974)
		(width 0.350012)
		(layer "F.Cu")
		(net "GND")
	)
	(segment
		(start 78.929484 -387.231128)
		(end 79.14894 -387.231128)
		(width 0.254)
		(layer "F.Cu")
		(net "GND")
	)
	(segment
		(start 286.380936 -102.122732)
		(end 286.377634 -102.126034)
		(width 0.4572)
		(layer "F.Cu")
		(net "GND")
	)
	(segment
		(start 333.39786 -250.420124)
		(end 332.931008 -250.154186)
		(width 0.350012)
		(layer "F.Cu")
		(net "GND")
	)
	(segment
		(start 115.067842 -251.230384)
		(end 115.534694 -250.964446)
		(width 0.350012)
		(layer "F.Cu")
		(net "GND")
	)
	(segment
		(start 85.366098 -180.38699)
		(end 85.366098 -180.665882)
		(width 0.2286)
		(layer "F.Cu")
		(net "GND")
	)
	(segment
		(start 408.145742 -391.333482)
		(end 408.244294 -391.23493)
		(width 0.2032)
		(layer "F.Cu")
		(net "GND")
	)
	(segment
		(start 133.69798 -281.920442)
		(end 134.164832 -282.18638)
		(width 0.350012)
		(layer "F.Cu")
		(net "GND")
	)
	(segment
		(start 459.75143 -40.45585)
		(end 460.39278 -40.45585)
		(width 0.4572)
		(layer "F.Cu")
		(net "GND")
	)
	(segment
		(start 333.697834 -290.019994)
		(end 333.230982 -290.285932)
		(width 0.350012)
		(layer "F.Cu")
		(net "GND")
	)
	(segment
		(start 124.718064 -383.92227)
		(end 124.417836 -383.622042)
		(width 0.254)
		(layer "F.Cu")
		(net "GND")
	)
	(segment
		(start 88.645746 -383.622296)
		(end 88.94572 -383.92227)
		(width 0.254)
		(layer "F.Cu")
		(net "GND")
	)
	(segment
		(start 364.417864 -237.460028)
		(end 364.884716 -237.19409)
		(width 0.350012)
		(layer "F.Cu")
		(net "GND")
	)
	(segment
		(start 45.793152 -388.36473)
		(end 45.582078 -388.431024)
		(width 0.254)
		(layer "F.Cu")
		(net "GND")
	)
	(segment
		(start 327.234042 -390.1694)
		(end 327.234042 -389.446262)
		(width 0.254)
		(layer "F.Cu")
		(net "GND")
	)
	(segment
		(start 342.245442 -391.784586)
		(end 342.245442 -391.333482)
		(width 0.254)
		(layer "F.Cu")
		(net "GND")
	)
	(segment
		(start 394.027914 -254.470154)
		(end 394.68298 -254.470154)
		(width 0.350012)
		(layer "F.Cu")
		(net "GND")
	)
	(segment
		(start 277.192232 -227.935028)
		(end 275.807932 -227.935028)
		(width 0.4572)
		(layer "F.Cu")
		(net "GND")
	)
	(segment
		(start 139.507976 -238.270288)
		(end 139.974828 -238.00435)
		(width 0.350012)
		(layer "F.Cu")
		(net "GND")
	)
	(segment
		(start 343.268046 -244.750082)
		(end 342.801194 -244.484144)
		(width 0.350012)
		(layer "F.Cu")
		(net "GND")
	)
	(segment
		(start 372.237 -423.7863)
		(end 372.237 -423.418)
		(width 0.254)
		(layer "F.Cu")
		(net "GND")
	)
	(segment
		(start 49.270666 -384.617722)
		(end 49.218088 -383.92227)
		(width 0.254)
		(layer "F.Cu")
		(net "GND")
	)
	(segment
		(start 338.744052 -399.76171)
		(end 338.6455 -399.663158)
		(width 0.254)
		(layer "F.Cu")
		(net "GND")
	)
	(segment
		(start 83.577938 -256.900426)
		(end 83.111086 -256.634488)
		(width 0.350012)
		(layer "F.Cu")
		(net "GND")
	)
	(segment
		(start 94.659958 -77.15504)
		(end 93.447108 -77.15504)
		(width 0.381)
		(layer "F.Cu")
		(net "GND")
	)
	(segment
		(start 59.428126 -305.285394)
		(end 58.043826 -305.285394)
		(width 0.4572)
		(layer "F.Cu")
		(net "GND")
	)
	(segment
		(start 418.746178 -396.710662)
		(end 418.098224 -396.520924)
		(width 0.254)
		(layer "F.Cu")
		(net "GND")
	)
	(segment
		(start 61.270642 -390.160002)
		(end 61.218064 -390.761474)
		(width 0.254)
		(layer "F.Cu")
		(net "GND")
	)
	(segment
		(start 355.018086 -247.1801)
		(end 354.551234 -246.914162)
		(width 0.350012)
		(layer "F.Cu")
		(net "GND")
	)
	(segment
		(start 277.192232 -199.885046)
		(end 275.807932 -199.885046)
		(width 0.4572)
		(layer "F.Cu")
		(net "GND")
	)
	(segment
		(start 80.11795 -293.260272)
		(end 79.651098 -293.52621)
		(width 0.350012)
		(layer "F.Cu")
		(net "GND")
	)
	(segment
		(start 144.677892 -239.080294)
		(end 145.144744 -238.814356)
		(width 0.350012)
		(layer "F.Cu")
		(net "GND")
	)
	(segment
		(start 406.098248 -395.0208)
		(end 405.406352 -394.831062)
		(width 0.254)
		(layer "F.Cu")
		(net "GND")
	)
	(segment
		(start 369.11788 -245.560088)
		(end 369.584732 -245.29415)
		(width 0.350012)
		(layer "F.Cu")
		(net "GND")
	)
	(segment
		(start 365.828072 -230.169974)
		(end 366.294924 -229.904036)
		(width 0.350012)
		(layer "F.Cu")
		(net "GND")
	)
	(segment
		(start 340.561676 -336.849466)
		(end 340.990174 -336.849466)
		(width 0.2286)
		(layer "F.Cu")
		(net "GND")
	)
	(segment
		(start 78.877922 -245.560342)
		(end 78.41107 -245.294404)
		(width 0.350012)
		(layer "F.Cu")
		(net "GND")
	)
	(segment
		(start 180.772308 -165.692074)
		(end 180.772308 -166.201598)
		(width 0.4572)
		(layer "F.Cu")
		(net "GND")
	)
	(segment
		(start 324.168262 -402.163788)
		(end 324.615048 -401.717002)
		(width 0.254)
		(layer "F.Cu")
		(net "GND")
	)
	(segment
		(start 82.167984 -251.230384)
		(end 81.701132 -250.964446)
		(width 0.350012)
		(layer "F.Cu")
		(net "GND")
	)
	(segment
		(start 137.05205 -113.157)
		(end 138.303 -111.90605)
		(width 0.381)
		(layer "F.Cu")
		(net "GND")
	)
	(segment
		(start 138.026902 -56.500014)
		(end 137.417302 -56.500014)
		(width 0.4572)
		(layer "F.Cu")
		(net "GND")
	)
	(segment
		(start 56.865774 -7.215124)
		(end 56.865774 -7.215886)
		(width 0.3556)
		(layer "F.Cu")
		(net "GND")
	)
	(segment
		(start 446.644268 -286.585152)
		(end 445.259968 -286.585152)
		(width 0.4572)
		(layer "F.Cu")
		(net "GND")
	)
	(segment
		(start 67.71513 -340.257638)
		(end 67.184778 -340.257638)
		(width 0.381)
		(layer "F.Cu")
		(net "GND")
	)
	(segment
		(start 269.648178 -293.384986)
		(end 268.263878 -293.384986)
		(width 0.4572)
		(layer "F.Cu")
		(net "GND")
	)
	(segment
		(start 159.34563 -382.951482)
		(end 159.444182 -382.85293)
		(width 0.254)
		(layer "F.Cu")
		(net "GND")
	)
	(segment
		(start 38.15969 -365.125)
		(end 38.374828 -364.909862)
		(width 0.381)
		(layer "F.Cu")
		(net "GND")
	)
	(segment
		(start 439.100214 -314.635134)
		(end 437.715914 -314.635134)
		(width 0.4572)
		(layer "F.Cu")
		(net "GND")
	)
	(segment
		(start 365.828072 -235.03001)
		(end 366.294924 -234.764072)
		(width 0.350012)
		(layer "F.Cu")
		(net "GND")
	)
	(segment
		(start 451.376288 -399.070322)
		(end 451.810628 -399.070322)
		(width 0.2032)
		(layer "F.Cu")
		(net "GND")
	)
	(segment
		(start 25.746964 -9.423654)
		(end 25.748234 -9.424924)
		(width 0.3556)
		(layer "F.Cu")
		(net "GND")
	)
	(segment
		(start 427.456092 -287.435036)
		(end 428.840392 -287.435036)
		(width 0.4572)
		(layer "F.Cu")
		(net "GND")
	)
	(segment
		(start 361.22229 -395.8209)
		(end 360.86669 -396.1765)
		(width 0.254)
		(layer "F.Cu")
		(net "GND")
	)
	(segment
		(start 366.128046 -284.350206)
		(end 366.594898 -284.616144)
		(width 0.350012)
		(layer "F.Cu")
		(net "GND")
	)
	(segment
		(start 374.588024 -273.010122)
		(end 375.054876 -273.27606)
		(width 0.350012)
		(layer "F.Cu")
		(net "GND")
	)
	(segment
		(start 27.547062 -7.217156)
		(end 27.547062 -8.320024)
		(width 0.3556)
		(layer "F.Cu")
		(net "GND")
	)
	(segment
		(start 335.692242 -394.25753)
		(end 335.536794 -394.412978)
		(width 0.254)
		(layer "F.Cu")
		(net "GND")
	)
	(segment
		(start 377.407932 -295.690036)
		(end 377.874784 -295.955974)
		(width 0.350012)
		(layer "F.Cu")
		(net "GND")
	)
	(segment
		(start 110.584996 -397.86179)
		(end 110.584996 -398.729962)
		(width 0.3048)
		(layer "F.Cu")
		(net "GND")
	)
	(segment
		(start 149.968712 -120.485662)
		(end 149.304248 -120.485662)
		(width 0.4572)
		(layer "F.Cu")
		(net "GND")
	)
	(segment
		(start 369.417854 -277.060152)
		(end 369.884706 -277.32609)
		(width 0.350012)
		(layer "F.Cu")
		(net "GND")
	)
	(segment
		(start 402.445728 -392.30427)
		(end 402.498306 -392.356848)
		(width 0.254)
		(layer "F.Cu")
		(net "GND")
	)
	(segment
		(start 9.949942 -52.634896)
		(end 11.512042 -52.634896)
		(width 0.4572)
		(layer "F.Cu")
		(net "GND")
	)
	(segment
		(start 88.446356 -388.328662)
		(end 87.798402 -388.138924)
		(width 0.254)
		(layer "F.Cu")
		(net "GND")
	)
	(segment
		(start 433.197 -434.786786)
		(end 432.562 -434.786786)
		(width 0.4318)
		(layer "F.Cu")
		(net "GND")
	)
	(segment
		(start 232.732072 -69.960236)
		(end 232.732072 -70.576186)
		(width 0.4572)
		(layer "F.Cu")
		(net "GND")
	)
	(segment
		(start 333.697834 -288.399982)
		(end 333.230982 -288.66592)
		(width 0.350012)
		(layer "F.Cu")
		(net "GND")
	)
	(segment
		(start 91.398344 -384.617722)
		(end 91.345766 -383.92227)
		(width 0.254)
		(layer "F.Cu")
		(net "GND")
	)
	(segment
		(start 101.318314 -393.902946)
		(end 101.318314 -393.510262)
		(width 0.254)
		(layer "F.Cu")
		(net "GND")
	)
	(segment
		(start 136.217914 -248.800366)
		(end 136.684766 -248.534428)
		(width 0.350012)
		(layer "F.Cu")
		(net "GND")
	)
	(segment
		(start 169.865802 -12.495784)
		(end 169.865802 -12.495022)
		(width 0.3556)
		(layer "F.Cu")
		(net "GND")
	)
	(segment
		(start 83.577938 -230.980234)
		(end 83.111086 -230.71455)
		(width 0.350012)
		(layer "F.Cu")
		(net "GND")
	)
	(segment
		(start 355.957886 -240.700052)
		(end 355.491034 -240.434114)
		(width 0.350012)
		(layer "F.Cu")
		(net "GND")
	)
	(segment
		(start 138.397996 -280.30043)
		(end 138.864848 -280.566368)
		(width 0.350012)
		(layer "F.Cu")
		(net "GND")
	)
	(segment
		(start 351.557844 -291.640006)
		(end 351.091246 -291.905944)
		(width 0.350012)
		(layer "F.Cu")
		(net "GND")
	)
	(segment
		(start 98.598482 -386.6388)
		(end 99.111562 -386.449062)
		(width 0.254)
		(layer "F.Cu")
		(net "GND")
	)
	(segment
		(start 65.81648 -391.830814)
		(end 65.81648 -391.37971)
		(width 0.254)
		(layer "F.Cu")
		(net "GND")
	)
	(segment
		(start 87.637874 -288.400236)
		(end 87.171022 -288.666174)
		(width 0.350012)
		(layer "F.Cu")
		(net "GND")
	)
	(segment
		(start 341.045546 -391.784586)
		(end 341.045546 -392.004296)
		(width 0.2032)
		(layer "F.Cu")
		(net "GND")
	)
	(segment
		(start 343.105994 -394.831062)
		(end 342.597994 -395.0208)
		(width 0.254)
		(layer "F.Cu")
		(net "GND")
	)
	(segment
		(start 98.918014 -288.400236)
		(end 98.451162 -288.666174)
		(width 0.350012)
		(layer "F.Cu")
		(net "GND")
	)
	(segment
		(start 126.647956 -263.290304)
		(end 127.114808 -263.556242)
		(width 0.350012)
		(layer "F.Cu")
		(net "GND")
	)
	(segment
		(start 117.217952 -382.951482)
		(end 117.316504 -382.85293)
		(width 0.254)
		(layer "F.Cu")
		(net "GND")
	)
	(segment
		(start 89.845642 -383.622042)
		(end 89.845642 -383.402586)
		(width 0.254)
		(layer "F.Cu")
		(net "GND")
	)
	(segment
		(start 104.265222 -31.254954)
		(end 104.635808 -31.254954)
		(width 0.254)
		(layer "F.Cu")
		(net "GND")
	)
	(segment
		(start 112.717834 -245.560342)
		(end 113.184686 -245.294404)
		(width 0.350012)
		(layer "F.Cu")
		(net "GND")
	)
	(segment
		(start 326.81799 -232.599992)
		(end 326.351138 -232.334054)
		(width 0.350012)
		(layer "F.Cu")
		(net "GND")
	)
	(segment
		(start 376.491246 -398.542002)
		(end 375.970546 -398.542002)
		(width 0.254)
		(layer "F.Cu")
		(net "GND")
	)
	(segment
		(start 381.167894 -263.29005)
		(end 381.634746 -263.555988)
		(width 0.350012)
		(layer "F.Cu")
		(net "GND")
	)
	(segment
		(start 406.098248 -396.520924)
		(end 405.546306 -396.710662)
		(width 0.254)
		(layer "F.Cu")
		(net "GND")
	)
	(segment
		(start 157.806136 -386.449062)
		(end 157.29839 -386.6388)
		(width 0.254)
		(layer "F.Cu")
		(net "GND")
	)
	(segment
		(start 114.597942 -224.50044)
		(end 115.064794 -224.234502)
		(width 0.350012)
		(layer "F.Cu")
		(net "GND")
	)
	(segment
		(start 358.307894 -236.650022)
		(end 357.841042 -236.384084)
		(width 0.350012)
		(layer "F.Cu")
		(net "GND")
	)
	(segment
		(start 355.31806 -270.580104)
		(end 354.851208 -270.846042)
		(width 0.350012)
		(layer "F.Cu")
		(net "GND")
	)
	(segment
		(start 256.835148 -53.523642)
		(end 255.693926 -52.38242)
		(width 0.254)
		(layer "F.Cu")
		(net "GND")
	)
	(segment
		(start 345.618054 -256.900172)
		(end 345.151202 -256.634234)
		(width 0.350012)
		(layer "F.Cu")
		(net "GND")
	)
	(segment
		(start 130.107944 -236.650276)
		(end 130.574796 -236.384338)
		(width 0.350012)
		(layer "F.Cu")
		(net "GND")
	)
	(segment
		(start 143.740632 -108.333032)
		(end 143.06042 -108.333032)
		(width 0.4572)
		(layer "F.Cu")
		(net "GND")
	)
	(segment
		(start 413.916368 -367.796064)
		(end 413.303974 -367.796064)
		(width 0.3556)
		(layer "F.Cu")
		(net "GND")
	)
	(segment
		(start 90.157808 -247.180354)
		(end 89.690956 -246.914416)
		(width 0.350012)
		(layer "F.Cu")
		(net "GND")
	)
	(segment
		(start 416.468052 -227.935028)
		(end 415.083752 -227.935028)
		(width 0.4572)
		(layer "F.Cu")
		(net "GND")
	)
	(segment
		(start 132.916422 -391.830814)
		(end 132.916422 -391.37971)
		(width 0.254)
		(layer "F.Cu")
		(net "GND")
	)
	(segment
		(start 391.03808 -277.060152)
		(end 391.504678 -277.32609)
		(width 0.350012)
		(layer "F.Cu")
		(net "GND")
	)
	(segment
		(start 376.638058 -250.420124)
		(end 377.10491 -250.154186)
		(width 0.350012)
		(layer "F.Cu")
		(net "GND")
	)
	(segment
		(start 92.34424 -391.830814)
		(end 92.34424 -391.37971)
		(width 0.254)
		(layer "F.Cu")
		(net "GND")
	)
	(segment
		(start 151.890222 -384.617722)
		(end 152.498298 -384.617722)
		(width 0.254)
		(layer "F.Cu")
		(net "GND")
	)
	(segment
		(start 117.41785 -243.94033)
		(end 117.884702 -243.674392)
		(width 0.350012)
		(layer "F.Cu")
		(net "GND")
	)
	(segment
		(start 371.297962 -260.860032)
		(end 371.764814 -261.12597)
		(width 0.350012)
		(layer "F.Cu")
		(net "GND")
	)
	(segment
		(start 338.6455 -391.784586)
		(end 338.6455 -391.333482)
		(width 0.254)
		(layer "F.Cu")
		(net "GND")
	)
	(segment
		(start 143.267938 -251.230384)
		(end 143.73479 -250.964446)
		(width 0.350012)
		(layer "F.Cu")
		(net "GND")
	)
	(segment
		(start 183.522112 -114.652806)
		(end 183.132222 -114.262916)
		(width 0.254)
		(layer "F.Cu")
		(net "GND")
	)
	(segment
		(start 412.690056 -392.999722)
		(end 412.098236 -392.999722)
		(width 0.254)
		(layer "F.Cu")
		(net "GND")
	)
	(segment
		(start 337.445604 -391.333482)
		(end 337.544156 -391.23493)
		(width 0.254)
		(layer "F.Cu")
		(net "GND")
	)
	(segment
		(start 384.457956 -293.260018)
		(end 384.924808 -293.525956)
		(width 0.350012)
		(layer "F.Cu")
		(net "GND")
	)
	(segment
		(start 386.41782 -399.663158)
		(end 386.718048 -399.143474)
		(width 0.254)
		(layer "F.Cu")
		(net "GND")
	)
	(segment
		(start 329.167998 -223.69018)
		(end 328.701146 -223.424242)
		(width 0.350012)
		(layer "F.Cu")
		(net "GND")
	)
	(segment
		(start 345.618054 -226.120198)
		(end 345.151202 -225.85426)
		(width 0.350012)
		(layer "F.Cu")
		(net "GND")
	)
	(segment
		(start 355.362002 -396.51305)
		(end 355.062028 -396.813024)
		(width 0.254)
		(layer "F.Cu")
		(net "GND")
	)
	(segment
		(start 377.678442 -394.831062)
		(end 377.170442 -395.0208)
		(width 0.254)
		(layer "F.Cu")
		(net "GND")
	)
	(segment
		(start 363.307884 -277.870158)
		(end 363.774736 -278.136096)
		(width 0.350012)
		(layer "F.Cu")
		(net "GND")
	)
	(segment
		(start 357.668068 -294.070024)
		(end 357.201216 -294.335962)
		(width 0.350012)
		(layer "F.Cu")
		(net "GND")
	)
	(segment
		(start 150.85695 -13.599922)
		(end 150.85568 -13.598652)
		(width 0.3556)
		(layer "F.Cu")
		(net "GND")
	)
	(segment
		(start 115.83797 -290.020248)
		(end 116.304822 -290.286186)
		(width 0.350012)
		(layer "F.Cu")
		(net "GND")
	)
	(segment
		(start 179.516024 -238.135414)
		(end 180.900324 -238.135414)
		(width 0.4572)
		(layer "F.Cu")
		(net "GND")
	)
	(segment
		(start 421.69842 -395.0208)
		(end 421.00627 -394.831062)
		(width 0.254)
		(layer "F.Cu")
		(net "GND")
	)
	(segment
		(start 352.305366 -438.992772)
		(end 351.689416 -438.992772)
		(width 0.381)
		(layer "F.Cu")
		(net "GND")
	)
	(segment
		(start 46.87062 -388.08152)
		(end 46.621192 -387.832092)
		(width 0.254)
		(layer "F.Cu")
		(net "GND")
	)
	(segment
		(start 146.248882 -389.63092)
		(end 146.248882 -389.030972)
		(width 0.254)
		(layer "F.Cu")
		(net "GND")
	)
	(segment
		(start 299.513498 -422.188386)
		(end 299.513498 -423.272966)
		(width 0.381)
		(layer "F.Cu")
		(net "GND")
	)
	(segment
		(start 88.577928 -293.260272)
		(end 88.111076 -293.52621)
		(width 0.350012)
		(layer "F.Cu")
		(net "GND")
	)
	(segment
		(start 380.86792 -241.510058)
		(end 381.334772 -241.24412)
		(width 0.350012)
		(layer "F.Cu")
		(net "GND")
	)
	(segment
		(start 66.314828 -384.831082)
		(end 66.314828 -385.21132)
		(width 0.254)
		(layer "F.Cu")
		(net "GND")
	)
	(segment
		(start 12.780772 -412.112968)
		(end 12.11072 -412.112968)
		(width 0.1778)
		(layer "F.Cu")
		(net "GND")
	)
	(segment
		(start 409.229306 -166.54018)
		(end 409.000706 -166.76878)
		(width 0.2286)
		(layer "F.Cu")
		(net "GND")
	)
	(segment
		(start 372.238016 -264.100056)
		(end 372.704868 -264.365994)
		(width 0.350012)
		(layer "F.Cu")
		(net "GND")
	)
	(segment
		(start 120.238012 -226.120452)
		(end 120.70461 -225.854514)
		(width 0.350012)
		(layer "F.Cu")
		(net "GND")
	)
	(segment
		(start 126.347982 -236.650276)
		(end 126.814834 -236.384338)
		(width 0.350012)
		(layer "F.Cu")
		(net "GND")
	)
	(segment
		(start 70.861936 -12.372848)
		(end 70.863206 -12.374118)
		(width 0.3556)
		(layer "F.Cu")
		(net "GND")
	)
	(segment
		(start 348.907862 -256.090166)
		(end 348.44101 -255.824228)
		(width 0.350012)
		(layer "F.Cu")
		(net "GND")
	)
	(segment
		(start 195.25615 -42.549572)
		(end 195.924424 -42.549572)
		(width 0.4572)
		(layer "F.Cu")
		(net "GND")
	)
	(segment
		(start 177.927 -138.032998)
		(end 177.927 -138.648948)
		(width 0.4572)
		(layer "F.Cu")
		(net "GND")
	)
	(segment
		(start 165.006274 -386.449062)
		(end 164.498274 -386.6388)
		(width 0.254)
		(layer "F.Cu")
		(net "GND")
	)
	(segment
		(start 329.065128 -137.194036)
		(end 329.065128 -137.036302)
		(width 0.381)
		(layer "F.Cu")
		(net "GND")
	)
	(segment
		(start 412.956756 -12.372848)
		(end 412.956756 -11.26998)
		(width 0.3556)
		(layer "F.Cu")
		(net "GND")
	)
	(segment
		(start 108.487972 -236.650276)
		(end 108.02112 -236.384338)
		(width 0.350012)
		(layer "F.Cu")
		(net "GND")
	)
	(segment
		(start 402.046948 -9.423654)
		(end 402.048218 -9.424924)
		(width 0.3556)
		(layer "F.Cu")
		(net "GND")
	)
	(segment
		(start 108.487972 -238.270288)
		(end 108.02112 -238.00435)
		(width 0.350012)
		(layer "F.Cu")
		(net "GND")
	)
	(segment
		(start 304.070258 -392.999722)
		(end 304.01768 -392.30427)
		(width 0.254)
		(layer "F.Cu")
		(net "GND")
	)
	(segment
		(start 450.088 -284.88513)
		(end 451.4723 -284.88513)
		(width 0.4572)
		(layer "F.Cu")
		(net "GND")
	)
	(segment
		(start 384.233166 -180.175408)
		(end 384.159506 -180.353208)
		(width 0.2286)
		(layer "F.Cu")
		(net "GND")
	)
	(segment
		(start 103.317802 -235.84027)
		(end 102.85095 -235.574332)
		(width 0.350012)
		(layer "F.Cu")
		(net "GND")
	)
	(segment
		(start 325.408036 -256.090166)
		(end 324.75297 -256.090166)
		(width 0.350012)
		(layer "F.Cu")
		(net "GND")
	)
	(segment
		(start 183.616092 -305.285394)
		(end 182.231792 -305.285394)
		(width 0.4572)
		(layer "F.Cu")
		(net "GND")
	)
	(segment
		(start 85.457792 -239.080294)
		(end 84.99094 -238.814356)
		(width 0.350012)
		(layer "F.Cu")
		(net "GND")
	)
	(segment
		(start 121.477786 -286.780478)
		(end 121.944638 -287.046162)
		(width 0.350012)
		(layer "F.Cu")
		(net "GND")
	)
	(segment
		(start 22.147022 -12.372848)
		(end 22.147022 -11.26998)
		(width 0.3556)
		(layer "F.Cu")
		(net "GND")
	)
	(segment
		(start 48.11014 -99.20859)
		(end 48.11014 -98.59772)
		(width 0.381)
		(layer "F.Cu")
		(net "GND")
	)
	(segment
		(start 412.956756 -9.423654)
		(end 412.958026 -9.424924)
		(width 0.3556)
		(layer "F.Cu")
		(net "GND")
	)
	(segment
		(start 80.757776 -240.700306)
		(end 80.291178 -240.434368)
		(width 0.350012)
		(layer "F.Cu")
		(net "GND")
	)
	(segment
		(start 179.516024 -296.785284)
		(end 180.900324 -296.785284)
		(width 0.4572)
		(layer "F.Cu")
		(net "GND")
	)
	(segment
		(start 304.01895 -362.839)
		(end 303.276 -362.839)
		(width 0.381)
		(layer "F.Cu")
		(net "GND")
	)
	(segment
		(start 30.484064 -80.824324)
		(end 30.484064 -81.440274)
		(width 0.4572)
		(layer "F.Cu")
		(net "GND")
	)
	(segment
		(start 334.637888 -268.960092)
		(end 334.171036 -269.22603)
		(width 0.350012)
		(layer "F.Cu")
		(net "GND")
	)
	(segment
		(start 388.688072 -268.150086)
		(end 389.154924 -268.416024)
		(width 0.350012)
		(layer "F.Cu")
		(net "GND")
	)
	(segment
		(start 52.870608 -384.617722)
		(end 53.462428 -384.617722)
		(width 0.254)
		(layer "F.Cu")
		(net "GND")
	)
	(segment
		(start 100.497894 -235.84027)
		(end 100.031042 -235.574332)
		(width 0.350012)
		(layer "F.Cu")
		(net "GND")
	)
	(segment
		(start 431.55616 -239.835182)
		(end 430.17186 -239.835182)
		(width 0.4572)
		(layer "F.Cu")
		(net "GND")
	)
	(segment
		(start 343.245948 -396.710662)
		(end 342.597994 -396.520924)
		(width 0.254)
		(layer "F.Cu")
		(net "GND")
	)
	(segment
		(start 364.417864 -229.360222)
		(end 364.884716 -229.094284)
		(width 0.350012)
		(layer "F.Cu")
		(net "GND")
	)
	(segment
		(start 10.522458 -423.821098)
		(end 11.265408 -423.821098)
		(width 0.4572)
		(layer "F.Cu")
		(net "GND")
	)
	(segment
		(start 20.346924 -7.217156)
		(end 20.346924 -8.320024)
		(width 0.3556)
		(layer "F.Cu")
		(net "GND")
	)
	(segment
		(start 108.487972 -226.930458)
		(end 108.02112 -226.66452)
		(width 0.350012)
		(layer "F.Cu")
		(net "GND")
	)
	(segment
		(start 417.745672 -399.663158)
		(end 418.045646 -399.143474)
		(width 0.254)
		(layer "F.Cu")
		(net "GND")
	)
	(segment
		(start 36.56457 -351.932748)
		(end 36.63442 -351.862898)
		(width 0.381)
		(layer "F.Cu")
		(net "GND")
	)
	(segment
		(start 110.367826 -247.99036)
		(end 109.900974 -247.724422)
		(width 0.350012)
		(layer "F.Cu")
		(net "GND")
	)
	(segment
		(start 186.722004 -122.65279)
		(end 187.111894 -123.04268)
		(width 0.254)
		(layer "F.Cu")
		(net "GND")
	)
	(segment
		(start 446.644268 -218.585034)
		(end 445.259968 -218.585034)
		(width 0.4572)
		(layer "F.Cu")
		(net "GND")
	)
	(segment
		(start 145.447766 -294.070278)
		(end 145.914618 -294.336216)
		(width 0.350012)
		(layer "F.Cu")
		(net "GND")
	)
	(segment
		(start 340.747858 -295.690036)
		(end 340.281006 -295.955974)
		(width 0.350012)
		(layer "F.Cu")
		(net "GND")
	)
	(segment
		(start 389.798052 -224.500186)
		(end 390.264904 -224.234248)
		(width 0.350012)
		(layer "F.Cu")
		(net "GND")
	)
	(segment
		(start 198.276972 -76.016866)
		(end 198.276972 -75.27163)
		(width 0.3556)
		(layer "F.Cu")
		(net "GND")
	)
	(segment
		(start 65.717928 -383.402586)
		(end 65.81648 -383.304034)
		(width 0.254)
		(layer "F.Cu")
		(net "GND")
	)
	(segment
		(start 335.918556 -398.613122)
		(end 335.148682 -398.613122)
		(width 0.254)
		(layer "F.Cu")
		(net "GND")
	)
	(segment
		(start 390.737852 -245.560088)
		(end 391.204704 -245.29415)
		(width 0.350012)
		(layer "F.Cu")
		(net "GND")
	)
	(segment
		(start 115.181888 -126.29896)
		(end 114.23904 -126.29896)
		(width 0.381)
		(layer "F.Cu")
		(net "GND")
	)
	(segment
		(start 273.092164 -275.535136)
		(end 274.476464 -275.535136)
		(width 0.4572)
		(layer "F.Cu")
		(net "GND")
	)
	(segment
		(start 129.57048 -384.617722)
		(end 130.1623 -384.617722)
		(width 0.254)
		(layer "F.Cu")
		(net "GND")
	)
	(segment
		(start 345.447874 -285.970218)
		(end 344.981022 -286.236156)
		(width 0.350012)
		(layer "F.Cu")
		(net "GND")
	)
	(segment
		(start 110.83798 -232.600246)
		(end 110.371128 -232.334308)
		(width 0.350012)
		(layer "F.Cu")
		(net "GND")
	)
	(segment
		(start 315.391038 -398.542002)
		(end 314.870338 -398.542002)
		(width 0.254)
		(layer "F.Cu")
		(net "GND")
	)
	(segment
		(start 156.25572 -13.598652)
		(end 156.25572 -12.495022)
		(width 0.3556)
		(layer "F.Cu")
		(net "GND")
	)
	(segment
		(start 435.000146 -287.435036)
		(end 436.384446 -287.435036)
		(width 0.4572)
		(layer "F.Cu")
		(net "GND")
	)
	(segment
		(start 87.544402 -391.37971)
		(end 87.44585 -391.281158)
		(width 0.254)
		(layer "F.Cu")
		(net "GND")
	)
	(segment
		(start 420.24427 -400.212814)
		(end 420.24427 -399.76171)
		(width 0.254)
		(layer "F.Cu")
		(net "GND")
	)
	(segment
		(start 99.387914 -294.070278)
		(end 98.921062 -294.336216)
		(width 0.350012)
		(layer "F.Cu")
		(net "GND")
	)
	(segment
		(start 118.770654 -386.6388)
		(end 118.078504 -386.449062)
		(width 0.254)
		(layer "F.Cu")
		(net "GND")
	)
	(segment
		(start 58.666888 -10.16635)
		(end 58.665618 -10.16508)
		(width 0.3556)
		(layer "F.Cu")
		(net "GND")
	)
	(segment
		(start 187.060078 -238.135414)
		(end 188.444378 -238.135414)
		(width 0.4572)
		(layer "F.Cu")
		(net "GND")
	)
	(segment
		(start 51.884072 -284.035246)
		(end 50.499772 -284.035246)
		(width 0.4572)
		(layer "F.Cu")
		(net "GND")
	)
	(segment
		(start 431.55616 -221.13494)
		(end 430.17186 -221.13494)
		(width 0.4572)
		(layer "F.Cu")
		(net "GND")
	)
	(segment
		(start 373.17807 -277.060152)
		(end 373.644922 -277.32609)
		(width 0.350012)
		(layer "F.Cu")
		(net "GND")
	)
	(segment
		(start 376.467878 -263.29005)
		(end 376.93473 -263.555988)
		(width 0.350012)
		(layer "F.Cu")
		(net "GND")
	)
	(segment
		(start 373.579644 -177.532284)
		(end 372.991634 -177.532284)
		(width 0.381)
		(layer "F.Cu")
		(net "GND")
	)
	(segment
		(start 352.197924 -252.040136)
		(end 351.731072 -251.774198)
		(width 0.350012)
		(layer "F.Cu")
		(net "GND")
	)
	(segment
		(start 382.91643 -400.212814)
		(end 382.91643 -399.76171)
		(width 0.254)
		(layer "F.Cu")
		(net "GND")
	)
	(segment
		(start 376.167904 -235.03001)
		(end 376.634756 -234.764072)
		(width 0.350012)
		(layer "F.Cu")
		(net "GND")
	)
	(segment
		(start 105.00995 -122.686318)
		(end 105.00995 -121.676668)
		(width 0.3048)
		(layer "F.Cu")
		(net "GND")
	)
	(segment
		(start 144.977866 -265.720322)
		(end 145.444718 -265.98626)
		(width 0.350012)
		(layer "F.Cu")
		(net "GND")
	)
	(segment
		(start 384.457956 -268.960092)
		(end 384.924808 -269.22603)
		(width 0.350012)
		(layer "F.Cu")
		(net "GND")
	)
	(segment
		(start 222.86595 -82.804)
		(end 222.631 -82.804)
		(width 0.4572)
		(layer "F.Cu")
		(net "GND")
	)
	(segment
		(start 77.64399 -174.560484)
		(end 77.613002 -174.560484)
		(width 0.2286)
		(layer "F.Cu")
		(net "GND")
	)
	(segment
		(start 366.128046 -271.39011)
		(end 366.594898 -271.656048)
		(width 0.350012)
		(layer "F.Cu")
		(net "GND")
	)
	(segment
		(start 80.58785 -276.2504)
		(end 80.120998 -276.516338)
		(width 0.350012)
		(layer "F.Cu")
		(net "GND")
	)
	(segment
		(start 126.647956 -290.830254)
		(end 127.114808 -291.096192)
		(width 0.350012)
		(layer "F.Cu")
		(net "GND")
	)
	(segment
		(start 305.255676 -437.170322)
		(end 304.620676 -437.170322)
		(width 0.4318)
		(layer "F.Cu")
		(net "GND")
	)
	(segment
		(start 370.618512 -396.710662)
		(end 369.970558 -396.46352)
		(width 0.254)
		(layer "F.Cu")
		(net "GND")
	)
	(segment
		(start 128.05791 -268.960346)
		(end 128.524762 -269.226284)
		(width 0.350012)
		(layer "F.Cu")
		(net "GND")
	)
	(segment
		(start 385.570476 -395.0208)
		(end 384.87858 -394.831062)
		(width 0.254)
		(layer "F.Cu")
		(net "GND")
	)
	(segment
		(start 156.25826 -16.551148)
		(end 156.25826 -17.915382)
		(width 0.3556)
		(layer "F.Cu")
		(net "GND")
	)
	(segment
		(start 302.51781 -391.784586)
		(end 302.51781 -391.339578)
		(width 0.254)
		(layer "F.Cu")
		(net "GND")
	)
	(segment
		(start 363.778038 -277.060152)
		(end 364.24489 -277.32609)
		(width 0.350012)
		(layer "F.Cu")
		(net "GND")
	)
	(segment
		(start 83.577938 -245.560342)
		(end 83.111086 -245.294404)
		(width 0.350012)
		(layer "F.Cu")
		(net "GND")
	)
	(segment
		(start 345.645994 -396.710662)
		(end 344.99804 -396.520924)
		(width 0.254)
		(layer "F.Cu")
		(net "GND")
	)
	(segment
		(start 85.936582 -179.678584)
		(end 85.463634 -180.151532)
		(width 0.2286)
		(layer "F.Cu")
		(net "GND")
	)
	(segment
		(start 122.41784 -291.64026)
		(end 122.884692 -291.906198)
		(width 0.350012)
		(layer "F.Cu")
		(net "GND")
	)
	(segment
		(start 101.907848 -223.690434)
		(end 101.440996 -223.424496)
		(width 0.350012)
		(layer "F.Cu")
		(net "GND")
	)
	(segment
		(start 50.11801 -383.402586)
		(end 50.11801 -383.622296)
		(width 0.254)
		(layer "F.Cu")
		(net "GND")
	)
	(segment
		(start 124.870464 -159.980884)
		(end 124.282454 -159.980884)
		(width 0.381)
		(layer "F.Cu")
		(net "GND")
	)
	(segment
		(start 105.967784 -287.590484)
		(end 105.500932 -287.856422)
		(width 0.350012)
		(layer "F.Cu")
		(net "GND")
	)
	(segment
		(start 149.7457 -383.402586)
		(end 149.7457 -382.951482)
		(width 0.254)
		(layer "F.Cu")
		(net "GND")
	)
	(segment
		(start 375.22785 -223.69018)
		(end 375.694702 -223.424242)
		(width 0.350012)
		(layer "F.Cu")
		(net "GND")
	)
	(segment
		(start 242.188492 -294.936926)
		(end 242.188492 -294.277796)
		(width 0.381)
		(layer "F.Cu")
		(net "GND")
	)
	(segment
		(start 139.80795 -266.530328)
		(end 140.274802 -266.796266)
		(width 0.350012)
		(layer "F.Cu")
		(net "GND")
	)
	(segment
		(start 265.54811 -312.935112)
		(end 266.93241 -312.935112)
		(width 0.4572)
		(layer "F.Cu")
		(net "GND")
	)
	(segment
		(start 383.048002 -282.730194)
		(end 383.514854 -282.996132)
		(width 0.350012)
		(layer "F.Cu")
		(net "GND")
	)
	(segment
		(start 95.327978 -246.370348)
		(end 94.861126 -246.10441)
		(width 0.350012)
		(layer "F.Cu")
		(net "GND")
	)
	(segment
		(start 380.86792 -247.990106)
		(end 381.334772 -247.724168)
		(width 0.350012)
		(layer "F.Cu")
		(net "GND")
	)
	(segment
		(start 194.604132 -240.68532)
		(end 195.988432 -240.68532)
		(width 0.4572)
		(layer "F.Cu")
		(net "GND")
	)
	(segment
		(start 355.018086 -229.360222)
		(end 354.551234 -229.094284)
		(width 0.350012)
		(layer "F.Cu")
		(net "GND")
	)
	(segment
		(start 133.346952 -13.599922)
		(end 133.346952 -12.551156)
		(width 0.3556)
		(layer "F.Cu")
		(net "GND")
	)
	(segment
		(start 315.370972 -32.572706)
		(end 314.761372 -32.572706)
		(width 0.3556)
		(layer "F.Cu")
		(net "GND")
	)
	(segment
		(start 42.105326 -348.79915)
		(end 42.35831 -348.546166)
		(width 0.2286)
		(layer "F.Cu")
		(net "GND")
	)
	(segment
		(start 164.973 -96.41205)
		(end 164.973 -97.155)
		(width 0.381)
		(layer "F.Cu")
		(net "GND")
	)
	(segment
		(start 325.408036 -247.990106)
		(end 324.75297 -247.990106)
		(width 0.350012)
		(layer "F.Cu")
		(net "GND")
	)
	(segment
		(start 54.070504 -388.138924)
		(end 54.718458 -388.328662)
		(width 0.254)
		(layer "F.Cu")
		(net "GND")
	)
	(segment
		(start 97.705672 -119.869204)
		(end 97.074736 -119.869204)
		(width 0.4064)
		(layer "F.Cu")
		(net "GND")
	)
	(segment
		(start 86.2457 -383.402586)
		(end 86.2457 -382.951482)
		(width 0.254)
		(layer "F.Cu")
		(net "GND")
	)
	(segment
		(start 364.717838 -285.160212)
		(end 365.18469 -285.42615)
		(width 0.350012)
		(layer "F.Cu")
		(net "GND")
	)
	(segment
		(start 367.685066 -424.403012)
		(end 367.685066 -425.018962)
		(width 0.381)
		(layer "F.Cu")
		(net "GND")
	)
	(segment
		(start 435.000146 -306.135024)
		(end 436.384446 -306.135024)
		(width 0.4572)
		(layer "F.Cu")
		(net "GND")
	)
	(segment
		(start 102.677976 -272.20037)
		(end 102.211124 -272.466308)
		(width 0.350012)
		(layer "F.Cu")
		(net "GND")
	)
	(segment
		(start 413.931862 -364.781592)
		(end 413.319468 -364.781592)
		(width 0.3556)
		(layer "F.Cu")
		(net "GND")
	)
	(segment
		(start 284.736032 -211.784946)
		(end 283.351732 -211.784946)
		(width 0.4572)
		(layer "F.Cu")
		(net "GND")
	)
	(segment
		(start 206.248 -230.485442)
		(end 204.8637 -230.485442)
		(width 0.4572)
		(layer "F.Cu")
		(net "GND")
	)
	(segment
		(start 138.098022 -224.50044)
		(end 138.564874 -224.234502)
		(width 0.350012)
		(layer "F.Cu")
		(net "GND")
	)
	(segment
		(start 68.961 -55.992014)
		(end 67.945 -55.992014)
		(width 0.381)
		(layer "F.Cu")
		(net "GND")
	)
	(segment
		(start 365.357918 -226.120198)
		(end 365.82477 -225.85426)
		(width 0.350012)
		(layer "F.Cu")
		(net "GND")
	)
	(segment
		(start 82.467958 -292.450266)
		(end 82.001106 -292.716204)
		(width 0.350012)
		(layer "F.Cu")
		(net "GND")
	)
	(segment
		(start 113.721134 -388.330948)
		(end 113.401602 -388.330948)
		(width 0.254)
		(layer "F.Cu")
		(net "GND")
	)
	(segment
		(start 316.578234 -394.831062)
		(end 316.070234 -395.0208)
		(width 0.254)
		(layer "F.Cu")
		(net "GND")
	)
	(segment
		(start 113.017808 -280.30043)
		(end 113.48466 -280.566368)
		(width 0.350012)
		(layer "F.Cu")
		(net "GND")
	)
	(segment
		(start 95.327978 -244.750336)
		(end 94.861126 -244.484398)
		(width 0.350012)
		(layer "F.Cu")
		(net "GND")
	)
	(segment
		(start 105.302558 -382.27)
		(end 105.628948 -381.94361)
		(width 0.254)
		(layer "F.Cu")
		(net "GND")
	)
	(segment
		(start 58.616596 -391.37971)
		(end 58.518044 -391.281158)
		(width 0.254)
		(layer "F.Cu")
		(net "GND")
	)
	(segment
		(start 123.997974 -224.50044)
		(end 124.464826 -224.234502)
		(width 0.350012)
		(layer "F.Cu")
		(net "GND")
	)
	(segment
		(start 90.457782 -288.400236)
		(end 89.99093 -288.666174)
		(width 0.350012)
		(layer "F.Cu")
		(net "GND")
	)
	(segment
		(start 355.557328 -163.26231)
		(end 356.207568 -163.26231)
		(width 0.381)
		(layer "F.Cu")
		(net "GND")
	)
	(segment
		(start 124.297948 -264.10031)
		(end 124.7648 -264.366248)
		(width 0.350012)
		(layer "F.Cu")
		(net "GND")
	)
	(segment
		(start 410.545788 -392.004296)
		(end 410.845762 -392.30427)
		(width 0.254)
		(layer "F.Cu")
		(net "GND")
	)
	(segment
		(start 91.144344 -391.830814)
		(end 91.144344 -391.37971)
		(width 0.254)
		(layer "F.Cu")
		(net "GND")
	)
	(segment
		(start 361.033568 -411.913324)
		(end 361.455208 -412.334964)
		(width 0.381)
		(layer "F.Cu")
		(net "GND")
	)
	(segment
		(start 313.670442 -392.999722)
		(end 313.062112 -392.999722)
		(width 0.254)
		(layer "F.Cu")
		(net "GND")
	)
	(segment
		(start 284.736032 -286.585152)
		(end 283.351732 -286.585152)
		(width 0.4572)
		(layer "F.Cu")
		(net "GND")
	)
	(segment
		(start 414.498282 -392.999722)
		(end 414.445704 -392.30427)
		(width 0.254)
		(layer "F.Cu")
		(net "GND")
	)
	(segment
		(start 339.977984 -243.940076)
		(end 339.511132 -243.674138)
		(width 0.350012)
		(layer "F.Cu")
		(net "GND")
	)
	(segment
		(start 96.737932 -224.50044)
		(end 96.27108 -224.234502)
		(width 0.350012)
		(layer "F.Cu")
		(net "GND")
	)
	(segment
		(start 368.17808 -243.940076)
		(end 368.644678 -243.674138)
		(width 0.350012)
		(layer "F.Cu")
		(net "GND")
	)
	(segment
		(start 338.868004 -292.450012)
		(end 338.401152 -292.71595)
		(width 0.350012)
		(layer "F.Cu")
		(net "GND")
	)
	(segment
		(start 121.678446 -386.449062)
		(end 121.170446 -386.6388)
		(width 0.254)
		(layer "F.Cu")
		(net "GND")
	)
	(segment
		(start 418.098224 -398.542002)
		(end 417.419028 -398.542002)
		(width 0.254)
		(layer "F.Cu")
		(net "GND")
	)
	(segment
		(start 40.23995 -212.635338)
		(end 41.62425 -212.635338)
		(width 0.4572)
		(layer "F.Cu")
		(net "GND")
	)
	(segment
		(start 146.38782 -284.35046)
		(end 147.042886 -284.35046)
		(width 0.350012)
		(layer "F.Cu")
		(net "GND")
	)
	(segment
		(start 350.14789 -295.690036)
		(end 349.681038 -295.955974)
		(width 0.350012)
		(layer "F.Cu")
		(net "GND")
	)
	(segment
		(start 409.69819 -398.542002)
		(end 409.018994 -398.542002)
		(width 0.254)
		(layer "F.Cu")
		(net "GND")
	)
	(segment
		(start 64.616584 -391.37971)
		(end 64.518032 -391.281158)
		(width 0.254)
		(layer "F.Cu")
		(net "GND")
	)
	(segment
		(start 113.487962 -284.35046)
		(end 113.954814 -284.616398)
		(width 0.350012)
		(layer "F.Cu")
		(net "GND")
	)
	(segment
		(start 393.06119 -179.678584)
		(end 392.587988 -180.151786)
		(width 0.2286)
		(layer "F.Cu")
		(net "GND")
	)
	(segment
		(start 108.017818 -230.980234)
		(end 107.550966 -230.714296)
		(width 0.350012)
		(layer "F.Cu")
		(net "GND")
	)
	(segment
		(start 431.36693 -12.372848)
		(end 431.36693 -11.26998)
		(width 0.3556)
		(layer "F.Cu")
		(net "GND")
	)
	(segment
		(start 144.677892 -242.320318)
		(end 145.144744 -242.05438)
		(width 0.350012)
		(layer "F.Cu")
		(net "GND")
	)
	(segment
		(start 31.145734 -7.215886)
		(end 31.147004 -7.217156)
		(width 0.3556)
		(layer "F.Cu")
		(net "GND")
	)
	(segment
		(start 325.70801 -271.39011)
		(end 325.052944 -271.39011)
		(width 0.350012)
		(layer "F.Cu")
		(net "GND")
	)
	(segment
		(start 372.991634 -177.532284)
		(end 372.921784 -177.602134)
		(width 0.381)
		(layer "F.Cu")
		(net "GND")
	)
	(segment
		(start 118.5164 -391.37971)
		(end 118.5164 -391.830814)
		(width 0.254)
		(layer "F.Cu")
		(net "GND")
	)
	(segment
		(start 363.307884 -268.150086)
		(end 363.774736 -268.416024)
		(width 0.350012)
		(layer "F.Cu")
		(net "GND")
	)
	(segment
		(start 78.109826 -387.231128)
		(end 78.62951 -386.931154)
		(width 0.254)
		(layer "F.Cu")
		(net "GND")
	)
	(segment
		(start 124.297948 -273.820382)
		(end 124.7648 -274.08632)
		(width 0.350012)
		(layer "F.Cu")
		(net "GND")
	)
	(segment
		(start 111.137954 -285.160466)
		(end 110.671102 -285.426404)
		(width 0.350012)
		(layer "F.Cu")
		(net "GND")
	)
	(segment
		(start 44.340018 -314.635388)
		(end 42.955718 -314.635388)
		(width 0.4572)
		(layer "F.Cu")
		(net "GND")
	)
	(segment
		(start 126.916434 -391.830814)
		(end 126.916434 -391.37971)
		(width 0.254)
		(layer "F.Cu")
		(net "GND")
	)
	(segment
		(start 420.155878 -366.602264)
		(end 420.031418 -366.602264)
		(width 0.3556)
		(layer "F.Cu")
		(net "GND")
	)
	(segment
		(start 418.606224 -394.831062)
		(end 418.098224 -395.0208)
		(width 0.254)
		(layer "F.Cu")
		(net "GND")
	)
	(segment
		(start 144.977866 -281.920442)
		(end 145.444718 -282.18638)
		(width 0.350012)
		(layer "F.Cu")
		(net "GND")
	)
	(segment
		(start 85.457792 -237.460282)
		(end 84.99094 -237.194344)
		(width 0.350012)
		(layer "F.Cu")
		(net "GND")
	)
	(segment
		(start 348.268036 -284.350206)
		(end 347.801184 -284.616144)
		(width 0.350012)
		(layer "F.Cu")
		(net "GND")
	)
	(segment
		(start 118.187978 -281.110436)
		(end 118.65483 -281.376374)
		(width 0.350012)
		(layer "F.Cu")
		(net "GND")
	)
	(segment
		(start 384.157982 -229.360222)
		(end 384.624834 -229.094284)
		(width 0.350012)
		(layer "F.Cu")
		(net "GND")
	)
	(segment
		(start 60.070492 -386.6388)
		(end 59.378596 -386.449062)
		(width 0.254)
		(layer "F.Cu")
		(net "GND")
	)
	(segment
		(start 412.367984 -238.13516)
		(end 413.752284 -238.13516)
		(width 0.4572)
		(layer "F.Cu")
		(net "GND")
	)
	(segment
		(start 339.977984 -239.08004)
		(end 339.511132 -238.814102)
		(width 0.350012)
		(layer "F.Cu")
		(net "GND")
	)
	(segment
		(start 103.147876 -274.630388)
		(end 102.681024 -274.896326)
		(width 0.350012)
		(layer "F.Cu")
		(net "GND")
	)
	(segment
		(start 335.536794 -394.412978)
		(end 335.148682 -394.412978)
		(width 0.254)
		(layer "F.Cu")
		(net "GND")
	)
	(segment
		(start 342.797892 -250.420124)
		(end 342.33104 -250.154186)
		(width 0.350012)
		(layer "F.Cu")
		(net "GND")
	)
	(segment
		(start 88.998298 -390.160002)
		(end 89.518998 -390.160002)
		(width 0.254)
		(layer "F.Cu")
		(net "GND")
	)
	(segment
		(start 302.51781 -391.339578)
		(end 302.46828 -391.290048)
		(width 0.254)
		(layer "F.Cu")
		(net "GND")
	)
	(segment
		(start 367.238026 -232.599992)
		(end 367.704878 -232.334054)
		(width 0.350012)
		(layer "F.Cu")
		(net "GND")
	)
	(segment
		(start 326.81799 -224.500186)
		(end 326.351138 -224.234248)
		(width 0.350012)
		(layer "F.Cu")
		(net "GND")
	)
	(segment
		(start 403.006306 -394.831062)
		(end 402.248878 -395.012926)
		(width 0.254)
		(layer "F.Cu")
		(net "GND")
	)
	(segment
		(start 384.457956 -272.200116)
		(end 384.924808 -272.466054)
		(width 0.350012)
		(layer "F.Cu")
		(net "GND")
	)
	(segment
		(start 202.147932 -275.53539)
		(end 203.532232 -275.53539)
		(width 0.4572)
		(layer "F.Cu")
		(net "GND")
	)
	(segment
		(start 127.691134 -390.160002)
		(end 127.170434 -390.160002)
		(width 0.254)
		(layer "F.Cu")
		(net "GND")
	)
	(segment
		(start 88.747854 -249.610372)
		(end 88.281002 -249.344434)
		(width 0.350012)
		(layer "F.Cu")
		(net "GND")
	)
	(segment
		(start 133.398006 -247.180354)
		(end 133.864858 -246.914416)
		(width 0.350012)
		(layer "F.Cu")
		(net "GND")
	)
	(segment
		(start 108.017818 -252.04039)
		(end 107.550966 -251.774452)
		(width 0.350012)
		(layer "F.Cu")
		(net "GND")
	)
	(segment
		(start 90.627962 -247.99036)
		(end 90.16111 -247.724422)
		(width 0.350012)
		(layer "F.Cu")
		(net "GND")
	)
	(segment
		(start 87.637874 -293.260272)
		(end 87.171022 -293.52621)
		(width 0.350012)
		(layer "F.Cu")
		(net "GND")
	)
	(segment
		(start 66.834512 -385.131056)
		(end 66.834512 -384.531108)
		(width 0.254)
		(layer "F.Cu")
		(net "GND")
	)
	(segment
		(start 106.137964 -229.360476)
		(end 105.671112 -229.094538)
		(width 0.350012)
		(layer "F.Cu")
		(net "GND")
	)
	(segment
		(start 13.206984 -394.847318)
		(end 13.206984 -395.248638)
		(width 0.254)
		(layer "F.Cu")
		(net "GND")
	)
	(segment
		(start 420.3573 -36.007548)
		(end 419.74135 -36.007548)
		(width 0.4572)
		(layer "F.Cu")
		(net "GND")
	)
	(segment
		(start 105.967784 -274.630388)
		(end 105.500932 -274.896326)
		(width 0.350012)
		(layer "F.Cu")
		(net "GND")
	)
	(segment
		(start 307.368194 -302.73498)
		(end 305.983894 -302.73498)
		(width 0.4572)
		(layer "F.Cu")
		(net "GND")
	)
	(segment
		(start 341.857838 -255.28016)
		(end 341.390986 -255.014222)
		(width 0.350012)
		(layer "F.Cu")
		(net "GND")
	)
	(segment
		(start 322.017644 -399.143474)
		(end 322.070476 -398.542002)
		(width 0.254)
		(layer "F.Cu")
		(net "GND")
	)
	(segment
		(start 331.81798 -272.200116)
		(end 331.351128 -272.466054)
		(width 0.350012)
		(layer "F.Cu")
		(net "GND")
	)
	(segment
		(start 396.646908 -9.423654)
		(end 396.648178 -9.424924)
		(width 0.3556)
		(layer "F.Cu")
		(net "GND")
	)
	(segment
		(start 347.968062 -254.470154)
		(end 347.50121 -254.204216)
		(width 0.350012)
		(layer "F.Cu")
		(net "GND")
	)
	(segment
		(start 23.416768 -435.925214)
		(end 23.416768 -435.290214)
		(width 0.3556)
		(layer "F.Cu")
		(net "GND")
	)
	(segment
		(start 353.137978 -237.460028)
		(end 352.671126 -237.19409)
		(width 0.350012)
		(layer "F.Cu")
		(net "GND")
	)
	(segment
		(start 117.247924 -268.15034)
		(end 117.714776 -268.416278)
		(width 0.350012)
		(layer "F.Cu")
		(net "GND")
	)
	(segment
		(start 279.893268 -100.421694)
		(end 279.893268 -99.530408)
		(width 0.3556)
		(layer "F.Cu")
		(net "GND")
	)
	(segment
		(start 424.012106 -277.235158)
		(end 422.627806 -277.235158)
		(width 0.4572)
		(layer "F.Cu")
		(net "GND")
	)
	(segment
		(start 205.393036 -98.244914)
		(end 205.914244 -98.244914)
		(width 0.381)
		(layer "F.Cu")
		(net "GND")
	)
	(segment
		(start 361.42803 -279.49017)
		(end 361.894882 -279.756108)
		(width 0.350012)
		(layer "F.Cu")
		(net "GND")
	)
	(segment
		(start 164.145722 -383.622296)
		(end 164.445696 -383.92227)
		(width 0.254)
		(layer "F.Cu")
		(net "GND")
	)
	(segment
		(start 345.918028 -280.300176)
		(end 345.451176 -280.566114)
		(width 0.350012)
		(layer "F.Cu")
		(net "GND")
	)
	(segment
		(start 273.092164 -228.785166)
		(end 274.476464 -228.785166)
		(width 0.4572)
		(layer "F.Cu")
		(net "GND")
	)
	(segment
		(start 335.148682 -393.24915)
		(end 335.39811 -392.999722)
		(width 0.254)
		(layer "F.Cu")
		(net "GND")
	)
	(segment
		(start 382.107948 -294.070024)
		(end 382.5748 -294.335962)
		(width 0.350012)
		(layer "F.Cu")
		(net "GND")
	)
	(segment
		(start 387.917944 -253.660148)
		(end 388.384796 -253.39421)
		(width 0.350012)
		(layer "F.Cu")
		(net "GND")
	)
	(segment
		(start 343.268046 -228.550216)
		(end 342.801194 -228.284278)
		(width 0.350012)
		(layer "F.Cu")
		(net "GND")
	)
	(segment
		(start 72.662034 -8.320024)
		(end 72.662034 -7.217156)
		(width 0.3556)
		(layer "F.Cu")
		(net "GND")
	)
	(segment
		(start 113.401602 -388.330948)
		(end 113.201704 -388.13105)
		(width 0.254)
		(layer "F.Cu")
		(net "GND")
	)
	(segment
		(start 94.998286 -390.160002)
		(end 95.518986 -390.160002)
		(width 0.254)
		(layer "F.Cu")
		(net "GND")
	)
	(segment
		(start 93.246194 -388.328662)
		(end 92.59824 -388.138924)
		(width 0.254)
		(layer "F.Cu")
		(net "GND")
	)
	(segment
		(start 119.291354 -390.160002)
		(end 118.770654 -390.160002)
		(width 0.254)
		(layer "F.Cu")
		(net "GND")
	)
	(segment
		(start 114.23904 -415.939986)
		(end 114.935 -415.939986)
		(width 0.381)
		(layer "F.Cu")
		(net "GND")
	)
	(segment
		(start 369.417854 -275.44014)
		(end 369.884706 -275.706078)
		(width 0.350012)
		(layer "F.Cu")
		(net "GND")
	)
	(segment
		(start 49.91862 -388.328662)
		(end 50.470562 -388.138924)
		(width 0.254)
		(layer "F.Cu")
		(net "GND")
	)
	(segment
		(start 113.917984 -390.761474)
		(end 113.61801 -391.281158)
		(width 0.254)
		(layer "F.Cu")
		(net "GND")
	)
	(segment
		(start 422.462198 -394.113004)
		(end 422.2115 -394.831062)
		(width 0.254)
		(layer "F.Cu")
		(net "GND")
	)
	(segment
		(start 260.99008 -139.648946)
		(end 260.99008 -140.391896)
		(width 0.1778)
		(layer "F.Cu")
		(net "GND")
	)
	(segment
		(start 114.597942 -252.04039)
		(end 115.064794 -251.774452)
		(width 0.350012)
		(layer "F.Cu")
		(net "GND")
	)
	(segment
		(start 113.017808 -273.820382)
		(end 113.48466 -274.08632)
		(width 0.350012)
		(layer "F.Cu")
		(net "GND")
	)
	(segment
		(start 252.140212 -106.905044)
		(end 252.585728 -106.905044)
		(width 0.4572)
		(layer "F.Cu")
		(net "GND")
	)
	(segment
		(start 146.49831 -388.08152)
		(end 146.248882 -387.832092)
		(width 0.254)
		(layer "F.Cu")
		(net "GND")
	)
	(segment
		(start 328.697844 -245.560088)
		(end 328.231246 -245.29415)
		(width 0.350012)
		(layer "F.Cu")
		(net "GND")
	)
	(segment
		(start 427.680628 -436.564786)
		(end 427.411896 -436.296054)
		(width 0.381)
		(layer "F.Cu")
		(net "GND")
	)
	(segment
		(start 48.017938 -390.761474)
		(end 47.717964 -391.281158)
		(width 0.254)
		(layer "F.Cu")
		(net "GND")
	)
	(segment
		(start 101.907848 -256.09042)
		(end 101.440996 -255.824482)
		(width 0.350012)
		(layer "F.Cu")
		(net "GND")
	)
	(segment
		(start 387.61797 -399.663158)
		(end 387.917944 -399.143474)
		(width 0.254)
		(layer "F.Cu")
		(net "GND")
	)
	(segment
		(start 365.657892 -285.160212)
		(end 366.124744 -285.42615)
		(width 0.350012)
		(layer "F.Cu")
		(net "GND")
	)
	(segment
		(start 156.045662 -390.761474)
		(end 155.745688 -391.281158)
		(width 0.254)
		(layer "F.Cu")
		(net "GND")
	)
	(segment
		(start 332.305914 -23.882858)
		(end 331.838046 -23.41499)
		(width 0.508)
		(layer "F.Cu")
		(net "GND")
	)
	(segment
		(start 114.897916 -291.64026)
		(end 115.364768 -291.906198)
		(width 0.350012)
		(layer "F.Cu")
		(net "GND")
	)
	(segment
		(start 209.239358 -142.249398)
		(end 209.239358 -142.490952)
		(width 0.4572)
		(layer "F.Cu")
		(net "GND")
	)
	(segment
		(start 374.75795 -239.08004)
		(end 375.224802 -238.814102)
		(width 0.350012)
		(layer "F.Cu")
		(net "GND")
	)
	(segment
		(start 429.568102 -12.37488)
		(end 429.568102 -12.374118)
		(width 0.3556)
		(layer "F.Cu")
		(net "GND")
	)
	(segment
		(start 146.248882 -386.030978)
		(end 146.248882 -385.43103)
		(width 0.254)
		(layer "F.Cu")
		(net "GND")
	)
	(segment
		(start 148.545804 -382.951482)
		(end 148.644356 -382.85293)
		(width 0.254)
		(layer "F.Cu")
		(net "GND")
	)
	(segment
		(start 132.61848 -388.328662)
		(end 131.970526 -388.138924)
		(width 0.254)
		(layer "F.Cu")
		(net "GND")
	)
	(segment
		(start 133.227826 -282.730448)
		(end 133.694678 -282.996386)
		(width 0.350012)
		(layer "F.Cu")
		(net "GND")
	)
	(segment
		(start 21.70811 -312.085228)
		(end 20.32381 -312.085228)
		(width 0.4572)
		(layer "F.Cu")
		(net "GND")
	)
	(segment
		(start 128.018032 -391.281158)
		(end 128.116584 -391.37971)
		(width 0.254)
		(layer "F.Cu")
		(net "GND")
	)
	(segment
		(start 402.623782 -322.13804)
		(end 403.025102 -322.53936)
		(width 0.381)
		(layer "F.Cu")
		(net "GND")
	)
	(segment
		(start 358.778048 -240.700052)
		(end 358.311196 -240.434114)
		(width 0.350012)
		(layer "F.Cu")
		(net "GND")
	)
	(segment
		(start 348.437962 -229.360222)
		(end 347.97111 -229.094284)
		(width 0.350012)
		(layer "F.Cu")
		(net "GND")
	)
	(segment
		(start 317.108078 -412.212536)
		(end 317.108078 -411.343602)
		(width 0.381)
		(layer "F.Cu")
		(net "GND")
	)
	(segment
		(start 80.58785 -274.630388)
		(end 80.120998 -274.896326)
		(width 0.350012)
		(layer "F.Cu")
		(net "GND")
	)
	(segment
		(start 78.62951 -386.931154)
		(end 78.929484 -387.231128)
		(width 0.254)
		(layer "F.Cu")
		(net "GND")
	)
	(segment
		(start 402.029422 -395.613128)
		(end 402.248878 -395.613128)
		(width 0.254)
		(layer "F.Cu")
		(net "GND")
	)
	(segment
		(start 55.066946 -9.423654)
		(end 55.068216 -9.424924)
		(width 0.3556)
		(layer "F.Cu")
		(net "GND")
	)
	(segment
		(start 109.347 -19.379692)
		(end 109.347 -18.5166)
		(width 0.381)
		(layer "F.Cu")
		(net "GND")
	)
	(segment
		(start 424.012106 -218.585034)
		(end 422.627806 -218.585034)
		(width 0.4572)
		(layer "F.Cu")
		(net "GND")
	)
	(segment
		(start 338.097876 -252.040136)
		(end 337.631024 -251.774198)
		(width 0.350012)
		(layer "F.Cu")
		(net "GND")
	)
	(segment
		(start 355.957886 -242.320064)
		(end 355.491034 -242.054126)
		(width 0.350012)
		(layer "F.Cu")
		(net "GND")
	)
	(segment
		(start 131.699 -109.07395)
		(end 132.715 -109.07395)
		(width 0.381)
		(layer "F.Cu")
		(net "GND")
	)
	(segment
		(start 161.745676 -383.622296)
		(end 162.04565 -383.92227)
		(width 0.254)
		(layer "F.Cu")
		(net "GND")
	)
	(segment
		(start 265.54811 -212.635084)
		(end 266.93241 -212.635084)
		(width 0.4572)
		(layer "F.Cu")
		(net "GND")
	)
	(segment
		(start 339.508084 -249.610118)
		(end 339.040978 -249.34418)
		(width 0.350012)
		(layer "F.Cu")
		(net "GND")
	)
	(segment
		(start 358.307894 -230.169974)
		(end 357.841042 -229.904036)
		(width 0.350012)
		(layer "F.Cu")
		(net "GND")
	)
	(segment
		(start 330.108052 -244.750082)
		(end 329.6412 -244.484144)
		(width 0.350012)
		(layer "F.Cu")
		(net "GND")
	)
	(segment
		(start 101.737922 -288.400236)
		(end 101.27107 -288.666174)
		(width 0.350012)
		(layer "F.Cu")
		(net "GND")
	)
	(segment
		(start 165.645592 -390.761474)
		(end 165.698424 -390.160002)
		(width 0.254)
		(layer "F.Cu")
		(net "GND")
	)
	(segment
		(start 406.945592 -391.784586)
		(end 406.945592 -392.004042)
		(width 0.2032)
		(layer "F.Cu")
		(net "GND")
	)
	(segment
		(start 284.736032 -239.835182)
		(end 283.351732 -239.835182)
		(width 0.4572)
		(layer "F.Cu")
		(net "GND")
	)
	(segment
		(start 364.417864 -226.120198)
		(end 364.884716 -225.85426)
		(width 0.350012)
		(layer "F.Cu")
		(net "GND")
	)
	(segment
		(start 280.635964 -278.085042)
		(end 282.020264 -278.085042)
		(width 0.4572)
		(layer "F.Cu")
		(net "GND")
	)
	(segment
		(start 52.262532 -384.617722)
		(end 51.670712 -384.617722)
		(width 0.254)
		(layer "F.Cu")
		(net "GND")
	)
	(segment
		(start 117.570504 -384.617722)
		(end 116.962428 -384.617722)
		(width 0.254)
		(layer "F.Cu")
		(net "GND")
	)
	(segment
		(start 119.458486 -429.823372)
		(end 119.458486 -429.006)
		(width 0.4318)
		(layer "F.Cu")
		(net "GND")
	)
	(segment
		(start 126.647956 -273.010376)
		(end 127.114808 -273.276314)
		(width 0.350012)
		(layer "F.Cu")
		(net "GND")
	)
	(segment
		(start 316.917832 -391.784586)
		(end 316.917832 -392.004296)
		(width 0.254)
		(layer "F.Cu")
		(net "GND")
	)
	(segment
		(start 271.739106 -349.781622)
		(end 271.770094 -349.781622)
		(width 0.2286)
		(layer "F.Cu")
		(net "GND")
	)
	(segment
		(start 379.457966 -243.940076)
		(end 379.924818 -243.674138)
		(width 0.350012)
		(layer "F.Cu")
		(net "GND")
	)
	(segment
		(start 323.234558 -412.212536)
		(end 323.234558 -411.305502)
		(width 0.381)
		(layer "F.Cu")
		(net "GND")
	)
	(segment
		(start 79.14894 -387.832092)
		(end 79.14894 -387.231128)
		(width 0.254)
		(layer "F.Cu")
		(net "GND")
	)
	(segment
		(start 125.877828 -247.180354)
		(end 126.34468 -246.914416)
		(width 0.350012)
		(layer "F.Cu")
		(net "GND")
	)
	(segment
		(start 365.331248 -39.843964)
		(end 365.331248 -38.650164)
		(width 0.3556)
		(layer "F.Cu")
		(net "GND")
	)
	(segment
		(start 368.947954 -269.770098)
		(end 369.414806 -270.036036)
		(width 0.350012)
		(layer "F.Cu")
		(net "GND")
	)
	(segment
		(start 143.567912 -281.110436)
		(end 144.034764 -281.376374)
		(width 0.350012)
		(layer "F.Cu")
		(net "GND")
	)
	(segment
		(start 91.717368 -339.413596)
		(end 91.717368 -340.044532)
		(width 0.381)
		(layer "F.Cu")
		(net "GND")
	)
	(segment
		(start 435.000146 -238.13516)
		(end 436.384446 -238.13516)
		(width 0.4572)
		(layer "F.Cu")
		(net "GND")
	)
	(segment
		(start 160.898332 -388.138924)
		(end 160.346136 -388.328662)
		(width 0.254)
		(layer "F.Cu")
		(net "GND")
	)
	(segment
		(start 66.314828 -387.231128)
		(end 66.314828 -387.831076)
		(width 0.254)
		(layer "F.Cu")
		(net "GND")
	)
	(segment
		(start 314.66282 -338.060538)
		(end 314.693808 -338.060538)
		(width 0.2286)
		(layer "F.Cu")
		(net "GND")
	)
	(segment
		(start 358.307894 -233.409998)
		(end 357.841042 -233.14406)
		(width 0.350012)
		(layer "F.Cu")
		(net "GND")
	)
	(segment
		(start 369.588034 -223.69018)
		(end 370.054886 -223.424242)
		(width 0.350012)
		(layer "F.Cu")
		(net "GND")
	)
	(segment
		(start 213.369398 -21.067014)
		(end 212.799168 -21.637244)
		(width 0.3556)
		(layer "F.Cu")
		(net "GND")
	)
	(segment
		(start 378.347986 -284.350206)
		(end 378.814838 -284.616144)
		(width 0.350012)
		(layer "F.Cu")
		(net "GND")
	)
	(segment
		(start 255.261618 -50.382424)
		(end 256.041398 -50.382424)
		(width 0.254)
		(layer "F.Cu")
		(net "GND")
	)
	(segment
		(start 179.516024 -200.735438)
		(end 180.900324 -200.735438)
		(width 0.4572)
		(layer "F.Cu")
		(net "GND")
	)
	(segment
		(start 22.148292 -12.374118)
		(end 22.147022 -12.372848)
		(width 0.3556)
		(layer "F.Cu")
		(net "GND")
	)
	(segment
		(start 442.5442 -306.135024)
		(end 443.9285 -306.135024)
		(width 0.4572)
		(layer "F.Cu")
		(net "GND")
	)
	(segment
		(start 18.54708 -7.217156)
		(end 18.54708 -8.320024)
		(width 0.3556)
		(layer "F.Cu")
		(net "GND")
	)
	(segment
		(start 369.417854 -283.5402)
		(end 369.884706 -283.806138)
		(width 0.350012)
		(layer "F.Cu")
		(net "GND")
	)
	(segment
		(start 66.101468 -384.617722)
		(end 65.462404 -384.617722)
		(width 0.254)
		(layer "F.Cu")
		(net "GND")
	)
	(segment
		(start 335.277968 -245.560088)
		(end 334.811116 -245.29415)
		(width 0.350012)
		(layer "F.Cu")
		(net "GND")
	)
	(segment
		(start 77.937868 -224.50044)
		(end 77.471016 -224.234502)
		(width 0.350012)
		(layer "F.Cu")
		(net "GND")
	)
	(segment
		(start 387.917944 -247.1801)
		(end 388.384796 -246.914162)
		(width 0.350012)
		(layer "F.Cu")
		(net "GND")
	)
	(segment
		(start 92.80779 -294.070278)
		(end 92.340938 -294.336216)
		(width 0.350012)
		(layer "F.Cu")
		(net "GND")
	)
	(segment
		(start 360.657902 -245.560088)
		(end 361.124754 -245.29415)
		(width 0.350012)
		(layer "F.Cu")
		(net "GND")
	)
	(segment
		(start 120.537986 -265.720322)
		(end 121.004838 -265.98626)
		(width 0.350012)
		(layer "F.Cu")
		(net "GND")
	)
	(segment
		(start 115.067842 -244.750336)
		(end 115.534694 -244.484398)
		(width 0.350012)
		(layer "F.Cu")
		(net "GND")
	)
	(segment
		(start 332.28788 -287.59023)
		(end 331.821028 -287.856168)
		(width 0.350012)
		(layer "F.Cu")
		(net "GND")
	)
	(segment
		(start 141.687804 -274.630388)
		(end 142.154656 -274.896326)
		(width 0.350012)
		(layer "F.Cu")
		(net "GND")
	)
	(segment
		(start 322.834254 -394.113004)
		(end 322.583556 -394.831062)
		(width 0.254)
		(layer "F.Cu")
		(net "GND")
	)
	(segment
		(start 171.97197 -240.68532)
		(end 173.35627 -240.68532)
		(width 0.4572)
		(layer "F.Cu")
		(net "GND")
	)
	(segment
		(start 368.947954 -277.870158)
		(end 369.414806 -278.136096)
		(width 0.350012)
		(layer "F.Cu")
		(net "GND")
	)
	(segment
		(start 361.455208 -412.334964)
		(end 361.625388 -412.334964)
		(width 0.381)
		(layer "F.Cu")
		(net "GND")
	)
	(segment
		(start 81.118964 -390.160002)
		(end 81.798414 -390.160002)
		(width 0.254)
		(layer "F.Cu")
		(net "GND")
	)
	(segment
		(start 193.55562 -423.204132)
		(end 193.55562 -423.820082)
		(width 0.381)
		(layer "F.Cu")
		(net "GND")
	)
	(segment
		(start 68.191888 -149.75459)
		(end 67.743578 -149.366732)
		(width 0.1778)
		(layer "F.Cu")
		(net "GND")
	)
	(segment
		(start 77.215746 -392.92276)
		(end 77.369924 -392.768582)
		(width 0.254)
		(layer "F.Cu")
		(net "GND")
	)
	(segment
		(start 106.437938 -277.060406)
		(end 105.971086 -277.326344)
		(width 0.350012)
		(layer "F.Cu")
		(net "GND")
	)
	(segment
		(start 336.987896 -263.29005)
		(end 336.521044 -263.555988)
		(width 0.350012)
		(layer "F.Cu")
		(net "GND")
	)
	(segment
		(start 116.477796 -226.120452)
		(end 116.944648 -225.854514)
		(width 0.350012)
		(layer "F.Cu")
		(net "GND")
	)
	(segment
		(start 95.944182 -391.37971)
		(end 95.84563 -391.281158)
		(width 0.254)
		(layer "F.Cu")
		(net "GND")
	)
	(segment
		(start 365.657892 -280.300176)
		(end 366.124744 -280.566114)
		(width 0.350012)
		(layer "F.Cu")
		(net "GND")
	)
	(segment
		(start 454.188068 -218.585034)
		(end 452.803768 -218.585034)
		(width 0.4572)
		(layer "F.Cu")
		(net "GND")
	)
	(segment
		(start 424.307 -434.786786)
		(end 423.672 -434.786786)
		(width 0.4318)
		(layer "F.Cu")
		(net "GND")
	)
	(segment
		(start 348.737936 -281.920188)
		(end 348.271084 -282.186126)
		(width 0.350012)
		(layer "F.Cu")
		(net "GND")
	)
	(segment
		(start 94.217998 -283.540454)
		(end 93.751146 -283.806392)
		(width 0.350012)
		(layer "F.Cu")
		(net "GND")
	)
	(segment
		(start 100.22205 -79.121)
		(end 100.22205 -79.71663)
		(width 0.381)
		(layer "F.Cu")
		(net "GND")
	)
	(segment
		(start 421.92194 -109.671358)
		(end 421.92194 -110.280958)
		(width 0.3556)
		(layer "F.Cu")
		(net "GND")
	)
	(segment
		(start 59.428126 -218.585288)
		(end 58.043826 -218.585288)
		(width 0.4572)
		(layer "F.Cu")
		(net "GND")
	)
	(segment
		(start 309.816246 -402.309838)
		(end 309.816246 -403.047454)
		(width 0.381)
		(layer "F.Cu")
		(net "GND")
	)
	(segment
		(start 25.746964 -11.26998)
		(end 25.746964 -10.16635)
		(width 0.3556)
		(layer "F.Cu")
		(net "GND")
	)
	(segment
		(start 416.545776 -399.663158)
		(end 416.84575 -399.143474)
		(width 0.254)
		(layer "F.Cu")
		(net "GND")
	)
	(segment
		(start 278.748998 -417.195)
		(end 279.12695 -417.195)
		(width 0.381)
		(layer "F.Cu")
		(net "GND")
	)
	(segment
		(start 446.644268 -293.384986)
		(end 445.259968 -293.384986)
		(width 0.4572)
		(layer "F.Cu")
		(net "GND")
	)
	(segment
		(start 115.83797 -273.820382)
		(end 116.304822 -274.08632)
		(width 0.350012)
		(layer "F.Cu")
		(net "GND")
	)
	(segment
		(start 83.877912 -262.480298)
		(end 83.41106 -262.746236)
		(width 0.350012)
		(layer "F.Cu")
		(net "GND")
	)
	(segment
		(start 176.072038 -302.735234)
		(end 174.687738 -302.735234)
		(width 0.4572)
		(layer "F.Cu")
		(net "GND")
	)
	(segment
		(start 332.622906 -142.973044)
		(end 332.172564 -143.005302)
		(width 0.1778)
		(layer "F.Cu")
		(net "GND")
	)
	(segment
		(start 63.670688 -386.6388)
		(end 62.978538 -386.449062)
		(width 0.254)
		(layer "F.Cu")
		(net "GND")
	)
	(segment
		(start 394.327888 -264.910062)
		(end 394.982954 -264.910062)
		(width 0.350012)
		(layer "F.Cu")
		(net "GND")
	)
	(segment
		(start 85.757766 -285.160466)
		(end 85.290914 -285.426404)
		(width 0.350012)
		(layer "F.Cu")
		(net "GND")
	)
	(segment
		(start 314.870338 -392.999722)
		(end 315.462158 -392.999722)
		(width 0.254)
		(layer "F.Cu")
		(net "GND")
	)
	(segment
		(start 58.518044 -383.622296)
		(end 58.818018 -383.92227)
		(width 0.254)
		(layer "F.Cu")
		(net "GND")
	)
	(segment
		(start 114.127788 -241.510312)
		(end 114.59464 -241.244374)
		(width 0.350012)
		(layer "F.Cu")
		(net "GND")
	)
	(segment
		(start 348.58452 -342.429338)
		(end 348.58452 -342.01354)
		(width 0.2286)
		(layer "F.Cu")
		(net "GND")
	)
	(segment
		(start 29.252164 -305.285394)
		(end 27.867864 -305.285394)
		(width 0.4572)
		(layer "F.Cu")
		(net "GND")
	)
	(segment
		(start 368.17808 -226.120198)
		(end 368.644932 -225.85426)
		(width 0.350012)
		(layer "F.Cu")
		(net "GND")
	)
	(segment
		(start 133.170676 -386.987034)
		(end 133.170676 -386.6388)
		(width 0.254)
		(layer "F.Cu")
		(net "GND")
	)
	(segment
		(start 349.378016 -240.700052)
		(end 348.911164 -240.434114)
		(width 0.350012)
		(layer "F.Cu")
		(net "GND")
	)
	(segment
		(start 385.570476 -392.999722)
		(end 386.162296 -392.999722)
		(width 0.254)
		(layer "F.Cu")
		(net "GND")
	)
	(segment
		(start 396.646908 -7.217156)
		(end 396.646908 -8.320024)
		(width 0.3556)
		(layer "F.Cu")
		(net "GND")
	)
	(segment
		(start 299.543724 -396.679674)
		(end 300.190662 -396.679674)
		(width 0.254)
		(layer "F.Cu")
		(net "GND")
	)
	(segment
		(start 156.945584 -382.951482)
		(end 157.044136 -382.85293)
		(width 0.254)
		(layer "F.Cu")
		(net "GND")
	)
	(segment
		(start 98.617786 -250.420378)
		(end 98.150934 -250.15444)
		(width 0.350012)
		(layer "F.Cu")
		(net "GND")
	)
	(segment
		(start 349.847916 -251.23013)
		(end 349.381064 -250.964192)
		(width 0.350012)
		(layer "F.Cu")
		(net "GND")
	)
	(segment
		(start 133.69798 -273.820382)
		(end 134.164832 -274.08632)
		(width 0.350012)
		(layer "F.Cu")
		(net "GND")
	)
	(segment
		(start 450.088 -221.985078)
		(end 451.4723 -221.985078)
		(width 0.4572)
		(layer "F.Cu")
		(net "GND")
	)
	(segment
		(start 374.16232 -392.999722)
		(end 373.5705 -392.999722)
		(width 0.254)
		(layer "F.Cu")
		(net "GND")
	)
	(segment
		(start 372.238016 -268.960092)
		(end 372.704868 -269.22603)
		(width 0.350012)
		(layer "F.Cu")
		(net "GND")
	)
	(segment
		(start 344.977974 -265.720068)
		(end 344.511122 -265.986006)
		(width 0.350012)
		(layer "F.Cu")
		(net "GND")
	)
	(segment
		(start 22.147022 -9.423654)
		(end 22.148292 -9.424924)
		(width 0.3556)
		(layer "F.Cu")
		(net "GND")
	)
	(segment
		(start 376.916442 -399.76171)
		(end 376.81789 -399.663158)
		(width 0.254)
		(layer "F.Cu")
		(net "GND")
	)
	(segment
		(start 95.327978 -249.610372)
		(end 94.861126 -249.344434)
		(width 0.350012)
		(layer "F.Cu")
		(net "GND")
	)
	(segment
		(start 398.012412 -411.064456)
		(end 398.012412 -411.959298)
		(width 0.381)
		(layer "F.Cu")
		(net "GND")
	)
	(segment
		(start 98.54565 -383.92227)
		(end 98.245676 -383.402586)
		(width 0.254)
		(layer "F.Cu")
		(net "GND")
	)
	(segment
		(start 307.368194 -239.835182)
		(end 305.983894 -239.835182)
		(width 0.4572)
		(layer "F.Cu")
		(net "GND")
	)
	(segment
		(start 105.66781 -243.130324)
		(end 105.200958 -242.864386)
		(width 0.350012)
		(layer "F.Cu")
		(net "GND")
	)
	(segment
		(start 109.427772 -249.610372)
		(end 108.961174 -249.344434)
		(width 0.350012)
		(layer "F.Cu")
		(net "GND")
	)
	(segment
		(start 359.115106 -167.418004)
		(end 358.862122 -167.670988)
		(width 0.2286)
		(layer "F.Cu")
		(net "GND")
	)
	(segment
		(start 302.123348 -430.2379)
		(end 302.123348 -429.606964)
		(width 0.381)
		(layer "F.Cu")
		(net "GND")
	)
	(segment
		(start 124.297948 -288.400236)
		(end 124.7648 -288.666174)
		(width 0.350012)
		(layer "F.Cu")
		(net "GND")
	)
	(segment
		(start 295.724072 -275.535136)
		(end 297.108372 -275.535136)
		(width 0.4572)
		(layer "F.Cu")
		(net "GND")
	)
	(segment
		(start 136.687814 -243.130324)
		(end 137.154666 -242.864386)
		(width 0.350012)
		(layer "F.Cu")
		(net "GND")
	)
	(segment
		(start 350.94545 -399.143474)
		(end 350.998028 -398.542002)
		(width 0.254)
		(layer "F.Cu")
		(net "GND")
	)
	(segment
		(start 315.214 -366.79505)
		(end 314.62345 -366.79505)
		(width 0.381)
		(layer "F.Cu")
		(net "GND")
	)
	(segment
		(start 280.64079 -351.973896)
		(end 280.387552 -352.227134)
		(width 0.381)
		(layer "F.Cu")
		(net "GND")
	)
	(segment
		(start 158.68904 -107.075986)
		(end 158.68904 -107.840526)
		(width 0.381)
		(layer "F.Cu")
		(net "GND")
	)
	(segment
		(start 83.877912 -291.64026)
		(end 83.41106 -291.906198)
		(width 0.350012)
		(layer "F.Cu")
		(net "GND")
	)
	(segment
		(start 378.347986 -279.49017)
		(end 378.814838 -279.756108)
		(width 0.350012)
		(layer "F.Cu")
		(net "GND")
	)
	(segment
		(start 362.368084 -269.770098)
		(end 362.834682 -270.036036)
		(width 0.350012)
		(layer "F.Cu")
		(net "GND")
	)
	(segment
		(start 93.79839 -384.617722)
		(end 93.745812 -383.92227)
		(width 0.254)
		(layer "F.Cu")
		(net "GND")
	)
	(segment
		(start 83.577938 -248.800366)
		(end 83.111086 -248.534428)
		(width 0.350012)
		(layer "F.Cu")
		(net "GND")
	)
	(segment
		(start 25.746964 -10.16635)
		(end 25.745694 -10.16508)
		(width 0.3556)
		(layer "F.Cu")
		(net "GND")
	)
	(segment
		(start 409.28036 -142.644114)
		(end 409.050744 -142.414498)
		(width 0.381)
		(layer "F.Cu")
		(net "GND")
	)
	(segment
		(start 119.597932 -277.060406)
		(end 120.064784 -277.326344)
		(width 0.350012)
		(layer "F.Cu")
		(net "GND")
	)
	(segment
		(start 48.070516 -390.160002)
		(end 48.017938 -390.761474)
		(width 0.254)
		(layer "F.Cu")
		(net "GND")
	)
	(segment
		(start 348.268036 -285.970218)
		(end 347.801184 -286.236156)
		(width 0.350012)
		(layer "F.Cu")
		(net "GND")
	)
	(segment
		(start 95.48368 -37.865558)
		(end 95.48368 -37.230558)
		(width 0.3556)
		(layer "F.Cu")
		(net "GND")
	)
	(segment
		(start 120.707912 -251.230384)
		(end 121.174764 -250.964446)
		(width 0.350012)
		(layer "F.Cu")
		(net "GND")
	)
	(segment
		(start 343.56802 -282.730194)
		(end 343.101168 -282.996132)
		(width 0.350012)
		(layer "F.Cu")
		(net "GND")
	)
	(segment
		(start 391.208006 -241.510058)
		(end 391.674858 -241.24412)
		(width 0.350012)
		(layer "F.Cu")
		(net "GND")
	)
	(segment
		(start 33.198054 -349.786448)
		(end 33.229042 -349.786448)
		(width 0.2286)
		(layer "F.Cu")
		(net "GND")
	)
	(segment
		(start 373.17807 -291.640006)
		(end 373.644922 -291.905944)
		(width 0.350012)
		(layer "F.Cu")
		(net "GND")
	)
	(segment
		(start 97.507806 -276.2504)
		(end 97.040954 -276.516338)
		(width 0.350012)
		(layer "F.Cu")
		(net "GND")
	)
	(segment
		(start 101.758242 -414.87217)
		(end 101.758242 -413.962088)
		(width 0.508)
		(layer "F.Cu")
		(net "GND")
	)
	(segment
		(start 356.207568 -163.26231)
		(end 356.222808 -163.27755)
		(width 0.381)
		(layer "F.Cu")
		(net "GND")
	)
	(segment
		(start 412.94558 -399.663158)
		(end 413.245808 -399.143474)
		(width 0.254)
		(layer "F.Cu")
		(net "GND")
	)
	(segment
		(start 335.747868 -223.69018)
		(end 335.281016 -223.424242)
		(width 0.350012)
		(layer "F.Cu")
		(net "GND")
	)
	(segment
		(start 362.368084 -279.49017)
		(end 362.834682 -279.756108)
		(width 0.350012)
		(layer "F.Cu")
		(net "GND")
	)
	(segment
		(start 128.370584 -388.138924)
		(end 127.818388 -388.328662)
		(width 0.254)
		(layer "F.Cu")
		(net "GND")
	)
	(segment
		(start 53.267102 -10.16635)
		(end 53.265832 -10.16508)
		(width 0.3556)
		(layer "F.Cu")
		(net "GND")
	)
	(segment
		(start 387.448044 -244.750082)
		(end 387.914896 -244.484144)
		(width 0.350012)
		(layer "F.Cu")
		(net "GND")
	)
	(segment
		(start 414.755584 -7.215886)
		(end 414.756854 -7.217156)
		(width 0.3556)
		(layer "F.Cu")
		(net "GND")
	)
	(segment
		(start 179.516024 -228.78542)
		(end 180.900324 -228.78542)
		(width 0.4572)
		(layer "F.Cu")
		(net "GND")
	)
	(segment
		(start 131.817872 -262.480298)
		(end 132.284724 -262.746236)
		(width 0.350012)
		(layer "F.Cu")
		(net "GND")
	)
	(segment
		(start 119.127778 -266.530328)
		(end 119.59463 -266.796266)
		(width 0.350012)
		(layer "F.Cu")
		(net "GND")
	)
	(segment
		(start 138.013948 -167.510206)
		(end 138.217148 -167.510206)
		(width 0.4572)
		(layer "F.Cu")
		(net "GND")
	)
	(segment
		(start 401.209764 -395.613128)
		(end 400.732752 -395.42974)
		(width 0.254)
		(layer "F.Cu")
		(net "GND")
	)
	(segment
		(start 17.812258 -428.589948)
		(end 17.812258 -427.980348)
		(width 0.3556)
		(layer "F.Cu")
		(net "GND")
	)
	(segment
		(start 345.1479 -236.650022)
		(end 344.681048 -236.384084)
		(width 0.350012)
		(layer "F.Cu")
		(net "GND")
	)
	(segment
		(start 382.748028 -252.850142)
		(end 383.21488 -252.584204)
		(width 0.350012)
		(layer "F.Cu")
		(net "GND")
	)
	(segment
		(start 149.54631 -388.328662)
		(end 148.898356 -388.138924)
		(width 0.254)
		(layer "F.Cu")
		(net "GND")
	)
	(segment
		(start 356.728014 -274.630134)
		(end 356.261162 -274.896072)
		(width 0.350012)
		(layer "F.Cu")
		(net "GND")
	)
	(segment
		(start 273.092164 -306.135024)
		(end 274.476464 -306.135024)
		(width 0.4572)
		(layer "F.Cu")
		(net "GND")
	)
	(segment
		(start 99.857814 -280.30043)
		(end 99.390962 -280.566368)
		(width 0.350012)
		(layer "F.Cu")
		(net "GND")
	)
	(segment
		(start 108.957872 -226.120452)
		(end 108.49102 -225.854514)
		(width 0.350012)
		(layer "F.Cu")
		(net "GND")
	)
	(segment
		(start 168.527984 -312.085228)
		(end 167.143684 -312.085228)
		(width 0.4572)
		(layer "F.Cu")
		(net "GND")
	)
	(segment
		(start 109.065314 -405.633682)
		(end 108.806234 -405.892762)
		(width 0.3048)
		(layer "F.Cu")
		(net "GND")
	)
	(segment
		(start 130.407918 -269.770352)
		(end 130.87477 -270.03629)
		(width 0.350012)
		(layer "F.Cu")
		(net "GND")
	)
	(segment
		(start 348.268036 -268.150086)
		(end 347.801184 -268.416024)
		(width 0.350012)
		(layer "F.Cu")
		(net "GND")
	)
	(segment
		(start 78.109826 -387.231128)
		(end 77.632814 -387.04774)
		(width 0.254)
		(layer "F.Cu")
		(net "GND")
	)
	(segment
		(start 117.570504 -386.6388)
		(end 116.878608 -386.449062)
		(width 0.254)
		(layer "F.Cu")
		(net "GND")
	)
	(segment
		(start 125.238002 -262.480298)
		(end 125.704854 -262.746236)
		(width 0.350012)
		(layer "F.Cu")
		(net "GND")
	)
	(segment
		(start 288.180018 -212.635084)
		(end 289.564318 -212.635084)
		(width 0.4572)
		(layer "F.Cu")
		(net "GND")
	)
	(segment
		(start 292.280086 -295.935146)
		(end 290.895786 -295.935146)
		(width 0.4572)
		(layer "F.Cu")
		(net "GND")
	)
	(segment
		(start 24.948642 -349.786448)
		(end 25.519126 -349.215964)
		(width 0.2286)
		(layer "F.Cu")
		(net "GND")
	)
	(segment
		(start 335.108042 -264.910062)
		(end 334.64119 -265.176)
		(width 0.350012)
		(layer "F.Cu")
		(net "GND")
	)
	(segment
		(start 128.370584 -386.6388)
		(end 127.678434 -386.449062)
		(width 0.254)
		(layer "F.Cu")
		(net "GND")
	)
	(segment
		(start 82.945732 -390.761474)
		(end 82.99831 -390.160002)
		(width 0.254)
		(layer "F.Cu")
		(net "GND")
	)
	(segment
		(start 376.467878 -264.910062)
		(end 376.93473 -265.176)
		(width 0.350012)
		(layer "F.Cu")
		(net "GND")
	)
	(segment
		(start 131.517898 -239.080294)
		(end 131.98475 -238.814356)
		(width 0.350012)
		(layer "F.Cu")
		(net "GND")
	)
	(segment
		(start 108.017818 -237.460282)
		(end 107.550966 -237.194344)
		(width 0.350012)
		(layer "F.Cu")
		(net "GND")
	)
	(segment
		(start 144.677892 -235.84027)
		(end 145.144744 -235.574332)
		(width 0.350012)
		(layer "F.Cu")
		(net "GND")
	)
	(segment
		(start 201.352658 -119.721376)
		(end 202.502008 -119.721376)
		(width 0.4572)
		(layer "F.Cu")
		(net "GND")
	)
	(segment
		(start 152.498298 -390.160002)
		(end 152.44572 -390.761474)
		(width 0.254)
		(layer "F.Cu")
		(net "GND")
	)
	(segment
		(start 424.031918 -360.824018)
		(end 424.757342 -360.824018)
		(width 0.3556)
		(layer "F.Cu")
		(net "GND")
	)
	(segment
		(start 331.987906 -230.169974)
		(end 331.521054 -229.904036)
		(width 0.350012)
		(layer "F.Cu")
		(net "GND")
	)
	(segment
		(start 387.917944 -230.97998)
		(end 388.384796 -230.714296)
		(width 0.350012)
		(layer "F.Cu")
		(net "GND")
	)
	(segment
		(start 341.687912 -276.250146)
		(end 341.22106 -276.516084)
		(width 0.350012)
		(layer "F.Cu")
		(net "GND")
	)
	(segment
		(start 292.999668 -403.721062)
		(end 291.916612 -403.721062)
		(width 0.381)
		(layer "F.Cu")
		(net "GND")
	)
	(segment
		(start 422.462198 -393.513056)
		(end 422.462198 -392.913108)
		(width 0.254)
		(layer "F.Cu")
		(net "GND")
	)
	(segment
		(start 133.227826 -273.010376)
		(end 133.694678 -273.276314)
		(width 0.350012)
		(layer "F.Cu")
		(net "GND")
	)
	(segment
		(start 331.81798 -283.5402)
		(end 331.351128 -283.806138)
		(width 0.350012)
		(layer "F.Cu")
		(net "GND")
	)
	(segment
		(start 446.644268 -312.084974)
		(end 445.259968 -312.084974)
		(width 0.4572)
		(layer "F.Cu")
		(net "GND")
	)
	(segment
		(start 115.537996 -242.320318)
		(end 116.004848 -242.05438)
		(width 0.350012)
		(layer "F.Cu")
		(net "GND")
	)
	(segment
		(start 380.86792 -239.890046)
		(end 381.334772 -239.624108)
		(width 0.350012)
		(layer "F.Cu")
		(net "GND")
	)
	(segment
		(start 353.607878 -226.930204)
		(end 353.141026 -226.664266)
		(width 0.350012)
		(layer "F.Cu")
		(net "GND")
	)
	(segment
		(start 365.187992 -268.150086)
		(end 365.654844 -268.416024)
		(width 0.350012)
		(layer "F.Cu")
		(net "GND")
	)
	(segment
		(start 258.344924 -53.523642)
		(end 256.835148 -53.523642)
		(width 0.254)
		(layer "F.Cu")
		(net "GND")
	)
	(segment
		(start 108.487972 -241.510312)
		(end 108.02112 -241.244374)
		(width 0.350012)
		(layer "F.Cu")
		(net "GND")
	)
	(segment
		(start 359.257854 -164.238432)
		(end 358.727502 -164.238432)
		(width 0.381)
		(layer "F.Cu")
		(net "GND")
	)
	(segment
		(start 157.29839 -388.138924)
		(end 156.746194 -388.328662)
		(width 0.254)
		(layer "F.Cu")
		(net "GND")
	)
	(segment
		(start 92.037916 -237.460282)
		(end 91.571064 -237.194344)
		(width 0.350012)
		(layer "F.Cu")
		(net "GND")
	)
	(segment
		(start 307.368194 -286.585152)
		(end 305.983894 -286.585152)
		(width 0.4572)
		(layer "F.Cu")
		(net "GND")
	)
	(segment
		(start 106.437938 -280.30043)
		(end 105.971086 -280.566368)
		(width 0.350012)
		(layer "F.Cu")
		(net "GND")
	)
	(segment
		(start 380.86792 -252.850142)
		(end 381.334772 -252.584204)
		(width 0.350012)
		(layer "F.Cu")
		(net "GND")
	)
	(segment
		(start 375.970546 -392.999722)
		(end 376.562366 -392.999722)
		(width 0.254)
		(layer "F.Cu")
		(net "GND")
	)
	(segment
		(start 122.117866 -255.280414)
		(end 122.584718 -255.014476)
		(width 0.350012)
		(layer "F.Cu")
		(net "GND")
	)
	(segment
		(start 56.417972 -390.761474)
		(end 56.47055 -390.160002)
		(width 0.254)
		(layer "F.Cu")
		(net "GND")
	)
	(segment
		(start 105.19791 -229.360476)
		(end 104.731058 -229.094538)
		(width 0.350012)
		(layer "F.Cu")
		(net "GND")
	)
	(segment
		(start 320.340228 -45.859954)
		(end 320.949828 -45.859954)
		(width 0.3556)
		(layer "F.Cu")
		(net "GND")
	)
	(segment
		(start 18.232628 -39.926514)
		(end 18.231866 -39.927276)
		(width 0.4572)
		(layer "F.Cu")
		(net "GND")
	)
	(segment
		(start 328.998072 -262.480044)
		(end 328.53122 -262.745982)
		(width 0.350012)
		(layer "F.Cu")
		(net "GND")
	)
	(segment
		(start 364.717838 -280.300176)
		(end 365.18469 -280.566114)
		(width 0.350012)
		(layer "F.Cu")
		(net "GND")
	)
	(segment
		(start 36.449 -366.37595)
		(end 36.443412 -365.76)
		(width 0.381)
		(layer "F.Cu")
		(net "GND")
	)
	(segment
		(start 386.50799 -222.070168)
		(end 386.974842 -221.80423)
		(width 0.350012)
		(layer "F.Cu")
		(net "GND")
	)
	(segment
		(start 431.3682 -12.37488)
		(end 431.3682 -12.374118)
		(width 0.3556)
		(layer "F.Cu")
		(net "GND")
	)
	(segment
		(start 101.437948 -222.880428)
		(end 100.971096 -222.61449)
		(width 0.350012)
		(layer "F.Cu")
		(net "GND")
	)
	(segment
		(start 97.97796 -281.920442)
		(end 97.511108 -282.18638)
		(width 0.350012)
		(layer "F.Cu")
		(net "GND")
	)
	(segment
		(start 131.716526 -391.830814)
		(end 131.716526 -391.37971)
		(width 0.254)
		(layer "F.Cu")
		(net "GND")
	)
	(segment
		(start 348.268036 -263.29005)
		(end 347.801184 -263.555988)
		(width 0.350012)
		(layer "F.Cu")
		(net "GND")
	)
	(segment
		(start 85.457792 -242.320318)
		(end 84.99094 -242.05438)
		(width 0.350012)
		(layer "F.Cu")
		(net "GND")
	)
	(segment
		(start 403.846792 -7.217156)
		(end 403.846792 -8.320024)
		(width 0.3556)
		(layer "F.Cu")
		(net "GND")
	)
	(segment
		(start 411.40634 -394.831062)
		(end 410.89834 -395.0208)
		(width 0.254)
		(layer "F.Cu")
		(net "GND")
	)
	(segment
		(start 412.098236 -398.542002)
		(end 412.045658 -399.143474)
		(width 0.254)
		(layer "F.Cu")
		(net "GND")
	)
	(segment
		(start 141.687804 -271.390364)
		(end 142.154656 -271.656302)
		(width 0.350012)
		(layer "F.Cu")
		(net "GND")
	)
	(segment
		(start 100.797868 -267.340334)
		(end 100.331016 -267.606272)
		(width 0.350012)
		(layer "F.Cu")
		(net "GND")
	)
	(segment
		(start 165.60165 -437.423052)
		(end 166.912798 -437.423052)
		(width 0.381)
		(layer "F.Cu")
		(net "GND")
	)
	(segment
		(start 77.767942 -285.970472)
		(end 77.112876 -285.970472)
		(width 0.350012)
		(layer "F.Cu")
		(net "GND")
	)
	(segment
		(start 95.627952 -287.590484)
		(end 95.1611 -287.856422)
		(width 0.350012)
		(layer "F.Cu")
		(net "GND")
	)
	(segment
		(start 168.821862 -438.840372)
		(end 168.186862 -438.840372)
		(width 0.4318)
		(layer "F.Cu")
		(net "GND")
	)
	(segment
		(start 331.987906 -256.090166)
		(end 331.521054 -255.824228)
		(width 0.350012)
		(layer "F.Cu")
		(net "GND")
	)
	(segment
		(start 178.289458 -45.299884)
		(end 177.108358 -45.299884)
		(width 0.254)
		(layer "F.Cu")
		(net "GND")
	)
	(segment
		(start 135.107934 -263.290304)
		(end 135.574786 -263.556242)
		(width 0.350012)
		(layer "F.Cu")
		(net "GND")
	)
	(segment
		(start 363.307884 -285.970218)
		(end 363.774736 -286.236156)
		(width 0.350012)
		(layer "F.Cu")
		(net "GND")
	)
	(segment
		(start 317.016384 -399.76171)
		(end 317.016384 -400.212814)
		(width 0.254)
		(layer "F.Cu")
		(net "GND")
	)
	(segment
		(start 120.707912 -226.930458)
		(end 121.174764 -226.66452)
		(width 0.350012)
		(layer "F.Cu")
		(net "GND")
	)
	(segment
		(start 405.745696 -392.004296)
		(end 406.04567 -392.30427)
		(width 0.254)
		(layer "F.Cu")
		(net "GND")
	)
	(segment
		(start 104.265222 -33.718754)
		(end 104.635808 -33.718754)
		(width 0.254)
		(layer "F.Cu")
		(net "GND")
	)
	(segment
		(start 132.927852 -246.370348)
		(end 133.394704 -246.10441)
		(width 0.350012)
		(layer "F.Cu")
		(net "GND")
	)
	(segment
		(start 82.167984 -244.750336)
		(end 81.701132 -244.484398)
		(width 0.350012)
		(layer "F.Cu")
		(net "GND")
	)
	(segment
		(start 369.417854 -280.300176)
		(end 369.884706 -280.566114)
		(width 0.350012)
		(layer "F.Cu")
		(net "GND")
	)
	(segment
		(start 334.808068 -226.930204)
		(end 334.341216 -226.664266)
		(width 0.350012)
		(layer "F.Cu")
		(net "GND")
	)
	(segment
		(start 104.257856 -235.84027)
		(end 103.791004 -235.574332)
		(width 0.350012)
		(layer "F.Cu")
		(net "GND")
	)
	(segment
		(start 99.55784 -248.800366)
		(end 99.090988 -248.534428)
		(width 0.350012)
		(layer "F.Cu")
		(net "GND")
	)
	(segment
		(start 331.987906 -236.650022)
		(end 331.521054 -236.384084)
		(width 0.350012)
		(layer "F.Cu")
		(net "GND")
	)
	(segment
		(start 446.729612 -422.114726)
		(end 447.399664 -422.114726)
		(width 0.1778)
		(layer "F.Cu")
		(net "GND")
	)
	(segment
		(start 67.237356 -337.58505)
		(end 67.327526 -337.367372)
		(width 0.2286)
		(layer "F.Cu")
		(net "GND")
	)
	(segment
		(start 347.975174 -344.35161)
		(end 347.975174 -344.604594)
		(width 0.381)
		(layer "F.Cu")
		(net "GND")
	)
	(segment
		(start 378.347986 -266.530074)
		(end 378.814838 -266.796012)
		(width 0.350012)
		(layer "F.Cu")
		(net "GND")
	)
	(segment
		(start 157.292802 -351.247456)
		(end 157.292802 -350.256856)
		(width 0.381)
		(layer "F.Cu")
		(net "GND")
	)
	(segment
		(start 128.878584 -386.449062)
		(end 128.370584 -386.6388)
		(width 0.254)
		(layer "F.Cu")
		(net "GND")
	)
	(segment
		(start 327.117964 -268.960092)
		(end 326.651112 -269.22603)
		(width 0.350012)
		(layer "F.Cu")
		(net "GND")
	)
	(segment
		(start 342.245442 -391.784586)
		(end 342.245442 -392.004296)
		(width 0.254)
		(layer "F.Cu")
		(net "GND")
	)
	(segment
		(start 346.557854 -240.700052)
		(end 346.091002 -240.434114)
		(width 0.350012)
		(layer "F.Cu")
		(net "GND")
	)
	(segment
		(start 414.14573 -391.784586)
		(end 414.14573 -392.004296)
		(width 0.254)
		(layer "F.Cu")
		(net "GND")
	)
	(segment
		(start 358.137968 -291.640006)
		(end 357.671116 -291.905944)
		(width 0.350012)
		(layer "F.Cu")
		(net "GND")
	)
	(segment
		(start 176.072038 -202.435206)
		(end 174.687738 -202.435206)
		(width 0.4572)
		(layer "F.Cu")
		(net "GND")
	)
	(segment
		(start 343.56802 -281.110182)
		(end 343.101168 -281.37612)
		(width 0.350012)
		(layer "F.Cu")
		(net "GND")
	)
	(segment
		(start 424.012106 -302.73498)
		(end 422.627806 -302.73498)
		(width 0.4572)
		(layer "F.Cu")
		(net "GND")
	)
	(segment
		(start 104.257856 -250.420378)
		(end 103.791004 -250.15444)
		(width 0.350012)
		(layer "F.Cu")
		(net "GND")
	)
	(segment
		(start 146.38782 -276.2504)
		(end 147.042886 -276.2504)
		(width 0.350012)
		(layer "F.Cu")
		(net "GND")
	)
	(segment
		(start 29.252164 -312.085228)
		(end 27.867864 -312.085228)
		(width 0.4572)
		(layer "F.Cu")
		(net "GND")
	)
	(segment
		(start 320.817748 -392.30427)
		(end 320.870326 -392.999722)
		(width 0.254)
		(layer "F.Cu")
		(net "GND")
	)
	(segment
		(start 51.468274 -12.37488)
		(end 51.468274 -12.374118)
		(width 0.3556)
		(layer "F.Cu")
		(net "GND")
	)
	(segment
		(start 130.107944 -243.130324)
		(end 130.574796 -242.864386)
		(width 0.350012)
		(layer "F.Cu")
		(net "GND")
	)
	(segment
		(start 253.042928 -107.362244)
		(end 253.042928 -107.80776)
		(width 0.4572)
		(layer "F.Cu")
		(net "GND")
	)
	(segment
		(start 308.191154 -398.542002)
		(end 307.670454 -398.542002)
		(width 0.254)
		(layer "F.Cu")
		(net "GND")
	)
	(segment
		(start 303.268126 -284.88513)
		(end 304.652426 -284.88513)
		(width 0.4572)
		(layer "F.Cu")
		(net "GND")
	)
	(segment
		(start 133.69798 -280.30043)
		(end 134.164832 -280.566368)
		(width 0.350012)
		(layer "F.Cu")
		(net "GND")
	)
	(segment
		(start 126.31166 -30.832806)
		(end 125.0442 -30.832806)
		(width 0.3556)
		(layer "F.Cu")
		(net "GND")
	)
	(segment
		(start 145.729452 -388.13105)
		(end 145.420842 -388.36473)
		(width 0.254)
		(layer "F.Cu")
		(net "GND")
	)
	(segment
		(start 392.61796 -242.320064)
		(end 393.084812 -242.054126)
		(width 0.350012)
		(layer "F.Cu")
		(net "GND")
	)
	(segment
		(start 131.970526 -384.617722)
		(end 131.36245 -384.617722)
		(width 0.254)
		(layer "F.Cu")
		(net "GND")
	)
	(segment
		(start 443.853316 -30.837378)
		(end 443.851792 -30.838902)
		(width 0.254)
		(layer "F.Cu")
		(net "GND")
	)
	(segment
		(start 80.598264 -390.160002)
		(end 80.545686 -390.761474)
		(width 0.254)
		(layer "F.Cu")
		(net "GND")
	)
	(segment
		(start 129.63779 -248.800366)
		(end 130.104642 -248.534428)
		(width 0.350012)
		(layer "F.Cu")
		(net "GND")
	)
	(segment
		(start 104.257856 -252.04039)
		(end 103.791004 -251.774452)
		(width 0.350012)
		(layer "F.Cu")
		(net "GND")
	)
	(segment
		(start 427.766988 -10.16635)
		(end 427.765718 -10.16508)
		(width 0.3556)
		(layer "F.Cu")
		(net "GND")
	)
	(segment
		(start 42.055796 -7.215124)
		(end 42.055796 -7.215886)
		(width 0.3556)
		(layer "F.Cu")
		(net "GND")
	)
	(segment
		(start 52.518056 -391.281158)
		(end 52.81803 -390.761474)
		(width 0.254)
		(layer "F.Cu")
		(net "GND")
	)
	(segment
		(start 105.967784 -279.490424)
		(end 105.500932 -279.756362)
		(width 0.350012)
		(layer "F.Cu")
		(net "GND")
	)
	(segment
		(start 380.86792 -246.370094)
		(end 381.334772 -246.104156)
		(width 0.350012)
		(layer "F.Cu")
		(net "GND")
	)
	(segment
		(start 129.57048 -390.160002)
		(end 128.891284 -390.160002)
		(width 0.254)
		(layer "F.Cu")
		(net "GND")
	)
	(segment
		(start 335.022444 -399.686272)
		(end 335.045558 -399.663158)
		(width 0.254)
		(layer "F.Cu")
		(net "GND")
	)
	(segment
		(start 80.757776 -243.94033)
		(end 80.291178 -243.674392)
		(width 0.350012)
		(layer "F.Cu")
		(net "GND")
	)
	(segment
		(start 330.408026 -273.010122)
		(end 329.941174 -273.27606)
		(width 0.350012)
		(layer "F.Cu")
		(net "GND")
	)
	(segment
		(start 146.06905 -117.348)
		(end 146.06905 -118.364)
		(width 0.381)
		(layer "F.Cu")
		(net "GND")
	)
	(segment
		(start 75.617832 -337.553046)
		(end 75.112626 -338.058252)
		(width 0.2286)
		(layer "F.Cu")
		(net "GND")
	)
	(segment
		(start 142.797784 -250.420378)
		(end 143.264636 -250.15444)
		(width 0.350012)
		(layer "F.Cu")
		(net "GND")
	)
	(segment
		(start 338.868004 -284.350206)
		(end 338.401152 -284.616144)
		(width 0.350012)
		(layer "F.Cu")
		(net "GND")
	)
	(segment
		(start 72.45604 -60.254896)
		(end 72.45604 -59.436)
		(width 0.381)
		(layer "F.Cu")
		(net "GND")
	)
	(segment
		(start 351.25787 -226.120198)
		(end 350.791018 -225.85426)
		(width 0.350012)
		(layer "F.Cu")
		(net "GND")
	)
	(segment
		(start 125.707902 -279.490424)
		(end 126.174754 -279.756362)
		(width 0.350012)
		(layer "F.Cu")
		(net "GND")
	)
	(segment
		(start 126.817882 -382.951482)
		(end 126.916434 -382.85293)
		(width 0.254)
		(layer "F.Cu")
		(net "GND")
	)
	(segment
		(start 160.780984 -120.40108)
		(end 160.780984 -121.490486)
		(width 0.4572)
		(layer "F.Cu")
		(net "GND")
	)
	(segment
		(start 328.998072 -278.680164)
		(end 328.53122 -278.946102)
		(width 0.350012)
		(layer "F.Cu")
		(net "GND")
	)
	(segment
		(start 420.49827 -392.999722)
		(end 420.445692 -392.30427)
		(width 0.254)
		(layer "F.Cu")
		(net "GND")
	)
	(segment
		(start 33.363662 -430.799748)
		(end 33.363662 -430.190148)
		(width 0.3556)
		(layer "F.Cu")
		(net "GND")
	)
	(segment
		(start 110.711488 -224.373948)
		(end 110.83798 -224.50044)
		(width 0.350012)
		(layer "F.Cu")
		(net "GND")
	)
	(segment
		(start 133.398006 -256.900426)
		(end 133.864858 -256.634488)
		(width 0.350012)
		(layer "F.Cu")
		(net "GND")
	)
	(segment
		(start 79.177896 -267.340334)
		(end 78.711044 -267.606272)
		(width 0.350012)
		(layer "F.Cu")
		(net "GND")
	)
	(segment
		(start 388.217918 -275.44014)
		(end 388.68477 -275.706078)
		(width 0.350012)
		(layer "F.Cu")
		(net "GND")
	)
	(segment
		(start 79.177896 -290.020248)
		(end 78.711044 -290.286186)
		(width 0.350012)
		(layer "F.Cu")
		(net "GND")
	)
	(segment
		(start 123.52782 -239.8903)
		(end 123.994672 -239.624362)
		(width 0.350012)
		(layer "F.Cu")
		(net "GND")
	)
	(segment
		(start 134.16788 -268.15034)
		(end 134.634732 -268.416278)
		(width 0.350012)
		(layer "F.Cu")
		(net "GND")
	)
	(segment
		(start 387.917944 -250.420124)
		(end 388.384796 -250.154186)
		(width 0.350012)
		(layer "F.Cu")
		(net "GND")
	)
	(segment
		(start 307.062124 -392.999722)
		(end 306.470304 -392.999722)
		(width 0.254)
		(layer "F.Cu")
		(net "GND")
	)
	(segment
		(start 375.057924 -268.960092)
		(end 375.524776 -269.22603)
		(width 0.350012)
		(layer "F.Cu")
		(net "GND")
	)
	(segment
		(start 370.357908 -264.100056)
		(end 370.82476 -264.365994)
		(width 0.350012)
		(layer "F.Cu")
		(net "GND")
	)
	(segment
		(start 359.365042 -164.34562)
		(end 359.257854 -164.238432)
		(width 0.381)
		(layer "F.Cu")
		(net "GND")
	)
	(segment
		(start 322.53428 -396.813024)
		(end 322.31457 -396.813024)
		(width 0.254)
		(layer "F.Cu")
		(net "GND")
	)
	(segment
		(start 198.7042 -293.38524)
		(end 197.3199 -293.38524)
		(width 0.4572)
		(layer "F.Cu")
		(net "GND")
	)
	(segment
		(start 132.916422 -383.304034)
		(end 132.916422 -382.85293)
		(width 0.254)
		(layer "F.Cu")
		(net "GND")
	)
	(segment
		(start 323.018404 -338.053426)
		(end 323.049392 -338.053426)
		(width 0.2286)
		(layer "F.Cu")
		(net "GND")
	)
	(segment
		(start 370.527834 -256.090166)
		(end 370.994686 -255.824228)
		(width 0.350012)
		(layer "F.Cu")
		(net "GND")
	)
	(segment
		(start 209.423 -129.94005)
		(end 209.423 -130.683)
		(width 0.381)
		(layer "F.Cu")
		(net "GND")
	)
	(segment
		(start 349.544132 -400.212814)
		(end 349.544132 -399.76171)
		(width 0.254)
		(layer "F.Cu")
		(net "GND")
	)
	(segment
		(start 428.120302 -436.564786)
		(end 427.680628 -436.564786)
		(width 0.381)
		(layer "F.Cu")
		(net "GND")
	)
	(segment
		(start 370.357908 -270.580104)
		(end 370.82476 -270.846042)
		(width 0.350012)
		(layer "F.Cu")
		(net "GND")
	)
	(segment
		(start 121.117868 -390.761474)
		(end 121.170446 -390.160002)
		(width 0.254)
		(layer "F.Cu")
		(net "GND")
	)
	(segment
		(start 120.817894 -383.402586)
		(end 120.817894 -383.622296)
		(width 0.254)
		(layer "F.Cu")
		(net "GND")
	)
	(segment
		(start 128.52781 -266.530328)
		(end 128.994662 -266.796266)
		(width 0.350012)
		(layer "F.Cu")
		(net "GND")
	)
	(segment
		(start 168.527984 -314.635388)
		(end 167.143684 -314.635388)
		(width 0.4572)
		(layer "F.Cu")
		(net "GND")
	)
	(segment
		(start 358.778048 -247.1801)
		(end 358.311196 -246.914162)
		(width 0.350012)
		(layer "F.Cu")
		(net "GND")
	)
	(segment
		(start 190.104014 -54.04104)
		(end 189.410848 -54.04104)
		(width 0.381)
		(layer "F.Cu")
		(net "GND")
	)
	(segment
		(start 376.467878 -292.450012)
		(end 376.93473 -292.71595)
		(width 0.350012)
		(layer "F.Cu")
		(net "GND")
	)
	(segment
		(start 173.764194 -391.34288)
		(end 173.651926 -391.34288)
		(width 0.254)
		(layer "F.Cu")
		(net "GND")
	)
	(segment
		(start 383.048002 -277.870158)
		(end 383.514854 -278.136096)
		(width 0.350012)
		(layer "F.Cu")
		(net "GND")
	)
	(segment
		(start 53.816504 -391.830814)
		(end 53.816504 -391.37971)
		(width 0.254)
		(layer "F.Cu")
		(net "GND")
	)
	(segment
		(start 121.007886 -276.2504)
		(end 121.474738 -276.516338)
		(width 0.350012)
		(layer "F.Cu")
		(net "GND")
	)
	(segment
		(start 351.37979 -158.074106)
		(end 350.875346 -158.57855)
		(width 0.2286)
		(layer "F.Cu")
		(net "GND")
	)
	(segment
		(start 454.188068 -286.585152)
		(end 452.803768 -286.585152)
		(width 0.4572)
		(layer "F.Cu")
		(net "GND")
	)
	(segment
		(start 104.55783 -294.880284)
		(end 104.090978 -295.146222)
		(width 0.350012)
		(layer "F.Cu")
		(net "GND")
	)
	(segment
		(start 66.314828 -387.831076)
		(end 66.534538 -387.831076)
		(width 0.254)
		(layer "F.Cu")
		(net "GND")
	)
	(segment
		(start 315.717682 -391.333482)
		(end 315.816234 -391.23493)
		(width 0.254)
		(layer "F.Cu")
		(net "GND")
	)
	(segment
		(start 81.69783 -250.420378)
		(end 81.230978 -250.15444)
		(width 0.350012)
		(layer "F.Cu")
		(net "GND")
	)
	(segment
		(start 331.518006 -243.940076)
		(end 331.051154 -243.674138)
		(width 0.350012)
		(layer "F.Cu")
		(net "GND")
	)
	(segment
		(start 321.816222 -391.686034)
		(end 321.816222 -391.23493)
		(width 0.254)
		(layer "F.Cu")
		(net "GND")
	)
	(segment
		(start 255.312926 -68.296536)
		(end 255.947926 -68.296536)
		(width 0.4572)
		(layer "F.Cu")
		(net "GND")
	)
	(segment
		(start 371.297962 -273.820128)
		(end 371.764814 -274.086066)
		(width 0.350012)
		(layer "F.Cu")
		(net "GND")
	)
	(segment
		(start 85.457792 -226.120452)
		(end 84.99094 -225.854514)
		(width 0.350012)
		(layer "F.Cu")
		(net "GND")
	)
	(segment
		(start 8.324596 -133.01853)
		(end 8.324596 -133.55193)
		(width 0.3556)
		(layer "F.Cu")
		(net "GND")
	)
	(segment
		(start 90.627962 -222.070422)
		(end 90.627962 -221.504764)
		(width 0.350012)
		(layer "F.Cu")
		(net "GND")
	)
	(segment
		(start 372.877842 -243.940076)
		(end 373.344694 -243.674138)
		(width 0.350012)
		(layer "F.Cu")
		(net "GND")
	)
	(segment
		(start 353.907852 -271.39011)
		(end 353.441 -271.656048)
		(width 0.350012)
		(layer "F.Cu")
		(net "GND")
	)
	(segment
		(start 221.199456 -104.130856)
		(end 221.199456 -104.12222)
		(width 0.381)
		(layer "F.Cu")
		(net "GND")
	)
	(segment
		(start 386.50799 -249.610118)
		(end 386.974842 -249.34418)
		(width 0.350012)
		(layer "F.Cu")
		(net "GND")
	)
	(segment
		(start 122.41784 -285.160466)
		(end 122.884692 -285.426404)
		(width 0.350012)
		(layer "F.Cu")
		(net "GND")
	)
	(segment
		(start 126.794514 -163.367466)
		(end 126.366016 -163.367466)
		(width 0.2286)
		(layer "F.Cu")
		(net "GND")
	)
	(segment
		(start 105.19791 -235.84027)
		(end 104.731058 -235.574332)
		(width 0.350012)
		(layer "F.Cu")
		(net "GND")
	)
	(segment
		(start 132.457952 -250.420378)
		(end 132.924804 -250.15444)
		(width 0.350012)
		(layer "F.Cu")
		(net "GND")
	)
	(segment
		(start 347.497908 -232.599992)
		(end 347.031056 -232.334054)
		(width 0.350012)
		(layer "F.Cu")
		(net "GND")
	)
	(segment
		(start 392.61796 -237.460028)
		(end 393.084812 -237.19409)
		(width 0.350012)
		(layer "F.Cu")
		(net "GND")
	)
	(segment
		(start 413.946086 -396.710662)
		(end 414.498282 -396.520924)
		(width 0.254)
		(layer "F.Cu")
		(net "GND")
	)
	(segment
		(start 133.117844 -383.92227)
		(end 132.81787 -383.402586)
		(width 0.254)
		(layer "F.Cu")
		(net "GND")
	)
	(segment
		(start 187.060078 -294.235378)
		(end 188.444378 -294.235378)
		(width 0.4572)
		(layer "F.Cu")
		(net "GND")
	)
	(segment
		(start 58.26252 -384.617722)
		(end 58.870596 -384.617722)
		(width 0.254)
		(layer "F.Cu")
		(net "GND")
	)
	(segment
		(start 361.42803 -287.59023)
		(end 361.894882 -287.856168)
		(width 0.350012)
		(layer "F.Cu")
		(net "GND")
	)
	(segment
		(start 424.307 -438.634886)
		(end 423.672 -438.634886)
		(width 0.4318)
		(layer "F.Cu")
		(net "GND")
	)
	(segment
		(start 162.098228 -388.138924)
		(end 161.546286 -388.328662)
		(width 0.254)
		(layer "F.Cu")
		(net "GND")
	)
	(segment
		(start 82.167984 -243.130324)
		(end 81.701132 -242.864386)
		(width 0.350012)
		(layer "F.Cu")
		(net "GND")
	)
	(segment
		(start 127.64897 -162.127184)
		(end 127.617982 -162.127184)
		(width 0.2286)
		(layer "F.Cu")
		(net "GND")
	)
	(segment
		(start 403.5552 -77.913484)
		(end 402.917914 -77.913484)
		(width 0.4572)
		(layer "F.Cu")
		(net "GND")
	)
	(segment
		(start 107.078018 -243.94033)
		(end 106.611166 -243.674392)
		(width 0.350012)
		(layer "F.Cu")
		(net "GND")
	)
	(segment
		(start 371.767862 -290.83)
		(end 372.234714 -291.095938)
		(width 0.350012)
		(layer "F.Cu")
		(net "GND")
	)
	(segment
		(start 398.012412 -411.959298)
		(end 398.26565 -412.212536)
		(width 0.381)
		(layer "F.Cu")
		(net "GND")
	)
	(segment
		(start 384.457956 -264.100056)
		(end 384.924808 -264.365994)
		(width 0.350012)
		(layer "F.Cu")
		(net "GND")
	)
	(segment
		(start 328.697844 -230.97998)
		(end 328.231246 -230.714296)
		(width 0.350012)
		(layer "F.Cu")
		(net "GND")
	)
	(segment
		(start 350.618044 -270.580104)
		(end 350.151192 -270.846042)
		(width 0.350012)
		(layer "F.Cu")
		(net "GND")
	)
	(segment
		(start 106.137964 -247.180354)
		(end 105.671112 -246.914416)
		(width 0.350012)
		(layer "F.Cu")
		(net "GND")
	)
	(segment
		(start 108.09097 -23.371556)
		(end 108.09097 -24.154638)
		(width 0.381)
		(layer "F.Cu")
		(net "GND")
	)
	(segment
		(start 95.327978 -256.09042)
		(end 94.861126 -255.824482)
		(width 0.350012)
		(layer "F.Cu")
		(net "GND")
	)
	(segment
		(start 171.97197 -200.735438)
		(end 173.35627 -200.735438)
		(width 0.4572)
		(layer "F.Cu")
		(net "GND")
	)
	(segment
		(start 364.717838 -265.720068)
		(end 365.18469 -265.986006)
		(width 0.350012)
		(layer "F.Cu")
		(net "GND")
	)
	(segment
		(start 367.538254 -172.513752)
		(end 367.007902 -172.513752)
		(width 0.381)
		(layer "F.Cu")
		(net "GND")
	)
	(segment
		(start 51.670712 -388.138924)
		(end 52.318412 -388.328662)
		(width 0.254)
		(layer "F.Cu")
		(net "GND")
	)
	(segment
		(start 336.218022 -224.500186)
		(end 335.75117 -224.234248)
		(width 0.350012)
		(layer "F.Cu")
		(net "GND")
	)
	(segment
		(start 44.340018 -305.285394)
		(end 42.955718 -305.285394)
		(width 0.4572)
		(layer "F.Cu")
		(net "GND")
	)
	(segment
		(start 62.117986 -391.281158)
		(end 62.41796 -390.761474)
		(width 0.254)
		(layer "F.Cu")
		(net "GND")
	)
	(segment
		(start 423.327576 -356.32644)
		(end 423.397426 -356.25659)
		(width 0.3556)
		(layer "F.Cu")
		(net "GND")
	)
	(segment
		(start 98.54565 -390.761474)
		(end 98.598482 -390.160002)
		(width 0.254)
		(layer "F.Cu")
		(net "GND")
	)
	(segment
		(start 403.444202 -399.76171)
		(end 403.444202 -400.212814)
		(width 0.254)
		(layer "F.Cu")
		(net "GND")
	)
	(segment
		(start 379.75794 -283.5402)
		(end 380.224792 -283.806138)
		(width 0.350012)
		(layer "F.Cu")
		(net "GND")
	)
	(segment
		(start 383.217928 -224.500186)
		(end 383.68478 -224.234248)
		(width 0.350012)
		(layer "F.Cu")
		(net "GND")
	)
	(segment
		(start 47.784004 -231.335326)
		(end 49.168304 -231.335326)
		(width 0.4572)
		(layer "F.Cu")
		(net "GND")
	)
	(segment
		(start 171.97197 -287.43529)
		(end 173.35627 -287.43529)
		(width 0.4572)
		(layer "F.Cu")
		(net "GND")
	)
	(segment
		(start 407.446988 -8.320024)
		(end 407.446988 -9.423654)
		(width 0.3556)
		(layer "F.Cu")
		(net "GND")
	)
	(segment
		(start 89.047828 -282.730448)
		(end 88.580976 -282.996386)
		(width 0.350012)
		(layer "F.Cu")
		(net "GND")
	)
	(segment
		(start 36.837112 -368.855498)
		(end 36.837112 -369.49507)
		(width 0.381)
		(layer "F.Cu")
		(net "GND")
	)
	(segment
		(start 319.416176 -399.76171)
		(end 319.317624 -399.663158)
		(width 0.254)
		(layer "F.Cu")
		(net "GND")
	)
	(segment
		(start 336.987896 -294.070024)
		(end 336.521044 -294.335962)
		(width 0.350012)
		(layer "F.Cu")
		(net "GND")
	)
	(segment
		(start 454.188068 -302.73498)
		(end 452.803768 -302.73498)
		(width 0.4572)
		(layer "F.Cu")
		(net "GND")
	)
	(segment
		(start 447.419476 -422.263062)
		(end 447.167762 -422.514776)
		(width 0.1778)
		(layer "F.Cu")
		(net "GND")
	)
	(segment
		(start 133.398006 -245.560342)
		(end 133.864858 -245.294404)
		(width 0.350012)
		(layer "F.Cu")
		(net "GND")
	)
	(segment
		(start 31.147004 -8.320024)
		(end 31.147004 -9.423654)
		(width 0.3556)
		(layer "F.Cu")
		(net "GND")
	)
	(segment
		(start 146.474688 -58.392822)
		(end 146.855688 -58.773822)
		(width 0.1778)
		(layer "F.Cu")
		(net "GND")
	)
	(segment
		(start 395.794738 -395.4399)
		(end 395.794738 -395.8209)
		(width 0.254)
		(layer "F.Cu")
		(net "GND")
	)
	(segment
		(start 368.478054 -288.399982)
		(end 368.944906 -288.66592)
		(width 0.350012)
		(layer "F.Cu")
		(net "GND")
	)
	(segment
		(start 421.345614 -391.784586)
		(end 421.444166 -391.686034)
		(width 0.254)
		(layer "F.Cu")
		(net "GND")
	)
	(segment
		(start 356.728014 -284.350206)
		(end 356.261162 -284.616144)
		(width 0.350012)
		(layer "F.Cu")
		(net "GND")
	)
	(segment
		(start 375.617994 -391.333482)
		(end 375.716546 -391.23493)
		(width 0.2032)
		(layer "F.Cu")
		(net "GND")
	)
	(segment
		(start 328.227944 -222.070168)
		(end 327.761092 -221.80423)
		(width 0.350012)
		(layer "F.Cu")
		(net "GND")
	)
	(segment
		(start 347.497908 -227.74021)
		(end 347.031056 -227.474272)
		(width 0.350012)
		(layer "F.Cu")
		(net "GND")
	)
	(segment
		(start 389.327898 -243.13007)
		(end 389.79475 -242.864132)
		(width 0.350012)
		(layer "F.Cu")
		(net "GND")
	)
	(segment
		(start 408.498294 -398.542002)
		(end 408.445716 -399.143474)
		(width 0.254)
		(layer "F.Cu")
		(net "GND")
	)
	(segment
		(start 335.277968 -229.360222)
		(end 334.811116 -229.094284)
		(width 0.350012)
		(layer "F.Cu")
		(net "GND")
	)
	(segment
		(start 377.762262 -392.999722)
		(end 377.170442 -392.999722)
		(width 0.254)
		(layer "F.Cu")
		(net "GND")
	)
	(segment
		(start 119.37365 -438.793382)
		(end 119.37365 -438.101232)
		(width 0.381)
		(layer "F.Cu")
		(net "GND")
	)
	(segment
		(start 352.497898 -267.34008)
		(end 352.031046 -267.606018)
		(width 0.350012)
		(layer "F.Cu")
		(net "GND")
	)
	(segment
		(start 376.81789 -391.333482)
		(end 376.916442 -391.23493)
		(width 0.254)
		(layer "F.Cu")
		(net "GND")
	)
	(segment
		(start 109.427772 -233.410252)
		(end 108.961174 -233.144314)
		(width 0.350012)
		(layer "F.Cu")
		(net "GND")
	)
	(segment
		(start 55.328058 -219.435426)
		(end 56.712358 -219.435426)
		(width 0.4572)
		(layer "F.Cu")
		(net "GND")
	)
	(segment
		(start 389.327898 -228.550216)
		(end 389.79475 -228.284278)
		(width 0.350012)
		(layer "F.Cu")
		(net "GND")
	)
	(segment
		(start 91.398344 -390.160002)
		(end 91.919044 -390.160002)
		(width 0.254)
		(layer "F.Cu")
		(net "GND")
	)
	(segment
		(start 457.85151 -41.755822)
		(end 457.21016 -41.755822)
		(width 0.4572)
		(layer "F.Cu")
		(net "GND")
	)
	(segment
		(start 69.977 -59.45505)
		(end 70.993 -59.45505)
		(width 0.381)
		(layer "F.Cu")
		(net "GND")
	)
	(segment
		(start 123.323604 -30.815026)
		(end 125.02642 -30.815026)
		(width 0.3556)
		(layer "F.Cu")
		(net "GND")
	)
	(segment
		(start 56.865774 -7.215886)
		(end 56.867044 -7.217156)
		(width 0.3556)
		(layer "F.Cu")
		(net "GND")
	)
	(segment
		(start 347.797882 -277.060152)
		(end 347.33103 -277.32609)
		(width 0.350012)
		(layer "F.Cu")
		(net "GND")
	)
	(segment
		(start 443.13348 -433.89931)
		(end 442.49848 -433.89931)
		(width 0.4318)
		(layer "F.Cu")
		(net "GND")
	)
	(segment
		(start 370.057934 -256.900172)
		(end 370.524786 -256.634234)
		(width 0.350012)
		(layer "F.Cu")
		(net "GND")
	)
	(segment
		(start 332.28788 -282.730194)
		(end 331.821028 -282.996132)
		(width 0.350012)
		(layer "F.Cu")
		(net "GND")
	)
	(segment
		(start 335.148682 -396.712948)
		(end 334.82915 -396.712948)
		(width 0.254)
		(layer "F.Cu")
		(net "GND")
	)
	(segment
		(start 81.058004 -286.780478)
		(end 80.591152 -287.046162)
		(width 0.350012)
		(layer "F.Cu")
		(net "GND")
	)
	(segment
		(start 22.147022 -8.320024)
		(end 22.147022 -9.423654)
		(width 0.3556)
		(layer "F.Cu")
		(net "GND")
	)
	(segment
		(start 47.784004 -312.935366)
		(end 49.168304 -312.935366)
		(width 0.4572)
		(layer "F.Cu")
		(net "GND")
	)
	(segment
		(start 345.943936 -399.76171)
		(end 345.845384 -399.663158)
		(width 0.254)
		(layer "F.Cu")
		(net "GND")
	)
	(segment
		(start 105.66781 -231.79024)
		(end 105.200958 -231.524302)
		(width 0.350012)
		(layer "F.Cu")
		(net "GND")
	)
	(segment
		(start 374.11787 -265.720068)
		(end 374.584722 -265.986006)
		(width 0.350012)
		(layer "F.Cu")
		(net "GND")
	)
	(segment
		(start 22.299676 -388.771384)
		(end 21.938996 -388.771384)
		(width 0.2286)
		(layer "F.Cu")
		(net "GND")
	)
	(segment
		(start 442.5442 -210.085178)
		(end 443.9285 -210.085178)
		(width 0.4572)
		(layer "F.Cu")
		(net "GND")
	)
	(segment
		(start 165.729158 -384.005836)
		(end 165.645592 -383.92227)
		(width 0.254)
		(layer "F.Cu")
		(net "GND")
	)
	(segment
		(start 371.767862 -269.770098)
		(end 372.234714 -270.036036)
		(width 0.350012)
		(layer "F.Cu")
		(net "GND")
	)
	(segment
		(start 168.180766 -436.132224)
		(end 168.10863 -436.20436)
		(width 0.381)
		(layer "F.Cu")
		(net "GND")
	)
	(segment
		(start 108.317792 -286.780478)
		(end 107.851448 -287.045908)
		(width 0.350012)
		(layer "F.Cu")
		(net "GND")
	)
	(segment
		(start 295.724072 -221.985078)
		(end 297.108372 -221.985078)
		(width 0.4572)
		(layer "F.Cu")
		(net "GND")
	)
	(segment
		(start 79.14894 -388.330948)
		(end 78.829408 -388.330948)
		(width 0.254)
		(layer "F.Cu")
		(net "GND")
	)
	(segment
		(start 123.05792 -237.460282)
		(end 123.524772 -237.194344)
		(width 0.350012)
		(layer "F.Cu")
		(net "GND")
	)
	(segment
		(start 381.638048 -267.34008)
		(end 382.1049 -267.606018)
		(width 0.350012)
		(layer "F.Cu")
		(net "GND")
	)
	(segment
		(start 49.270666 -390.160002)
		(end 49.791366 -390.160002)
		(width 0.254)
		(layer "F.Cu")
		(net "GND")
	)
	(segment
		(start 353.437952 -268.960092)
		(end 352.9711 -269.22603)
		(width 0.350012)
		(layer "F.Cu")
		(net "GND")
	)
	(segment
		(start 17.16405 -73.66)
		(end 17.16405 -73.025)
		(width 0.381)
		(layer "F.Cu")
		(net "GND")
	)
	(segment
		(start 380.86792 -226.930204)
		(end 381.334772 -226.664266)
		(width 0.350012)
		(layer "F.Cu")
		(net "GND")
	)
	(segment
		(start 146.087846 -249.610372)
		(end 146.742912 -249.610372)
		(width 0.350012)
		(layer "F.Cu")
		(net "GND")
	)
	(segment
		(start 130.107944 -228.55047)
		(end 130.574796 -228.284532)
		(width 0.350012)
		(layer "F.Cu")
		(net "GND")
	)
	(segment
		(start 292.280086 -293.384986)
		(end 290.895786 -293.384986)
		(width 0.4572)
		(layer "F.Cu")
		(net "GND")
	)
	(segment
		(start 82.467958 -276.2504)
		(end 82.001106 -276.516338)
		(width 0.350012)
		(layer "F.Cu")
		(net "GND")
	)
	(segment
		(start 75.165712 -403.830536)
		(end 75.165712 -403.581362)
		(width 0.381)
		(layer "F.Cu")
		(net "GND")
	)
	(segment
		(start 320.870326 -396.520924)
		(end 320.318384 -396.710662)
		(width 0.254)
		(layer "F.Cu")
		(net "GND")
	)
	(segment
		(start 44.340018 -312.085228)
		(end 42.955718 -312.085228)
		(width 0.4572)
		(layer "F.Cu")
		(net "GND")
	)
	(segment
		(start 93.91777 -224.50044)
		(end 93.450918 -224.234502)
		(width 0.350012)
		(layer "F.Cu")
		(net "GND")
	)
	(segment
		(start 450.088 -294.235124)
		(end 451.4723 -294.235124)
		(width 0.4572)
		(layer "F.Cu")
		(net "GND")
	)
	(segment
		(start 120.707912 -231.79024)
		(end 121.174764 -231.524302)
		(width 0.350012)
		(layer "F.Cu")
		(net "GND")
	)
	(segment
		(start 354.078032 -252.040136)
		(end 353.61118 -251.774198)
		(width 0.350012)
		(layer "F.Cu")
		(net "GND")
	)
	(segment
		(start 67.743578 -149.366732)
		(end 67.716654 -148.990812)
		(width 0.1778)
		(layer "F.Cu")
		(net "GND")
	)
	(segment
		(start 374.28805 -254.470154)
		(end 374.754902 -254.204216)
		(width 0.350012)
		(layer "F.Cu")
		(net "GND")
	)
	(segment
		(start 84.347812 -266.530328)
		(end 83.88096 -266.796266)
		(width 0.350012)
		(layer "F.Cu")
		(net "GND")
	)
	(segment
		(start 318.226186 -360.66095)
		(end 318.277748 -360.66095)
		(width 0.381)
		(layer "F.Cu")
		(net "GND")
	)
	(segment
		(start 113.61801 -383.402586)
		(end 113.61801 -383.622296)
		(width 0.254)
		(layer "F.Cu")
		(net "GND")
	)
	(segment
		(start 46.16704 -433.657502)
		(end 45.959014 -433.657502)
		(width 0.381)
		(layer "F.Cu")
		(net "GND")
	)
	(segment
		(start 135.118094 -151.27351)
		(end 135.648446 -151.27351)
		(width 0.381)
		(layer "F.Cu")
		(net "GND")
	)
	(segment
		(start 374.588024 -274.630134)
		(end 375.054876 -274.896072)
		(width 0.350012)
		(layer "F.Cu")
		(net "GND")
	)
	(segment
		(start 80.757776 -224.50044)
		(end 80.291178 -224.234502)
		(width 0.350012)
		(layer "F.Cu")
		(net "GND")
	)
	(segment
		(start 355.31806 -280.300176)
		(end 354.851208 -280.566114)
		(width 0.350012)
		(layer "F.Cu")
		(net "GND")
	)
	(segment
		(start 52.262532 -384.617722)
		(end 52.870608 -384.617722)
		(width 0.254)
		(layer "F.Cu")
		(net "GND")
	)
	(segment
		(start 312.499248 -23.12924)
		(end 312.499248 -22.51329)
		(width 0.4572)
		(layer "F.Cu")
		(net "GND")
	)
	(segment
		(start 14.257782 -416.451034)
		(end 14.257782 -416.569652)
		(width 0.381)
		(layer "F.Cu")
		(net "GND")
	)
	(segment
		(start 331.81798 -280.300176)
		(end 331.351128 -280.566114)
		(width 0.350012)
		(layer "F.Cu")
		(net "GND")
	)
	(segment
		(start 169.81805 -134.493)
		(end 170.561 -134.493)
		(width 0.381)
		(layer "F.Cu")
		(net "GND")
	)
	(segment
		(start 373.291608 -426.567854)
		(end 372.516146 -426.567854)
		(width 0.3556)
		(layer "F.Cu")
		(net "GND")
	)
	(segment
		(start 239.13592 -292.988238)
		(end 239.13592 -293.42207)
		(width 0.4572)
		(layer "F.Cu")
		(net "GND")
	)
	(segment
		(start 125.877828 -255.280414)
		(end 126.34468 -255.014476)
		(width 0.350012)
		(layer "F.Cu")
		(net "GND")
	)
	(segment
		(start 25.745694 -7.215886)
		(end 25.746964 -7.217156)
		(width 0.3556)
		(layer "F.Cu")
		(net "GND")
	)
	(segment
		(start 79.045816 -382.958086)
		(end 78.996286 -382.908556)
		(width 0.254)
		(layer "F.Cu")
		(net "GND")
	)
	(segment
		(start 127.170434 -388.138924)
		(end 126.618492 -388.328662)
		(width 0.254)
		(layer "F.Cu")
		(net "GND")
	)
	(segment
		(start 314.870338 -398.542002)
		(end 314.81776 -399.143474)
		(width 0.254)
		(layer "F.Cu")
		(net "GND")
	)
	(segment
		(start 163.946332 -388.328662)
		(end 163.298378 -388.138924)
		(width 0.254)
		(layer "F.Cu")
		(net "GND")
	)
	(segment
		(start 88.747854 -244.750336)
		(end 88.281002 -244.484398)
		(width 0.350012)
		(layer "F.Cu")
		(net "GND")
	)
	(segment
		(start 129.63779 -224.50044)
		(end 130.104642 -224.234502)
		(width 0.350012)
		(layer "F.Cu")
		(net "GND")
	)
	(segment
		(start 50.254662 -403.425406)
		(end 50.659792 -403.830536)
		(width 0.381)
		(layer "F.Cu")
		(net "GND")
	)
	(segment
		(start 313.670442 -396.520924)
		(end 313.118246 -396.710662)
		(width 0.254)
		(layer "F.Cu")
		(net "GND")
	)
	(segment
		(start 425.96689 -7.217156)
		(end 425.96689 -8.320024)
		(width 0.3556)
		(layer "F.Cu")
		(net "GND")
	)
	(segment
		(start 133.8453 -390.160002)
		(end 133.170676 -390.160002)
		(width 0.254)
		(layer "F.Cu")
		(net "GND")
	)
	(segment
		(start 412.367984 -315.485018)
		(end 413.752284 -315.485018)
		(width 0.4572)
		(layer "F.Cu")
		(net "GND")
	)
	(segment
		(start 353.607878 -246.370094)
		(end 353.141026 -246.104156)
		(width 0.350012)
		(layer "F.Cu")
		(net "GND")
	)
	(segment
		(start 202.254104 -341.055198)
		(end 203.36002 -341.055198)
		(width 0.1778)
		(layer "F.Cu")
		(net "GND")
	)
	(segment
		(start 269.648178 -209.23504)
		(end 268.263878 -209.23504)
		(width 0.4572)
		(layer "F.Cu")
		(net "GND")
	)
	(segment
		(start 334.331564 -144.055592)
		(end 334.331564 -143.386556)
		(width 0.381)
		(layer "F.Cu")
		(net "GND")
	)
	(segment
		(start 411.870144 -141.982952)
		(end 411.45714 -141.982952)
		(width 0.1778)
		(layer "F.Cu")
		(net "GND")
	)
	(segment
		(start 153.249884 -322.731892)
		(end 153.249884 -321.715892)
		(width 0.4064)
		(layer "F.Cu")
		(net "GND")
	)
	(segment
		(start 288.180018 -228.785166)
		(end 289.564318 -228.785166)
		(width 0.4572)
		(layer "F.Cu")
		(net "GND")
	)
	(segment
		(start 381.716534 -399.76171)
		(end 381.716534 -400.212814)
		(width 0.254)
		(layer "F.Cu")
		(net "GND")
	)
	(segment
		(start 381.167894 -269.770098)
		(end 381.634746 -270.036036)
		(width 0.350012)
		(layer "F.Cu")
		(net "GND")
	)
	(segment
		(start 368.478054 -265.720068)
		(end 368.944906 -265.986006)
		(width 0.350012)
		(layer "F.Cu")
		(net "GND")
	)
	(segment
		(start 304.97526 -351.050352)
		(end 304.97526 -351.681288)
		(width 0.381)
		(layer "F.Cu")
		(net "GND")
	)
	(segment
		(start 358.778048 -235.840016)
		(end 358.311196 -235.574078)
		(width 0.350012)
		(layer "F.Cu")
		(net "GND")
	)
	(segment
		(start 357.668068 -281.110182)
		(end 357.201216 -281.37612)
		(width 0.350012)
		(layer "F.Cu")
		(net "GND")
	)
	(segment
		(start 167.320722 -350.248474)
		(end 167.329358 -350.239838)
		(width 0.381)
		(layer "F.Cu")
		(net "GND")
	)
	(segment
		(start 80.344264 -391.37971)
		(end 80.344264 -391.830814)
		(width 0.254)
		(layer "F.Cu")
		(net "GND")
	)
	(segment
		(start 336.687922 -247.990106)
		(end 336.22107 -247.724168)
		(width 0.350012)
		(layer "F.Cu")
		(net "GND")
	)
	(segment
		(start 94.998286 -386.6388)
		(end 94.30639 -386.449062)
		(width 0.254)
		(layer "F.Cu")
		(net "GND")
	)
	(segment
		(start 209.422492 -36.880038)
		(end 209.422746 -36.880292)
		(width 0.254)
		(layer "F.Cu")
		(net "GND")
	)
	(segment
		(start 363.478064 -234.220004)
		(end 363.944916 -233.954066)
		(width 0.350012)
		(layer "F.Cu")
		(net "GND")
	)
	(segment
		(start 271.328134 -421.63873)
		(end 271.328134 -422.345612)
		(width 0.381)
		(layer "F.Cu")
		(net "GND")
	)
	(segment
		(start 132.927852 -236.650276)
		(end 133.394704 -236.384338)
		(width 0.350012)
		(layer "F.Cu")
		(net "GND")
	)
	(segment
		(start 67.716654 -148.025612)
		(end 67.716654 -148.990812)
		(width 0.254)
		(layer "F.Cu")
		(net "GND")
	)
	(segment
		(start 176.978056 -427.597062)
		(end 177.292762 -427.911768)
		(width 0.381)
		(layer "F.Cu")
		(net "GND")
	)
	(segment
		(start 281.008582 -351.973896)
		(end 280.64079 -351.973896)
		(width 0.381)
		(layer "F.Cu")
		(net "GND")
	)
	(segment
		(start 139.80795 -263.290304)
		(end 140.274802 -263.556242)
		(width 0.350012)
		(layer "F.Cu")
		(net "GND")
	)
	(segment
		(start 104.55783 -273.820382)
		(end 104.090978 -274.08632)
		(width 0.350012)
		(layer "F.Cu")
		(net "GND")
	)
	(segment
		(start 109.728 -294.070278)
		(end 109.261148 -294.336216)
		(width 0.350012)
		(layer "F.Cu")
		(net "GND")
	)
	(segment
		(start 372.407942 -223.69018)
		(end 372.874794 -223.424242)
		(width 0.350012)
		(layer "F.Cu")
		(net "GND")
	)
	(segment
		(start 19.508724 -404.68931)
		(end 19.508724 -405.468328)
		(width 0.381)
		(layer "F.Cu")
		(net "GND")
	)
	(segment
		(start 131.517898 -242.320318)
		(end 131.98475 -242.05438)
		(width 0.350012)
		(layer "F.Cu")
		(net "GND")
	)
	(segment
		(start 58.662316 -349.346774)
		(end 58.793126 -349.031306)
		(width 0.2286)
		(layer "F.Cu")
		(net "GND")
	)
	(segment
		(start 105.19791 -245.560342)
		(end 104.731058 -245.294404)
		(width 0.350012)
		(layer "F.Cu")
		(net "GND")
	)
	(segment
		(start 420.562532 -353.42449)
		(end 420.562532 -353.192842)
		(width 0.2286)
		(layer "F.Cu")
		(net "GND")
	)
	(segment
		(start 146.49831 -383.974848)
		(end 146.49831 -384.617722)
		(width 0.254)
		(layer "F.Cu")
		(net "GND")
	)
	(segment
		(start 381.970534 -395.0208)
		(end 381.278384 -394.831062)
		(width 0.254)
		(layer "F.Cu")
		(net "GND")
	)
	(segment
		(start 123.52782 -233.410252)
		(end 123.994672 -233.144314)
		(width 0.350012)
		(layer "F.Cu")
		(net "GND")
	)
	(segment
		(start 425.79163 -389.535416)
		(end 425.232068 -389.535416)
		(width 0.254)
		(layer "F.Cu")
		(net "GND")
	)
	(segment
		(start 424.325796 -362.79963)
		(end 424.01871 -362.79963)
		(width 0.3556)
		(layer "F.Cu")
		(net "GND")
	)
	(segment
		(start 424.166792 -8.320024)
		(end 424.166792 -9.423654)
		(width 0.3556)
		(layer "F.Cu")
		(net "GND")
	)
	(segment
		(start 284.736032 -209.23504)
		(end 283.351732 -209.23504)
		(width 0.4572)
		(layer "F.Cu")
		(net "GND")
	)
	(segment
		(start 409.44419 -399.76171)
		(end 409.345638 -399.663158)
		(width 0.254)
		(layer "F.Cu")
		(net "GND")
	)
	(segment
		(start 418.355526 -7.215124)
		(end 418.355526 -7.215886)
		(width 0.3556)
		(layer "F.Cu")
		(net "GND")
	)
	(segment
		(start 77.467968 -226.930458)
		(end 77.001116 -226.66452)
		(width 0.350012)
		(layer "F.Cu")
		(net "GND")
	)
	(segment
		(start 386.41782 -391.333482)
		(end 386.516372 -391.23493)
		(width 0.254)
		(layer "F.Cu")
		(net "GND")
	)
	(segment
		(start 132.287772 -294.070278)
		(end 132.754878 -294.336216)
		(width 0.350012)
		(layer "F.Cu")
		(net "GND")
	)
	(segment
		(start 46.16704 -439.153554)
		(end 46.16704 -439.763154)
		(width 0.381)
		(layer "F.Cu")
		(net "GND")
	)
	(segment
		(start 122.117866 -232.600246)
		(end 122.584718 -232.334308)
		(width 0.350012)
		(layer "F.Cu")
		(net "GND")
	)
	(segment
		(start 334.637888 -293.260018)
		(end 334.171036 -293.525956)
		(width 0.350012)
		(layer "F.Cu")
		(net "GND")
	)
	(segment
		(start 384.457956 -260.860032)
		(end 384.924808 -261.12597)
		(width 0.350012)
		(layer "F.Cu")
		(net "GND")
	)
	(segment
		(start 307.368194 -314.635134)
		(end 305.983894 -314.635134)
		(width 0.4572)
		(layer "F.Cu")
		(net "GND")
	)
	(segment
		(start 113.017808 -277.060406)
		(end 113.48466 -277.326344)
		(width 0.350012)
		(layer "F.Cu")
		(net "GND")
	)
	(segment
		(start 252.20041 -73.814178)
		(end 252.20041 -71.218806)
		(width 0.3556)
		(layer "F.Cu")
		(net "GND")
	)
	(segment
		(start 356.42804 -241.510058)
		(end 355.961188 -241.24412)
		(width 0.350012)
		(layer "F.Cu")
		(net "GND")
	)
	(segment
		(start 335.045558 -392.004296)
		(end 335.345532 -392.30427)
		(width 0.254)
		(layer "F.Cu")
		(net "GND")
	)
	(segment
		(start 328.694542 -395.4399)
		(end 328.694542 -395.8209)
		(width 0.254)
		(layer "F.Cu")
		(net "GND")
	)
	(segment
		(start 335.148682 -394.412978)
		(end 335.148682 -395.012926)
		(width 0.254)
		(layer "F.Cu")
		(net "GND")
	)
	(segment
		(start 450.317616 -401.93087)
		(end 450.317616 -402.59127)
		(width 0.381)
		(layer "F.Cu")
		(net "GND")
	)
	(segment
		(start 136.217914 -235.84027)
		(end 136.684766 -235.574332)
		(width 0.350012)
		(layer "F.Cu")
		(net "GND")
	)
	(segment
		(start 329.17384 -412.025338)
		(end 329.361038 -412.212536)
		(width 0.381)
		(layer "F.Cu")
		(net "GND")
	)
	(segment
		(start 406.04567 -399.143474)
		(end 406.098248 -398.542002)
		(width 0.254)
		(layer "F.Cu")
		(net "GND")
	)
	(segment
		(start 391.03808 -288.399982)
		(end 391.504678 -288.66592)
		(width 0.350012)
		(layer "F.Cu")
		(net "GND")
	)
	(segment
		(start 164.427916 -306.135278)
		(end 165.812216 -306.135278)
		(width 0.4572)
		(layer "F.Cu")
		(net "GND")
	)
	(segment
		(start 89.047828 -279.490424)
		(end 88.580976 -279.756362)
		(width 0.350012)
		(layer "F.Cu")
		(net "GND")
	)
	(segment
		(start 126.347982 -249.610372)
		(end 126.814834 -249.344434)
		(width 0.350012)
		(layer "F.Cu")
		(net "GND")
	)
	(segment
		(start 162.945572 -382.951482)
		(end 163.044124 -382.85293)
		(width 0.254)
		(layer "F.Cu")
		(net "GND")
	)
	(segment
		(start 91.045792 -383.402586)
		(end 91.045792 -382.951482)
		(width 0.254)
		(layer "F.Cu")
		(net "GND")
	)
	(segment
		(start 308.63286 -403.15896)
		(end 308.61635 -403.14245)
		(width 0.381)
		(layer "F.Cu")
		(net "GND")
	)
	(segment
		(start 332.28788 -277.870158)
		(end 331.821028 -278.136096)
		(width 0.350012)
		(layer "F.Cu")
		(net "GND")
	)
	(segment
		(start 97.507806 -290.830254)
		(end 97.040954 -291.096192)
		(width 0.350012)
		(layer "F.Cu")
		(net "GND")
	)
	(segment
		(start 67.812412 -40.437562)
		(end 67.202558 -40.437562)
		(width 0.4572)
		(layer "F.Cu")
		(net "GND")
	)
	(segment
		(start 41.8211 -389.0264)
		(end 41.8211 -388.4549)
		(width 0.254)
		(layer "F.Cu")
		(net "GND")
	)
	(segment
		(start 329.167998 -249.610118)
		(end 328.701146 -249.34418)
		(width 0.350012)
		(layer "F.Cu")
		(net "GND")
	)
	(segment
		(start 30.315662 -430.769014)
		(end 30.315662 -430.159414)
		(width 0.3556)
		(layer "F.Cu")
		(net "GND")
	)
	(segment
		(start 366.297972 -242.320064)
		(end 366.764824 -242.054126)
		(width 0.350012)
		(layer "F.Cu")
		(net "GND")
	)
	(segment
		(start 148.898356 -388.138924)
		(end 148.34616 -388.328662)
		(width 0.254)
		(layer "F.Cu")
		(net "GND")
	)
	(segment
		(start 347.906086 -394.831062)
		(end 347.398086 -395.0208)
		(width 0.254)
		(layer "F.Cu")
		(net "GND")
	)
	(segment
		(start 340.747858 -268.150086)
		(end 340.281006 -268.416024)
		(width 0.350012)
		(layer "F.Cu")
		(net "GND")
	)
	(segment
		(start 408.407108 -140.884656)
		(end 408.05989 -140.537438)
		(width 0.3556)
		(layer "F.Cu")
		(net "GND")
	)
	(segment
		(start 414.736788 -56.347868)
		(end 413.917638 -56.347868)
		(width 0.4572)
		(layer "F.Cu")
		(net "GND")
	)
	(segment
		(start 450.508878 -399.740628)
		(end 450.705982 -399.740628)
		(width 0.2032)
		(layer "F.Cu")
		(net "GND")
	)
	(segment
		(start 429.142144 -352.965258)
		(end 428.88916 -353.218242)
		(width 0.2286)
		(layer "F.Cu")
		(net "GND")
	)
	(segment
		(start 381.620522 -34.178748)
		(end 380.711456 -34.178748)
		(width 0.4572)
		(layer "F.Cu")
		(net "GND")
	)
	(segment
		(start 346.858082 -265.720068)
		(end 346.39123 -265.986006)
		(width 0.350012)
		(layer "F.Cu")
		(net "GND")
	)
	(segment
		(start 94.744286 -391.830814)
		(end 94.744286 -391.37971)
		(width 0.254)
		(layer "F.Cu")
		(net "GND")
	)
	(segment
		(start 416.556952 -10.16635)
		(end 416.555682 -10.16508)
		(width 0.3556)
		(layer "F.Cu")
		(net "GND")
	)
	(segment
		(start 284.736032 -314.635134)
		(end 283.351732 -314.635134)
		(width 0.4572)
		(layer "F.Cu")
		(net "GND")
	)
	(segment
		(start 367.067846 -266.530074)
		(end 367.534698 -266.796012)
		(width 0.350012)
		(layer "F.Cu")
		(net "GND")
	)
	(segment
		(start 353.907852 -289.209988)
		(end 353.441 -289.475926)
		(width 0.350012)
		(layer "F.Cu")
		(net "GND")
	)
	(segment
		(start 53.378608 -386.449062)
		(end 52.870608 -386.6388)
		(width 0.254)
		(layer "F.Cu")
		(net "GND")
	)
	(segment
		(start 90.457782 -264.10031)
		(end 89.99093 -264.366248)
		(width 0.350012)
		(layer "F.Cu")
		(net "GND")
	)
	(segment
		(start 354.34397 -400.212814)
		(end 354.34397 -399.76171)
		(width 0.254)
		(layer "F.Cu")
		(net "GND")
	)
	(segment
		(start 48.070516 -384.617722)
		(end 48.017938 -383.92227)
		(width 0.254)
		(layer "F.Cu")
		(net "GND")
	)
	(segment
		(start 113.61801 -383.402586)
		(end 113.61801 -382.957578)
		(width 0.254)
		(layer "F.Cu")
		(net "GND")
	)
	(segment
		(start 454.188068 -239.835182)
		(end 452.803768 -239.835182)
		(width 0.4572)
		(layer "F.Cu")
		(net "GND")
	)
	(segment
		(start 387.448044 -238.270034)
		(end 387.914896 -238.004096)
		(width 0.350012)
		(layer "F.Cu")
		(net "GND")
	)
	(segment
		(start 424.166792 -12.372848)
		(end 424.166792 -11.26998)
		(width 0.3556)
		(layer "F.Cu")
		(net "GND")
	)
	(segment
		(start 47.784004 -294.235378)
		(end 49.168304 -294.235378)
		(width 0.4572)
		(layer "F.Cu")
		(net "GND")
	)
	(segment
		(start 375.057924 -275.44014)
		(end 375.524776 -275.706078)
		(width 0.350012)
		(layer "F.Cu")
		(net "GND")
	)
	(segment
		(start 90.198448 -390.160002)
		(end 90.719148 -390.160002)
		(width 0.254)
		(layer "F.Cu")
		(net "GND")
	)
	(segment
		(start 306.117752 -391.784586)
		(end 306.117752 -391.333482)
		(width 0.254)
		(layer "F.Cu")
		(net "GND")
	)
	(segment
		(start 115.367816 -290.830254)
		(end 115.834668 -291.096192)
		(width 0.350012)
		(layer "F.Cu")
		(net "GND")
	)
	(segment
		(start 37.338 -366.37595)
		(end 37.332412 -365.76)
		(width 0.381)
		(layer "F.Cu")
		(net "GND")
	)
	(segment
		(start 409.345638 -391.333482)
		(end 409.44419 -391.23493)
		(width 0.254)
		(layer "F.Cu")
		(net "GND")
	)
	(segment
		(start 446.644268 -302.73498)
		(end 445.259968 -302.73498)
		(width 0.4572)
		(layer "F.Cu")
		(net "GND")
	)
	(segment
		(start 283.464 -423.81805)
		(end 283.464 -424.441366)
		(width 0.381)
		(layer "F.Cu")
		(net "GND")
	)
	(segment
		(start 80.757776 -255.280414)
		(end 80.291178 -255.014476)
		(width 0.350012)
		(layer "F.Cu")
		(net "GND")
	)
	(segment
		(start 428.813722 -423.221658)
		(end 428.813722 -422.605708)
		(width 0.381)
		(layer "F.Cu")
		(net "GND")
	)
	(segment
		(start 124.297948 -270.580358)
		(end 124.7648 -270.846296)
		(width 0.350012)
		(layer "F.Cu")
		(net "GND")
	)
	(segment
		(start 380.417832 -391.784586)
		(end 380.417832 -391.333482)
		(width 0.254)
		(layer "F.Cu")
		(net "GND")
	)
	(segment
		(start 120.707912 -254.470408)
		(end 121.174764 -254.20447)
		(width 0.350012)
		(layer "F.Cu")
		(net "GND")
	)
	(segment
		(start 325.70801 -289.209988)
		(end 325.052944 -289.209988)
		(width 0.350012)
		(layer "F.Cu")
		(net "GND")
	)
	(segment
		(start 204.814932 -115.657376)
		(end 203.899008 -115.657376)
		(width 0.508)
		(layer "F.Cu")
		(net "GND")
	)
	(segment
		(start 216.943432 -23.172928)
		(end 217.062812 -23.292308)
		(width 0.3556)
		(layer "F.Cu")
		(net "GND")
	)
	(segment
		(start 345.1479 -231.789986)
		(end 344.681048 -231.524048)
		(width 0.350012)
		(layer "F.Cu")
		(net "GND")
	)
	(segment
		(start 140.447776 -225.310446)
		(end 140.914882 -225.044508)
		(width 0.350012)
		(layer "F.Cu")
		(net "GND")
	)
	(segment
		(start 368.64798 -249.610118)
		(end 369.114832 -249.34418)
		(width 0.350012)
		(layer "F.Cu")
		(net "GND")
	)
	(segment
		(start 368.947954 -274.630134)
		(end 369.414806 -274.896072)
		(width 0.350012)
		(layer "F.Cu")
		(net "GND")
	)
	(segment
		(start 124.937774 -240.700306)
		(end 125.404626 -240.434368)
		(width 0.350012)
		(layer "F.Cu")
		(net "GND")
	)
	(segment
		(start 408.498294 -398.542002)
		(end 407.819098 -398.542002)
		(width 0.254)
		(layer "F.Cu")
		(net "GND")
	)
	(segment
		(start 362.53801 -250.420124)
		(end 363.004862 -250.154186)
		(width 0.350012)
		(layer "F.Cu")
		(net "GND")
	)
	(segment
		(start 353.907852 -266.530074)
		(end 353.441 -266.796012)
		(width 0.350012)
		(layer "F.Cu")
		(net "GND")
	)
	(segment
		(start 46.494954 -391.304272)
		(end 46.518068 -391.281158)
		(width 0.254)
		(layer "F.Cu")
		(net "GND")
	)
	(segment
		(start 25.152096 -275.53539)
		(end 26.536396 -275.53539)
		(width 0.4572)
		(layer "F.Cu")
		(net "GND")
	)
	(segment
		(start 127.757936 -224.50044)
		(end 128.224788 -224.234502)
		(width 0.350012)
		(layer "F.Cu")
		(net "GND")
	)
	(segment
		(start 345.918028 -273.820128)
		(end 345.451176 -274.086066)
		(width 0.350012)
		(layer "F.Cu")
		(net "GND")
	)
	(segment
		(start 127.117856 -390.761474)
		(end 127.170434 -390.160002)
		(width 0.254)
		(layer "F.Cu")
		(net "GND")
	)
	(segment
		(start 427.456092 -228.785166)
		(end 428.840392 -228.785166)
		(width 0.4572)
		(layer "F.Cu")
		(net "GND")
	)
	(segment
		(start 359.059988 -417.448238)
		(end 358.952546 -417.55568)
		(width 0.381)
		(layer "F.Cu")
		(net "GND")
	)
	(segment
		(start 295.724072 -219.435172)
		(end 297.108372 -219.435172)
		(width 0.4572)
		(layer "F.Cu")
		(net "GND")
	)
	(segment
		(start 372.877842 -226.120198)
		(end 373.344694 -225.85426)
		(width 0.350012)
		(layer "F.Cu")
		(net "GND")
	)
	(segment
		(start 146.248882 -388.330948)
		(end 145.92935 -388.330948)
		(width 0.254)
		(layer "F.Cu")
		(net "GND")
	)
	(segment
		(start 102.725982 -179.627784)
		(end 102.235 -180.118766)
		(width 0.2286)
		(layer "F.Cu")
		(net "GND")
	)
	(segment
		(start 99.857814 -281.920442)
		(end 99.390962 -282.18638)
		(width 0.350012)
		(layer "F.Cu")
		(net "GND")
	)
	(segment
		(start 4.576318 -133.08838)
		(end 5.229098 -133.08838)
		(width 0.3556)
		(layer "F.Cu")
		(net "GND")
	)
	(segment
		(start 302.620934 -393.81303)
		(end 302.620934 -393.24915)
		(width 0.254)
		(layer "F.Cu")
		(net "GND")
	)
	(segment
		(start 108.787946 -285.970472)
		(end 108.321094 -286.23641)
		(width 0.350012)
		(layer "F.Cu")
		(net "GND")
	)
	(segment
		(start 346.557854 -250.420124)
		(end 346.091002 -250.154186)
		(width 0.350012)
		(layer "F.Cu")
		(net "GND")
	)
	(segment
		(start 379.927866 -249.610118)
		(end 380.394718 -249.34418)
		(width 0.350012)
		(layer "F.Cu")
		(net "GND")
	)
	(segment
		(start 133.117844 -390.761474)
		(end 133.170676 -390.160002)
		(width 0.254)
		(layer "F.Cu")
		(net "GND")
	)
	(segment
		(start 386.41782 -392.004042)
		(end 386.41782 -391.784586)
		(width 0.254)
		(layer "F.Cu")
		(net "GND")
	)
	(segment
		(start 36.411662 -430.799748)
		(end 36.411662 -430.190148)
		(width 0.3556)
		(layer "F.Cu")
		(net "GND")
	)
	(segment
		(start 118.09095 -420.497)
		(end 117.475 -420.497)
		(width 0.381)
		(layer "F.Cu")
		(net "GND")
	)
	(segment
		(start 106.437938 -293.260272)
		(end 105.971086 -293.52621)
		(width 0.350012)
		(layer "F.Cu")
		(net "GND")
	)
	(segment
		(start 97.677986 -229.360476)
		(end 97.211134 -229.094538)
		(width 0.350012)
		(layer "F.Cu")
		(net "GND")
	)
	(segment
		(start 82.99831 -390.160002)
		(end 83.51901 -390.160002)
		(width 0.254)
		(layer "F.Cu")
		(net "GND")
	)
	(segment
		(start 447.16065 -7.215886)
		(end 447.16065 -7.215124)
		(width 0.3556)
		(layer "F.Cu")
		(net "GND")
	)
	(segment
		(start 103.787956 -222.070422)
		(end 104.261158 -221.804484)
		(width 0.350012)
		(layer "F.Cu")
		(net "GND")
	)
	(segment
		(start 102.847902 -228.55047)
		(end 102.38105 -228.284532)
		(width 0.350012)
		(layer "F.Cu")
		(net "GND")
	)
	(segment
		(start 280.635964 -212.635084)
		(end 282.020264 -212.635084)
		(width 0.4572)
		(layer "F.Cu")
		(net "GND")
	)
	(segment
		(start 132.927852 -256.09042)
		(end 133.394704 -255.824482)
		(width 0.350012)
		(layer "F.Cu")
		(net "GND")
	)
	(segment
		(start 121.477786 -273.820382)
		(end 121.944638 -274.08632)
		(width 0.350012)
		(layer "F.Cu")
		(net "GND")
	)
	(segment
		(start 351.557844 -288.399982)
		(end 351.091246 -288.66592)
		(width 0.350012)
		(layer "F.Cu")
		(net "GND")
	)
	(segment
		(start 371.170454 -392.999722)
		(end 371.762274 -392.999722)
		(width 0.254)
		(layer "F.Cu")
		(net "GND")
	)
	(segment
		(start 153.345642 -382.951482)
		(end 153.444194 -382.85293)
		(width 0.254)
		(layer "F.Cu")
		(net "GND")
	)
	(segment
		(start 182.722012 -113.85296)
		(end 182.332122 -113.46307)
		(width 0.254)
		(layer "F.Cu")
		(net "GND")
	)
	(segment
		(start 352.197924 -240.700052)
		(end 351.731072 -240.434114)
		(width 0.350012)
		(layer "F.Cu")
		(net "GND")
	)
	(segment
		(start 409.345638 -391.784586)
		(end 409.345638 -392.004296)
		(width 0.254)
		(layer "F.Cu")
		(net "GND")
	)
	(segment
		(start 122.370596 -386.6388)
		(end 121.678446 -386.449062)
		(width 0.254)
		(layer "F.Cu")
		(net "GND")
	)
	(segment
		(start 361.3023 -390.652)
		(end 361.62869 -390.32561)
		(width 0.254)
		(layer "F.Cu")
		(net "GND")
	)
	(segment
		(start 392.14806 -251.23013)
		(end 392.614912 -250.964192)
		(width 0.350012)
		(layer "F.Cu")
		(net "GND")
	)
	(segment
		(start 441.344558 -30.651704)
		(end 441.344558 -29.584142)
		(width 0.254)
		(layer "F.Cu")
		(net "GND")
	)
	(segment
		(start 119.597932 -281.920442)
		(end 120.064784 -282.18638)
		(width 0.350012)
		(layer "F.Cu")
		(net "GND")
	)
	(segment
		(start 429.566832 -10.16635)
		(end 429.565562 -10.16508)
		(width 0.3556)
		(layer "F.Cu")
		(net "GND")
	)
	(segment
		(start 90.380312 -75.654154)
		(end 90.381328 -75.65517)
		(width 0.4572)
		(layer "F.Cu")
		(net "GND")
	)
	(segment
		(start 48.32858 -394.82268)
		(end 47.816516 -394.310616)
		(width 0.381)
		(layer "F.Cu")
		(net "GND")
	)
	(segment
		(start 118.723664 -438.793382)
		(end 118.723664 -438.101232)
		(width 0.381)
		(layer "F.Cu")
		(net "GND")
	)
	(segment
		(start 110.83798 -248.800366)
		(end 110.371128 -248.534428)
		(width 0.350012)
		(layer "F.Cu")
		(net "GND")
	)
	(segment
		(start 189.263274 -16.551148)
		(end 189.263274 -17.654778)
		(width 0.3556)
		(layer "F.Cu")
		(net "GND")
	)
	(segment
		(start 416.468052 -295.935146)
		(end 415.083752 -295.935146)
		(width 0.4572)
		(layer "F.Cu")
		(net "GND")
	)
	(segment
		(start 134.80796 -251.230384)
		(end 135.274812 -250.964446)
		(width 0.350012)
		(layer "F.Cu")
		(net "GND")
	)
	(segment
		(start 148.898356 -384.617722)
		(end 148.845778 -383.92227)
		(width 0.254)
		(layer "F.Cu")
		(net "GND")
	)
	(segment
		(start 273.092164 -303.585118)
		(end 274.476464 -303.585118)
		(width 0.4572)
		(layer "F.Cu")
		(net "GND")
	)
	(segment
		(start 102.378002 -227.740464)
		(end 101.91115 -227.474526)
		(width 0.350012)
		(layer "F.Cu")
		(net "GND")
	)
	(segment
		(start 139.507976 -225.310446)
		(end 139.974828 -225.044508)
		(width 0.350012)
		(layer "F.Cu")
		(net "GND")
	)
	(segment
		(start 138.397996 -267.340334)
		(end 138.864848 -267.606272)
		(width 0.350012)
		(layer "F.Cu")
		(net "GND")
	)
	(segment
		(start 105.967784 -290.830254)
		(end 105.500932 -291.096192)
		(width 0.350012)
		(layer "F.Cu")
		(net "GND")
	)
	(segment
		(start 183.616092 -199.8853)
		(end 182.231792 -199.8853)
		(width 0.4572)
		(layer "F.Cu")
		(net "GND")
	)
	(segment
		(start 435.000146 -219.435172)
		(end 436.384446 -219.435172)
		(width 0.4572)
		(layer "F.Cu")
		(net "GND")
	)
	(segment
		(start 35.97656 -351.932748)
		(end 36.56457 -351.932748)
		(width 0.381)
		(layer "F.Cu")
		(net "GND")
	)
	(segment
		(start 23.80361 -333.151226)
		(end 22.8981 -333.151226)
		(width 0.254)
		(layer "F.Cu")
		(net "GND")
	)
	(segment
		(start 269.648178 -227.935028)
		(end 268.263878 -227.935028)
		(width 0.4572)
		(layer "F.Cu")
		(net "GND")
	)
	(segment
		(start 351.557844 -270.580104)
		(end 351.091246 -270.846042)
		(width 0.350012)
		(layer "F.Cu")
		(net "GND")
	)
	(segment
		(start 20.346924 -12.372848)
		(end 20.346924 -11.26998)
		(width 0.3556)
		(layer "F.Cu")
		(net "GND")
	)
	(segment
		(start 368.17808 -252.040136)
		(end 368.644678 -251.774198)
		(width 0.350012)
		(layer "F.Cu")
		(net "GND")
	)
	(segment
		(start 109.728 -279.490424)
		(end 109.261148 -279.756362)
		(width 0.350012)
		(layer "F.Cu")
		(net "GND")
	)
	(segment
		(start 115.367816 -273.010376)
		(end 115.834668 -273.276314)
		(width 0.350012)
		(layer "F.Cu")
		(net "GND")
	)
	(segment
		(start 90.927936 -295.69029)
		(end 90.461084 -295.956228)
		(width 0.350012)
		(layer "F.Cu")
		(net "GND")
	)
	(segment
		(start 379.570488 -392.999722)
		(end 379.51791 -392.30427)
		(width 0.254)
		(layer "F.Cu")
		(net "GND")
	)
	(segment
		(start 424.012106 -312.084974)
		(end 422.627806 -312.084974)
		(width 0.4572)
		(layer "F.Cu")
		(net "GND")
	)
	(segment
		(start 135.27786 -250.420378)
		(end 135.744712 -250.15444)
		(width 0.350012)
		(layer "F.Cu")
		(net "GND")
	)
	(segment
		(start 365.981234 -34.243772)
		(end 365.981234 -33.049972)
		(width 0.3556)
		(layer "F.Cu")
		(net "GND")
	)
	(segment
		(start 371.467888 -236.650022)
		(end 371.93474 -236.384084)
		(width 0.350012)
		(layer "F.Cu")
		(net "GND")
	)
	(segment
		(start 320.517774 -391.784586)
		(end 320.517774 -392.004296)
		(width 0.254)
		(layer "F.Cu")
		(net "GND")
	)
	(segment
		(start 114.817906 -391.281158)
		(end 114.916458 -391.37971)
		(width 0.254)
		(layer "F.Cu")
		(net "GND")
	)
	(segment
		(start 369.11788 -248.800112)
		(end 369.584732 -248.534174)
		(width 0.350012)
		(layer "F.Cu")
		(net "GND")
	)
	(segment
		(start 371.767862 -273.010122)
		(end 372.234714 -273.27606)
		(width 0.350012)
		(layer "F.Cu")
		(net "GND")
	)
	(segment
		(start 302.870362 -396.46352)
		(end 302.620934 -396.214092)
		(width 0.254)
		(layer "F.Cu")
		(net "GND")
	)
	(segment
		(start 85.96757 -179.678584)
		(end 85.936582 -179.678584)
		(width 0.2286)
		(layer "F.Cu")
		(net "GND")
	)
	(segment
		(start 345.1479 -226.930204)
		(end 344.681048 -226.664266)
		(width 0.350012)
		(layer "F.Cu")
		(net "GND")
	)
	(segment
		(start 47.164752 -385.87553)
		(end 47.009304 -386.030978)
		(width 0.254)
		(layer "F.Cu")
		(net "GND")
	)
	(segment
		(start 297.283378 -348.794324)
		(end 297.536362 -348.54134)
		(width 0.2286)
		(layer "F.Cu")
		(net "GND")
	)
	(segment
		(start 394.027914 -256.090166)
		(end 394.68298 -256.090166)
		(width 0.350012)
		(layer "F.Cu")
		(net "GND")
	)
	(segment
		(start 316.917832 -391.333482)
		(end 317.016384 -391.23493)
		(width 0.254)
		(layer "F.Cu")
		(net "GND")
	)
	(segment
		(start 429.566832 -9.423654)
		(end 429.568102 -9.424924)
		(width 0.3556)
		(layer "F.Cu")
		(net "GND")
	)
	(segment
		(start 391.208006 -247.990106)
		(end 391.674858 -247.724168)
		(width 0.350012)
		(layer "F.Cu")
		(net "GND")
	)
	(segment
		(start 41.450768 -351.10547)
		(end 41.450768 -351.736406)
		(width 0.381)
		(layer "F.Cu")
		(net "GND")
	)
	(segment
		(start 344.977974 -262.480044)
		(end 344.511122 -262.745982)
		(width 0.350012)
		(layer "F.Cu")
		(net "GND")
	)
	(segment
		(start 411.196536 -134.807706)
		(end 411.196536 -135.480552)
		(width 0.3556)
		(layer "F.Cu")
		(net "GND")
	)
	(segment
		(start 328.527918 -276.250146)
		(end 328.061066 -276.516084)
		(width 0.350012)
		(layer "F.Cu")
		(net "GND")
	)
	(segment
		(start 105.967784 -282.730448)
		(end 105.500932 -282.996386)
		(width 0.350012)
		(layer "F.Cu")
		(net "GND")
	)
	(segment
		(start 391.03808 -273.820128)
		(end 391.504678 -274.086066)
		(width 0.350012)
		(layer "F.Cu")
		(net "GND")
	)
	(segment
		(start 341.857838 -245.560088)
		(end 341.390986 -245.29415)
		(width 0.350012)
		(layer "F.Cu")
		(net "GND")
	)
	(segment
		(start 11.512042 -50.094896)
		(end 11.51636 -50.099214)
		(width 0.4572)
		(layer "F.Cu")
		(net "GND")
	)
	(segment
		(start 56.90997 -31.664148)
		(end 56.90997 -32.295084)
		(width 0.4572)
		(layer "F.Cu")
		(net "GND")
	)
	(segment
		(start 362.368084 -284.350206)
		(end 362.834682 -284.616144)
		(width 0.350012)
		(layer "F.Cu")
		(net "GND")
	)
	(segment
		(start 306.470304 -392.999722)
		(end 305.862228 -392.999722)
		(width 0.254)
		(layer "F.Cu")
		(net "GND")
	)
	(segment
		(start 123.357894 -273.820382)
		(end 123.824746 -274.08632)
		(width 0.350012)
		(layer "F.Cu")
		(net "GND")
	)
	(segment
		(start 350.31807 -255.28016)
		(end 349.851218 -255.014222)
		(width 0.350012)
		(layer "F.Cu")
		(net "GND")
	)
	(segment
		(start 325.49338 -395.22273)
		(end 325.736712 -395.466062)
		(width 0.381)
		(layer "F.Cu")
		(net "GND")
	)
	(segment
		(start 206.248 -286.585406)
		(end 204.8637 -286.585406)
		(width 0.4572)
		(layer "F.Cu")
		(net "GND")
	)
	(segment
		(start 134.80796 -225.310446)
		(end 135.274812 -225.044508)
		(width 0.350012)
		(layer "F.Cu")
		(net "GND")
	)
	(segment
		(start 411.41904 -398.542002)
		(end 410.89834 -398.542002)
		(width 0.254)
		(layer "F.Cu")
		(net "GND")
	)
	(segment
		(start 126.647956 -276.2504)
		(end 127.114808 -276.516338)
		(width 0.350012)
		(layer "F.Cu")
		(net "GND")
	)
	(segment
		(start 314.81776 -399.143474)
		(end 314.517786 -399.663158)
		(width 0.254)
		(layer "F.Cu")
		(net "GND")
	)
	(segment
		(start 343.56802 -292.450012)
		(end 343.101168 -292.71595)
		(width 0.350012)
		(layer "F.Cu")
		(net "GND")
	)
	(segment
		(start 340.277958 -270.580104)
		(end 339.811106 -270.846042)
		(width 0.350012)
		(layer "F.Cu")
		(net "GND")
	)
	(segment
		(start 133.346952 -12.551156)
		(end 133.289802 -12.494006)
		(width 0.3556)
		(layer "F.Cu")
		(net "GND")
	)
	(segment
		(start 378.817886 -294.88003)
		(end 379.284738 -295.145968)
		(width 0.350012)
		(layer "F.Cu")
		(net "GND")
	)
	(segment
		(start 91.045792 -382.951482)
		(end 91.144344 -382.85293)
		(width 0.254)
		(layer "F.Cu")
		(net "GND")
	)
	(segment
		(start 135.252714 -154.706066)
		(end 134.824216 -154.706066)
		(width 0.2286)
		(layer "F.Cu")
		(net "GND")
	)
	(segment
		(start 309.37835 -394.831062)
		(end 308.87035 -395.0208)
		(width 0.254)
		(layer "F.Cu")
		(net "GND")
	)
	(segment
		(start 335.148682 -398.613122)
		(end 335.148682 -398.01292)
		(width 0.254)
		(layer "F.Cu")
		(net "GND")
	)
	(segment
		(start 356.25786 -281.920188)
		(end 355.791008 -282.186126)
		(width 0.350012)
		(layer "F.Cu")
		(net "GND")
	)
	(segment
		(start 108.787946 -279.490424)
		(end 108.321094 -279.756362)
		(width 0.350012)
		(layer "F.Cu")
		(net "GND")
	)
	(segment
		(start 32.695896 -238.135414)
		(end 34.080196 -238.135414)
		(width 0.4572)
		(layer "F.Cu")
		(net "GND")
	)
	(segment
		(start 407.446988 -9.423654)
		(end 407.448258 -9.424924)
		(width 0.3556)
		(layer "F.Cu")
		(net "GND")
	)
	(segment
		(start 104.409748 -387.0579)
		(end 105.222548 -387.0579)
		(width 0.254)
		(layer "F.Cu")
		(net "GND")
	)
	(segment
		(start 104.55783 -288.400236)
		(end 104.090978 -288.666174)
		(width 0.350012)
		(layer "F.Cu")
		(net "GND")
	)
	(segment
		(start 130.407918 -271.390364)
		(end 130.87477 -271.656302)
		(width 0.350012)
		(layer "F.Cu")
		(net "GND")
	)
	(segment
		(start 379.217936 -391.784586)
		(end 379.217936 -391.333482)
		(width 0.254)
		(layer "F.Cu")
		(net "GND")
	)
	(segment
		(start 144.977866 -278.680418)
		(end 145.444718 -278.946356)
		(width 0.350012)
		(layer "F.Cu")
		(net "GND")
	)
	(segment
		(start 369.231418 -39.843964)
		(end 369.231418 -38.650164)
		(width 0.3556)
		(layer "F.Cu")
		(net "GND")
	)
	(segment
		(start 328.527918 -284.350206)
		(end 328.061066 -284.616144)
		(width 0.350012)
		(layer "F.Cu")
		(net "GND")
	)
	(segment
		(start 416.218878 -398.542002)
		(end 415.698178 -398.542002)
		(width 0.254)
		(layer "F.Cu")
		(net "GND")
	)
	(segment
		(start 17.422368 -107.60837)
		(end 17.422368 -106.735372)
		(width 0.3556)
		(layer "F.Cu")
		(net "GND")
	)
	(segment
		(start 90.927936 -287.590484)
		(end 90.461084 -287.856422)
		(width 0.350012)
		(layer "F.Cu")
		(net "GND")
	)
	(segment
		(start 25.748234 -12.37488)
		(end 25.748234 -12.374118)
		(width 0.3556)
		(layer "F.Cu")
		(net "GND")
	)
	(segment
		(start 153.090118 -384.617722)
		(end 152.498298 -384.617722)
		(width 0.254)
		(layer "F.Cu")
		(net "GND")
	)
	(segment
		(start 100.327968 -276.2504)
		(end 99.861116 -276.516338)
		(width 0.350012)
		(layer "F.Cu")
		(net "GND")
	)
	(segment
		(start 410.89834 -396.520924)
		(end 410.346144 -396.710662)
		(width 0.254)
		(layer "F.Cu")
		(net "GND")
	)
	(segment
		(start 363.478064 -248.800112)
		(end 363.944916 -248.534174)
		(width 0.350012)
		(layer "F.Cu")
		(net "GND")
	)
	(segment
		(start 141.38783 -247.99036)
		(end 141.854682 -247.724422)
		(width 0.350012)
		(layer "F.Cu")
		(net "GND")
	)
	(segment
		(start 133.346952 -16.549878)
		(end 133.346952 -17.652746)
		(width 0.3556)
		(layer "F.Cu")
		(net "GND")
	)
	(segment
		(start 124.027438 -54.375558)
		(end 124.49429 -54.375558)
		(width 0.1778)
		(layer "F.Cu")
		(net "GND")
	)
	(segment
		(start 376.174 -427.7487)
		(end 376.174 -427.827186)
		(width 0.254)
		(layer "F.Cu")
		(net "GND")
	)
	(segment
		(start 354.378006 -281.920188)
		(end 353.911154 -282.186126)
		(width 0.350012)
		(layer "F.Cu")
		(net "GND")
	)
	(segment
		(start 407.446988 -10.16635)
		(end 407.445718 -10.16508)
		(width 0.3556)
		(layer "F.Cu")
		(net "GND")
	)
	(segment
		(start 101.076252 -55.282084)
		(end 100.832158 -55.03799)
		(width 0.4572)
		(layer "F.Cu")
		(net "GND")
	)
	(segment
		(start 81.22793 -249.610372)
		(end 80.761078 -249.344434)
		(width 0.350012)
		(layer "F.Cu")
		(net "GND")
	)
	(segment
		(start 348.014036 -342.999822)
		(end 348.58452 -342.429338)
		(width 0.2286)
		(layer "F.Cu")
		(net "GND")
	)
	(segment
		(start 90.157808 -232.600246)
		(end 89.690956 -232.334308)
		(width 0.350012)
		(layer "F.Cu")
		(net "GND")
	)
	(segment
		(start 431.36693 -11.26998)
		(end 431.36693 -10.16635)
		(width 0.3556)
		(layer "F.Cu")
		(net "GND")
	)
	(segment
		(start 387.917944 -232.599992)
		(end 388.384796 -232.334054)
		(width 0.350012)
		(layer "F.Cu")
		(net "GND")
	)
	(segment
		(start 37.333428 -133.857238)
		(end 36.720018 -133.857238)
		(width 0.3556)
		(layer "F.Cu")
		(net "GND")
	)
	(segment
		(start 120.707912 -247.99036)
		(end 121.174764 -247.724422)
		(width 0.350012)
		(layer "F.Cu")
		(net "GND")
	)
	(segment
		(start 40.23995 -303.585372)
		(end 41.62425 -303.585372)
		(width 0.4572)
		(layer "F.Cu")
		(net "GND")
	)
	(segment
		(start 102.847902 -244.750336)
		(end 102.38105 -244.484398)
		(width 0.350012)
		(layer "F.Cu")
		(net "GND")
	)
	(segment
		(start 379.570488 -398.542002)
		(end 378.891292 -398.542002)
		(width 0.254)
		(layer "F.Cu")
		(net "GND")
	)
	(segment
		(start 375.057924 -260.860032)
		(end 375.524776 -261.12597)
		(width 0.350012)
		(layer "F.Cu")
		(net "GND")
	)
	(segment
		(start 119.297958 -247.180354)
		(end 119.76481 -246.914416)
		(width 0.350012)
		(layer "F.Cu")
		(net "GND")
	)
	(segment
		(start 113.339372 -405.91994)
		(end 113.339372 -403.991318)
		(width 0.3302)
		(layer "F.Cu")
		(net "GND")
	)
	(segment
		(start 424.01871 -363.773974)
		(end 424.010074 -363.78261)
		(width 0.3556)
		(layer "F.Cu")
		(net "GND")
	)
	(segment
		(start 381.338074 -248.800112)
		(end 381.804926 -248.534174)
		(width 0.350012)
		(layer "F.Cu")
		(net "GND")
	)
	(segment
		(start 339.977984 -245.560088)
		(end 339.511132 -245.29415)
		(width 0.350012)
		(layer "F.Cu")
		(net "GND")
	)
	(segment
		(start 115.537996 -239.080294)
		(end 116.004848 -238.814356)
		(width 0.350012)
		(layer "F.Cu")
		(net "GND")
	)
	(segment
		(start 18.230088 -107.123484)
		(end 17.722088 -107.631484)
		(width 0.3556)
		(layer "F.Cu")
		(net "GND")
	)
	(segment
		(start 105.66781 -238.270288)
		(end 105.200958 -238.00435)
		(width 0.350012)
		(layer "F.Cu")
		(net "GND")
	)
	(segment
		(start 126.177802 -293.260272)
		(end 126.644654 -293.52621)
		(width 0.350012)
		(layer "F.Cu")
		(net "GND")
	)
	(segment
		(start 132.364226 -112.268)
		(end 132.799074 -112.702848)
		(width 0.381)
		(layer "F.Cu")
		(net "GND")
	)
	(segment
		(start 65.518538 -388.328662)
		(end 66.314828 -387.831076)
		(width 0.254)
		(layer "F.Cu")
		(net "GND")
	)
	(segment
		(start 384.87858 -394.831062)
		(end 384.37058 -395.0208)
		(width 0.254)
		(layer "F.Cu")
		(net "GND")
	)
	(segment
		(start 440.203336 -32.670242)
		(end 440.203336 -31.792926)
		(width 0.254)
		(layer "F.Cu")
		(net "GND")
	)
	(segment
		(start 129.63779 -243.94033)
		(end 130.104642 -243.674392)
		(width 0.350012)
		(layer "F.Cu")
		(net "GND")
	)
	(segment
		(start 424.166792 -11.26998)
		(end 424.166792 -10.16635)
		(width 0.3556)
		(layer "F.Cu")
		(net "GND")
	)
	(segment
		(start 153.006298 -386.449062)
		(end 152.498298 -386.6388)
		(width 0.254)
		(layer "F.Cu")
		(net "GND")
	)
	(segment
		(start 269.648178 -230.485188)
		(end 268.263878 -230.485188)
		(width 0.4572)
		(layer "F.Cu")
		(net "GND")
	)
	(segment
		(start 331.047852 -223.69018)
		(end 330.581 -223.424242)
		(width 0.350012)
		(layer "F.Cu")
		(net "GND")
	)
	(segment
		(start 404.290022 -392.999722)
		(end 404.898352 -392.999722)
		(width 0.254)
		(layer "F.Cu")
		(net "GND")
	)
	(segment
		(start 50.481738 -351.978722)
		(end 50.2285 -352.23196)
		(width 0.381)
		(layer "F.Cu")
		(net "GND")
	)
	(segment
		(start 379.457966 -253.660148)
		(end 379.924818 -253.39421)
		(width 0.350012)
		(layer "F.Cu")
		(net "GND")
	)
	(segment
		(start 156.769816 -118.132352)
		(end 157.966664 -118.132352)
		(width 0.4572)
		(layer "F.Cu")
		(net "GND")
	)
	(segment
		(start 53.717952 -383.402586)
		(end 53.717952 -382.951482)
		(width 0.254)
		(layer "F.Cu")
		(net "GND")
	)
	(segment
		(start 334.808068 -243.13007)
		(end 334.341216 -242.864132)
		(width 0.350012)
		(layer "F.Cu")
		(net "GND")
	)
	(segment
		(start 56.47055 -388.138924)
		(end 57.118504 -388.328662)
		(width 0.254)
		(layer "F.Cu")
		(net "GND")
	)
	(segment
		(start 59.428126 -277.235412)
		(end 58.043826 -277.235412)
		(width 0.4572)
		(layer "F.Cu")
		(net "GND")
	)
	(segment
		(start 379.457966 -247.1801)
		(end 379.924818 -246.914162)
		(width 0.350012)
		(layer "F.Cu")
		(net "GND")
	)
	(segment
		(start 122.117866 -240.700306)
		(end 122.584718 -240.434368)
		(width 0.350012)
		(layer "F.Cu")
		(net "GND")
	)
	(segment
		(start 155.490164 -384.617722)
		(end 156.09824 -384.617722)
		(width 0.254)
		(layer "F.Cu")
		(net "GND")
	)
	(segment
		(start 83.944206 -391.830814)
		(end 83.944206 -391.37971)
		(width 0.254)
		(layer "F.Cu")
		(net "GND")
	)
	(segment
		(start 429.76165 -398.91208)
		(end 429.622458 -398.91208)
		(width 0.254)
		(layer "F.Cu")
		(net "GND")
	)
	(segment
		(start 154.290014 -384.617722)
		(end 154.898344 -384.617722)
		(width 0.254)
		(layer "F.Cu")
		(net "GND")
	)
	(segment
		(start 343.268046 -235.03001)
		(end 342.801194 -234.764072)
		(width 0.350012)
		(layer "F.Cu")
		(net "GND")
	)
	(segment
		(start 442.5442 -200.735184)
		(end 443.9285 -200.735184)
		(width 0.4572)
		(layer "F.Cu")
		(net "GND")
	)
	(segment
		(start 168.527984 -211.7852)
		(end 167.143684 -211.7852)
		(width 0.4572)
		(layer "F.Cu")
		(net "GND")
	)
	(segment
		(start 67.58051 -336.825082)
		(end 68.009008 -336.825082)
		(width 0.2286)
		(layer "F.Cu")
		(net "GND")
	)
	(segment
		(start 63.42253 -36.65728)
		(end 64.05753 -36.65728)
		(width 0.3556)
		(layer "F.Cu")
		(net "GND")
	)
	(segment
		(start 376.167904 -233.409998)
		(end 376.634756 -233.14406)
		(width 0.350012)
		(layer "F.Cu")
		(net "GND")
	)
	(segment
		(start 27.547062 -11.26998)
		(end 27.547062 -10.16635)
		(width 0.3556)
		(layer "F.Cu")
		(net "GND")
	)
	(segment
		(start 407.806144 -394.831062)
		(end 407.298398 -395.0208)
		(width 0.254)
		(layer "F.Cu")
		(net "GND")
	)
	(segment
		(start 36.795964 -218.585288)
		(end 35.411664 -218.585288)
		(width 0.4572)
		(layer "F.Cu")
		(net "GND")
	)
	(segment
		(start 169.1767 -381.42418)
		(end 169.502836 -381.42418)
		(width 0.254)
		(layer "F.Cu")
		(net "GND")
	)
	(segment
		(start 87.8078 -249.610372)
		(end 87.340948 -249.344434)
		(width 0.350012)
		(layer "F.Cu")
		(net "GND")
	)
	(segment
		(start 356.728014 -276.250146)
		(end 356.261162 -276.516084)
		(width 0.350012)
		(layer "F.Cu")
		(net "GND")
	)
	(segment
		(start 114.197638 -394.862558)
		(end 113.687098 -394.352018)
		(width 0.254)
		(layer "F.Cu")
		(net "GND")
	)
	(segment
		(start 334.629252 -396.51305)
		(end 334.320642 -396.74673)
		(width 0.254)
		(layer "F.Cu")
		(net "GND")
	)
	(segment
		(start 373.17807 -270.580104)
		(end 373.644922 -270.846042)
		(width 0.350012)
		(layer "F.Cu")
		(net "GND")
	)
	(segment
		(start 359.078022 -280.300176)
		(end 358.61117 -280.566114)
		(width 0.350012)
		(layer "F.Cu")
		(net "GND")
	)
	(segment
		(start 21.70811 -227.935282)
		(end 20.32381 -227.935282)
		(width 0.4572)
		(layer "F.Cu")
		(net "GND")
	)
	(segment
		(start 349.378016 -247.1801)
		(end 348.911164 -246.914162)
		(width 0.350012)
		(layer "F.Cu")
		(net "GND")
	)
	(segment
		(start 354.078032 -235.840016)
		(end 353.61118 -235.574078)
		(width 0.350012)
		(layer "F.Cu")
		(net "GND")
	)
	(segment
		(start 107.078018 -222.880428)
		(end 107.081066 -221.804484)
		(width 0.254)
		(layer "F.Cu")
		(net "GND")
	)
	(segment
		(start 390.737852 -230.97998)
		(end 391.204704 -230.714296)
		(width 0.350012)
		(layer "F.Cu")
		(net "GND")
	)
	(segment
		(start 344.977974 -260.860032)
		(end 344.511122 -261.12597)
		(width 0.350012)
		(layer "F.Cu")
		(net "GND")
	)
	(segment
		(start 84.347812 -292.450266)
		(end 83.88096 -292.716204)
		(width 0.350012)
		(layer "F.Cu")
		(net "GND")
	)
	(segment
		(start 133.934454 -385.131056)
		(end 133.934454 -384.531108)
		(width 0.254)
		(layer "F.Cu")
		(net "GND")
	)
	(segment
		(start 212.593682 -110.630208)
		(end 212.36051 -110.397036)
		(width 0.381)
		(layer "F.Cu")
		(net "GND")
	)
	(segment
		(start 179.516024 -231.335326)
		(end 180.900324 -231.335326)
		(width 0.4572)
		(layer "F.Cu")
		(net "GND")
	)
	(segment
		(start 52.518056 -383.402586)
		(end 52.518056 -382.951482)
		(width 0.2032)
		(layer "F.Cu")
		(net "GND")
	)
	(segment
		(start 161.844228 -391.830814)
		(end 161.844228 -391.37971)
		(width 0.254)
		(layer "F.Cu")
		(net "GND")
	)
	(segment
		(start 389.327898 -233.409998)
		(end 389.79475 -233.14406)
		(width 0.350012)
		(layer "F.Cu")
		(net "GND")
	)
	(segment
		(start 147.698206 -390.160002)
		(end 147.018756 -390.160002)
		(width 0.254)
		(layer "F.Cu")
		(net "GND")
	)
	(segment
		(start 27.545792 -7.215886)
		(end 27.547062 -7.217156)
		(width 0.3556)
		(layer "F.Cu")
		(net "GND")
	)
	(segment
		(start 461.81137 -38.565836)
		(end 461.81137 -37.92855)
		(width 0.4572)
		(layer "F.Cu")
		(net "GND")
	)
	(segment
		(start 361.128056 -238.270034)
		(end 361.594908 -238.004096)
		(width 0.350012)
		(layer "F.Cu")
		(net "GND")
	)
	(segment
		(start 322.476622 -395.451076)
		(end 322.31457 -395.613128)
		(width 0.254)
		(layer "F.Cu")
		(net "GND")
	)
	(segment
		(start 126.949454 -403.830536)
		(end 126.949454 -402.882354)
		(width 0.381)
		(layer "F.Cu")
		(net "GND")
	)
	(segment
		(start 377.577858 -245.560088)
		(end 378.04471 -245.29415)
		(width 0.350012)
		(layer "F.Cu")
		(net "GND")
	)
	(segment
		(start 176.072038 -305.285394)
		(end 174.687738 -305.285394)
		(width 0.4572)
		(layer "F.Cu")
		(net "GND")
	)
	(segment
		(start 128.208278 -403.830536)
		(end 128.208278 -402.961602)
		(width 0.381)
		(layer "F.Cu")
		(net "GND")
	)
	(segment
		(start 115.83797 -278.680418)
		(end 116.304822 -278.946356)
		(width 0.350012)
		(layer "F.Cu")
		(net "GND")
	)
	(segment
		(start 118.417848 -382.951482)
		(end 118.5164 -382.85293)
		(width 0.2032)
		(layer "F.Cu")
		(net "GND")
	)
	(segment
		(start 82.467958 -282.730448)
		(end 82.001106 -282.996386)
		(width 0.350012)
		(layer "F.Cu")
		(net "GND")
	)
	(segment
		(start 55.065676 -7.215886)
		(end 55.066946 -7.217156)
		(width 0.3556)
		(layer "F.Cu")
		(net "GND")
	)
	(segment
		(start 125.238002 -288.400236)
		(end 125.704854 -288.666174)
		(width 0.350012)
		(layer "F.Cu")
		(net "GND")
	)
	(segment
		(start 384.37058 -392.999722)
		(end 383.76225 -392.999722)
		(width 0.254)
		(layer "F.Cu")
		(net "GND")
	)
	(segment
		(start 345.918028 -291.640006)
		(end 345.451176 -291.905944)
		(width 0.350012)
		(layer "F.Cu")
		(net "GND")
	)
	(segment
		(start 87.757 -145.90141)
		(end 88.431878 -145.90141)
		(width 0.4572)
		(layer "F.Cu")
		(net "GND")
	)
	(segment
		(start 412.045658 -399.143474)
		(end 411.745684 -399.663158)
		(width 0.254)
		(layer "F.Cu")
		(net "GND")
	)
	(segment
		(start 335.345532 -399.143474)
		(end 335.045558 -399.663158)
		(width 0.254)
		(layer "F.Cu")
		(net "GND")
	)
	(segment
		(start 94.1959 -416.4076)
		(end 94.1959 -416.635184)
		(width 0.254)
		(layer "F.Cu")
		(net "GND")
	)
	(segment
		(start 18.54835 -12.37488)
		(end 18.54835 -12.374118)
		(width 0.3556)
		(layer "F.Cu")
		(net "GND")
	)
	(segment
		(start 370.057934 -237.460028)
		(end 370.524786 -237.19409)
		(width 0.350012)
		(layer "F.Cu")
		(net "GND")
	)
	(segment
		(start 369.417854 -290.019994)
		(end 369.884706 -290.285932)
		(width 0.350012)
		(layer "F.Cu")
		(net "GND")
	)
	(segment
		(start 97.990152 -384.617722)
		(end 97.398332 -384.617722)
		(width 0.254)
		(layer "F.Cu")
		(net "GND")
	)
	(segment
		(start 115.067842 -239.8903)
		(end 115.534694 -239.624362)
		(width 0.350012)
		(layer "F.Cu")
		(net "GND")
	)
	(segment
		(start 381.338074 -234.220004)
		(end 381.804926 -233.954066)
		(width 0.350012)
		(layer "F.Cu")
		(net "GND")
	)
	(segment
		(start 38.45687 -7.217156)
		(end 38.45687 -8.320024)
		(width 0.3556)
		(layer "F.Cu")
		(net "GND")
	)
	(segment
		(start 374.75795 -237.460028)
		(end 375.224802 -237.19409)
		(width 0.350012)
		(layer "F.Cu")
		(net "GND")
	)
	(segment
		(start 217.062812 -27.76347)
		(end 216.811098 -28.015184)
		(width 0.3556)
		(layer "F.Cu")
		(net "GND")
	)
	(segment
		(start 366.128046 -269.770098)
		(end 366.594898 -270.036036)
		(width 0.350012)
		(layer "F.Cu")
		(net "GND")
	)
	(segment
		(start 355.362002 -392.913108)
		(end 355.142292 -392.913108)
		(width 0.254)
		(layer "F.Cu")
		(net "GND")
	)
	(segment
		(start 100.027994 -243.130324)
		(end 99.561142 -242.864386)
		(width 0.350012)
		(layer "F.Cu")
		(net "GND")
	)
	(segment
		(start 113.721134 -389.030972)
		(end 113.721134 -388.330948)
		(width 0.254)
		(layer "F.Cu")
		(net "GND")
	)
	(segment
		(start 78.877922 -253.660402)
		(end 78.41107 -253.394464)
		(width 0.350012)
		(layer "F.Cu")
		(net "GND")
	)
	(segment
		(start 143.567912 -279.490424)
		(end 144.034764 -279.756362)
		(width 0.350012)
		(layer "F.Cu")
		(net "GND")
	)
	(segment
		(start 110.83798 -239.080294)
		(end 110.371128 -238.814356)
		(width 0.350012)
		(layer "F.Cu")
		(net "GND")
	)
	(segment
		(start 117.247924 -266.530328)
		(end 117.714776 -266.796266)
		(width 0.350012)
		(layer "F.Cu")
		(net "GND")
	)
	(segment
		(start 353.437952 -278.680164)
		(end 352.9711 -278.946102)
		(width 0.350012)
		(layer "F.Cu")
		(net "GND")
	)
	(segment
		(start 419.912038 -315.485018)
		(end 421.296338 -315.485018)
		(width 0.4572)
		(layer "F.Cu")
		(net "GND")
	)
	(segment
		(start 253.413006 -69.596508)
		(end 252.778006 -69.596508)
		(width 0.4572)
		(layer "F.Cu")
		(net "GND")
	)
	(segment
		(start 103.617776 -291.64026)
		(end 103.151178 -291.906198)
		(width 0.350012)
		(layer "F.Cu")
		(net "GND")
	)
	(segment
		(start 333.39786 -234.220004)
		(end 332.931008 -233.954066)
		(width 0.350012)
		(layer "F.Cu")
		(net "GND")
	)
	(segment
		(start 425.96562 -7.215886)
		(end 425.96689 -7.217156)
		(width 0.3556)
		(layer "F.Cu")
		(net "GND")
	)
	(segment
		(start 289.17392 -399.286984)
		(end 289.00501 -399.286984)
		(width 0.254)
		(layer "F.Cu")
		(net "GND")
	)
	(segment
		(start 140.748004 -294.070278)
		(end 141.214856 -294.336216)
		(width 0.350012)
		(layer "F.Cu")
		(net "GND")
	)
	(segment
		(start 142.797784 -235.84027)
		(end 143.264636 -235.574332)
		(width 0.350012)
		(layer "F.Cu")
		(net "GND")
	)
	(segment
		(start 368.64798 -244.750082)
		(end 369.114832 -244.484144)
		(width 0.350012)
		(layer "F.Cu")
		(net "GND")
	)
	(segment
		(start 95.327978 -241.510312)
		(end 94.861126 -241.244374)
		(width 0.350012)
		(layer "F.Cu")
		(net "GND")
	)
	(segment
		(start 362.067856 -238.270034)
		(end 362.534708 -238.004096)
		(width 0.350012)
		(layer "F.Cu")
		(net "GND")
	)
	(segment
		(start 82.467958 -294.070278)
		(end 82.001106 -294.336216)
		(width 0.350012)
		(layer "F.Cu")
		(net "GND")
	)
	(segment
		(start 344.977974 -283.5402)
		(end 344.511122 -283.806138)
		(width 0.350012)
		(layer "F.Cu")
		(net "GND")
	)
	(segment
		(start 328.227944 -246.370094)
		(end 327.761092 -246.104156)
		(width 0.350012)
		(layer "F.Cu")
		(net "GND")
	)
	(segment
		(start 192.322196 -118.652798)
		(end 192.712086 -119.042688)
		(width 0.254)
		(layer "F.Cu")
		(net "GND")
	)
	(segment
		(start 113.970562 -384.617722)
		(end 114.562382 -384.617722)
		(width 0.254)
		(layer "F.Cu")
		(net "GND")
	)
	(segment
		(start 54.591204 -390.160002)
		(end 54.070504 -390.160002)
		(width 0.254)
		(layer "F.Cu")
		(net "GND")
	)
	(segment
		(start 386.03809 -250.420124)
		(end 386.504942 -250.154186)
		(width 0.350012)
		(layer "F.Cu")
		(net "GND")
	)
	(segment
		(start 136.687814 -252.850396)
		(end 137.154666 -252.584458)
		(width 0.350012)
		(layer "F.Cu")
		(net "GND")
	)
	(segment
		(start 199.202294 -376.440446)
		(end 195.88988 -376.440446)
		(width 0.4572)
		(layer "F.Cu")
		(net "GND")
	)
	(segment
		(start 95.627952 -263.290304)
		(end 95.1611 -263.556242)
		(width 0.350012)
		(layer "F.Cu")
		(net "GND")
	)
	(segment
		(start 360.957876 -280.300176)
		(end 361.424728 -280.566114)
		(width 0.350012)
		(layer "F.Cu")
		(net "GND")
	)
	(segment
		(start 84.047838 -226.930458)
		(end 83.580986 -226.66452)
		(width 0.350012)
		(layer "F.Cu")
		(net "GND")
	)
	(segment
		(start 385.299204 -63.3095)
		(end 385.178808 -63.429896)
		(width 0.4572)
		(layer "F.Cu")
		(net "GND")
	)
	(segment
		(start 356.25786 -278.680164)
		(end 355.791008 -278.946102)
		(width 0.350012)
		(layer "F.Cu")
		(net "GND")
	)
	(segment
		(start 438.056782 -439.52541)
		(end 437.425846 -439.52541)
		(width 0.381)
		(layer "F.Cu")
		(net "GND")
	)
	(segment
		(start 372.407942 -251.23013)
		(end 372.874794 -250.964192)
		(width 0.350012)
		(layer "F.Cu")
		(net "GND")
	)
	(segment
		(start 371.297962 -293.260018)
		(end 371.764814 -293.525956)
		(width 0.350012)
		(layer "F.Cu")
		(net "GND")
	)
	(segment
		(start 160.290002 -384.617722)
		(end 159.698182 -384.617722)
		(width 0.254)
		(layer "F.Cu")
		(net "GND")
	)
	(segment
		(start 126.177802 -267.340334)
		(end 126.644654 -267.606272)
		(width 0.350012)
		(layer "F.Cu")
		(net "GND")
	)
	(segment
		(start 338.868004 -264.910062)
		(end 338.401152 -265.176)
		(width 0.350012)
		(layer "F.Cu")
		(net "GND")
	)
	(segment
		(start 123.21794 -391.281158)
		(end 123.517914 -390.761474)
		(width 0.254)
		(layer "F.Cu")
		(net "GND")
	)
	(segment
		(start 304.3555 -403.20976)
		(end 303.816258 -402.670518)
		(width 0.381)
		(layer "F.Cu")
		(net "GND")
	)
	(segment
		(start 103.617776 -293.260272)
		(end 103.151178 -293.52621)
		(width 0.350012)
		(layer "F.Cu")
		(net "GND")
	)
	(segment
		(start 370.817902 -399.663158)
		(end 370.916454 -399.76171)
		(width 0.254)
		(layer "F.Cu")
		(net "GND")
	)
	(segment
		(start 130.718052 -390.761474)
		(end 130.77063 -390.160002)
		(width 0.254)
		(layer "F.Cu")
		(net "GND")
	)
	(segment
		(start 268.99997 -124.469398)
		(end 268.99997 -125.104398)
		(width 0.381)
		(layer "F.Cu")
		(net "GND")
	)
	(segment
		(start 338.56803 -228.550216)
		(end 338.101178 -228.284278)
		(width 0.350012)
		(layer "F.Cu")
		(net "GND")
	)
	(segment
		(start 81.798414 -388.138924)
		(end 81.246218 -388.328662)
		(width 0.254)
		(layer "F.Cu")
		(net "GND")
	)
	(segment
		(start 361.128056 -244.750082)
		(end 361.594908 -244.484144)
		(width 0.350012)
		(layer "F.Cu")
		(net "GND")
	)
	(segment
		(start 402.045678 -7.215124)
		(end 402.045678 -7.215886)
		(width 0.3556)
		(layer "F.Cu")
		(net "GND")
	)
	(segment
		(start 315.717682 -392.004296)
		(end 316.017656 -392.30427)
		(width 0.254)
		(layer "F.Cu")
		(net "GND")
	)
	(segment
		(start 113.721134 -386.630926)
		(end 113.721134 -387.231128)
		(width 0.254)
		(layer "F.Cu")
		(net "GND")
	)
	(segment
		(start 79.177896 -265.720322)
		(end 78.711044 -265.98626)
		(width 0.350012)
		(layer "F.Cu")
		(net "GND")
	)
	(segment
		(start 352.197924 -229.360222)
		(end 351.731072 -229.094284)
		(width 0.350012)
		(layer "F.Cu")
		(net "GND")
	)
	(segment
		(start 392.587988 -180.151786)
		(end 392.490706 -180.386736)
		(width 0.2286)
		(layer "F.Cu")
		(net "GND")
	)
	(segment
		(start 191.160146 -230.485442)
		(end 189.775846 -230.485442)
		(width 0.4572)
		(layer "F.Cu")
		(net "GND")
	)
	(segment
		(start 337.798156 -396.520924)
		(end 337.24596 -396.710662)
		(width 0.254)
		(layer "F.Cu")
		(net "GND")
	)
	(segment
		(start 391.208006 -251.23013)
		(end 391.674858 -250.964192)
		(width 0.350012)
		(layer "F.Cu")
		(net "GND")
	)
	(segment
		(start 319.67043 -398.542002)
		(end 318.99098 -398.542002)
		(width 0.254)
		(layer "F.Cu")
		(net "GND")
	)
	(segment
		(start 79.114904 -394.954506)
		(end 79.114904 -394.352018)
		(width 0.254)
		(layer "F.Cu")
		(net "GND")
	)
	(segment
		(start 136.10717 -153.465784)
		(end 136.076182 -153.465784)
		(width 0.2286)
		(layer "F.Cu")
		(net "GND")
	)
	(segment
		(start 139.80795 -290.830254)
		(end 140.274802 -291.096192)
		(width 0.350012)
		(layer "F.Cu")
		(net "GND")
	)
	(segment
		(start 320.817748 -399.143474)
		(end 320.870326 -398.542002)
		(width 0.254)
		(layer "F.Cu")
		(net "GND")
	)
	(segment
		(start 202.036934 -337.480148)
		(end 202.036934 -338.139278)
		(width 0.381)
		(layer "F.Cu")
		(net "GND")
	)
	(segment
		(start 143.740632 -98.355658)
		(end 142.800832 -98.355658)
		(width 0.3556)
		(layer "F.Cu")
		(net "GND")
	)
	(segment
		(start 104.469946 -55.282084)
		(end 104.469946 -55.803546)
		(width 0.4572)
		(layer "F.Cu")
		(net "GND")
	)
	(segment
		(start 384.157982 -248.800112)
		(end 384.624834 -248.534174)
		(width 0.350012)
		(layer "F.Cu")
		(net "GND")
	)
	(segment
		(start 402.145754 -391.340086)
		(end 402.096224 -391.290556)
		(width 0.254)
		(layer "F.Cu")
		(net "GND")
	)
	(segment
		(start 315.717682 -399.663158)
		(end 316.017656 -399.143474)
		(width 0.254)
		(layer "F.Cu")
		(net "GND")
	)
	(segment
		(start 366.297972 -250.420124)
		(end 366.764824 -250.154186)
		(width 0.350012)
		(layer "F.Cu")
		(net "GND")
	)
	(segment
		(start 105.222548 -387.206998)
		(end 105.058464 -387.602984)
		(width 0.254)
		(layer "F.Cu")
		(net "GND")
	)
	(segment
		(start 387.448044 -226.930204)
		(end 387.914896 -226.664266)
		(width 0.350012)
		(layer "F.Cu")
		(net "GND")
	)
	(segment
		(start 322.31457 -396.213076)
		(end 322.53428 -396.213076)
		(width 0.254)
		(layer "F.Cu")
		(net "GND")
	)
	(segment
		(start 90.157808 -229.360476)
		(end 89.690956 -229.094538)
		(width 0.350012)
		(layer "F.Cu")
		(net "GND")
	)
	(segment
		(start 443.982602 -417.77666)
		(end 443.982602 -417.05911)
		(width 0.381)
		(layer "F.Cu")
		(net "GND")
	)
	(segment
		(start 55.862474 -384.617722)
		(end 56.47055 -384.617722)
		(width 0.254)
		(layer "F.Cu")
		(net "GND")
	)
	(segment
		(start 391.845038 -143.551148)
		(end 392.67384 -143.551148)
		(width 0.4572)
		(layer "F.Cu")
		(net "GND")
	)
	(segment
		(start 416.289998 -392.999722)
		(end 416.898328 -392.999722)
		(width 0.254)
		(layer "F.Cu")
		(net "GND")
	)
	(segment
		(start 167.79621 -394.0937)
		(end 167.79621 -393.781788)
		(width 0.254)
		(layer "F.Cu")
		(net "GND")
	)
	(segment
		(start 424.166792 -10.16635)
		(end 424.165522 -10.16508)
		(width 0.3556)
		(layer "F.Cu")
		(net "GND")
	)
	(segment
		(start 139.977876 -252.04039)
		(end 140.444728 -251.774452)
		(width 0.350012)
		(layer "F.Cu")
		(net "GND")
	)
	(segment
		(start 403.846792 -12.372848)
		(end 403.846792 -11.26998)
		(width 0.3556)
		(layer "F.Cu")
		(net "GND")
	)
	(segment
		(start 450.088 -212.635084)
		(end 451.4723 -212.635084)
		(width 0.4572)
		(layer "F.Cu")
		(net "GND")
	)
	(segment
		(start 398.446752 -12.372848)
		(end 398.446752 -11.26998)
		(width 0.3556)
		(layer "F.Cu")
		(net "GND")
	)
	(segment
		(start 101.907848 -251.230384)
		(end 101.440996 -250.964446)
		(width 0.350012)
		(layer "F.Cu")
		(net "GND")
	)
	(segment
		(start 43.85691 -12.372848)
		(end 43.85691 -11.26998)
		(width 0.3556)
		(layer "F.Cu")
		(net "GND")
	)
	(segment
		(start 72.662034 -11.26998)
		(end 72.662034 -12.372848)
		(width 0.3556)
		(layer "F.Cu")
		(net "GND")
	)
	(segment
		(start 156.96819 -96.412558)
		(end 156.30779 -96.412558)
		(width 0.4064)
		(layer "F.Cu")
		(net "GND")
	)
	(segment
		(start 164.343588 -128.890014)
		(end 164.608764 -128.890014)
		(width 0.381)
		(layer "F.Cu")
		(net "GND")
	)
	(segment
		(start 108.487972 -231.79024)
		(end 108.02112 -231.524302)
		(width 0.350012)
		(layer "F.Cu")
		(net "GND")
	)
	(segment
		(start 279.113742 -124.305314)
		(end 278.504142 -124.305314)
		(width 0.381)
		(layer "F.Cu")
		(net "GND")
	)
	(segment
		(start 339.738208 -338.089748)
		(end 340.308692 -337.519264)
		(width 0.2286)
		(layer "F.Cu")
		(net "GND")
	)
	(segment
		(start 156.09824 -388.138924)
		(end 155.546298 -388.328662)
		(width 0.254)
		(layer "F.Cu")
		(net "GND")
	)
	(segment
		(start 136.687814 -226.930458)
		(end 137.154666 -226.66452)
		(width 0.350012)
		(layer "F.Cu")
		(net "GND")
	)
	(segment
		(start 441.776866 -403.238462)
		(end 441.758324 -403.21992)
		(width 0.254)
		(layer "F.Cu")
		(net "GND")
	)
	(segment
		(start 66.534538 -387.831076)
		(end 66.834512 -388.13105)
		(width 0.254)
		(layer "F.Cu")
		(net "GND")
	)
	(segment
		(start 141.38783 -239.8903)
		(end 141.854682 -239.624362)
		(width 0.350012)
		(layer "F.Cu")
		(net "GND")
	)
	(segment
		(start 343.268046 -238.270034)
		(end 342.801194 -238.004096)
		(width 0.350012)
		(layer "F.Cu")
		(net "GND")
	)
	(segment
		(start 123.52782 -226.930458)
		(end 123.994672 -226.66452)
		(width 0.350012)
		(layer "F.Cu")
		(net "GND")
	)
	(segment
		(start 400.315684 -402.282152)
		(end 400.315684 -401.30476)
		(width 0.254)
		(layer "F.Cu")
		(net "GND")
	)
	(segment
		(start 371.938042 -229.360222)
		(end 372.404894 -229.094284)
		(width 0.350012)
		(layer "F.Cu")
		(net "GND")
	)
	(segment
		(start 90.627962 -252.850396)
		(end 90.16111 -252.584458)
		(width 0.350012)
		(layer "F.Cu")
		(net "GND")
	)
	(segment
		(start 350.618044 -285.160212)
		(end 350.151192 -285.42615)
		(width 0.350012)
		(layer "F.Cu")
		(net "GND")
	)
	(segment
		(start 21.70811 -314.635388)
		(end 20.32381 -314.635388)
		(width 0.4572)
		(layer "F.Cu")
		(net "GND")
	)
	(segment
		(start 431.55616 -305.28514)
		(end 430.17186 -305.28514)
		(width 0.4572)
		(layer "F.Cu")
		(net "GND")
	)
	(segment
		(start 321.391026 -398.542002)
		(end 320.870326 -398.542002)
		(width 0.254)
		(layer "F.Cu")
		(net "GND")
	)
	(segment
		(start 29.252164 -202.435206)
		(end 27.867864 -202.435206)
		(width 0.4572)
		(layer "F.Cu")
		(net "GND")
	)
	(segment
		(start 98.918014 -285.160466)
		(end 98.451162 -285.426404)
		(width 0.350012)
		(layer "F.Cu")
		(net "GND")
	)
	(segment
		(start 340.705948 -394.831062)
		(end 340.198202 -395.0208)
		(width 0.254)
		(layer "F.Cu")
		(net "GND")
	)
	(segment
		(start 126.817882 -383.402586)
		(end 126.817882 -383.622296)
		(width 0.254)
		(layer "F.Cu")
		(net "GND")
	)
	(segment
		(start 374.28805 -239.890046)
		(end 374.754902 -239.624108)
		(width 0.350012)
		(layer "F.Cu")
		(net "GND")
	)
	(segment
		(start 381.638048 -290.019994)
		(end 382.1049 -290.285932)
		(width 0.350012)
		(layer "F.Cu")
		(net "GND")
	)
	(segment
		(start 338.39785 -290.019994)
		(end 337.930998 -290.285932)
		(width 0.350012)
		(layer "F.Cu")
		(net "GND")
	)
	(segment
		(start 168.527984 -274.685252)
		(end 167.143684 -274.685252)
		(width 0.4572)
		(layer "F.Cu")
		(net "GND")
	)
	(segment
		(start 331.518006 -240.700052)
		(end 331.051154 -240.434114)
		(width 0.350012)
		(layer "F.Cu")
		(net "GND")
	)
	(segment
		(start 25.152096 -219.435426)
		(end 26.536396 -219.435426)
		(width 0.4572)
		(layer "F.Cu")
		(net "GND")
	)
	(segment
		(start 21.577046 -98.171508)
		(end 22.23008 -98.171508)
		(width 0.3556)
		(layer "F.Cu")
		(net "GND")
	)
	(segment
		(start 366.297972 -227.74021)
		(end 366.764824 -227.474272)
		(width 0.350012)
		(layer "F.Cu")
		(net "GND")
	)
	(segment
		(start 380.770638 -395.0208)
		(end 380.078488 -394.831062)
		(width 0.254)
		(layer "F.Cu")
		(net "GND")
	)
	(segment
		(start 327.117964 -291.640006)
		(end 326.651112 -291.905944)
		(width 0.350012)
		(layer "F.Cu")
		(net "GND")
	)
	(segment
		(start 381.982472 -177.532284)
		(end 381.394462 -177.532284)
		(width 0.381)
		(layer "F.Cu")
		(net "GND")
	)
	(segment
		(start 98.617786 -235.84027)
		(end 98.150934 -235.574332)
		(width 0.350012)
		(layer "F.Cu")
		(net "GND")
	)
	(segment
		(start 133.69798 -268.960346)
		(end 134.164832 -269.226284)
		(width 0.350012)
		(layer "F.Cu")
		(net "GND")
	)
	(segment
		(start 194.604132 -284.885384)
		(end 195.988432 -284.885384)
		(width 0.4572)
		(layer "F.Cu")
		(net "GND")
	)
	(segment
		(start 378.347986 -289.209988)
		(end 378.814838 -289.475926)
		(width 0.350012)
		(layer "F.Cu")
		(net "GND")
	)
	(segment
		(start 360.957876 -278.680164)
		(end 361.424728 -278.946102)
		(width 0.350012)
		(layer "F.Cu")
		(net "GND")
	)
	(segment
		(start 346.71889 -398.542002)
		(end 346.19819 -398.542002)
		(width 0.254)
		(layer "F.Cu")
		(net "GND")
	)
	(segment
		(start 140.27785 -264.10031)
		(end 140.744702 -264.366248)
		(width 0.350012)
		(layer "F.Cu")
		(net "GND")
	)
	(segment
		(start 338.39785 -286.780224)
		(end 337.931506 -287.045654)
		(width 0.350012)
		(layer "F.Cu")
		(net "GND")
	)
	(segment
		(start 117.41785 -247.180354)
		(end 117.884702 -246.914416)
		(width 0.350012)
		(layer "F.Cu")
		(net "GND")
	)
	(segment
		(start 442.5442 -287.435036)
		(end 443.9285 -287.435036)
		(width 0.4572)
		(layer "F.Cu")
		(net "GND")
	)
	(segment
		(start 450.088 -312.935112)
		(end 451.4723 -312.935112)
		(width 0.4572)
		(layer "F.Cu")
		(net "GND")
	)
	(segment
		(start 119.917972 -390.761474)
		(end 119.97055 -390.160002)
		(width 0.254)
		(layer "F.Cu")
		(net "GND")
	)
	(segment
		(start 100.027994 -249.610372)
		(end 99.561142 -249.344434)
		(width 0.350012)
		(layer "F.Cu")
		(net "GND")
	)
	(segment
		(start 47.816516 -391.37971)
		(end 47.816516 -391.830814)
		(width 0.254)
		(layer "F.Cu")
		(net "GND")
	)
	(segment
		(start 112.717834 -250.420378)
		(end 113.184686 -250.15444)
		(width 0.350012)
		(layer "F.Cu")
		(net "GND")
	)
	(segment
		(start 115.067842 -243.130324)
		(end 115.534694 -242.864386)
		(width 0.350012)
		(layer "F.Cu")
		(net "GND")
	)
	(segment
		(start 391.715244 -401.717002)
		(end 391.890504 -401.892262)
		(width 0.254)
		(layer "F.Cu")
		(net "GND")
	)
	(segment
		(start 47.717964 -383.402586)
		(end 47.717964 -382.951482)
		(width 0.254)
		(layer "F.Cu")
		(net "GND")
	)
	(segment
		(start 420.145718 -392.004296)
		(end 420.445692 -392.30427)
		(width 0.254)
		(layer "F.Cu")
		(net "GND")
	)
	(segment
		(start 100.647754 -342.018366)
		(end 100.901754 -341.764366)
		(width 0.2286)
		(layer "F.Cu")
		(net "GND")
	)
	(segment
		(start 404.898352 -396.520924)
		(end 404.346156 -396.710662)
		(width 0.254)
		(layer "F.Cu")
		(net "GND")
	)
	(segment
		(start 310.917844 -391.784586)
		(end 310.917844 -392.004296)
		(width 0.254)
		(layer "F.Cu")
		(net "GND")
	)
	(segment
		(start 389.327898 -244.750082)
		(end 389.79475 -244.484144)
		(width 0.350012)
		(layer "F.Cu")
		(net "GND")
	)
	(segment
		(start 431.36693 -8.320024)
		(end 431.36693 -9.423654)
		(width 0.3556)
		(layer "F.Cu")
		(net "GND")
	)
	(segment
		(start 256.842006 -125.38837)
		(end 256.232406 -125.38837)
		(width 0.381)
		(layer "F.Cu")
		(net "GND")
	)
	(segment
		(start 374.75795 -227.74021)
		(end 375.224802 -227.474272)
		(width 0.350012)
		(layer "F.Cu")
		(net "GND")
	)
	(segment
		(start 368.478054 -273.820128)
		(end 368.944906 -274.086066)
		(width 0.350012)
		(layer "F.Cu")
		(net "GND")
	)
	(segment
		(start 374.75795 -234.220004)
		(end 375.224802 -233.954066)
		(width 0.350012)
		(layer "F.Cu")
		(net "GND")
	)
	(segment
		(start 443.35319 -30.365954)
		(end 443.344554 -30.37459)
		(width 0.254)
		(layer "F.Cu")
		(net "GND")
	)
	(segment
		(start 176.072038 -211.7852)
		(end 174.687738 -211.7852)
		(width 0.4572)
		(layer "F.Cu")
		(net "GND")
	)
	(segment
		(start 51.884072 -202.435206)
		(end 50.499772 -202.435206)
		(width 0.4572)
		(layer "F.Cu")
		(net "GND")
	)
	(segment
		(start 149.7457 -391.281158)
		(end 150.045674 -390.761474)
		(width 0.254)
		(layer "F.Cu")
		(net "GND")
	)
	(segment
		(start 23.946866 -8.320024)
		(end 23.946866 -9.423654)
		(width 0.3556)
		(layer "F.Cu")
		(net "GND")
	)
	(segment
		(start 185.663332 -16.551148)
		(end 185.663332 -18.037556)
		(width 0.3556)
		(layer "F.Cu")
		(net "GND")
	)
	(segment
		(start 331.253592 -142.79753)
		(end 331.253592 -142.293086)
		(width 0.254)
		(layer "F.Cu")
		(net "GND")
	)
	(segment
		(start 83.557364 -138.562334)
		(end 83.557364 -139.19962)
		(width 0.4572)
		(layer "F.Cu")
		(net "GND")
	)
	(segment
		(start 55.328058 -315.485272)
		(end 56.712358 -315.485272)
		(width 0.4572)
		(layer "F.Cu")
		(net "GND")
	)
	(segment
		(start 20.25396 -360.521758)
		(end 20.25396 -360.341926)
		(width 0.381)
		(layer "F.Cu")
		(net "GND")
	)
	(segment
		(start 197.77583 -106.64571)
		(end 198.325232 -106.64571)
		(width 0.4572)
		(layer "F.Cu")
		(net "GND")
	)
	(segment
		(start 357.668068 -268.150086)
		(end 357.201216 -268.416024)
		(width 0.350012)
		(layer "F.Cu")
		(net "GND")
	)
	(segment
		(start 85.757766 -265.720322)
		(end 85.290914 -265.98626)
		(width 0.350012)
		(layer "F.Cu")
		(net "GND")
	)
	(segment
		(start 166.912798 -437.423052)
		(end 166.921942 -437.432196)
		(width 0.381)
		(layer "F.Cu")
		(net "GND")
	)
	(segment
		(start 102.45217 -381.7874)
		(end 102.695248 -381.7874)
		(width 0.254)
		(layer "F.Cu")
		(net "GND")
	)
	(segment
		(start 133.576822 -387.069076)
		(end 133.41477 -387.231128)
		(width 0.254)
		(layer "F.Cu")
		(net "GND")
	)
	(segment
		(start 308.517798 -392.004296)
		(end 308.817772 -392.30427)
		(width 0.2032)
		(layer "F.Cu")
		(net "GND")
	)
	(segment
		(start 330.938632 -411.140656)
		(end 331.352398 -411.140656)
		(width 0.381)
		(layer "F.Cu")
		(net "GND")
	)
	(segment
		(start 331.977492 -337.468464)
		(end 331.977492 -337.05165)
		(width 0.2286)
		(layer "F.Cu")
		(net "GND")
	)
	(segment
		(start 386.338064 -264.100056)
		(end 386.804916 -264.365994)
		(width 0.350012)
		(layer "F.Cu")
		(net "GND")
	)
	(segment
		(start 305.614578 -348.794324)
		(end 305.867562 -348.54134)
		(width 0.2286)
		(layer "F.Cu")
		(net "GND")
	)
	(segment
		(start 354.842318 -393.59332)
		(end 355.362002 -394.113004)
		(width 0.254)
		(layer "F.Cu")
		(net "GND")
	)
	(segment
		(start 135.107934 -271.390364)
		(end 135.574786 -271.656302)
		(width 0.350012)
		(layer "F.Cu")
		(net "GND")
	)
	(segment
		(start 391.208006 -228.550216)
		(end 391.674858 -228.284278)
		(width 0.350012)
		(layer "F.Cu")
		(net "GND")
	)
	(segment
		(start 65.975992 -403.830536)
		(end 65.975992 -402.947886)
		(width 0.381)
		(layer "F.Cu")
		(net "GND")
	)
	(segment
		(start 141.38783 -235.030264)
		(end 141.854682 -234.764326)
		(width 0.350012)
		(layer "F.Cu")
		(net "GND")
	)
	(segment
		(start 412.958026 -12.37488)
		(end 412.958026 -12.374118)
		(width 0.3556)
		(layer "F.Cu")
		(net "GND")
	)
	(segment
		(start 413.044132 -399.76171)
		(end 412.94558 -399.663158)
		(width 0.254)
		(layer "F.Cu")
		(net "GND")
	)
	(segment
		(start 335.045558 -391.784586)
		(end 335.045558 -392.004296)
		(width 0.254)
		(layer "F.Cu")
		(net "GND")
	)
	(segment
		(start 16.451834 -394.428726)
		(end 17.067784 -394.428726)
		(width 0.254)
		(layer "F.Cu")
		(net "GND")
	)
	(segment
		(start 99.857814 -290.020248)
		(end 99.390962 -290.286186)
		(width 0.350012)
		(layer "F.Cu")
		(net "GND")
	)
	(segment
		(start 167.800782 -349.265494)
		(end 168.075102 -348.991174)
		(width 0.381)
		(layer "F.Cu")
		(net "GND")
	)
	(segment
		(start 139.80795 -285.970472)
		(end 140.274802 -286.23641)
		(width 0.350012)
		(layer "F.Cu")
		(net "GND")
	)
	(segment
		(start 355.00437 -395.451076)
		(end 354.842318 -395.613128)
		(width 0.254)
		(layer "F.Cu")
		(net "GND")
	)
	(segment
		(start 363.778038 -268.960092)
		(end 364.24489 -269.22603)
		(width 0.350012)
		(layer "F.Cu")
		(net "GND")
	)
	(segment
		(start 259.131308 -136.703054)
		(end 259.762244 -136.703054)
		(width 0.381)
		(layer "F.Cu")
		(net "GND")
	)
	(segment
		(start 355.957886 -232.599992)
		(end 355.491034 -232.334054)
		(width 0.350012)
		(layer "F.Cu")
		(net "GND")
	)
	(segment
		(start 386.03809 -245.560088)
		(end 386.504942 -245.29415)
		(width 0.350012)
		(layer "F.Cu")
		(net "GND")
	)
	(segment
		(start 412.367984 -231.335072)
		(end 413.752284 -231.335072)
		(width 0.4572)
		(layer "F.Cu")
		(net "GND")
	)
	(segment
		(start 341.989918 -392.999722)
		(end 342.597994 -392.999722)
		(width 0.254)
		(layer "F.Cu")
		(net "GND")
	)
	(segment
		(start 61.139832 -52.743354)
		(end 61.711586 -52.743354)
		(width 0.381)
		(layer "F.Cu")
		(net "GND")
	)
	(segment
		(start 122.117866 -253.660402)
		(end 122.584718 -253.394464)
		(width 0.350012)
		(layer "F.Cu")
		(net "GND")
	)
	(segment
		(start 337.445604 -391.784586)
		(end 337.445604 -391.333482)
		(width 0.254)
		(layer "F.Cu")
		(net "GND")
	)
	(segment
		(start 418.18179 -160.702498)
		(end 417.703762 -161.180526)
		(width 0.2286)
		(layer "F.Cu")
		(net "GND")
	)
	(segment
		(start 178.289458 -48.299878)
		(end 177.108358 -48.299878)
		(width 0.254)
		(layer "F.Cu")
		(net "GND")
	)
	(segment
		(start 416.468052 -305.28514)
		(end 415.083752 -305.28514)
		(width 0.4572)
		(layer "F.Cu")
		(net "GND")
	)
	(segment
		(start 141.687804 -284.35046)
		(end 142.154656 -284.616398)
		(width 0.350012)
		(layer "F.Cu")
		(net "GND")
	)
	(segment
		(start 111.137954 -278.680418)
		(end 110.671102 -278.946356)
		(width 0.350012)
		(layer "F.Cu")
		(net "GND")
	)
	(segment
		(start 314.967366 -112.58677)
		(end 315.576966 -112.58677)
		(width 0.381)
		(layer "F.Cu")
		(net "GND")
	)
	(segment
		(start 17.608042 -238.135414)
		(end 18.992342 -238.135414)
		(width 0.4572)
		(layer "F.Cu")
		(net "GND")
	)
	(segment
		(start 123.05792 -235.84027)
		(end 123.524772 -235.574332)
		(width 0.350012)
		(layer "F.Cu")
		(net "GND")
	)
	(segment
		(start 108.044996 -403.92985)
		(end 108.044996 -404.061422)
		(width 0.381)
		(layer "F.Cu")
		(net "GND")
	)
	(segment
		(start 191.160146 -199.8853)
		(end 189.775846 -199.8853)
		(width 0.4572)
		(layer "F.Cu")
		(net "GND")
	)
	(segment
		(start 176.81067 -92.493846)
		(end 177.295556 -92.493846)
		(width 0.381)
		(layer "F.Cu")
		(net "GND")
	)
	(segment
		(start 138.397996 -277.060406)
		(end 138.864848 -277.326344)
		(width 0.350012)
		(layer "F.Cu")
		(net "GND")
	)
	(segment
		(start 350.421702 -155.881832)
		(end 350.952054 -155.881832)
		(width 0.381)
		(layer "F.Cu")
		(net "GND")
	)
	(segment
		(start 178.289458 -54.299866)
		(end 177.108358 -54.299866)
		(width 0.254)
		(layer "F.Cu")
		(net "GND")
	)
	(segment
		(start 40.23995 -231.335326)
		(end 41.62425 -231.335326)
		(width 0.4572)
		(layer "F.Cu")
		(net "GND")
	)
	(segment
		(start 438.629552 -425.94911)
		(end 437.978042 -425.94911)
		(width 0.381)
		(layer "F.Cu")
		(net "GND")
	)
	(segment
		(start 107.078018 -229.360476)
		(end 106.611166 -229.094538)
		(width 0.350012)
		(layer "F.Cu")
		(net "GND")
	)
	(segment
		(start 79.14894 -390.231122)
		(end 79.918814 -390.231122)
		(width 0.254)
		(layer "F.Cu")
		(net "GND")
	)
	(segment
		(start 338.56803 -251.23013)
		(end 338.101178 -250.964192)
		(width 0.350012)
		(layer "F.Cu")
		(net "GND")
	)
	(segment
		(start 408.713178 -142.009368)
		(end 408.271726 -142.45082)
		(width 0.381)
		(layer "F.Cu")
		(net "GND")
	)
	(segment
		(start 442.740288 -364.49127)
		(end 442.740288 -363.781594)
		(width 0.4064)
		(layer "F.Cu")
		(net "GND")
	)
	(segment
		(start 224.72396 -81.287112)
		(end 224.72396 -80.264)
		(width 0.4572)
		(layer "F.Cu")
		(net "GND")
	)
	(segment
		(start 112.717834 -230.980234)
		(end 113.184686 -230.71455)
		(width 0.350012)
		(layer "F.Cu")
		(net "GND")
	)
	(segment
		(start 302.620934 -393.24915)
		(end 302.870362 -392.999722)
		(width 0.254)
		(layer "F.Cu")
		(net "GND")
	)
	(segment
		(start 52.63896 -351.932748)
		(end 53.22697 -351.932748)
		(width 0.381)
		(layer "F.Cu")
		(net "GND")
	)
	(segment
		(start 372.238016 -270.580104)
		(end 372.704868 -270.846042)
		(width 0.350012)
		(layer "F.Cu")
		(net "GND")
	)
	(segment
		(start 288.180018 -315.485018)
		(end 289.564318 -315.485018)
		(width 0.4572)
		(layer "F.Cu")
		(net "GND")
	)
	(segment
		(start 126.7206 -42.684192)
		(end 126.7206 -41.014396)
		(width 0.381)
		(layer "F.Cu")
		(net "GND")
	)
	(segment
		(start 273.092164 -219.435172)
		(end 274.476464 -219.435172)
		(width 0.4572)
		(layer "F.Cu")
		(net "GND")
	)
	(segment
		(start 136.946894 -16.549878)
		(end 136.948164 -16.551148)
		(width 0.3556)
		(layer "F.Cu")
		(net "GND")
	)
	(segment
		(start 368.17808 -250.420124)
		(end 368.644678 -250.154186)
		(width 0.350012)
		(layer "F.Cu")
		(net "GND")
	)
	(segment
		(start 302.817784 -399.143474)
		(end 302.51781 -399.663158)
		(width 0.254)
		(layer "F.Cu")
		(net "GND")
	)
	(segment
		(start 415.444178 -399.76171)
		(end 415.345626 -399.663158)
		(width 0.254)
		(layer "F.Cu")
		(net "GND")
	)
	(segment
		(start 45.657008 -10.16635)
		(end 45.655738 -10.16508)
		(width 0.3556)
		(layer "F.Cu")
		(net "GND")
	)
	(segment
		(start 140.3096 -402.755608)
		(end 140.3096 -403.678898)
		(width 0.381)
		(layer "F.Cu")
		(net "GND")
	)
	(segment
		(start 168.527984 -199.8853)
		(end 167.143684 -199.8853)
		(width 0.4572)
		(layer "F.Cu")
		(net "GND")
	)
	(segment
		(start 97.037906 -286.780478)
		(end 96.571054 -287.046162)
		(width 0.350012)
		(layer "F.Cu")
		(net "GND")
	)
	(segment
		(start 118.187978 -276.2504)
		(end 118.65483 -276.516338)
		(width 0.350012)
		(layer "F.Cu")
		(net "GND")
	)
	(segment
		(start 427.456092 -200.735184)
		(end 428.840392 -200.735184)
		(width 0.4572)
		(layer "F.Cu")
		(net "GND")
	)
	(segment
		(start 136.217914 -245.560342)
		(end 136.684766 -245.294404)
		(width 0.350012)
		(layer "F.Cu")
		(net "GND")
	)
	(segment
		(start 100.797868 -288.400236)
		(end 100.331016 -288.666174)
		(width 0.350012)
		(layer "F.Cu")
		(net "GND")
	)
	(segment
		(start 412.956756 -8.320024)
		(end 412.956756 -9.423654)
		(width 0.3556)
		(layer "F.Cu")
		(net "GND")
	)
	(segment
		(start 193.779902 -387.660642)
		(end 192.573402 -387.660642)
		(width 0.4572)
		(layer "F.Cu")
		(net "GND")
	)
	(segment
		(start 374.77065 -398.542002)
		(end 374.0912 -398.542002)
		(width 0.254)
		(layer "F.Cu")
		(net "GND")
	)
	(segment
		(start 93.10624 -386.449062)
		(end 92.59824 -386.6388)
		(width 0.254)
		(layer "F.Cu")
		(net "GND")
	)
	(segment
		(start 86.598252 -384.617722)
		(end 86.545674 -383.92227)
		(width 0.254)
		(layer "F.Cu")
		(net "GND")
	)
	(segment
		(start 110.6678 -273.010376)
		(end 110.200948 -273.276314)
		(width 0.350012)
		(layer "F.Cu")
		(net "GND")
	)
	(segment
		(start 9.949942 -51.364896)
		(end 11.512042 -51.364896)
		(width 0.4572)
		(layer "F.Cu")
		(net "GND")
	)
	(segment
		(start 216.788492 -20.569682)
		(end 216.788492 -23.017988)
		(width 0.3556)
		(layer "F.Cu")
		(net "GND")
	)
	(segment
		(start 284.736032 -277.235158)
		(end 283.351732 -277.235158)
		(width 0.4572)
		(layer "F.Cu")
		(net "GND")
	)
	(segment
		(start 141.857984 -250.420378)
		(end 142.324836 -250.15444)
		(width 0.350012)
		(layer "F.Cu")
		(net "GND")
	)
	(segment
		(start 385.933442 -138.170158)
		(end 386.06222 -138.04138)
		(width 0.381)
		(layer "F.Cu")
		(net "GND")
	)
	(segment
		(start 47.821088 -32.677608)
		(end 47.5615 -32.937196)
		(width 0.4572)
		(layer "F.Cu")
		(net "GND")
	)
	(segment
		(start 389.327898 -241.510058)
		(end 389.79475 -241.24412)
		(width 0.350012)
		(layer "F.Cu")
		(net "GND")
	)
	(segment
		(start 92.037916 -234.220258)
		(end 91.571064 -233.95432)
		(width 0.350012)
		(layer "F.Cu")
		(net "GND")
	)
	(segment
		(start 164.121084 -46.954948)
		(end 163.190174 -46.954948)
		(width 0.3556)
		(layer "F.Cu")
		(net "GND")
	)
	(segment
		(start 338.097876 -227.74021)
		(end 337.631024 -227.474272)
		(width 0.350012)
		(layer "F.Cu")
		(net "GND")
	)
	(segment
		(start 104.55783 -265.720322)
		(end 104.090978 -265.98626)
		(width 0.350012)
		(layer "F.Cu")
		(net "GND")
	)
	(segment
		(start 299.82414 -218.585034)
		(end 298.43984 -218.585034)
		(width 0.4572)
		(layer "F.Cu")
		(net "GND")
	)
	(segment
		(start 99.903788 -399.630138)
		(end 99.687888 -399.846038)
		(width 0.3302)
		(layer "F.Cu")
		(net "GND")
	)
	(segment
		(start 91.398344 -388.138924)
		(end 90.846148 -388.328662)
		(width 0.254)
		(layer "F.Cu")
		(net "GND")
	)
	(segment
		(start 144.037812 -268.960346)
		(end 144.504664 -269.226284)
		(width 0.350012)
		(layer "F.Cu")
		(net "GND")
	)
	(segment
		(start 131.517898 -240.700306)
		(end 131.98475 -240.434368)
		(width 0.350012)
		(layer "F.Cu")
		(net "GND")
	)
	(segment
		(start 368.17808 -224.500186)
		(end 368.644678 -224.234248)
		(width 0.350012)
		(layer "F.Cu")
		(net "GND")
	)
	(segment
		(start 165.645592 -383.92227)
		(end 165.345618 -383.402586)
		(width 0.254)
		(layer "F.Cu")
		(net "GND")
	)
	(segment
		(start 121.170446 -388.138924)
		(end 120.618504 -388.328662)
		(width 0.254)
		(layer "F.Cu")
		(net "GND")
	)
	(segment
		(start 121.762266 -384.617722)
		(end 122.370596 -384.617722)
		(width 0.254)
		(layer "F.Cu")
		(net "GND")
	)
	(segment
		(start 144.677892 -227.740464)
		(end 145.144744 -227.474526)
		(width 0.350012)
		(layer "F.Cu")
		(net "GND")
	)
	(segment
		(start 344.306144 -394.831062)
		(end 343.798144 -395.0208)
		(width 0.254)
		(layer "F.Cu")
		(net "GND")
	)
	(segment
		(start 378.817886 -293.260018)
		(end 379.284738 -293.525956)
		(width 0.350012)
		(layer "F.Cu")
		(net "GND")
	)
	(segment
		(start 165.0365 -419.7096)
		(end 165.0365 -419.25494)
		(width 0.3048)
		(layer "F.Cu")
		(net "GND")
	)
	(segment
		(start 133.227826 -276.2504)
		(end 133.694678 -276.516338)
		(width 0.350012)
		(layer "F.Cu")
		(net "GND")
	)
	(segment
		(start 380.86792 -223.69018)
		(end 381.334772 -223.424242)
		(width 0.350012)
		(layer "F.Cu")
		(net "GND")
	)
	(segment
		(start 415.345626 -399.663158)
		(end 415.6456 -399.143474)
		(width 0.254)
		(layer "F.Cu")
		(net "GND")
	)
	(segment
		(start 461.993996 -107.043728)
		(end 461.993996 -107.678728)
		(width 0.3556)
		(layer "F.Cu")
		(net "GND")
	)
	(segment
		(start 307.670454 -395.0208)
		(end 306.978304 -394.831062)
		(width 0.254)
		(layer "F.Cu")
		(net "GND")
	)
	(segment
		(start 40.23995 -240.68532)
		(end 41.62425 -240.68532)
		(width 0.4572)
		(layer "F.Cu")
		(net "GND")
	)
	(segment
		(start 123.827794 -261.670292)
		(end 124.294646 -261.93623)
		(width 0.350012)
		(layer "F.Cu")
		(net "GND")
	)
	(segment
		(start 150.945596 -383.622042)
		(end 151.245824 -383.92227)
		(width 0.2032)
		(layer "F.Cu")
		(net "GND")
	)
	(segment
		(start 429.570642 -352.965258)
		(end 429.142144 -352.965258)
		(width 0.2286)
		(layer "F.Cu")
		(net "GND")
	)
	(segment
		(start 50.216562 -391.830814)
		(end 50.216562 -391.37971)
		(width 0.254)
		(layer "F.Cu")
		(net "GND")
	)
	(segment
		(start 314.81776 -392.30427)
		(end 314.870338 -392.999722)
		(width 0.254)
		(layer "F.Cu")
		(net "GND")
	)
	(segment
		(start 123.997974 -232.600246)
		(end 124.464826 -232.334308)
		(width 0.350012)
		(layer "F.Cu")
		(net "GND")
	)
	(segment
		(start 341.218012 -293.260018)
		(end 340.75116 -293.525956)
		(width 0.350012)
		(layer "F.Cu")
		(net "GND")
	)
	(segment
		(start 347.968062 -239.890046)
		(end 347.50121 -239.624108)
		(width 0.350012)
		(layer "F.Cu")
		(net "GND")
	)
	(segment
		(start 115.067842 -231.79024)
		(end 115.534694 -231.524302)
		(width 0.350012)
		(layer "F.Cu")
		(net "GND")
	)
	(segment
		(start 55.270654 -384.617722)
		(end 55.862474 -384.617722)
		(width 0.254)
		(layer "F.Cu")
		(net "GND")
	)
	(segment
		(start 389.627872 -273.010122)
		(end 390.094724 -273.27606)
		(width 0.350012)
		(layer "F.Cu")
		(net "GND")
	)
	(segment
		(start 81.058004 -272.20037)
		(end 80.591152 -272.466308)
		(width 0.350012)
		(layer "F.Cu")
		(net "GND")
	)
	(segment
		(start 333.733394 -142.070582)
		(end 333.326994 -142.30477)
		(width 0.1778)
		(layer "F.Cu")
		(net "GND")
	)
	(segment
		(start 85.919056 -390.160002)
		(end 86.598252 -390.160002)
		(width 0.254)
		(layer "F.Cu")
		(net "GND")
	)
	(segment
		(start 194.604132 -306.135278)
		(end 195.988432 -306.135278)
		(width 0.4572)
		(layer "F.Cu")
		(net "GND")
	)
	(segment
		(start 403.698202 -396.520924)
		(end 403.14626 -396.710662)
		(width 0.254)
		(layer "F.Cu")
		(net "GND")
	)
	(segment
		(start 402.145754 -392.004296)
		(end 402.445728 -392.30427)
		(width 0.254)
		(layer "F.Cu")
		(net "GND")
	)
	(segment
		(start 394.327888 -294.070024)
		(end 394.79474 -294.335962)
		(width 0.350012)
		(layer "F.Cu")
		(net "GND")
	)
	(segment
		(start 83.877912 -283.540454)
		(end 83.41106 -283.806392)
		(width 0.350012)
		(layer "F.Cu")
		(net "GND")
	)
	(segment
		(start 82.645758 -391.281158)
		(end 82.945732 -390.761474)
		(width 0.254)
		(layer "F.Cu")
		(net "GND")
	)
	(segment
		(start 320.09842 -104.42575)
		(end 320.707258 -104.42575)
		(width 0.4572)
		(layer "F.Cu")
		(net "GND")
	)
	(segment
		(start 392.917934 -278.680164)
		(end 393.384786 -278.946102)
		(width 0.350012)
		(layer "F.Cu")
		(net "GND")
	)
	(segment
		(start 114.127788 -238.270288)
		(end 114.59464 -238.00435)
		(width 0.350012)
		(layer "F.Cu")
		(net "GND")
	)
	(segment
		(start 426.673264 -423.221912)
		(end 426.54855 -423.221912)
		(width 0.381)
		(layer "F.Cu")
		(net "GND")
	)
	(segment
		(start 111.581946 -55.282084)
		(end 111.581946 -55.891684)
		(width 0.4572)
		(layer "F.Cu")
		(net "GND")
	)
	(segment
		(start 394.327888 -287.59023)
		(end 394.982954 -287.59023)
		(width 0.350012)
		(layer "F.Cu")
		(net "GND")
	)
	(segment
		(start 365.657892 -277.060152)
		(end 366.124744 -277.32609)
		(width 0.350012)
		(layer "F.Cu")
		(net "GND")
	)
	(segment
		(start 128.891284 -390.160002)
		(end 128.370584 -390.160002)
		(width 0.254)
		(layer "F.Cu")
		(net "GND")
	)
	(segment
		(start 350.618044 -290.019994)
		(end 350.151192 -290.285932)
		(width 0.350012)
		(layer "F.Cu")
		(net "GND")
	)
	(segment
		(start 70.749414 -387.084062)
		(end 70.265798 -387.084062)
		(width 0.381)
		(layer "F.Cu")
		(net "GND")
	)
	(segment
		(start 406.945592 -391.333482)
		(end 407.044144 -391.23493)
		(width 0.2032)
		(layer "F.Cu")
		(net "GND")
	)
	(segment
		(start 29.345636 -7.215124)
		(end 29.345636 -7.215886)
		(width 0.3556)
		(layer "F.Cu")
		(net "GND")
	)
	(segment
		(start 378.048012 -225.310192)
		(end 378.514864 -225.044254)
		(width 0.350012)
		(layer "F.Cu")
		(net "GND")
	)
	(segment
		(start 358.607868 -287.59023)
		(end 358.141016 -287.856168)
		(width 0.350012)
		(layer "F.Cu")
		(net "GND")
	)
	(segment
		(start 319.416176 -400.212814)
		(end 319.416176 -399.76171)
		(width 0.254)
		(layer "F.Cu")
		(net "GND")
	)
	(segment
		(start 89.047828 -277.870412)
		(end 88.580976 -278.13635)
		(width 0.350012)
		(layer "F.Cu")
		(net "GND")
	)
	(segment
		(start 364.417864 -252.040136)
		(end 364.884716 -251.774198)
		(width 0.350012)
		(layer "F.Cu")
		(net "GND")
	)
	(segment
		(start 342.343994 -399.76171)
		(end 342.245442 -399.663158)
		(width 0.254)
		(layer "F.Cu")
		(net "GND")
	)
	(segment
		(start 78.877922 -234.220258)
		(end 78.41107 -233.95432)
		(width 0.350012)
		(layer "F.Cu")
		(net "GND")
	)
	(segment
		(start 139.507976 -252.850396)
		(end 139.974828 -252.584458)
		(width 0.350012)
		(layer "F.Cu")
		(net "GND")
	)
	(segment
		(start 221.49308 -104.9782)
		(end 221.49308 -104.42448)
		(width 0.381)
		(layer "F.Cu")
		(net "GND")
	)
	(segment
		(start 364.717838 -291.640006)
		(end 365.18469 -291.905944)
		(width 0.350012)
		(layer "F.Cu")
		(net "GND")
	)
	(segment
		(start 363.307884 -284.350206)
		(end 363.774736 -284.616144)
		(width 0.350012)
		(layer "F.Cu")
		(net "GND")
	)
	(segment
		(start 136.517888 -288.400236)
		(end 136.98474 -288.666174)
		(width 0.350012)
		(layer "F.Cu")
		(net "GND")
	)
	(segment
		(start 361.22229 -395.4399)
		(end 361.22229 -395.8209)
		(width 0.254)
		(layer "F.Cu")
		(net "GND")
	)
	(segment
		(start 354.078032 -229.360222)
		(end 353.61118 -229.094284)
		(width 0.350012)
		(layer "F.Cu")
		(net "GND")
	)
	(segment
		(start 110.149894 -172.91431)
		(end 110.49635 -172.91431)
		(width 0.3048)
		(layer "F.Cu")
		(net "GND")
	)
	(segment
		(start 372.318026 -399.143474)
		(end 372.018052 -399.663158)
		(width 0.254)
		(layer "F.Cu")
		(net "GND")
	)
	(segment
		(start 4.194048 -135.42137)
		(end 4.194048 -133.47065)
		(width 0.3556)
		(layer "F.Cu")
		(net "GND")
	)
	(segment
		(start 363.478064 -235.840016)
		(end 363.944916 -235.574078)
		(width 0.350012)
		(layer "F.Cu")
		(net "GND")
	)
	(segment
		(start 108.787946 -284.35046)
		(end 108.321094 -284.616398)
		(width 0.350012)
		(layer "F.Cu")
		(net "GND")
	)
	(segment
		(start 340.277958 -293.260018)
		(end 339.811106 -293.525956)
		(width 0.350012)
		(layer "F.Cu")
		(net "GND")
	)
	(segment
		(start 159.444182 -391.37971)
		(end 159.34563 -391.281158)
		(width 0.254)
		(layer "F.Cu")
		(net "GND")
	)
	(segment
		(start 394.027914 -247.990106)
		(end 394.68298 -247.990106)
		(width 0.350012)
		(layer "F.Cu")
		(net "GND")
	)
	(segment
		(start 107.078018 -235.84027)
		(end 106.611166 -235.574332)
		(width 0.350012)
		(layer "F.Cu")
		(net "GND")
	)
	(segment
		(start 299.82414 -305.28514)
		(end 298.43984 -305.28514)
		(width 0.4572)
		(layer "F.Cu")
		(net "GND")
	)
	(segment
		(start 90.157808 -243.94033)
		(end 89.690956 -243.674392)
		(width 0.350012)
		(layer "F.Cu")
		(net "GND")
	)
	(segment
		(start 427.766988 -8.320024)
		(end 427.766988 -9.423654)
		(width 0.3556)
		(layer "F.Cu")
		(net "GND")
	)
	(segment
		(start 347.706188 -344.87358)
		(end 347.706188 -345.192096)
		(width 0.381)
		(layer "F.Cu")
		(net "GND")
	)
	(segment
		(start 325.408036 -236.650022)
		(end 324.75297 -236.650022)
		(width 0.350012)
		(layer "F.Cu")
		(net "GND")
	)
	(segment
		(start 418.21354 -110.128558)
		(end 418.36594 -110.280958)
		(width 0.3556)
		(layer "F.Cu")
		(net "GND")
	)
	(segment
		(start 381.338074 -243.940076)
		(end 381.804926 -243.674138)
		(width 0.350012)
		(layer "F.Cu")
		(net "GND")
	)
	(segment
		(start 93.277944 -293.260272)
		(end 92.811092 -293.52621)
		(width 0.350012)
		(layer "F.Cu")
		(net "GND")
	)
	(segment
		(start 117.888004 -231.79024)
		(end 118.354856 -231.524302)
		(width 0.350012)
		(layer "F.Cu")
		(net "GND")
	)
	(segment
		(start 353.398074 -392.999722)
		(end 353.345496 -392.30427)
		(width 0.254)
		(layer "F.Cu")
		(net "GND")
	)
	(segment
		(start 84.047838 -256.09042)
		(end 83.580986 -255.824482)
		(width 0.350012)
		(layer "F.Cu")
		(net "GND")
	)
	(segment
		(start 85.457792 -240.700306)
		(end 84.99094 -240.434368)
		(width 0.350012)
		(layer "F.Cu")
		(net "GND")
	)
	(segment
		(start 139.25804 -112.026192)
		(end 139.409424 -111.874808)
		(width 0.381)
		(layer "F.Cu")
		(net "GND")
	)
	(segment
		(start 363.307884 -274.630134)
		(end 363.774736 -274.896072)
		(width 0.350012)
		(layer "F.Cu")
		(net "GND")
	)
	(segment
		(start 96.737932 -252.04039)
		(end 96.27108 -251.774452)
		(width 0.350012)
		(layer "F.Cu")
		(net "GND")
	)
	(segment
		(start 82.167984 -231.79024)
		(end 81.701132 -231.524302)
		(width 0.350012)
		(layer "F.Cu")
		(net "GND")
	)
	(segment
		(start 410.20619 -394.831062)
		(end 409.69819 -395.0208)
		(width 0.254)
		(layer "F.Cu")
		(net "GND")
	)
	(segment
		(start 402.045678 -7.215886)
		(end 402.046948 -7.217156)
		(width 0.3556)
		(layer "F.Cu")
		(net "GND")
	)
	(segment
		(start 90.927936 -264.910316)
		(end 90.461084 -265.176254)
		(width 0.350012)
		(layer "F.Cu")
		(net "GND")
	)
	(segment
		(start 136.517888 -277.060406)
		(end 136.98474 -277.326344)
		(width 0.350012)
		(layer "F.Cu")
		(net "GND")
	)
	(segment
		(start 165.698424 -390.160002)
		(end 166.373048 -390.160002)
		(width 0.254)
		(layer "F.Cu")
		(net "GND")
	)
	(segment
		(start 125.716538 -391.37971)
		(end 125.716538 -391.830814)
		(width 0.254)
		(layer "F.Cu")
		(net "GND")
	)
	(segment
		(start 341.687912 -281.110182)
		(end 341.22106 -281.37612)
		(width 0.350012)
		(layer "F.Cu")
		(net "GND")
	)
	(segment
		(start 414.14573 -391.333482)
		(end 414.244282 -391.23493)
		(width 0.254)
		(layer "F.Cu")
		(net "GND")
	)
	(segment
		(start 118.89105 -425.704)
		(end 119.01805 -425.704)
		(width 0.381)
		(layer "F.Cu")
		(net "GND")
	)
	(segment
		(start 338.56803 -252.850142)
		(end 338.101178 -252.584204)
		(width 0.350012)
		(layer "F.Cu")
		(net "GND")
	)
	(segment
		(start 333.697834 -291.640006)
		(end 333.230982 -291.905944)
		(width 0.350012)
		(layer "F.Cu")
		(net "GND")
	)
	(segment
		(start 120.618504 -388.328662)
		(end 119.97055 -388.138924)
		(width 0.254)
		(layer "F.Cu")
		(net "GND")
	)
	(segment
		(start 206.248 -218.585288)
		(end 204.8637 -218.585288)
		(width 0.4572)
		(layer "F.Cu")
		(net "GND")
	)
	(segment
		(start 318.47028 -396.520924)
		(end 317.918338 -396.710662)
		(width 0.254)
		(layer "F.Cu")
		(net "GND")
	)
	(segment
		(start 310.070246 -395.0208)
		(end 309.37835 -394.831062)
		(width 0.254)
		(layer "F.Cu")
		(net "GND")
	)
	(segment
		(start 355.31806 -293.260018)
		(end 354.851208 -293.525956)
		(width 0.350012)
		(layer "F.Cu")
		(net "GND")
	)
	(segment
		(start 409.018994 -398.542002)
		(end 408.498294 -398.542002)
		(width 0.254)
		(layer "F.Cu")
		(net "GND")
	)
	(segment
		(start 402.248878 -396.712948)
		(end 401.929346 -396.712948)
		(width 0.254)
		(layer "F.Cu")
		(net "GND")
	)
	(segment
		(start 95.327978 -247.99036)
		(end 94.861126 -247.724422)
		(width 0.350012)
		(layer "F.Cu")
		(net "GND")
	)
	(segment
		(start 144.315688 -392.92276)
		(end 144.469866 -392.768582)
		(width 0.254)
		(layer "F.Cu")
		(net "GND")
	)
	(segment
		(start 90.927936 -285.970472)
		(end 90.461084 -286.23641)
		(width 0.350012)
		(layer "F.Cu")
		(net "GND")
	)
	(segment
		(start 331.987906 -238.270034)
		(end 331.521054 -238.004096)
		(width 0.350012)
		(layer "F.Cu")
		(net "GND")
	)
	(segment
		(start 305.270408 -398.542002)
		(end 305.21783 -399.143474)
		(width 0.254)
		(layer "F.Cu")
		(net "GND")
	)
	(segment
		(start 339.977984 -234.220004)
		(end 339.511132 -233.954066)
		(width 0.350012)
		(layer "F.Cu")
		(net "GND")
	)
	(segment
		(start 128.52781 -285.970472)
		(end 128.994662 -286.23641)
		(width 0.350012)
		(layer "F.Cu")
		(net "GND")
	)
	(segment
		(start 229.203504 -151.752046)
		(end 229.203504 -151.042878)
		(width 0.381)
		(layer "F.Cu")
		(net "GND")
	)
	(segment
		(start 336.987896 -295.690036)
		(end 336.521044 -295.955974)
		(width 0.350012)
		(layer "F.Cu")
		(net "GND")
	)
	(segment
		(start 299.82414 -230.485188)
		(end 298.43984 -230.485188)
		(width 0.4572)
		(layer "F.Cu")
		(net "GND")
	)
	(segment
		(start 138.098022 -222.880428)
		(end 138.564874 -222.61449)
		(width 0.350012)
		(layer "F.Cu")
		(net "GND")
	)
	(segment
		(start 50.11801 -382.951482)
		(end 50.216562 -382.85293)
		(width 0.254)
		(layer "F.Cu")
		(net "GND")
	)
	(segment
		(start 142.797784 -243.94033)
		(end 143.264636 -243.674392)
		(width 0.350012)
		(layer "F.Cu")
		(net "GND")
	)
	(segment
		(start 378.048012 -231.789986)
		(end 378.514864 -231.524048)
		(width 0.350012)
		(layer "F.Cu")
		(net "GND")
	)
	(segment
		(start 307.368194 -199.885046)
		(end 305.983894 -199.885046)
		(width 0.4572)
		(layer "F.Cu")
		(net "GND")
	)
	(segment
		(start 328.527918 -290.83)
		(end 328.061066 -291.095938)
		(width 0.350012)
		(layer "F.Cu")
		(net "GND")
	)
	(segment
		(start 101.737922 -260.860286)
		(end 101.27107 -261.126224)
		(width 0.350012)
		(layer "F.Cu")
		(net "GND")
	)
	(segment
		(start 357.36784 -251.23013)
		(end 356.901242 -250.964192)
		(width 0.350012)
		(layer "F.Cu")
		(net "GND")
	)
	(segment
		(start 171.666916 -12.496292)
		(end 171.665646 -12.495022)
		(width 0.3556)
		(layer "F.Cu")
		(net "GND")
	)
	(segment
		(start 330.938632 -411.140656)
		(end 330.938632 -411.985714)
		(width 0.381)
		(layer "F.Cu")
		(net "GND")
	)
	(segment
		(start 113.017808 -291.64026)
		(end 113.48466 -291.906198)
		(width 0.350012)
		(layer "F.Cu")
		(net "GND")
	)
	(segment
		(start 314.967366 -113.60277)
		(end 315.576966 -113.60277)
		(width 0.381)
		(layer "F.Cu")
		(net "GND")
	)
	(segment
		(start 418.356796 -12.372848)
		(end 418.356796 -11.26998)
		(width 0.3556)
		(layer "F.Cu")
		(net "GND")
	)
	(segment
		(start 358.137968 -267.34008)
		(end 357.671116 -267.606018)
		(width 0.350012)
		(layer "F.Cu")
		(net "GND")
	)
	(segment
		(start 363.778038 -285.160212)
		(end 364.24489 -285.42615)
		(width 0.350012)
		(layer "F.Cu")
		(net "GND")
	)
	(segment
		(start 57.618122 -390.761474)
		(end 57.6707 -390.160002)
		(width 0.254)
		(layer "F.Cu")
		(net "GND")
	)
	(segment
		(start 341.918798 -398.542002)
		(end 341.398098 -398.542002)
		(width 0.254)
		(layer "F.Cu")
		(net "GND")
	)
	(segment
		(start 50.11801 -383.622296)
		(end 50.417984 -383.92227)
		(width 0.254)
		(layer "F.Cu")
		(net "GND")
	)
	(segment
		(start 389.201406 -392.999722)
		(end 389.201406 -392.387836)
		(width 0.254)
		(layer "F.Cu")
		(net "GND")
	)
	(segment
		(start 375.846848 -180.158898)
		(end 375.756678 -180.376576)
		(width 0.2286)
		(layer "F.Cu")
		(net "GND")
	)
	(segment
		(start 329.965304 -133.964172)
		(end 329.965304 -134.625842)
		(width 0.4572)
		(layer "F.Cu")
		(net "GND")
	)
	(segment
		(start 351.087944 -290.83)
		(end 350.621092 -291.095938)
		(width 0.350012)
		(layer "F.Cu")
		(net "GND")
	)
	(segment
		(start 356.728014 -285.970218)
		(end 356.261162 -286.236156)
		(width 0.350012)
		(layer "F.Cu")
		(net "GND")
	)
	(segment
		(start 376.467878 -277.870158)
		(end 376.93473 -278.136096)
		(width 0.350012)
		(layer "F.Cu")
		(net "GND")
	)
	(segment
		(start 109.728 -276.2504)
		(end 109.261148 -276.516338)
		(width 0.350012)
		(layer "F.Cu")
		(net "GND")
	)
	(segment
		(start 152.244298 -391.37971)
		(end 152.244298 -391.830814)
		(width 0.254)
		(layer "F.Cu")
		(net "GND")
	)
	(segment
		(start 51.884072 -199.8853)
		(end 50.499772 -199.8853)
		(width 0.4572)
		(layer "F.Cu")
		(net "GND")
	)
	(segment
		(start 384.457956 -283.5402)
		(end 384.924808 -283.806138)
		(width 0.350012)
		(layer "F.Cu")
		(net "GND")
	)
	(segment
		(start 143.098012 -293.260272)
		(end 143.56461 -293.52621)
		(width 0.350012)
		(layer "F.Cu")
		(net "GND")
	)
	(segment
		(start 123.997974 -250.420378)
		(end 124.464826 -250.15444)
		(width 0.350012)
		(layer "F.Cu")
		(net "GND")
	)
	(segment
		(start 126.478538 -386.449062)
		(end 125.970538 -386.6388)
		(width 0.254)
		(layer "F.Cu")
		(net "GND")
	)
	(segment
		(start 143.098012 -277.060406)
		(end 143.56461 -277.326344)
		(width 0.350012)
		(layer "F.Cu")
		(net "GND")
	)
	(segment
		(start 374.11787 -280.300176)
		(end 374.584722 -280.566114)
		(width 0.350012)
		(layer "F.Cu")
		(net "GND")
	)
	(segment
		(start 450.088 -210.085178)
		(end 451.4723 -210.085178)
		(width 0.4572)
		(layer "F.Cu")
		(net "GND")
	)
	(segment
		(start 419.992048 -354.18014)
		(end 420.431468 -353.74072)
		(width 0.2286)
		(layer "F.Cu")
		(net "GND")
	)
	(segment
		(start 416.468052 -312.084974)
		(end 415.083752 -312.084974)
		(width 0.4572)
		(layer "F.Cu")
		(net "GND")
	)
	(segment
		(start 97.207832 -243.130324)
		(end 96.74098 -242.864386)
		(width 0.350012)
		(layer "F.Cu")
		(net "GND")
	)
	(segment
		(start 139.977876 -227.740464)
		(end 140.444728 -227.474526)
		(width 0.350012)
		(layer "F.Cu")
		(net "GND")
	)
	(segment
		(start 379.75794 -277.060152)
		(end 380.224792 -277.32609)
		(width 0.350012)
		(layer "F.Cu")
		(net "GND")
	)
	(segment
		(start 335.277968 -226.120198)
		(end 334.811116 -225.85426)
		(width 0.350012)
		(layer "F.Cu")
		(net "GND")
	)
	(segment
		(start 419.912038 -228.785166)
		(end 421.296338 -228.785166)
		(width 0.4572)
		(layer "F.Cu")
		(net "GND")
	)
	(segment
		(start 166.462202 -384.531108)
		(end 166.242492 -384.531108)
		(width 0.254)
		(layer "F.Cu")
		(net "GND")
	)
	(segment
		(start 149.844252 -391.830814)
		(end 149.844252 -391.37971)
		(width 0.254)
		(layer "F.Cu")
		(net "GND")
	)
	(segment
		(start 403.848062 -12.37488)
		(end 403.848062 -12.374118)
		(width 0.3556)
		(layer "F.Cu")
		(net "GND")
	)
	(segment
		(start 125.234954 -30.642052)
		(end 125.0442 -30.832806)
		(width 0.4572)
		(layer "F.Cu")
		(net "GND")
	)
	(segment
		(start 48.070516 -390.160002)
		(end 47.391066 -390.160002)
		(width 0.254)
		(layer "F.Cu")
		(net "GND")
	)
	(segment
		(start 169.38879 -104.340152)
		(end 168.93159 -104.797352)
		(width 0.4572)
		(layer "F.Cu")
		(net "GND")
	)
	(segment
		(start 347.045534 -391.784586)
		(end 347.045534 -392.004296)
		(width 0.254)
		(layer "F.Cu")
		(net "GND")
	)
	(segment
		(start 330.408026 -266.530074)
		(end 329.941174 -266.796012)
		(width 0.350012)
		(layer "F.Cu")
		(net "GND")
	)
	(segment
		(start 398.676368 -75.518264)
		(end 398.676368 -74.883264)
		(width 0.3556)
		(layer "F.Cu")
		(net "GND")
	)
	(segment
		(start 331.987906 -225.310192)
		(end 331.521054 -225.044254)
		(width 0.350012)
		(layer "F.Cu")
		(net "GND")
	)
	(segment
		(start 77.467968 -223.690434)
		(end 77.001116 -223.424496)
		(width 0.350012)
		(layer "F.Cu")
		(net "GND")
	)
	(segment
		(start 92.59824 -390.160002)
		(end 93.11894 -390.160002)
		(width 0.254)
		(layer "F.Cu")
		(net "GND")
	)
	(segment
		(start 152.498298 -390.160002)
		(end 151.819102 -390.160002)
		(width 0.254)
		(layer "F.Cu")
		(net "GND")
	)
	(segment
		(start 102.207822 -264.910316)
		(end 101.74097 -265.176254)
		(width 0.350012)
		(layer "F.Cu")
		(net "GND")
	)
	(segment
		(start 366.297972 -230.97998)
		(end 366.764824 -230.714296)
		(width 0.350012)
		(layer "F.Cu")
		(net "GND")
	)
	(segment
		(start 340.277958 -283.5402)
		(end 339.811106 -283.806138)
		(width 0.350012)
		(layer "F.Cu")
		(net "GND")
	)
	(segment
		(start 382.91643 -399.76171)
		(end 382.817878 -399.663158)
		(width 0.254)
		(layer "F.Cu")
		(net "GND")
	)
	(segment
		(start 331.047852 -225.310192)
		(end 330.581 -225.044254)
		(width 0.350012)
		(layer "F.Cu")
		(net "GND")
	)
	(segment
		(start 87.3379 -256.900426)
		(end 86.871048 -256.634488)
		(width 0.350012)
		(layer "F.Cu")
		(net "GND")
	)
	(segment
		(start 335.195418 -25.737058)
		(end 335.195418 -26.727658)
		(width 0.4572)
		(layer "F.Cu")
		(net "GND")
	)
	(segment
		(start 178.289458 -43.800014)
		(end 177.108358 -43.800014)
		(width 0.254)
		(layer "F.Cu")
		(net "GND")
	)
	(segment
		(start 115.818412 -388.328662)
		(end 115.170458 -388.138924)
		(width 0.254)
		(layer "F.Cu")
		(net "GND")
	)
	(segment
		(start 102.021386 -386.84073)
		(end 102.264718 -387.084062)
		(width 0.381)
		(layer "F.Cu")
		(net "GND")
	)
	(segment
		(start 415.345626 -391.784586)
		(end 415.345626 -392.004296)
		(width 0.254)
		(layer "F.Cu")
		(net "GND")
	)
	(segment
		(start 369.72113 -396.712948)
		(end 369.401598 -396.712948)
		(width 0.254)
		(layer "F.Cu")
		(net "GND")
	)
	(segment
		(start 177.122074 -106.652822)
		(end 176.732184 -106.262932)
		(width 0.254)
		(layer "F.Cu")
		(net "GND")
	)
	(segment
		(start 126.177802 -270.580358)
		(end 126.644654 -270.846296)
		(width 0.350012)
		(layer "F.Cu")
		(net "GND")
	)
	(segment
		(start 113.017808 -285.160466)
		(end 113.48466 -285.426404)
		(width 0.350012)
		(layer "F.Cu")
		(net "GND")
	)
	(segment
		(start 102.677976 -280.30043)
		(end 102.211124 -280.566368)
		(width 0.350012)
		(layer "F.Cu")
		(net "GND")
	)
	(segment
		(start 107.847892 -266.530328)
		(end 107.38104 -266.796266)
		(width 0.350012)
		(layer "F.Cu")
		(net "GND")
	)
	(segment
		(start 66.070734 -390.160002)
		(end 66.745358 -390.160002)
		(width 0.254)
		(layer "F.Cu")
		(net "GND")
	)
	(segment
		(start 29.86405 -434.9623)
		(end 30.493208 -434.9623)
		(width 0.381)
		(layer "F.Cu")
		(net "GND")
	)
	(segment
		(start 419.912038 -219.435172)
		(end 421.296338 -219.435172)
		(width 0.4572)
		(layer "F.Cu")
		(net "GND")
	)
	(segment
		(start 125.783848 -40.3352)
		(end 125.5268 -40.3352)
		(width 0.381)
		(layer "F.Cu")
		(net "GND")
	)
	(segment
		(start 194.604132 -312.935366)
		(end 195.988432 -312.935366)
		(width 0.4572)
		(layer "F.Cu")
		(net "GND")
	)
	(segment
		(start 105.967784 -281.110436)
		(end 105.500932 -281.376374)
		(width 0.350012)
		(layer "F.Cu")
		(net "GND")
	)
	(segment
		(start 365.828072 -238.270034)
		(end 366.294924 -238.004096)
		(width 0.350012)
		(layer "F.Cu")
		(net "GND")
	)
	(segment
		(start 341.34552 -399.143474)
		(end 341.045546 -399.663158)
		(width 0.254)
		(layer "F.Cu")
		(net "GND")
	)
	(segment
		(start 130.417824 -391.281158)
		(end 130.718052 -390.761474)
		(width 0.254)
		(layer "F.Cu")
		(net "GND")
	)
	(segment
		(start 122.117866 -226.120452)
		(end 122.584718 -225.854514)
		(width 0.350012)
		(layer "F.Cu")
		(net "GND")
	)
	(segment
		(start 93.763338 -180.570378)
		(end 93.482922 -180.850794)
		(width 0.2286)
		(layer "F.Cu")
		(net "GND")
	)
	(segment
		(start 116.77777 -291.64026)
		(end 117.244622 -291.906198)
		(width 0.350012)
		(layer "F.Cu")
		(net "GND")
	)
	(segment
		(start 391.208006 -226.930204)
		(end 391.674858 -226.664266)
		(width 0.350012)
		(layer "F.Cu")
		(net "GND")
	)
	(segment
		(start 79.398368 -384.617722)
		(end 79.990188 -384.617722)
		(width 0.254)
		(layer "F.Cu")
		(net "GND")
	)
	(segment
		(start 157.81909 -390.160002)
		(end 157.29839 -390.160002)
		(width 0.254)
		(layer "F.Cu")
		(net "GND")
	)
	(segment
		(start 331.34808 -294.070024)
		(end 330.880974 -294.335962)
		(width 0.350012)
		(layer "F.Cu")
		(net "GND")
	)
	(segment
		(start 419.96106 -354.18014)
		(end 419.992048 -354.18014)
		(width 0.2286)
		(layer "F.Cu")
		(net "GND")
	)
	(segment
		(start 90.790268 -384.617722)
		(end 90.198448 -384.617722)
		(width 0.254)
		(layer "F.Cu")
		(net "GND")
	)
	(segment
		(start 51.467004 -10.16635)
		(end 51.465734 -10.16508)
		(width 0.3556)
		(layer "F.Cu")
		(net "GND")
	)
	(segment
		(start 133.69798 -293.260272)
		(end 134.164832 -293.52621)
		(width 0.350012)
		(layer "F.Cu")
		(net "GND")
	)
	(segment
		(start 70.861936 -8.320024)
		(end 70.861936 -7.217156)
		(width 0.3556)
		(layer "F.Cu")
		(net "GND")
	)
	(segment
		(start 355.142292 -392.913108)
		(end 354.842318 -393.213082)
		(width 0.254)
		(layer "F.Cu")
		(net "GND")
	)
	(segment
		(start 131.547108 -16.549878)
		(end 131.548378 -16.551148)
		(width 0.3556)
		(layer "F.Cu")
		(net "GND")
	)
	(segment
		(start 348.737936 -273.820128)
		(end 348.271084 -274.086066)
		(width 0.350012)
		(layer "F.Cu")
		(net "GND")
	)
	(segment
		(start 118.657878 -272.20037)
		(end 119.12473 -272.466308)
		(width 0.350012)
		(layer "F.Cu")
		(net "GND")
	)
	(segment
		(start 79.177896 -262.480298)
		(end 78.711044 -262.746236)
		(width 0.350012)
		(layer "F.Cu")
		(net "GND")
	)
	(segment
		(start 332.92796 -223.69018)
		(end 332.461108 -223.424242)
		(width 0.350012)
		(layer "F.Cu")
		(net "GND")
	)
	(segment
		(start 131.517898 -226.120452)
		(end 131.98475 -225.854514)
		(width 0.350012)
		(layer "F.Cu")
		(net "GND")
	)
	(segment
		(start 361.128056 -249.610118)
		(end 361.594908 -249.34418)
		(width 0.350012)
		(layer "F.Cu")
		(net "GND")
	)
	(segment
		(start 138.66495 -116.586)
		(end 138.66495 -117.11305)
		(width 0.381)
		(layer "F.Cu")
		(net "GND")
	)
	(segment
		(start 86.69782 -293.260272)
		(end 86.230968 -293.52621)
		(width 0.350012)
		(layer "F.Cu")
		(net "GND")
	)
	(segment
		(start 102.002082 -382.237488)
		(end 102.45217 -381.7874)
		(width 0.254)
		(layer "F.Cu")
		(net "GND")
	)
	(segment
		(start 390.737852 -239.08004)
		(end 391.204704 -238.814102)
		(width 0.350012)
		(layer "F.Cu")
		(net "GND")
	)
	(segment
		(start 90.157808 -235.84027)
		(end 89.690956 -235.574332)
		(width 0.350012)
		(layer "F.Cu")
		(net "GND")
	)
	(segment
		(start 374.588024 -287.59023)
		(end 375.054876 -287.856168)
		(width 0.350012)
		(layer "F.Cu")
		(net "GND")
	)
	(segment
		(start 330.408026 -281.110182)
		(end 329.941174 -281.37612)
		(width 0.350012)
		(layer "F.Cu")
		(net "GND")
	)
	(segment
		(start 168.527984 -302.735234)
		(end 167.143684 -302.735234)
		(width 0.4572)
		(layer "F.Cu")
		(net "GND")
	)
	(segment
		(start 401.209764 -395.613128)
		(end 401.729448 -395.313154)
		(width 0.254)
		(layer "F.Cu")
		(net "GND")
	)
	(segment
		(start 389.170672 -395.0208)
		(end 388.478522 -394.831062)
		(width 0.254)
		(layer "F.Cu")
		(net "GND")
	)
	(segment
		(start 110.367826 -238.270288)
		(end 109.900974 -238.00435)
		(width 0.350012)
		(layer "F.Cu")
		(net "GND")
	)
	(segment
		(start 53.717952 -383.402586)
		(end 53.717952 -383.622296)
		(width 0.254)
		(layer "F.Cu")
		(net "GND")
	)
	(segment
		(start 331.34808 -268.150086)
		(end 330.880974 -268.416024)
		(width 0.350012)
		(layer "F.Cu")
		(net "GND")
	)
	(segment
		(start 419.04412 -400.212814)
		(end 419.04412 -399.76171)
		(width 0.254)
		(layer "F.Cu")
		(net "GND")
	)
	(segment
		(start 90.457782 -272.20037)
		(end 89.99093 -272.466308)
		(width 0.350012)
		(layer "F.Cu")
		(net "GND")
	)
	(segment
		(start 163.298378 -384.617722)
		(end 163.2458 -383.92227)
		(width 0.254)
		(layer "F.Cu")
		(net "GND")
	)
	(segment
		(start 320.17843 -394.831062)
		(end 319.67043 -395.0208)
		(width 0.254)
		(layer "F.Cu")
		(net "GND")
	)
	(segment
		(start 429.76165 -399.72488)
		(end 429.649382 -399.72488)
		(width 0.254)
		(layer "F.Cu")
		(net "GND")
	)
	(segment
		(start 109.728 -269.770352)
		(end 109.261148 -270.03629)
		(width 0.350012)
		(layer "F.Cu")
		(net "GND")
	)
	(segment
		(start 51.884072 -305.285394)
		(end 50.499772 -305.285394)
		(width 0.4572)
		(layer "F.Cu")
		(net "GND")
	)
	(segment
		(start 394.327888 -282.730194)
		(end 394.982954 -282.730194)
		(width 0.350012)
		(layer "F.Cu")
		(net "GND")
	)
	(segment
		(start 305.270408 -396.520924)
		(end 304.718212 -396.710662)
		(width 0.254)
		(layer "F.Cu")
		(net "GND")
	)
	(segment
		(start 441.655708 -399.613628)
		(end 442.199014 -399.070322)
		(width 0.2286)
		(layer "F.Cu")
		(net "GND")
	)
	(segment
		(start 419.298374 -395.0208)
		(end 418.606224 -394.831062)
		(width 0.254)
		(layer "F.Cu")
		(net "GND")
	)
	(segment
		(start 15.073122 -416.912552)
		(end 14.892782 -416.912552)
		(width 0.381)
		(layer "F.Cu")
		(net "GND")
	)
	(segment
		(start 191.160146 -237.285276)
		(end 189.775846 -237.285276)
		(width 0.4572)
		(layer "F.Cu")
		(net "GND")
	)
	(segment
		(start 370.997988 -224.500186)
		(end 371.46484 -224.234248)
		(width 0.350012)
		(layer "F.Cu")
		(net "GND")
	)
	(segment
		(start 59.71794 -383.622296)
		(end 60.017914 -383.92227)
		(width 0.254)
		(layer "F.Cu")
		(net "GND")
	)
	(segment
		(start 384.627882 -236.650022)
		(end 385.094734 -236.384084)
		(width 0.350012)
		(layer "F.Cu")
		(net "GND")
	)
	(segment
		(start 115.83797 -270.580358)
		(end 116.304822 -270.846296)
		(width 0.350012)
		(layer "F.Cu")
		(net "GND")
	)
	(segment
		(start 360.657902 -247.1801)
		(end 361.124754 -246.914162)
		(width 0.350012)
		(layer "F.Cu")
		(net "GND")
	)
	(segment
		(start 67.327526 -337.078066)
		(end 67.58051 -336.825082)
		(width 0.2286)
		(layer "F.Cu")
		(net "GND")
	)
	(segment
		(start 105.967784 -276.2504)
		(end 105.500932 -276.516338)
		(width 0.350012)
		(layer "F.Cu")
		(net "GND")
	)
	(segment
		(start 22.07895 -361.061)
		(end 21.336 -361.061)
		(width 0.381)
		(layer "F.Cu")
		(net "GND")
	)
	(segment
		(start 20.769834 -393.915392)
		(end 21.075396 -394.220954)
		(width 0.381)
		(layer "F.Cu")
		(net "GND")
	)
	(segment
		(start 38.180772 -58.630312)
		(end 38.180772 -59.318144)
		(width 0.381)
		(layer "F.Cu")
		(net "GND")
	)
	(segment
		(start 365.357918 -232.599992)
		(end 365.82477 -232.334054)
		(width 0.350012)
		(layer "F.Cu")
		(net "GND")
	)
	(segment
		(start 121.477786 -270.580358)
		(end 121.944638 -270.846296)
		(width 0.350012)
		(layer "F.Cu")
		(net "GND")
	)
	(segment
		(start 119.617998 -391.281158)
		(end 119.917972 -390.761474)
		(width 0.254)
		(layer "F.Cu")
		(net "GND")
	)
	(segment
		(start 325.70801 -273.010122)
		(end 325.052944 -273.010122)
		(width 0.350012)
		(layer "F.Cu")
		(net "GND")
	)
	(segment
		(start 343.268046 -256.090166)
		(end 342.801194 -255.824228)
		(width 0.350012)
		(layer "F.Cu")
		(net "GND")
	)
	(segment
		(start 165.972744 -436.153052)
		(end 166.249858 -436.430166)
		(width 0.381)
		(layer "F.Cu")
		(net "GND")
	)
	(segment
		(start 387.448044 -235.03001)
		(end 387.914896 -234.764072)
		(width 0.350012)
		(layer "F.Cu")
		(net "GND")
	)
	(segment
		(start 144.677892 -250.420378)
		(end 145.144744 -250.15444)
		(width 0.350012)
		(layer "F.Cu")
		(net "GND")
	)
	(segment
		(start 60.591192 -390.160002)
		(end 60.070492 -390.160002)
		(width 0.254)
		(layer "F.Cu")
		(net "GND")
	)
	(segment
		(start 135.107934 -292.450266)
		(end 135.574786 -292.716204)
		(width 0.350012)
		(layer "F.Cu")
		(net "GND")
	)
	(segment
		(start 403.34565 -391.784586)
		(end 403.34565 -391.333482)
		(width 0.254)
		(layer "F.Cu")
		(net "GND")
	)
	(segment
		(start 87.3379 -235.84027)
		(end 86.871048 -235.574332)
		(width 0.350012)
		(layer "F.Cu")
		(net "GND")
	)
	(segment
		(start 384.457956 -291.640006)
		(end 384.924808 -291.905944)
		(width 0.350012)
		(layer "F.Cu")
		(net "GND")
	)
	(segment
		(start 307.368194 -274.684998)
		(end 305.983894 -274.684998)
		(width 0.4572)
		(layer "F.Cu")
		(net "GND")
	)
	(segment
		(start 413.298386 -396.520924)
		(end 412.74619 -396.710662)
		(width 0.254)
		(layer "F.Cu")
		(net "GND")
	)
	(segment
		(start 124.297948 -268.960346)
		(end 124.7648 -269.226284)
		(width 0.350012)
		(layer "F.Cu")
		(net "GND")
	)
	(segment
		(start 302.620934 -394.412978)
		(end 302.620934 -395.012926)
		(width 0.254)
		(layer "F.Cu")
		(net "GND")
	)
	(segment
		(start 107.377992 -288.400236)
		(end 106.91114 -288.666174)
		(width 0.350012)
		(layer "F.Cu")
		(net "GND")
	)
	(segment
		(start 36.795964 -284.035246)
		(end 35.411664 -284.035246)
		(width 0.4572)
		(layer "F.Cu")
		(net "GND")
	)
	(segment
		(start 136.517888 -267.340334)
		(end 136.98474 -267.606272)
		(width 0.350012)
		(layer "F.Cu")
		(net "GND")
	)
	(segment
		(start 90.157808 -234.220258)
		(end 89.690956 -233.95432)
		(width 0.350012)
		(layer "F.Cu")
		(net "GND")
	)
	(segment
		(start 144.677892 -247.180354)
		(end 145.144744 -246.914416)
		(width 0.350012)
		(layer "F.Cu")
		(net "GND")
	)
	(segment
		(start 352.198178 -392.999722)
		(end 352.1456 -392.30427)
		(width 0.254)
		(layer "F.Cu")
		(net "GND")
	)
	(segment
		(start 128.52781 -281.110436)
		(end 128.994662 -281.376374)
		(width 0.350012)
		(layer "F.Cu")
		(net "GND")
	)
	(segment
		(start 217.062812 -25.311354)
		(end 217.062812 -27.76347)
		(width 0.3556)
		(layer "F.Cu")
		(net "GND")
	)
	(segment
		(start 140.397992 -382.40716)
		(end 140.397992 -382.54432)
		(width 0.254)
		(layer "F.Cu")
		(net "GND")
	)
	(segment
		(start 163.2458 -383.92227)
		(end 162.945572 -383.622042)
		(width 0.254)
		(layer "F.Cu")
		(net "GND")
	)
	(segment
		(start 183.522112 -113.85296)
		(end 183.132222 -113.46307)
		(width 0.254)
		(layer "F.Cu")
		(net "GND")
	)
	(segment
		(start 132.491226 -390.160002)
		(end 131.970526 -390.160002)
		(width 0.254)
		(layer "F.Cu")
		(net "GND")
	)
	(segment
		(start 174.57928 -100.740718)
		(end 174.625 -100.694998)
		(width 0.4572)
		(layer "F.Cu")
		(net "GND")
	)
	(segment
		(start 304.070258 -395.0208)
		(end 303.378362 -394.831062)
		(width 0.254)
		(layer "F.Cu")
		(net "GND")
	)
	(segment
		(start 410.845762 -399.143474)
		(end 410.89834 -398.542002)
		(width 0.254)
		(layer "F.Cu")
		(net "GND")
	)
	(segment
		(start 286.377634 -102.126034)
		(end 286.377634 -102.816152)
		(width 0.4572)
		(layer "F.Cu")
		(net "GND")
	)
	(segment
		(start 107.537504 -25.183592)
		(end 107.537504 -24.552656)
		(width 0.381)
		(layer "F.Cu")
		(net "GND")
	)
	(segment
		(start 350.618044 -273.820128)
		(end 350.151192 -274.086066)
		(width 0.350012)
		(layer "F.Cu")
		(net "GND")
	)
	(segment
		(start 384.018028 -392.004296)
		(end 384.318002 -392.30427)
		(width 0.254)
		(layer "F.Cu")
		(net "GND")
	)
	(segment
		(start 396.646908 -12.372848)
		(end 396.646908 -11.26998)
		(width 0.3556)
		(layer "F.Cu")
		(net "GND")
	)
	(segment
		(start 336.987896 -271.39011)
		(end 336.521044 -271.656048)
		(width 0.350012)
		(layer "F.Cu")
		(net "GND")
	)
	(segment
		(start 311.270396 -395.0208)
		(end 310.578246 -394.831062)
		(width 0.254)
		(layer "F.Cu")
		(net "GND")
	)
	(segment
		(start 333.39786 -247.1801)
		(end 332.931008 -246.914162)
		(width 0.350012)
		(layer "F.Cu")
		(net "GND")
	)
	(segment
		(start 338.868004 -282.730194)
		(end 338.401152 -282.996132)
		(width 0.350012)
		(layer "F.Cu")
		(net "GND")
	)
	(segment
		(start 31.148274 -12.374118)
		(end 31.147004 -12.372848)
		(width 0.3556)
		(layer "F.Cu")
		(net "GND")
	)
	(segment
		(start 240.425478 -291.011102)
		(end 240.163096 -291.011102)
		(width 0.4572)
		(layer "F.Cu")
		(net "GND")
	)
	(segment
		(start 305.614578 -349.211138)
		(end 305.614578 -348.794324)
		(width 0.2286)
		(layer "F.Cu")
		(net "GND")
	)
	(segment
		(start 351.25787 -243.940076)
		(end 350.791018 -243.674138)
		(width 0.350012)
		(layer "F.Cu")
		(net "GND")
	)
	(segment
		(start 387.917944 -243.940076)
		(end 388.384796 -243.674138)
		(width 0.350012)
		(layer "F.Cu")
		(net "GND")
	)
	(segment
		(start 163.160964 -428.721774)
		(end 162.90417 -428.46498)
		(width 0.3048)
		(layer "F.Cu")
		(net "GND")
	)
	(segment
		(start 347.968062 -249.610118)
		(end 347.50121 -249.34418)
		(width 0.350012)
		(layer "F.Cu")
		(net "GND")
	)
	(segment
		(start 318.912494 -412.212536)
		(end 318.912494 -411.332426)
		(width 0.381)
		(layer "F.Cu")
		(net "GND")
	)
	(segment
		(start 344.389964 -392.999722)
		(end 343.798144 -392.999722)
		(width 0.254)
		(layer "F.Cu")
		(net "GND")
	)
	(segment
		(start 336.687922 -230.169974)
		(end 336.22107 -229.904036)
		(width 0.350012)
		(layer "F.Cu")
		(net "GND")
	)
	(segment
		(start 331.81798 -268.960092)
		(end 331.351128 -269.22603)
		(width 0.350012)
		(layer "F.Cu")
		(net "GND")
	)
	(segment
		(start 81.190084 -384.617722)
		(end 80.598264 -384.617722)
		(width 0.254)
		(layer "F.Cu")
		(net "GND")
	)
	(segment
		(start 352.785172 -429.356012)
		(end 352.785172 -428.721012)
		(width 0.4318)
		(layer "F.Cu")
		(net "GND")
	)
	(segment
		(start 381.338074 -232.599992)
		(end 381.804926 -232.334054)
		(width 0.350012)
		(layer "F.Cu")
		(net "GND")
	)
	(segment
		(start 119.99595 -425.704)
		(end 119.507 -425.21505)
		(width 0.381)
		(layer "F.Cu")
		(net "GND")
	)
	(segment
		(start 384.927856 -261.670038)
		(end 385.394708 -261.935976)
		(width 0.350012)
		(layer "F.Cu")
		(net "GND")
	)
	(segment
		(start 171.60748 -103.96728)
		(end 172.684948 -103.96728)
		(width 0.4572)
		(layer "F.Cu")
		(net "GND")
	)
	(segment
		(start 111.137954 -290.020248)
		(end 110.671102 -290.286186)
		(width 0.350012)
		(layer "F.Cu")
		(net "GND")
	)
	(segment
		(start 292.280086 -199.885046)
		(end 290.895786 -199.885046)
		(width 0.4572)
		(layer "F.Cu")
		(net "GND")
	)
	(segment
		(start 83.577938 -232.600246)
		(end 83.111086 -232.334308)
		(width 0.350012)
		(layer "F.Cu")
		(net "GND")
	)
	(segment
		(start 108.487972 -235.030264)
		(end 108.02112 -234.764326)
		(width 0.350012)
		(layer "F.Cu")
		(net "GND")
	)
	(segment
		(start 81.246218 -388.328662)
		(end 80.598264 -388.138924)
		(width 0.254)
		(layer "F.Cu")
		(net "GND")
	)
	(segment
		(start 202.147932 -238.135414)
		(end 203.532232 -238.135414)
		(width 0.4572)
		(layer "F.Cu")
		(net "GND")
	)
	(segment
		(start 36.795964 -277.235412)
		(end 35.411664 -277.235412)
		(width 0.4572)
		(layer "F.Cu")
		(net "GND")
	)
	(segment
		(start 405.64562 -7.215124)
		(end 405.64562 -7.215886)
		(width 0.3556)
		(layer "F.Cu")
		(net "GND")
	)
	(segment
		(start 110.15599 -23.134828)
		(end 109.13999 -23.134828)
		(width 0.381)
		(layer "F.Cu")
		(net "GND")
	)
	(segment
		(start 38.45814 -12.374118)
		(end 38.45687 -12.372848)
		(width 0.3556)
		(layer "F.Cu")
		(net "GND")
	)
	(segment
		(start 192.199514 -67.391788)
		(end 191.841882 -67.391788)
		(width 0.3556)
		(layer "F.Cu")
		(net "GND")
	)
	(segment
		(start 338.389976 -392.999722)
		(end 338.998052 -392.999722)
		(width 0.254)
		(layer "F.Cu")
		(net "GND")
	)
	(segment
		(start 420.155624 -7.215124)
		(end 420.155624 -7.215886)
		(width 0.3556)
		(layer "F.Cu")
		(net "GND")
	)
	(segment
		(start 288.94659 -351.973896)
		(end 288.693352 -352.227134)
		(width 0.381)
		(layer "F.Cu")
		(net "GND")
	)
	(segment
		(start 153.249884 -321.715892)
		(end 153.738834 -321.715892)
		(width 0.4064)
		(layer "F.Cu")
		(net "GND")
	)
	(segment
		(start 93.91777 -256.900426)
		(end 93.450918 -256.634488)
		(width 0.350012)
		(layer "F.Cu")
		(net "GND")
	)
	(segment
		(start 97.037906 -260.860286)
		(end 96.571054 -261.126224)
		(width 0.350012)
		(layer "F.Cu")
		(net "GND")
	)
	(segment
		(start 53.267102 -8.320024)
		(end 53.267102 -9.423654)
		(width 0.3556)
		(layer "F.Cu")
		(net "GND")
	)
	(segment
		(start 97.652078 -406.769316)
		(end 97.652078 -404.859744)
		(width 0.3302)
		(layer "F.Cu")
		(net "GND")
	)
	(segment
		(start 144.677892 -252.04039)
		(end 145.144744 -251.774452)
		(width 0.350012)
		(layer "F.Cu")
		(net "GND")
	)
	(segment
		(start 192.322196 -111.452914)
		(end 192.712086 -111.063024)
		(width 0.254)
		(layer "F.Cu")
		(net "GND")
	)
	(segment
		(start 85.757766 -290.020248)
		(end 85.290914 -290.286186)
		(width 0.350012)
		(layer "F.Cu")
		(net "GND")
	)
	(segment
		(start 446.644268 -237.285022)
		(end 445.259968 -237.285022)
		(width 0.4572)
		(layer "F.Cu")
		(net "GND")
	)
	(segment
		(start 390.737852 -240.700052)
		(end 391.204704 -240.434114)
		(width 0.350012)
		(layer "F.Cu")
		(net "GND")
	)
	(segment
		(start 135.107934 -273.010376)
		(end 135.574786 -273.276314)
		(width 0.350012)
		(layer "F.Cu")
		(net "GND")
	)
	(segment
		(start 442.5442 -294.235124)
		(end 443.9285 -294.235124)
		(width 0.4572)
		(layer "F.Cu")
		(net "GND")
	)
	(segment
		(start 42.057066 -8.320024)
		(end 42.057066 -9.423654)
		(width 0.3556)
		(layer "F.Cu")
		(net "GND")
	)
	(segment
		(start 355.062028 -396.213076)
		(end 355.362002 -396.51305)
		(width 0.254)
		(layer "F.Cu")
		(net "GND")
	)
	(segment
		(start 292.280086 -286.585152)
		(end 290.895786 -286.585152)
		(width 0.4572)
		(layer "F.Cu")
		(net "GND")
	)
	(segment
		(start 191.160146 -305.285394)
		(end 189.775846 -305.285394)
		(width 0.4572)
		(layer "F.Cu")
		(net "GND")
	)
	(segment
		(start 349.105982 -394.831062)
		(end 348.597982 -395.0208)
		(width 0.254)
		(layer "F.Cu")
		(net "GND")
	)
	(segment
		(start 338.097876 -253.660148)
		(end 337.631024 -253.39421)
		(width 0.350012)
		(layer "F.Cu")
		(net "GND")
	)
	(segment
		(start 134.334758 -403.830536)
		(end 134.334758 -402.923502)
		(width 0.381)
		(layer "F.Cu")
		(net "GND")
	)
	(segment
		(start 306.820316 -426.191426)
		(end 306.820316 -426.826426)
		(width 0.381)
		(layer "F.Cu")
		(net "GND")
	)
	(segment
		(start 345.1479 -247.990106)
		(end 344.681048 -247.724168)
		(width 0.350012)
		(layer "F.Cu")
		(net "GND")
	)
	(segment
		(start 80.58785 -266.530328)
		(end 80.120998 -266.796266)
		(width 0.350012)
		(layer "F.Cu")
		(net "GND")
	)
	(segment
		(start 368.64798 -226.930204)
		(end 369.114832 -226.664266)
		(width 0.350012)
		(layer "F.Cu")
		(net "GND")
	)
	(segment
		(start 279.893268 -99.530408)
		(end 279.632156 -99.269296)
		(width 0.3556)
		(layer "F.Cu")
		(net "GND")
	)
	(segment
		(start 394.327888 -292.450012)
		(end 394.982954 -292.450012)
		(width 0.350012)
		(layer "F.Cu")
		(net "GND")
	)
	(segment
		(start 265.54811 -238.13516)
		(end 266.93241 -238.13516)
		(width 0.4572)
		(layer "F.Cu")
		(net "GND")
	)
	(segment
		(start 307.670454 -398.542002)
		(end 306.991004 -398.542002)
		(width 0.254)
		(layer "F.Cu")
		(net "GND")
	)
	(segment
		(start 156.630116 -351.247456)
		(end 157.292802 -351.247456)
		(width 0.381)
		(layer "F.Cu")
		(net "GND")
	)
	(segment
		(start 381.338074 -250.420124)
		(end 381.804926 -250.154186)
		(width 0.350012)
		(layer "F.Cu")
		(net "GND")
	)
	(segment
		(start 425.96816 -12.374118)
		(end 425.96689 -12.372848)
		(width 0.3556)
		(layer "F.Cu")
		(net "GND")
	)
	(segment
		(start 122.41784 -267.340334)
		(end 122.884692 -267.606272)
		(width 0.350012)
		(layer "F.Cu")
		(net "GND")
	)
	(segment
		(start 68.871846 -163.670996)
		(end 68.979034 -163.778184)
		(width 0.381)
		(layer "F.Cu")
		(net "GND")
	)
	(segment
		(start 331.81798 -288.399982)
		(end 331.351128 -288.66592)
		(width 0.350012)
		(layer "F.Cu")
		(net "GND")
	)
	(segment
		(start 162.746182 -388.328662)
		(end 162.098228 -388.138924)
		(width 0.254)
		(layer "F.Cu")
		(net "GND")
	)
	(segment
		(start 87.798402 -386.6388)
		(end 87.106252 -386.449062)
		(width 0.254)
		(layer "F.Cu")
		(net "GND")
	)
	(segment
		(start 139.80795 -268.15034)
		(end 140.274802 -268.416278)
		(width 0.350012)
		(layer "F.Cu")
		(net "GND")
	)
	(segment
		(start 165.942518 -385.21132)
		(end 166.462202 -385.731004)
		(width 0.254)
		(layer "F.Cu")
		(net "GND")
	)
	(segment
		(start 353.585272 -424.279314)
		(end 353.585272 -423.648378)
		(width 0.381)
		(layer "F.Cu")
		(net "GND")
	)
	(segment
		(start 51.465734 -7.215124)
		(end 51.465734 -7.215886)
		(width 0.3556)
		(layer "F.Cu")
		(net "GND")
	)
	(segment
		(start 346.858082 -288.399982)
		(end 346.39123 -288.66592)
		(width 0.350012)
		(layer "F.Cu")
		(net "GND")
	)
	(segment
		(start 296.973498 -427.388274)
		(end 296.973498 -428.527718)
		(width 0.381)
		(layer "F.Cu")
		(net "GND")
	)
	(segment
		(start 327.117964 -293.260018)
		(end 326.651112 -293.525956)
		(width 0.350012)
		(layer "F.Cu")
		(net "GND")
	)
	(segment
		(start 83.408012 -268.15034)
		(end 82.940906 -268.416278)
		(width 0.350012)
		(layer "F.Cu")
		(net "GND")
	)
	(segment
		(start 342.158066 -293.260018)
		(end 341.691214 -293.525956)
		(width 0.350012)
		(layer "F.Cu")
		(net "GND")
	)
	(segment
		(start 348.268036 -266.530074)
		(end 347.801184 -266.796012)
		(width 0.350012)
		(layer "F.Cu")
		(net "GND")
	)
	(segment
		(start 384.157982 -253.660148)
		(end 384.624834 -253.39421)
		(width 0.350012)
		(layer "F.Cu")
		(net "GND")
	)
	(segment
		(start 97.04578 -382.951482)
		(end 97.144332 -382.85293)
		(width 0.254)
		(layer "F.Cu")
		(net "GND")
	)
	(segment
		(start 113.917984 -383.92227)
		(end 113.970562 -383.974848)
		(width 0.254)
		(layer "F.Cu")
		(net "GND")
	)
	(segment
		(start 133.075934 -403.830536)
		(end 133.075934 -402.947886)
		(width 0.381)
		(layer "F.Cu")
		(net "GND")
	)
	(segment
		(start 265.54811 -306.135024)
		(end 266.93241 -306.135024)
		(width 0.4572)
		(layer "F.Cu")
		(net "GND")
	)
	(segment
		(start 110.643924 -388.297674)
		(end 111.290862 -388.297674)
		(width 0.254)
		(layer "F.Cu")
		(net "GND")
	)
	(segment
		(start 327.117964 -290.019994)
		(end 326.651112 -290.285932)
		(width 0.350012)
		(layer "F.Cu")
		(net "GND")
	)
	(segment
		(start 312.417714 -399.143474)
		(end 312.470292 -398.542002)
		(width 0.254)
		(layer "F.Cu")
		(net "GND")
	)
	(segment
		(start 389.627872 -282.730194)
		(end 390.094724 -282.996132)
		(width 0.350012)
		(layer "F.Cu")
		(net "GND")
	)
	(segment
		(start 68.42887 -147.81784)
		(end 67.924426 -147.81784)
		(width 0.254)
		(layer "F.Cu")
		(net "GND")
	)
	(segment
		(start 138.397996 -293.260272)
		(end 138.864848 -293.52621)
		(width 0.350012)
		(layer "F.Cu")
		(net "GND")
	)
	(segment
		(start 229.507796 -292.961822)
		(end 228.029516 -293.654226)
		(width 0.1778)
		(layer "F.Cu")
		(net "GND")
	)
	(segment
		(start 99.55784 -240.700306)
		(end 99.090988 -240.434368)
		(width 0.350012)
		(layer "F.Cu")
		(net "GND")
	)
	(segment
		(start 363.307884 -287.59023)
		(end 363.774736 -287.856168)
		(width 0.350012)
		(layer "F.Cu")
		(net "GND")
	)
	(segment
		(start 142.797784 -230.980234)
		(end 143.264636 -230.71455)
		(width 0.350012)
		(layer "F.Cu")
		(net "GND")
	)
	(segment
		(start 10.971784 -138.13917)
		(end 9.332468 -138.13917)
		(width 0.3556)
		(layer "F.Cu")
		(net "GND")
	)
	(segment
		(start 124.937774 -222.880428)
		(end 125.404626 -222.61449)
		(width 0.350012)
		(layer "F.Cu")
		(net "GND")
	)
	(segment
		(start 123.827794 -277.870412)
		(end 124.294646 -278.13635)
		(width 0.350012)
		(layer "F.Cu")
		(net "GND")
	)
	(segment
		(start 227.19157 -291.406326)
		(end 227.856034 -290.741862)
		(width 0.4572)
		(layer "F.Cu")
		(net "GND")
	)
	(segment
		(start 347.144086 -399.76171)
		(end 347.045534 -399.663158)
		(width 0.254)
		(layer "F.Cu")
		(net "GND")
	)
	(segment
		(start 158.498286 -386.6388)
		(end 157.806136 -386.449062)
		(width 0.254)
		(layer "F.Cu")
		(net "GND")
	)
	(segment
		(start 349.44558 -399.663158)
		(end 349.745554 -399.143474)
		(width 0.254)
		(layer "F.Cu")
		(net "GND")
	)
	(segment
		(start 142.797784 -248.800366)
		(end 143.264636 -248.534428)
		(width 0.350012)
		(layer "F.Cu")
		(net "GND")
	)
	(segment
		(start 227.423726 -293.654226)
		(end 228.029516 -293.654226)
		(width 0.4572)
		(layer "F.Cu")
		(net "GND")
	)
	(segment
		(start 105.497884 -281.920442)
		(end 105.031032 -282.18638)
		(width 0.350012)
		(layer "F.Cu")
		(net "GND")
	)
	(segment
		(start 352.45548 -437.875172)
		(end 352.45548 -437.240172)
		(width 0.381)
		(layer "F.Cu")
		(net "GND")
	)
	(segment
		(start 104.236266 -398.729962)
		(end 104.236266 -397.37284)
		(width 0.3048)
		(layer "F.Cu")
		(net "GND")
	)
	(segment
		(start 366.597946 -280.300176)
		(end 367.064798 -280.566114)
		(width 0.350012)
		(layer "F.Cu")
		(net "GND")
	)
	(segment
		(start 121.762266 -384.617722)
		(end 121.170446 -384.617722)
		(width 0.254)
		(layer "F.Cu")
		(net "GND")
	)
	(segment
		(start 148.545804 -383.402586)
		(end 148.545804 -382.951482)
		(width 0.254)
		(layer "F.Cu")
		(net "GND")
	)
	(segment
		(start 100.22205 -79.71663)
		(end 100.644198 -80.138778)
		(width 0.381)
		(layer "F.Cu")
		(net "GND")
	)
	(segment
		(start 121.007886 -269.770352)
		(end 121.474738 -270.03629)
		(width 0.350012)
		(layer "F.Cu")
		(net "GND")
	)
	(segment
		(start 330.369672 -33.969706)
		(end 330.321158 -33.921192)
		(width 0.3556)
		(layer "F.Cu")
		(net "GND")
	)
	(segment
		(start 241.971322 -291.361876)
		(end 240.865406 -291.361876)
		(width 0.1778)
		(layer "F.Cu")
		(net "GND")
	)
	(segment
		(start 77.467968 -230.170228)
		(end 76.812902 -230.170228)
		(width 0.350012)
		(layer "F.Cu")
		(net "GND")
	)
	(segment
		(start 4.194048 -135.42137)
		(end 4.194048 -137.27303)
		(width 0.3556)
		(layer "F.Cu")
		(net "GND")
	)
	(segment
		(start 138.867896 -294.070278)
		(end 139.334748 -294.336216)
		(width 0.350012)
		(layer "F.Cu")
		(net "GND")
	)
	(segment
		(start 416.556952 -7.217156)
		(end 416.556952 -8.320024)
		(width 0.3556)
		(layer "F.Cu")
		(net "GND")
	)
	(segment
		(start 132.927852 -225.310446)
		(end 133.394704 -225.044508)
		(width 0.350012)
		(layer "F.Cu")
		(net "GND")
	)
	(segment
		(start 284.736032 -302.73498)
		(end 283.351732 -302.73498)
		(width 0.4572)
		(layer "F.Cu")
		(net "GND")
	)
	(segment
		(start 379.217936 -399.663158)
		(end 379.51791 -399.143474)
		(width 0.254)
		(layer "F.Cu")
		(net "GND")
	)
	(segment
		(start 42.058336 -12.37488)
		(end 42.058336 -12.374118)
		(width 0.3556)
		(layer "F.Cu")
		(net "GND")
	)
	(segment
		(start 151.946102 -388.328662)
		(end 151.298402 -388.138924)
		(width 0.254)
		(layer "F.Cu")
		(net "GND")
	)
	(segment
		(start 392.917934 -272.200116)
		(end 393.384786 -272.466054)
		(width 0.350012)
		(layer "F.Cu")
		(net "GND")
	)
	(segment
		(start 374.588024 -263.29005)
		(end 375.054876 -263.555988)
		(width 0.350012)
		(layer "F.Cu")
		(net "GND")
	)
	(segment
		(start 122.116596 -391.37971)
		(end 122.018044 -391.281158)
		(width 0.254)
		(layer "F.Cu")
		(net "GND")
	)
	(segment
		(start 323.353684 -395.613128)
		(end 323.191632 -395.451076)
		(width 0.254)
		(layer "F.Cu")
		(net "GND")
	)
	(segment
		(start 99.39147 -287.045908)
		(end 99.391216 -287.04667)
		(width 0.350012)
		(layer "F.Cu")
		(net "GND")
	)
	(segment
		(start 227.19157 -293.42207)
		(end 227.423726 -293.654226)
		(width 0.4572)
		(layer "F.Cu")
		(net "GND")
	)
	(segment
		(start 105.66781 -226.930458)
		(end 105.200958 -226.66452)
		(width 0.350012)
		(layer "F.Cu")
		(net "GND")
	)
	(segment
		(start 108.017818 -235.84027)
		(end 107.550966 -235.574332)
		(width 0.350012)
		(layer "F.Cu")
		(net "GND")
	)
	(segment
		(start 92.33789 -262.480298)
		(end 91.871038 -262.746236)
		(width 0.350012)
		(layer "F.Cu")
		(net "GND")
	)
	(segment
		(start 118.357904 -229.360476)
		(end 118.824756 -229.094538)
		(width 0.350012)
		(layer "F.Cu")
		(net "GND")
	)
	(segment
		(start 301.58182 -396.813024)
		(end 301.104808 -396.67815)
		(width 0.254)
		(layer "F.Cu")
		(net "GND")
	)
	(segment
		(start 86.2457 -382.951482)
		(end 86.344252 -382.85293)
		(width 0.254)
		(layer "F.Cu")
		(net "GND")
	)
	(segment
		(start 79.918814 -390.231122)
		(end 79.918814 -390.160002)
		(width 0.254)
		(layer "F.Cu")
		(net "GND")
	)
	(segment
		(start 399.160238 -392.1252)
		(end 399.693638 -392.1252)
		(width 0.254)
		(layer "F.Cu")
		(net "GND")
	)
	(segment
		(start 113.970562 -388.08152)
		(end 113.721134 -388.330948)
		(width 0.254)
		(layer "F.Cu")
		(net "GND")
	)
	(segment
		(start 373.64797 -261.670038)
		(end 374.114822 -261.935976)
		(width 0.350012)
		(layer "F.Cu")
		(net "GND")
	)
	(segment
		(start 347.045534 -392.004296)
		(end 347.345508 -392.30427)
		(width 0.254)
		(layer "F.Cu")
		(net "GND")
	)
	(segment
		(start 85.457792 -224.50044)
		(end 84.99094 -224.234502)
		(width 0.350012)
		(layer "F.Cu")
		(net "GND")
	)
	(segment
		(start 393.046966 -11.26998)
		(end 393.045696 -10.16508)
		(width 0.3556)
		(layer "F.Cu")
		(net "GND")
	)
	(segment
		(start 413.806132 -394.831062)
		(end 413.298386 -395.0208)
		(width 0.254)
		(layer "F.Cu")
		(net "GND")
	)
	(segment
		(start 358.778048 -243.940076)
		(end 358.311196 -243.674138)
		(width 0.350012)
		(layer "F.Cu")
		(net "GND")
	)
	(segment
		(start 23.946866 -10.16635)
		(end 23.945596 -10.16508)
		(width 0.3556)
		(layer "F.Cu")
		(net "GND")
	)
	(segment
		(start 125.877828 -252.04039)
		(end 126.34468 -251.774452)
		(width 0.350012)
		(layer "F.Cu")
		(net "GND")
	)
	(segment
		(start 10.01014 -97.683828)
		(end 9.90981 -97.784158)
		(width 0.3556)
		(layer "F.Cu")
		(net "GND")
	)
	(segment
		(start 86.868 -236.650276)
		(end 86.401148 -236.384338)
		(width 0.350012)
		(layer "F.Cu")
		(net "GND")
	)
	(segment
		(start 363.00791 -247.990106)
		(end 363.474762 -247.724168)
		(width 0.350012)
		(layer "F.Cu")
		(net "GND")
	)
	(segment
		(start 396.123668 -390.652)
		(end 396.397988 -390.92632)
		(width 0.254)
		(layer "F.Cu")
		(net "GND")
	)
	(segment
		(start 288.180018 -303.585118)
		(end 289.564318 -303.585118)
		(width 0.4572)
		(layer "F.Cu")
		(net "GND")
	)
	(segment
		(start 107.377992 -280.30043)
		(end 106.91114 -280.566368)
		(width 0.350012)
		(layer "F.Cu")
		(net "GND")
	)
	(segment
		(start 442.183266 -397.554958)
		(end 442.34862 -397.720312)
		(width 0.2032)
		(layer "F.Cu")
		(net "GND")
	)
	(segment
		(start 118.657878 -288.400236)
		(end 119.12473 -288.666174)
		(width 0.350012)
		(layer "F.Cu")
		(net "GND")
	)
	(segment
		(start 126.347982 -230.170228)
		(end 126.814834 -229.90429)
		(width 0.350012)
		(layer "F.Cu")
		(net "GND")
	)
	(segment
		(start 322.070476 -398.542002)
		(end 321.391026 -398.542002)
		(width 0.254)
		(layer "F.Cu")
		(net "GND")
	)
	(segment
		(start 273.092164 -284.88513)
		(end 274.476464 -284.88513)
		(width 0.4572)
		(layer "F.Cu")
		(net "GND")
	)
	(segment
		(start 129.63779 -235.84027)
		(end 130.104642 -235.574332)
		(width 0.350012)
		(layer "F.Cu")
		(net "GND")
	)
	(segment
		(start 336.245454 -391.333482)
		(end 336.344006 -391.23493)
		(width 0.254)
		(layer "F.Cu")
		(net "GND")
	)
	(segment
		(start 55.066946 -10.16635)
		(end 55.065676 -10.16508)
		(width 0.3556)
		(layer "F.Cu")
		(net "GND")
	)
	(segment
		(start 305.013106 -349.781622)
		(end 305.044094 -349.781622)
		(width 0.2286)
		(layer "F.Cu")
		(net "GND")
	)
	(segment
		(start 85.457792 -245.560342)
		(end 84.99094 -245.294404)
		(width 0.350012)
		(layer "F.Cu")
		(net "GND")
	)
	(segment
		(start 133.227826 -271.390364)
		(end 133.694678 -271.656302)
		(width 0.350012)
		(layer "F.Cu")
		(net "GND")
	)
	(segment
		(start 313.416188 -399.76171)
		(end 313.317636 -399.663158)
		(width 0.254)
		(layer "F.Cu")
		(net "GND")
	)
	(segment
		(start 353.907852 -273.010122)
		(end 353.441 -273.27606)
		(width 0.350012)
		(layer "F.Cu")
		(net "GND")
	)
	(segment
		(start 125.812042 -43.59275)
		(end 126.7206 -42.684192)
		(width 0.381)
		(layer "F.Cu")
		(net "GND")
	)
	(segment
		(start 132.927852 -230.170228)
		(end 133.394704 -229.90429)
		(width 0.350012)
		(layer "F.Cu")
		(net "GND")
	)
	(segment
		(start 123.357894 -270.580358)
		(end 123.824746 -270.846296)
		(width 0.350012)
		(layer "F.Cu")
		(net "GND")
	)
	(segment
		(start 424.918378 -363.201712)
		(end 424.727878 -363.201712)
		(width 0.3556)
		(layer "F.Cu")
		(net "GND")
	)
	(segment
		(start 345.447874 -289.209988)
		(end 344.981022 -289.475926)
		(width 0.350012)
		(layer "F.Cu")
		(net "GND")
	)
	(segment
		(start 251.16409 -48.737012)
		(end 251.16409 -48.155606)
		(width 0.4572)
		(layer "F.Cu")
		(net "GND")
	)
	(segment
		(start 97.507806 -271.390364)
		(end 97.040954 -271.656302)
		(width 0.350012)
		(layer "F.Cu")
		(net "GND")
	)
	(segment
		(start 81.69783 -224.50044)
		(end 81.230978 -224.234502)
		(width 0.350012)
		(layer "F.Cu")
		(net "GND")
	)
	(segment
		(start 347.968062 -244.750082)
		(end 347.50121 -244.484144)
		(width 0.350012)
		(layer "F.Cu")
		(net "GND")
	)
	(segment
		(start 179.516024 -312.935366)
		(end 180.900324 -312.935366)
		(width 0.4572)
		(layer "F.Cu")
		(net "GND")
	)
	(segment
		(start 368.64798 -241.510058)
		(end 369.114832 -241.24412)
		(width 0.350012)
		(layer "F.Cu")
		(net "GND")
	)
	(segment
		(start 377.117864 -399.143474)
		(end 377.170442 -398.542002)
		(width 0.254)
		(layer "F.Cu")
		(net "GND")
	)
	(segment
		(start 108.360464 -172.960284)
		(end 107.772454 -172.960284)
		(width 0.381)
		(layer "F.Cu")
		(net "GND")
	)
	(segment
		(start 144.552416 -117.475)
		(end 144.643856 -117.38356)
		(width 0.381)
		(layer "F.Cu")
		(net "GND")
	)
	(segment
		(start 340.277958 -267.34008)
		(end 339.811106 -267.606018)
		(width 0.350012)
		(layer "F.Cu")
		(net "GND")
	)
	(segment
		(start 402.12264 -399.686272)
		(end 402.145754 -399.663158)
		(width 0.254)
		(layer "F.Cu")
		(net "GND")
	)
	(segment
		(start 104.521 -419.989)
		(end 103.90505 -419.989)
		(width 0.381)
		(layer "F.Cu")
		(net "GND")
	)
	(segment
		(start 128.227836 -228.55047)
		(end 128.694688 -228.284532)
		(width 0.350012)
		(layer "F.Cu")
		(net "GND")
	)
	(segment
		(start 340.718902 -398.542002)
		(end 340.198202 -398.542002)
		(width 0.254)
		(layer "F.Cu")
		(net "GND")
	)
	(segment
		(start 164.145722 -383.402586)
		(end 164.145722 -382.951482)
		(width 0.254)
		(layer "F.Cu")
		(net "GND")
	)
	(segment
		(start 345.918028 -288.399982)
		(end 345.451176 -288.66592)
		(width 0.350012)
		(layer "F.Cu")
		(net "GND")
	)
	(segment
		(start 82.467958 -281.110436)
		(end 82.001106 -281.376374)
		(width 0.350012)
		(layer "F.Cu")
		(net "GND")
	)
	(segment
		(start 11.533124 -50.099214)
		(end 11.537442 -50.094896)
		(width 0.4572)
		(layer "F.Cu")
		(net "GND")
	)
	(segment
		(start 388.217918 -290.019994)
		(end 388.68477 -290.285932)
		(width 0.350012)
		(layer "F.Cu")
		(net "GND")
	)
	(segment
		(start 167.337994 -347.294454)
		(end 167.337994 -348.284546)
		(width 0.381)
		(layer "F.Cu")
		(net "GND")
	)
	(segment
		(start 126.647956 -287.590484)
		(end 127.114808 -287.856422)
		(width 0.350012)
		(layer "F.Cu")
		(net "GND")
	)
	(segment
		(start 27.547062 -12.372848)
		(end 27.547062 -11.26998)
		(width 0.3556)
		(layer "F.Cu")
		(net "GND")
	)
	(segment
		(start 18.54708 -12.372848)
		(end 18.54708 -11.26998)
		(width 0.3556)
		(layer "F.Cu")
		(net "GND")
	)
	(segment
		(start 364.417864 -250.420124)
		(end 364.884716 -250.154186)
		(width 0.350012)
		(layer "F.Cu")
		(net "GND")
	)
	(segment
		(start 365.828072 -243.13007)
		(end 366.294924 -242.864132)
		(width 0.350012)
		(layer "F.Cu")
		(net "GND")
	)
	(segment
		(start 374.588024 -282.730194)
		(end 375.054876 -282.996132)
		(width 0.350012)
		(layer "F.Cu")
		(net "GND")
	)
	(segment
		(start 98.245676 -391.281158)
		(end 98.54565 -390.761474)
		(width 0.254)
		(layer "F.Cu")
		(net "GND")
	)
	(segment
		(start 378.048012 -251.23013)
		(end 378.514864 -250.964192)
		(width 0.350012)
		(layer "F.Cu")
		(net "GND")
	)
	(segment
		(start 454.188068 -312.084974)
		(end 452.803768 -312.084974)
		(width 0.4572)
		(layer "F.Cu")
		(net "GND")
	)
	(segment
		(start 422.180766 -402.4757)
		(end 422.180766 -401.873212)
		(width 0.254)
		(layer "F.Cu")
		(net "GND")
	)
	(segment
		(start 114.428016 -287.590484)
		(end 114.894614 -287.856422)
		(width 0.350012)
		(layer "F.Cu")
		(net "GND")
	)
	(segment
		(start 87.167974 -281.110436)
		(end 86.701122 -281.376374)
		(width 0.350012)
		(layer "F.Cu")
		(net "GND")
	)
	(segment
		(start 365.828072 -228.550216)
		(end 366.294924 -228.284278)
		(width 0.350012)
		(layer "F.Cu")
		(net "GND")
	)
	(segment
		(start 177.122074 -123.45289)
		(end 176.732184 -123.84278)
		(width 0.254)
		(layer "F.Cu")
		(net "GND")
	)
	(segment
		(start 354.078032 -224.500186)
		(end 353.61118 -224.234248)
		(width 0.350012)
		(layer "F.Cu")
		(net "GND")
	)
	(segment
		(start 143.160242 -385.58216)
		(end 143.693642 -385.58216)
		(width 0.254)
		(layer "F.Cu")
		(net "GND")
	)
	(segment
		(start 307.791612 -351.927922)
		(end 308.379622 -351.927922)
		(width 0.381)
		(layer "F.Cu")
		(net "GND")
	)
	(segment
		(start 126.347982 -235.030264)
		(end 126.814834 -234.764326)
		(width 0.350012)
		(layer "F.Cu")
		(net "GND")
	)
	(segment
		(start 164.498274 -390.160002)
		(end 163.819078 -390.160002)
		(width 0.254)
		(layer "F.Cu")
		(net "GND")
	)
	(segment
		(start 379.51791 -399.143474)
		(end 379.570488 -398.542002)
		(width 0.254)
		(layer "F.Cu")
		(net "GND")
	)
	(segment
		(start 384.927856 -279.49017)
		(end 385.394708 -279.756108)
		(width 0.350012)
		(layer "F.Cu")
		(net "GND")
	)
	(segment
		(start 162.052 -105.51795)
		(end 161.3408 -105.51795)
		(width 0.381)
		(layer "F.Cu")
		(net "GND")
	)
	(segment
		(start 351.25787 -235.840016)
		(end 350.791018 -235.574078)
		(width 0.350012)
		(layer "F.Cu")
		(net "GND")
	)
	(segment
		(start 142.346934 -16.549878)
		(end 142.348204 -16.551148)
		(width 0.3556)
		(layer "F.Cu")
		(net "GND")
	)
	(segment
		(start 349.44558 -391.784586)
		(end 349.44558 -392.004296)
		(width 0.254)
		(layer "F.Cu")
		(net "GND")
	)
	(segment
		(start 104.475026 -397.13408)
		(end 104.475026 -396.701518)
		(width 0.3048)
		(layer "F.Cu")
		(net "GND")
	)
	(segment
		(start 332.060042 -393.04468)
		(end 332.593442 -393.04468)
		(width 0.254)
		(layer "F.Cu")
		(net "GND")
	)
	(segment
		(start 176.694338 -30.338014)
		(end 176.694084 -30.33776)
		(width 0.254)
		(layer "F.Cu")
		(net "GND")
	)
	(segment
		(start 409.345638 -391.784586)
		(end 409.345638 -391.333482)
		(width 0.254)
		(layer "F.Cu")
		(net "GND")
	)
	(segment
		(start 376.174 -427.827186)
		(end 375.76125 -428.239936)
		(width 0.254)
		(layer "F.Cu")
		(net "GND")
	)
	(segment
		(start 138.098022 -234.220258)
		(end 138.564874 -233.95432)
		(width 0.350012)
		(layer "F.Cu")
		(net "GND")
	)
	(segment
		(start 164.918136 -419.827964)
		(end 164.918136 -421.216582)
		(width 0.3048)
		(layer "F.Cu")
		(net "GND")
	)
	(segment
		(start 315.816234 -399.76171)
		(end 315.717682 -399.663158)
		(width 0.254)
		(layer "F.Cu")
		(net "GND")
	)
	(segment
		(start 355.31806 -285.160212)
		(end 354.851208 -285.42615)
		(width 0.350012)
		(layer "F.Cu")
		(net "GND")
	)
	(segment
		(start 368.64798 -228.550216)
		(end 369.114832 -228.284278)
		(width 0.350012)
		(layer "F.Cu")
		(net "GND")
	)
	(segment
		(start 255.13284 -92.319094)
		(end 255.799082 -92.319094)
		(width 0.4572)
		(layer "F.Cu")
		(net "GND")
	)
	(segment
		(start 419.912038 -296.78503)
		(end 421.296338 -296.78503)
		(width 0.4572)
		(layer "F.Cu")
		(net "GND")
	)
	(segment
		(start 99.606862 -55.04053)
		(end 98.98507 -55.04053)
		(width 0.508)
		(layer "F.Cu")
		(net "GND")
	)
	(segment
		(start 146.49831 -384.617722)
		(end 147.09013 -384.617722)
		(width 0.254)
		(layer "F.Cu")
		(net "GND")
	)
	(segment
		(start 88.306402 -386.449062)
		(end 87.798402 -386.6388)
		(width 0.254)
		(layer "F.Cu")
		(net "GND")
	)
	(segment
		(start 310.75757 -22.585934)
		(end 310.75757 -23.201884)
		(width 0.4572)
		(layer "F.Cu")
		(net "GND")
	)
	(segment
		(start 345.618054 -237.460028)
		(end 345.151202 -237.19409)
		(width 0.350012)
		(layer "F.Cu")
		(net "GND")
	)
	(segment
		(start 340.845902 -396.710662)
		(end 340.198202 -396.520924)
		(width 0.254)
		(layer "F.Cu")
		(net "GND")
	)
	(segment
		(start 379.457966 -256.900172)
		(end 379.924818 -256.634234)
		(width 0.350012)
		(layer "F.Cu")
		(net "GND")
	)
	(segment
		(start 386.338064 -270.580104)
		(end 386.804916 -270.846042)
		(width 0.350012)
		(layer "F.Cu")
		(net "GND")
	)
	(segment
		(start 127.42545 -27.463496)
		(end 127.71501 -27.173936)
		(width 0.3556)
		(layer "F.Cu")
		(net "GND")
	)
	(segment
		(start 373.64797 -279.49017)
		(end 374.114822 -279.756108)
		(width 0.350012)
		(layer "F.Cu")
		(net "GND")
	)
	(segment
		(start 114.127788 -230.170228)
		(end 114.59464 -229.90429)
		(width 0.350012)
		(layer "F.Cu")
		(net "GND")
	)
	(segment
		(start 376.167904 -225.310192)
		(end 376.634756 -225.044254)
		(width 0.350012)
		(layer "F.Cu")
		(net "GND")
	)
	(segment
		(start 32.947102 -10.16635)
		(end 32.945832 -10.16508)
		(width 0.3556)
		(layer "F.Cu")
		(net "GND")
	)
	(segment
		(start 97.677986 -226.120452)
		(end 97.211134 -225.854514)
		(width 0.350012)
		(layer "F.Cu")
		(net "GND")
	)
	(segment
		(start 416.898328 -392.999722)
		(end 416.84575 -392.30427)
		(width 0.254)
		(layer "F.Cu")
		(net "GND")
	)
	(segment
		(start 344.207846 -223.69018)
		(end 343.740994 -223.424242)
		(width 0.350012)
		(layer "F.Cu")
		(net "GND")
	)
	(segment
		(start 333.39786 -232.599992)
		(end 332.931008 -232.334054)
		(width 0.350012)
		(layer "F.Cu")
		(net "GND")
	)
	(segment
		(start 305.63439 -351.973896)
		(end 305.381152 -352.227134)
		(width 0.381)
		(layer "F.Cu")
		(net "GND")
	)
	(segment
		(start 50.71491 -348.546166)
		(end 51.143408 -348.546166)
		(width 0.2286)
		(layer "F.Cu")
		(net "GND")
	)
	(segment
		(start 93.44787 -251.230384)
		(end 92.981018 -250.964446)
		(width 0.350012)
		(layer "F.Cu")
		(net "GND")
	)
	(segment
		(start 316.213236 -360.300016)
		(end 316.202568 -360.289348)
		(width 0.381)
		(layer "F.Cu")
		(net "GND")
	)
	(segment
		(start 159.006286 -386.449062)
		(end 158.498286 -386.6388)
		(width 0.254)
		(layer "F.Cu")
		(net "GND")
	)
	(segment
		(start 138.334242 -381.7874)
		(end 138.334242 -381.064262)
		(width 0.254)
		(layer "F.Cu")
		(net "GND")
	)
	(segment
		(start 50.470562 -386.6388)
		(end 49.778666 -386.449062)
		(width 0.254)
		(layer "F.Cu")
		(net "GND")
	)
	(segment
		(start 391.03808 -283.5402)
		(end 391.504678 -283.806138)
		(width 0.350012)
		(layer "F.Cu")
		(net "GND")
	)
	(segment
		(start 340.696296 -340.282022)
		(end 340.328504 -340.282022)
		(width 0.381)
		(layer "F.Cu")
		(net "GND")
	)
	(segment
		(start 93.747844 -290.830254)
		(end 93.280992 -291.096192)
		(width 0.350012)
		(layer "F.Cu")
		(net "GND")
	)
	(segment
		(start 188.18479 -356.578408)
		(end 187.931552 -356.831646)
		(width 0.381)
		(layer "F.Cu")
		(net "GND")
	)
	(segment
		(start 194.604132 -219.435426)
		(end 195.988432 -219.435426)
		(width 0.4572)
		(layer "F.Cu")
		(net "GND")
	)
	(segment
		(start 28.28417 -351.932748)
		(end 28.35402 -351.862898)
		(width 0.381)
		(layer "F.Cu")
		(net "GND")
	)
	(segment
		(start 353.137978 -235.840016)
		(end 352.671126 -235.574078)
		(width 0.350012)
		(layer "F.Cu")
		(net "GND")
	)
	(segment
		(start 412.367984 -312.935112)
		(end 413.752284 -312.935112)
		(width 0.4572)
		(layer "F.Cu")
		(net "GND")
	)
	(segment
		(start 87.167974 -290.830254)
		(end 86.701122 -291.096192)
		(width 0.350012)
		(layer "F.Cu")
		(net "GND")
	)
	(segment
		(start 383.86385 -180.961538)
		(end 383.478024 -180.961538)
		(width 0.2286)
		(layer "F.Cu")
		(net "GND")
	)
	(segment
		(start 80.287876 -236.650276)
		(end 79.821024 -236.384338)
		(width 0.350012)
		(layer "F.Cu")
		(net "GND")
	)
	(segment
		(start 354.842318 -395.613128)
		(end 354.598224 -395.369034)
		(width 0.254)
		(layer "F.Cu")
		(net "GND")
	)
	(segment
		(start 36.640262 -418.849048)
		(end 36.640262 -418.264848)
		(width 0.3556)
		(layer "F.Cu")
		(net "GND")
	)
	(segment
		(start 52.81803 -390.761474)
		(end 52.870608 -390.160002)
		(width 0.254)
		(layer "F.Cu")
		(net "GND")
	)
	(segment
		(start 378.988066 -225.310192)
		(end 379.454918 -225.044254)
		(width 0.350012)
		(layer "F.Cu")
		(net "GND")
	)
	(segment
		(start 14.265402 -106.32567)
		(end 14.265402 -105.937812)
		(width 0.3556)
		(layer "F.Cu")
		(net "GND")
	)
	(segment
		(start 114.478562 -386.449062)
		(end 113.721134 -386.630926)
		(width 0.254)
		(layer "F.Cu")
		(net "GND")
	)
	(segment
		(start 288.180018 -219.435172)
		(end 289.564318 -219.435172)
		(width 0.4572)
		(layer "F.Cu")
		(net "GND")
	)
	(segment
		(start 105.967784 -273.010376)
		(end 105.500932 -273.276314)
		(width 0.350012)
		(layer "F.Cu")
		(net "GND")
	)
	(segment
		(start 454.188068 -274.684998)
		(end 452.803768 -274.684998)
		(width 0.4572)
		(layer "F.Cu")
		(net "GND")
	)
	(segment
		(start 375.698004 -224.500186)
		(end 376.164856 -224.234248)
		(width 0.350012)
		(layer "F.Cu")
		(net "GND")
	)
	(segment
		(start 295.724072 -231.335072)
		(end 297.108372 -231.335072)
		(width 0.4572)
		(layer "F.Cu")
		(net "GND")
	)
	(segment
		(start 183.522112 -116.252752)
		(end 183.132222 -116.642642)
		(width 0.254)
		(layer "F.Cu")
		(net "GND")
	)
	(segment
		(start 80.287876 -233.410252)
		(end 79.821024 -233.144314)
		(width 0.350012)
		(layer "F.Cu")
		(net "GND")
	)
	(segment
		(start 69.493638 -386.84073)
		(end 69.73697 -387.084062)
		(width 0.381)
		(layer "F.Cu")
		(net "GND")
	)
	(segment
		(start 146.248882 -384.86715)
		(end 146.49831 -384.617722)
		(width 0.254)
		(layer "F.Cu")
		(net "GND")
	)
	(segment
		(start 389.414766 -396.213076)
		(end 388.618476 -396.710662)
		(width 0.254)
		(layer "F.Cu")
		(net "GND")
	)
	(segment
		(start 346.705936 -394.831062)
		(end 346.19819 -395.0208)
		(width 0.254)
		(layer "F.Cu")
		(net "GND")
	)
	(segment
		(start 58.812938 -351.978722)
		(end 58.5597 -352.23196)
		(width 0.381)
		(layer "F.Cu")
		(net "GND")
	)
	(segment
		(start 372.238016 -278.680164)
		(end 372.704868 -278.946102)
		(width 0.350012)
		(layer "F.Cu")
		(net "GND")
	)
	(segment
		(start 239.13592 -293.42207)
		(end 239.368076 -293.654226)
		(width 0.4572)
		(layer "F.Cu")
		(net "GND")
	)
	(segment
		(start 59.428126 -312.085228)
		(end 58.043826 -312.085228)
		(width 0.4572)
		(layer "F.Cu")
		(net "GND")
	)
	(segment
		(start 32.947102 -9.423654)
		(end 32.948372 -9.424924)
		(width 0.3556)
		(layer "F.Cu")
		(net "GND")
	)
	(segment
		(start 180.339492 -26.240232)
		(end 180.891688 -26.240232)
		(width 0.4572)
		(layer "F.Cu")
		(net "GND")
	)
	(segment
		(start 100.327968 -282.730448)
		(end 99.861116 -282.996386)
		(width 0.350012)
		(layer "F.Cu")
		(net "GND")
	)
	(segment
		(start 421.942514 -396.213076)
		(end 422.162224 -396.213076)
		(width 0.254)
		(layer "F.Cu")
		(net "GND")
	)
	(segment
		(start 376.167904 -230.169974)
		(end 376.634756 -229.904036)
		(width 0.350012)
		(layer "F.Cu")
		(net "GND")
	)
	(segment
		(start 305.778408 -394.831062)
		(end 305.270408 -395.0208)
		(width 0.254)
		(layer "F.Cu")
		(net "GND")
	)
	(segment
		(start 319.617852 -399.143474)
		(end 319.67043 -398.542002)
		(width 0.254)
		(layer "F.Cu")
		(net "GND")
	)
	(segment
		(start 359.078022 -273.820128)
		(end 358.61117 -274.086066)
		(width 0.350012)
		(layer "F.Cu")
		(net "GND")
	)
	(segment
		(start 44.340018 -209.235294)
		(end 42.955718 -209.235294)
		(width 0.4572)
		(layer "F.Cu")
		(net "GND")
	)
	(segment
		(start 269.423134 -333.045562)
		(end 270.45285 -333.045562)
		(width 0.4572)
		(layer "F.Cu")
		(net "GND")
	)
	(segment
		(start 92.113354 -73.110852)
		(end 91.608656 -73.110852)
		(width 0.2286)
		(layer "F.Cu")
		(net "GND")
	)
	(segment
		(start 84.19846 -386.6388)
		(end 83.50631 -386.449062)
		(width 0.254)
		(layer "F.Cu")
		(net "GND")
	)
	(segment
		(start 370.057934 -253.660148)
		(end 370.524786 -253.39421)
		(width 0.350012)
		(layer "F.Cu")
		(net "GND")
	)
	(segment
		(start 336.987896 -266.530074)
		(end 336.521044 -266.796012)
		(width 0.350012)
		(layer "F.Cu")
		(net "GND")
	)
	(segment
		(start 326.81799 -248.800112)
		(end 326.351138 -248.534174)
		(width 0.350012)
		(layer "F.Cu")
		(net "GND")
	)
	(segment
		(start 393.046966 -8.320024)
		(end 393.048236 -9.424924)
		(width 0.3556)
		(layer "F.Cu")
		(net "GND")
	)
	(segment
		(start 76.184252 -402.814536)
		(end 76.184252 -403.590252)
		(width 0.381)
		(layer "F.Cu")
		(net "GND")
	)
	(segment
		(start 328.998072 -277.060152)
		(end 328.53122 -277.32609)
		(width 0.350012)
		(layer "F.Cu")
		(net "GND")
	)
	(segment
		(start 363.00791 -243.13007)
		(end 363.474762 -242.864132)
		(width 0.350012)
		(layer "F.Cu")
		(net "GND")
	)
	(segment
		(start 45.657008 -8.320024)
		(end 45.657008 -9.423654)
		(width 0.3556)
		(layer "F.Cu")
		(net "GND")
	)
	(segment
		(start 47.784004 -287.43529)
		(end 49.168304 -287.43529)
		(width 0.4572)
		(layer "F.Cu")
		(net "GND")
	)
	(segment
		(start 349.67799 -270.580104)
		(end 349.211138 -270.846042)
		(width 0.350012)
		(layer "F.Cu")
		(net "GND")
	)
	(segment
		(start 370.997988 -247.1801)
		(end 371.46484 -246.914162)
		(width 0.350012)
		(layer "F.Cu")
		(net "GND")
	)
	(segment
		(start 365.357918 -229.360222)
		(end 365.82477 -229.094284)
		(width 0.350012)
		(layer "F.Cu")
		(net "GND")
	)
	(segment
		(start 136.687814 -251.230384)
		(end 137.154666 -250.964446)
		(width 0.350012)
		(layer "F.Cu")
		(net "GND")
	)
	(segment
		(start 363.307884 -276.250146)
		(end 363.774736 -276.516084)
		(width 0.350012)
		(layer "F.Cu")
		(net "GND")
	)
	(segment
		(start 109.897926 -250.420378)
		(end 109.431074 -250.15444)
		(width 0.350012)
		(layer "F.Cu")
		(net "GND")
	)
	(segment
		(start 134.80796 -230.170228)
		(end 135.274812 -229.90429)
		(width 0.350012)
		(layer "F.Cu")
		(net "GND")
	)
	(segment
		(start 390.737852 -243.940076)
		(end 391.204704 -243.674138)
		(width 0.350012)
		(layer "F.Cu")
		(net "GND")
	)
	(segment
		(start 391.50798 -285.970218)
		(end 391.974832 -286.236156)
		(width 0.350012)
		(layer "F.Cu")
		(net "GND")
	)
	(segment
		(start 399.160238 -393.04468)
		(end 399.693638 -393.04468)
		(width 0.254)
		(layer "F.Cu")
		(net "GND")
	)
	(segment
		(start 85.287866 -294.070278)
		(end 84.821014 -294.336216)
		(width 0.350012)
		(layer "F.Cu")
		(net "GND")
	)
	(segment
		(start 168.821862 -436.132224)
		(end 168.180766 -436.132224)
		(width 0.381)
		(layer "F.Cu")
		(net "GND")
	)
	(segment
		(start 261.05104 -114.765328)
		(end 261.05104 -115.481354)
		(width 0.3556)
		(layer "F.Cu")
		(net "GND")
	)
	(segment
		(start 94.217998 -268.960346)
		(end 93.751146 -269.226284)
		(width 0.350012)
		(layer "F.Cu")
		(net "GND")
	)
	(segment
		(start 90.157808 -252.04039)
		(end 89.690956 -251.774452)
		(width 0.350012)
		(layer "F.Cu")
		(net "GND")
	)
	(segment
		(start 118.357904 -235.84027)
		(end 118.824756 -235.574332)
		(width 0.350012)
		(layer "F.Cu")
		(net "GND")
	)
	(segment
		(start 46.621192 -384.86715)
		(end 46.87062 -384.617722)
		(width 0.254)
		(layer "F.Cu")
		(net "GND")
	)
	(segment
		(start 389.327898 -230.169974)
		(end 389.79475 -229.904036)
		(width 0.350012)
		(layer "F.Cu")
		(net "GND")
	)
	(segment
		(start 130.07848 -386.449062)
		(end 129.57048 -386.6388)
		(width 0.254)
		(layer "F.Cu")
		(net "GND")
	)
	(segment
		(start 109.728 -273.010376)
		(end 109.261148 -273.276314)
		(width 0.350012)
		(layer "F.Cu")
		(net "GND")
	)
	(segment
		(start 125.877828 -229.360476)
		(end 126.34468 -229.094538)
		(width 0.350012)
		(layer "F.Cu")
		(net "GND")
	)
	(segment
		(start 127.762254 -384.617722)
		(end 127.170434 -384.617722)
		(width 0.254)
		(layer "F.Cu")
		(net "GND")
	)
	(segment
		(start 356.42804 -231.789986)
		(end 355.961188 -231.524048)
		(width 0.350012)
		(layer "F.Cu")
		(net "GND")
	)
	(segment
		(start 386.03809 -253.660148)
		(end 386.504942 -253.39421)
		(width 0.350012)
		(layer "F.Cu")
		(net "GND")
	)
	(segment
		(start 174.844456 -418.056314)
		(end 174.45355 -418.44722)
		(width 0.381)
		(layer "F.Cu")
		(net "GND")
	)
	(segment
		(start 80.245712 -383.622296)
		(end 80.545686 -383.92227)
		(width 0.254)
		(layer "F.Cu")
		(net "GND")
	)
	(segment
		(start 72.5551 -382.27)
		(end 73.02373 -382.27)
		(width 0.254)
		(layer "F.Cu")
		(net "GND")
	)
	(segment
		(start 29.252164 -211.7852)
		(end 27.867864 -211.7852)
		(width 0.4572)
		(layer "F.Cu")
		(net "GND")
	)
	(segment
		(start 335.577942 -267.34008)
		(end 335.11109 -267.606018)
		(width 0.350012)
		(layer "F.Cu")
		(net "GND")
	)
	(segment
		(start 97.037906 -267.340334)
		(end 96.571054 -267.606272)
		(width 0.350012)
		(layer "F.Cu")
		(net "GND")
	)
	(segment
		(start 332.28788 -281.110182)
		(end 331.821028 -281.37612)
		(width 0.350012)
		(layer "F.Cu")
		(net "GND")
	)
	(segment
		(start 102.677976 -293.260272)
		(end 102.211124 -293.52621)
		(width 0.350012)
		(layer "F.Cu")
		(net "GND")
	)
	(segment
		(start 146.38782 -268.15034)
		(end 147.042886 -268.15034)
		(width 0.350012)
		(layer "F.Cu")
		(net "GND")
	)
	(segment
		(start 118.187978 -279.490424)
		(end 118.65483 -279.756362)
		(width 0.350012)
		(layer "F.Cu")
		(net "GND")
	)
	(segment
		(start 81.445862 -382.951482)
		(end 81.544414 -382.85293)
		(width 0.254)
		(layer "F.Cu")
		(net "GND")
	)
	(segment
		(start 347.797882 -272.200116)
		(end 347.33103 -272.466054)
		(width 0.350012)
		(layer "F.Cu")
		(net "GND")
	)
	(segment
		(start 127.117856 -293.260272)
		(end 127.584708 -293.52621)
		(width 0.350012)
		(layer "F.Cu")
		(net "GND")
	)
	(segment
		(start 104.475026 -396.701518)
		(end 104.310688 -396.53718)
		(width 0.3048)
		(layer "F.Cu")
		(net "GND")
	)
	(segment
		(start 353.137978 -247.1801)
		(end 352.671126 -246.914162)
		(width 0.350012)
		(layer "F.Cu")
		(net "GND")
	)
	(segment
		(start 371.938042 -247.1801)
		(end 372.404894 -246.914162)
		(width 0.350012)
		(layer "F.Cu")
		(net "GND")
	)
	(segment
		(start 84.517992 -250.420378)
		(end 84.05114 -250.15444)
		(width 0.350012)
		(layer "F.Cu")
		(net "GND")
	)
	(segment
		(start 95.327978 -235.030264)
		(end 94.861126 -234.764326)
		(width 0.350012)
		(layer "F.Cu")
		(net "GND")
	)
	(segment
		(start 339.518752 -398.542002)
		(end 338.998052 -398.542002)
		(width 0.254)
		(layer "F.Cu")
		(net "GND")
	)
	(segment
		(start 140.748004 -268.15034)
		(end 141.214856 -268.416278)
		(width 0.350012)
		(layer "F.Cu")
		(net "GND")
	)
	(segment
		(start 162.90417 -428.46498)
		(end 162.90417 -428.23638)
		(width 0.3048)
		(layer "F.Cu")
		(net "GND")
	)
	(segment
		(start 256.192274 -134.605268)
		(end 257.125724 -134.605268)
		(width 0.3556)
		(layer "F.Cu")
		(net "GND")
	)
	(segment
		(start 388.387844 -225.310192)
		(end 388.85495 -225.044254)
		(width 0.350012)
		(layer "F.Cu")
		(net "GND")
	)
	(segment
		(start 335.108042 -274.630134)
		(end 334.64119 -274.896072)
		(width 0.350012)
		(layer "F.Cu")
		(net "GND")
	)
	(segment
		(start 53.68544 -394.716)
		(end 53.816504 -394.584936)
		(width 0.381)
		(layer "F.Cu")
		(net "GND")
	)
	(segment
		(start 84.347812 -282.730448)
		(end 83.88096 -282.996386)
		(width 0.350012)
		(layer "F.Cu")
		(net "GND")
	)
	(segment
		(start 332.230476 -336.798666)
		(end 332.658974 -336.798666)
		(width 0.2286)
		(layer "F.Cu")
		(net "GND")
	)
	(segment
		(start 386.338064 -283.5402)
		(end 386.804916 -283.806138)
		(width 0.350012)
		(layer "F.Cu")
		(net "GND")
	)
	(segment
		(start 45.657008 -11.26998)
		(end 45.657008 -10.16635)
		(width 0.3556)
		(layer "F.Cu")
		(net "GND")
	)
	(segment
		(start 95.590106 -384.617722)
		(end 96.198436 -384.617722)
		(width 0.254)
		(layer "F.Cu")
		(net "GND")
	)
	(segment
		(start 431.55616 -209.23504)
		(end 430.17186 -209.23504)
		(width 0.4572)
		(layer "F.Cu")
		(net "GND")
	)
	(segment
		(start 356.25786 -285.160212)
		(end 355.791008 -285.42615)
		(width 0.350012)
		(layer "F.Cu")
		(net "GND")
	)
	(segment
		(start 126.723902 -30.249368)
		(end 127.212344 -30.249368)
		(width 0.381)
		(layer "F.Cu")
		(net "GND")
	)
	(segment
		(start 116.370608 -388.138924)
		(end 115.818412 -388.328662)
		(width 0.254)
		(layer "F.Cu")
		(net "GND")
	)
	(segment
		(start 187.060078 -210.085432)
		(end 188.444378 -210.085432)
		(width 0.4572)
		(layer "F.Cu")
		(net "GND")
	)
	(segment
		(start 15.98422 -79.467964)
		(end 15.98422 -78.830678)
		(width 0.4064)
		(layer "F.Cu")
		(net "GND")
	)
	(segment
		(start 135.593074 -154.365706)
		(end 135.252714 -154.706066)
		(width 0.2286)
		(layer "F.Cu")
		(net "GND")
	)
	(segment
		(start 393.092178 -179.678584)
		(end 393.06119 -179.678584)
		(width 0.2286)
		(layer "F.Cu")
		(net "GND")
	)
	(segment
		(start 424.012106 -202.434952)
		(end 422.627806 -202.434952)
		(width 0.4572)
		(layer "F.Cu")
		(net "GND")
	)
	(segment
		(start 84.040726 -337.33232)
		(end 84.040726 -337.056476)
		(width 0.2286)
		(layer "F.Cu")
		(net "GND")
	)
	(segment
		(start 102.677976 -267.340334)
		(end 102.211124 -267.606272)
		(width 0.350012)
		(layer "F.Cu")
		(net "GND")
	)
	(segment
		(start 71.2343 -381.7874)
		(end 71.2343 -381.064262)
		(width 0.254)
		(layer "F.Cu")
		(net "GND")
	)
	(segment
		(start 165.345618 -391.281158)
		(end 165.645592 -390.761474)
		(width 0.254)
		(layer "F.Cu")
		(net "GND")
	)
	(segment
		(start 365.357918 -235.840016)
		(end 365.82477 -235.574078)
		(width 0.350012)
		(layer "F.Cu")
		(net "GND")
	)
	(segment
		(start 370.997988 -240.700052)
		(end 371.46484 -240.434114)
		(width 0.350012)
		(layer "F.Cu")
		(net "GND")
	)
	(segment
		(start 153.94305 -104.648)
		(end 154.668474 -104.648)
		(width 0.381)
		(layer "F.Cu")
		(net "GND")
	)
	(segment
		(start 146.06905 -118.364)
		(end 146.761454 -118.364)
		(width 0.381)
		(layer "F.Cu")
		(net "GND")
	)
	(segment
		(start 139.507976 -247.99036)
		(end 139.974828 -247.724422)
		(width 0.350012)
		(layer "F.Cu")
		(net "GND")
	)
	(segment
		(start 305.270408 -392.999722)
		(end 304.662078 -392.999722)
		(width 0.254)
		(layer "F.Cu")
		(net "GND")
	)
	(segment
		(start 394.981938 -395.4399)
		(end 395.794738 -395.4399)
		(width 0.254)
		(layer "F.Cu")
		(net "GND")
	)
	(segment
		(start 446.644268 -211.784946)
		(end 445.259968 -211.784946)
		(width 0.4572)
		(layer "F.Cu")
		(net "GND")
	)
	(segment
		(start 369.417854 -260.860032)
		(end 369.884706 -261.12597)
		(width 0.350012)
		(layer "F.Cu")
		(net "GND")
	)
	(segment
		(start 86.868 -243.130324)
		(end 86.401148 -242.864386)
		(width 0.350012)
		(layer "F.Cu")
		(net "GND")
	)
	(segment
		(start 149.844252 -391.37971)
		(end 149.7457 -391.281158)
		(width 0.254)
		(layer "F.Cu")
		(net "GND")
	)
	(segment
		(start 80.757776 -230.980234)
		(end 80.291178 -230.71455)
		(width 0.350012)
		(layer "F.Cu")
		(net "GND")
	)
	(segment
		(start 130.877818 -293.260272)
		(end 131.34467 -293.52621)
		(width 0.350012)
		(layer "F.Cu")
		(net "GND")
	)
	(segment
		(start 51.317906 -383.402586)
		(end 51.317906 -382.951482)
		(width 0.2032)
		(layer "F.Cu")
		(net "GND")
	)
	(segment
		(start 105.497884 -290.020248)
		(end 105.031032 -290.286186)
		(width 0.350012)
		(layer "F.Cu")
		(net "GND")
	)
	(segment
		(start 105.19791 -242.320318)
		(end 104.731058 -242.05438)
		(width 0.350012)
		(layer "F.Cu")
		(net "GND")
	)
	(segment
		(start 381.617982 -391.784586)
		(end 381.617982 -392.004296)
		(width 0.254)
		(layer "F.Cu")
		(net "GND")
	)
	(segment
		(start 146.248882 -389.030972)
		(end 146.248882 -388.330948)
		(width 0.254)
		(layer "F.Cu")
		(net "GND")
	)
	(segment
		(start 307.368194 -237.285022)
		(end 305.983894 -237.285022)
		(width 0.4572)
		(layer "F.Cu")
		(net "GND")
	)
	(segment
		(start 32.695896 -275.53539)
		(end 34.080196 -275.53539)
		(width 0.4572)
		(layer "F.Cu")
		(net "GND")
	)
	(segment
		(start 44.340018 -277.235412)
		(end 42.955718 -277.235412)
		(width 0.4572)
		(layer "F.Cu")
		(net "GND")
	)
	(segment
		(start 79.14894 -390.564624)
		(end 79.34579 -390.761474)
		(width 0.254)
		(layer "F.Cu")
		(net "GND")
	)
	(segment
		(start 371.297962 -262.480044)
		(end 371.764814 -262.745982)
		(width 0.350012)
		(layer "F.Cu")
		(net "GND")
	)
	(segment
		(start 92.371926 -337.107276)
		(end 92.62491 -336.854292)
		(width 0.2286)
		(layer "F.Cu")
		(net "GND")
	)
	(segment
		(start 115.067842 -238.270288)
		(end 115.534694 -238.00435)
		(width 0.350012)
		(layer "F.Cu")
		(net "GND")
	)
	(segment
		(start 131.047998 -225.310446)
		(end 131.51485 -225.044508)
		(width 0.350012)
		(layer "F.Cu")
		(net "GND")
	)
	(segment
		(start 383.048002 -285.970218)
		(end 383.514854 -286.236156)
		(width 0.350012)
		(layer "F.Cu")
		(net "GND")
	)
	(segment
		(start 141.687804 -264.910316)
		(end 142.154656 -265.176254)
		(width 0.350012)
		(layer "F.Cu")
		(net "GND")
	)
	(segment
		(start 139.977876 -248.800366)
		(end 140.444728 -248.534428)
		(width 0.350012)
		(layer "F.Cu")
		(net "GND")
	)
	(segment
		(start 102.847902 -243.130324)
		(end 102.38105 -242.864386)
		(width 0.350012)
		(layer "F.Cu")
		(net "GND")
	)
	(segment
		(start 72.235568 -341.04707)
		(end 71.625968 -341.04707)
		(width 0.4572)
		(layer "F.Cu")
		(net "GND")
	)
	(segment
		(start 335.577942 -278.680164)
		(end 335.11109 -278.946102)
		(width 0.350012)
		(layer "F.Cu")
		(net "GND")
	)
	(segment
		(start 47.784004 -219.435426)
		(end 49.168304 -219.435426)
		(width 0.4572)
		(layer "F.Cu")
		(net "GND")
	)
	(segment
		(start 140.27785 -280.30043)
		(end 140.744702 -280.566368)
		(width 0.350012)
		(layer "F.Cu")
		(net "GND")
	)
	(segment
		(start 331.39507 -20.76577)
		(end 331.39507 -20.270978)
		(width 0.381)
		(layer "F.Cu")
		(net "GND")
	)
	(segment
		(start 127.117856 -280.30043)
		(end 127.584708 -280.566368)
		(width 0.350012)
		(layer "F.Cu")
		(net "GND")
	)
	(segment
		(start 334.808068 -231.789986)
		(end 334.341216 -231.524048)
		(width 0.350012)
		(layer "F.Cu")
		(net "GND")
	)
	(segment
		(start 392.61796 -248.800112)
		(end 393.084812 -248.534174)
		(width 0.350012)
		(layer "F.Cu")
		(net "GND")
	)
	(segment
		(start 164.427916 -231.335326)
		(end 165.812216 -231.335326)
		(width 0.4572)
		(layer "F.Cu")
		(net "GND")
	)
	(segment
		(start 102.847902 -241.510312)
		(end 102.38105 -241.244374)
		(width 0.350012)
		(layer "F.Cu")
		(net "GND")
	)
	(segment
		(start 313.670442 -398.542002)
		(end 312.990992 -398.542002)
		(width 0.254)
		(layer "F.Cu")
		(net "GND")
	)
	(segment
		(start 118.363238 -41.5798)
		(end 118.363238 -42.2656)
		(width 0.4572)
		(layer "F.Cu")
		(net "GND")
	)
	(segment
		(start 82.467958 -271.390364)
		(end 82.001106 -271.656302)
		(width 0.350012)
		(layer "F.Cu")
		(net "GND")
	)
	(segment
		(start 171.97197 -221.985332)
		(end 173.35627 -221.985332)
		(width 0.4572)
		(layer "F.Cu")
		(net "GND")
	)
	(segment
		(start 372.877842 -247.1801)
		(end 373.344694 -246.914162)
		(width 0.350012)
		(layer "F.Cu")
		(net "GND")
	)
	(segment
		(start 179.516024 -221.985332)
		(end 180.900324 -221.985332)
		(width 0.4572)
		(layer "F.Cu")
		(net "GND")
	)
	(segment
		(start 322.950078 -60.094876)
		(end 324.543928 -60.094876)
		(width 0.4572)
		(layer "F.Cu")
		(net "GND")
	)
	(segment
		(start 96.84639 -388.328662)
		(end 97.398332 -388.138924)
		(width 0.254)
		(layer "F.Cu")
		(net "GND")
	)
	(segment
		(start 355.957886 -237.460028)
		(end 355.491034 -237.19409)
		(width 0.350012)
		(layer "F.Cu")
		(net "GND")
	)
	(segment
		(start 271.485106 -121.83237)
		(end 272.094706 -121.83237)
		(width 0.381)
		(layer "F.Cu")
		(net "GND")
	)
	(segment
		(start 409.034742 -140.884656)
		(end 409.050744 -140.900658)
		(width 0.381)
		(layer "F.Cu")
		(net "GND")
	)
	(segment
		(start 280.873962 -348.54134)
		(end 281.30246 -348.54134)
		(width 0.2286)
		(layer "F.Cu")
		(net "GND")
	)
	(segment
		(start 139.507976 -228.55047)
		(end 139.974828 -228.284532)
		(width 0.350012)
		(layer "F.Cu")
		(net "GND")
	)
	(segment
		(start 367.538 -281.920188)
		(end 368.004852 -282.186126)
		(width 0.350012)
		(layer "F.Cu")
		(net "GND")
	)
	(segment
		(start 173.769528 -57.399936)
		(end 176.333404 -57.399936)
		(width 0.3556)
		(layer "F.Cu")
		(net "GND")
	)
	(segment
		(start 139.977876 -245.560342)
		(end 140.444728 -245.294404)
		(width 0.350012)
		(layer "F.Cu")
		(net "GND")
	)
	(segment
		(start 356.42804 -236.650022)
		(end 355.961188 -236.384084)
		(width 0.350012)
		(layer "F.Cu")
		(net "GND")
	)
	(segment
		(start 332.28788 -285.970218)
		(end 331.821028 -286.236156)
		(width 0.350012)
		(layer "F.Cu")
		(net "GND")
	)
	(segment
		(start 416.556952 -8.320024)
		(end 416.556952 -9.423654)
		(width 0.3556)
		(layer "F.Cu")
		(net "GND")
	)
	(segment
		(start 329.760072 -32.953706)
		(end 330.369672 -32.953706)
		(width 0.3556)
		(layer "F.Cu")
		(net "GND")
	)
	(segment
		(start 284.736032 -295.935146)
		(end 283.351732 -295.935146)
		(width 0.4572)
		(layer "F.Cu")
		(net "GND")
	)
	(segment
		(start 269.648178 -314.635134)
		(end 268.263878 -314.635134)
		(width 0.4572)
		(layer "F.Cu")
		(net "GND")
	)
	(segment
		(start 385.217924 -391.784586)
		(end 385.217924 -391.333482)
		(width 0.254)
		(layer "F.Cu")
		(net "GND")
	)
	(segment
		(start 22.07895 -358.775)
		(end 21.336 -358.775)
		(width 0.381)
		(layer "F.Cu")
		(net "GND")
	)
	(segment
		(start 388.217918 -267.34008)
		(end 388.68477 -267.606018)
		(width 0.350012)
		(layer "F.Cu")
		(net "GND")
	)
	(segment
		(start 80.287876 -256.09042)
		(end 79.821024 -255.824482)
		(width 0.350012)
		(layer "F.Cu")
		(net "GND")
	)
	(segment
		(start 371.467888 -243.13007)
		(end 371.93474 -242.864132)
		(width 0.350012)
		(layer "F.Cu")
		(net "GND")
	)
	(segment
		(start 139.83716 -387.622796)
		(end 139.86764 -387.592316)
		(width 0.254)
		(layer "F.Cu")
		(net "GND")
	)
	(segment
		(start 103.052372 -30.219904)
		(end 102.548436 -30.219904)
		(width 0.254)
		(layer "F.Cu")
		(net "GND")
	)
	(segment
		(start 90.457782 -281.920442)
		(end 89.99093 -282.18638)
		(width 0.350012)
		(layer "F.Cu")
		(net "GND")
	)
	(segment
		(start 160.290002 -384.617722)
		(end 160.898332 -384.617722)
		(width 0.254)
		(layer "F.Cu")
		(net "GND")
	)
	(segment
		(start 346.19819 -395.0208)
		(end 345.50604 -394.831062)
		(width 0.254)
		(layer "F.Cu")
		(net "GND")
	)
	(segment
		(start 60.017914 -390.761474)
		(end 60.070492 -390.160002)
		(width 0.254)
		(layer "F.Cu")
		(net "GND")
	)
	(segment
		(start 92.037916 -243.94033)
		(end 91.571064 -243.674392)
		(width 0.350012)
		(layer "F.Cu")
		(net "GND")
	)
	(segment
		(start 112.68202 -388.431024)
		(end 112.205008 -388.29615)
		(width 0.254)
		(layer "F.Cu")
		(net "GND")
	)
	(segment
		(start 420.155624 -7.215886)
		(end 420.156894 -7.217156)
		(width 0.3556)
		(layer "F.Cu")
		(net "GND")
	)
	(segment
		(start 101.696266 -403.92985)
		(end 101.696266 -405.27351)
		(width 0.381)
		(layer "F.Cu")
		(net "GND")
	)
	(segment
		(start 86.22792 -294.070278)
		(end 85.761068 -294.336216)
		(width 0.350012)
		(layer "F.Cu")
		(net "GND")
	)
	(segment
		(start 260.231636 -101.022404)
		(end 261.041896 -101.022404)
		(width 0.4572)
		(layer "F.Cu")
		(net "GND")
	)
	(segment
		(start 392.917934 -260.860032)
		(end 393.384786 -261.12597)
		(width 0.350012)
		(layer "F.Cu")
		(net "GND")
	)
	(segment
		(start 145.92935 -388.330948)
		(end 145.729452 -388.13105)
		(width 0.254)
		(layer "F.Cu")
		(net "GND")
	)
	(segment
		(start 326.81799 -229.360222)
		(end 326.351138 -229.094284)
		(width 0.350012)
		(layer "F.Cu")
		(net "GND")
	)
	(segment
		(start 91.045792 -383.402586)
		(end 91.045792 -383.622296)
		(width 0.254)
		(layer "F.Cu")
		(net "GND")
	)
	(segment
		(start 122.41784 -277.060406)
		(end 122.884692 -277.326344)
		(width 0.350012)
		(layer "F.Cu")
		(net "GND")
	)
	(segment
		(start 344.99804 -398.542002)
		(end 344.945462 -399.143474)
		(width 0.254)
		(layer "F.Cu")
		(net "GND")
	)
	(segment
		(start 50.216562 -391.37971)
		(end 50.11801 -391.281158)
		(width 0.254)
		(layer "F.Cu")
		(net "GND")
	)
	(segment
		(start 394.84681 -12.372848)
		(end 394.84681 -11.26998)
		(width 0.3556)
		(layer "F.Cu")
		(net "GND")
	)
	(segment
		(start 97.207832 -231.79024)
		(end 96.74098 -231.524302)
		(width 0.350012)
		(layer "F.Cu")
		(net "GND")
	)
	(segment
		(start 416.468052 -277.235158)
		(end 415.083752 -277.235158)
		(width 0.4572)
		(layer "F.Cu")
		(net "GND")
	)
	(segment
		(start 131.817872 -275.440394)
		(end 132.284724 -275.706332)
		(width 0.350012)
		(layer "F.Cu")
		(net "GND")
	)
	(segment
		(start 391.03808 -260.860032)
		(end 391.504932 -261.12597)
		(width 0.350012)
		(layer "F.Cu")
		(net "GND")
	)
	(segment
		(start 111.137954 -294.880284)
		(end 110.671102 -295.146222)
		(width 0.350012)
		(layer "F.Cu")
		(net "GND")
	)
	(segment
		(start 262.848852 -136.703054)
		(end 262.217916 -136.703054)
		(width 0.381)
		(layer "F.Cu")
		(net "GND")
	)
	(segment
		(start 343.798144 -396.520924)
		(end 343.245948 -396.710662)
		(width 0.254)
		(layer "F.Cu")
		(net "GND")
	)
	(segment
		(start 160.54578 -383.402586)
		(end 160.54578 -382.951482)
		(width 0.254)
		(layer "F.Cu")
		(net "GND")
	)
	(segment
		(start 12.235688 -136.875266)
		(end 10.971784 -138.13917)
		(width 0.3556)
		(layer "F.Cu")
		(net "GND")
	)
	(segment
		(start 131.438142 -53.974492)
		(end 131.565142 -53.847492)
		(width 0.1778)
		(layer "F.Cu")
		(net "GND")
	)
	(segment
		(start 66.583814 -386.449062)
		(end 66.834512 -385.731004)
		(width 0.254)
		(layer "F.Cu")
		(net "GND")
	)
	(segment
		(start 129.938018 -272.20037)
		(end 130.40487 -272.466308)
		(width 0.350012)
		(layer "F.Cu")
		(net "GND")
	)
	(segment
		(start 131.517898 -243.94033)
		(end 131.98475 -243.674392)
		(width 0.350012)
		(layer "F.Cu")
		(net "GND")
	)
	(segment
		(start 400.518122 -171.91355)
		(end 400.518122 -171.30395)
		(width 0.381)
		(layer "F.Cu")
		(net "GND")
	)
	(segment
		(start 386.03809 -224.500186)
		(end 386.504942 -224.234248)
		(width 0.350012)
		(layer "F.Cu")
		(net "GND")
	)
	(segment
		(start 120.916446 -391.830814)
		(end 120.916446 -391.37971)
		(width 0.254)
		(layer "F.Cu")
		(net "GND")
	)
	(segment
		(start 102.847902 -246.370348)
		(end 102.38105 -246.10441)
		(width 0.350012)
		(layer "F.Cu")
		(net "GND")
	)
	(segment
		(start 379.75794 -290.019994)
		(end 380.224792 -290.285932)
		(width 0.350012)
		(layer "F.Cu")
		(net "GND")
	)
	(segment
		(start 381.167894 -290.83)
		(end 381.634746 -291.095938)
		(width 0.350012)
		(layer "F.Cu")
		(net "GND")
	)
	(segment
		(start 59.428126 -293.38524)
		(end 58.043826 -293.38524)
		(width 0.4572)
		(layer "F.Cu")
		(net "GND")
	)
	(segment
		(start 122.887994 -263.290304)
		(end 123.354846 -263.556242)
		(width 0.350012)
		(layer "F.Cu")
		(net "GND")
	)
	(segment
		(start 107.547918 -249.610372)
		(end 107.081066 -249.344434)
		(width 0.350012)
		(layer "F.Cu")
		(net "GND")
	)
	(segment
		(start 341.387938 -225.310192)
		(end 340.921086 -225.044254)
		(width 0.350012)
		(layer "F.Cu")
		(net "GND")
	)
	(segment
		(start 354.378006 -273.820128)
		(end 353.911154 -274.086066)
		(width 0.350012)
		(layer "F.Cu")
		(net "GND")
	)
	(segment
		(start 328.697844 -243.940076)
		(end 328.231246 -243.674138)
		(width 0.350012)
		(layer "F.Cu")
		(net "GND")
	)
	(segment
		(start 410.64434 -400.212814)
		(end 410.64434 -399.76171)
		(width 0.254)
		(layer "F.Cu")
		(net "GND")
	)
	(segment
		(start 142.797784 -224.50044)
		(end 143.264636 -224.234502)
		(width 0.350012)
		(layer "F.Cu")
		(net "GND")
	)
	(segment
		(start 331.352398 -411.140656)
		(end 332.424278 -412.212536)
		(width 0.381)
		(layer "F.Cu")
		(net "GND")
	)
	(segment
		(start 87.3379 -245.560342)
		(end 86.871048 -245.294404)
		(width 0.350012)
		(layer "F.Cu")
		(net "GND")
	)
	(segment
		(start 116.36121 -62.002162)
		(end 116.998496 -62.002162)
		(width 0.4572)
		(layer "F.Cu")
		(net "GND")
	)
	(segment
		(start 125.617986 -383.402586)
		(end 125.617986 -383.622296)
		(width 0.254)
		(layer "F.Cu")
		(net "GND")
	)
	(segment
		(start 87.777828 -148.94941)
		(end 87.168228 -148.94941)
		(width 0.381)
		(layer "F.Cu")
		(net "GND")
	)
	(segment
		(start 124.770642 -388.138924)
		(end 124.218446 -388.328662)
		(width 0.254)
		(layer "F.Cu")
		(net "GND")
	)
	(segment
		(start 95.627952 -266.530328)
		(end 95.1611 -266.796266)
		(width 0.350012)
		(layer "F.Cu")
		(net "GND")
	)
	(segment
		(start 356.42804 -238.270034)
		(end 355.961188 -238.004096)
		(width 0.350012)
		(layer "F.Cu")
		(net "GND")
	)
	(segment
		(start 379.75794 -291.640006)
		(end 380.224792 -291.905944)
		(width 0.350012)
		(layer "F.Cu")
		(net "GND")
	)
	(segment
		(start 355.957886 -245.560088)
		(end 355.491034 -245.29415)
		(width 0.350012)
		(layer "F.Cu")
		(net "GND")
	)
	(segment
		(start 102.378002 -248.800366)
		(end 101.91115 -248.534428)
		(width 0.350012)
		(layer "F.Cu")
		(net "GND")
	)
	(segment
		(start 42.055796 -7.215886)
		(end 42.057066 -7.217156)
		(width 0.3556)
		(layer "F.Cu")
		(net "GND")
	)
	(segment
		(start 435.000146 -312.935112)
		(end 436.384446 -312.935112)
		(width 0.4572)
		(layer "F.Cu")
		(net "GND")
	)
	(segment
		(start 199.202294 -389.880602)
		(end 195.88988 -389.880602)
		(width 0.4572)
		(layer "F.Cu")
		(net "GND")
	)
	(segment
		(start 424.012106 -293.384986)
		(end 422.627806 -293.384986)
		(width 0.4572)
		(layer "F.Cu")
		(net "GND")
	)
	(segment
		(start 319.282064 -118.682262)
		(end 319.537588 -118.426738)
		(width 0.3556)
		(layer "F.Cu")
		(net "GND")
	)
	(segment
		(start 380.86792 -225.310192)
		(end 381.334772 -225.044254)
		(width 0.350012)
		(layer "F.Cu")
		(net "GND")
	)
	(segment
		(start 423.796206 -402.163788)
		(end 424.242992 -401.717002)
		(width 0.254)
		(layer "F.Cu")
		(net "GND")
	)
	(segment
		(start 166.070534 -22.183598)
		(end 166.070534 -22.942804)
		(width 0.4572)
		(layer "F.Cu")
		(net "GND")
	)
	(segment
		(start 366.297972 -248.800112)
		(end 366.764824 -248.534174)
		(width 0.350012)
		(layer "F.Cu")
		(net "GND")
	)
	(segment
		(start 273.092164 -296.78503)
		(end 274.476464 -296.78503)
		(width 0.4572)
		(layer "F.Cu")
		(net "GND")
	)
	(segment
		(start 308.87035 -392.999722)
		(end 309.46217 -392.999722)
		(width 0.254)
		(layer "F.Cu")
		(net "GND")
	)
	(segment
		(start 416.468052 -237.285022)
		(end 415.083752 -237.285022)
		(width 0.4572)
		(layer "F.Cu")
		(net "GND")
	)
	(segment
		(start 370.817902 -391.784586)
		(end 370.817902 -391.333482)
		(width 0.254)
		(layer "F.Cu")
		(net "GND")
	)
	(segment
		(start 162.098228 -390.160002)
		(end 161.419032 -390.160002)
		(width 0.254)
		(layer "F.Cu")
		(net "GND")
	)
	(segment
		(start 328.527918 -266.530074)
		(end 328.061066 -266.796012)
		(width 0.350012)
		(layer "F.Cu")
		(net "GND")
	)
	(segment
		(start 160.845754 -390.761474)
		(end 160.898332 -390.160002)
		(width 0.254)
		(layer "F.Cu")
		(net "GND")
	)
	(segment
		(start 140.27785 -270.580358)
		(end 140.744702 -270.846296)
		(width 0.350012)
		(layer "F.Cu")
		(net "GND")
	)
	(segment
		(start 319.99809 -36.208462)
		(end 318.81699 -36.208462)
		(width 0.3556)
		(layer "F.Cu")
		(net "GND")
	)
	(segment
		(start 387.448044 -241.510058)
		(end 387.914896 -241.24412)
		(width 0.350012)
		(layer "F.Cu")
		(net "GND")
	)
	(segment
		(start 343.56802 -279.49017)
		(end 343.101168 -279.756108)
		(width 0.350012)
		(layer "F.Cu")
		(net "GND")
	)
	(segment
		(start 338.306156 -394.831062)
		(end 337.798156 -395.0208)
		(width 0.254)
		(layer "F.Cu")
		(net "GND")
	)
	(segment
		(start 80.598264 -384.617722)
		(end 80.545686 -383.92227)
		(width 0.254)
		(layer "F.Cu")
		(net "GND")
	)
	(segment
		(start 165.942518 -387.231128)
		(end 165.698424 -386.987034)
		(width 0.254)
		(layer "F.Cu")
		(net "GND")
	)
	(segment
		(start 131.517898 -253.660402)
		(end 131.98475 -253.394464)
		(width 0.350012)
		(layer "F.Cu")
		(net "GND")
	)
	(segment
		(start 139.977876 -247.180354)
		(end 140.444728 -246.914416)
		(width 0.350012)
		(layer "F.Cu")
		(net "GND")
	)
	(segment
		(start 302.101504 -396.51305)
		(end 301.792894 -396.74673)
		(width 0.254)
		(layer "F.Cu")
		(net "GND")
	)
	(segment
		(start 124.937774 -226.120452)
		(end 125.404626 -225.854514)
		(width 0.350012)
		(layer "F.Cu")
		(net "GND")
	)
	(segment
		(start 105.66781 -247.99036)
		(end 105.200958 -247.724422)
		(width 0.350012)
		(layer "F.Cu")
		(net "GND")
	)
	(segment
		(start 338.56803 -225.310192)
		(end 338.101178 -225.044254)
		(width 0.350012)
		(layer "F.Cu")
		(net "GND")
	)
	(segment
		(start 56.99125 -390.160002)
		(end 57.6707 -390.160002)
		(width 0.254)
		(layer "F.Cu")
		(net "GND")
	)
	(segment
		(start 85.906356 -386.449062)
		(end 86.598252 -386.6388)
		(width 0.254)
		(layer "F.Cu")
		(net "GND")
	)
	(segment
		(start 85.457792 -248.800366)
		(end 84.99094 -248.534428)
		(width 0.350012)
		(layer "F.Cu")
		(net "GND")
	)
	(segment
		(start 387.748018 -287.59023)
		(end 388.21487 -287.856168)
		(width 0.350012)
		(layer "F.Cu")
		(net "GND")
	)
	(segment
		(start 117.888004 -230.170228)
		(end 118.354856 -229.90429)
		(width 0.350012)
		(layer "F.Cu")
		(net "GND")
	)
	(segment
		(start 369.11788 -239.08004)
		(end 369.584732 -238.814102)
		(width 0.350012)
		(layer "F.Cu")
		(net "GND")
	)
	(segment
		(start 340.198202 -392.999722)
		(end 340.145624 -392.30427)
		(width 0.254)
		(layer "F.Cu")
		(net "GND")
	)
	(segment
		(start 345.1479 -230.169974)
		(end 344.681048 -229.904036)
		(width 0.350012)
		(layer "F.Cu")
		(net "GND")
	)
	(segment
		(start 191.52362 -421.426132)
		(end 190.886334 -421.426132)
		(width 0.381)
		(layer "F.Cu")
		(net "GND")
	)
	(segment
		(start 450.869558 -397.162528)
		(end 450.508878 -397.162528)
		(width 0.2286)
		(layer "F.Cu")
		(net "GND")
	)
	(segment
		(start 89.047828 -285.970472)
		(end 88.580976 -286.23641)
		(width 0.350012)
		(layer "F.Cu")
		(net "GND")
	)
	(segment
		(start 179.516024 -275.53539)
		(end 180.900324 -275.53539)
		(width 0.4572)
		(layer "F.Cu")
		(net "GND")
	)
	(segment
		(start 372.370604 -395.0208)
		(end 371.678454 -394.831062)
		(width 0.254)
		(layer "F.Cu")
		(net "GND")
	)
	(segment
		(start 115.170458 -386.6388)
		(end 114.478562 -386.449062)
		(width 0.254)
		(layer "F.Cu")
		(net "GND")
	)
	(segment
		(start 66.47688 -387.069076)
		(end 66.314828 -387.231128)
		(width 0.254)
		(layer "F.Cu")
		(net "GND")
	)
	(segment
		(start 103.147876 -269.770352)
		(end 102.681024 -270.03629)
		(width 0.350012)
		(layer "F.Cu")
		(net "GND")
	)
	(segment
		(start 83.877912 -260.860286)
		(end 83.41106 -261.126224)
		(width 0.350012)
		(layer "F.Cu")
		(net "GND")
	)
	(segment
		(start 101.760528 -36.6522)
		(end 102.397814 -36.6522)
		(width 0.381)
		(layer "F.Cu")
		(net "GND")
	)
	(segment
		(start 299.82414 -199.885046)
		(end 298.43984 -199.885046)
		(width 0.4572)
		(layer "F.Cu")
		(net "GND")
	)
	(segment
		(start 343.56802 -287.59023)
		(end 343.101168 -287.856168)
		(width 0.350012)
		(layer "F.Cu")
		(net "GND")
	)
	(segment
		(start 381.167894 -264.910062)
		(end 381.634746 -265.176)
		(width 0.350012)
		(layer "F.Cu")
		(net "GND")
	)
	(segment
		(start 148.845778 -390.761474)
		(end 148.898356 -390.160002)
		(width 0.254)
		(layer "F.Cu")
		(net "GND")
	)
	(segment
		(start 90.457782 -283.540454)
		(end 89.99093 -283.806392)
		(width 0.350012)
		(layer "F.Cu")
		(net "GND")
	)
	(segment
		(start 119.127778 -294.070278)
		(end 119.59463 -294.336216)
		(width 0.350012)
		(layer "F.Cu")
		(net "GND")
	)
	(segment
		(start 280.635964 -315.485018)
		(end 282.020264 -315.485018)
		(width 0.4572)
		(layer "F.Cu")
		(net "GND")
	)
	(segment
		(start 38.45687 -11.26998)
		(end 38.45687 -10.16635)
		(width 0.3556)
		(layer "F.Cu")
		(net "GND")
	)
	(segment
		(start 355.018086 -237.460028)
		(end 354.551234 -237.19409)
		(width 0.350012)
		(layer "F.Cu")
		(net "GND")
	)
	(segment
		(start 120.537986 -273.820382)
		(end 121.004838 -274.08632)
		(width 0.350012)
		(layer "F.Cu")
		(net "GND")
	)
	(segment
		(start 150.102316 -56.204358)
		(end 149.492716 -56.204358)
		(width 0.4572)
		(layer "F.Cu")
		(net "GND")
	)
	(segment
		(start 133.714744 -384.531108)
		(end 133.41477 -384.831082)
		(width 0.254)
		(layer "F.Cu")
		(net "GND")
	)
	(segment
		(start 40.256968 -8.320024)
		(end 40.256968 -9.423654)
		(width 0.3556)
		(layer "F.Cu")
		(net "GND")
	)
	(segment
		(start 316.552326 -359.93959)
		(end 318.08801 -359.93959)
		(width 0.381)
		(layer "F.Cu")
		(net "GND")
	)
	(segment
		(start 106.437938 -267.340334)
		(end 105.971086 -267.606272)
		(width 0.350012)
		(layer "F.Cu")
		(net "GND")
	)
	(segment
		(start 87.3379 -255.280414)
		(end 86.871048 -255.014476)
		(width 0.350012)
		(layer "F.Cu")
		(net "GND")
	)
	(segment
		(start 389.11784 -392.30427)
		(end 388.817866 -391.784586)
		(width 0.254)
		(layer "F.Cu")
		(net "GND")
	)
	(segment
		(start 102.378002 -235.84027)
		(end 101.91115 -235.574332)
		(width 0.350012)
		(layer "F.Cu")
		(net "GND")
	)
	(segment
		(start 78.877922 -240.700306)
		(end 78.41107 -240.434368)
		(width 0.350012)
		(layer "F.Cu")
		(net "GND")
	)
	(segment
		(start 265.54811 -278.085042)
		(end 266.93241 -278.085042)
		(width 0.4572)
		(layer "F.Cu")
		(net "GND")
	)
	(segment
		(start 133.934454 -388.13105)
		(end 133.63448 -388.431024)
		(width 0.254)
		(layer "F.Cu")
		(net "GND")
	)
	(segment
		(start 392.917934 -273.820128)
		(end 393.384786 -274.086066)
		(width 0.350012)
		(layer "F.Cu")
		(net "GND")
	)
	(segment
		(start 20.25396 -360.341926)
		(end 20.677886 -359.918)
		(width 0.381)
		(layer "F.Cu")
		(net "GND")
	)
	(segment
		(start 336.245454 -392.004296)
		(end 336.545428 -392.30427)
		(width 0.254)
		(layer "F.Cu")
		(net "GND")
	)
	(segment
		(start 412.367984 -203.28509)
		(end 413.752284 -203.28509)
		(width 0.4572)
		(layer "F.Cu")
		(net "GND")
	)
	(segment
		(start 392.917934 -268.960092)
		(end 393.384786 -269.22603)
		(width 0.350012)
		(layer "F.Cu")
		(net "GND")
	)
	(segment
		(start 116.477796 -229.360476)
		(end 116.944648 -229.094538)
		(width 0.350012)
		(layer "F.Cu")
		(net "GND")
	)
	(segment
		(start 343.544144 -399.76171)
		(end 343.445592 -399.663158)
		(width 0.254)
		(layer "F.Cu")
		(net "GND")
	)
	(segment
		(start 122.41784 -264.10031)
		(end 122.884692 -264.366248)
		(width 0.350012)
		(layer "F.Cu")
		(net "GND")
	)
	(segment
		(start 23.946866 -7.217156)
		(end 23.946866 -8.320024)
		(width 0.3556)
		(layer "F.Cu")
		(net "GND")
	)
	(segment
		(start 374.0785 -394.831062)
		(end 373.5705 -395.0208)
		(width 0.254)
		(layer "F.Cu")
		(net "GND")
	)
	(segment
		(start 378.370592 -392.999722)
		(end 378.962412 -392.999722)
		(width 0.254)
		(layer "F.Cu")
		(net "GND")
	)
	(segment
		(start 336.687922 -244.750082)
		(end 336.22107 -244.484144)
		(width 0.350012)
		(layer "F.Cu")
		(net "GND")
	)
	(segment
		(start 325.408036 -231.789986)
		(end 324.75297 -231.789986)
		(width 0.350012)
		(layer "F.Cu")
		(net "GND")
	)
	(segment
		(start 119.297958 -243.94033)
		(end 119.76481 -243.674392)
		(width 0.350012)
		(layer "F.Cu")
		(net "GND")
	)
	(segment
		(start 392.917934 -267.34008)
		(end 393.384786 -267.606018)
		(width 0.350012)
		(layer "F.Cu")
		(net "GND")
	)
	(segment
		(start 347.797882 -290.019994)
		(end 347.33103 -290.285932)
		(width 0.350012)
		(layer "F.Cu")
		(net "GND")
	)
	(segment
		(start 102.378002 -237.460282)
		(end 101.91115 -237.194344)
		(width 0.350012)
		(layer "F.Cu")
		(net "GND")
	)
	(segment
		(start 312.470292 -398.542002)
		(end 311.791096 -398.542002)
		(width 0.254)
		(layer "F.Cu")
		(net "GND")
	)
	(segment
		(start 168.60901 -394.0937)
		(end 168.418256 -393.902946)
		(width 0.254)
		(layer "F.Cu")
		(net "GND")
	)
	(segment
		(start 109.728 -287.590484)
		(end 109.261148 -287.856422)
		(width 0.350012)
		(layer "F.Cu")
		(net "GND")
	)
	(segment
		(start 372.877842 -237.460028)
		(end 373.344694 -237.19409)
		(width 0.350012)
		(layer "F.Cu")
		(net "GND")
	)
	(segment
		(start 335.277968 -230.97998)
		(end 334.811116 -230.714296)
		(width 0.350012)
		(layer "F.Cu")
		(net "GND")
	)
	(segment
		(start 110.537498 -175.778922)
		(end 110.537498 -176.093882)
		(width 0.2286)
		(layer "F.Cu")
		(net "GND")
	)
	(segment
		(start 43.66895 -438.15)
		(end 43.66895 -438.805574)
		(width 0.381)
		(layer "F.Cu")
		(net "GND")
	)
	(segment
		(start 94.998286 -388.138924)
		(end 94.446344 -388.328662)
		(width 0.254)
		(layer "F.Cu")
		(net "GND")
	)
	(segment
		(start 99.111562 -386.449062)
		(end 99.36226 -385.731004)
		(width 0.254)
		(layer "F.Cu")
		(net "GND")
	)
	(segment
		(start 101.555296 -415.075116)
		(end 101.758242 -414.87217)
		(width 0.508)
		(layer "F.Cu")
		(net "GND")
	)
	(segment
		(start 119.597932 -288.400236)
		(end 120.064784 -288.666174)
		(width 0.350012)
		(layer "F.Cu")
		(net "GND")
	)
	(segment
		(start 387.917944 -245.560088)
		(end 388.384796 -245.29415)
		(width 0.350012)
		(layer "F.Cu")
		(net "GND")
	)
	(segment
		(start 82.167984 -246.370348)
		(end 81.701132 -246.10441)
		(width 0.350012)
		(layer "F.Cu")
		(net "GND")
	)
	(segment
		(start 405.844248 -400.212814)
		(end 405.844248 -399.76171)
		(width 0.254)
		(layer "F.Cu")
		(net "GND")
	)
	(segment
		(start 123.52782 -235.030264)
		(end 123.994672 -234.764326)
		(width 0.350012)
		(layer "F.Cu")
		(net "GND")
	)
	(segment
		(start 338.868004 -279.49017)
		(end 338.401152 -279.756108)
		(width 0.350012)
		(layer "F.Cu")
		(net "GND")
	)
	(segment
		(start 122.587766 -256.09042)
		(end 123.054618 -255.824482)
		(width 0.350012)
		(layer "F.Cu")
		(net "GND")
	)
	(segment
		(start 376.467878 -261.670038)
		(end 376.93473 -261.935976)
		(width 0.350012)
		(layer "F.Cu")
		(net "GND")
	)
	(segment
		(start 168.527984 -221.135194)
		(end 167.143684 -221.135194)
		(width 0.4572)
		(layer "F.Cu")
		(net "GND")
	)
	(segment
		(start 129.217928 -383.622296)
		(end 129.517902 -383.92227)
		(width 0.254)
		(layer "F.Cu")
		(net "GND")
	)
	(segment
		(start 374.588024 -290.83)
		(end 375.054876 -291.095938)
		(width 0.350012)
		(layer "F.Cu")
		(net "GND")
	)
	(segment
		(start 377.878086 -268.960092)
		(end 378.344938 -269.22603)
		(width 0.350012)
		(layer "F.Cu")
		(net "GND")
	)
	(segment
		(start 410.346144 -396.710662)
		(end 409.69819 -396.520924)
		(width 0.254)
		(layer "F.Cu")
		(net "GND")
	)
	(segment
		(start 431.55616 -284.034992)
		(end 430.17186 -284.034992)
		(width 0.4572)
		(layer "F.Cu")
		(net "GND")
	)
	(segment
		(start 56.47055 -390.160002)
		(end 56.99125 -390.160002)
		(width 0.254)
		(layer "F.Cu")
		(net "GND")
	)
	(segment
		(start 123.316492 -391.37971)
		(end 123.21794 -391.281158)
		(width 0.254)
		(layer "F.Cu")
		(net "GND")
	)
	(segment
		(start 327.579228 -43.573954)
		(end 328.188828 -43.573954)
		(width 0.3556)
		(layer "F.Cu")
		(net "GND")
	)
	(segment
		(start 353.398074 -396.520924)
		(end 352.846132 -396.710662)
		(width 0.254)
		(layer "F.Cu")
		(net "GND")
	)
	(segment
		(start 99.857814 -268.960346)
		(end 99.390962 -269.226284)
		(width 0.350012)
		(layer "F.Cu")
		(net "GND")
	)
	(segment
		(start 44.340018 -237.285276)
		(end 42.955718 -237.285276)
		(width 0.4572)
		(layer "F.Cu")
		(net "GND")
	)
	(segment
		(start 315.816234 -400.212814)
		(end 315.816234 -399.76171)
		(width 0.254)
		(layer "F.Cu")
		(net "GND")
	)
	(segment
		(start 335.277968 -248.800112)
		(end 334.811116 -248.534174)
		(width 0.350012)
		(layer "F.Cu")
		(net "GND")
	)
	(segment
		(start 129.938018 -293.260272)
		(end 130.40487 -293.52621)
		(width 0.350012)
		(layer "F.Cu")
		(net "GND")
	)
	(segment
		(start 135.14705 -12.496292)
		(end 135.14578 -12.495022)
		(width 0.4572)
		(layer "F.Cu")
		(net "GND")
	)
	(segment
		(start 171.97197 -228.78542)
		(end 173.35627 -228.78542)
		(width 0.4572)
		(layer "F.Cu")
		(net "GND")
	)
	(segment
		(start 128.018032 -382.951482)
		(end 128.116584 -382.85293)
		(width 0.254)
		(layer "F.Cu")
		(net "GND")
	)
	(segment
		(start 97.677986 -247.180354)
		(end 97.211134 -246.914416)
		(width 0.350012)
		(layer "F.Cu")
		(net "GND")
	)
	(segment
		(start 340.31936 -19.143726)
		(end 340.31936 -18.50644)
		(width 0.4572)
		(layer "F.Cu")
		(net "GND")
	)
	(segment
		(start 104.934004 -25.183592)
		(end 104.318054 -25.183592)
		(width 0.381)
		(layer "F.Cu")
		(net "GND")
	)
	(segment
		(start 35.821112 -368.855498)
		(end 35.821112 -369.49507)
		(width 0.381)
		(layer "F.Cu")
		(net "GND")
	)
	(segment
		(start 327.117964 -272.200116)
		(end 326.651112 -272.466054)
		(width 0.350012)
		(layer "F.Cu")
		(net "GND")
	)
	(segment
		(start 90.627962 -231.79024)
		(end 90.16111 -231.524302)
		(width 0.350012)
		(layer "F.Cu")
		(net "GND")
	)
	(segment
		(start 86.80577 -340.190074)
		(end 86.87562 -340.120224)
		(width 0.381)
		(layer "F.Cu")
		(net "GND")
	)
	(segment
		(start 384.627882 -251.23013)
		(end 385.094734 -250.964192)
		(width 0.350012)
		(layer "F.Cu")
		(net "GND")
	)
	(segment
		(start 370.357908 -288.399982)
		(end 370.82476 -288.66592)
		(width 0.350012)
		(layer "F.Cu")
		(net "GND")
	)
	(segment
		(start 331.987906 -243.13007)
		(end 331.521054 -242.864132)
		(width 0.350012)
		(layer "F.Cu")
		(net "GND")
	)
	(segment
		(start 116.370608 -384.617722)
		(end 115.762278 -384.617722)
		(width 0.254)
		(layer "F.Cu")
		(net "GND")
	)
	(segment
		(start 30.520894 -438.433464)
		(end 31.613094 -438.433464)
		(width 0.3556)
		(layer "F.Cu")
		(net "GND")
	)
	(segment
		(start 370.057934 -243.940076)
		(end 370.524786 -243.674138)
		(width 0.350012)
		(layer "F.Cu")
		(net "GND")
	)
	(segment
		(start 352.497898 -277.060152)
		(end 352.031046 -277.32609)
		(width 0.350012)
		(layer "F.Cu")
		(net "GND")
	)
	(segment
		(start 90.627962 -239.8903)
		(end 90.16111 -239.624362)
		(width 0.350012)
		(layer "F.Cu")
		(net "GND")
	)
	(segment
		(start 369.11788 -240.700052)
		(end 369.584732 -240.434114)
		(width 0.350012)
		(layer "F.Cu")
		(net "GND")
	)
	(segment
		(start 124.297948 -290.020248)
		(end 124.7648 -290.286186)
		(width 0.350012)
		(layer "F.Cu")
		(net "GND")
	)
	(segment
		(start 90.457782 -277.060406)
		(end 89.99093 -277.326344)
		(width 0.350012)
		(layer "F.Cu")
		(net "GND")
	)
	(segment
		(start 123.357894 -281.920442)
		(end 123.824746 -282.18638)
		(width 0.350012)
		(layer "F.Cu")
		(net "GND")
	)
	(segment
		(start 47.717964 -391.281158)
		(end 47.816516 -391.37971)
		(width 0.254)
		(layer "F.Cu")
		(net "GND")
	)
	(segment
		(start 423.23766 -366.212628)
		(end 423.23766 -366.875314)
		(width 0.3556)
		(layer "F.Cu")
		(net "GND")
	)
	(segment
		(start 340.74989 -60.094876)
		(end 339.15604 -60.094876)
		(width 0.4572)
		(layer "F.Cu")
		(net "GND")
	)
	(segment
		(start 390.737852 -224.500186)
		(end 391.204704 -224.234248)
		(width 0.350012)
		(layer "F.Cu")
		(net "GND")
	)
	(segment
		(start 90.927936 -277.870412)
		(end 90.461084 -278.13635)
		(width 0.350012)
		(layer "F.Cu")
		(net "GND")
	)
	(segment
		(start 138.098022 -245.560342)
		(end 138.564874 -245.294404)
		(width 0.350012)
		(layer "F.Cu")
		(net "GND")
	)
	(segment
		(start 438.488836 -169.55643)
		(end 438.488836 -170.26763)
		(width 0.3048)
		(layer "F.Cu")
		(net "GND")
	)
	(segment
		(start 127.117856 -262.480298)
		(end 127.584708 -262.746236)
		(width 0.350012)
		(layer "F.Cu")
		(net "GND")
	)
	(segment
		(start 417.353242 -161.94278)
		(end 416.929824 -161.94278)
		(width 0.2286)
		(layer "F.Cu")
		(net "GND")
	)
	(segment
		(start 175.204374 -418.056314)
		(end 174.844456 -418.056314)
		(width 0.381)
		(layer "F.Cu")
		(net "GND")
	)
	(segment
		(start 97.97796 -285.160466)
		(end 97.511108 -285.426404)
		(width 0.350012)
		(layer "F.Cu")
		(net "GND")
	)
	(segment
		(start 151.181562 -44.585636)
		(end 150.560278 -44.585636)
		(width 0.3556)
		(layer "F.Cu")
		(net "GND")
	)
	(segment
		(start 328.227944 -256.090166)
		(end 327.761092 -255.824228)
		(width 0.350012)
		(layer "F.Cu")
		(net "GND")
	)
	(segment
		(start 29.252164 -295.9354)
		(end 27.867864 -295.9354)
		(width 0.4572)
		(layer "F.Cu")
		(net "GND")
	)
	(segment
		(start 118.417848 -391.281158)
		(end 118.5164 -391.37971)
		(width 0.254)
		(layer "F.Cu")
		(net "GND")
	)
	(segment
		(start 157.29839 -390.160002)
		(end 156.61894 -390.160002)
		(width 0.254)
		(layer "F.Cu")
		(net "GND")
	)
	(segment
		(start 173.764194 -390.53008)
		(end 173.625002 -390.53008)
		(width 0.254)
		(layer "F.Cu")
		(net "GND")
	)
	(segment
		(start 177.470562 -92.493084)
		(end 177.67808 -92.285566)
		(width 0.381)
		(layer "F.Cu")
		(net "GND")
	)
	(segment
		(start 346.387928 -266.530074)
		(end 345.921076 -266.796012)
		(width 0.350012)
		(layer "F.Cu")
		(net "GND")
	)
	(segment
		(start 86.22792 -295.69029)
		(end 85.761068 -295.956228)
		(width 0.350012)
		(layer "F.Cu")
		(net "GND")
	)
	(segment
		(start 134.453884 -387.231128)
		(end 134.291832 -387.069076)
		(width 0.254)
		(layer "F.Cu")
		(net "GND")
	)
	(segment
		(start 312.11774 -391.784586)
		(end 312.11774 -392.004296)
		(width 0.254)
		(layer "F.Cu")
		(net "GND")
	)
	(segment
		(start 118.187978 -284.35046)
		(end 118.65483 -284.616398)
		(width 0.350012)
		(layer "F.Cu")
		(net "GND")
	)
	(segment
		(start 284.243018 -392.870182)
		(end 284.243018 -394.070078)
		(width 0.4318)
		(layer "F.Cu")
		(net "GND")
	)
	(segment
		(start 100.327968 -285.970472)
		(end 99.861116 -286.23641)
		(width 0.350012)
		(layer "F.Cu")
		(net "GND")
	)
	(segment
		(start 130.407918 -281.110436)
		(end 130.87477 -281.376374)
		(width 0.350012)
		(layer "F.Cu")
		(net "GND")
	)
	(segment
		(start 346.557854 -255.28016)
		(end 346.091002 -255.014222)
		(width 0.350012)
		(layer "F.Cu")
		(net "GND")
	)
	(segment
		(start 361.625388 -408.915616)
		(end 361.625388 -408.588464)
		(width 0.381)
		(layer "F.Cu")
		(net "GND")
	)
	(segment
		(start 99.687888 -399.846038)
		(end 98.608388 -399.846038)
		(width 0.3302)
		(layer "F.Cu")
		(net "GND")
	)
	(segment
		(start 122.117866 -229.360476)
		(end 122.584718 -229.094538)
		(width 0.350012)
		(layer "F.Cu")
		(net "GND")
	)
	(segment
		(start 322.31457 -393.213082)
		(end 322.10121 -392.999722)
		(width 0.254)
		(layer "F.Cu")
		(net "GND")
	)
	(segment
		(start 310.070246 -396.520924)
		(end 309.518304 -396.710662)
		(width 0.254)
		(layer "F.Cu")
		(net "GND")
	)
	(segment
		(start 346.858082 -285.160212)
		(end 346.39123 -285.42615)
		(width 0.350012)
		(layer "F.Cu")
		(net "GND")
	)
	(segment
		(start 78.877922 -239.080294)
		(end 78.41107 -238.814356)
		(width 0.350012)
		(layer "F.Cu")
		(net "GND")
	)
	(segment
		(start 211.008722 -126.469648)
		(end 211.008722 -127.18796)
		(width 0.4572)
		(layer "F.Cu")
		(net "GND")
	)
	(segment
		(start 130.012694 -403.830536)
		(end 130.012694 -402.950426)
		(width 0.381)
		(layer "F.Cu")
		(net "GND")
	)
	(segment
		(start 367.395506 -175.693324)
		(end 367.142522 -175.946308)
		(width 0.2286)
		(layer "F.Cu")
		(net "GND")
	)
	(segment
		(start 376.638058 -224.500186)
		(end 377.10491 -224.234248)
		(width 0.350012)
		(layer "F.Cu")
		(net "GND")
	)
	(segment
		(start 121.007886 -290.830254)
		(end 121.474738 -291.096192)
		(width 0.350012)
		(layer "F.Cu")
		(net "GND")
	)
	(segment
		(start 151.298402 -388.138924)
		(end 150.746206 -388.328662)
		(width 0.254)
		(layer "F.Cu")
		(net "GND")
	)
	(segment
		(start 85.045804 -383.622296)
		(end 85.345778 -383.92227)
		(width 0.2032)
		(layer "F.Cu")
		(net "GND")
	)
	(segment
		(start 359.520236 -395.22273)
		(end 359.276904 -395.466062)
		(width 0.381)
		(layer "F.Cu")
		(net "GND")
	)
	(segment
		(start 88.998298 -386.6388)
		(end 88.306402 -386.449062)
		(width 0.254)
		(layer "F.Cu")
		(net "GND")
	)
	(segment
		(start 109.701584 -13.974064)
		(end 109.363256 -14.312392)
		(width 0.4572)
		(layer "F.Cu")
		(net "GND")
	)
	(segment
		(start 366.597946 -272.200116)
		(end 367.064798 -272.466054)
		(width 0.350012)
		(layer "F.Cu")
		(net "GND")
	)
	(segment
		(start 345.845384 -391.784586)
		(end 345.845384 -391.333482)
		(width 0.254)
		(layer "F.Cu")
		(net "GND")
	)
	(segment
		(start 409.69819 -395.0208)
		(end 409.006294 -394.831062)
		(width 0.254)
		(layer "F.Cu")
		(net "GND")
	)
	(segment
		(start 402.498306 -396.46352)
		(end 402.248878 -396.214092)
		(width 0.254)
		(layer "F.Cu")
		(net "GND")
	)
	(segment
		(start 372.018052 -392.004296)
		(end 372.318026 -392.30427)
		(width 0.254)
		(layer "F.Cu")
		(net "GND")
	)
	(segment
		(start 361.89793 -291.640006)
		(end 362.364782 -291.905944)
		(width 0.350012)
		(layer "F.Cu")
		(net "GND")
	)
	(segment
		(start 116.314474 -54.636162)
		(end 116.314474 -54.026562)
		(width 0.4572)
		(layer "F.Cu")
		(net "GND")
	)
	(segment
		(start 351.087944 -287.59023)
		(end 350.621092 -287.856168)
		(width 0.350012)
		(layer "F.Cu")
		(net "GND")
	)
	(segment
		(start 133.41477 -387.831076)
		(end 132.61848 -388.328662)
		(width 0.254)
		(layer "F.Cu")
		(net "GND")
	)
	(segment
		(start 118.999 -124.44095)
		(end 118.34495 -124.44095)
		(width 0.381)
		(layer "F.Cu")
		(net "GND")
	)
	(segment
		(start 100.327968 -271.390364)
		(end 99.861116 -271.656302)
		(width 0.350012)
		(layer "F.Cu")
		(net "GND")
	)
	(segment
		(start 10.873486 -92.287598)
		(end 10.873486 -91.658948)
		(width 0.3556)
		(layer "F.Cu")
		(net "GND")
	)
	(segment
		(start 360.657902 -248.800112)
		(end 361.124754 -248.534174)
		(width 0.350012)
		(layer "F.Cu")
		(net "GND")
	)
	(segment
		(start 360.657902 -224.500186)
		(end 361.124754 -224.234248)
		(width 0.350012)
		(layer "F.Cu")
		(net "GND")
	)
	(segment
		(start 331.977492 -337.05165)
		(end 332.230476 -336.798666)
		(width 0.2286)
		(layer "F.Cu")
		(net "GND")
	)
	(segment
		(start 333.4258 -401.217384)
		(end 333.215488 -401.427696)
		(width 0.254)
		(layer "F.Cu")
		(net "GND")
	)
	(segment
		(start 93.74505 -177.418238)
		(end 94.00286 -177.160428)
		(width 0.381)
		(layer "F.Cu")
		(net "GND")
	)
	(segment
		(start 360.657902 -234.220004)
		(end 361.124754 -233.954066)
		(width 0.350012)
		(layer "F.Cu")
		(net "GND")
	)
	(segment
		(start 98.50247 -407.619708)
		(end 97.652078 -406.769316)
		(width 0.3302)
		(layer "F.Cu")
		(net "GND")
	)
	(segment
		(start 349.67799 -288.399982)
		(end 349.211138 -288.66592)
		(width 0.350012)
		(layer "F.Cu")
		(net "GND")
	)
	(segment
		(start 164.958014 -44.247054)
		(end 164.958014 -44.958762)
		(width 0.4572)
		(layer "F.Cu")
		(net "GND")
	)
	(segment
		(start 348.632272 -155.927806)
		(end 348.044262 -155.927806)
		(width 0.381)
		(layer "F.Cu")
		(net "GND")
	)
	(segment
		(start 203.497434 -341.192612)
		(end 203.799948 -341.405972)
		(width 0.4572)
		(layer "F.Cu")
		(net "GND")
	)
	(segment
		(start 92.037916 -256.900426)
		(end 91.571064 -256.634488)
		(width 0.350012)
		(layer "F.Cu")
		(net "GND")
	)
	(segment
		(start 48.578516 -386.449062)
		(end 48.070516 -386.6388)
		(width 0.254)
		(layer "F.Cu")
		(net "GND")
	)
	(segment
		(start 366.128046 -290.83)
		(end 366.594898 -291.095938)
		(width 0.350012)
		(layer "F.Cu")
		(net "GND")
	)
	(segment
		(start 389.327898 -231.789986)
		(end 389.79475 -231.524048)
		(width 0.350012)
		(layer "F.Cu")
		(net "GND")
	)
	(segment
		(start 187.060078 -275.53539)
		(end 188.444378 -275.53539)
		(width 0.4572)
		(layer "F.Cu")
		(net "GND")
	)
	(segment
		(start 154.545792 -383.402586)
		(end 154.545792 -383.622296)
		(width 0.254)
		(layer "F.Cu")
		(net "GND")
	)
	(segment
		(start 83.577938 -242.320318)
		(end 83.111086 -242.05438)
		(width 0.350012)
		(layer "F.Cu")
		(net "GND")
	)
	(segment
		(start 202.147932 -203.285344)
		(end 203.532232 -203.285344)
		(width 0.4572)
		(layer "F.Cu")
		(net "GND")
	)
	(segment
		(start 335.277968 -234.220004)
		(end 334.811116 -233.954066)
		(width 0.350012)
		(layer "F.Cu")
		(net "GND")
	)
	(segment
		(start 79.990188 -384.617722)
		(end 80.598264 -384.617722)
		(width 0.254)
		(layer "F.Cu")
		(net "GND")
	)
	(segment
		(start 345.1479 -246.370094)
		(end 344.681048 -246.104156)
		(width 0.350012)
		(layer "F.Cu")
		(net "GND")
	)
	(segment
		(start 146.087846 -228.55047)
		(end 146.554698 -228.284532)
		(width 0.350012)
		(layer "F.Cu")
		(net "GND")
	)
	(segment
		(start 336.517996 -293.260018)
		(end 336.051144 -293.525956)
		(width 0.350012)
		(layer "F.Cu")
		(net "GND")
	)
	(segment
		(start 333.697834 -278.680164)
		(end 333.230982 -278.946102)
		(width 0.350012)
		(layer "F.Cu")
		(net "GND")
	)
	(segment
		(start 191.841882 -67.391788)
		(end 191.588644 -67.645026)
		(width 0.3556)
		(layer "F.Cu")
		(net "GND")
	)
	(segment
		(start 306.116228 -109.69625)
		(end 305.093878 -109.69625)
		(width 0.381)
		(layer "F.Cu")
		(net "GND")
	)
	(segment
		(start 144.207992 -222.070422)
		(end 144.674844 -221.804484)
		(width 0.350012)
		(layer "F.Cu")
		(net "GND")
	)
	(segment
		(start 371.170454 -398.542002)
		(end 370.491004 -398.542002)
		(width 0.254)
		(layer "F.Cu")
		(net "GND")
	)
	(segment
		(start 340.74989 -63.904876)
		(end 339.15604 -63.904876)
		(width 0.4572)
		(layer "F.Cu")
		(net "GND")
	)
	(segment
		(start 303.816258 -402.670518)
		(end 303.816258 -402.284438)
		(width 0.381)
		(layer "F.Cu")
		(net "GND")
	)
	(segment
		(start 311.778396 -394.831062)
		(end 311.270396 -395.0208)
		(width 0.254)
		(layer "F.Cu")
		(net "GND")
	)
	(segment
		(start 183.616092 -218.585288)
		(end 182.231792 -218.585288)
		(width 0.4572)
		(layer "F.Cu")
		(net "GND")
	)
	(segment
		(start 45.655738 -7.215124)
		(end 45.655738 -7.215886)
		(width 0.3556)
		(layer "F.Cu")
		(net "GND")
	)
	(segment
		(start 100.027994 -226.930458)
		(end 99.561142 -226.66452)
		(width 0.350012)
		(layer "F.Cu")
		(net "GND")
	)
	(segment
		(start 44.340018 -295.9354)
		(end 42.955718 -295.9354)
		(width 0.4572)
		(layer "F.Cu")
		(net "GND")
	)
	(segment
		(start 406.464262 -163.382198)
		(end 406.394412 -163.452048)
		(width 0.381)
		(layer "F.Cu")
		(net "GND")
	)
	(segment
		(start 162.378136 -426.41647)
		(end 162.378136 -427.494446)
		(width 0.381)
		(layer "F.Cu")
		(net "GND")
	)
	(segment
		(start 363.994446 -405.52243)
		(end 364.638336 -405.52243)
		(width 0.381)
		(layer "F.Cu")
		(net "GND")
	)
	(segment
		(start 143.567912 -269.770352)
		(end 144.034764 -270.03629)
		(width 0.350012)
		(layer "F.Cu")
		(net "GND")
	)
	(segment
		(start 84.060538 -340.236048)
		(end 83.8073 -340.489286)
		(width 0.381)
		(layer "F.Cu")
		(net "GND")
	)
	(segment
		(start 335.277968 -256.900172)
		(end 334.811116 -256.634234)
		(width 0.350012)
		(layer "F.Cu")
		(net "GND")
	)
	(segment
		(start 361.42803 -266.530074)
		(end 361.894882 -266.796012)
		(width 0.350012)
		(layer "F.Cu")
		(net "GND")
	)
	(segment
		(start 337.189826 -392.999722)
		(end 336.598006 -392.999722)
		(width 0.254)
		(layer "F.Cu")
		(net "GND")
	)
	(segment
		(start 401.40128 -322.13804)
		(end 402.623782 -322.13804)
		(width 0.381)
		(layer "F.Cu")
		(net "GND")
	)
	(segment
		(start 127.047498 -163.114482)
		(end 126.794514 -163.367466)
		(width 0.2286)
		(layer "F.Cu")
		(net "GND")
	)
	(segment
		(start 288.180018 -306.135024)
		(end 289.564318 -306.135024)
		(width 0.4572)
		(layer "F.Cu")
		(net "GND")
	)
	(segment
		(start 368.478054 -291.640006)
		(end 368.944906 -291.905944)
		(width 0.350012)
		(layer "F.Cu")
		(net "GND")
	)
	(segment
		(start 198.7042 -277.235412)
		(end 197.3199 -277.235412)
		(width 0.4572)
		(layer "F.Cu")
		(net "GND")
	)
	(segment
		(start 332.28788 -279.49017)
		(end 331.821028 -279.756108)
		(width 0.350012)
		(layer "F.Cu")
		(net "GND")
	)
	(segment
		(start 421.070278 -366.602264)
		(end 420.613078 -367.059464)
		(width 0.3556)
		(layer "F.Cu")
		(net "GND")
	)
	(segment
		(start 117.41785 -229.360476)
		(end 117.884702 -229.094538)
		(width 0.350012)
		(layer "F.Cu")
		(net "GND")
	)
	(segment
		(start 333.39786 -255.28016)
		(end 332.931008 -255.014222)
		(width 0.350012)
		(layer "F.Cu")
		(net "GND")
	)
	(segment
		(start 356.25786 -288.399982)
		(end 355.791008 -288.66592)
		(width 0.350012)
		(layer "F.Cu")
		(net "GND")
	)
	(segment
		(start 341.687912 -289.209988)
		(end 341.22106 -289.475926)
		(width 0.350012)
		(layer "F.Cu")
		(net "GND")
	)
	(segment
		(start 338.998052 -395.0208)
		(end 338.306156 -394.831062)
		(width 0.254)
		(layer "F.Cu")
		(net "GND")
	)
	(segment
		(start 139.037822 -250.420378)
		(end 139.504674 -250.15444)
		(width 0.350012)
		(layer "F.Cu")
		(net "GND")
	)
	(segment
		(start 109.897926 -252.04039)
		(end 109.431074 -251.774452)
		(width 0.350012)
		(layer "F.Cu")
		(net "GND")
	)
	(segment
		(start 113.487962 -279.490424)
		(end 113.954814 -279.756362)
		(width 0.350012)
		(layer "F.Cu")
		(net "GND")
	)
	(segment
		(start 375.756678 -180.665882)
		(end 375.503694 -180.918866)
		(width 0.2286)
		(layer "F.Cu")
		(net "GND")
	)
	(segment
		(start 29.346906 -12.372848)
		(end 29.346906 -11.26998)
		(width 0.3556)
		(layer "F.Cu")
		(net "GND")
	)
	(segment
		(start 141.38783 -254.470408)
		(end 141.854682 -254.20447)
		(width 0.350012)
		(layer "F.Cu")
		(net "GND")
	)
	(segment
		(start 428.88916 -353.635056)
		(end 428.318676 -354.20554)
		(width 0.2286)
		(layer "F.Cu")
		(net "GND")
	)
	(segment
		(start 370.057934 -226.120198)
		(end 370.524786 -225.85426)
		(width 0.350012)
		(layer "F.Cu")
		(net "GND")
	)
	(segment
		(start 103.317802 -226.120452)
		(end 102.85095 -225.854514)
		(width 0.350012)
		(layer "F.Cu")
		(net "GND")
	)
	(segment
		(start 299.98035 -363.982)
		(end 299.3136 -363.982)
		(width 0.381)
		(layer "F.Cu")
		(net "GND")
	)
	(segment
		(start 412.087314 -143.967962)
		(end 412.087314 -143.298926)
		(width 0.381)
		(layer "F.Cu")
		(net "GND")
	)
	(segment
		(start 301.871888 -119.479568)
		(end 301.169578 -119.479568)
		(width 0.3556)
		(layer "F.Cu")
		(net "GND")
	)
	(segment
		(start 45.254926 -37.40404)
		(end 46.367192 -37.40404)
		(width 0.381)
		(layer "F.Cu")
		(net "GND")
	)
	(segment
		(start 106.137964 -252.04039)
		(end 105.671112 -251.774452)
		(width 0.350012)
		(layer "F.Cu")
		(net "GND")
	)
	(segment
		(start 164.608764 -128.890014)
		(end 165.041834 -128.456944)
		(width 0.381)
		(layer "F.Cu")
		(net "GND")
	)
	(segment
		(start 77.467968 -241.510312)
		(end 76.812902 -241.510312)
		(width 0.350012)
		(layer "F.Cu")
		(net "GND")
	)
	(segment
		(start 51.317906 -383.622042)
		(end 51.618134 -383.92227)
		(width 0.2032)
		(layer "F.Cu")
		(net "GND")
	)
	(segment
		(start 43.532552 -384.66268)
		(end 44.065952 -384.66268)
		(width 0.254)
		(layer "F.Cu")
		(net "GND")
	)
	(segment
		(start 79.537052 -386.030978)
		(end 79.14894 -386.030978)
		(width 0.254)
		(layer "F.Cu")
		(net "GND")
	)
	(segment
		(start 458.629766 -97.864422)
		(end 457.943966 -97.864422)
		(width 0.3556)
		(layer "F.Cu")
		(net "GND")
	)
	(segment
		(start 333.326994 -142.30477)
		(end 332.885542 -142.669514)
		(width 0.1778)
		(layer "F.Cu")
		(net "GND")
	)
	(segment
		(start 95.327978 -225.310446)
		(end 94.861126 -225.044508)
		(width 0.350012)
		(layer "F.Cu")
		(net "GND")
	)
	(segment
		(start 131.547108 -12.496546)
		(end 131.545584 -12.495022)
		(width 0.3556)
		(layer "F.Cu")
		(net "GND")
	)
	(segment
		(start 90.432128 -139.80541)
		(end 90.432128 -139.372594)
		(width 0.4572)
		(layer "F.Cu")
		(net "GND")
	)
	(segment
		(start 103.185722 -26.035254)
		(end 103.185722 -25.419304)
		(width 0.381)
		(layer "F.Cu")
		(net "GND")
	)
	(segment
		(start 409.034742 -140.520928)
		(end 409.034742 -140.884656)
		(width 0.3556)
		(layer "F.Cu")
		(net "GND")
	)
	(segment
		(start 121.177812 -245.560342)
		(end 121.644664 -245.294404)
		(width 0.350012)
		(layer "F.Cu")
		(net "GND")
	)
	(segment
		(start 416.206178 -394.831062)
		(end 415.698178 -395.0208)
		(width 0.254)
		(layer "F.Cu")
		(net "GND")
	)
	(segment
		(start 99.55784 -245.560342)
		(end 99.090988 -245.294404)
		(width 0.350012)
		(layer "F.Cu")
		(net "GND")
	)
	(segment
		(start 343.445592 -391.333482)
		(end 343.544144 -391.23493)
		(width 0.254)
		(layer "F.Cu")
		(net "GND")
	)
	(segment
		(start 424.012106 -314.635134)
		(end 422.627806 -314.635134)
		(width 0.4572)
		(layer "F.Cu")
		(net "GND")
	)
	(segment
		(start 92.037916 -227.740464)
		(end 91.571064 -227.474526)
		(width 0.350012)
		(layer "F.Cu")
		(net "GND")
	)
	(segment
		(start 47.875444 -421.326564)
		(end 47.875444 -421.231314)
		(width 0.381)
		(layer "F.Cu")
		(net "GND")
	)
	(segment
		(start 292.280086 -274.684998)
		(end 290.895786 -274.684998)
		(width 0.4572)
		(layer "F.Cu")
		(net "GND")
	)
	(segment
		(start 54.918102 -383.402586)
		(end 54.918102 -382.951482)
		(width 0.254)
		(layer "F.Cu")
		(net "GND")
	)
	(segment
		(start 89.047828 -294.070278)
		(end 88.580976 -294.336216)
		(width 0.350012)
		(layer "F.Cu")
		(net "GND")
	)
	(segment
		(start 105.19791 -240.700306)
		(end 104.731058 -240.434368)
		(width 0.350012)
		(layer "F.Cu")
		(net "GND")
	)
	(segment
		(start 384.318002 -392.30427)
		(end 384.37058 -392.999722)
		(width 0.254)
		(layer "F.Cu")
		(net "GND")
	)
	(segment
		(start 57.317894 -391.281158)
		(end 57.618122 -390.761474)
		(width 0.254)
		(layer "F.Cu")
		(net "GND")
	)
	(segment
		(start 287.339024 -399.313908)
		(end 287.97631 -399.313908)
		(width 0.4572)
		(layer "F.Cu")
		(net "GND")
	)
	(segment
		(start 146.49831 -388.08152)
		(end 146.248882 -388.330948)
		(width 0.254)
		(layer "F.Cu")
		(net "GND")
	)
	(segment
		(start 127.117856 -290.020248)
		(end 127.584708 -290.286186)
		(width 0.350012)
		(layer "F.Cu")
		(net "GND")
	)
	(segment
		(start 102.378002 -242.320318)
		(end 101.91115 -242.05438)
		(width 0.350012)
		(layer "F.Cu")
		(net "GND")
	)
	(segment
		(start 330.408026 -282.730194)
		(end 329.941174 -282.996132)
		(width 0.350012)
		(layer "F.Cu")
		(net "GND")
	)
	(segment
		(start 99.857814 -288.400236)
		(end 99.390962 -288.666174)
		(width 0.350012)
		(layer "F.Cu")
		(net "GND")
	)
	(segment
		(start 388.217918 -285.160212)
		(end 388.68477 -285.42615)
		(width 0.350012)
		(layer "F.Cu")
		(net "GND")
	)
	(segment
		(start 87.246206 -388.328662)
		(end 86.598252 -388.138924)
		(width 0.254)
		(layer "F.Cu")
		(net "GND")
	)
	(segment
		(start 143.098012 -262.480298)
		(end 143.56461 -262.746236)
		(width 0.350012)
		(layer "F.Cu")
		(net "GND")
	)
	(segment
		(start 90.927936 -289.210242)
		(end 90.461084 -289.47618)
		(width 0.350012)
		(layer "F.Cu")
		(net "GND")
	)
	(segment
		(start 422.162224 -396.213076)
		(end 422.462198 -396.51305)
		(width 0.254)
		(layer "F.Cu")
		(net "GND")
	)
	(segment
		(start 125.877828 -226.120452)
		(end 126.34468 -225.854514)
		(width 0.350012)
		(layer "F.Cu")
		(net "GND")
	)
	(segment
		(start 295.724072 -315.485018)
		(end 297.108372 -315.485018)
		(width 0.4572)
		(layer "F.Cu")
		(net "GND")
	)
	(segment
		(start 81.798414 -384.617722)
		(end 81.745836 -383.92227)
		(width 0.254)
		(layer "F.Cu")
		(net "GND")
	)
	(segment
		(start 376.167904 -252.850142)
		(end 376.634756 -252.584204)
		(width 0.350012)
		(layer "F.Cu")
		(net "GND")
	)
	(segment
		(start 416.558222 -12.374118)
		(end 416.556952 -12.372848)
		(width 0.3556)
		(layer "F.Cu")
		(net "GND")
	)
	(segment
		(start 355.018086 -232.599992)
		(end 354.551234 -232.334054)
		(width 0.350012)
		(layer "F.Cu")
		(net "GND")
	)
	(segment
		(start 384.018028 -391.333482)
		(end 384.11658 -391.23493)
		(width 0.254)
		(layer "F.Cu")
		(net "GND")
	)
	(segment
		(start 108.49102 -224.234502)
		(end 108.017818 -224.50044)
		(width 0.350012)
		(layer "F.Cu")
		(net "GND")
	)
	(segment
		(start 121.477786 -283.540454)
		(end 121.944638 -283.806392)
		(width 0.350012)
		(layer "F.Cu")
		(net "GND")
	)
	(segment
		(start 104.55783 -291.64026)
		(end 104.090978 -291.906198)
		(width 0.350012)
		(layer "F.Cu")
		(net "GND")
	)
	(segment
		(start 360.957876 -286.780224)
		(end 361.424728 -287.045908)
		(width 0.350012)
		(layer "F.Cu")
		(net "GND")
	)
	(segment
		(start 139.977876 -226.120452)
		(end 140.444728 -225.854514)
		(width 0.350012)
		(layer "F.Cu")
		(net "GND")
	)
	(segment
		(start 378.85624 -150.993348)
		(end 379.570234 -150.993348)
		(width 0.4572)
		(layer "F.Cu")
		(net "GND")
	)
	(segment
		(start 459.158594 -45.864526)
		(end 459.158594 -45.233082)
		(width 0.381)
		(layer "F.Cu")
		(net "GND")
	)
	(segment
		(start 62.978538 -386.449062)
		(end 62.470538 -386.6388)
		(width 0.254)
		(layer "F.Cu")
		(net "GND")
	)
	(segment
		(start 343.56802 -266.530074)
		(end 343.101168 -266.796012)
		(width 0.350012)
		(layer "F.Cu")
		(net "GND")
	)
	(segment
		(start 164.498274 -384.617722)
		(end 164.445696 -383.92227)
		(width 0.254)
		(layer "F.Cu")
		(net "GND")
	)
	(segment
		(start 47.784004 -210.085432)
		(end 49.168304 -210.085432)
		(width 0.4572)
		(layer "F.Cu")
		(net "GND")
	)
	(segment
		(start 49.666906 -11.26998)
		(end 49.666906 -10.16635)
		(width 0.3556)
		(layer "F.Cu")
		(net "GND")
	)
	(segment
		(start 338.097876 -245.560088)
		(end 337.631024 -245.29415)
		(width 0.350012)
		(layer "F.Cu")
		(net "GND")
	)
	(segment
		(start 377.818396 -396.710662)
		(end 377.170442 -396.520924)
		(width 0.254)
		(layer "F.Cu")
		(net "GND")
	)
	(segment
		(start 47.784004 -284.885384)
		(end 49.168304 -284.885384)
		(width 0.4572)
		(layer "F.Cu")
		(net "GND")
	)
	(segment
		(start 99.55784 -229.360476)
		(end 99.090988 -229.094538)
		(width 0.350012)
		(layer "F.Cu")
		(net "GND")
	)
	(segment
		(start 160.206182 -386.449062)
		(end 159.698182 -386.6388)
		(width 0.254)
		(layer "F.Cu")
		(net "GND")
	)
	(segment
		(start 347.989906 -392.999722)
		(end 347.398086 -392.999722)
		(width 0.254)
		(layer "F.Cu")
		(net "GND")
	)
	(segment
		(start 378.347986 -264.910062)
		(end 378.814838 -265.176)
		(width 0.350012)
		(layer "F.Cu")
		(net "GND")
	)
	(segment
		(start 418.945568 -391.784586)
		(end 418.945568 -391.333482)
		(width 0.254)
		(layer "F.Cu")
		(net "GND")
	)
	(segment
		(start 121.117868 -383.92227)
		(end 121.170446 -384.617722)
		(width 0.254)
		(layer "F.Cu")
		(net "GND")
	)
	(segment
		(start 370.057934 -255.28016)
		(end 370.524786 -255.014222)
		(width 0.350012)
		(layer "F.Cu")
		(net "GND")
	)
	(segment
		(start 194.604132 -228.78542)
		(end 195.988432 -228.78542)
		(width 0.4572)
		(layer "F.Cu")
		(net "GND")
	)
	(segment
		(start 376.06732 -423.904918)
		(end 374.090438 -423.904918)
		(width 0.254)
		(layer "F.Cu")
		(net "GND")
	)
	(segment
		(start 77.467968 -235.030264)
		(end 76.812902 -235.030264)
		(width 0.350012)
		(layer "F.Cu")
		(net "GND")
	)
	(segment
		(start 200.12787 -95.872808)
		(end 201.291952 -95.872808)
		(width 0.381)
		(layer "F.Cu")
		(net "GND")
	)
	(segment
		(start 124.297948 -272.20037)
		(end 124.7648 -272.466308)
		(width 0.350012)
		(layer "F.Cu")
		(net "GND")
	)
	(segment
		(start 115.83797 -268.960346)
		(end 116.304822 -269.226284)
		(width 0.350012)
		(layer "F.Cu")
		(net "GND")
	)
	(segment
		(start 382.748028 -249.610118)
		(end 383.21488 -249.34418)
		(width 0.350012)
		(layer "F.Cu")
		(net "GND")
	)
	(segment
		(start 402.248878 -396.214092)
		(end 402.248878 -395.613128)
		(width 0.254)
		(layer "F.Cu")
		(net "GND")
	)
	(segment
		(start 315.717682 -391.784586)
		(end 315.717682 -391.333482)
		(width 0.254)
		(layer "F.Cu")
		(net "GND")
	)
	(segment
		(start 331.997304 -340.231222)
		(end 331.744066 -340.48446)
		(width 0.381)
		(layer "F.Cu")
		(net "GND")
	)
	(segment
		(start 18.841466 -40.942514)
		(end 18.232628 -40.942514)
		(width 0.4572)
		(layer "F.Cu")
		(net "GND")
	)
	(segment
		(start 367.96599 -174.706026)
		(end 367.492026 -175.17999)
		(width 0.2286)
		(layer "F.Cu")
		(net "GND")
	)
	(segment
		(start 118.357904 -243.94033)
		(end 118.824756 -243.674392)
		(width 0.350012)
		(layer "F.Cu")
		(net "GND")
	)
	(segment
		(start 366.128046 -287.59023)
		(end 366.594898 -287.856168)
		(width 0.350012)
		(layer "F.Cu")
		(net "GND")
	)
	(segment
		(start 404.845774 -399.143474)
		(end 404.898352 -398.542002)
		(width 0.254)
		(layer "F.Cu")
		(net "GND")
	)
	(segment
		(start 64.54013 -53.14569)
		(end 64.83858 -53.44414)
		(width 0.381)
		(layer "F.Cu")
		(net "GND")
	)
	(segment
		(start 449.339716 -401.93087)
		(end 449.339716 -402.76907)
		(width 0.381)
		(layer "F.Cu")
		(net "GND")
	)
	(segment
		(start 240.727992 -291.224462)
		(end 240.425478 -291.011102)
		(width 0.4572)
		(layer "F.Cu")
		(net "GND")
	)
	(segment
		(start 391.50798 -271.39011)
		(end 391.974832 -271.656048)
		(width 0.350012)
		(layer "F.Cu")
		(net "GND")
	)
	(segment
		(start 330.108052 -252.850142)
		(end 329.6412 -252.584204)
		(width 0.350012)
		(layer "F.Cu")
		(net "GND")
	)
	(segment
		(start 92.253816 -337.6422)
		(end 92.371926 -337.357212)
		(width 0.2286)
		(layer "F.Cu")
		(net "GND")
	)
	(segment
		(start 108.787946 -274.630388)
		(end 108.321094 -274.896326)
		(width 0.350012)
		(layer "F.Cu")
		(net "GND")
	)
	(segment
		(start 348.268036 -290.83)
		(end 347.801184 -291.095938)
		(width 0.350012)
		(layer "F.Cu")
		(net "GND")
	)
	(segment
		(start 98.608388 -399.846038)
		(end 98.566224 -399.888202)
		(width 0.3302)
		(layer "F.Cu")
		(net "GND")
	)
	(segment
		(start 372.370604 -392.999722)
		(end 372.318026 -392.30427)
		(width 0.254)
		(layer "F.Cu")
		(net "GND")
	)
	(segment
		(start 338.868004 -290.83)
		(end 338.401152 -291.095938)
		(width 0.350012)
		(layer "F.Cu")
		(net "GND")
	)
	(segment
		(start 116.477796 -247.180354)
		(end 116.944648 -246.914416)
		(width 0.350012)
		(layer "F.Cu")
		(net "GND")
	)
	(segment
		(start 386.338064 -273.820128)
		(end 386.804916 -274.086066)
		(width 0.350012)
		(layer "F.Cu")
		(net "GND")
	)
	(segment
		(start 126.817882 -237.460282)
		(end 127.284734 -237.194344)
		(width 0.350012)
		(layer "F.Cu")
		(net "GND")
	)
	(segment
		(start 383.048002 -276.250146)
		(end 383.514854 -276.516084)
		(width 0.350012)
		(layer "F.Cu")
		(net "GND")
	)
	(segment
		(start 386.03809 -232.599992)
		(end 386.504942 -232.334054)
		(width 0.350012)
		(layer "F.Cu")
		(net "GND")
	)
	(segment
		(start 87.167974 -276.2504)
		(end 86.701122 -276.516338)
		(width 0.350012)
		(layer "F.Cu")
		(net "GND")
	)
	(segment
		(start 379.75794 -286.780224)
		(end 380.224792 -287.045908)
		(width 0.350012)
		(layer "F.Cu")
		(net "GND")
	)
	(segment
		(start 89.590118 -384.617722)
		(end 88.998298 -384.617722)
		(width 0.254)
		(layer "F.Cu")
		(net "GND")
	)
	(segment
		(start 88.319102 -390.160002)
		(end 88.998298 -390.160002)
		(width 0.254)
		(layer "F.Cu")
		(net "GND")
	)
	(segment
		(start 310.7182 -396.710662)
		(end 310.070246 -396.520924)
		(width 0.254)
		(layer "F.Cu")
		(net "GND")
	)
	(segment
		(start 49.276 -435.59095)
		(end 49.276 -434.939948)
		(width 0.381)
		(layer "F.Cu")
		(net "GND")
	)
	(segment
		(start 146.445732 -390.761474)
		(end 146.145758 -391.281158)
		(width 0.254)
		(layer "F.Cu")
		(net "GND")
	)
	(segment
		(start 117.888004 -241.510312)
		(end 118.354856 -241.244374)
		(width 0.350012)
		(layer "F.Cu")
		(net "GND")
	)
	(segment
		(start 102.847902 -226.930458)
		(end 102.38105 -226.66452)
		(width 0.350012)
		(layer "F.Cu")
		(net "GND")
	)
	(segment
		(start 356.728014 -277.870158)
		(end 356.261162 -278.136096)
		(width 0.350012)
		(layer "F.Cu")
		(net "GND")
	)
	(segment
		(start 113.187988 -238.270288)
		(end 113.65484 -238.00435)
		(width 0.350012)
		(layer "F.Cu")
		(net "GND")
	)
	(segment
		(start 328.227944 -236.650022)
		(end 327.761092 -236.384084)
		(width 0.350012)
		(layer "F.Cu")
		(net "GND")
	)
	(segment
		(start 349.798132 -396.520924)
		(end 349.245936 -396.710662)
		(width 0.254)
		(layer "F.Cu")
		(net "GND")
	)
	(segment
		(start 369.618006 -391.784586)
		(end 369.618006 -391.339578)
		(width 0.254)
		(layer "F.Cu")
		(net "GND")
	)
	(segment
		(start 116.018056 -383.402586)
		(end 116.018056 -383.622296)
		(width 0.254)
		(layer "F.Cu")
		(net "GND")
	)
	(segment
		(start 440.203336 -31.792926)
		(end 441.344558 -30.651704)
		(width 0.254)
		(layer "F.Cu")
		(net "GND")
	)
	(segment
		(start 406.690068 -392.999722)
		(end 406.098248 -392.999722)
		(width 0.254)
		(layer "F.Cu")
		(net "GND")
	)
	(segment
		(start 340.277958 -275.44014)
		(end 339.811106 -275.706078)
		(width 0.350012)
		(layer "F.Cu")
		(net "GND")
	)
	(segment
		(start 159.35706 -38.144958)
		(end 158.895796 -38.144958)
		(width 0.4572)
		(layer "F.Cu")
		(net "GND")
	)
	(segment
		(start 92.159582 -74.68362)
		(end 91.549982 -74.68362)
		(width 0.4572)
		(layer "F.Cu")
		(net "GND")
	)
	(segment
		(start 109.427772 -241.510312)
		(end 108.961174 -241.244374)
		(width 0.350012)
		(layer "F.Cu")
		(net "GND")
	)
	(segment
		(start 171.97197 -203.285344)
		(end 173.35627 -203.285344)
		(width 0.4572)
		(layer "F.Cu")
		(net "GND")
	)
	(segment
		(start 101.907848 -222.070422)
		(end 101.440996 -221.804484)
		(width 0.350012)
		(layer "F.Cu")
		(net "GND")
	)
	(segment
		(start 327.117964 -260.860032)
		(end 326.651112 -261.12597)
		(width 0.350012)
		(layer "F.Cu")
		(net "GND")
	)
	(segment
		(start 439.100214 -221.13494)
		(end 437.715914 -221.13494)
		(width 0.4572)
		(layer "F.Cu")
		(net "GND")
	)
	(segment
		(start 387.448044 -256.090166)
		(end 387.914896 -255.824228)
		(width 0.350012)
		(layer "F.Cu")
		(net "GND")
	)
	(segment
		(start 119.01805 -425.704)
		(end 119.507 -425.21505)
		(width 0.381)
		(layer "F.Cu")
		(net "GND")
	)
	(segment
		(start 123.05792 -226.120452)
		(end 123.524772 -225.854514)
		(width 0.350012)
		(layer "F.Cu")
		(net "GND")
	)
	(segment
		(start 356.25786 -286.780224)
		(end 355.791008 -287.046162)
		(width 0.350012)
		(layer "F.Cu")
		(net "GND")
	)
	(segment
		(start 188.552582 -356.578408)
		(end 188.18479 -356.578408)
		(width 0.381)
		(layer "F.Cu")
		(net "GND")
	)
	(segment
		(start 82.167984 -233.410252)
		(end 81.701132 -233.144314)
		(width 0.350012)
		(layer "F.Cu")
		(net "GND")
	)
	(segment
		(start 31.145734 -7.215124)
		(end 31.145734 -7.215886)
		(width 0.3556)
		(layer "F.Cu")
		(net "GND")
	)
	(segment
		(start 196.457824 -64.336168)
		(end 196.457824 -63.447422)
		(width 0.4572)
		(layer "F.Cu")
		(net "GND")
	)
	(segment
		(start 368.947954 -263.29005)
		(end 369.414806 -263.555988)
		(width 0.350012)
		(layer "F.Cu")
		(net "GND")
	)
	(segment
		(start 188.322204 -112.25276)
		(end 188.712094 -111.86287)
		(width 0.254)
		(layer "F.Cu")
		(net "GND")
	)
	(segment
		(start 130.877818 -294.880284)
		(end 131.34467 -295.146222)
		(width 0.350012)
		(layer "F.Cu")
		(net "GND")
	)
	(segment
		(start 416.468052 -209.23504)
		(end 415.083752 -209.23504)
		(width 0.4572)
		(layer "F.Cu")
		(net "GND")
	)
	(segment
		(start 418.098224 -396.520924)
		(end 417.546282 -396.710662)
		(width 0.254)
		(layer "F.Cu")
		(net "GND")
	)
	(segment
		(start 385.570476 -396.520924)
		(end 385.018534 -396.710662)
		(width 0.254)
		(layer "F.Cu")
		(net "GND")
	)
	(segment
		(start 384.465576 -63.373)
		(end 384.465576 -63.648082)
		(width 0.4572)
		(layer "F.Cu")
		(net "GND")
	)
	(segment
		(start 62.470538 -384.617722)
		(end 61.862462 -384.617722)
		(width 0.254)
		(layer "F.Cu")
		(net "GND")
	)
	(segment
		(start 44.340018 -221.135194)
		(end 42.955718 -221.135194)
		(width 0.4572)
		(layer "F.Cu")
		(net "GND")
	)
	(segment
		(start 307.317648 -392.004042)
		(end 307.617876 -392.30427)
		(width 0.2032)
		(layer "F.Cu")
		(net "GND")
	)
	(segment
		(start 391.03808 -278.680164)
		(end 391.504678 -278.946102)
		(width 0.350012)
		(layer "F.Cu")
		(net "GND")
	)
	(segment
		(start 87.167974 -269.770352)
		(end 86.701122 -270.03629)
		(width 0.350012)
		(layer "F.Cu")
		(net "GND")
	)
	(segment
		(start 93.44787 -252.850396)
		(end 92.981018 -252.584458)
		(width 0.350012)
		(layer "F.Cu")
		(net "GND")
	)
	(segment
		(start 147.698206 -384.617722)
		(end 147.645628 -383.92227)
		(width 0.254)
		(layer "F.Cu")
		(net "GND")
	)
	(segment
		(start 376.467878 -276.250146)
		(end 376.93473 -276.516084)
		(width 0.350012)
		(layer "F.Cu")
		(net "GND")
	)
	(segment
		(start 347.797882 -281.920188)
		(end 347.33103 -282.186126)
		(width 0.350012)
		(layer "F.Cu")
		(net "GND")
	)
	(segment
		(start 159.090106 -384.617722)
		(end 159.698182 -384.617722)
		(width 0.254)
		(layer "F.Cu")
		(net "GND")
	)
	(segment
		(start 347.497908 -256.900172)
		(end 347.031056 -256.634234)
		(width 0.350012)
		(layer "F.Cu")
		(net "GND")
	)
	(segment
		(start 369.417854 -281.920188)
		(end 369.884706 -282.186126)
		(width 0.350012)
		(layer "F.Cu")
		(net "GND")
	)
	(segment
		(start 179.516024 -287.43529)
		(end 180.900324 -287.43529)
		(width 0.4572)
		(layer "F.Cu")
		(net "GND")
	)
	(segment
		(start 166.880286 -440.182)
		(end 166.921942 -440.140344)
		(width 0.381)
		(layer "F.Cu")
		(net "GND")
	)
	(segment
		(start 338.868004 -268.150086)
		(end 338.401152 -268.416024)
		(width 0.350012)
		(layer "F.Cu")
		(net "GND")
	)
	(segment
		(start 115.83797 -288.400236)
		(end 116.304822 -288.666174)
		(width 0.350012)
		(layer "F.Cu")
		(net "GND")
	)
	(segment
		(start 108.317792 -290.020248)
		(end 107.85094 -290.286186)
		(width 0.350012)
		(layer "F.Cu")
		(net "GND")
	)
	(segment
		(start 387.748018 -274.630134)
		(end 388.21487 -274.896072)
		(width 0.350012)
		(layer "F.Cu")
		(net "GND")
	)
	(segment
		(start 307.404516 -436.120794)
		(end 306.77358 -436.120794)
		(width 0.381)
		(layer "F.Cu")
		(net "GND")
	)
	(segment
		(start 78.877922 -247.180354)
		(end 78.41107 -246.914416)
		(width 0.350012)
		(layer "F.Cu")
		(net "GND")
	)
	(segment
		(start 378.01804 -391.784586)
		(end 378.01804 -392.004296)
		(width 0.254)
		(layer "F.Cu")
		(net "GND")
	)
	(segment
		(start 338.6455 -391.784586)
		(end 338.6455 -392.004296)
		(width 0.254)
		(layer "F.Cu")
		(net "GND")
	)
	(segment
		(start 350.618044 -283.5402)
		(end 350.151192 -283.806138)
		(width 0.350012)
		(layer "F.Cu")
		(net "GND")
	)
	(segment
		(start 146.087846 -236.650276)
		(end 146.742912 -236.650276)
		(width 0.350012)
		(layer "F.Cu")
		(net "GND")
	)
	(segment
		(start 335.148682 -396.214092)
		(end 335.148682 -395.613128)
		(width 0.254)
		(layer "F.Cu")
		(net "GND")
	)
	(segment
		(start 424.012106 -286.585152)
		(end 422.627806 -286.585152)
		(width 0.4572)
		(layer "F.Cu")
		(net "GND")
	)
	(segment
		(start 412.956756 -10.16635)
		(end 412.955486 -10.16508)
		(width 0.3556)
		(layer "F.Cu")
		(net "GND")
	)
	(segment
		(start 129.018538 -388.328662)
		(end 128.370584 -388.138924)
		(width 0.254)
		(layer "F.Cu")
		(net "GND")
	)
	(segment
		(start 4.194048 -133.47065)
		(end 4.576318 -133.08838)
		(width 0.3556)
		(layer "F.Cu")
		(net "GND")
	)
	(segment
		(start 378.048012 -228.550216)
		(end 378.514864 -228.284278)
		(width 0.350012)
		(layer "F.Cu")
		(net "GND")
	)
	(segment
		(start 326.81799 -239.08004)
		(end 326.351138 -238.814102)
		(width 0.350012)
		(layer "F.Cu")
		(net "GND")
	)
	(segment
		(start 338.097876 -239.08004)
		(end 337.631024 -238.814102)
		(width 0.350012)
		(layer "F.Cu")
		(net "GND")
	)
	(segment
		(start 109.219238 -41.5798)
		(end 109.219238 -42.2656)
		(width 0.4572)
		(layer "F.Cu")
		(net "GND")
	)
	(segment
		(start 111.137954 -291.64026)
		(end 110.671102 -291.906198)
		(width 0.350012)
		(layer "F.Cu")
		(net "GND")
	)
	(segment
		(start 360.957876 -281.920188)
		(end 361.424728 -282.186126)
		(width 0.350012)
		(layer "F.Cu")
		(net "GND")
	)
	(segment
		(start 222.631 -82.804)
		(end 222.123 -83.312)
		(width 0.4572)
		(layer "F.Cu")
		(net "GND")
	)
	(segment
		(start 143.098012 -278.680418)
		(end 143.56461 -278.946356)
		(width 0.350012)
		(layer "F.Cu")
		(net "GND")
	)
	(segment
		(start 138.303 -111.90605)
		(end 138.303 -111.77143)
		(width 0.381)
		(layer "F.Cu")
		(net "GND")
	)
	(segment
		(start 413.298386 -395.0208)
		(end 412.606236 -394.831062)
		(width 0.254)
		(layer "F.Cu")
		(net "GND")
	)
	(segment
		(start 417.611306 -161.684716)
		(end 417.353242 -161.94278)
		(width 0.2286)
		(layer "F.Cu")
		(net "GND")
	)
	(segment
		(start 356.728014 -281.110182)
		(end 356.261162 -281.37612)
		(width 0.350012)
		(layer "F.Cu")
		(net "GND")
	)
	(segment
		(start 336.687922 -239.890046)
		(end 336.22107 -239.624108)
		(width 0.350012)
		(layer "F.Cu")
		(net "GND")
	)
	(segment
		(start 20.793202 -361.061)
		(end 20.25396 -360.521758)
		(width 0.381)
		(layer "F.Cu")
		(net "GND")
	)
	(segment
		(start 403.090126 -392.999722)
		(end 403.698202 -392.999722)
		(width 0.254)
		(layer "F.Cu")
		(net "GND")
	)
	(segment
		(start 116.116608 -391.37971)
		(end 116.116608 -391.830814)
		(width 0.254)
		(layer "F.Cu")
		(net "GND")
	)
	(segment
		(start 392.917934 -291.640006)
		(end 393.384786 -291.905944)
		(width 0.350012)
		(layer "F.Cu")
		(net "GND")
	)
	(segment
		(start 117.475 -440.309)
		(end 118.21795 -440.309)
		(width 0.381)
		(layer "F.Cu")
		(net "GND")
	)
	(segment
		(start 408.145742 -391.784586)
		(end 408.145742 -392.004296)
		(width 0.2032)
		(layer "F.Cu")
		(net "GND")
	)
	(segment
		(start 118.357904 -237.460282)
		(end 118.824756 -237.194344)
		(width 0.350012)
		(layer "F.Cu")
		(net "GND")
	)
	(segment
		(start 292.655244 -398.151096)
		(end 292.655244 -398.924018)
		(width 0.254)
		(layer "F.Cu")
		(net "GND")
	)
	(segment
		(start 122.41784 -270.580358)
		(end 122.884692 -270.846296)
		(width 0.350012)
		(layer "F.Cu")
		(net "GND")
	)
	(segment
		(start 378.116592 -400.212814)
		(end 378.116592 -399.76171)
		(width 0.254)
		(layer "F.Cu")
		(net "GND")
	)
	(segment
		(start 331.81798 -267.34008)
		(end 331.351128 -267.606018)
		(width 0.350012)
		(layer "F.Cu")
		(net "GND")
	)
	(segment
		(start 376.467878 -268.150086)
		(end 376.93473 -268.416024)
		(width 0.350012)
		(layer "F.Cu")
		(net "GND")
	)
	(segment
		(start 327.28789 -222.070168)
		(end 326.821038 -221.80423)
		(width 0.350012)
		(layer "F.Cu")
		(net "GND")
	)
	(segment
		(start 370.057934 -235.840016)
		(end 370.524786 -235.574078)
		(width 0.350012)
		(layer "F.Cu")
		(net "GND")
	)
	(segment
		(start 54.266592 -360.473498)
		(end 54.266592 -359.730548)
		(width 0.381)
		(layer "F.Cu")
		(net "GND")
	)
	(segment
		(start 59.428126 -239.835436)
		(end 58.043826 -239.835436)
		(width 0.4572)
		(layer "F.Cu")
		(net "GND")
	)
	(segment
		(start 47.784004 -228.78542)
		(end 49.168304 -228.78542)
		(width 0.4572)
		(layer "F.Cu")
		(net "GND")
	)
	(segment
		(start 81.745836 -390.761474)
		(end 81.798414 -390.160002)
		(width 0.254)
		(layer "F.Cu")
		(net "GND")
	)
	(segment
		(start 179.267866 -354.360734)
		(end 179.83835 -353.79025)
		(width 0.2286)
		(layer "F.Cu")
		(net "GND")
	)
	(segment
		(start 331.81798 -262.480044)
		(end 331.351128 -262.745982)
		(width 0.350012)
		(layer "F.Cu")
		(net "GND")
	)
	(segment
		(start 98.842576 -387.831076)
		(end 98.046286 -388.328662)
		(width 0.254)
		(layer "F.Cu")
		(net "GND")
	)
	(segment
		(start 57.118504 -388.328662)
		(end 57.6707 -388.138924)
		(width 0.254)
		(layer "F.Cu")
		(net "GND")
	)
	(segment
		(start 40.23995 -228.78542)
		(end 41.62425 -228.78542)
		(width 0.4572)
		(layer "F.Cu")
		(net "GND")
	)
	(segment
		(start 107.377992 -294.880284)
		(end 106.91114 -295.146222)
		(width 0.350012)
		(layer "F.Cu")
		(net "GND")
	)
	(segment
		(start 352.197924 -222.880174)
		(end 351.731072 -222.614236)
		(width 0.350012)
		(layer "F.Cu")
		(net "GND")
	)
	(segment
		(start 310.917844 -391.333482)
		(end 311.016396 -391.23493)
		(width 0.254)
		(layer "F.Cu")
		(net "GND")
	)
	(segment
		(start 327.579228 -42.176954)
		(end 328.188828 -42.176954)
		(width 0.3556)
		(layer "F.Cu")
		(net "GND")
	)
	(segment
		(start 13.629132 -390.679178)
		(end 14.162024 -390.679178)
		(width 0.2286)
		(layer "F.Cu")
		(net "GND")
	)
	(segment
		(start 90.706194 -386.449062)
		(end 90.198448 -386.6388)
		(width 0.254)
		(layer "F.Cu")
		(net "GND")
	)
	(segment
		(start 320.340228 -41.668954)
		(end 320.949828 -41.668954)
		(width 0.3556)
		(layer "F.Cu")
		(net "GND")
	)
	(segment
		(start 129.57048 -388.138924)
		(end 129.018538 -388.328662)
		(width 0.254)
		(layer "F.Cu")
		(net "GND")
	)
	(segment
		(start 64.870584 -390.160002)
		(end 64.191388 -390.160002)
		(width 0.254)
		(layer "F.Cu")
		(net "GND")
	)
	(segment
		(start 156.25699 -13.599922)
		(end 156.25572 -13.598652)
		(width 0.3556)
		(layer "F.Cu")
		(net "GND")
	)
	(segment
		(start 95.627952 -282.730448)
		(end 95.1611 -282.996386)
		(width 0.350012)
		(layer "F.Cu")
		(net "GND")
	)
	(segment
		(start 33.144968 -351.10547)
		(end 33.144968 -351.736406)
		(width 0.381)
		(layer "F.Cu")
		(net "GND")
	)
	(segment
		(start 120.238012 -243.94033)
		(end 120.70461 -243.674392)
		(width 0.350012)
		(layer "F.Cu")
		(net "GND")
	)
	(segment
		(start 373.217948 -391.784586)
		(end 373.217948 -392.004296)
		(width 0.254)
		(layer "F.Cu")
		(net "GND")
	)
	(segment
		(start 113.721134 -389.63092)
		(end 113.721134 -389.030972)
		(width 0.254)
		(layer "F.Cu")
		(net "GND")
	)
	(segment
		(start 53.267102 -11.26998)
		(end 53.267102 -10.16635)
		(width 0.3556)
		(layer "F.Cu")
		(net "GND")
	)
	(segment
		(start 92.75953 -340.286848)
		(end 92.391738 -340.286848)
		(width 0.381)
		(layer "F.Cu")
		(net "GND")
	)
	(segment
		(start 129.517902 -383.92227)
		(end 129.57048 -384.617722)
		(width 0.254)
		(layer "F.Cu")
		(net "GND")
	)
	(segment
		(start 74.277474 -172.414184)
		(end 74.207624 -172.484034)
		(width 0.381)
		(layer "F.Cu")
		(net "GND")
	)
	(segment
		(start 368.600736 -402.282152)
		(end 367.787936 -402.282152)
		(width 0.254)
		(layer "F.Cu")
		(net "GND")
	)
	(segment
		(start 325.408036 -225.310192)
		(end 324.941184 -225.044254)
		(width 0.350012)
		(layer "F.Cu")
		(net "GND")
	)
	(segment
		(start 328.998072 -286.780224)
		(end 328.53122 -287.045908)
		(width 0.350012)
		(layer "F.Cu")
		(net "GND")
	)
	(segment
		(start 95.64624 -388.328662)
		(end 96.198436 -388.138924)
		(width 0.254)
		(layer "F.Cu")
		(net "GND")
	)
	(segment
		(start 97.906332 -386.449062)
		(end 97.398332 -386.6388)
		(width 0.254)
		(layer "F.Cu")
		(net "GND")
	)
	(segment
		(start 304.070258 -398.542002)
		(end 303.390808 -398.542002)
		(width 0.254)
		(layer "F.Cu")
		(net "GND")
	)
	(segment
		(start 198.7042 -274.685252)
		(end 197.3199 -274.685252)
		(width 0.4572)
		(layer "F.Cu")
		(net "GND")
	)
	(segment
		(start 410.89834 -395.0208)
		(end 410.20619 -394.831062)
		(width 0.254)
		(layer "F.Cu")
		(net "GND")
	)
	(segment
		(start 25.152096 -284.885384)
		(end 26.536396 -284.885384)
		(width 0.4572)
		(layer "F.Cu")
		(net "GND")
	)
	(segment
		(start 327.758044 -250.420124)
		(end 327.291192 -250.154186)
		(width 0.350012)
		(layer "F.Cu")
		(net "GND")
	)
	(segment
		(start 338.998052 -398.542002)
		(end 338.318856 -398.542002)
		(width 0.254)
		(layer "F.Cu")
		(net "GND")
	)
	(segment
		(start 363.307884 -282.730194)
		(end 363.774736 -282.996132)
		(width 0.350012)
		(layer "F.Cu")
		(net "GND")
	)
	(segment
		(start 348.437962 -235.840016)
		(end 347.97111 -235.574078)
		(width 0.350012)
		(layer "F.Cu")
		(net "GND")
	)
	(segment
		(start 9.949942 -50.094896)
		(end 11.512042 -50.094896)
		(width 0.4572)
		(layer "F.Cu")
		(net "GND")
	)
	(segment
		(start 107.377992 -270.580358)
		(end 106.91114 -270.846296)
		(width 0.350012)
		(layer "F.Cu")
		(net "GND")
	)
	(segment
		(start 380.86792 -244.750082)
		(end 381.334772 -244.484144)
		(width 0.350012)
		(layer "F.Cu")
		(net "GND")
	)
	(segment
		(start 350.645476 -399.663158)
		(end 350.94545 -399.143474)
		(width 0.254)
		(layer "F.Cu")
		(net "GND")
	)
	(segment
		(start 131.817872 -278.680418)
		(end 132.284724 -278.946356)
		(width 0.350012)
		(layer "F.Cu")
		(net "GND")
	)
	(segment
		(start 76.364592 -336.81797)
		(end 75.936094 -336.81797)
		(width 0.2286)
		(layer "F.Cu")
		(net "GND")
	)
	(segment
		(start 124.417836 -382.951482)
		(end 124.516388 -382.85293)
		(width 0.254)
		(layer "F.Cu")
		(net "GND")
	)
	(segment
		(start 360.957876 -275.44014)
		(end 361.424728 -275.706078)
		(width 0.350012)
		(layer "F.Cu")
		(net "GND")
	)
	(segment
		(start 163.423854 -107.834176)
		(end 163.746942 -108.157264)
		(width 0.381)
		(layer "F.Cu")
		(net "GND")
	)
	(segment
		(start 304.917856 -391.333482)
		(end 305.016408 -391.23493)
		(width 0.254)
		(layer "F.Cu")
		(net "GND")
	)
	(segment
		(start 348.268036 -281.110182)
		(end 347.801184 -281.37612)
		(width 0.350012)
		(layer "F.Cu")
		(net "GND")
	)
	(segment
		(start 29.252164 -274.685252)
		(end 27.867864 -274.685252)
		(width 0.4572)
		(layer "F.Cu")
		(net "GND")
	)
	(segment
		(start 366.63249 -393.96416)
		(end 367.16589 -393.96416)
		(width 0.254)
		(layer "F.Cu")
		(net "GND")
	)
	(segment
		(start 320.172334 -341.042244)
		(end 319.562734 -341.042244)
		(width 0.4572)
		(layer "F.Cu")
		(net "GND")
	)
	(segment
		(start 381.338074 -235.840016)
		(end 381.804926 -235.574078)
		(width 0.350012)
		(layer "F.Cu")
		(net "GND")
	)
	(segment
		(start 133.41477 -385.21132)
		(end 133.934454 -385.731004)
		(width 0.254)
		(layer "F.Cu")
		(net "GND")
	)
	(segment
		(start 372.683278 -176.59731)
		(end 372.937278 -176.85131)
		(width 0.381)
		(layer "F.Cu")
		(net "GND")
	)
	(segment
		(start 149.902164 -45.24375)
		(end 149.401276 -45.24375)
		(width 0.3556)
		(layer "F.Cu")
		(net "GND")
	)
	(segment
		(start 112.16005 -406.4508)
		(end 112.808512 -406.4508)
		(width 0.381)
		(layer "F.Cu")
		(net "GND")
	)
	(segment
		(start 364.717838 -267.34008)
		(end 365.18469 -267.606018)
		(width 0.350012)
		(layer "F.Cu")
		(net "GND")
	)
	(segment
		(start 58.178446 -386.449062)
		(end 58.870596 -386.6388)
		(width 0.254)
		(layer "F.Cu")
		(net "GND")
	)
	(segment
		(start 370.813584 -15.637002)
		(end 371.45087 -15.637002)
		(width 0.4572)
		(layer "F.Cu")
		(net "GND")
	)
	(segment
		(start 55.328058 -303.585372)
		(end 56.712358 -303.585372)
		(width 0.4572)
		(layer "F.Cu")
		(net "GND")
	)
	(segment
		(start 32.947102 -12.372848)
		(end 32.947102 -11.26998)
		(width 0.3556)
		(layer "F.Cu")
		(net "GND")
	)
	(segment
		(start 420.613078 -367.059464)
		(end 420.155878 -366.602264)
		(width 0.3556)
		(layer "F.Cu")
		(net "GND")
	)
	(segment
		(start 332.45806 -250.420124)
		(end 331.991208 -250.154186)
		(width 0.350012)
		(layer "F.Cu")
		(net "GND")
	)
	(segment
		(start 405.546306 -396.710662)
		(end 404.898352 -396.520924)
		(width 0.254)
		(layer "F.Cu")
		(net "GND")
	)
	(segment
		(start 339.70722 -338.089748)
		(end 339.738208 -338.089748)
		(width 0.2286)
		(layer "F.Cu")
		(net "GND")
	)
	(segment
		(start 59.18073 -351.978722)
		(end 58.812938 -351.978722)
		(width 0.381)
		(layer "F.Cu")
		(net "GND")
	)
	(segment
		(start 139.507976 -251.230384)
		(end 139.974828 -250.964446)
		(width 0.350012)
		(layer "F.Cu")
		(net "GND")
	)
	(segment
		(start 304.590958 -398.542002)
		(end 304.070258 -398.542002)
		(width 0.254)
		(layer "F.Cu")
		(net "GND")
	)
	(segment
		(start 41.503854 -349.786448)
		(end 41.534842 -349.786448)
		(width 0.2286)
		(layer "F.Cu")
		(net "GND")
	)
	(segment
		(start 340.277958 -291.640006)
		(end 339.811106 -291.905944)
		(width 0.350012)
		(layer "F.Cu")
		(net "GND")
	)
	(segment
		(start 314.517786 -399.663158)
		(end 314.616338 -399.76171)
		(width 0.254)
		(layer "F.Cu")
		(net "GND")
	)
	(segment
		(start 31.147004 -10.16635)
		(end 31.145734 -10.16508)
		(width 0.3556)
		(layer "F.Cu")
		(net "GND")
	)
	(segment
		(start 115.367816 -279.490424)
		(end 115.834668 -279.756362)
		(width 0.350012)
		(layer "F.Cu")
		(net "GND")
	)
	(segment
		(start 416.468052 -199.885046)
		(end 415.083752 -199.885046)
		(width 0.4572)
		(layer "F.Cu")
		(net "GND")
	)
	(segment
		(start 376.167904 -244.750082)
		(end 376.634756 -244.484144)
		(width 0.350012)
		(layer "F.Cu")
		(net "GND")
	)
	(segment
		(start 328.527918 -289.209988)
		(end 328.061066 -289.475926)
		(width 0.350012)
		(layer "F.Cu")
		(net "GND")
	)
	(segment
		(start 408.271726 -142.45082)
		(end 408.271726 -142.57782)
		(width 0.381)
		(layer "F.Cu")
		(net "GND")
	)
	(segment
		(start 91.345766 -390.761474)
		(end 91.398344 -390.160002)
		(width 0.254)
		(layer "F.Cu")
		(net "GND")
	)
	(segment
		(start 178.943 -140.572998)
		(end 178.943 -141.188948)
		(width 0.4572)
		(layer "F.Cu")
		(net "GND")
	)
	(segment
		(start 66.070734 -386.6388)
		(end 66.583814 -386.449062)
		(width 0.254)
		(layer "F.Cu")
		(net "GND")
	)
	(segment
		(start 349.245936 -396.710662)
		(end 348.597982 -396.520924)
		(width 0.254)
		(layer "F.Cu")
		(net "GND")
	)
	(segment
		(start 81.058004 -277.060406)
		(end 80.591152 -277.326344)
		(width 0.350012)
		(layer "F.Cu")
		(net "GND")
	)
	(segment
		(start 168.527984 -227.935282)
		(end 167.143684 -227.935282)
		(width 0.4572)
		(layer "F.Cu")
		(net "GND")
	)
	(segment
		(start 139.80795 -292.450266)
		(end 140.274802 -292.716204)
		(width 0.350012)
		(layer "F.Cu")
		(net "GND")
	)
	(segment
		(start 40.255698 -7.215124)
		(end 40.255698 -7.215886)
		(width 0.3556)
		(layer "F.Cu")
		(net "GND")
	)
	(segment
		(start 139.507976 -241.510312)
		(end 139.974828 -241.244374)
		(width 0.350012)
		(layer "F.Cu")
		(net "GND")
	)
	(segment
		(start 377.878086 -278.680164)
		(end 378.344938 -278.946102)
		(width 0.350012)
		(layer "F.Cu")
		(net "GND")
	)
	(segment
		(start 12.860274 -391.222484)
		(end 13.085826 -391.222484)
		(width 0.2286)
		(layer "F.Cu")
		(net "GND")
	)
	(segment
		(start 134.80796 -241.510312)
		(end 135.274812 -241.244374)
		(width 0.350012)
		(layer "F.Cu")
		(net "GND")
	)
	(segment
		(start 169.502836 -381.42418)
		(end 169.724324 -381.645668)
		(width 0.254)
		(layer "F.Cu")
		(net "GND")
	)
	(segment
		(start 13.221208 -427.742858)
		(end 13.221208 -427.098206)
		(width 0.3556)
		(layer "F.Cu")
		(net "GND")
	)
	(segment
		(start 367.238026 -229.360222)
		(end 367.704878 -229.094284)
		(width 0.350012)
		(layer "F.Cu")
		(net "GND")
	)
	(segment
		(start 54.918102 -383.622296)
		(end 55.218076 -383.92227)
		(width 0.254)
		(layer "F.Cu")
		(net "GND")
	)
	(segment
		(start 347.968062 -231.789986)
		(end 347.50121 -231.524048)
		(width 0.350012)
		(layer "F.Cu")
		(net "GND")
	)
	(segment
		(start 93.482922 -180.850794)
		(end 93.081856 -180.850794)
		(width 0.2286)
		(layer "F.Cu")
		(net "GND")
	)
	(segment
		(start 115.067842 -241.510312)
		(end 115.534694 -241.244374)
		(width 0.350012)
		(layer "F.Cu")
		(net "GND")
	)
	(segment
		(start 386.03809 -235.840016)
		(end 386.504942 -235.574078)
		(width 0.350012)
		(layer "F.Cu")
		(net "GND")
	)
	(segment
		(start 90.157808 -248.800366)
		(end 89.690956 -248.534428)
		(width 0.350012)
		(layer "F.Cu")
		(net "GND")
	)
	(segment
		(start 198.7042 -302.735234)
		(end 197.3199 -302.735234)
		(width 0.4572)
		(layer "F.Cu")
		(net "GND")
	)
	(segment
		(start 156.945584 -383.622042)
		(end 156.945584 -383.402586)
		(width 0.254)
		(layer "F.Cu")
		(net "GND")
	)
	(segment
		(start 442.5442 -296.78503)
		(end 443.9285 -296.78503)
		(width 0.4572)
		(layer "F.Cu")
		(net "GND")
	)
	(segment
		(start 383.048002 -261.670038)
		(end 383.514854 -261.935976)
		(width 0.350012)
		(layer "F.Cu")
		(net "GND")
	)
	(segment
		(start 104.261158 -221.804484)
		(end 104.257856 -222.880428)
		(width 0.254)
		(layer "F.Cu")
		(net "GND")
	)
	(segment
		(start 60.920122 -180.891942)
		(end 60.920122 -180.26761)
		(width 0.381)
		(layer "F.Cu")
		(net "GND")
	)
	(segment
		(start 334.808068 -246.370094)
		(end 334.341216 -246.104156)
		(width 0.350012)
		(layer "F.Cu")
		(net "GND")
	)
	(segment
		(start 108.787946 -282.730448)
		(end 108.321094 -282.996386)
		(width 0.350012)
		(layer "F.Cu")
		(net "GND")
	)
	(segment
		(start 369.11788 -242.320064)
		(end 369.584732 -242.054126)
		(width 0.350012)
		(layer "F.Cu")
		(net "GND")
	)
	(segment
		(start 454.188068 -230.485188)
		(end 452.803768 -230.485188)
		(width 0.4572)
		(layer "F.Cu")
		(net "GND")
	)
	(segment
		(start 144.977866 -262.480298)
		(end 145.444718 -262.746236)
		(width 0.350012)
		(layer "F.Cu")
		(net "GND")
	)
	(segment
		(start 90.927936 -274.630388)
		(end 90.461084 -274.896326)
		(width 0.350012)
		(layer "F.Cu")
		(net "GND")
	)
	(segment
		(start 387.970522 -395.0208)
		(end 387.278626 -394.831062)
		(width 0.254)
		(layer "F.Cu")
		(net "GND")
	)
	(segment
		(start 320.517774 -391.333482)
		(end 320.616326 -391.23493)
		(width 0.254)
		(layer "F.Cu")
		(net "GND")
	)
	(segment
		(start 340.277958 -286.780224)
		(end 339.811106 -287.045908)
		(width 0.350012)
		(layer "F.Cu")
		(net "GND")
	)
	(segment
		(start 351.728024 -251.23013)
		(end 351.261172 -250.964192)
		(width 0.350012)
		(layer "F.Cu")
		(net "GND")
	)
	(segment
		(start 391.03808 -293.260018)
		(end 391.504678 -293.525956)
		(width 0.350012)
		(layer "F.Cu")
		(net "GND")
	)
	(segment
		(start 327.587864 -268.150086)
		(end 327.121012 -268.416024)
		(width 0.350012)
		(layer "F.Cu")
		(net "GND")
	)
	(segment
		(start 363.00791 -236.650022)
		(end 363.474762 -236.384084)
		(width 0.350012)
		(layer "F.Cu")
		(net "GND")
	)
	(segment
		(start 162.04565 -390.761474)
		(end 162.098228 -390.160002)
		(width 0.254)
		(layer "F.Cu")
		(net "GND")
	)
	(segment
		(start 390.313672 -177.532284)
		(end 389.725662 -177.532284)
		(width 0.381)
		(layer "F.Cu")
		(net "GND")
	)
	(segment
		(start 96.097852 -268.960346)
		(end 95.631 -269.226284)
		(width 0.350012)
		(layer "F.Cu")
		(net "GND")
	)
	(segment
		(start 332.28788 -290.83)
		(end 331.821028 -291.095938)
		(width 0.350012)
		(layer "F.Cu")
		(net "GND")
	)
	(segment
		(start 102.677976 -273.820382)
		(end 102.211124 -274.08632)
		(width 0.350012)
		(layer "F.Cu")
		(net "GND")
	)
	(segment
		(start 413.890206 -392.999722)
		(end 413.298386 -392.999722)
		(width 0.254)
		(layer "F.Cu")
		(net "GND")
	)
	(segment
		(start 132.927852 -222.070422)
		(end 133.394704 -221.804484)
		(width 0.350012)
		(layer "F.Cu")
		(net "GND")
	)
	(segment
		(start 367.538 -277.060152)
		(end 368.004852 -277.32609)
		(width 0.350012)
		(layer "F.Cu")
		(net "GND")
	)
	(segment
		(start 139.977876 -235.84027)
		(end 140.444728 -235.574332)
		(width 0.350012)
		(layer "F.Cu")
		(net "GND")
	)
	(segment
		(start 109.897926 -226.120452)
		(end 109.431074 -225.854514)
		(width 0.350012)
		(layer "F.Cu")
		(net "GND")
	)
	(segment
		(start 144.977866 -286.780478)
		(end 145.444718 -287.046162)
		(width 0.350012)
		(layer "F.Cu")
		(net "GND")
	)
	(segment
		(start 105.19791 -248.800366)
		(end 104.731058 -248.534428)
		(width 0.350012)
		(layer "F.Cu")
		(net "GND")
	)
	(segment
		(start 450.088 -315.485018)
		(end 451.4723 -315.485018)
		(width 0.4572)
		(layer "F.Cu")
		(net "GND")
	)
	(segment
		(start 86.868 -231.79024)
		(end 86.401148 -231.524302)
		(width 0.350012)
		(layer "F.Cu")
		(net "GND")
	)
	(segment
		(start 282.941522 -114.82197)
		(end 282.941522 -115.20297)
		(width 0.3556)
		(layer "F.Cu")
		(net "GND")
	)
	(segment
		(start 347.797882 -268.960092)
		(end 347.33103 -269.22603)
		(width 0.350012)
		(layer "F.Cu")
		(net "GND")
	)
	(segment
		(start 358.001824 -390.619488)
		(end 358.451912 -390.1694)
		(width 0.254)
		(layer "F.Cu")
		(net "GND")
	)
	(segment
		(start 51.884072 -286.585406)
		(end 50.499772 -286.585406)
		(width 0.4572)
		(layer "F.Cu")
		(net "GND")
	)
	(segment
		(start 77.185266 -172.36821)
		(end 77.292454 -172.475398)
		(width 0.381)
		(layer "F.Cu")
		(net "GND")
	)
	(segment
		(start 420.025068 -103.691436)
		(end 420.025068 -104.20731)
		(width 0.254)
		(layer "F.Cu")
		(net "GND")
	)
	(segment
		(start 46.87062 -388.08152)
		(end 47.518574 -388.328662)
		(width 0.254)
		(layer "F.Cu")
		(net "GND")
	)
	(segment
		(start 366.128046 -276.250146)
		(end 366.594898 -276.516084)
		(width 0.350012)
		(layer "F.Cu")
		(net "GND")
	)
	(segment
		(start 306.117752 -399.663158)
		(end 306.417726 -399.143474)
		(width 0.254)
		(layer "F.Cu")
		(net "GND")
	)
	(segment
		(start 387.716522 -399.76171)
		(end 387.61797 -399.663158)
		(width 0.254)
		(layer "F.Cu")
		(net "GND")
	)
	(segment
		(start 269.648178 -199.885046)
		(end 268.263878 -199.885046)
		(width 0.4572)
		(layer "F.Cu")
		(net "GND")
	)
	(segment
		(start 343.268046 -230.169974)
		(end 342.801194 -229.904036)
		(width 0.350012)
		(layer "F.Cu")
		(net "GND")
	)
	(segment
		(start 100.497894 -229.360476)
		(end 100.031042 -229.094538)
		(width 0.350012)
		(layer "F.Cu")
		(net "GND")
	)
	(segment
		(start 25.040844 -394.410184)
		(end 25.747726 -394.410184)
		(width 0.4572)
		(layer "F.Cu")
		(net "GND")
	)
	(segment
		(start 338.39785 -275.44014)
		(end 337.930998 -275.706078)
		(width 0.350012)
		(layer "F.Cu")
		(net "GND")
	)
	(segment
		(start 83.877912 -275.440394)
		(end 83.41106 -275.706332)
		(width 0.350012)
		(layer "F.Cu")
		(net "GND")
	)
	(segment
		(start 139.507976 -231.79024)
		(end 139.974828 -231.524302)
		(width 0.350012)
		(layer "F.Cu")
		(net "GND")
	)
	(segment
		(start 109.549946 -52.46243)
		(end 109.549946 -51.85283)
		(width 0.4572)
		(layer "F.Cu")
		(net "GND")
	)
	(segment
		(start 168.527984 -202.435206)
		(end 167.143684 -202.435206)
		(width 0.4572)
		(layer "F.Cu")
		(net "GND")
	)
	(segment
		(start 388.478522 -394.831062)
		(end 387.970522 -395.0208)
		(width 0.254)
		(layer "F.Cu")
		(net "GND")
	)
	(segment
		(start 326.81799 -256.900172)
		(end 326.351138 -256.634234)
		(width 0.350012)
		(layer "F.Cu")
		(net "GND")
	)
	(segment
		(start 322.070476 -395.0208)
		(end 321.378326 -394.831062)
		(width 0.254)
		(layer "F.Cu")
		(net "GND")
	)
	(segment
		(start 31.312612 -421.281098)
		(end 31.312612 -421.916098)
		(width 0.3556)
		(layer "F.Cu")
		(net "GND")
	)
	(segment
		(start 427.456092 -210.085178)
		(end 428.840392 -210.085178)
		(width 0.4572)
		(layer "F.Cu")
		(net "GND")
	)
	(segment
		(start 85.398356 -386.6388)
		(end 85.906356 -386.449062)
		(width 0.254)
		(layer "F.Cu")
		(net "GND")
	)
	(segment
		(start 335.108042 -276.250146)
		(end 334.64119 -276.516084)
		(width 0.350012)
		(layer "F.Cu")
		(net "GND")
	)
	(segment
		(start 154.898344 -390.160002)
		(end 154.218894 -390.160002)
		(width 0.254)
		(layer "F.Cu")
		(net "GND")
	)
	(segment
		(start 325.70801 -264.910062)
		(end 325.052944 -264.910062)
		(width 0.350012)
		(layer "F.Cu")
		(net "GND")
	)
	(segment
		(start 416.468052 -302.73498)
		(end 415.083752 -302.73498)
		(width 0.4572)
		(layer "F.Cu")
		(net "GND")
	)
	(segment
		(start 98.950272 -36.97859)
		(end 98.478848 -37.450014)
		(width 0.3556)
		(layer "F.Cu")
		(net "GND")
	)
	(segment
		(start 316.23 -365.01705)
		(end 317.246 -365.01705)
		(width 0.381)
		(layer "F.Cu")
		(net "GND")
	)
	(segment
		(start 377.577858 -250.420124)
		(end 378.04471 -250.154186)
		(width 0.350012)
		(layer "F.Cu")
		(net "GND")
	)
	(segment
		(start 424.012106 -209.23504)
		(end 422.627806 -209.23504)
		(width 0.4572)
		(layer "F.Cu")
		(net "GND")
	)
	(segment
		(start 113.721134 -390.564624)
		(end 113.917984 -390.761474)
		(width 0.254)
		(layer "F.Cu")
		(net "GND")
	)
	(segment
		(start 350.14789 -263.29005)
		(end 349.681038 -263.555988)
		(width 0.350012)
		(layer "F.Cu")
		(net "GND")
	)
	(segment
		(start 166.981632 -387.231128)
		(end 166.81958 -387.069076)
		(width 0.254)
		(layer "F.Cu")
		(net "GND")
	)
	(segment
		(start 133.227826 -261.670292)
		(end 133.694678 -261.93623)
		(width 0.350012)
		(layer "F.Cu")
		(net "GND")
	)
	(segment
		(start 330.408026 -287.59023)
		(end 329.941174 -287.856168)
		(width 0.350012)
		(layer "F.Cu")
		(net "GND")
	)
	(segment
		(start 176.072038 -199.8853)
		(end 174.687738 -199.8853)
		(width 0.4572)
		(layer "F.Cu")
		(net "GND")
	)
	(segment
		(start 51.670712 -384.617722)
		(end 51.062382 -384.617722)
		(width 0.254)
		(layer "F.Cu")
		(net "GND")
	)
	(segment
		(start 439.072782 -433.09921)
		(end 439.703718 -433.09921)
		(width 0.381)
		(layer "F.Cu")
		(net "GND")
	)
	(segment
		(start 386.41782 -391.784586)
		(end 386.41782 -391.333482)
		(width 0.254)
		(layer "F.Cu")
		(net "GND")
	)
	(segment
		(start 384.627882 -252.850142)
		(end 385.094734 -252.584204)
		(width 0.350012)
		(layer "F.Cu")
		(net "GND")
	)
	(segment
		(start 120.707912 -228.55047)
		(end 121.174764 -228.284532)
		(width 0.350012)
		(layer "F.Cu")
		(net "GND")
	)
	(segment
		(start 13.73505 -77.089)
		(end 14.38148 -77.089)
		(width 0.381)
		(layer "F.Cu")
		(net "GND")
	)
	(segment
		(start 288.66592 -97.967292)
		(end 289.3568 -97.967292)
		(width 0.4572)
		(layer "F.Cu")
		(net "GND")
	)
	(segment
		(start 356.25786 -272.200116)
		(end 355.791008 -272.466054)
		(width 0.350012)
		(layer "F.Cu")
		(net "GND")
	)
	(segment
		(start 306.262532 -411.815534)
		(end 306.659534 -412.212536)
		(width 0.381)
		(layer "F.Cu")
		(net "GND")
	)
	(segment
		(start 389.327898 -225.310192)
		(end 389.79475 -225.044254)
		(width 0.350012)
		(layer "F.Cu")
		(net "GND")
	)
	(segment
		(start 108.317792 -281.920442)
		(end 107.85094 -282.18638)
		(width 0.350012)
		(layer "F.Cu")
		(net "GND")
	)
	(segment
		(start 376.562366 -392.999722)
		(end 377.170442 -392.999722)
		(width 0.254)
		(layer "F.Cu")
		(net "GND")
	)
	(segment
		(start 117.888004 -239.8903)
		(end 118.354856 -239.624362)
		(width 0.350012)
		(layer "F.Cu")
		(net "GND")
	)
	(segment
		(start 148.898356 -386.6388)
		(end 148.206206 -386.449062)
		(width 0.254)
		(layer "F.Cu")
		(net "GND")
	)
	(segment
		(start 374.28805 -251.23013)
		(end 374.754902 -250.964192)
		(width 0.350012)
		(layer "F.Cu")
		(net "GND")
	)
	(segment
		(start 357.837994 -226.120198)
		(end 357.371142 -225.85426)
		(width 0.350012)
		(layer "F.Cu")
		(net "GND")
	)
	(segment
		(start 129.57048 -386.6388)
		(end 128.878584 -386.449062)
		(width 0.254)
		(layer "F.Cu")
		(net "GND")
	)
	(segment
		(start 185.922158 -113.85296)
		(end 186.312048 -113.46307)
		(width 0.254)
		(layer "F.Cu")
		(net "GND")
	)
	(segment
		(start 95.327978 -236.650276)
		(end 94.861126 -236.384338)
		(width 0.350012)
		(layer "F.Cu")
		(net "GND")
	)
	(segment
		(start 343.56802 -276.250146)
		(end 343.101168 -276.516084)
		(width 0.350012)
		(layer "F.Cu")
		(net "GND")
	)
	(segment
		(start 348.268036 -264.910062)
		(end 347.801184 -265.176)
		(width 0.350012)
		(layer "F.Cu")
		(net "GND")
	)
	(segment
		(start 101.737922 -294.880284)
		(end 101.27107 -295.146222)
		(width 0.350012)
		(layer "F.Cu")
		(net "GND")
	)
	(segment
		(start 32.947102 -8.320024)
		(end 32.947102 -9.423654)
		(width 0.3556)
		(layer "F.Cu")
		(net "GND")
	)
	(segment
		(start 351.25787 -232.599992)
		(end 350.791018 -232.334054)
		(width 0.350012)
		(layer "F.Cu")
		(net "GND")
	)
	(segment
		(start 102.378002 -240.700306)
		(end 101.91115 -240.434368)
		(width 0.350012)
		(layer "F.Cu")
		(net "GND")
	)
	(segment
		(start 130.107944 -241.510312)
		(end 130.574796 -241.244374)
		(width 0.350012)
		(layer "F.Cu")
		(net "GND")
	)
	(segment
		(start 314.475876 -70.573392)
		(end 314.475876 -71.265542)
		(width 0.508)
		(layer "F.Cu")
		(net "GND")
	)
	(segment
		(start 366.597946 -265.720068)
		(end 367.064798 -265.986006)
		(width 0.350012)
		(layer "F.Cu")
		(net "GND")
	)
	(segment
		(start 130.107944 -225.310446)
		(end 130.574796 -225.044508)
		(width 0.350012)
		(layer "F.Cu")
		(net "GND")
	)
	(segment
		(start 138.098022 -226.120452)
		(end 138.564874 -225.854514)
		(width 0.350012)
		(layer "F.Cu")
		(net "GND")
	)
	(segment
		(start 40.23995 -296.785284)
		(end 41.62425 -296.785284)
		(width 0.4572)
		(layer "F.Cu")
		(net "GND")
	)
	(segment
		(start 98.617786 -224.50044)
		(end 98.150934 -224.234502)
		(width 0.350012)
		(layer "F.Cu")
		(net "GND")
	)
	(segment
		(start 352.027998 -266.530074)
		(end 351.561146 -266.796012)
		(width 0.350012)
		(layer "F.Cu")
		(net "GND")
	)
	(segment
		(start 371.170454 -398.542002)
		(end 371.117876 -399.143474)
		(width 0.254)
		(layer "F.Cu")
		(net "GND")
	)
	(segment
		(start 113.017808 -293.260272)
		(end 113.48466 -293.52621)
		(width 0.350012)
		(layer "F.Cu")
		(net "GND")
	)
	(segment
		(start 381.278384 -394.831062)
		(end 380.770638 -395.0208)
		(width 0.254)
		(layer "F.Cu")
		(net "GND")
	)
	(segment
		(start 412.956756 -7.217156)
		(end 412.956756 -8.320024)
		(width 0.3556)
		(layer "F.Cu")
		(net "GND")
	)
	(segment
		(start 353.345496 -399.143474)
		(end 353.398074 -398.542002)
		(width 0.254)
		(layer "F.Cu")
		(net "GND")
	)
	(segment
		(start 408.498294 -392.999722)
		(end 408.445716 -392.30427)
		(width 0.254)
		(layer "F.Cu")
		(net "GND")
	)
	(segment
		(start 122.018044 -383.402586)
		(end 122.018044 -383.622296)
		(width 0.254)
		(layer "F.Cu")
		(net "GND")
	)
	(segment
		(start 337.745578 -399.143474)
		(end 337.798156 -398.542002)
		(width 0.254)
		(layer "F.Cu")
		(net "GND")
	)
	(segment
		(start 128.76403 -57.13222)
		(end 129.83718 -57.13222)
		(width 0.4572)
		(layer "F.Cu")
		(net "GND")
	)
	(segment
		(start 374.090438 -423.904918)
		(end 373.790464 -424.204892)
		(width 0.254)
		(layer "F.Cu")
		(net "GND")
	)
	(segment
		(start 61.108336 -403.830536)
		(end 61.108336 -402.961602)
		(width 0.381)
		(layer "F.Cu")
		(net "GND")
	)
	(segment
		(start 87.118952 -390.160002)
		(end 87.798402 -390.160002)
		(width 0.254)
		(layer "F.Cu")
		(net "GND")
	)
	(segment
		(start 451.739 -47.475394)
		(end 451.739 -46.68266)
		(width 0.3048)
		(layer "F.Cu")
		(net "GND")
	)
	(segment
		(start 115.367816 -282.730448)
		(end 115.834668 -282.996386)
		(width 0.350012)
		(layer "F.Cu")
		(net "GND")
	)
	(segment
		(start 108.51515 -122.66676)
		(end 108.51515 -121.65711)
		(width 0.3048)
		(layer "F.Cu")
		(net "GND")
	)
	(segment
		(start 259.89788 -48.050196)
		(end 259.89788 -48.659542)
		(width 0.4572)
		(layer "F.Cu")
		(net "GND")
	)
	(segment
		(start 343.268046 -252.850142)
		(end 342.801194 -252.584204)
		(width 0.350012)
		(layer "F.Cu")
		(net "GND")
	)
	(segment
		(start 379.75794 -264.100056)
		(end 380.224792 -264.365994)
		(width 0.350012)
		(layer "F.Cu")
		(net "GND")
	)
	(segment
		(start 241.461798 -292.961822)
		(end 241.971322 -292.961822)
		(width 0.1778)
		(layer "F.Cu")
		(net "GND")
	)
	(segment
		(start 115.067842 -226.930458)
		(end 115.534694 -226.66452)
		(width 0.350012)
		(layer "F.Cu")
		(net "GND")
	)
	(segment
		(start 356.728014 -273.010122)
		(end 356.261162 -273.27606)
		(width 0.350012)
		(layer "F.Cu")
		(net "GND")
	)
	(segment
		(start 359.078022 -291.640006)
		(end 358.61117 -291.905944)
		(width 0.350012)
		(layer "F.Cu")
		(net "GND")
	)
	(segment
		(start 115.067842 -235.030264)
		(end 115.534694 -234.764326)
		(width 0.350012)
		(layer "F.Cu")
		(net "GND")
	)
	(segment
		(start 119.297958 -232.600246)
		(end 119.76481 -232.334308)
		(width 0.350012)
		(layer "F.Cu")
		(net "GND")
	)
	(segment
		(start 92.391738 -340.286848)
		(end 92.1385 -340.540086)
		(width 0.381)
		(layer "F.Cu")
		(net "GND")
	)
	(segment
		(start 163.82238 -16.594582)
		(end 163.82238 -17.608804)
		(width 0.3556)
		(layer "F.Cu")
		(net "GND")
	)
	(segment
		(start 171.97197 -296.785284)
		(end 173.35627 -296.785284)
		(width 0.4572)
		(layer "F.Cu")
		(net "GND")
	)
	(segment
		(start 371.767862 -285.970218)
		(end 372.234714 -286.236156)
		(width 0.350012)
		(layer "F.Cu")
		(net "GND")
	)
	(segment
		(start 345.1479 -244.750082)
		(end 344.681048 -244.484144)
		(width 0.350012)
		(layer "F.Cu")
		(net "GND")
	)
	(segment
		(start 139.811252 -382.00584)
		(end 139.996672 -382.00584)
		(width 0.254)
		(layer "F.Cu")
		(net "GND")
	)
	(segment
		(start 93.91777 -255.280414)
		(end 93.450918 -255.014476)
		(width 0.350012)
		(layer "F.Cu")
		(net "GND")
	)
	(segment
		(start 311.270396 -392.999722)
		(end 311.862216 -392.999722)
		(width 0.254)
		(layer "F.Cu")
		(net "GND")
	)
	(segment
		(start 93.91777 -248.800366)
		(end 93.450918 -248.534428)
		(width 0.350012)
		(layer "F.Cu")
		(net "GND")
	)
	(segment
		(start 320.616326 -399.76171)
		(end 320.517774 -399.663158)
		(width 0.254)
		(layer "F.Cu")
		(net "GND")
	)
	(segment
		(start 384.927856 -289.209988)
		(end 385.394708 -289.475926)
		(width 0.350012)
		(layer "F.Cu")
		(net "GND")
	)
	(segment
		(start 350.31807 -245.560088)
		(end 349.851218 -245.29415)
		(width 0.350012)
		(layer "F.Cu")
		(net "GND")
	)
	(segment
		(start 427.766988 -12.372848)
		(end 427.766988 -11.26998)
		(width 0.3556)
		(layer "F.Cu")
		(net "GND")
	)
	(segment
		(start 336.687922 -243.13007)
		(end 336.22107 -242.864132)
		(width 0.350012)
		(layer "F.Cu")
		(net "GND")
	)
	(segment
		(start 377.107958 -249.610118)
		(end 377.57481 -249.34418)
		(width 0.350012)
		(layer "F.Cu")
		(net "GND")
	)
	(segment
		(start 439.100214 -312.084974)
		(end 437.715914 -312.084974)
		(width 0.4572)
		(layer "F.Cu")
		(net "GND")
	)
	(segment
		(start 118.187978 -289.210242)
		(end 118.65483 -289.47618)
		(width 0.350012)
		(layer "F.Cu")
		(net "GND")
	)
	(segment
		(start 202.147932 -219.435426)
		(end 203.532232 -219.435426)
		(width 0.4572)
		(layer "F.Cu")
		(net "GND")
	)
	(segment
		(start 280.635964 -306.135024)
		(end 282.020264 -306.135024)
		(width 0.4572)
		(layer "F.Cu")
		(net "GND")
	)
	(segment
		(start 21.70811 -209.235294)
		(end 20.32381 -209.235294)
		(width 0.4572)
		(layer "F.Cu")
		(net "GND")
	)
	(segment
		(start 180.772308 -166.201598)
		(end 180.929026 -166.358316)
		(width 0.4572)
		(layer "F.Cu")
		(net "GND")
	)
	(segment
		(start 168.527984 -237.285276)
		(end 167.143684 -237.285276)
		(width 0.4572)
		(layer "F.Cu")
		(net "GND")
	)
	(segment
		(start 357.36784 -236.650022)
		(end 356.901242 -236.384084)
		(width 0.350012)
		(layer "F.Cu")
		(net "GND")
	)
	(segment
		(start 334.167988 -268.150086)
		(end 333.701136 -268.416024)
		(width 0.350012)
		(layer "F.Cu")
		(net "GND")
	)
	(segment
		(start 112.808512 -406.4508)
		(end 113.339372 -405.91994)
		(width 0.3302)
		(layer "F.Cu")
		(net "GND")
	)
	(segment
		(start 88.94572 -390.761474)
		(end 88.645746 -391.281158)
		(width 0.254)
		(layer "F.Cu")
		(net "GND")
	)
	(segment
		(start 335.108042 -294.070024)
		(end 334.64119 -294.335962)
		(width 0.350012)
		(layer "F.Cu")
		(net "GND")
	)
	(segment
		(start 391.208006 -252.850142)
		(end 391.674858 -252.584204)
		(width 0.350012)
		(layer "F.Cu")
		(net "GND")
	)
	(segment
		(start 130.1623 -384.617722)
		(end 130.77063 -384.617722)
		(width 0.254)
		(layer "F.Cu")
		(net "GND")
	)
	(segment
		(start 136.217914 -243.94033)
		(end 136.684766 -243.674392)
		(width 0.350012)
		(layer "F.Cu")
		(net "GND")
	)
	(segment
		(start 381.338074 -242.320064)
		(end 381.804926 -242.054126)
		(width 0.350012)
		(layer "F.Cu")
		(net "GND")
	)
	(segment
		(start 11.265408 -422.551098)
		(end 11.265408 -423.821098)
		(width 0.4572)
		(layer "F.Cu")
		(net "GND")
	)
	(segment
		(start 63.118492 -388.328662)
		(end 63.670688 -388.138924)
		(width 0.254)
		(layer "F.Cu")
		(net "GND")
	)
	(segment
		(start 102.677976 -277.060406)
		(end 102.211124 -277.326344)
		(width 0.350012)
		(layer "F.Cu")
		(net "GND")
	)
	(segment
		(start 376.81789 -392.004296)
		(end 377.117864 -392.30427)
		(width 0.254)
		(layer "F.Cu")
		(net "GND")
	)
	(segment
		(start 394.027914 -235.03001)
		(end 394.68298 -235.03001)
		(width 0.350012)
		(layer "F.Cu")
		(net "GND")
	)
	(segment
		(start 399.171668 -394.800074)
		(end 399.171668 -393.97559)
		(width 0.254)
		(layer "F.Cu")
		(net "GND")
	)
	(segment
		(start 113.017808 -275.440394)
		(end 113.48466 -275.706332)
		(width 0.350012)
		(layer "F.Cu")
		(net "GND")
	)
	(segment
		(start 52.616608 -391.37971)
		(end 52.518056 -391.281158)
		(width 0.254)
		(layer "F.Cu")
		(net "GND")
	)
	(segment
		(start 202.147932 -200.735438)
		(end 203.532232 -200.735438)
		(width 0.4572)
		(layer "F.Cu")
		(net "GND")
	)
	(segment
		(start 127.170434 -384.617722)
		(end 127.117856 -383.92227)
		(width 0.254)
		(layer "F.Cu")
		(net "GND")
	)
	(segment
		(start 144.677892 -240.700306)
		(end 145.144744 -240.434368)
		(width 0.350012)
		(layer "F.Cu")
		(net "GND")
	)
	(segment
		(start 377.878086 -286.780224)
		(end 378.344938 -287.046162)
		(width 0.350012)
		(layer "F.Cu")
		(net "GND")
	)
	(segment
		(start 338.097876 -229.360222)
		(end 337.631024 -229.094284)
		(width 0.350012)
		(layer "F.Cu")
		(net "GND")
	)
	(segment
		(start 333.868014 -225.310192)
		(end 333.401162 -225.044254)
		(width 0.350012)
		(layer "F.Cu")
		(net "GND")
	)
	(segment
		(start 211.992464 -26.468324)
		(end 211.992464 -23.958296)
		(width 0.3556)
		(layer "F.Cu")
		(net "GND")
	)
	(segment
		(start 392.61796 -250.420124)
		(end 393.084812 -250.154186)
		(width 0.350012)
		(layer "F.Cu")
		(net "GND")
	)
	(segment
		(start 22.102318 -423.450258)
		(end 22.724364 -423.450258)
		(width 0.4572)
		(layer "F.Cu")
		(net "GND")
	)
	(segment
		(start 202.147932 -240.68532)
		(end 203.532232 -240.68532)
		(width 0.4572)
		(layer "F.Cu")
		(net "GND")
	)
	(segment
		(start 415.345626 -391.784586)
		(end 415.345626 -391.333482)
		(width 0.254)
		(layer "F.Cu")
		(net "GND")
	)
	(segment
		(start 130.107944 -252.850396)
		(end 130.574796 -252.584458)
		(width 0.350012)
		(layer "F.Cu")
		(net "GND")
	)
	(segment
		(start 327.579228 -41.160954)
		(end 328.188828 -41.160954)
		(width 0.3556)
		(layer "F.Cu")
		(net "GND")
	)
	(segment
		(start 393.046966 -12.372848)
		(end 393.046966 -11.26998)
		(width 0.3556)
		(layer "F.Cu")
		(net "GND")
	)
	(segment
		(start 94.217998 -281.920442)
		(end 93.751146 -282.18638)
		(width 0.350012)
		(layer "F.Cu")
		(net "GND")
	)
	(segment
		(start 333.697834 -267.34008)
		(end 333.230982 -267.606018)
		(width 0.350012)
		(layer "F.Cu")
		(net "GND")
	)
	(segment
		(start 382.817878 -391.333482)
		(end 382.91643 -391.23493)
		(width 0.254)
		(layer "F.Cu")
		(net "GND")
	)
	(segment
		(start 104.257856 -240.700306)
		(end 103.791004 -240.434368)
		(width 0.350012)
		(layer "F.Cu")
		(net "GND")
	)
	(segment
		(start 419.912038 -287.435036)
		(end 421.296338 -287.435036)
		(width 0.4572)
		(layer "F.Cu")
		(net "GND")
	)
	(segment
		(start 331.518006 -222.880174)
		(end 331.051154 -222.614236)
		(width 0.350012)
		(layer "F.Cu")
		(net "GND")
	)
	(segment
		(start 153.444194 -391.830814)
		(end 153.444194 -391.37971)
		(width 0.254)
		(layer "F.Cu")
		(net "GND")
	)
	(segment
		(start 154.545792 -383.402586)
		(end 154.545792 -382.951482)
		(width 0.254)
		(layer "F.Cu")
		(net "GND")
	)
	(segment
		(start 59.391296 -390.160002)
		(end 60.070492 -390.160002)
		(width 0.254)
		(layer "F.Cu")
		(net "GND")
	)
	(segment
		(start 72.6948 -387.4389)
		(end 72.3392 -387.7945)
		(width 0.254)
		(layer "F.Cu")
		(net "GND")
	)
	(segment
		(start 299.82414 -312.084974)
		(end 298.43984 -312.084974)
		(width 0.4572)
		(layer "F.Cu")
		(net "GND")
	)
	(segment
		(start 17.722088 -107.631484)
		(end 17.445482 -107.631484)
		(width 0.3556)
		(layer "F.Cu")
		(net "GND")
	)
	(segment
		(start 341.387938 -238.270034)
		(end 340.921086 -238.004096)
		(width 0.350012)
		(layer "F.Cu")
		(net "GND")
	)
	(segment
		(start 114.916458 -391.37971)
		(end 114.916458 -391.830814)
		(width 0.254)
		(layer "F.Cu")
		(net "GND")
	)
	(segment
		(start 379.28804 -268.150086)
		(end 379.754892 -268.416024)
		(width 0.350012)
		(layer "F.Cu")
		(net "GND")
	)
	(segment
		(start 403.34565 -391.333482)
		(end 403.444202 -391.23493)
		(width 0.254)
		(layer "F.Cu")
		(net "GND")
	)
	(segment
		(start 389.11784 -399.143474)
		(end 389.170672 -398.542002)
		(width 0.254)
		(layer "F.Cu")
		(net "GND")
	)
	(segment
		(start 131.617974 -383.622296)
		(end 131.917948 -383.92227)
		(width 0.254)
		(layer "F.Cu")
		(net "GND")
	)
	(segment
		(start 431.36566 -7.215886)
		(end 431.36693 -7.217156)
		(width 0.3556)
		(layer "F.Cu")
		(net "GND")
	)
	(segment
		(start 381.167894 -284.350206)
		(end 381.634746 -284.616144)
		(width 0.350012)
		(layer "F.Cu")
		(net "GND")
	)
	(segment
		(start 141.38783 -249.610372)
		(end 141.854682 -249.344434)
		(width 0.350012)
		(layer "F.Cu")
		(net "GND")
	)
	(segment
		(start 134.38505 -109.07395)
		(end 135.128 -108.331)
		(width 0.381)
		(layer "F.Cu")
		(net "GND")
	)
	(segment
		(start 188.322204 -117.852952)
		(end 188.712094 -118.242842)
		(width 0.254)
		(layer "F.Cu")
		(net "GND")
	)
	(segment
		(start 362.837984 -265.720068)
		(end 363.304836 -265.986006)
		(width 0.350012)
		(layer "F.Cu")
		(net "GND")
	)
	(segment
		(start 359.716578 -166.430706)
		(end 359.68559 -166.430706)
		(width 0.2286)
		(layer "F.Cu")
		(net "GND")
	)
	(segment
		(start 90.457782 -293.260272)
		(end 89.99093 -293.52621)
		(width 0.350012)
		(layer "F.Cu")
		(net "GND")
	)
	(segment
		(start 21.70811 -295.9354)
		(end 20.32381 -295.9354)
		(width 0.4572)
		(layer "F.Cu")
		(net "GND")
	)
	(segment
		(start 388.217918 -273.820128)
		(end 388.68477 -274.086066)
		(width 0.350012)
		(layer "F.Cu")
		(net "GND")
	)
	(segment
		(start 325.79691 -340.199726)
		(end 326.38492 -340.199726)
		(width 0.381)
		(layer "F.Cu")
		(net "GND")
	)
	(segment
		(start 169.867072 -13.599922)
		(end 169.867072 -12.497054)
		(width 0.3556)
		(layer "F.Cu")
		(net "GND")
	)
	(segment
		(start 158.145734 -382.951482)
		(end 158.244286 -382.85293)
		(width 0.254)
		(layer "F.Cu")
		(net "GND")
	)
	(segment
		(start 176.072038 -209.235294)
		(end 174.687738 -209.235294)
		(width 0.4572)
		(layer "F.Cu")
		(net "GND")
	)
	(segment
		(start 300.571916 -19.09699)
		(end 300.571916 -19.73199)
		(width 0.4064)
		(layer "F.Cu")
		(net "GND")
	)
	(segment
		(start 51.670712 -390.160002)
		(end 52.191412 -390.160002)
		(width 0.254)
		(layer "F.Cu")
		(net "GND")
	)
	(segment
		(start 420.145718 -391.784586)
		(end 420.145718 -391.333482)
		(width 0.254)
		(layer "F.Cu")
		(net "GND")
	)
	(segment
		(start 203.36002 -341.055198)
		(end 203.497434 -341.192612)
		(width 0.1778)
		(layer "F.Cu")
		(net "GND")
	)
	(segment
		(start 350.761554 -345.146122)
		(end 351.349564 -345.146122)
		(width 0.381)
		(layer "F.Cu")
		(net "GND")
	)
	(segment
		(start 77.467968 -251.230384)
		(end 76.812902 -251.230384)
		(width 0.350012)
		(layer "F.Cu")
		(net "GND")
	)
	(segment
		(start 386.03809 -237.460028)
		(end 386.504942 -237.19409)
		(width 0.350012)
		(layer "F.Cu")
		(net "GND")
	)
	(segment
		(start 419.298374 -398.542002)
		(end 418.618924 -398.542002)
		(width 0.254)
		(layer "F.Cu")
		(net "GND")
	)
	(segment
		(start 115.537996 -230.980234)
		(end 116.004848 -230.714296)
		(width 0.350012)
		(layer "F.Cu")
		(net "GND")
	)
	(segment
		(start 128.52781 -287.590484)
		(end 128.994662 -287.856422)
		(width 0.350012)
		(layer "F.Cu")
		(net "GND")
	)
	(segment
		(start 404.5458 -391.784586)
		(end 404.5458 -392.004296)
		(width 0.254)
		(layer "F.Cu")
		(net "GND")
	)
	(segment
		(start 151.890222 -384.617722)
		(end 151.298402 -384.617722)
		(width 0.254)
		(layer "F.Cu")
		(net "GND")
	)
	(segment
		(start 389.627872 -289.209988)
		(end 390.094724 -289.475926)
		(width 0.350012)
		(layer "F.Cu")
		(net "GND")
	)
	(segment
		(start 338.56803 -246.370094)
		(end 338.101178 -246.104156)
		(width 0.350012)
		(layer "F.Cu")
		(net "GND")
	)
	(segment
		(start 83.577938 -237.460282)
		(end 83.111086 -237.194344)
		(width 0.350012)
		(layer "F.Cu")
		(net "GND")
	)
	(segment
		(start 303.268126 -287.435036)
		(end 304.652426 -287.435036)
		(width 0.4572)
		(layer "F.Cu")
		(net "GND")
	)
	(segment
		(start 388.217918 -286.780224)
		(end 388.68477 -287.045908)
		(width 0.350012)
		(layer "F.Cu")
		(net "GND")
	)
	(segment
		(start 292.280086 -239.835182)
		(end 290.895786 -239.835182)
		(width 0.4572)
		(layer "F.Cu")
		(net "GND")
	)
	(segment
		(start 355.487986 -222.070168)
		(end 355.021134 -221.80423)
		(width 0.350012)
		(layer "F.Cu")
		(net "GND")
	)
	(segment
		(start 351.087944 -276.250146)
		(end 350.621092 -276.516084)
		(width 0.350012)
		(layer "F.Cu")
		(net "GND")
	)
	(segment
		(start 108.787946 -273.010376)
		(end 108.321094 -273.276314)
		(width 0.350012)
		(layer "F.Cu")
		(net "GND")
	)
	(segment
		(start 233.671872 -140.855192)
		(end 233.523536 -140.855192)
		(width 0.4572)
		(layer "F.Cu")
		(net "GND")
	)
	(segment
		(start 162.162744 -343.753948)
		(end 162.162744 -343.122758)
		(width 0.4572)
		(layer "F.Cu")
		(net "GND")
	)
	(segment
		(start 100.797868 -277.060406)
		(end 100.331016 -277.326344)
		(width 0.350012)
		(layer "F.Cu")
		(net "GND")
	)
	(segment
		(start 125.970538 -390.160002)
		(end 125.291342 -390.160002)
		(width 0.254)
		(layer "F.Cu")
		(net "GND")
	)
	(segment
		(start 187.060078 -306.135278)
		(end 188.444378 -306.135278)
		(width 0.4572)
		(layer "F.Cu")
		(net "GND")
	)
	(segment
		(start 325.70801 -292.450012)
		(end 325.052944 -292.450012)
		(width 0.350012)
		(layer "F.Cu")
		(net "GND")
	)
	(segment
		(start 146.38782 -290.830254)
		(end 147.042886 -290.830254)
		(width 0.350012)
		(layer "F.Cu")
		(net "GND")
	)
	(segment
		(start 378.347986 -294.070024)
		(end 378.814838 -294.335962)
		(width 0.350012)
		(layer "F.Cu")
		(net "GND")
	)
	(segment
		(start 443.853316 -29.575506)
		(end 443.853316 -30.837378)
		(width 0.254)
		(layer "F.Cu")
		(net "GND")
	)
	(segment
		(start 164.145722 -391.281158)
		(end 164.445696 -390.761474)
		(width 0.254)
		(layer "F.Cu")
		(net "GND")
	)
	(segment
		(start 232.000044 -58.764932)
		(end 230.96728 -58.764932)
		(width 0.381)
		(layer "F.Cu")
		(net "GND")
	)
	(segment
		(start 123.30176 -26.916126)
		(end 122.68708 -27.530806)
		(width 0.3556)
		(layer "F.Cu")
		(net "GND")
	)
	(segment
		(start 91.86799 -294.070278)
		(end 91.401138 -294.336216)
		(width 0.350012)
		(layer "F.Cu")
		(net "GND")
	)
	(segment
		(start 116.77777 -285.160466)
		(end 117.244622 -285.426404)
		(width 0.350012)
		(layer "F.Cu")
		(net "GND")
	)
	(segment
		(start 128.227836 -254.470408)
		(end 128.694688 -254.20447)
		(width 0.350012)
		(layer "F.Cu")
		(net "GND")
	)
	(segment
		(start 25.519126 -349.215964)
		(end 25.519126 -348.79915)
		(width 0.2286)
		(layer "F.Cu")
		(net "GND")
	)
	(segment
		(start 36.795964 -302.735234)
		(end 35.411664 -302.735234)
		(width 0.4572)
		(layer "F.Cu")
		(net "GND")
	)
	(segment
		(start 355.957886 -243.940076)
		(end 355.491034 -243.674138)
		(width 0.350012)
		(layer "F.Cu")
		(net "GND")
	)
	(segment
		(start 205.990444 -346.505022)
		(end 205.990444 -345.867736)
		(width 0.4572)
		(layer "F.Cu")
		(net "GND")
	)
	(segment
		(start 60.070492 -388.138924)
		(end 60.718446 -388.328662)
		(width 0.254)
		(layer "F.Cu")
		(net "GND")
	)
	(segment
		(start 381.917956 -399.143474)
		(end 381.617982 -399.663158)
		(width 0.254)
		(layer "F.Cu")
		(net "GND")
	)
	(segment
		(start 56.117998 -383.622296)
		(end 56.417972 -383.92227)
		(width 0.254)
		(layer "F.Cu")
		(net "GND")
	)
	(segment
		(start 123.997974 -252.04039)
		(end 124.464826 -251.774452)
		(width 0.350012)
		(layer "F.Cu")
		(net "GND")
	)
	(segment
		(start 122.41784 -288.400236)
		(end 122.884692 -288.666174)
		(width 0.350012)
		(layer "F.Cu")
		(net "GND")
	)
	(segment
		(start 72.663304 -12.374118)
		(end 72.663304 -12.37488)
		(width 0.3556)
		(layer "F.Cu")
		(net "GND")
	)
	(segment
		(start 105.497884 -268.960346)
		(end 105.031032 -269.226284)
		(width 0.350012)
		(layer "F.Cu")
		(net "GND")
	)
	(segment
		(start 138.098022 -232.600246)
		(end 138.564874 -232.334308)
		(width 0.350012)
		(layer "F.Cu")
		(net "GND")
	)
	(segment
		(start 341.687912 -279.49017)
		(end 341.22106 -279.756108)
		(width 0.350012)
		(layer "F.Cu")
		(net "GND")
	)
	(segment
		(start 423.9514 -42.357548)
		(end 422.9354 -42.357548)
		(width 0.4572)
		(layer "F.Cu")
		(net "GND")
	)
	(segment
		(start 100.55733 -342.524588)
		(end 100.647754 -342.306402)
		(width 0.2286)
		(layer "F.Cu")
		(net "GND")
	)
	(segment
		(start 84.047838 -251.230384)
		(end 83.580986 -250.964446)
		(width 0.350012)
		(layer "F.Cu")
		(net "GND")
	)
	(segment
		(start 168.527984 -295.9354)
		(end 167.143684 -295.9354)
		(width 0.4572)
		(layer "F.Cu")
		(net "GND")
	)
	(segment
		(start 146.38782 -274.630388)
		(end 147.042886 -274.630388)
		(width 0.350012)
		(layer "F.Cu")
		(net "GND")
	)
	(segment
		(start 115.170458 -390.160002)
		(end 115.11788 -390.761474)
		(width 0.254)
		(layer "F.Cu")
		(net "GND")
	)
	(segment
		(start 450.705982 -399.740628)
		(end 451.376288 -399.070322)
		(width 0.2032)
		(layer "F.Cu")
		(net "GND")
	)
	(segment
		(start 73.02373 -382.27)
		(end 73.29805 -382.54432)
		(width 0.254)
		(layer "F.Cu")
		(net "GND")
	)
	(segment
		(start 79.14894 -390.231122)
		(end 79.14894 -389.63092)
		(width 0.254)
		(layer "F.Cu")
		(net "GND")
	)
	(segment
		(start 446.644268 -202.434952)
		(end 445.259968 -202.434952)
		(width 0.4572)
		(layer "F.Cu")
		(net "GND")
	)
	(segment
		(start 129.63779 -250.420378)
		(end 130.104642 -250.15444)
		(width 0.350012)
		(layer "F.Cu")
		(net "GND")
	)
	(segment
		(start 133.398006 -248.800366)
		(end 133.864858 -248.534428)
		(width 0.350012)
		(layer "F.Cu")
		(net "GND")
	)
	(segment
		(start 84.047838 -241.510312)
		(end 83.580986 -241.244374)
		(width 0.350012)
		(layer "F.Cu")
		(net "GND")
	)
	(segment
		(start 400.24812 -12.37488)
		(end 400.24812 -12.374118)
		(width 0.3556)
		(layer "F.Cu")
		(net "GND")
	)
	(segment
		(start 305.418998 -40.890698)
		(end 304.809398 -40.890698)
		(width 0.3556)
		(layer "F.Cu")
		(net "GND")
	)
	(segment
		(start 166.18077 -393.509246)
		(end 166.11727 -393.445746)
		(width 0.254)
		(layer "F.Cu")
		(net "GND")
	)
	(segment
		(start 103.317802 -232.600246)
		(end 102.85095 -232.334308)
		(width 0.350012)
		(layer "F.Cu")
		(net "GND")
	)
	(segment
		(start 123.827794 -282.730448)
		(end 124.294646 -282.996386)
		(width 0.350012)
		(layer "F.Cu")
		(net "GND")
	)
	(segment
		(start 392.917934 -275.44014)
		(end 393.384786 -275.706078)
		(width 0.350012)
		(layer "F.Cu")
		(net "GND")
	)
	(segment
		(start 429.565562 -7.215124)
		(end 429.565562 -7.215886)
		(width 0.3556)
		(layer "F.Cu")
		(net "GND")
	)
	(segment
		(start 175.553116 -32.013144)
		(end 176.694338 -30.871922)
		(width 0.254)
		(layer "F.Cu")
		(net "GND")
	)
	(segment
		(start 58.818018 -383.92227)
		(end 58.870596 -384.617722)
		(width 0.254)
		(layer "F.Cu")
		(net "GND")
	)
	(segment
		(start 103.147876 -282.730448)
		(end 102.681024 -282.996386)
		(width 0.350012)
		(layer "F.Cu")
		(net "GND")
	)
	(segment
		(start 81.190084 -384.617722)
		(end 81.798414 -384.617722)
		(width 0.254)
		(layer "F.Cu")
		(net "GND")
	)
	(segment
		(start 144.977866 -275.440394)
		(end 145.444718 -275.706332)
		(width 0.350012)
		(layer "F.Cu")
		(net "GND")
	)
	(segment
		(start 173.295056 -56.925464)
		(end 173.769528 -57.399936)
		(width 0.3556)
		(layer "F.Cu")
		(net "GND")
	)
	(segment
		(start 371.297962 -277.060152)
		(end 371.764814 -277.32609)
		(width 0.350012)
		(layer "F.Cu")
		(net "GND")
	)
	(segment
		(start 26.626566 -39.037514)
		(end 26.626566 -38.402514)
		(width 0.3556)
		(layer "F.Cu")
		(net "GND")
	)
	(segment
		(start 19.844258 -428.589948)
		(end 19.844258 -427.980348)
		(width 0.3556)
		(layer "F.Cu")
		(net "GND")
	)
	(segment
		(start 410.659326 -140.310616)
		(end 410.340302 -140.310616)
		(width 0.3556)
		(layer "F.Cu")
		(net "GND")
	)
	(segment
		(start 153.598372 -65.76314)
		(end 153.598372 -65.420748)
		(width 0.381)
		(layer "F.Cu")
		(net "GND")
	)
	(segment
		(start 370.225066 -424.403012)
		(end 370.225066 -424.838622)
		(width 0.381)
		(layer "F.Cu")
		(net "GND")
	)
	(segment
		(start 346.557854 -226.120198)
		(end 346.091002 -225.85426)
		(width 0.350012)
		(layer "F.Cu")
		(net "GND")
	)
	(segment
		(start 384.018028 -391.784586)
		(end 384.018028 -392.004296)
		(width 0.254)
		(layer "F.Cu")
		(net "GND")
	)
	(segment
		(start 372.891304 -398.542002)
		(end 372.370604 -398.542002)
		(width 0.254)
		(layer "F.Cu")
		(net "GND")
	)
	(segment
		(start 59.428126 -295.9354)
		(end 58.043826 -295.9354)
		(width 0.4572)
		(layer "F.Cu")
		(net "GND")
	)
	(segment
		(start 110.643924 -386.418074)
		(end 110.643924 -385.59359)
		(width 0.254)
		(layer "F.Cu")
		(net "GND")
	)
	(segment
		(start 143.567912 -274.630388)
		(end 144.034764 -274.896326)
		(width 0.350012)
		(layer "F.Cu")
		(net "GND")
	)
	(segment
		(start 153.698194 -388.138924)
		(end 153.146252 -388.328662)
		(width 0.254)
		(layer "F.Cu")
		(net "GND")
	)
	(segment
		(start 131.817872 -270.580358)
		(end 132.284724 -270.846296)
		(width 0.350012)
		(layer "F.Cu")
		(net "GND")
	)
	(segment
		(start 371.938042 -224.500186)
		(end 372.404894 -224.234248)
		(width 0.350012)
		(layer "F.Cu")
		(net "GND")
	)
	(segment
		(start 107.847892 -295.69029)
		(end 107.38104 -295.956228)
		(width 0.350012)
		(layer "F.Cu")
		(net "GND")
	)
	(segment
		(start 398.446752 -8.320024)
		(end 398.446752 -9.423654)
		(width 0.3556)
		(layer "F.Cu")
		(net "GND")
	)
	(segment
		(start 446.644268 -274.684998)
		(end 445.259968 -274.684998)
		(width 0.4572)
		(layer "F.Cu")
		(net "GND")
	)
	(segment
		(start 332.28788 -268.150086)
		(end 331.821028 -268.416024)
		(width 0.350012)
		(layer "F.Cu")
		(net "GND")
	)
	(segment
		(start 328.527918 -285.970218)
		(end 328.061066 -286.236156)
		(width 0.350012)
		(layer "F.Cu")
		(net "GND")
	)
	(segment
		(start 381.807974 -225.310192)
		(end 382.274826 -225.044254)
		(width 0.350012)
		(layer "F.Cu")
		(net "GND")
	)
	(segment
		(start 355.78796 -268.150086)
		(end 355.321108 -268.416024)
		(width 0.350012)
		(layer "F.Cu")
		(net "GND")
	)
	(segment
		(start 347.968062 -256.090166)
		(end 347.50121 -255.824228)
		(width 0.350012)
		(layer "F.Cu")
		(net "GND")
	)
	(segment
		(start 110.377732 -397.654526)
		(end 110.584996 -397.86179)
		(width 0.3048)
		(layer "F.Cu")
		(net "GND")
	)
	(segment
		(start 140.27785 -285.160466)
		(end 140.744702 -285.426404)
		(width 0.350012)
		(layer "F.Cu")
		(net "GND")
	)
	(segment
		(start 378.01804 -391.784586)
		(end 378.01804 -391.333482)
		(width 0.254)
		(layer "F.Cu")
		(net "GND")
	)
	(segment
		(start 320.340228 -39.55542)
		(end 320.340228 -40.652954)
		(width 0.3556)
		(layer "F.Cu")
		(net "GND")
	)
	(segment
		(start 415.006282 -394.831062)
		(end 414.498282 -395.0208)
		(width 0.254)
		(layer "F.Cu")
		(net "GND")
	)
	(segment
		(start 53.265832 -7.215886)
		(end 53.267102 -7.217156)
		(width 0.3556)
		(layer "F.Cu")
		(net "GND")
	)
	(segment
		(start 380.71806 -392.30427)
		(end 380.417832 -392.004042)
		(width 0.254)
		(layer "F.Cu")
		(net "GND")
	)
	(segment
		(start 97.207832 -228.55047)
		(end 96.74098 -228.284532)
		(width 0.350012)
		(layer "F.Cu")
		(net "GND")
	)
	(segment
		(start 406.945592 -399.663158)
		(end 407.24582 -399.143474)
		(width 0.254)
		(layer "F.Cu")
		(net "GND")
	)
	(segment
		(start 381.338074 -237.460028)
		(end 381.804926 -237.19409)
		(width 0.350012)
		(layer "F.Cu")
		(net "GND")
	)
	(segment
		(start 121.177812 -243.94033)
		(end 121.644664 -243.674392)
		(width 0.350012)
		(layer "F.Cu")
		(net "GND")
	)
	(segment
		(start 370.997988 -235.840016)
		(end 371.46484 -235.574078)
		(width 0.350012)
		(layer "F.Cu")
		(net "GND")
	)
	(segment
		(start 147.877022 -23.963376)
		(end 147.344892 -24.495506)
		(width 0.4572)
		(layer "F.Cu")
		(net "GND")
	)
	(segment
		(start 100.497894 -255.280414)
		(end 100.031042 -255.014476)
		(width 0.350012)
		(layer "F.Cu")
		(net "GND")
	)
	(segment
		(start 132.562346 -384.617722)
		(end 133.20141 -384.617722)
		(width 0.254)
		(layer "F.Cu")
		(net "GND")
	)
	(segment
		(start 148.644356 -391.830814)
		(end 148.644356 -391.37971)
		(width 0.254)
		(layer "F.Cu")
		(net "GND")
	)
	(segment
		(start 387.448044 -223.69018)
		(end 387.914896 -223.424242)
		(width 0.350012)
		(layer "F.Cu")
		(net "GND")
	)
	(segment
		(start 358.607868 -276.250146)
		(end 358.141016 -276.516084)
		(width 0.350012)
		(layer "F.Cu")
		(net "GND")
	)
	(segment
		(start 338.39785 -273.820128)
		(end 337.930998 -274.086066)
		(width 0.350012)
		(layer "F.Cu")
		(net "GND")
	)
	(segment
		(start 346.858082 -264.100056)
		(end 346.39123 -264.365994)
		(width 0.350012)
		(layer "F.Cu")
		(net "GND")
	)
	(segment
		(start 351.557844 -277.060152)
		(end 351.091246 -277.32609)
		(width 0.350012)
		(layer "F.Cu")
		(net "GND")
	)
	(segment
		(start 313.317636 -391.784586)
		(end 313.317636 -391.333482)
		(width 0.254)
		(layer "F.Cu")
		(net "GND")
	)
	(segment
		(start 140.27785 -260.860286)
		(end 140.744702 -261.126224)
		(width 0.350012)
		(layer "F.Cu")
		(net "GND")
	)
	(segment
		(start 183.616092 -312.085228)
		(end 182.231792 -312.085228)
		(width 0.4572)
		(layer "F.Cu")
		(net "GND")
	)
	(segment
		(start 342.485726 -340.236048)
		(end 343.073736 -340.236048)
		(width 0.381)
		(layer "F.Cu")
		(net "GND")
	)
	(segment
		(start 51.468274 -12.374118)
		(end 51.467004 -12.372848)
		(width 0.3556)
		(layer "F.Cu")
		(net "GND")
	)
	(segment
		(start 332.28788 -271.39011)
		(end 331.821028 -271.656048)
		(width 0.350012)
		(layer "F.Cu")
		(net "GND")
	)
	(segment
		(start 316.507876 -70.573392)
		(end 316.507876 -71.265542)
		(width 0.508)
		(layer "F.Cu")
		(net "GND")
	)
	(segment
		(start 139.977876 -230.980234)
		(end 140.444728 -230.71455)
		(width 0.350012)
		(layer "F.Cu")
		(net "GND")
	)
	(segment
		(start 353.137978 -232.599992)
		(end 352.671126 -232.334054)
		(width 0.350012)
		(layer "F.Cu")
		(net "GND")
	)
	(segment
		(start 348.437962 -250.420124)
		(end 347.97111 -250.154186)
		(width 0.350012)
		(layer "F.Cu")
		(net "GND")
	)
	(segment
		(start 135.02132 -394.08608)
		(end 134.23646 -394.08608)
		(width 0.3048)
		(layer "F.Cu")
		(net "GND")
	)
	(segment
		(start 100.327968 -281.110436)
		(end 99.861116 -281.376374)
		(width 0.350012)
		(layer "F.Cu")
		(net "GND")
	)
	(segment
		(start 273.092164 -240.685066)
		(end 274.476464 -240.685066)
		(width 0.4572)
		(layer "F.Cu")
		(net "GND")
	)
	(segment
		(start 435.000146 -210.085178)
		(end 436.384446 -210.085178)
		(width 0.4572)
		(layer "F.Cu")
		(net "GND")
	)
	(segment
		(start 96.737932 -253.660402)
		(end 96.27108 -253.394464)
		(width 0.350012)
		(layer "F.Cu")
		(net "GND")
	)
	(segment
		(start 389.327898 -238.270034)
		(end 389.79475 -238.004096)
		(width 0.350012)
		(layer "F.Cu")
		(net "GND")
	)
	(segment
		(start 382.748028 -239.890046)
		(end 383.21488 -239.624108)
		(width 0.350012)
		(layer "F.Cu")
		(net "GND")
	)
	(segment
		(start 371.467888 -230.169974)
		(end 371.93474 -229.904036)
		(width 0.350012)
		(layer "F.Cu")
		(net "GND")
	)
	(segment
		(start 56.117998 -383.402586)
		(end 56.117998 -382.951482)
		(width 0.254)
		(layer "F.Cu")
		(net "GND")
	)
	(segment
		(start 387.448044 -249.610118)
		(end 387.914896 -249.34418)
		(width 0.350012)
		(layer "F.Cu")
		(net "GND")
	)
	(segment
		(start 140.27785 -294.880284)
		(end 140.744702 -295.146222)
		(width 0.350012)
		(layer "F.Cu")
		(net "GND")
	)
	(segment
		(start 347.797882 -270.580104)
		(end 347.33103 -270.846042)
		(width 0.350012)
		(layer "F.Cu")
		(net "GND")
	)
	(segment
		(start 348.24543 -391.784586)
		(end 348.24543 -392.004296)
		(width 0.254)
		(layer "F.Cu")
		(net "GND")
	)
	(segment
		(start 100.027994 -244.750336)
		(end 99.561142 -244.484398)
		(width 0.350012)
		(layer "F.Cu")
		(net "GND")
	)
	(segment
		(start 373.817896 -226.120198)
		(end 374.284748 -225.85426)
		(width 0.350012)
		(layer "F.Cu")
		(net "GND")
	)
	(segment
		(start 135.748014 -249.610372)
		(end 136.214866 -249.344434)
		(width 0.350012)
		(layer "F.Cu")
		(net "GND")
	)
	(segment
		(start 359.078022 -281.920188)
		(end 358.61117 -282.186126)
		(width 0.350012)
		(layer "F.Cu")
		(net "GND")
	)
	(segment
		(start 333.697834 -262.480044)
		(end 333.230982 -262.745982)
		(width 0.350012)
		(layer "F.Cu")
		(net "GND")
	)
	(segment
		(start 82.601054 -177.532284)
		(end 82.531204 -177.602134)
		(width 0.381)
		(layer "F.Cu")
		(net "GND")
	)
	(segment
		(start 136.217914 -255.280414)
		(end 136.684766 -255.014476)
		(width 0.350012)
		(layer "F.Cu")
		(net "GND")
	)
	(segment
		(start 389.627872 -266.530074)
		(end 390.094724 -266.796012)
		(width 0.350012)
		(layer "F.Cu")
		(net "GND")
	)
	(segment
		(start 60.91809 -383.402586)
		(end 60.91809 -383.622296)
		(width 0.254)
		(layer "F.Cu")
		(net "GND")
	)
	(segment
		(start 22.1361 -391.349484)
		(end 22.806406 -390.679178)
		(width 0.2032)
		(layer "F.Cu")
		(net "GND")
	)
	(segment
		(start 380.86792 -256.090166)
		(end 381.334772 -255.824228)
		(width 0.350012)
		(layer "F.Cu")
		(net "GND")
	)
	(segment
		(start 390.267952 -223.69018)
		(end 390.734804 -223.424242)
		(width 0.350012)
		(layer "F.Cu")
		(net "GND")
	)
	(segment
		(start 387.748018 -261.670038)
		(end 388.21487 -261.935976)
		(width 0.350012)
		(layer "F.Cu")
		(net "GND")
	)
	(segment
		(start 198.7042 -286.585406)
		(end 197.3199 -286.585406)
		(width 0.4572)
		(layer "F.Cu")
		(net "GND")
	)
	(segment
		(start 348.737936 -264.100056)
		(end 348.271084 -264.365994)
		(width 0.350012)
		(layer "F.Cu")
		(net "GND")
	)
	(segment
		(start 366.597946 -285.160212)
		(end 367.064798 -285.42615)
		(width 0.350012)
		(layer "F.Cu")
		(net "GND")
	)
	(segment
		(start 370.997988 -232.599992)
		(end 371.46484 -232.334054)
		(width 0.350012)
		(layer "F.Cu")
		(net "GND")
	)
	(segment
		(start 411.49016 -392.999722)
		(end 412.098236 -392.999722)
		(width 0.254)
		(layer "F.Cu")
		(net "GND")
	)
	(segment
		(start 325.408036 -228.550216)
		(end 324.941184 -228.284278)
		(width 0.350012)
		(layer "F.Cu")
		(net "GND")
	)
	(segment
		(start 120.238012 -250.420378)
		(end 120.70461 -250.15444)
		(width 0.350012)
		(layer "F.Cu")
		(net "GND")
	)
	(segment
		(start 157.89021 -384.617722)
		(end 158.498286 -384.617722)
		(width 0.254)
		(layer "F.Cu")
		(net "GND")
	)
	(segment
		(start 119.297958 -240.700306)
		(end 119.76481 -240.434368)
		(width 0.350012)
		(layer "F.Cu")
		(net "GND")
	)
	(segment
		(start 186.038236 -428.814992)
		(end 186.038236 -429.42764)
		(width 0.381)
		(layer "F.Cu")
		(net "GND")
	)
	(segment
		(start 29.346906 -11.26998)
		(end 29.346906 -10.16635)
		(width 0.3556)
		(layer "F.Cu")
		(net "GND")
	)
	(segment
		(start 180.891688 -26.240232)
		(end 181.20868 -25.92324)
		(width 0.4572)
		(layer "F.Cu")
		(net "GND")
	)
	(segment
		(start 379.75794 -293.260018)
		(end 380.224792 -293.525956)
		(width 0.350012)
		(layer "F.Cu")
		(net "GND")
	)
	(segment
		(start 83.577938 -222.880428)
		(end 83.111086 -222.61449)
		(width 0.350012)
		(layer "F.Cu")
		(net "GND")
	)
	(segment
		(start 202.147932 -315.485272)
		(end 203.532232 -315.485272)
		(width 0.4572)
		(layer "F.Cu")
		(net "GND")
	)
	(segment
		(start 350.389952 -392.999722)
		(end 349.798132 -392.999722)
		(width 0.254)
		(layer "F.Cu")
		(net "GND")
	)
	(segment
		(start 308.262274 -392.999722)
		(end 308.87035 -392.999722)
		(width 0.254)
		(layer "F.Cu")
		(net "GND")
	)
	(segment
		(start 362.368084 -276.250146)
		(end 362.834682 -276.516084)
		(width 0.350012)
		(layer "F.Cu")
		(net "GND")
	)
	(segment
		(start 346.79001 -392.999722)
		(end 346.19819 -392.999722)
		(width 0.254)
		(layer "F.Cu")
		(net "GND")
	)
	(segment
		(start 59.51855 -388.328662)
		(end 60.070492 -388.138924)
		(width 0.254)
		(layer "F.Cu")
		(net "GND")
	)
	(segment
		(start 146.145758 -383.622296)
		(end 146.445732 -383.92227)
		(width 0.254)
		(layer "F.Cu")
		(net "GND")
	)
	(segment
		(start 400.893026 -174.649892)
		(end 401.437094 -174.105824)
		(width 0.2286)
		(layer "F.Cu")
		(net "GND")
	)
	(segment
		(start 325.70801 -268.150086)
		(end 325.052944 -268.150086)
		(width 0.350012)
		(layer "F.Cu")
		(net "GND")
	)
	(segment
		(start 124.297948 -277.060406)
		(end 124.7648 -277.326344)
		(width 0.350012)
		(layer "F.Cu")
		(net "GND")
	)
	(segment
		(start 328.998072 -267.34008)
		(end 328.53122 -267.606018)
		(width 0.350012)
		(layer "F.Cu")
		(net "GND")
	)
	(segment
		(start 431.36566 -7.215124)
		(end 431.36566 -7.215886)
		(width 0.3556)
		(layer "F.Cu")
		(net "GND")
	)
	(segment
		(start 87.798402 -390.160002)
		(end 88.319102 -390.160002)
		(width 0.254)
		(layer "F.Cu")
		(net "GND")
	)
	(segment
		(start 81.058004 -273.820382)
		(end 80.591152 -274.08632)
		(width 0.350012)
		(layer "F.Cu")
		(net "GND")
	)
	(segment
		(start 206.248 -274.685252)
		(end 204.8637 -274.685252)
		(width 0.4572)
		(layer "F.Cu")
		(net "GND")
	)
	(segment
		(start 421.345614 -399.663158)
		(end 421.645588 -399.143474)
		(width 0.254)
		(layer "F.Cu")
		(net "GND")
	)
	(segment
		(start 94.645734 -391.281158)
		(end 94.945708 -390.761474)
		(width 0.254)
		(layer "F.Cu")
		(net "GND")
	)
	(segment
		(start 146.38782 -285.970472)
		(end 147.042886 -285.970472)
		(width 0.350012)
		(layer "F.Cu")
		(net "GND")
	)
	(segment
		(start 450.088 -278.085042)
		(end 451.4723 -278.085042)
		(width 0.4572)
		(layer "F.Cu")
		(net "GND")
	)
	(segment
		(start 295.724072 -296.78503)
		(end 297.108372 -296.78503)
		(width 0.4572)
		(layer "F.Cu")
		(net "GND")
	)
	(segment
		(start 223.8121 -48.78197)
		(end 223.068134 -48.78197)
		(width 0.3556)
		(layer "F.Cu")
		(net "GND")
	)
	(segment
		(start 277.192232 -305.28514)
		(end 275.807932 -305.28514)
		(width 0.4572)
		(layer "F.Cu")
		(net "GND")
	)
	(segment
		(start 139.507976 -249.610372)
		(end 139.974828 -249.344434)
		(width 0.350012)
		(layer "F.Cu")
		(net "GND")
	)
	(segment
		(start 230.275638 -158.981648)
		(end 230.275638 -159.620204)
		(width 0.4064)
		(layer "F.Cu")
		(net "GND")
	)
	(segment
		(start 227.088192 -289.012122)
		(end 226.478592 -289.012122)
		(width 0.4572)
		(layer "F.Cu")
		(net "GND")
	)
	(segment
		(start 120.537986 -270.580358)
		(end 121.004838 -270.846296)
		(width 0.350012)
		(layer "F.Cu")
		(net "GND")
	)
	(segment
		(start 98.617786 -255.280414)
		(end 98.150934 -255.014476)
		(width 0.350012)
		(layer "F.Cu")
		(net "GND")
	)
	(segment
		(start 328.058018 -268.960092)
		(end 327.591166 -269.22603)
		(width 0.350012)
		(layer "F.Cu")
		(net "GND")
	)
	(segment
		(start 377.878086 -288.399982)
		(end 378.344938 -288.66592)
		(width 0.350012)
		(layer "F.Cu")
		(net "GND")
	)
	(segment
		(start 356.89794 -224.500186)
		(end 356.431088 -224.234248)
		(width 0.350012)
		(layer "F.Cu")
		(net "GND")
	)
	(segment
		(start 336.245454 -391.784586)
		(end 336.245454 -392.004296)
		(width 0.254)
		(layer "F.Cu")
		(net "GND")
	)
	(segment
		(start 113.721134 -387.832092)
		(end 113.721134 -387.231128)
		(width 0.254)
		(layer "F.Cu")
		(net "GND")
	)
	(segment
		(start 345.918028 -270.580104)
		(end 345.451176 -270.846042)
		(width 0.350012)
		(layer "F.Cu")
		(net "GND")
	)
	(segment
		(start 328.527918 -261.670038)
		(end 328.061066 -261.935976)
		(width 0.350012)
		(layer "F.Cu")
		(net "GND")
	)
	(segment
		(start 108.017818 -242.320318)
		(end 107.550966 -242.05438)
		(width 0.350012)
		(layer "F.Cu")
		(net "GND")
	)
	(segment
		(start 150.945596 -383.402586)
		(end 150.945596 -382.951482)
		(width 0.2032)
		(layer "F.Cu")
		(net "GND")
	)
	(segment
		(start 40.23995 -312.935366)
		(end 41.62425 -312.935366)
		(width 0.4572)
		(layer "F.Cu")
		(net "GND")
	)
	(segment
		(start 164.145722 -383.402586)
		(end 164.145722 -383.622296)
		(width 0.254)
		(layer "F.Cu")
		(net "GND")
	)
	(segment
		(start 128.227836 -231.79024)
		(end 128.694688 -231.524302)
		(width 0.350012)
		(layer "F.Cu")
		(net "GND")
	)
	(segment
		(start 107.078018 -232.600246)
		(end 106.611166 -232.334308)
		(width 0.350012)
		(layer "F.Cu")
		(net "GND")
	)
	(segment
		(start 147.698206 -388.138924)
		(end 147.146264 -388.328662)
		(width 0.254)
		(layer "F.Cu")
		(net "GND")
	)
	(segment
		(start 107.547918 -223.690434)
		(end 108.49102 -224.234502)
		(width 0.254)
		(layer "F.Cu")
		(net "GND")
	)
	(segment
		(start 123.05792 -240.700306)
		(end 123.524772 -240.434368)
		(width 0.350012)
		(layer "F.Cu")
		(net "GND")
	)
	(segment
		(start 363.307884 -266.530074)
		(end 363.774736 -266.796012)
		(width 0.350012)
		(layer "F.Cu")
		(net "GND")
	)
	(segment
		(start 29.346906 -8.320024)
		(end 29.346906 -9.423654)
		(width 0.3556)
		(layer "F.Cu")
		(net "GND")
	)
	(segment
		(start 118.767098 -169.56659)
		(end 118.767098 -169.845482)
		(width 0.2286)
		(layer "F.Cu")
		(net "GND")
	)
	(segment
		(start 136.217914 -234.220258)
		(end 136.684766 -233.95432)
		(width 0.350012)
		(layer "F.Cu")
		(net "GND")
	)
	(segment
		(start 320.340228 -47.002954)
		(end 320.949828 -47.002954)
		(width 0.3556)
		(layer "F.Cu")
		(net "GND")
	)
	(segment
		(start 112.717834 -227.740464)
		(end 113.184686 -227.474526)
		(width 0.350012)
		(layer "F.Cu")
		(net "GND")
	)
	(segment
		(start 11.512042 -52.634896)
		(end 11.51636 -52.639214)
		(width 0.4572)
		(layer "F.Cu")
		(net "GND")
	)
	(segment
		(start 442.5442 -278.085042)
		(end 443.9285 -278.085042)
		(width 0.4572)
		(layer "F.Cu")
		(net "GND")
	)
	(segment
		(start 418.023802 -158.779972)
		(end 418.023802 -159.310324)
		(width 0.381)
		(layer "F.Cu")
		(net "GND")
	)
	(segment
		(start 318.277748 -360.66095)
		(end 318.74587 -360.192828)
		(width 0.381)
		(layer "F.Cu")
		(net "GND")
	)
	(segment
		(start 88.998298 -390.160002)
		(end 88.94572 -390.761474)
		(width 0.254)
		(layer "F.Cu")
		(net "GND")
	)
	(segment
		(start 125.877828 -253.660402)
		(end 126.34468 -253.394464)
		(width 0.350012)
		(layer "F.Cu")
		(net "GND")
	)
	(segment
		(start 343.268046 -243.13007)
		(end 342.801194 -242.864132)
		(width 0.350012)
		(layer "F.Cu")
		(net "GND")
	)
	(segment
		(start 187.060078 -200.735438)
		(end 188.444378 -200.735438)
		(width 0.4572)
		(layer "F.Cu")
		(net "GND")
	)
	(segment
		(start 381.638048 -273.820128)
		(end 382.1049 -274.086066)
		(width 0.350012)
		(layer "F.Cu")
		(net "GND")
	)
	(segment
		(start 331.81798 -281.920188)
		(end 331.351128 -282.186126)
		(width 0.350012)
		(layer "F.Cu")
		(net "GND")
	)
	(segment
		(start 64.178688 -386.449062)
		(end 63.670688 -386.6388)
		(width 0.254)
		(layer "F.Cu")
		(net "GND")
	)
	(segment
		(start 349.378016 -226.120198)
		(end 348.911164 -225.85426)
		(width 0.350012)
		(layer "F.Cu")
		(net "GND")
	)
	(segment
		(start 280.635964 -231.335072)
		(end 282.020264 -231.335072)
		(width 0.4572)
		(layer "F.Cu")
		(net "GND")
	)
	(segment
		(start 98.842576 -384.831082)
		(end 98.629216 -384.617722)
		(width 0.254)
		(layer "F.Cu")
		(net "GND")
	)
	(segment
		(start 76.654914 -172.36821)
		(end 77.185266 -172.36821)
		(width 0.381)
		(layer "F.Cu")
		(net "GND")
	)
	(segment
		(start 370.057934 -222.880174)
		(end 370.524786 -222.614236)
		(width 0.350012)
		(layer "F.Cu")
		(net "GND")
	)
	(segment
		(start 368.17808 -232.599992)
		(end 368.644678 -232.334054)
		(width 0.350012)
		(layer "F.Cu")
		(net "GND")
	)
	(segment
		(start 419.81374 -103.480108)
		(end 420.025068 -103.691436)
		(width 0.254)
		(layer "F.Cu")
		(net "GND")
	)
	(segment
		(start 213.369398 -20.687792)
		(end 213.369398 -21.067014)
		(width 0.3556)
		(layer "F.Cu")
		(net "GND")
	)
	(segment
		(start 119.617998 -382.951482)
		(end 119.71655 -382.85293)
		(width 0.2032)
		(layer "F.Cu")
		(net "GND")
	)
	(segment
		(start 370.817902 -392.004296)
		(end 371.117876 -392.30427)
		(width 0.254)
		(layer "F.Cu")
		(net "GND")
	)
	(segment
		(start 381.638048 -280.300176)
		(end 382.1049 -280.566114)
		(width 0.350012)
		(layer "F.Cu")
		(net "GND")
	)
	(segment
		(start 133.346952 -17.652746)
		(end 133.348222 -17.654016)
		(width 0.3556)
		(layer "F.Cu")
		(net "GND")
	)
	(segment
		(start 89.987882 -294.070278)
		(end 89.52103 -294.336216)
		(width 0.350012)
		(layer "F.Cu")
		(net "GND")
	)
	(segment
		(start 345.1479 -228.550216)
		(end 344.681048 -228.284278)
		(width 0.350012)
		(layer "F.Cu")
		(net "GND")
	)
	(segment
		(start 384.457956 -286.780224)
		(end 384.924808 -287.045908)
		(width 0.350012)
		(layer "F.Cu")
		(net "GND")
	)
	(segment
		(start 335.577942 -262.480044)
		(end 335.11109 -262.745982)
		(width 0.350012)
		(layer "F.Cu")
		(net "GND")
	)
	(segment
		(start 136.987788 -264.910316)
		(end 137.45464 -265.176254)
		(width 0.350012)
		(layer "F.Cu")
		(net "GND")
	)
	(segment
		(start 79.34579 -390.761474)
		(end 79.045816 -391.281158)
		(width 0.254)
		(layer "F.Cu")
		(net "GND")
	)
	(segment
		(start 404.206202 -394.831062)
		(end 403.698202 -395.0208)
		(width 0.254)
		(layer "F.Cu")
		(net "GND")
	)
	(segment
		(start 59.428126 -284.035246)
		(end 58.043826 -284.035246)
		(width 0.4572)
		(layer "F.Cu")
		(net "GND")
	)
	(segment
		(start 120.238012 -229.360476)
		(end 120.70461 -229.094538)
		(width 0.350012)
		(layer "F.Cu")
		(net "GND")
	)
	(segment
		(start 119.97055 -384.617722)
		(end 120.56237 -384.617722)
		(width 0.254)
		(layer "F.Cu")
		(net "GND")
	)
	(segment
		(start 128.227836 -247.99036)
		(end 128.694688 -247.724422)
		(width 0.350012)
		(layer "F.Cu")
		(net "GND")
	)
	(segment
		(start 79.177896 -260.860286)
		(end 78.711044 -261.126224)
		(width 0.350012)
		(layer "F.Cu")
		(net "GND")
	)
	(segment
		(start 103.185722 -30.086554)
		(end 103.052372 -30.219904)
		(width 0.254)
		(layer "F.Cu")
		(net "GND")
	)
	(segment
		(start 36.795964 -274.685252)
		(end 35.411664 -274.685252)
		(width 0.4572)
		(layer "F.Cu")
		(net "GND")
	)
	(segment
		(start 342.245442 -392.004296)
		(end 342.545416 -392.30427)
		(width 0.254)
		(layer "F.Cu")
		(net "GND")
	)
	(segment
		(start 213.369398 -19.870674)
		(end 213.722458 -19.517614)
		(width 0.3556)
		(layer "F.Cu")
		(net "GND")
	)
	(segment
		(start 59.378596 -386.449062)
		(end 58.870596 -386.6388)
		(width 0.254)
		(layer "F.Cu")
		(net "GND")
	)
	(segment
		(start 12.827 -79.0194)
		(end 12.00404 -79.0194)
		(width 0.4064)
		(layer "F.Cu")
		(net "GND")
	)
	(segment
		(start 115.067842 -249.610372)
		(end 115.534694 -249.344434)
		(width 0.350012)
		(layer "F.Cu")
		(net "GND")
	)
	(segment
		(start 382.748028 -230.169974)
		(end 383.21488 -229.904036)
		(width 0.350012)
		(layer "F.Cu")
		(net "GND")
	)
	(segment
		(start 40.23995 -315.485272)
		(end 41.62425 -315.485272)
		(width 0.4572)
		(layer "F.Cu")
		(net "GND")
	)
	(segment
		(start 105.19791 -239.080294)
		(end 104.731058 -238.814356)
		(width 0.350012)
		(layer "F.Cu")
		(net "GND")
	)
	(segment
		(start 109.13999 -23.134828)
		(end 109.13999 -22.518878)
		(width 0.381)
		(layer "F.Cu")
		(net "GND")
	)
	(segment
		(start 25.152096 -231.335326)
		(end 26.536396 -231.335326)
		(width 0.4572)
		(layer "F.Cu")
		(net "GND")
	)
	(segment
		(start 336.687922 -251.23013)
		(end 336.22107 -250.964192)
		(width 0.350012)
		(layer "F.Cu")
		(net "GND")
	)
	(segment
		(start 376.916442 -400.212814)
		(end 376.916442 -399.76171)
		(width 0.254)
		(layer "F.Cu")
		(net "GND")
	)
	(segment
		(start 439.100214 -284.034992)
		(end 437.715914 -284.034992)
		(width 0.4572)
		(layer "F.Cu")
		(net "GND")
	)
	(segment
		(start 84.19846 -390.160002)
		(end 84.71916 -390.160002)
		(width 0.254)
		(layer "F.Cu")
		(net "GND")
	)
	(segment
		(start 325.70801 -266.530074)
		(end 325.052944 -266.530074)
		(width 0.350012)
		(layer "F.Cu")
		(net "GND")
	)
	(segment
		(start 379.457966 -235.840016)
		(end 379.924818 -235.574078)
		(width 0.350012)
		(layer "F.Cu")
		(net "GND")
	)
	(segment
		(start 206.248 -295.9354)
		(end 204.8637 -295.9354)
		(width 0.4572)
		(layer "F.Cu")
		(net "GND")
	)
	(segment
		(start 327.117964 -262.480044)
		(end 326.651112 -262.745982)
		(width 0.350012)
		(layer "F.Cu")
		(net "GND")
	)
	(segment
		(start 402.048218 -12.37488)
		(end 402.048218 -12.374118)
		(width 0.3556)
		(layer "F.Cu")
		(net "GND")
	)
	(segment
		(start 128.227836 -241.510312)
		(end 128.694688 -241.244374)
		(width 0.350012)
		(layer "F.Cu")
		(net "GND")
	)
	(segment
		(start 80.757776 -229.360476)
		(end 80.291178 -229.094538)
		(width 0.350012)
		(layer "F.Cu")
		(net "GND")
	)
	(segment
		(start 97.97796 -288.400236)
		(end 97.511108 -288.666174)
		(width 0.350012)
		(layer "F.Cu")
		(net "GND")
	)
	(segment
		(start 344.977974 -272.200116)
		(end 344.511122 -272.466054)
		(width 0.350012)
		(layer "F.Cu")
		(net "GND")
	)
	(segment
		(start 132.927852 -241.510312)
		(end 133.394704 -241.244374)
		(width 0.350012)
		(layer "F.Cu")
		(net "GND")
	)
	(segment
		(start 123.01855 -388.328662)
		(end 123.570492 -388.138924)
		(width 0.254)
		(layer "F.Cu")
		(net "GND")
	)
	(segment
		(start 152.884632 -95.612458)
		(end 151.944832 -95.612458)
		(width 0.3556)
		(layer "F.Cu")
		(net "GND")
	)
	(segment
		(start 163.298378 -390.160002)
		(end 162.618928 -390.160002)
		(width 0.254)
		(layer "F.Cu")
		(net "GND")
	)
	(segment
		(start 92.33789 -294.880284)
		(end 91.871038 -295.146222)
		(width 0.350012)
		(layer "F.Cu")
		(net "GND")
	)
	(segment
		(start 136.987788 -266.530328)
		(end 137.45464 -266.796266)
		(width 0.350012)
		(layer "F.Cu")
		(net "GND")
	)
	(segment
		(start 394.84554 -7.215886)
		(end 394.84681 -7.217156)
		(width 0.3556)
		(layer "F.Cu")
		(net "GND")
	)
	(segment
		(start 378.517912 -222.880174)
		(end 378.984764 -222.614236)
		(width 0.350012)
		(layer "F.Cu")
		(net "GND")
	)
	(segment
		(start 331.81798 -291.640006)
		(end 331.351128 -291.905944)
		(width 0.350012)
		(layer "F.Cu")
		(net "GND")
	)
	(segment
		(start 146.38782 -263.290304)
		(end 147.042886 -263.290304)
		(width 0.350012)
		(layer "F.Cu")
		(net "GND")
	)
	(segment
		(start 13.085826 -391.222484)
		(end 13.629132 -390.679178)
		(width 0.2286)
		(layer "F.Cu")
		(net "GND")
	)
	(segment
		(start 117.717824 -285.160466)
		(end 118.184676 -285.426404)
		(width 0.350012)
		(layer "F.Cu")
		(net "GND")
	)
	(segment
		(start 326.81799 -243.940076)
		(end 326.351138 -243.674138)
		(width 0.350012)
		(layer "F.Cu")
		(net "GND")
	)
	(segment
		(start 416.289998 -392.999722)
		(end 415.698178 -392.999722)
		(width 0.254)
		(layer "F.Cu")
		(net "GND")
	)
	(segment
		(start 98.344228 -391.830814)
		(end 98.344228 -391.37971)
		(width 0.254)
		(layer "F.Cu")
		(net "GND")
	)
	(segment
		(start 102.235 -180.118766)
		(end 102.155498 -180.31079)
		(width 0.2286)
		(layer "F.Cu")
		(net "GND")
	)
	(segment
		(start 358.307894 -238.270034)
		(end 357.841042 -238.004096)
		(width 0.350012)
		(layer "F.Cu")
		(net "GND")
	)
	(segment
		(start 303.754028 -13.41501)
		(end 303.754028 -14.46149)
		(width 0.3556)
		(layer "F.Cu")
		(net "GND")
	)
	(segment
		(start 144.677892 -248.800366)
		(end 145.144744 -248.534428)
		(width 0.350012)
		(layer "F.Cu")
		(net "GND")
	)
	(segment
		(start 358.778048 -229.360222)
		(end 358.311196 -229.094284)
		(width 0.350012)
		(layer "F.Cu")
		(net "GND")
	)
	(segment
		(start 96.790256 -384.617722)
		(end 96.198436 -384.617722)
		(width 0.254)
		(layer "F.Cu")
		(net "GND")
	)
	(segment
		(start 325.70801 -274.630134)
		(end 325.052944 -274.630134)
		(width 0.350012)
		(layer "F.Cu")
		(net "GND")
	)
	(segment
		(start 345.918028 -281.920188)
		(end 345.451176 -282.186126)
		(width 0.350012)
		(layer "F.Cu")
		(net "GND")
	)
	(segment
		(start 42.057066 -11.26998)
		(end 42.057066 -10.16635)
		(width 0.3556)
		(layer "F.Cu")
		(net "GND")
	)
	(segment
		(start 164.427916 -210.085432)
		(end 165.812216 -210.085432)
		(width 0.4572)
		(layer "F.Cu")
		(net "GND")
	)
	(segment
		(start 81.798414 -390.160002)
		(end 82.319114 -390.160002)
		(width 0.254)
		(layer "F.Cu")
		(net "GND")
	)
	(segment
		(start 81.058004 -264.10031)
		(end 80.591152 -264.366248)
		(width 0.350012)
		(layer "F.Cu")
		(net "GND")
	)
	(segment
		(start 374.28805 -244.750082)
		(end 374.754902 -244.484144)
		(width 0.350012)
		(layer "F.Cu")
		(net "GND")
	)
	(segment
		(start 129.938018 -277.060406)
		(end 130.40487 -277.326344)
		(width 0.350012)
		(layer "F.Cu")
		(net "GND")
	)
	(segment
		(start 376.467878 -274.630134)
		(end 376.93473 -274.896072)
		(width 0.350012)
		(layer "F.Cu")
		(net "GND")
	)
	(segment
		(start 265.54811 -219.435172)
		(end 266.93241 -219.435172)
		(width 0.4572)
		(layer "F.Cu")
		(net "GND")
	)
	(segment
		(start 325.70801 -269.770098)
		(end 325.052944 -269.770098)
		(width 0.350012)
		(layer "F.Cu")
		(net "GND")
	)
	(segment
		(start 381.362458 -392.999722)
		(end 380.770638 -392.999722)
		(width 0.254)
		(layer "F.Cu")
		(net "GND")
	)
	(segment
		(start 349.67799 -293.260018)
		(end 349.211138 -293.525956)
		(width 0.350012)
		(layer "F.Cu")
		(net "GND")
	)
	(segment
		(start 159.698182 -386.6388)
		(end 159.006286 -386.449062)
		(width 0.254)
		(layer "F.Cu")
		(net "GND")
	)
	(segment
		(start 355.957886 -239.08004)
		(end 355.491034 -238.814102)
		(width 0.350012)
		(layer "F.Cu")
		(net "GND")
	)
	(segment
		(start 97.507806 -287.590484)
		(end 97.040954 -287.856422)
		(width 0.350012)
		(layer "F.Cu")
		(net "GND")
	)
	(segment
		(start 403.34565 -391.784586)
		(end 403.34565 -392.004296)
		(width 0.254)
		(layer "F.Cu")
		(net "GND")
	)
	(segment
		(start 146.792442 -385.87553)
		(end 146.636994 -386.030978)
		(width 0.254)
		(layer "F.Cu")
		(net "GND")
	)
	(segment
		(start 17.608042 -219.435426)
		(end 18.992342 -219.435426)
		(width 0.4572)
		(layer "F.Cu")
		(net "GND")
	)
	(segment
		(start 291.715444 -13.509244)
		(end 290.27882 -13.509244)
		(width 0.3556)
		(layer "F.Cu")
		(net "GND")
	)
	(segment
		(start 412.098236 -396.520924)
		(end 411.546294 -396.710662)
		(width 0.254)
		(layer "F.Cu")
		(net "GND")
	)
	(segment
		(start 126.647956 -289.210242)
		(end 127.114808 -289.47618)
		(width 0.350012)
		(layer "F.Cu")
		(net "GND")
	)
	(segment
		(start 312.11774 -399.663158)
		(end 312.417714 -399.143474)
		(width 0.254)
		(layer "F.Cu")
		(net "GND")
	)
	(segment
		(start 341.687912 -266.530074)
		(end 341.22106 -266.796012)
		(width 0.350012)
		(layer "F.Cu")
		(net "GND")
	)
	(segment
		(start 330.408026 -264.910062)
		(end 329.941174 -265.176)
		(width 0.350012)
		(layer "F.Cu")
		(net "GND")
	)
	(segment
		(start 353.398074 -395.0208)
		(end 352.706178 -394.831062)
		(width 0.254)
		(layer "F.Cu")
		(net "GND")
	)
	(segment
		(start 98.918014 -267.340334)
		(end 98.451162 -267.606272)
		(width 0.350012)
		(layer "F.Cu")
		(net "GND")
	)
	(segment
		(start 366.128046 -277.870158)
		(end 366.594898 -278.136096)
		(width 0.350012)
		(layer "F.Cu")
		(net "GND")
	)
	(segment
		(start 391.50798 -281.110182)
		(end 391.974832 -281.37612)
		(width 0.350012)
		(layer "F.Cu")
		(net "GND")
	)
	(segment
		(start 102.378002 -234.220258)
		(end 101.91115 -233.95432)
		(width 0.350012)
		(layer "F.Cu")
		(net "GND")
	)
	(segment
		(start 123.827794 -285.970472)
		(end 124.294646 -286.23641)
		(width 0.350012)
		(layer "F.Cu")
		(net "GND")
	)
	(segment
		(start 387.448044 -247.990106)
		(end 387.914896 -247.724168)
		(width 0.350012)
		(layer "F.Cu")
		(net "GND")
	)
	(segment
		(start 79.647796 -295.69029)
		(end 79.180944 -295.956228)
		(width 0.350012)
		(layer "F.Cu")
		(net "GND")
	)
	(segment
		(start 272.593562 -348.54134)
		(end 273.02206 -348.54134)
		(width 0.2286)
		(layer "F.Cu")
		(net "GND")
	)
	(segment
		(start 288.180018 -221.985078)
		(end 289.564318 -221.985078)
		(width 0.4572)
		(layer "F.Cu")
		(net "GND")
	)
	(segment
		(start 441.344558 -29.584142)
		(end 441.353194 -29.575506)
		(width 0.254)
		(layer "F.Cu")
		(net "GND")
	)
	(segment
		(start 346.19819 -396.520924)
		(end 346.84589 -396.710662)
		(width 0.254)
		(layer "F.Cu")
		(net "GND")
	)
	(segment
		(start 61.918596 -388.328662)
		(end 62.470538 -388.138924)
		(width 0.254)
		(layer "F.Cu")
		(net "GND")
	)
	(segment
		(start 124.516388 -391.830814)
		(end 124.516388 -391.37971)
		(width 0.254)
		(layer "F.Cu")
		(net "GND")
	)
	(segment
		(start 124.767848 -263.290304)
		(end 125.2347 -263.556242)
		(width 0.350012)
		(layer "F.Cu")
		(net "GND")
	)
	(segment
		(start 393.045696 -7.215124)
		(end 393.045696 -7.215886)
		(width 0.3556)
		(layer "F.Cu")
		(net "GND")
	)
	(segment
		(start 360.957876 -285.160212)
		(end 361.424728 -285.42615)
		(width 0.350012)
		(layer "F.Cu")
		(net "GND")
	)
	(segment
		(start 141.687804 -292.450266)
		(end 142.154656 -292.716204)
		(width 0.350012)
		(layer "F.Cu")
		(net "GND")
	)
	(segment
		(start 336.687922 -236.650022)
		(end 336.22107 -236.384084)
		(width 0.350012)
		(layer "F.Cu")
		(net "GND")
	)
	(segment
		(start 103.013764 -36.6522)
		(end 102.397814 -36.6522)
		(width 0.381)
		(layer "F.Cu")
		(net "GND")
	)
	(segment
		(start 371.938042 -242.320064)
		(end 372.404894 -242.054126)
		(width 0.350012)
		(layer "F.Cu")
		(net "GND")
	)
	(segment
		(start 51.670712 -386.6388)
		(end 50.978562 -386.449062)
		(width 0.254)
		(layer "F.Cu")
		(net "GND")
	)
	(segment
		(start 77.767942 -269.770352)
		(end 77.112876 -269.770352)
		(width 0.350012)
		(layer "F.Cu")
		(net "GND")
	)
	(segment
		(start 138.397996 -288.400236)
		(end 138.864848 -288.666174)
		(width 0.350012)
		(layer "F.Cu")
		(net "GND")
	)
	(segment
		(start 85.457792 -234.220258)
		(end 84.99094 -233.95432)
		(width 0.350012)
		(layer "F.Cu")
		(net "GND")
	)
	(segment
		(start 128.52781 -276.2504)
		(end 128.994662 -276.516338)
		(width 0.350012)
		(layer "F.Cu")
		(net "GND")
	)
	(segment
		(start 367.538 -288.399982)
		(end 368.004852 -288.66592)
		(width 0.350012)
		(layer "F.Cu")
		(net "GND")
	)
	(segment
		(start 363.778038 -283.5402)
		(end 364.24489 -283.806138)
		(width 0.350012)
		(layer "F.Cu")
		(net "GND")
	)
	(segment
		(start 372.238016 -283.5402)
		(end 372.704868 -283.806138)
		(width 0.350012)
		(layer "F.Cu")
		(net "GND")
	)
	(segment
		(start 351.589848 -392.999722)
		(end 350.998028 -392.999722)
		(width 0.254)
		(layer "F.Cu")
		(net "GND")
	)
	(segment
		(start 331.518006 -239.08004)
		(end 331.051154 -238.814102)
		(width 0.350012)
		(layer "F.Cu")
		(net "GND")
	)
	(segment
		(start 394.327888 -285.970218)
		(end 394.982954 -285.970218)
		(width 0.350012)
		(layer "F.Cu")
		(net "GND")
	)
	(segment
		(start 354.842318 -393.213082)
		(end 354.842318 -393.59332)
		(width 0.254)
		(layer "F.Cu")
		(net "GND")
	)
	(segment
		(start 102.378002 -253.660402)
		(end 101.91115 -253.394464)
		(width 0.350012)
		(layer "F.Cu")
		(net "GND")
	)
	(segment
		(start 330.108052 -246.370094)
		(end 329.6412 -246.104156)
		(width 0.350012)
		(layer "F.Cu")
		(net "GND")
	)
	(segment
		(start 161.082736 -105.776014)
		(end 161.3408 -105.51795)
		(width 0.381)
		(layer "F.Cu")
		(net "GND")
	)
	(segment
		(start 384.927856 -281.110182)
		(end 385.394708 -281.37612)
		(width 0.350012)
		(layer "F.Cu")
		(net "GND")
	)
	(segment
		(start 403.846792 -9.423654)
		(end 403.848062 -9.424924)
		(width 0.3556)
		(layer "F.Cu")
		(net "GND")
	)
	(segment
		(start 143.171672 -388.297674)
		(end 143.81861 -388.297674)
		(width 0.254)
		(layer "F.Cu")
		(net "GND")
	)
	(segment
		(start 106.074718 -20.084542)
		(end 106.168698 -19.990562)
		(width 0.381)
		(layer "F.Cu")
		(net "GND")
	)
	(segment
		(start 65.530222 -32.373824)
		(end 65.530222 -31.304484)
		(width 0.254)
		(layer "F.Cu")
		(net "GND")
	)
	(segment
		(start 327.881742 -395.4399)
		(end 328.694542 -395.4399)
		(width 0.254)
		(layer "F.Cu")
		(net "GND")
	)
	(segment
		(start 340.277958 -290.019994)
		(end 339.811106 -290.285932)
		(width 0.350012)
		(layer "F.Cu")
		(net "GND")
	)
	(segment
		(start 37.319712 -428.012098)
		(end 37.319712 -427.377098)
		(width 0.3556)
		(layer "F.Cu")
		(net "GND")
	)
	(segment
		(start 95.84563 -383.622042)
		(end 95.84563 -383.402586)
		(width 0.254)
		(layer "F.Cu")
		(net "GND")
	)
	(segment
		(start 320.870326 -398.542002)
		(end 320.19113 -398.542002)
		(width 0.254)
		(layer "F.Cu")
		(net "GND")
	)
	(segment
		(start 154.545792 -383.622296)
		(end 154.845766 -383.92227)
		(width 0.254)
		(layer "F.Cu")
		(net "GND")
	)
	(segment
		(start 328.998072 -288.399982)
		(end 328.53122 -288.66592)
		(width 0.350012)
		(layer "F.Cu")
		(net "GND")
	)
	(segment
		(start 115.367816 -289.210242)
		(end 115.834668 -289.47618)
		(width 0.350012)
		(layer "F.Cu")
		(net "GND")
	)
	(segment
		(start 78.877922 -227.740464)
		(end 78.41107 -227.474526)
		(width 0.350012)
		(layer "F.Cu")
		(net "GND")
	)
	(segment
		(start 112.717834 -239.080294)
		(end 113.184686 -238.814356)
		(width 0.350012)
		(layer "F.Cu")
		(net "GND")
	)
	(segment
		(start 348.737936 -267.34008)
		(end 348.271084 -267.606018)
		(width 0.350012)
		(layer "F.Cu")
		(net "GND")
	)
	(segment
		(start 138.397996 -283.540454)
		(end 138.864848 -283.806392)
		(width 0.350012)
		(layer "F.Cu")
		(net "GND")
	)
	(segment
		(start 381.338074 -255.28016)
		(end 381.804926 -255.014222)
		(width 0.350012)
		(layer "F.Cu")
		(net "GND")
	)
	(segment
		(start 303.816258 -399.76171)
		(end 303.816258 -400.212814)
		(width 0.254)
		(layer "F.Cu")
		(net "GND")
	)
	(segment
		(start 384.627882 -246.370094)
		(end 385.094734 -246.104156)
		(width 0.350012)
		(layer "F.Cu")
		(net "GND")
	)
	(segment
		(start 110.83798 -242.320318)
		(end 110.371128 -242.05438)
		(width 0.350012)
		(layer "F.Cu")
		(net "GND")
	)
	(segment
		(start 439.100214 -227.935028)
		(end 437.715914 -227.935028)
		(width 0.4572)
		(layer "F.Cu")
		(net "GND")
	)
	(segment
		(start 154.218894 -390.160002)
		(end 153.698194 -390.160002)
		(width 0.254)
		(layer "F.Cu")
		(net "GND")
	)
	(segment
		(start 427.456092 -238.13516)
		(end 428.840392 -238.13516)
		(width 0.4572)
		(layer "F.Cu")
		(net "GND")
	)
	(segment
		(start 372.370604 -398.542002)
		(end 372.318026 -399.143474)
		(width 0.254)
		(layer "F.Cu")
		(net "GND")
	)
	(segment
		(start 389.414766 -395.613128)
		(end 389.170672 -395.369034)
		(width 0.254)
		(layer "F.Cu")
		(net "GND")
	)
	(segment
		(start 72.6948 -387.0579)
		(end 72.6948 -387.4389)
		(width 0.254)
		(layer "F.Cu")
		(net "GND")
	)
	(segment
		(start 123.827794 -289.210242)
		(end 124.294646 -289.47618)
		(width 0.350012)
		(layer "F.Cu")
		(net "GND")
	)
	(segment
		(start 123.52782 -236.650276)
		(end 123.994672 -236.384338)
		(width 0.350012)
		(layer "F.Cu")
		(net "GND")
	)
	(segment
		(start 356.25786 -270.580104)
		(end 355.791008 -270.846042)
		(width 0.350012)
		(layer "F.Cu")
		(net "GND")
	)
	(segment
		(start 337.445604 -392.004296)
		(end 337.745578 -392.30427)
		(width 0.254)
		(layer "F.Cu")
		(net "GND")
	)
	(segment
		(start 123.52782 -231.79024)
		(end 123.994672 -231.524302)
		(width 0.350012)
		(layer "F.Cu")
		(net "GND")
	)
	(segment
		(start 103.617776 -273.820382)
		(end 103.151178 -274.08632)
		(width 0.350012)
		(layer "F.Cu")
		(net "GND")
	)
	(segment
		(start 92.59824 -384.617722)
		(end 92.545662 -383.92227)
		(width 0.254)
		(layer "F.Cu")
		(net "GND")
	)
	(segment
		(start 108.787946 -277.870412)
		(end 108.321094 -278.13635)
		(width 0.350012)
		(layer "F.Cu")
		(net "GND")
	)
	(segment
		(start 176.072038 -218.585288)
		(end 174.687738 -218.585288)
		(width 0.4572)
		(layer "F.Cu")
		(net "GND")
	)
	(segment
		(start 298.451016 -22.747224)
		(end 299.066966 -22.747224)
		(width 0.4064)
		(layer "F.Cu")
		(net "GND")
	)
	(segment
		(start 133.398006 -242.320318)
		(end 133.864858 -242.05438)
		(width 0.350012)
		(layer "F.Cu")
		(net "GND")
	)
	(segment
		(start 421.444166 -399.76171)
		(end 421.345614 -399.663158)
		(width 0.254)
		(layer "F.Cu")
		(net "GND")
	)
	(segment
		(start 128.52781 -268.15034)
		(end 128.994662 -268.416278)
		(width 0.350012)
		(layer "F.Cu")
		(net "GND")
	)
	(segment
		(start 120.817894 -383.622296)
		(end 121.117868 -383.92227)
		(width 0.254)
		(layer "F.Cu")
		(net "GND")
	)
	(segment
		(start 319.317624 -391.784586)
		(end 319.317624 -391.333482)
		(width 0.254)
		(layer "F.Cu")
		(net "GND")
	)
	(segment
		(start 117.888004 -244.750336)
		(end 118.354856 -244.484398)
		(width 0.350012)
		(layer "F.Cu")
		(net "GND")
	)
	(segment
		(start 329.637898 -222.880174)
		(end 329.171046 -222.614236)
		(width 0.350012)
		(layer "F.Cu")
		(net "GND")
	)
	(segment
		(start 374.28805 -228.550216)
		(end 374.754902 -228.284278)
		(width 0.350012)
		(layer "F.Cu")
		(net "GND")
	)
	(segment
		(start 97.207832 -247.99036)
		(end 96.74098 -247.724422)
		(width 0.350012)
		(layer "F.Cu")
		(net "GND")
	)
	(segment
		(start 147.00631 -386.449062)
		(end 146.248882 -386.630926)
		(width 0.254)
		(layer "F.Cu")
		(net "GND")
	)
	(segment
		(start 374.218454 -396.710662)
		(end 373.5705 -396.520924)
		(width 0.254)
		(layer "F.Cu")
		(net "GND")
	)
	(segment
		(start 47.717964 -383.622296)
		(end 48.017938 -383.92227)
		(width 0.254)
		(layer "F.Cu")
		(net "GND")
	)
	(segment
		(start 416.468052 -211.784946)
		(end 415.083752 -211.784946)
		(width 0.4572)
		(layer "F.Cu")
		(net "GND")
	)
	(segment
		(start 140.27785 -272.20037)
		(end 140.744702 -272.466308)
		(width 0.350012)
		(layer "F.Cu")
		(net "GND")
	)
	(segment
		(start 360.957876 -270.580104)
		(end 361.424728 -270.846042)
		(width 0.350012)
		(layer "F.Cu")
		(net "GND")
	)
	(segment
		(start 308.87035 -395.0208)
		(end 308.1782 -394.831062)
		(width 0.254)
		(layer "F.Cu")
		(net "GND")
	)
	(segment
		(start 387.61797 -392.004296)
		(end 387.917944 -392.30427)
		(width 0.254)
		(layer "F.Cu")
		(net "GND")
	)
	(segment
		(start 269.648178 -295.935146)
		(end 268.263878 -295.935146)
		(width 0.4572)
		(layer "F.Cu")
		(net "GND")
	)
	(segment
		(start 62.41796 -390.761474)
		(end 62.470538 -390.160002)
		(width 0.254)
		(layer "F.Cu")
		(net "GND")
	)
	(segment
		(start 56.868314 -12.374118)
		(end 56.867044 -12.372848)
		(width 0.3556)
		(layer "F.Cu")
		(net "GND")
	)
	(segment
		(start 169.38879 -103.71582)
		(end 169.38879 -104.340152)
		(width 0.4572)
		(layer "F.Cu")
		(net "GND")
	)
	(segment
		(start 141.38783 -231.79024)
		(end 141.854682 -231.524302)
		(width 0.350012)
		(layer "F.Cu")
		(net "GND")
	)
	(segment
		(start 426.54855 -423.221912)
		(end 425.950634 -423.819828)
		(width 0.381)
		(layer "F.Cu")
		(net "GND")
	)
	(segment
		(start 330.623164 -141.074902)
		(end 330.623418 -141.074902)
		(width 0.254)
		(layer "F.Cu")
		(net "GND")
	)
	(segment
		(start 329.241912 -103.66375)
		(end 328.492358 -103.66375)
		(width 0.4572)
		(layer "F.Cu")
		(net "GND")
	)
	(segment
		(start 282.941522 -115.20297)
		(end 283.370528 -115.631976)
		(width 0.3556)
		(layer "F.Cu")
		(net "GND")
	)
	(segment
		(start 400.24558 -7.215124)
		(end 400.24558 -7.215886)
		(width 0.3556)
		(layer "F.Cu")
		(net "GND")
	)
	(segment
		(start 101.737922 -262.480298)
		(end 101.27107 -262.746236)
		(width 0.350012)
		(layer "F.Cu")
		(net "GND")
	)
	(segment
		(start 178.289458 -49.800002)
		(end 177.108358 -49.800002)
		(width 0.254)
		(layer "F.Cu")
		(net "GND")
	)
	(segment
		(start 328.227944 -228.550216)
		(end 327.761092 -228.284278)
		(width 0.350012)
		(layer "F.Cu")
		(net "GND")
	)
	(segment
		(start 105.19791 -243.94033)
		(end 104.731058 -243.674392)
		(width 0.350012)
		(layer "F.Cu")
		(net "GND")
	)
	(segment
		(start 416.545776 -392.004296)
		(end 416.84575 -392.30427)
		(width 0.254)
		(layer "F.Cu")
		(net "GND")
	)
	(segment
		(start 123.827794 -271.390364)
		(end 124.294646 -271.656302)
		(width 0.350012)
		(layer "F.Cu")
		(net "GND")
	)
	(segment
		(start 93.44787 -243.130324)
		(end 92.981018 -242.864386)
		(width 0.350012)
		(layer "F.Cu")
		(net "GND")
	)
	(segment
		(start 117.217952 -383.402586)
		(end 117.217952 -382.951482)
		(width 0.254)
		(layer "F.Cu")
		(net "GND")
	)
	(segment
		(start 45.959014 -433.657502)
		(end 45.578776 -434.03774)
		(width 0.381)
		(layer "F.Cu")
		(net "GND")
	)
	(segment
		(start 130.407918 -276.2504)
		(end 130.87477 -276.516338)
		(width 0.350012)
		(layer "F.Cu")
		(net "GND")
	)
	(segment
		(start 96.145858 -383.92227)
		(end 95.84563 -383.622042)
		(width 0.254)
		(layer "F.Cu")
		(net "GND")
	)
	(segment
		(start 54.918102 -391.281158)
		(end 55.218076 -390.761474)
		(width 0.254)
		(layer "F.Cu")
		(net "GND")
	)
	(segment
		(start 323.639688 -340.2457)
		(end 323.38645 -340.498938)
		(width 0.381)
		(layer "F.Cu")
		(net "GND")
	)
	(segment
		(start 111.137954 -273.820382)
		(end 110.671102 -274.08632)
		(width 0.350012)
		(layer "F.Cu")
		(net "GND")
	)
	(segment
		(start 118.357904 -248.800366)
		(end 118.824756 -248.534428)
		(width 0.350012)
		(layer "F.Cu")
		(net "GND")
	)
	(segment
		(start 185.922158 -109.052868)
		(end 186.312048 -108.662978)
		(width 0.254)
		(layer "F.Cu")
		(net "GND")
	)
	(segment
		(start 201.123042 -387.960616)
		(end 200.476358 -387.960616)
		(width 0.4572)
		(layer "F.Cu")
		(net "GND")
	)
	(segment
		(start 369.11788 -230.97998)
		(end 369.584732 -230.714296)
		(width 0.350012)
		(layer "F.Cu")
		(net "GND")
	)
	(segment
		(start 208.929986 -134.17296)
		(end 208.929986 -134.842504)
		(width 0.381)
		(layer "F.Cu")
		(net "GND")
	)
	(segment
		(start 424.166792 -7.217156)
		(end 424.166792 -8.320024)
		(width 0.3556)
		(layer "F.Cu")
		(net "GND")
	)
	(segment
		(start 58.818018 -390.761474)
		(end 58.518044 -391.281158)
		(width 0.254)
		(layer "F.Cu")
		(net "GND")
	)
	(segment
		(start 147.345654 -382.951482)
		(end 147.444206 -382.85293)
		(width 0.254)
		(layer "F.Cu")
		(net "GND")
	)
	(segment
		(start 116.331238 -41.5798)
		(end 116.331238 -42.2656)
		(width 0.4572)
		(layer "F.Cu")
		(net "GND")
	)
	(segment
		(start 303.754028 -14.46149)
		(end 303.774348 -14.48181)
		(width 0.3556)
		(layer "F.Cu")
		(net "GND")
	)
	(segment
		(start 76.105512 -39.675562)
		(end 76.105512 -40.310308)
		(width 0.4572)
		(layer "F.Cu")
		(net "GND")
	)
	(segment
		(start 129.938018 -264.10031)
		(end 130.40487 -264.366248)
		(width 0.350012)
		(layer "F.Cu")
		(net "GND")
	)
	(segment
		(start 97.677986 -243.94033)
		(end 97.211134 -243.674392)
		(width 0.350012)
		(layer "F.Cu")
		(net "GND")
	)
	(segment
		(start 327.117964 -283.5402)
		(end 326.651112 -283.806138)
		(width 0.350012)
		(layer "F.Cu")
		(net "GND")
	)
	(segment
		(start 383.048002 -273.010122)
		(end 383.514854 -273.27606)
		(width 0.350012)
		(layer "F.Cu")
		(net "GND")
	)
	(segment
		(start 418.945568 -391.333482)
		(end 419.04412 -391.23493)
		(width 0.254)
		(layer "F.Cu")
		(net "GND")
	)
	(segment
		(start 150.690072 -384.617722)
		(end 151.298402 -384.617722)
		(width 0.254)
		(layer "F.Cu")
		(net "GND")
	)
	(segment
		(start 343.445592 -399.663158)
		(end 343.745566 -399.143474)
		(width 0.254)
		(layer "F.Cu")
		(net "GND")
	)
	(segment
		(start 94.217998 -278.680418)
		(end 93.751146 -278.946356)
		(width 0.350012)
		(layer "F.Cu")
		(net "GND")
	)
	(segment
		(start 122.887994 -292.450266)
		(end 123.354846 -292.716204)
		(width 0.350012)
		(layer "F.Cu")
		(net "GND")
	)
	(segment
		(start 49.813972 -402.87194)
		(end 48.855376 -403.830536)
		(width 0.381)
		(layer "F.Cu")
		(net "GND")
	)
	(segment
		(start 318.117728 -391.784586)
		(end 318.117728 -391.333482)
		(width 0.254)
		(layer "F.Cu")
		(net "GND")
	)
	(segment
		(start 154.545792 -382.951482)
		(end 154.644344 -382.85293)
		(width 0.254)
		(layer "F.Cu")
		(net "GND")
	)
	(segment
		(start 335.39811 -392.999722)
		(end 335.98993 -392.999722)
		(width 0.254)
		(layer "F.Cu")
		(net "GND")
	)
	(segment
		(start 446.522602 -417.46551)
		(end 446.471802 -417.41471)
		(width 0.4572)
		(layer "F.Cu")
		(net "GND")
	)
	(segment
		(start 132.44068 -27.52598)
		(end 132.44068 -27.896566)
		(width 0.254)
		(layer "F.Cu")
		(net "GND")
	)
	(segment
		(start 146.145758 -382.958086)
		(end 146.096228 -382.908556)
		(width 0.254)
		(layer "F.Cu")
		(net "GND")
	)
	(segment
		(start 303.774348 -14.48181)
		(end 304.468276 -14.48181)
		(width 0.3556)
		(layer "F.Cu")
		(net "GND")
	)
	(segment
		(start 419.912038 -203.28509)
		(end 421.296338 -203.28509)
		(width 0.4572)
		(layer "F.Cu")
		(net "GND")
	)
	(segment
		(start 160.218882 -390.160002)
		(end 159.698182 -390.160002)
		(width 0.254)
		(layer "F.Cu")
		(net "GND")
	)
	(segment
		(start 326.81799 -242.320064)
		(end 326.351138 -242.054126)
		(width 0.350012)
		(layer "F.Cu")
		(net "GND")
	)
	(segment
		(start 79.177896 -280.30043)
		(end 78.711044 -280.566368)
		(width 0.350012)
		(layer "F.Cu")
		(net "GND")
	)
	(segment
		(start 151.19604 -40.803576)
		(end 151.19604 -41.44137)
		(width 0.381)
		(layer "F.Cu")
		(net "GND")
	)
	(segment
		(start 92.33789 -273.820382)
		(end 91.871038 -274.08632)
		(width 0.350012)
		(layer "F.Cu")
		(net "GND")
	)
	(segment
		(start 165.60165 -440.182)
		(end 166.880286 -440.182)
		(width 0.381)
		(layer "F.Cu")
		(net "GND")
	)
	(segment
		(start 403.845522 -7.215886)
		(end 403.846792 -7.217156)
		(width 0.3556)
		(layer "F.Cu")
		(net "GND")
	)
	(segment
		(start 116.31803 -390.761474)
		(end 116.018056 -391.281158)
		(width 0.254)
		(layer "F.Cu")
		(net "GND")
	)
	(segment
		(start 209.292444 -107.467146)
		(end 209.890106 -107.467146)
		(width 0.381)
		(layer "F.Cu")
		(net "GND")
	)
	(segment
		(start 75.715114 -17.096486)
		(end 75.253088 -17.558512)
		(width 0.4572)
		(layer "F.Cu")
		(net "GND")
	)
	(segment
		(start 364.717838 -273.820128)
		(end 365.18469 -274.086066)
		(width 0.350012)
		(layer "F.Cu")
		(net "GND")
	)
	(segment
		(start 32.695896 -240.68532)
		(end 34.080196 -240.68532)
		(width 0.4572)
		(layer "F.Cu")
		(net "GND")
	)
	(segment
		(start 433.165504 -7.215886)
		(end 433.166774 -7.217156)
		(width 0.3556)
		(layer "F.Cu")
		(net "GND")
	)
	(segment
		(start 402.792438 -394.25753)
		(end 402.63699 -394.412978)
		(width 0.254)
		(layer "F.Cu")
		(net "GND")
	)
	(segment
		(start 379.75794 -270.580104)
		(end 380.224792 -270.846042)
		(width 0.350012)
		(layer "F.Cu")
		(net "GND")
	)
	(segment
		(start 120.79605 -420.497)
		(end 121.539 -420.497)
		(width 0.381)
		(layer "F.Cu")
		(net "GND")
	)
	(segment
		(start 83.622134 -45.997622)
		(end 83.174586 -46.44517)
		(width 0.3556)
		(layer "F.Cu")
		(net "GND")
	)
	(segment
		(start 137.849356 -387.084062)
		(end 137.36574 -387.084062)
		(width 0.381)
		(layer "F.Cu")
		(net "GND")
	)
	(segment
		(start 107.377992 -277.060406)
		(end 106.91114 -277.326344)
		(width 0.350012)
		(layer "F.Cu")
		(net "GND")
	)
	(segment
		(start 102.207822 -294.070278)
		(end 101.74097 -294.336216)
		(width 0.350012)
		(layer "F.Cu")
		(net "GND")
	)
	(segment
		(start 414.14573 -392.004296)
		(end 414.445704 -392.30427)
		(width 0.254)
		(layer "F.Cu")
		(net "GND")
	)
	(segment
		(start 79.398368 -383.974848)
		(end 79.398368 -384.617722)
		(width 0.254)
		(layer "F.Cu")
		(net "GND")
	)
	(segment
		(start 422.104566 -395.451076)
		(end 421.942514 -395.613128)
		(width 0.254)
		(layer "F.Cu")
		(net "GND")
	)
	(segment
		(start 90.457782 -294.880284)
		(end 89.99093 -295.146222)
		(width 0.350012)
		(layer "F.Cu")
		(net "GND")
	)
	(segment
		(start 113.017808 -268.960346)
		(end 113.48466 -269.226284)
		(width 0.350012)
		(layer "F.Cu")
		(net "GND")
	)
	(segment
		(start 369.72113 -394.412978)
		(end 369.72113 -393.81303)
		(width 0.254)
		(layer "F.Cu")
		(net "GND")
	)
	(segment
		(start 360.40949 -395.4399)
		(end 361.22229 -395.4399)
		(width 0.254)
		(layer "F.Cu")
		(net "GND")
	)
	(segment
		(start 29.252164 -221.135194)
		(end 27.867864 -221.135194)
		(width 0.4572)
		(layer "F.Cu")
		(net "GND")
	)
	(segment
		(start 146.087846 -231.79024)
		(end 146.742912 -231.79024)
		(width 0.350012)
		(layer "F.Cu")
		(net "GND")
	)
	(segment
		(start 388.217918 -270.580104)
		(end 388.68477 -270.846042)
		(width 0.350012)
		(layer "F.Cu")
		(net "GND")
	)
	(segment
		(start 446.644268 -227.935028)
		(end 445.259968 -227.935028)
		(width 0.4572)
		(layer "F.Cu")
		(net "GND")
	)
	(segment
		(start 40.256968 -7.217156)
		(end 40.256968 -8.320024)
		(width 0.3556)
		(layer "F.Cu")
		(net "GND")
	)
	(segment
		(start 338.56803 -222.070168)
		(end 338.101178 -221.80423)
		(width 0.350012)
		(layer "F.Cu")
		(net "GND")
	)
	(segment
		(start 373.3165 -400.212814)
		(end 373.3165 -399.76171)
		(width 0.254)
		(layer "F.Cu")
		(net "GND")
	)
	(segment
		(start 152.145746 -383.622296)
		(end 152.44572 -383.92227)
		(width 0.2032)
		(layer "F.Cu")
		(net "GND")
	)
	(segment
		(start 63.670688 -388.138924)
		(end 64.318642 -388.328662)
		(width 0.254)
		(layer "F.Cu")
		(net "GND")
	)
	(segment
		(start 131.817872 -264.10031)
		(end 132.284724 -264.366248)
		(width 0.350012)
		(layer "F.Cu")
		(net "GND")
	)
	(segment
		(start 381.617982 -391.333482)
		(end 381.716534 -391.23493)
		(width 0.254)
		(layer "F.Cu")
		(net "GND")
	)
	(segment
		(start 129.57048 -384.617722)
		(end 128.962404 -384.617722)
		(width 0.254)
		(layer "F.Cu")
		(net "GND")
	)
	(segment
		(start 369.417854 -262.480044)
		(end 369.884706 -262.745982)
		(width 0.350012)
		(layer "F.Cu")
		(net "GND")
	)
	(segment
		(start 87.637874 -281.920442)
		(end 87.171022 -282.18638)
		(width 0.350012)
		(layer "F.Cu")
		(net "GND")
	)
	(segment
		(start 363.307884 -271.39011)
		(end 363.774736 -271.656048)
		(width 0.350012)
		(layer "F.Cu")
		(net "GND")
	)
	(segment
		(start 70.307454 -146.939762)
		(end 69.894958 -146.939762)
		(width 0.254)
		(layer "F.Cu")
		(net "GND")
	)
	(segment
		(start 86.2457 -383.622296)
		(end 86.545674 -383.92227)
		(width 0.254)
		(layer "F.Cu")
		(net "GND")
	)
	(segment
		(start 187.060078 -278.085296)
		(end 188.444378 -278.085296)
		(width 0.4572)
		(layer "F.Cu")
		(net "GND")
	)
	(segment
		(start 105.400602 -20.758658)
		(end 105.400602 -21.171408)
		(width 0.381)
		(layer "F.Cu")
		(net "GND")
	)
	(segment
		(start 123.357894 -288.400236)
		(end 123.824746 -288.666174)
		(width 0.350012)
		(layer "F.Cu")
		(net "GND")
	)
	(segment
		(start 104.72801 -223.690434)
		(end 104.731058 -224.234502)
		(width 0.350012)
		(layer "F.Cu")
		(net "GND")
	)
	(segment
		(start 356.884732 -417.095178)
		(end 356.884732 -416.460178)
		(width 0.4318)
		(layer "F.Cu")
		(net "GND")
	)
	(segment
		(start 130.407918 -285.970472)
		(end 130.87477 -286.23641)
		(width 0.350012)
		(layer "F.Cu")
		(net "GND")
	)
	(segment
		(start 150.945596 -383.402586)
		(end 150.945596 -383.622042)
		(width 0.2032)
		(layer "F.Cu")
		(net "GND")
	)
	(segment
		(start 113.017808 -278.680418)
		(end 113.48466 -278.946356)
		(width 0.350012)
		(layer "F.Cu")
		(net "GND")
	)
	(segment
		(start 69.299582 -165.86327)
		(end 68.807076 -166.355776)
		(width 0.2286)
		(layer "F.Cu")
		(net "GND")
	)
	(segment
		(start 118.514114 -170.098466)
		(end 118.085616 -170.098466)
		(width 0.2286)
		(layer "F.Cu")
		(net "GND")
	)
	(segment
		(start 126.659894 -159.93491)
		(end 127.190246 -159.93491)
		(width 0.381)
		(layer "F.Cu")
		(net "GND")
	)
	(segment
		(start 125.278388 -386.449062)
		(end 124.770642 -386.6388)
		(width 0.254)
		(layer "F.Cu")
		(net "GND")
	)
	(segment
		(start 379.217936 -392.004296)
		(end 379.51791 -392.30427)
		(width 0.254)
		(layer "F.Cu")
		(net "GND")
	)
	(segment
		(start 153.444194 -391.37971)
		(end 153.345642 -391.281158)
		(width 0.254)
		(layer "F.Cu")
		(net "GND")
	)
	(segment
		(start 82.446368 -388.328662)
		(end 81.798414 -388.138924)
		(width 0.254)
		(layer "F.Cu")
		(net "GND")
	)
	(segment
		(start 123.997974 -239.080294)
		(end 124.464826 -238.814356)
		(width 0.350012)
		(layer "F.Cu")
		(net "GND")
	)
	(segment
		(start 131.817872 -280.30043)
		(end 132.284724 -280.566368)
		(width 0.350012)
		(layer "F.Cu")
		(net "GND")
	)
	(segment
		(start 126.347982 -233.410252)
		(end 126.814834 -233.144314)
		(width 0.350012)
		(layer "F.Cu")
		(net "GND")
	)
	(segment
		(start 170.266106 -125.751336)
		(end 170.16857 -125.848872)
		(width 0.4572)
		(layer "F.Cu")
		(net "GND")
	)
	(segment
		(start 116.590064 -166.711884)
		(end 116.002054 -166.711884)
		(width 0.381)
		(layer "F.Cu")
		(net "GND")
	)
	(segment
		(start 376.467878 -279.49017)
		(end 376.93473 -279.756108)
		(width 0.350012)
		(layer "F.Cu")
		(net "GND")
	)
	(segment
		(start 377.577858 -230.97998)
		(end 378.04471 -230.714296)
		(width 0.350012)
		(layer "F.Cu")
		(net "GND")
	)
	(segment
		(start 131.817872 -288.400236)
		(end 132.284724 -288.666174)
		(width 0.350012)
		(layer "F.Cu")
		(net "GND")
	)
	(segment
		(start 360.957876 -268.960092)
		(end 361.424728 -269.22603)
		(width 0.350012)
		(layer "F.Cu")
		(net "GND")
	)
	(segment
		(start 140.27785 -268.960346)
		(end 140.744702 -269.226284)
		(width 0.350012)
		(layer "F.Cu")
		(net "GND")
	)
	(segment
		(start 25.746964 -8.320024)
		(end 25.746964 -9.423654)
		(width 0.3556)
		(layer "F.Cu")
		(net "GND")
	)
	(segment
		(start 86.868 -226.930458)
		(end 86.401148 -226.66452)
		(width 0.350012)
		(layer "F.Cu")
		(net "GND")
	)
	(segment
		(start 142.348204 -16.551148)
		(end 142.348204 -17.654778)
		(width 0.3556)
		(layer "F.Cu")
		(net "GND")
	)
	(segment
		(start 384.627882 -238.270034)
		(end 385.094734 -238.004096)
		(width 0.350012)
		(layer "F.Cu")
		(net "GND")
	)
	(segment
		(start 336.987896 -276.250146)
		(end 336.521044 -276.516084)
		(width 0.350012)
		(layer "F.Cu")
		(net "GND")
	)
	(segment
		(start 9.90981 -97.784158)
		(end 9.29513 -97.784158)
		(width 0.3556)
		(layer "F.Cu")
		(net "GND")
	)
	(segment
		(start 368.64798 -236.650022)
		(end 369.114832 -236.384084)
		(width 0.350012)
		(layer "F.Cu")
		(net "GND")
	)
	(segment
		(start 79.177896 -264.10031)
		(end 78.711044 -264.366248)
		(width 0.350012)
		(layer "F.Cu")
		(net "GND")
	)
	(segment
		(start 14.486128 -107.631484)
		(end 14.445996 -107.591352)
		(width 0.3556)
		(layer "F.Cu")
		(net "GND")
	)
	(segment
		(start 97.97796 -291.64026)
		(end 97.511108 -291.906198)
		(width 0.350012)
		(layer "F.Cu")
		(net "GND")
	)
	(segment
		(start 84.145882 -390.761474)
		(end 84.19846 -390.160002)
		(width 0.254)
		(layer "F.Cu")
		(net "GND")
	)
	(segment
		(start 136.217914 -250.420378)
		(end 136.684766 -250.15444)
		(width 0.350012)
		(layer "F.Cu")
		(net "GND")
	)
	(segment
		(start 442.5442 -315.485018)
		(end 443.9285 -315.485018)
		(width 0.4572)
		(layer "F.Cu")
		(net "GND")
	)
	(segment
		(start 368.17808 -229.360222)
		(end 368.644932 -229.094284)
		(width 0.350012)
		(layer "F.Cu")
		(net "GND")
	)
	(segment
		(start 403.698202 -392.999722)
		(end 403.645624 -392.30427)
		(width 0.254)
		(layer "F.Cu")
		(net "GND")
	)
	(segment
		(start 308.1782 -394.831062)
		(end 307.670454 -395.0208)
		(width 0.254)
		(layer "F.Cu")
		(net "GND")
	)
	(segment
		(start 328.527918 -269.770098)
		(end 328.061066 -270.036036)
		(width 0.350012)
		(layer "F.Cu")
		(net "GND")
	)
	(segment
		(start 354.078032 -247.1801)
		(end 353.61118 -246.914162)
		(width 0.350012)
		(layer "F.Cu")
		(net "GND")
	)
	(segment
		(start 284.736032 -274.684998)
		(end 283.351732 -274.684998)
		(width 0.4572)
		(layer "F.Cu")
		(net "GND")
	)
	(segment
		(start 110.632494 -383.7432)
		(end 111.165894 -383.7432)
		(width 0.254)
		(layer "F.Cu")
		(net "GND")
	)
	(segment
		(start 40.256968 -11.26998)
		(end 40.256968 -10.16635)
		(width 0.3556)
		(layer "F.Cu")
		(net "GND")
	)
	(segment
		(start 134.35076 -393.25804)
		(end 134.23138 -393.37742)
		(width 0.3048)
		(layer "F.Cu")
		(net "GND")
	)
	(segment
		(start 347.968062 -246.370094)
		(end 347.50121 -246.104156)
		(width 0.350012)
		(layer "F.Cu")
		(net "GND")
	)
	(segment
		(start 335.577942 -286.780224)
		(end 335.11109 -287.045908)
		(width 0.350012)
		(layer "F.Cu")
		(net "GND")
	)
	(segment
		(start 330.321158 -33.921192)
		(end 329.808586 -33.921192)
		(width 0.3556)
		(layer "F.Cu")
		(net "GND")
	)
	(segment
		(start 110.1979 -267.340334)
		(end 109.731048 -267.606272)
		(width 0.350012)
		(layer "F.Cu")
		(net "GND")
	)
	(segment
		(start 51.618134 -390.761474)
		(end 51.317906 -391.281158)
		(width 0.254)
		(layer "F.Cu")
		(net "GND")
	)
	(segment
		(start 140.27785 -273.820382)
		(end 140.744702 -274.08632)
		(width 0.350012)
		(layer "F.Cu")
		(net "GND")
	)
	(segment
		(start 362.53801 -224.500186)
		(end 363.004862 -224.234248)
		(width 0.350012)
		(layer "F.Cu")
		(net "GND")
	)
	(segment
		(start 368.947954 -264.910062)
		(end 369.414806 -265.176)
		(width 0.350012)
		(layer "F.Cu")
		(net "GND")
	)
	(segment
		(start 355.111304 -394.831062)
		(end 354.598224 -395.0208)
		(width 0.254)
		(layer "F.Cu")
		(net "GND")
	)
	(segment
		(start 363.307884 -289.209988)
		(end 363.774736 -289.475926)
		(width 0.350012)
		(layer "F.Cu")
		(net "GND")
	)
	(segment
		(start 88.998298 -388.138924)
		(end 88.446356 -388.328662)
		(width 0.254)
		(layer "F.Cu")
		(net "GND")
	)
	(segment
		(start 383.048002 -263.29005)
		(end 383.514854 -263.555988)
		(width 0.350012)
		(layer "F.Cu")
		(net "GND")
	)
	(segment
		(start 400.24812 -12.374118)
		(end 400.24685 -12.372848)
		(width 0.3556)
		(layer "F.Cu")
		(net "GND")
	)
	(segment
		(start 87.637874 -268.960346)
		(end 87.171022 -269.226284)
		(width 0.350012)
		(layer "F.Cu")
		(net "GND")
	)
	(segment
		(start 110.83798 -227.740464)
		(end 110.371128 -227.474526)
		(width 0.350012)
		(layer "F.Cu")
		(net "GND")
	)
	(segment
		(start 21.70811 -274.685252)
		(end 20.32381 -274.685252)
		(width 0.4572)
		(layer "F.Cu")
		(net "GND")
	)
	(segment
		(start 143.567912 -284.35046)
		(end 144.034764 -284.616398)
		(width 0.350012)
		(layer "F.Cu")
		(net "GND")
	)
	(segment
		(start 347.497908 -248.800112)
		(end 347.031056 -248.534174)
		(width 0.350012)
		(layer "F.Cu")
		(net "GND")
	)
	(segment
		(start 330.108052 -239.890046)
		(end 329.6412 -239.624108)
		(width 0.350012)
		(layer "F.Cu")
		(net "GND")
	)
	(segment
		(start 150.945596 -382.951482)
		(end 151.044148 -382.85293)
		(width 0.2032)
		(layer "F.Cu")
		(net "GND")
	)
	(segment
		(start 55.270654 -390.160002)
		(end 54.591204 -390.160002)
		(width 0.254)
		(layer "F.Cu")
		(net "GND")
	)
	(segment
		(start 387.448044 -239.890046)
		(end 387.914896 -239.624108)
		(width 0.350012)
		(layer "F.Cu")
		(net "GND")
	)
	(segment
		(start 162.098228 -384.617722)
		(end 161.490152 -384.617722)
		(width 0.254)
		(layer "F.Cu")
		(net "GND")
	)
	(segment
		(start 124.767848 -268.15034)
		(end 125.2347 -268.416278)
		(width 0.350012)
		(layer "F.Cu")
		(net "GND")
	)
	(segment
		(start 237.612682 -160.972754)
		(end 237.688882 -161.048954)
		(width 0.381)
		(layer "F.Cu")
		(net "GND")
	)
	(segment
		(start 379.75794 -260.860032)
		(end 380.224792 -261.12597)
		(width 0.350012)
		(layer "F.Cu")
		(net "GND")
	)
	(segment
		(start 347.497908 -242.320064)
		(end 347.031056 -242.054126)
		(width 0.350012)
		(layer "F.Cu")
		(net "GND")
	)
	(segment
		(start 360.957876 -283.5402)
		(end 361.424728 -283.806138)
		(width 0.350012)
		(layer "F.Cu")
		(net "GND")
	)
	(segment
		(start 135.107934 -281.110436)
		(end 135.574786 -281.376374)
		(width 0.350012)
		(layer "F.Cu")
		(net "GND")
	)
	(segment
		(start 431.066194 -356.35184)
		(end 431.654204 -356.35184)
		(width 0.3556)
		(layer "F.Cu")
		(net "GND")
	)
	(segment
		(start 96.568006 -294.070278)
		(end 96.101154 -294.336216)
		(width 0.350012)
		(layer "F.Cu")
		(net "GND")
	)
	(segment
		(start 84.347812 -289.210242)
		(end 83.88096 -289.47618)
		(width 0.350012)
		(layer "F.Cu")
		(net "GND")
	)
	(segment
		(start 118.657878 -290.020248)
		(end 119.12473 -290.286186)
		(width 0.350012)
		(layer "F.Cu")
		(net "GND")
	)
	(segment
		(start 353.437952 -272.200116)
		(end 352.9711 -272.466054)
		(width 0.350012)
		(layer "F.Cu")
		(net "GND")
	)
	(segment
		(start 103.617776 -270.580358)
		(end 103.151178 -270.846296)
		(width 0.350012)
		(layer "F.Cu")
		(net "GND")
	)
	(segment
		(start 133.348222 -17.654016)
		(end 133.348222 -17.654778)
		(width 0.3556)
		(layer "F.Cu")
		(net "GND")
	)
	(segment
		(start 275.105622 -351.927922)
		(end 275.175472 -351.858072)
		(width 0.381)
		(layer "F.Cu")
		(net "GND")
	)
	(segment
		(start 80.245712 -383.402586)
		(end 80.245712 -382.951482)
		(width 0.254)
		(layer "F.Cu")
		(net "GND")
	)
	(segment
		(start 99.55784 -224.50044)
		(end 99.090988 -224.234502)
		(width 0.350012)
		(layer "F.Cu")
		(net "GND")
	)
	(segment
		(start 330.375514 -140.826998)
		(end 330.623418 -141.074902)
		(width 0.254)
		(layer "F.Cu")
		(net "GND")
	)
	(segment
		(start 407.890218 -392.999722)
		(end 407.298398 -392.999722)
		(width 0.254)
		(layer "F.Cu")
		(net "GND")
	)
	(segment
		(start 386.03809 -234.220004)
		(end 386.504942 -233.954066)
		(width 0.350012)
		(layer "F.Cu")
		(net "GND")
	)
	(segment
		(start 333.39786 -224.500186)
		(end 332.931008 -224.234248)
		(width 0.350012)
		(layer "F.Cu")
		(net "GND")
	)
	(segment
		(start 335.022444 -400.15795)
		(end 335.022444 -399.686272)
		(width 0.254)
		(layer "F.Cu")
		(net "GND")
	)
	(segment
		(start 387.278626 -394.831062)
		(end 386.770626 -395.0208)
		(width 0.254)
		(layer "F.Cu")
		(net "GND")
	)
	(segment
		(start 118.999 -434.70195)
		(end 118.999 -433.959)
		(width 0.381)
		(layer "F.Cu")
		(net "GND")
	)
	(segment
		(start 47.784004 -238.135414)
		(end 49.168304 -238.135414)
		(width 0.4572)
		(layer "F.Cu")
		(net "GND")
	)
	(segment
		(start 374.75795 -230.97998)
		(end 375.224802 -230.714296)
		(width 0.350012)
		(layer "F.Cu")
		(net "GND")
	)
	(segment
		(start 183.861964 -13.599922)
		(end 183.860694 -13.598652)
		(width 0.3556)
		(layer "F.Cu")
		(net "GND")
	)
	(segment
		(start 110.83798 -226.120452)
		(end 110.371128 -225.854514)
		(width 0.350012)
		(layer "F.Cu")
		(net "GND")
	)
	(segment
		(start 345.845384 -392.004042)
		(end 345.845384 -391.784586)
		(width 0.254)
		(layer "F.Cu")
		(net "GND")
	)
	(segment
		(start 372.238016 -288.399982)
		(end 372.704868 -288.66592)
		(width 0.350012)
		(layer "F.Cu")
		(net "GND")
	)
	(segment
		(start 46.30166 -388.330948)
		(end 46.621192 -388.330948)
		(width 0.254)
		(layer "F.Cu")
		(net "GND")
	)
	(segment
		(start 58.1914 -390.160002)
		(end 57.6707 -390.160002)
		(width 0.254)
		(layer "F.Cu")
		(net "GND")
	)
	(segment
		(start 352.197924 -226.120198)
		(end 351.731072 -225.85426)
		(width 0.350012)
		(layer "F.Cu")
		(net "GND")
	)
	(segment
		(start 345.447874 -290.83)
		(end 344.981022 -291.095938)
		(width 0.350012)
		(layer "F.Cu")
		(net "GND")
	)
	(segment
		(start 146.799046 -66.337434)
		(end 146.183096 -66.337434)
		(width 0.4572)
		(layer "F.Cu")
		(net "GND")
	)
	(segment
		(start 327.117964 -285.160212)
		(end 326.651112 -285.42615)
		(width 0.350012)
		(layer "F.Cu")
		(net "GND")
	)
	(segment
		(start 268.755368 -103.26624)
		(end 269.609824 -103.26624)
		(width 0.4572)
		(layer "F.Cu")
		(net "GND")
	)
	(segment
		(start 54.918102 -382.951482)
		(end 55.016654 -382.85293)
		(width 0.254)
		(layer "F.Cu")
		(net "GND")
	)
	(segment
		(start 392.953748 -320.627756)
		(end 393.097004 -320.4845)
		(width 0.508)
		(layer "F.Cu")
		(net "GND")
	)
	(segment
		(start 47.37862 -386.449062)
		(end 46.621192 -386.630926)
		(width 0.254)
		(layer "F.Cu")
		(net "GND")
	)
	(segment
		(start 85.457792 -235.84027)
		(end 84.99094 -235.574332)
		(width 0.350012)
		(layer "F.Cu")
		(net "GND")
	)
	(segment
		(start 174.815246 -103.029512)
		(end 174.57928 -102.793546)
		(width 0.4572)
		(layer "F.Cu")
		(net "GND")
	)
	(segment
		(start 333.39786 -230.97998)
		(end 332.931008 -230.714042)
		(width 0.350012)
		(layer "F.Cu")
		(net "GND")
	)
	(segment
		(start 154.346148 -388.328662)
		(end 153.698194 -388.138924)
		(width 0.254)
		(layer "F.Cu")
		(net "GND")
	)
	(segment
		(start 381.338074 -247.1801)
		(end 381.804926 -246.914162)
		(width 0.350012)
		(layer "F.Cu")
		(net "GND")
	)
	(segment
		(start 357.837994 -252.040136)
		(end 357.371142 -251.774198)
		(width 0.350012)
		(layer "F.Cu")
		(net "GND")
	)
	(segment
		(start 135.27786 -222.880428)
		(end 135.744712 -222.61449)
		(width 0.350012)
		(layer "F.Cu")
		(net "GND")
	)
	(segment
		(start 95.84563 -391.281158)
		(end 96.145858 -390.761474)
		(width 0.254)
		(layer "F.Cu")
		(net "GND")
	)
	(segment
		(start 336.046064 -396.710662)
		(end 335.39811 -396.46352)
		(width 0.254)
		(layer "F.Cu")
		(net "GND")
	)
	(segment
		(start 330.408026 -290.83)
		(end 329.941174 -291.095938)
		(width 0.350012)
		(layer "F.Cu")
		(net "GND")
	)
	(segment
		(start 416.468052 -230.485188)
		(end 415.083752 -230.485188)
		(width 0.4572)
		(layer "F.Cu")
		(net "GND")
	)
	(segment
		(start 376.411236 -178.359562)
		(end 376.411236 -177.71618)
		(width 0.381)
		(layer "F.Cu")
		(net "GND")
	)
	(segment
		(start 49.666906 -8.320024)
		(end 49.666906 -9.423654)
		(width 0.3556)
		(layer "F.Cu")
		(net "GND")
	)
	(segment
		(start 371.297962 -291.640006)
		(end 371.764814 -291.905944)
		(width 0.350012)
		(layer "F.Cu")
		(net "GND")
	)
	(segment
		(start 40.23995 -210.085432)
		(end 41.62425 -210.085432)
		(width 0.4572)
		(layer "F.Cu")
		(net "GND")
	)
	(segment
		(start 274.517612 -351.927922)
		(end 275.105622 -351.927922)
		(width 0.381)
		(layer "F.Cu")
		(net "GND")
	)
	(segment
		(start 100.647754 -342.306402)
		(end 100.647754 -342.018366)
		(width 0.2286)
		(layer "F.Cu")
		(net "GND")
	)
	(segment
		(start 90.157808 -240.700306)
		(end 89.690956 -240.434368)
		(width 0.350012)
		(layer "F.Cu")
		(net "GND")
	)
	(segment
		(start 115.367816 -285.970472)
		(end 115.834668 -286.23641)
		(width 0.350012)
		(layer "F.Cu")
		(net "GND")
	)
	(segment
		(start 83.944206 -391.37971)
		(end 83.845654 -391.281158)
		(width 0.254)
		(layer "F.Cu")
		(net "GND")
	)
	(segment
		(start 83.622134 -45.36694)
		(end 83.622134 -45.997622)
		(width 0.3556)
		(layer "F.Cu")
		(net "GND")
	)
	(segment
		(start 421.444166 -400.212814)
		(end 421.444166 -399.76171)
		(width 0.254)
		(layer "F.Cu")
		(net "GND")
	)
	(segment
		(start 402.248878 -397.412972)
		(end 402.248878 -396.712948)
		(width 0.254)
		(layer "F.Cu")
		(net "GND")
	)
	(segment
		(start 19.400012 -357.90632)
		(end 18.384012 -357.90632)
		(width 0.381)
		(layer "F.Cu")
		(net "GND")
	)
	(segment
		(start 350.31807 -243.940076)
		(end 349.851218 -243.674138)
		(width 0.350012)
		(layer "F.Cu")
		(net "GND")
	)
	(segment
		(start 331.987906 -235.03001)
		(end 331.521054 -234.764072)
		(width 0.350012)
		(layer "F.Cu")
		(net "GND")
	)
	(segment
		(start 136.987788 -279.490424)
		(end 137.45464 -279.756362)
		(width 0.350012)
		(layer "F.Cu")
		(net "GND")
	)
	(segment
		(start 25.152096 -240.68532)
		(end 26.536396 -240.68532)
		(width 0.4572)
		(layer "F.Cu")
		(net "GND")
	)
	(segment
		(start 347.028008 -223.69018)
		(end 346.561156 -223.424242)
		(width 0.350012)
		(layer "F.Cu")
		(net "GND")
	)
	(segment
		(start 381.638048 -291.640006)
		(end 382.1049 -291.905944)
		(width 0.350012)
		(layer "F.Cu")
		(net "GND")
	)
	(segment
		(start 114.817906 -383.622296)
		(end 115.11788 -383.92227)
		(width 0.254)
		(layer "F.Cu")
		(net "GND")
	)
	(segment
		(start 131.517898 -252.04039)
		(end 131.98475 -251.774452)
		(width 0.350012)
		(layer "F.Cu")
		(net "GND")
	)
	(segment
		(start 392.593576 -395.22273)
		(end 392.836908 -395.466062)
		(width 0.381)
		(layer "F.Cu")
		(net "GND")
	)
	(segment
		(start 97.398332 -384.617722)
		(end 97.345754 -383.92227)
		(width 0.254)
		(layer "F.Cu")
		(net "GND")
	)
	(segment
		(start 335.108042 -266.530074)
		(end 334.64119 -266.796012)
		(width 0.350012)
		(layer "F.Cu")
		(net "GND")
	)
	(segment
		(start 91.990164 -384.617722)
		(end 92.59824 -384.617722)
		(width 0.254)
		(layer "F.Cu")
		(net "GND")
	)
	(segment
		(start 396.645638 -7.215124)
		(end 396.645638 -7.215886)
		(width 0.3556)
		(layer "F.Cu")
		(net "GND")
	)
	(segment
		(start 119.597932 -285.160466)
		(end 120.064784 -285.426404)
		(width 0.350012)
		(layer "F.Cu")
		(net "GND")
	)
	(segment
		(start 52.178458 -386.449062)
		(end 51.670712 -386.6388)
		(width 0.254)
		(layer "F.Cu")
		(net "GND")
	)
	(segment
		(start 92.80779 -268.15034)
		(end 92.340938 -268.416278)
		(width 0.350012)
		(layer "F.Cu")
		(net "GND")
	)
	(segment
		(start 85.757766 -277.060406)
		(end 85.290914 -277.326344)
		(width 0.350012)
		(layer "F.Cu")
		(net "GND")
	)
	(segment
		(start 75.165712 -403.581362)
		(end 74.357738 -402.773388)
		(width 0.381)
		(layer "F.Cu")
		(net "GND")
	)
	(segment
		(start 418.355526 -11.26871)
		(end 418.355526 -10.16508)
		(width 0.3556)
		(layer "F.Cu")
		(net "GND")
	)
	(segment
		(start 87.167974 -274.630388)
		(end 86.701122 -274.896326)
		(width 0.350012)
		(layer "F.Cu")
		(net "GND")
	)
	(segment
		(start 143.267938 -243.130324)
		(end 143.73479 -242.864386)
		(width 0.350012)
		(layer "F.Cu")
		(net "GND")
	)
	(segment
		(start 388.462266 -51.1175)
		(end 388.463536 -51.11623)
		(width 0.4572)
		(layer "F.Cu")
		(net "GND")
	)
	(segment
		(start 94.217998 -267.340334)
		(end 93.751146 -267.606272)
		(width 0.350012)
		(layer "F.Cu")
		(net "GND")
	)
	(segment
		(start 90.627962 -244.750336)
		(end 90.16111 -244.484398)
		(width 0.350012)
		(layer "F.Cu")
		(net "GND")
	)
	(segment
		(start 386.718048 -399.143474)
		(end 386.770626 -398.542002)
		(width 0.254)
		(layer "F.Cu")
		(net "GND")
	)
	(segment
		(start 112.717834 -237.460282)
		(end 113.184686 -237.194344)
		(width 0.350012)
		(layer "F.Cu")
		(net "GND")
	)
	(segment
		(start 47.784004 -203.285344)
		(end 49.168304 -203.285344)
		(width 0.4572)
		(layer "F.Cu")
		(net "GND")
	)
	(segment
		(start 161.30524 -37.139372)
		(end 160.362646 -37.139372)
		(width 0.4572)
		(layer "F.Cu")
		(net "GND")
	)
	(segment
		(start 349.378016 -229.360222)
		(end 348.911164 -229.094284)
		(width 0.350012)
		(layer "F.Cu")
		(net "GND")
	)
	(segment
		(start 90.157808 -227.740464)
		(end 89.690956 -227.474526)
		(width 0.350012)
		(layer "F.Cu")
		(net "GND")
	)
	(segment
		(start 331.987906 -251.23013)
		(end 331.521054 -250.964192)
		(width 0.350012)
		(layer "F.Cu")
		(net "GND")
	)
	(segment
		(start 165.942518 -387.231128)
		(end 165.942518 -387.831076)
		(width 0.254)
		(layer "F.Cu")
		(net "GND")
	)
	(segment
		(start 384.627882 -226.930204)
		(end 385.094734 -226.664266)
		(width 0.350012)
		(layer "F.Cu")
		(net "GND")
	)
	(segment
		(start 374.588024 -284.350206)
		(end 375.054876 -284.616144)
		(width 0.350012)
		(layer "F.Cu")
		(net "GND")
	)
	(segment
		(start 356.42804 -233.409998)
		(end 355.961188 -233.14406)
		(width 0.350012)
		(layer "F.Cu")
		(net "GND")
	)
	(segment
		(start 269.648178 -221.13494)
		(end 268.263878 -221.13494)
		(width 0.4572)
		(layer "F.Cu")
		(net "GND")
	)
	(segment
		(start 103.147876 -276.2504)
		(end 102.681024 -276.516338)
		(width 0.350012)
		(layer "F.Cu")
		(net "GND")
	)
	(segment
		(start 369.401598 -396.712948)
		(end 369.2017 -396.51305)
		(width 0.254)
		(layer "F.Cu")
		(net "GND")
	)
	(segment
		(start 126.571756 -30.097222)
		(end 126.723902 -30.249368)
		(width 0.381)
		(layer "F.Cu")
		(net "GND")
	)
	(segment
		(start 169.19956 -17.585944)
		(end 169.268394 -17.654778)
		(width 0.3556)
		(layer "F.Cu")
		(net "GND")
	)
	(segment
		(start 167.329358 -349.265494)
		(end 167.800782 -349.265494)
		(width 0.381)
		(layer "F.Cu")
		(net "GND")
	)
	(segment
		(start 332.365096 -340.231222)
		(end 331.997304 -340.231222)
		(width 0.381)
		(layer "F.Cu")
		(net "GND")
	)
	(segment
		(start 259.44195 -102.108)
		(end 259.44195 -102.85095)
		(width 0.381)
		(layer "F.Cu")
		(net "GND")
	)
	(segment
		(start 60.91809 -382.951482)
		(end 61.016642 -382.85293)
		(width 0.254)
		(layer "F.Cu")
		(net "GND")
	)
	(segment
		(start 335.39811 -396.46352)
		(end 335.148682 -396.712948)
		(width 0.254)
		(layer "F.Cu")
		(net "GND")
	)
	(segment
		(start 140.91793 -222.880428)
		(end 141.384782 -222.61449)
		(width 0.350012)
		(layer "F.Cu")
		(net "GND")
	)
	(segment
		(start 356.728014 -269.770098)
		(end 356.261162 -270.036036)
		(width 0.350012)
		(layer "F.Cu")
		(net "GND")
	)
	(segment
		(start 327.117964 -278.680164)
		(end 326.651112 -278.946102)
		(width 0.350012)
		(layer "F.Cu")
		(net "GND")
	)
	(segment
		(start 128.227836 -238.270288)
		(end 128.694688 -238.00435)
		(width 0.350012)
		(layer "F.Cu")
		(net "GND")
	)
	(segment
		(start 128.227836 -225.310446)
		(end 128.694688 -225.044508)
		(width 0.350012)
		(layer "F.Cu")
		(net "GND")
	)
	(segment
		(start 108.017818 -239.080294)
		(end 107.550966 -238.814356)
		(width 0.350012)
		(layer "F.Cu")
		(net "GND")
	)
	(segment
		(start 388.688072 -294.070024)
		(end 389.154924 -294.335962)
		(width 0.350012)
		(layer "F.Cu")
		(net "GND")
	)
	(segment
		(start 446.644268 -230.485188)
		(end 445.259968 -230.485188)
		(width 0.4572)
		(layer "F.Cu")
		(net "GND")
	)
	(segment
		(start 456.734672 -107.018836)
		(end 456.048872 -107.018836)
		(width 0.3556)
		(layer "F.Cu")
		(net "GND")
	)
	(segment
		(start 114.897916 -293.260272)
		(end 115.364768 -293.52621)
		(width 0.350012)
		(layer "F.Cu")
		(net "GND")
	)
	(segment
		(start 402.248878 -398.01292)
		(end 402.248878 -397.412972)
		(width 0.254)
		(layer "F.Cu")
		(net "GND")
	)
	(segment
		(start 97.745296 -422.83253)
		(end 97.745296 -423.284904)
		(width 0.381)
		(layer "F.Cu")
		(net "GND")
	)
	(segment
		(start 69.2023 -29.319728)
		(end 69.172582 -29.29001)
		(width 0.254)
		(layer "F.Cu")
		(net "GND")
	)
	(segment
		(start 102.677976 -278.680418)
		(end 102.211124 -278.946356)
		(width 0.350012)
		(layer "F.Cu")
		(net "GND")
	)
	(segment
		(start 154.898344 -388.138924)
		(end 154.346148 -388.328662)
		(width 0.254)
		(layer "F.Cu")
		(net "GND")
	)
	(segment
		(start 170.869356 -125.751336)
		(end 170.869356 -123.748546)
		(width 0.4572)
		(layer "F.Cu")
		(net "GND")
	)
	(segment
		(start 336.987896 -289.209988)
		(end 336.521044 -289.475926)
		(width 0.350012)
		(layer "F.Cu")
		(net "GND")
	)
	(segment
		(start 166.26586 -13.598652)
		(end 166.26586 -12.495022)
		(width 0.3556)
		(layer "F.Cu")
		(net "GND")
	)
	(segment
		(start 368.64798 -256.090166)
		(end 369.114832 -255.824228)
		(width 0.350012)
		(layer "F.Cu")
		(net "GND")
	)
	(segment
		(start 336.598006 -395.0208)
		(end 335.90611 -394.831062)
		(width 0.254)
		(layer "F.Cu")
		(net "GND")
	)
	(segment
		(start 24.36495 -362.204)
		(end 24.36495 -363.347)
		(width 0.381)
		(layer "F.Cu")
		(net "GND")
	)
	(segment
		(start 159.34563 -383.622296)
		(end 159.645604 -383.92227)
		(width 0.254)
		(layer "F.Cu")
		(net "GND")
	)
	(segment
		(start 124.937774 -224.50044)
		(end 125.404626 -224.234502)
		(width 0.350012)
		(layer "F.Cu")
		(net "GND")
	)
	(segment
		(start 118.313962 -17.784064)
		(end 118.929912 -17.784064)
		(width 0.381)
		(layer "F.Cu")
		(net "GND")
	)
	(segment
		(start 163.82238 -17.608804)
		(end 163.868354 -17.654778)
		(width 0.3556)
		(layer "F.Cu")
		(net "GND")
	)
	(segment
		(start 369.501674 -395.613128)
		(end 369.72113 -395.613128)
		(width 0.254)
		(layer "F.Cu")
		(net "GND")
	)
	(segment
		(start 336.687922 -241.510058)
		(end 336.22107 -241.24412)
		(width 0.350012)
		(layer "F.Cu")
		(net "GND")
	)
	(segment
		(start 116.13896 -414.640014)
		(end 116.13896 -413.893)
		(width 0.381)
		(layer "F.Cu")
		(net "GND")
	)
	(segment
		(start 97.037906 -280.30043)
		(end 96.571054 -280.566368)
		(width 0.350012)
		(layer "F.Cu")
		(net "GND")
	)
	(segment
		(start 402.248878 -393.81303)
		(end 402.248878 -393.24915)
		(width 0.254)
		(layer "F.Cu")
		(net "GND")
	)
	(segment
		(start 113.017808 -288.400236)
		(end 113.48466 -288.666174)
		(width 0.350012)
		(layer "F.Cu")
		(net "GND")
	)
	(segment
		(start 81.445862 -391.281158)
		(end 81.745836 -390.761474)
		(width 0.254)
		(layer "F.Cu")
		(net "GND")
	)
	(segment
		(start 355.31806 -291.640006)
		(end 354.851208 -291.905944)
		(width 0.350012)
		(layer "F.Cu")
		(net "GND")
	)
	(segment
		(start 61.52261 -37.957252)
		(end 61.52261 -38.554152)
		(width 0.3556)
		(layer "F.Cu")
		(net "GND")
	)
	(segment
		(start 154.644344 -391.37971)
		(end 154.545792 -391.281158)
		(width 0.254)
		(layer "F.Cu")
		(net "GND")
	)
	(segment
		(start 67.812412 -39.421562)
		(end 67.202558 -39.421562)
		(width 0.4572)
		(layer "F.Cu")
		(net "GND")
	)
	(segment
		(start 277.192232 -314.635134)
		(end 275.807932 -314.635134)
		(width 0.4572)
		(layer "F.Cu")
		(net "GND")
	)
	(segment
		(start 33.799526 -348.79915)
		(end 34.05251 -348.546166)
		(width 0.2286)
		(layer "F.Cu")
		(net "GND")
	)
	(segment
		(start 372.707916 -268.150086)
		(end 373.174768 -268.416024)
		(width 0.350012)
		(layer "F.Cu")
		(net "GND")
	)
	(segment
		(start 108.629704 -327.582276)
		(end 108.521754 -327.474326)
		(width 0.254)
		(layer "F.Cu")
		(net "GND")
	)
	(segment
		(start 164.498274 -384.617722)
		(end 163.890198 -384.617722)
		(width 0.254)
		(layer "F.Cu")
		(net "GND")
	)
	(segment
		(start 355.957886 -224.500186)
		(end 355.491034 -224.234248)
		(width 0.350012)
		(layer "F.Cu")
		(net "GND")
	)
	(segment
		(start 324.615048 -401.717002)
		(end 324.790308 -401.892262)
		(width 0.254)
		(layer "F.Cu")
		(net "GND")
	)
	(segment
		(start 256.439924 -49.612296)
		(end 256.884932 -49.612296)
		(width 0.254)
		(layer "F.Cu")
		(net "GND")
	)
	(segment
		(start 169.506646 -101.018594)
		(end 170.568112 -101.018594)
		(width 0.4572)
		(layer "F.Cu")
		(net "GND")
	)
	(segment
		(start 198.7042 -218.585288)
		(end 197.3199 -218.585288)
		(width 0.4572)
		(layer "F.Cu")
		(net "GND")
	)
	(segment
		(start 79.022702 -391.77595)
		(end 79.022702 -391.304272)
		(width 0.254)
		(layer "F.Cu")
		(net "GND")
	)
	(segment
		(start 375.057924 -293.260018)
		(end 375.524776 -293.525956)
		(width 0.350012)
		(layer "F.Cu")
		(net "GND")
	)
	(segment
		(start 84.347812 -274.630388)
		(end 83.88096 -274.896326)
		(width 0.350012)
		(layer "F.Cu")
		(net "GND")
	)
	(segment
		(start 292.216332 -364.891066)
		(end 292.216332 -364.019084)
		(width 0.4064)
		(layer "F.Cu")
		(net "GND")
	)
	(segment
		(start 363.00791 -238.270034)
		(end 363.474762 -238.004096)
		(width 0.350012)
		(layer "F.Cu")
		(net "GND")
	)
	(segment
		(start 373.217948 -399.663158)
		(end 373.517922 -399.143474)
		(width 0.254)
		(layer "F.Cu")
		(net "GND")
	)
	(segment
		(start 67.327526 -337.367372)
		(end 67.327526 -337.078066)
		(width 0.2286)
		(layer "F.Cu")
		(net "GND")
	)
	(segment
		(start 128.227836 -239.8903)
		(end 128.694688 -239.624362)
		(width 0.350012)
		(layer "F.Cu")
		(net "GND")
	)
	(segment
		(start 404.5458 -399.663158)
		(end 404.845774 -399.143474)
		(width 0.254)
		(layer "F.Cu")
		(net "GND")
	)
	(segment
		(start 435.000146 -294.235124)
		(end 436.384446 -294.235124)
		(width 0.4572)
		(layer "F.Cu")
		(net "GND")
	)
	(segment
		(start 36.795964 -312.085228)
		(end 35.411664 -312.085228)
		(width 0.4572)
		(layer "F.Cu")
		(net "GND")
	)
	(segment
		(start 40.256968 -10.16635)
		(end 40.255698 -10.16508)
		(width 0.3556)
		(layer "F.Cu")
		(net "GND")
	)
	(segment
		(start 384.627882 -247.990106)
		(end 385.094734 -247.724168)
		(width 0.350012)
		(layer "F.Cu")
		(net "GND")
	)
	(segment
		(start 330.408026 -292.450012)
		(end 329.941174 -292.71595)
		(width 0.350012)
		(layer "F.Cu")
		(net "GND")
	)
	(segment
		(start 93.91777 -234.220258)
		(end 93.450918 -233.95432)
		(width 0.350012)
		(layer "F.Cu")
		(net "GND")
	)
	(segment
		(start 133.398006 -250.420378)
		(end 133.864858 -250.15444)
		(width 0.350012)
		(layer "F.Cu")
		(net "GND")
	)
	(segment
		(start 163.2458 -390.761474)
		(end 163.298378 -390.160002)
		(width 0.254)
		(layer "F.Cu")
		(net "GND")
	)
	(segment
		(start 93.91777 -226.120452)
		(end 93.450918 -225.854514)
		(width 0.350012)
		(layer "F.Cu")
		(net "GND")
	)
	(segment
		(start 118.417848 -383.402586)
		(end 118.417848 -383.622042)
		(width 0.2032)
		(layer "F.Cu")
		(net "GND")
	)
	(segment
		(start 387.917944 -226.120198)
		(end 388.384796 -225.85426)
		(width 0.350012)
		(layer "F.Cu")
		(net "GND")
	)
	(segment
		(start 105.918 -423.69105)
		(end 106.68 -423.69105)
		(width 0.381)
		(layer "F.Cu")
		(net "GND")
	)
	(segment
		(start 35.395662 -430.799748)
		(end 35.395662 -430.190148)
		(width 0.3556)
		(layer "F.Cu")
		(net "GND")
	)
	(segment
		(start 84.347812 -264.910316)
		(end 83.88096 -265.176254)
		(width 0.350012)
		(layer "F.Cu")
		(net "GND")
	)
	(segment
		(start 148.545804 -383.402586)
		(end 148.545804 -383.622296)
		(width 0.254)
		(layer "F.Cu")
		(net "GND")
	)
	(segment
		(start 389.327898 -226.930204)
		(end 389.79475 -226.664266)
		(width 0.350012)
		(layer "F.Cu")
		(net "GND")
	)
	(segment
		(start 370.969032 -34.637472)
		(end 371.606318 -34.637472)
		(width 0.4064)
		(layer "F.Cu")
		(net "GND")
	)
	(segment
		(start 192.199514 -68.407788)
		(end 191.589914 -68.407788)
		(width 0.3556)
		(layer "F.Cu")
		(net "GND")
	)
	(segment
		(start 94.998286 -384.617722)
		(end 94.945708 -383.92227)
		(width 0.254)
		(layer "F.Cu")
		(net "GND")
	)
	(segment
		(start 358.451912 -390.1694)
		(end 358.69499 -390.1694)
		(width 0.254)
		(layer "F.Cu")
		(net "GND")
	)
	(segment
		(start 371.467888 -244.750082)
		(end 371.93474 -244.484144)
		(width 0.350012)
		(layer "F.Cu")
		(net "GND")
	)
	(segment
		(start 125.238002 -270.580358)
		(end 125.704854 -270.846296)
		(width 0.350012)
		(layer "F.Cu")
		(net "GND")
	)
	(segment
		(start 402.248878 -398.613122)
		(end 402.248878 -398.946624)
		(width 0.254)
		(layer "F.Cu")
		(net "GND")
	)
	(segment
		(start 383.217928 -250.420124)
		(end 383.68478 -250.154186)
		(width 0.350012)
		(layer "F.Cu")
		(net "GND")
	)
	(segment
		(start 103.147876 -277.870412)
		(end 102.681024 -278.13635)
		(width 0.350012)
		(layer "F.Cu")
		(net "GND")
	)
	(segment
		(start 410.64434 -399.76171)
		(end 410.545788 -399.663158)
		(width 0.254)
		(layer "F.Cu")
		(net "GND")
	)
	(segment
		(start 125.877828 -240.700306)
		(end 126.34468 -240.434368)
		(width 0.350012)
		(layer "F.Cu")
		(net "GND")
	)
	(segment
		(start 350.618044 -286.780224)
		(end 350.151192 -287.045908)
		(width 0.350012)
		(layer "F.Cu")
		(net "GND")
	)
	(segment
		(start 153.090118 -384.617722)
		(end 153.698194 -384.617722)
		(width 0.254)
		(layer "F.Cu")
		(net "GND")
	)
	(segment
		(start 113.970562 -383.974848)
		(end 113.970562 -384.617722)
		(width 0.254)
		(layer "F.Cu")
		(net "GND")
	)
	(segment
		(start 333.697834 -260.860032)
		(end 333.230982 -261.12597)
		(width 0.350012)
		(layer "F.Cu")
		(net "GND")
	)
	(segment
		(start 411.45714 -141.982952)
		(end 410.722318 -142.287498)
		(width 0.1778)
		(layer "F.Cu")
		(net "GND")
	)
	(segment
		(start 51.884072 -237.285276)
		(end 50.499772 -237.285276)
		(width 0.4572)
		(layer "F.Cu")
		(net "GND")
	)
	(segment
		(start 407.446988 -12.372848)
		(end 407.446988 -11.26998)
		(width 0.3556)
		(layer "F.Cu")
		(net "GND")
	)
	(segment
		(start 405.64816 -12.37488)
		(end 405.64816 -12.374118)
		(width 0.3556)
		(layer "F.Cu")
		(net "GND")
	)
	(segment
		(start 143.098012 -268.960346)
		(end 143.56461 -269.226284)
		(width 0.350012)
		(layer "F.Cu")
		(net "GND")
	)
	(segment
		(start 85.757766 -293.260272)
		(end 85.290914 -293.52621)
		(width 0.350012)
		(layer "F.Cu")
		(net "GND")
	)
	(segment
		(start 366.297972 -235.840016)
		(end 366.764824 -235.574078)
		(width 0.350012)
		(layer "F.Cu")
		(net "GND")
	)
	(segment
		(start 152.498298 -384.617722)
		(end 152.44572 -383.92227)
		(width 0.254)
		(layer "F.Cu")
		(net "GND")
	)
	(segment
		(start 187.060078 -287.43529)
		(end 188.444378 -287.43529)
		(width 0.4572)
		(layer "F.Cu")
		(net "GND")
	)
	(segment
		(start 116.891308 -390.160002)
		(end 116.370608 -390.160002)
		(width 0.254)
		(layer "F.Cu")
		(net "GND")
	)
	(segment
		(start 288.180018 -287.435036)
		(end 289.564318 -287.435036)
		(width 0.4572)
		(layer "F.Cu")
		(net "GND")
	)
	(segment
		(start 415.345626 -392.004296)
		(end 415.6456 -392.30427)
		(width 0.254)
		(layer "F.Cu")
		(net "GND")
	)
	(segment
		(start 206.248 -209.235294)
		(end 204.8637 -209.235294)
		(width 0.4572)
		(layer "F.Cu")
		(net "GND")
	)
	(segment
		(start 168.066974 -13.599922)
		(end 168.065704 -13.598652)
		(width 0.3556)
		(layer "F.Cu")
		(net "GND")
	)
	(segment
		(start 450.088 -203.28509)
		(end 451.4723 -203.28509)
		(width 0.4572)
		(layer "F.Cu")
		(net "GND")
	)
	(segment
		(start 121.477786 -272.20037)
		(end 121.944638 -272.466308)
		(width 0.350012)
		(layer "F.Cu")
		(net "GND")
	)
	(segment
		(start 139.977876 -240.700306)
		(end 140.444728 -240.434368)
		(width 0.350012)
		(layer "F.Cu")
		(net "GND")
	)
	(segment
		(start 86.2457 -391.281158)
		(end 86.545674 -390.761474)
		(width 0.254)
		(layer "F.Cu")
		(net "GND")
	)
	(segment
		(start 403.025102 -323.036184)
		(end 403.05609 -323.067172)
		(width 0.381)
		(layer "F.Cu")
		(net "GND")
	)
	(segment
		(start 98.147886 -251.230384)
		(end 97.681034 -250.964446)
		(width 0.350012)
		(layer "F.Cu")
		(net "GND")
	)
	(segment
		(start 88.747854 -247.99036)
		(end 88.281002 -247.724422)
		(width 0.350012)
		(layer "F.Cu")
		(net "GND")
	)
	(segment
		(start 166.162228 -388.431024)
		(end 165.942518 -388.431024)
		(width 0.254)
		(layer "F.Cu")
		(net "GND")
	)
	(segment
		(start 78.877922 -248.800366)
		(end 78.41107 -248.534428)
		(width 0.350012)
		(layer "F.Cu")
		(net "GND")
	)
	(segment
		(start 284.736032 -237.285022)
		(end 283.351732 -237.285022)
		(width 0.4572)
		(layer "F.Cu")
		(net "GND")
	)
	(segment
		(start 87.637874 -267.340334)
		(end 87.171022 -267.606272)
		(width 0.350012)
		(layer "F.Cu")
		(net "GND")
	)
	(segment
		(start 84.347812 -284.35046)
		(end 83.88096 -284.616398)
		(width 0.350012)
		(layer "F.Cu")
		(net "GND")
	)
	(segment
		(start 103.147876 -284.35046)
		(end 102.681024 -284.616398)
		(width 0.350012)
		(layer "F.Cu")
		(net "GND")
	)
	(segment
		(start 280.050494 -349.781622)
		(end 280.620978 -349.211138)
		(width 0.2286)
		(layer "F.Cu")
		(net "GND")
	)
	(segment
		(start 389.170672 -395.369034)
		(end 389.170672 -395.0208)
		(width 0.254)
		(layer "F.Cu")
		(net "GND")
	)
	(segment
		(start 125.877828 -250.420378)
		(end 126.34468 -250.15444)
		(width 0.350012)
		(layer "F.Cu")
		(net "GND")
	)
	(segment
		(start 99.062286 -387.831076)
		(end 99.36226 -388.13105)
		(width 0.254)
		(layer "F.Cu")
		(net "GND")
	)
	(segment
		(start 187.060078 -284.885384)
		(end 188.444378 -284.885384)
		(width 0.4572)
		(layer "F.Cu")
		(net "GND")
	)
	(segment
		(start 198.7042 -199.8853)
		(end 197.3199 -199.8853)
		(width 0.4572)
		(layer "F.Cu")
		(net "GND")
	)
	(segment
		(start 103.99014 -24.855678)
		(end 103.99014 -20.69084)
		(width 0.381)
		(layer "F.Cu")
		(net "GND")
	)
	(segment
		(start 158.395416 -55.696612)
		(end 158.39567 -55.696358)
		(width 0.4572)
		(layer "F.Cu")
		(net "GND")
	)
	(segment
		(start 341.857838 -234.220004)
		(end 341.390986 -233.954066)
		(width 0.350012)
		(layer "F.Cu")
		(net "GND")
	)
	(segment
		(start 441.23356 -439.047382)
		(end 441.86856 -439.047382)
		(width 0.4318)
		(layer "F.Cu")
		(net "GND")
	)
	(segment
		(start 394.84808 -12.37488)
		(end 394.84808 -12.374118)
		(width 0.3556)
		(layer "F.Cu")
		(net "GND")
	)
	(segment
		(start 126.817882 -230.980234)
		(end 127.284734 -230.71455)
		(width 0.350012)
		(layer "F.Cu")
		(net "GND")
	)
	(segment
		(start 33.225994 -134.488936)
		(end 33.868614 -134.488936)
		(width 0.4064)
		(layer "F.Cu")
		(net "GND")
	)
	(segment
		(start 118.379494 -166.66591)
		(end 118.607078 -166.66591)
		(width 0.381)
		(layer "F.Cu")
		(net "GND")
	)
	(segment
		(start 133.41477 -387.831076)
		(end 133.63448 -387.831076)
		(width 0.254)
		(layer "F.Cu")
		(net "GND")
	)
	(segment
		(start 405.745696 -391.333482)
		(end 405.844248 -391.23493)
		(width 0.254)
		(layer "F.Cu")
		(net "GND")
	)
	(segment
		(start 103.147876 -273.010376)
		(end 102.681024 -273.276314)
		(width 0.350012)
		(layer "F.Cu")
		(net "GND")
	)
	(segment
		(start 364.888018 -249.610118)
		(end 365.35487 -249.34418)
		(width 0.350012)
		(layer "F.Cu")
		(net "GND")
	)
	(segment
		(start 308.517798 -391.333482)
		(end 308.61635 -391.23493)
		(width 0.2032)
		(layer "F.Cu")
		(net "GND")
	)
	(segment
		(start 335.108042 -281.110182)
		(end 334.64119 -281.37612)
		(width 0.350012)
		(layer "F.Cu")
		(net "GND")
	)
	(segment
		(start 376.167904 -238.270034)
		(end 376.634756 -238.004096)
		(width 0.350012)
		(layer "F.Cu")
		(net "GND")
	)
	(segment
		(start 431.55616 -274.684998)
		(end 430.17186 -274.684998)
		(width 0.4572)
		(layer "F.Cu")
		(net "GND")
	)
	(segment
		(start 382.748028 -233.409998)
		(end 383.21488 -233.14406)
		(width 0.350012)
		(layer "F.Cu")
		(net "GND")
	)
	(segment
		(start 98.629216 -384.005836)
		(end 98.54565 -383.92227)
		(width 0.254)
		(layer "F.Cu")
		(net "GND")
	)
	(segment
		(start 77.215746 -393.900152)
		(end 77.215746 -392.92276)
		(width 0.254)
		(layer "F.Cu")
		(net "GND")
	)
	(segment
		(start 133.69798 -286.780478)
		(end 134.164832 -287.046416)
		(width 0.350012)
		(layer "F.Cu")
		(net "GND")
	)
	(segment
		(start 327.28789 -223.69018)
		(end 326.821038 -223.424242)
		(width 0.350012)
		(layer "F.Cu")
		(net "GND")
	)
	(segment
		(start 90.627962 -241.510312)
		(end 90.16111 -241.244374)
		(width 0.350012)
		(layer "F.Cu")
		(net "GND")
	)
	(segment
		(start 422.462198 -392.913108)
		(end 422.242488 -392.913108)
		(width 0.254)
		(layer "F.Cu")
		(net "GND")
	)
	(segment
		(start 97.507806 -284.35046)
		(end 97.040954 -284.616398)
		(width 0.350012)
		(layer "F.Cu")
		(net "GND")
	)
	(segment
		(start 146.087846 -241.510312)
		(end 146.742912 -241.510312)
		(width 0.350012)
		(layer "F.Cu")
		(net "GND")
	)
	(segment
		(start 386.078476 -394.831062)
		(end 385.570476 -395.0208)
		(width 0.254)
		(layer "F.Cu")
		(net "GND")
	)
	(segment
		(start 363.00791 -251.23013)
		(end 363.474762 -250.964192)
		(width 0.350012)
		(layer "F.Cu")
		(net "GND")
	)
	(segment
		(start 348.437962 -252.040136)
		(end 347.97111 -251.774198)
		(width 0.350012)
		(layer "F.Cu")
		(net "GND")
	)
	(segment
		(start 129.63779 -253.660402)
		(end 130.104642 -253.394464)
		(width 0.350012)
		(layer "F.Cu")
		(net "GND")
	)
	(segment
		(start 87.167974 -279.490424)
		(end 86.701122 -279.756362)
		(width 0.350012)
		(layer "F.Cu")
		(net "GND")
	)
	(segment
		(start 353.607878 -236.650022)
		(end 353.141026 -236.384084)
		(width 0.350012)
		(layer "F.Cu")
		(net "GND")
	)
	(segment
		(start 114.491008 -390.160002)
		(end 114.491008 -390.231122)
		(width 0.254)
		(layer "F.Cu")
		(net "GND")
	)
	(segment
		(start 360.657902 -222.880174)
		(end 361.124754 -222.614236)
		(width 0.350012)
		(layer "F.Cu")
		(net "GND")
	)
	(segment
		(start 369.72113 -398.613122)
		(end 369.72113 -398.946624)
		(width 0.254)
		(layer "F.Cu")
		(net "GND")
	)
	(segment
		(start 83.174586 -46.44517)
		(end 82.92465 -46.44517)
		(width 0.3556)
		(layer "F.Cu")
		(net "GND")
	)
	(segment
		(start 378.347986 -285.970218)
		(end 378.814838 -286.236156)
		(width 0.350012)
		(layer "F.Cu")
		(net "GND")
	)
	(segment
		(start 100.967794 -256.09042)
		(end 100.500942 -255.824482)
		(width 0.350012)
		(layer "F.Cu")
		(net "GND")
	)
	(segment
		(start 173.651926 -391.34288)
		(end 173.232064 -390.923018)
		(width 0.254)
		(layer "F.Cu")
		(net "GND")
	)
	(segment
		(start 52.518056 -383.622296)
		(end 52.81803 -383.92227)
		(width 0.2032)
		(layer "F.Cu")
		(net "GND")
	)
	(segment
		(start 381.362458 -392.999722)
		(end 381.970534 -392.999722)
		(width 0.254)
		(layer "F.Cu")
		(net "GND")
	)
	(segment
		(start 121.477786 -281.920442)
		(end 121.944638 -282.18638)
		(width 0.350012)
		(layer "F.Cu")
		(net "GND")
	)
	(segment
		(start 301.58182 -395.613128)
		(end 302.101504 -395.313154)
		(width 0.254)
		(layer "F.Cu")
		(net "GND")
	)
	(segment
		(start 373.817896 -247.1801)
		(end 374.284748 -246.914162)
		(width 0.350012)
		(layer "F.Cu")
		(net "GND")
	)
	(segment
		(start 428.234602 -355.524562)
		(end 428.234602 -356.155498)
		(width 0.381)
		(layer "F.Cu")
		(net "GND")
	)
	(segment
		(start 144.977866 -290.020248)
		(end 145.444718 -290.286186)
		(width 0.350012)
		(layer "F.Cu")
		(net "GND")
	)
	(segment
		(start 418.945568 -392.004042)
		(end 418.945568 -391.784586)
		(width 0.254)
		(layer "F.Cu")
		(net "GND")
	)
	(segment
		(start 398.446752 -11.26998)
		(end 398.446752 -10.16635)
		(width 0.3556)
		(layer "F.Cu")
		(net "GND")
	)
	(segment
		(start 370.817902 -391.333482)
		(end 370.916454 -391.23493)
		(width 0.254)
		(layer "F.Cu")
		(net "GND")
	)
	(segment
		(start 133.398006 -227.740464)
		(end 133.864858 -227.474526)
		(width 0.350012)
		(layer "F.Cu")
		(net "GND")
	)
	(segment
		(start 374.77065 -392.999722)
		(end 374.718072 -392.30427)
		(width 0.254)
		(layer "F.Cu")
		(net "GND")
	)
	(segment
		(start 322.070476 -395.369034)
		(end 322.070476 -395.0208)
		(width 0.254)
		(layer "F.Cu")
		(net "GND")
	)
	(segment
		(start 265.54811 -303.585118)
		(end 266.93241 -303.585118)
		(width 0.4572)
		(layer "F.Cu")
		(net "GND")
	)
	(segment
		(start 176.694338 -30.871922)
		(end 176.694338 -30.338014)
		(width 0.254)
		(layer "F.Cu")
		(net "GND")
	)
	(segment
		(start 147.877022 -23.684992)
		(end 147.877022 -23.963376)
		(width 0.4572)
		(layer "F.Cu")
		(net "GND")
	)
	(segment
		(start 95.627952 -290.830254)
		(end 95.1611 -291.096192)
		(width 0.350012)
		(layer "F.Cu")
		(net "GND")
	)
	(segment
		(start 342.245442 -391.333482)
		(end 342.343994 -391.23493)
		(width 0.254)
		(layer "F.Cu")
		(net "GND")
	)
	(segment
		(start 346.19819 -398.542002)
		(end 345.51874 -398.542002)
		(width 0.254)
		(layer "F.Cu")
		(net "GND")
	)
	(segment
		(start 354.598224 -395.369034)
		(end 354.598224 -395.0208)
		(width 0.254)
		(layer "F.Cu")
		(net "GND")
	)
	(segment
		(start 333.39786 -253.660148)
		(end 332.931008 -253.39421)
		(width 0.350012)
		(layer "F.Cu")
		(net "GND")
	)
	(segment
		(start 450.088 -296.78503)
		(end 451.4723 -296.78503)
		(width 0.4572)
		(layer "F.Cu")
		(net "GND")
	)
	(segment
		(start 108.317792 -265.720322)
		(end 107.85094 -265.98626)
		(width 0.350012)
		(layer "F.Cu")
		(net "GND")
	)
	(segment
		(start 291.103812 -351.927922)
		(end 291.691822 -351.927922)
		(width 0.381)
		(layer "F.Cu")
		(net "GND")
	)
	(segment
		(start 127.117856 -272.20037)
		(end 127.584708 -272.466308)
		(width 0.350012)
		(layer "F.Cu")
		(net "GND")
	)
	(segment
		(start 141.38783 -226.930458)
		(end 141.854682 -226.66452)
		(width 0.350012)
		(layer "F.Cu")
		(net "GND")
	)
	(segment
		(start 89.047828 -271.390364)
		(end 88.580976 -271.656302)
		(width 0.350012)
		(layer "F.Cu")
		(net "GND")
	)
	(segment
		(start 375.503694 -180.918866)
		(end 375.075196 -180.918866)
		(width 0.2286)
		(layer "F.Cu")
		(net "GND")
	)
	(segment
		(start 375.617994 -399.663158)
		(end 375.917968 -399.143474)
		(width 0.254)
		(layer "F.Cu")
		(net "GND")
	)
	(segment
		(start 427.246288 -390.68629)
		(end 427.779688 -390.68629)
		(width 0.254)
		(layer "F.Cu")
		(net "GND")
	)
	(segment
		(start 382.94945 -412.212536)
		(end 382.94945 -411.264354)
		(width 0.381)
		(layer "F.Cu")
		(net "GND")
	)
	(segment
		(start 102.155498 -180.615082)
		(end 101.902514 -180.868066)
		(width 0.2286)
		(layer "F.Cu")
		(net "GND")
	)
	(segment
		(start 129.74574 -12.495784)
		(end 129.74574 -12.495022)
		(width 0.3556)
		(layer "F.Cu")
		(net "GND")
	)
	(segment
		(start 303.009046 -394.412978)
		(end 302.620934 -394.412978)
		(width 0.254)
		(layer "F.Cu")
		(net "GND")
	)
	(segment
		(start 446.644268 -209.23504)
		(end 445.259968 -209.23504)
		(width 0.4572)
		(layer "F.Cu")
		(net "GND")
	)
	(segment
		(start 326.81799 -226.120198)
		(end 326.351138 -225.85426)
		(width 0.350012)
		(layer "F.Cu")
		(net "GND")
	)
	(segment
		(start 64.518032 -383.402586)
		(end 64.518032 -382.951482)
		(width 0.254)
		(layer "F.Cu")
		(net "GND")
	)
	(segment
		(start 421.174418 -366.602264)
		(end 421.070278 -366.602264)
		(width 0.3556)
		(layer "F.Cu")
		(net "GND")
	)
	(segment
		(start 130.77063 -384.617722)
		(end 131.36245 -384.617722)
		(width 0.254)
		(layer "F.Cu")
		(net "GND")
	)
	(segment
		(start 124.937774 -229.360476)
		(end 125.404626 -229.094538)
		(width 0.350012)
		(layer "F.Cu")
		(net "GND")
	)
	(segment
		(start 129.938018 -262.480298)
		(end 130.40487 -262.746236)
		(width 0.350012)
		(layer "F.Cu")
		(net "GND")
	)
	(segment
		(start 160.58896 -105.776014)
		(end 161.082736 -105.776014)
		(width 0.381)
		(layer "F.Cu")
		(net "GND")
	)
	(segment
		(start 185.122058 -120.252744)
		(end 184.732168 -120.642634)
		(width 0.254)
		(layer "F.Cu")
		(net "GND")
	)
	(segment
		(start 105.497884 -283.540454)
		(end 105.031032 -283.806392)
		(width 0.350012)
		(layer "F.Cu")
		(net "GND")
	)
	(segment
		(start 79.347822 -222.070422)
		(end 78.88097 -221.804484)
		(width 0.350012)
		(layer "F.Cu")
		(net "GND")
	)
	(segment
		(start 49.666906 -10.16635)
		(end 49.665636 -10.16508)
		(width 0.3556)
		(layer "F.Cu")
		(net "GND")
	)
	(segment
		(start 318.117728 -399.663158)
		(end 318.417702 -399.143474)
		(width 0.254)
		(layer "F.Cu")
		(net "GND")
	)
	(segment
		(start 358.778048 -222.880174)
		(end 358.311196 -222.614236)
		(width 0.350012)
		(layer "F.Cu")
		(net "GND")
	)
	(segment
		(start 256.610358 -110.090204)
		(end 257.39471 -110.090204)
		(width 0.4572)
		(layer "F.Cu")
		(net "GND")
	)
	(segment
		(start 81.22793 -223.690434)
		(end 80.761078 -223.424496)
		(width 0.350012)
		(layer "F.Cu")
		(net "GND")
	)
	(segment
		(start 157.94609 -388.328662)
		(end 158.498286 -388.138924)
		(width 0.254)
		(layer "F.Cu")
		(net "GND")
	)
	(segment
		(start 55.066946 -12.372848)
		(end 55.066946 -11.26998)
		(width 0.3556)
		(layer "F.Cu")
		(net "GND")
	)
	(segment
		(start 101.437948 -224.50044)
		(end 100.971096 -224.234502)
		(width 0.350012)
		(layer "F.Cu")
		(net "GND")
	)
	(segment
		(start 34.82848 -368.867182)
		(end 34.82848 -369.506754)
		(width 0.381)
		(layer "F.Cu")
		(net "GND")
	)
	(segment
		(start 51.467004 -11.26998)
		(end 51.467004 -10.16635)
		(width 0.3556)
		(layer "F.Cu")
		(net "GND")
	)
	(segment
		(start 110.6678 -287.590484)
		(end 110.200948 -287.856422)
		(width 0.350012)
		(layer "F.Cu")
		(net "GND")
	)
	(segment
		(start 180.32222 -109.852968)
		(end 179.93233 -109.463078)
		(width 0.254)
		(layer "F.Cu")
		(net "GND")
	)
	(segment
		(start 84.987892 -223.690434)
		(end 84.52104 -223.424496)
		(width 0.350012)
		(layer "F.Cu")
		(net "GND")
	)
	(segment
		(start 132.927852 -231.79024)
		(end 133.394704 -231.524302)
		(width 0.350012)
		(layer "F.Cu")
		(net "GND")
	)
	(segment
		(start 404.290022 -392.999722)
		(end 403.698202 -392.999722)
		(width 0.254)
		(layer "F.Cu")
		(net "GND")
	)
	(segment
		(start 23.948136 -12.374118)
		(end 23.946866 -12.372848)
		(width 0.3556)
		(layer "F.Cu")
		(net "GND")
	)
	(segment
		(start 332.28788 -294.070024)
		(end 331.821028 -294.335962)
		(width 0.350012)
		(layer "F.Cu")
		(net "GND")
	)
	(segment
		(start 400.24558 -7.215886)
		(end 400.24685 -7.217156)
		(width 0.3556)
		(layer "F.Cu")
		(net "GND")
	)
	(segment
		(start 379.75794 -273.820128)
		(end 380.224792 -274.086066)
		(width 0.350012)
		(layer "F.Cu")
		(net "GND")
	)
	(segment
		(start 388.217918 -293.260018)
		(end 388.68477 -293.525956)
		(width 0.350012)
		(layer "F.Cu")
		(net "GND")
	)
	(segment
		(start 352.497898 -288.399982)
		(end 352.031046 -288.66592)
		(width 0.350012)
		(layer "F.Cu")
		(net "GND")
	)
	(segment
		(start 130.407918 -279.490424)
		(end 130.87477 -279.756362)
		(width 0.350012)
		(layer "F.Cu")
		(net "GND")
	)
	(segment
		(start 374.28805 -233.409998)
		(end 374.754902 -233.14406)
		(width 0.350012)
		(layer "F.Cu")
		(net "GND")
	)
	(segment
		(start 139.80795 -289.210242)
		(end 140.274802 -289.47618)
		(width 0.350012)
		(layer "F.Cu")
		(net "GND")
	)
	(segment
		(start 366.63249 -393.04468)
		(end 367.16589 -393.04468)
		(width 0.254)
		(layer "F.Cu")
		(net "GND")
	)
	(segment
		(start 122.891296 -390.160002)
		(end 122.370596 -390.160002)
		(width 0.254)
		(layer "F.Cu")
		(net "GND")
	)
	(segment
		(start 386.97789 -224.500186)
		(end 387.444742 -224.234248)
		(width 0.350012)
		(layer "F.Cu")
		(net "GND")
	)
	(segment
		(start 114.127788 -236.650276)
		(end 114.59464 -236.384338)
		(width 0.350012)
		(layer "F.Cu")
		(net "GND")
	)
	(segment
		(start 61.218064 -390.761474)
		(end 60.91809 -391.281158)
		(width 0.254)
		(layer "F.Cu")
		(net "GND")
	)
	(segment
		(start 48.918114 -383.402586)
		(end 48.918114 -383.622296)
		(width 0.254)
		(layer "F.Cu")
		(net "GND")
	)
	(segment
		(start 46.401736 -387.231128)
		(end 46.621192 -387.231128)
		(width 0.254)
		(layer "F.Cu")
		(net "GND")
	)
	(segment
		(start 21.70811 -239.835436)
		(end 20.32381 -239.835436)
		(width 0.4572)
		(layer "F.Cu")
		(net "GND")
	)
	(segment
		(start 370.505228 -143.910558)
		(end 369.895628 -144.520158)
		(width 0.4572)
		(layer "F.Cu")
		(net "GND")
	)
	(segment
		(start 351.087944 -281.110182)
		(end 350.621092 -281.37612)
		(width 0.350012)
		(layer "F.Cu")
		(net "GND")
	)
	(segment
		(start 384.018028 -399.663158)
		(end 384.11658 -399.76171)
		(width 0.254)
		(layer "F.Cu")
		(net "GND")
	)
	(segment
		(start 306.216304 -399.76171)
		(end 306.117752 -399.663158)
		(width 0.254)
		(layer "F.Cu")
		(net "GND")
	)
	(segment
		(start 165.942518 -384.831082)
		(end 165.942518 -385.21132)
		(width 0.254)
		(layer "F.Cu")
		(net "GND")
	)
	(segment
		(start 307.368194 -312.084974)
		(end 305.983894 -312.084974)
		(width 0.4572)
		(layer "F.Cu")
		(net "GND")
	)
	(segment
		(start 105.66781 -251.230384)
		(end 105.200958 -250.964446)
		(width 0.350012)
		(layer "F.Cu")
		(net "GND")
	)
	(segment
		(start 365.828072 -233.409998)
		(end 366.294924 -233.14406)
		(width 0.350012)
		(layer "F.Cu")
		(net "GND")
	)
	(segment
		(start 424.012106 -274.684998)
		(end 422.627806 -274.684998)
		(width 0.4572)
		(layer "F.Cu")
		(net "GND")
	)
	(segment
		(start 64.518032 -383.402586)
		(end 64.518032 -383.622296)
		(width 0.254)
		(layer "F.Cu")
		(net "GND")
	)
	(segment
		(start 334.109568 -396.813024)
		(end 333.632556 -396.67815)
		(width 0.254)
		(layer "F.Cu")
		(net "GND")
	)
	(segment
		(start 97.577402 -71.21398)
		(end 98.187002 -71.21398)
		(width 0.4572)
		(layer "F.Cu")
		(net "GND")
	)
	(segment
		(start 46.16704 -436.372)
		(end 46.82236 -436.372)
		(width 0.381)
		(layer "F.Cu")
		(net "GND")
	)
	(segment
		(start 360.957876 -291.640006)
		(end 361.424728 -291.905944)
		(width 0.350012)
		(layer "F.Cu")
		(net "GND")
	)
	(segment
		(start 427.765718 -7.215124)
		(end 427.765718 -7.215886)
		(width 0.3556)
		(layer "F.Cu")
		(net "GND")
	)
	(segment
		(start 409.345638 -392.004296)
		(end 409.645612 -392.30427)
		(width 0.254)
		(layer "F.Cu")
		(net "GND")
	)
	(segment
		(start 284.736032 -305.28514)
		(end 283.351732 -305.28514)
		(width 0.4572)
		(layer "F.Cu")
		(net "GND")
	)
	(segment
		(start 417.745672 -391.784586)
		(end 417.745672 -391.333482)
		(width 0.254)
		(layer "F.Cu")
		(net "GND")
	)
	(segment
		(start 142.797784 -229.360476)
		(end 143.264636 -229.094538)
		(width 0.350012)
		(layer "F.Cu")
		(net "GND")
	)
	(segment
		(start 236.599984 -53.364892)
		(end 237.616238 -53.364892)
		(width 0.381)
		(layer "F.Cu")
		(net "GND")
	)
	(segment
		(start 374.77065 -396.520924)
		(end 374.218454 -396.710662)
		(width 0.254)
		(layer "F.Cu")
		(net "GND")
	)
	(segment
		(start 409.006294 -394.831062)
		(end 408.498294 -395.0208)
		(width 0.254)
		(layer "F.Cu")
		(net "GND")
	)
	(segment
		(start 81.058004 -262.480298)
		(end 80.591152 -262.746236)
		(width 0.350012)
		(layer "F.Cu")
		(net "GND")
	)
	(segment
		(start 292.280086 -209.23504)
		(end 290.895786 -209.23504)
		(width 0.4572)
		(layer "F.Cu")
		(net "GND")
	)
	(segment
		(start 383.67843 -394.831062)
		(end 383.17043 -395.0208)
		(width 0.254)
		(layer "F.Cu")
		(net "GND")
	)
	(segment
		(start 26.554684 -394.733526)
		(end 26.484326 -394.733526)
		(width 0.4572)
		(layer "F.Cu")
		(net "GND")
	)
	(segment
		(start 95.627952 -271.390364)
		(end 95.1611 -271.656302)
		(width 0.350012)
		(layer "F.Cu")
		(net "GND")
	)
	(segment
		(start 108.487972 -239.8903)
		(end 108.02112 -239.624362)
		(width 0.350012)
		(layer "F.Cu")
		(net "GND")
	)
	(segment
		(start 420.156894 -11.26998)
		(end 420.156894 -10.16635)
		(width 0.3556)
		(layer "F.Cu")
		(net "GND")
	)
	(segment
		(start 106.137964 -240.700306)
		(end 105.671112 -240.434368)
		(width 0.350012)
		(layer "F.Cu")
		(net "GND")
	)
	(segment
		(start 90.198448 -386.6388)
		(end 89.506298 -386.449062)
		(width 0.254)
		(layer "F.Cu")
		(net "GND")
	)
	(segment
		(start 322.31457 -395.613128)
		(end 322.31457 -396.213076)
		(width 0.254)
		(layer "F.Cu")
		(net "GND")
	)
	(segment
		(start 328.697844 -253.660148)
		(end 328.231246 -253.39421)
		(width 0.350012)
		(layer "F.Cu")
		(net "GND")
	)
	(segment
		(start 292.280086 -230.485188)
		(end 290.895786 -230.485188)
		(width 0.4572)
		(layer "F.Cu")
		(net "GND")
	)
	(segment
		(start 183.616092 -314.635388)
		(end 182.231792 -314.635388)
		(width 0.4572)
		(layer "F.Cu")
		(net "GND")
	)
	(segment
		(start 105.027984 -294.070278)
		(end 104.561132 -294.336216)
		(width 0.350012)
		(layer "F.Cu")
		(net "GND")
	)
	(segment
		(start 393.558014 -224.500186)
		(end 394.024866 -224.234248)
		(width 0.350012)
		(layer "F.Cu")
		(net "GND")
	)
	(segment
		(start 166.162228 -387.831076)
		(end 166.462202 -388.13105)
		(width 0.254)
		(layer "F.Cu")
		(net "GND")
	)
	(segment
		(start 442.34862 -397.720312)
		(end 442.731906 -397.720312)
		(width 0.2032)
		(layer "F.Cu")
		(net "GND")
	)
	(segment
		(start 82.645758 -383.402586)
		(end 82.645758 -383.622296)
		(width 0.254)
		(layer "F.Cu")
		(net "GND")
	)
	(segment
		(start 126.58979 -27.463496)
		(end 126.22911 -27.463496)
		(width 0.3556)
		(layer "F.Cu")
		(net "GND")
	)
	(segment
		(start 80.11795 -268.960346)
		(end 79.651098 -269.226284)
		(width 0.350012)
		(layer "F.Cu")
		(net "GND")
	)
	(segment
		(start 410.89834 -392.999722)
		(end 410.845762 -392.30427)
		(width 0.254)
		(layer "F.Cu")
		(net "GND")
	)
	(segment
		(start 182.710836 -92.274898)
		(end 182.710836 -91.701112)
		(width 0.4572)
		(layer "F.Cu")
		(net "GND")
	)
	(segment
		(start 118.091204 -390.160002)
		(end 117.570504 -390.160002)
		(width 0.254)
		(layer "F.Cu")
		(net "GND")
	)
	(segment
		(start 50.52695 -433.578)
		(end 50.52695 -433.127658)
		(width 0.381)
		(layer "F.Cu")
		(net "GND")
	)
	(segment
		(start 314.517786 -392.004296)
		(end 314.81776 -392.30427)
		(width 0.254)
		(layer "F.Cu")
		(net "GND")
	)
	(segment
		(start 416.468052 -314.635134)
		(end 415.083752 -314.635134)
		(width 0.4572)
		(layer "F.Cu")
		(net "GND")
	)
	(segment
		(start 120.537986 -277.060406)
		(end 121.004838 -277.326344)
		(width 0.350012)
		(layer "F.Cu")
		(net "GND")
	)
	(segment
		(start 378.048012 -236.650022)
		(end 378.514864 -236.384084)
		(width 0.350012)
		(layer "F.Cu")
		(net "GND")
	)
	(segment
		(start 383.217928 -222.880174)
		(end 383.68478 -222.614236)
		(width 0.350012)
		(layer "F.Cu")
		(net "GND")
	)
	(segment
		(start 353.144074 -399.76171)
		(end 353.045522 -399.663158)
		(width 0.254)
		(layer "F.Cu")
		(net "GND")
	)
	(segment
		(start 179.83835 -353.373436)
		(end 180.091334 -353.120452)
		(width 0.2286)
		(layer "F.Cu")
		(net "GND")
	)
	(segment
		(start 138.397996 -262.480298)
		(end 138.864848 -262.746236)
		(width 0.350012)
		(layer "F.Cu")
		(net "GND")
	)
	(segment
		(start 363.00791 -228.550216)
		(end 363.474762 -228.284278)
		(width 0.350012)
		(layer "F.Cu")
		(net "GND")
	)
	(segment
		(start 341.387938 -226.930204)
		(end 340.921086 -226.664266)
		(width 0.350012)
		(layer "F.Cu")
		(net "GND")
	)
	(segment
		(start 115.83797 -283.540454)
		(end 116.304822 -283.806392)
		(width 0.350012)
		(layer "F.Cu")
		(net "GND")
	)
	(segment
		(start 378.048012 -233.409998)
		(end 378.514864 -233.14406)
		(width 0.350012)
		(layer "F.Cu")
		(net "GND")
	)
	(segment
		(start 423.9514 -39.817548)
		(end 422.9354 -39.817548)
		(width 0.4572)
		(layer "F.Cu")
		(net "GND")
	)
	(segment
		(start 392.490706 -180.386736)
		(end 392.490706 -180.665882)
		(width 0.2286)
		(layer "F.Cu")
		(net "GND")
	)
	(segment
		(start 21.70811 -277.235412)
		(end 20.32381 -277.235412)
		(width 0.4572)
		(layer "F.Cu")
		(net "GND")
	)
	(segment
		(start 396.645638 -7.215886)
		(end 396.646908 -7.217156)
		(width 0.3556)
		(layer "F.Cu")
		(net "GND")
	)
	(segment
		(start 346.858082 -291.640006)
		(end 346.39123 -291.905944)
		(width 0.350012)
		(layer "F.Cu")
		(net "GND")
	)
	(segment
		(start 95.327978 -226.930458)
		(end 94.861126 -226.66452)
		(width 0.350012)
		(layer "F.Cu")
		(net "GND")
	)
	(segment
		(start 29.346906 -7.217156)
		(end 29.346906 -8.320024)
		(width 0.3556)
		(layer "F.Cu")
		(net "GND")
	)
	(segment
		(start 21.70811 -211.7852)
		(end 20.32381 -211.7852)
		(width 0.4572)
		(layer "F.Cu")
		(net "GND")
	)
	(segment
		(start 356.42804 -239.890046)
		(end 355.961188 -239.624108)
		(width 0.350012)
		(layer "F.Cu")
		(net "GND")
	)
	(segment
		(start 383.048002 -292.450012)
		(end 383.514854 -292.71595)
		(width 0.350012)
		(layer "F.Cu")
		(net "GND")
	)
	(segment
		(start 336.987896 -277.870158)
		(end 336.521044 -278.136096)
		(width 0.350012)
		(layer "F.Cu")
		(net "GND")
	)
	(segment
		(start 202.147932 -231.335326)
		(end 203.532232 -231.335326)
		(width 0.4572)
		(layer "F.Cu")
		(net "GND")
	)
	(segment
		(start 357.668068 -266.530074)
		(end 357.201216 -266.796012)
		(width 0.350012)
		(layer "F.Cu")
		(net "GND")
	)
	(segment
		(start 311.270396 -396.520924)
		(end 311.91835 -396.710662)
		(width 0.254)
		(layer "F.Cu")
		(net "GND")
	)
	(segment
		(start 370.357908 -267.34008)
		(end 370.82476 -267.606018)
		(width 0.350012)
		(layer "F.Cu")
		(net "GND")
	)
	(segment
		(start 319.99809 -35.573462)
		(end 318.81699 -35.573462)
		(width 0.3556)
		(layer "F.Cu")
		(net "GND")
	)
	(segment
		(start 136.517888 -260.860286)
		(end 136.98474 -261.126224)
		(width 0.350012)
		(layer "F.Cu")
		(net "GND")
	)
	(segment
		(start 89.047828 -290.830254)
		(end 88.580976 -291.096192)
		(width 0.350012)
		(layer "F.Cu")
		(net "GND")
	)
	(segment
		(start 359.078022 -283.5402)
		(end 358.61117 -283.806138)
		(width 0.350012)
		(layer "F.Cu")
		(net "GND")
	)
	(segment
		(start 50.417984 -383.92227)
		(end 50.470562 -384.617722)
		(width 0.254)
		(layer "F.Cu")
		(net "GND")
	)
	(segment
		(start 83.877912 -286.780478)
		(end 83.41106 -287.046162)
		(width 0.350012)
		(layer "F.Cu")
		(net "GND")
	)
	(segment
		(start 59.428126 -227.935282)
		(end 58.043826 -227.935282)
		(width 0.4572)
		(layer "F.Cu")
		(net "GND")
	)
	(segment
		(start 76.359512 -336.81289)
		(end 76.364592 -336.81797)
		(width 0.2286)
		(layer "F.Cu")
		(net "GND")
	)
	(segment
		(start 93.747844 -271.390364)
		(end 93.280992 -271.656302)
		(width 0.350012)
		(layer "F.Cu")
		(net "GND")
	)
	(segment
		(start 133.227826 -292.450266)
		(end 133.694678 -292.716204)
		(width 0.350012)
		(layer "F.Cu")
		(net "GND")
	)
	(segment
		(start 128.227836 -252.850396)
		(end 128.694688 -252.584458)
		(width 0.350012)
		(layer "F.Cu")
		(net "GND")
	)
	(segment
		(start 90.627962 -256.09042)
		(end 90.16111 -255.824482)
		(width 0.350012)
		(layer "F.Cu")
		(net "GND")
	)
	(segment
		(start 303.268126 -212.635084)
		(end 304.652426 -212.635084)
		(width 0.4572)
		(layer "F.Cu")
		(net "GND")
	)
	(segment
		(start 353.989894 -392.999722)
		(end 353.398074 -392.999722)
		(width 0.254)
		(layer "F.Cu")
		(net "GND")
	)
	(segment
		(start 187.060078 -228.78542)
		(end 188.444378 -228.78542)
		(width 0.4572)
		(layer "F.Cu")
		(net "GND")
	)
	(segment
		(start 365.657892 -270.580104)
		(end 366.124744 -270.846042)
		(width 0.350012)
		(layer "F.Cu")
		(net "GND")
	)
	(segment
		(start 78.109826 -388.431024)
		(end 77.632814 -388.29615)
		(width 0.254)
		(layer "F.Cu")
		(net "GND")
	)
	(segment
		(start 334.629252 -395.313154)
		(end 334.929226 -395.613128)
		(width 0.254)
		(layer "F.Cu")
		(net "GND")
	)
	(segment
		(start 372.877842 -229.360222)
		(end 373.344694 -229.094284)
		(width 0.350012)
		(layer "F.Cu")
		(net "GND")
	)
	(segment
		(start 76.07173 -385.59359)
		(end 76.0603 -385.58216)
		(width 0.254)
		(layer "F.Cu")
		(net "GND")
	)
	(segment
		(start 424.418252 -402.284946)
		(end 424.418252 -401.892262)
		(width 0.254)
		(layer "F.Cu")
		(net "GND")
	)
	(segment
		(start 157.044136 -391.37971)
		(end 156.945584 -391.281158)
		(width 0.254)
		(layer "F.Cu")
		(net "GND")
	)
	(segment
		(start 320.517774 -399.663158)
		(end 320.817748 -399.143474)
		(width 0.254)
		(layer "F.Cu")
		(net "GND")
	)
	(segment
		(start 441.23356 -435.199282)
		(end 441.86856 -435.199282)
		(width 0.4318)
		(layer "F.Cu")
		(net "GND")
	)
	(segment
		(start 20.677886 -359.918)
		(end 21.336 -359.918)
		(width 0.381)
		(layer "F.Cu")
		(net "GND")
	)
	(segment
		(start 350.809306 -159.061404)
		(end 350.556322 -159.314388)
		(width 0.2286)
		(layer "F.Cu")
		(net "GND")
	)
	(segment
		(start 354.078032 -232.599992)
		(end 353.61118 -232.334054)
		(width 0.350012)
		(layer "F.Cu")
		(net "GND")
	)
	(segment
		(start 318.21628 -399.76171)
		(end 318.117728 -399.663158)
		(width 0.254)
		(layer "F.Cu")
		(net "GND")
	)
	(segment
		(start 46.518068 -382.957578)
		(end 46.468538 -382.908048)
		(width 0.254)
		(layer "F.Cu")
		(net "GND")
	)
	(segment
		(start 54.718458 -388.328662)
		(end 55.270654 -388.138924)
		(width 0.254)
		(layer "F.Cu")
		(net "GND")
	)
	(segment
		(start 66.614802 -384.531108)
		(end 66.314828 -384.831082)
		(width 0.254)
		(layer "F.Cu")
		(net "GND")
	)
	(segment
		(start 183.616092 -221.135194)
		(end 182.231792 -221.135194)
		(width 0.4572)
		(layer "F.Cu")
		(net "GND")
	)
	(segment
		(start 333.697834 -281.920188)
		(end 333.230982 -282.186126)
		(width 0.350012)
		(layer "F.Cu")
		(net "GND")
	)
	(segment
		(start 25.152096 -228.78542)
		(end 26.536396 -228.78542)
		(width 0.4572)
		(layer "F.Cu")
		(net "GND")
	)
	(segment
		(start 33.81248 -368.867182)
		(end 33.81248 -369.506754)
		(width 0.381)
		(layer "F.Cu")
		(net "GND")
	)
	(segment
		(start 384.72999 -179.678584)
		(end 384.233166 -180.175408)
		(width 0.2286)
		(layer "F.Cu")
		(net "GND")
	)
	(segment
		(start 346.087954 -249.610118)
		(end 345.621102 -249.34418)
		(width 0.350012)
		(layer "F.Cu")
		(net "GND")
	)
	(segment
		(start 52.870608 -388.138924)
		(end 53.518562 -388.328662)
		(width 0.254)
		(layer "F.Cu")
		(net "GND")
	)
	(segment
		(start 325.70801 -284.350206)
		(end 325.052944 -284.350206)
		(width 0.350012)
		(layer "F.Cu")
		(net "GND")
	)
	(segment
		(start 365.357918 -243.940076)
		(end 365.82477 -243.674138)
		(width 0.350012)
		(layer "F.Cu")
		(net "GND")
	)
	(segment
		(start 88.577928 -294.880284)
		(end 88.111076 -295.146222)
		(width 0.350012)
		(layer "F.Cu")
		(net "GND")
	)
	(segment
		(start 156.945584 -391.281158)
		(end 157.245812 -390.761474)
		(width 0.254)
		(layer "F.Cu")
		(net "GND")
	)
	(segment
		(start 160.346136 -388.328662)
		(end 159.698182 -388.138924)
		(width 0.254)
		(layer "F.Cu")
		(net "GND")
	)
	(segment
		(start 345.599766 -29.51607)
		(end 345.599766 -30.57652)
		(width 0.4572)
		(layer "F.Cu")
		(net "GND")
	)
	(segment
		(start 53.594 -434.109114)
		(end 53.620162 -434.082952)
		(width 0.381)
		(layer "F.Cu")
		(net "GND")
	)
	(segment
		(start 350.78797 -244.750082)
		(end 350.321118 -244.484144)
		(width 0.350012)
		(layer "F.Cu")
		(net "GND")
	)
	(segment
		(start 206.248 -211.7852)
		(end 204.8637 -211.7852)
		(width 0.4572)
		(layer "F.Cu")
		(net "GND")
	)
	(segment
		(start 102.847902 -231.79024)
		(end 102.38105 -231.524302)
		(width 0.350012)
		(layer "F.Cu")
		(net "GND")
	)
	(segment
		(start 139.80795 -281.110436)
		(end 140.274802 -281.376374)
		(width 0.350012)
		(layer "F.Cu")
		(net "GND")
	)
	(segment
		(start 385.39801 -294.88003)
		(end 385.864862 -295.145968)
		(width 0.350012)
		(layer "F.Cu")
		(net "GND")
	)
	(segment
		(start 378.817886 -268.960092)
		(end 379.284738 -269.22603)
		(width 0.350012)
		(layer "F.Cu")
		(net "GND")
	)
	(segment
		(start 123.685046 -27.929586)
		(end 123.685046 -27.07894)
		(width 0.4572)
		(layer "F.Cu")
		(net "GND")
	)
	(segment
		(start 389.93445 -393.513056)
		(end 389.93445 -392.913108)
		(width 0.254)
		(layer "F.Cu")
		(net "GND")
	)
	(segment
		(start 126.347982 -239.8903)
		(end 126.814834 -239.624362)
		(width 0.350012)
		(layer "F.Cu")
		(net "GND")
	)
	(segment
		(start 107.377992 -293.260272)
		(end 106.91114 -293.52621)
		(width 0.350012)
		(layer "F.Cu")
		(net "GND")
	)
	(segment
		(start 383.117852 -399.143474)
		(end 383.17043 -398.542002)
		(width 0.254)
		(layer "F.Cu")
		(net "GND")
	)
	(segment
		(start 294.369744 -18.780506)
		(end 293.516558 -18.780506)
		(width 0.3556)
		(layer "F.Cu")
		(net "GND")
	)
	(segment
		(start 202.147932 -278.085296)
		(end 203.532232 -278.085296)
		(width 0.4572)
		(layer "F.Cu")
		(net "GND")
	)
	(segment
		(start 349.67799 -285.160212)
		(end 349.211138 -285.42615)
		(width 0.350012)
		(layer "F.Cu")
		(net "GND")
	)
	(segment
		(start 55.328058 -287.43529)
		(end 56.712358 -287.43529)
		(width 0.4572)
		(layer "F.Cu")
		(net "GND")
	)
	(segment
		(start 328.227944 -231.789986)
		(end 327.761092 -231.524048)
		(width 0.350012)
		(layer "F.Cu")
		(net "GND")
	)
	(segment
		(start 102.207822 -268.15034)
		(end 101.74097 -268.416278)
		(width 0.350012)
		(layer "F.Cu")
		(net "GND")
	)
	(segment
		(start 384.513328 -138.170158)
		(end 385.933442 -138.170158)
		(width 0.381)
		(layer "F.Cu")
		(net "GND")
	)
	(segment
		(start 369.72113 -398.01292)
		(end 369.72113 -397.412972)
		(width 0.254)
		(layer "F.Cu")
		(net "GND")
	)
	(segment
		(start 346.858082 -281.920188)
		(end 346.39123 -282.186126)
		(width 0.350012)
		(layer "F.Cu")
		(net "GND")
	)
	(segment
		(start 51.884072 -295.9354)
		(end 50.499772 -295.9354)
		(width 0.4572)
		(layer "F.Cu")
		(net "GND")
	)
	(segment
		(start 151.819102 -390.160002)
		(end 151.298402 -390.160002)
		(width 0.254)
		(layer "F.Cu")
		(net "GND")
	)
	(segment
		(start 187.522104 -113.05286)
		(end 187.911994 -112.66297)
		(width 0.254)
		(layer "F.Cu")
		(net "GND")
	)
	(segment
		(start 349.378016 -235.840016)
		(end 348.911164 -235.574078)
		(width 0.350012)
		(layer "F.Cu")
		(net "GND")
	)
	(segment
		(start 366.597946 -267.34008)
		(end 367.064798 -267.606018)
		(width 0.350012)
		(layer "F.Cu")
		(net "GND")
	)
	(segment
		(start 350.78797 -233.409998)
		(end 350.321118 -233.14406)
		(width 0.350012)
		(layer "F.Cu")
		(net "GND")
	)
	(segment
		(start 139.80795 -282.730448)
		(end 140.274802 -282.996386)
		(width 0.350012)
		(layer "F.Cu")
		(net "GND")
	)
	(segment
		(start 93.91777 -240.700306)
		(end 93.450918 -240.434368)
		(width 0.350012)
		(layer "F.Cu")
		(net "GND")
	)
	(segment
		(start 347.497908 -239.08004)
		(end 347.031056 -238.814102)
		(width 0.350012)
		(layer "F.Cu")
		(net "GND")
	)
	(segment
		(start 182.722012 -116.252752)
		(end 182.332122 -116.642642)
		(width 0.254)
		(layer "F.Cu")
		(net "GND")
	)
	(segment
		(start 342.158066 -278.680164)
		(end 341.691214 -278.946102)
		(width 0.350012)
		(layer "F.Cu")
		(net "GND")
	)
	(segment
		(start 126.817882 -248.800366)
		(end 127.284734 -248.534428)
		(width 0.350012)
		(layer "F.Cu")
		(net "GND")
	)
	(segment
		(start 102.677976 -270.580358)
		(end 102.211124 -270.846296)
		(width 0.350012)
		(layer "F.Cu")
		(net "GND")
	)
	(segment
		(start 113.187988 -236.650276)
		(end 113.65484 -236.384338)
		(width 0.350012)
		(layer "F.Cu")
		(net "GND")
	)
	(segment
		(start 35.649662 -418.239448)
		(end 35.649662 -418.849048)
		(width 0.3556)
		(layer "F.Cu")
		(net "GND")
	)
	(segment
		(start 186.722004 -117.052852)
		(end 187.111894 -117.442742)
		(width 0.254)
		(layer "F.Cu")
		(net "GND")
	)
	(segment
		(start 187.316872 -429.330612)
		(end 187.43549 -429.330612)
		(width 0.381)
		(layer "F.Cu")
		(net "GND")
	)
	(segment
		(start 13.67155 -107.123484)
		(end 13.67155 -107.24515)
		(width 0.3556)
		(layer "F.Cu")
		(net "GND")
	)
	(segment
		(start 435.000146 -231.335072)
		(end 436.384446 -231.335072)
		(width 0.4572)
		(layer "F.Cu")
		(net "GND")
	)
	(segment
		(start 421.146224 -396.710662)
		(end 420.49827 -396.520924)
		(width 0.254)
		(layer "F.Cu")
		(net "GND")
	)
	(segment
		(start 136.217914 -240.700306)
		(end 136.684766 -240.434368)
		(width 0.350012)
		(layer "F.Cu")
		(net "GND")
	)
	(segment
		(start 433.166774 -11.26998)
		(end 433.166774 -12.372848)
		(width 0.3556)
		(layer "F.Cu")
		(net "GND")
	)
	(segment
		(start 128.69799 -250.420378)
		(end 129.164842 -250.15444)
		(width 0.350012)
		(layer "F.Cu")
		(net "GND")
	)
	(segment
		(start 307.368194 -305.28514)
		(end 305.983894 -305.28514)
		(width 0.4572)
		(layer "F.Cu")
		(net "GND")
	)
	(segment
		(start 337.106006 -394.831062)
		(end 336.598006 -395.0208)
		(width 0.254)
		(layer "F.Cu")
		(net "GND")
	)
	(segment
		(start 135.107934 -277.870412)
		(end 135.574786 -278.13635)
		(width 0.350012)
		(layer "F.Cu")
		(net "GND")
	)
	(segment
		(start 145.640552 -107.03306)
		(end 146.282918 -107.03306)
		(width 0.4572)
		(layer "F.Cu")
		(net "GND")
	)
	(segment
		(start 250.15952 -67.254374)
		(end 249.54357 -67.254374)
		(width 0.4572)
		(layer "F.Cu")
		(net "GND")
	)
	(segment
		(start 399.171668 -396.679674)
		(end 399.818606 -396.679674)
		(width 0.254)
		(layer "F.Cu")
		(net "GND")
	)
	(segment
		(start 74.357738 -402.834094)
		(end 73.361296 -403.830536)
		(width 0.381)
		(layer "F.Cu")
		(net "GND")
	)
	(segment
		(start 358.778048 -239.08004)
		(end 358.311196 -238.814102)
		(width 0.350012)
		(layer "F.Cu")
		(net "GND")
	)
	(segment
		(start 308.82336 -433.542694)
		(end 309.08625 -433.279804)
		(width 0.381)
		(layer "F.Cu")
		(net "GND")
	)
	(segment
		(start 327.117964 -267.34008)
		(end 326.651112 -267.606018)
		(width 0.350012)
		(layer "F.Cu")
		(net "GND")
	)
	(segment
		(start 96.737932 -234.220258)
		(end 96.27108 -233.95432)
		(width 0.350012)
		(layer "F.Cu")
		(net "GND")
	)
	(segment
		(start 122.68708 -30.178502)
		(end 123.323604 -30.815026)
		(width 0.3556)
		(layer "F.Cu")
		(net "GND")
	)
	(segment
		(start 63.317882 -383.402586)
		(end 63.317882 -382.951482)
		(width 0.254)
		(layer "F.Cu")
		(net "GND")
	)
	(segment
		(start 140.27785 -278.680418)
		(end 140.744702 -278.946356)
		(width 0.350012)
		(layer "F.Cu")
		(net "GND")
	)
	(segment
		(start 116.002054 -166.711884)
		(end 115.932204 -166.781734)
		(width 0.381)
		(layer "F.Cu")
		(net "GND")
	)
	(segment
		(start 431.55616 -230.485188)
		(end 430.17186 -230.485188)
		(width 0.4572)
		(layer "F.Cu")
		(net "GND")
	)
	(segment
		(start 360.235246 -62.0903)
		(end 359.313226 -62.0903)
		(width 0.381)
		(layer "F.Cu")
		(net "GND")
	)
	(segment
		(start 108.017818 -232.600246)
		(end 107.550966 -232.334308)
		(width 0.350012)
		(layer "F.Cu")
		(net "GND")
	)
	(segment
		(start 138.397996 -260.860286)
		(end 138.864848 -261.126224)
		(width 0.350012)
		(layer "F.Cu")
		(net "GND")
	)
	(segment
		(start 424.012106 -295.935146)
		(end 422.627806 -295.935146)
		(width 0.4572)
		(layer "F.Cu")
		(net "GND")
	)
	(segment
		(start 328.227944 -252.850142)
		(end 327.761092 -252.584204)
		(width 0.350012)
		(layer "F.Cu")
		(net "GND")
	)
	(segment
		(start 367.238026 -222.880174)
		(end 367.704878 -222.614236)
		(width 0.350012)
		(layer "F.Cu")
		(net "GND")
	)
	(segment
		(start 110.83798 -229.360476)
		(end 110.371128 -229.094538)
		(width 0.350012)
		(layer "F.Cu")
		(net "GND")
	)
	(segment
		(start 358.778048 -234.220004)
		(end 358.311196 -233.954066)
		(width 0.350012)
		(layer "F.Cu")
		(net "GND")
	)
	(segment
		(start 94.217998 -262.480298)
		(end 93.751146 -262.746236)
		(width 0.350012)
		(layer "F.Cu")
		(net "GND")
	)
	(segment
		(start 51.577494 -32.677608)
		(end 51.577494 -33.314132)
		(width 0.4572)
		(layer "F.Cu")
		(net "GND")
	)
	(segment
		(start 458.487526 -92.515182)
		(end 458.487526 -92.977462)
		(width 0.3556)
		(layer "F.Cu")
		(net "GND")
	)
	(segment
		(start 89.646252 -388.328662)
		(end 88.998298 -388.138924)
		(width 0.254)
		(layer "F.Cu")
		(net "GND")
	)
	(segment
		(start 360.657902 -243.940076)
		(end 361.124754 -243.674138)
		(width 0.350012)
		(layer "F.Cu")
		(net "GND")
	)
	(segment
		(start 424.166792 -9.423654)
		(end 424.168062 -9.424924)
		(width 0.3556)
		(layer "F.Cu")
		(net "GND")
	)
	(segment
		(start 40.23995 -219.435426)
		(end 41.62425 -219.435426)
		(width 0.4572)
		(layer "F.Cu")
		(net "GND")
	)
	(segment
		(start 153.249884 -323.747892)
		(end 153.249884 -322.731892)
		(width 0.4064)
		(layer "F.Cu")
		(net "GND")
	)
	(segment
		(start 138.098022 -253.660402)
		(end 138.564874 -253.394464)
		(width 0.350012)
		(layer "F.Cu")
		(net "GND")
	)
	(segment
		(start 156.519626 -122.769884)
		(end 157.812486 -122.769884)
		(width 0.4572)
		(layer "F.Cu")
		(net "GND")
	)
	(segment
		(start 87.167974 -284.35046)
		(end 86.701122 -284.616398)
		(width 0.350012)
		(layer "F.Cu")
		(net "GND")
	)
	(segment
		(start 98.344736 -119.50573)
		(end 98.344736 -120.12168)
		(width 0.4064)
		(layer "F.Cu")
		(net "GND")
	)
	(segment
		(start 358.778048 -232.599992)
		(end 358.311196 -232.334054)
		(width 0.350012)
		(layer "F.Cu")
		(net "GND")
	)
	(segment
		(start 102.207822 -266.530328)
		(end 101.74097 -266.796266)
		(width 0.350012)
		(layer "F.Cu")
		(net "GND")
	)
	(segment
		(start 338.39785 -262.480044)
		(end 337.930998 -262.745982)
		(width 0.350012)
		(layer "F.Cu")
		(net "GND")
	)
	(segment
		(start 446.522602 -418.56406)
		(end 446.522602 -417.46551)
		(width 0.4572)
		(layer "F.Cu")
		(net "GND")
	)
	(segment
		(start 130.407918 -266.530328)
		(end 130.87477 -266.796266)
		(width 0.350012)
		(layer "F.Cu")
		(net "GND")
	)
	(segment
		(start 346.19819 -396.520924)
		(end 345.645994 -396.710662)
		(width 0.254)
		(layer "F.Cu")
		(net "GND")
	)
	(segment
		(start 55.016654 -391.37971)
		(end 54.918102 -391.281158)
		(width 0.254)
		(layer "F.Cu")
		(net "GND")
	)
	(segment
		(start 353.907852 -290.83)
		(end 353.441 -291.095938)
		(width 0.350012)
		(layer "F.Cu")
		(net "GND")
	)
	(segment
		(start 320.616326 -402.309838)
		(end 320.616326 -402.890736)
		(width 0.3048)
		(layer "F.Cu")
		(net "GND")
	)
	(segment
		(start 92.037916 -253.660402)
		(end 91.571064 -253.394464)
		(width 0.350012)
		(layer "F.Cu")
		(net "GND")
	)
	(segment
		(start 180.710332 -92.27439)
		(end 180.710332 -91.669616)
		(width 0.4572)
		(layer "F.Cu")
		(net "GND")
	)
	(segment
		(start 103.317802 -229.360476)
		(end 102.85095 -229.094538)
		(width 0.350012)
		(layer "F.Cu")
		(net "GND")
	)
	(segment
		(start 371.297962 -285.160212)
		(end 371.764814 -285.42615)
		(width 0.350012)
		(layer "F.Cu")
		(net "GND")
	)
	(segment
		(start 126.647956 -285.970472)
		(end 127.114808 -286.23641)
		(width 0.350012)
		(layer "F.Cu")
		(net "GND")
	)
	(segment
		(start 124.718064 -383.92227)
		(end 124.770642 -384.617722)
		(width 0.254)
		(layer "F.Cu")
		(net "GND")
	)
	(segment
		(start 102.378002 -255.280414)
		(end 101.91115 -255.014476)
		(width 0.350012)
		(layer "F.Cu")
		(net "GND")
	)
	(segment
		(start 123.827794 -269.770352)
		(end 124.294646 -270.03629)
		(width 0.350012)
		(layer "F.Cu")
		(net "GND")
	)
	(segment
		(start 55.068216 -12.374118)
		(end 55.066946 -12.372848)
		(width 0.3556)
		(layer "F.Cu")
		(net "GND")
	)
	(segment
		(start 55.270654 -386.6388)
		(end 54.578504 -386.449062)
		(width 0.254)
		(layer "F.Cu")
		(net "GND")
	)
	(segment
		(start 292.280086 -312.084974)
		(end 290.895786 -312.084974)
		(width 0.4572)
		(layer "F.Cu")
		(net "GND")
	)
	(segment
		(start 120.56237 -384.617722)
		(end 121.170446 -384.617722)
		(width 0.254)
		(layer "F.Cu")
		(net "GND")
	)
	(segment
		(start 178.289458 -46.800008)
		(end 177.108358 -46.800008)
		(width 0.254)
		(layer "F.Cu")
		(net "GND")
	)
	(segment
		(start 277.250906 -429.572166)
		(end 276.61362 -429.572166)
		(width 0.381)
		(layer "F.Cu")
		(net "GND")
	)
	(segment
		(start 131.817872 -293.260272)
		(end 132.284724 -293.52621)
		(width 0.350012)
		(layer "F.Cu")
		(net "GND")
	)
	(segment
		(start 292.280086 -202.434952)
		(end 290.895786 -202.434952)
		(width 0.4572)
		(layer "F.Cu")
		(net "GND")
	)
	(segment
		(start 407.044144 -400.212814)
		(end 407.044144 -399.76171)
		(width 0.254)
		(layer "F.Cu")
		(net "GND")
	)
	(segment
		(start 361.597956 -226.120198)
		(end 362.064808 -225.85426)
		(width 0.350012)
		(layer "F.Cu")
		(net "GND")
	)
	(segment
		(start 376.89028 -31.923482)
		(end 376.89028 -31.169102)
		(width 0.4572)
		(layer "F.Cu")
		(net "GND")
	)
	(segment
		(start 143.267938 -233.410252)
		(end 143.73479 -233.144314)
		(width 0.350012)
		(layer "F.Cu")
		(net "GND")
	)
	(segment
		(start 117.717824 -273.820382)
		(end 118.184676 -274.08632)
		(width 0.350012)
		(layer "F.Cu")
		(net "GND")
	)
	(segment
		(start 202.147932 -284.885384)
		(end 203.532232 -284.885384)
		(width 0.4572)
		(layer "F.Cu")
		(net "GND")
	)
	(segment
		(start 194.914774 -425.022264)
		(end 194.914774 -425.854876)
		(width 0.381)
		(layer "F.Cu")
		(net "GND")
	)
	(segment
		(start 116.77777 -265.720322)
		(end 117.244622 -265.98626)
		(width 0.350012)
		(layer "F.Cu")
		(net "GND")
	)
	(segment
		(start 136.517888 -283.540454)
		(end 136.98474 -283.806392)
		(width 0.350012)
		(layer "F.Cu")
		(net "GND")
	)
	(segment
		(start 206.248 -221.135194)
		(end 204.8637 -221.135194)
		(width 0.4572)
		(layer "F.Cu")
		(net "GND")
	)
	(segment
		(start 345.447874 -276.250146)
		(end 344.981022 -276.516084)
		(width 0.350012)
		(layer "F.Cu")
		(net "GND")
	)
	(segment
		(start 344.645488 -391.784586)
		(end 344.645488 -392.004296)
		(width 0.254)
		(layer "F.Cu")
		(net "GND")
	)
	(segment
		(start 331.987906 -226.930204)
		(end 331.521054 -226.664266)
		(width 0.350012)
		(layer "F.Cu")
		(net "GND")
	)
	(segment
		(start 103.317802 -247.180354)
		(end 102.85095 -246.914416)
		(width 0.350012)
		(layer "F.Cu")
		(net "GND")
	)
	(segment
		(start 424.027346 -360.82859)
		(end 424.031918 -360.824018)
		(width 0.3556)
		(layer "F.Cu")
		(net "GND")
	)
	(segment
		(start 117.717824 -291.64026)
		(end 118.184676 -291.906198)
		(width 0.350012)
		(layer "F.Cu")
		(net "GND")
	)
	(segment
		(start 61.218064 -383.92227)
		(end 61.270642 -384.617722)
		(width 0.254)
		(layer "F.Cu")
		(net "GND")
	)
	(segment
		(start 323.191632 -395.451076)
		(end 322.476622 -395.451076)
		(width 0.254)
		(layer "F.Cu")
		(net "GND")
	)
	(segment
		(start 368.64798 -247.990106)
		(end 369.114832 -247.724168)
		(width 0.350012)
		(layer "F.Cu")
		(net "GND")
	)
	(segment
		(start 347.968062 -230.169974)
		(end 347.50121 -229.904036)
		(width 0.350012)
		(layer "F.Cu")
		(net "GND")
	)
	(segment
		(start 364.417864 -243.940076)
		(end 364.884716 -243.674138)
		(width 0.350012)
		(layer "F.Cu")
		(net "GND")
	)
	(segment
		(start 191.160146 -295.9354)
		(end 189.775846 -295.9354)
		(width 0.4572)
		(layer "F.Cu")
		(net "GND")
	)
	(segment
		(start 89.047828 -292.450266)
		(end 88.580976 -292.716204)
		(width 0.350012)
		(layer "F.Cu")
		(net "GND")
	)
	(segment
		(start 66.671444 -29.291026)
		(end 66.67246 -29.29001)
		(width 0.254)
		(layer "F.Cu")
		(net "GND")
	)
	(segment
		(start 297.283378 -349.211138)
		(end 297.283378 -348.794324)
		(width 0.2286)
		(layer "F.Cu")
		(net "GND")
	)
	(segment
		(start 51.062382 -384.617722)
		(end 50.470562 -384.617722)
		(width 0.254)
		(layer "F.Cu")
		(net "GND")
	)
	(segment
		(start 349.118682 -398.542002)
		(end 348.597982 -398.542002)
		(width 0.254)
		(layer "F.Cu")
		(net "GND")
	)
	(segment
		(start 351.087944 -271.39011)
		(end 350.621092 -271.656048)
		(width 0.350012)
		(layer "F.Cu")
		(net "GND")
	)
	(segment
		(start 418.690044 -392.999722)
		(end 419.298374 -392.999722)
		(width 0.254)
		(layer "F.Cu")
		(net "GND")
	)
	(segment
		(start 350.31807 -253.660148)
		(end 349.851218 -253.39421)
		(width 0.350012)
		(layer "F.Cu")
		(net "GND")
	)
	(segment
		(start 363.478064 -242.320064)
		(end 363.944916 -242.054126)
		(width 0.350012)
		(layer "F.Cu")
		(net "GND")
	)
	(segment
		(start 109.728 -268.15034)
		(end 109.261148 -268.416278)
		(width 0.350012)
		(layer "F.Cu")
		(net "GND")
	)
	(segment
		(start 103.998522 -33.452054)
		(end 104.265222 -33.718754)
		(width 0.254)
		(layer "F.Cu")
		(net "GND")
	)
	(segment
		(start 379.217936 -391.333482)
		(end 379.316488 -391.23493)
		(width 0.254)
		(layer "F.Cu")
		(net "GND")
	)
	(segment
		(start 414.498282 -395.0208)
		(end 413.806132 -394.831062)
		(width 0.254)
		(layer "F.Cu")
		(net "GND")
	)
	(segment
		(start 299.82414 -274.684998)
		(end 298.43984 -274.684998)
		(width 0.4572)
		(layer "F.Cu")
		(net "GND")
	)
	(segment
		(start 331.322934 -339.35797)
		(end 331.322934 -339.988906)
		(width 0.381)
		(layer "F.Cu")
		(net "GND")
	)
	(segment
		(start 420.49827 -398.542002)
		(end 421.01897 -398.542002)
		(width 0.254)
		(layer "F.Cu")
		(net "GND")
	)
	(segment
		(start 422.242488 -392.913108)
		(end 421.942514 -393.213082)
		(width 0.254)
		(layer "F.Cu")
		(net "GND")
	)
	(segment
		(start 439.100214 -230.485188)
		(end 437.715914 -230.485188)
		(width 0.4572)
		(layer "F.Cu")
		(net "GND")
	)
	(segment
		(start 155.406344 -386.449062)
		(end 154.898344 -386.6388)
		(width 0.254)
		(layer "F.Cu")
		(net "GND")
	)
	(segment
		(start 190.721996 -122.65279)
		(end 191.111886 -123.04268)
		(width 0.254)
		(layer "F.Cu")
		(net "GND")
	)
	(segment
		(start 371.691154 -398.542002)
		(end 371.170454 -398.542002)
		(width 0.254)
		(layer "F.Cu")
		(net "GND")
	)
	(segment
		(start 407.446988 -11.26998)
		(end 407.446988 -10.16635)
		(width 0.3556)
		(layer "F.Cu")
		(net "GND")
	)
	(segment
		(start 124.937774 -235.84027)
		(end 125.404626 -235.574332)
		(width 0.350012)
		(layer "F.Cu")
		(net "GND")
	)
	(segment
		(start 176.978056 -427.226984)
		(end 176.978056 -427.597062)
		(width 0.381)
		(layer "F.Cu")
		(net "GND")
	)
	(segment
		(start 343.445592 -392.004296)
		(end 343.745566 -392.30427)
		(width 0.254)
		(layer "F.Cu")
		(net "GND")
	)
	(segment
		(start 126.347982 -251.230384)
		(end 126.814834 -250.964446)
		(width 0.350012)
		(layer "F.Cu")
		(net "GND")
	)
	(segment
		(start 363.478064 -227.74021)
		(end 363.944916 -227.474272)
		(width 0.350012)
		(layer "F.Cu")
		(net "GND")
	)
	(segment
		(start 166.462202 -385.731004)
		(end 166.211504 -386.449062)
		(width 0.254)
		(layer "F.Cu")
		(net "GND")
	)
	(segment
		(start 386.03809 -240.700052)
		(end 386.504942 -240.434114)
		(width 0.350012)
		(layer "F.Cu")
		(net "GND")
	)
	(segment
		(start 187.522104 -114.652806)
		(end 187.911994 -114.262916)
		(width 0.254)
		(layer "F.Cu")
		(net "GND")
	)
	(segment
		(start 354.842318 -395.613128)
		(end 354.842318 -396.213076)
		(width 0.254)
		(layer "F.Cu")
		(net "GND")
	)
	(segment
		(start 115.537996 -229.360476)
		(end 116.004848 -229.094538)
		(width 0.350012)
		(layer "F.Cu")
		(net "GND")
	)
	(segment
		(start 261.05104 -115.481354)
		(end 261.201662 -115.631976)
		(width 0.3556)
		(layer "F.Cu")
		(net "GND")
	)
	(segment
		(start 92.33789 -281.920442)
		(end 91.871038 -282.18638)
		(width 0.350012)
		(layer "F.Cu")
		(net "GND")
	)
	(segment
		(start 164.445696 -390.761474)
		(end 164.498274 -390.160002)
		(width 0.254)
		(layer "F.Cu")
		(net "GND")
	)
	(segment
		(start 374.516396 -399.76171)
		(end 374.516396 -400.212814)
		(width 0.254)
		(layer "F.Cu")
		(net "GND")
	)
	(segment
		(start 343.445592 -391.784586)
		(end 343.445592 -391.333482)
		(width 0.254)
		(layer "F.Cu")
		(net "GND")
	)
	(segment
		(start 386.770626 -395.0208)
		(end 386.078476 -394.831062)
		(width 0.254)
		(layer "F.Cu")
		(net "GND")
	)
	(segment
		(start 129.63779 -229.360476)
		(end 130.104642 -229.094538)
		(width 0.350012)
		(layer "F.Cu")
		(net "GND")
	)
	(segment
		(start 81.058004 -278.680418)
		(end 80.591152 -278.946356)
		(width 0.350012)
		(layer "F.Cu")
		(net "GND")
	)
	(segment
		(start 303.717706 -392.004296)
		(end 304.01768 -392.30427)
		(width 0.254)
		(layer "F.Cu")
		(net "GND")
	)
	(segment
		(start 179.516024 -284.885384)
		(end 180.900324 -284.885384)
		(width 0.4572)
		(layer "F.Cu")
		(net "GND")
	)
	(segment
		(start 97.144332 -391.37971)
		(end 97.04578 -391.281158)
		(width 0.254)
		(layer "F.Cu")
		(net "GND")
	)
	(segment
		(start 303.831498 -25.62225)
		(end 304.931572 -25.62225)
		(width 0.381)
		(layer "F.Cu")
		(net "GND")
	)
	(segment
		(start 402.248878 -395.012926)
		(end 402.248878 -395.613128)
		(width 0.254)
		(layer "F.Cu")
		(net "GND")
	)
	(segment
		(start 64.870584 -384.617722)
		(end 64.262508 -384.617722)
		(width 0.254)
		(layer "F.Cu")
		(net "GND")
	)
	(segment
		(start 369.888008 -294.070024)
		(end 370.35486 -294.335962)
		(width 0.350012)
		(layer "F.Cu")
		(net "GND")
	)
	(segment
		(start 346.087954 -225.310192)
		(end 345.621102 -225.044254)
		(width 0.350012)
		(layer "F.Cu")
		(net "GND")
	)
	(segment
		(start 109.427772 -230.170228)
		(end 108.961174 -229.90429)
		(width 0.350012)
		(layer "F.Cu")
		(net "GND")
	)
	(segment
		(start 447.399664 -422.114726)
		(end 447.419476 -422.134538)
		(width 0.1778)
		(layer "F.Cu")
		(net "GND")
	)
	(segment
		(start 342.158066 -272.200116)
		(end 341.691214 -272.466054)
		(width 0.350012)
		(layer "F.Cu")
		(net "GND")
	)
	(segment
		(start 412.74619 -396.710662)
		(end 412.098236 -396.520924)
		(width 0.254)
		(layer "F.Cu")
		(net "GND")
	)
	(segment
		(start 272.340578 -348.794324)
		(end 272.593562 -348.54134)
		(width 0.2286)
		(layer "F.Cu")
		(net "GND")
	)
	(segment
		(start 412.098236 -395.0208)
		(end 411.40634 -394.831062)
		(width 0.254)
		(layer "F.Cu")
		(net "GND")
	)
	(segment
		(start 133.227826 -295.69029)
		(end 133.235954 -295.720516)
		(width 0.350012)
		(layer "F.Cu")
		(net "GND")
	)
	(segment
		(start 421.942514 -395.613128)
		(end 421.942514 -396.213076)
		(width 0.254)
		(layer "F.Cu")
		(net "GND")
	)
	(segment
		(start 385.217924 -391.333482)
		(end 385.316476 -391.23493)
		(width 0.254)
		(layer "F.Cu")
		(net "GND")
	)
	(segment
		(start 115.678458 -386.449062)
		(end 115.170458 -386.6388)
		(width 0.254)
		(layer "F.Cu")
		(net "GND")
	)
	(segment
		(start 403.846792 -8.320024)
		(end 403.846792 -9.423654)
		(width 0.3556)
		(layer "F.Cu")
		(net "GND")
	)
	(segment
		(start 144.977866 -260.860286)
		(end 145.444718 -261.126224)
		(width 0.350012)
		(layer "F.Cu")
		(net "GND")
	)
	(segment
		(start 80.287876 -241.510312)
		(end 79.821024 -241.244374)
		(width 0.350012)
		(layer "F.Cu")
		(net "GND")
	)
	(segment
		(start 130.877818 -268.960346)
		(end 131.34467 -269.226284)
		(width 0.350012)
		(layer "F.Cu")
		(net "GND")
	)
	(segment
		(start 381.167894 -292.450012)
		(end 381.634746 -292.71595)
		(width 0.350012)
		(layer "F.Cu")
		(net "GND")
	)
	(segment
		(start 347.497908 -234.220004)
		(end 347.031056 -233.954066)
		(width 0.350012)
		(layer "F.Cu")
		(net "GND")
	)
	(segment
		(start 83.941158 -337.572858)
		(end 84.040726 -337.33232)
		(width 0.2286)
		(layer "F.Cu")
		(net "GND")
	)
	(segment
		(start 82.645758 -382.951482)
		(end 82.74431 -382.85293)
		(width 0.254)
		(layer "F.Cu")
		(net "GND")
	)
	(segment
		(start 454.611994 -45.864526)
		(end 454.611994 -45.233082)
		(width 0.381)
		(layer "F.Cu")
		(net "GND")
	)
	(segment
		(start 316.070234 -398.542002)
		(end 315.391038 -398.542002)
		(width 0.254)
		(layer "F.Cu")
		(net "GND")
	)
	(segment
		(start 187.522104 -115.452906)
		(end 187.911994 -115.842796)
		(width 0.254)
		(layer "F.Cu")
		(net "GND")
	)
	(segment
		(start 325.70801 -287.59023)
		(end 325.052944 -287.59023)
		(width 0.350012)
		(layer "F.Cu")
		(net "GND")
	)
	(segment
		(start 299.82414 -284.034992)
		(end 298.43984 -284.034992)
		(width 0.4572)
		(layer "F.Cu")
		(net "GND")
	)
	(segment
		(start 153.258266 -16.551148)
		(end 153.258266 -17.910048)
		(width 0.3556)
		(layer "F.Cu")
		(net "GND")
	)
	(segment
		(start 131.617974 -382.951482)
		(end 131.716526 -382.85293)
		(width 0.254)
		(layer "F.Cu")
		(net "GND")
	)
	(segment
		(start 269.648178 -277.235158)
		(end 268.263878 -277.235158)
		(width 0.4572)
		(layer "F.Cu")
		(net "GND")
	)
	(segment
		(start 346.557854 -229.360222)
		(end 346.091002 -229.094284)
		(width 0.350012)
		(layer "F.Cu")
		(net "GND")
	)
	(segment
		(start 355.957886 -250.420124)
		(end 355.491034 -250.154186)
		(width 0.350012)
		(layer "F.Cu")
		(net "GND")
	)
	(segment
		(start 55.778654 -386.449062)
		(end 55.270654 -386.6388)
		(width 0.254)
		(layer "F.Cu")
		(net "GND")
	)
	(segment
		(start 128.227836 -230.170228)
		(end 128.694688 -229.90429)
		(width 0.350012)
		(layer "F.Cu")
		(net "GND")
	)
	(segment
		(start 428.88916 -353.218242)
		(end 428.88916 -353.635056)
		(width 0.2286)
		(layer "F.Cu")
		(net "GND")
	)
	(segment
		(start 133.227826 -269.770352)
		(end 133.694678 -270.03629)
		(width 0.350012)
		(layer "F.Cu")
		(net "GND")
	)
	(segment
		(start 133.227826 -281.110436)
		(end 133.694678 -281.376374)
		(width 0.350012)
		(layer "F.Cu")
		(net "GND")
	)
	(segment
		(start 391.50798 -269.770098)
		(end 391.974832 -270.036036)
		(width 0.350012)
		(layer "F.Cu")
		(net "GND")
	)
	(segment
		(start 346.84589 -396.710662)
		(end 347.398086 -396.520924)
		(width 0.254)
		(layer "F.Cu")
		(net "GND")
	)
	(segment
		(start 338.097876 -256.900172)
		(end 337.631024 -256.634234)
		(width 0.350012)
		(layer "F.Cu")
		(net "GND")
	)
	(segment
		(start 92.037916 -222.880428)
		(end 91.571064 -222.61449)
		(width 0.350012)
		(layer "F.Cu")
		(net "GND")
	)
	(segment
		(start 354.378006 -265.720068)
		(end 353.911154 -265.986006)
		(width 0.350012)
		(layer "F.Cu")
		(net "GND")
	)
	(segment
		(start 392.917934 -281.920188)
		(end 393.384786 -282.186126)
		(width 0.350012)
		(layer "F.Cu")
		(net "GND")
	)
	(segment
		(start 166.211504 -386.449062)
		(end 165.698424 -386.6388)
		(width 0.254)
		(layer "F.Cu")
		(net "GND")
	)
	(segment
		(start 97.230438 -401.551648)
		(end 97.230438 -400.640296)
		(width 0.3302)
		(layer "F.Cu")
		(net "GND")
	)
	(segment
		(start 109.518704 -327.582276)
		(end 108.629704 -327.582276)
		(width 0.254)
		(layer "F.Cu")
		(net "GND")
	)
	(segment
		(start 455.124566 -403.12467)
		(end 455.054208 -403.12467)
		(width 0.4572)
		(layer "F.Cu")
		(net "GND")
	)
	(segment
		(start 301.800768 -148.749766)
		(end 301.800768 -149.672802)
		(width 0.3048)
		(layer "F.Cu")
		(net "GND")
	)
	(segment
		(start 349.378016 -256.900172)
		(end 348.911164 -256.634234)
		(width 0.350012)
		(layer "F.Cu")
		(net "GND")
	)
	(segment
		(start 83.386168 -339.362796)
		(end 83.386168 -339.993732)
		(width 0.381)
		(layer "F.Cu")
		(net "GND")
	)
	(segment
		(start 368.17808 -235.840016)
		(end 368.644678 -235.574078)
		(width 0.350012)
		(layer "F.Cu")
		(net "GND")
	)
	(segment
		(start 415.698178 -395.0208)
		(end 415.006282 -394.831062)
		(width 0.254)
		(layer "F.Cu")
		(net "GND")
	)
	(segment
		(start 339.977984 -237.460028)
		(end 339.511132 -237.19409)
		(width 0.350012)
		(layer "F.Cu")
		(net "GND")
	)
	(segment
		(start 336.987896 -269.770098)
		(end 336.521044 -270.036036)
		(width 0.350012)
		(layer "F.Cu")
		(net "GND")
	)
	(segment
		(start 17.608042 -303.585372)
		(end 18.992342 -303.585372)
		(width 0.4572)
		(layer "F.Cu")
		(net "GND")
	)
	(segment
		(start 361.128056 -251.23013)
		(end 361.594908 -250.964192)
		(width 0.350012)
		(layer "F.Cu")
		(net "GND")
	)
	(segment
		(start 404.898352 -398.542002)
		(end 404.218902 -398.542002)
		(width 0.254)
		(layer "F.Cu")
		(net "GND")
	)
	(segment
		(start 66.017902 -383.92227)
		(end 65.717928 -383.402586)
		(width 0.254)
		(layer "F.Cu")
		(net "GND")
	)
	(segment
		(start 146.248882 -390.231122)
		(end 146.248882 -389.63092)
		(width 0.254)
		(layer "F.Cu")
		(net "GND")
	)
	(segment
		(start 139.80795 -276.2504)
		(end 140.274802 -276.516338)
		(width 0.350012)
		(layer "F.Cu")
		(net "GND")
	)
	(segment
		(start 334.808068 -241.510058)
		(end 334.341216 -241.24412)
		(width 0.350012)
		(layer "F.Cu")
		(net "GND")
	)
	(segment
		(start 124.49429 -54.375558)
		(end 124.87529 -53.994558)
		(width 0.1778)
		(layer "F.Cu")
		(net "GND")
	)
	(segment
		(start 364.630462 -172.559726)
		(end 364.560612 -172.629576)
		(width 0.381)
		(layer "F.Cu")
		(net "GND")
	)
	(segment
		(start 8.806434 -381.562356)
		(end 10.031984 -381.562356)
		(width 0.254)
		(layer "F.Cu")
		(net "GND")
	)
	(segment
		(start 128.52781 -274.630388)
		(end 128.994662 -274.896326)
		(width 0.350012)
		(layer "F.Cu")
		(net "GND")
	)
	(segment
		(start 115.067842 -247.99036)
		(end 115.534694 -247.724422)
		(width 0.350012)
		(layer "F.Cu")
		(net "GND")
	)
	(segment
		(start 156.746194 -388.328662)
		(end 156.09824 -388.138924)
		(width 0.254)
		(layer "F.Cu")
		(net "GND")
	)
	(segment
		(start 329.637898 -250.420124)
		(end 329.171046 -250.154186)
		(width 0.350012)
		(layer "F.Cu")
		(net "GND")
	)
	(segment
		(start 51.317906 -383.402586)
		(end 51.317906 -383.622042)
		(width 0.2032)
		(layer "F.Cu")
		(net "GND")
	)
	(segment
		(start 384.927856 -290.83)
		(end 385.394708 -291.095938)
		(width 0.350012)
		(layer "F.Cu")
		(net "GND")
	)
	(segment
		(start 108.017818 -243.94033)
		(end 107.550966 -243.674392)
		(width 0.350012)
		(layer "F.Cu")
		(net "GND")
	)
	(segment
		(start 135.107934 -290.830254)
		(end 135.574786 -291.096192)
		(width 0.350012)
		(layer "F.Cu")
		(net "GND")
	)
	(segment
		(start 369.11788 -237.460028)
		(end 369.584732 -237.19409)
		(width 0.350012)
		(layer "F.Cu")
		(net "GND")
	)
	(segment
		(start 392.622278 -177.951638)
		(end 392.749278 -178.078638)
		(width 0.381)
		(layer "F.Cu")
		(net "GND")
	)
	(segment
		(start 278.503126 -417.440872)
		(end 278.748998 -417.195)
		(width 0.381)
		(layer "F.Cu")
		(net "GND")
	)
	(segment
		(start 90.627962 -235.030264)
		(end 90.16111 -234.764326)
		(width 0.350012)
		(layer "F.Cu")
		(net "GND")
	)
	(segment
		(start 116.477796 -237.460282)
		(end 116.944648 -237.194344)
		(width 0.350012)
		(layer "F.Cu")
		(net "GND")
	)
	(segment
		(start 159.645604 -390.761474)
		(end 159.698182 -390.160002)
		(width 0.254)
		(layer "F.Cu")
		(net "GND")
	)
	(segment
		(start 14.01826 -92.287598)
		(end 14.01826 -91.658948)
		(width 0.3556)
		(layer "F.Cu")
		(net "GND")
	)
	(segment
		(start 131.547108 -13.599922)
		(end 131.547108 -12.496546)
		(width 0.3556)
		(layer "F.Cu")
		(net "GND")
	)
	(segment
		(start 18.54708 -8.320024)
		(end 18.54835 -9.424924)
		(width 0.3556)
		(layer "F.Cu")
		(net "GND")
	)
	(segment
		(start 352.197924 -224.500186)
		(end 351.731072 -224.234248)
		(width 0.350012)
		(layer "F.Cu")
		(net "GND")
	)
	(segment
		(start 363.478064 -230.97998)
		(end 363.944916 -230.714042)
		(width 0.350012)
		(layer "F.Cu")
		(net "GND")
	)
	(segment
		(start 116.370608 -390.160002)
		(end 115.691158 -390.160002)
		(width 0.254)
		(layer "F.Cu")
		(net "GND")
	)
	(segment
		(start 455.985626 -47.22114)
		(end 455.750168 -47.456598)
		(width 0.254)
		(layer "F.Cu")
		(net "GND")
	)
	(segment
		(start 305.044094 -349.781622)
		(end 305.614578 -349.211138)
		(width 0.2286)
		(layer "F.Cu")
		(net "GND")
	)
	(segment
		(start 89.047828 -281.110436)
		(end 88.580976 -281.376374)
		(width 0.350012)
		(layer "F.Cu")
		(net "GND")
	)
	(segment
		(start 379.457966 -224.500186)
		(end 379.924818 -224.234248)
		(width 0.350012)
		(layer "F.Cu")
		(net "GND")
	)
	(segment
		(start 338.56803 -256.090166)
		(end 338.101178 -255.824228)
		(width 0.350012)
		(layer "F.Cu")
		(net "GND")
	)
	(segment
		(start 55.328058 -221.985332)
		(end 56.712358 -221.985332)
		(width 0.4572)
		(layer "F.Cu")
		(net "GND")
	)
	(segment
		(start 420.156894 -8.320024)
		(end 420.156894 -9.423654)
		(width 0.3556)
		(layer "F.Cu")
		(net "GND")
	)
	(segment
		(start 369.618006 -391.339578)
		(end 369.568476 -391.290048)
		(width 0.254)
		(layer "F.Cu")
		(net "GND")
	)
	(segment
		(start 92.545662 -390.761474)
		(end 92.59824 -390.160002)
		(width 0.254)
		(layer "F.Cu")
		(net "GND")
	)
	(segment
		(start 149.490176 -384.617722)
		(end 150.098252 -384.617722)
		(width 0.254)
		(layer "F.Cu")
		(net "GND")
	)
	(segment
		(start 341.387938 -252.850142)
		(end 340.921086 -252.584204)
		(width 0.350012)
		(layer "F.Cu")
		(net "GND")
	)
	(segment
		(start 427.456092 -240.685066)
		(end 428.840392 -240.685066)
		(width 0.4572)
		(layer "F.Cu")
		(net "GND")
	)
	(segment
		(start 95.79102 -61.87821)
		(end 96.523048 -61.87821)
		(width 0.4572)
		(layer "F.Cu")
		(net "GND")
	)
	(segment
		(start 367.538 -273.820128)
		(end 368.004852 -274.086066)
		(width 0.350012)
		(layer "F.Cu")
		(net "GND")
	)
	(segment
		(start 81.058004 -268.960346)
		(end 80.591152 -269.226284)
		(width 0.350012)
		(layer "F.Cu")
		(net "GND")
	)
	(segment
		(start 124.516388 -391.37971)
		(end 124.417836 -391.281158)
		(width 0.254)
		(layer "F.Cu")
		(net "GND")
	)
	(segment
		(start 93.44787 -247.99036)
		(end 92.981018 -247.724422)
		(width 0.350012)
		(layer "F.Cu")
		(net "GND")
	)
	(segment
		(start 167.090344 -343.753948)
		(end 167.090344 -343.122758)
		(width 0.4572)
		(layer "F.Cu")
		(net "GND")
	)
	(segment
		(start 154.655266 -108.09859)
		(end 153.872184 -108.09859)
		(width 0.381)
		(layer "F.Cu")
		(net "GND")
	)
	(segment
		(start 102.264718 -387.084062)
		(end 102.793546 -387.084062)
		(width 0.381)
		(layer "F.Cu")
		(net "GND")
	)
	(segment
		(start 57.6707 -386.6388)
		(end 56.97855 -386.449062)
		(width 0.254)
		(layer "F.Cu")
		(net "GND")
	)
	(segment
		(start 317.918338 -396.710662)
		(end 317.270384 -396.520924)
		(width 0.254)
		(layer "F.Cu")
		(net "GND")
	)
	(segment
		(start 331.987906 -244.750082)
		(end 331.521054 -244.484144)
		(width 0.350012)
		(layer "F.Cu")
		(net "GND")
	)
	(segment
		(start 82.167984 -238.270288)
		(end 81.701132 -238.00435)
		(width 0.350012)
		(layer "F.Cu")
		(net "GND")
	)
	(segment
		(start 357.42626 -326.69226)
		(end 357.53421 -326.58431)
		(width 0.4572)
		(layer "F.Cu")
		(net "GND")
	)
	(segment
		(start 349.378016 -243.940076)
		(end 348.911164 -243.674138)
		(width 0.350012)
		(layer "F.Cu")
		(net "GND")
	)
	(segment
		(start 377.878086 -267.34008)
		(end 378.344938 -267.606018)
		(width 0.350012)
		(layer "F.Cu")
		(net "GND")
	)
	(segment
		(start 118.357904 -224.50044)
		(end 118.824756 -224.234502)
		(width 0.350012)
		(layer "F.Cu")
		(net "GND")
	)
	(segment
		(start 265.54811 -240.685066)
		(end 266.93241 -240.685066)
		(width 0.4572)
		(layer "F.Cu")
		(net "GND")
	)
	(segment
		(start 146.087846 -238.270288)
		(end 146.742912 -238.270288)
		(width 0.350012)
		(layer "F.Cu")
		(net "GND")
	)
	(segment
		(start 84.84616 -388.328662)
		(end 84.19846 -388.138924)
		(width 0.254)
		(layer "F.Cu")
		(net "GND")
	)
	(segment
		(start 166.548308 -352.678492)
		(end 166.548308 -353.341178)
		(width 0.381)
		(layer "F.Cu")
		(net "GND")
	)
	(segment
		(start 202.147932 -296.785284)
		(end 203.532232 -296.785284)
		(width 0.4572)
		(layer "F.Cu")
		(net "GND")
	)
	(segment
		(start 364.888018 -251.23013)
		(end 365.35487 -250.964192)
		(width 0.350012)
		(layer "F.Cu")
		(net "GND")
	)
	(segment
		(start 78.448154 -340.204552)
		(end 78.518004 -340.134702)
		(width 0.381)
		(layer "F.Cu")
		(net "GND")
	)
	(segment
		(start 129.938018 -288.400236)
		(end 130.40487 -288.666174)
		(width 0.350012)
		(layer "F.Cu")
		(net "GND")
	)
	(segment
		(start 29.348176 -12.37488)
		(end 29.348176 -12.374118)
		(width 0.3556)
		(layer "F.Cu")
		(net "GND")
	)
	(segment
		(start 42.125138 -351.978722)
		(end 41.8719 -352.23196)
		(width 0.381)
		(layer "F.Cu")
		(net "GND")
	)
	(segment
		(start 331.407008 -338.038948)
		(end 331.977492 -337.468464)
		(width 0.2286)
		(layer "F.Cu")
		(net "GND")
	)
	(segment
		(start 108.017818 -248.800366)
		(end 107.550966 -248.534428)
		(width 0.350012)
		(layer "F.Cu")
		(net "GND")
	)
	(segment
		(start 123.997974 -253.660402)
		(end 124.464826 -253.394464)
		(width 0.350012)
		(layer "F.Cu")
		(net "GND")
	)
	(segment
		(start 88.747854 -256.09042)
		(end 88.281002 -255.824482)
		(width 0.350012)
		(layer "F.Cu")
		(net "GND")
	)
	(segment
		(start 338.868004 -276.250146)
		(end 338.401152 -276.516084)
		(width 0.350012)
		(layer "F.Cu")
		(net "GND")
	)
	(segment
		(start 256.041398 -50.382424)
		(end 256.049272 -50.390298)
		(width 0.254)
		(layer "F.Cu")
		(net "GND")
	)
	(segment
		(start 52.616608 -391.830814)
		(end 52.616608 -391.37971)
		(width 0.254)
		(layer "F.Cu")
		(net "GND")
	)
	(segment
		(start 312.990992 -398.542002)
		(end 312.470292 -398.542002)
		(width 0.254)
		(layer "F.Cu")
		(net "GND")
	)
	(segment
		(start 98.222562 -31.435548)
		(end 99.266248 -31.435548)
		(width 0.381)
		(layer "F.Cu")
		(net "GND")
	)
	(segment
		(start 408.244294 -399.76171)
		(end 408.244294 -400.212814)
		(width 0.254)
		(layer "F.Cu")
		(net "GND")
	)
	(segment
		(start 343.268046 -233.409998)
		(end 342.801194 -233.14406)
		(width 0.350012)
		(layer "F.Cu")
		(net "GND")
	)
	(segment
		(start 387.970522 -396.520924)
		(end 387.41858 -396.710662)
		(width 0.254)
		(layer "F.Cu")
		(net "GND")
	)
	(segment
		(start 66.773044 -36.800028)
		(end 66.773044 -37.437314)
		(width 0.4572)
		(layer "F.Cu")
		(net "GND")
	)
	(segment
		(start 374.28805 -252.850142)
		(end 374.754902 -252.584204)
		(width 0.350012)
		(layer "F.Cu")
		(net "GND")
	)
	(segment
		(start 353.137978 -227.74021)
		(end 352.671126 -227.474272)
		(width 0.350012)
		(layer "F.Cu")
		(net "GND")
	)
	(segment
		(start 333.697834 -283.5402)
		(end 333.230982 -283.806138)
		(width 0.350012)
		(layer "F.Cu")
		(net "GND")
	)
	(segment
		(start 149.419056 -390.160002)
		(end 148.898356 -390.160002)
		(width 0.254)
		(layer "F.Cu")
		(net "GND")
	)
	(segment
		(start 386.03809 -242.320064)
		(end 386.504942 -242.054126)
		(width 0.350012)
		(layer "F.Cu")
		(net "GND")
	)
	(segment
		(start 164.143944 -343.753948)
		(end 164.143944 -343.122758)
		(width 0.4572)
		(layer "F.Cu")
		(net "GND")
	)
	(segment
		(start 420.562532 -353.192842)
		(end 420.815516 -352.939858)
		(width 0.2286)
		(layer "F.Cu")
		(net "GND")
	)
	(segment
		(start 84.42833 -340.236048)
		(end 84.060538 -340.236048)
		(width 0.381)
		(layer "F.Cu")
		(net "GND")
	)
	(segment
		(start 394.027914 -239.890046)
		(end 394.68298 -239.890046)
		(width 0.350012)
		(layer "F.Cu")
		(net "GND")
	)
	(segment
		(start 368.682016 -395.613128)
		(end 368.205004 -395.42974)
		(width 0.254)
		(layer "F.Cu")
		(net "GND")
	)
	(segment
		(start 227.856034 -290.741862)
		(end 227.949506 -290.741862)
		(width 0.4572)
		(layer "F.Cu")
		(net "GND")
	)
	(segment
		(start 79.177896 -270.580358)
		(end 78.711044 -270.846296)
		(width 0.350012)
		(layer "F.Cu")
		(net "GND")
	)
	(segment
		(start 283.310076 -412.179008)
		(end 283.310076 -411.557724)
		(width 0.381)
		(layer "F.Cu")
		(net "GND")
	)
	(segment
		(start 349.67799 -291.640006)
		(end 349.211138 -291.905944)
		(width 0.350012)
		(layer "F.Cu")
		(net "GND")
	)
	(segment
		(start 62.470538 -386.6388)
		(end 61.778642 -386.449062)
		(width 0.254)
		(layer "F.Cu")
		(net "GND")
	)
	(segment
		(start 21.70811 -305.285394)
		(end 20.32381 -305.285394)
		(width 0.4572)
		(layer "F.Cu")
		(net "GND")
	)
	(segment
		(start 314.191142 -398.542002)
		(end 313.670442 -398.542002)
		(width 0.254)
		(layer "F.Cu")
		(net "GND")
	)
	(segment
		(start 314.693808 -338.060538)
		(end 315.264292 -337.490054)
		(width 0.2286)
		(layer "F.Cu")
		(net "GND")
	)
	(segment
		(start 372.238016 -280.300176)
		(end 372.704868 -280.566114)
		(width 0.350012)
		(layer "F.Cu")
		(net "GND")
	)
	(segment
		(start 43.85691 -11.26998)
		(end 43.85564 -11.26871)
		(width 0.3556)
		(layer "F.Cu")
		(net "GND")
	)
	(segment
		(start 122.117866 -237.460282)
		(end 122.584718 -237.194344)
		(width 0.350012)
		(layer "F.Cu")
		(net "GND")
	)
	(segment
		(start 80.757776 -256.900426)
		(end 80.291178 -256.634488)
		(width 0.350012)
		(layer "F.Cu")
		(net "GND")
	)
	(segment
		(start 216.788492 -23.017988)
		(end 216.943432 -23.172928)
		(width 0.3556)
		(layer "F.Cu")
		(net "GND")
	)
	(segment
		(start 116.94795 -251.230384)
		(end 117.414802 -250.964446)
		(width 0.350012)
		(layer "F.Cu")
		(net "GND")
	)
	(segment
		(start 347.797882 -286.780224)
		(end 347.33103 -287.046162)
		(width 0.350012)
		(layer "F.Cu")
		(net "GND")
	)
	(segment
		(start 139.507976 -243.130324)
		(end 139.974828 -242.864386)
		(width 0.350012)
		(layer "F.Cu")
		(net "GND")
	)
	(segment
		(start 21.70811 -202.435206)
		(end 20.32381 -202.435206)
		(width 0.4572)
		(layer "F.Cu")
		(net "GND")
	)
	(segment
		(start 81.997804 -293.260272)
		(end 81.530952 -293.52621)
		(width 0.350012)
		(layer "F.Cu")
		(net "GND")
	)
	(segment
		(start 131.817872 -265.720322)
		(end 132.284724 -265.98626)
		(width 0.350012)
		(layer "F.Cu")
		(net "GND")
	)
	(segment
		(start 351.410778 -158.074106)
		(end 351.37979 -158.074106)
		(width 0.2286)
		(layer "F.Cu")
		(net "GND")
	)
	(segment
		(start 392.61796 -239.08004)
		(end 393.084812 -238.814102)
		(width 0.350012)
		(layer "F.Cu")
		(net "GND")
	)
	(segment
		(start 303.268126 -312.935112)
		(end 304.652426 -312.935112)
		(width 0.4572)
		(layer "F.Cu")
		(net "GND")
	)
	(segment
		(start 305.00828 -403.15134)
		(end 305.016154 -403.143466)
		(width 0.381)
		(layer "F.Cu")
		(net "GND")
	)
	(segment
		(start 113.059972 -399.060416)
		(end 112.97666 -399.143728)
		(width 0.3302)
		(layer "F.Cu")
		(net "GND")
	)
	(segment
		(start 101.737922 -293.260272)
		(end 101.27107 -293.52621)
		(width 0.350012)
		(layer "F.Cu")
		(net "GND")
	)
	(segment
		(start 108.787946 -281.110436)
		(end 108.321094 -281.376374)
		(width 0.350012)
		(layer "F.Cu")
		(net "GND")
	)
	(segment
		(start 133.227826 -277.870412)
		(end 133.694678 -278.13635)
		(width 0.350012)
		(layer "F.Cu")
		(net "GND")
	)
	(segment
		(start 418.358066 -12.374118)
		(end 418.356796 -12.372848)
		(width 0.3556)
		(layer "F.Cu")
		(net "GND")
	)
	(segment
		(start 331.253592 -142.293086)
		(end 331.262482 -142.284196)
		(width 0.254)
		(layer "F.Cu")
		(net "GND")
	)
	(segment
		(start 338.56803 -239.890046)
		(end 338.101178 -239.624108)
		(width 0.350012)
		(layer "F.Cu")
		(net "GND")
	)
	(segment
		(start 100.027994 -254.470408)
		(end 99.561142 -254.20447)
		(width 0.350012)
		(layer "F.Cu")
		(net "GND")
	)
	(segment
		(start 190.342012 -356.532434)
		(end 190.930022 -356.532434)
		(width 0.381)
		(layer "F.Cu")
		(net "GND")
	)
	(segment
		(start 85.457792 -252.04039)
		(end 84.99094 -251.774452)
		(width 0.350012)
		(layer "F.Cu")
		(net "GND")
	)
	(segment
		(start 396.258796 -411.033468)
		(end 396.258796 -411.15615)
		(width 0.381)
		(layer "F.Cu")
		(net "GND")
	)
	(segment
		(start 171.246546 -381.90805)
		(end 170.905424 -381.566928)
		(width 0.254)
		(layer "F.Cu")
		(net "GND")
	)
	(segment
		(start 431.55616 -295.935146)
		(end 430.17186 -295.935146)
		(width 0.4572)
		(layer "F.Cu")
		(net "GND")
	)
	(segment
		(start 108.317792 -278.680418)
		(end 107.85094 -278.946356)
		(width 0.350012)
		(layer "F.Cu")
		(net "GND")
	)
	(segment
		(start 464.135978 -93.309186)
		(end 464.751928 -93.309186)
		(width 0.4572)
		(layer "F.Cu")
		(net "GND")
	)
	(segment
		(start 366.597946 -283.5402)
		(end 367.064798 -283.806138)
		(width 0.350012)
		(layer "F.Cu")
		(net "GND")
	)
	(segment
		(start 330.408026 -294.070024)
		(end 329.941174 -294.335962)
		(width 0.350012)
		(layer "F.Cu")
		(net "GND")
	)
	(segment
		(start 156.69006 -384.617722)
		(end 156.09824 -384.617722)
		(width 0.254)
		(layer "F.Cu")
		(net "GND")
	)
	(segment
		(start 140.27785 -265.720322)
		(end 140.744702 -265.98626)
		(width 0.350012)
		(layer "F.Cu")
		(net "GND")
	)
	(segment
		(start 127.678434 -386.449062)
		(end 127.170434 -386.6388)
		(width 0.254)
		(layer "F.Cu")
		(net "GND")
	)
	(segment
		(start 419.912038 -200.735184)
		(end 421.296338 -200.735184)
		(width 0.4572)
		(layer "F.Cu")
		(net "GND")
	)
	(segment
		(start 363.00791 -249.610118)
		(end 363.474762 -249.34418)
		(width 0.350012)
		(layer "F.Cu")
		(net "GND")
	)
	(segment
		(start 299.82414 -202.434952)
		(end 298.43984 -202.434952)
		(width 0.4572)
		(layer "F.Cu")
		(net "GND")
	)
	(segment
		(start 346.858082 -277.060152)
		(end 346.39123 -277.32609)
		(width 0.350012)
		(layer "F.Cu")
		(net "GND")
	)
	(segment
		(start 60.91809 -383.622296)
		(end 61.218064 -383.92227)
		(width 0.254)
		(layer "F.Cu")
		(net "GND")
	)
	(segment
		(start 320.340228 -42.684954)
		(end 320.949828 -42.684954)
		(width 0.3556)
		(layer "F.Cu")
		(net "GND")
	)
	(segment
		(start 118.357904 -227.740464)
		(end 118.824756 -227.474526)
		(width 0.350012)
		(layer "F.Cu")
		(net "GND")
	)
	(segment
		(start 454.188068 -293.384986)
		(end 452.803768 -293.384986)
		(width 0.4572)
		(layer "F.Cu")
		(net "GND")
	)
	(segment
		(start 345.58986 -392.999722)
		(end 344.99804 -392.999722)
		(width 0.254)
		(layer "F.Cu")
		(net "GND")
	)
	(segment
		(start 402.63699 -394.412978)
		(end 402.248878 -394.412978)
		(width 0.254)
		(layer "F.Cu")
		(net "GND")
	)
	(segment
		(start 121.007886 -277.870412)
		(end 121.474738 -278.13635)
		(width 0.350012)
		(layer "F.Cu")
		(net "GND")
	)
	(segment
		(start 98.147886 -222.070422)
		(end 97.681034 -221.804484)
		(width 0.350012)
		(layer "F.Cu")
		(net "GND")
	)
	(segment
		(start 128.227836 -236.650276)
		(end 128.694688 -236.384338)
		(width 0.350012)
		(layer "F.Cu")
		(net "GND")
	)
	(segment
		(start 419.912038 -221.985078)
		(end 421.296338 -221.985078)
		(width 0.4572)
		(layer "F.Cu")
		(net "GND")
	)
	(segment
		(start 36.795964 -202.435206)
		(end 35.411664 -202.435206)
		(width 0.4572)
		(layer "F.Cu")
		(net "GND")
	)
	(segment
		(start 380.417832 -392.004042)
		(end 380.417832 -391.784586)
		(width 0.254)
		(layer "F.Cu")
		(net "GND")
	)
	(segment
		(start 84.047838 -228.55047)
		(end 83.580986 -228.284532)
		(width 0.350012)
		(layer "F.Cu")
		(net "GND")
	)
	(segment
		(start 454.188068 -211.784946)
		(end 452.803768 -211.784946)
		(width 0.4572)
		(layer "F.Cu")
		(net "GND")
	)
	(segment
		(start 86.868 -225.310446)
		(end 86.401148 -225.044508)
		(width 0.350012)
		(layer "F.Cu")
		(net "GND")
	)
	(segment
		(start 158.395416 -56.331358)
		(end 158.395416 -55.696612)
		(width 0.4572)
		(layer "F.Cu")
		(net "GND")
	)
	(segment
		(start 393.097004 -319.794128)
		(end 392.953748 -319.650872)
		(width 0.508)
		(layer "F.Cu")
		(net "GND")
	)
	(segment
		(start 277.192232 -239.835182)
		(end 275.807932 -239.835182)
		(width 0.4572)
		(layer "F.Cu")
		(net "GND")
	)
	(segment
		(start 120.238012 -240.700306)
		(end 120.70461 -240.434368)
		(width 0.350012)
		(layer "F.Cu")
		(net "GND")
	)
	(segment
		(start 328.227944 -247.990106)
		(end 327.761092 -247.724168)
		(width 0.350012)
		(layer "F.Cu")
		(net "GND")
	)
	(segment
		(start 389.157972 -268.960092)
		(end 389.624824 -269.22603)
		(width 0.350012)
		(layer "F.Cu")
		(net "GND")
	)
	(segment
		(start 396.646908 -11.26998)
		(end 396.645638 -10.16508)
		(width 0.3556)
		(layer "F.Cu")
		(net "GND")
	)
	(segment
		(start 131.617974 -383.402586)
		(end 131.617974 -383.622296)
		(width 0.254)
		(layer "F.Cu")
		(net "GND")
	)
	(segment
		(start 336.687922 -238.270034)
		(end 336.22107 -238.004096)
		(width 0.350012)
		(layer "F.Cu")
		(net "GND")
	)
	(segment
		(start 111.633 -123.55195)
		(end 111.633 -122.936)
		(width 0.381)
		(layer "F.Cu")
		(net "GND")
	)
	(segment
		(start 374.0912 -398.542002)
		(end 373.5705 -398.542002)
		(width 0.254)
		(layer "F.Cu")
		(net "GND")
	)
	(segment
		(start 344.977974 -278.680164)
		(end 344.511122 -278.946102)
		(width 0.350012)
		(layer "F.Cu")
		(net "GND")
	)
	(segment
		(start 85.757766 -275.440394)
		(end 85.290914 -275.706332)
		(width 0.350012)
		(layer "F.Cu")
		(net "GND")
	)
	(segment
		(start 12.090908 -411.964632)
		(end 12.090908 -412.093156)
		(width 0.1778)
		(layer "F.Cu")
		(net "GND")
	)
	(segment
		(start 370.505228 -143.504158)
		(end 370.505228 -143.910558)
		(width 0.4572)
		(layer "F.Cu")
		(net "GND")
	)
	(segment
		(start 25.745694 -7.215124)
		(end 25.745694 -7.215886)
		(width 0.3556)
		(layer "F.Cu")
		(net "GND")
	)
	(segment
		(start 131.517898 -256.900426)
		(end 131.98475 -256.634488)
		(width 0.350012)
		(layer "F.Cu")
		(net "GND")
	)
	(segment
		(start 5.403088 -132.91439)
		(end 8.428736 -132.91439)
		(width 0.3556)
		(layer "F.Cu")
		(net "GND")
	)
	(segment
		(start 93.375734 -177.418238)
		(end 93.74505 -177.418238)
		(width 0.381)
		(layer "F.Cu")
		(net "GND")
	)
	(segment
		(start 59.428126 -314.635388)
		(end 58.043826 -314.635388)
		(width 0.4572)
		(layer "F.Cu")
		(net "GND")
	)
	(segment
		(start 78.62951 -388.13105)
		(end 78.3209 -388.36473)
		(width 0.254)
		(layer "F.Cu")
		(net "GND")
	)
	(segment
		(start 111.137954 -293.260272)
		(end 110.671102 -293.52621)
		(width 0.350012)
		(layer "F.Cu")
		(net "GND")
	)
	(segment
		(start 437.707786 -166.684452)
		(end 437.707786 -166.024814)
		(width 0.3556)
		(layer "F.Cu")
		(net "GND")
	)
	(segment
		(start 153.345642 -383.622296)
		(end 153.645616 -383.92227)
		(width 0.254)
		(layer "F.Cu")
		(net "GND")
	)
	(segment
		(start 51.467004 -7.217156)
		(end 51.467004 -8.320024)
		(width 0.3556)
		(layer "F.Cu")
		(net "GND")
	)
	(segment
		(start 307.368194 -295.935146)
		(end 305.983894 -295.935146)
		(width 0.4572)
		(layer "F.Cu")
		(net "GND")
	)
	(segment
		(start 366.597946 -270.580104)
		(end 367.064798 -270.846042)
		(width 0.350012)
		(layer "F.Cu")
		(net "GND")
	)
	(segment
		(start 105.66781 -239.8903)
		(end 105.200958 -239.624362)
		(width 0.350012)
		(layer "F.Cu")
		(net "GND")
	)
	(segment
		(start 85.291422 -287.045908)
		(end 85.291168 -287.04667)
		(width 0.350012)
		(layer "F.Cu")
		(net "GND")
	)
	(segment
		(start 126.177802 -291.64026)
		(end 126.644654 -291.906198)
		(width 0.350012)
		(layer "F.Cu")
		(net "GND")
	)
	(segment
		(start 105.66781 -249.610372)
		(end 105.200958 -249.344434)
		(width 0.350012)
		(layer "F.Cu")
		(net "GND")
	)
	(segment
		(start 115.389152 -402.19376)
		(end 115.389152 -402.611082)
		(width 0.3302)
		(layer "F.Cu")
		(net "GND")
	)
	(segment
		(start 164.427916 -212.635338)
		(end 165.812216 -212.635338)
		(width 0.4572)
		(layer "F.Cu")
		(net "GND")
	)
	(segment
		(start 331.81798 -290.019994)
		(end 331.351128 -290.285932)
		(width 0.350012)
		(layer "F.Cu")
		(net "GND")
	)
	(segment
		(start 295.724072 -240.685066)
		(end 297.108372 -240.685066)
		(width 0.4572)
		(layer "F.Cu")
		(net "GND")
	)
	(segment
		(start 331.518006 -242.320064)
		(end 331.051154 -242.054126)
		(width 0.350012)
		(layer "F.Cu")
		(net "GND")
	)
	(segment
		(start 87.3379 -243.94033)
		(end 86.871048 -243.674392)
		(width 0.350012)
		(layer "F.Cu")
		(net "GND")
	)
	(segment
		(start 126.347982 -244.750336)
		(end 126.814834 -244.484398)
		(width 0.350012)
		(layer "F.Cu")
		(net "GND")
	)
	(segment
		(start 128.227836 -226.930458)
		(end 128.694688 -226.66452)
		(width 0.350012)
		(layer "F.Cu")
		(net "GND")
	)
	(segment
		(start 273.092164 -278.085042)
		(end 274.476464 -278.085042)
		(width 0.4572)
		(layer "F.Cu")
		(net "GND")
	)
	(segment
		(start 130.417824 -382.951482)
		(end 130.516376 -382.85293)
		(width 0.254)
		(layer "F.Cu")
		(net "GND")
	)
	(segment
		(start 392.103102 -177.48631)
		(end 392.241278 -177.48631)
		(width 0.381)
		(layer "F.Cu")
		(net "GND")
	)
	(segment
		(start 411.745684 -392.004296)
		(end 412.045658 -392.30427)
		(width 0.254)
		(layer "F.Cu")
		(net "GND")
	)
	(segment
		(start 146.445732 -383.92227)
		(end 146.49831 -383.974848)
		(width 0.254)
		(layer "F.Cu")
		(net "GND")
	)
	(segment
		(start 125.238002 -280.30043)
		(end 125.704854 -280.566368)
		(width 0.350012)
		(layer "F.Cu")
		(net "GND")
	)
	(segment
		(start 113.721134 -384.86715)
		(end 113.970562 -384.617722)
		(width 0.254)
		(layer "F.Cu")
		(net "GND")
	)
	(segment
		(start 145.729452 -386.931154)
		(end 146.029426 -387.231128)
		(width 0.254)
		(layer "F.Cu")
		(net "GND")
	)
	(segment
		(start 136.687814 -233.410252)
		(end 137.154666 -233.144314)
		(width 0.350012)
		(layer "F.Cu")
		(net "GND")
	)
	(segment
		(start 103.147876 -287.590484)
		(end 102.681024 -287.856422)
		(width 0.350012)
		(layer "F.Cu")
		(net "GND")
	)
	(segment
		(start 366.297972 -224.500186)
		(end 366.764824 -224.234248)
		(width 0.350012)
		(layer "F.Cu")
		(net "GND")
	)
	(segment
		(start 59.428126 -199.8853)
		(end 58.043826 -199.8853)
		(width 0.4572)
		(layer "F.Cu")
		(net "GND")
	)
	(segment
		(start 111.137954 -268.960346)
		(end 110.671102 -269.226284)
		(width 0.350012)
		(layer "F.Cu")
		(net "GND")
	)
	(segment
		(start 136.517888 -281.920442)
		(end 136.98474 -282.18638)
		(width 0.350012)
		(layer "F.Cu")
		(net "GND")
	)
	(segment
		(start 93.54439 -391.830814)
		(end 93.54439 -391.37971)
		(width 0.254)
		(layer "F.Cu")
		(net "GND")
	)
	(segment
		(start 249.28703 -46.395132)
		(end 249.28703 -47.088806)
		(width 0.4572)
		(layer "F.Cu")
		(net "GND")
	)
	(segment
		(start 100.497894 -237.460282)
		(end 100.031042 -237.194344)
		(width 0.350012)
		(layer "F.Cu")
		(net "GND")
	)
	(segment
		(start 92.33789 -293.260272)
		(end 91.871038 -293.52621)
		(width 0.350012)
		(layer "F.Cu")
		(net "GND")
	)
	(segment
		(start 92.33789 -275.440394)
		(end 91.871038 -275.706332)
		(width 0.350012)
		(layer "F.Cu")
		(net "GND")
	)
	(segment
		(start 349.44558 -391.784586)
		(end 349.44558 -391.333482)
		(width 0.254)
		(layer "F.Cu")
		(net "GND")
	)
	(segment
		(start 128.52781 -292.450266)
		(end 128.994662 -292.716204)
		(width 0.350012)
		(layer "F.Cu")
		(net "GND")
	)
	(segment
		(start 328.492358 -102.52075)
		(end 328.492358 -101.88575)
		(width 0.3556)
		(layer "F.Cu")
		(net "GND")
	)
	(segment
		(start 163.178744 -343.753948)
		(end 163.178744 -343.122758)
		(width 0.4572)
		(layer "F.Cu")
		(net "GND")
	)
	(segment
		(start 331.81798 -260.860032)
		(end 331.351128 -261.12597)
		(width 0.350012)
		(layer "F.Cu")
		(net "GND")
	)
	(segment
		(start 117.41785 -237.460282)
		(end 117.884702 -237.194344)
		(width 0.350012)
		(layer "F.Cu")
		(net "GND")
	)
	(segment
		(start 139.977876 -256.900426)
		(end 140.444728 -256.634488)
		(width 0.350012)
		(layer "F.Cu")
		(net "GND")
	)
	(segment
		(start 138.397996 -268.960346)
		(end 138.864848 -269.226284)
		(width 0.350012)
		(layer "F.Cu")
		(net "GND")
	)
	(segment
		(start 386.03809 -247.1801)
		(end 386.504942 -246.914162)
		(width 0.350012)
		(layer "F.Cu")
		(net "GND")
	)
	(segment
		(start 43.543982 -385.59359)
		(end 43.532552 -385.58216)
		(width 0.254)
		(layer "F.Cu")
		(net "GND")
	)
	(segment
		(start 387.61797 -391.784586)
		(end 387.61797 -391.333482)
		(width 0.254)
		(layer "F.Cu")
		(net "GND")
	)
	(segment
		(start 95.627952 -292.450266)
		(end 95.1611 -292.716204)
		(width 0.350012)
		(layer "F.Cu")
		(net "GND")
	)
	(segment
		(start 206.248 -314.635388)
		(end 204.8637 -314.635388)
		(width 0.4572)
		(layer "F.Cu")
		(net "GND")
	)
	(segment
		(start 389.627872 -268.150086)
		(end 390.094724 -268.416024)
		(width 0.350012)
		(layer "F.Cu")
		(net "GND")
	)
	(segment
		(start 416.468052 -218.585034)
		(end 415.083752 -218.585034)
		(width 0.4572)
		(layer "F.Cu")
		(net "GND")
	)
	(segment
		(start 280.635964 -210.085178)
		(end 282.020264 -210.085178)
		(width 0.4572)
		(layer "F.Cu")
		(net "GND")
	)
	(segment
		(start 227.19157 -292.988238)
		(end 227.19157 -291.863526)
		(width 0.4572)
		(layer "F.Cu")
		(net "GND")
	)
	(segment
		(start 126.571756 -30.57271)
		(end 126.31166 -30.832806)
		(width 0.3556)
		(layer "F.Cu")
		(net "GND")
	)
	(segment
		(start 349.798132 -398.542002)
		(end 349.118682 -398.542002)
		(width 0.254)
		(layer "F.Cu")
		(net "GND")
	)
	(segment
		(start 386.338064 -281.920188)
		(end 386.804916 -282.186126)
		(width 0.350012)
		(layer "F.Cu")
		(net "GND")
	)
	(segment
		(start 143.267938 -238.270288)
		(end 143.73479 -238.00435)
		(width 0.350012)
		(layer "F.Cu")
		(net "GND")
	)
	(segment
		(start 84.517992 -224.50044)
		(end 84.05114 -224.234502)
		(width 0.350012)
		(layer "F.Cu")
		(net "GND")
	)
	(segment
		(start 358.137968 -265.720068)
		(end 357.671116 -265.986006)
		(width 0.350012)
		(layer "F.Cu")
		(net "GND")
	)
	(segment
		(start 387.448044 -243.13007)
		(end 387.914896 -242.864132)
		(width 0.350012)
		(layer "F.Cu")
		(net "GND")
	)
	(segment
		(start 121.177812 -237.460282)
		(end 121.644664 -237.194344)
		(width 0.350012)
		(layer "F.Cu")
		(net "GND")
	)
	(segment
		(start 125.362462 -384.617722)
		(end 124.770642 -384.617722)
		(width 0.254)
		(layer "F.Cu")
		(net "GND")
	)
	(segment
		(start 55.066946 -7.217156)
		(end 55.066946 -8.320024)
		(width 0.3556)
		(layer "F.Cu")
		(net "GND")
	)
	(segment
		(start 362.53801 -252.040136)
		(end 363.004862 -251.774198)
		(width 0.350012)
		(layer "F.Cu")
		(net "GND")
	)
	(segment
		(start 154.898344 -384.617722)
		(end 154.845766 -383.92227)
		(width 0.254)
		(layer "F.Cu")
		(net "GND")
	)
	(segment
		(start 359.078022 -290.019994)
		(end 358.61117 -290.285932)
		(width 0.350012)
		(layer "F.Cu")
		(net "GND")
	)
	(segment
		(start 105.497884 -285.160466)
		(end 105.031032 -285.426404)
		(width 0.350012)
		(layer "F.Cu")
		(net "GND")
	)
	(segment
		(start 79.177896 -288.400236)
		(end 78.711044 -288.666174)
		(width 0.350012)
		(layer "F.Cu")
		(net "GND")
	)
	(segment
		(start 383.048002 -284.350206)
		(end 383.514854 -284.616144)
		(width 0.350012)
		(layer "F.Cu")
		(net "GND")
	)
	(segment
		(start 409.309824 -166.018464)
		(end 409.229306 -166.21252)
		(width 0.2286)
		(layer "F.Cu")
		(net "GND")
	)
	(segment
		(start 129.82956 -27.896566)
		(end 129.82956 -27.3939)
		(width 0.254)
		(layer "F.Cu")
		(net "GND")
	)
	(segment
		(start 115.08359 -418.340032)
		(end 115.08359 -418.734494)
		(width 0.381)
		(layer "F.Cu")
		(net "GND")
	)
	(segment
		(start 144.677892 -256.900426)
		(end 145.144744 -256.634488)
		(width 0.350012)
		(layer "F.Cu")
		(net "GND")
	)
	(segment
		(start 118.657878 -273.820382)
		(end 119.12473 -274.08632)
		(width 0.350012)
		(layer "F.Cu")
		(net "GND")
	)
	(segment
		(start 136.517888 -286.780478)
		(end 136.98474 -287.046162)
		(width 0.350012)
		(layer "F.Cu")
		(net "GND")
	)
	(segment
		(start 350.998028 -395.0208)
		(end 350.306132 -394.831062)
		(width 0.254)
		(layer "F.Cu")
		(net "GND")
	)
	(segment
		(start 143.14805 -114.554)
		(end 143.14805 -113.89995)
		(width 0.381)
		(layer "F.Cu")
		(net "GND")
	)
	(segment
		(start 126.347982 -241.510312)
		(end 126.814834 -241.244374)
		(width 0.350012)
		(layer "F.Cu")
		(net "GND")
	)
	(segment
		(start 99.857814 -285.160466)
		(end 99.390962 -285.426404)
		(width 0.350012)
		(layer "F.Cu")
		(net "GND")
	)
	(segment
		(start 21.876258 -428.589948)
		(end 21.876258 -427.980348)
		(width 0.3556)
		(layer "F.Cu")
		(net "GND")
	)
	(segment
		(start 405.490172 -392.999722)
		(end 404.898352 -392.999722)
		(width 0.254)
		(layer "F.Cu")
		(net "GND")
	)
	(segment
		(start 322.7451 -398.542002)
		(end 322.070476 -398.542002)
		(width 0.254)
		(layer "F.Cu")
		(net "GND")
	)
	(segment
		(start 344.977974 -293.260018)
		(end 344.511122 -293.525956)
		(width 0.350012)
		(layer "F.Cu")
		(net "GND")
	)
	(segment
		(start 343.268046 -226.930204)
		(end 342.801194 -226.664266)
		(width 0.350012)
		(layer "F.Cu")
		(net "GND")
	)
	(segment
		(start 118.657878 -277.060406)
		(end 119.12473 -277.326344)
		(width 0.350012)
		(layer "F.Cu")
		(net "GND")
	)
	(segment
		(start 94.30639 -386.449062)
		(end 93.79839 -386.6388)
		(width 0.254)
		(layer "F.Cu")
		(net "GND")
	)
	(segment
		(start 369.11788 -243.940076)
		(end 369.584732 -243.674138)
		(width 0.350012)
		(layer "F.Cu")
		(net "GND")
	)
	(segment
		(start 98.44786 -263.290304)
		(end 97.981008 -263.556242)
		(width 0.350012)
		(layer "F.Cu")
		(net "GND")
	)
	(segment
		(start 302.620934 -396.214092)
		(end 302.620934 -395.613128)
		(width 0.254)
		(layer "F.Cu")
		(net "GND")
	)
	(segment
		(start 327.117964 -275.44014)
		(end 326.651112 -275.706078)
		(width 0.350012)
		(layer "F.Cu")
		(net "GND")
	)
	(segment
		(start 342.046052 -396.710662)
		(end 341.398098 -396.520924)
		(width 0.254)
		(layer "F.Cu")
		(net "GND")
	)
	(segment
		(start 351.589848 -392.999722)
		(end 352.198178 -392.999722)
		(width 0.254)
		(layer "F.Cu")
		(net "GND")
	)
	(segment
		(start 370.527834 -249.610118)
		(end 370.994686 -249.34418)
		(width 0.350012)
		(layer "F.Cu")
		(net "GND")
	)
	(segment
		(start 120.537986 -291.64026)
		(end 121.004838 -291.906198)
		(width 0.350012)
		(layer "F.Cu")
		(net "GND")
	)
	(segment
		(start 359.078022 -294.88003)
		(end 358.61117 -295.145968)
		(width 0.350012)
		(layer "F.Cu")
		(net "GND")
	)
	(segment
		(start 346.858082 -267.34008)
		(end 346.39123 -267.606018)
		(width 0.350012)
		(layer "F.Cu")
		(net "GND")
	)
	(segment
		(start 25.152096 -212.635338)
		(end 26.536396 -212.635338)
		(width 0.4572)
		(layer "F.Cu")
		(net "GND")
	)
	(segment
		(start 91.586304 -177.464212)
		(end 90.998294 -177.464212)
		(width 0.381)
		(layer "F.Cu")
		(net "GND")
	)
	(segment
		(start 321.71767 -399.663158)
		(end 322.017644 -399.143474)
		(width 0.254)
		(layer "F.Cu")
		(net "GND")
	)
	(segment
		(start 363.778038 -275.44014)
		(end 364.24489 -275.706078)
		(width 0.350012)
		(layer "F.Cu")
		(net "GND")
	)
	(segment
		(start 328.697844 -240.700052)
		(end 328.231246 -240.434114)
		(width 0.350012)
		(layer "F.Cu")
		(net "GND")
	)
	(segment
		(start 359.078022 -285.160212)
		(end 358.61117 -285.42615)
		(width 0.350012)
		(layer "F.Cu")
		(net "GND")
	)
	(segment
		(start 158.145734 -383.622296)
		(end 158.445708 -383.92227)
		(width 0.254)
		(layer "F.Cu")
		(net "GND")
	)
	(segment
		(start 116.962428 -384.617722)
		(end 116.370608 -384.617722)
		(width 0.254)
		(layer "F.Cu")
		(net "GND")
	)
	(segment
		(start 376.327162 -179.678584)
		(end 375.846848 -180.158898)
		(width 0.2286)
		(layer "F.Cu")
		(net "GND")
	)
	(segment
		(start 64.616584 -391.830814)
		(end 64.616584 -391.37971)
		(width 0.254)
		(layer "F.Cu")
		(net "GND")
	)
	(segment
		(start 354.078032 -226.120198)
		(end 353.61118 -225.85426)
		(width 0.350012)
		(layer "F.Cu")
		(net "GND")
	)
	(segment
		(start 370.357908 -277.060152)
		(end 370.82476 -277.32609)
		(width 0.350012)
		(layer "F.Cu")
		(net "GND")
	)
	(segment
		(start 350.14789 -268.150086)
		(end 349.681038 -268.416024)
		(width 0.350012)
		(layer "F.Cu")
		(net "GND")
	)
	(segment
		(start 121.477786 -262.480298)
		(end 121.944638 -262.746236)
		(width 0.350012)
		(layer "F.Cu")
		(net "GND")
	)
	(segment
		(start 118.827804 -249.610372)
		(end 119.294656 -249.344434)
		(width 0.350012)
		(layer "F.Cu")
		(net "GND")
	)
	(segment
		(start 122.370596 -388.138924)
		(end 121.8184 -388.328662)
		(width 0.254)
		(layer "F.Cu")
		(net "GND")
	)
	(segment
		(start 148.206206 -386.449062)
		(end 147.698206 -386.6388)
		(width 0.254)
		(layer "F.Cu")
		(net "GND")
	)
	(segment
		(start 327.234042 -389.446262)
		(end 327.277476 -389.402828)
		(width 0.254)
		(layer "F.Cu")
		(net "GND")
	)
	(segment
		(start 114.264694 -385.87553)
		(end 114.109246 -386.030978)
		(width 0.254)
		(layer "F.Cu")
		(net "GND")
	)
	(segment
		(start 407.946098 -396.710662)
		(end 407.298398 -396.520924)
		(width 0.254)
		(layer "F.Cu")
		(net "GND")
	)
	(segment
		(start 194.604132 -203.285344)
		(end 195.988432 -203.285344)
		(width 0.4572)
		(layer "F.Cu")
		(net "GND")
	)
	(segment
		(start 316.23 -363.23905)
		(end 315.595 -363.23905)
		(width 0.381)
		(layer "F.Cu")
		(net "GND")
	)
	(segment
		(start 100.07727 -343.004648)
		(end 100.55733 -342.524588)
		(width 0.2286)
		(layer "F.Cu")
		(net "GND")
	)
	(segment
		(start 114.92992 -68.811394)
		(end 114.92992 -69.44868)
		(width 0.381)
		(layer "F.Cu")
		(net "GND")
	)
	(segment
		(start 129.938018 -268.960346)
		(end 130.40487 -269.226284)
		(width 0.350012)
		(layer "F.Cu")
		(net "GND")
	)
	(segment
		(start 331.987906 -252.850142)
		(end 331.521054 -252.584204)
		(width 0.350012)
		(layer "F.Cu")
		(net "GND")
	)
	(segment
		(start 8.428736 -132.91439)
		(end 8.324596 -133.01853)
		(width 0.3556)
		(layer "F.Cu")
		(net "GND")
	)
	(segment
		(start 59.428126 -286.585406)
		(end 58.043826 -286.585406)
		(width 0.4572)
		(layer "F.Cu")
		(net "GND")
	)
	(segment
		(start 330.108052 -233.409998)
		(end 329.6412 -233.14406)
		(width 0.350012)
		(layer "F.Cu")
		(net "GND")
	)
	(segment
		(start 385.316476 -399.76171)
		(end 385.217924 -399.663158)
		(width 0.254)
		(layer "F.Cu")
		(net "GND")
	)
	(segment
		(start 125.234954 -29.779722)
		(end 125.234954 -30.642052)
		(width 0.4572)
		(layer "F.Cu")
		(net "GND")
	)
	(segment
		(start 170.255184 -429.798734)
		(end 169.263568 -429.798734)
		(width 0.381)
		(layer "F.Cu")
		(net "GND")
	)
	(segment
		(start 348.737936 -277.060152)
		(end 348.271084 -277.32609)
		(width 0.350012)
		(layer "F.Cu")
		(net "GND")
	)
	(segment
		(start 316.070234 -395.0208)
		(end 315.378338 -394.831062)
		(width 0.254)
		(layer "F.Cu")
		(net "GND")
	)
	(segment
		(start 351.943924 -399.76171)
		(end 351.845372 -399.663158)
		(width 0.254)
		(layer "F.Cu")
		(net "GND")
	)
	(segment
		(start 431.55616 -237.285022)
		(end 430.17186 -237.285022)
		(width 0.4572)
		(layer "F.Cu")
		(net "GND")
	)
	(segment
		(start 352.497898 -265.720068)
		(end 352.031046 -265.986006)
		(width 0.350012)
		(layer "F.Cu")
		(net "GND")
	)
	(segment
		(start 151.806148 -386.449062)
		(end 151.298402 -386.6388)
		(width 0.254)
		(layer "F.Cu")
		(net "GND")
	)
	(segment
		(start 387.448044 -225.310192)
		(end 387.914896 -225.044254)
		(width 0.350012)
		(layer "F.Cu")
		(net "GND")
	)
	(segment
		(start 90.627962 -223.690434)
		(end 90.16111 -223.424496)
		(width 0.350012)
		(layer "F.Cu")
		(net "GND")
	)
	(segment
		(start 61.270642 -384.617722)
		(end 60.662312 -384.617722)
		(width 0.254)
		(layer "F.Cu")
		(net "GND")
	)
	(segment
		(start 123.997974 -234.220258)
		(end 124.464826 -233.95432)
		(width 0.350012)
		(layer "F.Cu")
		(net "GND")
	)
	(segment
		(start 324.790308 -401.892262)
		(end 324.790308 -402.462746)
		(width 0.254)
		(layer "F.Cu")
		(net "GND")
	)
	(segment
		(start 64.870584 -386.6388)
		(end 64.178688 -386.449062)
		(width 0.254)
		(layer "F.Cu")
		(net "GND")
	)
	(segment
		(start 329.637898 -224.500186)
		(end 329.171046 -224.234248)
		(width 0.350012)
		(layer "F.Cu")
		(net "GND")
	)
	(segment
		(start 112.717834 -247.180354)
		(end 113.184686 -246.914416)
		(width 0.350012)
		(layer "F.Cu")
		(net "GND")
	)
	(segment
		(start 401.420838 -396.74673)
		(end 401.209764 -396.813024)
		(width 0.254)
		(layer "F.Cu")
		(net "GND")
	)
	(segment
		(start 156.25699 -16.549878)
		(end 156.25826 -16.551148)
		(width 0.3556)
		(layer "F.Cu")
		(net "GND")
	)
	(segment
		(start 139.507976 -246.370348)
		(end 139.974828 -246.10441)
		(width 0.350012)
		(layer "F.Cu")
		(net "GND")
	)
	(segment
		(start 353.437952 -273.820128)
		(end 352.9711 -274.086066)
		(width 0.350012)
		(layer "F.Cu")
		(net "GND")
	)
	(segment
		(start 407.298398 -395.0208)
		(end 406.606248 -394.831062)
		(width 0.254)
		(layer "F.Cu")
		(net "GND")
	)
	(segment
		(start 178.289458 -55.79999)
		(end 177.108358 -55.79999)
		(width 0.254)
		(layer "F.Cu")
		(net "GND")
	)
	(segment
		(start 111.137954 -277.060406)
		(end 110.671102 -277.326344)
		(width 0.350012)
		(layer "F.Cu")
		(net "GND")
	)
	(segment
		(start 417.745672 -391.784586)
		(end 417.745672 -392.004296)
		(width 0.254)
		(layer "F.Cu")
		(net "GND")
	)
	(segment
		(start 359.078022 -270.580104)
		(end 358.61117 -270.846042)
		(width 0.350012)
		(layer "F.Cu")
		(net "GND")
	)
	(segment
		(start 190.930022 -356.532434)
		(end 190.999872 -356.462584)
		(width 0.381)
		(layer "F.Cu")
		(net "GND")
	)
	(segment
		(start 424.418252 -401.892262)
		(end 424.242992 -401.717002)
		(width 0.254)
		(layer "F.Cu")
		(net "GND")
	)
	(segment
		(start 162.93846 -107.834176)
		(end 163.423854 -107.834176)
		(width 0.381)
		(layer "F.Cu")
		(net "GND")
	)
	(segment
		(start 126.647956 -271.390364)
		(end 127.114808 -271.656302)
		(width 0.350012)
		(layer "F.Cu")
		(net "GND")
	)
	(segment
		(start 356.25786 -290.019994)
		(end 355.791008 -290.285932)
		(width 0.350012)
		(layer "F.Cu")
		(net "GND")
	)
	(segment
		(start 287.79978 -401.181062)
		(end 288.930842 -401.181062)
		(width 0.381)
		(layer "F.Cu")
		(net "GND")
	)
	(segment
		(start 49.016666 -391.37971)
		(end 49.016666 -391.830814)
		(width 0.254)
		(layer "F.Cu")
		(net "GND")
	)
	(segment
		(start 416.556952 -11.26998)
		(end 416.556952 -10.16635)
		(width 0.3556)
		(layer "F.Cu")
		(net "GND")
	)
	(segment
		(start 424.168062 -12.374118)
		(end 424.166792 -12.372848)
		(width 0.3556)
		(layer "F.Cu")
		(net "GND")
	)
	(segment
		(start 343.56802 -290.83)
		(end 343.101168 -291.095938)
		(width 0.350012)
		(layer "F.Cu")
		(net "GND")
	)
	(segment
		(start 344.678 -224.500186)
		(end 344.211148 -224.234248)
		(width 0.350012)
		(layer "F.Cu")
		(net "GND")
	)
	(segment
		(start 329.760072 -31.937706)
		(end 330.369672 -31.937706)
		(width 0.3556)
		(layer "F.Cu")
		(net "GND")
	)
	(segment
		(start 107.081066 -221.804484)
		(end 106.607864 -222.070422)
		(width 0.350012)
		(layer "F.Cu")
		(net "GND")
	)
	(segment
		(start 325.70801 -261.670038)
		(end 325.052944 -261.670038)
		(width 0.350012)
		(layer "F.Cu")
		(net "GND")
	)
	(segment
		(start 308.420516 -433.542694)
		(end 308.82336 -433.542694)
		(width 0.381)
		(layer "F.Cu")
		(net "GND")
	)
	(segment
		(start 93.747844 -264.910316)
		(end 93.280992 -265.176254)
		(width 0.350012)
		(layer "F.Cu")
		(net "GND")
	)
	(segment
		(start 55.328058 -284.885384)
		(end 56.712358 -284.885384)
		(width 0.4572)
		(layer "F.Cu")
		(net "GND")
	)
	(segment
		(start 165.018974 -390.160002)
		(end 165.698424 -390.160002)
		(width 0.254)
		(layer "F.Cu")
		(net "GND")
	)
	(segment
		(start 146.087846 -256.09042)
		(end 146.742912 -256.09042)
		(width 0.350012)
		(layer "F.Cu")
		(net "GND")
	)
	(segment
		(start 85.990176 -384.617722)
		(end 86.598252 -384.617722)
		(width 0.254)
		(layer "F.Cu")
		(net "GND")
	)
	(segment
		(start 21.747734 -393.539726)
		(end 21.747734 -394.200126)
		(width 0.381)
		(layer "F.Cu")
		(net "GND")
	)
	(segment
		(start 394.327888 -281.110182)
		(end 394.982954 -281.110182)
		(width 0.350012)
		(layer "F.Cu")
		(net "GND")
	)
	(segment
		(start 105.967784 -289.210242)
		(end 105.500932 -289.47618)
		(width 0.350012)
		(layer "F.Cu")
		(net "GND")
	)
	(segment
		(start 82.99831 -388.138924)
		(end 83.646264 -388.328662)
		(width 0.254)
		(layer "F.Cu")
		(net "GND")
	)
	(segment
		(start 299.82414 -227.935028)
		(end 298.43984 -227.935028)
		(width 0.4572)
		(layer "F.Cu")
		(net "GND")
	)
	(segment
		(start 131.817872 -272.20037)
		(end 132.284724 -272.466308)
		(width 0.350012)
		(layer "F.Cu")
		(net "GND")
	)
	(segment
		(start 194.604132 -275.53539)
		(end 195.988432 -275.53539)
		(width 0.4572)
		(layer "F.Cu")
		(net "GND")
	)
	(segment
		(start 328.697844 -224.500186)
		(end 328.231246 -224.234248)
		(width 0.350012)
		(layer "F.Cu")
		(net "GND")
	)
	(segment
		(start 331.81798 -278.680164)
		(end 331.351128 -278.946102)
		(width 0.350012)
		(layer "F.Cu")
		(net "GND")
	)
	(segment
		(start 98.918014 -262.480298)
		(end 98.451162 -262.746236)
		(width 0.350012)
		(layer "F.Cu")
		(net "GND")
	)
	(segment
		(start 331.81798 -265.720068)
		(end 331.351128 -265.986006)
		(width 0.350012)
		(layer "F.Cu")
		(net "GND")
	)
	(segment
		(start 120.707912 -252.850396)
		(end 121.174764 -252.584458)
		(width 0.350012)
		(layer "F.Cu")
		(net "GND")
	)
	(segment
		(start 345.618054 -232.599992)
		(end 345.151202 -232.334054)
		(width 0.350012)
		(layer "F.Cu")
		(net "GND")
	)
	(segment
		(start 414.244282 -399.76171)
		(end 414.14573 -399.663158)
		(width 0.254)
		(layer "F.Cu")
		(net "GND")
	)
	(segment
		(start 371.767862 -276.250146)
		(end 372.234714 -276.516084)
		(width 0.350012)
		(layer "F.Cu")
		(net "GND")
	)
	(segment
		(start 431.55616 -227.935028)
		(end 430.17186 -227.935028)
		(width 0.4572)
		(layer "F.Cu")
		(net "GND")
	)
	(segment
		(start 122.370596 -384.617722)
		(end 122.962416 -384.617722)
		(width 0.254)
		(layer "F.Cu")
		(net "GND")
	)
	(segment
		(start 63.670688 -384.617722)
		(end 63.61811 -383.92227)
		(width 0.254)
		(layer "F.Cu")
		(net "GND")
	)
	(segment
		(start 86.598252 -390.160002)
		(end 87.118952 -390.160002)
		(width 0.254)
		(layer "F.Cu")
		(net "GND")
	)
	(segment
		(start 338.56803 -226.930204)
		(end 338.101178 -226.664266)
		(width 0.350012)
		(layer "F.Cu")
		(net "GND")
	)
	(segment
		(start 345.943936 -400.212814)
		(end 345.943936 -399.76171)
		(width 0.254)
		(layer "F.Cu")
		(net "GND")
	)
	(segment
		(start 348.437962 -240.700052)
		(end 347.97111 -240.434114)
		(width 0.350012)
		(layer "F.Cu")
		(net "GND")
	)
	(segment
		(start 292.280086 -305.28514)
		(end 290.895786 -305.28514)
		(width 0.4572)
		(layer "F.Cu")
		(net "GND")
	)
	(segment
		(start 414.756854 -8.320024)
		(end 414.756854 -9.423654)
		(width 0.3556)
		(layer "F.Cu")
		(net "GND")
	)
	(segment
		(start 116.477796 -232.600246)
		(end 116.944648 -232.334308)
		(width 0.350012)
		(layer "F.Cu")
		(net "GND")
	)
	(segment
		(start 138.098022 -242.320318)
		(end 138.564874 -242.05438)
		(width 0.350012)
		(layer "F.Cu")
		(net "GND")
	)
	(segment
		(start 146.38782 -292.450266)
		(end 147.042886 -292.450266)
		(width 0.350012)
		(layer "F.Cu")
		(net "GND")
	)
	(segment
		(start 327.587864 -295.690036)
		(end 327.121012 -295.955974)
		(width 0.350012)
		(layer "F.Cu")
		(net "GND")
	)
	(segment
		(start 47.784004 -240.68532)
		(end 49.168304 -240.68532)
		(width 0.4572)
		(layer "F.Cu")
		(net "GND")
	)
	(segment
		(start 357.668068 -269.770098)
		(end 357.201216 -270.036036)
		(width 0.350012)
		(layer "F.Cu")
		(net "GND")
	)
	(segment
		(start 318.97828 -394.831062)
		(end 318.47028 -395.0208)
		(width 0.254)
		(layer "F.Cu")
		(net "GND")
	)
	(segment
		(start 335.39811 -392.356848)
		(end 335.39811 -392.999722)
		(width 0.254)
		(layer "F.Cu")
		(net "GND")
	)
	(segment
		(start 113.721134 -386.030978)
		(end 113.721134 -386.630926)
		(width 0.254)
		(layer "F.Cu")
		(net "GND")
	)
	(segment
		(start 394.027914 -226.930204)
		(end 394.494766 -226.664266)
		(width 0.350012)
		(layer "F.Cu")
		(net "GND")
	)
	(segment
		(start 95.84563 -383.402586)
		(end 95.84563 -382.951482)
		(width 0.254)
		(layer "F.Cu")
		(net "GND")
	)
	(segment
		(start 392.61796 -253.660148)
		(end 393.084812 -253.39421)
		(width 0.350012)
		(layer "F.Cu")
		(net "GND")
	)
	(segment
		(start 340.447884 -225.310192)
		(end 339.981032 -225.044254)
		(width 0.350012)
		(layer "F.Cu")
		(net "GND")
	)
	(segment
		(start 403.14626 -396.710662)
		(end 402.498306 -396.46352)
		(width 0.254)
		(layer "F.Cu")
		(net "GND")
	)
	(segment
		(start 13.67155 -107.24515)
		(end 14.057884 -107.631484)
		(width 0.3556)
		(layer "F.Cu")
		(net "GND")
	)
	(segment
		(start 136.836912 -387.084062)
		(end 137.36574 -387.084062)
		(width 0.381)
		(layer "F.Cu")
		(net "GND")
	)
	(segment
		(start 117.41785 -240.700306)
		(end 117.884702 -240.434368)
		(width 0.350012)
		(layer "F.Cu")
		(net "GND")
	)
	(segment
		(start 128.52781 -277.870412)
		(end 128.994662 -278.13635)
		(width 0.350012)
		(layer "F.Cu")
		(net "GND")
	)
	(segment
		(start 328.694542 -395.8209)
		(end 328.338942 -396.1765)
		(width 0.254)
		(layer "F.Cu")
		(net "GND")
	)
	(segment
		(start 105.19791 -234.220258)
		(end 104.731058 -233.95432)
		(width 0.350012)
		(layer "F.Cu")
		(net "GND")
	)
	(segment
		(start 44.87037 -351.932748)
		(end 44.94022 -351.862898)
		(width 0.381)
		(layer "F.Cu")
		(net "GND")
	)
	(segment
		(start 361.42803 -268.150086)
		(end 361.894882 -268.416024)
		(width 0.350012)
		(layer "F.Cu")
		(net "GND")
	)
	(segment
		(start 381.167894 -274.630134)
		(end 381.634746 -274.896072)
		(width 0.350012)
		(layer "F.Cu")
		(net "GND")
	)
	(segment
		(start 356.25786 -283.5402)
		(end 355.791008 -283.806138)
		(width 0.350012)
		(layer "F.Cu")
		(net "GND")
	)
	(segment
		(start 387.917944 -237.460028)
		(end 388.384796 -237.19409)
		(width 0.350012)
		(layer "F.Cu")
		(net "GND")
	)
	(segment
		(start 90.157808 -239.080294)
		(end 89.690956 -238.814356)
		(width 0.350012)
		(layer "F.Cu")
		(net "GND")
	)
	(segment
		(start 350.78797 -230.169974)
		(end 350.321118 -229.904036)
		(width 0.350012)
		(layer "F.Cu")
		(net "GND")
	)
	(segment
		(start 104.08793 -268.15034)
		(end 103.621078 -268.416278)
		(width 0.350012)
		(layer "F.Cu")
		(net "GND")
	)
	(segment
		(start 350.78797 -247.990106)
		(end 350.321118 -247.724168)
		(width 0.350012)
		(layer "F.Cu")
		(net "GND")
	)
	(segment
		(start 315.370972 -33.715706)
		(end 314.761372 -33.715706)
		(width 0.3556)
		(layer "F.Cu")
		(net "GND")
	)
	(segment
		(start 143.171672 -386.418074)
		(end 143.171672 -385.59359)
		(width 0.254)
		(layer "F.Cu")
		(net "GND")
	)
	(segment
		(start 88.861392 -72.86371)
		(end 89.567512 -72.86371)
		(width 0.4572)
		(layer "F.Cu")
		(net "GND")
	)
	(segment
		(start 342.158066 -291.640006)
		(end 341.691214 -291.905944)
		(width 0.350012)
		(layer "F.Cu")
		(net "GND")
	)
	(segment
		(start 8.447278 -137.25398)
		(end 8.082788 -137.61847)
		(width 0.3556)
		(layer "F.Cu")
		(net "GND")
	)
	(segment
		(start 338.097876 -237.460028)
		(end 337.631024 -237.19409)
		(width 0.350012)
		(layer "F.Cu")
		(net "GND")
	)
	(segment
		(start 147.444206 -391.37971)
		(end 147.444206 -391.830814)
		(width 0.254)
		(layer "F.Cu")
		(net "GND")
	)
	(segment
		(start 191.160146 -302.735234)
		(end 189.775846 -302.735234)
		(width 0.4572)
		(layer "F.Cu")
		(net "GND")
	)
	(segment
		(start 87.798402 -388.138924)
		(end 87.246206 -388.328662)
		(width 0.254)
		(layer "F.Cu")
		(net "GND")
	)
	(segment
		(start 376.467878 -271.39011)
		(end 376.93473 -271.656048)
		(width 0.350012)
		(layer "F.Cu")
		(net "GND")
	)
	(segment
		(start 333.227934 -294.070024)
		(end 332.761082 -294.335962)
		(width 0.350012)
		(layer "F.Cu")
		(net "GND")
	)
	(segment
		(start 454.188068 -237.285022)
		(end 452.803768 -237.285022)
		(width 0.4572)
		(layer "F.Cu")
		(net "GND")
	)
	(segment
		(start 308.517798 -391.784586)
		(end 308.517798 -392.004296)
		(width 0.2032)
		(layer "F.Cu")
		(net "GND")
	)
	(segment
		(start 95.327978 -239.8903)
		(end 94.861126 -239.624362)
		(width 0.350012)
		(layer "F.Cu")
		(net "GND")
	)
	(segment
		(start 118.657878 -280.30043)
		(end 119.12473 -280.566368)
		(width 0.350012)
		(layer "F.Cu")
		(net "GND")
	)
	(segment
		(start 363.778038 -288.399982)
		(end 364.24489 -288.66592)
		(width 0.350012)
		(layer "F.Cu")
		(net "GND")
	)
	(segment
		(start 281.183334 -437.923686)
		(end 281.818334 -437.923686)
		(width 0.4318)
		(layer "F.Cu")
		(net "GND")
	)
	(segment
		(start 110.632494 -385.58216)
		(end 111.165894 -385.58216)
		(width 0.254)
		(layer "F.Cu")
		(net "GND")
	)
	(segment
		(start 277.192232 -277.235158)
		(end 275.807932 -277.235158)
		(width 0.4572)
		(layer "F.Cu")
		(net "GND")
	)
	(segment
		(start 343.445592 -391.784586)
		(end 343.445592 -392.004296)
		(width 0.254)
		(layer "F.Cu")
		(net "GND")
	)
	(segment
		(start 363.478064 -247.1801)
		(end 363.944916 -246.914162)
		(width 0.350012)
		(layer "F.Cu")
		(net "GND")
	)
	(segment
		(start 414.756854 -12.372848)
		(end 414.756854 -11.26998)
		(width 0.3556)
		(layer "F.Cu")
		(net "GND")
	)
	(segment
		(start 90.457782 -280.30043)
		(end 89.99093 -280.566368)
		(width 0.350012)
		(layer "F.Cu")
		(net "GND")
	)
	(segment
		(start 365.357918 -240.700052)
		(end 365.82477 -240.434114)
		(width 0.350012)
		(layer "F.Cu")
		(net "GND")
	)
	(segment
		(start 130.407918 -264.910316)
		(end 130.87477 -265.176254)
		(width 0.350012)
		(layer "F.Cu")
		(net "GND")
	)
	(segment
		(start 99.857814 -272.20037)
		(end 99.390962 -272.466308)
		(width 0.350012)
		(layer "F.Cu")
		(net "GND")
	)
	(segment
		(start 349.67799 -273.820128)
		(end 349.211138 -274.086066)
		(width 0.350012)
		(layer "F.Cu")
		(net "GND")
	)
	(segment
		(start 313.617864 -399.143474)
		(end 313.670442 -398.542002)
		(width 0.254)
		(layer "F.Cu")
		(net "GND")
	)
	(segment
		(start 250.113546 -48.094138)
		(end 251.102622 -48.094138)
		(width 0.4572)
		(layer "F.Cu")
		(net "GND")
	)
	(segment
		(start 379.217936 -391.784586)
		(end 379.217936 -392.004296)
		(width 0.254)
		(layer "F.Cu")
		(net "GND")
	)
	(segment
		(start 29.252164 -230.485442)
		(end 27.867864 -230.485442)
		(width 0.4572)
		(layer "F.Cu")
		(net "GND")
	)
	(segment
		(start 63.416434 -391.37971)
		(end 63.317882 -391.281158)
		(width 0.254)
		(layer "F.Cu")
		(net "GND")
	)
	(segment
		(start 92.33789 -285.160466)
		(end 91.871038 -285.426404)
		(width 0.350012)
		(layer "F.Cu")
		(net "GND")
	)
	(segment
		(start 82.467958 -264.910316)
		(end 82.001106 -265.176254)
		(width 0.350012)
		(layer "F.Cu")
		(net "GND")
	)
	(segment
		(start 133.69798 -270.580358)
		(end 134.164832 -270.846296)
		(width 0.350012)
		(layer "F.Cu")
		(net "GND")
	)
	(segment
		(start 215.736424 -19.517614)
		(end 216.788492 -20.569682)
		(width 0.3556)
		(layer "F.Cu")
		(net "GND")
	)
	(segment
		(start 103.86695 -416.814)
		(end 103.14305 -416.814)
		(width 0.381)
		(layer "F.Cu")
		(net "GND")
	)
	(segment
		(start 146.43354 -31.18739)
		(end 146.43354 -31.958026)
		(width 0.254)
		(layer "F.Cu")
		(net "GND")
	)
	(segment
		(start 164.427916 -240.68532)
		(end 165.812216 -240.68532)
		(width 0.4572)
		(layer "F.Cu")
		(net "GND")
	)
	(segment
		(start 133.69798 -290.020248)
		(end 134.164832 -290.286186)
		(width 0.350012)
		(layer "F.Cu")
		(net "GND")
	)
	(segment
		(start 124.078492 -386.449062)
		(end 123.570492 -386.6388)
		(width 0.254)
		(layer "F.Cu")
		(net "GND")
	)
	(segment
		(start 99.062286 -388.431024)
		(end 98.842576 -388.431024)
		(width 0.254)
		(layer "F.Cu")
		(net "GND")
	)
	(segment
		(start 80.58785 -269.770352)
		(end 80.120998 -270.03629)
		(width 0.350012)
		(layer "F.Cu")
		(net "GND")
	)
	(segment
		(start 115.367816 -277.870412)
		(end 115.834668 -278.13635)
		(width 0.350012)
		(layer "F.Cu")
		(net "GND")
	)
	(segment
		(start 381.638048 -268.960092)
		(end 382.1049 -269.22603)
		(width 0.350012)
		(layer "F.Cu")
		(net "GND")
	)
	(segment
		(start 333.697834 -294.88003)
		(end 333.230982 -295.145968)
		(width 0.350012)
		(layer "F.Cu")
		(net "GND")
	)
	(segment
		(start 139.80795 -269.770352)
		(end 140.274802 -270.03629)
		(width 0.350012)
		(layer "F.Cu")
		(net "GND")
	)
	(segment
		(start 138.397996 -265.720322)
		(end 138.864848 -265.98626)
		(width 0.350012)
		(layer "F.Cu")
		(net "GND")
	)
	(segment
		(start 383.76225 -392.999722)
		(end 383.17043 -392.999722)
		(width 0.254)
		(layer "F.Cu")
		(net "GND")
	)
	(segment
		(start 120.067832 -292.450266)
		(end 120.534684 -292.716204)
		(width 0.350012)
		(layer "F.Cu")
		(net "GND")
	)
	(segment
		(start 412.367984 -306.135024)
		(end 413.752284 -306.135024)
		(width 0.4572)
		(layer "F.Cu")
		(net "GND")
	)
	(segment
		(start 25.152096 -312.935366)
		(end 26.536396 -312.935366)
		(width 0.4572)
		(layer "F.Cu")
		(net "GND")
	)
	(segment
		(start 161.844228 -391.37971)
		(end 161.745676 -391.281158)
		(width 0.254)
		(layer "F.Cu")
		(net "GND")
	)
	(segment
		(start 121.177812 -248.800366)
		(end 121.644664 -248.534428)
		(width 0.350012)
		(layer "F.Cu")
		(net "GND")
	)
	(segment
		(start 206.248 -302.735234)
		(end 204.8637 -302.735234)
		(width 0.4572)
		(layer "F.Cu")
		(net "GND")
	)
	(segment
		(start 53.268372 -12.37488)
		(end 53.268372 -12.374118)
		(width 0.3556)
		(layer "F.Cu")
		(net "GND")
	)
	(segment
		(start 331.987906 -231.789986)
		(end 331.521054 -231.524048)
		(width 0.350012)
		(layer "F.Cu")
		(net "GND")
	)
	(segment
		(start 370.527834 -251.23013)
		(end 370.994686 -250.964192)
		(width 0.350012)
		(layer "F.Cu")
		(net "GND")
	)
	(segment
		(start 99.55784 -256.900426)
		(end 99.090988 -256.634488)
		(width 0.350012)
		(layer "F.Cu")
		(net "GND")
	)
	(segment
		(start 100.027994 -231.79024)
		(end 99.561142 -231.524302)
		(width 0.350012)
		(layer "F.Cu")
		(net "GND")
	)
	(segment
		(start 402.145754 -391.784586)
		(end 402.145754 -391.340086)
		(width 0.254)
		(layer "F.Cu")
		(net "GND")
	)
	(segment
		(start 78.877922 -235.84027)
		(end 78.41107 -235.574332)
		(width 0.350012)
		(layer "F.Cu")
		(net "GND")
	)
	(segment
		(start 125.707902 -261.670292)
		(end 126.174754 -261.93623)
		(width 0.350012)
		(layer "F.Cu")
		(net "GND")
	)
	(segment
		(start 375.36247 -392.999722)
		(end 375.970546 -392.999722)
		(width 0.254)
		(layer "F.Cu")
		(net "GND")
	)
	(segment
		(start 95.327978 -251.230384)
		(end 94.861126 -250.964446)
		(width 0.350012)
		(layer "F.Cu")
		(net "GND")
	)
	(segment
		(start 447.157602 -17.433798)
		(end 446.543938 -17.433798)
		(width 0.4572)
		(layer "F.Cu")
		(net "GND")
	)
	(segment
		(start 60.91809 -383.402586)
		(end 60.91809 -382.951482)
		(width 0.254)
		(layer "F.Cu")
		(net "GND")
	)
	(segment
		(start 341.687912 -285.970218)
		(end 341.22106 -286.236156)
		(width 0.350012)
		(layer "F.Cu")
		(net "GND")
	)
	(segment
		(start 22.147022 -11.26998)
		(end 22.145752 -10.16508)
		(width 0.3556)
		(layer "F.Cu")
		(net "GND")
	)
	(segment
		(start 317.862204 -392.999722)
		(end 317.270384 -392.999722)
		(width 0.254)
		(layer "F.Cu")
		(net "GND")
	)
	(segment
		(start 372.018052 -399.663158)
		(end 372.116604 -399.76171)
		(width 0.254)
		(layer "F.Cu")
		(net "GND")
	)
	(segment
		(start 383.69113 -398.542002)
		(end 383.17043 -398.542002)
		(width 0.254)
		(layer "F.Cu")
		(net "GND")
	)
	(segment
		(start 354.598224 -395.0208)
		(end 353.906074 -394.831062)
		(width 0.254)
		(layer "F.Cu")
		(net "GND")
	)
	(segment
		(start 93.44787 -226.930458)
		(end 92.981018 -226.66452)
		(width 0.350012)
		(layer "F.Cu")
		(net "GND")
	)
	(segment
		(start 99.266248 -31.435548)
		(end 99.278186 -31.447486)
		(width 0.381)
		(layer "F.Cu")
		(net "GND")
	)
	(segment
		(start 386.516372 -399.76171)
		(end 386.41782 -399.663158)
		(width 0.254)
		(layer "F.Cu")
		(net "GND")
	)
	(segment
		(start 420.49827 -396.520924)
		(end 419.946328 -396.710662)
		(width 0.254)
		(layer "F.Cu")
		(net "GND")
	)
	(segment
		(start 72.662034 -12.372848)
		(end 72.663304 -12.374118)
		(width 0.3556)
		(layer "F.Cu")
		(net "GND")
	)
	(segment
		(start 62.41796 -383.92227)
		(end 62.470538 -384.617722)
		(width 0.254)
		(layer "F.Cu")
		(net "GND")
	)
	(segment
		(start 326.81799 -234.220004)
		(end 326.351138 -233.954066)
		(width 0.350012)
		(layer "F.Cu")
		(net "GND")
	)
	(segment
		(start 322.10121 -392.999722)
		(end 322.10121 -392.387836)
		(width 0.254)
		(layer "F.Cu")
		(net "GND")
	)
	(segment
		(start 128.018032 -383.402586)
		(end 128.018032 -382.951482)
		(width 0.254)
		(layer "F.Cu")
		(net "GND")
	)
	(segment
		(start 92.62491 -336.854292)
		(end 93.053408 -336.854292)
		(width 0.2286)
		(layer "F.Cu")
		(net "GND")
	)
	(segment
		(start 370.057934 -232.599992)
		(end 370.524786 -232.334054)
		(width 0.350012)
		(layer "F.Cu")
		(net "GND")
	)
	(segment
		(start 366.297972 -232.599992)
		(end 366.764824 -232.334054)
		(width 0.350012)
		(layer "F.Cu")
		(net "GND")
	)
	(segment
		(start 357.36784 -241.510058)
		(end 356.901242 -241.24412)
		(width 0.350012)
		(layer "F.Cu")
		(net "GND")
	)
	(segment
		(start 305.418998 -41.906698)
		(end 304.809398 -41.906698)
		(width 0.3556)
		(layer "F.Cu")
		(net "GND")
	)
	(segment
		(start 126.618492 -388.328662)
		(end 125.970538 -388.138924)
		(width 0.254)
		(layer "F.Cu")
		(net "GND")
	)
	(segment
		(start 153.345642 -391.281158)
		(end 153.645616 -390.761474)
		(width 0.254)
		(layer "F.Cu")
		(net "GND")
	)
	(segment
		(start 98.918014 -281.920442)
		(end 98.451162 -282.18638)
		(width 0.350012)
		(layer "F.Cu")
		(net "GND")
	)
	(segment
		(start 396.646908 -8.320024)
		(end 396.646908 -9.423654)
		(width 0.3556)
		(layer "F.Cu")
		(net "GND")
	)
	(segment
		(start 366.597946 -277.060152)
		(end 367.064798 -277.32609)
		(width 0.350012)
		(layer "F.Cu")
		(net "GND")
	)
	(segment
		(start 139.507976 -223.690434)
		(end 139.974828 -223.424496)
		(width 0.350012)
		(layer "F.Cu")
		(net "GND")
	)
	(segment
		(start 100.027994 -228.55047)
		(end 99.561142 -228.284532)
		(width 0.350012)
		(layer "F.Cu")
		(net "GND")
	)
	(segment
		(start 176.072038 -221.135194)
		(end 174.687738 -221.135194)
		(width 0.4572)
		(layer "F.Cu")
		(net "GND")
	)
	(segment
		(start 92.59824 -388.138924)
		(end 92.046298 -388.328662)
		(width 0.254)
		(layer "F.Cu")
		(net "GND")
	)
	(segment
		(start 387.748018 -284.350206)
		(end 388.21487 -284.616144)
		(width 0.350012)
		(layer "F.Cu")
		(net "GND")
	)
	(segment
		(start 403.018752 -398.613122)
		(end 402.248878 -398.613122)
		(width 0.254)
		(layer "F.Cu")
		(net "GND")
	)
	(segment
		(start 265.54811 -228.785166)
		(end 266.93241 -228.785166)
		(width 0.4572)
		(layer "F.Cu")
		(net "GND")
	)
	(segment
		(start 128.52781 -273.010376)
		(end 128.994662 -273.276314)
		(width 0.350012)
		(layer "F.Cu")
		(net "GND")
	)
	(segment
		(start 389.327898 -235.03001)
		(end 389.79475 -234.764072)
		(width 0.350012)
		(layer "F.Cu")
		(net "GND")
	)
	(segment
		(start 55.328058 -275.53539)
		(end 56.712358 -275.53539)
		(width 0.4572)
		(layer "F.Cu")
		(net "GND")
	)
	(segment
		(start 97.452942 -400.015202)
		(end 97.452942 -400.417792)
		(width 0.3302)
		(layer "F.Cu")
		(net "GND")
	)
	(segment
		(start 384.627882 -228.550216)
		(end 385.094734 -228.284278)
		(width 0.350012)
		(layer "F.Cu")
		(net "GND")
	)
	(segment
		(start 369.11788 -247.1801)
		(end 369.584732 -246.914162)
		(width 0.350012)
		(layer "F.Cu")
		(net "GND")
	)
	(segment
		(start 331.987906 -239.890046)
		(end 331.521054 -239.624108)
		(width 0.350012)
		(layer "F.Cu")
		(net "GND")
	)
	(segment
		(start 344.678 -245.560088)
		(end 344.211148 -245.29415)
		(width 0.350012)
		(layer "F.Cu")
		(net "GND")
	)
	(segment
		(start 356.350062 -164.284406)
		(end 356.280212 -164.354256)
		(width 0.381)
		(layer "F.Cu")
		(net "GND")
	)
	(segment
		(start 191.160146 -277.235412)
		(end 189.775846 -277.235412)
		(width 0.4572)
		(layer "F.Cu")
		(net "GND")
	)
	(segment
		(start 376.81789 -391.784586)
		(end 376.81789 -392.004296)
		(width 0.254)
		(layer "F.Cu")
		(net "GND")
	)
	(segment
		(start 373.17807 -285.160212)
		(end 373.644922 -285.42615)
		(width 0.350012)
		(layer "F.Cu")
		(net "GND")
	)
	(segment
		(start 138.66495 -117.11305)
		(end 138.049 -117.729)
		(width 0.381)
		(layer "F.Cu")
		(net "GND")
	)
	(segment
		(start 420.815516 -352.939858)
		(end 421.244014 -352.939858)
		(width 0.2286)
		(layer "F.Cu")
		(net "GND")
	)
	(segment
		(start 161.745676 -383.402586)
		(end 161.745676 -383.622296)
		(width 0.254)
		(layer "F.Cu")
		(net "GND")
	)
	(segment
		(start 420.24427 -399.76171)
		(end 420.145718 -399.663158)
		(width 0.254)
		(layer "F.Cu")
		(net "GND")
	)
	(segment
		(start 124.718064 -390.761474)
		(end 124.770642 -390.160002)
		(width 0.254)
		(layer "F.Cu")
		(net "GND")
	)
	(segment
		(start 165.109144 -343.753948)
		(end 165.109144 -343.122758)
		(width 0.4572)
		(layer "F.Cu")
		(net "GND")
	)
	(segment
		(start 123.827794 -284.35046)
		(end 124.294646 -284.616398)
		(width 0.350012)
		(layer "F.Cu")
		(net "GND")
	)
	(segment
		(start 424.727878 -363.201712)
		(end 424.325796 -362.79963)
		(width 0.3556)
		(layer "F.Cu")
		(net "GND")
	)
	(segment
		(start 21.336 -361.061)
		(end 20.793202 -361.061)
		(width 0.381)
		(layer "F.Cu")
		(net "GND")
	)
	(segment
		(start 410.340302 -140.310616)
		(end 409.792678 -139.762992)
		(width 0.3556)
		(layer "F.Cu")
		(net "GND")
	)
	(segment
		(start 84.047838 -254.470408)
		(end 83.580986 -254.20447)
		(width 0.350012)
		(layer "F.Cu")
		(net "GND")
	)
	(segment
		(start 326.81799 -247.1801)
		(end 326.351138 -246.914162)
		(width 0.350012)
		(layer "F.Cu")
		(net "GND")
	)
	(segment
		(start 341.619332 -21.043646)
		(end 341.619332 -21.680932)
		(width 0.4572)
		(layer "F.Cu")
		(net "GND")
	)
	(segment
		(start 329.937872 -294.88003)
		(end 329.47102 -295.145968)
		(width 0.350012)
		(layer "F.Cu")
		(net "GND")
	)
	(segment
		(start 113.721134 -386.030978)
		(end 113.721134 -385.43103)
		(width 0.254)
		(layer "F.Cu")
		(net "GND")
	)
	(segment
		(start 381.638048 -281.920188)
		(end 382.1049 -282.186126)
		(width 0.350012)
		(layer "F.Cu")
		(net "GND")
	)
	(segment
		(start 385.316476 -400.212814)
		(end 385.316476 -399.76171)
		(width 0.254)
		(layer "F.Cu")
		(net "GND")
	)
	(segment
		(start 308.002432 -412.128462)
		(end 307.918358 -412.212536)
		(width 0.381)
		(layer "F.Cu")
		(net "GND")
	)
	(segment
		(start 357.53421 -326.037702)
		(end 357.278432 -325.781924)
		(width 0.4572)
		(layer "F.Cu")
		(net "GND")
	)
	(segment
		(start 321.816222 -399.76171)
		(end 321.71767 -399.663158)
		(width 0.254)
		(layer "F.Cu")
		(net "GND")
	)
	(segment
		(start 55.328058 -240.68532)
		(end 56.712358 -240.68532)
		(width 0.4572)
		(layer "F.Cu")
		(net "GND")
	)
	(segment
		(start 128.370584 -390.160002)
		(end 127.691134 -390.160002)
		(width 0.254)
		(layer "F.Cu")
		(net "GND")
	)
	(segment
		(start 139.977876 -234.220258)
		(end 140.444728 -233.95432)
		(width 0.350012)
		(layer "F.Cu")
		(net "GND")
	)
	(segment
		(start 169.404792 -101.120448)
		(end 169.506646 -101.018594)
		(width 0.4572)
		(layer "F.Cu")
		(net "GND")
	)
	(segment
		(start 150.560278 -44.585636)
		(end 149.902164 -45.24375)
		(width 0.3556)
		(layer "F.Cu")
		(net "GND")
	)
	(segment
		(start 112.717834 -242.320318)
		(end 113.184686 -242.05438)
		(width 0.350012)
		(layer "F.Cu")
		(net "GND")
	)
	(segment
		(start 79.347822 -223.690434)
		(end 78.88097 -223.424496)
		(width 0.350012)
		(layer "F.Cu")
		(net "GND")
	)
	(segment
		(start 94.217998 -291.64026)
		(end 93.751146 -291.906198)
		(width 0.350012)
		(layer "F.Cu")
		(net "GND")
	)
	(segment
		(start 198.7042 -284.035246)
		(end 197.3199 -284.035246)
		(width 0.4572)
		(layer "F.Cu")
		(net "GND")
	)
	(segment
		(start 301.841408 -116.891308)
		(end 301.169578 -116.891308)
		(width 0.3556)
		(layer "F.Cu")
		(net "GND")
	)
	(segment
		(start 106.137964 -235.84027)
		(end 105.671112 -235.574332)
		(width 0.350012)
		(layer "F.Cu")
		(net "GND")
	)
	(segment
		(start 427.766988 -7.217156)
		(end 427.766988 -8.320024)
		(width 0.3556)
		(layer "F.Cu")
		(net "GND")
	)
	(segment
		(start 337.445604 -391.784586)
		(end 337.445604 -392.004296)
		(width 0.254)
		(layer "F.Cu")
		(net "GND")
	)
	(segment
		(start 370.357908 -285.160212)
		(end 370.82476 -285.42615)
		(width 0.350012)
		(layer "F.Cu")
		(net "GND")
	)
	(segment
		(start 40.256968 -9.423654)
		(end 40.258238 -9.424924)
		(width 0.3556)
		(layer "F.Cu")
		(net "GND")
	)
	(segment
		(start 126.347982 -231.79024)
		(end 126.814834 -231.524302)
		(width 0.350012)
		(layer "F.Cu")
		(net "GND")
	)
	(segment
		(start 394.327888 -279.49017)
		(end 394.982954 -279.49017)
		(width 0.350012)
		(layer "F.Cu")
		(net "GND")
	)
	(segment
		(start 412.955486 -7.215124)
		(end 412.955486 -7.215886)
		(width 0.3556)
		(layer "F.Cu")
		(net "GND")
	)
	(segment
		(start 332.071472 -393.97559)
		(end 332.060042 -393.96416)
		(width 0.254)
		(layer "F.Cu")
		(net "GND")
	)
	(segment
		(start 355.106732 -412.030418)
		(end 355.106732 -411.399482)
		(width 0.381)
		(layer "F.Cu")
		(net "GND")
	)
	(segment
		(start 94.31909 -390.160002)
		(end 94.998286 -390.160002)
		(width 0.254)
		(layer "F.Cu")
		(net "GND")
	)
	(segment
		(start 90.846148 -388.328662)
		(end 90.198448 -388.138924)
		(width 0.254)
		(layer "F.Cu")
		(net "GND")
	)
	(segment
		(start 416.468052 -221.13494)
		(end 415.083752 -221.13494)
		(width 0.4572)
		(layer "F.Cu")
		(net "GND")
	)
	(segment
		(start 333.39786 -239.08004)
		(end 332.931008 -238.814102)
		(width 0.350012)
		(layer "F.Cu")
		(net "GND")
	)
	(segment
		(start 303.268126 -294.235124)
		(end 304.652426 -294.235124)
		(width 0.4572)
		(layer "F.Cu")
		(net "GND")
	)
	(segment
		(start 17.608042 -287.43529)
		(end 18.992342 -287.43529)
		(width 0.4572)
		(layer "F.Cu")
		(net "GND")
	)
	(segment
		(start 236.599984 -56.965088)
		(end 237.616238 -56.965088)
		(width 0.381)
		(layer "F.Cu")
		(net "GND")
	)
	(segment
		(start 299.82414 -209.23504)
		(end 298.43984 -209.23504)
		(width 0.4572)
		(layer "F.Cu")
		(net "GND")
	)
	(segment
		(start 343.268046 -254.470154)
		(end 342.801194 -254.204216)
		(width 0.350012)
		(layer "F.Cu")
		(net "GND")
	)
	(segment
		(start 86.868 -247.99036)
		(end 86.401148 -247.724422)
		(width 0.350012)
		(layer "F.Cu")
		(net "GND")
	)
	(segment
		(start 350.318832 -398.542002)
		(end 349.798132 -398.542002)
		(width 0.254)
		(layer "F.Cu")
		(net "GND")
	)
	(segment
		(start 340.277958 -281.920188)
		(end 339.811106 -282.186126)
		(width 0.350012)
		(layer "F.Cu")
		(net "GND")
	)
	(segment
		(start 50.254662 -402.87194)
		(end 49.813972 -402.87194)
		(width 0.381)
		(layer "F.Cu")
		(net "GND")
	)
	(segment
		(start 407.298398 -398.542002)
		(end 406.618948 -398.542002)
		(width 0.254)
		(layer "F.Cu")
		(net "GND")
	)
	(segment
		(start 331.518006 -237.460028)
		(end 331.051154 -237.19409)
		(width 0.350012)
		(layer "F.Cu")
		(net "GND")
	)
	(segment
		(start 338.097876 -250.420124)
		(end 337.631024 -250.154186)
		(width 0.350012)
		(layer "F.Cu")
		(net "GND")
	)
	(segment
		(start 345.618054 -229.360222)
		(end 345.151202 -229.094284)
		(width 0.350012)
		(layer "F.Cu")
		(net "GND")
	)
	(segment
		(start 161.745676 -391.281158)
		(end 162.04565 -390.761474)
		(width 0.254)
		(layer "F.Cu")
		(net "GND")
	)
	(segment
		(start 367.538 -291.640006)
		(end 368.004852 -291.905944)
		(width 0.350012)
		(layer "F.Cu")
		(net "GND")
	)
	(segment
		(start 124.767848 -266.530328)
		(end 125.2347 -266.796266)
		(width 0.350012)
		(layer "F.Cu")
		(net "GND")
	)
	(segment
		(start 379.457966 -226.120198)
		(end 379.924818 -225.85426)
		(width 0.350012)
		(layer "F.Cu")
		(net "GND")
	)
	(segment
		(start 303.717706 -391.784586)
		(end 303.717706 -391.333482)
		(width 0.254)
		(layer "F.Cu")
		(net "GND")
	)
	(segment
		(start 126.223522 -40.517318)
		(end 125.783848 -40.3352)
		(width 0.381)
		(layer "F.Cu")
		(net "GND")
	)
	(segment
		(start 125.877828 -232.600246)
		(end 126.34468 -232.334308)
		(width 0.350012)
		(layer "F.Cu")
		(net "GND")
	)
	(segment
		(start 100.797868 -291.64026)
		(end 100.331016 -291.906198)
		(width 0.350012)
		(layer "F.Cu")
		(net "GND")
	)
	(segment
		(start 183.522112 -115.452906)
		(end 183.132222 -115.842796)
		(width 0.254)
		(layer "F.Cu")
		(net "GND")
	)
	(segment
		(start 333.697834 -280.300176)
		(end 333.230982 -280.566114)
		(width 0.350012)
		(layer "F.Cu")
		(net "GND")
	)
	(segment
		(start 79.177896 -285.160466)
		(end 78.711044 -285.426404)
		(width 0.350012)
		(layer "F.Cu")
		(net "GND")
	)
	(segment
		(start 4.539488 -137.61847)
		(end 6.829298 -137.61847)
		(width 0.3556)
		(layer "F.Cu")
		(net "GND")
	)
	(segment
		(start 100.027994 -239.8903)
		(end 99.561142 -239.624362)
		(width 0.350012)
		(layer "F.Cu")
		(net "GND")
	)
	(segment
		(start 113.487962 -273.010376)
		(end 113.954814 -273.276314)
		(width 0.350012)
		(layer "F.Cu")
		(net "GND")
	)
	(segment
		(start 80.598264 -390.160002)
		(end 81.118964 -390.160002)
		(width 0.254)
		(layer "F.Cu")
		(net "GND")
	)
	(segment
		(start 416.556952 -9.423654)
		(end 416.558222 -9.424924)
		(width 0.3556)
		(layer "F.Cu")
		(net "GND")
	)
	(segment
		(start 128.76403 -57.882028)
		(end 129.83718 -57.882028)
		(width 0.4064)
		(layer "F.Cu")
		(net "GND")
	)
	(segment
		(start 118.827804 -223.690434)
		(end 119.294656 -223.424496)
		(width 0.350012)
		(layer "F.Cu")
		(net "GND")
	)
	(segment
		(start 66.726054 -338.065364)
		(end 66.757042 -338.065364)
		(width 0.2286)
		(layer "F.Cu")
		(net "GND")
	)
	(segment
		(start 302.620934 -397.412972)
		(end 302.620934 -396.712948)
		(width 0.254)
		(layer "F.Cu")
		(net "GND")
	)
	(segment
		(start 386.03809 -248.800112)
		(end 386.504942 -248.534174)
		(width 0.350012)
		(layer "F.Cu")
		(net "GND")
	)
	(segment
		(start 64.518032 -382.951482)
		(end 64.616584 -382.85293)
		(width 0.254)
		(layer "F.Cu")
		(net "GND")
	)
	(segment
		(start 407.446988 -7.217156)
		(end 407.446988 -8.320024)
		(width 0.3556)
		(layer "F.Cu")
		(net "GND")
	)
	(segment
		(start 143.171672 -385.59359)
		(end 143.160242 -385.58216)
		(width 0.254)
		(layer "F.Cu")
		(net "GND")
	)
	(segment
		(start 106.137964 -237.460282)
		(end 105.671112 -237.194344)
		(width 0.350012)
		(layer "F.Cu")
		(net "GND")
	)
	(segment
		(start 162.618928 -390.160002)
		(end 162.098228 -390.160002)
		(width 0.254)
		(layer "F.Cu")
		(net "GND")
	)
	(segment
		(start 95.627952 -268.15034)
		(end 95.1611 -268.416278)
		(width 0.350012)
		(layer "F.Cu")
		(net "GND")
	)
	(segment
		(start 304.28692 -428.82058)
		(end 304.22342 -428.75708)
		(width 0.4318)
		(layer "F.Cu")
		(net "GND")
	)
	(segment
		(start 387.748018 -279.49017)
		(end 388.21487 -279.756108)
		(width 0.350012)
		(layer "F.Cu")
		(net "GND")
	)
	(segment
		(start 236.58957 -149.923754)
		(end 237.527846 -149.923754)
		(width 0.3556)
		(layer "F.Cu")
		(net "GND")
	)
	(segment
		(start 355.957886 -227.74021)
		(end 355.491034 -227.474272)
		(width 0.350012)
		(layer "F.Cu")
		(net "GND")
	)
	(segment
		(start 64.870584 -388.138924)
		(end 65.518538 -388.328662)
		(width 0.254)
		(layer "F.Cu")
		(net "GND")
	)
	(segment
		(start 53.816504 -394.584936)
		(end 53.816504 -393.927838)
		(width 0.381)
		(layer "F.Cu")
		(net "GND")
	)
	(segment
		(start 387.917944 -255.28016)
		(end 388.384796 -255.014222)
		(width 0.350012)
		(layer "F.Cu")
		(net "GND")
	)
	(segment
		(start 128.227836 -235.030264)
		(end 128.694688 -234.764326)
		(width 0.350012)
		(layer "F.Cu")
		(net "GND")
	)
	(segment
		(start 98.617786 -226.120452)
		(end 98.150934 -225.854514)
		(width 0.350012)
		(layer "F.Cu")
		(net "GND")
	)
	(segment
		(start 166.074344 -343.753948)
		(end 166.074344 -343.122758)
		(width 0.4572)
		(layer "F.Cu")
		(net "GND")
	)
	(segment
		(start 176.49698 -92.493084)
		(end 176.497742 -92.493846)
		(width 0.381)
		(layer "F.Cu")
		(net "GND")
	)
	(segment
		(start 85.045804 -391.281158)
		(end 85.144356 -391.37971)
		(width 0.254)
		(layer "F.Cu")
		(net "GND")
	)
	(segment
		(start 374.28805 -249.610118)
		(end 374.754902 -249.34418)
		(width 0.350012)
		(layer "F.Cu")
		(net "GND")
	)
	(segment
		(start 183.616092 -295.9354)
		(end 182.231792 -295.9354)
		(width 0.4572)
		(layer "F.Cu")
		(net "GND")
	)
	(segment
		(start 108.017818 -227.740464)
		(end 107.550966 -227.474526)
		(width 0.350012)
		(layer "F.Cu")
		(net "GND")
	)
	(segment
		(start 366.64392 -394.800074)
		(end 366.64392 -393.97559)
		(width 0.254)
		(layer "F.Cu")
		(net "GND")
	)
	(segment
		(start 307.670454 -398.542002)
		(end 307.617876 -399.143474)
		(width 0.254)
		(layer "F.Cu")
		(net "GND")
	)
	(segment
		(start 370.505228 -146.552158)
		(end 369.895628 -146.552158)
		(width 0.381)
		(layer "F.Cu")
		(net "GND")
	)
	(segment
		(start 375.369074 -177.48631)
		(end 375.73839 -177.48631)
		(width 0.381)
		(layer "F.Cu")
		(net "GND")
	)
	(segment
		(start 75.715114 -17.050512)
		(end 75.715114 -17.096486)
		(width 0.4572)
		(layer "F.Cu")
		(net "GND")
	)
	(segment
		(start 25.746964 -7.217156)
		(end 25.746964 -8.320024)
		(width 0.3556)
		(layer "F.Cu")
		(net "GND")
	)
	(segment
		(start 376.167904 -243.13007)
		(end 376.634756 -242.864132)
		(width 0.350012)
		(layer "F.Cu")
		(net "GND")
	)
	(segment
		(start 347.968062 -226.930204)
		(end 347.50121 -226.664266)
		(width 0.350012)
		(layer "F.Cu")
		(net "GND")
	)
	(segment
		(start 44.28236 -351.932748)
		(end 44.87037 -351.932748)
		(width 0.381)
		(layer "F.Cu")
		(net "GND")
	)
	(segment
		(start 210.786218 -138.077448)
		(end 209.944208 -138.077448)
		(width 0.4572)
		(layer "F.Cu")
		(net "GND")
	)
	(segment
		(start 352.718878 -398.542002)
		(end 352.198178 -398.542002)
		(width 0.254)
		(layer "F.Cu")
		(net "GND")
	)
	(segment
		(start 101.737922 -281.920442)
		(end 101.27107 -282.18638)
		(width 0.350012)
		(layer "F.Cu")
		(net "GND")
	)
	(segment
		(start 302.870362 -396.46352)
		(end 302.620934 -396.712948)
		(width 0.254)
		(layer "F.Cu")
		(net "GND")
	)
	(segment
		(start 92.037916 -248.800366)
		(end 91.571064 -248.534428)
		(width 0.350012)
		(layer "F.Cu")
		(net "GND")
	)
	(segment
		(start 147.82419 -102.694232)
		(end 147.16379 -102.694232)
		(width 0.4064)
		(layer "F.Cu")
		(net "GND")
	)
	(segment
		(start 269.648178 -211.784946)
		(end 268.263878 -211.784946)
		(width 0.4572)
		(layer "F.Cu")
		(net "GND")
	)
	(segment
		(start 120.916446 -391.37971)
		(end 120.817894 -391.281158)
		(width 0.254)
		(layer "F.Cu")
		(net "GND")
	)
	(segment
		(start 116.477796 -240.700306)
		(end 116.944648 -240.434368)
		(width 0.350012)
		(layer "F.Cu")
		(net "GND")
	)
	(segment
		(start 47.784004 -212.635338)
		(end 49.168304 -212.635338)
		(width 0.4572)
		(layer "F.Cu")
		(net "GND")
	)
	(segment
		(start 357.668068 -273.010122)
		(end 357.201216 -273.27606)
		(width 0.350012)
		(layer "F.Cu")
		(net "GND")
	)
	(segment
		(start 58.666888 -8.320024)
		(end 58.666888 -9.423654)
		(width 0.3556)
		(layer "F.Cu")
		(net "GND")
	)
	(segment
		(start 289.00501 -399.286984)
		(end 288.587942 -399.704052)
		(width 0.254)
		(layer "F.Cu")
		(net "GND")
	)
	(segment
		(start 88.390222 -384.617722)
		(end 87.798402 -384.617722)
		(width 0.254)
		(layer "F.Cu")
		(net "GND")
	)
	(segment
		(start 128.018032 -383.402586)
		(end 128.018032 -383.622296)
		(width 0.254)
		(layer "F.Cu")
		(net "GND")
	)
	(segment
		(start 342.158066 -283.5402)
		(end 341.691214 -283.806138)
		(width 0.350012)
		(layer "F.Cu")
		(net "GND")
	)
	(segment
		(start 375.528078 -268.150086)
		(end 375.99493 -268.416024)
		(width 0.350012)
		(layer "F.Cu")
		(net "GND")
	)
	(segment
		(start 421.942514 -393.59332)
		(end 422.462198 -394.113004)
		(width 0.254)
		(layer "F.Cu")
		(net "GND")
	)
	(segment
		(start 133.69798 -277.060406)
		(end 134.164832 -277.326344)
		(width 0.350012)
		(layer "F.Cu")
		(net "GND")
	)
	(segment
		(start 32.695896 -315.485272)
		(end 34.080196 -315.485272)
		(width 0.4572)
		(layer "F.Cu")
		(net "GND")
	)
	(segment
		(start 77.767942 -287.590484)
		(end 77.112876 -287.590484)
		(width 0.350012)
		(layer "F.Cu")
		(net "GND")
	)
	(segment
		(start 389.627872 -294.070024)
		(end 390.094724 -294.335962)
		(width 0.350012)
		(layer "F.Cu")
		(net "GND")
	)
	(segment
		(start 97.04578 -383.402586)
		(end 97.04578 -382.951482)
		(width 0.254)
		(layer "F.Cu")
		(net "GND")
	)
	(segment
		(start 301.841408 -109.779308)
		(end 301.231808 -109.779308)
		(width 0.381)
		(layer "F.Cu")
		(net "GND")
	)
	(segment
		(start 205.089506 -338.995004)
		(end 205.089506 -339.428836)
		(width 0.4572)
		(layer "F.Cu")
		(net "GND")
	)
	(segment
		(start 335.98993 -392.999722)
		(end 336.598006 -392.999722)
		(width 0.254)
		(layer "F.Cu")
		(net "GND")
	)
	(segment
		(start 38.4556 -7.215886)
		(end 38.45687 -7.217156)
		(width 0.3556)
		(layer "F.Cu")
		(net "GND")
	)
	(segment
		(start 318.117728 -392.004296)
		(end 318.417702 -392.30427)
		(width 0.254)
		(layer "F.Cu")
		(net "GND")
	)
	(segment
		(start 17.608042 -200.735438)
		(end 18.992342 -200.735438)
		(width 0.4572)
		(layer "F.Cu")
		(net "GND")
	)
	(segment
		(start 283.083254 -436.623714)
		(end 282.448254 -436.623714)
		(width 0.4318)
		(layer "F.Cu")
		(net "GND")
	)
	(segment
		(start 351.087944 -269.770098)
		(end 350.621092 -270.036036)
		(width 0.350012)
		(layer "F.Cu")
		(net "GND")
	)
	(segment
		(start 100.285296 -422.83253)
		(end 100.285296 -423.44848)
		(width 0.381)
		(layer "F.Cu")
		(net "GND")
	)
	(segment
		(start 353.607878 -231.789986)
		(end 353.141026 -231.524048)
		(width 0.350012)
		(layer "F.Cu")
		(net "GND")
	)
	(segment
		(start 135.107934 -261.670292)
		(end 135.574786 -261.93623)
		(width 0.350012)
		(layer "F.Cu")
		(net "GND")
	)
	(segment
		(start 115.83797 -275.440394)
		(end 116.304822 -275.706332)
		(width 0.350012)
		(layer "F.Cu")
		(net "GND")
	)
	(segment
		(start 128.69799 -224.50044)
		(end 129.164842 -224.234502)
		(width 0.350012)
		(layer "F.Cu")
		(net "GND")
	)
	(segment
		(start 29.252164 -284.035246)
		(end 27.867864 -284.035246)
		(width 0.4572)
		(layer "F.Cu")
		(net "GND")
	)
	(segment
		(start 105.967784 -266.530328)
		(end 105.500932 -266.796266)
		(width 0.350012)
		(layer "F.Cu")
		(net "GND")
	)
	(segment
		(start 99.278186 -31.447486)
		(end 99.4664 -31.259272)
		(width 0.381)
		(layer "F.Cu")
		(net "GND")
	)
	(segment
		(start 168.527984 -209.235294)
		(end 167.143684 -209.235294)
		(width 0.4572)
		(layer "F.Cu")
		(net "GND")
	)
	(segment
		(start 378.01804 -391.333482)
		(end 378.116592 -391.23493)
		(width 0.254)
		(layer "F.Cu")
		(net "GND")
	)
	(segment
		(start 351.728024 -249.610118)
		(end 351.261172 -249.34418)
		(width 0.350012)
		(layer "F.Cu")
		(net "GND")
	)
	(segment
		(start 391.03808 -291.640006)
		(end 391.504678 -291.905944)
		(width 0.350012)
		(layer "F.Cu")
		(net "GND")
	)
	(segment
		(start 368.682016 -395.613128)
		(end 369.2017 -395.313154)
		(width 0.254)
		(layer "F.Cu")
		(net "GND")
	)
	(segment
		(start 340.277958 -262.480044)
		(end 339.811106 -262.745982)
		(width 0.350012)
		(layer "F.Cu")
		(net "GND")
	)
	(segment
		(start 302.51781 -391.784586)
		(end 302.51781 -392.004296)
		(width 0.254)
		(layer "F.Cu")
		(net "GND")
	)
	(segment
		(start 409.69819 -396.520924)
		(end 409.146248 -396.710662)
		(width 0.254)
		(layer "F.Cu")
		(net "GND")
	)
	(segment
		(start 222.99295 -76.581)
		(end 222.363538 -76.581)
		(width 0.381)
		(layer "F.Cu")
		(net "GND")
	)
	(segment
		(start 166.18077 -394.0937)
		(end 166.18077 -393.509246)
		(width 0.254)
		(layer "F.Cu")
		(net "GND")
	)
	(segment
		(start 355.487986 -249.610118)
		(end 355.021134 -249.34418)
		(width 0.350012)
		(layer "F.Cu")
		(net "GND")
	)
	(segment
		(start 356.25786 -273.820128)
		(end 355.791008 -274.086066)
		(width 0.350012)
		(layer "F.Cu")
		(net "GND")
	)
	(segment
		(start 380.39802 -250.420124)
		(end 380.864872 -250.154186)
		(width 0.350012)
		(layer "F.Cu")
		(net "GND")
	)
	(segment
		(start 92.037916 -224.50044)
		(end 91.571064 -224.234502)
		(width 0.350012)
		(layer "F.Cu")
		(net "GND")
	)
	(segment
		(start 32.695896 -212.635338)
		(end 34.080196 -212.635338)
		(width 0.4572)
		(layer "F.Cu")
		(net "GND")
	)
	(segment
		(start 402.046948 -12.372848)
		(end 402.046948 -11.26998)
		(width 0.3556)
		(layer "F.Cu")
		(net "GND")
	)
	(segment
		(start 388.217918 -262.480044)
		(end 388.68477 -262.745982)
		(width 0.350012)
		(layer "F.Cu")
		(net "GND")
	)
	(segment
		(start 38.78707 -172.820584)
		(end 38.78707 -173.537372)
		(width 0.3556)
		(layer "F.Cu")
		(net "GND")
	)
	(segment
		(start 123.357894 -262.480298)
		(end 123.824746 -262.746236)
		(width 0.350012)
		(layer "F.Cu")
		(net "GND")
	)
	(segment
		(start 364.717838 -277.060152)
		(end 365.18469 -277.32609)
		(width 0.350012)
		(layer "F.Cu")
		(net "GND")
	)
	(segment
		(start 55.328058 -228.78542)
		(end 56.712358 -228.78542)
		(width 0.4572)
		(layer "F.Cu")
		(net "GND")
	)
	(segment
		(start 180.710332 -91.669616)
		(end 180.721 -91.658948)
		(width 0.4572)
		(layer "F.Cu")
		(net "GND")
	)
	(segment
		(start 363.00791 -231.789986)
		(end 363.474762 -231.524048)
		(width 0.350012)
		(layer "F.Cu")
		(net "GND")
	)
	(segment
		(start 48.918114 -382.951482)
		(end 49.016666 -382.85293)
		(width 0.254)
		(layer "F.Cu")
		(net "GND")
	)
	(segment
		(start 349.378016 -237.460028)
		(end 348.911164 -237.19409)
		(width 0.350012)
		(layer "F.Cu")
		(net "GND")
	)
	(segment
		(start 384.927856 -264.910062)
		(end 385.394708 -265.176)
		(width 0.350012)
		(layer "F.Cu")
		(net "GND")
	)
	(segment
		(start 376.167904 -246.370094)
		(end 376.634756 -246.104156)
		(width 0.350012)
		(layer "F.Cu")
		(net "GND")
	)
	(segment
		(start 86.2457 -383.402586)
		(end 86.2457 -383.622296)
		(width 0.254)
		(layer "F.Cu")
		(net "GND")
	)
	(segment
		(start 77.767942 -274.630388)
		(end 77.112876 -274.630388)
		(width 0.350012)
		(layer "F.Cu")
		(net "GND")
	)
	(segment
		(start 68.672456 -29.29001)
		(end 68.672456 -30.07741)
		(width 0.254)
		(layer "F.Cu")
		(net "GND")
	)
	(segment
		(start 114.817906 -383.402586)
		(end 114.817906 -382.951482)
		(width 0.254)
		(layer "F.Cu")
		(net "GND")
	)
	(segment
		(start 70.863206 -12.374118)
		(end 70.863206 -12.37488)
		(width 0.3556)
		(layer "F.Cu")
		(net "GND")
	)
	(segment
		(start 51.884072 -314.635388)
		(end 50.499772 -314.635388)
		(width 0.4572)
		(layer "F.Cu")
		(net "GND")
	)
	(segment
		(start 350.31807 -234.220004)
		(end 349.851218 -233.954066)
		(width 0.350012)
		(layer "F.Cu")
		(net "GND")
	)
	(segment
		(start 179.516024 -306.135278)
		(end 180.900324 -306.135278)
		(width 0.4572)
		(layer "F.Cu")
		(net "GND")
	)
	(segment
		(start 374.417844 -391.784586)
		(end 374.417844 -392.004042)
		(width 0.2032)
		(layer "F.Cu")
		(net "GND")
	)
	(segment
		(start 121.170446 -390.160002)
		(end 120.49125 -390.160002)
		(width 0.254)
		(layer "F.Cu")
		(net "GND")
	)
	(segment
		(start 352.497898 -270.580104)
		(end 352.031046 -270.846042)
		(width 0.350012)
		(layer "F.Cu")
		(net "GND")
	)
	(segment
		(start 347.931232 -21.256498)
		(end 347.931232 -22.247098)
		(width 0.4572)
		(layer "F.Cu")
		(net "GND")
	)
	(segment
		(start 98.344736 -124.728478)
		(end 98.344736 -125.573028)
		(width 0.4572)
		(layer "F.Cu")
		(net "GND")
	)
	(segment
		(start 303.268126 -238.13516)
		(end 304.652426 -238.13516)
		(width 0.4572)
		(layer "F.Cu")
		(net "GND")
	)
	(segment
		(start 84.987892 -249.610372)
		(end 84.52104 -249.344434)
		(width 0.350012)
		(layer "F.Cu")
		(net "GND")
	)
	(segment
		(start 265.54811 -287.435036)
		(end 266.93241 -287.435036)
		(width 0.4572)
		(layer "F.Cu")
		(net "GND")
	)
	(segment
		(start 183.860694 -12.817348)
		(end 183.535574 -12.492228)
		(width 0.3556)
		(layer "F.Cu")
		(net "GND")
	)
	(segment
		(start 151.044148 -391.37971)
		(end 150.945596 -391.281158)
		(width 0.254)
		(layer "F.Cu")
		(net "GND")
	)
	(segment
		(start 385.39801 -268.960092)
		(end 385.864862 -269.22603)
		(width 0.350012)
		(layer "F.Cu")
		(net "GND")
	)
	(segment
		(start 318.117728 -391.784586)
		(end 318.117728 -392.004296)
		(width 0.254)
		(layer "F.Cu")
		(net "GND")
	)
	(segment
		(start 338.097876 -243.940076)
		(end 337.631024 -243.674138)
		(width 0.350012)
		(layer "F.Cu")
		(net "GND")
	)
	(segment
		(start 346.557854 -253.660148)
		(end 346.091002 -253.39421)
		(width 0.350012)
		(layer "F.Cu")
		(net "GND")
	)
	(segment
		(start 348.737936 -291.640006)
		(end 348.271084 -291.905944)
		(width 0.350012)
		(layer "F.Cu")
		(net "GND")
	)
	(segment
		(start 393.097004 -320.4845)
		(end 393.097004 -319.794128)
		(width 0.508)
		(layer "F.Cu")
		(net "GND")
	)
	(segment
		(start 114.618516 -388.328662)
		(end 113.970562 -388.08152)
		(width 0.254)
		(layer "F.Cu")
		(net "GND")
	)
	(segment
		(start 386.338064 -285.160212)
		(end 386.804916 -285.42615)
		(width 0.350012)
		(layer "F.Cu")
		(net "GND")
	)
	(segment
		(start 82.848958 -68.64604)
		(end 84.074 -68.64604)
		(width 0.381)
		(layer "F.Cu")
		(net "GND")
	)
	(segment
		(start 411.019752 -140.310616)
		(end 410.659326 -140.310616)
		(width 0.1778)
		(layer "F.Cu")
		(net "GND")
	)
	(segment
		(start 110.367826 -244.750336)
		(end 109.900974 -244.484398)
		(width 0.350012)
		(layer "F.Cu")
		(net "GND")
	)
	(segment
		(start 56.47055 -386.6388)
		(end 55.778654 -386.449062)
		(width 0.254)
		(layer "F.Cu")
		(net "GND")
	)
	(segment
		(start 108.317792 -273.820382)
		(end 107.85094 -274.08632)
		(width 0.350012)
		(layer "F.Cu")
		(net "GND")
	)
	(segment
		(start 391.50798 -264.910062)
		(end 391.974832 -265.176)
		(width 0.350012)
		(layer "F.Cu")
		(net "GND")
	)
	(segment
		(start 169.19956 -16.617442)
		(end 169.19956 -17.585944)
		(width 0.3556)
		(layer "F.Cu")
		(net "GND")
	)
	(segment
		(start 348.437962 -224.500186)
		(end 347.97111 -224.234248)
		(width 0.350012)
		(layer "F.Cu")
		(net "GND")
	)
	(segment
		(start 121.177812 -230.980234)
		(end 121.644664 -230.71455)
		(width 0.350012)
		(layer "F.Cu")
		(net "GND")
	)
	(segment
		(start 45.582078 -387.231128)
		(end 45.105066 -387.04774)
		(width 0.254)
		(layer "F.Cu")
		(net "GND")
	)
	(segment
		(start 93.44787 -256.09042)
		(end 92.981018 -255.824482)
		(width 0.350012)
		(layer "F.Cu")
		(net "GND")
	)
	(segment
		(start 100.797868 -270.580358)
		(end 100.331016 -270.846296)
		(width 0.350012)
		(layer "F.Cu")
		(net "GND")
	)
	(segment
		(start 380.86792 -230.169974)
		(end 381.334772 -229.904036)
		(width 0.350012)
		(layer "F.Cu")
		(net "GND")
	)
	(segment
		(start 348.437962 -237.460028)
		(end 347.97111 -237.19409)
		(width 0.350012)
		(layer "F.Cu")
		(net "GND")
	)
	(segment
		(start 419.245796 -399.143474)
		(end 419.298374 -398.542002)
		(width 0.254)
		(layer "F.Cu")
		(net "GND")
	)
	(segment
		(start 368.947954 -281.110182)
		(end 369.414806 -281.37612)
		(width 0.350012)
		(layer "F.Cu")
		(net "GND")
	)
	(segment
		(start 194.604132 -287.43529)
		(end 195.988432 -287.43529)
		(width 0.4572)
		(layer "F.Cu")
		(net "GND")
	)
	(segment
		(start 107.078018 -226.120452)
		(end 106.611166 -225.854514)
		(width 0.350012)
		(layer "F.Cu")
		(net "GND")
	)
	(segment
		(start 284.736032 -230.485188)
		(end 283.351732 -230.485188)
		(width 0.4572)
		(layer "F.Cu")
		(net "GND")
	)
	(segment
		(start 421.09009 -392.999722)
		(end 420.49827 -392.999722)
		(width 0.254)
		(layer "F.Cu")
		(net "GND")
	)
	(segment
		(start 84.347812 -285.970472)
		(end 83.88096 -286.23641)
		(width 0.350012)
		(layer "F.Cu")
		(net "GND")
	)
	(segment
		(start 92.33789 -286.780478)
		(end 91.871038 -287.046162)
		(width 0.350012)
		(layer "F.Cu")
		(net "GND")
	)
	(segment
		(start 99.55784 -237.460282)
		(end 99.090988 -237.194344)
		(width 0.350012)
		(layer "F.Cu")
		(net "GND")
	)
	(segment
		(start 101.512878 -138.91641)
		(end 102.348284 -139.751816)
		(width 0.381)
		(layer "F.Cu")
		(net "GND")
	)
	(segment
		(start 92.33789 -268.960346)
		(end 91.871038 -269.226284)
		(width 0.350012)
		(layer "F.Cu")
		(net "GND")
	)
	(segment
		(start 123.997974 -242.320318)
		(end 124.464826 -242.05438)
		(width 0.350012)
		(layer "F.Cu")
		(net "GND")
	)
	(segment
		(start 415.018982 -398.542002)
		(end 414.498282 -398.542002)
		(width 0.254)
		(layer "F.Cu")
		(net "GND")
	)
	(segment
		(start 340.277958 -264.100056)
		(end 339.811106 -264.365994)
		(width 0.350012)
		(layer "F.Cu")
		(net "GND")
	)
	(segment
		(start 81.106264 -386.449062)
		(end 80.598264 -386.6388)
		(width 0.254)
		(layer "F.Cu")
		(net "GND")
	)
	(segment
		(start 123.827794 -273.010376)
		(end 124.294646 -273.276314)
		(width 0.350012)
		(layer "F.Cu")
		(net "GND")
	)
	(segment
		(start 110.609634 -175.604932)
		(end 110.537498 -175.778922)
		(width 0.2286)
		(layer "F.Cu")
		(net "GND")
	)
	(segment
		(start 80.573372 -176.40935)
		(end 80.712818 -176.40935)
		(width 0.4572)
		(layer "F.Cu")
		(net "GND")
	)
	(segment
		(start 102.677976 -268.960346)
		(end 102.211124 -269.226284)
		(width 0.350012)
		(layer "F.Cu")
		(net "GND")
	)
	(segment
		(start 419.890194 -392.999722)
		(end 419.298374 -392.999722)
		(width 0.254)
		(layer "F.Cu")
		(net "GND")
	)
	(segment
		(start 422.40708 -436.086758)
		(end 423.04208 -436.086758)
		(width 0.4318)
		(layer "F.Cu")
		(net "GND")
	)
	(segment
		(start 132.927852 -243.130324)
		(end 133.394704 -242.864386)
		(width 0.350012)
		(layer "F.Cu")
		(net "GND")
	)
	(segment
		(start 376.167904 -228.550216)
		(end 376.634756 -228.284278)
		(width 0.350012)
		(layer "F.Cu")
		(net "GND")
	)
	(segment
		(start 288.87928 -394.719048)
		(end 288.463736 -394.719048)
		(width 0.254)
		(layer "F.Cu")
		(net "GND")
	)
	(segment
		(start 90.627962 -254.470408)
		(end 90.16111 -254.20447)
		(width 0.350012)
		(layer "F.Cu")
		(net "GND")
	)
	(segment
		(start 108.317792 -280.30043)
		(end 107.85094 -280.566368)
		(width 0.350012)
		(layer "F.Cu")
		(net "GND")
	)
	(segment
		(start 288.180018 -312.935112)
		(end 289.564318 -312.935112)
		(width 0.4572)
		(layer "F.Cu")
		(net "GND")
	)
	(segment
		(start 82.467958 -277.870412)
		(end 82.001106 -278.13635)
		(width 0.350012)
		(layer "F.Cu")
		(net "GND")
	)
	(segment
		(start 97.207832 -235.030264)
		(end 96.74098 -234.764326)
		(width 0.350012)
		(layer "F.Cu")
		(net "GND")
	)
	(segment
		(start 364.366302 -27.89555)
		(end 364.366302 -27.1653)
		(width 0.4572)
		(layer "F.Cu")
		(net "GND")
	)
	(segment
		(start 330.408026 -268.150086)
		(end 329.941174 -268.416024)
		(width 0.350012)
		(layer "F.Cu")
		(net "GND")
	)
	(segment
		(start 85.757766 -264.10031)
		(end 85.290914 -264.366248)
		(width 0.350012)
		(layer "F.Cu")
		(net "GND")
	)
	(segment
		(start 156.69006 -384.617722)
		(end 157.29839 -384.617722)
		(width 0.254)
		(layer "F.Cu")
		(net "GND")
	)
	(segment
		(start 97.677986 -256.900426)
		(end 97.211134 -256.634488)
		(width 0.350012)
		(layer "F.Cu")
		(net "GND")
	)
	(segment
		(start 120.707912 -239.8903)
		(end 121.174764 -239.624362)
		(width 0.350012)
		(layer "F.Cu")
		(net "GND")
	)
	(segment
		(start 413.298386 -396.520924)
		(end 413.946086 -396.710662)
		(width 0.254)
		(layer "F.Cu")
		(net "GND")
	)
	(segment
		(start 365.357918 -247.1801)
		(end 365.82477 -246.914162)
		(width 0.350012)
		(layer "F.Cu")
		(net "GND")
	)
	(segment
		(start 350.952054 -155.881832)
		(end 351.059242 -155.98902)
		(width 0.381)
		(layer "F.Cu")
		(net "GND")
	)
	(segment
		(start 78.877922 -229.360476)
		(end 78.41107 -229.094538)
		(width 0.350012)
		(layer "F.Cu")
		(net "GND")
	)
	(segment
		(start 136.217914 -224.50044)
		(end 136.684766 -224.234502)
		(width 0.350012)
		(layer "F.Cu")
		(net "GND")
	)
	(segment
		(start 402.214842 -403.336506)
		(end 402.214842 -402.734018)
		(width 0.254)
		(layer "F.Cu")
		(net "GND")
	)
	(segment
		(start 376.467878 -289.209988)
		(end 376.93473 -289.475926)
		(width 0.350012)
		(layer "F.Cu")
		(net "GND")
	)
	(segment
		(start 397.307308 -63.3095)
		(end 399.415508 -63.3095)
		(width 0.4572)
		(layer "F.Cu")
		(net "GND")
	)
	(segment
		(start 331.518006 -230.97998)
		(end 331.051154 -230.714296)
		(width 0.350012)
		(layer "F.Cu")
		(net "GND")
	)
	(segment
		(start 106.137964 -224.50044)
		(end 105.671112 -224.234502)
		(width 0.350012)
		(layer "F.Cu")
		(net "GND")
	)
	(segment
		(start 113.017808 -290.020248)
		(end 113.48466 -290.286186)
		(width 0.350012)
		(layer "F.Cu")
		(net "GND")
	)
	(segment
		(start 140.3096 -403.678898)
		(end 140.461238 -403.830536)
		(width 0.381)
		(layer "F.Cu")
		(net "GND")
	)
	(segment
		(start 133.69798 -267.340334)
		(end 134.164832 -267.606272)
		(width 0.350012)
		(layer "F.Cu")
		(net "GND")
	)
	(segment
		(start 140.27785 -281.920442)
		(end 140.744702 -282.18638)
		(width 0.350012)
		(layer "F.Cu")
		(net "GND")
	)
	(segment
		(start 116.370608 -386.6388)
		(end 115.678458 -386.449062)
		(width 0.254)
		(layer "F.Cu")
		(net "GND")
	)
	(segment
		(start 362.368084 -287.59023)
		(end 362.834682 -287.856168)
		(width 0.350012)
		(layer "F.Cu")
		(net "GND")
	)
	(segment
		(start 11.717782 -415.663634)
		(end 12.987782 -415.663634)
		(width 0.4572)
		(layer "F.Cu")
		(net "GND")
	)
	(segment
		(start 185.922158 -117.052852)
		(end 186.312048 -117.442742)
		(width 0.254)
		(layer "F.Cu")
		(net "GND")
	)
	(segment
		(start 380.770638 -398.542002)
		(end 380.091188 -398.542002)
		(width 0.254)
		(layer "F.Cu")
		(net "GND")
	)
	(segment
		(start 354.378006 -291.640006)
		(end 353.911154 -291.905944)
		(width 0.350012)
		(layer "F.Cu")
		(net "GND")
	)
	(segment
		(start 418.945568 -399.663158)
		(end 419.245796 -399.143474)
		(width 0.254)
		(layer "F.Cu")
		(net "GND")
	)
	(segment
		(start 363.634274 -416.679126)
		(end 363.634274 -416.964114)
		(width 0.381)
		(layer "F.Cu")
		(net "GND")
	)
	(segment
		(start 341.857838 -239.08004)
		(end 341.390986 -238.814102)
		(width 0.350012)
		(layer "F.Cu")
		(net "GND")
	)
	(segment
		(start 352.1456 -399.143474)
		(end 352.198178 -398.542002)
		(width 0.254)
		(layer "F.Cu")
		(net "GND")
	)
	(segment
		(start 40.258238 -12.37488)
		(end 40.258238 -12.374118)
		(width 0.3556)
		(layer "F.Cu")
		(net "GND")
	)
	(segment
		(start 409.44419 -400.212814)
		(end 409.44419 -399.76171)
		(width 0.254)
		(layer "F.Cu")
		(net "GND")
	)
	(segment
		(start 114.428016 -284.35046)
		(end 114.894614 -284.616398)
		(width 0.350012)
		(layer "F.Cu")
		(net "GND")
	)
	(segment
		(start 374.417844 -391.784586)
		(end 374.417844 -391.333482)
		(width 0.2032)
		(layer "F.Cu")
		(net "GND")
	)
	(segment
		(start 341.387938 -233.409998)
		(end 340.921086 -233.14406)
		(width 0.350012)
		(layer "F.Cu")
		(net "GND")
	)
	(segment
		(start 388.491222 -398.542002)
		(end 387.970522 -398.542002)
		(width 0.254)
		(layer "F.Cu")
		(net "GND")
	)
	(segment
		(start 83.577938 -247.180354)
		(end 83.111086 -246.914416)
		(width 0.350012)
		(layer "F.Cu")
		(net "GND")
	)
	(segment
		(start 85.757766 -260.860286)
		(end 85.290914 -261.126224)
		(width 0.350012)
		(layer "F.Cu")
		(net "GND")
	)
	(segment
		(start 183.616092 -202.435206)
		(end 182.231792 -202.435206)
		(width 0.4572)
		(layer "F.Cu")
		(net "GND")
	)
	(segment
		(start 66.671444 -30.163262)
		(end 66.671444 -29.291026)
		(width 0.254)
		(layer "F.Cu")
		(net "GND")
	)
	(segment
		(start 125.02642 -30.815026)
		(end 125.0442 -30.832806)
		(width 0.3556)
		(layer "F.Cu")
		(net "GND")
	)
	(segment
		(start 360.657902 -229.360222)
		(end 361.124754 -229.094284)
		(width 0.350012)
		(layer "F.Cu")
		(net "GND")
	)
	(segment
		(start 133.398006 -239.080294)
		(end 133.864858 -238.814356)
		(width 0.350012)
		(layer "F.Cu")
		(net "GND")
	)
	(segment
		(start 363.778038 -286.780224)
		(end 364.24489 -287.046162)
		(width 0.350012)
		(layer "F.Cu")
		(net "GND")
	)
	(segment
		(start 331.112876 -21.047964)
		(end 331.39507 -20.76577)
		(width 0.381)
		(layer "F.Cu")
		(net "GND")
	)
	(segment
		(start 296.712894 -349.781622)
		(end 297.283378 -349.211138)
		(width 0.2286)
		(layer "F.Cu")
		(net "GND")
	)
	(segment
		(start 420.769542 -175.851312)
		(end 420.682166 -175.938688)
		(width 0.254)
		(layer "F.Cu")
		(net "GND")
	)
	(segment
		(start 427.456092 -221.985078)
		(end 428.840392 -221.985078)
		(width 0.4572)
		(layer "F.Cu")
		(net "GND")
	)
	(segment
		(start 318.300608 -25.6794)
		(end 319.040256 -25.6794)
		(width 0.4572)
		(layer "F.Cu")
		(net "GND")
	)
	(segment
		(start 302.022002 -23.14575)
		(end 302.637952 -23.14575)
		(width 0.4064)
		(layer "F.Cu")
		(net "GND")
	)
	(segment
		(start 124.417836 -383.622042)
		(end 124.417836 -383.402586)
		(width 0.254)
		(layer "F.Cu")
		(net "GND")
	)
	(segment
		(start 344.207846 -225.310192)
		(end 343.740994 -225.044254)
		(width 0.350012)
		(layer "F.Cu")
		(net "GND")
	)
	(segment
		(start 307.368194 -284.034992)
		(end 305.983894 -284.034992)
		(width 0.4572)
		(layer "F.Cu")
		(net "GND")
	)
	(segment
		(start 328.227944 -225.310192)
		(end 327.761092 -225.044254)
		(width 0.350012)
		(layer "F.Cu")
		(net "GND")
	)
	(segment
		(start 89.047828 -269.770352)
		(end 88.580976 -270.03629)
		(width 0.350012)
		(layer "F.Cu")
		(net "GND")
	)
	(segment
		(start 98.617786 -247.180354)
		(end 98.150934 -246.914416)
		(width 0.350012)
		(layer "F.Cu")
		(net "GND")
	)
	(segment
		(start 383.17043 -392.999722)
		(end 383.117852 -392.30427)
		(width 0.254)
		(layer "F.Cu")
		(net "GND")
	)
	(segment
		(start 85.045804 -382.951482)
		(end 85.144356 -382.85293)
		(width 0.2032)
		(layer "F.Cu")
		(net "GND")
	)
	(segment
		(start 382.748028 -226.930204)
		(end 383.21488 -226.664266)
		(width 0.350012)
		(layer "F.Cu")
		(net "GND")
	)
	(segment
		(start 390.45388 -395.613128)
		(end 390.291828 -395.451076)
		(width 0.254)
		(layer "F.Cu")
		(net "GND")
	)
	(segment
		(start 288.180018 -284.88513)
		(end 289.564318 -284.88513)
		(width 0.4572)
		(layer "F.Cu")
		(net "GND")
	)
	(segment
		(start 386.21843 -396.710662)
		(end 385.570476 -396.520924)
		(width 0.254)
		(layer "F.Cu")
		(net "GND")
	)
	(segment
		(start 57.6707 -386.6388)
		(end 58.178446 -386.449062)
		(width 0.254)
		(layer "F.Cu")
		(net "GND")
	)
	(segment
		(start 121.477786 -277.060406)
		(end 121.944638 -277.326344)
		(width 0.350012)
		(layer "F.Cu")
		(net "GND")
	)
	(segment
		(start 312.11774 -391.333482)
		(end 312.216292 -391.23493)
		(width 0.254)
		(layer "F.Cu")
		(net "GND")
	)
	(segment
		(start 67.202558 -40.437562)
		(end 67.201796 -40.438324)
		(width 0.4572)
		(layer "F.Cu")
		(net "GND")
	)
	(segment
		(start 303.390808 -398.613122)
		(end 302.620934 -398.613122)
		(width 0.254)
		(layer "F.Cu")
		(net "GND")
	)
	(segment
		(start 335.108042 -261.670038)
		(end 334.64119 -261.935976)
		(width 0.350012)
		(layer "F.Cu")
		(net "GND")
	)
	(segment
		(start 160.898332 -386.6388)
		(end 160.206182 -386.449062)
		(width 0.254)
		(layer "F.Cu")
		(net "GND")
	)
	(segment
		(start 68.729098 -166.54399)
		(end 68.729098 -166.850568)
		(width 0.2286)
		(layer "F.Cu")
		(net "GND")
	)
	(segment
		(start 386.03809 -229.360222)
		(end 386.504942 -229.094284)
		(width 0.350012)
		(layer "F.Cu")
		(net "GND")
	)
	(segment
		(start 149.406356 -386.449062)
		(end 148.898356 -386.6388)
		(width 0.254)
		(layer "F.Cu")
		(net "GND")
	)
	(segment
		(start 47.391066 -390.231122)
		(end 46.621192 -390.231122)
		(width 0.254)
		(layer "F.Cu")
		(net "GND")
	)
	(segment
		(start 384.457956 -273.820128)
		(end 384.924808 -274.086066)
		(width 0.350012)
		(layer "F.Cu")
		(net "GND")
	)
	(segment
		(start 363.478064 -229.360222)
		(end 363.944916 -229.094284)
		(width 0.350012)
		(layer "F.Cu")
		(net "GND")
	)
	(segment
		(start 409.090114 -392.999722)
		(end 408.498294 -392.999722)
		(width 0.254)
		(layer "F.Cu")
		(net "GND")
	)
	(segment
		(start 162.833812 -116.267484)
		(end 161.971736 -115.405408)
		(width 0.4572)
		(layer "F.Cu")
		(net "GND")
	)
	(segment
		(start 112.72774 -393.900152)
		(end 111.91494 -393.900152)
		(width 0.254)
		(layer "F.Cu")
		(net "GND")
	)
	(segment
		(start 390.737852 -234.220004)
		(end 391.204704 -233.954066)
		(width 0.350012)
		(layer "F.Cu")
		(net "GND")
	)
	(segment
		(start 410.29001 -392.999722)
		(end 410.89834 -392.999722)
		(width 0.254)
		(layer "F.Cu")
		(net "GND")
	)
	(segment
		(start 133.20141 -384.617722)
		(end 133.20141 -384.005836)
		(width 0.254)
		(layer "F.Cu")
		(net "GND")
	)
	(segment
		(start 402.248878 -393.24915)
		(end 402.498306 -392.999722)
		(width 0.254)
		(layer "F.Cu")
		(net "GND")
	)
	(segment
		(start 338.56803 -230.169974)
		(end 338.101178 -229.904036)
		(width 0.350012)
		(layer "F.Cu")
		(net "GND")
	)
	(segment
		(start 346.387928 -264.910062)
		(end 345.921076 -265.176)
		(width 0.350012)
		(layer "F.Cu")
		(net "GND")
	)
	(segment
		(start 347.497908 -245.560088)
		(end 347.031056 -245.29415)
		(width 0.350012)
		(layer "F.Cu")
		(net "GND")
	)
	(segment
		(start 115.537996 -243.94033)
		(end 116.004848 -243.674392)
		(width 0.350012)
		(layer "F.Cu")
		(net "GND")
	)
	(segment
		(start 386.338064 -286.780224)
		(end 386.804916 -287.046162)
		(width 0.350012)
		(layer "F.Cu")
		(net "GND")
	)
	(segment
		(start 76.07173 -388.297674)
		(end 76.718668 -388.297674)
		(width 0.254)
		(layer "F.Cu")
		(net "GND")
	)
	(segment
		(start 81.997804 -294.880284)
		(end 81.530952 -295.146222)
		(width 0.350012)
		(layer "F.Cu")
		(net "GND")
	)
	(segment
		(start 157.277308 -353.245928)
		(end 156.597858 -353.245928)
		(width 0.4572)
		(layer "F.Cu")
		(net "GND")
	)
	(segment
		(start 93.91777 -229.360476)
		(end 93.450918 -229.094538)
		(width 0.350012)
		(layer "F.Cu")
		(net "GND")
	)
	(segment
		(start 446.776602 -429.01616)
		(end 446.776602 -429.65751)
		(width 0.4572)
		(layer "F.Cu")
		(net "GND")
	)
	(segment
		(start 92.037916 -255.280414)
		(end 91.571064 -255.014476)
		(width 0.350012)
		(layer "F.Cu")
		(net "GND")
	)
	(segment
		(start 120.79605 -435.483)
		(end 121.539 -435.483)
		(width 0.381)
		(layer "F.Cu")
		(net "GND")
	)
	(segment
		(start 116.878608 -386.449062)
		(end 116.370608 -386.6388)
		(width 0.254)
		(layer "F.Cu")
		(net "GND")
	)
	(segment
		(start 96.737932 -242.320318)
		(end 96.27108 -242.05438)
		(width 0.350012)
		(layer "F.Cu")
		(net "GND")
	)
	(segment
		(start 248.1961 -268.092936)
		(end 248.1961 -267.381736)
		(width 0.381)
		(layer "F.Cu")
		(net "GND")
	)
	(segment
		(start 424.012106 -227.935028)
		(end 422.627806 -227.935028)
		(width 0.4572)
		(layer "F.Cu")
		(net "GND")
	)
	(segment
		(start 328.998072 -264.100056)
		(end 328.53122 -264.365994)
		(width 0.350012)
		(layer "F.Cu")
		(net "GND")
	)
	(segment
		(start 98.147886 -252.850396)
		(end 97.681034 -252.584458)
		(width 0.350012)
		(layer "F.Cu")
		(net "GND")
	)
	(segment
		(start 118.718076 -390.761474)
		(end 118.417848 -391.281158)
		(width 0.254)
		(layer "F.Cu")
		(net "GND")
	)
	(segment
		(start 383.048002 -289.209988)
		(end 383.514854 -289.475926)
		(width 0.350012)
		(layer "F.Cu")
		(net "GND")
	)
	(segment
		(start 341.045546 -391.333482)
		(end 341.144098 -391.23493)
		(width 0.2032)
		(layer "F.Cu")
		(net "GND")
	)
	(segment
		(start 11.51636 -53.909214)
		(end 11.533124 -53.909214)
		(width 0.4572)
		(layer "F.Cu")
		(net "GND")
	)
	(segment
		(start 173.467014 -17.774158)
		(end 173.468284 -17.775428)
		(width 0.3556)
		(layer "F.Cu")
		(net "GND")
	)
	(segment
		(start 112.893094 -388.36473)
		(end 112.68202 -388.431024)
		(width 0.254)
		(layer "F.Cu")
		(net "GND")
	)
	(segment
		(start 90.927936 -266.530328)
		(end 90.461084 -266.796266)
		(width 0.350012)
		(layer "F.Cu")
		(net "GND")
	)
	(segment
		(start 318.21628 -400.212814)
		(end 318.21628 -399.76171)
		(width 0.254)
		(layer "F.Cu")
		(net "GND")
	)
	(segment
		(start 98.842576 -385.21132)
		(end 99.36226 -385.731004)
		(width 0.254)
		(layer "F.Cu")
		(net "GND")
	)
	(segment
		(start 103.787956 -251.230384)
		(end 103.321104 -250.964446)
		(width 0.350012)
		(layer "F.Cu")
		(net "GND")
	)
	(segment
		(start 11.51636 -50.099214)
		(end 11.533124 -50.099214)
		(width 0.4572)
		(layer "F.Cu")
		(net "GND")
	)
	(segment
		(start 363.478064 -232.599992)
		(end 363.944916 -232.334054)
		(width 0.350012)
		(layer "F.Cu")
		(net "GND")
	)
	(segment
		(start 127.190246 -159.93491)
		(end 127.297434 -160.042098)
		(width 0.381)
		(layer "F.Cu")
		(net "GND")
	)
	(segment
		(start 355.487986 -223.69018)
		(end 355.021134 -223.424242)
		(width 0.350012)
		(layer "F.Cu")
		(net "GND")
	)
	(segment
		(start 336.987896 -290.83)
		(end 336.521044 -291.095938)
		(width 0.350012)
		(layer "F.Cu")
		(net "GND")
	)
	(segment
		(start 92.33789 -280.30043)
		(end 91.871038 -280.566368)
		(width 0.350012)
		(layer "F.Cu")
		(net "GND")
	)
	(segment
		(start 116.018056 -383.402586)
		(end 116.018056 -382.951482)
		(width 0.254)
		(layer "F.Cu")
		(net "GND")
	)
	(segment
		(start 406.606248 -394.831062)
		(end 406.098248 -395.0208)
		(width 0.254)
		(layer "F.Cu")
		(net "GND")
	)
	(segment
		(start 147.018756 -390.160002)
		(end 147.018756 -390.231122)
		(width 0.254)
		(layer "F.Cu")
		(net "GND")
	)
	(segment
		(start 61.778642 -386.449062)
		(end 61.270642 -386.6388)
		(width 0.254)
		(layer "F.Cu")
		(net "GND")
	)
	(segment
		(start 17.608042 -231.335326)
		(end 18.992342 -231.335326)
		(width 0.4572)
		(layer "F.Cu")
		(net "GND")
	)
	(segment
		(start 428.283116 -109.66704)
		(end 428.283116 -110.27664)
		(width 0.4572)
		(layer "F.Cu")
		(net "GND")
	)
	(segment
		(start 368.478054 -285.160212)
		(end 368.944906 -285.42615)
		(width 0.350012)
		(layer "F.Cu")
		(net "GND")
	)
	(segment
		(start 39.55796 -438.531)
		(end 39.55796 -439.350404)
		(width 0.381)
		(layer "F.Cu")
		(net "GND")
	)
	(segment
		(start 339.977984 -248.800112)
		(end 339.511132 -248.534174)
		(width 0.350012)
		(layer "F.Cu")
		(net "GND")
	)
	(segment
		(start 118.657878 -267.340334)
		(end 119.12473 -267.606272)
		(width 0.350012)
		(layer "F.Cu")
		(net "GND")
	)
	(segment
		(start 98.918014 -270.580358)
		(end 98.451162 -270.846296)
		(width 0.350012)
		(layer "F.Cu")
		(net "GND")
	)
	(segment
		(start 4.194048 -137.27303)
		(end 4.539488 -137.61847)
		(width 0.3556)
		(layer "F.Cu")
		(net "GND")
	)
	(segment
		(start 384.141218 -177.48631)
		(end 384.399028 -177.2285)
		(width 0.381)
		(layer "F.Cu")
		(net "GND")
	)
	(segment
		(start 122.587766 -252.850396)
		(end 123.054618 -252.584458)
		(width 0.350012)
		(layer "F.Cu")
		(net "GND")
	)
	(segment
		(start 360.957876 -267.34008)
		(end 361.424728 -267.606018)
		(width 0.350012)
		(layer "F.Cu")
		(net "GND")
	)
	(segment
		(start 107.547918 -251.230384)
		(end 107.081066 -250.964446)
		(width 0.350012)
		(layer "F.Cu")
		(net "GND")
	)
	(segment
		(start 371.767862 -284.350206)
		(end 372.234714 -284.616144)
		(width 0.350012)
		(layer "F.Cu")
		(net "GND")
	)
	(segment
		(start 412.367984 -210.085178)
		(end 413.752284 -210.085178)
		(width 0.4572)
		(layer "F.Cu")
		(net "GND")
	)
	(segment
		(start 140.27785 -275.440394)
		(end 140.744702 -275.706332)
		(width 0.350012)
		(layer "F.Cu")
		(net "GND")
	)
	(segment
		(start 121.007886 -287.590484)
		(end 121.474738 -287.856422)
		(width 0.350012)
		(layer "F.Cu")
		(net "GND")
	)
	(segment
		(start 360.35996 -412.909258)
		(end 360.35996 -412.217108)
		(width 0.4318)
		(layer "F.Cu")
		(net "GND")
	)
	(segment
		(start 127.117856 -278.680418)
		(end 127.584708 -278.946356)
		(width 0.350012)
		(layer "F.Cu")
		(net "GND")
	)
	(segment
		(start 304.070258 -398.542002)
		(end 304.01768 -399.143474)
		(width 0.254)
		(layer "F.Cu")
		(net "GND")
	)
	(segment
		(start 271.295876 -419.37178)
		(end 271.295876 -420.141146)
		(width 0.381)
		(layer "F.Cu")
		(net "GND")
	)
	(segment
		(start 357.668068 -284.350206)
		(end 357.201216 -284.616144)
		(width 0.350012)
		(layer "F.Cu")
		(net "GND")
	)
	(segment
		(start 80.58785 -264.910316)
		(end 80.120998 -265.176254)
		(width 0.350012)
		(layer "F.Cu")
		(net "GND")
	)
	(segment
		(start 348.597982 -392.999722)
		(end 348.545404 -392.30427)
		(width 0.254)
		(layer "F.Cu")
		(net "GND")
	)
	(segment
		(start 355.018086 -224.500186)
		(end 354.551234 -224.234248)
		(width 0.350012)
		(layer "F.Cu")
		(net "GND")
	)
	(segment
		(start 383.048002 -279.49017)
		(end 383.514854 -279.756108)
		(width 0.350012)
		(layer "F.Cu")
		(net "GND")
	)
	(segment
		(start 95.590106 -384.617722)
		(end 94.998286 -384.617722)
		(width 0.254)
		(layer "F.Cu")
		(net "GND")
	)
	(segment
		(start 12.733782 -405.211534)
		(end 12.733782 -404.490174)
		(width 0.4572)
		(layer "F.Cu")
		(net "GND")
	)
	(segment
		(start 333.697834 -275.44014)
		(end 333.230982 -275.706078)
		(width 0.350012)
		(layer "F.Cu")
		(net "GND")
	)
	(segment
		(start 116.477796 -235.84027)
		(end 116.944648 -235.574332)
		(width 0.350012)
		(layer "F.Cu")
		(net "GND")
	)
	(segment
		(start 80.58785 -281.110436)
		(end 80.120998 -281.376374)
		(width 0.350012)
		(layer "F.Cu")
		(net "GND")
	)
	(segment
		(start 26.393394 -425.593256)
		(end 26.393394 -426.609256)
		(width 0.4572)
		(layer "F.Cu")
		(net "GND")
	)
	(segment
		(start 198.7042 -295.9354)
		(end 197.3199 -295.9354)
		(width 0.4572)
		(layer "F.Cu")
		(net "GND")
	)
	(segment
		(start 351.506028 -394.831062)
		(end 350.998028 -395.0208)
		(width 0.254)
		(layer "F.Cu")
		(net "GND")
	)
	(segment
		(start 131.817872 -268.960346)
		(end 132.284724 -269.226284)
		(width 0.350012)
		(layer "F.Cu")
		(net "GND")
	)
	(segment
		(start 362.368084 -281.110182)
		(end 362.834682 -281.37612)
		(width 0.350012)
		(layer "F.Cu")
		(net "GND")
	)
	(segment
		(start 135.107934 -289.210242)
		(end 135.574786 -289.47618)
		(width 0.350012)
		(layer "F.Cu")
		(net "GND")
	)
	(segment
		(start 136.987788 -261.670292)
		(end 137.45464 -261.93623)
		(width 0.350012)
		(layer "F.Cu")
		(net "GND")
	)
	(segment
		(start 182.722012 -117.852952)
		(end 182.332122 -118.242842)
		(width 0.254)
		(layer "F.Cu")
		(net "GND")
	)
	(segment
		(start 88.747854 -226.930458)
		(end 88.281002 -226.66452)
		(width 0.350012)
		(layer "F.Cu")
		(net "GND")
	)
	(segment
		(start 51.670712 -384.617722)
		(end 51.618134 -383.92227)
		(width 0.254)
		(layer "F.Cu")
		(net "GND")
	)
	(segment
		(start 416.545776 -391.784586)
		(end 416.545776 -391.333482)
		(width 0.254)
		(layer "F.Cu")
		(net "GND")
	)
	(segment
		(start 95.489522 -135.666734)
		(end 95.489522 -133.325362)
		(width 0.4572)
		(layer "F.Cu")
		(net "GND")
	)
	(segment
		(start 132.478526 -386.449062)
		(end 131.970526 -386.6388)
		(width 0.254)
		(layer "F.Cu")
		(net "GND")
	)
	(segment
		(start 277.192232 -230.485188)
		(end 275.807932 -230.485188)
		(width 0.4572)
		(layer "F.Cu")
		(net "GND")
	)
	(segment
		(start 387.448044 -228.550216)
		(end 387.914896 -228.284278)
		(width 0.350012)
		(layer "F.Cu")
		(net "GND")
	)
	(segment
		(start 53.267102 -7.217156)
		(end 53.267102 -8.320024)
		(width 0.3556)
		(layer "F.Cu")
		(net "GND")
	)
	(segment
		(start 90.627962 -249.610372)
		(end 90.16111 -249.344434)
		(width 0.350012)
		(layer "F.Cu")
		(net "GND")
	)
	(segment
		(start 98.842576 -387.231128)
		(end 98.598482 -386.987034)
		(width 0.254)
		(layer "F.Cu")
		(net "GND")
	)
	(segment
		(start 140.820394 -38.796468)
		(end 141.429994 -38.796468)
		(width 0.381)
		(layer "F.Cu")
		(net "GND")
	)
	(segment
		(start 387.748018 -271.39011)
		(end 388.21487 -271.656048)
		(width 0.350012)
		(layer "F.Cu")
		(net "GND")
	)
	(segment
		(start 99.080828 -394.0937)
		(end 99.080828 -393.491212)
		(width 0.254)
		(layer "F.Cu")
		(net "GND")
	)
	(segment
		(start 70.992746 -386.84073)
		(end 70.749414 -387.084062)
		(width 0.381)
		(layer "F.Cu")
		(net "GND")
	)
	(segment
		(start 194.657726 -69.92366)
		(end 195.536566 -69.92366)
		(width 0.254)
		(layer "F.Cu")
		(net "GND")
	)
	(segment
		(start 83.577938 -252.04039)
		(end 83.111086 -251.774452)
		(width 0.350012)
		(layer "F.Cu")
		(net "GND")
	)
	(segment
		(start 136.217914 -230.980234)
		(end 136.684766 -230.71455)
		(width 0.350012)
		(layer "F.Cu")
		(net "GND")
	)
	(segment
		(start 100.497894 -226.120452)
		(end 100.031042 -225.854514)
		(width 0.350012)
		(layer "F.Cu")
		(net "GND")
	)
	(segment
		(start 331.518006 -235.840016)
		(end 331.051154 -235.574078)
		(width 0.350012)
		(layer "F.Cu")
		(net "GND")
	)
	(segment
		(start 57.317894 -383.622042)
		(end 57.317894 -383.402586)
		(width 0.254)
		(layer "F.Cu")
		(net "GND")
	)
	(segment
		(start 138.098022 -227.740464)
		(end 138.564874 -227.474526)
		(width 0.350012)
		(layer "F.Cu")
		(net "GND")
	)
	(segment
		(start 143.098012 -267.340334)
		(end 143.56461 -267.606272)
		(width 0.350012)
		(layer "F.Cu")
		(net "GND")
	)
	(segment
		(start 102.847902 -230.170228)
		(end 102.38105 -229.90429)
		(width 0.350012)
		(layer "F.Cu")
		(net "GND")
	)
	(segment
		(start 43.85564 -11.26871)
		(end 43.85564 -10.16508)
		(width 0.3556)
		(layer "F.Cu")
		(net "GND")
	)
	(segment
		(start 93.44787 -238.270288)
		(end 92.981018 -238.00435)
		(width 0.350012)
		(layer "F.Cu")
		(net "GND")
	)
	(segment
		(start 375.970546 -398.542002)
		(end 375.29135 -398.542002)
		(width 0.254)
		(layer "F.Cu")
		(net "GND")
	)
	(segment
		(start 338.6455 -391.333482)
		(end 338.744052 -391.23493)
		(width 0.254)
		(layer "F.Cu")
		(net "GND")
	)
	(segment
		(start 153.877772 -66.04254)
		(end 153.598372 -65.76314)
		(width 0.381)
		(layer "F.Cu")
		(net "GND")
	)
	(segment
		(start 198.7042 -312.085228)
		(end 197.3199 -312.085228)
		(width 0.4572)
		(layer "F.Cu")
		(net "GND")
	)
	(segment
		(start 343.097866 -293.260018)
		(end 342.631014 -293.525956)
		(width 0.350012)
		(layer "F.Cu")
		(net "GND")
	)
	(segment
		(start 139.80795 -277.870412)
		(end 140.274802 -278.13635)
		(width 0.350012)
		(layer "F.Cu")
		(net "GND")
	)
	(segment
		(start 87.637874 -277.060406)
		(end 87.171022 -277.326344)
		(width 0.350012)
		(layer "F.Cu")
		(net "GND")
	)
	(segment
		(start 108.487972 -230.170228)
		(end 108.02112 -229.90429)
		(width 0.350012)
		(layer "F.Cu")
		(net "GND")
	)
	(segment
		(start 211.992464 -22.443948)
		(end 212.799168 -21.637244)
		(width 0.3556)
		(layer "F.Cu")
		(net "GND")
	)
	(segment
		(start 353.437952 -285.160212)
		(end 352.9711 -285.42615)
		(width 0.350012)
		(layer "F.Cu")
		(net "GND")
	)
	(segment
		(start 322.834254 -392.913108)
		(end 322.614544 -392.913108)
		(width 0.254)
		(layer "F.Cu")
		(net "GND")
	)
	(segment
		(start 384.157982 -250.420124)
		(end 384.624834 -250.154186)
		(width 0.350012)
		(layer "F.Cu")
		(net "GND")
	)
	(segment
		(start 184.322212 -122.65279)
		(end 183.932322 -123.04268)
		(width 0.254)
		(layer "F.Cu")
		(net "GND")
	)
	(segment
		(start 442.5442 -212.635084)
		(end 443.9285 -212.635084)
		(width 0.4572)
		(layer "F.Cu")
		(net "GND")
	)
	(segment
		(start 103.412798 -345.150948)
		(end 103.482648 -345.081098)
		(width 0.381)
		(layer "F.Cu")
		(net "GND")
	)
	(segment
		(start 269.648178 -239.835182)
		(end 268.263878 -239.835182)
		(width 0.4572)
		(layer "F.Cu")
		(net "GND")
	)
	(segment
		(start 341.387938 -246.370094)
		(end 340.921086 -246.104156)
		(width 0.350012)
		(layer "F.Cu")
		(net "GND")
	)
	(segment
		(start 354.378006 -288.399982)
		(end 353.911154 -288.66592)
		(width 0.350012)
		(layer "F.Cu")
		(net "GND")
	)
	(segment
		(start 105.66781 -236.650276)
		(end 105.200958 -236.384338)
		(width 0.350012)
		(layer "F.Cu")
		(net "GND")
	)
	(segment
		(start 388.618476 -396.710662)
		(end 387.970522 -396.520924)
		(width 0.254)
		(layer "F.Cu")
		(net "GND")
	)
	(segment
		(start 177.137568 -153.93924)
		(end 177.137568 -152.828244)
		(width 0.4572)
		(layer "F.Cu")
		(net "GND")
	)
	(segment
		(start 398.140682 -171.959524)
		(end 398.070832 -172.029374)
		(width 0.381)
		(layer "F.Cu")
		(net "GND")
	)
	(segment
		(start 100.497894 -243.94033)
		(end 100.031042 -243.674392)
		(width 0.350012)
		(layer "F.Cu")
		(net "GND")
	)
	(segment
		(start 374.11787 -288.399982)
		(end 374.584722 -288.66592)
		(width 0.350012)
		(layer "F.Cu")
		(net "GND")
	)
	(segment
		(start 377.117864 -392.30427)
		(end 377.170442 -392.999722)
		(width 0.254)
		(layer "F.Cu")
		(net "GND")
	)
	(segment
		(start 185.122058 -116.252752)
		(end 184.732168 -116.642642)
		(width 0.254)
		(layer "F.Cu")
		(net "GND")
	)
	(segment
		(start 80.757776 -245.560342)
		(end 80.291178 -245.294404)
		(width 0.350012)
		(layer "F.Cu")
		(net "GND")
	)
	(segment
		(start 350.645476 -392.004296)
		(end 350.94545 -392.30427)
		(width 0.254)
		(layer "F.Cu")
		(net "GND")
	)
	(segment
		(start 58.3184 -388.328662)
		(end 57.6707 -388.138924)
		(width 0.254)
		(layer "F.Cu")
		(net "GND")
	)
	(segment
		(start 341.687912 -264.910062)
		(end 341.22106 -265.176)
		(width 0.350012)
		(layer "F.Cu")
		(net "GND")
	)
	(segment
		(start 175.553116 -33.353248)
		(end 175.553116 -32.013144)
		(width 0.254)
		(layer "F.Cu")
		(net "GND")
	)
	(segment
		(start 128.52781 -271.390364)
		(end 128.994662 -271.656302)
		(width 0.350012)
		(layer "F.Cu")
		(net "GND")
	)
	(segment
		(start 44.340018 -239.835436)
		(end 42.955718 -239.835436)
		(width 0.4572)
		(layer "F.Cu")
		(net "GND")
	)
	(segment
		(start 123.997974 -255.280414)
		(end 124.464826 -255.014476)
		(width 0.350012)
		(layer "F.Cu")
		(net "GND")
	)
	(segment
		(start 121.177812 -242.320318)
		(end 121.644664 -242.05438)
		(width 0.350012)
		(layer "F.Cu")
		(net "GND")
	)
	(segment
		(start 381.167894 -295.690036)
		(end 381.62992 -295.95318)
		(width 0.350012)
		(layer "F.Cu")
		(net "GND")
	)
	(segment
		(start 62.117986 -383.402586)
		(end 62.117986 -383.622296)
		(width 0.254)
		(layer "F.Cu")
		(net "GND")
	)
	(segment
		(start 335.577942 -281.920188)
		(end 335.11109 -282.186126)
		(width 0.350012)
		(layer "F.Cu")
		(net "GND")
	)
	(segment
		(start 412.367984 -275.535136)
		(end 413.752284 -275.535136)
		(width 0.4572)
		(layer "F.Cu")
		(net "GND")
	)
	(segment
		(start 93.747844 -274.630388)
		(end 93.280992 -274.896326)
		(width 0.350012)
		(layer "F.Cu")
		(net "GND")
	)
	(segment
		(start 342.597994 -395.0208)
		(end 341.906098 -394.831062)
		(width 0.254)
		(layer "F.Cu")
		(net "GND")
	)
	(segment
		(start 170.905424 -381.566928)
		(end 170.905424 -381.020828)
		(width 0.254)
		(layer "F.Cu")
		(net "GND")
	)
	(segment
		(start 216.811098 -28.015184)
		(end 214.08771 -28.015184)
		(width 0.3556)
		(layer "F.Cu")
		(net "GND")
	)
	(segment
		(start 357.668068 -287.59023)
		(end 357.201216 -287.856168)
		(width 0.350012)
		(layer "F.Cu")
		(net "GND")
	)
	(segment
		(start 403.025102 -322.53936)
		(end 403.025102 -323.036184)
		(width 0.381)
		(layer "F.Cu")
		(net "GND")
	)
	(segment
		(start 27.548332 -12.374118)
		(end 27.547062 -12.372848)
		(width 0.3556)
		(layer "F.Cu")
		(net "GND")
	)
	(segment
		(start 66.017902 -383.92227)
		(end 66.101468 -384.005836)
		(width 0.254)
		(layer "F.Cu")
		(net "GND")
	)
	(segment
		(start 121.477786 -260.860286)
		(end 121.944638 -261.126224)
		(width 0.350012)
		(layer "F.Cu")
		(net "GND")
	)
	(segment
		(start 96.568006 -268.15034)
		(end 96.101154 -268.416278)
		(width 0.350012)
		(layer "F.Cu")
		(net "GND")
	)
	(segment
		(start 64.63538 -393.946634)
		(end 64.616584 -393.927838)
		(width 0.3048)
		(layer "F.Cu")
		(net "GND")
	)
	(segment
		(start 345.918028 -277.060152)
		(end 345.451176 -277.32609)
		(width 0.350012)
		(layer "F.Cu")
		(net "GND")
	)
	(segment
		(start 354.628958 -392.999722)
		(end 354.628958 -392.387836)
		(width 0.254)
		(layer "F.Cu")
		(net "GND")
	)
	(segment
		(start 373.17807 -262.480044)
		(end 373.644922 -262.745982)
		(width 0.350012)
		(layer "F.Cu")
		(net "GND")
	)
	(segment
		(start 79.398368 -388.08152)
		(end 80.046322 -388.328662)
		(width 0.254)
		(layer "F.Cu")
		(net "GND")
	)
	(segment
		(start 305.867562 -348.54134)
		(end 306.29606 -348.54134)
		(width 0.2286)
		(layer "F.Cu")
		(net "GND")
	)
	(segment
		(start 389.798052 -250.420124)
		(end 390.264904 -250.154186)
		(width 0.350012)
		(layer "F.Cu")
		(net "GND")
	)
	(segment
		(start 374.588024 -266.530074)
		(end 375.054876 -266.796012)
		(width 0.350012)
		(layer "F.Cu")
		(net "GND")
	)
	(segment
		(start 167.342566 -347.289882)
		(end 167.337994 -347.294454)
		(width 0.381)
		(layer "F.Cu")
		(net "GND")
	)
	(segment
		(start 280.019506 -349.781622)
		(end 280.050494 -349.781622)
		(width 0.2286)
		(layer "F.Cu")
		(net "GND")
	)
	(segment
		(start 191.160146 -274.685252)
		(end 189.775846 -274.685252)
		(width 0.4572)
		(layer "F.Cu")
		(net "GND")
	)
	(segment
		(start 55.328058 -278.085296)
		(end 56.712358 -278.085296)
		(width 0.4572)
		(layer "F.Cu")
		(net "GND")
	)
	(segment
		(start 353.437952 -281.920188)
		(end 352.9711 -282.186126)
		(width 0.350012)
		(layer "F.Cu")
		(net "GND")
	)
	(segment
		(start 344.508074 -294.070024)
		(end 344.041222 -294.335962)
		(width 0.350012)
		(layer "F.Cu")
		(net "GND")
	)
	(segment
		(start 116.370608 -390.160002)
		(end 116.31803 -390.761474)
		(width 0.254)
		(layer "F.Cu")
		(net "GND")
	)
	(segment
		(start 309.816246 -400.212814)
		(end 309.816246 -399.76171)
		(width 0.254)
		(layer "F.Cu")
		(net "GND")
	)
	(segment
		(start 94.446344 -388.328662)
		(end 93.79839 -388.138924)
		(width 0.254)
		(layer "F.Cu")
		(net "GND")
	)
	(segment
		(start 177.104294 -416.756342)
		(end 176.0601 -416.756342)
		(width 0.381)
		(layer "F.Cu")
		(net "GND")
	)
	(segment
		(start 142.797784 -255.280414)
		(end 143.264636 -255.014476)
		(width 0.350012)
		(layer "F.Cu")
		(net "GND")
	)
	(segment
		(start 378.048012 -238.270034)
		(end 378.514864 -238.004096)
		(width 0.350012)
		(layer "F.Cu")
		(net "GND")
	)
	(segment
		(start 312.703972 -36.890706)
		(end 312.703972 -36.09975)
		(width 0.3556)
		(layer "F.Cu")
		(net "GND")
	)
	(segment
		(start 303.268126 -228.785166)
		(end 304.652426 -228.785166)
		(width 0.4572)
		(layer "F.Cu")
		(net "GND")
	)
	(segment
		(start 372.238016 -290.019994)
		(end 372.704868 -290.285932)
		(width 0.350012)
		(layer "F.Cu")
		(net "GND")
	)
	(segment
		(start 169.724324 -381.645668)
		(end 169.724324 -381.771906)
		(width 0.254)
		(layer "F.Cu")
		(net "GND")
	)
	(segment
		(start 94.645734 -383.402586)
		(end 94.645734 -382.951482)
		(width 0.254)
		(layer "F.Cu")
		(net "GND")
	)
	(segment
		(start 130.467354 -55.541164)
		(end 130.848354 -55.922164)
		(width 0.1778)
		(layer "F.Cu")
		(net "GND")
	)
	(segment
		(start 81.058004 -291.64026)
		(end 80.591152 -291.906198)
		(width 0.350012)
		(layer "F.Cu")
		(net "GND")
	)
	(segment
		(start 394.327888 -276.250146)
		(end 394.982954 -276.250146)
		(width 0.350012)
		(layer "F.Cu")
		(net "GND")
	)
	(segment
		(start 315.264292 -337.07324)
		(end 315.517276 -336.820256)
		(width 0.2286)
		(layer "F.Cu")
		(net "GND")
	)
	(segment
		(start 105.497884 -280.30043)
		(end 105.031032 -280.566368)
		(width 0.350012)
		(layer "F.Cu")
		(net "GND")
	)
	(segment
		(start 36.640262 -418.264848)
		(end 36.665662 -418.239448)
		(width 0.3556)
		(layer "F.Cu")
		(net "GND")
	)
	(segment
		(start 374.28805 -231.789986)
		(end 374.754902 -231.524048)
		(width 0.350012)
		(layer "F.Cu")
		(net "GND")
	)
	(segment
		(start 307.670454 -396.520924)
		(end 307.118258 -396.710662)
		(width 0.254)
		(layer "F.Cu")
		(net "GND")
	)
	(segment
		(start 58.870596 -390.160002)
		(end 58.1914 -390.160002)
		(width 0.254)
		(layer "F.Cu")
		(net "GND")
	)
	(segment
		(start 359.078022 -286.780224)
		(end 358.61117 -287.045908)
		(width 0.350012)
		(layer "F.Cu")
		(net "GND")
	)
	(segment
		(start 414.755584 -7.215124)
		(end 414.755584 -7.215886)
		(width 0.3556)
		(layer "F.Cu")
		(net "GND")
	)
	(segment
		(start 136.517888 -264.10031)
		(end 136.98474 -264.366248)
		(width 0.350012)
		(layer "F.Cu")
		(net "GND")
	)
	(segment
		(start 315.370972 -34.858706)
		(end 314.761372 -34.858706)
		(width 0.3556)
		(layer "F.Cu")
		(net "GND")
	)
	(segment
		(start 56.117998 -391.281158)
		(end 56.417972 -390.761474)
		(width 0.254)
		(layer "F.Cu")
		(net "GND")
	)
	(segment
		(start 168.527984 -286.585406)
		(end 167.143684 -286.585406)
		(width 0.4572)
		(layer "F.Cu")
		(net "GND")
	)
	(segment
		(start 381.418338 -396.710662)
		(end 380.770638 -396.520924)
		(width 0.254)
		(layer "F.Cu")
		(net "GND")
	)
	(segment
		(start 388.217918 -278.680164)
		(end 388.68477 -278.946102)
		(width 0.350012)
		(layer "F.Cu")
		(net "GND")
	)
	(segment
		(start 212.19795 -120.65)
		(end 212.19795 -121.38406)
		(width 0.381)
		(layer "F.Cu")
		(net "GND")
	)
	(segment
		(start 118.318534 -61.916056)
		(end 117.957346 -61.554868)
		(width 0.4572)
		(layer "F.Cu")
		(net "GND")
	)
	(segment
		(start 176.072038 -284.035246)
		(end 174.687738 -284.035246)
		(width 0.4572)
		(layer "F.Cu")
		(net "GND")
	)
	(segment
		(start 370.997988 -229.360222)
		(end 371.46484 -229.094284)
		(width 0.350012)
		(layer "F.Cu")
		(net "GND")
	)
	(segment
		(start 5.229098 -134.288022)
		(end 5.229098 -133.08838)
		(width 0.3556)
		(layer "F.Cu")
		(net "GND")
	)
	(segment
		(start 90.627962 -251.230384)
		(end 90.16111 -250.964446)
		(width 0.350012)
		(layer "F.Cu")
		(net "GND")
	)
	(segment
		(start 152.145746 -383.402586)
		(end 152.145746 -382.951482)
		(width 0.2032)
		(layer "F.Cu")
		(net "GND")
	)
	(segment
		(start 104.257856 -224.50044)
		(end 103.791004 -224.234502)
		(width 0.350012)
		(layer "F.Cu")
		(net "GND")
	)
	(segment
		(start 292.280086 -218.585034)
		(end 290.895786 -218.585034)
		(width 0.4572)
		(layer "F.Cu")
		(net "GND")
	)
	(segment
		(start 382.817878 -391.784586)
		(end 382.817878 -391.333482)
		(width 0.254)
		(layer "F.Cu")
		(net "GND")
	)
	(segment
		(start 387.917944 -399.143474)
		(end 387.970522 -398.542002)
		(width 0.254)
		(layer "F.Cu")
		(net "GND")
	)
	(segment
		(start 338.097876 -240.700052)
		(end 337.631024 -240.434114)
		(width 0.350012)
		(layer "F.Cu")
		(net "GND")
	)
	(segment
		(start 105.66781 -230.170228)
		(end 105.200958 -229.90429)
		(width 0.350012)
		(layer "F.Cu")
		(net "GND")
	)
	(segment
		(start 127.381 -109.11205)
		(end 127.381 -109.982)
		(width 0.381)
		(layer "F.Cu")
		(net "GND")
	)
	(segment
		(start 124.937774 -232.600246)
		(end 125.404626 -232.334308)
		(width 0.350012)
		(layer "F.Cu")
		(net "GND")
	)
	(segment
		(start 179.516024 -315.485272)
		(end 180.900324 -315.485272)
		(width 0.4572)
		(layer "F.Cu")
		(net "GND")
	)
	(segment
		(start 118.827804 -251.230384)
		(end 119.294656 -250.964446)
		(width 0.350012)
		(layer "F.Cu")
		(net "GND")
	)
	(segment
		(start 363.962188 -412.370016)
		(end 363.301026 -412.370016)
		(width 0.381)
		(layer "F.Cu")
		(net "GND")
	)
	(segment
		(start 113.017808 -272.20037)
		(end 113.48466 -272.466308)
		(width 0.350012)
		(layer "F.Cu")
		(net "GND")
	)
	(segment
		(start 179.516024 -294.235378)
		(end 180.900324 -294.235378)
		(width 0.4572)
		(layer "F.Cu")
		(net "GND")
	)
	(segment
		(start 93.747844 -269.770352)
		(end 93.280992 -270.03629)
		(width 0.350012)
		(layer "F.Cu")
		(net "GND")
	)
	(segment
		(start 187.43549 -429.330612)
		(end 188.296804 -428.469298)
		(width 0.381)
		(layer "F.Cu")
		(net "GND")
	)
	(segment
		(start 56.97855 -386.449062)
		(end 56.47055 -386.6388)
		(width 0.254)
		(layer "F.Cu")
		(net "GND")
	)
	(segment
		(start 357.50881 -402.4757)
		(end 357.318056 -402.284946)
		(width 0.254)
		(layer "F.Cu")
		(net "GND")
	)
	(segment
		(start 319.67043 -392.999722)
		(end 320.26225 -392.999722)
		(width 0.254)
		(layer "F.Cu")
		(net "GND")
	)
	(segment
		(start 328.697844 -229.360222)
		(end 328.231246 -229.094284)
		(width 0.350012)
		(layer "F.Cu")
		(net "GND")
	)
	(segment
		(start 152.884632 -98.355658)
		(end 151.944832 -98.355658)
		(width 0.3556)
		(layer "F.Cu")
		(net "GND")
	)
	(segment
		(start 429.565562 -7.215886)
		(end 429.566832 -7.217156)
		(width 0.3556)
		(layer "F.Cu")
		(net "GND")
	)
	(segment
		(start 183.616092 -209.235294)
		(end 182.231792 -209.235294)
		(width 0.4572)
		(layer "F.Cu")
		(net "GND")
	)
	(segment
		(start 82.306414 -386.449062)
		(end 81.798414 -386.6388)
		(width 0.254)
		(layer "F.Cu")
		(net "GND")
	)
	(segment
		(start 155.754578 -45.64888)
		(end 155.754578 -46.286166)
		(width 0.4064)
		(layer "F.Cu")
		(net "GND")
	)
	(segment
		(start 239.032542 -289.012122)
		(end 238.380778 -289.012122)
		(width 0.381)
		(layer "F.Cu")
		(net "GND")
	)
	(segment
		(start 187.060078 -231.335326)
		(end 188.444378 -231.335326)
		(width 0.4572)
		(layer "F.Cu")
		(net "GND")
	)
	(segment
		(start 130.718052 -383.92227)
		(end 130.417824 -383.622042)
		(width 0.254)
		(layer "F.Cu")
		(net "GND")
	)
	(segment
		(start 346.557854 -252.040136)
		(end 346.091002 -251.774198)
		(width 0.350012)
		(layer "F.Cu")
		(net "GND")
	)
	(segment
		(start 334.167988 -294.070024)
		(end 333.701136 -294.335962)
		(width 0.350012)
		(layer "F.Cu")
		(net "GND")
	)
	(segment
		(start 92.33789 -260.860286)
		(end 91.871038 -261.126224)
		(width 0.350012)
		(layer "F.Cu")
		(net "GND")
	)
	(segment
		(start 117.888004 -228.55047)
		(end 118.354856 -228.284532)
		(width 0.350012)
		(layer "F.Cu")
		(net "GND")
	)
	(segment
		(start 341.687912 -271.39011)
		(end 341.22106 -271.656048)
		(width 0.350012)
		(layer "F.Cu")
		(net "GND")
	)
	(segment
		(start 331.518006 -234.220004)
		(end 331.051154 -233.954066)
		(width 0.350012)
		(layer "F.Cu")
		(net "GND")
	)
	(segment
		(start 339.589872 -392.999722)
		(end 340.198202 -392.999722)
		(width 0.254)
		(layer "F.Cu")
		(net "GND")
	)
	(segment
		(start 388.217918 -260.860032)
		(end 388.68477 -261.12597)
		(width 0.350012)
		(layer "F.Cu")
		(net "GND")
	)
	(segment
		(start 355.957886 -247.1801)
		(end 355.491034 -246.914162)
		(width 0.350012)
		(layer "F.Cu")
		(net "GND")
	)
	(segment
		(start 96.267778 -223.690434)
		(end 95.800926 -223.424496)
		(width 0.350012)
		(layer "F.Cu")
		(net "GND")
	)
	(segment
		(start 386.807964 -294.070024)
		(end 387.274816 -294.335962)
		(width 0.350012)
		(layer "F.Cu")
		(net "GND")
	)
	(segment
		(start 348.268036 -274.630134)
		(end 347.801184 -274.896072)
		(width 0.350012)
		(layer "F.Cu")
		(net "GND")
	)
	(segment
		(start 141.687804 -282.730448)
		(end 142.154656 -282.996386)
		(width 0.350012)
		(layer "F.Cu")
		(net "GND")
	)
	(segment
		(start 316.917832 -399.663158)
		(end 317.016384 -399.76171)
		(width 0.254)
		(layer "F.Cu")
		(net "GND")
	)
	(segment
		(start 176.072038 -239.835436)
		(end 174.687738 -239.835436)
		(width 0.4572)
		(layer "F.Cu")
		(net "GND")
	)
	(segment
		(start 88.747854 -246.370348)
		(end 88.281002 -246.10441)
		(width 0.350012)
		(layer "F.Cu")
		(net "GND")
	)
	(segment
		(start 32.695896 -221.985332)
		(end 34.080196 -221.985332)
		(width 0.4572)
		(layer "F.Cu")
		(net "GND")
	)
	(segment
		(start 36.795964 -227.935282)
		(end 35.411664 -227.935282)
		(width 0.4572)
		(layer "F.Cu")
		(net "GND")
	)
	(segment
		(start 164.244274 -391.37971)
		(end 164.145722 -391.281158)
		(width 0.254)
		(layer "F.Cu")
		(net "GND")
	)
	(segment
		(start 284.736032 -221.13494)
		(end 283.351732 -221.13494)
		(width 0.4572)
		(layer "F.Cu")
		(net "GND")
	)
	(segment
		(start 384.37058 -398.542002)
		(end 383.69113 -398.542002)
		(width 0.254)
		(layer "F.Cu")
		(net "GND")
	)
	(segment
		(start 302.620934 -398.946624)
		(end 302.817784 -399.143474)
		(width 0.254)
		(layer "F.Cu")
		(net "GND")
	)
	(segment
		(start 445.360552 -8.318754)
		(end 445.360552 -7.215124)
		(width 0.3556)
		(layer "F.Cu")
		(net "GND")
	)
	(segment
		(start 17.608042 -228.78542)
		(end 18.992342 -228.78542)
		(width 0.4572)
		(layer "F.Cu")
		(net "GND")
	)
	(segment
		(start 379.457966 -240.700052)
		(end 379.924818 -240.434114)
		(width 0.350012)
		(layer "F.Cu")
		(net "GND")
	)
	(segment
		(start 132.927852 -239.8903)
		(end 133.394704 -239.624362)
		(width 0.350012)
		(layer "F.Cu")
		(net "GND")
	)
	(segment
		(start 89.047828 -261.670292)
		(end 88.580976 -261.93623)
		(width 0.350012)
		(layer "F.Cu")
		(net "GND")
	)
	(segment
		(start 59.428126 -230.485442)
		(end 58.043826 -230.485442)
		(width 0.4572)
		(layer "F.Cu")
		(net "GND")
	)
	(segment
		(start 368.64798 -254.470154)
		(end 369.114832 -254.204216)
		(width 0.350012)
		(layer "F.Cu")
		(net "GND")
	)
	(segment
		(start 205.089506 -341.010748)
		(end 204.425042 -341.675212)
		(width 0.4572)
		(layer "F.Cu")
		(net "GND")
	)
	(segment
		(start 107.377992 -291.64026)
		(end 106.91114 -291.906198)
		(width 0.350012)
		(layer "F.Cu")
		(net "GND")
	)
	(segment
		(start 93.445838 -383.402586)
		(end 93.445838 -382.951482)
		(width 0.254)
		(layer "F.Cu")
		(net "GND")
	)
	(segment
		(start 338.39785 -294.88003)
		(end 337.930998 -295.145968)
		(width 0.350012)
		(layer "F.Cu")
		(net "GND")
	)
	(segment
		(start 369.11788 -232.599992)
		(end 369.584732 -232.334054)
		(width 0.350012)
		(layer "F.Cu")
		(net "GND")
	)
	(segment
		(start 64.374268 -162.790886)
		(end 64.686434 -163.103052)
		(width 0.381)
		(layer "F.Cu")
		(net "GND")
	)
	(segment
		(start 106.309922 -124.561346)
		(end 106.309922 -125.570996)
		(width 0.3048)
		(layer "F.Cu")
		(net "GND")
	)
	(segment
		(start 94.417896 -178.29149)
		(end 94.417896 -177.6603)
		(width 0.381)
		(layer "F.Cu")
		(net "GND")
	)
	(segment
		(start 133.41477 -384.831082)
		(end 133.20141 -384.617722)
		(width 0.254)
		(layer "F.Cu")
		(net "GND")
	)
	(segment
		(start 193.922142 -106.652822)
		(end 194.312032 -106.262932)
		(width 0.254)
		(layer "F.Cu")
		(net "GND")
	)
	(segment
		(start 120.707912 -230.170228)
		(end 121.174764 -229.90429)
		(width 0.350012)
		(layer "F.Cu")
		(net "GND")
	)
	(segment
		(start 339.977984 -247.1801)
		(end 339.511132 -246.914162)
		(width 0.350012)
		(layer "F.Cu")
		(net "GND")
	)
	(segment
		(start 55.918608 -388.328662)
		(end 56.47055 -388.138924)
		(width 0.254)
		(layer "F.Cu")
		(net "GND")
	)
	(segment
		(start 373.817896 -240.700052)
		(end 374.284748 -240.434114)
		(width 0.350012)
		(layer "F.Cu")
		(net "GND")
	)
	(segment
		(start 380.86792 -243.13007)
		(end 381.334772 -242.864132)
		(width 0.350012)
		(layer "F.Cu")
		(net "GND")
	)
	(segment
		(start 145.363438 -37.903404)
		(end 144.391888 -37.903404)
		(width 0.4572)
		(layer "F.Cu")
		(net "GND")
	)
	(segment
		(start 325.70801 -277.870158)
		(end 325.052944 -277.870158)
		(width 0.350012)
		(layer "F.Cu")
		(net "GND")
	)
	(segment
		(start 101.318314 -393.510262)
		(end 101.143054 -393.335002)
		(width 0.254)
		(layer "F.Cu")
		(net "GND")
	)
	(segment
		(start 146.248882 -386.630926)
		(end 146.248882 -387.231128)
		(width 0.254)
		(layer "F.Cu")
		(net "GND")
	)
	(segment
		(start 332.172564 -143.005302)
		(end 331.461364 -143.005302)
		(width 0.254)
		(layer "F.Cu")
		(net "GND")
	)
	(segment
		(start 185.662062 -16.549878)
		(end 185.663332 -16.551148)
		(width 0.3556)
		(layer "F.Cu")
		(net "GND")
	)
	(segment
		(start 350.31807 -247.1801)
		(end 349.851218 -246.914162)
		(width 0.350012)
		(layer "F.Cu")
		(net "GND")
	)
	(segment
		(start 313.600338 -22.97938)
		(end 313.134248 -22.51329)
		(width 0.4572)
		(layer "F.Cu")
		(net "GND")
	)
	(segment
		(start 148.218906 -390.160002)
		(end 147.698206 -390.160002)
		(width 0.254)
		(layer "F.Cu")
		(net "GND")
	)
	(segment
		(start 185.122058 -117.052852)
		(end 184.732168 -117.442742)
		(width 0.254)
		(layer "F.Cu")
		(net "GND")
	)
	(segment
		(start 389.627872 -292.450012)
		(end 390.094724 -292.71595)
		(width 0.350012)
		(layer "F.Cu")
		(net "GND")
	)
	(segment
		(start 87.44585 -391.281158)
		(end 87.745824 -390.761474)
		(width 0.254)
		(layer "F.Cu")
		(net "GND")
	)
	(segment
		(start 384.157982 -239.08004)
		(end 384.624834 -238.814102)
		(width 0.350012)
		(layer "F.Cu")
		(net "GND")
	)
	(segment
		(start 421.00627 -394.831062)
		(end 420.49827 -395.0208)
		(width 0.254)
		(layer "F.Cu")
		(net "GND")
	)
	(segment
		(start 336.687922 -254.470154)
		(end 336.22107 -254.204216)
		(width 0.350012)
		(layer "F.Cu")
		(net "GND")
	)
	(segment
		(start 449.072508 -92.493592)
		(end 449.71208 -92.493592)
		(width 0.3556)
		(layer "F.Cu")
		(net "GND")
	)
	(segment
		(start 130.407918 -261.670292)
		(end 130.87477 -261.93623)
		(width 0.350012)
		(layer "F.Cu")
		(net "GND")
	)
	(segment
		(start 391.208006 -233.409998)
		(end 391.674858 -233.14406)
		(width 0.350012)
		(layer "F.Cu")
		(net "GND")
	)
	(segment
		(start 392.14806 -225.310192)
		(end 392.614912 -225.044254)
		(width 0.350012)
		(layer "F.Cu")
		(net "GND")
	)
	(segment
		(start 341.045546 -399.663158)
		(end 341.144098 -399.76171)
		(width 0.254)
		(layer "F.Cu")
		(net "GND")
	)
	(segment
		(start 58.666888 -11.26998)
		(end 58.666888 -10.16635)
		(width 0.3556)
		(layer "F.Cu")
		(net "GND")
	)
	(segment
		(start 143.567912 -285.970472)
		(end 144.034764 -286.23641)
		(width 0.350012)
		(layer "F.Cu")
		(net "GND")
	)
	(segment
		(start 111.13897 -175.106584)
		(end 111.107982 -175.106584)
		(width 0.2286)
		(layer "F.Cu")
		(net "GND")
	)
	(segment
		(start 375.36247 -392.999722)
		(end 374.77065 -392.999722)
		(width 0.254)
		(layer "F.Cu")
		(net "GND")
	)
	(segment
		(start 338.868004 -274.630134)
		(end 338.401152 -274.896072)
		(width 0.350012)
		(layer "F.Cu")
		(net "GND")
	)
	(segment
		(start 357.36784 -230.169974)
		(end 356.901242 -229.904036)
		(width 0.350012)
		(layer "F.Cu")
		(net "GND")
	)
	(segment
		(start 394.327888 -289.209988)
		(end 394.982954 -289.209988)
		(width 0.350012)
		(layer "F.Cu")
		(net "GND")
	)
	(segment
		(start 32.947102 -7.217156)
		(end 32.947102 -8.320024)
		(width 0.3556)
		(layer "F.Cu")
		(net "GND")
	)
	(segment
		(start 386.03809 -226.120198)
		(end 386.504942 -225.85426)
		(width 0.350012)
		(layer "F.Cu")
		(net "GND")
	)
	(segment
		(start 115.537996 -247.180354)
		(end 116.004848 -246.914416)
		(width 0.350012)
		(layer "F.Cu")
		(net "GND")
	)
	(segment
		(start 121.007886 -274.630388)
		(end 121.474738 -274.896326)
		(width 0.350012)
		(layer "F.Cu")
		(net "GND")
	)
	(segment
		(start 213.722458 -19.517614)
		(end 215.736424 -19.517614)
		(width 0.3556)
		(layer "F.Cu")
		(net "GND")
	)
	(segment
		(start 154.845766 -390.761474)
		(end 154.898344 -390.160002)
		(width 0.254)
		(layer "F.Cu")
		(net "GND")
	)
	(segment
		(start 49.665636 -7.215124)
		(end 49.665636 -7.215886)
		(width 0.3556)
		(layer "F.Cu")
		(net "GND")
	)
	(segment
		(start 183.616092 -230.485442)
		(end 182.231792 -230.485442)
		(width 0.4572)
		(layer "F.Cu")
		(net "GND")
	)
	(segment
		(start 102.677976 -286.780478)
		(end 102.211124 -287.046162)
		(width 0.350012)
		(layer "F.Cu")
		(net "GND")
	)
	(segment
		(start 387.716522 -400.212814)
		(end 387.716522 -399.76171)
		(width 0.254)
		(layer "F.Cu")
		(net "GND")
	)
	(segment
		(start 110.377732 -397.232378)
		(end 110.377732 -397.654526)
		(width 0.3048)
		(layer "F.Cu")
		(net "GND")
	)
	(segment
		(start 52.518056 -383.402586)
		(end 52.518056 -383.622296)
		(width 0.2032)
		(layer "F.Cu")
		(net "GND")
	)
	(segment
		(start 86.868 -252.850396)
		(end 86.401148 -252.584458)
		(width 0.350012)
		(layer "F.Cu")
		(net "GND")
	)
	(segment
		(start 113.201704 -386.931154)
		(end 113.501678 -387.231128)
		(width 0.254)
		(layer "F.Cu")
		(net "GND")
	)
	(segment
		(start 363.478064 -240.700052)
		(end 363.944916 -240.434114)
		(width 0.350012)
		(layer "F.Cu")
		(net "GND")
	)
	(segment
		(start 354.34397 -399.76171)
		(end 354.245418 -399.663158)
		(width 0.254)
		(layer "F.Cu")
		(net "GND")
	)
	(segment
		(start 322.965318 -339.372448)
		(end 322.965318 -340.003384)
		(width 0.381)
		(layer "F.Cu")
		(net "GND")
	)
	(segment
		(start 145.420842 -388.36473)
		(end 145.209768 -388.431024)
		(width 0.254)
		(layer "F.Cu")
		(net "GND")
	)
	(segment
		(start 370.26469 -394.25753)
		(end 370.109242 -394.412978)
		(width 0.254)
		(layer "F.Cu")
		(net "GND")
	)
	(segment
		(start 108.317792 -268.960346)
		(end 107.85094 -269.226284)
		(width 0.350012)
		(layer "F.Cu")
		(net "GND")
	)
	(segment
		(start 47.784004 -303.585372)
		(end 49.168304 -303.585372)
		(width 0.4572)
		(layer "F.Cu")
		(net "GND")
	)
	(segment
		(start 154.290014 -384.617722)
		(end 153.698194 -384.617722)
		(width 0.254)
		(layer "F.Cu")
		(net "GND")
	)
	(segment
		(start 179.516024 -203.285344)
		(end 180.900324 -203.285344)
		(width 0.4572)
		(layer "F.Cu")
		(net "GND")
	)
	(segment
		(start 376.81789 -399.663158)
		(end 377.117864 -399.143474)
		(width 0.254)
		(layer "F.Cu")
		(net "GND")
	)
	(segment
		(start 92.245688 -383.402586)
		(end 92.245688 -383.622296)
		(width 0.254)
		(layer "F.Cu")
		(net "GND")
	)
	(segment
		(start 51.118516 -388.328662)
		(end 51.670712 -388.138924)
		(width 0.254)
		(layer "F.Cu")
		(net "GND")
	)
	(segment
		(start 56.117998 -383.402586)
		(end 56.117998 -383.622296)
		(width 0.254)
		(layer "F.Cu")
		(net "GND")
	)
	(segment
		(start 392.61796 -247.1801)
		(end 393.084812 -246.914162)
		(width 0.350012)
		(layer "F.Cu")
		(net "GND")
	)
	(segment
		(start 135.107934 -294.070278)
		(end 135.574786 -294.336216)
		(width 0.350012)
		(layer "F.Cu")
		(net "GND")
	)
	(segment
		(start 133.398006 -230.980234)
		(end 133.864858 -230.714296)
		(width 0.350012)
		(layer "F.Cu")
		(net "GND")
	)
	(segment
		(start 122.41784 -273.820382)
		(end 122.884692 -274.08632)
		(width 0.350012)
		(layer "F.Cu")
		(net "GND")
	)
	(segment
		(start 56.21655 -391.37971)
		(end 56.117998 -391.281158)
		(width 0.254)
		(layer "F.Cu")
		(net "GND")
	)
	(segment
		(start 109.815122 -124.541788)
		(end 109.815122 -125.551438)
		(width 0.3048)
		(layer "F.Cu")
		(net "GND")
	)
	(segment
		(start 141.687804 -269.770352)
		(end 142.154656 -270.03629)
		(width 0.350012)
		(layer "F.Cu")
		(net "GND")
	)
	(segment
		(start 91.398344 -386.6388)
		(end 91.906344 -386.449062)
		(width 0.254)
		(layer "F.Cu")
		(net "GND")
	)
	(segment
		(start 63.805308 -162.790886)
		(end 64.374268 -162.790886)
		(width 0.381)
		(layer "F.Cu")
		(net "GND")
	)
	(segment
		(start 179.516024 -212.635338)
		(end 180.900324 -212.635338)
		(width 0.4572)
		(layer "F.Cu")
		(net "GND")
	)
	(segment
		(start 148.545804 -383.622296)
		(end 148.845778 -383.92227)
		(width 0.254)
		(layer "F.Cu")
		(net "GND")
	)
	(segment
		(start 131.817872 -283.540454)
		(end 132.284724 -283.806392)
		(width 0.350012)
		(layer "F.Cu")
		(net "GND")
	)
	(segment
		(start 354.842318 -396.213076)
		(end 355.062028 -396.213076)
		(width 0.254)
		(layer "F.Cu")
		(net "GND")
	)
	(segment
		(start 297.820842 -397.4084)
		(end 297.820842 -396.8369)
		(width 0.254)
		(layer "F.Cu")
		(net "GND")
	)
	(segment
		(start 415.345626 -391.333482)
		(end 415.444178 -391.23493)
		(width 0.254)
		(layer "F.Cu")
		(net "GND")
	)
	(segment
		(start 108.317792 -288.400236)
		(end 107.85094 -288.666174)
		(width 0.350012)
		(layer "F.Cu")
		(net "GND")
	)
	(segment
		(start 421.01897 -398.542002)
		(end 421.69842 -398.542002)
		(width 0.254)
		(layer "F.Cu")
		(net "GND")
	)
	(segment
		(start 284.556962 -426.59554)
		(end 284.556962 -427.24197)
		(width 0.381)
		(layer "F.Cu")
		(net "GND")
	)
	(segment
		(start 392.61796 -245.560088)
		(end 393.084812 -245.29415)
		(width 0.350012)
		(layer "F.Cu")
		(net "GND")
	)
	(segment
		(start 168.93159 -104.797352)
		(end 167.86479 -104.797352)
		(width 0.4572)
		(layer "F.Cu")
		(net "GND")
	)
	(segment
		(start 351.4852 -427.456092)
		(end 351.4852 -428.091092)
		(width 0.4318)
		(layer "F.Cu")
		(net "GND")
	)
	(segment
		(start 328.697844 -234.220004)
		(end 328.231246 -233.954066)
		(width 0.350012)
		(layer "F.Cu")
		(net "GND")
	)
	(segment
		(start 341.398098 -398.542002)
		(end 341.34552 -399.143474)
		(width 0.254)
		(layer "F.Cu")
		(net "GND")
	)
	(segment
		(start 46.518068 -383.622296)
		(end 46.818042 -383.92227)
		(width 0.254)
		(layer "F.Cu")
		(net "GND")
	)
	(segment
		(start 352.1456 -392.30427)
		(end 351.845372 -392.004042)
		(width 0.254)
		(layer "F.Cu")
		(net "GND")
	)
	(segment
		(start 369.11788 -235.840016)
		(end 369.584732 -235.574078)
		(width 0.350012)
		(layer "F.Cu")
		(net "GND")
	)
	(segment
		(start 412.367984 -303.585118)
		(end 413.752284 -303.585118)
		(width 0.4572)
		(layer "F.Cu")
		(net "GND")
	)
	(segment
		(start 21.70811 -284.035246)
		(end 20.32381 -284.035246)
		(width 0.4572)
		(layer "F.Cu")
		(net "GND")
	)
	(segment
		(start 168.065704 -13.598652)
		(end 168.065704 -12.495022)
		(width 0.3556)
		(layer "F.Cu")
		(net "GND")
	)
	(segment
		(start 187.060078 -315.485272)
		(end 188.444378 -315.485272)
		(width 0.4572)
		(layer "F.Cu")
		(net "GND")
	)
	(segment
		(start 371.938042 -234.220004)
		(end 372.404894 -233.954066)
		(width 0.350012)
		(layer "F.Cu")
		(net "GND")
	)
	(segment
		(start 347.398086 -392.999722)
		(end 347.345508 -392.30427)
		(width 0.254)
		(layer "F.Cu")
		(net "GND")
	)
	(segment
		(start 194.604132 -238.135414)
		(end 195.988432 -238.135414)
		(width 0.4572)
		(layer "F.Cu")
		(net "GND")
	)
	(segment
		(start 139.977876 -237.460282)
		(end 140.444728 -237.194344)
		(width 0.350012)
		(layer "F.Cu")
		(net "GND")
	)
	(segment
		(start 191.160146 -293.38524)
		(end 189.775846 -293.38524)
		(width 0.4572)
		(layer "F.Cu")
		(net "GND")
	)
	(segment
		(start 58.793126 -348.79915)
		(end 59.04611 -348.546166)
		(width 0.2286)
		(layer "F.Cu")
		(net "GND")
	)
	(segment
		(start 227.949506 -290.741862)
		(end 228.218746 -291.011102)
		(width 0.4572)
		(layer "F.Cu")
		(net "GND")
	)
	(segment
		(start 427.456092 -312.935112)
		(end 428.840392 -312.935112)
		(width 0.4572)
		(layer "F.Cu")
		(net "GND")
	)
	(segment
		(start 374.588024 -276.250146)
		(end 375.054876 -276.516084)
		(width 0.350012)
		(layer "F.Cu")
		(net "GND")
	)
	(segment
		(start 450.088 -240.685066)
		(end 451.4723 -240.685066)
		(width 0.4572)
		(layer "F.Cu")
		(net "GND")
	)
	(segment
		(start 307.368194 -277.235158)
		(end 305.983894 -277.235158)
		(width 0.4572)
		(layer "F.Cu")
		(net "GND")
	)
	(segment
		(start 116.77777 -273.820382)
		(end 117.244622 -274.08632)
		(width 0.350012)
		(layer "F.Cu")
		(net "GND")
	)
	(segment
		(start 384.457956 -277.060152)
		(end 384.924808 -277.32609)
		(width 0.350012)
		(layer "F.Cu")
		(net "GND")
	)
	(segment
		(start 353.437952 -290.019994)
		(end 352.9711 -290.285932)
		(width 0.350012)
		(layer "F.Cu")
		(net "GND")
	)
	(segment
		(start 80.757776 -239.080294)
		(end 80.291178 -238.814356)
		(width 0.350012)
		(layer "F.Cu")
		(net "GND")
	)
	(segment
		(start 371.938042 -235.840016)
		(end 372.404894 -235.574078)
		(width 0.350012)
		(layer "F.Cu")
		(net "GND")
	)
	(segment
		(start 92.037916 -232.600246)
		(end 91.571064 -232.334308)
		(width 0.350012)
		(layer "F.Cu")
		(net "GND")
	)
	(segment
		(start 198.7042 -227.935282)
		(end 197.3199 -227.935282)
		(width 0.4572)
		(layer "F.Cu")
		(net "GND")
	)
	(segment
		(start 46.621192 -386.630926)
		(end 46.621192 -387.231128)
		(width 0.254)
		(layer "F.Cu")
		(net "GND")
	)
	(segment
		(start 55.270654 -390.160002)
		(end 55.791354 -390.160002)
		(width 0.254)
		(layer "F.Cu")
		(net "GND")
	)
	(segment
		(start 84.71916 -390.160002)
		(end 85.398356 -390.160002)
		(width 0.254)
		(layer "F.Cu")
		(net "GND")
	)
	(segment
		(start 11.51636 -52.639214)
		(end 11.533124 -52.639214)
		(width 0.4572)
		(layer "F.Cu")
		(net "GND")
	)
	(segment
		(start 212.593682 -116.732812)
		(end 211.899754 -116.732812)
		(width 0.381)
		(layer "F.Cu")
		(net "GND")
	)
	(segment
		(start 378.01804 -392.004296)
		(end 378.318014 -392.30427)
		(width 0.254)
		(layer "F.Cu")
		(net "GND")
	)
	(segment
		(start 120.791986 -419.28796)
		(end 120.791986 -420.492936)
		(width 0.381)
		(layer "F.Cu")
		(net "GND")
	)
	(segment
		(start 113.657888 -226.120452)
		(end 114.12474 -225.854514)
		(width 0.350012)
		(layer "F.Cu")
		(net "GND")
	)
	(segment
		(start 383.048002 -287.59023)
		(end 383.514854 -287.856168)
		(width 0.350012)
		(layer "F.Cu")
		(net "GND")
	)
	(segment
		(start 144.677892 -243.94033)
		(end 145.144744 -243.674392)
		(width 0.350012)
		(layer "F.Cu")
		(net "GND")
	)
	(segment
		(start 349.378016 -224.500186)
		(end 348.911164 -224.234248)
		(width 0.350012)
		(layer "F.Cu")
		(net "GND")
	)
	(segment
		(start 280.620978 -348.794324)
		(end 280.873962 -348.54134)
		(width 0.2286)
		(layer "F.Cu")
		(net "GND")
	)
	(segment
		(start 351.25787 -224.500186)
		(end 350.791018 -224.234248)
		(width 0.350012)
		(layer "F.Cu")
		(net "GND")
	)
	(segment
		(start 121.007886 -264.910316)
		(end 121.474738 -265.176254)
		(width 0.350012)
		(layer "F.Cu")
		(net "GND")
	)
	(segment
		(start 422.26611 -366.204246)
		(end 422.26611 -366.866932)
		(width 0.381)
		(layer "F.Cu")
		(net "GND")
	)
	(segment
		(start 372.877842 -222.880174)
		(end 373.344694 -222.614236)
		(width 0.350012)
		(layer "F.Cu")
		(net "GND")
	)
	(segment
		(start 386.03809 -227.74021)
		(end 386.504942 -227.474272)
		(width 0.350012)
		(layer "F.Cu")
		(net "GND")
	)
	(segment
		(start 355.58476 -415.195258)
		(end 355.58476 -415.830258)
		(width 0.4318)
		(layer "F.Cu")
		(net "GND")
	)
	(segment
		(start 359.276904 -395.466062)
		(end 358.793288 -395.466062)
		(width 0.381)
		(layer "F.Cu")
		(net "GND")
	)
	(segment
		(start 133.235954 -295.720516)
		(end 133.69798 -295.98366)
		(width 0.350012)
		(layer "F.Cu")
		(net "GND")
	)
	(segment
		(start 358.607868 -273.010122)
		(end 358.141016 -273.27606)
		(width 0.350012)
		(layer "F.Cu")
		(net "GND")
	)
	(segment
		(start 89.047828 -266.530328)
		(end 88.580976 -266.796266)
		(width 0.350012)
		(layer "F.Cu")
		(net "GND")
	)
	(segment
		(start 318.029336 -340.206838)
		(end 318.099186 -340.136988)
		(width 0.381)
		(layer "F.Cu")
		(net "GND")
	)
	(segment
		(start 110.024418 -224.373948)
		(end 110.711488 -224.373948)
		(width 0.350012)
		(layer "F.Cu")
		(net "GND")
	)
	(segment
		(start 347.497908 -237.460028)
		(end 347.031056 -237.19409)
		(width 0.350012)
		(layer "F.Cu")
		(net "GND")
	)
	(segment
		(start 368.955066 -424.403012)
		(end 368.955066 -425.018962)
		(width 0.381)
		(layer "F.Cu")
		(net "GND")
	)
	(segment
		(start 355.018086 -240.700052)
		(end 354.551234 -240.434114)
		(width 0.350012)
		(layer "F.Cu")
		(net "GND")
	)
	(segment
		(start 398.445482 -7.215124)
		(end 398.445482 -7.215886)
		(width 0.3556)
		(layer "F.Cu")
		(net "GND")
	)
	(segment
		(start 381.167894 -271.39011)
		(end 381.634746 -271.656048)
		(width 0.350012)
		(layer "F.Cu")
		(net "GND")
	)
	(segment
		(start 269.648178 -274.684998)
		(end 268.263878 -274.684998)
		(width 0.4572)
		(layer "F.Cu")
		(net "GND")
	)
	(segment
		(start 350.306132 -394.831062)
		(end 349.798132 -395.0208)
		(width 0.254)
		(layer "F.Cu")
		(net "GND")
	)
	(segment
		(start 314.870338 -396.520924)
		(end 314.318142 -396.710662)
		(width 0.254)
		(layer "F.Cu")
		(net "GND")
	)
	(segment
		(start 46.101762 -388.13105)
		(end 45.793152 -388.36473)
		(width 0.254)
		(layer "F.Cu")
		(net "GND")
	)
	(segment
		(start 358.778048 -245.560088)
		(end 358.311196 -245.29415)
		(width 0.350012)
		(layer "F.Cu")
		(net "GND")
	)
	(segment
		(start 150.098252 -384.617722)
		(end 150.045674 -383.92227)
		(width 0.254)
		(layer "F.Cu")
		(net "GND")
	)
	(segment
		(start 82.167984 -236.650276)
		(end 81.701132 -236.384338)
		(width 0.350012)
		(layer "F.Cu")
		(net "GND")
	)
	(segment
		(start 85.927946 -225.310446)
		(end 85.461094 -225.044508)
		(width 0.350012)
		(layer "F.Cu")
		(net "GND")
	)
	(segment
		(start 158.244286 -391.830814)
		(end 158.244286 -391.37971)
		(width 0.254)
		(layer "F.Cu")
		(net "GND")
	)
	(segment
		(start 83.877912 -264.10031)
		(end 83.41106 -264.366248)
		(width 0.350012)
		(layer "F.Cu")
		(net "GND")
	)
	(segment
		(start 133.69798 -260.860286)
		(end 134.164832 -261.126224)
		(width 0.350012)
		(layer "F.Cu")
		(net "GND")
	)
	(segment
		(start 17.608042 -240.68532)
		(end 18.992342 -240.68532)
		(width 0.4572)
		(layer "F.Cu")
		(net "GND")
	)
	(segment
		(start 442.5442 -228.785166)
		(end 443.9285 -228.785166)
		(width 0.4572)
		(layer "F.Cu")
		(net "GND")
	)
	(segment
		(start 368.682016 -396.813024)
		(end 368.205004 -396.67815)
		(width 0.254)
		(layer "F.Cu")
		(net "GND")
	)
	(segment
		(start 338.097876 -242.320064)
		(end 337.631024 -242.054126)
		(width 0.350012)
		(layer "F.Cu")
		(net "GND")
	)
	(segment
		(start 47.784004 -278.085296)
		(end 49.168304 -278.085296)
		(width 0.4572)
		(layer "F.Cu")
		(net "GND")
	)
	(segment
		(start 419.946328 -396.710662)
		(end 419.298374 -396.520924)
		(width 0.254)
		(layer "F.Cu")
		(net "GND")
	)
	(segment
		(start 170.869356 -123.748546)
		(end 170.804078 -123.683268)
		(width 0.4572)
		(layer "F.Cu")
		(net "GND")
	)
	(segment
		(start 103.052372 -28.022804)
		(end 102.548436 -28.022804)
		(width 0.254)
		(layer "F.Cu")
		(net "GND")
	)
	(segment
		(start 349.847916 -254.470154)
		(end 349.381064 -254.204216)
		(width 0.350012)
		(layer "F.Cu")
		(net "GND")
	)
	(segment
		(start 343.268046 -231.789986)
		(end 342.801194 -231.524048)
		(width 0.350012)
		(layer "F.Cu")
		(net "GND")
	)
	(segment
		(start 387.917944 -222.880174)
		(end 388.384796 -222.614236)
		(width 0.350012)
		(layer "F.Cu")
		(net "GND")
	)
	(segment
		(start 311.016396 -400.212814)
		(end 311.016396 -399.76171)
		(width 0.254)
		(layer "F.Cu")
		(net "GND")
	)
	(segment
		(start 133.69798 -264.10031)
		(end 134.164832 -264.366248)
		(width 0.350012)
		(layer "F.Cu")
		(net "GND")
	)
	(segment
		(start 287.581086 -424.90898)
		(end 287.10763 -425.382436)
		(width 0.381)
		(layer "F.Cu")
		(net "GND")
	)
	(segment
		(start 415.434272 -158.556198)
		(end 414.846262 -158.556198)
		(width 0.381)
		(layer "F.Cu")
		(net "GND")
	)
	(segment
		(start 306.262532 -411.295596)
		(end 305.772058 -411.295596)
		(width 0.381)
		(layer "F.Cu")
		(net "GND")
	)
	(segment
		(start 102.677976 -288.400236)
		(end 102.211124 -288.666174)
		(width 0.350012)
		(layer "F.Cu")
		(net "GND")
	)
	(segment
		(start 363.307884 -269.770098)
		(end 363.774736 -270.036036)
		(width 0.350012)
		(layer "F.Cu")
		(net "GND")
	)
	(segment
		(start 183.616092 -237.285276)
		(end 182.231792 -237.285276)
		(width 0.4572)
		(layer "F.Cu")
		(net "GND")
	)
	(segment
		(start 209.959956 -38.169342)
		(end 210.59521 -38.169342)
		(width 0.4572)
		(layer "F.Cu")
		(net "GND")
	)
	(segment
		(start 51.884072 -211.7852)
		(end 50.499772 -211.7852)
		(width 0.4572)
		(layer "F.Cu")
		(net "GND")
	)
	(segment
		(start 318.74587 -360.192828)
		(end 318.74587 -359.924604)
		(width 0.381)
		(layer "F.Cu")
		(net "GND")
	)
	(segment
		(start 110.643924 -385.59359)
		(end 110.632494 -385.58216)
		(width 0.254)
		(layer "F.Cu")
		(net "GND")
	)
	(segment
		(start 390.281668 -76.408026)
		(end 390.28243 -76.407264)
		(width 0.4572)
		(layer "F.Cu")
		(net "GND")
	)
	(segment
		(start 102.75697 -179.627784)
		(end 102.725982 -179.627784)
		(width 0.2286)
		(layer "F.Cu")
		(net "GND")
	)
	(segment
		(start 405.012398 -75.013312)
		(end 406.358598 -75.013312)
		(width 0.4572)
		(layer "F.Cu")
		(net "GND")
	)
	(segment
		(start 397.307308 -55.6895)
		(end 395.32687 -55.6895)
		(width 0.4572)
		(layer "F.Cu")
		(net "GND")
	)
	(segment
		(start 108.017818 -229.360476)
		(end 107.550966 -229.094538)
		(width 0.350012)
		(layer "F.Cu")
		(net "GND")
	)
	(segment
		(start 83.845654 -382.951482)
		(end 83.944206 -382.85293)
		(width 0.2032)
		(layer "F.Cu")
		(net "GND")
	)
	(segment
		(start 129.74701 -16.549878)
		(end 129.74701 -17.668748)
		(width 0.3556)
		(layer "F.Cu")
		(net "GND")
	)
	(segment
		(start 381.394462 -177.532284)
		(end 381.324612 -177.602134)
		(width 0.381)
		(layer "F.Cu")
		(net "GND")
	)
	(segment
		(start 403.018752 -398.542002)
		(end 403.018752 -398.613122)
		(width 0.254)
		(layer "F.Cu")
		(net "GND")
	)
	(segment
		(start 112.717834 -229.360476)
		(end 113.184686 -229.094538)
		(width 0.350012)
		(layer "F.Cu")
		(net "GND")
	)
	(segment
		(start 389.627872 -276.250146)
		(end 390.094724 -276.516084)
		(width 0.350012)
		(layer "F.Cu")
		(net "GND")
	)
	(segment
		(start 80.287876 -251.230384)
		(end 79.821024 -250.964446)
		(width 0.350012)
		(layer "F.Cu")
		(net "GND")
	)
	(segment
		(start 265.54811 -210.085178)
		(end 266.93241 -210.085178)
		(width 0.4572)
		(layer "F.Cu")
		(net "GND")
	)
	(segment
		(start 56.867044 -10.16635)
		(end 56.865774 -10.16508)
		(width 0.3556)
		(layer "F.Cu")
		(net "GND")
	)
	(segment
		(start 399.160238 -393.96416)
		(end 399.693638 -393.96416)
		(width 0.254)
		(layer "F.Cu")
		(net "GND")
	)
	(segment
		(start 325.408036 -223.69018)
		(end 324.941184 -223.424242)
		(width 0.350012)
		(layer "F.Cu")
		(net "GND")
	)
	(segment
		(start 379.75794 -265.720068)
		(end 380.224792 -265.986006)
		(width 0.350012)
		(layer "F.Cu")
		(net "GND")
	)
	(segment
		(start 338.868004 -277.870158)
		(end 338.401152 -278.136096)
		(width 0.350012)
		(layer "F.Cu")
		(net "GND")
	)
	(segment
		(start 146.214846 -394.954506)
		(end 146.214846 -394.352018)
		(width 0.254)
		(layer "F.Cu")
		(net "GND")
	)
	(segment
		(start 357.839518 -27.695398)
		(end 356.848918 -27.695398)
		(width 0.4572)
		(layer "F.Cu")
		(net "GND")
	)
	(segment
		(start 65.530222 -31.304484)
		(end 66.671444 -30.163262)
		(width 0.254)
		(layer "F.Cu")
		(net "GND")
	)
	(segment
		(start 424.012106 -199.885046)
		(end 422.627806 -199.885046)
		(width 0.4572)
		(layer "F.Cu")
		(net "GND")
	)
	(segment
		(start 183.522112 -113.05286)
		(end 183.132222 -112.66297)
		(width 0.254)
		(layer "F.Cu")
		(net "GND")
	)
	(segment
		(start 337.798156 -392.999722)
		(end 337.745578 -392.30427)
		(width 0.254)
		(layer "F.Cu")
		(net "GND")
	)
	(segment
		(start 240.865406 -291.361876)
		(end 240.727992 -291.224462)
		(width 0.1778)
		(layer "F.Cu")
		(net "GND")
	)
	(segment
		(start 336.598006 -396.520924)
		(end 336.046064 -396.710662)
		(width 0.254)
		(layer "F.Cu")
		(net "GND")
	)
	(segment
		(start 375.970546 -392.999722)
		(end 375.917968 -392.30427)
		(width 0.254)
		(layer "F.Cu")
		(net "GND")
	)
	(segment
		(start 95.944182 -391.830814)
		(end 95.944182 -391.37971)
		(width 0.254)
		(layer "F.Cu")
		(net "GND")
	)
	(segment
		(start 394.327888 -263.29005)
		(end 394.982954 -263.29005)
		(width 0.350012)
		(layer "F.Cu")
		(net "GND")
	)
	(segment
		(start 347.968062 -241.510058)
		(end 347.50121 -241.24412)
		(width 0.350012)
		(layer "F.Cu")
		(net "GND")
	)
	(segment
		(start 148.898356 -390.160002)
		(end 148.218906 -390.160002)
		(width 0.254)
		(layer "F.Cu")
		(net "GND")
	)
	(segment
		(start 347.497908 -240.700052)
		(end 347.031056 -240.434114)
		(width 0.350012)
		(layer "F.Cu")
		(net "GND")
	)
	(segment
		(start 123.05792 -232.600246)
		(end 123.524772 -232.334308)
		(width 0.350012)
		(layer "F.Cu")
		(net "GND")
	)
	(segment
		(start 446.644268 -277.235158)
		(end 445.259968 -277.235158)
		(width 0.4572)
		(layer "F.Cu")
		(net "GND")
	)
	(segment
		(start 79.022702 -391.304272)
		(end 79.045816 -391.281158)
		(width 0.254)
		(layer "F.Cu")
		(net "GND")
	)
	(segment
		(start 345.1479 -235.03001)
		(end 344.681048 -234.764072)
		(width 0.350012)
		(layer "F.Cu")
		(net "GND")
	)
	(segment
		(start 87.637874 -294.880284)
		(end 87.171022 -295.146222)
		(width 0.350012)
		(layer "F.Cu")
		(net "GND")
	)
	(segment
		(start 370.057934 -247.1801)
		(end 370.524786 -246.914162)
		(width 0.350012)
		(layer "F.Cu")
		(net "GND")
	)
	(segment
		(start 164.427916 -275.53539)
		(end 165.812216 -275.53539)
		(width 0.4572)
		(layer "F.Cu")
		(net "GND")
	)
	(segment
		(start 110.83798 -245.560342)
		(end 110.371128 -245.294404)
		(width 0.350012)
		(layer "F.Cu")
		(net "GND")
	)
	(segment
		(start 435.000146 -275.535136)
		(end 436.384446 -275.535136)
		(width 0.4572)
		(layer "F.Cu")
		(net "GND")
	)
	(segment
		(start 409.79979 -165.528498)
		(end 409.309824 -166.018464)
		(width 0.2286)
		(layer "F.Cu")
		(net "GND")
	)
	(segment
		(start 424.012106 -284.034992)
		(end 422.627806 -284.034992)
		(width 0.4572)
		(layer "F.Cu")
		(net "GND")
	)
	(segment
		(start 388.817866 -391.784586)
		(end 388.916418 -391.686034)
		(width 0.254)
		(layer "F.Cu")
		(net "GND")
	)
	(segment
		(start 68.651374 -150.551642)
		(end 68.191888 -149.75459)
		(width 0.1778)
		(layer "F.Cu")
		(net "GND")
	)
	(segment
		(start 320.09842 -103.40975)
		(end 320.707258 -103.40975)
		(width 0.4572)
		(layer "F.Cu")
		(net "GND")
	)
	(segment
		(start 371.467888 -241.510058)
		(end 371.93474 -241.24412)
		(width 0.350012)
		(layer "F.Cu")
		(net "GND")
	)
	(segment
		(start 105.967784 -285.970472)
		(end 105.500932 -286.23641)
		(width 0.350012)
		(layer "F.Cu")
		(net "GND")
	)
	(segment
		(start 328.998072 -281.920188)
		(end 328.53122 -282.186126)
		(width 0.350012)
		(layer "F.Cu")
		(net "GND")
	)
	(segment
		(start 131.548378 -16.551148)
		(end 131.548378 -17.654778)
		(width 0.3556)
		(layer "F.Cu")
		(net "GND")
	)
	(segment
		(start 403.34565 -399.663158)
		(end 403.444202 -399.76171)
		(width 0.254)
		(layer "F.Cu")
		(net "GND")
	)
	(segment
		(start 92.33789 -283.540454)
		(end 91.871038 -283.806392)
		(width 0.350012)
		(layer "F.Cu")
		(net "GND")
	)
	(segment
		(start 187.316872 -429.330612)
		(end 187.316872 -429.801782)
		(width 0.381)
		(layer "F.Cu")
		(net "GND")
	)
	(segment
		(start 308.002432 -411.295596)
		(end 308.002432 -412.128462)
		(width 0.381)
		(layer "F.Cu")
		(net "GND")
	)
	(segment
		(start 92.037916 -229.360476)
		(end 91.571064 -229.094538)
		(width 0.350012)
		(layer "F.Cu")
		(net "GND")
	)
	(segment
		(start 43.54449 -101.74224)
		(end 44.18584 -101.74224)
		(width 0.381)
		(layer "F.Cu")
		(net "GND")
	)
	(segment
		(start 126.177802 -280.30043)
		(end 126.644654 -280.566368)
		(width 0.350012)
		(layer "F.Cu")
		(net "GND")
	)
	(segment
		(start 136.987788 -285.970472)
		(end 137.45464 -286.23641)
		(width 0.350012)
		(layer "F.Cu")
		(net "GND")
	)
	(segment
		(start 120.537986 -267.340334)
		(end 121.004838 -267.606272)
		(width 0.350012)
		(layer "F.Cu")
		(net "GND")
	)
	(segment
		(start 373.5705 -398.542002)
		(end 372.891304 -398.542002)
		(width 0.254)
		(layer "F.Cu")
		(net "GND")
	)
	(segment
		(start 391.50798 -261.670038)
		(end 391.974832 -261.935976)
		(width 0.350012)
		(layer "F.Cu")
		(net "GND")
	)
	(segment
		(start 100.327968 -290.830254)
		(end 99.861116 -291.096192)
		(width 0.350012)
		(layer "F.Cu")
		(net "GND")
	)
	(segment
		(start 302.301402 -396.712948)
		(end 302.101504 -396.51305)
		(width 0.254)
		(layer "F.Cu")
		(net "GND")
	)
	(segment
		(start 85.457792 -256.900426)
		(end 84.99094 -256.634488)
		(width 0.350012)
		(layer "F.Cu")
		(net "GND")
	)
	(segment
		(start 61.711586 -52.743354)
		(end 62.5475 -51.90744)
		(width 0.381)
		(layer "F.Cu")
		(net "GND")
	)
	(segment
		(start 362.094526 -406.822402)
		(end 361.420156 -406.822402)
		(width 0.381)
		(layer "F.Cu")
		(net "GND")
	)
	(segment
		(start 349.189802 -392.999722)
		(end 348.597982 -392.999722)
		(width 0.254)
		(layer "F.Cu")
		(net "GND")
	)
	(segment
		(start 410.545788 -391.784586)
		(end 410.545788 -391.333482)
		(width 0.254)
		(layer "F.Cu")
		(net "GND")
	)
	(segment
		(start 304.22342 -428.75708)
		(end 304.22342 -428.08906)
		(width 0.4318)
		(layer "F.Cu")
		(net "GND")
	)
	(segment
		(start 116.370608 -384.617722)
		(end 116.31803 -383.92227)
		(width 0.254)
		(layer "F.Cu")
		(net "GND")
	)
	(segment
		(start 49.862486 -384.617722)
		(end 49.270666 -384.617722)
		(width 0.254)
		(layer "F.Cu")
		(net "GND")
	)
	(segment
		(start 335.148682 -397.412972)
		(end 335.148682 -396.712948)
		(width 0.254)
		(layer "F.Cu")
		(net "GND")
	)
	(segment
		(start 336.687922 -233.409998)
		(end 336.22107 -233.14406)
		(width 0.350012)
		(layer "F.Cu")
		(net "GND")
	)
	(segment
		(start 122.117866 -247.180354)
		(end 122.584718 -246.914416)
		(width 0.350012)
		(layer "F.Cu")
		(net "GND")
	)
	(segment
		(start 98.566224 -399.888202)
		(end 97.579942 -399.888202)
		(width 0.3302)
		(layer "F.Cu")
		(net "GND")
	)
	(segment
		(start 271.607788 -102.647242)
		(end 270.228822 -102.647242)
		(width 0.4572)
		(layer "F.Cu")
		(net "GND")
	)
	(segment
		(start 89.944194 -391.37971)
		(end 89.845642 -391.281158)
		(width 0.254)
		(layer "F.Cu")
		(net "GND")
	)
	(segment
		(start 123.570492 -386.6388)
		(end 122.878596 -386.449062)
		(width 0.254)
		(layer "F.Cu")
		(net "GND")
	)
	(segment
		(start 165.942518 -387.831076)
		(end 166.162228 -387.831076)
		(width 0.254)
		(layer "F.Cu")
		(net "GND")
	)
	(segment
		(start 85.757766 -291.64026)
		(end 85.290914 -291.906198)
		(width 0.350012)
		(layer "F.Cu")
		(net "GND")
	)
	(segment
		(start 342.158066 -286.780224)
		(end 341.691214 -287.045908)
		(width 0.350012)
		(layer "F.Cu")
		(net "GND")
	)
	(segment
		(start 418.355526 -7.215886)
		(end 418.356796 -7.217156)
		(width 0.3556)
		(layer "F.Cu")
		(net "GND")
	)
	(segment
		(start 47.784004 -200.735438)
		(end 49.168304 -200.735438)
		(width 0.4572)
		(layer "F.Cu")
		(net "GND")
	)
	(segment
		(start 303.268126 -210.085178)
		(end 304.652426 -210.085178)
		(width 0.4572)
		(layer "F.Cu")
		(net "GND")
	)
	(segment
		(start 92.037916 -250.420378)
		(end 91.571064 -250.15444)
		(width 0.350012)
		(layer "F.Cu")
		(net "GND")
	)
	(segment
		(start 32.945832 -7.215124)
		(end 32.945832 -7.215886)
		(width 0.3556)
		(layer "F.Cu")
		(net "GND")
	)
	(segment
		(start 52.011072 -403.73808)
		(end 51.918616 -403.830536)
		(width 0.381)
		(layer "F.Cu")
		(net "GND")
	)
	(segment
		(start 338.39785 -272.200116)
		(end 337.930998 -272.466054)
		(width 0.350012)
		(layer "F.Cu")
		(net "GND")
	)
	(segment
		(start 132.927852 -249.610372)
		(end 133.394704 -249.344434)
		(width 0.350012)
		(layer "F.Cu")
		(net "GND")
	)
	(segment
		(start 371.767862 -274.630134)
		(end 372.234714 -274.896072)
		(width 0.350012)
		(layer "F.Cu")
		(net "GND")
	)
	(segment
		(start 20.769834 -393.539726)
		(end 20.769834 -393.915392)
		(width 0.381)
		(layer "F.Cu")
		(net "GND")
	)
	(segment
		(start 325.408036 -233.409998)
		(end 324.75297 -233.409998)
		(width 0.350012)
		(layer "F.Cu")
		(net "GND")
	)
	(segment
		(start 125.418342 -388.328662)
		(end 124.770642 -388.138924)
		(width 0.254)
		(layer "F.Cu")
		(net "GND")
	)
	(segment
		(start 90.157808 -237.460282)
		(end 89.690956 -237.194344)
		(width 0.350012)
		(layer "F.Cu")
		(net "GND")
	)
	(segment
		(start 113.970562 -388.08152)
		(end 113.721134 -387.832092)
		(width 0.254)
		(layer "F.Cu")
		(net "GND")
	)
	(segment
		(start 119.492014 -417.38804)
		(end 118.9609 -417.919154)
		(width 0.381)
		(layer "F.Cu")
		(net "GND")
	)
	(segment
		(start 450.088 -238.13516)
		(end 451.4723 -238.13516)
		(width 0.4572)
		(layer "F.Cu")
		(net "GND")
	)
	(segment
		(start 358.862122 -167.670988)
		(end 358.433624 -167.670988)
		(width 0.2286)
		(layer "F.Cu")
		(net "GND")
	)
	(segment
		(start 162.945572 -383.402586)
		(end 162.945572 -382.951482)
		(width 0.254)
		(layer "F.Cu")
		(net "GND")
	)
	(segment
		(start 100.027994 -230.170228)
		(end 99.561142 -229.90429)
		(width 0.350012)
		(layer "F.Cu")
		(net "GND")
	)
	(segment
		(start 368.947954 -285.970218)
		(end 369.414806 -286.236156)
		(width 0.350012)
		(layer "F.Cu")
		(net "GND")
	)
	(segment
		(start 330.108052 -230.169974)
		(end 329.6412 -229.904036)
		(width 0.350012)
		(layer "F.Cu")
		(net "GND")
	)
	(segment
		(start 335.108042 -285.970218)
		(end 334.64119 -286.236156)
		(width 0.350012)
		(layer "F.Cu")
		(net "GND")
	)
	(segment
		(start 89.845642 -391.281158)
		(end 90.14587 -390.761474)
		(width 0.254)
		(layer "F.Cu")
		(net "GND")
	)
	(segment
		(start 83.107784 -223.690434)
		(end 82.640932 -223.424496)
		(width 0.350012)
		(layer "F.Cu")
		(net "GND")
	)
	(segment
		(start 380.71806 -399.143474)
		(end 380.770638 -398.542002)
		(width 0.254)
		(layer "F.Cu")
		(net "GND")
	)
	(segment
		(start 85.144356 -391.37971)
		(end 85.144356 -391.830814)
		(width 0.254)
		(layer "F.Cu")
		(net "GND")
	)
	(segment
		(start 309.717694 -392.004296)
		(end 310.017668 -392.30427)
		(width 0.254)
		(layer "F.Cu")
		(net "GND")
	)
	(segment
		(start 48.070516 -386.6388)
		(end 47.37862 -386.449062)
		(width 0.254)
		(layer "F.Cu")
		(net "GND")
	)
	(segment
		(start 420.246302 -437.834786)
		(end 420.877238 -437.834786)
		(width 0.381)
		(layer "F.Cu")
		(net "GND")
	)
	(segment
		(start 85.457792 -243.94033)
		(end 84.99094 -243.674392)
		(width 0.350012)
		(layer "F.Cu")
		(net "GND")
	)
	(segment
		(start 84.978494 -177.48631)
		(end 85.34781 -177.48631)
		(width 0.381)
		(layer "F.Cu")
		(net "GND")
	)
	(segment
		(start 145.209768 -387.231128)
		(end 144.732756 -387.04774)
		(width 0.254)
		(layer "F.Cu")
		(net "GND")
	)
	(segment
		(start 413.245808 -399.143474)
		(end 413.298386 -398.542002)
		(width 0.254)
		(layer "F.Cu")
		(net "GND")
	)
	(segment
		(start 331.518006 -255.28016)
		(end 331.051154 -255.014222)
		(width 0.350012)
		(layer "F.Cu")
		(net "GND")
	)
	(segment
		(start 16.837406 -76.544678)
		(end 16.20012 -76.544678)
		(width 0.4064)
		(layer "F.Cu")
		(net "GND")
	)
	(segment
		(start 40.23995 -284.885384)
		(end 41.62425 -284.885384)
		(width 0.4572)
		(layer "F.Cu")
		(net "GND")
	)
	(segment
		(start 421.729154 -392.387836)
		(end 421.645588 -392.30427)
		(width 0.254)
		(layer "F.Cu")
		(net "GND")
	)
	(segment
		(start 229.503224 -155.284932)
		(end 229.503224 -155.971748)
		(width 0.381)
		(layer "F.Cu")
		(net "GND")
	)
	(segment
		(start 113.487962 -281.110436)
		(end 113.954814 -281.376374)
		(width 0.350012)
		(layer "F.Cu")
		(net "GND")
	)
	(segment
		(start 389.414766 -393.213082)
		(end 389.414766 -393.59332)
		(width 0.254)
		(layer "F.Cu")
		(net "GND")
	)
	(segment
		(start 378.048012 -246.370094)
		(end 378.514864 -246.104156)
		(width 0.350012)
		(layer "F.Cu")
		(net "GND")
	)
	(segment
		(start 443.35319 -29.575506)
		(end 443.35319 -30.365954)
		(width 0.254)
		(layer "F.Cu")
		(net "GND")
	)
	(segment
		(start 131.517898 -229.360476)
		(end 131.98475 -229.094538)
		(width 0.350012)
		(layer "F.Cu")
		(net "GND")
	)
	(segment
		(start 337.445604 -399.663158)
		(end 337.745578 -399.143474)
		(width 0.254)
		(layer "F.Cu")
		(net "GND")
	)
	(segment
		(start 102.677976 -265.720322)
		(end 102.211124 -265.98626)
		(width 0.350012)
		(layer "F.Cu")
		(net "GND")
	)
	(segment
		(start 172.593 -133.11505)
		(end 172.593 -133.815836)
		(width 0.381)
		(layer "F.Cu")
		(net "GND")
	)
	(segment
		(start 413.245808 -392.30427)
		(end 412.94558 -392.004042)
		(width 0.254)
		(layer "F.Cu")
		(net "GND")
	)
	(segment
		(start 377.170442 -396.520924)
		(end 376.6185 -396.710662)
		(width 0.254)
		(layer "F.Cu")
		(net "GND")
	)
	(segment
		(start 177.296318 -92.493084)
		(end 177.470562 -92.493084)
		(width 0.381)
		(layer "F.Cu")
		(net "GND")
	)
	(segment
		(start 325.70801 -281.110182)
		(end 325.052944 -281.110182)
		(width 0.350012)
		(layer "F.Cu")
		(net "GND")
	)
	(segment
		(start 371.467888 -239.890046)
		(end 371.93474 -239.624108)
		(width 0.350012)
		(layer "F.Cu")
		(net "GND")
	)
	(segment
		(start 307.368194 -227.935028)
		(end 305.983894 -227.935028)
		(width 0.4572)
		(layer "F.Cu")
		(net "GND")
	)
	(segment
		(start 370.478558 -394.831062)
		(end 369.72113 -395.012926)
		(width 0.254)
		(layer "F.Cu")
		(net "GND")
	)
	(segment
		(start 350.744028 -400.212814)
		(end 350.744028 -399.76171)
		(width 0.254)
		(layer "F.Cu")
		(net "GND")
	)
	(segment
		(start 404.5458 -391.333482)
		(end 404.644352 -391.23493)
		(width 0.254)
		(layer "F.Cu")
		(net "GND")
	)
	(segment
		(start 102.378002 -247.180354)
		(end 101.91115 -246.914416)
		(width 0.350012)
		(layer "F.Cu")
		(net "GND")
	)
	(segment
		(start 93.91777 -245.560342)
		(end 93.450918 -245.294404)
		(width 0.350012)
		(layer "F.Cu")
		(net "GND")
	)
	(segment
		(start 82.467958 -287.590484)
		(end 82.001106 -287.856422)
		(width 0.350012)
		(layer "F.Cu")
		(net "GND")
	)
	(segment
		(start 129.63779 -240.700306)
		(end 130.104642 -240.434368)
		(width 0.350012)
		(layer "F.Cu")
		(net "GND")
	)
	(segment
		(start 302.51781 -392.004296)
		(end 302.817784 -392.30427)
		(width 0.254)
		(layer "F.Cu")
		(net "GND")
	)
	(segment
		(start 58.870596 -388.138924)
		(end 59.51855 -388.328662)
		(width 0.254)
		(layer "F.Cu")
		(net "GND")
	)
	(segment
		(start 111.137954 -281.920442)
		(end 110.671102 -282.18638)
		(width 0.350012)
		(layer "F.Cu")
		(net "GND")
	)
	(segment
		(start 347.497908 -247.1801)
		(end 347.031056 -246.914162)
		(width 0.350012)
		(layer "F.Cu")
		(net "GND")
	)
	(segment
		(start 33.868614 -134.488936)
		(end 34.242248 -134.86257)
		(width 0.4064)
		(layer "F.Cu")
		(net "GND")
	)
	(segment
		(start 117.888004 -238.270288)
		(end 118.354856 -238.00435)
		(width 0.350012)
		(layer "F.Cu")
		(net "GND")
	)
	(segment
		(start 457.329794 -45.864526)
		(end 458.244194 -45.864526)
		(width 0.3556)
		(layer "F.Cu")
		(net "GND")
	)
	(segment
		(start 47.717964 -382.951482)
		(end 47.816516 -382.85293)
		(width 0.254)
		(layer "F.Cu")
		(net "GND")
	)
	(segment
		(start 391.208006 -246.370094)
		(end 391.674858 -246.104156)
		(width 0.350012)
		(layer "F.Cu")
		(net "GND")
	)
	(segment
		(start 349.798132 -395.0208)
		(end 349.105982 -394.831062)
		(width 0.254)
		(layer "F.Cu")
		(net "GND")
	)
	(segment
		(start 80.287876 -222.070422)
		(end 79.821024 -221.804484)
		(width 0.350012)
		(layer "F.Cu")
		(net "GND")
	)
	(segment
		(start 299.460412 -351.927922)
		(end 300.048422 -351.927922)
		(width 0.381)
		(layer "F.Cu")
		(net "GND")
	)
	(segment
		(start 133.227826 -289.210242)
		(end 133.694678 -289.47618)
		(width 0.350012)
		(layer "F.Cu")
		(net "GND")
	)
	(segment
		(start 130.218434 -388.328662)
		(end 129.57048 -388.138924)
		(width 0.254)
		(layer "F.Cu")
		(net "GND")
	)
	(segment
		(start 130.417824 -383.622042)
		(end 130.417824 -383.402586)
		(width 0.254)
		(layer "F.Cu")
		(net "GND")
	)
	(segment
		(start 371.938042 -232.599992)
		(end 372.404894 -232.334054)
		(width 0.350012)
		(layer "F.Cu")
		(net "GND")
	)
	(segment
		(start 363.00791 -230.169974)
		(end 363.474762 -229.904036)
		(width 0.350012)
		(layer "F.Cu")
		(net "GND")
	)
	(segment
		(start 270.228822 -102.647242)
		(end 269.609824 -103.26624)
		(width 0.4572)
		(layer "F.Cu")
		(net "GND")
	)
	(segment
		(start 352.497898 -293.260018)
		(end 352.031046 -293.525956)
		(width 0.350012)
		(layer "F.Cu")
		(net "GND")
	)
	(segment
		(start 381.917956 -392.30427)
		(end 381.970534 -392.999722)
		(width 0.254)
		(layer "F.Cu")
		(net "GND")
	)
	(segment
		(start 372.370604 -392.999722)
		(end 371.762274 -392.999722)
		(width 0.254)
		(layer "F.Cu")
		(net "GND")
	)
	(segment
		(start 83.877912 -288.400236)
		(end 83.41106 -288.666174)
		(width 0.350012)
		(layer "F.Cu")
		(net "GND")
	)
	(segment
		(start 90.157808 -255.280414)
		(end 89.690956 -255.014476)
		(width 0.350012)
		(layer "F.Cu")
		(net "GND")
	)
	(segment
		(start 122.116596 -391.830814)
		(end 122.116596 -391.37971)
		(width 0.254)
		(layer "F.Cu")
		(net "GND")
	)
	(segment
		(start 188.164978 -353.398836)
		(end 188.164978 -353.81565)
		(width 0.2286)
		(layer "F.Cu")
		(net "GND")
	)
	(segment
		(start 96.715834 -135.652002)
		(end 96.715834 -133.325362)
		(width 0.4572)
		(layer "F.Cu")
		(net "GND")
	)
	(segment
		(start 158.244286 -391.37971)
		(end 158.145734 -391.281158)
		(width 0.254)
		(layer "F.Cu")
		(net "GND")
	)
	(segment
		(start 130.107944 -246.370348)
		(end 130.574796 -246.10441)
		(width 0.350012)
		(layer "F.Cu")
		(net "GND")
	)
	(segment
		(start 102.811834 -176.838102)
		(end 102.811834 -177.46218)
		(width 0.381)
		(layer "F.Cu")
		(net "GND")
	)
	(segment
		(start 380.516384 -400.212814)
		(end 380.516384 -399.76171)
		(width 0.254)
		(layer "F.Cu")
		(net "GND")
	)
	(segment
		(start 45.658278 -12.374118)
		(end 45.657008 -12.372848)
		(width 0.3556)
		(layer "F.Cu")
		(net "GND")
	)
	(segment
		(start 97.037906 -278.680418)
		(end 96.571054 -278.946356)
		(width 0.350012)
		(layer "F.Cu")
		(net "GND")
	)
	(segment
		(start 343.56802 -261.670038)
		(end 343.101168 -261.935976)
		(width 0.350012)
		(layer "F.Cu")
		(net "GND")
	)
	(segment
		(start 120.791986 -420.492936)
		(end 120.79605 -420.497)
		(width 0.381)
		(layer "F.Cu")
		(net "GND")
	)
	(segment
		(start 421.09009 -392.999722)
		(end 421.729154 -392.999722)
		(width 0.254)
		(layer "F.Cu")
		(net "GND")
	)
	(segment
		(start 154.742896 -108.01096)
		(end 154.655266 -108.09859)
		(width 0.381)
		(layer "F.Cu")
		(net "GND")
	)
	(segment
		(start 419.912038 -284.88513)
		(end 421.296338 -284.88513)
		(width 0.4572)
		(layer "F.Cu")
		(net "GND")
	)
	(segment
		(start 373.817896 -250.420124)
		(end 374.284748 -250.154186)
		(width 0.350012)
		(layer "F.Cu")
		(net "GND")
	)
	(segment
		(start 133.227826 -263.290304)
		(end 133.694678 -263.556242)
		(width 0.350012)
		(layer "F.Cu")
		(net "GND")
	)
	(segment
		(start 128.52781 -261.670292)
		(end 128.994662 -261.93623)
		(width 0.350012)
		(layer "F.Cu")
		(net "GND")
	)
	(segment
		(start 90.927936 -263.290304)
		(end 90.461084 -263.556242)
		(width 0.350012)
		(layer "F.Cu")
		(net "GND")
	)
	(segment
		(start 394.027914 -243.13007)
		(end 394.68298 -243.13007)
		(width 0.350012)
		(layer "F.Cu")
		(net "GND")
	)
	(segment
		(start 55.066946 -11.26998)
		(end 55.066946 -10.16635)
		(width 0.3556)
		(layer "F.Cu")
		(net "GND")
	)
	(segment
		(start 336.987896 -285.970218)
		(end 336.521044 -286.236156)
		(width 0.350012)
		(layer "F.Cu")
		(net "GND")
	)
	(segment
		(start 90.627962 -226.930458)
		(end 90.16111 -226.66452)
		(width 0.350012)
		(layer "F.Cu")
		(net "GND")
	)
	(segment
		(start 17.380458 -418.290248)
		(end 17.380458 -417.68014)
		(width 0.381)
		(layer "F.Cu")
		(net "GND")
	)
	(segment
		(start 353.607878 -230.169974)
		(end 353.141026 -229.904036)
		(width 0.350012)
		(layer "F.Cu")
		(net "GND")
	)
	(segment
		(start 91.097862 -224.50044)
		(end 90.63101 -224.234502)
		(width 0.350012)
		(layer "F.Cu")
		(net "GND")
	)
	(segment
		(start 88.82253 -72.824848)
		(end 88.861392 -72.86371)
		(width 0.4572)
		(layer "F.Cu")
		(net "GND")
	)
	(segment
		(start 328.998072 -273.820128)
		(end 328.53122 -274.086066)
		(width 0.350012)
		(layer "F.Cu")
		(net "GND")
	)
	(segment
		(start 410.89834 -398.542002)
		(end 410.21889 -398.542002)
		(width 0.254)
		(layer "F.Cu")
		(net "GND")
	)
	(segment
		(start 140.277342 -402.755608)
		(end 139.202414 -403.830536)
		(width 0.381)
		(layer "F.Cu")
		(net "GND")
	)
	(segment
		(start 377.577858 -255.28016)
		(end 378.04471 -255.014222)
		(width 0.350012)
		(layer "F.Cu")
		(net "GND")
	)
	(segment
		(start 178.31689 -401.452842)
		(end 177.70094 -401.452842)
		(width 0.254)
		(layer "F.Cu")
		(net "GND")
	)
	(segment
		(start 401.929346 -396.712948)
		(end 401.729448 -396.51305)
		(width 0.254)
		(layer "F.Cu")
		(net "GND")
	)
	(segment
		(start 95.627952 -264.910316)
		(end 95.1611 -265.176254)
		(width 0.350012)
		(layer "F.Cu")
		(net "GND")
	)
	(segment
		(start 417.71189 -105.207308)
		(end 417.10229 -105.207308)
		(width 0.3556)
		(layer "F.Cu")
		(net "GND")
	)
	(segment
		(start 179.516024 -278.085296)
		(end 180.900324 -278.085296)
		(width 0.4572)
		(layer "F.Cu")
		(net "GND")
	)
	(segment
		(start 369.888008 -261.670038)
		(end 370.35486 -261.935976)
		(width 0.350012)
		(layer "F.Cu")
		(net "GND")
	)
	(segment
		(start 29.252164 -286.585406)
		(end 27.867864 -286.585406)
		(width 0.4572)
		(layer "F.Cu")
		(net "GND")
	)
	(segment
		(start 32.695896 -306.135278)
		(end 34.080196 -306.135278)
		(width 0.4572)
		(layer "F.Cu")
		(net "GND")
	)
	(segment
		(start 115.170458 -390.160002)
		(end 114.491008 -390.160002)
		(width 0.254)
		(layer "F.Cu")
		(net "GND")
	)
	(segment
		(start 303.268126 -203.28509)
		(end 304.652426 -203.28509)
		(width 0.4572)
		(layer "F.Cu")
		(net "GND")
	)
	(segment
		(start 110.537498 -176.093882)
		(end 110.284514 -176.346866)
		(width 0.2286)
		(layer "F.Cu")
		(net "GND")
	)
	(segment
		(start 378.048012 -241.510058)
		(end 378.514864 -241.24412)
		(width 0.350012)
		(layer "F.Cu")
		(net "GND")
	)
	(segment
		(start 142.327884 -249.610372)
		(end 142.794736 -249.344434)
		(width 0.350012)
		(layer "F.Cu")
		(net "GND")
	)
	(segment
		(start 376.167904 -247.990106)
		(end 376.634756 -247.724168)
		(width 0.350012)
		(layer "F.Cu")
		(net "GND")
	)
	(segment
		(start 339.977984 -224.500186)
		(end 339.511132 -224.234248)
		(width 0.350012)
		(layer "F.Cu")
		(net "GND")
	)
	(segment
		(start 136.59358 -386.84073)
		(end 136.836912 -387.084062)
		(width 0.381)
		(layer "F.Cu")
		(net "GND")
	)
	(segment
		(start 394.333984 -389.446516)
		(end 394.377672 -389.402828)
		(width 0.254)
		(layer "F.Cu")
		(net "GND")
	)
	(segment
		(start 128.52781 -294.070278)
		(end 128.994662 -294.336216)
		(width 0.350012)
		(layer "F.Cu")
		(net "GND")
	)
	(segment
		(start 95.627952 -274.630388)
		(end 95.1611 -274.896326)
		(width 0.350012)
		(layer "F.Cu")
		(net "GND")
	)
	(segment
		(start 374.28805 -226.930204)
		(end 374.754902 -226.664266)
		(width 0.350012)
		(layer "F.Cu")
		(net "GND")
	)
	(segment
		(start 434.796692 -20.649184)
		(end 434.796692 -20.025868)
		(width 0.3556)
		(layer "F.Cu")
		(net "GND")
	)
	(segment
		(start 355.018086 -243.940076)
		(end 354.551234 -243.674138)
		(width 0.350012)
		(layer "F.Cu")
		(net "GND")
	)
	(segment
		(start 372.877842 -235.840016)
		(end 373.344694 -235.574078)
		(width 0.350012)
		(layer "F.Cu")
		(net "GND")
	)
	(segment
		(start 351.349564 -345.146122)
		(end 351.419414 -345.076272)
		(width 0.381)
		(layer "F.Cu")
		(net "GND")
	)
	(segment
		(start 369.970558 -392.999722)
		(end 370.562378 -392.999722)
		(width 0.254)
		(layer "F.Cu")
		(net "GND")
	)
	(segment
		(start 338.318856 -398.542002)
		(end 337.798156 -398.542002)
		(width 0.254)
		(layer "F.Cu")
		(net "GND")
	)
	(segment
		(start 381.167894 -289.209988)
		(end 381.634746 -289.475926)
		(width 0.350012)
		(layer "F.Cu")
		(net "GND")
	)
	(segment
		(start 342.245442 -399.663158)
		(end 342.545416 -399.143474)
		(width 0.254)
		(layer "F.Cu")
		(net "GND")
	)
	(segment
		(start 350.31807 -232.599992)
		(end 349.851218 -232.334054)
		(width 0.350012)
		(layer "F.Cu")
		(net "GND")
	)
	(segment
		(start 394.327888 -290.83)
		(end 394.982954 -290.83)
		(width 0.350012)
		(layer "F.Cu")
		(net "GND")
	)
	(segment
		(start 391.890504 -402.462746)
		(end 392.081258 -402.6535)
		(width 0.254)
		(layer "F.Cu")
		(net "GND")
	)
	(segment
		(start 88.645746 -391.281158)
		(end 88.744298 -391.37971)
		(width 0.254)
		(layer "F.Cu")
		(net "GND")
	)
	(segment
		(start 353.907852 -279.49017)
		(end 353.441 -279.756108)
		(width 0.350012)
		(layer "F.Cu")
		(net "GND")
	)
	(segment
		(start 389.683752 -394.831062)
		(end 389.170672 -395.0208)
		(width 0.254)
		(layer "F.Cu")
		(net "GND")
	)
	(segment
		(start 345.618054 -240.700052)
		(end 345.151202 -240.434114)
		(width 0.350012)
		(layer "F.Cu")
		(net "GND")
	)
	(segment
		(start 47.784004 -296.785284)
		(end 49.168304 -296.785284)
		(width 0.4572)
		(layer "F.Cu")
		(net "GND")
	)
	(segment
		(start 130.417824 -383.402586)
		(end 130.417824 -382.951482)
		(width 0.254)
		(layer "F.Cu")
		(net "GND")
	)
	(segment
		(start 387.448044 -251.23013)
		(end 387.914896 -250.964192)
		(width 0.350012)
		(layer "F.Cu")
		(net "GND")
	)
	(segment
		(start 369.970558 -396.46352)
		(end 369.72113 -396.214092)
		(width 0.254)
		(layer "F.Cu")
		(net "GND")
	)
	(segment
		(start 411.49016 -392.999722)
		(end 410.89834 -392.999722)
		(width 0.254)
		(layer "F.Cu")
		(net "GND")
	)
	(segment
		(start 373.17807 -280.300176)
		(end 373.644922 -280.566114)
		(width 0.350012)
		(layer "F.Cu")
		(net "GND")
	)
	(segment
		(start 345.618054 -235.840016)
		(end 345.151202 -235.574078)
		(width 0.350012)
		(layer "F.Cu")
		(net "GND")
	)
	(segment
		(start 347.968062 -228.550216)
		(end 347.50121 -228.284278)
		(width 0.350012)
		(layer "F.Cu")
		(net "GND")
	)
	(segment
		(start 27.547062 -9.423654)
		(end 27.548332 -9.424924)
		(width 0.3556)
		(layer "F.Cu")
		(net "GND")
	)
	(segment
		(start 373.5705 -392.999722)
		(end 372.962424 -392.999722)
		(width 0.254)
		(layer "F.Cu")
		(net "GND")
	)
	(segment
		(start 306.117752 -391.333482)
		(end 306.216304 -391.23493)
		(width 0.254)
		(layer "F.Cu")
		(net "GND")
	)
	(segment
		(start 331.81798 -294.88003)
		(end 331.351128 -295.145968)
		(width 0.350012)
		(layer "F.Cu")
		(net "GND")
	)
	(segment
		(start 347.797882 -280.300176)
		(end 347.33103 -280.566114)
		(width 0.350012)
		(layer "F.Cu")
		(net "GND")
	)
	(segment
		(start 175.528732 -33.377632)
		(end 175.553116 -33.353248)
		(width 0.254)
		(layer "F.Cu")
		(net "GND")
	)
	(segment
		(start 104.55783 -270.580358)
		(end 104.090978 -270.846296)
		(width 0.350012)
		(layer "F.Cu")
		(net "GND")
	)
	(segment
		(start 178.69408 -30.33776)
		(end 178.69408 -31.013908)
		(width 0.254)
		(layer "F.Cu")
		(net "GND")
	)
	(segment
		(start 79.045816 -383.402586)
		(end 79.045816 -382.958086)
		(width 0.254)
		(layer "F.Cu")
		(net "GND")
	)
	(segment
		(start 232.000044 -55.16499)
		(end 230.96728 -55.16499)
		(width 0.381)
		(layer "F.Cu")
		(net "GND")
	)
	(segment
		(start 303.748948 -15.62481)
		(end 303.748948 -14.50721)
		(width 0.508)
		(layer "F.Cu")
		(net "GND")
	)
	(segment
		(start 370.527834 -254.470154)
		(end 370.994686 -254.204216)
		(width 0.350012)
		(layer "F.Cu")
		(net "GND")
	)
	(segment
		(start 120.707912 -246.370348)
		(end 121.174764 -246.10441)
		(width 0.350012)
		(layer "F.Cu")
		(net "GND")
	)
	(segment
		(start 168.527984 -284.035246)
		(end 167.143684 -284.035246)
		(width 0.4572)
		(layer "F.Cu")
		(net "GND")
	)
	(segment
		(start 347.989906 -392.999722)
		(end 348.597982 -392.999722)
		(width 0.254)
		(layer "F.Cu")
		(net "GND")
	)
	(segment
		(start 112.717834 -234.220258)
		(end 113.184686 -233.95432)
		(width 0.350012)
		(layer "F.Cu")
		(net "GND")
	)
	(segment
		(start 61.270642 -388.138924)
		(end 61.918596 -388.328662)
		(width 0.254)
		(layer "F.Cu")
		(net "GND")
	)
	(segment
		(start 89.047828 -295.69029)
		(end 88.580976 -295.956228)
		(width 0.350012)
		(layer "F.Cu")
		(net "GND")
	)
	(segment
		(start 404.644352 -400.212814)
		(end 404.644352 -399.76171)
		(width 0.254)
		(layer "F.Cu")
		(net "GND")
	)
	(segment
		(start 350.998028 -398.542002)
		(end 350.318832 -398.542002)
		(width 0.254)
		(layer "F.Cu")
		(net "GND")
	)
	(segment
		(start 382.748028 -254.470154)
		(end 383.21488 -254.204216)
		(width 0.350012)
		(layer "F.Cu")
		(net "GND")
	)
	(segment
		(start 355.957886 -234.220004)
		(end 355.491034 -233.954066)
		(width 0.350012)
		(layer "F.Cu")
		(net "GND")
	)
	(segment
		(start 435.000146 -228.785166)
		(end 436.384446 -228.785166)
		(width 0.4572)
		(layer "F.Cu")
		(net "GND")
	)
	(segment
		(start 339.943948 -399.76171)
		(end 339.845396 -399.663158)
		(width 0.254)
		(layer "F.Cu")
		(net "GND")
	)
	(segment
		(start 75.936094 -336.81797)
		(end 75.68311 -337.070954)
		(width 0.2286)
		(layer "F.Cu")
		(net "GND")
	)
	(segment
		(start 163.819078 -390.160002)
		(end 163.298378 -390.160002)
		(width 0.254)
		(layer "F.Cu")
		(net "GND")
	)
	(segment
		(start 340.277958 -278.680164)
		(end 339.811106 -278.946102)
		(width 0.350012)
		(layer "F.Cu")
		(net "GND")
	)
	(segment
		(start 412.94558 -392.004042)
		(end 412.94558 -391.784586)
		(width 0.254)
		(layer "F.Cu")
		(net "GND")
	)
	(segment
		(start 371.767862 -261.670038)
		(end 372.234714 -261.935976)
		(width 0.350012)
		(layer "F.Cu")
		(net "GND")
	)
	(segment
		(start 328.527918 -271.39011)
		(end 328.061066 -271.656048)
		(width 0.350012)
		(layer "F.Cu")
		(net "GND")
	)
	(segment
		(start 303.462182 -392.999722)
		(end 304.070258 -392.999722)
		(width 0.254)
		(layer "F.Cu")
		(net "GND")
	)
	(segment
		(start 328.058018 -293.260018)
		(end 327.591166 -293.525956)
		(width 0.350012)
		(layer "F.Cu")
		(net "GND")
	)
	(segment
		(start 377.577858 -253.660148)
		(end 378.04471 -253.39421)
		(width 0.350012)
		(layer "F.Cu")
		(net "GND")
	)
	(segment
		(start 178.72202 -107.452922)
		(end 178.33213 -107.063032)
		(width 0.254)
		(layer "F.Cu")
		(net "GND")
	)
	(segment
		(start 439.100214 -218.585034)
		(end 437.715914 -218.585034)
		(width 0.4572)
		(layer "F.Cu")
		(net "GND")
	)
	(segment
		(start 358.778048 -226.120198)
		(end 358.311196 -225.85426)
		(width 0.350012)
		(layer "F.Cu")
		(net "GND")
	)
	(segment
		(start 333.39786 -229.360222)
		(end 332.931008 -229.094284)
		(width 0.350012)
		(layer "F.Cu")
		(net "GND")
	)
	(segment
		(start 50.84953 -351.978722)
		(end 50.481738 -351.978722)
		(width 0.381)
		(layer "F.Cu")
		(net "GND")
	)
	(segment
		(start 360.657902 -226.120198)
		(end 361.124754 -225.85426)
		(width 0.350012)
		(layer "F.Cu")
		(net "GND")
	)
	(segment
		(start 143.267938 -256.09042)
		(end 143.73479 -255.824482)
		(width 0.350012)
		(layer "F.Cu")
		(net "GND")
	)
	(segment
		(start 357.36784 -238.270034)
		(end 356.901242 -238.004096)
		(width 0.350012)
		(layer "F.Cu")
		(net "GND")
	)
	(segment
		(start 367.395506 -175.412908)
		(end 367.395506 -175.693324)
		(width 0.2286)
		(layer "F.Cu")
		(net "GND")
	)
	(segment
		(start 412.367984 -278.085042)
		(end 413.752284 -278.085042)
		(width 0.4572)
		(layer "F.Cu")
		(net "GND")
	)
	(segment
		(start 369.2017 -396.51305)
		(end 368.89309 -396.74673)
		(width 0.254)
		(layer "F.Cu")
		(net "GND")
	)
	(segment
		(start 83.845654 -383.622042)
		(end 84.145882 -383.92227)
		(width 0.2032)
		(layer "F.Cu")
		(net "GND")
	)
	(segment
		(start 50.216562 -394.733018)
		(end 50.216562 -393.927838)
		(width 0.381)
		(layer "F.Cu")
		(net "GND")
	)
	(segment
		(start 352.197924 -235.840016)
		(end 351.731072 -235.574078)
		(width 0.350012)
		(layer "F.Cu")
		(net "GND")
	)
	(segment
		(start 115.367816 -281.110436)
		(end 115.834668 -281.376374)
		(width 0.350012)
		(layer "F.Cu")
		(net "GND")
	)
	(segment
		(start 108.787946 -290.830254)
		(end 108.321094 -291.096192)
		(width 0.350012)
		(layer "F.Cu")
		(net "GND")
	)
	(segment
		(start 29.252164 -314.635388)
		(end 27.867864 -314.635388)
		(width 0.4572)
		(layer "F.Cu")
		(net "GND")
	)
	(segment
		(start 311.91835 -396.710662)
		(end 312.470292 -396.520924)
		(width 0.254)
		(layer "F.Cu")
		(net "GND")
	)
	(segment
		(start 65.81648 -391.37971)
		(end 65.717928 -391.281158)
		(width 0.254)
		(layer "F.Cu")
		(net "GND")
	)
	(segment
		(start 385.217924 -391.784586)
		(end 385.217924 -392.004296)
		(width 0.254)
		(layer "F.Cu")
		(net "GND")
	)
	(segment
		(start 338.097876 -224.500186)
		(end 337.631024 -224.234248)
		(width 0.350012)
		(layer "F.Cu")
		(net "GND")
	)
	(segment
		(start 367.492026 -175.17999)
		(end 367.395506 -175.412908)
		(width 0.2286)
		(layer "F.Cu")
		(net "GND")
	)
	(segment
		(start 399.171668 -393.97559)
		(end 399.160238 -393.96416)
		(width 0.254)
		(layer "F.Cu")
		(net "GND")
	)
	(segment
		(start 127.287782 -223.690434)
		(end 127.754634 -223.424496)
		(width 0.350012)
		(layer "F.Cu")
		(net "GND")
	)
	(segment
		(start 81.798414 -386.6388)
		(end 81.106264 -386.449062)
		(width 0.254)
		(layer "F.Cu")
		(net "GND")
	)
	(segment
		(start 41.534842 -349.786448)
		(end 42.105326 -349.215964)
		(width 0.2286)
		(layer "F.Cu")
		(net "GND")
	)
	(segment
		(start 382.748028 -251.23013)
		(end 383.21488 -250.964192)
		(width 0.350012)
		(layer "F.Cu")
		(net "GND")
	)
	(segment
		(start 101.737922 -285.160466)
		(end 101.27107 -285.426404)
		(width 0.350012)
		(layer "F.Cu")
		(net "GND")
	)
	(segment
		(start 152.498298 -388.138924)
		(end 151.946102 -388.328662)
		(width 0.254)
		(layer "F.Cu")
		(net "GND")
	)
	(segment
		(start 133.934454 -384.531108)
		(end 133.714744 -384.531108)
		(width 0.254)
		(layer "F.Cu")
		(net "GND")
	)
	(segment
		(start 389.627872 -269.770098)
		(end 390.094724 -270.036036)
		(width 0.350012)
		(layer "F.Cu")
		(net "GND")
	)
	(segment
		(start 69.359526 -147.475194)
		(end 69.359526 -147.82673)
		(width 0.254)
		(layer "F.Cu")
		(net "GND")
	)
	(segment
		(start 319.617852 -392.30427)
		(end 319.317624 -392.004042)
		(width 0.254)
		(layer "F.Cu")
		(net "GND")
	)
	(segment
		(start 32.945832 -7.215886)
		(end 32.947102 -7.217156)
		(width 0.3556)
		(layer "F.Cu")
		(net "GND")
	)
	(segment
		(start 420.156894 -9.423654)
		(end 420.158164 -9.424924)
		(width 0.3556)
		(layer "F.Cu")
		(net "GND")
	)
	(segment
		(start 25.152096 -238.135414)
		(end 26.536396 -238.135414)
		(width 0.4572)
		(layer "F.Cu")
		(net "GND")
	)
	(segment
		(start 97.677986 -240.700306)
		(end 97.211134 -240.434368)
		(width 0.350012)
		(layer "F.Cu")
		(net "GND")
	)
	(segment
		(start 144.677892 -237.460282)
		(end 145.144744 -237.194344)
		(width 0.350012)
		(layer "F.Cu")
		(net "GND")
	)
	(segment
		(start 228.218746 -291.011102)
		(end 228.481128 -291.011102)
		(width 0.4572)
		(layer "F.Cu")
		(net "GND")
	)
	(segment
		(start 180.824378 -153.232612)
		(end 181.619398 -153.232612)
		(width 0.4572)
		(layer "F.Cu")
		(net "GND")
	)
	(segment
		(start 372.407942 -254.470154)
		(end 372.874794 -254.204216)
		(width 0.350012)
		(layer "F.Cu")
		(net "GND")
	)
	(segment
		(start 133.398006 -255.280414)
		(end 133.864858 -255.014476)
		(width 0.350012)
		(layer "F.Cu")
		(net "GND")
	)
	(segment
		(start 136.687814 -236.650276)
		(end 137.154666 -236.384338)
		(width 0.350012)
		(layer "F.Cu")
		(net "GND")
	)
	(segment
		(start 115.83797 -285.160466)
		(end 116.304822 -285.426404)
		(width 0.350012)
		(layer "F.Cu")
		(net "GND")
	)
	(segment
		(start 335.148682 -398.946624)
		(end 335.345532 -399.143474)
		(width 0.254)
		(layer "F.Cu")
		(net "GND")
	)
	(segment
		(start 381.62992 -295.95318)
		(end 381.638048 -295.983406)
		(width 0.350012)
		(layer "F.Cu")
		(net "GND")
	)
	(segment
		(start 105.13695 -419.989)
		(end 104.521 -419.989)
		(width 0.381)
		(layer "F.Cu")
		(net "GND")
	)
	(segment
		(start 90.790268 -384.617722)
		(end 91.398344 -384.617722)
		(width 0.254)
		(layer "F.Cu")
		(net "GND")
	)
	(segment
		(start 381.638048 -283.5402)
		(end 382.1049 -283.806138)
		(width 0.350012)
		(layer "F.Cu")
		(net "GND")
	)
	(segment
		(start 369.417854 -270.580104)
		(end 369.884706 -270.846042)
		(width 0.350012)
		(layer "F.Cu")
		(net "GND")
	)
	(segment
		(start 110.284514 -176.346866)
		(end 109.856016 -176.346866)
		(width 0.2286)
		(layer "F.Cu")
		(net "GND")
	)
	(segment
		(start 97.207832 -226.930458)
		(end 96.74098 -226.66452)
		(width 0.350012)
		(layer "F.Cu")
		(net "GND")
	)
	(segment
		(start 337.45805 -268.960092)
		(end 336.991198 -269.22603)
		(width 0.350012)
		(layer "F.Cu")
		(net "GND")
	)
	(segment
		(start 342.327992 -223.69018)
		(end 341.86114 -223.424242)
		(width 0.350012)
		(layer "F.Cu")
		(net "GND")
	)
	(segment
		(start 355.957886 -229.360222)
		(end 355.491034 -229.094284)
		(width 0.350012)
		(layer "F.Cu")
		(net "GND")
	)
	(segment
		(start 384.457956 -267.34008)
		(end 384.924808 -267.606018)
		(width 0.350012)
		(layer "F.Cu")
		(net "GND")
	)
	(segment
		(start 352.197924 -232.599992)
		(end 351.731072 -232.334054)
		(width 0.350012)
		(layer "F.Cu")
		(net "GND")
	)
	(segment
		(start 88.998298 -384.617722)
		(end 88.94572 -383.92227)
		(width 0.254)
		(layer "F.Cu")
		(net "GND")
	)
	(segment
		(start 20.345654 -7.215886)
		(end 20.346924 -7.217156)
		(width 0.3556)
		(layer "F.Cu")
		(net "GND")
	)
	(segment
		(start 387.970522 -392.999722)
		(end 387.362446 -392.999722)
		(width 0.254)
		(layer "F.Cu")
		(net "GND")
	)
	(segment
		(start 442.5442 -284.88513)
		(end 443.9285 -284.88513)
		(width 0.4572)
		(layer "F.Cu")
		(net "GND")
	)
	(segment
		(start 365.657892 -281.920188)
		(end 366.124744 -282.186126)
		(width 0.350012)
		(layer "F.Cu")
		(net "GND")
	)
	(segment
		(start 110.49635 -172.91431)
		(end 110.77702 -173.19498)
		(width 0.3048)
		(layer "F.Cu")
		(net "GND")
	)
	(segment
		(start 66.017902 -390.761474)
		(end 66.070734 -390.160002)
		(width 0.254)
		(layer "F.Cu")
		(net "GND")
	)
	(segment
		(start 58.518044 -383.402586)
		(end 58.518044 -383.622296)
		(width 0.254)
		(layer "F.Cu")
		(net "GND")
	)
	(segment
		(start 353.137978 -242.320064)
		(end 352.671126 -242.054126)
		(width 0.350012)
		(layer "F.Cu")
		(net "GND")
	)
	(segment
		(start 129.467864 -295.69029)
		(end 129.934716 -295.956228)
		(width 0.350012)
		(layer "F.Cu")
		(net "GND")
	)
	(segment
		(start 37.61105 -364.109)
		(end 38.3286 -364.109)
		(width 0.381)
		(layer "F.Cu")
		(net "GND")
	)
	(segment
		(start 25.152096 -203.285344)
		(end 26.536396 -203.285344)
		(width 0.4572)
		(layer "F.Cu")
		(net "GND")
	)
	(segment
		(start 335.148682 -393.81303)
		(end 335.148682 -393.24915)
		(width 0.254)
		(layer "F.Cu")
		(net "GND")
	)
	(segment
		(start 205.089506 -340.553548)
		(end 205.089506 -339.428836)
		(width 0.4572)
		(layer "F.Cu")
		(net "GND")
	)
	(segment
		(start 302.101504 -395.313154)
		(end 302.401478 -395.613128)
		(width 0.254)
		(layer "F.Cu")
		(net "GND")
	)
	(segment
		(start 386.770626 -392.999722)
		(end 387.362446 -392.999722)
		(width 0.254)
		(layer "F.Cu")
		(net "GND")
	)
	(segment
		(start 384.927856 -284.350206)
		(end 385.394708 -284.616144)
		(width 0.350012)
		(layer "F.Cu")
		(net "GND")
	)
	(segment
		(start 118.657878 -275.440394)
		(end 119.12473 -275.706332)
		(width 0.350012)
		(layer "F.Cu")
		(net "GND")
	)
	(segment
		(start 306.262532 -411.295596)
		(end 306.262532 -411.815534)
		(width 0.381)
		(layer "F.Cu")
		(net "GND")
	)
	(segment
		(start 198.7042 -230.485442)
		(end 197.3199 -230.485442)
		(width 0.4572)
		(layer "F.Cu")
		(net "GND")
	)
	(segment
		(start 63.062358 -384.617722)
		(end 63.670688 -384.617722)
		(width 0.254)
		(layer "F.Cu")
		(net "GND")
	)
	(segment
		(start 85.757766 -283.540454)
		(end 85.290914 -283.806392)
		(width 0.350012)
		(layer "F.Cu")
		(net "GND")
	)
	(segment
		(start 176.072038 -286.585406)
		(end 174.687738 -286.585406)
		(width 0.4572)
		(layer "F.Cu")
		(net "GND")
	)
	(segment
		(start 96.737932 -255.280414)
		(end 96.27108 -255.014476)
		(width 0.350012)
		(layer "F.Cu")
		(net "GND")
	)
	(segment
		(start 367.124488 -13.444982)
		(end 366.244378 -13.444982)
		(width 0.4572)
		(layer "F.Cu")
		(net "GND")
	)
	(segment
		(start 264.878566 -132.352796)
		(end 265.494516 -132.352796)
		(width 0.381)
		(layer "F.Cu")
		(net "GND")
	)
	(segment
		(start 345.447874 -282.730194)
		(end 344.981022 -282.996132)
		(width 0.350012)
		(layer "F.Cu")
		(net "GND")
	)
	(segment
		(start 368.64798 -231.789986)
		(end 369.114832 -231.524048)
		(width 0.350012)
		(layer "F.Cu")
		(net "GND")
	)
	(segment
		(start 372.238016 -267.34008)
		(end 372.704868 -267.606018)
		(width 0.350012)
		(layer "F.Cu")
		(net "GND")
	)
	(segment
		(start 185.122058 -107.452922)
		(end 184.732168 -107.063032)
		(width 0.254)
		(layer "F.Cu")
		(net "GND")
	)
	(segment
		(start 100.027994 -247.99036)
		(end 99.561142 -247.724422)
		(width 0.350012)
		(layer "F.Cu")
		(net "GND")
	)
	(segment
		(start 92.33789 -272.20037)
		(end 91.871038 -272.466308)
		(width 0.350012)
		(layer "F.Cu")
		(net "GND")
	)
	(segment
		(start 89.845642 -382.951482)
		(end 89.944194 -382.85293)
		(width 0.254)
		(layer "F.Cu")
		(net "GND")
	)
	(segment
		(start 345.50604 -394.831062)
		(end 344.99804 -395.0208)
		(width 0.254)
		(layer "F.Cu")
		(net "GND")
	)
	(segment
		(start 194.38239 -70.198996)
		(end 194.657726 -69.92366)
		(width 0.254)
		(layer "F.Cu")
		(net "GND")
	)
	(segment
		(start 359.1941 -166.922196)
		(end 359.115106 -167.11295)
		(width 0.2286)
		(layer "F.Cu")
		(net "GND")
	)
	(segment
		(start 90.627962 -246.370348)
		(end 90.16111 -246.10441)
		(width 0.350012)
		(layer "F.Cu")
		(net "GND")
	)
	(segment
		(start 123.997974 -247.180354)
		(end 124.464826 -246.914416)
		(width 0.350012)
		(layer "F.Cu")
		(net "GND")
	)
	(segment
		(start 189.262004 -13.599922)
		(end 189.262004 -12.4968)
		(width 0.3556)
		(layer "F.Cu")
		(net "GND")
	)
	(segment
		(start 110.584996 -398.729962)
		(end 110.584996 -399.736056)
		(width 0.3048)
		(layer "F.Cu")
		(net "GND")
	)
	(segment
		(start 107.547918 -222.070422)
		(end 107.081066 -221.804484)
		(width 0.350012)
		(layer "F.Cu")
		(net "GND")
	)
	(segment
		(start 42.057066 -7.217156)
		(end 42.057066 -8.320024)
		(width 0.3556)
		(layer "F.Cu")
		(net "GND")
	)
	(segment
		(start 353.398074 -392.999722)
		(end 352.789998 -392.999722)
		(width 0.254)
		(layer "F.Cu")
		(net "GND")
	)
	(segment
		(start 341.045546 -392.004296)
		(end 341.34552 -392.30427)
		(width 0.2032)
		(layer "F.Cu")
		(net "GND")
	)
	(segment
		(start 370.828062 -263.29005)
		(end 371.294914 -263.555988)
		(width 0.350012)
		(layer "F.Cu")
		(net "GND")
	)
	(segment
		(start 87.167974 -285.970472)
		(end 86.701122 -286.23641)
		(width 0.350012)
		(layer "F.Cu")
		(net "GND")
	)
	(segment
		(start 164.427916 -296.785284)
		(end 165.812216 -296.785284)
		(width 0.4572)
		(layer "F.Cu")
		(net "GND")
	)
	(segment
		(start 100.497894 -240.700306)
		(end 100.031042 -240.434368)
		(width 0.350012)
		(layer "F.Cu")
		(net "GND")
	)
	(segment
		(start 379.457966 -239.08004)
		(end 379.924818 -238.814102)
		(width 0.350012)
		(layer "F.Cu")
		(net "GND")
	)
	(segment
		(start 329.17384 -411.137608)
		(end 329.17384 -411.14091)
		(width 0.381)
		(layer "F.Cu")
		(net "GND")
	)
	(segment
		(start 341.387938 -256.090166)
		(end 340.921086 -255.824228)
		(width 0.350012)
		(layer "F.Cu")
		(net "GND")
	)
	(segment
		(start 303.268126 -221.985078)
		(end 304.652426 -221.985078)
		(width 0.4572)
		(layer "F.Cu")
		(net "GND")
	)
	(segment
		(start 380.86792 -235.03001)
		(end 381.334772 -234.764072)
		(width 0.350012)
		(layer "F.Cu")
		(net "GND")
	)
	(segment
		(start 179.194206 -30.763972)
		(end 179.194206 -30.33776)
		(width 0.254)
		(layer "F.Cu")
		(net "GND")
	)
	(segment
		(start 363.00791 -235.03001)
		(end 363.474762 -234.764072)
		(width 0.350012)
		(layer "F.Cu")
		(net "GND")
	)
	(segment
		(start 151.298402 -386.6388)
		(end 150.606252 -386.449062)
		(width 0.254)
		(layer "F.Cu")
		(net "GND")
	)
	(segment
		(start 76.0603 -384.66268)
		(end 76.5937 -384.66268)
		(width 0.254)
		(layer "F.Cu")
		(net "GND")
	)
	(segment
		(start 202.147932 -228.78542)
		(end 203.532232 -228.78542)
		(width 0.4572)
		(layer "F.Cu")
		(net "GND")
	)
	(segment
		(start 11.590782 -405.211534)
		(end 11.590782 -404.490174)
		(width 0.4572)
		(layer "F.Cu")
		(net "GND")
	)
	(segment
		(start 374.11787 -293.260018)
		(end 374.584722 -293.525956)
		(width 0.350012)
		(layer "F.Cu")
		(net "GND")
	)
	(segment
		(start 119.597932 -270.580358)
		(end 120.064784 -270.846296)
		(width 0.350012)
		(layer "F.Cu")
		(net "GND")
	)
	(segment
		(start 132.927852 -223.690434)
		(end 133.394704 -223.424496)
		(width 0.350012)
		(layer "F.Cu")
		(net "GND")
	)
	(segment
		(start 154.644344 -391.830814)
		(end 154.644344 -391.37971)
		(width 0.254)
		(layer "F.Cu")
		(net "GND")
	)
	(segment
		(start 342.158066 -288.399982)
		(end 341.691214 -288.66592)
		(width 0.350012)
		(layer "F.Cu")
		(net "GND")
	)
	(segment
		(start 304.01895 -360.426)
		(end 303.53 -360.426)
		(width 0.381)
		(layer "F.Cu")
		(net "GND")
	)
	(segment
		(start 350.998028 -392.999722)
		(end 350.94545 -392.30427)
		(width 0.254)
		(layer "F.Cu")
		(net "GND")
	)
	(segment
		(start 95.627952 -277.870412)
		(end 95.1611 -278.13635)
		(width 0.350012)
		(layer "F.Cu")
		(net "GND")
	)
	(segment
		(start 122.018044 -391.281158)
		(end 122.318018 -390.761474)
		(width 0.254)
		(layer "F.Cu")
		(net "GND")
	)
	(segment
		(start 337.798156 -395.0208)
		(end 337.106006 -394.831062)
		(width 0.254)
		(layer "F.Cu")
		(net "GND")
	)
	(segment
		(start 21.70811 -237.285276)
		(end 20.32381 -237.285276)
		(width 0.4572)
		(layer "F.Cu")
		(net "GND")
	)
	(segment
		(start 340.747858 -294.070024)
		(end 340.281006 -294.335962)
		(width 0.350012)
		(layer "F.Cu")
		(net "GND")
	)
	(segment
		(start 56.117998 -382.951482)
		(end 56.21655 -382.85293)
		(width 0.254)
		(layer "F.Cu")
		(net "GND")
	)
	(segment
		(start 378.347986 -261.670038)
		(end 378.814838 -261.935976)
		(width 0.350012)
		(layer "F.Cu")
		(net "GND")
	)
	(segment
		(start 406.098248 -392.999722)
		(end 406.04567 -392.30427)
		(width 0.254)
		(layer "F.Cu")
		(net "GND")
	)
	(segment
		(start 51.317906 -391.281158)
		(end 51.416458 -391.37971)
		(width 0.254)
		(layer "F.Cu")
		(net "GND")
	)
	(segment
		(start 400.24685 -9.423654)
		(end 400.24812 -9.424924)
		(width 0.3556)
		(layer "F.Cu")
		(net "GND")
	)
	(segment
		(start 376.35815 -179.678584)
		(end 376.327162 -179.678584)
		(width 0.2286)
		(layer "F.Cu")
		(net "GND")
	)
	(segment
		(start 108.787946 -271.390364)
		(end 108.321094 -271.656302)
		(width 0.350012)
		(layer "F.Cu")
		(net "GND")
	)
	(segment
		(start 122.887994 -268.15034)
		(end 123.354846 -268.416278)
		(width 0.350012)
		(layer "F.Cu")
		(net "GND")
	)
	(segment
		(start 44.340018 -293.38524)
		(end 42.955718 -293.38524)
		(width 0.4572)
		(layer "F.Cu")
		(net "GND")
	)
	(segment
		(start 357.684832 -412.030418)
		(end 357.684832 -411.81147)
		(width 0.381)
		(layer "F.Cu")
		(net "GND")
	)
	(segment
		(start 56.15305 -40.40505)
		(end 56.388 -40.64)
		(width 0.381)
		(layer "F.Cu")
		(net "GND")
	)
	(segment
		(start 97.97796 -277.060406)
		(end 97.511108 -277.326344)
		(width 0.350012)
		(layer "F.Cu")
		(net "GND")
	)
	(segment
		(start 382.618488 -396.710662)
		(end 381.970534 -396.520924)
		(width 0.254)
		(layer "F.Cu")
		(net "GND")
	)
	(segment
		(start 336.687922 -226.930204)
		(end 336.22107 -226.664266)
		(width 0.350012)
		(layer "F.Cu")
		(net "GND")
	)
	(segment
		(start 108.317792 -277.060406)
		(end 107.85094 -277.326344)
		(width 0.350012)
		(layer "F.Cu")
		(net "GND")
	)
	(segment
		(start 133.227826 -284.35046)
		(end 133.694678 -284.616398)
		(width 0.350012)
		(layer "F.Cu")
		(net "GND")
	)
	(segment
		(start 83.877912 -285.160466)
		(end 83.41106 -285.426404)
		(width 0.350012)
		(layer "F.Cu")
		(net "GND")
	)
	(segment
		(start 379.457966 -232.599992)
		(end 379.924818 -232.334054)
		(width 0.350012)
		(layer "F.Cu")
		(net "GND")
	)
	(segment
		(start 208.683352 -123.569984)
		(end 207.813148 -123.569984)
		(width 0.3556)
		(layer "F.Cu")
		(net "GND")
	)
	(segment
		(start 112.97666 -399.143728)
		(end 112.769904 -399.642584)
		(width 0.3302)
		(layer "F.Cu")
		(net "GND")
	)
	(segment
		(start 105.497884 -277.060406)
		(end 105.031032 -277.326344)
		(width 0.350012)
		(layer "F.Cu")
		(net "GND")
	)
	(segment
		(start 126.817882 -239.080294)
		(end 127.284734 -238.814356)
		(width 0.350012)
		(layer "F.Cu")
		(net "GND")
	)
	(segment
		(start 439.100214 -211.784946)
		(end 437.715914 -211.784946)
		(width 0.4572)
		(layer "F.Cu")
		(net "GND")
	)
	(segment
		(start 437.515 -94.833948)
		(end 437.515 -94.471998)
		(width 0.3556)
		(layer "F.Cu")
		(net "GND")
	)
	(segment
		(start 330.108052 -254.470154)
		(end 329.6412 -254.204216)
		(width 0.350012)
		(layer "F.Cu")
		(net "GND")
	)
	(segment
		(start 445.252602 -417.77666)
		(end 445.252602 -417.44011)
		(width 0.381)
		(layer "F.Cu")
		(net "GND")
	)
	(segment
		(start 390.737852 -229.360222)
		(end 391.204704 -229.094284)
		(width 0.350012)
		(layer "F.Cu")
		(net "GND")
	)
	(segment
		(start 110.6678 -279.490424)
		(end 110.200948 -279.756362)
		(width 0.350012)
		(layer "F.Cu")
		(net "GND")
	)
	(segment
		(start 123.997974 -235.84027)
		(end 124.464826 -235.574332)
		(width 0.350012)
		(layer "F.Cu")
		(net "GND")
	)
	(segment
		(start 143.098012 -286.780478)
		(end 143.56461 -287.046162)
		(width 0.350012)
		(layer "F.Cu")
		(net "GND")
	)
	(segment
		(start 118.770654 -388.138924)
		(end 118.218458 -388.328662)
		(width 0.254)
		(layer "F.Cu")
		(net "GND")
	)
	(segment
		(start 87.44585 -383.402586)
		(end 87.44585 -382.951482)
		(width 0.254)
		(layer "F.Cu")
		(net "GND")
	)
	(segment
		(start 341.857838 -226.120198)
		(end 341.390986 -225.85426)
		(width 0.350012)
		(layer "F.Cu")
		(net "GND")
	)
	(segment
		(start 114.127788 -244.750336)
		(end 114.59464 -244.484398)
		(width 0.350012)
		(layer "F.Cu")
		(net "GND")
	)
	(segment
		(start 168.394634 -426.470826)
		(end 168.394634 -428.452788)
		(width 0.381)
		(layer "F.Cu")
		(net "GND")
	)
	(segment
		(start 21.581364 -95.510604)
		(end 22.264116 -95.510604)
		(width 0.3556)
		(layer "F.Cu")
		(net "GND")
	)
	(segment
		(start 49.778666 -386.449062)
		(end 49.270666 -386.6388)
		(width 0.254)
		(layer "F.Cu")
		(net "GND")
	)
	(segment
		(start 88.747854 -236.650276)
		(end 88.281002 -236.384338)
		(width 0.350012)
		(layer "F.Cu")
		(net "GND")
	)
	(segment
		(start 179.516024 -240.68532)
		(end 180.900324 -240.68532)
		(width 0.4572)
		(layer "F.Cu")
		(net "GND")
	)
	(segment
		(start 83.577938 -253.660402)
		(end 83.111086 -253.394464)
		(width 0.350012)
		(layer "F.Cu")
		(net "GND")
	)
	(segment
		(start 136.987788 -284.35046)
		(end 137.45464 -284.616398)
		(width 0.350012)
		(layer "F.Cu")
		(net "GND")
	)
	(segment
		(start 84.047838 -225.310446)
		(end 83.580986 -225.044508)
		(width 0.350012)
		(layer "F.Cu")
		(net "GND")
	)
	(segment
		(start 90.157808 -253.660402)
		(end 89.690956 -253.394464)
		(width 0.350012)
		(layer "F.Cu")
		(net "GND")
	)
	(segment
		(start 121.477786 -288.400236)
		(end 121.944638 -288.666174)
		(width 0.350012)
		(layer "F.Cu")
		(net "GND")
	)
	(segment
		(start 19.915124 -407.576528)
		(end 19.915124 -407.471626)
		(width 0.381)
		(layer "F.Cu")
		(net "GND")
	)
	(segment
		(start 31.585662 -418.239448)
		(end 31.585662 -418.849048)
		(width 0.3556)
		(layer "F.Cu")
		(net "GND")
	)
	(segment
		(start 129.938018 -291.64026)
		(end 130.40487 -291.906198)
		(width 0.350012)
		(layer "F.Cu")
		(net "GND")
	)
	(segment
		(start 91.990164 -384.617722)
		(end 91.398344 -384.617722)
		(width 0.254)
		(layer "F.Cu")
		(net "GND")
	)
	(segment
		(start 375.716546 -400.212814)
		(end 375.716546 -399.76171)
		(width 0.254)
		(layer "F.Cu")
		(net "GND")
	)
	(segment
		(start 424.027346 -361.818682)
		(end 424.027346 -360.82859)
		(width 0.3556)
		(layer "F.Cu")
		(net "GND")
	)
	(segment
		(start 454.188068 -227.935028)
		(end 452.803768 -227.935028)
		(width 0.4572)
		(layer "F.Cu")
		(net "GND")
	)
	(segment
		(start 46.101762 -386.931154)
		(end 46.401736 -387.231128)
		(width 0.254)
		(layer "F.Cu")
		(net "GND")
	)
	(segment
		(start 357.837994 -250.420124)
		(end 357.371142 -250.154186)
		(width 0.350012)
		(layer "F.Cu")
		(net "GND")
	)
	(segment
		(start 126.177802 -281.920442)
		(end 126.644654 -282.18638)
		(width 0.350012)
		(layer "F.Cu")
		(net "GND")
	)
	(segment
		(start 90.198448 -388.138924)
		(end 89.646252 -388.328662)
		(width 0.254)
		(layer "F.Cu")
		(net "GND")
	)
	(segment
		(start 33.799526 -349.215964)
		(end 33.799526 -348.79915)
		(width 0.2286)
		(layer "F.Cu")
		(net "GND")
	)
	(segment
		(start 326.495156 -103.058214)
		(end 327.203308 -103.058214)
		(width 0.2286)
		(layer "F.Cu")
		(net "GND")
	)
	(segment
		(start 362.334302 -415.130742)
		(end 362.04906 -415.415984)
		(width 0.381)
		(layer "F.Cu")
		(net "GND")
	)
	(segment
		(start 112.717834 -243.94033)
		(end 113.184686 -243.674392)
		(width 0.350012)
		(layer "F.Cu")
		(net "GND")
	)
	(segment
		(start 80.287876 -238.270288)
		(end 79.821024 -238.00435)
		(width 0.350012)
		(layer "F.Cu")
		(net "GND")
	)
	(segment
		(start 353.907852 -287.59023)
		(end 353.441 -287.856168)
		(width 0.350012)
		(layer "F.Cu")
		(net "GND")
	)
	(segment
		(start 157.29839 -384.617722)
		(end 157.245812 -383.92227)
		(width 0.254)
		(layer "F.Cu")
		(net "GND")
	)
	(segment
		(start 121.007886 -284.35046)
		(end 121.474738 -284.616398)
		(width 0.350012)
		(layer "F.Cu")
		(net "GND")
	)
	(segment
		(start 438.427876 -94.327472)
		(end 439.28792 -94.327472)
		(width 0.3556)
		(layer "F.Cu")
		(net "GND")
	)
	(segment
		(start 336.344006 -399.76171)
		(end 336.344006 -400.212814)
		(width 0.254)
		(layer "F.Cu")
		(net "GND")
	)
	(segment
		(start 236.599984 -49.76495)
		(end 237.616238 -49.76495)
		(width 0.4572)
		(layer "F.Cu")
		(net "GND")
	)
	(segment
		(start 391.208006 -236.650022)
		(end 391.674858 -236.384084)
		(width 0.350012)
		(layer "F.Cu")
		(net "GND")
	)
	(segment
		(start 353.398074 -398.542002)
		(end 353.918774 -398.542002)
		(width 0.254)
		(layer "F.Cu")
		(net "GND")
	)
	(segment
		(start 379.75794 -272.200116)
		(end 380.224792 -272.466054)
		(width 0.350012)
		(layer "F.Cu")
		(net "GND")
	)
	(segment
		(start 382.748028 -228.550216)
		(end 383.21488 -228.284278)
		(width 0.350012)
		(layer "F.Cu")
		(net "GND")
	)
	(segment
		(start 261.201662 -115.631976)
		(end 261.37489 -115.631976)
		(width 0.3556)
		(layer "F.Cu")
		(net "GND")
	)
	(segment
		(start 12.351004 -140.30071)
		(end 12.351004 -139.65809)
		(width 0.381)
		(layer "F.Cu")
		(net "GND")
	)
	(segment
		(start 392.61796 -252.040136)
		(end 393.084812 -251.774198)
		(width 0.350012)
		(layer "F.Cu")
		(net "GND")
	)
	(segment
		(start 273.092164 -294.235124)
		(end 274.476464 -294.235124)
		(width 0.4572)
		(layer "F.Cu")
		(net "GND")
	)
	(segment
		(start 49.218088 -390.761474)
		(end 48.918114 -391.281158)
		(width 0.254)
		(layer "F.Cu")
		(net "GND")
	)
	(segment
		(start 369.11788 -227.74021)
		(end 369.584732 -227.474272)
		(width 0.350012)
		(layer "F.Cu")
		(net "GND")
	)
	(segment
		(start 349.847916 -223.69018)
		(end 349.381064 -223.424242)
		(width 0.350012)
		(layer "F.Cu")
		(net "GND")
	)
	(segment
		(start 330.877926 -268.960092)
		(end 330.411074 -269.22603)
		(width 0.350012)
		(layer "F.Cu")
		(net "GND")
	)
	(segment
		(start 406.945592 -392.004042)
		(end 407.24582 -392.30427)
		(width 0.2032)
		(layer "F.Cu")
		(net "GND")
	)
	(segment
		(start 313.317636 -391.333482)
		(end 313.416188 -391.23493)
		(width 0.254)
		(layer "F.Cu")
		(net "GND")
	)
	(segment
		(start 141.217904 -268.960346)
		(end 141.684756 -269.226284)
		(width 0.350012)
		(layer "F.Cu")
		(net "GND")
	)
	(segment
		(start 332.28788 -261.670038)
		(end 331.821028 -261.935976)
		(width 0.350012)
		(layer "F.Cu")
		(net "GND")
	)
	(segment
		(start 342.158066 -267.34008)
		(end 341.691214 -267.606018)
		(width 0.350012)
		(layer "F.Cu")
		(net "GND")
	)
	(segment
		(start 372.707916 -294.070024)
		(end 373.174768 -294.335962)
		(width 0.350012)
		(layer "F.Cu")
		(net "GND")
	)
	(segment
		(start 379.457966 -248.800112)
		(end 379.924818 -248.534174)
		(width 0.350012)
		(layer "F.Cu")
		(net "GND")
	)
	(segment
		(start 389.627872 -284.350206)
		(end 390.094724 -284.616144)
		(width 0.350012)
		(layer "F.Cu")
		(net "GND")
	)
	(segment
		(start 156.22905 -111.76)
		(end 156.22905 -112.522)
		(width 0.381)
		(layer "F.Cu")
		(net "GND")
	)
	(segment
		(start 57.6707 -384.617722)
		(end 57.06237 -384.617722)
		(width 0.254)
		(layer "F.Cu")
		(net "GND")
	)
	(segment
		(start 384.457956 -262.480044)
		(end 384.924808 -262.745982)
		(width 0.350012)
		(layer "F.Cu")
		(net "GND")
	)
	(segment
		(start 129.74701 -13.599922)
		(end 129.74701 -12.497054)
		(width 0.3556)
		(layer "F.Cu")
		(net "GND")
	)
	(segment
		(start 143.56334 -31.18739)
		(end 143.56334 -31.958026)
		(width 0.254)
		(layer "F.Cu")
		(net "GND")
	)
	(segment
		(start 352.497898 -281.920188)
		(end 352.031046 -282.186126)
		(width 0.350012)
		(layer "F.Cu")
		(net "GND")
	)
	(segment
		(start 33.819338 -351.978722)
		(end 33.5661 -352.23196)
		(width 0.381)
		(layer "F.Cu")
		(net "GND")
	)
	(segment
		(start 392.917934 -264.100056)
		(end 393.384786 -264.365994)
		(width 0.350012)
		(layer "F.Cu")
		(net "GND")
	)
	(segment
		(start 305.270408 -392.999722)
		(end 305.21783 -392.30427)
		(width 0.254)
		(layer "F.Cu")
		(net "GND")
	)
	(segment
		(start 32.695896 -312.935366)
		(end 34.080196 -312.935366)
		(width 0.4572)
		(layer "F.Cu")
		(net "GND")
	)
	(segment
		(start 198.7042 -209.235294)
		(end 197.3199 -209.235294)
		(width 0.4572)
		(layer "F.Cu")
		(net "GND")
	)
	(segment
		(start 164.145722 -382.951482)
		(end 164.244274 -382.85293)
		(width 0.254)
		(layer "F.Cu")
		(net "GND")
	)
	(segment
		(start 132.927852 -238.270288)
		(end 133.394704 -238.00435)
		(width 0.350012)
		(layer "F.Cu")
		(net "GND")
	)
	(segment
		(start 161.419032 -390.160002)
		(end 160.898332 -390.160002)
		(width 0.254)
		(layer "F.Cu")
		(net "GND")
	)
	(segment
		(start 88.747854 -235.030264)
		(end 88.281002 -234.764326)
		(width 0.350012)
		(layer "F.Cu")
		(net "GND")
	)
	(segment
		(start 338.39785 -277.060152)
		(end 337.930998 -277.32609)
		(width 0.350012)
		(layer "F.Cu")
		(net "GND")
	)
	(segment
		(start 405.406352 -394.831062)
		(end 404.898352 -395.0208)
		(width 0.254)
		(layer "F.Cu")
		(net "GND")
	)
	(segment
		(start 330.623418 -141.074902)
		(end 330.910946 -141.36243)
		(width 0.254)
		(layer "F.Cu")
		(net "GND")
	)
	(segment
		(start 75.028552 -339.377274)
		(end 75.028552 -340.00821)
		(width 0.381)
		(layer "F.Cu")
		(net "GND")
	)
	(segment
		(start 380.711456 -34.178748)
		(end 379.866906 -33.334198)
		(width 0.4572)
		(layer "F.Cu")
		(net "GND")
	)
	(segment
		(start 126.817882 -383.622296)
		(end 127.117856 -383.92227)
		(width 0.254)
		(layer "F.Cu")
		(net "GND")
	)
	(segment
		(start 112.717834 -240.700306)
		(end 113.184686 -240.434368)
		(width 0.350012)
		(layer "F.Cu")
		(net "GND")
	)
	(segment
		(start 36.795964 -239.835436)
		(end 35.411664 -239.835436)
		(width 0.4572)
		(layer "F.Cu")
		(net "GND")
	)
	(segment
		(start 446.644268 -239.835182)
		(end 445.259968 -239.835182)
		(width 0.4572)
		(layer "F.Cu")
		(net "GND")
	)
	(segment
		(start 80.58785 -271.390364)
		(end 80.120998 -271.656302)
		(width 0.350012)
		(layer "F.Cu")
		(net "GND")
	)
	(segment
		(start 306.216304 -400.212814)
		(end 306.216304 -399.76171)
		(width 0.254)
		(layer "F.Cu")
		(net "GND")
	)
	(segment
		(start 60.34659 -180.746908)
		(end 60.491624 -180.891942)
		(width 0.381)
		(layer "F.Cu")
		(net "GND")
	)
	(segment
		(start 46.621192 -388.330948)
		(end 46.87062 -388.08152)
		(width 0.254)
		(layer "F.Cu")
		(net "GND")
	)
	(segment
		(start 169.867072 -12.497054)
		(end 169.865802 -12.495784)
		(width 0.3556)
		(layer "F.Cu")
		(net "GND")
	)
	(segment
		(start 139.507976 -256.09042)
		(end 139.974828 -255.824482)
		(width 0.350012)
		(layer "F.Cu")
		(net "GND")
	)
	(segment
		(start 36.795964 -293.38524)
		(end 35.411664 -293.38524)
		(width 0.4572)
		(layer "F.Cu")
		(net "GND")
	)
	(segment
		(start 102.847902 -247.99036)
		(end 102.38105 -247.724422)
		(width 0.350012)
		(layer "F.Cu")
		(net "GND")
	)
	(segment
		(start 328.998072 -272.200116)
		(end 328.53122 -272.466054)
		(width 0.350012)
		(layer "F.Cu")
		(net "GND")
	)
	(segment
		(start 132.927852 -254.470408)
		(end 133.394704 -254.20447)
		(width 0.350012)
		(layer "F.Cu")
		(net "GND")
	)
	(segment
		(start 307.670454 -392.999722)
		(end 307.062124 -392.999722)
		(width 0.254)
		(layer "F.Cu")
		(net "GND")
	)
	(segment
		(start 191.160146 -239.835436)
		(end 189.775846 -239.835436)
		(width 0.4572)
		(layer "F.Cu")
		(net "GND")
	)
	(segment
		(start 158.145734 -383.402586)
		(end 158.145734 -382.951482)
		(width 0.254)
		(layer "F.Cu")
		(net "GND")
	)
	(segment
		(start 358.607868 -284.350206)
		(end 358.141016 -284.616144)
		(width 0.350012)
		(layer "F.Cu")
		(net "GND")
	)
	(segment
		(start 176.072038 -312.085228)
		(end 174.687738 -312.085228)
		(width 0.4572)
		(layer "F.Cu")
		(net "GND")
	)
	(segment
		(start 46.87062 -384.617722)
		(end 47.46244 -384.617722)
		(width 0.254)
		(layer "F.Cu")
		(net "GND")
	)
	(segment
		(start 132.927852 -244.750336)
		(end 133.394704 -244.484398)
		(width 0.350012)
		(layer "F.Cu")
		(net "GND")
	)
	(segment
		(start 335.108042 -284.350206)
		(end 334.64119 -284.616144)
		(width 0.350012)
		(layer "F.Cu")
		(net "GND")
	)
	(segment
		(start 387.748018 -285.970218)
		(end 388.21487 -286.236156)
		(width 0.350012)
		(layer "F.Cu")
		(net "GND")
	)
	(segment
		(start 396.258796 -412.010098)
		(end 396.461234 -412.212536)
		(width 0.381)
		(layer "F.Cu")
		(net "GND")
	)
	(segment
		(start 141.687804 -287.590484)
		(end 142.154656 -287.856422)
		(width 0.350012)
		(layer "F.Cu")
		(net "GND")
	)
	(segment
		(start 416.644328 -400.212814)
		(end 416.644328 -399.76171)
		(width 0.254)
		(layer "F.Cu")
		(net "GND")
	)
	(segment
		(start 325.408036 -249.610118)
		(end 324.75297 -249.610118)
		(width 0.350012)
		(layer "F.Cu")
		(net "GND")
	)
	(segment
		(start 377.691142 -398.542002)
		(end 377.170442 -398.542002)
		(width 0.254)
		(layer "F.Cu")
		(net "GND")
	)
	(segment
		(start 184.222644 -409.128722)
		(end 184.070244 -409.281122)
		(width 0.3556)
		(layer "F.Cu")
		(net "GND")
	)
	(segment
		(start 350.31807 -235.840016)
		(end 349.851218 -235.574078)
		(width 0.350012)
		(layer "F.Cu")
		(net "GND")
	)
	(segment
		(start 420.445692 -399.143474)
		(end 420.49827 -398.542002)
		(width 0.254)
		(layer "F.Cu")
		(net "GND")
	)
	(segment
		(start 113.487962 -276.2504)
		(end 113.954814 -276.516338)
		(width 0.350012)
		(layer "F.Cu")
		(net "GND")
	)
	(segment
		(start 419.597586 -175.938688)
		(end 419.597586 -175.2092)
		(width 0.254)
		(layer "F.Cu")
		(net "GND")
	)
	(segment
		(start 356.42804 -230.169974)
		(end 355.961188 -229.904036)
		(width 0.350012)
		(layer "F.Cu")
		(net "GND")
	)
	(segment
		(start 336.545428 -399.143474)
		(end 336.245454 -399.663158)
		(width 0.254)
		(layer "F.Cu")
		(net "GND")
	)
	(segment
		(start 347.497908 -224.500186)
		(end 347.031056 -224.234248)
		(width 0.350012)
		(layer "F.Cu")
		(net "GND")
	)
	(segment
		(start 420.431468 -353.74072)
		(end 420.562532 -353.42449)
		(width 0.2286)
		(layer "F.Cu")
		(net "GND")
	)
	(segment
		(start 303.268126 -303.585118)
		(end 304.652426 -303.585118)
		(width 0.4572)
		(layer "F.Cu")
		(net "GND")
	)
	(segment
		(start 104.236266 -397.37284)
		(end 104.475026 -397.13408)
		(width 0.3048)
		(layer "F.Cu")
		(net "GND")
	)
	(segment
		(start 82.467958 -269.770352)
		(end 82.001106 -270.03629)
		(width 0.350012)
		(layer "F.Cu")
		(net "GND")
	)
	(segment
		(start 102.847902 -236.650276)
		(end 102.38105 -236.384338)
		(width 0.350012)
		(layer "F.Cu")
		(net "GND")
	)
	(segment
		(start 387.748018 -290.83)
		(end 388.21487 -291.095938)
		(width 0.350012)
		(layer "F.Cu")
		(net "GND")
	)
	(segment
		(start 133.683756 -386.449062)
		(end 133.170676 -386.6388)
		(width 0.254)
		(layer "F.Cu")
		(net "GND")
	)
	(segment
		(start 280.635964 -303.585118)
		(end 282.020264 -303.585118)
		(width 0.4572)
		(layer "F.Cu")
		(net "GND")
	)
	(segment
		(start 136.987788 -274.630388)
		(end 137.45464 -274.896326)
		(width 0.350012)
		(layer "F.Cu")
		(net "GND")
	)
	(segment
		(start 136.076182 -153.465784)
		(end 135.593074 -153.948892)
		(width 0.2286)
		(layer "F.Cu")
		(net "GND")
	)
	(segment
		(start 386.338064 -278.680164)
		(end 386.804916 -278.946102)
		(width 0.350012)
		(layer "F.Cu")
		(net "GND")
	)
	(segment
		(start 335.918556 -398.542002)
		(end 335.918556 -398.613122)
		(width 0.254)
		(layer "F.Cu")
		(net "GND")
	)
	(segment
		(start 379.570488 -395.0208)
		(end 378.878592 -394.831062)
		(width 0.254)
		(layer "F.Cu")
		(net "GND")
	)
	(segment
		(start 390.737852 -250.420124)
		(end 391.204704 -250.154186)
		(width 0.350012)
		(layer "F.Cu")
		(net "GND")
	)
	(segment
		(start 206.248 -199.8853)
		(end 204.8637 -199.8853)
		(width 0.4572)
		(layer "F.Cu")
		(net "GND")
	)
	(segment
		(start 85.398356 -386.6388)
		(end 84.706206 -386.449062)
		(width 0.254)
		(layer "F.Cu")
		(net "GND")
	)
	(segment
		(start 90.927936 -279.490424)
		(end 90.461084 -279.756362)
		(width 0.350012)
		(layer "F.Cu")
		(net "GND")
	)
	(segment
		(start 388.916418 -400.212814)
		(end 388.916418 -399.76171)
		(width 0.254)
		(layer "F.Cu")
		(net "GND")
	)
	(segment
		(start 354.545392 -399.143474)
		(end 354.598224 -398.542002)
		(width 0.254)
		(layer "F.Cu")
		(net "GND")
	)
	(segment
		(start 133.227826 -268.15034)
		(end 133.694678 -268.416278)
		(width 0.350012)
		(layer "F.Cu")
		(net "GND")
	)
	(segment
		(start 71.882 -387.0579)
		(end 72.6948 -387.0579)
		(width 0.254)
		(layer "F.Cu")
		(net "GND")
	)
	(segment
		(start 273.092164 -231.335072)
		(end 274.476464 -231.335072)
		(width 0.4572)
		(layer "F.Cu")
		(net "GND")
	)
	(segment
		(start 59.816492 -391.830814)
		(end 59.816492 -391.37971)
		(width 0.254)
		(layer "F.Cu")
		(net "GND")
	)
	(segment
		(start 86.020656 -178.359562)
		(end 86.020656 -177.71364)
		(width 0.381)
		(layer "F.Cu")
		(net "GND")
	)
	(segment
		(start 398.728692 -171.959524)
		(end 398.140682 -171.959524)
		(width 0.381)
		(layer "F.Cu")
		(net "GND")
	)
	(segment
		(start 236.599984 -55.16499)
		(end 237.616238 -55.16499)
		(width 0.381)
		(layer "F.Cu")
		(net "GND")
	)
	(segment
		(start 81.445862 -383.402586)
		(end 81.445862 -382.951482)
		(width 0.254)
		(layer "F.Cu")
		(net "GND")
	)
	(segment
		(start 384.627882 -256.090166)
		(end 385.094734 -255.824228)
		(width 0.350012)
		(layer "F.Cu")
		(net "GND")
	)
	(segment
		(start 126.647956 -281.110436)
		(end 127.114808 -281.376374)
		(width 0.350012)
		(layer "F.Cu")
		(net "GND")
	)
	(segment
		(start 133.69798 -278.680418)
		(end 134.164832 -278.946356)
		(width 0.350012)
		(layer "F.Cu")
		(net "GND")
	)
	(segment
		(start 110.1979 -291.64026)
		(end 109.731048 -291.906198)
		(width 0.350012)
		(layer "F.Cu")
		(net "GND")
	)
	(segment
		(start 431.29708 -436.086758)
		(end 431.93208 -436.086758)
		(width 0.4318)
		(layer "F.Cu")
		(net "GND")
	)
	(segment
		(start 130.09118 -390.160002)
		(end 129.57048 -390.160002)
		(width 0.254)
		(layer "F.Cu")
		(net "GND")
	)
	(segment
		(start 354.378006 -270.580104)
		(end 353.911154 -270.846042)
		(width 0.350012)
		(layer "F.Cu")
		(net "GND")
	)
	(segment
		(start 347.968062 -252.850142)
		(end 347.50121 -252.584204)
		(width 0.350012)
		(layer "F.Cu")
		(net "GND")
	)
	(segment
		(start 370.997988 -226.120198)
		(end 371.46484 -225.85426)
		(width 0.350012)
		(layer "F.Cu")
		(net "GND")
	)
	(segment
		(start 79.398368 -388.08152)
		(end 79.14894 -387.832092)
		(width 0.254)
		(layer "F.Cu")
		(net "GND")
	)
	(segment
		(start 409.883102 -142.644114)
		(end 409.28036 -142.644114)
		(width 0.381)
		(layer "F.Cu")
		(net "GND")
	)
	(segment
		(start 165.090094 -384.617722)
		(end 164.498274 -384.617722)
		(width 0.254)
		(layer "F.Cu")
		(net "GND")
	)
	(segment
		(start 421.645588 -392.30427)
		(end 421.345614 -391.784586)
		(width 0.254)
		(layer "F.Cu")
		(net "GND")
	)
	(segment
		(start 295.724072 -284.88513)
		(end 297.108372 -284.88513)
		(width 0.4572)
		(layer "F.Cu")
		(net "GND")
	)
	(segment
		(start 317.217806 -399.143474)
		(end 316.917832 -399.663158)
		(width 0.254)
		(layer "F.Cu")
		(net "GND")
	)
	(segment
		(start 378.318014 -399.143474)
		(end 378.370592 -398.542002)
		(width 0.254)
		(layer "F.Cu")
		(net "GND")
	)
	(segment
		(start 420.49827 -392.999722)
		(end 419.890194 -392.999722)
		(width 0.254)
		(layer "F.Cu")
		(net "GND")
	)
	(segment
		(start 338.56803 -238.270034)
		(end 338.101178 -238.004096)
		(width 0.350012)
		(layer "F.Cu")
		(net "GND")
	)
	(segment
		(start 417.745672 -391.333482)
		(end 417.844224 -391.23493)
		(width 0.254)
		(layer "F.Cu")
		(net "GND")
	)
	(segment
		(start 394.84681 -8.320024)
		(end 394.84808 -9.424924)
		(width 0.3556)
		(layer "F.Cu")
		(net "GND")
	)
	(segment
		(start 325.70801 -282.730194)
		(end 325.052944 -282.730194)
		(width 0.350012)
		(layer "F.Cu")
		(net "GND")
	)
	(segment
		(start 353.137978 -245.560088)
		(end 352.671126 -245.29415)
		(width 0.350012)
		(layer "F.Cu")
		(net "GND")
	)
	(segment
		(start 143.267938 -247.99036)
		(end 143.73479 -247.724422)
		(width 0.350012)
		(layer "F.Cu")
		(net "GND")
	)
	(segment
		(start 85.757766 -262.480298)
		(end 85.290914 -262.746236)
		(width 0.350012)
		(layer "F.Cu")
		(net "GND")
	)
	(segment
		(start 406.690068 -392.999722)
		(end 407.298398 -392.999722)
		(width 0.254)
		(layer "F.Cu")
		(net "GND")
	)
	(segment
		(start 400.56054 -175.346106)
		(end 400.893026 -175.01362)
		(width 0.2286)
		(layer "F.Cu")
		(net "GND")
	)
	(segment
		(start 431.36693 -7.217156)
		(end 431.36693 -8.320024)
		(width 0.3556)
		(layer "F.Cu")
		(net "GND")
	)
	(segment
		(start 56.15305 -39.751)
		(end 56.15305 -40.40505)
		(width 0.381)
		(layer "F.Cu")
		(net "GND")
	)
	(segment
		(start 85.045804 -383.402586)
		(end 85.045804 -383.622296)
		(width 0.2032)
		(layer "F.Cu")
		(net "GND")
	)
	(segment
		(start 51.884072 -274.685252)
		(end 50.499772 -274.685252)
		(width 0.4572)
		(layer "F.Cu")
		(net "GND")
	)
	(segment
		(start 90.627962 -236.650276)
		(end 90.16111 -236.384338)
		(width 0.350012)
		(layer "F.Cu")
		(net "GND")
	)
	(segment
		(start 126.647956 -282.730448)
		(end 127.114808 -282.996386)
		(width 0.350012)
		(layer "F.Cu")
		(net "GND")
	)
	(segment
		(start 439.100214 -293.384986)
		(end 437.715914 -293.384986)
		(width 0.4572)
		(layer "F.Cu")
		(net "GND")
	)
	(segment
		(start 348.044262 -155.927806)
		(end 347.974412 -155.997656)
		(width 0.381)
		(layer "F.Cu")
		(net "GND")
	)
	(segment
		(start 88.277954 -250.420378)
		(end 87.811102 -250.15444)
		(width 0.350012)
		(layer "F.Cu")
		(net "GND")
	)
	(segment
		(start 310.662066 -392.999722)
		(end 310.070246 -392.999722)
		(width 0.254)
		(layer "F.Cu")
		(net "GND")
	)
	(segment
		(start 99.857814 -283.540454)
		(end 99.390962 -283.806392)
		(width 0.350012)
		(layer "F.Cu")
		(net "GND")
	)
	(segment
		(start 128.52781 -264.910316)
		(end 128.994662 -265.176254)
		(width 0.350012)
		(layer "F.Cu")
		(net "GND")
	)
	(segment
		(start 134.80796 -249.610372)
		(end 135.274812 -249.344434)
		(width 0.350012)
		(layer "F.Cu")
		(net "GND")
	)
	(segment
		(start 124.937774 -237.460282)
		(end 125.404626 -237.194344)
		(width 0.350012)
		(layer "F.Cu")
		(net "GND")
	)
	(segment
		(start 368.17808 -247.1801)
		(end 368.644678 -246.914162)
		(width 0.350012)
		(layer "F.Cu")
		(net "GND")
	)
	(segment
		(start 442.5442 -238.13516)
		(end 443.9285 -238.13516)
		(width 0.4572)
		(layer "F.Cu")
		(net "GND")
	)
	(segment
		(start 406.618948 -398.542002)
		(end 406.098248 -398.542002)
		(width 0.254)
		(layer "F.Cu")
		(net "GND")
	)
	(segment
		(start 365.657892 -293.260018)
		(end 366.124744 -293.525956)
		(width 0.350012)
		(layer "F.Cu")
		(net "GND")
	)
	(segment
		(start 391.890504 -401.892262)
		(end 391.890504 -402.462746)
		(width 0.254)
		(layer "F.Cu")
		(net "GND")
	)
	(segment
		(start 56.867044 -8.320024)
		(end 56.867044 -9.423654)
		(width 0.3556)
		(layer "F.Cu")
		(net "GND")
	)
	(segment
		(start 391.50798 -284.350206)
		(end 391.974832 -284.616144)
		(width 0.350012)
		(layer "F.Cu")
		(net "GND")
	)
	(segment
		(start 355.78796 -266.530074)
		(end 355.321108 -266.796012)
		(width 0.350012)
		(layer "F.Cu")
		(net "GND")
	)
	(segment
		(start 321.71767 -391.784586)
		(end 321.816222 -391.686034)
		(width 0.254)
		(layer "F.Cu")
		(net "GND")
	)
	(segment
		(start 384.37058 -395.0208)
		(end 383.67843 -394.831062)
		(width 0.254)
		(layer "F.Cu")
		(net "GND")
	)
	(segment
		(start 31.017718 -53.909214)
		(end 32.605218 -53.909214)
		(width 0.4572)
		(layer "F.Cu")
		(net "GND")
	)
	(segment
		(start 44.340018 -274.685252)
		(end 42.955718 -274.685252)
		(width 0.4572)
		(layer "F.Cu")
		(net "GND")
	)
	(segment
		(start 82.167984 -241.510312)
		(end 81.701132 -241.244374)
		(width 0.350012)
		(layer "F.Cu")
		(net "GND")
	)
	(segment
		(start 82.167984 -239.8903)
		(end 81.701132 -239.624362)
		(width 0.350012)
		(layer "F.Cu")
		(net "GND")
	)
	(segment
		(start 146.38782 -277.870412)
		(end 147.042886 -277.870412)
		(width 0.350012)
		(layer "F.Cu")
		(net "GND")
	)
	(segment
		(start 180.225954 -356.553008)
		(end 180.225954 -357.270812)
		(width 0.381)
		(layer "F.Cu")
		(net "GND")
	)
	(segment
		(start 419.230302 -436.564786)
		(end 418.599366 -436.564786)
		(width 0.381)
		(layer "F.Cu")
		(net "GND")
	)
	(segment
		(start 105.66781 -244.750336)
		(end 105.200958 -244.484398)
		(width 0.350012)
		(layer "F.Cu")
		(net "GND")
	)
	(segment
		(start 95.627952 -289.210242)
		(end 95.1611 -289.47618)
		(width 0.350012)
		(layer "F.Cu")
		(net "GND")
	)
	(segment
		(start 376.467878 -269.770098)
		(end 376.93473 -270.036036)
		(width 0.350012)
		(layer "F.Cu")
		(net "GND")
	)
	(segment
		(start 381.338074 -245.560088)
		(end 381.804926 -245.29415)
		(width 0.350012)
		(layer "F.Cu")
		(net "GND")
	)
	(segment
		(start 325.877936 -224.500186)
		(end 325.411084 -224.234248)
		(width 0.350012)
		(layer "F.Cu")
		(net "GND")
	)
	(segment
		(start 78.877922 -224.50044)
		(end 78.41107 -224.234502)
		(width 0.350012)
		(layer "F.Cu")
		(net "GND")
	)
	(segment
		(start 333.39786 -252.040136)
		(end 332.931008 -251.774198)
		(width 0.350012)
		(layer "F.Cu")
		(net "GND")
	)
	(segment
		(start 358.778048 -248.800112)
		(end 358.311196 -248.534174)
		(width 0.350012)
		(layer "F.Cu")
		(net "GND")
	)
	(segment
		(start 392.963146 -320.637154)
		(end 392.953748 -320.627756)
		(width 0.508)
		(layer "F.Cu")
		(net "GND")
	)
	(segment
		(start 136.946894 -13.599922)
		(end 136.946894 -12.496292)
		(width 0.4572)
		(layer "F.Cu")
		(net "GND")
	)
	(segment
		(start 416.555682 -7.215886)
		(end 416.556952 -7.217156)
		(width 0.3556)
		(layer "F.Cu")
		(net "GND")
	)
	(segment
		(start 17.608042 -210.085432)
		(end 18.992342 -210.085432)
		(width 0.4572)
		(layer "F.Cu")
		(net "GND")
	)
	(segment
		(start 127.287782 -222.070422)
		(end 127.287782 -221.517972)
		(width 0.350012)
		(layer "F.Cu")
		(net "GND")
	)
	(segment
		(start 288.27222 -351.100644)
		(end 288.27222 -351.73158)
		(width 0.381)
		(layer "F.Cu")
		(net "GND")
	)
	(segment
		(start 358.778048 -224.500186)
		(end 358.311196 -224.234248)
		(width 0.350012)
		(layer "F.Cu")
		(net "GND")
	)
	(segment
		(start 145.209768 -387.231128)
		(end 145.729452 -386.931154)
		(width 0.254)
		(layer "F.Cu")
		(net "GND")
	)
	(segment
		(start 13.613384 -388.561326)
		(end 13.613384 -389.163814)
		(width 0.2032)
		(layer "F.Cu")
		(net "GND")
	)
	(segment
		(start 44.340018 -218.585288)
		(end 42.955718 -218.585288)
		(width 0.4572)
		(layer "F.Cu")
		(net "GND")
	)
	(segment
		(start 107.654598 -404.45182)
		(end 107.189778 -404.45182)
		(width 0.381)
		(layer "F.Cu")
		(net "GND")
	)
	(segment
		(start 299.82414 -277.235158)
		(end 298.43984 -277.235158)
		(width 0.4572)
		(layer "F.Cu")
		(net "GND")
	)
	(segment
		(start 23.946866 -12.372848)
		(end 23.946866 -11.26998)
		(width 0.3556)
		(layer "F.Cu")
		(net "GND")
	)
	(segment
		(start 308.61635 -399.76171)
		(end 308.517798 -399.663158)
		(width 0.254)
		(layer "F.Cu")
		(net "GND")
	)
	(segment
		(start 385.39801 -293.260018)
		(end 385.864862 -293.525956)
		(width 0.350012)
		(layer "F.Cu")
		(net "GND")
	)
	(segment
		(start 80.287876 -247.99036)
		(end 79.821024 -247.724422)
		(width 0.350012)
		(layer "F.Cu")
		(net "GND")
	)
	(segment
		(start 148.290026 -384.617722)
		(end 148.898356 -384.617722)
		(width 0.254)
		(layer "F.Cu")
		(net "GND")
	)
	(segment
		(start 325.70801 -279.49017)
		(end 325.052944 -279.49017)
		(width 0.350012)
		(layer "F.Cu")
		(net "GND")
	)
	(segment
		(start 133.69798 -265.720322)
		(end 134.164832 -265.98626)
		(width 0.350012)
		(layer "F.Cu")
		(net "GND")
	)
	(segment
		(start 334.114394 -142.070582)
		(end 333.733394 -142.070582)
		(width 0.1778)
		(layer "F.Cu")
		(net "GND")
	)
	(segment
		(start 147.345654 -383.402586)
		(end 147.345654 -382.951482)
		(width 0.254)
		(layer "F.Cu")
		(net "GND")
	)
	(segment
		(start 79.177896 -283.540454)
		(end 78.711044 -283.806392)
		(width 0.350012)
		(layer "F.Cu")
		(net "GND")
	)
	(segment
		(start 316.590934 -398.542002)
		(end 316.070234 -398.542002)
		(width 0.254)
		(layer "F.Cu")
		(net "GND")
	)
	(segment
		(start 307.617876 -399.143474)
		(end 307.317648 -399.663158)
		(width 0.254)
		(layer "F.Cu")
		(net "GND")
	)
	(segment
		(start 88.645746 -382.951482)
		(end 88.744298 -382.85293)
		(width 0.254)
		(layer "F.Cu")
		(net "GND")
	)
	(segment
		(start 136.687814 -238.270288)
		(end 137.154666 -238.00435)
		(width 0.350012)
		(layer "F.Cu")
		(net "GND")
	)
	(segment
		(start 66.314828 -385.21132)
		(end 66.834512 -385.731004)
		(width 0.254)
		(layer "F.Cu")
		(net "GND")
	)
	(segment
		(start 316.070234 -392.999722)
		(end 316.017656 -392.30427)
		(width 0.254)
		(layer "F.Cu")
		(net "GND")
	)
	(segment
		(start 339.977984 -235.840016)
		(end 339.511132 -235.574078)
		(width 0.350012)
		(layer "F.Cu")
		(net "GND")
	)
	(segment
		(start 304.701448 -431.2539)
		(end 304.701448 -431.884836)
		(width 0.381)
		(layer "F.Cu")
		(net "GND")
	)
	(segment
		(start 29.252164 -218.585288)
		(end 27.867864 -218.585288)
		(width 0.4572)
		(layer "F.Cu")
		(net "GND")
	)
	(segment
		(start 417.12896 -100.591112)
		(end 417.12896 -101.499162)
		(width 0.508)
		(layer "F.Cu")
		(net "GND")
	)
	(segment
		(start 67.353942 -387.231128)
		(end 67.19189 -387.069076)
		(width 0.254)
		(layer "F.Cu")
		(net "GND")
	)
	(segment
		(start 70.860666 -7.215886)
		(end 70.860666 -7.215124)
		(width 0.3556)
		(layer "F.Cu")
		(net "GND")
	)
	(segment
		(start 100.027994 -246.370348)
		(end 99.561142 -246.10441)
		(width 0.350012)
		(layer "F.Cu")
		(net "GND")
	)
	(segment
		(start 387.748018 -292.450012)
		(end 388.21487 -292.71595)
		(width 0.350012)
		(layer "F.Cu")
		(net "GND")
	)
	(segment
		(start 98.918014 -277.060406)
		(end 98.451162 -277.326344)
		(width 0.350012)
		(layer "F.Cu")
		(net "GND")
	)
	(segment
		(start 50.417984 -390.761474)
		(end 50.470562 -390.160002)
		(width 0.254)
		(layer "F.Cu")
		(net "GND")
	)
	(segment
		(start 251.263658 -96.265746)
		(end 251.263658 -98.884994)
		(width 0.381)
		(layer "F.Cu")
		(net "GND")
	)
	(segment
		(start 315.849254 -412.212536)
		(end 315.849254 -411.264354)
		(width 0.381)
		(layer "F.Cu")
		(net "GND")
	)
	(segment
		(start 121.007886 -273.010376)
		(end 121.474738 -273.276314)
		(width 0.350012)
		(layer "F.Cu")
		(net "GND")
	)
	(segment
		(start 373.64797 -292.450012)
		(end 374.114822 -292.71595)
		(width 0.350012)
		(layer "F.Cu")
		(net "GND")
	)
	(segment
		(start 338.56803 -231.789986)
		(end 338.101178 -231.524048)
		(width 0.350012)
		(layer "F.Cu")
		(net "GND")
	)
	(segment
		(start 335.277968 -239.08004)
		(end 334.811116 -238.814102)
		(width 0.350012)
		(layer "F.Cu")
		(net "GND")
	)
	(segment
		(start 292.280086 -221.13494)
		(end 290.895786 -221.13494)
		(width 0.4572)
		(layer "F.Cu")
		(net "GND")
	)
	(segment
		(start 94.217998 -273.820382)
		(end 93.751146 -274.08632)
		(width 0.350012)
		(layer "F.Cu")
		(net "GND")
	)
	(segment
		(start 55.270654 -388.138924)
		(end 55.918608 -388.328662)
		(width 0.254)
		(layer "F.Cu")
		(net "GND")
	)
	(segment
		(start 144.677892 -245.560342)
		(end 145.144744 -245.294404)
		(width 0.350012)
		(layer "F.Cu")
		(net "GND")
	)
	(segment
		(start 55.066946 -8.320024)
		(end 55.066946 -9.423654)
		(width 0.3556)
		(layer "F.Cu")
		(net "GND")
	)
	(segment
		(start 346.557854 -224.500186)
		(end 346.091002 -224.234248)
		(width 0.350012)
		(layer "F.Cu")
		(net "GND")
	)
	(segment
		(start 156.30779 -101.238812)
		(end 156.96819 -101.238812)
		(width 0.4572)
		(layer "F.Cu")
		(net "GND")
	)
	(segment
		(start 213.369398 -20.687792)
		(end 213.369398 -19.870674)
		(width 0.3556)
		(layer "F.Cu")
		(net "GND")
	)
	(segment
		(start 84.987892 -222.070422)
		(end 84.987892 -221.504764)
		(width 0.350012)
		(layer "F.Cu")
		(net "GND")
	)
	(segment
		(start 381.167894 -281.110182)
		(end 381.634746 -281.37612)
		(width 0.350012)
		(layer "F.Cu")
		(net "GND")
	)
	(segment
		(start 143.098012 -272.20037)
		(end 143.56461 -272.466308)
		(width 0.350012)
		(layer "F.Cu")
		(net "GND")
	)
	(segment
		(start 288.929572 -412.341822)
		(end 289.243008 -412.655258)
		(width 0.381)
		(layer "F.Cu")
		(net "GND")
	)
	(segment
		(start 176.497742 -92.493846)
		(end 176.81067 -92.493846)
		(width 0.381)
		(layer "F.Cu")
		(net "GND")
	)
	(segment
		(start 343.68359 -171.346622)
		(end 343.096088 -171.346622)
		(width 0.254)
		(layer "F.Cu")
		(net "GND")
	)
	(segment
		(start 339.506052 -394.831062)
		(end 338.998052 -395.0208)
		(width 0.254)
		(layer "F.Cu")
		(net "GND")
	)
	(segment
		(start 194.604132 -294.235378)
		(end 195.988432 -294.235378)
		(width 0.4572)
		(layer "F.Cu")
		(net "GND")
	)
	(segment
		(start 392.622278 -177.86731)
		(end 392.622278 -177.951638)
		(width 0.381)
		(layer "F.Cu")
		(net "GND")
	)
	(segment
		(start 139.037822 -224.50044)
		(end 139.504674 -224.234502)
		(width 0.350012)
		(layer "F.Cu")
		(net "GND")
	)
	(segment
		(start 369.11788 -234.220004)
		(end 369.584732 -233.954066)
		(width 0.350012)
		(layer "F.Cu")
		(net "GND")
	)
	(segment
		(start 356.42804 -243.13007)
		(end 355.961188 -242.864132)
		(width 0.350012)
		(layer "F.Cu")
		(net "GND")
	)
	(segment
		(start 353.607878 -241.510058)
		(end 353.141026 -241.24412)
		(width 0.350012)
		(layer "F.Cu")
		(net "GND")
	)
	(segment
		(start 341.857838 -235.840016)
		(end 341.390986 -235.574078)
		(width 0.350012)
		(layer "F.Cu")
		(net "GND")
	)
	(segment
		(start 352.198178 -396.520924)
		(end 351.645982 -396.710662)
		(width 0.254)
		(layer "F.Cu")
		(net "GND")
	)
	(segment
		(start 156.09824 -384.617722)
		(end 156.045662 -383.92227)
		(width 0.254)
		(layer "F.Cu")
		(net "GND")
	)
	(segment
		(start 174.57928 -102.793546)
		(end 174.57928 -100.740718)
		(width 0.4572)
		(layer "F.Cu")
		(net "GND")
	)
	(segment
		(start 386.03809 -252.040136)
		(end 386.504942 -251.774198)
		(width 0.350012)
		(layer "F.Cu")
		(net "GND")
	)
	(segment
		(start 120.16105 -426.72)
		(end 120.904 -426.72)
		(width 0.381)
		(layer "F.Cu")
		(net "GND")
	)
	(segment
		(start 371.938042 -250.420124)
		(end 372.404894 -250.154186)
		(width 0.350012)
		(layer "F.Cu")
		(net "GND")
	)
	(segment
		(start 140.27785 -288.400236)
		(end 140.744702 -288.666174)
		(width 0.350012)
		(layer "F.Cu")
		(net "GND")
	)
	(segment
		(start 134.80796 -236.650276)
		(end 135.274812 -236.384338)
		(width 0.350012)
		(layer "F.Cu")
		(net "GND")
	)
	(segment
		(start 146.38782 -269.770352)
		(end 147.042886 -269.770352)
		(width 0.350012)
		(layer "F.Cu")
		(net "GND")
	)
	(segment
		(start 142.797784 -245.560342)
		(end 143.264636 -245.294404)
		(width 0.350012)
		(layer "F.Cu")
		(net "GND")
	)
	(segment
		(start 95.627952 -294.070278)
		(end 95.1611 -294.336216)
		(width 0.350012)
		(layer "F.Cu")
		(net "GND")
	)
	(segment
		(start 156.09824 -390.160002)
		(end 155.419044 -390.160002)
		(width 0.254)
		(layer "F.Cu")
		(net "GND")
	)
	(segment
		(start 307.4162 -399.76171)
		(end 307.4162 -400.212814)
		(width 0.254)
		(layer "F.Cu")
		(net "GND")
	)
	(segment
		(start 97.037906 -290.020248)
		(end 96.571054 -290.286186)
		(width 0.350012)
		(layer "F.Cu")
		(net "GND")
	)
	(segment
		(start 265.54811 -294.235124)
		(end 266.93241 -294.235124)
		(width 0.4572)
		(layer "F.Cu")
		(net "GND")
	)
	(segment
		(start 367.787936 -402.282152)
		(end 367.787936 -401.37715)
		(width 0.254)
		(layer "F.Cu")
		(net "GND")
	)
	(segment
		(start 344.977974 -280.300176)
		(end 344.511122 -280.566114)
		(width 0.350012)
		(layer "F.Cu")
		(net "GND")
	)
	(segment
		(start 392.917934 -280.300176)
		(end 393.384786 -280.566114)
		(width 0.350012)
		(layer "F.Cu")
		(net "GND")
	)
	(segment
		(start 336.598006 -398.542002)
		(end 336.545428 -399.143474)
		(width 0.254)
		(layer "F.Cu")
		(net "GND")
	)
	(segment
		(start 371.818408 -396.710662)
		(end 371.170454 -396.520924)
		(width 0.254)
		(layer "F.Cu")
		(net "GND")
	)
	(segment
		(start 40.258238 -12.374118)
		(end 40.256968 -12.372848)
		(width 0.3556)
		(layer "F.Cu")
		(net "GND")
	)
	(segment
		(start 78.877922 -252.04039)
		(end 78.41107 -251.774452)
		(width 0.350012)
		(layer "F.Cu")
		(net "GND")
	)
	(segment
		(start 343.189814 -392.999722)
		(end 343.798144 -392.999722)
		(width 0.254)
		(layer "F.Cu")
		(net "GND")
	)
	(segment
		(start 45.657008 -7.217156)
		(end 45.657008 -8.320024)
		(width 0.3556)
		(layer "F.Cu")
		(net "GND")
	)
	(segment
		(start 143.160242 -383.7432)
		(end 143.693642 -383.7432)
		(width 0.254)
		(layer "F.Cu")
		(net "GND")
	)
	(segment
		(start 325.70801 -276.250146)
		(end 325.052944 -276.250146)
		(width 0.350012)
		(layer "F.Cu")
		(net "GND")
	)
	(segment
		(start 338.868004 -266.530074)
		(end 338.401152 -266.796012)
		(width 0.350012)
		(layer "F.Cu")
		(net "GND")
	)
	(segment
		(start 370.057934 -252.040136)
		(end 370.524786 -251.774198)
		(width 0.350012)
		(layer "F.Cu")
		(net "GND")
	)
	(segment
		(start 230.275638 -147.932648)
		(end 230.275638 -147.24253)
		(width 0.3556)
		(layer "F.Cu")
		(net "GND")
	)
	(segment
		(start 84.047838 -230.170228)
		(end 83.580986 -229.90429)
		(width 0.350012)
		(layer "F.Cu")
		(net "GND")
	)
	(segment
		(start 84.047838 -244.750336)
		(end 83.580986 -244.484398)
		(width 0.350012)
		(layer "F.Cu")
		(net "GND")
	)
	(segment
		(start 84.347812 -268.15034)
		(end 83.88096 -268.416278)
		(width 0.350012)
		(layer "F.Cu")
		(net "GND")
	)
	(segment
		(start 350.556322 -159.314388)
		(end 350.127824 -159.314388)
		(width 0.2286)
		(layer "F.Cu")
		(net "GND")
	)
	(segment
		(start 45.658278 -12.37488)
		(end 45.658278 -12.374118)
		(width 0.3556)
		(layer "F.Cu")
		(net "GND")
	)
	(segment
		(start 63.670688 -390.160002)
		(end 62.991238 -390.160002)
		(width 0.254)
		(layer "F.Cu")
		(net "GND")
	)
	(segment
		(start 75.68311 -337.070954)
		(end 75.68311 -337.395312)
		(width 0.2286)
		(layer "F.Cu")
		(net "GND")
	)
	(segment
		(start 299.532294 -393.04468)
		(end 300.065694 -393.04468)
		(width 0.254)
		(layer "F.Cu")
		(net "GND")
	)
	(segment
		(start 358.307894 -241.510058)
		(end 357.841042 -241.24412)
		(width 0.350012)
		(layer "F.Cu")
		(net "GND")
	)
	(segment
		(start 335.045558 -391.784586)
		(end 335.045558 -391.340086)
		(width 0.254)
		(layer "F.Cu")
		(net "GND")
	)
	(segment
		(start 60.97016 -351.932748)
		(end 61.55817 -351.932748)
		(width 0.381)
		(layer "F.Cu")
		(net "GND")
	)
	(segment
		(start 344.678 -255.28016)
		(end 344.211148 -255.014222)
		(width 0.350012)
		(layer "F.Cu")
		(net "GND")
	)
	(segment
		(start 301.161704 -430.55032)
		(end 301.161704 -431.101246)
		(width 0.381)
		(layer "F.Cu")
		(net "GND")
	)
	(segment
		(start 346.145612 -399.143474)
		(end 346.19819 -398.542002)
		(width 0.254)
		(layer "F.Cu")
		(net "GND")
	)
	(segment
		(start 99.55784 -235.84027)
		(end 99.090988 -235.574332)
		(width 0.350012)
		(layer "F.Cu")
		(net "GND")
	)
	(segment
		(start 389.414766 -393.59332)
		(end 389.93445 -394.113004)
		(width 0.254)
		(layer "F.Cu")
		(net "GND")
	)
	(segment
		(start 163.305744 -116.267484)
		(end 162.833812 -116.267484)
		(width 0.4572)
		(layer "F.Cu")
		(net "GND")
	)
	(segment
		(start 366.597946 -273.820128)
		(end 367.064798 -274.086066)
		(width 0.350012)
		(layer "F.Cu")
		(net "GND")
	)
	(segment
		(start 38.4556 -7.215124)
		(end 38.4556 -7.215886)
		(width 0.3556)
		(layer "F.Cu")
		(net "GND")
	)
	(segment
		(start 389.414766 -396.213076)
		(end 389.634476 -396.213076)
		(width 0.254)
		(layer "F.Cu")
		(net "GND")
	)
	(segment
		(start 339.977984 -222.880174)
		(end 339.511132 -222.614236)
		(width 0.350012)
		(layer "F.Cu")
		(net "GND")
	)
	(segment
		(start 311.016396 -399.76171)
		(end 310.917844 -399.663158)
		(width 0.254)
		(layer "F.Cu")
		(net "GND")
	)
	(segment
		(start 194.604132 -296.785284)
		(end 195.988432 -296.785284)
		(width 0.4572)
		(layer "F.Cu")
		(net "GND")
	)
	(segment
		(start 362.067856 -247.990106)
		(end 362.534708 -247.724168)
		(width 0.350012)
		(layer "F.Cu")
		(net "GND")
	)
	(segment
		(start 331.81798 -264.100056)
		(end 331.351128 -264.365994)
		(width 0.350012)
		(layer "F.Cu")
		(net "GND")
	)
	(segment
		(start 118.657878 -278.680418)
		(end 119.12473 -278.946356)
		(width 0.350012)
		(layer "F.Cu")
		(net "GND")
	)
	(segment
		(start 377.878086 -264.100056)
		(end 378.344938 -264.365994)
		(width 0.350012)
		(layer "F.Cu")
		(net "GND")
	)
	(segment
		(start 103.886 -424.11396)
		(end 103.886 -423.42435)
		(width 0.381)
		(layer "F.Cu")
		(net "GND")
	)
	(segment
		(start 55.016654 -391.830814)
		(end 55.016654 -391.37971)
		(width 0.254)
		(layer "F.Cu")
		(net "GND")
	)
	(segment
		(start 98.147886 -256.09042)
		(end 97.681034 -255.824482)
		(width 0.350012)
		(layer "F.Cu")
		(net "GND")
	)
	(segment
		(start 370.997988 -243.940076)
		(end 371.46484 -243.674138)
		(width 0.350012)
		(layer "F.Cu")
		(net "GND")
	)
	(segment
		(start 77.767942 -284.35046)
		(end 77.112876 -284.35046)
		(width 0.350012)
		(layer "F.Cu")
		(net "GND")
	)
	(segment
		(start 341.857838 -243.940076)
		(end 341.390986 -243.674138)
		(width 0.350012)
		(layer "F.Cu")
		(net "GND")
	)
	(segment
		(start 51.884072 -221.135194)
		(end 50.499772 -221.135194)
		(width 0.4572)
		(layer "F.Cu")
		(net "GND")
	)
	(segment
		(start 353.607878 -247.990106)
		(end 353.141026 -247.724168)
		(width 0.350012)
		(layer "F.Cu")
		(net "GND")
	)
	(segment
		(start 125.617986 -383.402586)
		(end 125.617986 -382.951482)
		(width 0.254)
		(layer "F.Cu")
		(net "GND")
	)
	(segment
		(start 134.80796 -231.79024)
		(end 135.274812 -231.524302)
		(width 0.350012)
		(layer "F.Cu")
		(net "GND")
	)
	(segment
		(start 398.448022 -12.374118)
		(end 398.446752 -12.372848)
		(width 0.3556)
		(layer "F.Cu")
		(net "GND")
	)
	(segment
		(start 108.487972 -243.130324)
		(end 108.02112 -242.864386)
		(width 0.350012)
		(layer "F.Cu")
		(net "GND")
	)
	(segment
		(start 435.000146 -315.485018)
		(end 436.384446 -315.485018)
		(width 0.4572)
		(layer "F.Cu")
		(net "GND")
	)
	(segment
		(start 94.998286 -384.617722)
		(end 94.39021 -384.617722)
		(width 0.254)
		(layer "F.Cu")
		(net "GND")
	)
	(segment
		(start 110.83798 -247.180354)
		(end 110.371128 -246.914416)
		(width 0.350012)
		(layer "F.Cu")
		(net "GND")
	)
	(segment
		(start 150.098252 -390.160002)
		(end 149.419056 -390.160002)
		(width 0.254)
		(layer "F.Cu")
		(net "GND")
	)
	(segment
		(start 115.367816 -266.530328)
		(end 115.834668 -266.796266)
		(width 0.350012)
		(layer "F.Cu")
		(net "GND")
	)
	(segment
		(start 86.338156 -41.95318)
		(end 85.722206 -41.95318)
		(width 0.4064)
		(layer "F.Cu")
		(net "GND")
	)
	(segment
		(start 361.42803 -276.250146)
		(end 361.894882 -276.516084)
		(width 0.350012)
		(layer "F.Cu")
		(net "GND")
	)
	(segment
		(start 92.037916 -245.560342)
		(end 91.571064 -245.294404)
		(width 0.350012)
		(layer "F.Cu")
		(net "GND")
	)
	(segment
		(start 389.576818 -395.451076)
		(end 389.414766 -395.613128)
		(width 0.254)
		(layer "F.Cu")
		(net "GND")
	)
	(segment
		(start 320.870326 -392.999722)
		(end 321.462146 -392.999722)
		(width 0.254)
		(layer "F.Cu")
		(net "GND")
	)
	(segment
		(start 39.43604 -436.499)
		(end 40.09644 -436.499)
		(width 0.381)
		(layer "F.Cu")
		(net "GND")
	)
	(segment
		(start 138.397996 -281.920442)
		(end 138.864848 -282.18638)
		(width 0.350012)
		(layer "F.Cu")
		(net "GND")
	)
	(segment
		(start 385.86791 -268.150086)
		(end 386.334762 -268.416024)
		(width 0.350012)
		(layer "F.Cu")
		(net "GND")
	)
	(segment
		(start 164.498274 -390.160002)
		(end 165.018974 -390.160002)
		(width 0.254)
		(layer "F.Cu")
		(net "GND")
	)
	(segment
		(start 371.467888 -246.370094)
		(end 371.93474 -246.104156)
		(width 0.350012)
		(layer "F.Cu")
		(net "GND")
	)
	(segment
		(start 143.267938 -241.510312)
		(end 143.73479 -241.244374)
		(width 0.350012)
		(layer "F.Cu")
		(net "GND")
	)
	(segment
		(start 351.728024 -222.070168)
		(end 351.261172 -221.80423)
		(width 0.350012)
		(layer "F.Cu")
		(net "GND")
	)
	(segment
		(start 337.158076 -222.880174)
		(end 336.691224 -222.614236)
		(width 0.350012)
		(layer "F.Cu")
		(net "GND")
	)
	(segment
		(start 51.884072 -218.585288)
		(end 50.499772 -218.585288)
		(width 0.4572)
		(layer "F.Cu")
		(net "GND")
	)
	(segment
		(start 106.137964 -232.600246)
		(end 105.671112 -232.334308)
		(width 0.350012)
		(layer "F.Cu")
		(net "GND")
	)
	(segment
		(start 380.770638 -396.520924)
		(end 380.218442 -396.710662)
		(width 0.254)
		(layer "F.Cu")
		(net "GND")
	)
	(segment
		(start 56.47055 -390.160002)
		(end 55.791354 -390.160002)
		(width 0.254)
		(layer "F.Cu")
		(net "GND")
	)
	(segment
		(start 142.327884 -223.690434)
		(end 142.794736 -223.424496)
		(width 0.350012)
		(layer "F.Cu")
		(net "GND")
	)
	(segment
		(start 381.970534 -398.542002)
		(end 381.291338 -398.542002)
		(width 0.254)
		(layer "F.Cu")
		(net "GND")
	)
	(segment
		(start 371.938042 -237.460028)
		(end 372.404894 -237.19409)
		(width 0.350012)
		(layer "F.Cu")
		(net "GND")
	)
	(segment
		(start 114.597942 -250.420378)
		(end 115.064794 -250.15444)
		(width 0.350012)
		(layer "F.Cu")
		(net "GND")
	)
	(segment
		(start 288.180018 -210.085178)
		(end 289.564318 -210.085178)
		(width 0.4572)
		(layer "F.Cu")
		(net "GND")
	)
	(segment
		(start 333.215488 -401.427696)
		(end 333.215488 -402.282152)
		(width 0.254)
		(layer "F.Cu")
		(net "GND")
	)
	(segment
		(start 144.977866 -280.30043)
		(end 145.444718 -280.566368)
		(width 0.350012)
		(layer "F.Cu")
		(net "GND")
	)
	(segment
		(start 109.427772 -236.650276)
		(end 108.961174 -236.384338)
		(width 0.350012)
		(layer "F.Cu")
		(net "GND")
	)
	(segment
		(start 332.28788 -284.350206)
		(end 331.821028 -284.616144)
		(width 0.350012)
		(layer "F.Cu")
		(net "GND")
	)
	(segment
		(start 338.44611 -396.710662)
		(end 337.798156 -396.520924)
		(width 0.254)
		(layer "F.Cu")
		(net "GND")
	)
	(segment
		(start 395.32687 -55.6895)
		(end 395.092174 -55.454804)
		(width 0.4572)
		(layer "F.Cu")
		(net "GND")
	)
	(segment
		(start 326.81799 -230.97998)
		(end 326.351138 -230.714296)
		(width 0.350012)
		(layer "F.Cu")
		(net "GND")
	)
	(segment
		(start 270.45285 -333.045562)
		(end 270.48841 -333.010002)
		(width 0.4572)
		(layer "F.Cu")
		(net "GND")
	)
	(segment
		(start 118.218458 -388.328662)
		(end 117.570504 -388.138924)
		(width 0.254)
		(layer "F.Cu")
		(net "GND")
	)
	(segment
		(start 295.724072 -210.085178)
		(end 297.108372 -210.085178)
		(width 0.4572)
		(layer "F.Cu")
		(net "GND")
	)
	(segment
		(start 130.77063 -386.6388)
		(end 130.07848 -386.449062)
		(width 0.254)
		(layer "F.Cu")
		(net "GND")
	)
	(segment
		(start 54.070504 -390.160002)
		(end 53.391308 -390.160002)
		(width 0.254)
		(layer "F.Cu")
		(net "GND")
	)
	(segment
		(start 117.717824 -280.30043)
		(end 118.184676 -280.566368)
		(width 0.350012)
		(layer "F.Cu")
		(net "GND")
	)
	(segment
		(start 122.41784 -281.920442)
		(end 122.884692 -282.18638)
		(width 0.350012)
		(layer "F.Cu")
		(net "GND")
	)
	(segment
		(start 351.087944 -284.350206)
		(end 350.621092 -284.616144)
		(width 0.350012)
		(layer "F.Cu")
		(net "GND")
	)
	(segment
		(start 402.046948 -11.26998)
		(end 402.046948 -10.16635)
		(width 0.3556)
		(layer "F.Cu")
		(net "GND")
	)
	(segment
		(start 97.507806 -285.970472)
		(end 97.040954 -286.23641)
		(width 0.350012)
		(layer "F.Cu")
		(net "GND")
	)
	(segment
		(start 232.000044 -53.364892)
		(end 230.96728 -53.364892)
		(width 0.381)
		(layer "F.Cu")
		(net "GND")
	)
	(segment
		(start 387.748018 -263.29005)
		(end 388.21487 -263.555988)
		(width 0.350012)
		(layer "F.Cu")
		(net "GND")
	)
	(segment
		(start 331.987906 -233.409998)
		(end 331.521054 -233.14406)
		(width 0.350012)
		(layer "F.Cu")
		(net "GND")
	)
	(segment
		(start 349.44558 -392.004296)
		(end 349.745554 -392.30427)
		(width 0.254)
		(layer "F.Cu")
		(net "GND")
	)
	(segment
		(start 412.618936 -398.542002)
		(end 412.098236 -398.542002)
		(width 0.254)
		(layer "F.Cu")
		(net "GND")
	)
	(segment
		(start 350.998028 -392.999722)
		(end 350.389952 -392.999722)
		(width 0.254)
		(layer "F.Cu")
		(net "GND")
	)
	(segment
		(start 79.398368 -388.08152)
		(end 79.14894 -388.330948)
		(width 0.254)
		(layer "F.Cu")
		(net "GND")
	)
	(segment
		(start 83.577938 -250.420378)
		(end 83.111086 -250.15444)
		(width 0.350012)
		(layer "F.Cu")
		(net "GND")
	)
	(segment
		(start 356.42804 -226.930204)
		(end 355.961188 -226.664266)
		(width 0.350012)
		(layer "F.Cu")
		(net "GND")
	)
	(segment
		(start 107.078018 -224.50044)
		(end 106.611166 -224.234502)
		(width 0.350012)
		(layer "F.Cu")
		(net "GND")
	)
	(segment
		(start 97.037906 -264.10031)
		(end 96.571054 -264.366248)
		(width 0.350012)
		(layer "F.Cu")
		(net "GND")
	)
	(segment
		(start 453.610726 -402.801328)
		(end 454.317608 -402.801328)
		(width 0.4572)
		(layer "F.Cu")
		(net "GND")
	)
	(segment
		(start 179.516024 -219.435426)
		(end 180.900324 -219.435426)
		(width 0.4572)
		(layer "F.Cu")
		(net "GND")
	)
	(segment
		(start 123.827794 -287.590484)
		(end 124.294646 -287.856422)
		(width 0.350012)
		(layer "F.Cu")
		(net "GND")
	)
	(segment
		(start 356.42804 -235.03001)
		(end 355.961188 -234.764072)
		(width 0.350012)
		(layer "F.Cu")
		(net "GND")
	)
	(segment
		(start 349.745554 -399.143474)
		(end 349.798132 -398.542002)
		(width 0.254)
		(layer "F.Cu")
		(net "GND")
	)
	(segment
		(start 416.556952 -12.372848)
		(end 416.556952 -11.26998)
		(width 0.3556)
		(layer "F.Cu")
		(net "GND")
	)
	(segment
		(start 17.608042 -275.53539)
		(end 18.992342 -275.53539)
		(width 0.4572)
		(layer "F.Cu")
		(net "GND")
	)
	(segment
		(start 345.447874 -281.110182)
		(end 344.981022 -281.37612)
		(width 0.350012)
		(layer "F.Cu")
		(net "GND")
	)
	(segment
		(start 122.887994 -266.530328)
		(end 123.354846 -266.796266)
		(width 0.350012)
		(layer "F.Cu")
		(net "GND")
	)
	(segment
		(start 183.616092 -274.685252)
		(end 182.231792 -274.685252)
		(width 0.4572)
		(layer "F.Cu")
		(net "GND")
	)
	(segment
		(start 123.357894 -277.060406)
		(end 123.824746 -277.326344)
		(width 0.350012)
		(layer "F.Cu")
		(net "GND")
	)
	(segment
		(start 38.016688 -169.763694)
		(end 38.016688 -169.037)
		(width 0.3556)
		(layer "F.Cu")
		(net "GND")
	)
	(segment
		(start 378.347986 -281.110182)
		(end 378.814838 -281.37612)
		(width 0.350012)
		(layer "F.Cu")
		(net "GND")
	)
	(segment
		(start 135.107934 -269.770352)
		(end 135.574786 -270.03629)
		(width 0.350012)
		(layer "F.Cu")
		(net "GND")
	)
	(segment
		(start 133.20141 -384.005836)
		(end 133.117844 -383.92227)
		(width 0.254)
		(layer "F.Cu")
		(net "GND")
	)
	(segment
		(start 352.789998 -392.999722)
		(end 352.198178 -392.999722)
		(width 0.254)
		(layer "F.Cu")
		(net "GND")
	)
	(segment
		(start 40.23995 -238.135414)
		(end 41.62425 -238.135414)
		(width 0.4572)
		(layer "F.Cu")
		(net "GND")
	)
	(segment
		(start 327.117964 -288.399982)
		(end 326.651112 -288.66592)
		(width 0.350012)
		(layer "F.Cu")
		(net "GND")
	)
	(segment
		(start 295.724072 -238.13516)
		(end 297.108372 -238.13516)
		(width 0.4572)
		(layer "F.Cu")
		(net "GND")
	)
	(segment
		(start 409.034742 -140.884656)
		(end 408.407108 -140.884656)
		(width 0.3556)
		(layer "F.Cu")
		(net "GND")
	)
	(segment
		(start 99.857814 -273.820382)
		(end 99.390962 -274.08632)
		(width 0.350012)
		(layer "F.Cu")
		(net "GND")
	)
	(segment
		(start 136.517888 -272.20037)
		(end 136.98474 -272.466308)
		(width 0.350012)
		(layer "F.Cu")
		(net "GND")
	)
	(segment
		(start 407.448258 -12.374118)
		(end 407.446988 -12.372848)
		(width 0.3556)
		(layer "F.Cu")
		(net "GND")
	)
	(segment
		(start 320.097658 -103.410512)
		(end 320.09842 -103.40975)
		(width 0.4572)
		(layer "F.Cu")
		(net "GND")
	)
	(segment
		(start 131.271518 -403.830536)
		(end 131.271518 -402.931122)
		(width 0.381)
		(layer "F.Cu")
		(net "GND")
	)
	(segment
		(start 365.357918 -237.460028)
		(end 365.82477 -237.19409)
		(width 0.350012)
		(layer "F.Cu")
		(net "GND")
	)
	(segment
		(start 128.370584 -390.160002)
		(end 128.318006 -390.761474)
		(width 0.254)
		(layer "F.Cu")
		(net "GND")
	)
	(segment
		(start 105.967784 -268.15034)
		(end 105.500932 -268.416278)
		(width 0.350012)
		(layer "F.Cu")
		(net "GND")
	)
	(segment
		(start 101.437948 -237.460282)
		(end 100.971096 -237.194344)
		(width 0.350012)
		(layer "F.Cu")
		(net "GND")
	)
	(segment
		(start 412.956756 -11.26998)
		(end 412.956756 -10.16635)
		(width 0.3556)
		(layer "F.Cu")
		(net "GND")
	)
	(segment
		(start 185.399172 -22.097492)
		(end 184.897776 -22.598888)
		(width 0.4572)
		(layer "F.Cu")
		(net "GND")
	)
	(segment
		(start 392.917934 -286.780224)
		(end 393.384786 -287.045908)
		(width 0.350012)
		(layer "F.Cu")
		(net "GND")
	)
	(segment
		(start 118.770654 -390.160002)
		(end 118.091204 -390.160002)
		(width 0.254)
		(layer "F.Cu")
		(net "GND")
	)
	(segment
		(start 387.917944 -240.700052)
		(end 388.384796 -240.434114)
		(width 0.350012)
		(layer "F.Cu")
		(net "GND")
	)
	(segment
		(start 407.448258 -12.37488)
		(end 407.448258 -12.374118)
		(width 0.3556)
		(layer "F.Cu")
		(net "GND")
	)
	(segment
		(start 97.577402 -74.76998)
		(end 97.577402 -75.147932)
		(width 0.4572)
		(layer "F.Cu")
		(net "GND")
	)
	(segment
		(start 341.387938 -236.650022)
		(end 340.921086 -236.384084)
		(width 0.350012)
		(layer "F.Cu")
		(net "GND")
	)
	(segment
		(start 355.08057 -402.4757)
		(end 355.08057 -401.873212)
		(width 0.254)
		(layer "F.Cu")
		(net "GND")
	)
	(segment
		(start 208.622138 -141.632178)
		(end 209.239358 -142.249398)
		(width 0.4572)
		(layer "F.Cu")
		(net "GND")
	)
	(segment
		(start 317.270384 -392.999722)
		(end 316.662054 -392.999722)
		(width 0.254)
		(layer "F.Cu")
		(net "GND")
	)
	(segment
		(start 250.15952 -69.962522)
		(end 249.54357 -69.962522)
		(width 0.4572)
		(layer "F.Cu")
		(net "GND")
	)
	(segment
		(start 362.067856 -236.650022)
		(end 362.534708 -236.384084)
		(width 0.350012)
		(layer "F.Cu")
		(net "GND")
	)
	(segment
		(start 124.297948 -281.920442)
		(end 124.7648 -282.18638)
		(width 0.350012)
		(layer "F.Cu")
		(net "GND")
	)
	(segment
		(start 103.317802 -243.94033)
		(end 102.85095 -243.674392)
		(width 0.350012)
		(layer "F.Cu")
		(net "GND")
	)
	(segment
		(start 103.617776 -288.400236)
		(end 103.151178 -288.666174)
		(width 0.350012)
		(layer "F.Cu")
		(net "GND")
	)
	(segment
		(start 82.167984 -247.99036)
		(end 81.701132 -247.724422)
		(width 0.350012)
		(layer "F.Cu")
		(net "GND")
	)
	(segment
		(start 84.347812 -276.2504)
		(end 83.88096 -276.516338)
		(width 0.350012)
		(layer "F.Cu")
		(net "GND")
	)
	(segment
		(start 126.347982 -246.370348)
		(end 126.814834 -246.10441)
		(width 0.350012)
		(layer "F.Cu")
		(net "GND")
	)
	(segment
		(start 139.80795 -287.590484)
		(end 140.274802 -287.856422)
		(width 0.350012)
		(layer "F.Cu")
		(net "GND")
	)
	(segment
		(start 128.116584 -391.37971)
		(end 128.116584 -391.830814)
		(width 0.254)
		(layer "F.Cu")
		(net "GND")
	)
	(segment
		(start 90.927936 -268.15034)
		(end 90.461084 -268.416278)
		(width 0.350012)
		(layer "F.Cu")
		(net "GND")
	)
	(segment
		(start 94.217998 -264.10031)
		(end 93.751146 -264.366248)
		(width 0.350012)
		(layer "F.Cu")
		(net "GND")
	)
	(segment
		(start 387.917944 -229.360222)
		(end 388.384796 -229.094284)
		(width 0.350012)
		(layer "F.Cu")
		(net "GND")
	)
	(segment
		(start 155.84424 -391.37971)
		(end 155.84424 -391.830814)
		(width 0.254)
		(layer "F.Cu")
		(net "GND")
	)
	(segment
		(start 415.698178 -396.520924)
		(end 415.146236 -396.710662)
		(width 0.254)
		(layer "F.Cu")
		(net "GND")
	)
	(segment
		(start 191.160146 -314.635388)
		(end 189.775846 -314.635388)
		(width 0.4572)
		(layer "F.Cu")
		(net "GND")
	)
	(segment
		(start 74.10831 -39.070026)
		(end 74.816462 -39.070026)
		(width 0.2286)
		(layer "F.Cu")
		(net "GND")
	)
	(segment
		(start 120.707912 -256.09042)
		(end 121.174764 -255.824482)
		(width 0.350012)
		(layer "F.Cu")
		(net "GND")
	)
	(segment
		(start 356.69601 -402.163788)
		(end 357.142796 -401.717002)
		(width 0.254)
		(layer "F.Cu")
		(net "GND")
	)
	(segment
		(start 164.427916 -312.935366)
		(end 165.812216 -312.935366)
		(width 0.4572)
		(layer "F.Cu")
		(net "GND")
	)
	(segment
		(start 86.344252 -391.37971)
		(end 86.2457 -391.281158)
		(width 0.254)
		(layer "F.Cu")
		(net "GND")
	)
	(segment
		(start 308.87035 -392.999722)
		(end 308.817772 -392.30427)
		(width 0.254)
		(layer "F.Cu")
		(net "GND")
	)
	(segment
		(start 364.417864 -235.840016)
		(end 364.884716 -235.574078)
		(width 0.350012)
		(layer "F.Cu")
		(net "GND")
	)
	(segment
		(start 97.037906 -265.720322)
		(end 96.571054 -265.98626)
		(width 0.350012)
		(layer "F.Cu")
		(net "GND")
	)
	(segment
		(start 387.748018 -294.070024)
		(end 388.21487 -294.335962)
		(width 0.350012)
		(layer "F.Cu")
		(net "GND")
	)
	(segment
		(start 118.078504 -386.449062)
		(end 117.570504 -386.6388)
		(width 0.254)
		(layer "F.Cu")
		(net "GND")
	)
	(segment
		(start 67.924426 -147.81784)
		(end 67.716654 -148.025612)
		(width 0.254)
		(layer "F.Cu")
		(net "GND")
	)
	(segment
		(start 303.343818 -434.914294)
		(end 303.978818 -434.914294)
		(width 0.4318)
		(layer "F.Cu")
		(net "GND")
	)
	(segment
		(start 99.14255 -384.531108)
		(end 98.842576 -384.831082)
		(width 0.254)
		(layer "F.Cu")
		(net "GND")
	)
	(segment
		(start 89.047828 -268.15034)
		(end 88.580976 -268.416278)
		(width 0.350012)
		(layer "F.Cu")
		(net "GND")
	)
	(segment
		(start 164.427916 -200.735438)
		(end 165.812216 -200.735438)
		(width 0.4572)
		(layer "F.Cu")
		(net "GND")
	)
	(segment
		(start 68.790566 -394.080746)
		(end 68.98132 -394.2715)
		(width 0.254)
		(layer "F.Cu")
		(net "GND")
	)
	(segment
		(start 90.14587 -390.761474)
		(end 90.198448 -390.160002)
		(width 0.254)
		(layer "F.Cu")
		(net "GND")
	)
	(segment
		(start 21.70811 -230.485442)
		(end 20.32381 -230.485442)
		(width 0.4572)
		(layer "F.Cu")
		(net "GND")
	)
	(segment
		(start 68.807076 -166.355776)
		(end 68.729098 -166.54399)
		(width 0.2286)
		(layer "F.Cu")
		(net "GND")
	)
	(segment
		(start 131.517898 -255.280414)
		(end 131.98475 -255.014476)
		(width 0.350012)
		(layer "F.Cu")
		(net "GND")
	)
	(segment
		(start 152.53208 -102.038912)
		(end 153.22423 -102.038912)
		(width 0.4064)
		(layer "F.Cu")
		(net "GND")
	)
	(segment
		(start 154.206194 -386.449062)
		(end 153.698194 -386.6388)
		(width 0.254)
		(layer "F.Cu")
		(net "GND")
	)
	(segment
		(start 49.666906 -7.217156)
		(end 49.666906 -8.320024)
		(width 0.3556)
		(layer "F.Cu")
		(net "GND")
	)
	(segment
		(start 292.280086 -237.285022)
		(end 290.895786 -237.285022)
		(width 0.4572)
		(layer "F.Cu")
		(net "GND")
	)
	(segment
		(start 362.067856 -241.510058)
		(end 362.534708 -241.24412)
		(width 0.350012)
		(layer "F.Cu")
		(net "GND")
	)
	(segment
		(start 414.244282 -400.212814)
		(end 414.244282 -399.76171)
		(width 0.254)
		(layer "F.Cu")
		(net "GND")
	)
	(segment
		(start 335.39811 -396.46352)
		(end 335.148682 -396.214092)
		(width 0.254)
		(layer "F.Cu")
		(net "GND")
	)
	(segment
		(start 147.645628 -390.761474)
		(end 147.345654 -391.281158)
		(width 0.254)
		(layer "F.Cu")
		(net "GND")
	)
	(segment
		(start 415.698178 -392.999722)
		(end 415.6456 -392.30427)
		(width 0.254)
		(layer "F.Cu")
		(net "GND")
	)
	(segment
		(start 17.608042 -294.235378)
		(end 18.992342 -294.235378)
		(width 0.4572)
		(layer "F.Cu")
		(net "GND")
	)
	(segment
		(start 292.280086 -211.784946)
		(end 290.895786 -211.784946)
		(width 0.4572)
		(layer "F.Cu")
		(net "GND")
	)
	(segment
		(start 343.189814 -392.999722)
		(end 342.597994 -392.999722)
		(width 0.254)
		(layer "F.Cu")
		(net "GND")
	)
	(segment
		(start 236.58957 -153.606754)
		(end 235.453682 -153.606754)
		(width 0.381)
		(layer "F.Cu")
		(net "GND")
	)
	(segment
		(start 103.998522 -31.521654)
		(end 104.265222 -31.254954)
		(width 0.254)
		(layer "F.Cu")
		(net "GND")
	)
	(segment
		(start 118.657878 -268.960346)
		(end 119.12473 -269.226284)
		(width 0.350012)
		(layer "F.Cu")
		(net "GND")
	)
	(segment
		(start 58.870596 -384.617722)
		(end 59.462416 -384.617722)
		(width 0.254)
		(layer "F.Cu")
		(net "GND")
	)
	(segment
		(start 366.128046 -289.209988)
		(end 366.594898 -289.475926)
		(width 0.350012)
		(layer "F.Cu")
		(net "GND")
	)
	(segment
		(start 306.470304 -396.520924)
		(end 305.918362 -396.710662)
		(width 0.254)
		(layer "F.Cu")
		(net "GND")
	)
	(segment
		(start 384.159506 -180.665882)
		(end 383.86385 -180.961538)
		(width 0.2286)
		(layer "F.Cu")
		(net "GND")
	)
	(segment
		(start 401.729448 -396.51305)
		(end 401.420838 -396.74673)
		(width 0.254)
		(layer "F.Cu")
		(net "GND")
	)
	(segment
		(start 379.316488 -399.76171)
		(end 379.217936 -399.663158)
		(width 0.254)
		(layer "F.Cu")
		(net "GND")
	)
	(segment
		(start 373.217948 -392.004296)
		(end 373.517922 -392.30427)
		(width 0.254)
		(layer "F.Cu")
		(net "GND")
	)
	(segment
		(start 387.917944 -234.220004)
		(end 388.384796 -233.954066)
		(width 0.350012)
		(layer "F.Cu")
		(net "GND")
	)
	(segment
		(start 121.8184 -388.328662)
		(end 121.170446 -388.138924)
		(width 0.254)
		(layer "F.Cu")
		(net "GND")
	)
	(segment
		(start 349.67799 -262.480044)
		(end 349.211138 -262.745982)
		(width 0.350012)
		(layer "F.Cu")
		(net "GND")
	)
	(segment
		(start 117.717824 -270.580358)
		(end 118.184676 -270.846296)
		(width 0.350012)
		(layer "F.Cu")
		(net "GND")
	)
	(segment
		(start 288.568638 -412.341822)
		(end 288.929572 -412.341822)
		(width 0.381)
		(layer "F.Cu")
		(net "GND")
	)
	(segment
		(start 137.927842 -268.15034)
		(end 138.394694 -268.416278)
		(width 0.350012)
		(layer "F.Cu")
		(net "GND")
	)
	(segment
		(start 123.997974 -237.460282)
		(end 124.464826 -237.194344)
		(width 0.350012)
		(layer "F.Cu")
		(net "GND")
	)
	(segment
		(start 308.141624 -24.090884)
		(end 308.757574 -24.090884)
		(width 0.381)
		(layer "F.Cu")
		(net "GND")
	)
	(segment
		(start 384.627882 -241.510058)
		(end 385.094734 -241.24412)
		(width 0.350012)
		(layer "F.Cu")
		(net "GND")
	)
	(segment
		(start 114.629946 -55.282084)
		(end 115.260882 -55.282084)
		(width 0.4572)
		(layer "F.Cu")
		(net "GND")
	)
	(segment
		(start 122.117866 -243.94033)
		(end 122.584718 -243.674392)
		(width 0.350012)
		(layer "F.Cu")
		(net "GND")
	)
	(segment
		(start 352.846132 -396.710662)
		(end 352.198178 -396.520924)
		(width 0.254)
		(layer "F.Cu")
		(net "GND")
	)
	(segment
		(start 344.678 -237.460028)
		(end 344.211148 -237.19409)
		(width 0.350012)
		(layer "F.Cu")
		(net "GND")
	)
	(segment
		(start 8.447278 -137.25398)
		(end 8.437118 -137.25398)
		(width 0.3556)
		(layer "F.Cu")
		(net "GND")
	)
	(segment
		(start 88.747854 -228.55047)
		(end 88.281002 -228.284532)
		(width 0.350012)
		(layer "F.Cu")
		(net "GND")
	)
	(segment
		(start 64.83858 -53.44414)
		(end 64.83858 -53.82133)
		(width 0.381)
		(layer "F.Cu")
		(net "GND")
	)
	(segment
		(start 40.255698 -7.215886)
		(end 40.256968 -7.217156)
		(width 0.3556)
		(layer "F.Cu")
		(net "GND")
	)
	(segment
		(start 111.91494 -393.900152)
		(end 111.91494 -393.40917)
		(width 0.254)
		(layer "F.Cu")
		(net "GND")
	)
	(segment
		(start 343.268046 -246.370094)
		(end 342.801194 -246.104156)
		(width 0.350012)
		(layer "F.Cu")
		(net "GND")
	)
	(segment
		(start 360.657902 -227.74021)
		(end 361.124754 -227.474272)
		(width 0.350012)
		(layer "F.Cu")
		(net "GND")
	)
	(segment
		(start 384.89128 -398.542002)
		(end 384.37058 -398.542002)
		(width 0.254)
		(layer "F.Cu")
		(net "GND")
	)
	(segment
		(start 168.418256 -393.902946)
		(end 168.418256 -393.510262)
		(width 0.254)
		(layer "F.Cu")
		(net "GND")
	)
	(segment
		(start 67.234816 -403.830536)
		(end 67.234816 -402.923502)
		(width 0.381)
		(layer "F.Cu")
		(net "GND")
	)
	(segment
		(start 40.23995 -278.085296)
		(end 41.62425 -278.085296)
		(width 0.4572)
		(layer "F.Cu")
		(net "GND")
	)
	(segment
		(start 132.740654 -151.319484)
		(end 132.670804 -151.389334)
		(width 0.381)
		(layer "F.Cu")
		(net "GND")
	)
	(segment
		(start 146.122644 -391.77595)
		(end 146.122644 -391.304272)
		(width 0.254)
		(layer "F.Cu")
		(net "GND")
	)
	(segment
		(start 97.97796 -273.820382)
		(end 97.511108 -274.08632)
		(width 0.350012)
		(layer "F.Cu")
		(net "GND")
	)
	(segment
		(start 334.808068 -247.990106)
		(end 334.341216 -247.724168)
		(width 0.350012)
		(layer "F.Cu")
		(net "GND")
	)
	(segment
		(start 327.579228 -46.748954)
		(end 328.188828 -46.748954)
		(width 0.3556)
		(layer "F.Cu")
		(net "GND")
	)
	(segment
		(start 66.482214 -163.78682)
		(end 65.894204 -163.78682)
		(width 0.381)
		(layer "F.Cu")
		(net "GND")
	)
	(segment
		(start 82.467958 -261.670292)
		(end 82.001106 -261.93623)
		(width 0.350012)
		(layer "F.Cu")
		(net "GND")
	)
	(segment
		(start 147.82419 -99.155758)
		(end 147.16379 -99.155758)
		(width 0.4064)
		(layer "F.Cu")
		(net "GND")
	)
	(segment
		(start 84.278216 -143.785844)
		(end 85.024976 -143.785844)
		(width 0.4572)
		(layer "F.Cu")
		(net "GND")
	)
	(segment
		(start 143.88084 -40.803576)
		(end 143.243554 -40.803576)
		(width 0.381)
		(layer "F.Cu")
		(net "GND")
	)
	(segment
		(start 331.81798 -273.820128)
		(end 331.351128 -274.086066)
		(width 0.350012)
		(layer "F.Cu")
		(net "GND")
	)
	(segment
		(start 386.03809 -243.940076)
		(end 386.504942 -243.674138)
		(width 0.350012)
		(layer "F.Cu")
		(net "GND")
	)
	(segment
		(start 172.14342 -415.503868)
		(end 172.066966 -415.503868)
		(width 0.381)
		(layer "F.Cu")
		(net "GND")
	)
	(segment
		(start 120.238012 -252.04039)
		(end 120.70461 -251.774452)
		(width 0.350012)
		(layer "F.Cu")
		(net "GND")
	)
	(segment
		(start 120.758712 -16.50365)
		(end 121.653046 -16.50365)
		(width 0.4572)
		(layer "F.Cu")
		(net "GND")
	)
	(segment
		(start 350.31807 -252.040136)
		(end 349.851218 -251.774198)
		(width 0.350012)
		(layer "F.Cu")
		(net "GND")
	)
	(segment
		(start 356.728014 -282.730194)
		(end 356.261162 -282.996132)
		(width 0.350012)
		(layer "F.Cu")
		(net "GND")
	)
	(segment
		(start 301.871888 -20.99691)
		(end 301.871888 -20.36191)
		(width 0.4064)
		(layer "F.Cu")
		(net "GND")
	)
	(segment
		(start 47.391066 -390.160002)
		(end 47.391066 -390.231122)
		(width 0.254)
		(layer "F.Cu")
		(net "GND")
	)
	(segment
		(start 118.357904 -250.420378)
		(end 118.824756 -250.15444)
		(width 0.350012)
		(layer "F.Cu")
		(net "GND")
	)
	(segment
		(start 391.208006 -231.789986)
		(end 391.674858 -231.524048)
		(width 0.350012)
		(layer "F.Cu")
		(net "GND")
	)
	(segment
		(start 100.497894 -247.180354)
		(end 100.031042 -246.914416)
		(width 0.350012)
		(layer "F.Cu")
		(net "GND")
	)
	(segment
		(start 366.297972 -237.460028)
		(end 366.764824 -237.19409)
		(width 0.350012)
		(layer "F.Cu")
		(net "GND")
	)
	(segment
		(start 288.926778 -348.794324)
		(end 289.179762 -348.54134)
		(width 0.2286)
		(layer "F.Cu")
		(net "GND")
	)
	(segment
		(start 113.187988 -223.690434)
		(end 113.65484 -223.424496)
		(width 0.350012)
		(layer "F.Cu")
		(net "GND")
	)
	(segment
		(start 327.117964 -277.060152)
		(end 326.651112 -277.32609)
		(width 0.350012)
		(layer "F.Cu")
		(net "GND")
	)
	(segment
		(start 87.3379 -239.080294)
		(end 86.871048 -238.814356)
		(width 0.350012)
		(layer "F.Cu")
		(net "GND")
	)
	(segment
		(start 12.296648 -136.814306)
		(end 12.296648 -135.91413)
		(width 0.254)
		(layer "F.Cu")
		(net "GND")
	)
	(segment
		(start 330.108052 -251.23013)
		(end 329.6412 -250.964192)
		(width 0.350012)
		(layer "F.Cu")
		(net "GND")
	)
	(segment
		(start 150.690072 -384.617722)
		(end 150.098252 -384.617722)
		(width 0.254)
		(layer "F.Cu")
		(net "GND")
	)
	(segment
		(start 100.327968 -273.010376)
		(end 99.861116 -273.276314)
		(width 0.350012)
		(layer "F.Cu")
		(net "GND")
	)
	(segment
		(start 36.795964 -199.8853)
		(end 35.411664 -199.8853)
		(width 0.4572)
		(layer "F.Cu")
		(net "GND")
	)
	(segment
		(start 95.797878 -222.880428)
		(end 95.331026 -222.61449)
		(width 0.350012)
		(layer "F.Cu")
		(net "GND")
	)
	(segment
		(start 48.070516 -384.617722)
		(end 48.662336 -384.617722)
		(width 0.254)
		(layer "F.Cu")
		(net "GND")
	)
	(segment
		(start 344.99804 -396.520924)
		(end 344.446098 -396.710662)
		(width 0.254)
		(layer "F.Cu")
		(net "GND")
	)
	(segment
		(start 344.446098 -396.710662)
		(end 343.798144 -396.520924)
		(width 0.254)
		(layer "F.Cu")
		(net "GND")
	)
	(segment
		(start 102.378002 -229.360476)
		(end 101.91115 -229.094538)
		(width 0.350012)
		(layer "F.Cu")
		(net "GND")
	)
	(segment
		(start 333.697834 -265.720068)
		(end 333.230982 -265.986006)
		(width 0.350012)
		(layer "F.Cu")
		(net "GND")
	)
	(segment
		(start 117.888004 -233.410252)
		(end 118.354856 -233.144314)
		(width 0.350012)
		(layer "F.Cu")
		(net "GND")
	)
	(segment
		(start 116.77777 -277.060406)
		(end 117.244622 -277.326344)
		(width 0.350012)
		(layer "F.Cu")
		(net "GND")
	)
	(segment
		(start 394.327888 -268.150086)
		(end 394.982954 -268.150086)
		(width 0.350012)
		(layer "F.Cu")
		(net "GND")
	)
	(segment
		(start 299.82414 -237.285022)
		(end 298.43984 -237.285022)
		(width 0.4572)
		(layer "F.Cu")
		(net "GND")
	)
	(segment
		(start 32.601662 -418.239448)
		(end 32.601662 -418.849048)
		(width 0.3556)
		(layer "F.Cu")
		(net "GND")
	)
	(segment
		(start 191.160146 -227.935282)
		(end 189.775846 -227.935282)
		(width 0.4572)
		(layer "F.Cu")
		(net "GND")
	)
	(segment
		(start 154.898344 -386.6388)
		(end 154.206194 -386.449062)
		(width 0.254)
		(layer "F.Cu")
		(net "GND")
	)
	(segment
		(start 92.037916 -242.320318)
		(end 91.571064 -242.05438)
		(width 0.350012)
		(layer "F.Cu")
		(net "GND")
	)
	(segment
		(start 336.245454 -399.663158)
		(end 336.344006 -399.76171)
		(width 0.254)
		(layer "F.Cu")
		(net "GND")
	)
	(segment
		(start 130.407918 -274.630388)
		(end 130.87477 -274.896326)
		(width 0.350012)
		(layer "F.Cu")
		(net "GND")
	)
	(segment
		(start 76.0603 -385.58216)
		(end 76.5937 -385.58216)
		(width 0.254)
		(layer "F.Cu")
		(net "GND")
	)
	(segment
		(start 116.77777 -281.920442)
		(end 117.244622 -282.18638)
		(width 0.350012)
		(layer "F.Cu")
		(net "GND")
	)
	(segment
		(start 123.357894 -291.64026)
		(end 123.824746 -291.906198)
		(width 0.350012)
		(layer "F.Cu")
		(net "GND")
	)
	(segment
		(start 128.52781 -269.770352)
		(end 128.994662 -270.03629)
		(width 0.350012)
		(layer "F.Cu")
		(net "GND")
	)
	(segment
		(start 130.107944 -247.99036)
		(end 130.574796 -247.724422)
		(width 0.350012)
		(layer "F.Cu")
		(net "GND")
	)
	(segment
		(start 125.291342 -390.160002)
		(end 124.770642 -390.160002)
		(width 0.254)
		(layer "F.Cu")
		(net "GND")
	)
	(segment
		(start 422.462198 -396.51305)
		(end 422.162224 -396.813024)
		(width 0.254)
		(layer "F.Cu")
		(net "GND")
	)
	(segment
		(start 363.307884 -273.010122)
		(end 363.774736 -273.27606)
		(width 0.350012)
		(layer "F.Cu")
		(net "GND")
	)
	(segment
		(start 204.241146 -338.79409)
		(end 204.254608 -338.807552)
		(width 0.4572)
		(layer "F.Cu")
		(net "GND")
	)
	(segment
		(start 127.117856 -268.960346)
		(end 127.584708 -269.226284)
		(width 0.350012)
		(layer "F.Cu")
		(net "GND")
	)
	(segment
		(start 450.088 -303.585118)
		(end 451.4723 -303.585118)
		(width 0.4572)
		(layer "F.Cu")
		(net "GND")
	)
	(segment
		(start 108.317792 -272.20037)
		(end 107.85094 -272.466308)
		(width 0.350012)
		(layer "F.Cu")
		(net "GND")
	)
	(segment
		(start 384.627882 -233.409998)
		(end 385.094734 -233.14406)
		(width 0.350012)
		(layer "F.Cu")
		(net "GND")
	)
	(segment
		(start 126.177802 -285.160466)
		(end 126.644654 -285.426404)
		(width 0.350012)
		(layer "F.Cu")
		(net "GND")
	)
	(segment
		(start 353.607878 -251.23013)
		(end 353.141026 -250.964192)
		(width 0.350012)
		(layer "F.Cu")
		(net "GND")
	)
	(segment
		(start 166.921942 -437.432196)
		(end 167.556942 -437.432196)
		(width 0.4318)
		(layer "F.Cu")
		(net "GND")
	)
	(segment
		(start 51.884072 -277.235412)
		(end 50.499772 -277.235412)
		(width 0.4572)
		(layer "F.Cu")
		(net "GND")
	)
	(segment
		(start 106.437938 -288.400236)
		(end 105.971086 -288.666174)
		(width 0.350012)
		(layer "F.Cu")
		(net "GND")
	)
	(segment
		(start 450.984112 -397.277082)
		(end 450.869558 -397.162528)
		(width 0.2286)
		(layer "F.Cu")
		(net "GND")
	)
	(segment
		(start 90.457782 -273.820382)
		(end 89.99093 -274.08632)
		(width 0.350012)
		(layer "F.Cu")
		(net "GND")
	)
	(segment
		(start 135.14705 -13.599922)
		(end 135.14705 -12.496292)
		(width 0.4572)
		(layer "F.Cu")
		(net "GND")
	)
	(segment
		(start 287.10763 -425.382436)
		(end 286.737806 -425.382436)
		(width 0.381)
		(layer "F.Cu")
		(net "GND")
	)
	(segment
		(start 368.947954 -290.83)
		(end 369.414806 -291.095938)
		(width 0.350012)
		(layer "F.Cu")
		(net "GND")
	)
	(segment
		(start 326.81799 -237.460028)
		(end 326.351138 -237.19409)
		(width 0.350012)
		(layer "F.Cu")
		(net "GND")
	)
	(segment
		(start 393.048236 -12.37488)
		(end 393.048236 -12.374118)
		(width 0.3556)
		(layer "F.Cu")
		(net "GND")
	)
	(segment
		(start 84.347812 -290.830254)
		(end 83.88096 -291.096192)
		(width 0.350012)
		(layer "F.Cu")
		(net "GND")
	)
	(segment
		(start 372.238016 -265.720068)
		(end 372.704868 -265.986006)
		(width 0.350012)
		(layer "F.Cu")
		(net "GND")
	)
	(segment
		(start 83.470242 -338.043774)
		(end 83.941158 -337.572858)
		(width 0.2286)
		(layer "F.Cu")
		(net "GND")
	)
	(segment
		(start 400.24685 -12.372848)
		(end 400.24685 -11.26998)
		(width 0.3556)
		(layer "F.Cu")
		(net "GND")
	)
	(segment
		(start 331.987906 -254.470154)
		(end 331.521054 -254.204216)
		(width 0.350012)
		(layer "F.Cu")
		(net "GND")
	)
	(segment
		(start 97.677986 -237.460282)
		(end 97.211134 -237.194344)
		(width 0.350012)
		(layer "F.Cu")
		(net "GND")
	)
	(segment
		(start 402.248878 -398.613122)
		(end 402.248878 -398.01292)
		(width 0.254)
		(layer "F.Cu")
		(net "GND")
	)
	(segment
		(start 139.86764 -387.592316)
		(end 139.86764 -387.130798)
		(width 0.254)
		(layer "F.Cu")
		(net "GND")
	)
	(segment
		(start 367.787936 -401.37715)
		(end 367.914936 -401.25015)
		(width 0.254)
		(layer "F.Cu")
		(net "GND")
	)
	(segment
		(start 25.152096 -294.235378)
		(end 26.536396 -294.235378)
		(width 0.4572)
		(layer "F.Cu")
		(net "GND")
	)
	(segment
		(start 48.918114 -391.281158)
		(end 49.016666 -391.37971)
		(width 0.254)
		(layer "F.Cu")
		(net "GND")
	)
	(segment
		(start 386.338064 -275.44014)
		(end 386.804916 -275.706078)
		(width 0.350012)
		(layer "F.Cu")
		(net "GND")
	)
	(segment
		(start 377.878086 -273.820128)
		(end 378.344938 -274.086066)
		(width 0.350012)
		(layer "F.Cu")
		(net "GND")
	)
	(segment
		(start 191.160146 -312.085228)
		(end 189.775846 -312.085228)
		(width 0.4572)
		(layer "F.Cu")
		(net "GND")
	)
	(segment
		(start 295.724072 -312.935112)
		(end 297.108372 -312.935112)
		(width 0.4572)
		(layer "F.Cu")
		(net "GND")
	)
	(segment
		(start 427.456092 -231.335072)
		(end 428.840392 -231.335072)
		(width 0.4572)
		(layer "F.Cu")
		(net "GND")
	)
	(segment
		(start 378.962412 -392.999722)
		(end 379.570488 -392.999722)
		(width 0.254)
		(layer "F.Cu")
		(net "GND")
	)
	(segment
		(start 370.828062 -266.530074)
		(end 371.294914 -266.796012)
		(width 0.350012)
		(layer "F.Cu")
		(net "GND")
	)
	(segment
		(start 134.291832 -387.069076)
		(end 133.576822 -387.069076)
		(width 0.254)
		(layer "F.Cu")
		(net "GND")
	)
	(segment
		(start 93.747844 -266.530328)
		(end 93.280992 -266.796266)
		(width 0.350012)
		(layer "F.Cu")
		(net "GND")
	)
	(segment
		(start 383.048002 -264.910062)
		(end 383.514854 -265.176)
		(width 0.350012)
		(layer "F.Cu")
		(net "GND")
	)
	(segment
		(start 328.697844 -235.840016)
		(end 328.231246 -235.574078)
		(width 0.350012)
		(layer "F.Cu")
		(net "GND")
	)
	(segment
		(start 366.64392 -396.679674)
		(end 367.290858 -396.679674)
		(width 0.254)
		(layer "F.Cu")
		(net "GND")
	)
	(segment
		(start 151.091392 -109.781086)
		(end 152.187656 -109.781086)
		(width 0.3556)
		(layer "F.Cu")
		(net "GND")
	)
	(segment
		(start 204.254608 -338.807552)
		(end 204.902054 -338.807552)
		(width 0.4572)
		(layer "F.Cu")
		(net "GND")
	)
	(segment
		(start 127.305054 -53.15839)
		(end 126.689104 -53.15839)
		(width 0.4572)
		(layer "F.Cu")
		(net "GND")
	)
	(segment
		(start 77.767942 -279.490424)
		(end 77.112876 -279.490424)
		(width 0.350012)
		(layer "F.Cu")
		(net "GND")
	)
	(segment
		(start 138.098022 -237.460282)
		(end 138.564874 -237.194344)
		(width 0.350012)
		(layer "F.Cu")
		(net "GND")
	)
	(segment
		(start 323.87286 -336.813144)
		(end 324.301358 -336.813144)
		(width 0.2286)
		(layer "F.Cu")
		(net "GND")
	)
	(segment
		(start 347.797882 -278.680164)
		(end 347.33103 -278.946102)
		(width 0.350012)
		(layer "F.Cu")
		(net "GND")
	)
	(segment
		(start 104.257856 -247.180354)
		(end 103.791004 -246.914416)
		(width 0.350012)
		(layer "F.Cu")
		(net "GND")
	)
	(segment
		(start 110.83798 -230.980234)
		(end 110.371128 -230.71455)
		(width 0.350012)
		(layer "F.Cu")
		(net "GND")
	)
	(segment
		(start 134.16788 -294.070278)
		(end 134.634732 -294.336216)
		(width 0.350012)
		(layer "F.Cu")
		(net "GND")
	)
	(segment
		(start 416.468052 -274.684998)
		(end 415.083752 -274.684998)
		(width 0.4572)
		(layer "F.Cu")
		(net "GND")
	)
	(segment
		(start 122.370596 -388.138924)
		(end 123.01855 -388.328662)
		(width 0.254)
		(layer "F.Cu")
		(net "GND")
	)
	(segment
		(start 48.918114 -383.402586)
		(end 48.918114 -382.951482)
		(width 0.254)
		(layer "F.Cu")
		(net "GND")
	)
	(segment
		(start 147.146264 -388.328662)
		(end 146.49831 -388.08152)
		(width 0.254)
		(layer "F.Cu")
		(net "GND")
	)
	(segment
		(start 179.516024 -303.585372)
		(end 180.900324 -303.585372)
		(width 0.4572)
		(layer "F.Cu")
		(net "GND")
	)
	(segment
		(start 38.45687 -12.372848)
		(end 38.45687 -11.26998)
		(width 0.3556)
		(layer "F.Cu")
		(net "GND")
	)
	(segment
		(start 415.698178 -398.542002)
		(end 415.018982 -398.542002)
		(width 0.254)
		(layer "F.Cu")
		(net "GND")
	)
	(segment
		(start 360.657902 -252.040136)
		(end 361.124754 -251.774198)
		(width 0.350012)
		(layer "F.Cu")
		(net "GND")
	)
	(segment
		(start 55.328058 -306.135278)
		(end 56.712358 -306.135278)
		(width 0.4572)
		(layer "F.Cu")
		(net "GND")
	)
	(segment
		(start 89.047828 -273.010376)
		(end 88.580976 -273.276314)
		(width 0.350012)
		(layer "F.Cu")
		(net "GND")
	)
	(segment
		(start 454.188068 -277.235158)
		(end 452.803768 -277.235158)
		(width 0.4572)
		(layer "F.Cu")
		(net "GND")
	)
	(segment
		(start 53.268372 -12.374118)
		(end 53.267102 -12.372848)
		(width 0.3556)
		(layer "F.Cu")
		(net "GND")
	)
	(segment
		(start 391.50798 -274.630134)
		(end 391.974832 -274.896072)
		(width 0.350012)
		(layer "F.Cu")
		(net "GND")
	)
	(segment
		(start 13.778738 -389.329168)
		(end 14.162024 -389.329168)
		(width 0.2032)
		(layer "F.Cu")
		(net "GND")
	)
	(segment
		(start 65.378584 -386.449062)
		(end 64.870584 -386.6388)
		(width 0.254)
		(layer "F.Cu")
		(net "GND")
	)
	(segment
		(start 105.19791 -227.740464)
		(end 104.731058 -227.474526)
		(width 0.350012)
		(layer "F.Cu")
		(net "GND")
	)
	(segment
		(start 336.687922 -231.789986)
		(end 336.22107 -231.524048)
		(width 0.350012)
		(layer "F.Cu")
		(net "GND")
	)
	(segment
		(start 339.977984 -252.040136)
		(end 339.511132 -251.774198)
		(width 0.350012)
		(layer "F.Cu")
		(net "GND")
	)
	(segment
		(start 114.127788 -247.99036)
		(end 114.59464 -247.724422)
		(width 0.350012)
		(layer "F.Cu")
		(net "GND")
	)
	(segment
		(start 344.644472 -21.03501)
		(end 344.644472 -21.672296)
		(width 0.4572)
		(layer "F.Cu")
		(net "GND")
	)
	(segment
		(start 387.448044 -246.370094)
		(end 387.914896 -246.104156)
		(width 0.350012)
		(layer "F.Cu")
		(net "GND")
	)
	(segment
		(start 341.387938 -231.789986)
		(end 340.921086 -231.524048)
		(width 0.350012)
		(layer "F.Cu")
		(net "GND")
	)
	(segment
		(start 108.317792 -270.580358)
		(end 107.85094 -270.846296)
		(width 0.350012)
		(layer "F.Cu")
		(net "GND")
	)
	(segment
		(start 307.368194 -202.434952)
		(end 305.983894 -202.434952)
		(width 0.4572)
		(layer "F.Cu")
		(net "GND")
	)
	(segment
		(start 83.577938 -240.700306)
		(end 83.111086 -240.434368)
		(width 0.350012)
		(layer "F.Cu")
		(net "GND")
	)
	(segment
		(start 335.90611 -394.831062)
		(end 335.148682 -395.012926)
		(width 0.254)
		(layer "F.Cu")
		(net "GND")
	)
	(segment
		(start 414.14573 -391.784586)
		(end 414.14573 -391.333482)
		(width 0.254)
		(layer "F.Cu")
		(net "GND")
	)
	(segment
		(start 206.248 -312.085228)
		(end 204.8637 -312.085228)
		(width 0.4572)
		(layer "F.Cu")
		(net "GND")
	)
	(segment
		(start 146.087846 -223.690434)
		(end 146.554698 -223.424496)
		(width 0.350012)
		(layer "F.Cu")
		(net "GND")
	)
	(segment
		(start 256.169922 -49.882298)
		(end 256.439924 -49.612296)
		(width 0.254)
		(layer "F.Cu")
		(net "GND")
	)
	(segment
		(start 292.280086 -284.034992)
		(end 290.895786 -284.034992)
		(width 0.4572)
		(layer "F.Cu")
		(net "GND")
	)
	(segment
		(start 46.87062 -383.974848)
		(end 46.87062 -384.617722)
		(width 0.254)
		(layer "F.Cu")
		(net "GND")
	)
	(segment
		(start 385.018534 -396.710662)
		(end 384.37058 -396.520924)
		(width 0.254)
		(layer "F.Cu")
		(net "GND")
	)
	(segment
		(start 86.868 -246.370348)
		(end 86.401148 -246.10441)
		(width 0.350012)
		(layer "F.Cu")
		(net "GND")
	)
	(segment
		(start 113.187988 -247.99036)
		(end 113.65484 -247.724422)
		(width 0.350012)
		(layer "F.Cu")
		(net "GND")
	)
	(segment
		(start 390.737852 -253.660148)
		(end 391.204704 -253.39421)
		(width 0.350012)
		(layer "F.Cu")
		(net "GND")
	)
	(segment
		(start 122.018044 -382.951482)
		(end 122.116596 -382.85293)
		(width 0.254)
		(layer "F.Cu")
		(net "GND")
	)
	(segment
		(start 48.918114 -383.622296)
		(end 49.218088 -383.92227)
		(width 0.254)
		(layer "F.Cu")
		(net "GND")
	)
	(segment
		(start 111.137954 -275.440394)
		(end 110.671102 -275.706332)
		(width 0.350012)
		(layer "F.Cu")
		(net "GND")
	)
	(segment
		(start 15.98422 -71.847964)
		(end 15.98422 -71.210678)
		(width 0.4064)
		(layer "F.Cu")
		(net "GND")
	)
	(segment
		(start 83.877912 -272.20037)
		(end 83.41106 -272.466308)
		(width 0.350012)
		(layer "F.Cu")
		(net "GND")
	)
	(segment
		(start 58.804556 -41.15562)
		(end 58.53303 -40.884094)
		(width 0.4572)
		(layer "F.Cu")
		(net "GND")
	)
	(segment
		(start 92.507816 -225.310446)
		(end 92.040964 -225.044508)
		(width 0.350012)
		(layer "F.Cu")
		(net "GND")
	)
	(segment
		(start 372.407942 -249.610118)
		(end 372.874794 -249.34418)
		(width 0.350012)
		(layer "F.Cu")
		(net "GND")
	)
	(segment
		(start 304.01895 -359.283)
		(end 304.01895 -360.426)
		(width 0.381)
		(layer "F.Cu")
		(net "GND")
	)
	(segment
		(start 83.577938 -234.220258)
		(end 83.111086 -233.95432)
		(width 0.350012)
		(layer "F.Cu")
		(net "GND")
	)
	(segment
		(start 11.351768 -73.694798)
		(end 12.164568 -73.694798)
		(width 0.4572)
		(layer "F.Cu")
		(net "GND")
	)
	(segment
		(start 417.745672 -392.004296)
		(end 418.045646 -392.30427)
		(width 0.254)
		(layer "F.Cu")
		(net "GND")
	)
	(segment
		(start 158.145734 -391.281158)
		(end 158.445708 -390.761474)
		(width 0.254)
		(layer "F.Cu")
		(net "GND")
	)
	(segment
		(start 117.570504 -388.138924)
		(end 117.018562 -388.328662)
		(width 0.254)
		(layer "F.Cu")
		(net "GND")
	)
	(segment
		(start 384.927856 -276.250146)
		(end 385.394708 -276.516084)
		(width 0.350012)
		(layer "F.Cu")
		(net "GND")
	)
	(segment
		(start 11.51636 -51.369214)
		(end 11.533124 -51.369214)
		(width 0.4572)
		(layer "F.Cu")
		(net "GND")
	)
	(segment
		(start 390.737852 -255.28016)
		(end 391.204704 -255.014222)
		(width 0.350012)
		(layer "F.Cu")
		(net "GND")
	)
	(segment
		(start 331.461364 -143.005302)
		(end 331.253592 -142.79753)
		(width 0.254)
		(layer "F.Cu")
		(net "GND")
	)
	(segment
		(start 183.616092 -302.735234)
		(end 182.231792 -302.735234)
		(width 0.4572)
		(layer "F.Cu")
		(net "GND")
	)
	(segment
		(start 343.268046 -251.23013)
		(end 342.801194 -250.964192)
		(width 0.350012)
		(layer "F.Cu")
		(net "GND")
	)
	(segment
		(start 252.585728 -106.905044)
		(end 253.042928 -107.362244)
		(width 0.4572)
		(layer "F.Cu")
		(net "GND")
	)
	(segment
		(start 123.997974 -245.560342)
		(end 124.464826 -245.294404)
		(width 0.350012)
		(layer "F.Cu")
		(net "GND")
	)
	(segment
		(start 383.048002 -290.83)
		(end 383.514854 -291.095938)
		(width 0.350012)
		(layer "F.Cu")
		(net "GND")
	)
	(segment
		(start 95.081598 -352.475038)
		(end 95.80626 -352.475038)
		(width 0.381)
		(layer "F.Cu")
		(net "GND")
	)
	(segment
		(start 164.041328 -428.721774)
		(end 163.160964 -428.721774)
		(width 0.3048)
		(layer "F.Cu")
		(net "GND")
	)
	(segment
		(start 142.467838 -402.773896)
		(end 143.524478 -403.830536)
		(width 0.381)
		(layer "F.Cu")
		(net "GND")
	)
	(segment
		(start 385.517898 -392.30427)
		(end 385.570476 -392.999722)
		(width 0.254)
		(layer "F.Cu")
		(net "GND")
	)
	(segment
		(start 387.970522 -392.999722)
		(end 388.562342 -392.999722)
		(width 0.254)
		(layer "F.Cu")
		(net "GND")
	)
	(segment
		(start 359.059988 -416.792918)
		(end 359.059988 -417.448238)
		(width 0.381)
		(layer "F.Cu")
		(net "GND")
	)
	(segment
		(start 338.6455 -399.663158)
		(end 338.945474 -399.143474)
		(width 0.254)
		(layer "F.Cu")
		(net "GND")
	)
	(segment
		(start 339.845396 -391.784586)
		(end 339.845396 -391.333482)
		(width 0.2032)
		(layer "F.Cu")
		(net "GND")
	)
	(segment
		(start 338.097876 -232.599992)
		(end 337.631024 -232.334054)
		(width 0.350012)
		(layer "F.Cu")
		(net "GND")
	)
	(segment
		(start 336.987896 -281.110182)
		(end 336.521044 -281.37612)
		(width 0.350012)
		(layer "F.Cu")
		(net "GND")
	)
	(segment
		(start 405.64816 -12.374118)
		(end 405.64689 -12.372848)
		(width 0.3556)
		(layer "F.Cu")
		(net "GND")
	)
	(segment
		(start 132.927852 -235.030264)
		(end 133.394704 -234.764326)
		(width 0.350012)
		(layer "F.Cu")
		(net "GND")
	)
	(segment
		(start 359.078022 -272.200116)
		(end 358.61117 -272.466054)
		(width 0.350012)
		(layer "F.Cu")
		(net "GND")
	)
	(segment
		(start 347.983048 -342.999822)
		(end 348.014036 -342.999822)
		(width 0.2286)
		(layer "F.Cu")
		(net "GND")
	)
	(segment
		(start 82.937858 -268.960346)
		(end 82.471006 -269.226284)
		(width 0.350012)
		(layer "F.Cu")
		(net "GND")
	)
	(segment
		(start 360.957876 -265.720068)
		(end 361.424728 -265.986006)
		(width 0.350012)
		(layer "F.Cu")
		(net "GND")
	)
	(segment
		(start 21.70811 -218.585288)
		(end 20.32381 -218.585288)
		(width 0.4572)
		(layer "F.Cu")
		(net "GND")
	)
	(segment
		(start 344.508074 -268.150086)
		(end 344.041222 -268.416024)
		(width 0.350012)
		(layer "F.Cu")
		(net "GND")
	)
	(segment
		(start 435.000146 -221.985078)
		(end 436.384446 -221.985078)
		(width 0.4572)
		(layer "F.Cu")
		(net "GND")
	)
	(segment
		(start 354.545392 -392.30427)
		(end 354.245418 -391.784586)
		(width 0.254)
		(layer "F.Cu")
		(net "GND")
	)
	(segment
		(start 128.370584 -384.617722)
		(end 127.762254 -384.617722)
		(width 0.254)
		(layer "F.Cu")
		(net "GND")
	)
	(segment
		(start 111.107982 -175.106584)
		(end 110.609634 -175.604932)
		(width 0.2286)
		(layer "F.Cu")
		(net "GND")
	)
	(segment
		(start 344.03792 -294.88003)
		(end 343.571068 -295.145968)
		(width 0.350012)
		(layer "F.Cu")
		(net "GND")
	)
	(segment
		(start 405.64689 -11.26998)
		(end 405.64689 -10.16635)
		(width 0.3556)
		(layer "F.Cu")
		(net "GND")
	)
	(segment
		(start 79.6925 -385.87553)
		(end 79.537052 -386.030978)
		(width 0.254)
		(layer "F.Cu")
		(net "GND")
	)
	(segment
		(start 299.82414 -239.835182)
		(end 298.43984 -239.835182)
		(width 0.4572)
		(layer "F.Cu")
		(net "GND")
	)
	(segment
		(start 227.19157 -291.863526)
		(end 227.19157 -291.406326)
		(width 0.4572)
		(layer "F.Cu")
		(net "GND")
	)
	(segment
		(start 375.057924 -262.480044)
		(end 375.524776 -262.745982)
		(width 0.350012)
		(layer "F.Cu")
		(net "GND")
	)
	(segment
		(start 128.52781 -279.490424)
		(end 128.994662 -279.756362)
		(width 0.350012)
		(layer "F.Cu")
		(net "GND")
	)
	(segment
		(start 90.627962 -225.310446)
		(end 90.16111 -225.044508)
		(width 0.350012)
		(layer "F.Cu")
		(net "GND")
	)
	(segment
		(start 126.347982 -254.470408)
		(end 126.814834 -254.20447)
		(width 0.350012)
		(layer "F.Cu")
		(net "GND")
	)
	(segment
		(start 163.044124 -391.37971)
		(end 162.945572 -391.281158)
		(width 0.254)
		(layer "F.Cu")
		(net "GND")
	)
	(segment
		(start 124.467874 -249.610372)
		(end 124.934726 -249.344434)
		(width 0.350012)
		(layer "F.Cu")
		(net "GND")
	)
	(segment
		(start 108.521754 -327.474326)
		(end 108.521754 -328.103738)
		(width 0.4572)
		(layer "F.Cu")
		(net "GND")
	)
	(segment
		(start 151.245824 -390.761474)
		(end 151.298402 -390.160002)
		(width 0.254)
		(layer "F.Cu")
		(net "GND")
	)
	(segment
		(start 336.687922 -246.370094)
		(end 336.22107 -246.104156)
		(width 0.350012)
		(layer "F.Cu")
		(net "GND")
	)
	(segment
		(start 139.80795 -284.35046)
		(end 140.274802 -284.616398)
		(width 0.350012)
		(layer "F.Cu")
		(net "GND")
	)
	(segment
		(start 98.598482 -390.160002)
		(end 99.273106 -390.160002)
		(width 0.254)
		(layer "F.Cu")
		(net "GND")
	)
	(segment
		(start 46.818042 -390.761474)
		(end 46.518068 -391.281158)
		(width 0.254)
		(layer "F.Cu")
		(net "GND")
	)
	(segment
		(start 427.456092 -306.135024)
		(end 428.840392 -306.135024)
		(width 0.4572)
		(layer "F.Cu")
		(net "GND")
	)
	(segment
		(start 406.098248 -398.542002)
		(end 405.419052 -398.542002)
		(width 0.254)
		(layer "F.Cu")
		(net "GND")
	)
	(segment
		(start 194.604132 -278.085296)
		(end 195.988432 -278.085296)
		(width 0.4572)
		(layer "F.Cu")
		(net "GND")
	)
	(segment
		(start 386.338064 -267.34008)
		(end 386.804916 -267.606018)
		(width 0.350012)
		(layer "F.Cu")
		(net "GND")
	)
	(segment
		(start 277.192232 -302.73498)
		(end 275.807932 -302.73498)
		(width 0.4572)
		(layer "F.Cu")
		(net "GND")
	)
	(segment
		(start 353.045522 -392.004296)
		(end 353.345496 -392.30427)
		(width 0.254)
		(layer "F.Cu")
		(net "GND")
	)
	(segment
		(start 92.037916 -239.080294)
		(end 91.571064 -238.814356)
		(width 0.350012)
		(layer "F.Cu")
		(net "GND")
	)
	(segment
		(start 330.108052 -228.550216)
		(end 329.6412 -228.284278)
		(width 0.350012)
		(layer "F.Cu")
		(net "GND")
	)
	(segment
		(start 40.23995 -221.985332)
		(end 41.62425 -221.985332)
		(width 0.4572)
		(layer "F.Cu")
		(net "GND")
	)
	(segment
		(start 25.152096 -303.585372)
		(end 26.536396 -303.585372)
		(width 0.4572)
		(layer "F.Cu")
		(net "GND")
	)
	(segment
		(start 338.56803 -235.03001)
		(end 338.101178 -234.764072)
		(width 0.350012)
		(layer "F.Cu")
		(net "GND")
	)
	(segment
		(start 357.318056 -401.892262)
		(end 357.142796 -401.717002)
		(width 0.254)
		(layer "F.Cu")
		(net "GND")
	)
	(segment
		(start 108.940346 -56.452262)
		(end 110.013496 -56.452262)
		(width 0.4572)
		(layer "F.Cu")
		(net "GND")
	)
	(segment
		(start 84.047838 -231.79024)
		(end 83.580986 -231.524302)
		(width 0.350012)
		(layer "F.Cu")
		(net "GND")
	)
	(segment
		(start 330.408026 -277.870158)
		(end 329.941174 -278.136096)
		(width 0.350012)
		(layer "F.Cu")
		(net "GND")
	)
	(segment
		(start 273.092164 -221.985078)
		(end 274.476464 -221.985078)
		(width 0.4572)
		(layer "F.Cu")
		(net "GND")
	)
	(segment
		(start 77.767942 -294.070278)
		(end 77.112876 -294.070278)
		(width 0.350012)
		(layer "F.Cu")
		(net "GND")
	)
	(segment
		(start 105.967784 -284.35046)
		(end 105.500932 -284.616398)
		(width 0.350012)
		(layer "F.Cu")
		(net "GND")
	)
	(segment
		(start 348.437962 -232.599992)
		(end 347.97111 -232.334054)
		(width 0.350012)
		(layer "F.Cu")
		(net "GND")
	)
	(segment
		(start 139.977876 -253.660402)
		(end 140.444728 -253.394464)
		(width 0.350012)
		(layer "F.Cu")
		(net "GND")
	)
	(segment
		(start 93.91777 -239.080294)
		(end 93.450918 -238.814356)
		(width 0.350012)
		(layer "F.Cu")
		(net "GND")
	)
	(segment
		(start 353.907852 -277.870158)
		(end 353.441 -278.136096)
		(width 0.350012)
		(layer "F.Cu")
		(net "GND")
	)
	(segment
		(start 352.497898 -291.640006)
		(end 352.031046 -291.905944)
		(width 0.350012)
		(layer "F.Cu")
		(net "GND")
	)
	(segment
		(start 355.362002 -393.513056)
		(end 355.362002 -392.913108)
		(width 0.254)
		(layer "F.Cu")
		(net "GND")
	)
	(segment
		(start 139.80795 -264.910316)
		(end 140.274802 -265.176254)
		(width 0.350012)
		(layer "F.Cu")
		(net "GND")
	)
	(segment
		(start 424.165522 -7.215124)
		(end 424.165522 -7.215886)
		(width 0.3556)
		(layer "F.Cu")
		(net "GND")
	)
	(segment
		(start 338.097876 -230.97998)
		(end 337.631024 -230.714042)
		(width 0.350012)
		(layer "F.Cu")
		(net "GND")
	)
	(segment
		(start 363.00791 -226.930204)
		(end 363.474762 -226.664266)
		(width 0.350012)
		(layer "F.Cu")
		(net "GND")
	)
	(segment
		(start 339.808058 -294.070024)
		(end 339.341206 -294.335962)
		(width 0.350012)
		(layer "F.Cu")
		(net "GND")
	)
	(segment
		(start 45.657008 -12.372848)
		(end 45.657008 -11.26998)
		(width 0.3556)
		(layer "F.Cu")
		(net "GND")
	)
	(segment
		(start 123.21794 -383.402586)
		(end 123.21794 -382.951482)
		(width 0.254)
		(layer "F.Cu")
		(net "GND")
	)
	(segment
		(start 90.927936 -276.2504)
		(end 90.461084 -276.516338)
		(width 0.350012)
		(layer "F.Cu")
		(net "GND")
	)
	(segment
		(start 134.80796 -254.470408)
		(end 135.274812 -254.20447)
		(width 0.350012)
		(layer "F.Cu")
		(net "GND")
	)
	(segment
		(start 391.83945 -138.142472)
		(end 391.897108 -138.084814)
		(width 0.254)
		(layer "F.Cu")
		(net "GND")
	)
	(segment
		(start 348.268036 -289.209988)
		(end 347.801184 -289.475926)
		(width 0.350012)
		(layer "F.Cu")
		(net "GND")
	)
	(segment
		(start 330.108052 -249.610118)
		(end 329.6412 -249.34418)
		(width 0.350012)
		(layer "F.Cu")
		(net "GND")
	)
	(segment
		(start 334.929226 -395.613128)
		(end 335.148682 -395.613128)
		(width 0.254)
		(layer "F.Cu")
		(net "GND")
	)
	(segment
		(start 100.327968 -266.530328)
		(end 99.861116 -266.796266)
		(width 0.350012)
		(layer "F.Cu")
		(net "GND")
	)
	(segment
		(start 120.238012 -247.180354)
		(end 120.70461 -246.914416)
		(width 0.350012)
		(layer "F.Cu")
		(net "GND")
	)
	(segment
		(start 94.217998 -277.060406)
		(end 93.751146 -277.326344)
		(width 0.350012)
		(layer "F.Cu")
		(net "GND")
	)
	(segment
		(start 99.857814 -286.780478)
		(end 99.39147 -287.045908)
		(width 0.350012)
		(layer "F.Cu")
		(net "GND")
	)
	(segment
		(start 429.568102 -12.374118)
		(end 429.566832 -12.372848)
		(width 0.3556)
		(layer "F.Cu")
		(net "GND")
	)
	(segment
		(start 201.000614 -68.026788)
		(end 201.000614 -67.271392)
		(width 0.4572)
		(layer "F.Cu")
		(net "GND")
	)
	(segment
		(start 230.926894 -51.565048)
		(end 232.000044 -51.565048)
		(width 0.381)
		(layer "F.Cu")
		(net "GND")
	)
	(segment
		(start 32.695896 -296.785284)
		(end 34.080196 -296.785284)
		(width 0.4572)
		(layer "F.Cu")
		(net "GND")
	)
	(segment
		(start 115.389152 -402.611082)
		(end 114.986816 -403.013418)
		(width 0.3302)
		(layer "F.Cu")
		(net "GND")
	)
	(segment
		(start 90.627962 -233.410252)
		(end 90.16111 -233.144314)
		(width 0.350012)
		(layer "F.Cu")
		(net "GND")
	)
	(segment
		(start 124.01804 -107.35691)
		(end 124.01804 -106.42092)
		(width 0.381)
		(layer "F.Cu")
		(net "GND")
	)
	(segment
		(start 205.914244 -98.244914)
		(end 206.138526 -98.469196)
		(width 0.381)
		(layer "F.Cu")
		(net "GND")
	)
	(segment
		(start 302.800258 -43.989498)
		(end 302.184054 -43.989498)
		(width 0.3556)
		(layer "F.Cu")
		(net "GND")
	)
	(segment
		(start 363.307884 -290.83)
		(end 363.774736 -291.095938)
		(width 0.350012)
		(layer "F.Cu")
		(net "GND")
	)
	(segment
		(start 404.898352 -392.999722)
		(end 404.845774 -392.30427)
		(width 0.254)
		(layer "F.Cu")
		(net "GND")
	)
	(segment
		(start 353.045522 -391.333482)
		(end 353.144074 -391.23493)
		(width 0.254)
		(layer "F.Cu")
		(net "GND")
	)
	(segment
		(start 301.019718 -145.877788)
		(end 301.019718 -145.238978)
		(width 0.4572)
		(layer "F.Cu")
		(net "GND")
	)
	(segment
		(start 349.544132 -399.76171)
		(end 349.44558 -399.663158)
		(width 0.254)
		(layer "F.Cu")
		(net "GND")
	)
	(segment
		(start 162.052 -108.09605)
		(end 162.676586 -108.09605)
		(width 0.381)
		(layer "F.Cu")
		(net "GND")
	)
	(segment
		(start 27.547062 -10.16635)
		(end 27.545792 -10.16508)
		(width 0.3556)
		(layer "F.Cu")
		(net "GND")
	)
	(segment
		(start 126.347982 -226.930458)
		(end 126.814834 -226.66452)
		(width 0.350012)
		(layer "F.Cu")
		(net "GND")
	)
	(segment
		(start 144.977866 -270.580358)
		(end 145.444718 -270.846296)
		(width 0.350012)
		(layer "F.Cu")
		(net "GND")
	)
	(segment
		(start 144.977866 -267.340334)
		(end 145.444718 -267.606272)
		(width 0.350012)
		(layer "F.Cu")
		(net "GND")
	)
	(segment
		(start 388.217918 -264.100056)
		(end 388.68477 -264.365994)
		(width 0.350012)
		(layer "F.Cu")
		(net "GND")
	)
	(segment
		(start 320.340228 -40.652954)
		(end 320.949828 -40.652954)
		(width 0.3556)
		(layer "F.Cu")
		(net "GND")
	)
	(segment
		(start 178.289458 -42.29989)
		(end 177.108358 -42.29989)
		(width 0.254)
		(layer "F.Cu")
		(net "GND")
	)
	(segment
		(start 369.417854 -286.780224)
		(end 369.884706 -287.045908)
		(width 0.350012)
		(layer "F.Cu")
		(net "GND")
	)
	(segment
		(start 89.047828 -264.910316)
		(end 88.580976 -265.176254)
		(width 0.350012)
		(layer "F.Cu")
		(net "GND")
	)
	(segment
		(start 387.917944 -235.840016)
		(end 388.384796 -235.574078)
		(width 0.350012)
		(layer "F.Cu")
		(net "GND")
	)
	(segment
		(start 129.31648 -391.37971)
		(end 129.217928 -391.281158)
		(width 0.254)
		(layer "F.Cu")
		(net "GND")
	)
	(segment
		(start 349.67799 -280.300176)
		(end 349.211138 -280.566114)
		(width 0.350012)
		(layer "F.Cu")
		(net "GND")
	)
	(segment
		(start 30.706314 -132.388864)
		(end 30.075378 -132.388864)
		(width 0.4064)
		(layer "F.Cu")
		(net "GND")
	)
	(segment
		(start 446.644268 -199.885046)
		(end 445.259968 -199.885046)
		(width 0.4572)
		(layer "F.Cu")
		(net "GND")
	)
	(segment
		(start 376.467878 -282.730194)
		(end 376.93473 -282.996132)
		(width 0.350012)
		(layer "F.Cu")
		(net "GND")
	)
	(segment
		(start 387.970522 -398.542002)
		(end 387.291326 -398.542002)
		(width 0.254)
		(layer "F.Cu")
		(net "GND")
	)
	(segment
		(start 123.20016 -146.957288)
		(end 124.05487 -146.957288)
		(width 0.254)
		(layer "F.Cu")
		(net "GND")
	)
	(segment
		(start 99.857814 -275.440394)
		(end 99.390962 -275.706332)
		(width 0.350012)
		(layer "F.Cu")
		(net "GND")
	)
	(segment
		(start 21.70811 -302.735234)
		(end 20.32381 -302.735234)
		(width 0.4572)
		(layer "F.Cu")
		(net "GND")
	)
	(segment
		(start 240.031524 -149.965918)
		(end 240.031524 -150.776686)
		(width 0.4572)
		(layer "F.Cu")
		(net "GND")
	)
	(segment
		(start 341.989918 -392.999722)
		(end 341.398098 -392.999722)
		(width 0.254)
		(layer "F.Cu")
		(net "GND")
	)
	(segment
		(start 143.567912 -290.830254)
		(end 144.034764 -291.096192)
		(width 0.350012)
		(layer "F.Cu")
		(net "GND")
	)
	(segment
		(start 98.598482 -386.6388)
		(end 97.906332 -386.449062)
		(width 0.254)
		(layer "F.Cu")
		(net "GND")
	)
	(segment
		(start 362.368084 -273.010122)
		(end 362.834682 -273.27606)
		(width 0.350012)
		(layer "F.Cu")
		(net "GND")
	)
	(segment
		(start 146.636994 -386.030978)
		(end 146.248882 -386.030978)
		(width 0.254)
		(layer "F.Cu")
		(net "GND")
	)
	(segment
		(start 49.270666 -386.6388)
		(end 48.578516 -386.449062)
		(width 0.254)
		(layer "F.Cu")
		(net "GND")
	)
	(segment
		(start 371.767862 -271.39011)
		(end 372.234714 -271.656048)
		(width 0.350012)
		(layer "F.Cu")
		(net "GND")
	)
	(segment
		(start 374.588024 -264.910062)
		(end 375.054876 -265.176)
		(width 0.350012)
		(layer "F.Cu")
		(net "GND")
	)
	(segment
		(start 112.717834 -235.84027)
		(end 113.184686 -235.574332)
		(width 0.350012)
		(layer "F.Cu")
		(net "GND")
	)
	(segment
		(start 366.297972 -240.700052)
		(end 366.764824 -240.434114)
		(width 0.350012)
		(layer "F.Cu")
		(net "GND")
	)
	(segment
		(start 299.82414 -302.73498)
		(end 298.43984 -302.73498)
		(width 0.4572)
		(layer "F.Cu")
		(net "GND")
	)
	(segment
		(start 255.261618 -49.882298)
		(end 256.169922 -49.882298)
		(width 0.254)
		(layer "F.Cu")
		(net "GND")
	)
	(segment
		(start 69.647054 -147.187666)
		(end 69.359526 -147.475194)
		(width 0.254)
		(layer "F.Cu")
		(net "GND")
	)
	(segment
		(start 109.728 -284.35046)
		(end 109.261148 -284.616398)
		(width 0.350012)
		(layer "F.Cu")
		(net "GND")
	)
	(segment
		(start 56.867044 -12.372848)
		(end 56.867044 -11.26998)
		(width 0.3556)
		(layer "F.Cu")
		(net "GND")
	)
	(segment
		(start 386.338064 -290.019994)
		(end 386.804916 -290.285932)
		(width 0.350012)
		(layer "F.Cu")
		(net "GND")
	)
	(segment
		(start 113.701068 -403.991318)
		(end 113.339372 -403.991318)
		(width 0.3302)
		(layer "F.Cu")
		(net "GND")
	)
	(segment
		(start 332.28788 -274.630134)
		(end 331.821028 -274.896072)
		(width 0.350012)
		(layer "F.Cu")
		(net "GND")
	)
	(segment
		(start 122.68708 -27.530806)
		(end 122.68708 -30.178502)
		(width 0.3556)
		(layer "F.Cu")
		(net "GND")
	)
	(segment
		(start 118.187978 -277.870412)
		(end 118.65483 -278.13635)
		(width 0.350012)
		(layer "F.Cu")
		(net "GND")
	)
	(segment
		(start 302.870362 -392.356848)
		(end 302.870362 -392.999722)
		(width 0.254)
		(layer "F.Cu")
		(net "GND")
	)
	(segment
		(start 102.207822 -261.670292)
		(end 101.74097 -261.93623)
		(width 0.350012)
		(layer "F.Cu")
		(net "GND")
	)
	(segment
		(start 82.167984 -254.470408)
		(end 81.701132 -254.20447)
		(width 0.350012)
		(layer "F.Cu")
		(net "GND")
	)
	(segment
		(start 49.807368 -351.10547)
		(end 49.807368 -351.736406)
		(width 0.381)
		(layer "F.Cu")
		(net "GND")
	)
	(segment
		(start 158.395416 -57.474358)
		(end 158.395416 -58.109104)
		(width 0.4572)
		(layer "F.Cu")
		(net "GND")
	)
	(segment
		(start 130.107944 -238.270288)
		(end 130.574796 -238.00435)
		(width 0.350012)
		(layer "F.Cu")
		(net "GND")
	)
	(segment
		(start 386.770626 -396.520924)
		(end 386.21843 -396.710662)
		(width 0.254)
		(layer "F.Cu")
		(net "GND")
	)
	(segment
		(start 435.000146 -200.735184)
		(end 436.384446 -200.735184)
		(width 0.4572)
		(layer "F.Cu")
		(net "GND")
	)
	(segment
		(start 18.650458 -418.290248)
		(end 18.650458 -417.68014)
		(width 0.381)
		(layer "F.Cu")
		(net "GND")
	)
	(segment
		(start 335.577942 -283.5402)
		(end 335.11109 -283.806138)
		(width 0.350012)
		(layer "F.Cu")
		(net "GND")
	)
	(segment
		(start 52.616608 -394.622528)
		(end 52.616608 -393.927838)
		(width 0.381)
		(layer "F.Cu")
		(net "GND")
	)
	(segment
		(start 130.467354 -55.074312)
		(end 130.467354 -55.541164)
		(width 0.1778)
		(layer "F.Cu")
		(net "GND")
	)
	(segment
		(start 99.47529 -40.115744)
		(end 99.47529 -40.917114)
		(width 0.3556)
		(layer "F.Cu")
		(net "GND")
	)
	(segment
		(start 46.621192 -386.030978)
		(end 46.621192 -385.43103)
		(width 0.254)
		(layer "F.Cu")
		(net "GND")
	)
	(segment
		(start 335.277968 -255.28016)
		(end 334.811116 -255.014222)
		(width 0.350012)
		(layer "F.Cu")
		(net "GND")
	)
	(segment
		(start 401.110958 -321.847718)
		(end 401.40128 -322.13804)
		(width 0.381)
		(layer "F.Cu")
		(net "GND")
	)
	(segment
		(start 341.857838 -224.500186)
		(end 341.390986 -224.234248)
		(width 0.350012)
		(layer "F.Cu")
		(net "GND")
	)
	(segment
		(start 412.098236 -398.542002)
		(end 411.41904 -398.542002)
		(width 0.254)
		(layer "F.Cu")
		(net "GND")
	)
	(segment
		(start 68.16852 -394.0937)
		(end 68.16852 -393.781788)
		(width 0.254)
		(layer "F.Cu")
		(net "GND")
	)
	(segment
		(start 394.333984 -390.1694)
		(end 394.333984 -389.446516)
		(width 0.254)
		(layer "F.Cu")
		(net "GND")
	)
	(segment
		(start 100.797868 -260.860286)
		(end 100.331016 -261.126224)
		(width 0.350012)
		(layer "F.Cu")
		(net "GND")
	)
	(segment
		(start 338.39785 -281.920188)
		(end 337.930998 -282.186126)
		(width 0.350012)
		(layer "F.Cu")
		(net "GND")
	)
	(segment
		(start 133.41477 -387.231128)
		(end 133.170676 -386.987034)
		(width 0.254)
		(layer "F.Cu")
		(net "GND")
	)
	(segment
		(start 447.16319 -12.374118)
		(end 447.16319 -12.37488)
		(width 0.3556)
		(layer "F.Cu")
		(net "GND")
	)
	(segment
		(start 118.834916 -166.893748)
		(end 119.137684 -166.893748)
		(width 0.381)
		(layer "F.Cu")
		(net "GND")
	)
	(segment
		(start 377.878086 -272.200116)
		(end 378.344938 -272.466054)
		(width 0.350012)
		(layer "F.Cu")
		(net "GND")
	)
	(segment
		(start 442.183266 -396.95247)
		(end 442.183266 -397.554958)
		(width 0.2032)
		(layer "F.Cu")
		(net "GND")
	)
	(segment
		(start 143.098012 -283.540454)
		(end 143.56461 -283.806392)
		(width 0.350012)
		(layer "F.Cu")
		(net "GND")
	)
	(segment
		(start 87.3379 -234.220258)
		(end 86.871048 -233.95432)
		(width 0.350012)
		(layer "F.Cu")
		(net "GND")
	)
	(segment
		(start 198.7042 -211.7852)
		(end 197.3199 -211.7852)
		(width 0.4572)
		(layer "F.Cu")
		(net "GND")
	)
	(segment
		(start 46.621192 -390.564624)
		(end 46.818042 -390.761474)
		(width 0.254)
		(layer "F.Cu")
		(net "GND")
	)
	(segment
		(start 367.996978 -174.706026)
		(end 367.96599 -174.706026)
		(width 0.2286)
		(layer "F.Cu")
		(net "GND")
	)
	(segment
		(start 93.445838 -382.951482)
		(end 93.54439 -382.85293)
		(width 0.254)
		(layer "F.Cu")
		(net "GND")
	)
	(segment
		(start 389.653018 -402.4757)
		(end 389.653018 -401.873212)
		(width 0.254)
		(layer "F.Cu")
		(net "GND")
	)
	(segment
		(start 419.298374 -392.999722)
		(end 419.245796 -392.30427)
		(width 0.254)
		(layer "F.Cu")
		(net "GND")
	)
	(segment
		(start 353.437952 -275.44014)
		(end 352.9711 -275.706078)
		(width 0.350012)
		(layer "F.Cu")
		(net "GND")
	)
	(segment
		(start 350.14789 -266.530074)
		(end 349.681038 -266.796012)
		(width 0.350012)
		(layer "F.Cu")
		(net "GND")
	)
	(segment
		(start 104.469946 -55.803546)
		(end 104.5972 -55.9308)
		(width 0.4572)
		(layer "F.Cu")
		(net "GND")
	)
	(segment
		(start 97.507806 -273.010376)
		(end 97.040954 -273.276314)
		(width 0.350012)
		(layer "F.Cu")
		(net "GND")
	)
	(segment
		(start 269.648178 -286.585152)
		(end 268.263878 -286.585152)
		(width 0.4572)
		(layer "F.Cu")
		(net "GND")
	)
	(segment
		(start 311.217818 -392.30427)
		(end 311.270396 -392.999722)
		(width 0.254)
		(layer "F.Cu")
		(net "GND")
	)
	(segment
		(start 22.145752 -7.215886)
		(end 22.147022 -7.217156)
		(width 0.3556)
		(layer "F.Cu")
		(net "GND")
	)
	(segment
		(start 348.437962 -226.120198)
		(end 347.97111 -225.85426)
		(width 0.350012)
		(layer "F.Cu")
		(net "GND")
	)
	(segment
		(start 53.267102 -12.372848)
		(end 53.267102 -11.26998)
		(width 0.3556)
		(layer "F.Cu")
		(net "GND")
	)
	(segment
		(start 79.177896 -277.060406)
		(end 78.711044 -277.326344)
		(width 0.350012)
		(layer "F.Cu")
		(net "GND")
	)
	(segment
		(start 336.987896 -261.670038)
		(end 336.521044 -261.935976)
		(width 0.350012)
		(layer "F.Cu")
		(net "GND")
	)
	(segment
		(start 288.325306 -349.781622)
		(end 288.356294 -349.781622)
		(width 0.2286)
		(layer "F.Cu")
		(net "GND")
	)
	(segment
		(start 58.53303 -40.884094)
		(end 58.53303 -40.404034)
		(width 0.4572)
		(layer "F.Cu")
		(net "GND")
	)
	(segment
		(start 141.38783 -238.270288)
		(end 141.854682 -238.00435)
		(width 0.350012)
		(layer "F.Cu")
		(net "GND")
	)
	(segment
		(start 412.367984 -296.78503)
		(end 413.752284 -296.78503)
		(width 0.4572)
		(layer "F.Cu")
		(net "GND")
	)
	(segment
		(start 446.644268 -295.935146)
		(end 445.259968 -295.935146)
		(width 0.4572)
		(layer "F.Cu")
		(net "GND")
	)
	(segment
		(start 348.268036 -261.670038)
		(end 347.801184 -261.935976)
		(width 0.350012)
		(layer "F.Cu")
		(net "GND")
	)
	(segment
		(start 295.724072 -306.135024)
		(end 297.108372 -306.135024)
		(width 0.4572)
		(layer "F.Cu")
		(net "GND")
	)
	(segment
		(start 119.297958 -226.120452)
		(end 119.76481 -225.854514)
		(width 0.350012)
		(layer "F.Cu")
		(net "GND")
	)
	(segment
		(start 291.730176 -395.231366)
		(end 292.451536 -395.231366)
		(width 0.254)
		(layer "F.Cu")
		(net "GND")
	)
	(segment
		(start 331.987906 -249.610118)
		(end 331.521054 -249.34418)
		(width 0.350012)
		(layer "F.Cu")
		(net "GND")
	)
	(segment
		(start 51.884072 -293.38524)
		(end 50.499772 -293.38524)
		(width 0.4572)
		(layer "F.Cu")
		(net "GND")
	)
	(segment
		(start 133.227826 -290.830254)
		(end 133.694678 -291.096192)
		(width 0.350012)
		(layer "F.Cu")
		(net "GND")
	)
	(segment
		(start 352.198178 -398.542002)
		(end 351.518728 -398.542002)
		(width 0.254)
		(layer "F.Cu")
		(net "GND")
	)
	(segment
		(start 370.057934 -250.420124)
		(end 370.524786 -250.154186)
		(width 0.350012)
		(layer "F.Cu")
		(net "GND")
	)
	(segment
		(start 14.445996 -107.591352)
		(end 14.445996 -106.506264)
		(width 0.3556)
		(layer "F.Cu")
		(net "GND")
	)
	(segment
		(start 439.100214 -237.285022)
		(end 437.715914 -237.285022)
		(width 0.4572)
		(layer "F.Cu")
		(net "GND")
	)
	(segment
		(start 110.1979 -265.720322)
		(end 109.731048 -265.98626)
		(width 0.350012)
		(layer "F.Cu")
		(net "GND")
	)
	(segment
		(start 142.797784 -239.080294)
		(end 143.264636 -238.814356)
		(width 0.350012)
		(layer "F.Cu")
		(net "GND")
	)
	(segment
		(start 353.907852 -274.630134)
		(end 353.441 -274.896072)
		(width 0.350012)
		(layer "F.Cu")
		(net "GND")
	)
	(segment
		(start 136.217914 -226.120452)
		(end 136.684766 -225.854514)
		(width 0.350012)
		(layer "F.Cu")
		(net "GND")
	)
	(segment
		(start 419.912038 -210.085178)
		(end 421.296338 -210.085178)
		(width 0.4572)
		(layer "F.Cu")
		(net "GND")
	)
	(segment
		(start 439.100214 -286.585152)
		(end 437.715914 -286.585152)
		(width 0.4572)
		(layer "F.Cu")
		(net "GND")
	)
	(segment
		(start 424.012106 -211.784946)
		(end 422.627806 -211.784946)
		(width 0.4572)
		(layer "F.Cu")
		(net "GND")
	)
	(segment
		(start 44.340018 -199.8853)
		(end 42.955718 -199.8853)
		(width 0.4572)
		(layer "F.Cu")
		(net "GND")
	)
	(segment
		(start 31.147004 -7.217156)
		(end 31.147004 -8.320024)
		(width 0.3556)
		(layer "F.Cu")
		(net "GND")
	)
	(segment
		(start 371.938042 -243.940076)
		(end 372.404894 -243.674138)
		(width 0.350012)
		(layer "F.Cu")
		(net "GND")
	)
	(segment
		(start 151.298402 -390.160002)
		(end 150.618952 -390.160002)
		(width 0.254)
		(layer "F.Cu")
		(net "GND")
	)
	(segment
		(start 308.517798 -391.784586)
		(end 308.517798 -391.333482)
		(width 0.2032)
		(layer "F.Cu")
		(net "GND")
	)
	(segment
		(start 334.109568 -395.613128)
		(end 334.629252 -395.313154)
		(width 0.254)
		(layer "F.Cu")
		(net "GND")
	)
	(segment
		(start 61.53277 -40.681148)
		(end 61.53277 -41.277794)
		(width 0.4572)
		(layer "F.Cu")
		(net "GND")
	)
	(segment
		(start 435.000146 -203.28509)
		(end 436.384446 -203.28509)
		(width 0.4572)
		(layer "F.Cu")
		(net "GND")
	)
	(segment
		(start 92.046298 -388.328662)
		(end 91.398344 -388.138924)
		(width 0.254)
		(layer "F.Cu")
		(net "GND")
	)
	(segment
		(start 314.62345 -366.79505)
		(end 314.2234 -366.395)
		(width 0.381)
		(layer "F.Cu")
		(net "GND")
	)
	(segment
		(start 326.81799 -250.420124)
		(end 326.351138 -250.154186)
		(width 0.350012)
		(layer "F.Cu")
		(net "GND")
	)
	(segment
		(start 47.009304 -386.030978)
		(end 46.621192 -386.030978)
		(width 0.254)
		(layer "F.Cu")
		(net "GND")
	)
	(segment
		(start 113.721134 -390.231122)
		(end 113.721134 -390.564624)
		(width 0.254)
		(layer "F.Cu")
		(net "GND")
	)
	(segment
		(start 108.806234 -405.892762)
		(end 108.378752 -405.892762)
		(width 0.3048)
		(layer "F.Cu")
		(net "GND")
	)
	(segment
		(start 377.577858 -248.800112)
		(end 378.04471 -248.534174)
		(width 0.350012)
		(layer "F.Cu")
		(net "GND")
	)
	(segment
		(start 378.878592 -394.831062)
		(end 378.370592 -395.0208)
		(width 0.254)
		(layer "F.Cu")
		(net "GND")
	)
	(segment
		(start 369.417854 -285.160212)
		(end 369.884706 -285.42615)
		(width 0.350012)
		(layer "F.Cu")
		(net "GND")
	)
	(segment
		(start 381.638048 -275.44014)
		(end 382.1049 -275.706078)
		(width 0.350012)
		(layer "F.Cu")
		(net "GND")
	)
	(segment
		(start 317.217806 -392.30427)
		(end 317.270384 -392.999722)
		(width 0.254)
		(layer "F.Cu")
		(net "GND")
	)
	(segment
		(start 83.877912 -268.960346)
		(end 83.41106 -269.226284)
		(width 0.350012)
		(layer "F.Cu")
		(net "GND")
	)
	(segment
		(start 387.748018 -276.250146)
		(end 388.21487 -276.516084)
		(width 0.350012)
		(layer "F.Cu")
		(net "GND")
	)
	(segment
		(start 138.397996 -273.820382)
		(end 138.864848 -274.08632)
		(width 0.350012)
		(layer "F.Cu")
		(net "GND")
	)
	(segment
		(start 373.018558 -396.710662)
		(end 372.370604 -396.520924)
		(width 0.254)
		(layer "F.Cu")
		(net "GND")
	)
	(segment
		(start 280.635964 -228.785166)
		(end 282.020264 -228.785166)
		(width 0.4572)
		(layer "F.Cu")
		(net "GND")
	)
	(segment
		(start 344.389964 -392.999722)
		(end 344.99804 -392.999722)
		(width 0.254)
		(layer "F.Cu")
		(net "GND")
	)
	(segment
		(start 128.997964 -293.260272)
		(end 129.464816 -293.52621)
		(width 0.350012)
		(layer "F.Cu")
		(net "GND")
	)
	(segment
		(start 105.497884 -273.820382)
		(end 105.031032 -274.08632)
		(width 0.350012)
		(layer "F.Cu")
		(net "GND")
	)
	(segment
		(start 110.367826 -236.650276)
		(end 109.900974 -236.384338)
		(width 0.350012)
		(layer "F.Cu")
		(net "GND")
	)
	(segment
		(start 347.797882 -293.260018)
		(end 347.33103 -293.525956)
		(width 0.350012)
		(layer "F.Cu")
		(net "GND")
	)
	(segment
		(start 198.7042 -314.635388)
		(end 197.3199 -314.635388)
		(width 0.4572)
		(layer "F.Cu")
		(net "GND")
	)
	(segment
		(start 83.189064 -177.532284)
		(end 82.601054 -177.532284)
		(width 0.381)
		(layer "F.Cu")
		(net "GND")
	)
	(segment
		(start 318.417702 -392.30427)
		(end 318.47028 -392.999722)
		(width 0.254)
		(layer "F.Cu")
		(net "GND")
	)
	(segment
		(start 427.456092 -296.78503)
		(end 428.840392 -296.78503)
		(width 0.4572)
		(layer "F.Cu")
		(net "GND")
	)
	(segment
		(start 171.97197 -275.53539)
		(end 173.35627 -275.53539)
		(width 0.4572)
		(layer "F.Cu")
		(net "GND")
	)
	(segment
		(start 119.71655 -391.37971)
		(end 119.617998 -391.281158)
		(width 0.254)
		(layer "F.Cu")
		(net "GND")
	)
	(segment
		(start 166.26713 -13.599922)
		(end 166.26586 -13.598652)
		(width 0.3556)
		(layer "F.Cu")
		(net "GND")
	)
	(segment
		(start 118.770654 -384.617722)
		(end 118.162324 -384.617722)
		(width 0.254)
		(layer "F.Cu")
		(net "GND")
	)
	(segment
		(start 80.757776 -253.660402)
		(end 80.291178 -253.394464)
		(width 0.350012)
		(layer "F.Cu")
		(net "GND")
	)
	(segment
		(start 389.93445 -394.113004)
		(end 389.683752 -394.831062)
		(width 0.254)
		(layer "F.Cu")
		(net "GND")
	)
	(segment
		(start 83.877912 -273.820382)
		(end 83.41106 -274.08632)
		(width 0.350012)
		(layer "F.Cu")
		(net "GND")
	)
	(segment
		(start 83.845654 -383.402586)
		(end 83.845654 -383.622042)
		(width 0.2032)
		(layer "F.Cu")
		(net "GND")
	)
	(segment
		(start 134.80796 -256.09042)
		(end 135.274812 -255.824482)
		(width 0.350012)
		(layer "F.Cu")
		(net "GND")
	)
	(segment
		(start 196.308218 -78.42377)
		(end 196.329808 -78.40218)
		(width 0.3556)
		(layer "F.Cu")
		(net "GND")
	)
	(segment
		(start 90.927936 -282.730448)
		(end 90.461084 -282.996386)
		(width 0.350012)
		(layer "F.Cu")
		(net "GND")
	)
	(segment
		(start 130.107944 -251.230384)
		(end 130.574796 -250.964446)
		(width 0.350012)
		(layer "F.Cu")
		(net "GND")
	)
	(segment
		(start 446.644268 -314.635134)
		(end 445.259968 -314.635134)
		(width 0.4572)
		(layer "F.Cu")
		(net "GND")
	)
	(segment
		(start 143.740632 -101.894132)
		(end 142.800832 -101.894132)
		(width 0.3556)
		(layer "F.Cu")
		(net "GND")
	)
	(segment
		(start 394.027914 -251.23013)
		(end 394.68298 -251.23013)
		(width 0.350012)
		(layer "F.Cu")
		(net "GND")
	)
	(segment
		(start 139.80795 -273.010376)
		(end 140.274802 -273.276314)
		(width 0.350012)
		(layer "F.Cu")
		(net "GND")
	)
	(segment
		(start 406.97658 -58.036968)
		(end 406.97658 -58.30062)
		(width 0.508)
		(layer "F.Cu")
		(net "GND")
	)
	(segment
		(start 450.088 -200.735184)
		(end 451.4723 -200.735184)
		(width 0.4572)
		(layer "F.Cu")
		(net "GND")
	)
	(segment
		(start 353.607878 -243.13007)
		(end 353.141026 -242.864132)
		(width 0.350012)
		(layer "F.Cu")
		(net "GND")
	)
	(segment
		(start 374.417844 -399.663158)
		(end 374.516396 -399.76171)
		(width 0.254)
		(layer "F.Cu")
		(net "GND")
	)
	(segment
		(start 143.098012 -288.400236)
		(end 143.56461 -288.666174)
		(width 0.350012)
		(layer "F.Cu")
		(net "GND")
	)
	(segment
		(start 125.91796 -383.92227)
		(end 125.970538 -384.617722)
		(width 0.254)
		(layer "F.Cu")
		(net "GND")
	)
	(segment
		(start 374.77065 -392.999722)
		(end 374.16232 -392.999722)
		(width 0.254)
		(layer "F.Cu")
		(net "GND")
	)
	(segment
		(start 129.82956 -27.3939)
		(end 129.96418 -27.25928)
		(width 0.254)
		(layer "F.Cu")
		(net "GND")
	)
	(segment
		(start 308.420516 -437.098694)
		(end 309.051452 -437.098694)
		(width 0.381)
		(layer "F.Cu")
		(net "GND")
	)
	(segment
		(start 339.646006 -396.710662)
		(end 338.998052 -396.520924)
		(width 0.254)
		(layer "F.Cu")
		(net "GND")
	)
	(segment
		(start 270.312134 -421.63873)
		(end 270.312134 -422.332404)
		(width 0.381)
		(layer "F.Cu")
		(net "GND")
	)
	(segment
		(start 371.938042 -255.28016)
		(end 372.404894 -255.014222)
		(width 0.350012)
		(layer "F.Cu")
		(net "GND")
	)
	(segment
		(start 139.996672 -382.00584)
		(end 140.397992 -382.40716)
		(width 0.254)
		(layer "F.Cu")
		(net "GND")
	)
	(segment
		(start 368.64798 -243.13007)
		(end 369.114832 -242.864132)
		(width 0.350012)
		(layer "F.Cu")
		(net "GND")
	)
	(segment
		(start 108.017818 -245.560342)
		(end 107.550966 -245.294404)
		(width 0.350012)
		(layer "F.Cu")
		(net "GND")
	)
	(segment
		(start 83.577938 -255.280414)
		(end 83.111086 -255.014476)
		(width 0.350012)
		(layer "F.Cu")
		(net "GND")
	)
	(segment
		(start 377.170442 -398.542002)
		(end 376.491246 -398.542002)
		(width 0.254)
		(layer "F.Cu")
		(net "GND")
	)
	(segment
		(start 391.208006 -243.13007)
		(end 391.674858 -242.864132)
		(width 0.350012)
		(layer "F.Cu")
		(net "GND")
	)
	(segment
		(start 371.767862 -287.59023)
		(end 372.234714 -287.856168)
		(width 0.350012)
		(layer "F.Cu")
		(net "GND")
	)
	(segment
		(start 83.845654 -383.402586)
		(end 83.845654 -382.951482)
		(width 0.2032)
		(layer "F.Cu")
		(net "GND")
	)
	(segment
		(start 423.796206 -402.4757)
		(end 423.796206 -402.163788)
		(width 0.254)
		(layer "F.Cu")
		(net "GND")
	)
	(segment
		(start 344.678 -230.97998)
		(end 344.211148 -230.714296)
		(width 0.350012)
		(layer "F.Cu")
		(net "GND")
	)
	(segment
		(start 44.340018 -202.435206)
		(end 42.955718 -202.435206)
		(width 0.4572)
		(layer "F.Cu")
		(net "GND")
	)
	(segment
		(start 96.737932 -237.460282)
		(end 96.27108 -237.194344)
		(width 0.350012)
		(layer "F.Cu")
		(net "GND")
	)
	(segment
		(start 150.098252 -386.6388)
		(end 149.406356 -386.449062)
		(width 0.254)
		(layer "F.Cu")
		(net "GND")
	)
	(segment
		(start 130.107944 -231.79024)
		(end 130.574796 -231.524302)
		(width 0.350012)
		(layer "F.Cu")
		(net "GND")
	)
	(segment
		(start 121.007886 -285.970472)
		(end 121.474738 -286.23641)
		(width 0.350012)
		(layer "F.Cu")
		(net "GND")
	)
	(segment
		(start 128.318006 -383.92227)
		(end 128.370584 -384.617722)
		(width 0.254)
		(layer "F.Cu")
		(net "GND")
	)
	(segment
		(start 146.38782 -282.730448)
		(end 147.042886 -282.730448)
		(width 0.350012)
		(layer "F.Cu")
		(net "GND")
	)
	(segment
		(start 347.045534 -399.663158)
		(end 347.345508 -399.143474)
		(width 0.254)
		(layer "F.Cu")
		(net "GND")
	)
	(segment
		(start 421.645588 -399.143474)
		(end 421.69842 -398.542002)
		(width 0.254)
		(layer "F.Cu")
		(net "GND")
	)
	(segment
		(start 344.645488 -391.333482)
		(end 344.74404 -391.23493)
		(width 0.254)
		(layer "F.Cu")
		(net "GND")
	)
	(segment
		(start 80.245712 -383.402586)
		(end 80.245712 -383.622296)
		(width 0.254)
		(layer "F.Cu")
		(net "GND")
	)
	(segment
		(start 146.38782 -294.070278)
		(end 146.854672 -294.336216)
		(width 0.350012)
		(layer "F.Cu")
		(net "GND")
	)
	(segment
		(start 427.456092 -294.235124)
		(end 428.840392 -294.235124)
		(width 0.4572)
		(layer "F.Cu")
		(net "GND")
	)
	(segment
		(start 100.505006 -345.196922)
		(end 100.397818 -345.089734)
		(width 0.381)
		(layer "F.Cu")
		(net "GND")
	)
	(segment
		(start 78.829408 -388.330948)
		(end 78.62951 -388.13105)
		(width 0.254)
		(layer "F.Cu")
		(net "GND")
	)
	(segment
		(start 331.518006 -256.900172)
		(end 331.051154 -256.634234)
		(width 0.350012)
		(layer "F.Cu")
		(net "GND")
	)
	(segment
		(start 334.742536 -340.185248)
		(end 334.812386 -340.115398)
		(width 0.381)
		(layer "F.Cu")
		(net "GND")
	)
	(segment
		(start 350.78797 -241.510058)
		(end 350.321118 -241.24412)
		(width 0.350012)
		(layer "F.Cu")
		(net "GND")
	)
	(segment
		(start 119.617998 -383.402586)
		(end 119.617998 -382.951482)
		(width 0.2032)
		(layer "F.Cu")
		(net "GND")
	)
	(segment
		(start 420.950136 -356.372414)
		(end 420.419784 -356.372414)
		(width 0.3556)
		(layer "F.Cu")
		(net "GND")
	)
	(segment
		(start 326.749156 -395.466062)
		(end 326.26554 -395.466062)
		(width 0.381)
		(layer "F.Cu")
		(net "GND")
	)
	(segment
		(start 368.64798 -239.890046)
		(end 369.114832 -239.624108)
		(width 0.350012)
		(layer "F.Cu")
		(net "GND")
	)
	(segment
		(start 139.80795 -271.390364)
		(end 140.274802 -271.656302)
		(width 0.350012)
		(layer "F.Cu")
		(net "GND")
	)
	(segment
		(start 129.938018 -267.340334)
		(end 130.40487 -267.606272)
		(width 0.350012)
		(layer "F.Cu")
		(net "GND")
	)
	(segment
		(start 299.82414 -221.13494)
		(end 298.43984 -221.13494)
		(width 0.4572)
		(layer "F.Cu")
		(net "GND")
	)
	(segment
		(start 313.617864 -392.30427)
		(end 313.670442 -392.999722)
		(width 0.254)
		(layer "F.Cu")
		(net "GND")
	)
	(segment
		(start 146.087846 -246.370348)
		(end 146.742912 -246.370348)
		(width 0.350012)
		(layer "F.Cu")
		(net "GND")
	)
	(segment
		(start 183.616092 -239.835436)
		(end 182.231792 -239.835436)
		(width 0.4572)
		(layer "F.Cu")
		(net "GND")
	)
	(segment
		(start 341.687912 -269.770098)
		(end 341.22106 -270.036036)
		(width 0.350012)
		(layer "F.Cu")
		(net "GND")
	)
	(segment
		(start 322.017644 -392.30427)
		(end 321.71767 -391.784586)
		(width 0.254)
		(layer "F.Cu")
		(net "GND")
	)
	(segment
		(start 8.082788 -137.61847)
		(end 6.829298 -137.61847)
		(width 0.3556)
		(layer "F.Cu")
		(net "GND")
	)
	(segment
		(start 79.14894 -386.630926)
		(end 79.14894 -387.231128)
		(width 0.254)
		(layer "F.Cu")
		(net "GND")
	)
	(segment
		(start 375.617994 -391.784586)
		(end 375.617994 -391.333482)
		(width 0.2032)
		(layer "F.Cu")
		(net "GND")
	)
	(segment
		(start 110.83798 -234.220258)
		(end 110.371128 -233.95432)
		(width 0.350012)
		(layer "F.Cu")
		(net "GND")
	)
	(segment
		(start 145.128488 -393.900152)
		(end 144.315688 -393.900152)
		(width 0.254)
		(layer "F.Cu")
		(net "GND")
	)
	(segment
		(start 127.047498 -162.83559)
		(end 127.047498 -163.114482)
		(width 0.2286)
		(layer "F.Cu")
		(net "GND")
	)
	(segment
		(start 376.467878 -266.530074)
		(end 376.93473 -266.796012)
		(width 0.350012)
		(layer "F.Cu")
		(net "GND")
	)
	(segment
		(start 129.938018 -278.680418)
		(end 130.40487 -278.946356)
		(width 0.350012)
		(layer "F.Cu")
		(net "GND")
	)
	(segment
		(start 344.678 -250.420124)
		(end 344.211148 -250.154186)
		(width 0.350012)
		(layer "F.Cu")
		(net "GND")
	)
	(segment
		(start 363.778038 -272.200116)
		(end 364.24489 -272.466054)
		(width 0.350012)
		(layer "F.Cu")
		(net "GND")
	)
	(segment
		(start 138.981942 -387.0579)
		(end 139.794742 -387.0579)
		(width 0.254)
		(layer "F.Cu")
		(net "GND")
	)
	(segment
		(start 145.773394 -54.513734)
		(end 145.773394 -53.897784)
		(width 0.4572)
		(layer "F.Cu")
		(net "GND")
	)
	(segment
		(start 236.58957 -160.972754)
		(end 237.612682 -160.972754)
		(width 0.381)
		(layer "F.Cu")
		(net "GND")
	)
	(segment
		(start 123.685046 -27.07894)
		(end 123.84786 -26.916126)
		(width 0.4572)
		(layer "F.Cu")
		(net "GND")
	)
	(segment
		(start 339.977984 -250.420124)
		(end 339.511132 -250.154186)
		(width 0.350012)
		(layer "F.Cu")
		(net "GND")
	)
	(segment
		(start 133.398006 -229.360476)
		(end 133.864858 -229.094538)
		(width 0.350012)
		(layer "F.Cu")
		(net "GND")
	)
	(segment
		(start 122.587766 -254.470408)
		(end 123.054618 -254.20447)
		(width 0.350012)
		(layer "F.Cu")
		(net "GND")
	)
	(segment
		(start 366.128046 -279.49017)
		(end 366.594898 -279.756108)
		(width 0.350012)
		(layer "F.Cu")
		(net "GND")
	)
	(segment
		(start 139.507976 -239.8903)
		(end 139.974828 -239.624362)
		(width 0.350012)
		(layer "F.Cu")
		(net "GND")
	)
	(segment
		(start 366.597946 -288.399982)
		(end 367.064798 -288.66592)
		(width 0.350012)
		(layer "F.Cu")
		(net "GND")
	)
	(segment
		(start 353.398074 -398.542002)
		(end 352.718878 -398.542002)
		(width 0.254)
		(layer "F.Cu")
		(net "GND")
	)
	(segment
		(start 143.098012 -291.64026)
		(end 143.56461 -291.906198)
		(width 0.350012)
		(layer "F.Cu")
		(net "GND")
	)
	(segment
		(start 419.245796 -392.30427)
		(end 418.945568 -392.004042)
		(width 0.254)
		(layer "F.Cu")
		(net "GND")
	)
	(segment
		(start 36.795964 -314.635388)
		(end 35.411664 -314.635388)
		(width 0.4572)
		(layer "F.Cu")
		(net "GND")
	)
	(segment
		(start 144.977866 -288.400236)
		(end 145.444718 -288.666174)
		(width 0.350012)
		(layer "F.Cu")
		(net "GND")
	)
	(segment
		(start 98.617786 -253.660402)
		(end 98.150934 -253.394464)
		(width 0.350012)
		(layer "F.Cu")
		(net "GND")
	)
	(segment
		(start 343.268046 -247.990106)
		(end 342.801194 -247.724168)
		(width 0.350012)
		(layer "F.Cu")
		(net "GND")
	)
	(segment
		(start 277.192232 -209.23504)
		(end 275.807932 -209.23504)
		(width 0.4572)
		(layer "F.Cu")
		(net "GND")
	)
	(segment
		(start 374.588024 -281.110182)
		(end 375.054876 -281.37612)
		(width 0.350012)
		(layer "F.Cu")
		(net "GND")
	)
	(segment
		(start 127.58801 -268.15034)
		(end 128.054862 -268.416278)
		(width 0.350012)
		(layer "F.Cu")
		(net "GND")
	)
	(segment
		(start 402.12264 -400.15795)
		(end 402.12264 -399.686272)
		(width 0.254)
		(layer "F.Cu")
		(net "GND")
	)
	(segment
		(start 123.52782 -241.510312)
		(end 123.994672 -241.244374)
		(width 0.350012)
		(layer "F.Cu")
		(net "GND")
	)
	(segment
		(start 147.345654 -383.622296)
		(end 147.645628 -383.92227)
		(width 0.254)
		(layer "F.Cu")
		(net "GND")
	)
	(segment
		(start 356.42804 -246.370094)
		(end 355.961188 -246.104156)
		(width 0.350012)
		(layer "F.Cu")
		(net "GND")
	)
	(segment
		(start 141.38783 -251.230384)
		(end 141.854682 -250.964446)
		(width 0.350012)
		(layer "F.Cu")
		(net "GND")
	)
	(segment
		(start 344.678 -242.320064)
		(end 344.211148 -242.054126)
		(width 0.350012)
		(layer "F.Cu")
		(net "GND")
	)
	(segment
		(start 383.517902 -293.260018)
		(end 383.984754 -293.525956)
		(width 0.350012)
		(layer "F.Cu")
		(net "GND")
	)
	(segment
		(start 334.808068 -256.090166)
		(end 334.341216 -255.824228)
		(width 0.350012)
		(layer "F.Cu")
		(net "GND")
	)
	(segment
		(start 113.957862 -291.64026)
		(end 114.424714 -291.906198)
		(width 0.350012)
		(layer "F.Cu")
		(net "GND")
	)
	(segment
		(start 343.745566 -399.143474)
		(end 343.798144 -398.542002)
		(width 0.254)
		(layer "F.Cu")
		(net "GND")
	)
	(segment
		(start 68.615306 -393.335002)
		(end 68.790566 -393.510262)
		(width 0.254)
		(layer "F.Cu")
		(net "GND")
	)
	(segment
		(start 384.814064 -178.359562)
		(end 384.814064 -177.71618)
		(width 0.381)
		(layer "F.Cu")
		(net "GND")
	)
	(segment
		(start 337.118706 -398.542002)
		(end 336.598006 -398.542002)
		(width 0.254)
		(layer "F.Cu")
		(net "GND")
	)
	(segment
		(start 124.770642 -386.6388)
		(end 124.078492 -386.449062)
		(width 0.254)
		(layer "F.Cu")
		(net "GND")
	)
	(segment
		(start 447.16192 -12.372848)
		(end 447.16319 -12.374118)
		(width 0.3556)
		(layer "F.Cu")
		(net "GND")
	)
	(segment
		(start 308.817772 -399.143474)
		(end 308.87035 -398.542002)
		(width 0.254)
		(layer "F.Cu")
		(net "GND")
	)
	(segment
		(start 256.992374 -129.617216)
		(end 257.608324 -129.617216)
		(width 0.381)
		(layer "F.Cu")
		(net "GND")
	)
	(segment
		(start 176.072038 -237.285276)
		(end 174.687738 -237.285276)
		(width 0.4572)
		(layer "F.Cu")
		(net "GND")
	)
	(segment
		(start 404.218902 -398.542002)
		(end 403.698202 -398.542002)
		(width 0.254)
		(layer "F.Cu")
		(net "GND")
	)
	(segment
		(start 113.721134 -385.43103)
		(end 113.721134 -384.86715)
		(width 0.254)
		(layer "F.Cu")
		(net "GND")
	)
	(segment
		(start 376.467878 -287.59023)
		(end 376.93473 -287.856168)
		(width 0.350012)
		(layer "F.Cu")
		(net "GND")
	)
	(segment
		(start 401.437094 -174.105824)
		(end 401.507198 -174.105824)
		(width 0.2286)
		(layer "F.Cu")
		(net "GND")
	)
	(segment
		(start 368.947954 -289.209988)
		(end 369.414806 -289.475926)
		(width 0.350012)
		(layer "F.Cu")
		(net "GND")
	)
	(segment
		(start 326.81799 -227.74021)
		(end 326.351138 -227.474272)
		(width 0.350012)
		(layer "F.Cu")
		(net "GND")
	)
	(segment
		(start 401.110958 -321.402202)
		(end 401.110958 -321.847718)
		(width 0.381)
		(layer "F.Cu")
		(net "GND")
	)
	(segment
		(start 335.277968 -253.660148)
		(end 334.811116 -253.39421)
		(width 0.350012)
		(layer "F.Cu")
		(net "GND")
	)
	(segment
		(start 125.877828 -235.84027)
		(end 126.34468 -235.574332)
		(width 0.350012)
		(layer "F.Cu")
		(net "GND")
	)
	(segment
		(start 354.378006 -277.060152)
		(end 353.911154 -277.32609)
		(width 0.350012)
		(layer "F.Cu")
		(net "GND")
	)
	(segment
		(start 441.827666 -396.59687)
		(end 442.183266 -396.95247)
		(width 0.2032)
		(layer "F.Cu")
		(net "GND")
	)
	(segment
		(start 387.748018 -277.870158)
		(end 388.21487 -278.136096)
		(width 0.350012)
		(layer "F.Cu")
		(net "GND")
	)
	(segment
		(start 348.737936 -265.720068)
		(end 348.271084 -265.986006)
		(width 0.350012)
		(layer "F.Cu")
		(net "GND")
	)
	(segment
		(start 88.645746 -383.402586)
		(end 88.645746 -382.951482)
		(width 0.254)
		(layer "F.Cu")
		(net "GND")
	)
	(segment
		(start 427.456092 -315.485018)
		(end 428.840392 -315.485018)
		(width 0.4572)
		(layer "F.Cu")
		(net "GND")
	)
	(segment
		(start 354.34397 -391.686034)
		(end 354.34397 -391.23493)
		(width 0.254)
		(layer "F.Cu")
		(net "GND")
	)
	(segment
		(start 100.497894 -253.660402)
		(end 100.031042 -253.394464)
		(width 0.350012)
		(layer "F.Cu")
		(net "GND")
	)
	(segment
		(start 52.194206 -36.26866)
		(end 51.642518 -36.820348)
		(width 0.4572)
		(layer "F.Cu")
		(net "GND")
	)
	(segment
		(start 322.950078 -61.364876)
		(end 324.543928 -61.364876)
		(width 0.4572)
		(layer "F.Cu")
		(net "GND")
	)
	(segment
		(start 394.327888 -266.530074)
		(end 394.982954 -266.530074)
		(width 0.350012)
		(layer "F.Cu")
		(net "GND")
	)
	(segment
		(start 381.638048 -262.480044)
		(end 382.1049 -262.745982)
		(width 0.350012)
		(layer "F.Cu")
		(net "GND")
	)
	(segment
		(start 133.227826 -266.530328)
		(end 133.694678 -266.796266)
		(width 0.350012)
		(layer "F.Cu")
		(net "GND")
	)
	(segment
		(start 121.177812 -227.740464)
		(end 121.644664 -227.474526)
		(width 0.350012)
		(layer "F.Cu")
		(net "GND")
	)
	(segment
		(start 375.756678 -180.376576)
		(end 375.756678 -180.665882)
		(width 0.2286)
		(layer "F.Cu")
		(net "GND")
	)
	(segment
		(start 418.098224 -392.999722)
		(end 417.490148 -392.999722)
		(width 0.254)
		(layer "F.Cu")
		(net "GND")
	)
	(segment
		(start 321.975734 -412.212536)
		(end 321.975734 -411.329886)
		(width 0.381)
		(layer "F.Cu")
		(net "GND")
	)
	(segment
		(start 165.942518 -384.831082)
		(end 165.729158 -384.617722)
		(width 0.254)
		(layer "F.Cu")
		(net "GND")
	)
	(segment
		(start 40.23995 -287.43529)
		(end 41.62425 -287.43529)
		(width 0.4572)
		(layer "F.Cu")
		(net "GND")
	)
	(segment
		(start 112.717834 -222.880428)
		(end 113.184686 -222.61449)
		(width 0.350012)
		(layer "F.Cu")
		(net "GND")
	)
	(segment
		(start 118.770654 -390.160002)
		(end 118.718076 -390.761474)
		(width 0.254)
		(layer "F.Cu")
		(net "GND")
	)
	(segment
		(start 370.527834 -252.850142)
		(end 370.994686 -252.584204)
		(width 0.350012)
		(layer "F.Cu")
		(net "GND")
	)
	(segment
		(start 134.23138 -393.37742)
		(end 134.23138 -394.081)
		(width 0.3048)
		(layer "F.Cu")
		(net "GND")
	)
	(segment
		(start 312.470292 -392.999722)
		(end 312.417714 -392.30427)
		(width 0.254)
		(layer "F.Cu")
		(net "GND")
	)
	(segment
		(start 322.614544 -392.913108)
		(end 322.31457 -393.213082)
		(width 0.254)
		(layer "F.Cu")
		(net "GND")
	)
	(segment
		(start 306.020216 -430.240186)
		(end 306.020216 -429.60925)
		(width 0.381)
		(layer "F.Cu")
		(net "GND")
	)
	(segment
		(start 122.587766 -249.610372)
		(end 123.054618 -249.344434)
		(width 0.350012)
		(layer "F.Cu")
		(net "GND")
	)
	(segment
		(start 77.767942 -276.2504)
		(end 77.112876 -276.2504)
		(width 0.350012)
		(layer "F.Cu")
		(net "GND")
	)
	(segment
		(start 391.50798 -266.530074)
		(end 391.974832 -266.796012)
		(width 0.350012)
		(layer "F.Cu")
		(net "GND")
	)
	(segment
		(start 24.36495 -363.347)
		(end 23.622 -363.347)
		(width 0.381)
		(layer "F.Cu")
		(net "GND")
	)
	(segment
		(start 305.918362 -396.710662)
		(end 305.270408 -396.520924)
		(width 0.254)
		(layer "F.Cu")
		(net "GND")
	)
	(segment
		(start 347.398086 -398.542002)
		(end 346.71889 -398.542002)
		(width 0.254)
		(layer "F.Cu")
		(net "GND")
	)
	(segment
		(start 97.144332 -391.830814)
		(end 97.144332 -391.37971)
		(width 0.254)
		(layer "F.Cu")
		(net "GND")
	)
	(segment
		(start 62.991238 -390.160002)
		(end 62.470538 -390.160002)
		(width 0.254)
		(layer "F.Cu")
		(net "GND")
	)
	(segment
		(start 326.648064 -294.070024)
		(end 326.181212 -294.335962)
		(width 0.350012)
		(layer "F.Cu")
		(net "GND")
	)
	(segment
		(start 99.857814 -277.060406)
		(end 99.390962 -277.326344)
		(width 0.350012)
		(layer "F.Cu")
		(net "GND")
	)
	(segment
		(start 74.34707 -148.051266)
		(end 74.34707 -147.38985)
		(width 0.381)
		(layer "F.Cu")
		(net "GND")
	)
	(segment
		(start 381.617982 -399.663158)
		(end 381.716534 -399.76171)
		(width 0.254)
		(layer "F.Cu")
		(net "GND")
	)
	(segment
		(start 442.5442 -221.985078)
		(end 443.9285 -221.985078)
		(width 0.4572)
		(layer "F.Cu")
		(net "GND")
	)
	(segment
		(start 65.391284 -390.160002)
		(end 64.870584 -390.160002)
		(width 0.254)
		(layer "F.Cu")
		(net "GND")
	)
	(segment
		(start 349.798132 -392.999722)
		(end 349.745554 -392.30427)
		(width 0.254)
		(layer "F.Cu")
		(net "GND")
	)
	(segment
		(start 353.907852 -285.970218)
		(end 353.441 -286.236156)
		(width 0.350012)
		(layer "F.Cu")
		(net "GND")
	)
	(segment
		(start 418.358066 -12.37488)
		(end 418.358066 -12.374118)
		(width 0.3556)
		(layer "F.Cu")
		(net "GND")
	)
	(segment
		(start 360.657902 -250.420124)
		(end 361.124754 -250.154186)
		(width 0.350012)
		(layer "F.Cu")
		(net "GND")
	)
	(segment
		(start 404.5458 -392.004296)
		(end 404.845774 -392.30427)
		(width 0.254)
		(layer "F.Cu")
		(net "GND")
	)
	(segment
		(start 32.947102 -11.26998)
		(end 32.947102 -10.16635)
		(width 0.3556)
		(layer "F.Cu")
		(net "GND")
	)
	(segment
		(start 47.784004 -221.985332)
		(end 49.168304 -221.985332)
		(width 0.4572)
		(layer "F.Cu")
		(net "GND")
	)
	(segment
		(start 100.696268 -393.781788)
		(end 101.143054 -393.335002)
		(width 0.254)
		(layer "F.Cu")
		(net "GND")
	)
	(segment
		(start 356.938072 -164.284406)
		(end 356.350062 -164.284406)
		(width 0.381)
		(layer "F.Cu")
		(net "GND")
	)
	(segment
		(start 367.538 -270.580104)
		(end 368.004852 -270.846042)
		(width 0.350012)
		(layer "F.Cu")
		(net "GND")
	)
	(segment
		(start 318.226186 -360.66095)
		(end 317.210186 -360.66095)
		(width 0.381)
		(layer "F.Cu")
		(net "GND")
	)
	(segment
		(start 202.147932 -210.085432)
		(end 203.532232 -210.085432)
		(width 0.4572)
		(layer "F.Cu")
		(net "GND")
	)
	(segment
		(start 427.456092 -303.585118)
		(end 428.840392 -303.585118)
		(width 0.4572)
		(layer "F.Cu")
		(net "GND")
	)
	(segment
		(start 367.914936 -401.25015)
		(end 367.92027 -401.25015)
		(width 0.254)
		(layer "F.Cu")
		(net "GND")
	)
	(segment
		(start 369.11788 -229.360222)
		(end 369.584732 -229.094284)
		(width 0.350012)
		(layer "F.Cu")
		(net "GND")
	)
	(segment
		(start 156.61894 -390.160002)
		(end 156.09824 -390.160002)
		(width 0.254)
		(layer "F.Cu")
		(net "GND")
	)
	(segment
		(start 337.92795 -294.070024)
		(end 337.461098 -294.335962)
		(width 0.350012)
		(layer "F.Cu")
		(net "GND")
	)
	(segment
		(start 97.507806 -269.770352)
		(end 97.040954 -270.03629)
		(width 0.350012)
		(layer "F.Cu")
		(net "GND")
	)
	(segment
		(start 105.497884 -278.680418)
		(end 105.031032 -278.946356)
		(width 0.350012)
		(layer "F.Cu")
		(net "GND")
	)
	(segment
		(start 109.257846 -291.64026)
		(end 108.790994 -291.906198)
		(width 0.350012)
		(layer "F.Cu")
		(net "GND")
	)
	(segment
		(start 84.79028 -384.617722)
		(end 84.19846 -384.617722)
		(width 0.254)
		(layer "F.Cu")
		(net "GND")
	)
	(segment
		(start 50.375566 -349.302324)
		(end 50.461926 -349.09379)
		(width 0.2286)
		(layer "F.Cu")
		(net "GND")
	)
	(segment
		(start 372.877842 -232.599992)
		(end 373.344694 -232.334054)
		(width 0.350012)
		(layer "F.Cu")
		(net "GND")
	)
	(segment
		(start 316.917832 -392.004296)
		(end 317.217806 -392.30427)
		(width 0.254)
		(layer "F.Cu")
		(net "GND")
	)
	(segment
		(start 136.517888 -262.480298)
		(end 136.98474 -262.746236)
		(width 0.350012)
		(layer "F.Cu")
		(net "GND")
	)
	(segment
		(start 277.192232 -202.434952)
		(end 275.807932 -202.434952)
		(width 0.4572)
		(layer "F.Cu")
		(net "GND")
	)
	(segment
		(start 58.668158 -12.374118)
		(end 58.666888 -12.372848)
		(width 0.3556)
		(layer "F.Cu")
		(net "GND")
	)
	(segment
		(start 126.817882 -234.220258)
		(end 127.284734 -233.95432)
		(width 0.350012)
		(layer "F.Cu")
		(net "GND")
	)
	(segment
		(start 93.79839 -390.160002)
		(end 94.31909 -390.160002)
		(width 0.254)
		(layer "F.Cu")
		(net "GND")
	)
	(segment
		(start 297.820842 -399.6055)
		(end 297.820842 -400.177)
		(width 0.254)
		(layer "F.Cu")
		(net "GND")
	)
	(segment
		(start 382.748028 -246.370094)
		(end 383.21488 -246.104156)
		(width 0.350012)
		(layer "F.Cu")
		(net "GND")
	)
	(segment
		(start 178.289458 -52.799996)
		(end 177.108358 -52.799996)
		(width 0.254)
		(layer "F.Cu")
		(net "GND")
	)
	(segment
		(start 62.117986 -383.402586)
		(end 62.117986 -382.951482)
		(width 0.254)
		(layer "F.Cu")
		(net "GND")
	)
	(segment
		(start 46.101762 -388.13105)
		(end 46.30166 -388.330948)
		(width 0.254)
		(layer "F.Cu")
		(net "GND")
	)
	(segment
		(start 414.758124 -12.37488)
		(end 414.758124 -12.374118)
		(width 0.3556)
		(layer "F.Cu")
		(net "GND")
	)
	(segment
		(start 315.02096 -340.252812)
		(end 315.651896 -340.252812)
		(width 0.381)
		(layer "F.Cu")
		(net "GND")
	)
	(segment
		(start 345.447874 -287.59023)
		(end 344.981022 -287.856168)
		(width 0.350012)
		(layer "F.Cu")
		(net "GND")
	)
	(segment
		(start 153.738834 -321.715892)
		(end 153.865834 -321.842892)
		(width 0.4064)
		(layer "F.Cu")
		(net "GND")
	)
	(segment
		(start 384.465576 -63.648082)
		(end 384.7846 -63.967106)
		(width 0.4572)
		(layer "F.Cu")
		(net "GND")
	)
	(segment
		(start 193.42354 -416.955986)
		(end 193.42354 -416.162236)
		(width 0.381)
		(layer "F.Cu")
		(net "GND")
	)
	(segment
		(start 280.635964 -312.935112)
		(end 282.020264 -312.935112)
		(width 0.4572)
		(layer "F.Cu")
		(net "GND")
	)
	(segment
		(start 60.91809 -391.281158)
		(end 61.016642 -391.37971)
		(width 0.254)
		(layer "F.Cu")
		(net "GND")
	)
	(segment
		(start 330.108052 -225.310192)
		(end 329.6412 -225.044254)
		(width 0.350012)
		(layer "F.Cu")
		(net "GND")
	)
	(segment
		(start 206.248 -277.235412)
		(end 204.8637 -277.235412)
		(width 0.4572)
		(layer "F.Cu")
		(net "GND")
	)
	(segment
		(start 379.75794 -280.300176)
		(end 380.224792 -280.566114)
		(width 0.350012)
		(layer "F.Cu")
		(net "GND")
	)
	(segment
		(start 114.597942 -226.120452)
		(end 115.064794 -225.854514)
		(width 0.350012)
		(layer "F.Cu")
		(net "GND")
	)
	(segment
		(start 299.82414 -286.585152)
		(end 298.43984 -286.585152)
		(width 0.4572)
		(layer "F.Cu")
		(net "GND")
	)
	(segment
		(start 372.238016 -285.160212)
		(end 372.704868 -285.42615)
		(width 0.350012)
		(layer "F.Cu")
		(net "GND")
	)
	(segment
		(start 58.870596 -390.160002)
		(end 58.818018 -390.761474)
		(width 0.254)
		(layer "F.Cu")
		(net "GND")
	)
	(segment
		(start 140.385546 -74.79919)
		(end 140.385546 -74.125582)
		(width 0.254)
		(layer "F.Cu")
		(net "GND")
	)
	(segment
		(start 18.54708 -11.26998)
		(end 18.54581 -10.16508)
		(width 0.3556)
		(layer "F.Cu")
		(net "GND")
	)
	(segment
		(start 322.583556 -394.831062)
		(end 322.070476 -395.0208)
		(width 0.254)
		(layer "F.Cu")
		(net "GND")
	)
	(segment
		(start 411.092142 -140.383006)
		(end 411.019752 -140.310616)
		(width 0.1778)
		(layer "F.Cu")
		(net "GND")
	)
	(segment
		(start 240.096802 -70.543674)
		(end 239.465866 -70.543674)
		(width 0.4572)
		(layer "F.Cu")
		(net "GND")
	)
	(segment
		(start 206.248 -239.835436)
		(end 204.8637 -239.835436)
		(width 0.4572)
		(layer "F.Cu")
		(net "GND")
	)
	(segment
		(start 331.518006 -247.1801)
		(end 331.051154 -246.914162)
		(width 0.350012)
		(layer "F.Cu")
		(net "GND")
	)
	(segment
		(start 348.737936 -288.399982)
		(end 348.271084 -288.66592)
		(width 0.350012)
		(layer "F.Cu")
		(net "GND")
	)
	(segment
		(start 40.23995 -275.53539)
		(end 41.62425 -275.53539)
		(width 0.4572)
		(layer "F.Cu")
		(net "GND")
	)
	(segment
		(start 328.527918 -279.49017)
		(end 328.061066 -279.756108)
		(width 0.350012)
		(layer "F.Cu")
		(net "GND")
	)
	(segment
		(start 413.298386 -392.999722)
		(end 413.245808 -392.30427)
		(width 0.254)
		(layer "F.Cu")
		(net "GND")
	)
	(segment
		(start 176.072038 -277.235412)
		(end 174.687738 -277.235412)
		(width 0.4572)
		(layer "F.Cu")
		(net "GND")
	)
	(segment
		(start 420.49827 -398.542002)
		(end 419.819074 -398.542002)
		(width 0.254)
		(layer "F.Cu")
		(net "GND")
	)
	(segment
		(start 97.037906 -283.540454)
		(end 96.571054 -283.806392)
		(width 0.350012)
		(layer "F.Cu")
		(net "GND")
	)
	(segment
		(start 303.378362 -394.831062)
		(end 302.620934 -395.012926)
		(width 0.254)
		(layer "F.Cu")
		(net "GND")
	)
	(segment
		(start 353.437952 -280.300176)
		(end 352.9711 -280.566114)
		(width 0.350012)
		(layer "F.Cu")
		(net "GND")
	)
	(segment
		(start 433.166774 -12.372848)
		(end 433.168044 -12.374118)
		(width 0.3556)
		(layer "F.Cu")
		(net "GND")
	)
	(segment
		(start 339.977984 -227.74021)
		(end 339.511132 -227.474272)
		(width 0.350012)
		(layer "F.Cu")
		(net "GND")
	)
	(segment
		(start 130.407918 -289.210242)
		(end 130.87477 -289.47618)
		(width 0.350012)
		(layer "F.Cu")
		(net "GND")
	)
	(segment
		(start 450.088 -287.435036)
		(end 451.4723 -287.435036)
		(width 0.4572)
		(layer "F.Cu")
		(net "GND")
	)
	(segment
		(start 427.907958 -365.825532)
		(end 428.586138 -365.825532)
		(width 0.508)
		(layer "F.Cu")
		(net "GND")
	)
	(segment
		(start 380.86792 -233.409998)
		(end 381.334772 -233.14406)
		(width 0.350012)
		(layer "F.Cu")
		(net "GND")
	)
	(segment
		(start 326.81799 -240.700052)
		(end 326.351138 -240.434114)
		(width 0.350012)
		(layer "F.Cu")
		(net "GND")
	)
	(segment
		(start 77.467968 -225.310446)
		(end 77.001116 -225.044508)
		(width 0.350012)
		(layer "F.Cu")
		(net "GND")
	)
	(segment
		(start 332.060042 -393.96416)
		(end 332.593442 -393.96416)
		(width 0.254)
		(layer "F.Cu")
		(net "GND")
	)
	(segment
		(start 27.545792 -7.215124)
		(end 27.545792 -7.215886)
		(width 0.3556)
		(layer "F.Cu")
		(net "GND")
	)
	(segment
		(start 89.506298 -386.449062)
		(end 88.998298 -386.6388)
		(width 0.254)
		(layer "F.Cu")
		(net "GND")
	)
	(segment
		(start 81.058004 -293.260272)
		(end 80.591152 -293.52621)
		(width 0.350012)
		(layer "F.Cu")
		(net "GND")
	)
	(segment
		(start 141.687804 -294.070278)
		(end 142.154656 -294.336216)
		(width 0.350012)
		(layer "F.Cu")
		(net "GND")
	)
	(segment
		(start 90.457782 -290.020248)
		(end 89.99093 -290.286186)
		(width 0.350012)
		(layer "F.Cu")
		(net "GND")
	)
	(segment
		(start 99.08794 -223.690434)
		(end 98.621088 -223.424496)
		(width 0.350012)
		(layer "F.Cu")
		(net "GND")
	)
	(segment
		(start 387.917944 -252.040136)
		(end 388.384796 -251.774198)
		(width 0.350012)
		(layer "F.Cu")
		(net "GND")
	)
	(segment
		(start 410.29001 -392.999722)
		(end 409.69819 -392.999722)
		(width 0.254)
		(layer "F.Cu")
		(net "GND")
	)
	(segment
		(start 386.03809 -230.97998)
		(end 386.504942 -230.714042)
		(width 0.350012)
		(layer "F.Cu")
		(net "GND")
	)
	(segment
		(start 153.698194 -384.617722)
		(end 153.645616 -383.92227)
		(width 0.254)
		(layer "F.Cu")
		(net "GND")
	)
	(segment
		(start 116.018056 -382.951482)
		(end 116.116608 -382.85293)
		(width 0.254)
		(layer "F.Cu")
		(net "GND")
	)
	(segment
		(start 427.456092 -219.435172)
		(end 428.840392 -219.435172)
		(width 0.4572)
		(layer "F.Cu")
		(net "GND")
	)
	(segment
		(start 338.56803 -244.750082)
		(end 338.101178 -244.484144)
		(width 0.350012)
		(layer "F.Cu")
		(net "GND")
	)
	(segment
		(start 93.397578 -157.355032)
		(end 93.397578 -156.829252)
		(width 0.4572)
		(layer "F.Cu")
		(net "GND")
	)
	(segment
		(start 381.338074 -240.700052)
		(end 381.804926 -240.434114)
		(width 0.350012)
		(layer "F.Cu")
		(net "GND")
	)
	(segment
		(start 69.894958 -146.939762)
		(end 69.647054 -147.187666)
		(width 0.254)
		(layer "F.Cu")
		(net "GND")
	)
	(segment
		(start 423.827448 -56.097678)
		(end 424.998642 -56.097678)
		(width 0.4572)
		(layer "F.Cu")
		(net "GND")
	)
	(segment
		(start 371.467888 -231.789986)
		(end 371.93474 -231.524048)
		(width 0.350012)
		(layer "F.Cu")
		(net "GND")
	)
	(segment
		(start 386.338064 -293.260018)
		(end 386.804916 -293.525956)
		(width 0.350012)
		(layer "F.Cu")
		(net "GND")
	)
	(segment
		(start 22.07895 -357.632)
		(end 21.336 -357.632)
		(width 0.381)
		(layer "F.Cu")
		(net "GND")
	)
	(segment
		(start 59.71794 -383.402586)
		(end 59.71794 -383.622296)
		(width 0.254)
		(layer "F.Cu")
		(net "GND")
	)
	(segment
		(start 34.379662 -430.799748)
		(end 34.379662 -430.190148)
		(width 0.3556)
		(layer "F.Cu")
		(net "GND")
	)
	(segment
		(start 163.168076 -32.523938)
		(end 163.168076 -33.317688)
		(width 0.4572)
		(layer "F.Cu")
		(net "GND")
	)
	(segment
		(start 179.236878 -354.360734)
		(end 179.267866 -354.360734)
		(width 0.2286)
		(layer "F.Cu")
		(net "GND")
	)
	(segment
		(start 164.244274 -391.830814)
		(end 164.244274 -391.37971)
		(width 0.254)
		(layer "F.Cu")
		(net "GND")
	)
	(segment
		(start 144.677892 -224.50044)
		(end 145.144744 -224.234502)
		(width 0.350012)
		(layer "F.Cu")
		(net "GND")
	)
	(segment
		(start 128.318006 -390.761474)
		(end 128.018032 -391.281158)
		(width 0.254)
		(layer "F.Cu")
		(net "GND")
	)
	(segment
		(start 87.637874 -262.480298)
		(end 87.171022 -262.746236)
		(width 0.350012)
		(layer "F.Cu")
		(net "GND")
	)
	(segment
		(start 13.613384 -389.163814)
		(end 13.778738 -389.329168)
		(width 0.2032)
		(layer "F.Cu")
		(net "GND")
	)
	(segment
		(start 384.457956 -278.680164)
		(end 384.924808 -278.946102)
		(width 0.350012)
		(layer "F.Cu")
		(net "GND")
	)
	(segment
		(start 143.567912 -264.910316)
		(end 144.034764 -265.176254)
		(width 0.350012)
		(layer "F.Cu")
		(net "GND")
	)
	(segment
		(start 327.117964 -264.100056)
		(end 326.651112 -264.365994)
		(width 0.350012)
		(layer "F.Cu")
		(net "GND")
	)
	(segment
		(start 343.268046 -236.650022)
		(end 342.801194 -236.384084)
		(width 0.350012)
		(layer "F.Cu")
		(net "GND")
	)
	(segment
		(start 283.370528 -115.631976)
		(end 284.127956 -115.631976)
		(width 0.3556)
		(layer "F.Cu")
		(net "GND")
	)
	(segment
		(start 331.81798 -285.160212)
		(end 331.351128 -285.42615)
		(width 0.350012)
		(layer "F.Cu")
		(net "GND")
	)
	(segment
		(start 157.29839 -388.138924)
		(end 157.94609 -388.328662)
		(width 0.254)
		(layer "F.Cu")
		(net "GND")
	)
	(segment
		(start 133.63448 -388.431024)
		(end 133.41477 -388.431024)
		(width 0.254)
		(layer "F.Cu")
		(net "GND")
	)
	(segment
		(start 196.457824 -63.447422)
		(end 196.458078 -63.447168)
		(width 0.4572)
		(layer "F.Cu")
		(net "GND")
	)
	(segment
		(start 171.97197 -231.335326)
		(end 173.35627 -231.335326)
		(width 0.4572)
		(layer "F.Cu")
		(net "GND")
	)
	(segment
		(start 183.878982 -35.836098)
		(end 183.930036 -35.887152)
		(width 0.4572)
		(layer "F.Cu")
		(net "GND")
	)
	(segment
		(start 100.497894 -224.50044)
		(end 100.031042 -224.234502)
		(width 0.350012)
		(layer "F.Cu")
		(net "GND")
	)
	(segment
		(start 346.858082 -262.480044)
		(end 346.39123 -262.745982)
		(width 0.350012)
		(layer "F.Cu")
		(net "GND")
	)
	(segment
		(start 343.268046 -223.69018)
		(end 342.801194 -223.424242)
		(width 0.350012)
		(layer "F.Cu")
		(net "GND")
	)
	(segment
		(start 82.390234 -384.617722)
		(end 81.798414 -384.617722)
		(width 0.254)
		(layer "F.Cu")
		(net "GND")
	)
	(segment
		(start 354.842318 -393.213082)
		(end 354.628958 -392.999722)
		(width 0.254)
		(layer "F.Cu")
		(net "GND")
	)
	(segment
		(start 351.087944 -274.630134)
		(end 350.621092 -274.896072)
		(width 0.350012)
		(layer "F.Cu")
		(net "GND")
	)
	(segment
		(start 350.78797 -246.370094)
		(end 350.321118 -246.104156)
		(width 0.350012)
		(layer "F.Cu")
		(net "GND")
	)
	(segment
		(start 307.118258 -396.710662)
		(end 306.470304 -396.520924)
		(width 0.254)
		(layer "F.Cu")
		(net "GND")
	)
	(segment
		(start 96.198436 -386.6388)
		(end 96.706436 -386.449062)
		(width 0.254)
		(layer "F.Cu")
		(net "GND")
	)
	(segment
		(start 12.235688 -136.875266)
		(end 12.296648 -136.814306)
		(width 0.254)
		(layer "F.Cu")
		(net "GND")
	)
	(segment
		(start 25.152096 -287.43529)
		(end 26.536396 -287.43529)
		(width 0.4572)
		(layer "F.Cu")
		(net "GND")
	)
	(segment
		(start 82.99831 -384.617722)
		(end 82.945732 -383.92227)
		(width 0.254)
		(layer "F.Cu")
		(net "GND")
	)
	(segment
		(start 162.90417 -428.23638)
		(end 162.90417 -428.02048)
		(width 0.3048)
		(layer "F.Cu")
		(net "GND")
	)
	(segment
		(start 439.512456 -44.329604)
		(end 439.512456 -45.107352)
		(width 0.4572)
		(layer "F.Cu")
		(net "GND")
	)
	(segment
		(start 334.808068 -228.550216)
		(end 334.341216 -228.284278)
		(width 0.350012)
		(layer "F.Cu")
		(net "GND")
	)
	(segment
		(start 427.975268 -58.797698)
		(end 427.975268 -59.436)
		(width 0.4572)
		(layer "F.Cu")
		(net "GND")
	)
	(segment
		(start 328.998072 -283.5402)
		(end 328.53122 -283.806138)
		(width 0.350012)
		(layer "F.Cu")
		(net "GND")
	)
	(segment
		(start 166.921942 -440.140344)
		(end 167.556942 -440.140344)
		(width 0.4318)
		(layer "F.Cu")
		(net "GND")
	)
	(segment
		(start 155.745688 -383.402586)
		(end 155.745688 -382.951482)
		(width 0.254)
		(layer "F.Cu")
		(net "GND")
	)
	(segment
		(start 330.108052 -226.930204)
		(end 329.6412 -226.664266)
		(width 0.350012)
		(layer "F.Cu")
		(net "GND")
	)
	(segment
		(start 138.397996 -264.10031)
		(end 138.864848 -264.366248)
		(width 0.350012)
		(layer "F.Cu")
		(net "GND")
	)
	(segment
		(start 69.73697 -387.084062)
		(end 70.265798 -387.084062)
		(width 0.381)
		(layer "F.Cu")
		(net "GND")
	)
	(segment
		(start 168.418256 -393.510262)
		(end 168.242996 -393.335002)
		(width 0.254)
		(layer "F.Cu")
		(net "GND")
	)
	(segment
		(start 128.227836 -233.410252)
		(end 128.694688 -233.144314)
		(width 0.350012)
		(layer "F.Cu")
		(net "GND")
	)
	(segment
		(start 115.83797 -286.780478)
		(end 116.304822 -287.046416)
		(width 0.350012)
		(layer "F.Cu")
		(net "GND")
	)
	(segment
		(start 180.091334 -353.120452)
		(end 180.519832 -353.120452)
		(width 0.2286)
		(layer "F.Cu")
		(net "GND")
	)
	(segment
		(start 134.80796 -246.370348)
		(end 135.274812 -246.10441)
		(width 0.350012)
		(layer "F.Cu")
		(net "GND")
	)
	(segment
		(start 83.877912 -281.920442)
		(end 83.41106 -282.18638)
		(width 0.350012)
		(layer "F.Cu")
		(net "GND")
	)
	(segment
		(start 371.938042 -252.040136)
		(end 372.404894 -251.774198)
		(width 0.350012)
		(layer "F.Cu")
		(net "GND")
	)
	(segment
		(start 404.5458 -391.784586)
		(end 404.5458 -391.333482)
		(width 0.254)
		(layer "F.Cu")
		(net "GND")
	)
	(segment
		(start 128.227836 -244.750336)
		(end 128.694688 -244.484398)
		(width 0.350012)
		(layer "F.Cu")
		(net "GND")
	)
	(segment
		(start 256.842006 -124.115068)
		(end 256.232406 -124.115068)
		(width 0.3556)
		(layer "F.Cu")
		(net "GND")
	)
	(segment
		(start 358.778048 -237.460028)
		(end 358.311196 -237.19409)
		(width 0.350012)
		(layer "F.Cu")
		(net "GND")
	)
	(segment
		(start 116.77777 -270.580358)
		(end 117.244622 -270.846296)
		(width 0.350012)
		(layer "F.Cu")
		(net "GND")
	)
	(segment
		(start 316.917832 -391.784586)
		(end 316.917832 -391.333482)
		(width 0.254)
		(layer "F.Cu")
		(net "GND")
	)
	(segment
		(start 212.36051 -110.397036)
		(end 211.94522 -110.397036)
		(width 0.381)
		(layer "F.Cu")
		(net "GND")
	)
	(segment
		(start 79.177896 -275.440394)
		(end 78.711044 -275.706332)
		(width 0.350012)
		(layer "F.Cu")
		(net "GND")
	)
	(segment
		(start 340.328504 -340.282022)
		(end 340.075266 -340.53526)
		(width 0.381)
		(layer "F.Cu")
		(net "GND")
	)
	(segment
		(start 202.254104 -339.455252)
		(end 202.830176 -339.455252)
		(width 0.1778)
		(layer "F.Cu")
		(net "GND")
	)
	(segment
		(start 412.606236 -394.831062)
		(end 412.098236 -395.0208)
		(width 0.254)
		(layer "F.Cu")
		(net "GND")
	)
	(segment
		(start 98.918014 -273.820382)
		(end 98.451162 -274.08632)
		(width 0.350012)
		(layer "F.Cu")
		(net "GND")
	)
	(segment
		(start 428.908972 -356.397814)
		(end 428.655734 -356.651052)
		(width 0.381)
		(layer "F.Cu")
		(net "GND")
	)
	(segment
		(start 125.238002 -277.060406)
		(end 125.704854 -277.326344)
		(width 0.350012)
		(layer "F.Cu")
		(net "GND")
	)
	(segment
		(start 307.317648 -391.784586)
		(end 307.317648 -391.333482)
		(width 0.2032)
		(layer "F.Cu")
		(net "GND")
	)
	(segment
		(start 171.97197 -294.235378)
		(end 173.35627 -294.235378)
		(width 0.4572)
		(layer "F.Cu")
		(net "GND")
	)
	(segment
		(start 66.070734 -390.160002)
		(end 65.391284 -390.160002)
		(width 0.254)
		(layer "F.Cu")
		(net "GND")
	)
	(segment
		(start 23.946866 -9.423654)
		(end 23.948136 -9.424924)
		(width 0.3556)
		(layer "F.Cu")
		(net "GND")
	)
	(segment
		(start 403.698202 -395.0208)
		(end 403.006306 -394.831062)
		(width 0.254)
		(layer "F.Cu")
		(net "GND")
	)
	(segment
		(start 77.467968 -228.55047)
		(end 77.001116 -228.284532)
		(width 0.350012)
		(layer "F.Cu")
		(net "GND")
	)
	(segment
		(start 304.917856 -391.784586)
		(end 304.917856 -391.333482)
		(width 0.254)
		(layer "F.Cu")
		(net "GND")
	)
	(segment
		(start 414.756854 -9.423654)
		(end 414.758124 -9.424924)
		(width 0.3556)
		(layer "F.Cu")
		(net "GND")
	)
	(segment
		(start 304.917856 -392.004296)
		(end 305.21783 -392.30427)
		(width 0.254)
		(layer "F.Cu")
		(net "GND")
	)
	(segment
		(start 139.977876 -222.880428)
		(end 140.444728 -222.61449)
		(width 0.350012)
		(layer "F.Cu")
		(net "GND")
	)
	(segment
		(start 335.277968 -235.840016)
		(end 334.811116 -235.574078)
		(width 0.350012)
		(layer "F.Cu")
		(net "GND")
	)
	(segment
		(start 381.167894 -282.730194)
		(end 381.634746 -282.996132)
		(width 0.350012)
		(layer "F.Cu")
		(net "GND")
	)
	(segment
		(start 303.748948 -14.50721)
		(end 303.774348 -14.48181)
		(width 0.508)
		(layer "F.Cu")
		(net "GND")
	)
	(segment
		(start 387.448044 -252.850142)
		(end 387.914896 -252.584204)
		(width 0.350012)
		(layer "F.Cu")
		(net "GND")
	)
	(segment
		(start 139.977876 -250.420378)
		(end 140.444728 -250.15444)
		(width 0.350012)
		(layer "F.Cu")
		(net "GND")
	)
	(segment
		(start 437.2356 -95.113348)
		(end 437.515 -94.833948)
		(width 0.3556)
		(layer "F.Cu")
		(net "GND")
	)
	(segment
		(start 409.69819 -392.999722)
		(end 409.645612 -392.30427)
		(width 0.254)
		(layer "F.Cu")
		(net "GND")
	)
	(segment
		(start 431.55616 -199.885046)
		(end 430.17186 -199.885046)
		(width 0.4572)
		(layer "F.Cu")
		(net "GND")
	)
	(segment
		(start 369.72113 -395.012926)
		(end 369.72113 -395.613128)
		(width 0.254)
		(layer "F.Cu")
		(net "GND")
	)
	(segment
		(start 340.277958 -285.160212)
		(end 339.811106 -285.42615)
		(width 0.350012)
		(layer "F.Cu")
		(net "GND")
	)
	(segment
		(start 128.227836 -246.370348)
		(end 128.694688 -246.10441)
		(width 0.350012)
		(layer "F.Cu")
		(net "GND")
	)
	(segment
		(start 385.811776 -63.3095)
		(end 385.299204 -63.3095)
		(width 0.4572)
		(layer "F.Cu")
		(net "GND")
	)
	(segment
		(start 131.917948 -390.761474)
		(end 131.970526 -390.160002)
		(width 0.254)
		(layer "F.Cu")
		(net "GND")
	)
	(segment
		(start 363.634274 -416.964114)
		(end 364.065058 -417.394898)
		(width 0.381)
		(layer "F.Cu")
		(net "GND")
	)
	(segment
		(start 284.736032 -202.434952)
		(end 283.351732 -202.434952)
		(width 0.4572)
		(layer "F.Cu")
		(net "GND")
	)
	(segment
		(start 379.457966 -234.220004)
		(end 379.924818 -233.954066)
		(width 0.350012)
		(layer "F.Cu")
		(net "GND")
	)
	(segment
		(start 82.99831 -388.138924)
		(end 82.446368 -388.328662)
		(width 0.254)
		(layer "F.Cu")
		(net "GND")
	)
	(segment
		(start 354.628958 -392.387836)
		(end 354.545392 -392.30427)
		(width 0.254)
		(layer "F.Cu")
		(net "GND")
	)
	(segment
		(start 115.08359 -418.734494)
		(end 115.341146 -418.99205)
		(width 0.381)
		(layer "F.Cu")
		(net "GND")
	)
	(segment
		(start 92.33789 -291.64026)
		(end 91.871038 -291.906198)
		(width 0.350012)
		(layer "F.Cu")
		(net "GND")
	)
	(segment
		(start 17.608042 -221.985332)
		(end 18.992342 -221.985332)
		(width 0.4572)
		(layer "F.Cu")
		(net "GND")
	)
	(segment
		(start 277.192232 -237.285022)
		(end 275.807932 -237.285022)
		(width 0.4572)
		(layer "F.Cu")
		(net "GND")
	)
	(segment
		(start 97.577402 -75.147932)
		(end 96.837246 -75.888088)
		(width 0.4572)
		(layer "F.Cu")
		(net "GND")
	)
	(segment
		(start 309.46217 -392.999722)
		(end 310.070246 -392.999722)
		(width 0.254)
		(layer "F.Cu")
		(net "GND")
	)
	(segment
		(start 52.011072 -402.878036)
		(end 52.770532 -402.878036)
		(width 0.381)
		(layer "F.Cu")
		(net "GND")
	)
	(segment
		(start 325.408036 -244.750082)
		(end 324.75297 -244.750082)
		(width 0.350012)
		(layer "F.Cu")
		(net "GND")
	)
	(segment
		(start 338.868004 -295.690036)
		(end 338.401152 -295.955974)
		(width 0.350012)
		(layer "F.Cu")
		(net "GND")
	)
	(segment
		(start 332.28788 -263.29005)
		(end 331.821028 -263.555988)
		(width 0.350012)
		(layer "F.Cu")
		(net "GND")
	)
	(segment
		(start 333.697834 -286.780224)
		(end 333.230982 -287.046162)
		(width 0.350012)
		(layer "F.Cu")
		(net "GND")
	)
	(segment
		(start 304.578258 -394.831062)
		(end 304.070258 -395.0208)
		(width 0.254)
		(layer "F.Cu")
		(net "GND")
	)
	(segment
		(start 351.65538 -434.857652)
		(end 351.03943 -434.857652)
		(width 0.381)
		(layer "F.Cu")
		(net "GND")
	)
	(segment
		(start 84.347812 -287.590484)
		(end 83.88096 -287.856422)
		(width 0.350012)
		(layer "F.Cu")
		(net "GND")
	)
	(segment
		(start 419.912038 -231.335072)
		(end 421.296338 -231.335072)
		(width 0.4572)
		(layer "F.Cu")
		(net "GND")
	)
	(segment
		(start 271.770094 -349.781622)
		(end 272.340578 -349.211138)
		(width 0.2286)
		(layer "F.Cu")
		(net "GND")
	)
	(segment
		(start 150.618952 -390.160002)
		(end 150.098252 -390.160002)
		(width 0.254)
		(layer "F.Cu")
		(net "GND")
	)
	(segment
		(start 146.087846 -233.410252)
		(end 146.742912 -233.410252)
		(width 0.350012)
		(layer "F.Cu")
		(net "GND")
	)
	(segment
		(start 343.798144 -392.999722)
		(end 343.745566 -392.30427)
		(width 0.254)
		(layer "F.Cu")
		(net "GND")
	)
	(segment
		(start 49.016412 -394.649452)
		(end 49.016412 -393.902438)
		(width 0.381)
		(layer "F.Cu")
		(net "GND")
	)
	(segment
		(start 168.527984 -230.485442)
		(end 167.143684 -230.485442)
		(width 0.4572)
		(layer "F.Cu")
		(net "GND")
	)
	(segment
		(start 424.168062 -12.37488)
		(end 424.168062 -12.374118)
		(width 0.3556)
		(layer "F.Cu")
		(net "GND")
	)
	(segment
		(start 303.268126 -231.335072)
		(end 304.652426 -231.335072)
		(width 0.4572)
		(layer "F.Cu")
		(net "GND")
	)
	(segment
		(start 350.31807 -224.500186)
		(end 349.851218 -224.234248)
		(width 0.350012)
		(layer "F.Cu")
		(net "GND")
	)
	(segment
		(start 343.3445 -19.13509)
		(end 343.3445 -18.497804)
		(width 0.4572)
		(layer "F.Cu")
		(net "GND")
	)
	(segment
		(start 368.947954 -266.530074)
		(end 369.414806 -266.796012)
		(width 0.350012)
		(layer "F.Cu")
		(net "GND")
	)
	(segment
		(start 95.518986 -390.160002)
		(end 96.198436 -390.160002)
		(width 0.254)
		(layer "F.Cu")
		(net "GND")
	)
	(segment
		(start 119.337582 -168.858184)
		(end 118.864634 -169.331132)
		(width 0.2286)
		(layer "F.Cu")
		(net "GND")
	)
	(segment
		(start 86.868 -228.55047)
		(end 86.401148 -228.284532)
		(width 0.350012)
		(layer "F.Cu")
		(net "GND")
	)
	(segment
		(start 100.027994 -252.850396)
		(end 99.561142 -252.584458)
		(width 0.350012)
		(layer "F.Cu")
		(net "GND")
	)
	(segment
		(start 337.92795 -268.150086)
		(end 337.461098 -268.416024)
		(width 0.350012)
		(layer "F.Cu")
		(net "GND")
	)
	(segment
		(start 374.28805 -246.370094)
		(end 374.754902 -246.104156)
		(width 0.350012)
		(layer "F.Cu")
		(net "GND")
	)
	(segment
		(start 26.135584 -395.082268)
		(end 25.932384 -395.082268)
		(width 0.4572)
		(layer "F.Cu")
		(net "GND")
	)
	(segment
		(start 205.192884 -343.404952)
		(end 205.802484 -343.404952)
		(width 0.4572)
		(layer "F.Cu")
		(net "GND")
	)
	(segment
		(start 103.147876 -289.210242)
		(end 102.681024 -289.47618)
		(width 0.350012)
		(layer "F.Cu")
		(net "GND")
	)
	(segment
		(start 419.230302 -440.412886)
		(end 418.599366 -440.412886)
		(width 0.381)
		(layer "F.Cu")
		(net "GND")
	)
	(segment
		(start 332.92796 -249.610118)
		(end 332.461108 -249.34418)
		(width 0.350012)
		(layer "F.Cu")
		(net "GND")
	)
	(segment
		(start 90.198448 -384.617722)
		(end 90.14587 -383.92227)
		(width 0.254)
		(layer "F.Cu")
		(net "GND")
	)
	(segment
		(start 138.567922 -222.070422)
		(end 138.567922 -221.50959)
		(width 0.350012)
		(layer "F.Cu")
		(net "GND")
	)
	(segment
		(start 363.914436 -409.931616)
		(end 363.23905 -409.931616)
		(width 0.381)
		(layer "F.Cu")
		(net "GND")
	)
	(segment
		(start 389.327898 -252.850142)
		(end 389.79475 -252.584204)
		(width 0.350012)
		(layer "F.Cu")
		(net "GND")
	)
	(segment
		(start 447.16192 -8.320024)
		(end 447.16192 -7.217156)
		(width 0.3556)
		(layer "F.Cu")
		(net "GND")
	)
	(segment
		(start 409.345638 -399.663158)
		(end 409.645612 -399.143474)
		(width 0.254)
		(layer "F.Cu")
		(net "GND")
	)
	(segment
		(start 117.316504 -391.830814)
		(end 117.316504 -391.37971)
		(width 0.254)
		(layer "F.Cu")
		(net "GND")
	)
	(segment
		(start 405.64562 -7.215886)
		(end 405.64689 -7.217156)
		(width 0.3556)
		(layer "F.Cu")
		(net "GND")
	)
	(segment
		(start 124.297948 -286.780478)
		(end 124.7648 -287.046162)
		(width 0.350012)
		(layer "F.Cu")
		(net "GND")
	)
	(segment
		(start 375.917968 -399.143474)
		(end 375.970546 -398.542002)
		(width 0.254)
		(layer "F.Cu")
		(net "GND")
	)
	(segment
		(start 124.297948 -267.340334)
		(end 124.7648 -267.606272)
		(width 0.350012)
		(layer "F.Cu")
		(net "GND")
	)
	(segment
		(start 344.945462 -399.143474)
		(end 344.645488 -399.663158)
		(width 0.254)
		(layer "F.Cu")
		(net "GND")
	)
	(segment
		(start 395.32687 -56.9595)
		(end 394.457174 -56.089804)
		(width 0.4572)
		(layer "F.Cu")
		(net "GND")
	)
	(segment
		(start 373.817896 -235.840016)
		(end 374.284748 -235.574078)
		(width 0.350012)
		(layer "F.Cu")
		(net "GND")
	)
	(segment
		(start 387.917944 -242.320064)
		(end 388.384796 -242.054126)
		(width 0.350012)
		(layer "F.Cu")
		(net "GND")
	)
	(segment
		(start 187.316872 -429.801782)
		(end 187.5917 -430.07661)
		(width 0.381)
		(layer "F.Cu")
		(net "GND")
	)
	(segment
		(start 176.115218 -92.285566)
		(end 176.322736 -92.493084)
		(width 0.381)
		(layer "F.Cu")
		(net "GND")
	)
	(segment
		(start 324.168262 -402.4757)
		(end 324.168262 -402.163788)
		(width 0.254)
		(layer "F.Cu")
		(net "GND")
	)
	(segment
		(start 102.378002 -224.50044)
		(end 101.91115 -224.234502)
		(width 0.350012)
		(layer "F.Cu")
		(net "GND")
	)
	(segment
		(start 171.97197 -278.085296)
		(end 173.35627 -278.085296)
		(width 0.4572)
		(layer "F.Cu")
		(net "GND")
	)
	(segment
		(start 198.7042 -305.285394)
		(end 197.3199 -305.285394)
		(width 0.4572)
		(layer "F.Cu")
		(net "GND")
	)
	(segment
		(start 106.437938 -270.580358)
		(end 105.971086 -270.846296)
		(width 0.350012)
		(layer "F.Cu")
		(net "GND")
	)
	(segment
		(start 98.617786 -243.94033)
		(end 98.150934 -243.674392)
		(width 0.350012)
		(layer "F.Cu")
		(net "GND")
	)
	(segment
		(start 306.117752 -391.784586)
		(end 306.117752 -392.004296)
		(width 0.254)
		(layer "F.Cu")
		(net "GND")
	)
	(segment
		(start 418.212778 -160.702498)
		(end 418.18179 -160.702498)
		(width 0.2286)
		(layer "F.Cu")
		(net "GND")
	)
	(segment
		(start 329.17384 -411.14091)
		(end 329.17384 -412.025338)
		(width 0.381)
		(layer "F.Cu")
		(net "GND")
	)
	(segment
		(start 44.340018 -227.935282)
		(end 42.955718 -227.935282)
		(width 0.4572)
		(layer "F.Cu")
		(net "GND")
	)
	(segment
		(start 78.028546 -393.900152)
		(end 77.215746 -393.900152)
		(width 0.254)
		(layer "F.Cu")
		(net "GND")
	)
	(segment
		(start 441.430156 -399.613628)
		(end 441.655708 -399.613628)
		(width 0.2286)
		(layer "F.Cu")
		(net "GND")
	)
	(segment
		(start 349.378016 -232.599992)
		(end 348.911164 -232.334054)
		(width 0.350012)
		(layer "F.Cu")
		(net "GND")
	)
	(segment
		(start 166.462202 -388.13105)
		(end 166.162228 -388.431024)
		(width 0.254)
		(layer "F.Cu")
		(net "GND")
	)
	(segment
		(start 394.327888 -273.010122)
		(end 394.982954 -273.010122)
		(width 0.350012)
		(layer "F.Cu")
		(net "GND")
	)
	(segment
		(start 374.588024 -268.150086)
		(end 375.054876 -268.416024)
		(width 0.350012)
		(layer "F.Cu")
		(net "GND")
	)
	(segment
		(start 438.2516 -94.503748)
		(end 438.427876 -94.327472)
		(width 0.3556)
		(layer "F.Cu")
		(net "GND")
	)
	(segment
		(start 435.000146 -296.78503)
		(end 436.384446 -296.78503)
		(width 0.4572)
		(layer "F.Cu")
		(net "GND")
	)
	(segment
		(start 356.25786 -267.34008)
		(end 355.791008 -267.606018)
		(width 0.350012)
		(layer "F.Cu")
		(net "GND")
	)
	(segment
		(start 383.048002 -269.770098)
		(end 383.514854 -270.036036)
		(width 0.350012)
		(layer "F.Cu")
		(net "GND")
	)
	(segment
		(start 124.297948 -275.440394)
		(end 124.7648 -275.706332)
		(width 0.350012)
		(layer "F.Cu")
		(net "GND")
	)
	(segment
		(start 253.413006 -66.88836)
		(end 252.778006 -66.88836)
		(width 0.4572)
		(layer "F.Cu")
		(net "GND")
	)
	(segment
		(start 51.467004 -9.423654)
		(end 51.468274 -9.424924)
		(width 0.3556)
		(layer "F.Cu")
		(net "GND")
	)
	(segment
		(start 427.768258 -12.374118)
		(end 427.766988 -12.372848)
		(width 0.3556)
		(layer "F.Cu")
		(net "GND")
	)
	(segment
		(start 301.73295 -355.854)
		(end 300.99 -355.854)
		(width 0.381)
		(layer "F.Cu")
		(net "GND")
	)
	(segment
		(start 339.589872 -392.999722)
		(end 338.998052 -392.999722)
		(width 0.254)
		(layer "F.Cu")
		(net "GND")
	)
	(segment
		(start 385.567936 -225.310192)
		(end 386.034788 -225.044254)
		(width 0.350012)
		(layer "F.Cu")
		(net "GND")
	)
	(segment
		(start 327.117964 -286.780224)
		(end 326.651112 -287.045908)
		(width 0.350012)
		(layer "F.Cu")
		(net "GND")
	)
	(segment
		(start 376.81789 -391.784586)
		(end 376.81789 -391.333482)
		(width 0.254)
		(layer "F.Cu")
		(net "GND")
	)
	(segment
		(start 122.117866 -235.84027)
		(end 122.584718 -235.574332)
		(width 0.350012)
		(layer "F.Cu")
		(net "GND")
	)
	(segment
		(start 343.544144 -400.212814)
		(end 343.544144 -399.76171)
		(width 0.254)
		(layer "F.Cu")
		(net "GND")
	)
	(segment
		(start 94.387924 -249.610372)
		(end 93.921072 -249.344434)
		(width 0.350012)
		(layer "F.Cu")
		(net "GND")
	)
	(segment
		(start 134.80796 -239.8903)
		(end 135.274812 -239.624362)
		(width 0.350012)
		(layer "F.Cu")
		(net "GND")
	)
	(segment
		(start 85.398356 -390.160002)
		(end 85.919056 -390.160002)
		(width 0.254)
		(layer "F.Cu")
		(net "GND")
	)
	(segment
		(start 99.390454 -177.481484)
		(end 99.320604 -177.551334)
		(width 0.381)
		(layer "F.Cu")
		(net "GND")
	)
	(segment
		(start 403.698202 -398.542002)
		(end 403.645624 -399.143474)
		(width 0.254)
		(layer "F.Cu")
		(net "GND")
	)
	(segment
		(start 340.277958 -277.060152)
		(end 339.811106 -277.32609)
		(width 0.350012)
		(layer "F.Cu")
		(net "GND")
	)
	(segment
		(start 136.687814 -246.370348)
		(end 137.154666 -246.10441)
		(width 0.350012)
		(layer "F.Cu")
		(net "GND")
	)
	(segment
		(start 94.857824 -250.420378)
		(end 94.390972 -250.15444)
		(width 0.350012)
		(layer "F.Cu")
		(net "GND")
	)
	(segment
		(start 120.707912 -241.510312)
		(end 121.174764 -241.244374)
		(width 0.350012)
		(layer "F.Cu")
		(net "GND")
	)
	(segment
		(start 77.860144 -340.204552)
		(end 78.448154 -340.204552)
		(width 0.381)
		(layer "F.Cu")
		(net "GND")
	)
	(segment
		(start 112.717834 -252.04039)
		(end 113.184686 -251.774452)
		(width 0.350012)
		(layer "F.Cu")
		(net "GND")
	)
	(segment
		(start 118.357904 -242.320318)
		(end 118.824756 -242.05438)
		(width 0.350012)
		(layer "F.Cu")
		(net "GND")
	)
	(segment
		(start 371.767862 -281.110182)
		(end 372.234714 -281.37612)
		(width 0.350012)
		(layer "F.Cu")
		(net "GND")
	)
	(segment
		(start 360.657902 -239.08004)
		(end 361.124754 -238.814102)
		(width 0.350012)
		(layer "F.Cu")
		(net "GND")
	)
	(segment
		(start 80.287876 -225.310446)
		(end 79.821024 -225.044508)
		(width 0.350012)
		(layer "F.Cu")
		(net "GND")
	)
	(segment
		(start 372.237 -423.418)
		(end 372.491 -423.164)
		(width 0.254)
		(layer "F.Cu")
		(net "GND")
	)
	(segment
		(start 17.608042 -306.135278)
		(end 18.992342 -306.135278)
		(width 0.4572)
		(layer "F.Cu")
		(net "GND")
	)
	(segment
		(start 341.398098 -392.999722)
		(end 341.34552 -392.30427)
		(width 0.254)
		(layer "F.Cu")
		(net "GND")
	)
	(segment
		(start 384.208274 -412.212536)
		(end 384.208274 -411.343602)
		(width 0.381)
		(layer "F.Cu")
		(net "GND")
	)
	(segment
		(start 415.6456 -399.143474)
		(end 415.698178 -398.542002)
		(width 0.254)
		(layer "F.Cu")
		(net "GND")
	)
	(segment
		(start 123.21794 -383.622296)
		(end 123.517914 -383.92227)
		(width 0.254)
		(layer "F.Cu")
		(net "GND")
	)
	(segment
		(start 108.787946 -289.210242)
		(end 108.321094 -289.47618)
		(width 0.350012)
		(layer "F.Cu")
		(net "GND")
	)
	(segment
		(start 126.571756 -30.097222)
		(end 126.571756 -30.57271)
		(width 0.3556)
		(layer "F.Cu")
		(net "GND")
	)
	(segment
		(start 77.467968 -239.8903)
		(end 76.812902 -239.8903)
		(width 0.350012)
		(layer "F.Cu")
		(net "GND")
	)
	(segment
		(start 280.635964 -284.88513)
		(end 282.020264 -284.88513)
		(width 0.4572)
		(layer "F.Cu")
		(net "GND")
	)
	(segment
		(start 303.518316 -396.710662)
		(end 302.870362 -396.46352)
		(width 0.254)
		(layer "F.Cu")
		(net "GND")
	)
	(segment
		(start 62.470538 -388.138924)
		(end 63.118492 -388.328662)
		(width 0.254)
		(layer "F.Cu")
		(net "GND")
	)
	(segment
		(start 181.122066 -122.65279)
		(end 180.732176 -123.04268)
		(width 0.254)
		(layer "F.Cu")
		(net "GND")
	)
	(segment
		(start 338.39785 -265.720068)
		(end 337.930998 -265.986006)
		(width 0.350012)
		(layer "F.Cu")
		(net "GND")
	)
	(segment
		(start 193.922142 -123.45289)
		(end 194.312032 -123.84278)
		(width 0.254)
		(layer "F.Cu")
		(net "GND")
	)
	(segment
		(start 353.045522 -399.663158)
		(end 353.345496 -399.143474)
		(width 0.254)
		(layer "F.Cu")
		(net "GND")
	)
	(segment
		(start 334.154526 -340.185248)
		(end 334.742536 -340.185248)
		(width 0.381)
		(layer "F.Cu")
		(net "GND")
	)
	(segment
		(start 113.594896 -391.77595)
		(end 113.594896 -391.304272)
		(width 0.254)
		(layer "F.Cu")
		(net "GND")
	)
	(segment
		(start 151.175466 -117.944646)
		(end 150.98522 -117.7544)
		(width 0.4572)
		(layer "F.Cu")
		(net "GND")
	)
	(segment
		(start 43.532552 -385.58216)
		(end 44.065952 -385.58216)
		(width 0.254)
		(layer "F.Cu")
		(net "GND")
	)
	(segment
		(start 115.537996 -232.600246)
		(end 116.004848 -232.334308)
		(width 0.350012)
		(layer "F.Cu")
		(net "GND")
	)
	(segment
		(start 111.137954 -270.580358)
		(end 110.671102 -270.846296)
		(width 0.350012)
		(layer "F.Cu")
		(net "GND")
	)
	(segment
		(start 131.970526 -388.138924)
		(end 131.418584 -388.328662)
		(width 0.254)
		(layer "F.Cu")
		(net "GND")
	)
	(segment
		(start 211.992464 -23.958296)
		(end 211.992464 -22.443948)
		(width 0.3556)
		(layer "F.Cu")
		(net "GND")
	)
	(segment
		(start 147.09013 -384.617722)
		(end 147.698206 -384.617722)
		(width 0.254)
		(layer "F.Cu")
		(net "GND")
	)
	(segment
		(start 98.918014 -280.30043)
		(end 98.451162 -280.566368)
		(width 0.350012)
		(layer "F.Cu")
		(net "GND")
	)
	(segment
		(start 138.092688 -386.84073)
		(end 137.849356 -387.084062)
		(width 0.381)
		(layer "F.Cu")
		(net "GND")
	)
	(segment
		(start 96.737932 -250.420378)
		(end 96.27108 -250.15444)
		(width 0.350012)
		(layer "F.Cu")
		(net "GND")
	)
	(segment
		(start 132.927852 -228.55047)
		(end 133.394704 -228.284532)
		(width 0.350012)
		(layer "F.Cu")
		(net "GND")
	)
	(segment
		(start 51.505104 -37.78504)
		(end 52.51704 -37.78504)
		(width 0.381)
		(layer "F.Cu")
		(net "GND")
	)
	(segment
		(start 369.594892 -399.686272)
		(end 369.618006 -399.663158)
		(width 0.254)
		(layer "F.Cu")
		(net "GND")
	)
	(segment
		(start 431.55616 -293.384986)
		(end 430.17186 -293.384986)
		(width 0.4572)
		(layer "F.Cu")
		(net "GND")
	)
	(segment
		(start 355.31806 -281.920188)
		(end 354.851208 -282.186126)
		(width 0.350012)
		(layer "F.Cu")
		(net "GND")
	)
	(segment
		(start 102.847902 -235.030264)
		(end 102.38105 -234.764326)
		(width 0.350012)
		(layer "F.Cu")
		(net "GND")
	)
	(segment
		(start 333.39786 -226.120198)
		(end 332.931008 -225.85426)
		(width 0.350012)
		(layer "F.Cu")
		(net "GND")
	)
	(segment
		(start 185.122058 -113.05286)
		(end 184.732168 -112.66297)
		(width 0.254)
		(layer "F.Cu")
		(net "GND")
	)
	(segment
		(start 402.063458 -136.231376)
		(end 401.255992 -136.231376)
		(width 0.4572)
		(layer "F.Cu")
		(net "GND")
	)
	(segment
		(start 91.097862 -250.420378)
		(end 90.63101 -250.15444)
		(width 0.350012)
		(layer "F.Cu")
		(net "GND")
	)
	(segment
		(start 117.217952 -383.402586)
		(end 117.217952 -383.622296)
		(width 0.254)
		(layer "F.Cu")
		(net "GND")
	)
	(segment
		(start 123.52782 -244.750336)
		(end 123.994672 -244.484398)
		(width 0.350012)
		(layer "F.Cu")
		(net "GND")
	)
	(segment
		(start 146.087846 -247.99036)
		(end 146.742912 -247.99036)
		(width 0.350012)
		(layer "F.Cu")
		(net "GND")
	)
	(segment
		(start 119.597932 -273.820382)
		(end 120.064784 -274.08632)
		(width 0.350012)
		(layer "F.Cu")
		(net "GND")
	)
	(segment
		(start 429.566832 -12.372848)
		(end 429.566832 -11.26998)
		(width 0.3556)
		(layer "F.Cu")
		(net "GND")
	)
	(segment
		(start 363.00791 -244.750082)
		(end 363.474762 -244.484144)
		(width 0.350012)
		(layer "F.Cu")
		(net "GND")
	)
	(segment
		(start 312.978292 -394.831062)
		(end 312.470292 -395.0208)
		(width 0.254)
		(layer "F.Cu")
		(net "GND")
	)
	(segment
		(start 164.427916 -219.435426)
		(end 165.812216 -219.435426)
		(width 0.4572)
		(layer "F.Cu")
		(net "GND")
	)
	(segment
		(start 389.07593 -412.212536)
		(end 389.07593 -411.329886)
		(width 0.381)
		(layer "F.Cu")
		(net "GND")
	)
	(segment
		(start 360.657902 -237.460028)
		(end 361.124754 -237.19409)
		(width 0.350012)
		(layer "F.Cu")
		(net "GND")
	)
	(segment
		(start 371.467888 -235.03001)
		(end 371.93474 -234.764072)
		(width 0.350012)
		(layer "F.Cu")
		(net "GND")
	)
	(segment
		(start 355.31806 -294.88003)
		(end 354.851208 -295.145968)
		(width 0.350012)
		(layer "F.Cu")
		(net "GND")
	)
	(segment
		(start 419.379654 -430.885346)
		(end 419.379654 -431.921412)
		(width 0.381)
		(layer "F.Cu")
		(net "GND")
	)
	(segment
		(start 277.192232 -312.084974)
		(end 275.807932 -312.084974)
		(width 0.4572)
		(layer "F.Cu")
		(net "GND")
	)
	(segment
		(start 333.697834 -272.200116)
		(end 333.230982 -272.466054)
		(width 0.350012)
		(layer "F.Cu")
		(net "GND")
	)
	(segment
		(start 142.074392 -402.773896)
		(end 142.467838 -402.773896)
		(width 0.381)
		(layer "F.Cu")
		(net "GND")
	)
	(segment
		(start 206.248 -284.035246)
		(end 204.8637 -284.035246)
		(width 0.4572)
		(layer "F.Cu")
		(net "GND")
	)
	(segment
		(start 118.657878 -283.540454)
		(end 119.12473 -283.806392)
		(width 0.350012)
		(layer "F.Cu")
		(net "GND")
	)
	(segment
		(start 316.017656 -399.143474)
		(end 316.070234 -398.542002)
		(width 0.254)
		(layer "F.Cu")
		(net "GND")
	)
	(segment
		(start 85.757766 -281.920442)
		(end 85.290914 -282.18638)
		(width 0.350012)
		(layer "F.Cu")
		(net "GND")
	)
	(segment
		(start 55.328058 -203.285344)
		(end 56.712358 -203.285344)
		(width 0.4572)
		(layer "F.Cu")
		(net "GND")
	)
	(segment
		(start 369.717066 -416.645598)
		(end 369.717066 -415.572956)
		(width 0.508)
		(layer "F.Cu")
		(net "GND")
	)
	(segment
		(start 416.468052 -284.034992)
		(end 415.083752 -284.034992)
		(width 0.4572)
		(layer "F.Cu")
		(net "GND")
	)
	(segment
		(start 139.977876 -255.280414)
		(end 140.444728 -255.014476)
		(width 0.350012)
		(layer "F.Cu")
		(net "GND")
	)
	(segment
		(start 31.017718 -52.639214)
		(end 32.605218 -52.639214)
		(width 0.4572)
		(layer "F.Cu")
		(net "GND")
	)
	(segment
		(start 102.677976 -281.920442)
		(end 102.211124 -282.18638)
		(width 0.350012)
		(layer "F.Cu")
		(net "GND")
	)
	(segment
		(start 383.048002 -281.110182)
		(end 383.514854 -281.37612)
		(width 0.350012)
		(layer "F.Cu")
		(net "GND")
	)
	(segment
		(start 386.338064 -265.720068)
		(end 386.804916 -265.986006)
		(width 0.350012)
		(layer "F.Cu")
		(net "GND")
	)
	(segment
		(start 86.868 -256.09042)
		(end 86.401148 -255.824482)
		(width 0.350012)
		(layer "F.Cu")
		(net "GND")
	)
	(segment
		(start 96.837246 -75.888088)
		(end 96.3168 -75.888088)
		(width 0.4572)
		(layer "F.Cu")
		(net "GND")
	)
	(segment
		(start 98.44786 -264.910316)
		(end 97.981008 -265.176254)
		(width 0.350012)
		(layer "F.Cu")
		(net "GND")
	)
	(segment
		(start 352.027998 -268.150086)
		(end 351.561146 -268.416024)
		(width 0.350012)
		(layer "F.Cu")
		(net "GND")
	)
	(segment
		(start 353.607878 -239.890046)
		(end 353.141026 -239.624108)
		(width 0.350012)
		(layer "F.Cu")
		(net "GND")
	)
	(segment
		(start 110.83798 -237.460282)
		(end 110.371128 -237.194344)
		(width 0.350012)
		(layer "F.Cu")
		(net "GND")
	)
	(segment
		(start 351.557844 -285.160212)
		(end 351.091246 -285.42615)
		(width 0.350012)
		(layer "F.Cu")
		(net "GND")
	)
	(segment
		(start 65.717928 -391.281158)
		(end 66.017902 -390.761474)
		(width 0.254)
		(layer "F.Cu")
		(net "GND")
	)
	(segment
		(start 41.8211 -390.652)
		(end 41.8211 -391.2235)
		(width 0.254)
		(layer "F.Cu")
		(net "GND")
	)
	(segment
		(start 90.998294 -177.464212)
		(end 90.928444 -177.534062)
		(width 0.381)
		(layer "F.Cu")
		(net "GND")
	)
	(segment
		(start 274.79371 -100.37953)
		(end 275.230082 -100.37953)
		(width 0.3556)
		(layer "F.Cu")
		(net "GND")
	)
	(segment
		(start 51.467004 -12.372848)
		(end 51.467004 -11.26998)
		(width 0.3556)
		(layer "F.Cu")
		(net "GND")
	)
	(segment
		(start 378.370592 -398.542002)
		(end 377.691142 -398.542002)
		(width 0.254)
		(layer "F.Cu")
		(net "GND")
	)
	(segment
		(start 454.317608 -402.801328)
		(end 454.324466 -402.79447)
		(width 0.4572)
		(layer "F.Cu")
		(net "GND")
	)
	(segment
		(start 82.167984 -256.09042)
		(end 81.701132 -255.824482)
		(width 0.350012)
		(layer "F.Cu")
		(net "GND")
	)
	(segment
		(start 301.73295 -365.125)
		(end 301.73295 -365.8616)
		(width 0.381)
		(layer "F.Cu")
		(net "GND")
	)
	(segment
		(start 368.947954 -282.730194)
		(end 369.414806 -282.996132)
		(width 0.350012)
		(layer "F.Cu")
		(net "GND")
	)
	(segment
		(start 51.884072 -230.485442)
		(end 50.499772 -230.485442)
		(width 0.4572)
		(layer "F.Cu")
		(net "GND")
	)
	(segment
		(start 301.841408 -111.811308)
		(end 301.231808 -111.811308)
		(width 0.381)
		(layer "F.Cu")
		(net "GND")
	)
	(segment
		(start 31.148274 -12.37488)
		(end 31.148274 -12.374118)
		(width 0.3556)
		(layer "F.Cu")
		(net "GND")
	)
	(segment
		(start 102.677976 -290.020248)
		(end 102.211124 -290.286186)
		(width 0.350012)
		(layer "F.Cu")
		(net "GND")
	)
	(segment
		(start 98.598482 -386.987034)
		(end 98.598482 -386.6388)
		(width 0.254)
		(layer "F.Cu")
		(net "GND")
	)
	(segment
		(start 332.28788 -273.010122)
		(end 331.821028 -273.27606)
		(width 0.350012)
		(layer "F.Cu")
		(net "GND")
	)
	(segment
		(start 146.38782 -281.110436)
		(end 147.042886 -281.110436)
		(width 0.350012)
		(layer "F.Cu")
		(net "GND")
	)
	(segment
		(start 55.328058 -210.085432)
		(end 56.712358 -210.085432)
		(width 0.4572)
		(layer "F.Cu")
		(net "GND")
	)
	(segment
		(start 38.45687 -9.423654)
		(end 38.45814 -9.424924)
		(width 0.3556)
		(layer "F.Cu")
		(net "GND")
	)
	(segment
		(start 302.923448 -426.18914)
		(end 302.923448 -426.82414)
		(width 0.4318)
		(layer "F.Cu")
		(net "GND")
	)
	(segment
		(start 366.597946 -268.960092)
		(end 367.064798 -269.22603)
		(width 0.350012)
		(layer "F.Cu")
		(net "GND")
	)
	(segment
		(start 387.748018 -289.209988)
		(end 388.21487 -289.475926)
		(width 0.350012)
		(layer "F.Cu")
		(net "GND")
	)
	(segment
		(start 332.885542 -142.669514)
		(end 332.622906 -142.973044)
		(width 0.1778)
		(layer "F.Cu")
		(net "GND")
	)
	(segment
		(start 12.987782 -416.762184)
		(end 13.038582 -416.812984)
		(width 0.4572)
		(layer "F.Cu")
		(net "GND")
	)
	(segment
		(start 42.49293 -351.978722)
		(end 42.125138 -351.978722)
		(width 0.381)
		(layer "F.Cu")
		(net "GND")
	)
	(segment
		(start 121.177812 -247.180354)
		(end 121.644664 -246.914416)
		(width 0.350012)
		(layer "F.Cu")
		(net "GND")
	)
	(segment
		(start 126.647956 -266.530328)
		(end 127.114808 -266.796266)
		(width 0.350012)
		(layer "F.Cu")
		(net "GND")
	)
	(segment
		(start 346.087954 -256.090166)
		(end 345.621102 -255.824228)
		(width 0.350012)
		(layer "F.Cu")
		(net "GND")
	)
	(segment
		(start 77.767942 -264.910316)
		(end 77.112876 -264.910316)
		(width 0.350012)
		(layer "F.Cu")
		(net "GND")
	)
	(segment
		(start 84.047838 -235.030264)
		(end 83.580986 -234.764326)
		(width 0.350012)
		(layer "F.Cu")
		(net "GND")
	)
	(segment
		(start 384.927856 -285.970218)
		(end 385.394708 -286.236156)
		(width 0.350012)
		(layer "F.Cu")
		(net "GND")
	)
	(segment
		(start 67.202558 -39.421562)
		(end 67.201796 -39.422324)
		(width 0.4572)
		(layer "F.Cu")
		(net "GND")
	)
	(segment
		(start 322.950078 -62.634876)
		(end 324.543928 -62.634876)
		(width 0.4572)
		(layer "F.Cu")
		(net "GND")
	)
	(segment
		(start 353.437952 -283.5402)
		(end 352.9711 -283.806138)
		(width 0.350012)
		(layer "F.Cu")
		(net "GND")
	)
	(segment
		(start 130.407918 -284.35046)
		(end 130.87477 -284.616398)
		(width 0.350012)
		(layer "F.Cu")
		(net "GND")
	)
	(segment
		(start 358.607868 -279.49017)
		(end 358.141016 -279.756108)
		(width 0.350012)
		(layer "F.Cu")
		(net "GND")
	)
	(segment
		(start 349.67799 -277.060152)
		(end 349.211138 -277.32609)
		(width 0.350012)
		(layer "F.Cu")
		(net "GND")
	)
	(segment
		(start 160.644332 -391.37971)
		(end 160.54578 -391.281158)
		(width 0.254)
		(layer "F.Cu")
		(net "GND")
	)
	(segment
		(start 117.217952 -391.281158)
		(end 117.517926 -390.761474)
		(width 0.254)
		(layer "F.Cu")
		(net "GND")
	)
	(segment
		(start 320.340228 -44.716954)
		(end 320.949828 -44.716954)
		(width 0.3556)
		(layer "F.Cu")
		(net "GND")
	)
	(segment
		(start 340.790022 -392.999722)
		(end 340.198202 -392.999722)
		(width 0.254)
		(layer "F.Cu")
		(net "GND")
	)
	(segment
		(start 179.83835 -353.79025)
		(end 179.83835 -353.373436)
		(width 0.2286)
		(layer "F.Cu")
		(net "GND")
	)
	(segment
		(start 163.044124 -391.830814)
		(end 163.044124 -391.37971)
		(width 0.254)
		(layer "F.Cu")
		(net "GND")
	)
	(segment
		(start 198.7042 -202.435206)
		(end 197.3199 -202.435206)
		(width 0.4572)
		(layer "F.Cu")
		(net "GND")
	)
	(segment
		(start 369.970558 -392.356848)
		(end 369.970558 -392.999722)
		(width 0.254)
		(layer "F.Cu")
		(net "GND")
	)
	(segment
		(start 353.137978 -224.500186)
		(end 352.671126 -224.234248)
		(width 0.350012)
		(layer "F.Cu")
		(net "GND")
	)
	(segment
		(start 97.037906 -275.440394)
		(end 96.571054 -275.706332)
		(width 0.350012)
		(layer "F.Cu")
		(net "GND")
	)
	(segment
		(start 64.318642 -388.328662)
		(end 64.870584 -388.138924)
		(width 0.254)
		(layer "F.Cu")
		(net "GND")
	)
	(segment
		(start 149.401276 -45.24375)
		(end 148.76399 -45.24375)
		(width 0.4572)
		(layer "F.Cu")
		(net "GND")
	)
	(segment
		(start 138.748262 -16.551148)
		(end 138.748262 -17.654778)
		(width 0.3556)
		(layer "F.Cu")
		(net "GND")
	)
	(segment
		(start 146.38782 -271.390364)
		(end 147.042886 -271.390364)
		(width 0.350012)
		(layer "F.Cu")
		(net "GND")
	)
	(segment
		(start 380.417832 -399.663158)
		(end 380.71806 -399.143474)
		(width 0.254)
		(layer "F.Cu")
		(net "GND")
	)
	(segment
		(start 333.39786 -243.940076)
		(end 332.931008 -243.674138)
		(width 0.350012)
		(layer "F.Cu")
		(net "GND")
	)
	(segment
		(start 23.945596 -7.215124)
		(end 23.945596 -7.215886)
		(width 0.3556)
		(layer "F.Cu")
		(net "GND")
	)
	(segment
		(start 325.308214 -36.208462)
		(end 326.489314 -36.208462)
		(width 0.3556)
		(layer "F.Cu")
		(net "GND")
	)
	(segment
		(start 376.167904 -236.650022)
		(end 376.634756 -236.384084)
		(width 0.350012)
		(layer "F.Cu")
		(net "GND")
	)
	(segment
		(start 439.100214 -277.235158)
		(end 437.715914 -277.235158)
		(width 0.4572)
		(layer "F.Cu")
		(net "GND")
	)
	(segment
		(start 321.462146 -392.999722)
		(end 322.10121 -392.999722)
		(width 0.254)
		(layer "F.Cu")
		(net "GND")
	)
	(segment
		(start 135.107934 -279.490424)
		(end 135.574786 -279.756362)
		(width 0.350012)
		(layer "F.Cu")
		(net "GND")
	)
	(segment
		(start 409.830778 -165.528498)
		(end 409.79979 -165.528498)
		(width 0.2286)
		(layer "F.Cu")
		(net "GND")
	)
	(segment
		(start 22.07895 -359.918)
		(end 21.336 -359.918)
		(width 0.381)
		(layer "F.Cu")
		(net "GND")
	)
	(segment
		(start 353.607878 -244.750082)
		(end 353.141026 -244.484144)
		(width 0.350012)
		(layer "F.Cu")
		(net "GND")
	)
	(segment
		(start 338.39785 -293.260018)
		(end 337.930998 -293.525956)
		(width 0.350012)
		(layer "F.Cu")
		(net "GND")
	)
	(segment
		(start 343.073736 -340.236048)
		(end 343.143586 -340.166198)
		(width 0.381)
		(layer "F.Cu")
		(net "GND")
	)
	(segment
		(start 188.01207 -417.404804)
		(end 188.731906 -417.404804)
		(width 0.381)
		(layer "F.Cu")
		(net "GND")
	)
	(segment
		(start 101.509068 -394.0937)
		(end 101.318314 -393.902946)
		(width 0.254)
		(layer "F.Cu")
		(net "GND")
	)
	(segment
		(start 102.378002 -252.04039)
		(end 101.91115 -251.774452)
		(width 0.350012)
		(layer "F.Cu")
		(net "GND")
	)
	(segment
		(start 373.817896 -252.040136)
		(end 374.284748 -251.774198)
		(width 0.350012)
		(layer "F.Cu")
		(net "GND")
	)
	(segment
		(start 457.9112 -37.265864)
		(end 458.60335 -37.265864)
		(width 0.4572)
		(layer "F.Cu")
		(net "GND")
	)
	(segment
		(start 51.435 -394.72362)
		(end 51.416458 -394.705078)
		(width 0.381)
		(layer "F.Cu")
		(net "GND")
	)
	(segment
		(start 118.357904 -252.04039)
		(end 118.824756 -251.774452)
		(width 0.350012)
		(layer "F.Cu")
		(net "GND")
	)
	(segment
		(start 211.76361 -57.948322)
		(end 210.90636 -57.948322)
		(width 0.3556)
		(layer "F.Cu")
		(net "GND")
	)
	(segment
		(start 363.478064 -237.460028)
		(end 363.944916 -237.19409)
		(width 0.350012)
		(layer "F.Cu")
		(net "GND")
	)
	(segment
		(start 122.887994 -264.910316)
		(end 123.354846 -265.176254)
		(width 0.350012)
		(layer "F.Cu")
		(net "GND")
	)
	(segment
		(start 63.317882 -383.622042)
		(end 63.317882 -383.402586)
		(width 0.254)
		(layer "F.Cu")
		(net "GND")
	)
	(segment
		(start 381.617982 -392.004296)
		(end 381.917956 -392.30427)
		(width 0.254)
		(layer "F.Cu")
		(net "GND")
	)
	(segment
		(start 347.144086 -400.212814)
		(end 347.144086 -399.76171)
		(width 0.254)
		(layer "F.Cu")
		(net "GND")
	)
	(segment
		(start 93.91777 -243.94033)
		(end 93.450918 -243.674392)
		(width 0.350012)
		(layer "F.Cu")
		(net "GND")
	)
	(segment
		(start 388.916418 -391.686034)
		(end 388.916418 -391.23493)
		(width 0.254)
		(layer "F.Cu")
		(net "GND")
	)
	(segment
		(start 87.3379 -240.700306)
		(end 86.871048 -240.434368)
		(width 0.350012)
		(layer "F.Cu")
		(net "GND")
	)
	(segment
		(start 371.938042 -227.74021)
		(end 372.404894 -227.474272)
		(width 0.350012)
		(layer "F.Cu")
		(net "GND")
	)
	(segment
		(start 366.597946 -290.019994)
		(end 367.064798 -290.285932)
		(width 0.350012)
		(layer "F.Cu")
		(net "GND")
	)
	(segment
		(start 159.34563 -383.402586)
		(end 159.34563 -383.622296)
		(width 0.254)
		(layer "F.Cu")
		(net "GND")
	)
	(segment
		(start 112.267238 -41.5798)
		(end 112.267238 -42.2656)
		(width 0.4572)
		(layer "F.Cu")
		(net "GND")
	)
	(segment
		(start 96.719136 -390.160002)
		(end 97.398332 -390.160002)
		(width 0.254)
		(layer "F.Cu")
		(net "GND")
	)
	(segment
		(start 132.457952 -224.50044)
		(end 132.924804 -224.234502)
		(width 0.350012)
		(layer "F.Cu")
		(net "GND")
	)
	(segment
		(start 164.427916 -287.43529)
		(end 165.812216 -287.43529)
		(width 0.4572)
		(layer "F.Cu")
		(net "GND")
	)
	(segment
		(start 121.177812 -235.84027)
		(end 121.644664 -235.574332)
		(width 0.350012)
		(layer "F.Cu")
		(net "GND")
	)
	(segment
		(start 351.845372 -391.333482)
		(end 351.943924 -391.23493)
		(width 0.254)
		(layer "F.Cu")
		(net "GND")
	)
	(segment
		(start 144.677892 -229.360476)
		(end 145.144744 -229.094538)
		(width 0.350012)
		(layer "F.Cu")
		(net "GND")
	)
	(segment
		(start 341.857838 -248.800112)
		(end 341.390986 -248.534174)
		(width 0.350012)
		(layer "F.Cu")
		(net "GND")
	)
	(segment
		(start 79.177896 -291.64026)
		(end 78.711044 -291.906198)
		(width 0.350012)
		(layer "F.Cu")
		(net "GND")
	)
	(segment
		(start 379.457966 -237.460028)
		(end 379.924818 -237.19409)
		(width 0.350012)
		(layer "F.Cu")
		(net "GND")
	)
	(segment
		(start 271.585944 -100.046028)
		(end 274.460208 -100.046028)
		(width 0.3556)
		(layer "F.Cu")
		(net "GND")
	)
	(segment
		(start 22.87905 -364.617)
		(end 23.622 -364.617)
		(width 0.381)
		(layer "F.Cu")
		(net "GND")
	)
	(segment
		(start 50.254662 -402.87194)
		(end 50.254662 -403.425406)
		(width 0.381)
		(layer "F.Cu")
		(net "GND")
	)
	(segment
		(start 100.327968 -268.15034)
		(end 99.861116 -268.416278)
		(width 0.350012)
		(layer "F.Cu")
		(net "GND")
	)
	(segment
		(start 100.027994 -256.09042)
		(end 99.561142 -255.824482)
		(width 0.350012)
		(layer "F.Cu")
		(net "GND")
	)
	(segment
		(start 385.217924 -399.663158)
		(end 385.517898 -399.143474)
		(width 0.254)
		(layer "F.Cu")
		(net "GND")
	)
	(segment
		(start 96.706436 -386.449062)
		(end 97.398332 -386.6388)
		(width 0.254)
		(layer "F.Cu")
		(net "GND")
	)
	(segment
		(start 131.917948 -383.92227)
		(end 131.970526 -384.617722)
		(width 0.254)
		(layer "F.Cu")
		(net "GND")
	)
	(segment
		(start 365.657892 -273.820128)
		(end 366.124744 -274.086066)
		(width 0.350012)
		(layer "F.Cu")
		(net "GND")
	)
	(segment
		(start 402.046948 -7.217156)
		(end 402.046948 -8.320024)
		(width 0.3556)
		(layer "F.Cu")
		(net "GND")
	)
	(segment
		(start 158.498286 -390.160002)
		(end 157.81909 -390.160002)
		(width 0.254)
		(layer "F.Cu")
		(net "GND")
	)
	(segment
		(start 32.695896 -203.285344)
		(end 34.080196 -203.285344)
		(width 0.4572)
		(layer "F.Cu")
		(net "GND")
	)
	(segment
		(start 52.70246 -394.70838)
		(end 52.616608 -394.622528)
		(width 0.381)
		(layer "F.Cu")
		(net "GND")
	)
	(segment
		(start 26.393394 -423.509694)
		(end 25.511506 -423.509694)
		(width 0.4572)
		(layer "F.Cu")
		(net "GND")
	)
	(segment
		(start 49.791366 -390.160002)
		(end 50.470562 -390.160002)
		(width 0.254)
		(layer "F.Cu")
		(net "GND")
	)
	(segment
		(start 380.078488 -394.831062)
		(end 379.570488 -395.0208)
		(width 0.254)
		(layer "F.Cu")
		(net "GND")
	)
	(segment
		(start 400.224244 -175.346106)
		(end 400.56054 -175.346106)
		(width 0.2286)
		(layer "F.Cu")
		(net "GND")
	)
	(segment
		(start 183.616092 -227.935282)
		(end 182.231792 -227.935282)
		(width 0.4572)
		(layer "F.Cu")
		(net "GND")
	)
	(segment
		(start 115.691158 -390.160002)
		(end 115.170458 -390.160002)
		(width 0.254)
		(layer "F.Cu")
		(net "GND")
	)
	(segment
		(start 378.347986 -274.630134)
		(end 378.814838 -274.896072)
		(width 0.350012)
		(layer "F.Cu")
		(net "GND")
	)
	(segment
		(start 338.56803 -254.470154)
		(end 338.101178 -254.204216)
		(width 0.350012)
		(layer "F.Cu")
		(net "GND")
	)
	(segment
		(start 288.180018 -200.735184)
		(end 289.564318 -200.735184)
		(width 0.4572)
		(layer "F.Cu")
		(net "GND")
	)
	(segment
		(start 77.467968 -246.370348)
		(end 76.812902 -246.370348)
		(width 0.350012)
		(layer "F.Cu")
		(net "GND")
	)
	(segment
		(start 7.610348 -101.854)
		(end 8.35914 -101.854)
		(width 0.3556)
		(layer "F.Cu")
		(net "GND")
	)
	(segment
		(start 389.414766 -393.213082)
		(end 389.201406 -392.999722)
		(width 0.254)
		(layer "F.Cu")
		(net "GND")
	)
	(segment
		(start 373.517922 -392.30427)
		(end 373.5705 -392.999722)
		(width 0.254)
		(layer "F.Cu")
		(net "GND")
	)
	(segment
		(start 36.795964 -305.285394)
		(end 35.411664 -305.285394)
		(width 0.4572)
		(layer "F.Cu")
		(net "GND")
	)
	(segment
		(start 326.81799 -245.560088)
		(end 326.351138 -245.29415)
		(width 0.350012)
		(layer "F.Cu")
		(net "GND")
	)
	(segment
		(start 314.318142 -396.710662)
		(end 313.670442 -396.520924)
		(width 0.254)
		(layer "F.Cu")
		(net "GND")
	)
	(segment
		(start 364.417864 -247.1801)
		(end 364.884716 -246.914162)
		(width 0.350012)
		(layer "F.Cu")
		(net "GND")
	)
	(segment
		(start 381.638048 -260.860032)
		(end 382.1049 -261.12597)
		(width 0.350012)
		(layer "F.Cu")
		(net "GND")
	)
	(segment
		(start 57.416446 -391.830814)
		(end 57.416446 -391.37971)
		(width 0.254)
		(layer "F.Cu")
		(net "GND")
	)
	(segment
		(start 141.38783 -225.310446)
		(end 141.854682 -225.044508)
		(width 0.350012)
		(layer "F.Cu")
		(net "GND")
	)
	(segment
		(start 338.998052 -396.520924)
		(end 338.44611 -396.710662)
		(width 0.254)
		(layer "F.Cu")
		(net "GND")
	)
	(segment
		(start 320.517774 -392.004296)
		(end 320.817748 -392.30427)
		(width 0.254)
		(layer "F.Cu")
		(net "GND")
	)
	(segment
		(start 82.467958 -266.530328)
		(end 82.001106 -266.796266)
		(width 0.350012)
		(layer "F.Cu")
		(net "GND")
	)
	(segment
		(start 387.748018 -282.730194)
		(end 388.21487 -282.996132)
		(width 0.350012)
		(layer "F.Cu")
		(net "GND")
	)
	(segment
		(start 104.55783 -293.260272)
		(end 104.090978 -293.52621)
		(width 0.350012)
		(layer "F.Cu")
		(net "GND")
	)
	(segment
		(start 136.987788 -269.770352)
		(end 137.45464 -270.03629)
		(width 0.350012)
		(layer "F.Cu")
		(net "GND")
	)
	(segment
		(start 333.39786 -240.700052)
		(end 332.931008 -240.434114)
		(width 0.350012)
		(layer "F.Cu")
		(net "GND")
	)
	(segment
		(start 330.408026 -276.250146)
		(end 329.941174 -276.516084)
		(width 0.350012)
		(layer "F.Cu")
		(net "GND")
	)
	(segment
		(start 388.217918 -268.960092)
		(end 388.68477 -269.22603)
		(width 0.350012)
		(layer "F.Cu")
		(net "GND")
	)
	(segment
		(start 413.819086 -398.542002)
		(end 413.298386 -398.542002)
		(width 0.254)
		(layer "F.Cu")
		(net "GND")
	)
	(segment
		(start 201.352658 -111.593376)
		(end 202.268582 -111.593376)
		(width 0.4064)
		(layer "F.Cu")
		(net "GND")
	)
	(segment
		(start 333.39786 -256.900172)
		(end 332.931008 -256.634234)
		(width 0.350012)
		(layer "F.Cu")
		(net "GND")
	)
	(segment
		(start 144.207992 -251.230384)
		(end 144.674844 -250.964446)
		(width 0.350012)
		(layer "F.Cu")
		(net "GND")
	)
	(segment
		(start 90.457782 -267.340334)
		(end 89.99093 -267.606272)
		(width 0.350012)
		(layer "F.Cu")
		(net "GND")
	)
	(segment
		(start 176.072038 -293.38524)
		(end 174.687738 -293.38524)
		(width 0.4572)
		(layer "F.Cu")
		(net "GND")
	)
	(segment
		(start 350.645476 -391.784586)
		(end 350.645476 -391.333482)
		(width 0.254)
		(layer "F.Cu")
		(net "GND")
	)
	(segment
		(start 239.13592 -291.406326)
		(end 239.800384 -290.741862)
		(width 0.4572)
		(layer "F.Cu")
		(net "GND")
	)
	(segment
		(start 83.877912 -267.340334)
		(end 83.41106 -267.606272)
		(width 0.350012)
		(layer "F.Cu")
		(net "GND")
	)
	(segment
		(start 115.83797 -272.20037)
		(end 116.304822 -272.466308)
		(width 0.350012)
		(layer "F.Cu")
		(net "GND")
	)
	(segment
		(start 123.357894 -293.260272)
		(end 123.824746 -293.52621)
		(width 0.350012)
		(layer "F.Cu")
		(net "GND")
	)
	(segment
		(start 350.618044 -288.399982)
		(end 350.151192 -288.66592)
		(width 0.350012)
		(layer "F.Cu")
		(net "GND")
	)
	(segment
		(start 368.478054 -270.580104)
		(end 368.944906 -270.846042)
		(width 0.350012)
		(layer "F.Cu")
		(net "GND")
	)
	(segment
		(start 62.216538 -391.830814)
		(end 62.216538 -391.37971)
		(width 0.254)
		(layer "F.Cu")
		(net "GND")
	)
	(segment
		(start 102.847902 -239.8903)
		(end 102.38105 -239.624362)
		(width 0.350012)
		(layer "F.Cu")
		(net "GND")
	)
	(segment
		(start 148.545804 -391.281158)
		(end 148.845778 -390.761474)
		(width 0.254)
		(layer "F.Cu")
		(net "GND")
	)
	(segment
		(start 196.329808 -78.40218)
		(end 196.329808 -77.06614)
		(width 0.3556)
		(layer "F.Cu")
		(net "GND")
	)
	(segment
		(start 375.057924 -272.200116)
		(end 375.524776 -272.466054)
		(width 0.350012)
		(layer "F.Cu")
		(net "GND")
	)
	(segment
		(start 123.05792 -247.180354)
		(end 123.524772 -246.914416)
		(width 0.350012)
		(layer "F.Cu")
		(net "GND")
	)
	(segment
		(start 121.647966 -223.690434)
		(end 122.114818 -223.424496)
		(width 0.350012)
		(layer "F.Cu")
		(net "GND")
	)
	(segment
		(start 140.54836 -16.551148)
		(end 140.54836 -17.654778)
		(width 0.3556)
		(layer "F.Cu")
		(net "GND")
	)
	(segment
		(start 389.725662 -177.532284)
		(end 389.655812 -177.602134)
		(width 0.381)
		(layer "F.Cu")
		(net "GND")
	)
	(segment
		(start 451.427342 -397.720312)
		(end 450.984112 -397.277082)
		(width 0.2032)
		(layer "F.Cu")
		(net "GND")
	)
	(segment
		(start 278.006556 -438.401714)
		(end 277.37562 -438.401714)
		(width 0.381)
		(layer "F.Cu")
		(net "GND")
	)
	(segment
		(start 415.146236 -396.710662)
		(end 414.498282 -396.520924)
		(width 0.254)
		(layer "F.Cu")
		(net "GND")
	)
	(segment
		(start 419.912038 -303.585118)
		(end 421.296338 -303.585118)
		(width 0.4572)
		(layer "F.Cu")
		(net "GND")
	)
	(segment
		(start 148.290026 -384.617722)
		(end 147.698206 -384.617722)
		(width 0.254)
		(layer "F.Cu")
		(net "GND")
	)
	(segment
		(start 95.327978 -238.270288)
		(end 94.861126 -238.00435)
		(width 0.350012)
		(layer "F.Cu")
		(net "GND")
	)
	(segment
		(start 338.097876 -235.840016)
		(end 337.631024 -235.574078)
		(width 0.350012)
		(layer "F.Cu")
		(net "GND")
	)
	(segment
		(start 160.54578 -383.402586)
		(end 160.54578 -383.622296)
		(width 0.254)
		(layer "F.Cu")
		(net "GND")
	)
	(segment
		(start 450.088 -231.335072)
		(end 451.4723 -231.335072)
		(width 0.4572)
		(layer "F.Cu")
		(net "GND")
	)
	(segment
		(start 51.670712 -390.160002)
		(end 50.991262 -390.160002)
		(width 0.254)
		(layer "F.Cu")
		(net "GND")
	)
	(segment
		(start 335.108042 -279.49017)
		(end 334.64119 -279.756108)
		(width 0.350012)
		(layer "F.Cu")
		(net "GND")
	)
	(segment
		(start 164.498274 -386.6388)
		(end 163.806378 -386.449062)
		(width 0.254)
		(layer "F.Cu")
		(net "GND")
	)
	(segment
		(start 90.457782 -265.720322)
		(end 89.99093 -265.98626)
		(width 0.350012)
		(layer "F.Cu")
		(net "GND")
	)
	(segment
		(start 160.54578 -391.281158)
		(end 160.845754 -390.761474)
		(width 0.254)
		(layer "F.Cu")
		(net "GND")
	)
	(segment
		(start 347.345508 -399.143474)
		(end 347.398086 -398.542002)
		(width 0.254)
		(layer "F.Cu")
		(net "GND")
	)
	(segment
		(start 77.467968 -233.410252)
		(end 76.812902 -233.410252)
		(width 0.350012)
		(layer "F.Cu")
		(net "GND")
	)
	(segment
		(start 399.415508 -63.3095)
		(end 399.934684 -63.828676)
		(width 0.4572)
		(layer "F.Cu")
		(net "GND")
	)
	(segment
		(start 183.616092 -293.38524)
		(end 182.231792 -293.38524)
		(width 0.4572)
		(layer "F.Cu")
		(net "GND")
	)
	(segment
		(start 348.737936 -285.160212)
		(end 348.271084 -285.42615)
		(width 0.350012)
		(layer "F.Cu")
		(net "GND")
	)
	(segment
		(start 136.987788 -290.830254)
		(end 137.45464 -291.096192)
		(width 0.350012)
		(layer "F.Cu")
		(net "GND")
	)
	(segment
		(start 155.745688 -382.951482)
		(end 155.84424 -382.85293)
		(width 0.254)
		(layer "F.Cu")
		(net "GND")
	)
	(segment
		(start 177.922174 -118.652798)
		(end 177.532284 -119.042688)
		(width 0.254)
		(layer "F.Cu")
		(net "GND")
	)
	(segment
		(start 84.047838 -246.370348)
		(end 83.580986 -246.10441)
		(width 0.350012)
		(layer "F.Cu")
		(net "GND")
	)
	(segment
		(start 114.678968 -403.013418)
		(end 113.701068 -403.991318)
		(width 0.3302)
		(layer "F.Cu")
		(net "GND")
	)
	(segment
		(start 369.2017 -395.313154)
		(end 369.501674 -395.613128)
		(width 0.254)
		(layer "F.Cu")
		(net "GND")
	)
	(segment
		(start 361.42803 -284.350206)
		(end 361.894882 -284.616144)
		(width 0.350012)
		(layer "F.Cu")
		(net "GND")
	)
	(segment
		(start 88.747854 -251.230384)
		(end 88.281002 -250.964446)
		(width 0.350012)
		(layer "F.Cu")
		(net "GND")
	)
	(segment
		(start 387.448044 -230.169974)
		(end 387.914896 -229.904036)
		(width 0.350012)
		(layer "F.Cu")
		(net "GND")
	)
	(segment
		(start 96.737932 -245.560342)
		(end 96.27108 -245.294404)
		(width 0.350012)
		(layer "F.Cu")
		(net "GND")
	)
	(segment
		(start 159.018986 -390.160002)
		(end 158.498286 -390.160002)
		(width 0.254)
		(layer "F.Cu")
		(net "GND")
	)
	(segment
		(start 119.297958 -222.880428)
		(end 119.76481 -222.61449)
		(width 0.350012)
		(layer "F.Cu")
		(net "GND")
	)
	(segment
		(start 93.91777 -253.660402)
		(end 93.450918 -253.394464)
		(width 0.350012)
		(layer "F.Cu")
		(net "GND")
	)
	(segment
		(start 431.55616 -314.635134)
		(end 430.17186 -314.635134)
		(width 0.4572)
		(layer "F.Cu")
		(net "GND")
	)
	(segment
		(start 332.28788 -292.450012)
		(end 331.821028 -292.71595)
		(width 0.350012)
		(layer "F.Cu")
		(net "GND")
	)
	(segment
		(start 133.227826 -287.590484)
		(end 133.694678 -287.856422)
		(width 0.350012)
		(layer "F.Cu")
		(net "GND")
	)
	(segment
		(start 23.945596 -7.215886)
		(end 23.946866 -7.217156)
		(width 0.3556)
		(layer "F.Cu")
		(net "GND")
	)
	(segment
		(start 25.152096 -296.785284)
		(end 26.536396 -296.785284)
		(width 0.4572)
		(layer "F.Cu")
		(net "GND")
	)
	(segment
		(start 383.17043 -398.542002)
		(end 382.491234 -398.542002)
		(width 0.254)
		(layer "F.Cu")
		(net "GND")
	)
	(segment
		(start 76.070714 -340.250526)
		(end 75.702922 -340.250526)
		(width 0.381)
		(layer "F.Cu")
		(net "GND")
	)
	(segment
		(start 352.497898 -273.820128)
		(end 352.031046 -274.086066)
		(width 0.350012)
		(layer "F.Cu")
		(net "GND")
	)
	(segment
		(start 123.316492 -391.830814)
		(end 123.316492 -391.37971)
		(width 0.254)
		(layer "F.Cu")
		(net "GND")
	)
	(segment
		(start 364.682278 -171.64431)
		(end 364.809278 -171.77131)
		(width 0.381)
		(layer "F.Cu")
		(net "GND")
	)
	(segment
		(start 382.107948 -268.150086)
		(end 382.5748 -268.416024)
		(width 0.350012)
		(layer "F.Cu")
		(net "GND")
	)
	(segment
		(start 96.737932 -227.740464)
		(end 96.27108 -227.474526)
		(width 0.350012)
		(layer "F.Cu")
		(net "GND")
	)
	(segment
		(start 386.770626 -392.999722)
		(end 386.718048 -392.30427)
		(width 0.254)
		(layer "F.Cu")
		(net "GND")
	)
	(segment
		(start 408.445716 -399.143474)
		(end 408.145742 -399.663158)
		(width 0.254)
		(layer "F.Cu")
		(net "GND")
	)
	(segment
		(start 11.512042 -53.904896)
		(end 11.51636 -53.909214)
		(width 0.4572)
		(layer "F.Cu")
		(net "GND")
	)
	(segment
		(start 99.55784 -232.600246)
		(end 99.090988 -232.334308)
		(width 0.350012)
		(layer "F.Cu")
		(net "GND")
	)
	(segment
		(start 342.327992 -249.610118)
		(end 341.86114 -249.34418)
		(width 0.350012)
		(layer "F.Cu")
		(net "GND")
	)
	(segment
		(start 54.017926 -390.761474)
		(end 54.070504 -390.160002)
		(width 0.254)
		(layer "F.Cu")
		(net "GND")
	)
	(segment
		(start 292.280086 -277.235158)
		(end 290.895786 -277.235158)
		(width 0.4572)
		(layer "F.Cu")
		(net "GND")
	)
	(segment
		(start 100.327968 -284.35046)
		(end 99.861116 -284.616398)
		(width 0.350012)
		(layer "F.Cu")
		(net "GND")
	)
	(segment
		(start 100.327968 -261.670292)
		(end 99.861116 -261.93623)
		(width 0.350012)
		(layer "F.Cu")
		(net "GND")
	)
	(segment
		(start 93.747844 -284.35046)
		(end 93.280992 -284.616398)
		(width 0.350012)
		(layer "F.Cu")
		(net "GND")
	)
	(segment
		(start 49.665636 -7.215886)
		(end 49.666906 -7.217156)
		(width 0.3556)
		(layer "F.Cu")
		(net "GND")
	)
	(segment
		(start 77.767942 -289.210242)
		(end 77.112876 -289.210242)
		(width 0.350012)
		(layer "F.Cu")
		(net "GND")
	)
	(segment
		(start 351.087944 -273.010122)
		(end 350.621092 -273.27606)
		(width 0.350012)
		(layer "F.Cu")
		(net "GND")
	)
	(segment
		(start 204.06233 -341.405972)
		(end 204.33157 -341.675212)
		(width 0.4572)
		(layer "F.Cu")
		(net "GND")
	)
	(segment
		(start 141.38783 -233.410252)
		(end 141.854682 -233.144314)
		(width 0.350012)
		(layer "F.Cu")
		(net "GND")
	)
	(segment
		(start 114.428016 -281.110436)
		(end 114.894614 -281.376374)
		(width 0.350012)
		(layer "F.Cu")
		(net "GND")
	)
	(segment
		(start 131.517898 -234.220258)
		(end 131.98475 -233.95432)
		(width 0.350012)
		(layer "F.Cu")
		(net "GND")
	)
	(segment
		(start 22.41423 -388.885938)
		(end 22.299676 -388.771384)
		(width 0.2286)
		(layer "F.Cu")
		(net "GND")
	)
	(segment
		(start 171.97197 -312.935366)
		(end 173.35627 -312.935366)
		(width 0.4572)
		(layer "F.Cu")
		(net "GND")
	)
	(segment
		(start 338.868004 -263.29005)
		(end 338.401152 -263.555988)
		(width 0.350012)
		(layer "F.Cu")
		(net "GND")
	)
	(segment
		(start 151.618442 -117.944646)
		(end 151.175466 -117.944646)
		(width 0.4572)
		(layer "F.Cu")
		(net "GND")
	)
	(segment
		(start 143.267938 -236.650276)
		(end 143.73479 -236.384338)
		(width 0.350012)
		(layer "F.Cu")
		(net "GND")
	)
	(segment
		(start 88.744298 -391.37971)
		(end 88.744298 -391.830814)
		(width 0.254)
		(layer "F.Cu")
		(net "GND")
	)
	(segment
		(start 322.950078 -63.904876)
		(end 324.543928 -63.904876)
		(width 0.4572)
		(layer "F.Cu")
		(net "GND")
	)
	(segment
		(start 341.398098 -396.520924)
		(end 340.845902 -396.710662)
		(width 0.254)
		(layer "F.Cu")
		(net "GND")
	)
	(segment
		(start 387.448044 -231.789986)
		(end 387.914896 -231.524048)
		(width 0.350012)
		(layer "F.Cu")
		(net "GND")
	)
	(segment
		(start 129.517902 -390.761474)
		(end 129.57048 -390.160002)
		(width 0.254)
		(layer "F.Cu")
		(net "GND")
	)
	(segment
		(start 319.118234 -396.710662)
		(end 318.47028 -396.520924)
		(width 0.254)
		(layer "F.Cu")
		(net "GND")
	)
	(segment
		(start 346.858082 -294.88003)
		(end 346.39123 -295.145968)
		(width 0.350012)
		(layer "F.Cu")
		(net "GND")
	)
	(segment
		(start 40.23995 -203.285344)
		(end 41.62425 -203.285344)
		(width 0.4572)
		(layer "F.Cu")
		(net "GND")
	)
	(segment
		(start 90.927936 -294.070278)
		(end 90.461084 -294.336216)
		(width 0.350012)
		(layer "F.Cu")
		(net "GND")
	)
	(segment
		(start 93.44787 -228.55047)
		(end 92.981018 -228.284532)
		(width 0.350012)
		(layer "F.Cu")
		(net "GND")
	)
	(segment
		(start 94.998286 -388.138924)
		(end 95.64624 -388.328662)
		(width 0.254)
		(layer "F.Cu")
		(net "GND")
	)
	(segment
		(start 416.346132 -396.710662)
		(end 415.698178 -396.520924)
		(width 0.254)
		(layer "F.Cu")
		(net "GND")
	)
	(segment
		(start 368.64798 -230.169974)
		(end 369.114832 -229.904036)
		(width 0.350012)
		(layer "F.Cu")
		(net "GND")
	)
	(segment
		(start 29.346906 -9.423654)
		(end 29.348176 -9.424924)
		(width 0.3556)
		(layer "F.Cu")
		(net "GND")
	)
	(segment
		(start 307.368194 -211.784946)
		(end 305.983894 -211.784946)
		(width 0.4572)
		(layer "F.Cu")
		(net "GND")
	)
	(segment
		(start 381.167894 -268.150086)
		(end 381.634746 -268.416024)
		(width 0.350012)
		(layer "F.Cu")
		(net "GND")
	)
	(segment
		(start 126.177802 -277.060406)
		(end 126.644654 -277.326344)
		(width 0.350012)
		(layer "F.Cu")
		(net "GND")
	)
	(segment
		(start 118.357904 -234.220258)
		(end 118.824756 -233.95432)
		(width 0.350012)
		(layer "F.Cu")
		(net "GND")
	)
	(segment
		(start 24.36495 -364.617)
		(end 23.622 -364.617)
		(width 0.381)
		(layer "F.Cu")
		(net "GND")
	)
	(segment
		(start 369.618006 -391.784586)
		(end 369.618006 -392.004296)
		(width 0.254)
		(layer "F.Cu")
		(net "GND")
	)
	(segment
		(start 80.046322 -388.328662)
		(end 80.598264 -388.138924)
		(width 0.254)
		(layer "F.Cu")
		(net "GND")
	)
	(segment
		(start 141.38783 -236.650276)
		(end 141.854682 -236.384338)
		(width 0.350012)
		(layer "F.Cu")
		(net "GND")
	)
	(segment
		(start 359.078022 -268.960092)
		(end 358.61117 -269.22603)
		(width 0.350012)
		(layer "F.Cu")
		(net "GND")
	)
	(segment
		(start 335.577942 -268.960092)
		(end 335.11109 -269.22603)
		(width 0.350012)
		(layer "F.Cu")
		(net "GND")
	)
	(segment
		(start 78.46695 -66.802)
		(end 78.46695 -66.05905)
		(width 0.381)
		(layer "F.Cu")
		(net "GND")
	)
	(segment
		(start 392.241278 -177.48631)
		(end 392.622278 -177.86731)
		(width 0.381)
		(layer "F.Cu")
		(net "GND")
	)
	(segment
		(start 136.687814 -247.99036)
		(end 137.154666 -247.724422)
		(width 0.350012)
		(layer "F.Cu")
		(net "GND")
	)
	(segment
		(start 424.012106 -239.835182)
		(end 422.627806 -239.835182)
		(width 0.4572)
		(layer "F.Cu")
		(net "GND")
	)
	(segment
		(start 417.419028 -398.542002)
		(end 416.898328 -398.542002)
		(width 0.254)
		(layer "F.Cu")
		(net "GND")
	)
	(segment
		(start 356.25786 -268.960092)
		(end 355.791008 -269.22603)
		(width 0.350012)
		(layer "F.Cu")
		(net "GND")
	)
	(segment
		(start 50.11801 -391.281158)
		(end 50.417984 -390.761474)
		(width 0.254)
		(layer "F.Cu")
		(net "GND")
	)
	(segment
		(start 101.737922 -273.820382)
		(end 101.27107 -274.08632)
		(width 0.350012)
		(layer "F.Cu")
		(net "GND")
	)
	(segment
		(start 184.322212 -113.05286)
		(end 183.932322 -112.66297)
		(width 0.254)
		(layer "F.Cu")
		(net "GND")
	)
	(segment
		(start 208.054956 -29.876242)
		(end 208.054956 -29.266896)
		(width 0.4572)
		(layer "F.Cu")
		(net "GND")
	)
	(segment
		(start 337.931506 -287.045654)
		(end 337.931506 -287.045908)
		(width 0.350012)
		(layer "F.Cu")
		(net "GND")
	)
	(segment
		(start 202.147932 -312.935366)
		(end 203.532232 -312.935366)
		(width 0.4572)
		(layer "F.Cu")
		(net "GND")
	)
	(segment
		(start 373.817896 -255.28016)
		(end 374.284748 -255.014222)
		(width 0.350012)
		(layer "F.Cu")
		(net "GND")
	)
	(segment
		(start 302.620934 -394.412978)
		(end 302.620934 -393.81303)
		(width 0.254)
		(layer "F.Cu")
		(net "GND")
	)
	(segment
		(start 146.38782 -261.670292)
		(end 147.042886 -261.670292)
		(width 0.350012)
		(layer "F.Cu")
		(net "GND")
	)
	(segment
		(start 85.398356 -390.160002)
		(end 85.345778 -390.761474)
		(width 0.254)
		(layer "F.Cu")
		(net "GND")
	)
	(segment
		(start 336.987896 -268.150086)
		(end 336.521044 -268.416024)
		(width 0.350012)
		(layer "F.Cu")
		(net "GND")
	)
	(segment
		(start 46.621192 -390.231122)
		(end 46.621192 -389.63092)
		(width 0.254)
		(layer "F.Cu")
		(net "GND")
	)
	(segment
		(start 203.799948 -341.405972)
		(end 204.06233 -341.405972)
		(width 0.4572)
		(layer "F.Cu")
		(net "GND")
	)
	(segment
		(start 104.257856 -232.600246)
		(end 103.791004 -232.334308)
		(width 0.350012)
		(layer "F.Cu")
		(net "GND")
	)
	(segment
		(start 345.447874 -273.010122)
		(end 344.981022 -273.27606)
		(width 0.350012)
		(layer "F.Cu")
		(net "GND")
	)
	(segment
		(start 132.927852 -247.99036)
		(end 133.394704 -247.724422)
		(width 0.350012)
		(layer "F.Cu")
		(net "GND")
	)
	(segment
		(start 118.187978 -282.730448)
		(end 118.65483 -282.996386)
		(width 0.350012)
		(layer "F.Cu")
		(net "GND")
	)
	(segment
		(start 54.017926 -383.92227)
		(end 54.070504 -384.617722)
		(width 0.254)
		(layer "F.Cu")
		(net "GND")
	)
	(segment
		(start 12.342622 -411.712918)
		(end 12.090908 -411.964632)
		(width 0.1778)
		(layer "F.Cu")
		(net "GND")
	)
	(segment
		(start 80.287876 -246.370348)
		(end 79.821024 -246.10441)
		(width 0.350012)
		(layer "F.Cu")
		(net "GND")
	)
	(segment
		(start 333.39786 -235.840016)
		(end 332.931008 -235.574078)
		(width 0.350012)
		(layer "F.Cu")
		(net "GND")
	)
	(segment
		(start 97.507806 -289.210242)
		(end 97.040954 -289.47618)
		(width 0.350012)
		(layer "F.Cu")
		(net "GND")
	)
	(segment
		(start 163.52139 -75.481434)
		(end 164.15639 -75.481434)
		(width 0.4572)
		(layer "F.Cu")
		(net "GND")
	)
	(segment
		(start 84.347812 -271.390364)
		(end 83.88096 -271.656302)
		(width 0.350012)
		(layer "F.Cu")
		(net "GND")
	)
	(segment
		(start 139.977876 -239.080294)
		(end 140.444728 -238.814356)
		(width 0.350012)
		(layer "F.Cu")
		(net "GND")
	)
	(segment
		(start 83.51901 -390.160002)
		(end 84.19846 -390.160002)
		(width 0.254)
		(layer "F.Cu")
		(net "GND")
	)
	(segment
		(start 412.367984 -200.735184)
		(end 413.752284 -200.735184)
		(width 0.4572)
		(layer "F.Cu")
		(net "GND")
	)
	(segment
		(start 319.0621 -392.999722)
		(end 319.67043 -392.999722)
		(width 0.254)
		(layer "F.Cu")
		(net "GND")
	)
	(via
		(at 216.777824 -12.542266)
		(size 0.508)
		(drill 0.254)
		(layers "F.Cu" "B.Cu")
		(net "GND")
	)
	(via
		(at 381.634746 -265.176)
		(size 0.4064)
		(drill 0.2032)
		(layers "F.Cu" "B.Cu")
		(net "GND")
	)
	(via
		(at 363.944916 -243.674138)
		(size 0.4064)
		(drill 0.2032)
		(layers "F.Cu" "B.Cu")
		(net "GND")
	)
	(via
		(at 100.500942 -255.824482)
		(size 0.4064)
		(drill 0.2032)
		(layers "F.Cu" "B.Cu")
		(net "GND")
	)
	(via
		(at 312.513218 -419.046152)
		(size 0.4572)
		(drill 0.254)
		(layers "F.Cu" "B.Cu")
		(net "GND")
	)
	(via
		(at 116.004848 -227.474526)
		(size 0.4064)
		(drill 0.2032)
		(layers "F.Cu" "B.Cu")
		(net "GND")
	)
	(via
		(at 133.725666 -157.681168)
		(size 0.49022)
		(drill 0.254)
		(layers "F.Cu" "B.Cu")
		(net "GND")
	)
	(via
		(at 64.475614 -372.15953)
		(size 0.508)
		(drill 0.254)
		(layers "F.Cu" "B.Cu")
		(net "GND")
	)
	(via
		(at 65.391284 -390.160002)
		(size 0.4064)
		(drill 0.2032)
		(layers "F.Cu" "B.Cu")
		(net "GND")
	)
	(via
		(at 405.12111 -0.762254)
		(size 0.508)
		(drill 0.254)
		(layers "F.Cu" "B.Cu")
		(net "GND")
	)
	(via
		(at 269.648178 -282.33497)
		(size 0.4826)
		(drill 0.254)
		(layers "F.Cu" "B.Cu")
		(net "GND")
	)
	(via
		(at 307.832506 -415.38652)
		(size 0.4064)
		(drill 0.2032)
		(layers "F.Cu" "B.Cu")
		(net "GND")
	)
	(via
		(at 106.91114 -280.566368)
		(size 0.4064)
		(drill 0.2032)
		(layers "F.Cu" "B.Cu")
		(net "GND")
	)
	(via
		(at 94.861126 -236.384338)
		(size 0.4064)
		(drill 0.2032)
		(layers "F.Cu" "B.Cu")
		(net "GND")
	)
	(via
		(at 434.565044 -20.880832)
		(size 0.508)
		(drill 0.254)
		(layers "F.Cu" "B.Cu")
		(net "GND")
	)
	(via
		(at 39.056818 -345.555824)
		(size 0.49022)
		(drill 0.254)
		(layers "F.Cu" "B.Cu")
		(net "GND")
	)
	(via
		(at 439.100214 -297.635168)
		(size 0.4826)
		(drill 0.254)
		(layers "F.Cu" "B.Cu")
		(net "GND")
	)
	(via
		(at 357.769922 -353.523804)
		(size 0.508)
		(drill 0.254)
		(layers "F.Cu" "B.Cu")
		(net "GND")
	)
	(via
		(at 24.034496 -220.710252)
		(size 0.4826)
		(drill 0.254)
		(layers "F.Cu" "B.Cu")
		(net "GND")
	)
	(via
		(at 411.349698 -435.0512)
		(size 0.4572)
		(drill 0.2032)
		(layers "F.Cu" "B.Cu")
		(net "GND")
	)
	(via
		(at 366.764824 -227.474272)
		(size 0.4064)
		(drill 0.2032)
		(layers "F.Cu" "B.Cu")
		(net "GND")
	)
	(via
		(at 148.787104 -373.30253)
		(size 0.508)
		(drill 0.254)
		(layers "F.Cu" "B.Cu")
		(net "GND")
	)
	(via
		(at 171.97197 -217.735404)
		(size 0.4826)
		(drill 0.254)
		(layers "F.Cu" "B.Cu")
		(net "GND")
	)
	(via
		(at 119.294656 -223.424496)
		(size 0.4064)
		(drill 0.2032)
		(layers "F.Cu" "B.Cu")
		(net "GND")
	)
	(via
		(at 143.264636 -225.854514)
		(size 0.4064)
		(drill 0.2032)
		(layers "F.Cu" "B.Cu")
		(net "GND")
	)
	(via
		(at 330.892658 -419.046152)
		(size 0.4572)
		(drill 0.254)
		(layers "F.Cu" "B.Cu")
		(net "GND")
	)
	(via
		(at 112.855756 -368.37493)
		(size 0.508)
		(drill 0.254)
		(layers "F.Cu" "B.Cu")
		(net "GND")
	)
	(via
		(at 102.38105 -233.144314)
		(size 0.4064)
		(drill 0.2032)
		(layers "F.Cu" "B.Cu")
		(net "GND")
	)
	(via
		(at 338.401152 -294.335962)
		(size 0.4064)
		(drill 0.2032)
		(layers "F.Cu" "B.Cu")
		(net "GND")
	)
	(via
		(at 390.981692 -377.41733)
		(size 0.508)
		(drill 0.254)
		(layers "F.Cu" "B.Cu")
		(net "GND")
	)
	(via
		(at 94.151958 -333.87919)
		(size 0.49022)
		(drill 0.254)
		(layers "F.Cu" "B.Cu")
		(net "GND")
	)
	(via
		(at 122.584718 -222.61449)
		(size 0.4064)
		(drill 0.2032)
		(layers "F.Cu" "B.Cu")
		(net "GND")
	)
	(via
		(at 383.035302 -415.38652)
		(size 0.4064)
		(drill 0.2032)
		(layers "F.Cu" "B.Cu")
		(net "GND")
	)
	(via
		(at 332.172564 -143.005302)
		(size 0.508)
		(drill 0.254)
		(layers "F.Cu" "B.Cu")
		(net "GND")
	)
	(via
		(at 257.429 -341.503)
		(size 0.508)
		(drill 0.254)
		(layers "F.Cu" "B.Cu")
		(net "GND")
	)
	(via
		(at 329.6412 -238.004096)
		(size 0.4064)
		(drill 0.2032)
		(layers "F.Cu" "B.Cu")
		(net "GND")
	)
	(via
		(at 28.134564 -304.010314)
		(size 0.4826)
		(drill 0.254)
		(layers "F.Cu" "B.Cu")
		(net "GND")
	)
	(via
		(at 278.289766 -343.472008)
		(size 0.508)
		(drill 0.254)
		(layers "F.Cu" "B.Cu")
		(net "GND")
	)
	(via
		(at 397.171164 -17.61236)
		(size 0.508)
		(drill 0.254)
		(layers "F.Cu" "B.Cu")
		(net "GND")
	)
	(via
		(at 344.249502 -437.49976)
		(size 0.4572)
		(drill 0.2032)
		(layers "F.Cu" "B.Cu")
		(net "GND")
	)
	(via
		(at 148.030946 -412.570168)
		(size 0.4064)
		(drill 0.2032)
		(layers "F.Cu" "B.Cu")
		(net "GND")
	)
	(via
		(at 56.513476 -407.638504)
		(size 0.4572)
		(drill 0.254)
		(layers "F.Cu" "B.Cu")
		(net "GND")
	)
	(via
		(at 288.180018 -250.884944)
		(size 0.4826)
		(drill 0.254)
		(layers "F.Cu" "B.Cu")
		(net "GND")
	)
	(via
		(at 291.205158 -421.244014)
		(size 0.508)
		(drill 0.254)
		(layers "F.Cu" "B.Cu")
		(net "GND")
	)
	(via
		(at 371.294914 -265.176)
		(size 0.4064)
		(drill 0.2032)
		(layers "F.Cu" "B.Cu")
		(net "GND")
	)
	(via
		(at 89.99093 -277.326344)
		(size 0.4064)
		(drill 0.2032)
		(layers "F.Cu" "B.Cu")
		(net "GND")
	)
	(via
		(at 367.534698 -266.796012)
		(size 0.4064)
		(drill 0.2032)
		(layers "F.Cu" "B.Cu")
		(net "GND")
	)
	(via
		(at 56.97855 -386.449062)
		(size 0.4064)
		(drill 0.2032)
		(layers "F.Cu" "B.Cu")
		(net "GND")
	)
	(via
		(at 344.981022 -282.996132)
		(size 0.4064)
		(drill 0.2032)
		(layers "F.Cu" "B.Cu")
		(net "GND")
	)
	(via
		(at 69.039232 -411.936184)
		(size 0.4572)
		(drill 0.254)
		(layers "F.Cu" "B.Cu")
		(net "GND")
	)
	(via
		(at 404.290022 -392.999722)
		(size 0.4064)
		(drill 0.2032)
		(layers "F.Cu" "B.Cu")
		(net "GND")
	)
	(via
		(at 396.349474 -431.29962)
		(size 0.4572)
		(drill 0.2032)
		(layers "F.Cu" "B.Cu")
		(net "GND")
	)
	(via
		(at 48.681894 -17.61236)
		(size 0.508)
		(drill 0.254)
		(layers "F.Cu" "B.Cu")
		(net "GND")
	)
	(via
		(at 148.392134 -411.936184)
		(size 0.4572)
		(drill 0.254)
		(layers "F.Cu" "B.Cu")
		(net "GND")
	)
	(via
		(at 325.24954 -426.54728)
		(size 0.4572)
		(drill 0.2032)
		(layers "F.Cu" "B.Cu")
		(net "GND")
	)
	(via
		(at 124.09932 -36.053268)
		(size 0.508)
		(drill 0.254)
		(layers "F.Cu" "B.Cu")
		(net "GND")
	)
	(via
		(at 98.150934 -235.574332)
		(size 0.4064)
		(drill 0.2032)
		(layers "F.Cu" "B.Cu")
		(net "GND")
	)
	(via
		(at 349.851218 -248.534174)
		(size 0.4064)
		(drill 0.2032)
		(layers "F.Cu" "B.Cu")
		(net "GND")
	)
	(via
		(at 334.171036 -293.525956)
		(size 0.4064)
		(drill 0.2032)
		(layers "F.Cu" "B.Cu")
		(net "GND")
	)
	(via
		(at 97.681034 -254.20447)
		(size 0.4064)
		(drill 0.2032)
		(layers "F.Cu" "B.Cu")
		(net "GND")
	)
	(via
		(at 394.929614 -416.020504)
		(size 0.4572)
		(drill 0.254)
		(layers "F.Cu" "B.Cu")
		(net "GND")
	)
	(via
		(at 346.995242 -258.830064)
		(size 0.4826)
		(drill 0.254)
		(layers "F.Cu" "B.Cu")
		(net "GND")
	)
	(via
		(at 351.303844 -379.88113)
		(size 0.508)
		(drill 0.254)
		(layers "F.Cu" "B.Cu")
		(net "GND")
	)
	(via
		(at 102.211124 -285.426404)
		(size 0.4064)
		(drill 0.2032)
		(layers "F.Cu" "B.Cu")
		(net "GND")
	)
	(via
		(at 99.177094 -67.994276)
		(size 0.508)
		(drill 0.254)
		(layers "F.Cu" "B.Cu")
		(net "GND")
	)
	(via
		(at 416.372294 -414.72866)
		(size 0.4572)
		(drill 0.254)
		(layers "F.Cu" "B.Cu")
		(net "GND")
	)
	(via
		(at 444.007748 -329.740006)
		(size 0.6604)
		(drill 0.3302)
		(layers "F.Cu" "B.Cu")
		(net "GND")
	)
	(via
		(at 385.873752 -383.00533)
		(size 0.508)
		(drill 0.254)
		(layers "F.Cu" "B.Cu")
		(net "GND")
	)
	(via
		(at 198.7042 -207.535272)
		(size 0.4826)
		(drill 0.254)
		(layers "F.Cu" "B.Cu")
		(net "GND")
	)
	(via
		(at 338.249514 -430.147222)
		(size 0.4572)
		(drill 0.2032)
		(layers "F.Cu" "B.Cu")
		(net "GND")
	)
	(via
		(at 303.462182 -392.999722)
		(size 0.4064)
		(drill 0.2032)
		(layers "F.Cu" "B.Cu")
		(net "GND")
	)
	(via
		(at 40.23995 -242.385342)
		(size 0.4826)
		(drill 0.254)
		(layers "F.Cu" "B.Cu")
		(net "GND")
	)
	(via
		(at 88.580976 -276.516338)
		(size 0.4064)
		(drill 0.2032)
		(layers "F.Cu" "B.Cu")
		(net "GND")
	)
	(via
		(at 189.752986 -351.886774)
		(size 0.49022)
		(drill 0.254)
		(layers "F.Cu" "B.Cu")
		(net "GND")
	)
	(via
		(at 345.621102 -255.824228)
		(size 0.4064)
		(drill 0.2032)
		(layers "F.Cu" "B.Cu")
		(net "GND")
	)
	(via
		(at 371.46484 -237.19409)
		(size 0.4064)
		(drill 0.2032)
		(layers "F.Cu" "B.Cu")
		(net "GND")
	)
	(via
		(at 160.730946 -410.030168)
		(size 0.4064)
		(drill 0.2032)
		(layers "F.Cu" "B.Cu")
		(net "GND")
	)
	(via
		(at 144.674844 -225.044508)
		(size 0.4064)
		(drill 0.2032)
		(layers "F.Cu" "B.Cu")
		(net "GND")
	)
	(via
		(at 135.574786 -276.516338)
		(size 0.4064)
		(drill 0.2032)
		(layers "F.Cu" "B.Cu")
		(net "GND")
	)
	(via
		(at 162.401504 -373.30253)
		(size 0.508)
		(drill 0.254)
		(layers "F.Cu" "B.Cu")
		(net "GND")
	)
	(via
		(at 385.394708 -266.796012)
		(size 0.4064)
		(drill 0.2032)
		(layers "F.Cu" "B.Cu")
		(net "GND")
	)
	(via
		(at 361.124754 -246.914162)
		(size 0.4064)
		(drill 0.2032)
		(layers "F.Cu" "B.Cu")
		(net "GND")
	)
	(via
		(at 351.091246 -282.186126)
		(size 0.4064)
		(drill 0.2032)
		(layers "F.Cu" "B.Cu")
		(net "GND")
	)
	(via
		(at 331.051154 -237.19409)
		(size 0.4064)
		(drill 0.2032)
		(layers "F.Cu" "B.Cu")
		(net "GND")
	)
	(via
		(at 140.822426 -404.46452)
		(size 0.4064)
		(drill 0.2032)
		(layers "F.Cu" "B.Cu")
		(net "GND")
	)
	(via
		(at 273.092164 -250.884944)
		(size 0.4826)
		(drill 0.254)
		(layers "F.Cu" "B.Cu")
		(net "GND")
	)
	(via
		(at 47.784004 -311.235344)
		(size 0.4826)
		(drill 0.254)
		(layers "F.Cu" "B.Cu")
		(net "GND")
	)
	(via
		(at 42.955718 -286.585406)
		(size 0.4826)
		(drill 0.254)
		(layers "F.Cu" "B.Cu")
		(net "GND")
	)
	(via
		(at 45.899578 -4.963414)
		(size 0.508)
		(drill 0.254)
		(layers "F.Cu" "B.Cu")
		(net "GND")
	)
	(via
		(at 86.701122 -289.47618)
		(size 0.4064)
		(drill 0.2032)
		(layers "F.Cu" "B.Cu")
		(net "GND")
	)
	(via
		(at 239.502696 -249.566938)
		(size 0.4826)
		(drill 0.254)
		(layers "F.Cu" "B.Cu")
		(net "GND")
	)
	(via
		(at 141.854682 -244.484398)
		(size 0.4064)
		(drill 0.2032)
		(layers "F.Cu" "B.Cu")
		(net "GND")
	)
	(via
		(at 448.148964 -14.607032)
		(size 0.508)
		(drill 0.254)
		(layers "F.Cu" "B.Cu")
		(net "GND")
	)
	(via
		(at 83.88096 -276.516338)
		(size 0.4064)
		(drill 0.2032)
		(layers "F.Cu" "B.Cu")
		(net "GND")
	)
	(via
		(at 184.480708 -421.137588)
		(size 0.508)
		(drill 0.254)
		(layers "F.Cu" "B.Cu")
		(net "GND")
	)
	(via
		(at 370.82476 -288.66592)
		(size 0.4064)
		(drill 0.2032)
		(layers "F.Cu" "B.Cu")
		(net "GND")
	)
	(via
		(at 421.029638 -304.860198)
		(size 0.4826)
		(drill 0.254)
		(layers "F.Cu" "B.Cu")
		(net "GND")
	)
	(via
		(at 280.635964 -216.035128)
		(size 0.4826)
		(drill 0.254)
		(layers "F.Cu" "B.Cu")
		(net "GND")
	)
	(via
		(at 179.516024 -264.485374)
		(size 0.4826)
		(drill 0.254)
		(layers "F.Cu" "B.Cu")
		(net "GND")
	)
	(via
		(at 380.629922 -149.311614)
		(size 0.508)
		(drill 0.254)
		(layers "F.Cu" "B.Cu")
		(net "GND")
	)
	(via
		(at 300.065694 -393.04468)
		(size 0.508)
		(drill 0.254)
		(layers "F.Cu" "B.Cu")
		(net "GND")
	)
	(via
		(at 338.101178 -234.764072)
		(size 0.4064)
		(drill 0.2032)
		(layers "F.Cu" "B.Cu")
		(net "GND")
	)
	(via
		(at 162.886644 -373.96293)
		(size 0.508)
		(drill 0.254)
		(layers "F.Cu" "B.Cu")
		(net "GND")
	)
	(via
		(at 411.59684 -379.88113)
		(size 0.508)
		(drill 0.254)
		(layers "F.Cu" "B.Cu")
		(net "GND")
	)
	(via
		(at 155.419044 -390.160002)
		(size 0.4064)
		(drill 0.2032)
		(layers "F.Cu" "B.Cu")
		(net "GND")
	)
	(via
		(at 83.88096 -278.13635)
		(size 0.4064)
		(drill 0.2032)
		(layers "F.Cu" "B.Cu")
		(net "GND")
	)
	(via
		(at 368.644678 -235.574078)
		(size 0.4064)
		(drill 0.2032)
		(layers "F.Cu" "B.Cu")
		(net "GND")
	)
	(via
		(at 345.038426 -420.952168)
		(size 0.4064)
		(drill 0.2032)
		(layers "F.Cu" "B.Cu")
		(net "GND")
	)
	(via
		(at 338.498942 -139.524486)
		(size 0.508)
		(drill 0.254)
		(layers "F.Cu" "B.Cu")
		(net "GND")
	)
	(via
		(at 398.657572 -204.897736)
		(size 0.508)
		(drill 0.254)
		(layers "F.Cu" "B.Cu")
		(net "GND")
	)
	(via
		(at 91.871038 -277.326344)
		(size 0.4064)
		(drill 0.2032)
		(layers "F.Cu" "B.Cu")
		(net "GND")
	)
	(via
		(at 78.314804 -410.030168)
		(size 0.4064)
		(drill 0.2032)
		(layers "F.Cu" "B.Cu")
		(net "GND")
	)
	(via
		(at 386.091176 -398.542002)
		(size 0.4064)
		(drill 0.2032)
		(layers "F.Cu" "B.Cu")
		(net "GND")
	)
	(via
		(at 189.775846 -312.085228)
		(size 0.4826)
		(drill 0.254)
		(layers "F.Cu" "B.Cu")
		(net "GND")
	)
	(via
		(at 99.055174 -259.73024)
		(size 0.4826)
		(drill 0.254)
		(layers "F.Cu" "B.Cu")
		(net "GND")
	)
	(via
		(at 183.616092 -288.285428)
		(size 0.4826)
		(drill 0.254)
		(layers "F.Cu" "B.Cu")
		(net "GND")
	)
	(via
		(at 434.023516 -331.111352)
		(size 0.508)
		(drill 0.254)
		(layers "F.Cu" "B.Cu")
		(net "GND")
	)
	(via
		(at 386.01269 -413.480504)
		(size 0.4572)
		(drill 0.254)
		(layers "F.Cu" "B.Cu")
		(net "GND")
	)
	(via
		(at 421.296338 -275.535136)
		(size 0.4826)
		(drill 0.254)
		(layers "F.Cu" "B.Cu")
		(net "GND")
	)
	(via
		(at 349.211138 -295.145968)
		(size 0.4064)
		(drill 0.2032)
		(layers "F.Cu" "B.Cu")
		(net "GND")
	)
	(via
		(at 331.521054 -244.484144)
		(size 0.4064)
		(drill 0.2032)
		(layers "F.Cu" "B.Cu")
		(net "GND")
	)
	(via
		(at 126.814834 -250.964446)
		(size 0.4064)
		(drill 0.2032)
		(layers "F.Cu" "B.Cu")
		(net "GND")
	)
	(via
		(at 118.5164 -382.85293)
		(size 0.4064)
		(drill 0.2032)
		(layers "F.Cu" "B.Cu")
		(net "GND")
	)
	(via
		(at 16.31569 -390.8425)
		(size 0.49022)
		(drill 0.254)
		(layers "F.Cu" "B.Cu")
		(net "GND")
	)
	(via
		(at 63.261494 -372.15953)
		(size 0.508)
		(drill 0.254)
		(layers "F.Cu" "B.Cu")
		(net "GND")
	)
	(via
		(at 361.124754 -224.234248)
		(size 0.4064)
		(drill 0.2032)
		(layers "F.Cu" "B.Cu")
		(net "GND")
	)
	(via
		(at 54.383178 -28.707588)
		(size 0.508)
		(drill 0.254)
		(layers "F.Cu" "B.Cu")
		(net "GND")
	)
	(via
		(at 230.961692 -49.76495)
		(size 0.508)
		(drill 0.254)
		(layers "F.Cu" "B.Cu")
		(net "GND")
	)
	(via
		(at 203.303632 -193.107564)
		(size 0.4826)
		(drill 0.254)
		(layers "F.Cu" "B.Cu")
		(net "GND")
	)
	(via
		(at 141.854682 -249.344434)
		(size 0.4064)
		(drill 0.2032)
		(layers "F.Cu" "B.Cu")
		(net "GND")
	)
	(via
		(at 145.444718 -293.52621)
		(size 0.4064)
		(drill 0.2032)
		(layers "F.Cu" "B.Cu")
		(net "GND")
	)
	(via
		(at 89.690956 -250.15444)
		(size 0.4064)
		(drill 0.2032)
		(layers "F.Cu" "B.Cu")
		(net "GND")
	)
	(via
		(at 40.23995 -199.035416)
		(size 0.4826)
		(drill 0.254)
		(layers "F.Cu" "B.Cu")
		(net "GND")
	)
	(via
		(at 56.712358 -219.435426)
		(size 0.4826)
		(drill 0.254)
		(layers "F.Cu" "B.Cu")
		(net "GND")
	)
	(via
		(at 140.349732 -439.651394)
		(size 0.4572)
		(drill 0.2032)
		(layers "F.Cu" "B.Cu")
		(net "GND")
	)
	(via
		(at 235.942124 -328.085704)
		(size 0.508)
		(drill 0.254)
		(layers "F.Cu" "B.Cu")
		(net "GND")
	)
	(via
		(at 58.310526 -229.210362)
		(size 0.4826)
		(drill 0.254)
		(layers "F.Cu" "B.Cu")
		(net "GND")
	)
	(via
		(at 273.092164 -281.485086)
		(size 0.4826)
		(drill 0.254)
		(layers "F.Cu" "B.Cu")
		(net "GND")
	)
	(via
		(at 204.8637 -218.585288)
		(size 0.4826)
		(drill 0.254)
		(layers "F.Cu" "B.Cu")
		(net "GND")
	)
	(via
		(at 317.862204 -392.999722)
		(size 0.4064)
		(drill 0.2032)
		(layers "F.Cu" "B.Cu")
		(net "GND")
	)
	(via
		(at 431.329592 -349.990156)
		(size 0.49022)
		(drill 0.254)
		(layers "F.Cu" "B.Cu")
		(net "GND")
	)
	(via
		(at 53.450236 -410.664152)
		(size 0.4572)
		(drill 0.254)
		(layers "F.Cu" "B.Cu")
		(net "GND")
	)
	(via
		(at 347.33103 -275.706078)
		(size 0.4064)
		(drill 0.2032)
		(layers "F.Cu" "B.Cu")
		(net "GND")
	)
	(via
		(at 95.6564 -146.6596)
		(size 0.508)
		(drill 0.254)
		(layers "F.Cu" "B.Cu")
		(net "GND")
	)
	(via
		(at 304.718212 -396.710662)
		(size 0.4064)
		(drill 0.2032)
		(layers "F.Cu" "B.Cu")
		(net "GND")
	)
	(via
		(at 32.695896 -292.535356)
		(size 0.4826)
		(drill 0.254)
		(layers "F.Cu" "B.Cu")
		(net "GND")
	)
	(via
		(at 366.764824 -251.774198)
		(size 0.4064)
		(drill 0.2032)
		(layers "F.Cu" "B.Cu")
		(net "GND")
	)
	(via
		(at 2.76225 -199.573134)
		(size 0.508)
		(drill 0.254)
		(layers "F.Cu" "B.Cu")
		(net "GND")
	)
	(via
		(at 340.24951 -427.851316)
		(size 0.4572)
		(drill 0.2032)
		(layers "F.Cu" "B.Cu")
		(net "GND")
	)
	(via
		(at 72.617584 -6.08711)
		(size 0.508)
		(drill 0.254)
		(layers "F.Cu" "B.Cu")
		(net "GND")
	)
	(via
		(at 405.565102 -418.412168)
		(size 0.4064)
		(drill 0.2032)
		(layers "F.Cu" "B.Cu")
		(net "GND")
	)
	(via
		(at 179.367688 -394.228828)
		(size 0.508)
		(drill 0.254)
		(layers "F.Cu" "B.Cu")
		(net "GND")
	)
	(via
		(at 139.825222 -153.392124)
		(size 0.6604)
		(drill 0.3302)
		(layers "F.Cu" "B.Cu")
		(net "GND")
	)
	(via
		(at 99.390962 -285.426404)
		(size 0.4064)
		(drill 0.2032)
		(layers "F.Cu" "B.Cu")
		(net "GND")
	)
	(via
		(at 201.36358 -358.46258)
		(size 0.6604)
		(drill 0.3302)
		(layers "F.Cu" "B.Cu")
		(net "GND")
	)
	(via
		(at 50.499772 -284.035246)
		(size 0.4826)
		(drill 0.254)
		(layers "F.Cu" "B.Cu")
		(net "GND")
	)
	(via
		(at 307.368194 -299.33519)
		(size 0.4826)
		(drill 0.254)
		(layers "F.Cu" "B.Cu")
		(net "GND")
	)
	(via
		(at 97.211134 -232.334308)
		(size 0.4064)
		(drill 0.2032)
		(layers "F.Cu" "B.Cu")
		(net "GND")
	)
	(via
		(at 144.469866 -392.768582)
		(size 0.508)
		(drill 0.254)
		(layers "F.Cu" "B.Cu")
		(net "GND")
	)
	(via
		(at 168.527984 -268.735302)
		(size 0.4826)
		(drill 0.254)
		(layers "F.Cu" "B.Cu")
		(net "GND")
	)
	(via
		(at 114.370866 -173.862746)
		(size 0.49022)
		(drill 0.254)
		(layers "F.Cu" "B.Cu")
		(net "GND")
	)
	(via
		(at 428.461678 -427.715172)
		(size 0.508)
		(drill 0.254)
		(layers "F.Cu" "B.Cu")
		(net "GND")
	)
	(via
		(at 266.93241 -203.28509)
		(size 0.4826)
		(drill 0.254)
		(layers "F.Cu" "B.Cu")
		(net "GND")
	)
	(via
		(at 387.914896 -225.044254)
		(size 0.4064)
		(drill 0.2032)
		(layers "F.Cu" "B.Cu")
		(net "GND")
	)
	(via
		(at 361.424728 -277.32609)
		(size 0.4064)
		(drill 0.2032)
		(layers "F.Cu" "B.Cu")
		(net "GND")
	)
	(via
		(at 114.335306 -412.570168)
		(size 0.4064)
		(drill 0.2032)
		(layers "F.Cu" "B.Cu")
		(net "GND")
	)
	(via
		(at 335.11109 -272.466054)
		(size 0.4064)
		(drill 0.2032)
		(layers "F.Cu" "B.Cu")
		(net "GND")
	)
	(via
		(at 85.919056 -390.160002)
		(size 0.4064)
		(drill 0.2032)
		(layers "F.Cu" "B.Cu")
		(net "GND")
	)
	(via
		(at 229.622096 -323.263768)
		(size 0.508)
		(drill 0.254)
		(layers "F.Cu" "B.Cu")
		(net "GND")
	)
	(via
		(at 164.427916 -242.385342)
		(size 0.4826)
		(drill 0.254)
		(layers "F.Cu" "B.Cu")
		(net "GND")
	)
	(via
		(at 52.279804 -404.46452)
		(size 0.4064)
		(drill 0.2032)
		(layers "F.Cu" "B.Cu")
		(net "GND")
	)
	(via
		(at 385.881118 -185.327798)
		(size 0.508)
		(drill 0.254)
		(layers "F.Cu" "B.Cu")
		(net "GND")
	)
	(via
		(at 398.445482 -10.16508)
		(size 0.508)
		(drill 0.254)
		(layers "F.Cu" "B.Cu")
		(net "GND")
	)
	(via
		(at 359.144824 -385.514088)
		(size 0.508)
		(drill 0.254)
		(layers "F.Cu" "B.Cu")
		(net "GND")
	)
	(via
		(at 21.16836 -420.205662)
		(size 0.508)
		(drill 0.254)
		(layers "F.Cu" "B.Cu")
		(net "GND")
	)
	(via
		(at 82.001106 -291.096192)
		(size 0.4064)
		(drill 0.2032)
		(layers "F.Cu" "B.Cu")
		(net "GND")
	)
	(via
		(at 38.05682 -112.24768)
		(size 0.508)
		(drill 0.254)
		(layers "F.Cu" "B.Cu")
		(net "GND")
	)
	(via
		(at 331.39507 -20.270978)
		(size 0.508)
		(drill 0.254)
		(layers "F.Cu" "B.Cu")
		(net "GND")
	)
	(via
		(at 421.296338 -312.935112)
		(size 0.4826)
		(drill 0.254)
		(layers "F.Cu" "B.Cu")
		(net "GND")
	)
	(via
		(at 341.691214 -269.22603)
		(size 0.4064)
		(drill 0.2032)
		(layers "F.Cu" "B.Cu")
		(net "GND")
	)
	(via
		(at 135.274812 -223.424496)
		(size 0.4064)
		(drill 0.2032)
		(layers "F.Cu" "B.Cu")
		(net "GND")
	)
	(via
		(at 176.072038 -301.035212)
		(size 0.4826)
		(drill 0.254)
		(layers "F.Cu" "B.Cu")
		(net "GND")
	)
	(via
		(at 339.811106 -264.365994)
		(size 0.4064)
		(drill 0.2032)
		(layers "F.Cu" "B.Cu")
		(net "GND")
	)
	(via
		(at 95.631 -269.226284)
		(size 0.4064)
		(drill 0.2032)
		(layers "F.Cu" "B.Cu")
		(net "GND")
	)
	(via
		(at 130.87477 -281.376374)
		(size 0.4064)
		(drill 0.2032)
		(layers "F.Cu" "B.Cu")
		(net "GND")
	)
	(via
		(at 305.983894 -312.084974)
		(size 0.4826)
		(drill 0.254)
		(layers "F.Cu" "B.Cu")
		(net "GND")
	)
	(via
		(at 23.945596 -7.215124)
		(size 0.508)
		(drill 0.254)
		(layers "F.Cu" "B.Cu")
		(net "GND")
	)
	(via
		(at 174.771304 -329.566524)
		(size 0.508)
		(drill 0.254)
		(layers "F.Cu" "B.Cu")
		(net "GND")
	)
	(via
		(at 388.063232 -381.68453)
		(size 0.508)
		(drill 0.254)
		(layers "F.Cu" "B.Cu")
		(net "GND")
	)
	(via
		(at 206.248 -306.985416)
		(size 0.4826)
		(drill 0.254)
		(layers "F.Cu" "B.Cu")
		(net "GND")
	)
	(via
		(at 304.423826 -193.10731)
		(size 0.4826)
		(drill 0.254)
		(layers "F.Cu" "B.Cu")
		(net "GND")
	)
	(via
		(at 113.48466 -290.286186)
		(size 0.4064)
		(drill 0.2032)
		(layers "F.Cu" "B.Cu")
		(net "GND")
	)
	(via
		(at 326.651112 -261.12597)
		(size 0.4064)
		(drill 0.2032)
		(layers "F.Cu" "B.Cu")
		(net "GND")
	)
	(via
		(at 112.205008 -387.04774)
		(size 0.4064)
		(drill 0.2032)
		(layers "F.Cu" "B.Cu")
		(net "GND")
	)
	(via
		(at 104.090978 -265.98626)
		(size 0.4064)
		(drill 0.2032)
		(layers "F.Cu" "B.Cu")
		(net "GND")
	)
	(via
		(at 387.473698 -184.679082)
		(size 0.49022)
		(drill 0.254)
		(layers "F.Cu" "B.Cu")
		(net "GND")
	)
	(via
		(at 381.634746 -287.856168)
		(size 0.4064)
		(drill 0.2032)
		(layers "F.Cu" "B.Cu")
		(net "GND")
	)
	(via
		(at 35.579558 -344.781886)
		(size 0.49022)
		(drill 0.254)
		(layers "F.Cu" "B.Cu")
		(net "GND")
	)
	(via
		(at 379.028198 -31.455868)
		(size 0.508)
		(drill 0.254)
		(layers "F.Cu" "B.Cu")
		(net "GND")
	)
	(via
		(at 386.804916 -293.525956)
		(size 0.4064)
		(drill 0.2032)
		(layers "F.Cu" "B.Cu")
		(net "GND")
	)
	(via
		(at 292.280086 -205.834996)
		(size 0.4826)
		(drill 0.254)
		(layers "F.Cu" "B.Cu")
		(net "GND")
	)
	(via
		(at 305.483006 -335.658968)
		(size 0.508)
		(drill 0.254)
		(layers "F.Cu" "B.Cu")
		(net "GND")
	)
	(via
		(at 380.768352 -379.22073)
		(size 0.508)
		(drill 0.254)
		(layers "F.Cu" "B.Cu")
		(net "GND")
	)
	(via
		(at 102.811834 -177.46218)
		(size 0.508)
		(drill 0.254)
		(layers "F.Cu" "B.Cu")
		(net "GND")
	)
	(via
		(at 298.43984 -314.635134)
		(size 0.4826)
		(drill 0.254)
		(layers "F.Cu" "B.Cu")
		(net "GND")
	)
	(via
		(at 403.187154 -441.227718)
		(size 0.508)
		(drill 0.254)
		(layers "F.Cu" "B.Cu")
		(net "GND")
	)
	(via
		(at 289.97783 -416.564318)
		(size 0.508)
		(drill 0.254)
		(layers "F.Cu" "B.Cu")
		(net "GND")
	)
	(via
		(at 382.1049 -272.466054)
		(size 0.4064)
		(drill 0.2032)
		(layers "F.Cu" "B.Cu")
		(net "GND")
	)
	(via
		(at 404.218902 -398.542002)
		(size 0.4064)
		(drill 0.2032)
		(layers "F.Cu" "B.Cu")
		(net "GND")
	)
	(via
		(at 98.150934 -243.674392)
		(size 0.4064)
		(drill 0.2032)
		(layers "F.Cu" "B.Cu")
		(net "GND")
	)
	(via
		(at 381.253492 -379.88113)
		(size 0.508)
		(drill 0.254)
		(layers "F.Cu" "B.Cu")
		(net "GND")
	)
	(via
		(at 289.564318 -296.78503)
		(size 0.4826)
		(drill 0.254)
		(layers "F.Cu" "B.Cu")
		(net "GND")
	)
	(via
		(at 384.702304 -55.81142)
		(size 0.508)
		(drill 0.254)
		(layers "F.Cu" "B.Cu")
		(net "GND")
	)
	(via
		(at 332.697074 -417.778184)
		(size 0.4572)
		(drill 0.254)
		(layers "F.Cu" "B.Cu")
		(net "GND")
	)
	(via
		(at 188.177678 -304.860452)
		(size 0.4826)
		(drill 0.254)
		(layers "F.Cu" "B.Cu")
		(net "GND")
	)
	(via
		(at 194.604132 -289.135312)
		(size 0.4826)
		(drill 0.254)
		(layers "F.Cu" "B.Cu")
		(net "GND")
	)
	(via
		(at 194.604132 -206.685388)
		(size 0.4826)
		(drill 0.254)
		(layers "F.Cu" "B.Cu")
		(net "GND")
	)
	(via
		(at 337.631024 -227.474272)
		(size 0.4064)
		(drill 0.2032)
		(layers "F.Cu" "B.Cu")
		(net "GND")
	)
	(via
		(at 88.281002 -231.524302)
		(size 0.4064)
		(drill 0.2032)
		(layers "F.Cu" "B.Cu")
		(net "GND")
	)
	(via
		(at 51.884072 -268.735302)
		(size 0.4826)
		(drill 0.254)
		(layers "F.Cu" "B.Cu")
		(net "GND")
	)
	(via
		(at 116.944648 -225.854514)
		(size 0.4064)
		(drill 0.2032)
		(layers "F.Cu" "B.Cu")
		(net "GND")
	)
	(via
		(at 233.64952 -291.228526)
		(size 0.508)
		(drill 0.254)
		(layers "F.Cu" "B.Cu")
		(net "GND")
	)
	(via
		(at 299.82414 -263.634982)
		(size 0.4826)
		(drill 0.254)
		(layers "F.Cu" "B.Cu")
		(net "GND")
	)
	(via
		(at 119.291354 -409.396184)
		(size 0.4572)
		(drill 0.254)
		(layers "F.Cu" "B.Cu")
		(net "GND")
	)
	(via
		(at 108.02112 -246.10441)
		(size 0.4064)
		(drill 0.2032)
		(layers "F.Cu" "B.Cu")
		(net "GND")
	)
	(via
		(at 154.604466 -410.030168)
		(size 0.4064)
		(drill 0.2032)
		(layers "F.Cu" "B.Cu")
		(net "GND")
	)
	(via
		(at 398.714468 -4.32943)
		(size 0.508)
		(drill 0.254)
		(layers "F.Cu" "B.Cu")
		(net "GND")
	)
	(via
		(at 193.32702 -350.00565)
		(size 0.49022)
		(drill 0.254)
		(layers "F.Cu" "B.Cu")
		(net "GND")
	)
	(via
		(at 386.06222 -138.04138)
		(size 0.508)
		(drill 0.254)
		(layers "F.Cu" "B.Cu")
		(net "GND")
	)
	(via
		(at 369.114832 -254.204216)
		(size 0.4064)
		(drill 0.2032)
		(layers "F.Cu" "B.Cu")
		(net "GND")
	)
	(via
		(at 62.639956 -406.370536)
		(size 0.4572)
		(drill 0.254)
		(layers "F.Cu" "B.Cu")
		(net "GND")
	)
	(via
		(at 406.597104 -18.247868)
		(size 0.508)
		(drill 0.254)
		(layers "F.Cu" "B.Cu")
		(net "GND")
	)
	(via
		(at 189.775846 -286.585406)
		(size 0.4826)
		(drill 0.254)
		(layers "F.Cu" "B.Cu")
		(net "GND")
	)
	(via
		(at 352.9711 -287.045908)
		(size 0.4064)
		(drill 0.2032)
		(layers "F.Cu" "B.Cu")
		(net "GND")
	)
	(via
		(at 146.860514 -409.396184)
		(size 0.4572)
		(drill 0.254)
		(layers "F.Cu" "B.Cu")
		(net "GND")
	)
	(via
		(at 9.106408 -177.119788)
		(size 0.508)
		(drill 0.254)
		(layers "F.Cu" "B.Cu")
		(net "GND")
	)
	(via
		(at 340.166452 -161.981134)
		(size 0.49022)
		(drill 0.254)
		(layers "F.Cu" "B.Cu")
		(net "GND")
	)
	(via
		(at 95.1611 -294.336216)
		(size 0.4064)
		(drill 0.2032)
		(layers "F.Cu" "B.Cu")
		(net "GND")
	)
	(via
		(at 317.704724 -333.845154)
		(size 0.49022)
		(drill 0.254)
		(layers "F.Cu" "B.Cu")
		(net "GND")
	)
	(via
		(at 418.355526 -7.215124)
		(size 0.508)
		(drill 0.254)
		(layers "F.Cu" "B.Cu")
		(net "GND")
	)
	(via
		(at 433.833016 -19.13636)
		(size 0.508)
		(drill 0.254)
		(layers "F.Cu" "B.Cu")
		(net "GND")
	)
	(via
		(at 96.74098 -239.624362)
		(size 0.4064)
		(drill 0.2032)
		(layers "F.Cu" "B.Cu")
		(net "GND")
	)
	(via
		(at 388.21487 -287.856168)
		(size 0.4064)
		(drill 0.2032)
		(layers "F.Cu" "B.Cu")
		(net "GND")
	)
	(via
		(at 92.981018 -231.524302)
		(size 0.4064)
		(drill 0.2032)
		(layers "F.Cu" "B.Cu")
		(net "GND")
	)
	(via
		(at 341.22106 -261.935976)
		(size 0.4064)
		(drill 0.2032)
		(layers "F.Cu" "B.Cu")
		(net "GND")
	)
	(via
		(at 377.549918 -186.648598)
		(size 0.508)
		(drill 0.254)
		(layers "F.Cu" "B.Cu")
		(net "GND")
	)
	(via
		(at 457.778104 -53.089302)
		(size 0.508)
		(drill 0.254)
		(layers "F.Cu" "B.Cu")
		(net "GND")
	)
	(via
		(at 189.861952 -12.461748)
		(size 0.508)
		(drill 0.254)
		(layers "F.Cu" "B.Cu")
		(net "GND")
	)
	(via
		(at 277.192232 -232.184956)
		(size 0.4826)
		(drill 0.254)
		(layers "F.Cu" "B.Cu")
		(net "GND")
	)
	(via
		(at 375.29135 -398.542002)
		(size 0.4064)
		(drill 0.2032)
		(layers "F.Cu" "B.Cu")
		(net "GND")
	)
	(via
		(at 282.020264 -303.585118)
		(size 0.4826)
		(drill 0.254)
		(layers "F.Cu" "B.Cu")
		(net "GND")
	)
	(via
		(at 339.96376 -328.155046)
		(size 0.508)
		(drill 0.254)
		(layers "F.Cu" "B.Cu")
		(net "GND")
	)
	(via
		(at 447.017394 -45.69206)
		(size 0.508)
		(drill 0.254)
		(layers "F.Cu" "B.Cu")
		(net "GND")
	)
	(via
		(at 95.264224 -354.010214)
		(size 0.508)
		(drill 0.254)
		(layers "F.Cu" "B.Cu")
		(net "GND")
	)
	(via
		(at 353.441 -276.516084)
		(size 0.4064)
		(drill 0.2032)
		(layers "F.Cu" "B.Cu")
		(net "GND")
	)
	(via
		(at 69.57187 -154.55519)
		(size 0.508)
		(drill 0.254)
		(layers "F.Cu" "B.Cu")
		(net "GND")
	)
	(via
		(at 223.978978 -316.46368)
		(size 0.508)
		(drill 0.254)
		(layers "F.Cu" "B.Cu")
		(net "GND")
	)
	(via
		(at 40.23995 -279.785318)
		(size 0.4826)
		(drill 0.254)
		(layers "F.Cu" "B.Cu")
		(net "GND")
	)
	(via
		(at 254.694944 -40.117522)
		(size 0.508)
		(drill 0.254)
		(layers "F.Cu" "B.Cu")
		(net "GND")
	)
	(via
		(at 105.031032 -275.706332)
		(size 0.4064)
		(drill 0.2032)
		(layers "F.Cu" "B.Cu")
		(net "GND")
	)
	(via
		(at 84.79282 -355.980746)
		(size 0.508)
		(drill 0.254)
		(layers "F.Cu" "B.Cu")
		(net "GND")
	)
	(via
		(at 86.871048 -240.434368)
		(size 0.4064)
		(drill 0.2032)
		(layers "F.Cu" "B.Cu")
		(net "GND")
	)
	(via
		(at 20.782788 -369.84305)
		(size 0.508)
		(drill 0.254)
		(layers "F.Cu" "B.Cu")
		(net "GND")
	)
	(via
		(at 354.851208 -282.186126)
		(size 0.4064)
		(drill 0.2032)
		(layers "F.Cu" "B.Cu")
		(net "GND")
	)
	(via
		(at 59.428126 -250.035314)
		(size 0.4826)
		(drill 0.254)
		(layers "F.Cu" "B.Cu")
		(net "GND")
	)
	(via
		(at 327.761092 -242.864132)
		(size 0.4064)
		(drill 0.2032)
		(layers "F.Cu" "B.Cu")
		(net "GND")
	)
	(via
		(at 68.447158 -333.060802)
		(size 0.49022)
		(drill 0.254)
		(layers "F.Cu" "B.Cu")
		(net "GND")
	)
	(via
		(at 85.290914 -274.08632)
		(size 0.4064)
		(drill 0.2032)
		(layers "F.Cu" "B.Cu")
		(net "GND")
	)
	(via
		(at 171.97197 -269.58544)
		(size 0.4826)
		(drill 0.254)
		(layers "F.Cu" "B.Cu")
		(net "GND")
	)
	(via
		(at 195.988432 -284.885384)
		(size 0.4826)
		(drill 0.254)
		(layers "F.Cu" "B.Cu")
		(net "GND")
	)
	(via
		(at 463.578194 -41.755822)
		(size 0.508)
		(drill 0.254)
		(layers "F.Cu" "B.Cu")
		(net "GND")
	)
	(via
		(at 384.858768 -206.830676)
		(size 0.508)
		(drill 0.254)
		(layers "F.Cu" "B.Cu")
		(net "GND")
	)
	(via
		(at 329.171046 -224.234248)
		(size 0.4064)
		(drill 0.2032)
		(layers "F.Cu" "B.Cu")
		(net "GND")
	)
	(via
		(at 452.995792 -54.091078)
		(size 0.508)
		(drill 0.254)
		(layers "F.Cu" "B.Cu")
		(net "GND")
	)
	(via
		(at 117.767862 -60.29706)
		(size 0.508)
		(drill 0.254)
		(layers "F.Cu" "B.Cu")
		(net "GND")
	)
	(via
		(at 177.664618 -347.65234)
		(size 0.508)
		(drill 0.254)
		(layers "F.Cu" "B.Cu")
		(net "GND")
	)
	(via
		(at 384.122422 -418.412168)
		(size 0.4064)
		(drill 0.2032)
		(layers "F.Cu" "B.Cu")
		(net "GND")
	)
	(via
		(at 98.344228 -382.85293)
		(size 0.4064)
		(drill 0.2032)
		(layers "F.Cu" "B.Cu")
		(net "GND")
	)
	(via
		(at 79.401924 -410.030168)
		(size 0.4064)
		(drill 0.2032)
		(layers "F.Cu" "B.Cu")
		(net "GND")
	)
	(via
		(at 354.34524 -261.23011)
		(size 0.4826)
		(drill 0.254)
		(layers "F.Cu" "B.Cu")
		(net "GND")
	)
	(via
		(at 245.59387 -291.228526)
		(size 0.508)
		(drill 0.254)
		(layers "F.Cu" "B.Cu")
		(net "GND")
	)
	(via
		(at 233.445558 -288.676334)
		(size 0.508)
		(drill 0.254)
		(layers "F.Cu" "B.Cu")
		(net "GND")
	)
	(via
		(at 146.501866 -410.030168)
		(size 0.4064)
		(drill 0.2032)
		(layers "F.Cu" "B.Cu")
		(net "GND")
	)
	(via
		(at 425.407074 -342.484964)
		(size 0.508)
		(drill 0.254)
		(layers "F.Cu" "B.Cu")
		(net "GND")
	)
	(via
		(at 80.249776 -430.299622)
		(size 0.4572)
		(drill 0.2032)
		(layers "F.Cu" "B.Cu")
		(net "GND")
	)
	(via
		(at 40.770302 -377.00712)
		(size 0.508)
		(drill 0.254)
		(layers "F.Cu" "B.Cu")
		(net "GND")
	)
	(via
		(at 442.5442 -292.535102)
		(size 0.4826)
		(drill 0.254)
		(layers "F.Cu" "B.Cu")
		(net "GND")
	)
	(via
		(at 36.795964 -297.635422)
		(size 0.4826)
		(drill 0.254)
		(layers "F.Cu" "B.Cu")
		(net "GND")
	)
	(via
		(at 116.744496 -373.96293)
		(size 0.508)
		(drill 0.254)
		(layers "F.Cu" "B.Cu")
		(net "GND")
	)
	(via
		(at 183.225694 -330.211684)
		(size 0.508)
		(drill 0.254)
		(layers "F.Cu" "B.Cu")
		(net "GND")
	)
	(via
		(at 398.676368 -74.883264)
		(size 0.508)
		(drill 0.254)
		(layers "F.Cu" "B.Cu")
		(net "GND")
	)
	(via
		(at 41.508934 -363.263434)
		(size 0.508)
		(drill 0.254)
		(layers "F.Cu" "B.Cu")
		(net "GND")
	)
	(via
		(at 292.280086 -265.335004)
		(size 0.4826)
		(drill 0.254)
		(layers "F.Cu" "B.Cu")
		(net "GND")
	)
	(via
		(at 359.740454 -247.45696)
		(size 0.4826)
		(drill 0.254)
		(layers "F.Cu" "B.Cu")
		(net "GND")
	)
	(via
		(at 107.550966 -232.334308)
		(size 0.4064)
		(drill 0.2032)
		(layers "F.Cu" "B.Cu")
		(net "GND")
	)
	(via
		(at 338.101178 -242.864132)
		(size 0.4064)
		(drill 0.2032)
		(layers "F.Cu" "B.Cu")
		(net "GND")
	)
	(via
		(at 412.3817 -170.629072)
		(size 0.508)
		(drill 0.254)
		(layers "F.Cu" "B.Cu")
		(net "GND")
	)
	(via
		(at 416.799522 -4.963414)
		(size 0.508)
		(drill 0.254)
		(layers "F.Cu" "B.Cu")
		(net "GND")
	)
	(via
		(at 346.39123 -277.32609)
		(size 0.4064)
		(drill 0.2032)
		(layers "F.Cu" "B.Cu")
		(net "GND")
	)
	(via
		(at 83.111086 -246.914416)
		(size 0.4064)
		(drill 0.2032)
		(layers "F.Cu" "B.Cu")
		(net "GND")
	)
	(via
		(at 442.5442 -223.6851)
		(size 0.4826)
		(drill 0.254)
		(layers "F.Cu" "B.Cu")
		(net "GND")
	)
	(via
		(at 60.115196 -154.84856)
		(size 0.508)
		(drill 0.254)
		(layers "F.Cu" "B.Cu")
		(net "GND")
	)
	(via
		(at 460.255366 -378.81687)
		(size 0.508)
		(drill 0.254)
		(layers "F.Cu" "B.Cu")
		(net "GND")
	)
	(via
		(at 420.158164 -9.424924)
		(size 0.508)
		(drill 0.254)
		(layers "F.Cu" "B.Cu")
		(net "GND")
	)
	(via
		(at 43.222418 -313.360308)
		(size 0.4826)
		(drill 0.254)
		(layers "F.Cu" "B.Cu")
		(net "GND")
	)
	(via
		(at 121.474738 -291.096192)
		(size 0.4064)
		(drill 0.2032)
		(layers "F.Cu" "B.Cu")
		(net "GND")
	)
	(via
		(at 355.957124 -339.069172)
		(size 0.508)
		(drill 0.254)
		(layers "F.Cu" "B.Cu")
		(net "GND")
	)
	(via
		(at 86.249764 -433.747164)
		(size 0.4572)
		(drill 0.2032)
		(layers "F.Cu" "B.Cu")
		(net "GND")
	)
	(via
		(at 76.812902 -230.170228)
		(size 0.4064)
		(drill 0.2032)
		(layers "F.Cu" "B.Cu")
		(net "GND")
	)
	(via
		(at 115.534694 -231.524302)
		(size 0.4064)
		(drill 0.2032)
		(layers "F.Cu" "B.Cu")
		(net "GND")
	)
	(via
		(at 382.49987 -189.514226)
		(size 0.508)
		(drill 0.254)
		(layers "F.Cu" "B.Cu")
		(net "GND")
	)
	(via
		(at 121.174764 -231.524302)
		(size 0.4064)
		(drill 0.2032)
		(layers "F.Cu" "B.Cu")
		(net "GND")
	)
	(via
		(at 419.379654 -431.921412)
		(size 0.508)
		(drill 0.254)
		(layers "F.Cu" "B.Cu")
		(net "GND")
	)
	(via
		(at 334.249522 -439.651394)
		(size 0.4572)
		(drill 0.2032)
		(layers "F.Cu" "B.Cu")
		(net "GND")
	)
	(via
		(at 26.536396 -296.785284)
		(size 0.4826)
		(drill 0.254)
		(layers "F.Cu" "B.Cu")
		(net "GND")
	)
	(via
		(at 76.584302 -369.03533)
		(size 0.508)
		(drill 0.254)
		(layers "F.Cu" "B.Cu")
		(net "GND")
	)
	(via
		(at 423.930064 -6.598158)
		(size 0.508)
		(drill 0.254)
		(layers "F.Cu" "B.Cu")
		(net "GND")
	)
	(via
		(at 79.760572 -406.370536)
		(size 0.4572)
		(drill 0.254)
		(layers "F.Cu" "B.Cu")
		(net "GND")
	)
	(via
		(at 331.833474 -38.81882)
		(size 0.508)
		(drill 0.254)
		(layers "F.Cu" "B.Cu")
		(net "GND")
	)
	(via
		(at 225.223578 -317.942468)
		(size 0.508)
		(drill 0.254)
		(layers "F.Cu" "B.Cu")
		(net "GND")
	)
	(via
		(at 374.284748 -240.434114)
		(size 0.4064)
		(drill 0.2032)
		(layers "F.Cu" "B.Cu")
		(net "GND")
	)
	(via
		(at 138.564874 -240.434368)
		(size 0.4064)
		(drill 0.2032)
		(layers "F.Cu" "B.Cu")
		(net "GND")
	)
	(via
		(at 179.516024 -214.33536)
		(size 0.4826)
		(drill 0.254)
		(layers "F.Cu" "B.Cu")
		(net "GND")
	)
	(via
		(at 136.98474 -264.366248)
		(size 0.4064)
		(drill 0.2032)
		(layers "F.Cu" "B.Cu")
		(net "GND")
	)
	(via
		(at 183.616092 -248.335292)
		(size 0.4826)
		(drill 0.254)
		(layers "F.Cu" "B.Cu")
		(net "GND")
	)
	(via
		(at 428.840392 -312.935112)
		(size 0.4826)
		(drill 0.254)
		(layers "F.Cu" "B.Cu")
		(net "GND")
	)
	(via
		(at 379.924818 -250.154186)
		(size 0.4064)
		(drill 0.2032)
		(layers "F.Cu" "B.Cu")
		(net "GND")
	)
	(via
		(at 435.000146 -217.73515)
		(size 0.4826)
		(drill 0.254)
		(layers "F.Cu" "B.Cu")
		(net "GND")
	)
	(via
		(at 303.892966 -342.811608)
		(size 0.508)
		(drill 0.254)
		(layers "F.Cu" "B.Cu")
		(net "GND")
	)
	(via
		(at 246.105426 -284.169358)
		(size 0.508)
		(drill 0.254)
		(layers "F.Cu" "B.Cu")
		(net "GND")
	)
	(via
		(at 379.924818 -248.534174)
		(size 0.4064)
		(drill 0.2032)
		(layers "F.Cu" "B.Cu")
		(net "GND")
	)
	(via
		(at 76.812902 -243.130324)
		(size 0.4064)
		(drill 0.2032)
		(layers "F.Cu" "B.Cu")
		(net "GND")
	)
	(via
		(at 396.73403 -419.046152)
		(size 0.4572)
		(drill 0.254)
		(layers "F.Cu" "B.Cu")
		(net "GND")
	)
	(via
		(at 176.072038 -265.335258)
		(size 0.4826)
		(drill 0.254)
		(layers "F.Cu" "B.Cu")
		(net "GND")
	)
	(via
		(at 317.249556 -432.451256)
		(size 0.4572)
		(drill 0.2032)
		(layers "F.Cu" "B.Cu")
		(net "GND")
	)
	(via
		(at 234.41152 -289.552126)
		(size 0.508)
		(drill 0.254)
		(layers "F.Cu" "B.Cu")
		(net "GND")
	)
	(via
		(at 116.228114 -410.664152)
		(size 0.4572)
		(drill 0.254)
		(layers "F.Cu" "B.Cu")
		(net "GND")
	)
	(via
		(at 131.98475 -232.334308)
		(size 0.4064)
		(drill 0.2032)
		(layers "F.Cu" "B.Cu")
		(net "GND")
	)
	(via
		(at 317.918338 -396.710662)
		(size 0.4064)
		(drill 0.2032)
		(layers "F.Cu" "B.Cu")
		(net "GND")
	)
	(via
		(at 78.314804 -407.00452)
		(size 0.4064)
		(drill 0.2032)
		(layers "F.Cu" "B.Cu")
		(net "GND")
	)
	(via
		(at 141.904466 -404.46452)
		(size 0.4064)
		(drill 0.2032)
		(layers "F.Cu" "B.Cu")
		(net "GND")
	)
	(via
		(at 21.70811 -213.485222)
		(size 0.4826)
		(drill 0.254)
		(layers "F.Cu" "B.Cu")
		(net "GND")
	)
	(via
		(at 62.11951 -172.172884)
		(size 0.508)
		(drill 0.254)
		(layers "F.Cu" "B.Cu")
		(net "GND")
	)
	(via
		(at 55.254652 -409.396184)
		(size 0.4572)
		(drill 0.254)
		(layers "F.Cu" "B.Cu")
		(net "GND")
	)
	(via
		(at 147.042886 -282.730448)
		(size 0.4064)
		(drill 0.2032)
		(layers "F.Cu" "B.Cu")
		(net "GND")
	)
	(via
		(at 120.70461 -229.094538)
		(size 0.4064)
		(drill 0.2032)
		(layers "F.Cu" "B.Cu")
		(net "GND")
	)
	(via
		(at 29.203142 -421.69969)
		(size 0.508)
		(drill 0.254)
		(layers "F.Cu" "B.Cu")
		(net "GND")
	)
	(via
		(at 55.328058 -197.335394)
		(size 0.4826)
		(drill 0.254)
		(layers "F.Cu" "B.Cu")
		(net "GND")
	)
	(via
		(at 405.915368 -5.597398)
		(size 0.508)
		(drill 0.254)
		(layers "F.Cu" "B.Cu")
		(net "GND")
	)
	(via
		(at 381.804926 -251.774198)
		(size 0.4064)
		(drill 0.2032)
		(layers "F.Cu" "B.Cu")
		(net "GND")
	)
	(via
		(at 405.650954 -413.480504)
		(size 0.4572)
		(drill 0.254)
		(layers "F.Cu" "B.Cu")
		(net "GND")
	)
	(via
		(at 374.637046 -183.893968)
		(size 0.49022)
		(drill 0.254)
		(layers "F.Cu" "B.Cu")
		(net "GND")
	)
	(via
		(at 189.775846 -295.9354)
		(size 0.4826)
		(drill 0.254)
		(layers "F.Cu" "B.Cu")
		(net "GND")
	)
	(via
		(at 355.791008 -277.32609)
		(size 0.4064)
		(drill 0.2032)
		(layers "F.Cu" "B.Cu")
		(net "GND")
	)
	(via
		(at 311.966356 -381.68453)
		(size 0.508)
		(drill 0.254)
		(layers "F.Cu" "B.Cu")
		(net "GND")
	)
	(via
		(at 15.05585 -389.4201)
		(size 0.49022)
		(drill 0.254)
		(layers "F.Cu" "B.Cu")
		(net "GND")
	)
	(via
		(at 121.174764 -234.764326)
		(size 0.4064)
		(drill 0.2032)
		(layers "F.Cu" "B.Cu")
		(net "GND")
	)
	(via
		(at 183.423814 -357.736648)
		(size 0.508)
		(drill 0.254)
		(layers "F.Cu" "B.Cu")
		(net "GND")
	)
	(via
		(at 29.252164 -318.035432)
		(size 0.4826)
		(drill 0.254)
		(layers "F.Cu" "B.Cu")
		(net "GND")
	)
	(via
		(at 289.564318 -275.535136)
		(size 0.4826)
		(drill 0.254)
		(layers "F.Cu" "B.Cu")
		(net "GND")
	)
	(via
		(at 21.876258 -428.589948)
		(size 0.508)
		(drill 0.254)
		(layers "F.Cu" "B.Cu")
		(net "GND")
	)
	(via
		(at 381.334772 -249.34418)
		(size 0.4064)
		(drill 0.2032)
		(layers "F.Cu" "B.Cu")
		(net "GND")
	)
	(via
		(at 447.761868 -294.660066)
		(size 0.4826)
		(drill 0.254)
		(layers "F.Cu" "B.Cu")
		(net "GND")
	)
	(via
		(at 99.390962 -272.466308)
		(size 0.4064)
		(drill 0.2032)
		(layers "F.Cu" "B.Cu")
		(net "GND")
	)
	(via
		(at 88.281002 -249.344434)
		(size 0.4064)
		(drill 0.2032)
		(layers "F.Cu" "B.Cu")
		(net "GND")
	)
	(via
		(at 277.192232 -251.735082)
		(size 0.4826)
		(drill 0.254)
		(layers "F.Cu" "B.Cu")
		(net "GND")
	)
	(via
		(at 183.616092 -280.635202)
		(size 0.4826)
		(drill 0.254)
		(layers "F.Cu" "B.Cu")
		(net "GND")
	)
	(via
		(at 125.059186 -407.00452)
		(size 0.4064)
		(drill 0.2032)
		(layers "F.Cu" "B.Cu")
		(net "GND")
	)
	(via
		(at 108.097066 -179.321968)
		(size 0.49022)
		(drill 0.254)
		(layers "F.Cu" "B.Cu")
		(net "GND")
	)
	(via
		(at 59.188096 -144.163288)
		(size 0.6604)
		(drill 0.3302)
		(layers "F.Cu" "B.Cu")
		(net "GND")
	)
	(via
		(at 412.08198 -379.22073)
		(size 0.508)
		(drill 0.254)
		(layers "F.Cu" "B.Cu")
		(net "GND")
	)
	(via
		(at 284.736032 -301.034958)
		(size 0.4826)
		(drill 0.254)
		(layers "F.Cu" "B.Cu")
		(net "GND")
	)
	(via
		(at 390.264904 -224.234248)
		(size 0.4064)
		(drill 0.2032)
		(layers "F.Cu" "B.Cu")
		(net "GND")
	)
	(via
		(at 420.877238 -433.986686)
		(size 0.508)
		(drill 0.254)
		(layers "F.Cu" "B.Cu")
		(net "GND")
	)
	(via
		(at 151.541226 -407.00452)
		(size 0.4064)
		(drill 0.2032)
		(layers "F.Cu" "B.Cu")
		(net "GND")
	)
	(via
		(at 135.274812 -228.284532)
		(size 0.4064)
		(drill 0.2032)
		(layers "F.Cu" "B.Cu")
		(net "GND")
	)
	(via
		(at 439.100214 -207.535018)
		(size 0.4826)
		(drill 0.254)
		(layers "F.Cu" "B.Cu")
		(net "GND")
	)
	(via
		(at 362.534708 -236.384084)
		(size 0.4064)
		(drill 0.2032)
		(layers "F.Cu" "B.Cu")
		(net "GND")
	)
	(via
		(at 299.82414 -250.03506)
		(size 0.4826)
		(drill 0.254)
		(layers "F.Cu" "B.Cu")
		(net "GND")
	)
	(via
		(at 422.627806 -312.084974)
		(size 0.4826)
		(drill 0.254)
		(layers "F.Cu" "B.Cu")
		(net "GND")
	)
	(via
		(at 118.184676 -282.18638)
		(size 0.4064)
		(drill 0.2032)
		(layers "F.Cu" "B.Cu")
		(net "GND")
	)
	(via
		(at 380.224792 -274.086066)
		(size 0.4064)
		(drill 0.2032)
		(layers "F.Cu" "B.Cu")
		(net "GND")
	)
	(via
		(at 442.760862 -422.390824)
		(size 0.508)
		(drill 0.254)
		(layers "F.Cu" "B.Cu")
		(net "GND")
	)
	(via
		(at 379.924818 -243.674138)
		(size 0.4064)
		(drill 0.2032)
		(layers "F.Cu" "B.Cu")
		(net "GND")
	)
	(via
		(at 351.03943 -434.857652)
		(size 0.508)
		(drill 0.254)
		(layers "F.Cu" "B.Cu")
		(net "GND")
	)
	(via
		(at 349.272098 -414.72866)
		(size 0.4572)
		(drill 0.254)
		(layers "F.Cu" "B.Cu")
		(net "GND")
	)
	(via
		(at 105.500932 -266.796266)
		(size 0.4064)
		(drill 0.2032)
		(layers "F.Cu" "B.Cu")
		(net "GND")
	)
	(via
		(at 436.117746 -314.210192)
		(size 0.4826)
		(drill 0.254)
		(layers "F.Cu" "B.Cu")
		(net "GND")
	)
	(via
		(at 387.914896 -249.34418)
		(size 0.4064)
		(drill 0.2032)
		(layers "F.Cu" "B.Cu")
		(net "GND")
	)
	(via
		(at 372.404894 -250.154186)
		(size 0.4064)
		(drill 0.2032)
		(layers "F.Cu" "B.Cu")
		(net "GND")
	)
	(via
		(at 334.585564 -149.738588)
		(size 0.508)
		(drill 0.254)
		(layers "F.Cu" "B.Cu")
		(net "GND")
	)
	(via
		(at 394.841222 -412.84652)
		(size 0.4064)
		(drill 0.2032)
		(layers "F.Cu" "B.Cu")
		(net "GND")
	)
	(via
		(at 352.9711 -280.566114)
		(size 0.4064)
		(drill 0.2032)
		(layers "F.Cu" "B.Cu")
		(net "GND")
	)
	(via
		(at 88.281002 -229.90429)
		(size 0.4064)
		(drill 0.2032)
		(layers "F.Cu" "B.Cu")
		(net "GND")
	)
	(via
		(at 427.765718 -10.16508)
		(size 0.508)
		(drill 0.254)
		(layers "F.Cu" "B.Cu")
		(net "GND")
	)
	(via
		(at 357.278432 -325.781924)
		(size 0.508)
		(drill 0.254)
		(layers "F.Cu" "B.Cu")
		(net "GND")
	)
	(via
		(at 361.424728 -267.606018)
		(size 0.4064)
		(drill 0.2032)
		(layers "F.Cu" "B.Cu")
		(net "GND")
	)
	(via
		(at 133.394704 -221.804484)
		(size 0.4064)
		(drill 0.2032)
		(layers "F.Cu" "B.Cu")
		(net "GND")
	)
	(via
		(at 157.220666 -404.46452)
		(size 0.4064)
		(drill 0.2032)
		(layers "F.Cu" "B.Cu")
		(net "GND")
	)
	(via
		(at 431.55616 -226.235006)
		(size 0.4826)
		(drill 0.254)
		(layers "F.Cu" "B.Cu")
		(net "GND")
	)
	(via
		(at 353.003104 -380.54153)
		(size 0.508)
		(drill 0.254)
		(layers "F.Cu" "B.Cu")
		(net "GND")
	)
	(via
		(at 286.570166 -343.472008)
		(size 0.508)
		(drill 0.254)
		(layers "F.Cu" "B.Cu")
		(net "GND")
	)
	(via
		(at 49.71542 -104.75214)
		(size 0.508)
		(drill 0.254)
		(layers "F.Cu" "B.Cu")
		(net "GND")
	)
	(via
		(at 131.98475 -237.194344)
		(size 0.4064)
		(drill 0.2032)
		(layers "F.Cu" "B.Cu")
		(net "GND")
	)
	(via
		(at 366.594898 -289.475926)
		(size 0.4064)
		(drill 0.2032)
		(layers "F.Cu" "B.Cu")
		(net "GND")
	)
	(via
		(at 348.271084 -261.12597)
		(size 0.4064)
		(drill 0.2032)
		(layers "F.Cu" "B.Cu")
		(net "GND")
	)
	(via
		(at 94.417896 -177.6603)
		(size 0.508)
		(drill 0.254)
		(layers "F.Cu" "B.Cu")
		(net "GND")
	)
	(via
		(at 376.634756 -241.24412)
		(size 0.4064)
		(drill 0.2032)
		(layers "F.Cu" "B.Cu")
		(net "GND")
	)
	(via
		(at 366.520222 -44.755816)
		(size 0.508)
		(drill 0.254)
		(layers "F.Cu" "B.Cu")
		(net "GND")
	)
	(via
		(at 446.644268 -198.185024)
		(size 0.4826)
		(drill 0.254)
		(layers "F.Cu" "B.Cu")
		(net "GND")
	)
	(via
		(at 416.468052 -299.33519)
		(size 0.4826)
		(drill 0.254)
		(layers "F.Cu" "B.Cu")
		(net "GND")
	)
	(via
		(at 383.21488 -242.864132)
		(size 0.4064)
		(drill 0.2032)
		(layers "F.Cu" "B.Cu")
		(net "GND")
	)
	(via
		(at 148.717254 -312.302144)
		(size 0.508)
		(drill 0.254)
		(layers "F.Cu" "B.Cu")
		(net "GND")
	)
	(via
		(at 238.252 -332.613)
		(size 0.508)
		(drill 0.254)
		(layers "F.Cu" "B.Cu")
		(net "GND")
	)
	(via
		(at 90.249756 -436.051198)
		(size 0.4572)
		(drill 0.2032)
		(layers "F.Cu" "B.Cu")
		(net "GND")
	)
	(via
		(at 324.509892 -102.724712)
		(size 0.508)
		(drill 0.254)
		(layers "F.Cu" "B.Cu")
		(net "GND")
	)
	(via
		(at 419.889432 -5.597398)
		(size 0.508)
		(drill 0.254)
		(layers "F.Cu" "B.Cu")
		(net "GND")
	)
	(via
		(at 405.650954 -421.586152)
		(size 0.4572)
		(drill 0.254)
		(layers "F.Cu" "B.Cu")
		(net "GND")
	)
	(via
		(at 382.349502 -427.851316)
		(size 0.4572)
		(drill 0.2032)
		(layers "F.Cu" "B.Cu")
		(net "GND")
	)
	(via
		(at 379.754892 -268.416024)
		(size 0.4064)
		(drill 0.2032)
		(layers "F.Cu" "B.Cu")
		(net "GND")
	)
	(via
		(at 176.072038 -251.735336)
		(size 0.4826)
		(drill 0.254)
		(layers "F.Cu" "B.Cu")
		(net "GND")
	)
	(via
		(at 442.5442 -225.385122)
		(size 0.4826)
		(drill 0.254)
		(layers "F.Cu" "B.Cu")
		(net "GND")
	)
	(via
		(at 382.349502 -436.347362)
		(size 0.4572)
		(drill 0.2032)
		(layers "F.Cu" "B.Cu")
		(net "GND")
	)
	(via
		(at 81.687162 -374.62333)
		(size 0.508)
		(drill 0.254)
		(layers "F.Cu" "B.Cu")
		(net "GND")
	)
	(via
		(at 455.305668 -275.960078)
		(size 0.4826)
		(drill 0.254)
		(layers "F.Cu" "B.Cu")
		(net "GND")
	)
	(via
		(at 142.265654 -413.204152)
		(size 0.4572)
		(drill 0.254)
		(layers "F.Cu" "B.Cu")
		(net "GND")
	)
	(via
		(at 402.31441 -4.32943)
		(size 0.508)
		(drill 0.254)
		(layers "F.Cu" "B.Cu")
		(net "GND")
	)
	(via
		(at 83.580986 -242.864386)
		(size 0.4064)
		(drill 0.2032)
		(layers "F.Cu" "B.Cu")
		(net "GND")
	)
	(via
		(at 101.440996 -250.964446)
		(size 0.4064)
		(drill 0.2032)
		(layers "F.Cu" "B.Cu")
		(net "GND")
	)
	(via
		(at 95.076772 -406.370536)
		(size 0.4572)
		(drill 0.254)
		(layers "F.Cu" "B.Cu")
		(net "GND")
	)
	(via
		(at 380.218442 -396.710662)
		(size 0.4064)
		(drill 0.2032)
		(layers "F.Cu" "B.Cu")
		(net "GND")
	)
	(via
		(at 5.478526 -12.542266)
		(size 0.508)
		(drill 0.254)
		(layers "F.Cu" "B.Cu")
		(net "GND")
	)
	(via
		(at 40.23995 -227.085398)
		(size 0.4826)
		(drill 0.254)
		(layers "F.Cu" "B.Cu")
		(net "GND")
	)
	(via
		(at 386.504942 -237.19409)
		(size 0.4064)
		(drill 0.2032)
		(layers "F.Cu" "B.Cu")
		(net "GND")
	)
	(via
		(at 268.263878 -286.585152)
		(size 0.4826)
		(drill 0.254)
		(layers "F.Cu" "B.Cu")
		(net "GND")
	)
	(via
		(at 390.60755 -417.778184)
		(size 0.4572)
		(drill 0.254)
		(layers "F.Cu" "B.Cu")
		(net "GND")
	)
	(via
		(at 382.676654 -414.752536)
		(size 0.4572)
		(drill 0.254)
		(layers "F.Cu" "B.Cu")
		(net "GND")
	)
	(via
		(at 464.065366 -378.05487)
		(size 0.508)
		(drill 0.254)
		(layers "F.Cu" "B.Cu")
		(net "GND")
	)
	(via
		(at 326.060308 -333.048864)
		(size 0.49022)
		(drill 0.254)
		(layers "F.Cu" "B.Cu")
		(net "GND")
	)
	(via
		(at 374.754902 -242.864132)
		(size 0.4064)
		(drill 0.2032)
		(layers "F.Cu" "B.Cu")
		(net "GND")
	)
	(via
		(at 49.168304 -287.43529)
		(size 0.4826)
		(drill 0.254)
		(layers "F.Cu" "B.Cu")
		(net "GND")
	)
	(via
		(at 283.351732 -239.835182)
		(size 0.4826)
		(drill 0.254)
		(layers "F.Cu" "B.Cu")
		(net "GND")
	)
	(via
		(at 330.618592 -384.175)
		(size 0.508)
		(drill 0.254)
		(layers "F.Cu" "B.Cu")
		(net "GND")
	)
	(via
		(at 454.229978 -396.884398)
		(size 0.49022)
		(drill 0.254)
		(layers "F.Cu" "B.Cu")
		(net "GND")
	)
	(via
		(at 264.43051 -304.860198)
		(size 0.4826)
		(drill 0.254)
		(layers "F.Cu" "B.Cu")
		(net "GND")
	)
	(via
		(at 64.050418 -345.555824)
		(size 0.49022)
		(drill 0.254)
		(layers "F.Cu" "B.Cu")
		(net "GND")
	)
	(via
		(at 373.316246 -183.893968)
		(size 0.49022)
		(drill 0.254)
		(layers "F.Cu" "B.Cu")
		(net "GND")
	)
	(via
		(at 364.24489 -277.32609)
		(size 0.4064)
		(drill 0.2032)
		(layers "F.Cu" "B.Cu")
		(net "GND")
	)
	(via
		(at 230.96728 -53.364892)
		(size 0.508)
		(drill 0.254)
		(layers "F.Cu" "B.Cu")
		(net "GND")
	)
	(via
		(at 105.200958 -234.764326)
		(size 0.4064)
		(drill 0.2032)
		(layers "F.Cu" "B.Cu")
		(net "GND")
	)
	(via
		(at 143.56461 -291.906198)
		(size 0.4064)
		(drill 0.2032)
		(layers "F.Cu" "B.Cu")
		(net "GND")
	)
	(via
		(at 345.621102 -252.584204)
		(size 0.4064)
		(drill 0.2032)
		(layers "F.Cu" "B.Cu")
		(net "GND")
	)
	(via
		(at 109.261148 -279.756362)
		(size 0.4064)
		(drill 0.2032)
		(layers "F.Cu" "B.Cu")
		(net "GND")
	)
	(via
		(at 454.188068 -224.534984)
		(size 0.4826)
		(drill 0.254)
		(layers "F.Cu" "B.Cu")
		(net "GND")
	)
	(via
		(at 331.029564 -135.563102)
		(size 0.508)
		(drill 0.254)
		(layers "F.Cu" "B.Cu")
		(net "GND")
	)
	(via
		(at 191.160146 -272.98523)
		(size 0.4826)
		(drill 0.254)
		(layers "F.Cu" "B.Cu")
		(net "GND")
	)
	(via
		(at 283.580586 -193.99631)
		(size 0.4826)
		(drill 0.254)
		(layers "F.Cu" "B.Cu")
		(net "GND")
	)
	(via
		(at 99.561142 -247.724422)
		(size 0.4064)
		(drill 0.2032)
		(layers "F.Cu" "B.Cu")
		(net "GND")
	)
	(via
		(at 419.912038 -227.085144)
		(size 0.4826)
		(drill 0.254)
		(layers "F.Cu" "B.Cu")
		(net "GND")
	)
	(via
		(at 467.5378 -228.143054)
		(size 0.508)
		(drill 0.254)
		(layers "F.Cu" "B.Cu")
		(net "GND")
	)
	(via
		(at 118.042436 -439.551572)
		(size 0.508)
		(drill 0.254)
		(layers "F.Cu" "B.Cu")
		(net "GND")
	)
	(via
		(at 299.82414 -282.33497)
		(size 0.4826)
		(drill 0.254)
		(layers "F.Cu" "B.Cu")
		(net "GND")
	)
	(via
		(at 109.900974 -241.244374)
		(size 0.4064)
		(drill 0.2032)
		(layers "F.Cu" "B.Cu")
		(net "GND")
	)
	(via
		(at 138.864848 -288.666174)
		(size 0.4064)
		(drill 0.2032)
		(layers "F.Cu" "B.Cu")
		(net "GND")
	)
	(via
		(at 126.34468 -251.774452)
		(size 0.4064)
		(drill 0.2032)
		(layers "F.Cu" "B.Cu")
		(net "GND")
	)
	(via
		(at 387.271514 -412.212536)
		(size 0.4572)
		(drill 0.254)
		(layers "F.Cu" "B.Cu")
		(net "GND")
	)
	(via
		(at 104.090978 -288.666174)
		(size 0.4064)
		(drill 0.2032)
		(layers "F.Cu" "B.Cu")
		(net "GND")
	)
	(via
		(at 50.386996 -407.638504)
		(size 0.4572)
		(drill 0.254)
		(layers "F.Cu" "B.Cu")
		(net "GND")
	)
	(via
		(at 140.444728 -245.294404)
		(size 0.4064)
		(drill 0.2032)
		(layers "F.Cu" "B.Cu")
		(net "GND")
	)
	(via
		(at 124.87529 -53.994558)
		(size 0.508)
		(drill 0.254)
		(layers "F.Cu" "B.Cu")
		(net "GND")
	)
	(via
		(at 413.319468 -364.781592)
		(size 0.508)
		(drill 0.254)
		(layers "F.Cu" "B.Cu")
		(net "GND")
	)
	(via
		(at 137.62482 -222.61449)
		(size 0.4064)
		(drill 0.2032)
		(layers "F.Cu" "B.Cu")
		(net "GND")
	)
	(via
		(at 80.249776 -427.851316)
		(size 0.4572)
		(drill 0.2032)
		(layers "F.Cu" "B.Cu")
		(net "GND")
	)
	(via
		(at 198.7042 -271.285208)
		(size 0.4826)
		(drill 0.254)
		(layers "F.Cu" "B.Cu")
		(net "GND")
	)
	(via
		(at 248.1961 -267.381736)
		(size 0.508)
		(drill 0.254)
		(layers "F.Cu" "B.Cu")
		(net "GND")
	)
	(via
		(at 364.884716 -250.154186)
		(size 0.4064)
		(drill 0.2032)
		(layers "F.Cu" "B.Cu")
		(net "GND")
	)
	(via
		(at 336.521044 -279.756108)
		(size 0.4064)
		(drill 0.2032)
		(layers "F.Cu" "B.Cu")
		(net "GND")
	)
	(via
		(at 266.70381 -193.10731)
		(size 0.4826)
		(drill 0.254)
		(layers "F.Cu" "B.Cu")
		(net "GND")
	)
	(via
		(at 283.351732 -230.485188)
		(size 0.4826)
		(drill 0.254)
		(layers "F.Cu" "B.Cu")
		(net "GND")
	)
	(via
		(at 125.362462 -384.617722)
		(size 0.4064)
		(drill 0.2032)
		(layers "F.Cu" "B.Cu")
		(net "GND")
	)
	(via
		(at 325.052944 -285.970218)
		(size 0.4064)
		(drill 0.2032)
		(layers "F.Cu" "B.Cu")
		(net "GND")
	)
	(via
		(at 129.739898 -409.396184)
		(size 0.4572)
		(drill 0.254)
		(layers "F.Cu" "B.Cu")
		(net "GND")
	)
	(via
		(at 363.944916 -238.814102)
		(size 0.4064)
		(drill 0.2032)
		(layers "F.Cu" "B.Cu")
		(net "GND")
	)
	(via
		(at 218.789758 -87.545926)
		(size 0.508)
		(drill 0.254)
		(layers "F.Cu" "B.Cu")
		(net "GND")
	)
	(via
		(at 140.349732 -433.747164)
		(size 0.4572)
		(drill 0.2032)
		(layers "F.Cu" "B.Cu")
		(net "GND")
	)
	(via
		(at 39.12235 -276.81047)
		(size 0.4826)
		(drill 0.254)
		(layers "F.Cu" "B.Cu")
		(net "GND")
	)
	(via
		(at 355.588062 -261.32282)
		(size 0.4826)
		(drill 0.254)
		(layers "F.Cu" "B.Cu")
		(net "GND")
	)
	(via
		(at 204.241146 -338.79409)
		(size 0.508)
		(drill 0.254)
		(layers "F.Cu" "B.Cu")
		(net "GND")
	)
	(via
		(at 90.381328 -75.65517)
		(size 0.508)
		(drill 0.254)
		(layers "F.Cu" "B.Cu")
		(net "GND")
	)
	(via
		(at 467.5378 -311.963054)
		(size 0.508)
		(drill 0.254)
		(layers "F.Cu" "B.Cu")
		(net "GND")
	)
	(via
		(at 86.230968 -293.52621)
		(size 0.4064)
		(drill 0.2032)
		(layers "F.Cu" "B.Cu")
		(net "GND")
	)
	(via
		(at 424.012106 -288.285174)
		(size 0.4826)
		(drill 0.254)
		(layers "F.Cu" "B.Cu")
		(net "GND")
	)
	(via
		(at 381.058674 -183.14289)
		(size 0.49022)
		(drill 0.254)
		(layers "F.Cu" "B.Cu")
		(net "GND")
	)
	(via
		(at 104.866948 -387.7945)
		(size 0.508)
		(drill 0.254)
		(layers "F.Cu" "B.Cu")
		(net "GND")
	)
	(via
		(at 411.777434 -413.480504)
		(size 0.4572)
		(drill 0.254)
		(layers "F.Cu" "B.Cu")
		(net "GND")
	)
	(via
		(at 343.541858 -162.122612)
		(size 0.508)
		(drill 0.254)
		(layers "F.Cu" "B.Cu")
		(net "GND")
	)
	(via
		(at 268.263878 -293.384986)
		(size 0.4826)
		(drill 0.254)
		(layers "F.Cu" "B.Cu")
		(net "GND")
	)
	(via
		(at 303.268126 -216.035128)
		(size 0.4826)
		(drill 0.254)
		(layers "F.Cu" "B.Cu")
		(net "GND")
	)
	(via
		(at 89.52103 -294.336216)
		(size 0.4064)
		(drill 0.2032)
		(layers "F.Cu" "B.Cu")
		(net "GND")
	)
	(via
		(at 432.67376 -304.01006)
		(size 0.4826)
		(drill 0.254)
		(layers "F.Cu" "B.Cu")
		(net "GND")
	)
	(via
		(at 268.263878 -199.885046)
		(size 0.4826)
		(drill 0.254)
		(layers "F.Cu" "B.Cu")
		(net "GND")
	)
	(via
		(at 89.99093 -262.746236)
		(size 0.4064)
		(drill 0.2032)
		(layers "F.Cu" "B.Cu")
		(net "GND")
	)
	(via
		(at 79.821024 -225.044508)
		(size 0.4064)
		(drill 0.2032)
		(layers "F.Cu" "B.Cu")
		(net "GND")
	)
	(via
		(at 460.267812 -406.45715)
		(size 0.508)
		(drill 0.254)
		(layers "F.Cu" "B.Cu")
		(net "GND")
	)
	(via
		(at 88.24976 -438.651396)
		(size 0.4572)
		(drill 0.2032)
		(layers "F.Cu" "B.Cu")
		(net "GND")
	)
	(via
		(at 304.855118 -413.480504)
		(size 0.4572)
		(drill 0.254)
		(layers "F.Cu" "B.Cu")
		(net "GND")
	)
	(via
		(at 86.701122 -270.03629)
		(size 0.4064)
		(drill 0.2032)
		(layers "F.Cu" "B.Cu")
		(net "GND")
	)
	(via
		(at 78.228952 -411.936184)
		(size 0.4572)
		(drill 0.254)
		(layers "F.Cu" "B.Cu")
		(net "GND")
	)
	(via
		(at 90.461084 -292.716204)
		(size 0.4064)
		(drill 0.2032)
		(layers "F.Cu" "B.Cu")
		(net "GND")
	)
	(via
		(at 176.072038 -253.435358)
		(size 0.4826)
		(drill 0.254)
		(layers "F.Cu" "B.Cu")
		(net "GND")
	)
	(via
		(at 368.944906 -265.986006)
		(size 0.4064)
		(drill 0.2032)
		(layers "F.Cu" "B.Cu")
		(net "GND")
	)
	(via
		(at 355.491034 -233.954066)
		(size 0.4064)
		(drill 0.2032)
		(layers "F.Cu" "B.Cu")
		(net "GND")
	)
	(via
		(at 99.861116 -270.03629)
		(size 0.4064)
		(drill 0.2032)
		(layers "F.Cu" "B.Cu")
		(net "GND")
	)
	(via
		(at 305.983894 -218.585034)
		(size 0.4826)
		(drill 0.254)
		(layers "F.Cu" "B.Cu")
		(net "GND")
	)
	(via
		(at 337.930998 -277.32609)
		(size 0.4064)
		(drill 0.2032)
		(layers "F.Cu" "B.Cu")
		(net "GND")
	)
	(via
		(at 354.34524 -258.379976)
		(size 0.4826)
		(drill 0.254)
		(layers "F.Cu" "B.Cu")
		(net "GND")
	)
	(via
		(at 367.704878 -243.674138)
		(size 0.4064)
		(drill 0.2032)
		(layers "F.Cu" "B.Cu")
		(net "GND")
	)
	(via
		(at 81.530952 -293.52621)
		(size 0.4064)
		(drill 0.2032)
		(layers "F.Cu" "B.Cu")
		(net "GND")
	)
	(via
		(at 430.17186 -312.084974)
		(size 0.4826)
		(drill 0.254)
		(layers "F.Cu" "B.Cu")
		(net "GND")
	)
	(via
		(at 113.954814 -268.416278)
		(size 0.4064)
		(drill 0.2032)
		(layers "F.Cu" "B.Cu")
		(net "GND")
	)
	(via
		(at 379.972062 -418.412168)
		(size 0.4064)
		(drill 0.2032)
		(layers "F.Cu" "B.Cu")
		(net "GND")
	)
	(via
		(at 430.664366 -392.479022)
		(size 0.508)
		(drill 0.254)
		(layers "F.Cu" "B.Cu")
		(net "GND")
	)
	(via
		(at 424.998642 -56.097678)
		(size 0.508)
		(drill 0.254)
		(layers "F.Cu" "B.Cu")
		(net "GND")
	)
	(via
		(at 143.349726 -438.651396)
		(size 0.4572)
		(drill 0.2032)
		(layers "F.Cu" "B.Cu")
		(net "GND")
	)
	(via
		(at 216.38133 -40.675814)
		(size 0.508)
		(drill 0.254)
		(layers "F.Cu" "B.Cu")
		(net "GND")
	)
	(via
		(at 334.249522 -434.899562)
		(size 0.4572)
		(drill 0.2032)
		(layers "F.Cu" "B.Cu")
		(net "GND")
	)
	(via
		(at 83.944206 -393.877038)
		(size 0.4572)
		(drill 0.254)
		(layers "F.Cu" "B.Cu")
		(net "GND")
	)
	(via
		(at 425.129706 -294.660066)
		(size 0.4826)
		(drill 0.254)
		(layers "F.Cu" "B.Cu")
		(net "GND")
	)
	(via
		(at 350.321118 -229.904036)
		(size 0.4064)
		(drill 0.2032)
		(layers "F.Cu" "B.Cu")
		(net "GND")
	)
	(via
		(at 58.401712 -0.762254)
		(size 0.508)
		(drill 0.254)
		(layers "F.Cu" "B.Cu")
		(net "GND")
	)
	(via
		(at 333.701136 -268.416024)
		(size 0.4064)
		(drill 0.2032)
		(layers "F.Cu" "B.Cu")
		(net "GND")
	)
	(via
		(at 326.351138 -225.85426)
		(size 0.4064)
		(drill 0.2032)
		(layers "F.Cu" "B.Cu")
		(net "GND")
	)
	(via
		(at 79.082646 -154.846528)
		(size 0.508)
		(drill 0.254)
		(layers "F.Cu" "B.Cu")
		(net "GND")
	)
	(via
		(at 83.580986 -228.284532)
		(size 0.4064)
		(drill 0.2032)
		(layers "F.Cu" "B.Cu")
		(net "GND")
	)
	(via
		(at 45.866558 -344.781886)
		(size 0.49022)
		(drill 0.254)
		(layers "F.Cu" "B.Cu")
		(net "GND")
	)
	(via
		(at 109.900974 -236.384338)
		(size 0.4064)
		(drill 0.2032)
		(layers "F.Cu" "B.Cu")
		(net "GND")
	)
	(via
		(at 315.24956 -430.299622)
		(size 0.4572)
		(drill 0.2032)
		(layers "F.Cu" "B.Cu")
		(net "GND")
	)
	(via
		(at 308.1782 -394.831062)
		(size 0.4064)
		(drill 0.2032)
		(layers "F.Cu" "B.Cu")
		(net "GND")
	)
	(via
		(at 140.744702 -267.606272)
		(size 0.4064)
		(drill 0.2032)
		(layers "F.Cu" "B.Cu")
		(net "GND")
	)
	(via
		(at 25.748234 -12.37488)
		(size 0.508)
		(drill 0.254)
		(layers "F.Cu" "B.Cu")
		(net "GND")
	)
	(via
		(at 407.349706 -426.69968)
		(size 0.4572)
		(drill 0.2032)
		(layers "F.Cu" "B.Cu")
		(net "GND")
	)
	(via
		(at 415.024316 -4.32943)
		(size 0.508)
		(drill 0.254)
		(layers "F.Cu" "B.Cu")
		(net "GND")
	)
	(via
		(at 313.416442 -402.309838)
		(size 0.4572)
		(drill 0.254)
		(layers "F.Cu" "B.Cu")
		(net "GND")
	)
	(via
		(at 405.34971 -432.451256)
		(size 0.4572)
		(drill 0.2032)
		(layers "F.Cu" "B.Cu")
		(net "GND")
	)
	(via
		(at 84.082636 -407.638504)
		(size 0.4572)
		(drill 0.254)
		(layers "F.Cu" "B.Cu")
		(net "GND")
	)
	(via
		(at 297.430444 -383.68986)
		(size 0.508)
		(drill 0.254)
		(layers "F.Cu" "B.Cu")
		(net "GND")
	)
	(via
		(at 62.43701 -170.877484)
		(size 0.508)
		(drill 0.254)
		(layers "F.Cu" "B.Cu")
		(net "GND")
	)
	(via
		(at 64.171576 -403.830536)
		(size 0.4572)
		(drill 0.254)
		(layers "F.Cu" "B.Cu")
		(net "GND")
	)
	(via
		(at 273.092164 -244.08511)
		(size 0.4826)
		(drill 0.254)
		(layers "F.Cu" "B.Cu")
		(net "GND")
	)
	(via
		(at 393.225528 -391.834116)
		(size 0.508)
		(drill 0.254)
		(layers "F.Cu" "B.Cu")
		(net "GND")
	)
	(via
		(at 25.152096 -217.735404)
		(size 0.4826)
		(drill 0.254)
		(layers "F.Cu" "B.Cu")
		(net "GND")
	)
	(via
		(at 366.275874 -178.92141)
		(size 0.49022)
		(drill 0.254)
		(layers "F.Cu" "B.Cu")
		(net "GND")
	)
	(via
		(at 367.704878 -246.914162)
		(size 0.4064)
		(drill 0.2032)
		(layers "F.Cu" "B.Cu")
		(net "GND")
	)
	(via
		(at 17.608042 -252.58522)
		(size 0.4826)
		(drill 0.254)
		(layers "F.Cu" "B.Cu")
		(net "GND")
	)
	(via
		(at 289.564318 -312.935112)
		(size 0.4826)
		(drill 0.254)
		(layers "F.Cu" "B.Cu")
		(net "GND")
	)
	(via
		(at 36.795964 -253.435358)
		(size 0.4826)
		(drill 0.254)
		(layers "F.Cu" "B.Cu")
		(net "GND")
	)
	(via
		(at 29.589476 -4.963414)
		(size 0.508)
		(drill 0.254)
		(layers "F.Cu" "B.Cu")
		(net "GND")
	)
	(via
		(at 384.624834 -230.714296)
		(size 0.4064)
		(drill 0.2032)
		(layers "F.Cu" "B.Cu")
		(net "GND")
	)
	(via
		(at 335.487518 -420.318184)
		(size 0.4572)
		(drill 0.254)
		(layers "F.Cu" "B.Cu")
		(net "GND")
	)
	(via
		(at 391.974832 -271.656048)
		(size 0.4064)
		(drill 0.2032)
		(layers "F.Cu" "B.Cu")
		(net "GND")
	)
	(via
		(at 13.43787 -386.92709)
		(size 0.508)
		(drill 0.254)
		(layers "F.Cu" "B.Cu")
		(net "GND")
	)
	(via
		(at 417.368482 -360.538014)
		(size 0.508)
		(drill 0.254)
		(layers "F.Cu" "B.Cu")
		(net "GND")
	)
	(via
		(at 380.224792 -262.745982)
		(size 0.4064)
		(drill 0.2032)
		(layers "F.Cu" "B.Cu")
		(net "GND")
	)
	(via
		(at 130.07848 -386.449062)
		(size 0.4064)
		(drill 0.2032)
		(layers "F.Cu" "B.Cu")
		(net "GND")
	)
	(via
		(at 210.59521 -38.169342)
		(size 0.508)
		(drill 0.254)
		(layers "F.Cu" "B.Cu")
		(net "GND")
	)
	(via
		(at 44.310554 -347.287088)
		(size 0.49022)
		(drill 0.254)
		(layers "F.Cu" "B.Cu")
		(net "GND")
	)
	(via
		(at 90.461084 -284.616398)
		(size 0.4064)
		(drill 0.2032)
		(layers "F.Cu" "B.Cu")
		(net "GND")
	)
	(via
		(at 312.786014 -420.318184)
		(size 0.4572)
		(drill 0.254)
		(layers "F.Cu" "B.Cu")
		(net "GND")
	)
	(via
		(at 330.543154 -441.227718)
		(size 0.508)
		(drill 0.254)
		(layers "F.Cu" "B.Cu")
		(net "GND")
	)
	(via
		(at 77.500734 -184.492392)
		(size 0.508)
		(drill 0.254)
		(layers "F.Cu" "B.Cu")
		(net "GND")
	)
	(via
		(at 140.744702 -282.18638)
		(size 0.4064)
		(drill 0.2032)
		(layers "F.Cu" "B.Cu")
		(net "GND")
	)
	(via
		(at 311.016396 -400.212814)
		(size 0.4064)
		(drill 0.2032)
		(layers "F.Cu" "B.Cu")
		(net "GND")
	)
	(via
		(at 122.962416 -384.617722)
		(size 0.4064)
		(drill 0.2032)
		(layers "F.Cu" "B.Cu")
		(net "GND")
	)
	(via
		(at 145.444718 -262.746236)
		(size 0.4064)
		(drill 0.2032)
		(layers "F.Cu" "B.Cu")
		(net "GND")
	)
	(via
		(at 394.982954 -290.83)
		(size 0.4064)
		(drill 0.2032)
		(layers "F.Cu" "B.Cu")
		(net "GND")
	)
	(via
		(at 405.34971 -433.747164)
		(size 0.4572)
		(drill 0.2032)
		(layers "F.Cu" "B.Cu")
		(net "GND")
	)
	(via
		(at 386.349494 -432.747166)
		(size 0.4572)
		(drill 0.2032)
		(layers "F.Cu" "B.Cu")
		(net "GND")
	)
	(via
		(at 427.456092 -244.08511)
		(size 0.4826)
		(drill 0.254)
		(layers "F.Cu" "B.Cu")
		(net "GND")
	)
	(via
		(at 446.644268 -268.735048)
		(size 0.4826)
		(drill 0.254)
		(layers "F.Cu" "B.Cu")
		(net "GND")
	)
	(via
		(at 327.249536 -435.0512)
		(size 0.4572)
		(drill 0.2032)
		(layers "F.Cu" "B.Cu")
		(net "GND")
	)
	(via
		(at 151.455374 -413.204152)
		(size 0.4572)
		(drill 0.254)
		(layers "F.Cu" "B.Cu")
		(net "GND")
	)
	(via
		(at 101.74097 -261.93623)
		(size 0.4064)
		(drill 0.2032)
		(layers "F.Cu" "B.Cu")
		(net "GND")
	)
	(via
		(at 6.936486 -97.517204)
		(size 0.508)
		(drill 0.254)
		(layers "F.Cu" "B.Cu")
		(net "GND")
	)
	(via
		(at 464.537806 -417.722812)
		(size 0.508)
		(drill 0.254)
		(layers "F.Cu" "B.Cu")
		(net "GND")
	)
	(via
		(at 332.931008 -224.234248)
		(size 0.4064)
		(drill 0.2032)
		(layers "F.Cu" "B.Cu")
		(net "GND")
	)
	(via
		(at 29.252164 -297.635422)
		(size 0.4826)
		(drill 0.254)
		(layers "F.Cu" "B.Cu")
		(net "GND")
	)
	(via
		(at 467.5378 -373.431054)
		(size 0.508)
		(drill 0.254)
		(layers "F.Cu" "B.Cu")
		(net "GND")
	)
	(via
		(at 394.68298 -233.409998)
		(size 0.4064)
		(drill 0.2032)
		(layers "F.Cu" "B.Cu")
		(net "GND")
	)
	(via
		(at 20.017232 -386.801106)
		(size 0.508)
		(drill 0.254)
		(layers "F.Cu" "B.Cu")
		(net "GND")
	)
	(via
		(at 58.043826 -221.135194)
		(size 0.4826)
		(drill 0.254)
		(layers "F.Cu" "B.Cu")
		(net "GND")
	)
	(via
		(at 194.604132 -250.885198)
		(size 0.4826)
		(drill 0.254)
		(layers "F.Cu" "B.Cu")
		(net "GND")
	)
	(via
		(at 26.626566 -38.402514)
		(size 0.508)
		(drill 0.254)
		(layers "F.Cu" "B.Cu")
		(net "GND")
	)
	(via
		(at 402.37664 -141.979142)
		(size 0.49022)
		(drill 0.254)
		(layers "F.Cu" "B.Cu")
		(net "GND")
	)
	(via
		(at 91.55811 -182.109872)
		(size 0.49022)
		(drill 0.254)
		(layers "F.Cu" "B.Cu")
		(net "GND")
	)
	(via
		(at 144.643856 -117.38356)
		(size 0.508)
		(drill 0.254)
		(layers "F.Cu" "B.Cu")
		(net "GND")
	)
	(via
		(at 388.384796 -232.334054)
		(size 0.4064)
		(drill 0.2032)
		(layers "F.Cu" "B.Cu")
		(net "GND")
	)
	(via
		(at 53.53812 -6.091174)
		(size 0.508)
		(drill 0.254)
		(layers "F.Cu" "B.Cu")
		(net "GND")
	)
	(via
		(at 55.328058 -301.88535)
		(size 0.4826)
		(drill 0.254)
		(layers "F.Cu" "B.Cu")
		(net "GND")
	)
	(via
		(at 385.03733 -189.514226)
		(size 0.508)
		(drill 0.254)
		(layers "F.Cu" "B.Cu")
		(net "GND")
	)
	(via
		(at 421.444166 -391.23493)
		(size 0.4064)
		(drill 0.2032)
		(layers "F.Cu" "B.Cu")
		(net "GND")
	)
	(via
		(at 265.54811 -206.685134)
		(size 0.4826)
		(drill 0.254)
		(layers "F.Cu" "B.Cu")
		(net "GND")
	)
	(via
		(at 95.301562 -373.30253)
		(size 0.508)
		(drill 0.254)
		(layers "F.Cu" "B.Cu")
		(net "GND")
	)
	(via
		(at 386.349494 -435.0512)
		(size 0.4572)
		(drill 0.2032)
		(layers "F.Cu" "B.Cu")
		(net "GND")
	)
	(via
		(at 392.349482 -426.54728)
		(size 0.4572)
		(drill 0.2032)
		(layers "F.Cu" "B.Cu")
		(net "GND")
	)
	(via
		(at 386.541518 -185.327798)
		(size 0.508)
		(drill 0.254)
		(layers "F.Cu" "B.Cu")
		(net "GND")
	)
	(via
		(at 176.072038 -243.235226)
		(size 0.4826)
		(drill 0.254)
		(layers "F.Cu" "B.Cu")
		(net "GND")
	)
	(via
		(at 370.524786 -222.614236)
		(size 0.4064)
		(drill 0.2032)
		(layers "F.Cu" "B.Cu")
		(net "GND")
	)
	(via
		(at 167.143684 -312.085228)
		(size 0.4826)
		(drill 0.254)
		(layers "F.Cu" "B.Cu")
		(net "GND")
	)
	(via
		(at 118.65483 -278.13635)
		(size 0.4064)
		(drill 0.2032)
		(layers "F.Cu" "B.Cu")
		(net "GND")
	)
	(via
		(at 399.359882 -76.661264)
		(size 0.508)
		(drill 0.254)
		(layers "F.Cu" "B.Cu")
		(net "GND")
	)
	(via
		(at 304.28692 -428.82058)
		(size 0.508)
		(drill 0.254)
		(layers "F.Cu" "B.Cu")
		(net "GND")
	)
	(via
		(at 144.034764 -266.796266)
		(size 0.4064)
		(drill 0.2032)
		(layers "F.Cu" "B.Cu")
		(net "GND")
	)
	(via
		(at 133.694678 -271.656302)
		(size 0.4064)
		(drill 0.2032)
		(layers "F.Cu" "B.Cu")
		(net "GND")
	)
	(via
		(at 331.821028 -282.996132)
		(size 0.4064)
		(drill 0.2032)
		(layers "F.Cu" "B.Cu")
		(net "GND")
	)
	(via
		(at 25.152096 -290.835334)
		(size 0.4826)
		(drill 0.254)
		(layers "F.Cu" "B.Cu")
		(net "GND")
	)
	(via
		(at 349.211138 -280.566114)
		(size 0.4064)
		(drill 0.2032)
		(layers "F.Cu" "B.Cu")
		(net "GND")
	)
	(via
		(at 379.924818 -224.234248)
		(size 0.4064)
		(drill 0.2032)
		(layers "F.Cu" "B.Cu")
		(net "GND")
	)
	(via
		(at 403.444202 -391.23493)
		(size 0.4064)
		(drill 0.2032)
		(layers "F.Cu" "B.Cu")
		(net "GND")
	)
	(via
		(at 427.456092 -245.785132)
		(size 0.4826)
		(drill 0.254)
		(layers "F.Cu" "B.Cu")
		(net "GND")
	)
	(via
		(at 334.811116 -245.29415)
		(size 0.4064)
		(drill 0.2032)
		(layers "F.Cu" "B.Cu")
		(net "GND")
	)
	(via
		(at 29.252164 -310.385206)
		(size 0.4826)
		(drill 0.254)
		(layers "F.Cu" "B.Cu")
		(net "GND")
	)
	(via
		(at 157.080458 -11.031728)
		(size 0.508)
		(drill 0.254)
		(layers "F.Cu" "B.Cu")
		(net "GND")
	)
	(via
		(at 393.384786 -293.525956)
		(size 0.4064)
		(drill 0.2032)
		(layers "F.Cu" "B.Cu")
		(net "GND")
	)
	(via
		(at 145.914618 -294.336216)
		(size 0.4064)
		(drill 0.2032)
		(layers "F.Cu" "B.Cu")
		(net "GND")
	)
	(via
		(at 126.34468 -235.574332)
		(size 0.4064)
		(drill 0.2032)
		(layers "F.Cu" "B.Cu")
		(net "GND")
	)
	(via
		(at 413.36214 -43.690032)
		(size 0.508)
		(drill 0.254)
		(layers "F.Cu" "B.Cu")
		(net "GND")
	)
	(via
		(at 352.671126 -243.674138)
		(size 0.4064)
		(drill 0.2032)
		(layers "F.Cu" "B.Cu")
		(net "GND")
	)
	(via
		(at 113.687098 -394.352018)
		(size 0.508)
		(drill 0.254)
		(layers "F.Cu" "B.Cu")
		(net "GND")
	)
	(via
		(at 145.144744 -229.094538)
		(size 0.4064)
		(drill 0.2032)
		(layers "F.Cu" "B.Cu")
		(net "GND")
	)
	(via
		(at 248.121932 -420.67099)
		(size 0.508)
		(drill 0.254)
		(layers "F.Cu" "B.Cu")
		(net "GND")
	)
	(via
		(at 446.519554 -54.972458)
		(size 0.508)
		(drill 0.254)
		(layers "F.Cu" "B.Cu")
		(net "GND")
	)
	(via
		(at 328.338942 -396.1765)
		(size 0.508)
		(drill 0.254)
		(layers "F.Cu" "B.Cu")
		(net "GND")
	)
	(via
		(at 355.791008 -293.525956)
		(size 0.4064)
		(drill 0.2032)
		(layers "F.Cu" "B.Cu")
		(net "GND")
	)
	(via
		(at 191.92621 -349.381572)
		(size 0.49022)
		(drill 0.254)
		(layers "F.Cu" "B.Cu")
		(net "GND")
	)
	(via
		(at 265.54811 -217.73515)
		(size 0.4826)
		(drill 0.254)
		(layers "F.Cu" "B.Cu")
		(net "GND")
	)
	(via
		(at 354.660708 -336.029808)
		(size 0.508)
		(drill 0.254)
		(layers "F.Cu" "B.Cu")
		(net "GND")
	)
	(via
		(at 334.996028 -391.290556)
		(size 0.4064)
		(drill 0.2032)
		(layers "F.Cu" "B.Cu")
		(net "GND")
	)
	(via
		(at 344.511122 -287.045908)
		(size 0.4064)
		(drill 0.2032)
		(layers "F.Cu" "B.Cu")
		(net "GND")
	)
	(via
		(at 123.524772 -237.194344)
		(size 0.4064)
		(drill 0.2032)
		(layers "F.Cu" "B.Cu")
		(net "GND")
	)
	(via
		(at 190.370206 -351.886774)
		(size 0.49022)
		(drill 0.254)
		(layers "F.Cu" "B.Cu")
		(net "GND")
	)
	(via
		(at 180.836316 -331.532484)
		(size 0.508)
		(drill 0.254)
		(layers "F.Cu" "B.Cu")
		(net "GND")
	)
	(via
		(at 372.316502 -412.84652)
		(size 0.4064)
		(drill 0.2032)
		(layers "F.Cu" "B.Cu")
		(net "GND")
	)
	(via
		(at 307.368194 -316.335156)
		(size 0.4826)
		(drill 0.254)
		(layers "F.Cu" "B.Cu")
		(net "GND")
	)
	(via
		(at 326.351138 -255.014222)
		(size 0.4064)
		(drill 0.2032)
		(layers "F.Cu" "B.Cu")
		(net "GND")
	)
	(via
		(at 279.518364 -211.360004)
		(size 0.4826)
		(drill 0.254)
		(layers "F.Cu" "B.Cu")
		(net "GND")
	)
	(via
		(at 110.497874 -261.323074)
		(size 0.4826)
		(drill 0.254)
		(layers "F.Cu" "B.Cu")
		(net "GND")
	)
	(via
		(at 113.636298 -416.926014)
		(size 0.508)
		(drill 0.254)
		(layers "F.Cu" "B.Cu")
		(net "GND")
	)
	(via
		(at 113.184686 -245.294404)
		(size 0.4064)
		(drill 0.2032)
		(layers "F.Cu" "B.Cu")
		(net "GND")
	)
	(via
		(at 296.059606 -144.555972)
		(size 0.508)
		(drill 0.254)
		(layers "F.Cu" "B.Cu")
		(net "GND")
	)
	(via
		(at 307.368194 -224.534984)
		(size 0.4826)
		(drill 0.254)
		(layers "F.Cu" "B.Cu")
		(net "GND")
	)
	(via
		(at 132.349748 -439.651394)
		(size 0.4572)
		(drill 0.2032)
		(layers "F.Cu" "B.Cu")
		(net "GND")
	)
	(via
		(at 282.40101 -344.77706)
		(size 0.49022)
		(drill 0.254)
		(layers "F.Cu" "B.Cu")
		(net "GND")
	)
	(via
		(at 80.120998 -286.23641)
		(size 0.4064)
		(drill 0.2032)
		(layers "F.Cu" "B.Cu")
		(net "GND")
	)
	(via
		(at 384.624834 -233.954066)
		(size 0.4064)
		(drill 0.2032)
		(layers "F.Cu" "B.Cu")
		(net "GND")
	)
	(via
		(at 99.612704 -332.704186)
		(size 0.508)
		(drill 0.254)
		(layers "F.Cu" "B.Cu")
		(net "GND")
	)
	(via
		(at 115.955318 -413.204152)
		(size 0.4572)
		(drill 0.254)
		(layers "F.Cu" "B.Cu")
		(net "GND")
	)
	(via
		(at 228.518212 -152.664922)
		(size 0.508)
		(drill 0.254)
		(layers "F.Cu" "B.Cu")
		(net "GND")
	)
	(via
		(at 406.406858 -168.027858)
		(size 0.49022)
		(drill 0.254)
		(layers "F.Cu" "B.Cu")
		(net "GND")
	)
	(via
		(at 59.428126 -204.135228)
		(size 0.4826)
		(drill 0.254)
		(layers "F.Cu" "B.Cu")
		(net "GND")
	)
	(via
		(at 350.795082 -258.830064)
		(size 0.4826)
		(drill 0.254)
		(layers "F.Cu" "B.Cu")
		(net "GND")
	)
	(via
		(at 123.054618 -254.20447)
		(size 0.4064)
		(drill 0.2032)
		(layers "F.Cu" "B.Cu")
		(net "GND")
	)
	(via
		(at 363.944916 -246.914162)
		(size 0.4064)
		(drill 0.2032)
		(layers "F.Cu" "B.Cu")
		(net "GND")
	)
	(via
		(at 408.714194 -421.586152)
		(size 0.4572)
		(drill 0.254)
		(layers "F.Cu" "B.Cu")
		(net "GND")
	)
	(via
		(at 373.55145 -182.177944)
		(size 0.49022)
		(drill 0.254)
		(layers "F.Cu" "B.Cu")
		(net "GND")
	)
	(via
		(at 138.567922 -221.50959)
		(size 0.4064)
		(drill 0.2032)
		(layers "F.Cu" "B.Cu")
		(net "GND")
	)
	(via
		(at 364.53064 -389.25246)
		(size 0.508)
		(drill 0.254)
		(layers "F.Cu" "B.Cu")
		(net "GND")
	)
	(via
		(at 344.644472 -21.672296)
		(size 0.508)
		(drill 0.254)
		(layers "F.Cu" "B.Cu")
		(net "GND")
	)
	(via
		(at 333.230982 -278.946102)
		(size 0.4064)
		(drill 0.2032)
		(layers "F.Cu" "B.Cu")
		(net "GND")
	)
	(via
		(at 86.401148 -238.00435)
		(size 0.4064)
		(drill 0.2032)
		(layers "F.Cu" "B.Cu")
		(net "GND")
	)
	(via
		(at 361.424728 -288.66592)
		(size 0.4064)
		(drill 0.2032)
		(layers "F.Cu" "B.Cu")
		(net "GND")
	)
	(via
		(at 107.550966 -251.774452)
		(size 0.4064)
		(drill 0.2032)
		(layers "F.Cu" "B.Cu")
		(net "GND")
	)
	(via
		(at 183.616092 -213.485222)
		(size 0.4826)
		(drill 0.254)
		(layers "F.Cu" "B.Cu")
		(net "GND")
	)
	(via
		(at 83.41106 -264.366248)
		(size 0.4064)
		(drill 0.2032)
		(layers "F.Cu" "B.Cu")
		(net "GND")
	)
	(via
		(at 131.418584 -388.328662)
		(size 0.4064)
		(drill 0.2032)
		(layers "F.Cu" "B.Cu")
		(net "GND")
	)
	(via
		(at 147.349718 -432.747166)
		(size 0.4572)
		(drill 0.2032)
		(layers "F.Cu" "B.Cu")
		(net "GND")
	)
	(via
		(at 422.627806 -221.13494)
		(size 0.4826)
		(drill 0.254)
		(layers "F.Cu" "B.Cu")
		(net "GND")
	)
	(via
		(at 298.70654 -238.560102)
		(size 0.4826)
		(drill 0.254)
		(layers "F.Cu" "B.Cu")
		(net "GND")
	)
	(via
		(at 135.939022 -388.892542)
		(size 0.508)
		(drill 0.254)
		(layers "F.Cu" "B.Cu")
		(net "GND")
	)
	(via
		(at 135.274812 -229.90429)
		(size 0.4064)
		(drill 0.2032)
		(layers "F.Cu" "B.Cu")
		(net "GND")
	)
	(via
		(at 255.132332 -422.13149)
		(size 0.508)
		(drill 0.254)
		(layers "F.Cu" "B.Cu")
		(net "GND")
	)
	(via
		(at 202.147932 -273.835368)
		(size 0.4826)
		(drill 0.254)
		(layers "F.Cu" "B.Cu")
		(net "GND")
	)
	(via
		(at 141.718792 -377.00712)
		(size 0.508)
		(drill 0.254)
		(layers "F.Cu" "B.Cu")
		(net "GND")
	)
	(via
		(at 82.997294 -328.111612)
		(size 0.508)
		(drill 0.254)
		(layers "F.Cu" "B.Cu")
		(net "GND")
	)
	(via
		(at 310.981598 -413.480504)
		(size 0.4572)
		(drill 0.254)
		(layers "F.Cu" "B.Cu")
		(net "GND")
	)
	(via
		(at 372.744492 -382.34493)
		(size 0.508)
		(drill 0.254)
		(layers "F.Cu" "B.Cu")
		(net "GND")
	)
	(via
		(at 55.016654 -393.877038)
		(size 0.4572)
		(drill 0.254)
		(layers "F.Cu" "B.Cu")
		(net "GND")
	)
	(via
		(at 446.668906 -22.136862)
		(size 0.508)
		(drill 0.254)
		(layers "F.Cu" "B.Cu")
		(net "GND")
	)
	(via
		(at 446.107566 -378.81687)
		(size 0.508)
		(drill 0.254)
		(layers "F.Cu" "B.Cu")
		(net "GND")
	)
	(via
		(at 371.764814 -277.32609)
		(size 0.4064)
		(drill 0.2032)
		(layers "F.Cu" "B.Cu")
		(net "GND")
	)
	(via
		(at 328.231246 -240.434114)
		(size 0.4064)
		(drill 0.2032)
		(layers "F.Cu" "B.Cu")
		(net "GND")
	)
	(via
		(at 450.088 -273.835114)
		(size 0.4826)
		(drill 0.254)
		(layers "F.Cu" "B.Cu")
		(net "GND")
	)
	(via
		(at 366.124744 -282.186126)
		(size 0.4064)
		(drill 0.2032)
		(layers "F.Cu" "B.Cu")
		(net "GND")
	)
	(via
		(at 241.579146 -160.580324)
		(size 0.508)
		(drill 0.254)
		(layers "F.Cu" "B.Cu")
		(net "GND")
	)
	(via
		(at 449.987924 -58.150252)
		(size 0.6604)
		(drill 0.3302)
		(layers "F.Cu" "B.Cu")
		(net "GND")
	)
	(via
		(at 81.019396 -409.396184)
		(size 0.4572)
		(drill 0.254)
		(layers "F.Cu" "B.Cu")
		(net "GND")
	)
	(via
		(at 461.689196 -47.929546)
		(size 0.508)
		(drill 0.254)
		(layers "F.Cu" "B.Cu")
		(net "GND")
	)
	(via
		(at 97.040954 -282.996386)
		(size 0.4064)
		(drill 0.2032)
		(layers "F.Cu" "B.Cu")
		(net "GND")
	)
	(via
		(at 129.83718 -57.13222)
		(size 0.508)
		(drill 0.254)
		(layers "F.Cu" "B.Cu")
		(net "GND")
	)
	(via
		(at 49.647094 -370.83873)
		(size 0.508)
		(drill 0.254)
		(layers "F.Cu" "B.Cu")
		(net "GND")
	)
	(via
		(at 140.744702 -270.846296)
		(size 0.4064)
		(drill 0.2032)
		(layers "F.Cu" "B.Cu")
		(net "GND")
	)
	(via
		(at 378.344938 -277.32609)
		(size 0.4064)
		(drill 0.2032)
		(layers "F.Cu" "B.Cu")
		(net "GND")
	)
	(via
		(at 36.795964 -226.23526)
		(size 0.4826)
		(drill 0.254)
		(layers "F.Cu" "B.Cu")
		(net "GND")
	)
	(via
		(at 58.043826 -286.585406)
		(size 0.4826)
		(drill 0.254)
		(layers "F.Cu" "B.Cu")
		(net "GND")
	)
	(via
		(at 130.104642 -243.674392)
		(size 0.4064)
		(drill 0.2032)
		(layers "F.Cu" "B.Cu")
		(net "GND")
	)
	(via
		(at 359.144824 -387.703568)
		(size 0.508)
		(drill 0.254)
		(layers "F.Cu" "B.Cu")
		(net "GND")
	)
	(via
		(at 101.27107 -293.52621)
		(size 0.4064)
		(drill 0.2032)
		(layers "F.Cu" "B.Cu")
		(net "GND")
	)
	(via
		(at 126.949454 -411.936184)
		(size 0.4572)
		(drill 0.254)
		(layers "F.Cu" "B.Cu")
		(net "GND")
	)
	(via
		(at 349.211138 -270.846042)
		(size 0.4064)
		(drill 0.2032)
		(layers "F.Cu" "B.Cu")
		(net "GND")
	)
	(via
		(at 95.1611 -266.796266)
		(size 0.4064)
		(drill 0.2032)
		(layers "F.Cu" "B.Cu")
		(net "GND")
	)
	(via
		(at 137.717276 -380.535688)
		(size 0.508)
		(drill 0.254)
		(layers "F.Cu" "B.Cu")
		(net "GND")
	)
	(via
		(at 312.454036 -379.22073)
		(size 0.508)
		(drill 0.254)
		(layers "F.Cu" "B.Cu")
		(net "GND")
	)
	(via
		(at 414.788858 -161.779458)
		(size 0.49022)
		(drill 0.254)
		(layers "F.Cu" "B.Cu")
		(net "GND")
	)
	(via
		(at 385.094734 -233.14406)
		(size 0.4064)
		(drill 0.2032)
		(layers "F.Cu" "B.Cu")
		(net "GND")
	)
	(via
		(at 320.097658 -103.410512)
		(size 0.508)
		(drill 0.254)
		(layers "F.Cu" "B.Cu")
		(net "GND")
	)
	(via
		(at 317.380874 -419.046152)
		(size 0.4572)
		(drill 0.254)
		(layers "F.Cu" "B.Cu")
		(net "GND")
	)
	(via
		(at 51.50993 -19.13636)
		(size 0.508)
		(drill 0.254)
		(layers "F.Cu" "B.Cu")
		(net "GND")
	)
	(via
		(at 315.24956 -438.651396)
		(size 0.4572)
		(drill 0.2032)
		(layers "F.Cu" "B.Cu")
		(net "GND")
	)
	(via
		(at 444.440056 -395.306042)
		(size 0.49022)
		(drill 0.254)
		(layers "F.Cu" "B.Cu")
		(net "GND")
	)
	(via
		(at 337.930998 -274.086066)
		(size 0.4064)
		(drill 0.2032)
		(layers "F.Cu" "B.Cu")
		(net "GND")
	)
	(via
		(at 173.454314 -18.451068)
		(size 0.508)
		(drill 0.254)
		(layers "F.Cu" "B.Cu")
		(net "GND")
	)
	(via
		(at 8.949182 -412.291784)
		(size 0.508)
		(drill 0.254)
		(layers "F.Cu" "B.Cu")
		(net "GND")
	)
	(via
		(at 141.214856 -294.336216)
		(size 0.4064)
		(drill 0.2032)
		(layers "F.Cu" "B.Cu")
		(net "GND")
	)
	(via
		(at 349.272098 -416.020504)
		(size 0.4572)
		(drill 0.254)
		(layers "F.Cu" "B.Cu")
		(net "GND")
	)
	(via
		(at 123.946666 -166.342568)
		(size 0.49022)
		(drill 0.254)
		(layers "F.Cu" "B.Cu")
		(net "GND")
	)
	(via
		(at 328.636884 -333.052928)
		(size 0.49022)
		(drill 0.254)
		(layers "F.Cu" "B.Cu")
		(net "GND")
	)
	(via
		(at 85.090762 -369.69573)
		(size 0.508)
		(drill 0.254)
		(layers "F.Cu" "B.Cu")
		(net "GND")
	)
	(via
		(at 326.351138 -230.714296)
		(size 0.4064)
		(drill 0.2032)
		(layers "F.Cu" "B.Cu")
		(net "GND")
	)
	(via
		(at 116.116354 -393.902438)
		(size 0.4572)
		(drill 0.254)
		(layers "F.Cu" "B.Cu")
		(net "GND")
	)
	(via
		(at 168.242996 -393.335002)
		(size 0.508)
		(drill 0.254)
		(layers "F.Cu" "B.Cu")
		(net "GND")
	)
	(via
		(at 177.664618 -346.99194)
		(size 0.508)
		(drill 0.254)
		(layers "F.Cu" "B.Cu")
		(net "GND")
	)
	(via
		(at 134.349744 -435.0512)
		(size 0.4572)
		(drill 0.2032)
		(layers "F.Cu" "B.Cu")
		(net "GND")
	)
	(via
		(at 85.290914 -282.18638)
		(size 0.4064)
		(drill 0.2032)
		(layers "F.Cu" "B.Cu")
		(net "GND")
	)
	(via
		(at 315.849254 -412.212536)
		(size 0.4572)
		(drill 0.254)
		(layers "F.Cu" "B.Cu")
		(net "GND")
	)
	(via
		(at 173.35627 -210.085432)
		(size 0.4826)
		(drill 0.254)
		(layers "F.Cu" "B.Cu")
		(net "GND")
	)
	(via
		(at 280.296366 -339.799168)
		(size 0.508)
		(drill 0.254)
		(layers "F.Cu" "B.Cu")
		(net "GND")
	)
	(via
		(at 413.450024 -18.247868)
		(size 0.508)
		(drill 0.254)
		(layers "F.Cu" "B.Cu")
		(net "GND")
	)
	(via
		(at 275.807932 -211.784946)
		(size 0.4826)
		(drill 0.254)
		(layers "F.Cu" "B.Cu")
		(net "GND")
	)
	(via
		(at 182.231792 -314.635388)
		(size 0.4826)
		(drill 0.254)
		(layers "F.Cu" "B.Cu")
		(net "GND")
	)
	(via
		(at 284.736032 -207.535018)
		(size 0.4826)
		(drill 0.254)
		(layers "F.Cu" "B.Cu")
		(net "GND")
	)
	(via
		(at 347.801184 -266.796012)
		(size 0.4064)
		(drill 0.2032)
		(layers "F.Cu" "B.Cu")
		(net "GND")
	)
	(via
		(at 30.569662 -418.239448)
		(size 0.508)
		(drill 0.254)
		(layers "F.Cu" "B.Cu")
		(net "GND")
	)
	(via
		(at 119.018558 -411.936184)
		(size 0.4572)
		(drill 0.254)
		(layers "F.Cu" "B.Cu")
		(net "GND")
	)
	(via
		(at 402.284692 -6.598158)
		(size 0.508)
		(drill 0.254)
		(layers "F.Cu" "B.Cu")
		(net "GND")
	)
	(via
		(at 97.981008 -265.176254)
		(size 0.4064)
		(drill 0.2032)
		(layers "F.Cu" "B.Cu")
		(net "GND")
	)
	(via
		(at 32.695896 -318.885316)
		(size 0.4826)
		(drill 0.254)
		(layers "F.Cu" "B.Cu")
		(net "GND")
	)
	(via
		(at 75.45451 -175.637444)
		(size 0.49022)
		(drill 0.254)
		(layers "F.Cu" "B.Cu")
		(net "GND")
	)
	(via
		(at 374.0785 -394.831062)
		(size 0.4064)
		(drill 0.2032)
		(layers "F.Cu" "B.Cu")
		(net "GND")
	)
	(via
		(at 59.935364 -407.00452)
		(size 0.4064)
		(drill 0.2032)
		(layers "F.Cu" "B.Cu")
		(net "GND")
	)
	(via
		(at 327.249536 -426.69968)
		(size 0.4572)
		(drill 0.2032)
		(layers "F.Cu" "B.Cu")
		(net "GND")
	)
	(via
		(at 111.165894 -385.58216)
		(size 0.508)
		(drill 0.254)
		(layers "F.Cu" "B.Cu")
		(net "GND")
	)
	(via
		(at 68.615306 -393.335002)
		(size 0.508)
		(drill 0.254)
		(layers "F.Cu" "B.Cu")
		(net "GND")
	)
	(via
		(at 355.321108 -266.796012)
		(size 0.4064)
		(drill 0.2032)
		(layers "F.Cu" "B.Cu")
		(net "GND")
	)
	(via
		(at 187.060078 -216.035382)
		(size 0.4826)
		(drill 0.254)
		(layers "F.Cu" "B.Cu")
		(net "GND")
	)
	(via
		(at 82.265266 -184.683146)
		(size 0.49022)
		(drill 0.254)
		(layers "F.Cu" "B.Cu")
		(net "GND")
	)
	(via
		(at 155.669234 -317.115952)
		(size 0.508)
		(drill 0.254)
		(layers "F.Cu" "B.Cu")
		(net "GND")
	)
	(via
		(at 130.104642 -240.434368)
		(size 0.4064)
		(drill 0.2032)
		(layers "F.Cu" "B.Cu")
		(net "GND")
	)
	(via
		(at 377.874784 -295.955974)
		(size 0.4064)
		(drill 0.2032)
		(layers "F.Cu" "B.Cu")
		(net "GND")
	)
	(via
		(at 393.084812 -240.434114)
		(size 0.4064)
		(drill 0.2032)
		(layers "F.Cu" "B.Cu")
		(net "GND")
	)
	(via
		(at 121.653046 -14.00429)
		(size 0.508)
		(drill 0.254)
		(layers "F.Cu" "B.Cu")
		(net "GND")
	)
	(via
		(at 50.978562 -386.449062)
		(size 0.4064)
		(drill 0.2032)
		(layers "F.Cu" "B.Cu")
		(net "GND")
	)
	(via
		(at 13.044932 -418.520118)
		(size 0.508)
		(drill 0.254)
		(layers "F.Cu" "B.Cu")
		(net "GND")
	)
	(via
		(at 423.663364 -349.175578)
		(size 0.49022)
		(drill 0.254)
		(layers "F.Cu" "B.Cu")
		(net "GND")
	)
	(via
		(at 322.061586 -418.412168)
		(size 0.4064)
		(drill 0.2032)
		(layers "F.Cu" "B.Cu")
		(net "GND")
	)
	(via
		(at 25.745694 -7.215124)
		(size 0.508)
		(drill 0.254)
		(layers "F.Cu" "B.Cu")
		(net "GND")
	)
	(via
		(at 198.25462 -332.805786)
		(size 0.508)
		(drill 0.254)
		(layers "F.Cu" "B.Cu")
		(net "GND")
	)
	(via
		(at 122.584718 -235.574332)
		(size 0.4064)
		(drill 0.2032)
		(layers "F.Cu" "B.Cu")
		(net "GND")
	)
	(via
		(at 347.54947 -332.69936)
		(size 0.508)
		(drill 0.254)
		(layers "F.Cu" "B.Cu")
		(net "GND")
	)
	(via
		(at 20.794472 -383.86639)
		(size 0.508)
		(drill 0.254)
		(layers "F.Cu" "B.Cu")
		(net "GND")
	)
	(via
		(at 85.290914 -262.746236)
		(size 0.4064)
		(drill 0.2032)
		(layers "F.Cu" "B.Cu")
		(net "GND")
	)
	(via
		(at 439.100214 -250.03506)
		(size 0.4826)
		(drill 0.254)
		(layers "F.Cu" "B.Cu")
		(net "GND")
	)
	(via
		(at 325.052944 -292.450012)
		(size 0.4064)
		(drill 0.2032)
		(layers "F.Cu" "B.Cu")
		(net "GND")
	)
	(via
		(at 40.954706 -415.581338)
		(size 0.4572)
		(drill 0.254)
		(layers "F.Cu" "B.Cu")
		(net "GND")
	)
	(via
		(at 374.584722 -274.086066)
		(size 0.4064)
		(drill 0.2032)
		(layers "F.Cu" "B.Cu")
		(net "GND")
	)
	(via
		(at 364.24489 -290.285932)
		(size 0.4064)
		(drill 0.2032)
		(layers "F.Cu" "B.Cu")
		(net "GND")
	)
	(via
		(at 373.344694 -237.19409)
		(size 0.4064)
		(drill 0.2032)
		(layers "F.Cu" "B.Cu")
		(net "GND")
	)
	(via
		(at 24.034496 -239.410494)
		(size 0.4826)
		(drill 0.254)
		(layers "F.Cu" "B.Cu")
		(net "GND")
	)
	(via
		(at 444.329566 -425.438824)
		(size 0.508)
		(drill 0.254)
		(layers "F.Cu" "B.Cu")
		(net "GND")
	)
	(via
		(at 106.91114 -288.666174)
		(size 0.4064)
		(drill 0.2032)
		(layers "F.Cu" "B.Cu")
		(net "GND")
	)
	(via
		(at 123.316492 -393.902438)
		(size 0.4572)
		(drill 0.254)
		(layers "F.Cu" "B.Cu")
		(net "GND")
	)
	(via
		(at 349.851218 -224.234248)
		(size 0.4064)
		(drill 0.2032)
		(layers "F.Cu" "B.Cu")
		(net "GND")
	)
	(via
		(at 100.46589 -12.542266)
		(size 0.508)
		(drill 0.254)
		(layers "F.Cu" "B.Cu")
		(net "GND")
	)
	(via
		(at 145.444718 -282.18638)
		(size 0.4064)
		(drill 0.2032)
		(layers "F.Cu" "B.Cu")
		(net "GND")
	)
	(via
		(at 349.544894 -421.586152)
		(size 0.4572)
		(drill 0.254)
		(layers "F.Cu" "B.Cu")
		(net "GND")
	)
	(via
		(at 179.516024 -269.58544)
		(size 0.4826)
		(drill 0.254)
		(layers "F.Cu" "B.Cu")
		(net "GND")
	)
	(via
		(at 265.54811 -234.735116)
		(size 0.4826)
		(drill 0.254)
		(layers "F.Cu" "B.Cu")
		(net "GND")
	)
	(via
		(at 303.390808 -398.542002)
		(size 0.4064)
		(drill 0.2032)
		(layers "F.Cu" "B.Cu")
		(net "GND")
	)
	(via
		(at 84.355432 -413.204152)
		(size 0.4572)
		(drill 0.254)
		(layers "F.Cu" "B.Cu")
		(net "GND")
	)
	(via
		(at 443.779656 -396.09522)
		(size 0.49022)
		(drill 0.254)
		(layers "F.Cu" "B.Cu")
		(net "GND")
	)
	(via
		(at 399.524474 -420.318184)
		(size 0.4572)
		(drill 0.254)
		(layers "F.Cu" "B.Cu")
		(net "GND")
	)
	(via
		(at 78.180946 -355.795326)
		(size 0.508)
		(drill 0.254)
		(layers "F.Cu" "B.Cu")
		(net "GND")
	)
	(via
		(at 52.616608 -393.927838)
		(size 0.4572)
		(drill 0.254)
		(layers "F.Cu" "B.Cu")
		(net "GND")
	)
	(via
		(at 58.310526 -275.960332)
		(size 0.4826)
		(drill 0.254)
		(layers "F.Cu" "B.Cu")
		(net "GND")
	)
	(via
		(at 147.042886 -276.2504)
		(size 0.4064)
		(drill 0.2032)
		(layers "F.Cu" "B.Cu")
		(net "GND")
	)
	(via
		(at 369.884706 -282.186126)
		(size 0.4064)
		(drill 0.2032)
		(layers "F.Cu" "B.Cu")
		(net "GND")
	)
	(via
		(at 246.105426 -285.286958)
		(size 0.508)
		(drill 0.254)
		(layers "F.Cu" "B.Cu")
		(net "GND")
	)
	(via
		(at 442.297566 -376.53087)
		(size 0.508)
		(drill 0.254)
		(layers "F.Cu" "B.Cu")
		(net "GND")
	)
	(via
		(at 349.381064 -254.204216)
		(size 0.4064)
		(drill 0.2032)
		(layers "F.Cu" "B.Cu")
		(net "GND")
	)
	(via
		(at 338.744052 -402.309838)
		(size 0.4572)
		(drill 0.254)
		(layers "F.Cu" "B.Cu")
		(net "GND")
	)
	(via
		(at 365.18469 -285.42615)
		(size 0.4064)
		(drill 0.2032)
		(layers "F.Cu" "B.Cu")
		(net "GND")
	)
	(via
		(at 108.321094 -286.23641)
		(size 0.4064)
		(drill 0.2032)
		(layers "F.Cu" "B.Cu")
		(net "GND")
	)
	(via
		(at 312.216292 -402.284438)
		(size 0.4572)
		(drill 0.254)
		(layers "F.Cu" "B.Cu")
		(net "GND")
	)
	(via
		(at 98.187002 -71.21398)
		(size 0.508)
		(drill 0.254)
		(layers "F.Cu" "B.Cu")
		(net "GND")
	)
	(via
		(at 347.50121 -250.964192)
		(size 0.4064)
		(drill 0.2032)
		(layers "F.Cu" "B.Cu")
		(net "GND")
	)
	(via
		(at 383.514854 -282.996132)
		(size 0.4064)
		(drill 0.2032)
		(layers "F.Cu" "B.Cu")
		(net "GND")
	)
	(via
		(at 147.344892 -24.495506)
		(size 0.508)
		(drill 0.254)
		(layers "F.Cu" "B.Cu")
		(net "GND")
	)
	(via
		(at 255.947926 -68.296536)
		(size 0.508)
		(drill 0.254)
		(layers "F.Cu" "B.Cu")
		(net "GND")
	)
	(via
		(at 91.871038 -290.286186)
		(size 0.4064)
		(drill 0.2032)
		(layers "F.Cu" "B.Cu")
		(net "GND")
	)
	(via
		(at 130.662172 -36.873434)
		(size 0.508)
		(drill 0.254)
		(layers "F.Cu" "B.Cu")
		(net "GND")
	)
	(via
		(at 277.192232 -316.335156)
		(size 0.4826)
		(drill 0.254)
		(layers "F.Cu" "B.Cu")
		(net "GND")
	)
	(via
		(at 347.97111 -253.39421)
		(size 0.4064)
		(drill 0.2032)
		(layers "F.Cu" "B.Cu")
		(net "GND")
	)
	(via
		(at 351.091246 -277.32609)
		(size 0.4064)
		(drill 0.2032)
		(layers "F.Cu" "B.Cu")
		(net "GND")
	)
	(via
		(at 386.804916 -278.946102)
		(size 0.4064)
		(drill 0.2032)
		(layers "F.Cu" "B.Cu")
		(net "GND")
	)
	(via
		(at 50.766472 -201.16038)
		(size 0.4826)
		(drill 0.254)
		(layers "F.Cu" "B.Cu")
		(net "GND")
	)
	(via
		(at 144.034764 -289.47618)
		(size 0.4064)
		(drill 0.2032)
		(layers "F.Cu" "B.Cu")
		(net "GND")
	)
	(via
		(at 325.399908 -333.048864)
		(size 0.49022)
		(drill 0.254)
		(layers "F.Cu" "B.Cu")
		(net "GND")
	)
	(via
		(at 66.177414 -369.69573)
		(size 0.508)
		(drill 0.254)
		(layers "F.Cu" "B.Cu")
		(net "GND")
	)
	(via
		(at 345.943936 -391.23493)
		(size 0.4064)
		(drill 0.2032)
		(layers "F.Cu" "B.Cu")
		(net "GND")
	)
	(via
		(at 42.955718 -239.835436)
		(size 0.4826)
		(drill 0.254)
		(layers "F.Cu" "B.Cu")
		(net "GND")
	)
	(via
		(at 178.289458 -43.800014)
		(size 0.508)
		(drill 0.254)
		(layers "F.Cu" "B.Cu")
		(net "GND")
	)
	(via
		(at 168.527984 -232.18521)
		(size 0.4826)
		(drill 0.254)
		(layers "F.Cu" "B.Cu")
		(net "GND")
	)
	(via
		(at 306.250594 -313.360054)
		(size 0.4826)
		(drill 0.254)
		(layers "F.Cu" "B.Cu")
		(net "GND")
	)
	(via
		(at 286.570166 -342.811608)
		(size 0.508)
		(drill 0.254)
		(layers "F.Cu" "B.Cu")
		(net "GND")
	)
	(via
		(at 422.373044 -398.542002)
		(size 0.4064)
		(drill 0.2032)
		(layers "F.Cu" "B.Cu")
		(net "GND")
	)
	(via
		(at 378.891292 -398.542002)
		(size 0.4064)
		(drill 0.2032)
		(layers "F.Cu" "B.Cu")
		(net "GND")
	)
	(via
		(at 228.029516 -293.654226)
		(size 0.508)
		(drill 0.254)
		(layers "F.Cu" "B.Cu")
		(net "GND")
	)
	(via
		(at 415.083752 -274.684998)
		(size 0.4826)
		(drill 0.254)
		(layers "F.Cu" "B.Cu")
		(net "GND")
	)
	(via
		(at 56.538114 -17.613122)
		(size 0.508)
		(drill 0.254)
		(layers "F.Cu" "B.Cu")
		(net "GND")
	)
	(via
		(at 32.128714 -344.137234)
		(size 0.508)
		(drill 0.254)
		(layers "F.Cu" "B.Cu")
		(net "GND")
	)
	(via
		(at 91.919044 -390.160002)
		(size 0.4064)
		(drill 0.2032)
		(layers "F.Cu" "B.Cu")
		(net "GND")
	)
	(via
		(at 407.45537 -421.586152)
		(size 0.4572)
		(drill 0.254)
		(layers "F.Cu" "B.Cu")
		(net "GND")
	)
	(via
		(at 173.35627 -284.885384)
		(size 0.4826)
		(drill 0.254)
		(layers "F.Cu" "B.Cu")
		(net "GND")
	)
	(via
		(at 372.491 -423.164)
		(size 0.508)
		(drill 0.254)
		(layers "F.Cu" "B.Cu")
		(net "GND")
	)
	(via
		(at 310.590946 -398.542002)
		(size 0.4064)
		(drill 0.2032)
		(layers "F.Cu" "B.Cu")
		(net "GND")
	)
	(via
		(at 298.70654 -219.860114)
		(size 0.4826)
		(drill 0.254)
		(layers "F.Cu" "B.Cu")
		(net "GND")
	)
	(via
		(at 421.00627 -394.831062)
		(size 0.4064)
		(drill 0.2032)
		(layers "F.Cu" "B.Cu")
		(net "GND")
	)
	(via
		(at 450.088 -262.785098)
		(size 0.4826)
		(drill 0.254)
		(layers "F.Cu" "B.Cu")
		(net "GND")
	)
	(via
		(at 467.5378 -189.027054)
		(size 0.508)
		(drill 0.254)
		(layers "F.Cu" "B.Cu")
		(net "GND")
	)
	(via
		(at 399.885662 -420.952168)
		(size 0.4064)
		(drill 0.2032)
		(layers "F.Cu" "B.Cu")
		(net "GND")
	)
	(via
		(at 93.450918 -229.094538)
		(size 0.4064)
		(drill 0.2032)
		(layers "F.Cu" "B.Cu")
		(net "GND")
	)
	(via
		(at 282.826206 -347.282262)
		(size 0.49022)
		(drill 0.254)
		(layers "F.Cu" "B.Cu")
		(net "GND")
	)
	(via
		(at 170.905424 -378.836428)
		(size 0.508)
		(drill 0.254)
		(layers "F.Cu" "B.Cu")
		(net "GND")
	)
	(via
		(at 389.79475 -246.104156)
		(size 0.4064)
		(drill 0.2032)
		(layers "F.Cu" "B.Cu")
		(net "GND")
	)
	(via
		(at 133.683756 -386.449062)
		(size 0.4064)
		(drill 0.2032)
		(layers "F.Cu" "B.Cu")
		(net "GND")
	)
	(via
		(at 63.24981 -432.747166)
		(size 0.4572)
		(drill 0.2032)
		(layers "F.Cu" "B.Cu")
		(net "GND")
	)
	(via
		(at 341.86114 -249.34418)
		(size 0.4064)
		(drill 0.2032)
		(layers "F.Cu" "B.Cu")
		(net "GND")
	)
	(via
		(at 449.373752 -392.143234)
		(size 0.508)
		(drill 0.254)
		(layers "F.Cu" "B.Cu")
		(net "GND")
	)
	(via
		(at 29.348176 -12.37488)
		(size 0.508)
		(drill 0.254)
		(layers "F.Cu" "B.Cu")
		(net "GND")
	)
	(via
		(at 431.55616 -243.234972)
		(size 0.4826)
		(drill 0.254)
		(layers "F.Cu" "B.Cu")
		(net "GND")
	)
	(via
		(at 136.98474 -287.046162)
		(size 0.4064)
		(drill 0.2032)
		(layers "F.Cu" "B.Cu")
		(net "GND")
	)
	(via
		(at 51.884072 -318.035432)
		(size 0.4826)
		(drill 0.254)
		(layers "F.Cu" "B.Cu")
		(net "GND")
	)
	(via
		(at 13.31087 -384.044444)
		(size 0.508)
		(drill 0.254)
		(layers "F.Cu" "B.Cu")
		(net "GND")
	)
	(via
		(at 120.461786 -404.46452)
		(size 0.4064)
		(drill 0.2032)
		(layers "F.Cu" "B.Cu")
		(net "GND")
	)
	(via
		(at 341.719154 -441.227718)
		(size 0.508)
		(drill 0.254)
		(layers "F.Cu" "B.Cu")
		(net "GND")
	)
	(via
		(at 327.761092 -221.80423)
		(size 0.4064)
		(drill 0.2032)
		(layers "F.Cu" "B.Cu")
		(net "GND")
	)
	(via
		(at 64.963294 -369.69573)
		(size 0.508)
		(drill 0.254)
		(layers "F.Cu" "B.Cu")
		(net "GND")
	)
	(via
		(at 427.759876 -19.771106)
		(size 0.508)
		(drill 0.254)
		(layers "F.Cu" "B.Cu")
		(net "GND")
	)
	(via
		(at 315.518292 -396.710662)
		(size 0.4064)
		(drill 0.2032)
		(layers "F.Cu" "B.Cu")
		(net "GND")
	)
	(via
		(at 299.82414 -265.335004)
		(size 0.4826)
		(drill 0.254)
		(layers "F.Cu" "B.Cu")
		(net "GND")
	)
	(via
		(at 388.34949 -436.051198)
		(size 0.4572)
		(drill 0.2032)
		(layers "F.Cu" "B.Cu")
		(net "GND")
	)
	(via
		(at 63.117222 -173.839124)
		(size 0.6604)
		(drill 0.3302)
		(layers "F.Cu" "B.Cu")
		(net "GND")
	)
	(via
		(at 104.465882 -380.535688)
		(size 0.508)
		(drill 0.254)
		(layers "F.Cu" "B.Cu")
		(net "GND")
	)
	(via
		(at 123.054618 -250.964446)
		(size 0.4064)
		(drill 0.2032)
		(layers "F.Cu" "B.Cu")
		(net "GND")
	)
	(via
		(at 284.736032 -255.135126)
		(size 0.4826)
		(drill 0.254)
		(layers "F.Cu" "B.Cu")
		(net "GND")
	)
	(via
		(at 311.778396 -394.831062)
		(size 0.4064)
		(drill 0.2032)
		(layers "F.Cu" "B.Cu")
		(net "GND")
	)
	(via
		(at 274.476464 -228.785166)
		(size 0.4826)
		(drill 0.254)
		(layers "F.Cu" "B.Cu")
		(net "GND")
	)
	(via
		(at 49.167034 -16.979138)
		(size 0.508)
		(drill 0.254)
		(layers "F.Cu" "B.Cu")
		(net "GND")
	)
	(via
		(at 295.724072 -309.535068)
		(size 0.4826)
		(drill 0.254)
		(layers "F.Cu" "B.Cu")
		(net "GND")
	)
	(via
		(at 341.390986 -238.814102)
		(size 0.4064)
		(drill 0.2032)
		(layers "F.Cu" "B.Cu")
		(net "GND")
	)
	(via
		(at 131.271518 -411.936184)
		(size 0.4572)
		(drill 0.254)
		(layers "F.Cu" "B.Cu")
		(net "GND")
	)
	(via
		(at 125.45949 -163.204144)
		(size 0.49022)
		(drill 0.254)
		(layers "F.Cu" "B.Cu")
		(net "GND")
	)
	(via
		(at 137.45464 -270.03629)
		(size 0.4064)
		(drill 0.2032)
		(layers "F.Cu" "B.Cu")
		(net "GND")
	)
	(via
		(at 373.644922 -280.566114)
		(size 0.4064)
		(drill 0.2032)
		(layers "F.Cu" "B.Cu")
		(net "GND")
	)
	(via
		(at 192.712086 -119.042688)
		(size 0.4572)
		(drill 0.254)
		(layers "F.Cu" "B.Cu")
		(net "GND")
	)
	(via
		(at 17.608042 -307.8353)
		(size 0.4826)
		(drill 0.254)
		(layers "F.Cu" "B.Cu")
		(net "GND")
	)
	(via
		(at 269.648178 -306.985162)
		(size 0.4826)
		(drill 0.254)
		(layers "F.Cu" "B.Cu")
		(net "GND")
	)
	(via
		(at 284.736032 -241.53495)
		(size 0.4826)
		(drill 0.254)
		(layers "F.Cu" "B.Cu")
		(net "GND")
	)
	(via
		(at 102.211124 -265.98626)
		(size 0.4064)
		(drill 0.2032)
		(layers "F.Cu" "B.Cu")
		(net "GND")
	)
	(via
		(at 110.371128 -232.334308)
		(size 0.4064)
		(drill 0.2032)
		(layers "F.Cu" "B.Cu")
		(net "GND")
	)
	(via
		(at 407.349706 -427.851316)
		(size 0.4572)
		(drill 0.2032)
		(layers "F.Cu" "B.Cu")
		(net "GND")
	)
	(via
		(at 87.141558 -333.039212)
		(size 0.49022)
		(drill 0.254)
		(layers "F.Cu" "B.Cu")
		(net "GND")
	)
	(via
		(at 353.990656 -169.923968)
		(size 0.49022)
		(drill 0.254)
		(layers "F.Cu" "B.Cu")
		(net "GND")
	)
	(via
		(at 236.119162 -225.806)
		(size 0.508)
		(drill 0.254)
		(layers "F.Cu" "B.Cu")
		(net "GND")
	)
	(via
		(at 458.260196 -65.211706)
		(size 0.508)
		(drill 0.254)
		(layers "F.Cu" "B.Cu")
		(net "GND")
	)
	(via
		(at 243.429282 -371.461538)
		(size 0.508)
		(drill 0.254)
		(layers "F.Cu" "B.Cu")
		(net "GND")
	)
	(via
		(at 56.712358 -203.285344)
		(size 0.4826)
		(drill 0.254)
		(layers "F.Cu" "B.Cu")
		(net "GND")
	)
	(via
		(at 159.201866 -404.46452)
		(size 0.4064)
		(drill 0.2032)
		(layers "F.Cu" "B.Cu")
		(net "GND")
	)
	(via
		(at 151.890222 -384.617722)
		(size 0.4064)
		(drill 0.2032)
		(layers "F.Cu" "B.Cu")
		(net "GND")
	)
	(via
		(at 44.340018 -226.23526)
		(size 0.4826)
		(drill 0.254)
		(layers "F.Cu" "B.Cu")
		(net "GND")
	)
	(via
		(at 164.427916 -262.785352)
		(size 0.4826)
		(drill 0.254)
		(layers "F.Cu" "B.Cu")
		(net "GND")
	)
	(via
		(at 2.76225 -126.929134)
		(size 0.508)
		(drill 0.254)
		(layers "F.Cu" "B.Cu")
		(net "GND")
	)
	(via
		(at 439.100214 -278.93518)
		(size 0.4826)
		(drill 0.254)
		(layers "F.Cu" "B.Cu")
		(net "GND")
	)
	(via
		(at 446.644268 -213.484968)
		(size 0.4826)
		(drill 0.254)
		(layers "F.Cu" "B.Cu")
		(net "GND")
	)
	(via
		(at 116.004848 -233.95432)
		(size 0.4064)
		(drill 0.2032)
		(layers "F.Cu" "B.Cu")
		(net "GND")
	)
	(via
		(at 442.0616 -392.095228)
		(size 0.508)
		(drill 0.254)
		(layers "F.Cu" "B.Cu")
		(net "GND")
	)
	(via
		(at 391.204704 -250.154186)
		(size 0.4064)
		(drill 0.2032)
		(layers "F.Cu" "B.Cu")
		(net "GND")
	)
	(via
		(at 282.826206 -348.704662)
		(size 0.49022)
		(drill 0.254)
		(layers "F.Cu" "B.Cu")
		(net "GND")
	)
	(via
		(at 457.628752 -392.651234)
		(size 0.508)
		(drill 0.254)
		(layers "F.Cu" "B.Cu")
		(net "GND")
	)
	(via
		(at 17.608042 -247.485408)
		(size 0.4826)
		(drill 0.254)
		(layers "F.Cu" "B.Cu")
		(net "GND")
	)
	(via
		(at 147.349718 -436.347362)
		(size 0.4572)
		(drill 0.2032)
		(layers "F.Cu" "B.Cu")
		(net "GND")
	)
	(via
		(at 343.13114 -337.012788)
		(size 0.49022)
		(drill 0.254)
		(layers "F.Cu" "B.Cu")
		(net "GND")
	)
	(via
		(at 121.944638 -269.226284)
		(size 0.4064)
		(drill 0.2032)
		(layers "F.Cu" "B.Cu")
		(net "GND")
	)
	(via
		(at 24.764492 -389.4201)
		(size 0.49022)
		(drill 0.254)
		(layers "F.Cu" "B.Cu")
		(net "GND")
	)
	(via
		(at 100.331016 -293.52621)
		(size 0.4064)
		(drill 0.2032)
		(layers "F.Cu" "B.Cu")
		(net "GND")
	)
	(via
		(at 445.259968 -277.235158)
		(size 0.4826)
		(drill 0.254)
		(layers "F.Cu" "B.Cu")
		(net "GND")
	)
	(via
		(at 368.004852 -282.186126)
		(size 0.4064)
		(drill 0.2032)
		(layers "F.Cu" "B.Cu")
		(net "GND")
	)
	(via
		(at 365.380778 -256.480056)
		(size 0.4826)
		(drill 0.254)
		(layers "F.Cu" "B.Cu")
		(net "GND")
	)
	(via
		(at 374.754902 -231.524048)
		(size 0.4064)
		(drill 0.2032)
		(layers "F.Cu" "B.Cu")
		(net "GND")
	)
	(via
		(at 108.321094 -273.276314)
		(size 0.4064)
		(drill 0.2032)
		(layers "F.Cu" "B.Cu")
		(net "GND")
	)
	(via
		(at 26.536396 -294.235378)
		(size 0.4826)
		(drill 0.254)
		(layers "F.Cu" "B.Cu")
		(net "GND")
	)
	(via
		(at 301.104808 -395.42974)
		(size 0.4064)
		(drill 0.2032)
		(layers "F.Cu" "B.Cu")
		(net "GND")
	)
	(via
		(at 399.438622 -415.38652)
		(size 0.4064)
		(drill 0.2032)
		(layers "F.Cu" "B.Cu")
		(net "GND")
	)
	(via
		(at 452.803768 -314.635134)
		(size 0.4826)
		(drill 0.254)
		(layers "F.Cu" "B.Cu")
		(net "GND")
	)
	(via
		(at 372.234714 -286.236156)
		(size 0.4064)
		(drill 0.2032)
		(layers "F.Cu" "B.Cu")
		(net "GND")
	)
	(via
		(at 393.084812 -233.954066)
		(size 0.4064)
		(drill 0.2032)
		(layers "F.Cu" "B.Cu")
		(net "GND")
	)
	(via
		(at 370.618512 -396.710662)
		(size 0.4064)
		(drill 0.2032)
		(layers "F.Cu" "B.Cu")
		(net "GND")
	)
	(via
		(at 132.404866 -158.470346)
		(size 0.49022)
		(drill 0.254)
		(layers "F.Cu" "B.Cu")
		(net "GND")
	)
	(via
		(at 366.764824 -240.434114)
		(size 0.4064)
		(drill 0.2032)
		(layers "F.Cu" "B.Cu")
		(net "GND")
	)
	(via
		(at 136.98474 -288.666174)
		(size 0.4064)
		(drill 0.2032)
		(layers "F.Cu" "B.Cu")
		(net "GND")
	)
	(via
		(at 56.712358 -312.935366)
		(size 0.4826)
		(drill 0.254)
		(layers "F.Cu" "B.Cu")
		(net "GND")
	)
	(via
		(at 99.861116 -281.376374)
		(size 0.4064)
		(drill 0.2032)
		(layers "F.Cu" "B.Cu")
		(net "GND")
	)
	(via
		(at 83.41106 -267.606272)
		(size 0.4064)
		(drill 0.2032)
		(layers "F.Cu" "B.Cu")
		(net "GND")
	)
	(via
		(at 416.468052 -248.335038)
		(size 0.4826)
		(drill 0.254)
		(layers "F.Cu" "B.Cu")
		(net "GND")
	)
	(via
		(at 262.217916 -136.703054)
		(size 0.508)
		(drill 0.254)
		(layers "F.Cu" "B.Cu")
		(net "GND")
	)
	(via
		(at 396.822422 -412.84652)
		(size 0.4064)
		(drill 0.2032)
		(layers "F.Cu" "B.Cu")
		(net "GND")
	)
	(via
		(at 102.401878 -144.63141)
		(size 0.508)
		(drill 0.254)
		(layers "F.Cu" "B.Cu")
		(net "GND")
	)
	(via
		(at 86.701122 -261.93623)
		(size 0.4064)
		(drill 0.2032)
		(layers "F.Cu" "B.Cu")
		(net "GND")
	)
	(via
		(at 171.97197 -225.385376)
		(size 0.4826)
		(drill 0.254)
		(layers "F.Cu" "B.Cu")
		(net "GND")
	)
	(via
		(at 93.447108 -77.15504)
		(size 0.508)
		(drill 0.254)
		(layers "F.Cu" "B.Cu")
		(net "GND")
	)
	(via
		(at 364.71479 -294.335962)
		(size 0.4064)
		(drill 0.2032)
		(layers "F.Cu" "B.Cu")
		(net "GND")
	)
	(via
		(at 253.978664 -46.875192)
		(size 0.508)
		(drill 0.254)
		(layers "F.Cu" "B.Cu")
		(net "GND")
	)
	(via
		(at 379.454918 -225.044254)
		(size 0.4064)
		(drill 0.2032)
		(layers "F.Cu" "B.Cu")
		(net "GND")
	)
	(via
		(at 29.252164 -244.935248)
		(size 0.4826)
		(drill 0.254)
		(layers "F.Cu" "B.Cu")
		(net "GND")
	)
	(via
		(at 41.62425 -228.78542)
		(size 0.4826)
		(drill 0.254)
		(layers "F.Cu" "B.Cu")
		(net "GND")
	)
	(via
		(at 128.994662 -294.336216)
		(size 0.4064)
		(drill 0.2032)
		(layers "F.Cu" "B.Cu")
		(net "GND")
	)
	(via
		(at 168.527984 -233.885232)
		(size 0.4826)
		(drill 0.254)
		(layers "F.Cu" "B.Cu")
		(net "GND")
	)
	(via
		(at 405.64816 -9.424924)
		(size 0.508)
		(drill 0.254)
		(layers "F.Cu" "B.Cu")
		(net "GND")
	)
	(via
		(at 148.665184 -56.630316)
		(size 0.508)
		(drill 0.254)
		(layers "F.Cu" "B.Cu")
		(net "GND")
	)
	(via
		(at 145.328894 -411.936184)
		(size 0.4572)
		(drill 0.254)
		(layers "F.Cu" "B.Cu")
		(net "GND")
	)
	(via
		(at 356.04196 -333.24292)
		(size 0.508)
		(drill 0.254)
		(layers "F.Cu" "B.Cu")
		(net "GND")
	)
	(via
		(at 405.27478 -380.54153)
		(size 0.508)
		(drill 0.254)
		(layers "F.Cu" "B.Cu")
		(net "GND")
	)
	(via
		(at 188.444378 -240.68532)
		(size 0.4826)
		(drill 0.254)
		(layers "F.Cu" "B.Cu")
		(net "GND")
	)
	(via
		(at 419.332918 -166.351712)
		(size 0.508)
		(drill 0.254)
		(layers "F.Cu" "B.Cu")
		(net "GND")
	)
	(via
		(at 282.020264 -228.785166)
		(size 0.4826)
		(drill 0.254)
		(layers "F.Cu" "B.Cu")
		(net "GND")
	)
	(via
		(at 306.77358 -439.676794)
		(size 0.508)
		(drill 0.254)
		(layers "F.Cu" "B.Cu")
		(net "GND")
	)
	(via
		(at 396.645638 -7.215124)
		(size 0.508)
		(drill 0.254)
		(layers "F.Cu" "B.Cu")
		(net "GND")
	)
	(via
		(at 346.481654 -412.212536)
		(size 0.4572)
		(drill 0.254)
		(layers "F.Cu" "B.Cu")
		(net "GND")
	)
	(via
		(at 115.364768 -267.606272)
		(size 0.4064)
		(drill 0.2032)
		(layers "F.Cu" "B.Cu")
		(net "GND")
	)
	(via
		(at 457.211684 -17.003522)
		(size 0.6604)
		(drill 0.3302)
		(layers "F.Cu" "B.Cu")
		(net "GND")
	)
	(via
		(at 388.68477 -272.466054)
		(size 0.4064)
		(drill 0.2032)
		(layers "F.Cu" "B.Cu")
		(net "GND")
	)
	(via
		(at 363.774736 -274.896072)
		(size 0.4064)
		(drill 0.2032)
		(layers "F.Cu" "B.Cu")
		(net "GND")
	)
	(via
		(at 74.959464 -355.125528)
		(size 0.508)
		(drill 0.254)
		(layers "F.Cu" "B.Cu")
		(net "GND")
	)
	(via
		(at 327.761092 -246.104156)
		(size 0.4064)
		(drill 0.2032)
		(layers "F.Cu" "B.Cu")
		(net "GND")
	)
	(via
		(at 123.886214 -405.098504)
		(size 0.4572)
		(drill 0.254)
		(layers "F.Cu" "B.Cu")
		(net "GND")
	)
	(via
		(at 394.667994 -321.179952)
		(size 0.508)
		(drill 0.254)
		(layers "F.Cu" "B.Cu")
		(net "GND")
	)
	(via
		(at 97.211134 -256.634488)
		(size 0.4064)
		(drill 0.2032)
		(layers "F.Cu" "B.Cu")
		(net "GND")
	)
	(via
		(at 352.5012 -294.335962)
		(size 0.4064)
		(drill 0.2032)
		(layers "F.Cu" "B.Cu")
		(net "GND")
	)
	(via
		(at 90.627962 -221.504764)
		(size 0.4064)
		(drill 0.2032)
		(layers "F.Cu" "B.Cu")
		(net "GND")
	)
	(via
		(at 78.75651 -186.648598)
		(size 0.508)
		(drill 0.254)
		(layers "F.Cu" "B.Cu")
		(net "GND")
	)
	(via
		(at 126.644654 -282.18638)
		(size 0.4064)
		(drill 0.2032)
		(layers "F.Cu" "B.Cu")
		(net "GND")
	)
	(via
		(at 444.622174 -410.6037)
		(size 0.508)
		(drill 0.254)
		(layers "F.Cu" "B.Cu")
		(net "GND")
	)
	(via
		(at 443.119256 -395.306042)
		(size 0.49022)
		(drill 0.254)
		(layers "F.Cu" "B.Cu")
		(net "GND")
	)
	(via
		(at 385.094734 -242.864132)
		(size 0.4064)
		(drill 0.2032)
		(layers "F.Cu" "B.Cu")
		(net "GND")
	)
	(via
		(at 233.651044 -44.958)
		(size 0.508)
		(drill 0.254)
		(layers "F.Cu" "B.Cu")
		(net "GND")
	)
	(via
		(at 411.5943 -381.68453)
		(size 0.508)
		(drill 0.254)
		(layers "F.Cu" "B.Cu")
		(net "GND")
	)
	(via
		(at 85.090762 -368.37493)
		(size 0.508)
		(drill 0.254)
		(layers "F.Cu" "B.Cu")
		(net "GND")
	)
	(via
		(at 162.746182 -388.328662)
		(size 0.4064)
		(drill 0.2032)
		(layers "F.Cu" "B.Cu")
		(net "GND")
	)
	(via
		(at 398.448022 -12.37488)
		(size 0.508)
		(drill 0.254)
		(layers "F.Cu" "B.Cu")
		(net "GND")
	)
	(via
		(at 147.042886 -287.590484)
		(size 0.4064)
		(drill 0.2032)
		(layers "F.Cu" "B.Cu")
		(net "GND")
	)
	(via
		(at 257.429 -333.375)
		(size 0.508)
		(drill 0.254)
		(layers "F.Cu" "B.Cu")
		(net "GND")
	)
	(via
		(at 390.710674 -183.893968)
		(size 0.49022)
		(drill 0.254)
		(layers "F.Cu" "B.Cu")
		(net "GND")
	)
	(via
		(at 147.349718 -429.147224)
		(size 0.4572)
		(drill 0.2032)
		(layers "F.Cu" "B.Cu")
		(net "GND")
	)
	(via
		(at 130.662172 -35.857434)
		(size 0.508)
		(drill 0.254)
		(layers "F.Cu" "B.Cu")
		(net "GND")
	)
	(via
		(at 108.321094 -271.656302)
		(size 0.4064)
		(drill 0.2032)
		(layers "F.Cu" "B.Cu")
		(net "GND")
	)
	(via
		(at 51.918616 -405.098504)
		(size 0.4572)
		(drill 0.254)
		(layers "F.Cu" "B.Cu")
		(net "GND")
	)
	(via
		(at 134.164832 -282.18638)
		(size 0.4064)
		(drill 0.2032)
		(layers "F.Cu" "B.Cu")
		(net "GND")
	)
	(via
		(at 346.39123 -262.745982)
		(size 0.4064)
		(drill 0.2032)
		(layers "F.Cu" "B.Cu")
		(net "GND")
	)
	(via
		(at 108.321094 -270.03629)
		(size 0.4064)
		(drill 0.2032)
		(layers "F.Cu" "B.Cu")
		(net "GND")
	)
	(via
		(at 63.71209 -170.863768)
		(size 0.49022)
		(drill 0.254)
		(layers "F.Cu" "B.Cu")
		(net "GND")
	)
	(via
		(at 192.045082 -55.94096)
		(size 0.508)
		(drill 0.254)
		(layers "F.Cu" "B.Cu")
		(net "GND")
	)
	(via
		(at 268.530578 -238.560102)
		(size 0.4826)
		(drill 0.254)
		(layers "F.Cu" "B.Cu")
		(net "GND")
	)
	(via
		(at 454.188068 -316.335156)
		(size 0.4826)
		(drill 0.254)
		(layers "F.Cu" "B.Cu")
		(net "GND")
	)
	(via
		(at 140.349732 -426.54728)
		(size 0.4572)
		(drill 0.2032)
		(layers "F.Cu" "B.Cu")
		(net "GND")
	)
	(via
		(at 417.406328 -394.831062)
		(size 0.4064)
		(drill 0.2032)
		(layers "F.Cu" "B.Cu")
		(net "GND")
	)
	(via
		(at 118.824756 -250.15444)
		(size 0.4064)
		(drill 0.2032)
		(layers "F.Cu" "B.Cu")
		(net "GND")
	)
	(via
		(at 329.6412 -231.524048)
		(size 0.4064)
		(drill 0.2032)
		(layers "F.Cu" "B.Cu")
		(net "GND")
	)
	(via
		(at 335.6102 -164.084)
		(size 0.508)
		(drill 0.254)
		(layers "F.Cu" "B.Cu")
		(net "GND")
	)
	(via
		(at 436.384446 -231.335072)
		(size 0.4826)
		(drill 0.254)
		(layers "F.Cu" "B.Cu")
		(net "GND")
	)
	(via
		(at 303.268126 -223.6851)
		(size 0.4826)
		(drill 0.254)
		(layers "F.Cu" "B.Cu")
		(net "GND")
	)
	(via
		(at 136.948164 -17.654778)
		(size 0.508)
		(drill 0.254)
		(layers "F.Cu" "B.Cu")
		(net "GND")
	)
	(via
		(at 195.988432 -219.435426)
		(size 0.4826)
		(drill 0.254)
		(layers "F.Cu" "B.Cu")
		(net "GND")
	)
	(via
		(at 288.180018 -199.035162)
		(size 0.4826)
		(drill 0.254)
		(layers "F.Cu" "B.Cu")
		(net "GND")
	)
	(via
		(at 337.930998 -272.466054)
		(size 0.4064)
		(drill 0.2032)
		(layers "F.Cu" "B.Cu")
		(net "GND")
	)
	(via
		(at 282.020264 -296.78503)
		(size 0.4826)
		(drill 0.254)
		(layers "F.Cu" "B.Cu")
		(net "GND")
	)
	(via
		(at 315.488066 -412.84652)
		(size 0.4064)
		(drill 0.2032)
		(layers "F.Cu" "B.Cu")
		(net "GND")
	)
	(via
		(at 258.335526 -327.747884)
		(size 0.508)
		(drill 0.254)
		(layers "F.Cu" "B.Cu")
		(net "GND")
	)
	(via
		(at 121.944638 -261.126224)
		(size 0.4064)
		(drill 0.2032)
		(layers "F.Cu" "B.Cu")
		(net "GND")
	)
	(via
		(at 451.894194 -54.63286)
		(size 0.508)
		(drill 0.254)
		(layers "F.Cu" "B.Cu")
		(net "GND")
	)
	(via
		(at 176.072038 -246.63527)
		(size 0.4826)
		(drill 0.254)
		(layers "F.Cu" "B.Cu")
		(net "GND")
	)
	(via
		(at 81.787746 -355.739446)
		(size 0.508)
		(drill 0.254)
		(layers "F.Cu" "B.Cu")
		(net "GND")
	)
	(via
		(at 80.591152 -274.08632)
		(size 0.4064)
		(drill 0.2032)
		(layers "F.Cu" "B.Cu")
		(net "GND")
	)
	(via
		(at 143.564864 -261.126224)
		(size 0.4064)
		(drill 0.2032)
		(layers "F.Cu" "B.Cu")
		(net "GND")
	)
	(via
		(at 262.275066 -142.223236)
		(size 0.508)
		(drill 0.254)
		(layers "F.Cu" "B.Cu")
		(net "GND")
	)
	(via
		(at 339.876384 -378.07773)
		(size 0.508)
		(drill 0.254)
		(layers "F.Cu" "B.Cu")
		(net "GND")
	)
	(via
		(at 95.076772 -407.638504)
		(size 0.4572)
		(drill 0.254)
		(layers "F.Cu" "B.Cu")
		(net "GND")
	)
	(via
		(at 113.48466 -277.326344)
		(size 0.4064)
		(drill 0.2032)
		(layers "F.Cu" "B.Cu")
		(net "GND")
	)
	(via
		(at 246.301514 -317.942468)
		(size 0.508)
		(drill 0.254)
		(layers "F.Cu" "B.Cu")
		(net "GND")
	)
	(via
		(at 108.02112 -228.284532)
		(size 0.4064)
		(drill 0.2032)
		(layers "F.Cu" "B.Cu")
		(net "GND")
	)
	(via
		(at 84.99094 -233.95432)
		(size 0.4064)
		(drill 0.2032)
		(layers "F.Cu" "B.Cu")
		(net "GND")
	)
	(via
		(at 375.379742 -420.952168)
		(size 0.4064)
		(drill 0.2032)
		(layers "F.Cu" "B.Cu")
		(net "GND")
	)
	(via
		(at 311.427876 -75.454764)
		(size 0.508)
		(drill 0.254)
		(layers "F.Cu" "B.Cu")
		(net "GND")
	)
	(via
		(at 197.3199 -277.235412)
		(size 0.4826)
		(drill 0.254)
		(layers "F.Cu" "B.Cu")
		(net "GND")
	)
	(via
		(at 443.9285 -303.585118)
		(size 0.4826)
		(drill 0.254)
		(layers "F.Cu" "B.Cu")
		(net "GND")
	)
	(via
		(at 417.903914 -421.586152)
		(size 0.4572)
		(drill 0.254)
		(layers "F.Cu" "B.Cu")
		(net "GND")
	)
	(via
		(at 136.945624 -12.495022)
		(size 0.508)
		(drill 0.254)
		(layers "F.Cu" "B.Cu")
		(net "GND")
	)
	(via
		(at 308.71541 -345.566238)
		(size 0.49022)
		(drill 0.254)
		(layers "F.Cu" "B.Cu")
		(net "GND")
	)
	(via
		(at 164.913564 -419.132004)
		(size 0.508)
		(drill 0.254)
		(layers "F.Cu" "B.Cu")
		(net "GND")
	)
	(via
		(at 167.556942 -440.140344)
		(size 0.508)
		(drill 0.254)
		(layers "F.Cu" "B.Cu")
		(net "GND")
	)
	(via
		(at 198.7042 -272.98523)
		(size 0.4826)
		(drill 0.254)
		(layers "F.Cu" "B.Cu")
		(net "GND")
	)
	(via
		(at 406.850088 -339.672422)
		(size 0.508)
		(drill 0.254)
		(layers "F.Cu" "B.Cu")
		(net "GND")
	)
	(via
		(at 400.897344 -344.450162)
		(size 0.508)
		(drill 0.254)
		(layers "F.Cu" "B.Cu")
		(net "GND")
	)
	(via
		(at 102.467918 -407.980896)
		(size 0.508)
		(drill 0.254)
		(layers "F.Cu" "B.Cu")
		(net "GND")
	)
	(via
		(at 386.034788 -225.044254)
		(size 0.4064)
		(drill 0.2032)
		(layers "F.Cu" "B.Cu")
		(net "GND")
	)
	(via
		(at 45.105066 -387.04774)
		(size 0.4064)
		(drill 0.2032)
		(layers "F.Cu" "B.Cu")
		(net "GND")
	)
	(via
		(at 376.93473 -282.996132)
		(size 0.4064)
		(drill 0.2032)
		(layers "F.Cu" "B.Cu")
		(net "GND")
	)
	(via
		(at 386.804916 -290.285932)
		(size 0.4064)
		(drill 0.2032)
		(layers "F.Cu" "B.Cu")
		(net "GND")
	)
	(via
		(at 287.485328 -408.24023)
		(size 0.508)
		(drill 0.254)
		(layers "F.Cu" "B.Cu")
		(net "GND")
	)
	(via
		(at 370.73967 -184.679082)
		(size 0.49022)
		(drill 0.254)
		(layers "F.Cu" "B.Cu")
		(net "GND")
	)
	(via
		(at 291.162486 -201.160126)
		(size 0.4826)
		(drill 0.254)
		(layers "F.Cu" "B.Cu")
		(net "GND")
	)
	(via
		(at 187.463176 -18.167604)
		(size 0.508)
		(drill 0.254)
		(layers "F.Cu" "B.Cu")
		(net "GND")
	)
	(via
		(at 106.87431 -414.14573)
		(size 0.508)
		(drill 0.254)
		(layers "F.Cu" "B.Cu")
		(net "GND")
	)
	(via
		(at 415.779966 -135.93826)
		(size 0.508)
		(drill 0.254)
		(layers "F.Cu" "B.Cu")
		(net "GND")
	)
	(via
		(at 330.581 -225.044254)
		(size 0.4064)
		(drill 0.2032)
		(layers "F.Cu" "B.Cu")
		(net "GND")
	)
	(via
		(at 86.795102 -373.96293)
		(size 0.508)
		(drill 0.254)
		(layers "F.Cu" "B.Cu")
		(net "GND")
	)
	(via
		(at 115.691158 -390.160002)
		(size 0.4064)
		(drill 0.2032)
		(layers "F.Cu" "B.Cu")
		(net "GND")
	)
	(via
		(at 308.19217 -362.601256)
		(size 0.508)
		(drill 0.254)
		(layers "F.Cu" "B.Cu")
		(net "GND")
	)
	(via
		(at 119.12473 -285.426404)
		(size 0.4064)
		(drill 0.2032)
		(layers "F.Cu" "B.Cu")
		(net "GND")
	)
	(via
		(at 118.824756 -240.434368)
		(size 0.4064)
		(drill 0.2032)
		(layers "F.Cu" "B.Cu")
		(net "GND")
	)
	(via
		(at 305.159156 -383.00533)
		(size 0.508)
		(drill 0.254)
		(layers "F.Cu" "B.Cu")
		(net "GND")
	)
	(via
		(at 421.296338 -221.985078)
		(size 0.4826)
		(drill 0.254)
		(layers "F.Cu" "B.Cu")
		(net "GND")
	)
	(via
		(at 328.53122 -269.22603)
		(size 0.4064)
		(drill 0.2032)
		(layers "F.Cu" "B.Cu")
		(net "GND")
	)
	(via
		(at 94.861126 -233.144314)
		(size 0.4064)
		(drill 0.2032)
		(layers "F.Cu" "B.Cu")
		(net "GND")
	)
	(via
		(at 164.973 -97.155)
		(size 0.508)
		(drill 0.254)
		(layers "F.Cu" "B.Cu")
		(net "GND")
	)
	(via
		(at 377.818396 -396.710662)
		(size 0.4064)
		(drill 0.2032)
		(layers "F.Cu" "B.Cu")
		(net "GND")
	)
	(via
		(at 136.796018 -74.873358)
		(size 0.508)
		(drill 0.254)
		(layers "F.Cu" "B.Cu")
		(net "GND")
	)
	(via
		(at 101.290628 -388.892542)
		(size 0.508)
		(drill 0.254)
		(layers "F.Cu" "B.Cu")
		(net "GND")
	)
	(via
		(at 126.34468 -246.914416)
		(size 0.4064)
		(drill 0.2032)
		(layers "F.Cu" "B.Cu")
		(net "GND")
	)
	(via
		(at 197.3199 -239.835436)
		(size 0.4826)
		(drill 0.254)
		(layers "F.Cu" "B.Cu")
		(net "GND")
	)
	(via
		(at 119.662956 -369.69573)
		(size 0.508)
		(drill 0.254)
		(layers "F.Cu" "B.Cu")
		(net "GND")
	)
	(via
		(at 163.796726 -407.00452)
		(size 0.4064)
		(drill 0.2032)
		(layers "F.Cu" "B.Cu")
		(net "GND")
	)
	(via
		(at 187.060078 -283.185362)
		(size 0.4826)
		(drill 0.254)
		(layers "F.Cu" "B.Cu")
		(net "GND")
	)
	(via
		(at 169.208704 -368.37493)
		(size 0.508)
		(drill 0.254)
		(layers "F.Cu" "B.Cu")
		(net "GND")
	)
	(via
		(at 326.821038 -225.044254)
		(size 0.4064)
		(drill 0.2032)
		(layers "F.Cu" "B.Cu")
		(net "GND")
	)
	(via
		(at 9.106408 -176.484788)
		(size 0.508)
		(drill 0.254)
		(layers "F.Cu" "B.Cu")
		(net "GND")
	)
	(via
		(at 299.066966 -23.763224)
		(size 0.508)
		(drill 0.254)
		(layers "F.Cu" "B.Cu")
		(net "GND")
	)
	(via
		(at 419.912038 -281.485086)
		(size 0.4826)
		(drill 0.254)
		(layers "F.Cu" "B.Cu")
		(net "GND")
	)
	(via
		(at 394.6525 -183.85536)
		(size 0.508)
		(drill 0.254)
		(layers "F.Cu" "B.Cu")
		(net "GND")
	)
	(via
		(at 176.490122 -6.042152)
		(size 0.508)
		(drill 0.254)
		(layers "F.Cu" "B.Cu")
		(net "GND")
	)
	(via
		(at 237.130844 -336.677254)
		(size 0.508)
		(drill 0.254)
		(layers "F.Cu" "B.Cu")
		(net "GND")
	)
	(via
		(at 431.3682 -12.37488)
		(size 0.508)
		(drill 0.254)
		(layers "F.Cu" "B.Cu")
		(net "GND")
	)
	(via
		(at 411.781498 -149.502114)
		(size 0.508)
		(drill 0.254)
		(layers "F.Cu" "B.Cu")
		(net "GND")
	)
	(via
		(at 149.406356 -386.449062)
		(size 0.4064)
		(drill 0.2032)
		(layers "F.Cu" "B.Cu")
		(net "GND")
	)
	(via
		(at 110.371128 -240.434368)
		(size 0.4064)
		(drill 0.2032)
		(layers "F.Cu" "B.Cu")
		(net "GND")
	)
	(via
		(at 199.8218 -285.310326)
		(size 0.4826)
		(drill 0.254)
		(layers "F.Cu" "B.Cu")
		(net "GND")
	)
	(via
		(at 195.988432 -294.235378)
		(size 0.4826)
		(drill 0.254)
		(layers "F.Cu" "B.Cu")
		(net "GND")
	)
	(via
		(at 150.491444 -369.03533)
		(size 0.508)
		(drill 0.254)
		(layers "F.Cu" "B.Cu")
		(net "GND")
	)
	(via
		(at 331.821028 -268.416024)
		(size 0.4064)
		(drill 0.2032)
		(layers "F.Cu" "B.Cu")
		(net "GND")
	)
	(via
		(at 343.271094 -222.614236)
		(size 0.4064)
		(drill 0.2032)
		(layers "F.Cu" "B.Cu")
		(net "GND")
	)
	(via
		(at 140.444728 -229.094538)
		(size 0.4064)
		(drill 0.2032)
		(layers "F.Cu" "B.Cu")
		(net "GND")
	)
	(via
		(at 95.472758 -333.87919)
		(size 0.49022)
		(drill 0.254)
		(layers "F.Cu" "B.Cu")
		(net "GND")
	)
	(via
		(at 325.124826 -415.38652)
		(size 0.4064)
		(drill 0.2032)
		(layers "F.Cu" "B.Cu")
		(net "GND")
	)
	(via
		(at 356.261162 -274.896072)
		(size 0.4064)
		(drill 0.2032)
		(layers "F.Cu" "B.Cu")
		(net "GND")
	)
	(via
		(at 195.721732 -230.0605)
		(size 0.4826)
		(drill 0.254)
		(layers "F.Cu" "B.Cu")
		(net "GND")
	)
	(via
		(at 332.931008 -227.474272)
		(size 0.4064)
		(drill 0.2032)
		(layers "F.Cu" "B.Cu")
		(net "GND")
	)
	(via
		(at 113.65484 -244.484398)
		(size 0.4064)
		(drill 0.2032)
		(layers "F.Cu" "B.Cu")
		(net "GND")
	)
	(via
		(at 366.594898 -281.37612)
		(size 0.4064)
		(drill 0.2032)
		(layers "F.Cu" "B.Cu")
		(net "GND")
	)
	(via
		(at 84.082636 -410.664152)
		(size 0.4572)
		(drill 0.254)
		(layers "F.Cu" "B.Cu")
		(net "GND")
	)
	(via
		(at 16.490442 -286.160464)
		(size 0.4826)
		(drill 0.254)
		(layers "F.Cu" "B.Cu")
		(net "GND")
	)
	(via
		(at 415.090102 -392.999722)
		(size 0.4064)
		(drill 0.2032)
		(layers "F.Cu" "B.Cu")
		(net "GND")
	)
	(via
		(at 83.557364 -137.925048)
		(size 0.508)
		(drill 0.254)
		(layers "F.Cu" "B.Cu")
		(net "GND")
	)
	(via
		(at 52.563014 -369.69573)
		(size 0.508)
		(drill 0.254)
		(layers "F.Cu" "B.Cu")
		(net "GND")
	)
	(via
		(at 423.99458 -376.75693)
		(size 0.508)
		(drill 0.254)
		(layers "F.Cu" "B.Cu")
		(net "GND")
	)
	(via
		(at 391.674858 -242.864132)
		(size 0.4064)
		(drill 0.2032)
		(layers "F.Cu" "B.Cu")
		(net "GND")
	)
	(via
		(at 430.17186 -230.485188)
		(size 0.4826)
		(drill 0.254)
		(layers "F.Cu" "B.Cu")
		(net "GND")
	)
	(via
		(at 96.74098 -241.244374)
		(size 0.4064)
		(drill 0.2032)
		(layers "F.Cu" "B.Cu")
		(net "GND")
	)
	(via
		(at 271.974564 -202.01001)
		(size 0.4826)
		(drill 0.254)
		(layers "F.Cu" "B.Cu")
		(net "GND")
	)
	(via
		(at 90.681302 -371.49913)
		(size 0.508)
		(drill 0.254)
		(layers "F.Cu" "B.Cu")
		(net "GND")
	)
	(via
		(at 45.329094 -17.61236)
		(size 0.508)
		(drill 0.254)
		(layers "F.Cu" "B.Cu")
		(net "GND")
	)
	(via
		(at 42.955718 -274.685252)
		(size 0.4826)
		(drill 0.254)
		(layers "F.Cu" "B.Cu")
		(net "GND")
	)
	(via
		(at 288.180018 -206.685134)
		(size 0.4826)
		(drill 0.254)
		(layers "F.Cu" "B.Cu")
		(net "GND")
	)
	(via
		(at 130.87477 -291.096192)
		(size 0.4064)
		(drill 0.2032)
		(layers "F.Cu" "B.Cu")
		(net "GND")
	)
	(via
		(at 25.152096 -250.885198)
		(size 0.4826)
		(drill 0.254)
		(layers "F.Cu" "B.Cu")
		(net "GND")
	)
	(via
		(at 160.290002 -384.617722)
		(size 0.4064)
		(drill 0.2032)
		(layers "F.Cu" "B.Cu")
		(net "GND")
	)
	(via
		(at 389.79475 -242.864132)
		(size 0.4064)
		(drill 0.2032)
		(layers "F.Cu" "B.Cu")
		(net "GND")
	)
	(via
		(at 88.950292 -410.664152)
		(size 0.4572)
		(drill 0.254)
		(layers "F.Cu" "B.Cu")
		(net "GND")
	)
	(via
		(at 154.245818 -407.638504)
		(size 0.4572)
		(drill 0.254)
		(layers "F.Cu" "B.Cu")
		(net "GND")
	)
	(via
		(at 122.584718 -256.634488)
		(size 0.4064)
		(drill 0.2032)
		(layers "F.Cu" "B.Cu")
		(net "GND")
	)
	(via
		(at 364.24489 -288.66592)
		(size 0.4064)
		(drill 0.2032)
		(layers "F.Cu" "B.Cu")
		(net "GND")
	)
	(via
		(at 122.584718 -229.094538)
		(size 0.4064)
		(drill 0.2032)
		(layers "F.Cu" "B.Cu")
		(net "GND")
	)
	(via
		(at 319.258696 -382.34493)
		(size 0.508)
		(drill 0.254)
		(layers "F.Cu" "B.Cu")
		(net "GND")
	)
	(via
		(at 29.252164 -316.33541)
		(size 0.4826)
		(drill 0.254)
		(layers "F.Cu" "B.Cu")
		(net "GND")
	)
	(via
		(at 63.579248 -169.46372)
		(size 0.508)
		(drill 0.254)
		(layers "F.Cu" "B.Cu")
		(net "GND")
	)
	(via
		(at 347.031056 -238.814102)
		(size 0.4064)
		(drill 0.2032)
		(layers "F.Cu" "B.Cu")
		(net "GND")
	)
	(via
		(at 60.718446 -388.328662)
		(size 0.4064)
		(drill 0.2032)
		(layers "F.Cu" "B.Cu")
		(net "GND")
	)
	(via
		(at 105.971086 -265.98626)
		(size 0.4064)
		(drill 0.2032)
		(layers "F.Cu" "B.Cu")
		(net "GND")
	)
	(via
		(at 103.886 -423.42435)
		(size 0.508)
		(drill 0.254)
		(layers "F.Cu" "B.Cu")
		(net "GND")
	)
	(via
		(at 116.987066 -173.862746)
		(size 0.49022)
		(drill 0.254)
		(layers "F.Cu" "B.Cu")
		(net "GND")
	)
	(via
		(at 412.087314 -143.298926)
		(size 0.508)
		(drill 0.254)
		(layers "F.Cu" "B.Cu")
		(net "GND")
	)
	(via
		(at 314.044838 -420.318184)
		(size 0.4572)
		(drill 0.254)
		(layers "F.Cu" "B.Cu")
		(net "GND")
	)
	(via
		(at 114.491008 -390.160002)
		(size 0.4064)
		(drill 0.2032)
		(layers "F.Cu" "B.Cu")
		(net "GND")
	)
	(via
		(at 334.91932 -362.01096)
		(size 0.508)
		(drill 0.254)
		(layers "F.Cu" "B.Cu")
		(net "GND")
	)
	(via
		(at 347.706188 -345.192096)
		(size 0.508)
		(drill 0.254)
		(layers "F.Cu" "B.Cu")
		(net "GND")
	)
	(via
		(at 102.653338 -383.452116)
		(size 0.508)
		(drill 0.254)
		(layers "F.Cu" "B.Cu")
		(net "GND")
	)
	(via
		(at 73.29805 -382.54432)
		(size 0.508)
		(drill 0.254)
		(layers "F.Cu" "B.Cu")
		(net "GND")
	)
	(via
		(at 14.361668 -149.738334)
		(size 0.508)
		(drill 0.254)
		(layers "F.Cu" "B.Cu")
		(net "GND")
	)
	(via
		(at 144.034764 -284.616398)
		(size 0.4064)
		(drill 0.2032)
		(layers "F.Cu" "B.Cu")
		(net "GND")
	)
	(via
		(at 422.76776 -351.68078)
		(size 0.49022)
		(drill 0.254)
		(layers "F.Cu" "B.Cu")
		(net "GND")
	)
	(via
		(at 53.808884 -407.00452)
		(size 0.4064)
		(drill 0.2032)
		(layers "F.Cu" "B.Cu")
		(net "GND")
	)
	(via
		(at 439.100214 -224.534984)
		(size 0.4826)
		(drill 0.254)
		(layers "F.Cu" "B.Cu")
		(net "GND")
	)
	(via
		(at 171.665646 -12.495022)
		(size 0.508)
		(drill 0.254)
		(layers "F.Cu" "B.Cu")
		(net "GND")
	)
	(via
		(at 148.644356 -382.85293)
		(size 0.4064)
		(drill 0.2032)
		(layers "F.Cu" "B.Cu")
		(net "GND")
	)
	(via
		(at 109.68482 -333.05496)
		(size 0.508)
		(drill 0.254)
		(layers "F.Cu" "B.Cu")
		(net "GND")
	)
	(via
		(at 338.389976 -392.999722)
		(size 0.4064)
		(drill 0.2032)
		(layers "F.Cu" "B.Cu")
		(net "GND")
	)
	(via
		(at 289.335718 -192.21831)
		(size 0.4826)
		(drill 0.254)
		(layers "F.Cu" "B.Cu")
		(net "GND")
	)
	(via
		(at 82.001106 -268.416278)
		(size 0.4064)
		(drill 0.2032)
		(layers "F.Cu" "B.Cu")
		(net "GND")
	)
	(via
		(at 118.824756 -243.674392)
		(size 0.4064)
		(drill 0.2032)
		(layers "F.Cu" "B.Cu")
		(net "GND")
	)
	(via
		(at 315.369956 -378.07773)
		(size 0.508)
		(drill 0.254)
		(layers "F.Cu" "B.Cu")
		(net "GND")
	)
	(via
		(at 99.390962 -280.566368)
		(size 0.4064)
		(drill 0.2032)
		(layers "F.Cu" "B.Cu")
		(net "GND")
	)
	(via
		(at 73.634092 -406.370536)
		(size 0.4572)
		(drill 0.254)
		(layers "F.Cu" "B.Cu")
		(net "GND")
	)
	(via
		(at 365.19104 -385.38912)
		(size 0.508)
		(drill 0.254)
		(layers "F.Cu" "B.Cu")
		(net "GND")
	)
	(via
		(at 198.7042 -306.985416)
		(size 0.4826)
		(drill 0.254)
		(layers "F.Cu" "B.Cu")
		(net "GND")
	)
	(via
		(at 297.108372 -219.435172)
		(size 0.4826)
		(drill 0.254)
		(layers "F.Cu" "B.Cu")
		(net "GND")
	)
	(via
		(at 64.085724 -410.030168)
		(size 0.4064)
		(drill 0.2032)
		(layers "F.Cu" "B.Cu")
		(net "GND")
	)
	(via
		(at 338.012532 -132.524246)
		(size 0.508)
		(drill 0.254)
		(layers "F.Cu" "B.Cu")
		(net "GND")
	)
	(via
		(at 82.74431 -382.85293)
		(size 0.4064)
		(drill 0.2032)
		(layers "F.Cu" "B.Cu")
		(net "GND")
	)
	(via
		(at 435.000146 -236.435138)
		(size 0.4826)
		(drill 0.254)
		(layers "F.Cu" "B.Cu")
		(net "GND")
	)
	(via
		(at 142.86865 -61.651134)
		(size 0.508)
		(drill 0.254)
		(layers "F.Cu" "B.Cu")
		(net "GND")
	)
	(via
		(at 356.884732 -416.460178)
		(size 0.508)
		(drill 0.254)
		(layers "F.Cu" "B.Cu")
		(net "GND")
	)
	(via
		(at 176.072038 -216.885266)
		(size 0.4826)
		(drill 0.254)
		(layers "F.Cu" "B.Cu")
		(net "GND")
	)
	(via
		(at 22.479 -342.9762)
		(size 0.49022)
		(drill 0.254)
		(layers "F.Cu" "B.Cu")
		(net "GND")
	)
	(via
		(at 91.144344 -382.85293)
		(size 0.4064)
		(drill 0.2032)
		(layers "F.Cu" "B.Cu")
		(net "GND")
	)
	(via
		(at 350.621092 -291.095938)
		(size 0.4064)
		(drill 0.2032)
		(layers "F.Cu" "B.Cu")
		(net "GND")
	)
	(via
		(at 52.191412 -407.638504)
		(size 0.4572)
		(drill 0.254)
		(layers "F.Cu" "B.Cu")
		(net "GND")
	)
	(via
		(at 198.7042 -235.585254)
		(size 0.4826)
		(drill 0.254)
		(layers "F.Cu" "B.Cu")
		(net "GND")
	)
	(via
		(at 203.532232 -312.935366)
		(size 0.4826)
		(drill 0.254)
		(layers "F.Cu" "B.Cu")
		(net "GND")
	)
	(via
		(at 317.022226 -418.412168)
		(size 0.4064)
		(drill 0.2032)
		(layers "F.Cu" "B.Cu")
		(net "GND")
	)
	(via
		(at 23.948136 -9.424924)
		(size 0.508)
		(drill 0.254)
		(layers "F.Cu" "B.Cu")
		(net "GND")
	)
	(via
		(at 416.286442 -412.84652)
		(size 0.4064)
		(drill 0.2032)
		(layers "F.Cu" "B.Cu")
		(net "GND")
	)
	(via
		(at 455.305668 -285.310072)
		(size 0.4826)
		(drill 0.254)
		(layers "F.Cu" "B.Cu")
		(net "GND")
	)
	(via
		(at 125.404626 -224.234502)
		(size 0.4064)
		(drill 0.2032)
		(layers "F.Cu" "B.Cu")
		(net "GND")
	)
	(via
		(at 113.954814 -279.756362)
		(size 0.4064)
		(drill 0.2032)
		(layers "F.Cu" "B.Cu")
		(net "GND")
	)
	(via
		(at 440.269376 -34.278062)
		(size 0.508)
		(drill 0.254)
		(layers "F.Cu" "B.Cu")
		(net "GND")
	)
	(via
		(at 325.052944 -289.209988)
		(size 0.4064)
		(drill 0.2032)
		(layers "F.Cu" "B.Cu")
		(net "GND")
	)
	(via
		(at 269.798546 -12.542266)
		(size 0.508)
		(drill 0.254)
		(layers "F.Cu" "B.Cu")
		(net "GND")
	)
	(via
		(at 394.349478 -429.147224)
		(size 0.4572)
		(drill 0.2032)
		(layers "F.Cu" "B.Cu")
		(net "GND")
	)
	(via
		(at 405.650954 -412.212536)
		(size 0.4572)
		(drill 0.254)
		(layers "F.Cu" "B.Cu")
		(net "GND")
	)
	(via
		(at 334.811116 -235.574078)
		(size 0.4064)
		(drill 0.2032)
		(layers "F.Cu" "B.Cu")
		(net "GND")
	)
	(via
		(at 329.958192 -385.87426)
		(size 0.508)
		(drill 0.254)
		(layers "F.Cu" "B.Cu")
		(net "GND")
	)
	(via
		(at 83.111086 -238.814356)
		(size 0.4064)
		(drill 0.2032)
		(layers "F.Cu" "B.Cu")
		(net "GND")
	)
	(via
		(at 64.444372 -410.664152)
		(size 0.4572)
		(drill 0.254)
		(layers "F.Cu" "B.Cu")
		(net "GND")
	)
	(via
		(at 449.339716 -402.76907)
		(size 0.508)
		(drill 0.254)
		(layers "F.Cu" "B.Cu")
		(net "GND")
	)
	(via
		(at 85.290914 -293.52621)
		(size 0.4064)
		(drill 0.2032)
		(layers "F.Cu" "B.Cu")
		(net "GND")
	)
	(via
		(at 394.982954 -273.010122)
		(size 0.4064)
		(drill 0.2032)
		(layers "F.Cu" "B.Cu")
		(net "GND")
	)
	(via
		(at 7.262368 -416.550094)
		(size 0.508)
		(drill 0.254)
		(layers "F.Cu" "B.Cu")
		(net "GND")
	)
	(via
		(at 421.029638 -230.060246)
		(size 0.4826)
		(drill 0.254)
		(layers "F.Cu" "B.Cu")
		(net "GND")
	)
	(via
		(at 275.807932 -209.23504)
		(size 0.4826)
		(drill 0.254)
		(layers "F.Cu" "B.Cu")
		(net "GND")
	)
	(via
		(at 84.99094 -243.674392)
		(size 0.4064)
		(drill 0.2032)
		(layers "F.Cu" "B.Cu")
		(net "GND")
	)
	(via
		(at 115.776502 -78.783942)
		(size 0.508)
		(drill 0.254)
		(layers "F.Cu" "B.Cu")
		(net "GND")
	)
	(via
		(at 334.864202 -358.496616)
		(size 0.508)
		(drill 0.254)
		(layers "F.Cu" "B.Cu")
		(net "GND")
	)
	(via
		(at 25.152096 -281.48534)
		(size 0.4826)
		(drill 0.254)
		(layers "F.Cu" "B.Cu")
		(net "GND")
	)
	(via
		(at 414.255458 -101.092508)
		(size 0.508)
		(drill 0.254)
		(layers "F.Cu" "B.Cu")
		(net "GND")
	)
	(via
		(at 312.224166 -344.132408)
		(size 0.508)
		(drill 0.254)
		(layers "F.Cu" "B.Cu")
		(net "GND")
	)
	(via
		(at 156.327856 -88.270588)
		(size 0.508)
		(drill 0.254)
		(layers "F.Cu" "B.Cu")
		(net "GND")
	)
	(via
		(at 439.100214 -241.53495)
		(size 0.4826)
		(drill 0.254)
		(layers "F.Cu" "B.Cu")
		(net "GND")
	)
	(via
		(at 281.818334 -437.923686)
		(size 0.508)
		(drill 0.254)
		(layers "F.Cu" "B.Cu")
		(net "GND")
	)
	(via
		(at 446.644268 -261.93496)
		(size 0.4826)
		(drill 0.254)
		(layers "F.Cu" "B.Cu")
		(net "GND")
	)
	(via
		(at 171.97197 -242.385342)
		(size 0.4826)
		(drill 0.254)
		(layers "F.Cu" "B.Cu")
		(net "GND")
	)
	(via
		(at 137.397998 -405.098504)
		(size 0.4572)
		(drill 0.254)
		(layers "F.Cu" "B.Cu")
		(net "GND")
	)
	(via
		(at 126.34976 -438.651396)
		(size 0.4572)
		(drill 0.2032)
		(layers "F.Cu" "B.Cu")
		(net "GND")
	)
	(via
		(at 370.82476 -265.986006)
		(size 0.4064)
		(drill 0.2032)
		(layers "F.Cu" "B.Cu")
		(net "GND")
	)
	(via
		(at 366.294924 -241.24412)
		(size 0.4064)
		(drill 0.2032)
		(layers "F.Cu" "B.Cu")
		(net "GND")
	)
	(via
		(at 17.608042 -318.885316)
		(size 0.4826)
		(drill 0.254)
		(layers "F.Cu" "B.Cu")
		(net "GND")
	)
	(via
		(at 426.089064 -154.8003)
		(size 0.508)
		(drill 0.254)
		(layers "F.Cu" "B.Cu")
		(net "GND")
	)
	(via
		(at 81.689702 -371.49913)
		(size 0.508)
		(drill 0.254)
		(layers "F.Cu" "B.Cu")
		(net "GND")
	)
	(via
		(at 29.252164 -267.03528)
		(size 0.4826)
		(drill 0.254)
		(layers "F.Cu" "B.Cu")
		(net "GND")
	)
	(via
		(at 22.724364 -423.450258)
		(size 0.508)
		(drill 0.254)
		(layers "F.Cu" "B.Cu")
		(net "GND")
	)
	(via
		(at 100.971096 -240.434368)
		(size 0.4064)
		(drill 0.2032)
		(layers "F.Cu" "B.Cu")
		(net "GND")
	)
	(via
		(at 193.167 -135.725408)
		(size 0.508)
		(drill 0.254)
		(layers "F.Cu" "B.Cu")
		(net "GND")
	)
	(via
		(at 146.742912 -249.610372)
		(size 0.4064)
		(drill 0.2032)
		(layers "F.Cu" "B.Cu")
		(net "GND")
	)
	(via
		(at 176.0601 -416.756342)
		(size 0.508)
		(drill 0.254)
		(layers "F.Cu" "B.Cu")
		(net "GND")
	)
	(via
		(at 68.76288 -388.892542)
		(size 0.508)
		(drill 0.254)
		(layers "F.Cu" "B.Cu")
		(net "GND")
	)
	(via
		(at 265.54811 -204.985112)
		(size 0.4826)
		(drill 0.254)
		(layers "F.Cu" "B.Cu")
		(net "GND")
	)
	(via
		(at 305.983894 -202.434952)
		(size 0.4826)
		(drill 0.254)
		(layers "F.Cu" "B.Cu")
		(net "GND")
	)
	(via
		(at 117.244622 -282.18638)
		(size 0.4064)
		(drill 0.2032)
		(layers "F.Cu" "B.Cu")
		(net "GND")
	)
	(via
		(at 117.884702 -243.674392)
		(size 0.4064)
		(drill 0.2032)
		(layers "F.Cu" "B.Cu")
		(net "GND")
	)
	(via
		(at 17.608042 -242.385342)
		(size 0.4826)
		(drill 0.254)
		(layers "F.Cu" "B.Cu")
		(net "GND")
	)
	(via
		(at 302.123348 -429.606964)
		(size 0.508)
		(drill 0.254)
		(layers "F.Cu" "B.Cu")
		(net "GND")
	)
	(via
		(at 379.924818 -240.434114)
		(size 0.4064)
		(drill 0.2032)
		(layers "F.Cu" "B.Cu")
		(net "GND")
	)
	(via
		(at 155.546298 -388.328662)
		(size 0.4064)
		(drill 0.2032)
		(layers "F.Cu" "B.Cu")
		(net "GND")
	)
	(via
		(at 327.761092 -228.284278)
		(size 0.4064)
		(drill 0.2032)
		(layers "F.Cu" "B.Cu")
		(net "GND")
	)
	(via
		(at 388.063232 -378.07773)
		(size 0.508)
		(drill 0.254)
		(layers "F.Cu" "B.Cu")
		(net "GND")
	)
	(via
		(at 132.063236 -369.69573)
		(size 0.508)
		(drill 0.254)
		(layers "F.Cu" "B.Cu")
		(net "GND")
	)
	(via
		(at 343.981278 -171.64431)
		(size 0.508)
		(drill 0.254)
		(layers "F.Cu" "B.Cu")
		(net "GND")
	)
	(via
		(at 370.524786 -256.634234)
		(size 0.4064)
		(drill 0.2032)
		(layers "F.Cu" "B.Cu")
		(net "GND")
	)
	(via
		(at 467.5378 -110.795054)
		(size 0.508)
		(drill 0.254)
		(layers "F.Cu" "B.Cu")
		(net "GND")
	)
	(via
		(at 117.018562 -388.328662)
		(size 0.4064)
		(drill 0.2032)
		(layers "F.Cu" "B.Cu")
		(net "GND")
	)
	(via
		(at 133.694678 -279.756362)
		(size 0.4064)
		(drill 0.2032)
		(layers "F.Cu" "B.Cu")
		(net "GND")
	)
	(via
		(at 82.001106 -271.656302)
		(size 0.4064)
		(drill 0.2032)
		(layers "F.Cu" "B.Cu")
		(net "GND")
	)
	(via
		(at 117.398546 -404.46452)
		(size 0.4064)
		(drill 0.2032)
		(layers "F.Cu" "B.Cu")
		(net "GND")
	)
	(via
		(at 432.67376 -201.160126)
		(size 0.4826)
		(drill 0.254)
		(layers "F.Cu" "B.Cu")
		(net "GND")
	)
	(via
		(at 319.249552 -425.547282)
		(size 0.4572)
		(drill 0.2032)
		(layers "F.Cu" "B.Cu")
		(net "GND")
	)
	(via
		(at 414.994852 -6.598158)
		(size 0.508)
		(drill 0.254)
		(layers "F.Cu" "B.Cu")
		(net "GND")
	)
	(via
		(at 50.55616 -423.39895)
		(size 0.508)
		(drill 0.254)
		(layers "F.Cu" "B.Cu")
		(net "GND")
	)
	(via
		(at 99.861116 -282.996386)
		(size 0.4064)
		(drill 0.2032)
		(layers "F.Cu" "B.Cu")
		(net "GND")
	)
	(via
		(at 306.212494 -192.21831)
		(size 0.4826)
		(drill 0.254)
		(layers "F.Cu" "B.Cu")
		(net "GND")
	)
	(via
		(at 106.611166 -224.234502)
		(size 0.4064)
		(drill 0.2032)
		(layers "F.Cu" "B.Cu")
		(net "GND")
	)
	(via
		(at 359.387902 -261.32282)
		(size 0.4826)
		(drill 0.254)
		(layers "F.Cu" "B.Cu")
		(net "GND")
	)
	(via
		(at 96.42094 -353.512374)
		(size 0.508)
		(drill 0.254)
		(layers "F.Cu" "B.Cu")
		(net "GND")
	)
	(via
		(at 187.060078 -255.13538)
		(size 0.4826)
		(drill 0.254)
		(layers "F.Cu" "B.Cu")
		(net "GND")
	)
	(via
		(at 306.863496 -377.41733)
		(size 0.508)
		(drill 0.254)
		(layers "F.Cu" "B.Cu")
		(net "GND")
	)
	(via
		(at 147.042886 -290.830254)
		(size 0.4064)
		(drill 0.2032)
		(layers "F.Cu" "B.Cu")
		(net "GND")
	)
	(via
		(at 163.044124 -393.927838)
		(size 0.4572)
		(drill 0.254)
		(layers "F.Cu" "B.Cu")
		(net "GND")
	)
	(via
		(at 70.212204 -407.00452)
		(size 0.4064)
		(drill 0.2032)
		(layers "F.Cu" "B.Cu")
		(net "GND")
	)
	(via
		(at 307.368194 -282.33497)
		(size 0.4826)
		(drill 0.254)
		(layers "F.Cu" "B.Cu")
		(net "GND")
	)
	(via
		(at 391.204704 -243.674138)
		(size 0.4064)
		(drill 0.2032)
		(layers "F.Cu" "B.Cu")
		(net "GND")
	)
	(via
		(at 59.428126 -216.885266)
		(size 0.4826)
		(drill 0.254)
		(layers "F.Cu" "B.Cu")
		(net "GND")
	)
	(via
		(at 338.550758 -420.318184)
		(size 0.4572)
		(drill 0.254)
		(layers "F.Cu" "B.Cu")
		(net "GND")
	)
	(via
		(at 183.616092 -282.335224)
		(size 0.4826)
		(drill 0.254)
		(layers "F.Cu" "B.Cu")
		(net "GND")
	)
	(via
		(at 174.687738 -277.235412)
		(size 0.4826)
		(drill 0.254)
		(layers "F.Cu" "B.Cu")
		(net "GND")
	)
	(via
		(at 315.188346 -334.12684)
		(size 0.508)
		(drill 0.254)
		(layers "F.Cu" "B.Cu")
		(net "GND")
	)
	(via
		(at 267.889736 -343.083896)
		(size 0.49022)
		(drill 0.254)
		(layers "F.Cu" "B.Cu")
		(net "GND")
	)
	(via
		(at 404.39213 -413.480504)
		(size 0.4572)
		(drill 0.254)
		(layers "F.Cu" "B.Cu")
		(net "GND")
	)
	(via
		(at 389.79475 -238.004096)
		(size 0.4064)
		(drill 0.2032)
		(layers "F.Cu" "B.Cu")
		(net "GND")
	)
	(via
		(at 78.41107 -253.394464)
		(size 0.4064)
		(drill 0.2032)
		(layers "F.Cu" "B.Cu")
		(net "GND")
	)
	(via
		(at 121.474738 -282.996386)
		(size 0.4064)
		(drill 0.2032)
		(layers "F.Cu" "B.Cu")
		(net "GND")
	)
	(via
		(at 55.068216 -12.37488)
		(size 0.508)
		(drill 0.254)
		(layers "F.Cu" "B.Cu")
		(net "GND")
	)
	(via
		(at 355.272848 -398.542002)
		(size 0.4064)
		(drill 0.2032)
		(layers "F.Cu" "B.Cu")
		(net "GND")
	)
	(via
		(at 59.462416 -384.617722)
		(size 0.4064)
		(drill 0.2032)
		(layers "F.Cu" "B.Cu")
		(net "GND")
	)
	(via
		(at 182.460392 -192.218564)
		(size 0.4826)
		(drill 0.254)
		(layers "F.Cu" "B.Cu")
		(net "GND")
	)
	(via
		(at 385.018534 -396.710662)
		(size 0.4064)
		(drill 0.2032)
		(layers "F.Cu" "B.Cu")
		(net "GND")
	)
	(via
		(at 447.761868 -238.560102)
		(size 0.4826)
		(drill 0.254)
		(layers "F.Cu" "B.Cu")
		(net "GND")
	)
	(via
		(at 102.85095 -229.094538)
		(size 0.4064)
		(drill 0.2032)
		(layers "F.Cu" "B.Cu")
		(net "GND")
	)
	(via
		(at 411.546294 -396.710662)
		(size 0.4064)
		(drill 0.2032)
		(layers "F.Cu" "B.Cu")
		(net "GND")
	)
	(via
		(at 379.035056 -183.171846)
		(size 0.49022)
		(drill 0.254)
		(layers "F.Cu" "B.Cu")
		(net "GND")
	)
	(via
		(at 16.23441 -395.93647)
		(size 0.508)
		(drill 0.254)
		(layers "F.Cu" "B.Cu")
		(net "GND")
	)
	(via
		(at 180.900324 -238.135414)
		(size 0.4826)
		(drill 0.254)
		(layers "F.Cu" "B.Cu")
		(net "GND")
	)
	(via
		(at 422.627806 -209.23504)
		(size 0.4826)
		(drill 0.254)
		(layers "F.Cu" "B.Cu")
		(net "GND")
	)
	(via
		(at 128.116584 -382.85293)
		(size 0.4064)
		(drill 0.2032)
		(layers "F.Cu" "B.Cu")
		(net "GND")
	)
	(via
		(at 134.164832 -274.08632)
		(size 0.4064)
		(drill 0.2032)
		(layers "F.Cu" "B.Cu")
		(net "GND")
	)
	(via
		(at 125.404626 -243.674392)
		(size 0.4064)
		(drill 0.2032)
		(layers "F.Cu" "B.Cu")
		(net "GND")
	)
	(via
		(at 148.666962 -77.00518)
		(size 0.6604)
		(drill 0.3302)
		(layers "F.Cu" "B.Cu")
		(net "GND")
	)
	(via
		(at 381.804926 -253.39421)
		(size 0.4064)
		(drill 0.2032)
		(layers "F.Cu" "B.Cu")
		(net "GND")
	)
	(via
		(at 364.294674 -179.710588)
		(size 0.49022)
		(drill 0.254)
		(layers "F.Cu" "B.Cu")
		(net "GND")
	)
	(via
		(at 332.4098 -149.3012)
		(size 0.508)
		(drill 0.254)
		(layers "F.Cu" "B.Cu")
		(net "GND")
	)
	(via
		(at 424.012106 -280.634948)
		(size 0.4826)
		(drill 0.254)
		(layers "F.Cu" "B.Cu")
		(net "GND")
	)
	(via
		(at 122.03049 -167.127682)
		(size 0.49022)
		(drill 0.254)
		(layers "F.Cu" "B.Cu")
		(net "GND")
	)
	(via
		(at 325.052944 -263.29005)
		(size 0.4064)
		(drill 0.2032)
		(layers "F.Cu" "B.Cu")
		(net "GND")
	)
	(via
		(at 189.752986 -353.309174)
		(size 0.49022)
		(drill 0.254)
		(layers "F.Cu" "B.Cu")
		(net "GND")
	)
	(via
		(at 350.717866 -418.412168)
		(size 0.4064)
		(drill 0.2032)
		(layers "F.Cu" "B.Cu")
		(net "GND")
	)
	(via
		(at 445.853566 -422.390824)
		(size 0.508)
		(drill 0.254)
		(layers "F.Cu" "B.Cu")
		(net "GND")
	)
	(via
		(at 50.499772 -227.935282)
		(size 0.4826)
		(drill 0.254)
		(layers "F.Cu" "B.Cu")
		(net "GND")
	)
	(via
		(at 102.261924 -32.88411)
		(size 0.508)
		(drill 0.254)
		(layers "F.Cu" "B.Cu")
		(net "GND")
	)
	(via
		(at 198.7042 -226.23526)
		(size 0.4826)
		(drill 0.254)
		(layers "F.Cu" "B.Cu")
		(net "GND")
	)
	(via
		(at 277.192232 -289.985196)
		(size 0.4826)
		(drill 0.254)
		(layers "F.Cu" "B.Cu")
		(net "GND")
	)
	(via
		(at 105.971086 -270.846296)
		(size 0.4064)
		(drill 0.2032)
		(layers "F.Cu" "B.Cu")
		(net "GND")
	)
	(via
		(at 219.743528 -84.662518)
		(size 0.508)
		(drill 0.254)
		(layers "F.Cu" "B.Cu")
		(net "GND")
	)
	(via
		(at 350.789748 -341.922862)
		(size 0.49022)
		(drill 0.254)
		(layers "F.Cu" "B.Cu")
		(net "GND")
	)
	(via
		(at 388.384796 -237.19409)
		(size 0.4064)
		(drill 0.2032)
		(layers "F.Cu" "B.Cu")
		(net "GND")
	)
	(via
		(at 51.884072 -196.485256)
		(size 0.4826)
		(drill 0.254)
		(layers "F.Cu" "B.Cu")
		(net "GND")
	)
	(via
		(at 82.912204 -404.46452)
		(size 0.4064)
		(drill 0.2032)
		(layers "F.Cu" "B.Cu")
		(net "GND")
	)
	(via
		(at 131.575556 -372.15953)
		(size 0.508)
		(drill 0.254)
		(layers "F.Cu" "B.Cu")
		(net "GND")
	)
	(via
		(at 106.299 -410.972)
		(size 0.508)
		(drill 0.254)
		(layers "F.Cu" "B.Cu")
		(net "GND")
	)
	(via
		(at 105.200958 -229.90429)
		(size 0.4064)
		(drill 0.2032)
		(layers "F.Cu" "B.Cu")
		(net "GND")
	)
	(via
		(at 95.1611 -270.03629)
		(size 0.4064)
		(drill 0.2032)
		(layers "F.Cu" "B.Cu")
		(net "GND")
	)
	(via
		(at 2.76225 -82.225134)
		(size 0.508)
		(drill 0.254)
		(layers "F.Cu" "B.Cu")
		(net "GND")
	)
	(via
		(at 424.012106 -297.635168)
		(size 0.4826)
		(drill 0.254)
		(layers "F.Cu" "B.Cu")
		(net "GND")
	)
	(via
		(at 96.49333 -424.191684)
		(size 0.508)
		(drill 0.254)
		(layers "F.Cu" "B.Cu")
		(net "GND")
	)
	(via
		(at 291.761672 -351.858072)
		(size 0.508)
		(drill 0.254)
		(layers "F.Cu" "B.Cu")
		(net "GND")
	)
	(via
		(at 74.61885 -375.793)
		(size 0.508)
		(drill 0.254)
		(layers "F.Cu" "B.Cu")
		(net "GND")
	)
	(via
		(at 197.3199 -202.435206)
		(size 0.4826)
		(drill 0.254)
		(layers "F.Cu" "B.Cu")
		(net "GND")
	)
	(via
		(at 299.82414 -224.534984)
		(size 0.4826)
		(drill 0.254)
		(layers "F.Cu" "B.Cu")
		(net "GND")
	)
	(via
		(at 31.415482 -4.32943)
		(size 0.508)
		(drill 0.254)
		(layers "F.Cu" "B.Cu")
		(net "GND")
	)
	(via
		(at 316.718188 -396.710662)
		(size 0.4064)
		(drill 0.2032)
		(layers "F.Cu" "B.Cu")
		(net "GND")
	)
	(via
		(at 140.349732 -427.699678)
		(size 0.4572)
		(drill 0.2032)
		(layers "F.Cu" "B.Cu")
		(net "GND")
	)
	(via
		(at 155.777438 -411.936184)
		(size 0.4572)
		(drill 0.254)
		(layers "F.Cu" "B.Cu")
		(net "GND")
	)
	(via
		(at 424.012106 -289.985196)
		(size 0.4826)
		(drill 0.254)
		(layers "F.Cu" "B.Cu")
		(net "GND")
	)
	(via
		(at 98.344736 -125.573028)
		(size 0.508)
		(drill 0.254)
		(layers "F.Cu" "B.Cu")
		(net "GND")
	)
	(via
		(at 201.690986 -140.603986)
		(size 0.508)
		(drill 0.254)
		(layers "F.Cu" "B.Cu")
		(net "GND")
	)
	(via
		(at 191.160146 -204.135228)
		(size 0.4826)
		(drill 0.254)
		(layers "F.Cu" "B.Cu")
		(net "GND")
	)
	(via
		(at 187.060078 -300.185328)
		(size 0.4826)
		(drill 0.254)
		(layers "F.Cu" "B.Cu")
		(net "GND")
	)
	(via
		(at 133.864858 -246.914416)
		(size 0.4064)
		(drill 0.2032)
		(layers "F.Cu" "B.Cu")
		(net "GND")
	)
	(via
		(at 76.249784 -425.547282)
		(size 0.4572)
		(drill 0.2032)
		(layers "F.Cu" "B.Cu")
		(net "GND")
	)
	(via
		(at 309.816246 -402.309838)
		(size 0.4572)
		(drill 0.254)
		(layers "F.Cu" "B.Cu")
		(net "GND")
	)
	(via
		(at 403.349714 -435.0512)
		(size 0.4572)
		(drill 0.2032)
		(layers "F.Cu" "B.Cu")
		(net "GND")
	)
	(via
		(at 393.384786 -278.946102)
		(size 0.4064)
		(drill 0.2032)
		(layers "F.Cu" "B.Cu")
		(net "GND")
	)
	(via
		(at 354.34524 -259.33019)
		(size 0.4826)
		(drill 0.254)
		(layers "F.Cu" "B.Cu")
		(net "GND")
	)
	(via
		(at 413.752284 -312.935112)
		(size 0.4826)
		(drill 0.254)
		(layers "F.Cu" "B.Cu")
		(net "GND")
	)
	(via
		(at 140.444728 -242.05438)
		(size 0.4064)
		(drill 0.2032)
		(layers "F.Cu" "B.Cu")
		(net "GND")
	)
	(via
		(at 349.381064 -249.34418)
		(size 0.4064)
		(drill 0.2032)
		(layers "F.Cu" "B.Cu")
		(net "GND")
	)
	(via
		(at 367.704878 -235.574078)
		(size 0.4064)
		(drill 0.2032)
		(layers "F.Cu" "B.Cu")
		(net "GND")
	)
	(via
		(at 300.053756 -380.54153)
		(size 0.508)
		(drill 0.254)
		(layers "F.Cu" "B.Cu")
		(net "GND")
	)
	(via
		(at 191.160146 -297.635422)
		(size 0.4826)
		(drill 0.254)
		(layers "F.Cu" "B.Cu")
		(net "GND")
	)
	(via
		(at 180.732176 -107.063032)
		(size 0.4572)
		(drill 0.254)
		(layers "F.Cu" "B.Cu")
		(net "GND")
	)
	(via
		(at 18.992342 -294.235378)
		(size 0.4826)
		(drill 0.254)
		(layers "F.Cu" "B.Cu")
		(net "GND")
	)
	(via
		(at 344.318844 -398.542002)
		(size 0.4064)
		(drill 0.2032)
		(layers "F.Cu" "B.Cu")
		(net "GND")
	)
	(via
		(at 99.561142 -231.524302)
		(size 0.4064)
		(drill 0.2032)
		(layers "F.Cu" "B.Cu")
		(net "GND")
	)
	(via
		(at 82.823812 -410.664152)
		(size 0.4572)
		(drill 0.254)
		(layers "F.Cu" "B.Cu")
		(net "GND")
	)
	(via
		(at 386.516372 -402.309838)
		(size 0.4572)
		(drill 0.254)
		(layers "F.Cu" "B.Cu")
		(net "GND")
	)
	(via
		(at 347.801184 -268.416024)
		(size 0.4064)
		(drill 0.2032)
		(layers "F.Cu" "B.Cu")
		(net "GND")
	)
	(via
		(at 171.97197 -245.785386)
		(size 0.4826)
		(drill 0.254)
		(layers "F.Cu" "B.Cu")
		(net "GND")
	)
	(via
		(at 412.367984 -250.884944)
		(size 0.4826)
		(drill 0.254)
		(layers "F.Cu" "B.Cu")
		(net "GND")
	)
	(via
		(at 240.07953 -370.034566)
		(size 0.508)
		(drill 0.254)
		(layers "F.Cu" "B.Cu")
		(net "GND")
	)
	(via
		(at 317.221108 -119.566182)
		(size 0.508)
		(drill 0.254)
		(layers "F.Cu" "B.Cu")
		(net "GND")
	)
	(via
		(at 326.570594 -419.046152)
		(size 0.4572)
		(drill 0.254)
		(layers "F.Cu" "B.Cu")
		(net "GND")
	)
	(via
		(at 43.222418 -219.860368)
		(size 0.4826)
		(drill 0.254)
		(layers "F.Cu" "B.Cu")
		(net "GND")
	)
	(via
		(at 312.871866 -415.38652)
		(size 0.4064)
		(drill 0.2032)
		(layers "F.Cu" "B.Cu")
		(net "GND")
	)
	(via
		(at 374.284748 -235.574078)
		(size 0.4064)
		(drill 0.2032)
		(layers "F.Cu" "B.Cu")
		(net "GND")
	)
	(via
		(at 308.05501 -345.566238)
		(size 0.49022)
		(drill 0.254)
		(layers "F.Cu" "B.Cu")
		(net "GND")
	)
	(via
		(at 195.44665 -19.14144)
		(size 0.508)
		(drill 0.254)
		(layers "F.Cu" "B.Cu")
		(net "GND")
	)
	(via
		(at 92.10675 -189.552326)
		(size 0.508)
		(drill 0.254)
		(layers "F.Cu" "B.Cu")
		(net "GND")
	)
	(via
		(at 351.731072 -225.85426)
		(size 0.4064)
		(drill 0.2032)
		(layers "F.Cu" "B.Cu")
		(net "GND")
	)
	(via
		(at 384.924808 -288.66592)
		(size 0.4064)
		(drill 0.2032)
		(layers "F.Cu" "B.Cu")
		(net "GND")
	)
	(via
		(at 84.355432 -405.098504)
		(size 0.4572)
		(drill 0.254)
		(layers "F.Cu" "B.Cu")
		(net "GND")
	)
	(via
		(at 371.93474 -239.624108)
		(size 0.4064)
		(drill 0.2032)
		(layers "F.Cu" "B.Cu")
		(net "GND")
	)
	(via
		(at 121.474738 -270.03629)
		(size 0.4064)
		(drill 0.2032)
		(layers "F.Cu" "B.Cu")
		(net "GND")
	)
	(via
		(at 439.100214 -205.834996)
		(size 0.4826)
		(drill 0.254)
		(layers "F.Cu" "B.Cu")
		(net "GND")
	)
	(via
		(at 355.491034 -227.474272)
		(size 0.4064)
		(drill 0.2032)
		(layers "F.Cu" "B.Cu")
		(net "GND")
	)
	(via
		(at 138.564874 -232.334308)
		(size 0.4064)
		(drill 0.2032)
		(layers "F.Cu" "B.Cu")
		(net "GND")
	)
	(via
		(at 157.349698 -427.699678)
		(size 0.4572)
		(drill 0.2032)
		(layers "F.Cu" "B.Cu")
		(net "GND")
	)
	(via
		(at 29.252164 -196.485256)
		(size 0.4826)
		(drill 0.254)
		(layers "F.Cu" "B.Cu")
		(net "GND")
	)
	(via
		(at 297.108372 -240.685066)
		(size 0.4826)
		(drill 0.254)
		(layers "F.Cu" "B.Cu")
		(net "GND")
	)
	(via
		(at 358.108504 -376.75693)
		(size 0.508)
		(drill 0.254)
		(layers "F.Cu" "B.Cu")
		(net "GND")
	)
	(via
		(at 354.718874 -171.435268)
		(size 0.49022)
		(drill 0.254)
		(layers "F.Cu" "B.Cu")
		(net "GND")
	)
	(via
		(at 155.754578 -46.286166)
		(size 0.508)
		(drill 0.254)
		(layers "F.Cu" "B.Cu")
		(net "GND")
	)
	(via
		(at 312.443876 -79.810864)
		(size 0.508)
		(drill 0.254)
		(layers "F.Cu" "B.Cu")
		(net "GND")
	)
	(via
		(at 326.821038 -250.964192)
		(size 0.4064)
		(drill 0.2032)
		(layers "F.Cu" "B.Cu")
		(net "GND")
	)
	(via
		(at 21.69033 -424.264074)
		(size 0.508)
		(drill 0.254)
		(layers "F.Cu" "B.Cu")
		(net "GND")
	)
	(via
		(at 410.604462 -418.412168)
		(size 0.4064)
		(drill 0.2032)
		(layers "F.Cu" "B.Cu")
		(net "GND")
	)
	(via
		(at 347.33103 -288.66592)
		(size 0.4064)
		(drill 0.2032)
		(layers "F.Cu" "B.Cu")
		(net "GND")
	)
	(via
		(at 288.180018 -197.33514)
		(size 0.4826)
		(drill 0.254)
		(layers "F.Cu" "B.Cu")
		(net "GND")
	)
	(via
		(at 443.9285 -221.985078)
		(size 0.4826)
		(drill 0.254)
		(layers "F.Cu" "B.Cu")
		(net "GND")
	)
	(via
		(at 125.417834 -406.370536)
		(size 0.4572)
		(drill 0.254)
		(layers "F.Cu" "B.Cu")
		(net "GND")
	)
	(via
		(at 79.821024 -250.964446)
		(size 0.4064)
		(drill 0.2032)
		(layers "F.Cu" "B.Cu")
		(net "GND")
	)
	(via
		(at 239.461802 -69.17436)
		(size 0.508)
		(drill 0.254)
		(layers "F.Cu" "B.Cu")
		(net "GND")
	)
	(via
		(at 113.65484 -247.724422)
		(size 0.4064)
		(drill 0.2032)
		(layers "F.Cu" "B.Cu")
		(net "GND")
	)
	(via
		(at 95.20682 -340.171024)
		(size 0.508)
		(drill 0.254)
		(layers "F.Cu" "B.Cu")
		(net "GND")
	)
	(via
		(at 378.344938 -267.606018)
		(size 0.4064)
		(drill 0.2032)
		(layers "F.Cu" "B.Cu")
		(net "GND")
	)
	(via
		(at 302.150526 -202.01001)
		(size 0.4826)
		(drill 0.254)
		(layers "F.Cu" "B.Cu")
		(net "GND")
	)
	(via
		(at 424.012106 -232.184956)
		(size 0.4826)
		(drill 0.254)
		(layers "F.Cu" "B.Cu")
		(net "GND")
	)
	(via
		(at 12.13104 -388.494524)
		(size 0.508)
		(drill 0.254)
		(layers "F.Cu" "B.Cu")
		(net "GND")
	)
	(via
		(at 140.734034 -406.370536)
		(size 0.4572)
		(drill 0.254)
		(layers "F.Cu" "B.Cu")
		(net "GND")
	)
	(via
		(at 349.544132 -402.309838)
		(size 0.4572)
		(drill 0.254)
		(layers "F.Cu" "B.Cu")
		(net "GND")
	)
	(via
		(at 332.931008 -245.29415)
		(size 0.4064)
		(drill 0.2032)
		(layers "F.Cu" "B.Cu")
		(net "GND")
	)
	(via
		(at 174.687738 -239.835436)
		(size 0.4826)
		(drill 0.254)
		(layers "F.Cu" "B.Cu")
		(net "GND")
	)
	(via
		(at 72.31507 -153.79319)
		(size 0.508)
		(drill 0.254)
		(layers "F.Cu" "B.Cu")
		(net "GND")
	)
	(via
		(at 56.357774 -336.275172)
		(size 0.508)
		(drill 0.254)
		(layers "F.Cu" "B.Cu")
		(net "GND")
	)
	(via
		(at 105.971086 -277.326344)
		(size 0.4064)
		(drill 0.2032)
		(layers "F.Cu" "B.Cu")
		(net "GND")
	)
	(via
		(at 452.803768 -221.13494)
		(size 0.4826)
		(drill 0.254)
		(layers "F.Cu" "B.Cu")
		(net "GND")
	)
	(via
		(at 94.488 -207.482948)
		(size 0.508)
		(drill 0.254)
		(layers "F.Cu" "B.Cu")
		(net "GND")
	)
	(via
		(at 277.192232 -205.834996)
		(size 0.4826)
		(drill 0.254)
		(layers "F.Cu" "B.Cu")
		(net "GND")
	)
	(via
		(at 146.860514 -410.664152)
		(size 0.4572)
		(drill 0.254)
		(layers "F.Cu" "B.Cu")
		(net "GND")
	)
	(via
		(at 25.152096 -300.185328)
		(size 0.4826)
		(drill 0.254)
		(layers "F.Cu" "B.Cu")
		(net "GND")
	)
	(via
		(at 358.61117 -272.466054)
		(size 0.4064)
		(drill 0.2032)
		(layers "F.Cu" "B.Cu")
		(net "GND")
	)
	(via
		(at 127.114808 -270.03629)
		(size 0.4064)
		(drill 0.2032)
		(layers "F.Cu" "B.Cu")
		(net "GND")
	)
	(via
		(at 308.449472 -351.858072)
		(size 0.508)
		(drill 0.254)
		(layers "F.Cu" "B.Cu")
		(net "GND")
	)
	(via
		(at 337.930998 -290.285932)
		(size 0.4064)
		(drill 0.2032)
		(layers "F.Cu" "B.Cu")
		(net "GND")
	)
	(via
		(at 186.447938 -347.39072)
		(size 0.508)
		(drill 0.254)
		(layers "F.Cu" "B.Cu")
		(net "GND")
	)
	(via
		(at 206.248 -235.585254)
		(size 0.4826)
		(drill 0.254)
		(layers "F.Cu" "B.Cu")
		(net "GND")
	)
	(via
		(at 394.68298 -252.850142)
		(size 0.4064)
		(drill 0.2032)
		(layers "F.Cu" "B.Cu")
		(net "GND")
	)
	(via
		(at 194.604132 -242.385342)
		(size 0.4826)
		(drill 0.254)
		(layers "F.Cu" "B.Cu")
		(net "GND")
	)
	(via
		(at 431.099468 -5.597398)
		(size 0.508)
		(drill 0.254)
		(layers "F.Cu" "B.Cu")
		(net "GND")
	)
	(via
		(at 20.921218 -18.247106)
		(size 0.508)
		(drill 0.254)
		(layers "F.Cu" "B.Cu")
		(net "GND")
	)
	(via
		(at 133.394704 -244.484398)
		(size 0.4064)
		(drill 0.2032)
		(layers "F.Cu" "B.Cu")
		(net "GND")
	)
	(via
		(at 347.801184 -281.37612)
		(size 0.4064)
		(drill 0.2032)
		(layers "F.Cu" "B.Cu")
		(net "GND")
	)
	(via
		(at 118.65483 -287.856422)
		(size 0.4064)
		(drill 0.2032)
		(layers "F.Cu" "B.Cu")
		(net "GND")
	)
	(via
		(at 265.54811 -317.18504)
		(size 0.4826)
		(drill 0.254)
		(layers "F.Cu" "B.Cu")
		(net "GND")
	)
	(via
		(at 46.666404 -239.410494)
		(size 0.4826)
		(drill 0.254)
		(layers "F.Cu" "B.Cu")
		(net "GND")
	)
	(via
		(at 83.88096 -282.996386)
		(size 0.4064)
		(drill 0.2032)
		(layers "F.Cu" "B.Cu")
		(net "GND")
	)
	(via
		(at 372.404894 -251.774198)
		(size 0.4064)
		(drill 0.2032)
		(layers "F.Cu" "B.Cu")
		(net "GND")
	)
	(via
		(at 337.631024 -243.674138)
		(size 0.4064)
		(drill 0.2032)
		(layers "F.Cu" "B.Cu")
		(net "GND")
	)
	(via
		(at 320.949828 -42.684954)
		(size 0.508)
		(drill 0.254)
		(layers "F.Cu" "B.Cu")
		(net "GND")
	)
	(via
		(at 8.590788 -371.36705)
		(size 0.508)
		(drill 0.254)
		(layers "F.Cu" "B.Cu")
		(net "GND")
	)
	(via
		(at 354.34524 -256.480056)
		(size 0.4826)
		(drill 0.254)
		(layers "F.Cu" "B.Cu")
		(net "GND")
	)
	(via
		(at 103.805482 -381.020828)
		(size 0.508)
		(drill 0.254)
		(layers "F.Cu" "B.Cu")
		(net "GND")
	)
	(via
		(at 388.34949 -427.699678)
		(size 0.4572)
		(drill 0.2032)
		(layers "F.Cu" "B.Cu")
		(net "GND")
	)
	(via
		(at 107.081066 -221.804484)
		(size 0.4064)
		(drill 0.2032)
		(layers "F.Cu" "B.Cu")
		(net "GND")
	)
	(via
		(at 305.093878 -109.69625)
		(size 0.508)
		(drill 0.254)
		(layers "F.Cu" "B.Cu")
		(net "GND")
	)
	(via
		(at 133.394704 -246.10441)
		(size 0.4064)
		(drill 0.2032)
		(layers "F.Cu" "B.Cu")
		(net "GND")
	)
	(via
		(at 123.135136 -259.73024)
		(size 0.4826)
		(drill 0.254)
		(layers "F.Cu" "B.Cu")
		(net "GND")
	)
	(via
		(at 27.959558 -345.571064)
		(size 0.49022)
		(drill 0.254)
		(layers "F.Cu" "B.Cu")
		(net "GND")
	)
	(via
		(at 88.24976 -436.347362)
		(size 0.4572)
		(drill 0.2032)
		(layers "F.Cu" "B.Cu")
		(net "GND")
	)
	(via
		(at 319.282064 -118.682262)
		(size 0.508)
		(drill 0.254)
		(layers "F.Cu" "B.Cu")
		(net "GND")
	)
	(via
		(at 333.230982 -274.086066)
		(size 0.4064)
		(drill 0.2032)
		(layers "F.Cu" "B.Cu")
		(net "GND")
	)
	(via
		(at 290.895786 -218.585034)
		(size 0.4826)
		(drill 0.254)
		(layers "F.Cu" "B.Cu")
		(net "GND")
	)
	(via
		(at 44.340018 -291.685218)
		(size 0.4826)
		(drill 0.254)
		(layers "F.Cu" "B.Cu")
		(net "GND")
	)
	(via
		(at 80.700118 -333.057754)
		(size 0.49022)
		(drill 0.254)
		(layers "F.Cu" "B.Cu")
		(net "GND")
	)
	(via
		(at 344.511122 -261.12597)
		(size 0.4064)
		(drill 0.2032)
		(layers "F.Cu" "B.Cu")
		(net "GND")
	)
	(via
		(at 305.127914 -419.046152)
		(size 0.4572)
		(drill 0.254)
		(layers "F.Cu" "B.Cu")
		(net "GND")
	)
	(via
		(at 97.681034 -249.344434)
		(size 0.4064)
		(drill 0.2032)
		(layers "F.Cu" "B.Cu")
		(net "GND")
	)
	(via
		(at 450.088 -227.085144)
		(size 0.4826)
		(drill 0.254)
		(layers "F.Cu" "B.Cu")
		(net "GND")
	)
	(via
		(at 316.43955 -77.53985)
		(size 0.508)
		(drill 0.254)
		(layers "F.Cu" "B.Cu")
		(net "GND")
	)
	(via
		(at 320.444114 -416.020504)
		(size 0.4572)
		(drill 0.254)
		(layers "F.Cu" "B.Cu")
		(net "GND")
	)
	(via
		(at 168.527984 -265.335258)
		(size 0.4826)
		(drill 0.254)
		(layers "F.Cu" "B.Cu")
		(net "GND")
	)
	(via
		(at 355.78796 -264.368026)
		(size 0.4064)
		(drill 0.2032)
		(layers "F.Cu" "B.Cu")
		(net "GND")
	)
	(via
		(at 132.803138 -409.396184)
		(size 0.4572)
		(drill 0.254)
		(layers "F.Cu" "B.Cu")
		(net "GND")
	)
	(via
		(at 358.437942 -256.387346)
		(size 0.4826)
		(drill 0.254)
		(layers "F.Cu" "B.Cu")
		(net "GND")
	)
	(via
		(at 339.811106 -277.32609)
		(size 0.4064)
		(drill 0.2032)
		(layers "F.Cu" "B.Cu")
		(net "GND")
	)
	(via
		(at 372.404894 -237.19409)
		(size 0.4064)
		(drill 0.2032)
		(layers "F.Cu" "B.Cu")
		(net "GND")
	)
	(via
		(at 392.680952 -376.75693)
		(size 0.508)
		(drill 0.254)
		(layers "F.Cu" "B.Cu")
		(net "GND")
	)
	(via
		(at 98.451162 -265.98626)
		(size 0.4064)
		(drill 0.2032)
		(layers "F.Cu" "B.Cu")
		(net "GND")
	)
	(via
		(at 45.206158 -346.322142)
		(size 0.49022)
		(drill 0.254)
		(layers "F.Cu" "B.Cu")
		(net "GND")
	)
	(via
		(at 408.347164 -17.613122)
		(size 0.508)
		(drill 0.254)
		(layers "F.Cu" "B.Cu")
		(net "GND")
	)
	(via
		(at 78.41107 -227.474526)
		(size 0.4064)
		(drill 0.2032)
		(layers "F.Cu" "B.Cu")
		(net "GND")
	)
	(via
		(at 203.532232 -315.485272)
		(size 0.4826)
		(drill 0.254)
		(layers "F.Cu" "B.Cu")
		(net "GND")
	)
	(via
		(at 442.769752 -393.159234)
		(size 0.508)
		(drill 0.254)
		(layers "F.Cu" "B.Cu")
		(net "GND")
	)
	(via
		(at 422.627806 -284.034992)
		(size 0.4826)
		(drill 0.254)
		(layers "F.Cu" "B.Cu")
		(net "GND")
	)
	(via
		(at 346.39123 -265.986006)
		(size 0.4064)
		(drill 0.2032)
		(layers "F.Cu" "B.Cu")
		(net "GND")
	)
	(via
		(at 375.054876 -265.176)
		(size 0.4064)
		(drill 0.2032)
		(layers "F.Cu" "B.Cu")
		(net "GND")
	)
	(via
		(at 285.873698 -417.005516)
		(size 0.4572)
		(drill 0.254)
		(layers "F.Cu" "B.Cu")
		(net "GND")
	)
	(via
		(at 336.521044 -292.71595)
		(size 0.4064)
		(drill 0.2032)
		(layers "F.Cu" "B.Cu")
		(net "GND")
	)
	(via
		(at 47.784004 -283.185362)
		(size 0.4826)
		(drill 0.254)
		(layers "F.Cu" "B.Cu")
		(net "GND")
	)
	(via
		(at 317.108078 -420.318184)
		(size 0.4572)
		(drill 0.254)
		(layers "F.Cu" "B.Cu")
		(net "GND")
	)
	(via
		(at 159.113474 -409.396184)
		(size 0.4572)
		(drill 0.254)
		(layers "F.Cu" "B.Cu")
		(net "GND")
	)
	(via
		(at 48.359314 -432.304952)
		(size 0.508)
		(drill 0.254)
		(layers "F.Cu" "B.Cu")
		(net "GND")
	)
	(via
		(at 83.88096 -273.276314)
		(size 0.4064)
		(drill 0.2032)
		(layers "F.Cu" "B.Cu")
		(net "GND")
	)
	(via
		(at 431.329592 -350.741234)
		(size 0.49022)
		(drill 0.254)
		(layers "F.Cu" "B.Cu")
		(net "GND")
	)
	(via
		(at 411.844236 -391.23493)
		(size 0.4064)
		(drill 0.2032)
		(layers "F.Cu" "B.Cu")
		(net "GND")
	)
	(via
		(at 171.97197 -266.185396)
		(size 0.4826)
		(drill 0.254)
		(layers "F.Cu" "B.Cu")
		(net "GND")
	)
	(via
		(at 346.208858 -417.778184)
		(size 0.4572)
		(drill 0.254)
		(layers "F.Cu" "B.Cu")
		(net "GND")
	)
	(via
		(at 125.404626 -237.194344)
		(size 0.4064)
		(drill 0.2032)
		(layers "F.Cu" "B.Cu")
		(net "GND")
	)
	(via
		(at 71.938134 -379.321568)
		(size 0.508)
		(drill 0.254)
		(layers "F.Cu" "B.Cu")
		(net "GND")
	)
	(via
		(at 334.341216 -228.284278)
		(size 0.4064)
		(drill 0.2032)
		(layers "F.Cu" "B.Cu")
		(net "GND")
	)
	(via
		(at 201.123042 -387.960616)
		(size 0.508)
		(drill 0.254)
		(layers "F.Cu" "B.Cu")
		(net "GND")
	)
	(via
		(at 70.149974 -336.988404)
		(size 0.49022)
		(drill 0.254)
		(layers "F.Cu" "B.Cu")
		(net "GND")
	)
	(via
		(at 274.476464 -315.485018)
		(size 0.4826)
		(drill 0.254)
		(layers "F.Cu" "B.Cu")
		(net "GND")
	)
	(via
		(at 355.791008 -290.285932)
		(size 0.4064)
		(drill 0.2032)
		(layers "F.Cu" "B.Cu")
		(net "GND")
	)
	(via
		(at 352.671126 -227.474272)
		(size 0.4064)
		(drill 0.2032)
		(layers "F.Cu" "B.Cu")
		(net "GND")
	)
	(via
		(at 303.268126 -214.335106)
		(size 0.4826)
		(drill 0.254)
		(layers "F.Cu" "B.Cu")
		(net "GND")
	)
	(via
		(at 463.070448 -390.819386)
		(size 0.508)
		(drill 0.254)
		(layers "F.Cu" "B.Cu")
		(net "GND")
	)
	(via
		(at 0.762254 -37.891212)
		(size 0.508)
		(drill 0.254)
		(layers "F.Cu" "B.Cu")
		(net "GND")
	)
	(via
		(at 394.296138 -181.075838)
		(size 0.508)
		(drill 0.254)
		(layers "F.Cu" "B.Cu")
		(net "GND")
	)
	(via
		(at 346.39123 -280.566114)
		(size 0.4064)
		(drill 0.2032)
		(layers "F.Cu" "B.Cu")
		(net "GND")
	)
	(via
		(at 44.541694 -368.37493)
		(size 0.508)
		(drill 0.254)
		(layers "F.Cu" "B.Cu")
		(net "GND")
	)
	(via
		(at 75.165712 -0.762254)
		(size 0.508)
		(drill 0.254)
		(layers "F.Cu" "B.Cu")
		(net "GND")
	)
	(via
		(at 393.717272 -384.299968)
		(size 0.508)
		(drill 0.254)
		(layers "F.Cu" "B.Cu")
		(net "GND")
	)
	(via
		(at 144.905222 -159.742124)
		(size 0.6604)
		(drill 0.3302)
		(layers "F.Cu" "B.Cu")
		(net "GND")
	)
	(via
		(at 132.349748 -433.747164)
		(size 0.4572)
		(drill 0.2032)
		(layers "F.Cu" "B.Cu")
		(net "GND")
	)
	(via
		(at 353.441 -291.095938)
		(size 0.4064)
		(drill 0.2032)
		(layers "F.Cu" "B.Cu")
		(net "GND")
	)
	(via
		(at 105.200958 -250.964446)
		(size 0.4064)
		(drill 0.2032)
		(layers "F.Cu" "B.Cu")
		(net "GND")
	)
	(via
		(at 418.265102 -420.952168)
		(size 0.4064)
		(drill 0.2032)
		(layers "F.Cu" "B.Cu")
		(net "GND")
	)
	(via
		(at 439.100214 -263.634982)
		(size 0.4826)
		(drill 0.254)
		(layers "F.Cu" "B.Cu")
		(net "GND")
	)
	(via
		(at 450.088 -309.535068)
		(size 0.4826)
		(drill 0.254)
		(layers "F.Cu" "B.Cu")
		(net "GND")
	)
	(via
		(at 127.284734 -237.194344)
		(size 0.4064)
		(drill 0.2032)
		(layers "F.Cu" "B.Cu")
		(net "GND")
	)
	(via
		(at 345.599766 -30.57652)
		(size 0.508)
		(drill 0.254)
		(layers "F.Cu" "B.Cu")
		(net "GND")
	)
	(via
		(at 381.43942 -206.215488)
		(size 0.508)
		(drill 0.254)
		(layers "F.Cu" "B.Cu")
		(net "GND")
	)
	(via
		(at 116.092224 -23.647654)
		(size 0.508)
		(drill 0.254)
		(layers "F.Cu" "B.Cu")
		(net "GND")
	)
	(via
		(at 326.651112 -290.285932)
		(size 0.4064)
		(drill 0.2032)
		(layers "F.Cu" "B.Cu")
		(net "GND")
	)
	(via
		(at 439.100214 -268.735048)
		(size 0.4826)
		(drill 0.254)
		(layers "F.Cu" "B.Cu")
		(net "GND")
	)
	(via
		(at 197.3199 -295.9354)
		(size 0.4826)
		(drill 0.254)
		(layers "F.Cu" "B.Cu")
		(net "GND")
	)
	(via
		(at 347.801184 -287.856168)
		(size 0.4064)
		(drill 0.2032)
		(layers "F.Cu" "B.Cu")
		(net "GND")
	)
	(via
		(at 13.044932 -419.155118)
		(size 0.508)
		(drill 0.254)
		(layers "F.Cu" "B.Cu")
		(net "GND")
	)
	(via
		(at 27.867864 -209.235294)
		(size 0.4826)
		(drill 0.254)
		(layers "F.Cu" "B.Cu")
		(net "GND")
	)
	(via
		(at 331.051154 -232.334054)
		(size 0.4064)
		(drill 0.2032)
		(layers "F.Cu" "B.Cu")
		(net "GND")
	)
	(via
		(at 114.424714 -291.906198)
		(size 0.4064)
		(drill 0.2032)
		(layers "F.Cu" "B.Cu")
		(net "GND")
	)
	(via
		(at 353.989894 -392.999722)
		(size 0.4064)
		(drill 0.2032)
		(layers "F.Cu" "B.Cu")
		(net "GND")
	)
	(via
		(at 143.438626 -410.030168)
		(size 0.4064)
		(drill 0.2032)
		(layers "F.Cu" "B.Cu")
		(net "GND")
	)
	(via
		(at 76.44511 -154.83078)
		(size 0.508)
		(drill 0.254)
		(layers "F.Cu" "B.Cu")
		(net "GND")
	)
	(via
		(at 458.390752 -393.540234)
		(size 0.508)
		(drill 0.254)
		(layers "F.Cu" "B.Cu")
		(net "GND")
	)
	(via
		(at 262.584692 -420.79545)
		(size 0.508)
		(drill 0.254)
		(layers "F.Cu" "B.Cu")
		(net "GND")
	)
	(via
		(at 390.60755 -416.020504)
		(size 0.4572)
		(drill 0.254)
		(layers "F.Cu" "B.Cu")
		(net "GND")
	)
	(via
		(at 107.780582 -338.187538)
		(size 0.508)
		(drill 0.254)
		(layers "F.Cu" "B.Cu")
		(net "GND")
	)
	(via
		(at 334.228694 -420.318184)
		(size 0.4572)
		(drill 0.254)
		(layers "F.Cu" "B.Cu")
		(net "GND")
	)
	(via
		(at 412.367984 -234.735116)
		(size 0.4826)
		(drill 0.254)
		(layers "F.Cu" "B.Cu")
		(net "GND")
	)
	(via
		(at 329.941174 -294.335962)
		(size 0.4064)
		(drill 0.2032)
		(layers "F.Cu" "B.Cu")
		(net "GND")
	)
	(via
		(at 180.732176 -123.04268)
		(size 0.4572)
		(drill 0.254)
		(layers "F.Cu" "B.Cu")
		(net "GND")
	)
	(via
		(at 119.59463 -294.336216)
		(size 0.4064)
		(drill 0.2032)
		(layers "F.Cu" "B.Cu")
		(net "GND")
	)
	(via
		(at 403.57298 -383.00533)
		(size 0.508)
		(drill 0.254)
		(layers "F.Cu" "B.Cu")
		(net "GND")
	)
	(via
		(at 365.187992 -264.368026)
		(size 0.4064)
		(drill 0.2032)
		(layers "F.Cu" "B.Cu")
		(net "GND")
	)
	(via
		(at 336.521044 -284.616144)
		(size 0.4064)
		(drill 0.2032)
		(layers "F.Cu" "B.Cu")
		(net "GND")
	)
	(via
		(at 105.520998 -415.641028)
		(size 0.508)
		(drill 0.254)
		(layers "F.Cu" "B.Cu")
		(net "GND")
	)
	(via
		(at 442.5442 -272.135092)
		(size 0.4826)
		(drill 0.254)
		(layers "F.Cu" "B.Cu")
		(net "GND")
	)
	(via
		(at 219.439236 -70.336918)
		(size 0.508)
		(drill 0.254)
		(layers "F.Cu" "B.Cu")
		(net "GND")
	)
	(via
		(at 355.791008 -269.22603)
		(size 0.4064)
		(drill 0.2032)
		(layers "F.Cu" "B.Cu")
		(net "GND")
	)
	(via
		(at 33.144968 -351.736406)
		(size 0.508)
		(drill 0.254)
		(layers "F.Cu" "B.Cu")
		(net "GND")
	)
	(via
		(at 308.573424 -106.938572)
		(size 0.508)
		(drill 0.254)
		(layers "F.Cu" "B.Cu")
		(net "GND")
	)
	(via
		(at 441.980066 -396.11427)
		(size 0.508)
		(drill 0.254)
		(layers "F.Cu" "B.Cu")
		(net "GND")
	)
	(via
		(at 301.104808 -396.67815)
		(size 0.4064)
		(drill 0.2032)
		(layers "F.Cu" "B.Cu")
		(net "GND")
	)
	(via
		(at 294.18407 -346.302076)
		(size 0.49022)
		(drill 0.254)
		(layers "F.Cu" "B.Cu")
		(net "GND")
	)
	(via
		(at 354.931218 -416.547554)
		(size 0.508)
		(drill 0.254)
		(layers "F.Cu" "B.Cu")
		(net "GND")
	)
	(via
		(at 372.404894 -245.29415)
		(size 0.4064)
		(drill 0.2032)
		(layers "F.Cu" "B.Cu")
		(net "GND")
	)
	(via
		(at 102.211124 -275.706332)
		(size 0.4064)
		(drill 0.2032)
		(layers "F.Cu" "B.Cu")
		(net "GND")
	)
	(via
		(at 32.128714 -343.476834)
		(size 0.508)
		(drill 0.254)
		(layers "F.Cu" "B.Cu")
		(net "GND")
	)
	(via
		(at 44.340018 -263.635236)
		(size 0.4826)
		(drill 0.254)
		(layers "F.Cu" "B.Cu")
		(net "GND")
	)
	(via
		(at 132.284724 -278.946356)
		(size 0.4064)
		(drill 0.2032)
		(layers "F.Cu" "B.Cu")
		(net "GND")
	)
	(via
		(at 24.034496 -295.510458)
		(size 0.4826)
		(drill 0.254)
		(layers "F.Cu" "B.Cu")
		(net "GND")
	)
	(via
		(at 421.296338 -203.28509)
		(size 0.4826)
		(drill 0.254)
		(layers "F.Cu" "B.Cu")
		(net "GND")
	)
	(via
		(at 176.072038 -306.985416)
		(size 0.4826)
		(drill 0.254)
		(layers "F.Cu" "B.Cu")
		(net "GND")
	)
	(via
		(at 135.274812 -254.20447)
		(size 0.4064)
		(drill 0.2032)
		(layers "F.Cu" "B.Cu")
		(net "GND")
	)
	(via
		(at 83.41106 -287.046162)
		(size 0.4064)
		(drill 0.2032)
		(layers "F.Cu" "B.Cu")
		(net "GND")
	)
	(via
		(at 280.635964 -267.885164)
		(size 0.4826)
		(drill 0.254)
		(layers "F.Cu" "B.Cu")
		(net "GND")
	)
	(via
		(at 35.411664 -286.585406)
		(size 0.4826)
		(drill 0.254)
		(layers "F.Cu" "B.Cu")
		(net "GND")
	)
	(via
		(at 360.876596 -349.784924)
		(size 0.508)
		(drill 0.254)
		(layers "F.Cu" "B.Cu")
		(net "GND")
	)
	(via
		(at 35.411664 -199.8853)
		(size 0.4826)
		(drill 0.254)
		(layers "F.Cu" "B.Cu")
		(net "GND")
	)
	(via
		(at 141.854682 -242.864386)
		(size 0.4064)
		(drill 0.2032)
		(layers "F.Cu" "B.Cu")
		(net "GND")
	)
	(via
		(at 393.384786 -277.32609)
		(size 0.4064)
		(drill 0.2032)
		(layers "F.Cu" "B.Cu")
		(net "GND")
	)
	(via
		(at 142.96644 -380.83744)
		(size 0.508)
		(drill 0.254)
		(layers "F.Cu" "B.Cu")
		(net "GND")
	)
	(via
		(at 361.124754 -225.85426)
		(size 0.4064)
		(drill 0.2032)
		(layers "F.Cu" "B.Cu")
		(net "GND")
	)
	(via
		(at 340.194138 -217.776552)
		(size 0.508)
		(drill 0.254)
		(layers "F.Cu" "B.Cu")
		(net "GND")
	)
	(via
		(at 345.451176 -285.42615)
		(size 0.4064)
		(drill 0.2032)
		(layers "F.Cu" "B.Cu")
		(net "GND")
	)
	(via
		(at 20.32381 -274.685252)
		(size 0.4826)
		(drill 0.254)
		(layers "F.Cu" "B.Cu")
		(net "GND")
	)
	(via
		(at 85.820758 -333.82839)
		(size 0.49022)
		(drill 0.254)
		(layers "F.Cu" "B.Cu")
		(net "GND")
	)
	(via
		(at 32.695896 -249.18543)
		(size 0.4826)
		(drill 0.254)
		(layers "F.Cu" "B.Cu")
		(net "GND")
	)
	(via
		(at 388.714742 -412.84652)
		(size 0.4064)
		(drill 0.2032)
		(layers "F.Cu" "B.Cu")
		(net "GND")
	)
	(via
		(at 113.184686 -224.234502)
		(size 0.4064)
		(drill 0.2032)
		(layers "F.Cu" "B.Cu")
		(net "GND")
	)
	(via
		(at 85.761068 -295.956228)
		(size 0.4064)
		(drill 0.2032)
		(layers "F.Cu" "B.Cu")
		(net "GND")
	)
	(via
		(at 154.206194 -386.449062)
		(size 0.4064)
		(drill 0.2032)
		(layers "F.Cu" "B.Cu")
		(net "GND")
	)
	(via
		(at 381.634746 -279.756108)
		(size 0.4064)
		(drill 0.2032)
		(layers "F.Cu" "B.Cu")
		(net "GND")
	)
	(via
		(at 427.456092 -281.485086)
		(size 0.4826)
		(drill 0.254)
		(layers "F.Cu" "B.Cu")
		(net "GND")
	)
	(via
		(at 105.200958 -238.00435)
		(size 0.4064)
		(drill 0.2032)
		(layers "F.Cu" "B.Cu")
		(net "GND")
	)
	(via
		(at 83.88096 -295.956228)
		(size 0.4064)
		(drill 0.2032)
		(layers "F.Cu" "B.Cu")
		(net "GND")
	)
	(via
		(at 277.192232 -215.18499)
		(size 0.4826)
		(drill 0.254)
		(layers "F.Cu" "B.Cu")
		(net "GND")
	)
	(via
		(at 350.364552 -337.99526)
		(size 0.49022)
		(drill 0.254)
		(layers "F.Cu" "B.Cu")
		(net "GND")
	)
	(via
		(at 354.851208 -293.525956)
		(size 0.4064)
		(drill 0.2032)
		(layers "F.Cu" "B.Cu")
		(net "GND")
	)
	(via
		(at 386.504942 -240.434114)
		(size 0.4064)
		(drill 0.2032)
		(layers "F.Cu" "B.Cu")
		(net "GND")
	)
	(via
		(at 51.884072 -222.835216)
		(size 0.4826)
		(drill 0.254)
		(layers "F.Cu" "B.Cu")
		(net "GND")
	)
	(via
		(at 303.268126 -247.485154)
		(size 0.4826)
		(drill 0.254)
		(layers "F.Cu" "B.Cu")
		(net "GND")
	)
	(via
		(at 186.312048 -112.66297)
		(size 0.4572)
		(drill 0.254)
		(layers "F.Cu" "B.Cu")
		(net "GND")
	)
	(via
		(at 467.5378 -379.019054)
		(size 0.508)
		(drill 0.254)
		(layers "F.Cu" "B.Cu")
		(net "GND")
	)
	(via
		(at 51.884072 -241.535204)
		(size 0.4826)
		(drill 0.254)
		(layers "F.Cu" "B.Cu")
		(net "GND")
	)
	(via
		(at 9.352788 -370.60505)
		(size 0.508)
		(drill 0.254)
		(layers "F.Cu" "B.Cu")
		(net "GND")
	)
	(via
		(at 384.349498 -432.451256)
		(size 0.4572)
		(drill 0.2032)
		(layers "F.Cu" "B.Cu")
		(net "GND")
	)
	(via
		(at 436.117746 -202.01001)
		(size 0.4826)
		(drill 0.254)
		(layers "F.Cu" "B.Cu")
		(net "GND")
	)
	(via
		(at 58.545222 -171.934124)
		(size 0.508)
		(drill 0.254)
		(layers "F.Cu" "B.Cu")
		(net "GND")
	)
	(via
		(at 27.867864 -277.235412)
		(size 0.4826)
		(drill 0.254)
		(layers "F.Cu" "B.Cu")
		(net "GND")
	)
	(via
		(at 96.790256 -384.617722)
		(size 0.4064)
		(drill 0.2032)
		(layers "F.Cu" "B.Cu")
		(net "GND")
	)
	(via
		(at 342.801194 -255.824228)
		(size 0.4064)
		(drill 0.2032)
		(layers "F.Cu" "B.Cu")
		(net "GND")
	)
	(via
		(at 92.981018 -242.864386)
		(size 0.4064)
		(drill 0.2032)
		(layers "F.Cu" "B.Cu")
		(net "GND")
	)
	(via
		(at 408.244294 -391.23493)
		(size 0.4064)
		(drill 0.2032)
		(layers "F.Cu" "B.Cu")
		(net "GND")
	)
	(via
		(at 118.824756 -235.574332)
		(size 0.4064)
		(drill 0.2032)
		(layers "F.Cu" "B.Cu")
		(net "GND")
	)
	(via
		(at 113.48466 -291.906198)
		(size 0.4064)
		(drill 0.2032)
		(layers "F.Cu" "B.Cu")
		(net "GND")
	)
	(via
		(at 366.594898 -273.27606)
		(size 0.4064)
		(drill 0.2032)
		(layers "F.Cu" "B.Cu")
		(net "GND")
	)
	(via
		(at 431.55616 -278.93518)
		(size 0.4826)
		(drill 0.254)
		(layers "F.Cu" "B.Cu")
		(net "GND")
	)
	(via
		(at 313.668156 -380.54153)
		(size 0.508)
		(drill 0.254)
		(layers "F.Cu" "B.Cu")
		(net "GND")
	)
	(via
		(at 72.516746 -13.510514)
		(size 0.508)
		(drill 0.254)
		(layers "F.Cu" "B.Cu")
		(net "GND")
	)
	(via
		(at 407.45537 -413.480504)
		(size 0.4572)
		(drill 0.254)
		(layers "F.Cu" "B.Cu")
		(net "GND")
	)
	(via
		(at 110.371128 -246.914416)
		(size 0.4064)
		(drill 0.2032)
		(layers "F.Cu" "B.Cu")
		(net "GND")
	)
	(via
		(at 446.644268 -306.985162)
		(size 0.4826)
		(drill 0.254)
		(layers "F.Cu" "B.Cu")
		(net "GND")
	)
	(via
		(at 278.289766 -344.132408)
		(size 0.508)
		(drill 0.254)
		(layers "F.Cu" "B.Cu")
		(net "GND")
	)
	(via
		(at 382.94945 -413.480504)
		(size 0.4572)
		(drill 0.254)
		(layers "F.Cu" "B.Cu")
		(net "GND")
	)
	(via
		(at 73.953624 -5.43433)
		(size 0.508)
		(drill 0.254)
		(layers "F.Cu" "B.Cu")
		(net "GND")
	)
	(via
		(at 142.154656 -282.996386)
		(size 0.4064)
		(drill 0.2032)
		(layers "F.Cu" "B.Cu")
		(net "GND")
	)
	(via
		(at 126.644654 -285.426404)
		(size 0.4064)
		(drill 0.2032)
		(layers "F.Cu" "B.Cu")
		(net "GND")
	)
	(via
		(at 67.3354 -151.149812)
		(size 0.508)
		(drill 0.254)
		(layers "F.Cu" "B.Cu")
		(net "GND")
	)
	(via
		(at 376.562366 -392.999722)
		(size 0.4064)
		(drill 0.2032)
		(layers "F.Cu" "B.Cu")
		(net "GND")
	)
	(via
		(at 225.223578 -318.704468)
		(size 0.508)
		(drill 0.254)
		(layers "F.Cu" "B.Cu")
		(net "GND")
	)
	(via
		(at 230.886 -230.886)
		(size 0.508)
		(drill 0.254)
		(layers "F.Cu" "B.Cu")
		(net "GND")
	)
	(via
		(at 29.252164 -263.635236)
		(size 0.4826)
		(drill 0.254)
		(layers "F.Cu" "B.Cu")
		(net "GND")
	)
	(via
		(at 50.766472 -313.360308)
		(size 0.4826)
		(drill 0.254)
		(layers "F.Cu" "B.Cu")
		(net "GND")
	)
	(via
		(at 331.821028 -289.475926)
		(size 0.4064)
		(drill 0.2032)
		(layers "F.Cu" "B.Cu")
		(net "GND")
	)
	(via
		(at 130.349752 -429.147224)
		(size 0.4572)
		(drill 0.2032)
		(layers "F.Cu" "B.Cu")
		(net "GND")
	)
	(via
		(at 341.975186 -420.952168)
		(size 0.4064)
		(drill 0.2032)
		(layers "F.Cu" "B.Cu")
		(net "GND")
	)
	(via
		(at 121.474738 -274.896326)
		(size 0.4064)
		(drill 0.2032)
		(layers "F.Cu" "B.Cu")
		(net "GND")
	)
	(via
		(at 182.67553 -48.22571)
		(size 0.508)
		(drill 0.254)
		(layers "F.Cu" "B.Cu")
		(net "GND")
	)
	(via
		(at 342.046052 -396.710662)
		(size 0.4064)
		(drill 0.2032)
		(layers "F.Cu" "B.Cu")
		(net "GND")
	)
	(via
		(at 80.249776 -437.49976)
		(size 0.4572)
		(drill 0.2032)
		(layers "F.Cu" "B.Cu")
		(net "GND")
	)
	(via
		(at 299.82414 -310.384952)
		(size 0.4826)
		(drill 0.254)
		(layers "F.Cu" "B.Cu")
		(net "GND")
	)
	(via
		(at 66.927222 -173.839124)
		(size 0.6604)
		(drill 0.3302)
		(layers "F.Cu" "B.Cu")
		(net "GND")
	)
	(via
		(at 87.131144 -31.12135)
		(size 0.508)
		(drill 0.254)
		(layers "F.Cu" "B.Cu")
		(net "GND")
	)
	(via
		(at 290.27882 -13.509244)
		(size 0.508)
		(drill 0.254)
		(layers "F.Cu" "B.Cu")
		(net "GND")
	)
	(via
		(at 323.249544 -433.899564)
		(size 0.4572)
		(drill 0.2032)
		(layers "F.Cu" "B.Cu")
		(net "GND")
	)
	(via
		(at 36.795964 -316.33541)
		(size 0.4826)
		(drill 0.254)
		(layers "F.Cu" "B.Cu")
		(net "GND")
	)
	(via
		(at 303.816258 -402.284438)
		(size 0.4572)
		(drill 0.254)
		(layers "F.Cu" "B.Cu")
		(net "GND")
	)
	(via
		(at 139.504674 -224.234502)
		(size 0.4064)
		(drill 0.2032)
		(layers "F.Cu" "B.Cu")
		(net "GND")
	)
	(via
		(at 83.88096 -266.796266)
		(size 0.4064)
		(drill 0.2032)
		(layers "F.Cu" "B.Cu")
		(net "GND")
	)
	(via
		(at 31.385002 -6.598158)
		(size 0.508)
		(drill 0.254)
		(layers "F.Cu" "B.Cu")
		(net "GND")
	)
	(via
		(at 277.192232 -267.035026)
		(size 0.4826)
		(drill 0.254)
		(layers "F.Cu" "B.Cu")
		(net "GND")
	)
	(via
		(at 189.775846 -274.685252)
		(size 0.4826)
		(drill 0.254)
		(layers "F.Cu" "B.Cu")
		(net "GND")
	)
	(via
		(at 140.744702 -272.466308)
		(size 0.4064)
		(drill 0.2032)
		(layers "F.Cu" "B.Cu")
		(net "GND")
	)
	(via
		(at 307.918358 -413.480504)
		(size 0.4572)
		(drill 0.254)
		(layers "F.Cu" "B.Cu")
		(net "GND")
	)
	(via
		(at 342.801194 -233.14406)
		(size 0.4064)
		(drill 0.2032)
		(layers "F.Cu" "B.Cu")
		(net "GND")
	)
	(via
		(at 387.54431 -414.752536)
		(size 0.4572)
		(drill 0.254)
		(layers "F.Cu" "B.Cu")
		(net "GND")
	)
	(via
		(at 160.780984 -121.490486)
		(size 0.508)
		(drill 0.254)
		(layers "F.Cu" "B.Cu")
		(net "GND")
	)
	(via
		(at 112.054386 -268.005814)
		(size 0.4826)
		(drill 0.254)
		(layers "F.Cu" "B.Cu")
		(net "GND")
	)
	(via
		(at 383.21488 -229.904036)
		(size 0.4064)
		(drill 0.2032)
		(layers "F.Cu" "B.Cu")
		(net "GND")
	)
	(via
		(at 94.314772 -55.531766)
		(size 0.508)
		(drill 0.254)
		(layers "F.Cu" "B.Cu")
		(net "GND")
	)
	(via
		(at 53.723032 -411.936184)
		(size 0.4572)
		(drill 0.254)
		(layers "F.Cu" "B.Cu")
		(net "GND")
	)
	(via
		(at 370.484146 -183.14543)
		(size 0.49022)
		(drill 0.254)
		(layers "F.Cu" "B.Cu")
		(net "GND")
	)
	(via
		(at 246.0752 -287.031684)
		(size 0.508)
		(drill 0.254)
		(layers "F.Cu" "B.Cu")
		(net "GND")
	)
	(via
		(at 147.444206 -382.85293)
		(size 0.4064)
		(drill 0.2032)
		(layers "F.Cu" "B.Cu")
		(net "GND")
	)
	(via
		(at 81.544414 -391.830814)
		(size 0.4064)
		(drill 0.2032)
		(layers "F.Cu" "B.Cu")
		(net "GND")
	)
	(via
		(at 338.249514 -433.747164)
		(size 0.4572)
		(drill 0.2032)
		(layers "F.Cu" "B.Cu")
		(net "GND")
	)
	(via
		(at 437.715914 -286.585152)
		(size 0.4826)
		(drill 0.254)
		(layers "F.Cu" "B.Cu")
		(net "GND")
	)
	(via
		(at 124.294646 -278.13635)
		(size 0.4064)
		(drill 0.2032)
		(layers "F.Cu" "B.Cu")
		(net "GND")
	)
	(via
		(at 84.99094 -232.334308)
		(size 0.4064)
		(drill 0.2032)
		(layers "F.Cu" "B.Cu")
		(net "GND")
	)
	(via
		(at 153.233882 -106.614976)
		(size 0.508)
		(drill 0.254)
		(layers "F.Cu" "B.Cu")
		(net "GND")
	)
	(via
		(at 309.813452 -436.120794)
		(size 0.508)
		(drill 0.254)
		(layers "F.Cu" "B.Cu")
		(net "GND")
	)
	(via
		(at 66.52387 -166.94023)
		(size 0.49022)
		(drill 0.254)
		(layers "F.Cu" "B.Cu")
		(net "GND")
	)
	(via
		(at 426.85462 -349.165926)
		(size 0.508)
		(drill 0.254)
		(layers "F.Cu" "B.Cu")
		(net "GND")
	)
	(via
		(at 88.580976 -281.376374)
		(size 0.4064)
		(drill 0.2032)
		(layers "F.Cu" "B.Cu")
		(net "GND")
	)
	(via
		(at 124.770896 -369.03533)
		(size 0.508)
		(drill 0.254)
		(layers "F.Cu" "B.Cu")
		(net "GND")
	)
	(via
		(at 342.249506 -431.29962)
		(size 0.4572)
		(drill 0.2032)
		(layers "F.Cu" "B.Cu")
		(net "GND")
	)
	(via
		(at 378.514864 -233.14406)
		(size 0.4064)
		(drill 0.2032)
		(layers "F.Cu" "B.Cu")
		(net "GND")
	)
	(via
		(at 53.518562 -388.328662)
		(size 0.4064)
		(drill 0.2032)
		(layers "F.Cu" "B.Cu")
		(net "GND")
	)
	(via
		(at 321.249548 -432.451256)
		(size 0.4572)
		(drill 0.2032)
		(layers "F.Cu" "B.Cu")
		(net "GND")
	)
	(via
		(at 277.37562 -437.093614)
		(size 0.508)
		(drill 0.254)
		(layers "F.Cu" "B.Cu")
		(net "GND")
	)
	(via
		(at 329.47102 -295.145968)
		(size 0.4064)
		(drill 0.2032)
		(layers "F.Cu" "B.Cu")
		(net "GND")
	)
	(via
		(at 41.402762 -423.281348)
		(size 0.508)
		(drill 0.254)
		(layers "F.Cu" "B.Cu")
		(net "GND")
	)
	(via
		(at 119.018558 -405.098504)
		(size 0.4572)
		(drill 0.254)
		(layers "F.Cu" "B.Cu")
		(net "GND")
	)
	(via
		(at 61.108336 -405.098504)
		(size 0.4572)
		(drill 0.254)
		(layers "F.Cu" "B.Cu")
		(net "GND")
	)
	(via
		(at 58.317892 -407.638504)
		(size 0.4572)
		(drill 0.254)
		(layers "F.Cu" "B.Cu")
		(net "GND")
	)
	(via
		(at 442.5442 -301.885096)
		(size 0.4826)
		(drill 0.254)
		(layers "F.Cu" "B.Cu")
		(net "GND")
	)
	(via
		(at 58.043826 -305.285394)
		(size 0.4826)
		(drill 0.254)
		(layers "F.Cu" "B.Cu")
		(net "GND")
	)
	(via
		(at 346.481654 -420.318184)
		(size 0.4572)
		(drill 0.254)
		(layers "F.Cu" "B.Cu")
		(net "GND")
	)
	(via
		(at 284.243018 -394.070078)
		(size 0.508)
		(drill 0.254)
		(layers "F.Cu" "B.Cu")
		(net "GND")
	)
	(via
		(at 383.21488 -234.764072)
		(size 0.4064)
		(drill 0.2032)
		(layers "F.Cu" "B.Cu")
		(net "GND")
	)
	(via
		(at 84.249768 -435.0512)
		(size 0.4572)
		(drill 0.2032)
		(layers "F.Cu" "B.Cu")
		(net "GND")
	)
	(via
		(at 308.61635 -402.309838)
		(size 0.4572)
		(drill 0.254)
		(layers "F.Cu" "B.Cu")
		(net "GND")
	)
	(via
		(at 119.291354 -406.370536)
		(size 0.4572)
		(drill 0.254)
		(layers "F.Cu" "B.Cu")
		(net "GND")
	)
	(via
		(at 94.861126 -254.20447)
		(size 0.4064)
		(drill 0.2032)
		(layers "F.Cu" "B.Cu")
		(net "GND")
	)
	(via
		(at 339.511132 -232.334054)
		(size 0.4064)
		(drill 0.2032)
		(layers "F.Cu" "B.Cu")
		(net "GND")
	)
	(via
		(at 114.92992 -69.44868)
		(size 0.508)
		(drill 0.254)
		(layers "F.Cu" "B.Cu")
		(net "GND")
	)
	(via
		(at 403.845522 -7.215124)
		(size 0.508)
		(drill 0.254)
		(layers "F.Cu" "B.Cu")
		(net "GND")
	)
	(via
		(at 171.97197 -214.33536)
		(size 0.4826)
		(drill 0.254)
		(layers "F.Cu" "B.Cu")
		(net "GND")
	)
	(via
		(at 71.829676 -409.396184)
		(size 0.4572)
		(drill 0.254)
		(layers "F.Cu" "B.Cu")
		(net "GND")
	)
	(via
		(at 415.28492 -19.771106)
		(size 0.508)
		(drill 0.254)
		(layers "F.Cu" "B.Cu")
		(net "GND")
	)
	(via
		(at 190.370206 -353.309174)
		(size 0.49022)
		(drill 0.254)
		(layers "F.Cu" "B.Cu")
		(net "GND")
	)
	(via
		(at 439.100214 -280.634948)
		(size 0.4826)
		(drill 0.254)
		(layers "F.Cu" "B.Cu")
		(net "GND")
	)
	(via
		(at 36.63442 -351.862898)
		(size 0.508)
		(drill 0.254)
		(layers "F.Cu" "B.Cu")
		(net "GND")
	)
	(via
		(at 18.992342 -210.085432)
		(size 0.4826)
		(drill 0.254)
		(layers "F.Cu" "B.Cu")
		(net "GND")
	)
	(via
		(at 116.259356 -374.62333)
		(size 0.508)
		(drill 0.254)
		(layers "F.Cu" "B.Cu")
		(net "GND")
	)
	(via
		(at 343.504266 -415.38652)
		(size 0.4064)
		(drill 0.2032)
		(layers "F.Cu" "B.Cu")
		(net "GND")
	)
	(via
		(at 403.105112 -332.012798)
		(size 0.508)
		(drill 0.254)
		(layers "F.Cu" "B.Cu")
		(net "GND")
	)
	(via
		(at 292.280086 -196.485002)
		(size 0.4826)
		(drill 0.254)
		(layers "F.Cu" "B.Cu")
		(net "GND")
	)
	(via
		(at 422.627806 -295.935146)
		(size 0.4826)
		(drill 0.254)
		(layers "F.Cu" "B.Cu")
		(net "GND")
	)
	(via
		(at 168.527984 -261.935214)
		(size 0.4826)
		(drill 0.254)
		(layers "F.Cu" "B.Cu")
		(net "GND")
	)
	(via
		(at 423.663364 -350.715834)
		(size 0.49022)
		(drill 0.254)
		(layers "F.Cu" "B.Cu")
		(net "GND")
	)
	(via
		(at 328.188066 -415.38652)
		(size 0.4064)
		(drill 0.2032)
		(layers "F.Cu" "B.Cu")
		(net "GND")
	)
	(via
		(at 386.504942 -232.334054)
		(size 0.4064)
		(drill 0.2032)
		(layers "F.Cu" "B.Cu")
		(net "GND")
	)
	(via
		(at 289.564318 -203.28509)
		(size 0.4826)
		(drill 0.254)
		(layers "F.Cu" "B.Cu")
		(net "GND")
	)
	(via
		(at 135.777986 -404.46452)
		(size 0.4064)
		(drill 0.2032)
		(layers "F.Cu" "B.Cu")
		(net "GND")
	)
	(via
		(at 353.141026 -241.24412)
		(size 0.4064)
		(drill 0.2032)
		(layers "F.Cu" "B.Cu")
		(net "GND")
	)
	(via
		(at 55.065676 -7.215124)
		(size 0.508)
		(drill 0.254)
		(layers "F.Cu" "B.Cu")
		(net "GND")
	)
	(via
		(at 50.766472 -210.510374)
		(size 0.4826)
		(drill 0.254)
		(layers "F.Cu" "B.Cu")
		(net "GND")
	)
	(via
		(at 351.261172 -249.34418)
		(size 0.4064)
		(drill 0.2032)
		(layers "F.Cu" "B.Cu")
		(net "GND")
	)
	(via
		(at 421.542972 -167.391334)
		(size 0.49022)
		(drill 0.254)
		(layers "F.Cu" "B.Cu")
		(net "GND")
	)
	(via
		(at 352.785172 -428.721012)
		(size 0.508)
		(drill 0.254)
		(layers "F.Cu" "B.Cu")
		(net "GND")
	)
	(via
		(at 44.843954 -16.979138)
		(size 0.508)
		(drill 0.254)
		(layers "F.Cu" "B.Cu")
		(net "GND")
	)
	(via
		(at 81.230978 -224.234502)
		(size 0.4064)
		(drill 0.2032)
		(layers "F.Cu" "B.Cu")
		(net "GND")
	)
	(via
		(at 328.061066 -291.095938)
		(size 0.4064)
		(drill 0.2032)
		(layers "F.Cu" "B.Cu")
		(net "GND")
	)
	(via
		(at 116.56187 -169.935144)
		(size 0.49022)
		(drill 0.254)
		(layers "F.Cu" "B.Cu")
		(net "GND")
	)
	(via
		(at 177.189638 -229.210362)
		(size 0.4826)
		(drill 0.254)
		(layers "F.Cu" "B.Cu")
		(net "GND")
	)
	(via
		(at 66.061844 -410.030168)
		(size 0.4064)
		(drill 0.2032)
		(layers "F.Cu" "B.Cu")
		(net "GND")
	)
	(via
		(at 164.979604 -434.155596)
		(size 0.508)
		(drill 0.254)
		(layers "F.Cu" "B.Cu")
		(net "GND")
	)
	(via
		(at 450.262752 -392.143234)
		(size 0.508)
		(drill 0.254)
		(layers "F.Cu" "B.Cu")
		(net "GND")
	)
	(via
		(at 438.64911 -0.762254)
		(size 0.508)
		(drill 0.254)
		(layers "F.Cu" "B.Cu")
		(net "GND")
	)
	(via
		(at 85.975444 -404.46452)
		(size 0.4064)
		(drill 0.2032)
		(layers "F.Cu" "B.Cu")
		(net "GND")
	)
	(via
		(at 341.390986 -243.674138)
		(size 0.4064)
		(drill 0.2032)
		(layers "F.Cu" "B.Cu")
		(net "GND")
	)
	(via
		(at 143.56461 -282.18638)
		(size 0.4064)
		(drill 0.2032)
		(layers "F.Cu" "B.Cu")
		(net "GND")
	)
	(via
		(at 17.608042 -199.035416)
		(size 0.4826)
		(drill 0.254)
		(layers "F.Cu" "B.Cu")
		(net "GND")
	)
	(via
		(at 178.249834 -343.404952)
		(size 0.508)
		(drill 0.254)
		(layers "F.Cu" "B.Cu")
		(net "GND")
	)
	(via
		(at 40.23995 -234.73537)
		(size 0.4826)
		(drill 0.254)
		(layers "F.Cu" "B.Cu")
		(net "GND")
	)
	(via
		(at 91.871038 -265.98626)
		(size 0.4064)
		(drill 0.2032)
		(layers "F.Cu" "B.Cu")
		(net "GND")
	)
	(via
		(at 358.311196 -243.674138)
		(size 0.4064)
		(drill 0.2032)
		(layers "F.Cu" "B.Cu")
		(net "GND")
	)
	(via
		(at 273.092164 -206.685134)
		(size 0.4826)
		(drill 0.254)
		(layers "F.Cu" "B.Cu")
		(net "GND")
	)
	(via
		(at 203.532232 -303.585372)
		(size 0.4826)
		(drill 0.254)
		(layers "F.Cu" "B.Cu")
		(net "GND")
	)
	(via
		(at 139.974828 -231.524302)
		(size 0.4064)
		(drill 0.2032)
		(layers "F.Cu" "B.Cu")
		(net "GND")
	)
	(via
		(at 308.05501 -346.317316)
		(size 0.49022)
		(drill 0.254)
		(layers "F.Cu" "B.Cu")
		(net "GND")
	)
	(via
		(at 82.249772 -427.699678)
		(size 0.4572)
		(drill 0.2032)
		(layers "F.Cu" "B.Cu")
		(net "GND")
	)
	(via
		(at 418.358066 -12.37488)
		(size 0.508)
		(drill 0.254)
		(layers "F.Cu" "B.Cu")
		(net "GND")
	)
	(via
		(at 369.584732 -232.334054)
		(size 0.4064)
		(drill 0.2032)
		(layers "F.Cu" "B.Cu")
		(net "GND")
	)
	(via
		(at 400.789902 -340.772242)
		(size 0.508)
		(drill 0.254)
		(layers "F.Cu" "B.Cu")
		(net "GND")
	)
	(via
		(at 110.671102 -291.906198)
		(size 0.4064)
		(drill 0.2032)
		(layers "F.Cu" "B.Cu")
		(net "GND")
	)
	(via
		(at 337.930998 -265.986006)
		(size 0.4064)
		(drill 0.2032)
		(layers "F.Cu" "B.Cu")
		(net "GND")
	)
	(via
		(at 182.67553 -46.957742)
		(size 0.508)
		(drill 0.254)
		(layers "F.Cu" "B.Cu")
		(net "GND")
	)
	(via
		(at 308.846474 -35.94862)
		(size 0.508)
		(drill 0.254)
		(layers "F.Cu" "B.Cu")
		(net "GND")
	)
	(via
		(at 243.293392 -421.48125)
		(size 0.508)
		(drill 0.254)
		(layers "F.Cu" "B.Cu")
		(net "GND")
	)
	(via
		(at 259.029962 -55.397146)
		(size 0.508)
		(drill 0.254)
		(layers "F.Cu" "B.Cu")
		(net "GND")
	)
	(via
		(at 95.1611 -282.996386)
		(size 0.4064)
		(drill 0.2032)
		(layers "F.Cu" "B.Cu")
		(net "GND")
	)
	(via
		(at 124.212604 -160.050734)
		(size 0.508)
		(drill 0.254)
		(layers "F.Cu" "B.Cu")
		(net "GND")
	)
	(via
		(at 164.427916 -225.385376)
		(size 0.4826)
		(drill 0.254)
		(layers "F.Cu" "B.Cu")
		(net "GND")
	)
	(via
		(at 199.8218 -229.210362)
		(size 0.4826)
		(drill 0.254)
		(layers "F.Cu" "B.Cu")
		(net "GND")
	)
	(via
		(at 194.604132 -264.485374)
		(size 0.4826)
		(drill 0.254)
		(layers "F.Cu" "B.Cu")
		(net "GND")
	)
	(via
		(at 30.786578 -346.365322)
		(size 0.49022)
		(drill 0.254)
		(layers "F.Cu" "B.Cu")
		(net "GND")
	)
	(via
		(at 235.0008 -284.948122)
		(size 0.508)
		(drill 0.254)
		(layers "F.Cu" "B.Cu")
		(net "GND")
	)
	(via
		(at 187.833 -342.679274)
		(size 0.508)
		(drill 0.254)
		(layers "F.Cu" "B.Cu")
		(net "GND")
	)
	(via
		(at 304.423826 -192.21831)
		(size 0.4826)
		(drill 0.254)
		(layers "F.Cu" "B.Cu")
		(net "GND")
	)
	(via
		(at 458.00391 -49.816258)
		(size 0.508)
		(drill 0.254)
		(layers "F.Cu" "B.Cu")
		(net "GND")
	)
	(via
		(at 321.21348 -331.750924)
		(size 0.508)
		(drill 0.254)
		(layers "F.Cu" "B.Cu")
		(net "GND")
	)
	(via
		(at 70.298056 -413.204152)
		(size 0.4572)
		(drill 0.254)
		(layers "F.Cu" "B.Cu")
		(net "GND")
	)
	(via
		(at 46.367192 -37.40404)
		(size 0.508)
		(drill 0.254)
		(layers "F.Cu" "B.Cu")
		(net "GND")
	)
	(via
		(at 394.349478 -433.899564)
		(size 0.4572)
		(drill 0.2032)
		(layers "F.Cu" "B.Cu")
		(net "GND")
	)
	(via
		(at 283.443426 -348.704662)
		(size 0.49022)
		(drill 0.254)
		(layers "F.Cu" "B.Cu")
		(net "GND")
	)
	(via
		(at 123.824746 -288.666174)
		(size 0.4064)
		(drill 0.2032)
		(layers "F.Cu" "B.Cu")
		(net "GND")
	)
	(via
		(at 30.315662 -430.769014)
		(size 0.508)
		(drill 0.254)
		(layers "F.Cu" "B.Cu")
		(net "GND")
	)
	(via
		(at 142.154656 -286.23641)
		(size 0.4064)
		(drill 0.2032)
		(layers "F.Cu" "B.Cu")
		(net "GND")
	)
	(via
		(at 418.746178 -396.710662)
		(size 0.4064)
		(drill 0.2032)
		(layers "F.Cu" "B.Cu")
		(net "GND")
	)
	(via
		(at 169.113708 -419.693598)
		(size 0.508)
		(drill 0.254)
		(layers "F.Cu" "B.Cu")
		(net "GND")
	)
	(via
		(at 55.328058 -217.735404)
		(size 0.4826)
		(drill 0.254)
		(layers "F.Cu" "B.Cu")
		(net "GND")
	)
	(via
		(at 454.188068 -263.634982)
		(size 0.4826)
		(drill 0.254)
		(layers "F.Cu" "B.Cu")
		(net "GND")
	)
	(via
		(at 108.097066 -180.111146)
		(size 0.49022)
		(drill 0.254)
		(layers "F.Cu" "B.Cu")
		(net "GND")
	)
	(via
		(at 256.21488 -36.882324)
		(size 0.508)
		(drill 0.254)
		(layers "F.Cu" "B.Cu")
		(net "GND")
	)
	(via
		(at 338.172044 -382.34493)
		(size 0.508)
		(drill 0.254)
		(layers "F.Cu" "B.Cu")
		(net "GND")
	)
	(via
		(at 2.76225 -143.693134)
		(size 0.508)
		(drill 0.254)
		(layers "F.Cu" "B.Cu")
		(net "GND")
	)
	(via
		(at 331.051154 -222.614236)
		(size 0.4064)
		(drill 0.2032)
		(layers "F.Cu" "B.Cu")
		(net "GND")
	)
	(via
		(at 114.894614 -287.856422)
		(size 0.4064)
		(drill 0.2032)
		(layers "F.Cu" "B.Cu")
		(net "GND")
	)
	(via
		(at 306.212494 -193.99631)
		(size 0.4826)
		(drill 0.254)
		(layers "F.Cu" "B.Cu")
		(net "GND")
	)
	(via
		(at 80.120998 -289.47618)
		(size 0.4064)
		(drill 0.2032)
		(layers "F.Cu" "B.Cu")
		(net "GND")
	)
	(via
		(at 370.484146 -183.896508)
		(size 0.49022)
		(drill 0.254)
		(layers "F.Cu" "B.Cu")
		(net "GND")
	)
	(via
		(at 305.016408 -391.23493)
		(size 0.4064)
		(drill 0.2032)
		(layers "F.Cu" "B.Cu")
		(net "GND")
	)
	(via
		(at 112.6236 -62.96152)
		(size 0.508)
		(drill 0.254)
		(layers "F.Cu" "B.Cu")
		(net "GND")
	)
	(via
		(at 389.845296 -398.542002)
		(size 0.4064)
		(drill 0.2032)
		(layers "F.Cu" "B.Cu")
		(net "GND")
	)
	(via
		(at 358.61117 -285.42615)
		(size 0.4064)
		(drill 0.2032)
		(layers "F.Cu" "B.Cu")
		(net "GND")
	)
	(via
		(at 48.95723 -433.604924)
		(size 0.508)
		(drill 0.254)
		(layers "F.Cu" "B.Cu")
		(net "GND")
	)
	(via
		(at 21.91004 -6.598158)
		(size 0.508)
		(drill 0.254)
		(layers "F.Cu" "B.Cu")
		(net "GND")
	)
	(via
		(at 138.841226 -404.46452)
		(size 0.4064)
		(drill 0.2032)
		(layers "F.Cu" "B.Cu")
		(net "GND")
	)
	(via
		(at 328.188828 -42.176954)
		(size 0.508)
		(drill 0.254)
		(layers "F.Cu" "B.Cu")
		(net "GND")
	)
	(via
		(at 329.6412 -234.764072)
		(size 0.4064)
		(drill 0.2032)
		(layers "F.Cu" "B.Cu")
		(net "GND")
	)
	(via
		(at 330.070968 -399.314924)
		(size 0.508)
		(drill 0.254)
		(layers "F.Cu" "B.Cu")
		(net "GND")
	)
	(via
		(at 373.486934 -416.020504)
		(size 0.4572)
		(drill 0.254)
		(layers "F.Cu" "B.Cu")
		(net "GND")
	)
	(via
		(at 108.832142 -258.795266)
		(size 0.4826)
		(drill 0.254)
		(layers "F.Cu" "B.Cu")
		(net "GND")
	)
	(via
		(at 427.456092 -272.135092)
		(size 0.4826)
		(drill 0.254)
		(layers "F.Cu" "B.Cu")
		(net "GND")
	)
	(via
		(at 67.234816 -413.204152)
		(size 0.4572)
		(drill 0.254)
		(layers "F.Cu" "B.Cu")
		(net "GND")
	)
	(via
		(at 164.427916 -283.185362)
		(size 0.4826)
		(drill 0.254)
		(layers "F.Cu" "B.Cu")
		(net "GND")
	)
	(via
		(at 24.980138 -18.503138)
		(size 0.508)
		(drill 0.254)
		(layers "F.Cu" "B.Cu")
		(net "GND")
	)
	(via
		(at 411.349698 -433.899564)
		(size 0.4572)
		(drill 0.2032)
		(layers "F.Cu" "B.Cu")
		(net "GND")
	)
	(via
		(at 379.613414 -416.020504)
		(size 0.4572)
		(drill 0.254)
		(layers "F.Cu" "B.Cu")
		(net "GND")
	)
	(via
		(at 115.834668 -276.516338)
		(size 0.4064)
		(drill 0.2032)
		(layers "F.Cu" "B.Cu")
		(net "GND")
	)
	(via
		(at 317.249556 -426.54728)
		(size 0.4572)
		(drill 0.2032)
		(layers "F.Cu" "B.Cu")
		(net "GND")
	)
	(via
		(at 107.38104 -295.956228)
		(size 0.4064)
		(drill 0.2032)
		(layers "F.Cu" "B.Cu")
		(net "GND")
	)
	(via
		(at 329.6412 -233.14406)
		(size 0.4064)
		(drill 0.2032)
		(layers "F.Cu" "B.Cu")
		(net "GND")
	)
	(via
		(at 105.031032 -274.08632)
		(size 0.4064)
		(drill 0.2032)
		(layers "F.Cu" "B.Cu")
		(net "GND")
	)
	(via
		(at 433.906168 -349.205042)
		(size 0.49022)
		(drill 0.254)
		(layers "F.Cu" "B.Cu")
		(net "GND")
	)
	(via
		(at 106.91114 -277.326344)
		(size 0.4064)
		(drill 0.2032)
		(layers "F.Cu" "B.Cu")
		(net "GND")
	)
	(via
		(at 417.18738 -383.00533)
		(size 0.508)
		(drill 0.254)
		(layers "F.Cu" "B.Cu")
		(net "GND")
	)
	(via
		(at 2.76225 -383.977134)
		(size 0.508)
		(drill 0.254)
		(layers "F.Cu" "B.Cu")
		(net "GND")
	)
	(via
		(at 413.752284 -278.085042)
		(size 0.4826)
		(drill 0.254)
		(layers "F.Cu" "B.Cu")
		(net "GND")
	)
	(via
		(at 375.716546 -402.309838)
		(size 0.4572)
		(drill 0.254)
		(layers "F.Cu" "B.Cu")
		(net "GND")
	)
	(via
		(at 330.882244 -379.88113)
		(size 0.508)
		(drill 0.254)
		(layers "F.Cu" "B.Cu")
		(net "GND")
	)
	(via
		(at 85.144356 -393.927838)
		(size 0.4572)
		(drill 0.254)
		(layers "F.Cu" "B.Cu")
		(net "GND")
	)
	(via
		(at 329.633834 -419.046152)
		(size 0.4572)
		(drill 0.254)
		(layers "F.Cu" "B.Cu")
		(net "GND")
	)
	(via
		(at 45.655738 -7.215124)
		(size 0.508)
		(drill 0.254)
		(layers "F.Cu" "B.Cu")
		(net "GND")
	)
	(via
		(at 340.921086 -238.004096)
		(size 0.4064)
		(drill 0.2032)
		(layers "F.Cu" "B.Cu")
		(net "GND")
	)
	(via
		(at 197.3199 -211.7852)
		(size 0.4826)
		(drill 0.254)
		(layers "F.Cu" "B.Cu")
		(net "GND")
	)
	(via
		(at 98.451162 -264.366248)
		(size 0.4064)
		(drill 0.2032)
		(layers "F.Cu" "B.Cu")
		(net "GND")
	)
	(via
		(at 140.444728 -233.95432)
		(size 0.4064)
		(drill 0.2032)
		(layers "F.Cu" "B.Cu")
		(net "GND")
	)
	(via
		(at 307.368194 -318.035178)
		(size 0.4826)
		(drill 0.254)
		(layers "F.Cu" "B.Cu")
		(net "GND")
	)
	(via
		(at 99.8093 -334.08112)
		(size 0.508)
		(drill 0.254)
		(layers "F.Cu" "B.Cu")
		(net "GND")
	)
	(via
		(at 21.70811 -289.98545)
		(size 0.4826)
		(drill 0.254)
		(layers "F.Cu" "B.Cu")
		(net "GND")
	)
	(via
		(at 386.349494 -436.347362)
		(size 0.4572)
		(drill 0.2032)
		(layers "F.Cu" "B.Cu")
		(net "GND")
	)
	(via
		(at 51.884072 -308.685438)
		(size 0.4826)
		(drill 0.254)
		(layers "F.Cu" "B.Cu")
		(net "GND")
	)
	(via
		(at 49.168304 -231.335326)
		(size 0.4826)
		(drill 0.254)
		(layers "F.Cu" "B.Cu")
		(net "GND")
	)
	(via
		(at 364.884716 -251.774198)
		(size 0.4064)
		(drill 0.2032)
		(layers "F.Cu" "B.Cu")
		(net "GND")
	)
	(via
		(at 130.574796 -242.864386)
		(size 0.4064)
		(drill 0.2032)
		(layers "F.Cu" "B.Cu")
		(net "GND")
	)
	(via
		(at 92.101924 -404.46452)
		(size 0.4064)
		(drill 0.2032)
		(layers "F.Cu" "B.Cu")
		(net "GND")
	)
	(via
		(at 349.851218 -229.094284)
		(size 0.4064)
		(drill 0.2032)
		(layers "F.Cu" "B.Cu")
		(net "GND")
	)
	(via
		(at 90.16111 -244.484398)
		(size 0.4064)
		(drill 0.2032)
		(layers "F.Cu" "B.Cu")
		(net "GND")
	)
	(via
		(at 334.341216 -247.724168)
		(size 0.4064)
		(drill 0.2032)
		(layers "F.Cu" "B.Cu")
		(net "GND")
	)
	(via
		(at 51.884072 -299.335444)
		(size 0.4826)
		(drill 0.254)
		(layers "F.Cu" "B.Cu")
		(net "GND")
	)
	(via
		(at 127.114808 -268.416278)
		(size 0.4064)
		(drill 0.2032)
		(layers "F.Cu" "B.Cu")
		(net "GND")
	)
	(via
		(at 431.55616 -280.634948)
		(size 0.4826)
		(drill 0.254)
		(layers "F.Cu" "B.Cu")
		(net "GND")
	)
	(via
		(at 428.557182 -342.49868)
		(size 0.508)
		(drill 0.254)
		(layers "F.Cu" "B.Cu")
		(net "GND")
	)
	(via
		(at 370.916454 -400.212814)
		(size 0.4064)
		(drill 0.2032)
		(layers "F.Cu" "B.Cu")
		(net "GND")
	)
	(via
		(at 446.644268 -244.934994)
		(size 0.4826)
		(drill 0.254)
		(layers "F.Cu" "B.Cu")
		(net "GND")
	)
	(via
		(at 322.177156 -376.75693)
		(size 0.508)
		(drill 0.254)
		(layers "F.Cu" "B.Cu")
		(net "GND")
	)
	(via
		(at 413.890206 -392.999722)
		(size 0.4064)
		(drill 0.2032)
		(layers "F.Cu" "B.Cu")
		(net "GND")
	)
	(via
		(at 427.456092 -216.035128)
		(size 0.4826)
		(drill 0.254)
		(layers "F.Cu" "B.Cu")
		(net "GND")
	)
	(via
		(at 129.651506 -412.570168)
		(size 0.4064)
		(drill 0.2032)
		(layers "F.Cu" "B.Cu")
		(net "GND")
	)
	(via
		(at 414.244282 -391.23493)
		(size 0.4064)
		(drill 0.2032)
		(layers "F.Cu" "B.Cu")
		(net "GND")
	)
	(via
		(at 16.490442 -239.410494)
		(size 0.4826)
		(drill 0.254)
		(layers "F.Cu" "B.Cu")
		(net "GND")
	)
	(via
		(at 305.918362 -396.710662)
		(size 0.4064)
		(drill 0.2032)
		(layers "F.Cu" "B.Cu")
		(net "GND")
	)
	(via
		(at 37.199062 -17.613122)
		(size 0.508)
		(drill 0.254)
		(layers "F.Cu" "B.Cu")
		(net "GND")
	)
	(via
		(at 404.346156 -396.710662)
		(size 0.4064)
		(drill 0.2032)
		(layers "F.Cu" "B.Cu")
		(net "GND")
	)
	(via
		(at 90.650314 -332.39456)
		(size 0.508)
		(drill 0.254)
		(layers "F.Cu" "B.Cu")
		(net "GND")
	)
	(via
		(at 101.767386 -338.789264)
		(size 0.49022)
		(drill 0.254)
		(layers "F.Cu" "B.Cu")
		(net "GND")
	)
	(via
		(at 348.013274 -417.778184)
		(size 0.4572)
		(drill 0.254)
		(layers "F.Cu" "B.Cu")
		(net "GND")
	)
	(via
		(at 93.545152 -405.098504)
		(size 0.4572)
		(drill 0.254)
		(layers "F.Cu" "B.Cu")
		(net "GND")
	)
	(via
		(at 31.613094 -438.433464)
		(size 0.508)
		(drill 0.254)
		(layers "F.Cu" "B.Cu")
		(net "GND")
	)
	(via
		(at 364.884716 -232.334054)
		(size 0.4064)
		(drill 0.2032)
		(layers "F.Cu" "B.Cu")
		(net "GND")
	)
	(via
		(at 379.613414 -414.752536)
		(size 0.4572)
		(drill 0.254)
		(layers "F.Cu" "B.Cu")
		(net "GND")
	)
	(via
		(at 94.577154 -337.017614)
		(size 0.49022)
		(drill 0.254)
		(layers "F.Cu" "B.Cu")
		(net "GND")
	)
	(via
		(at 338.101178 -239.624108)
		(size 0.4064)
		(drill 0.2032)
		(layers "F.Cu" "B.Cu")
		(net "GND")
	)
	(via
		(at 157.581854 -413.204152)
		(size 0.4572)
		(drill 0.254)
		(layers "F.Cu" "B.Cu")
		(net "GND")
	)
	(via
		(at 403.08784 -382.34493)
		(size 0.508)
		(drill 0.254)
		(layers "F.Cu" "B.Cu")
		(net "GND")
	)
	(via
		(at 121.852436 -373.30253)
		(size 0.508)
		(drill 0.254)
		(layers "F.Cu" "B.Cu")
		(net "GND")
	)
	(via
		(at 266.70381 -192.21831)
		(size 0.4826)
		(drill 0.254)
		(layers "F.Cu" "B.Cu")
		(net "GND")
	)
	(via
		(at 407.641298 -166.605458)
		(size 0.49022)
		(drill 0.254)
		(layers "F.Cu" "B.Cu")
		(net "GND")
	)
	(via
		(at 352.671126 -240.434114)
		(size 0.4064)
		(drill 0.2032)
		(layers "F.Cu" "B.Cu")
		(net "GND")
	)
	(via
		(at 96.20631 -185.276998)
		(size 0.508)
		(drill 0.254)
		(layers "F.Cu" "B.Cu")
		(net "GND")
	)
	(via
		(at 384.259074 -421.535352)
		(size 0.4572)
		(drill 0.254)
		(layers "F.Cu" "B.Cu")
		(net "GND")
	)
	(via
		(at 149.650958 -403.830536)
		(size 0.4572)
		(drill 0.254)
		(layers "F.Cu" "B.Cu")
		(net "GND")
	)
	(via
		(at 383.514854 -279.756108)
		(size 0.4064)
		(drill 0.2032)
		(layers "F.Cu" "B.Cu")
		(net "GND")
	)
	(via
		(at 372.704868 -287.045908)
		(size 0.4064)
		(drill 0.2032)
		(layers "F.Cu" "B.Cu")
		(net "GND")
	)
	(via
		(at 328.188828 -41.160954)
		(size 0.508)
		(drill 0.254)
		(layers "F.Cu" "B.Cu")
		(net "GND")
	)
	(via
		(at 348.449138 -167.977312)
		(size 0.508)
		(drill 0.254)
		(layers "F.Cu" "B.Cu")
		(net "GND")
	)
	(via
		(at 363.634274 -179.710588)
		(size 0.49022)
		(drill 0.254)
		(layers "F.Cu" "B.Cu")
		(net "GND")
	)
	(via
		(at 338.101178 -246.104156)
		(size 0.4064)
		(drill 0.2032)
		(layers "F.Cu" "B.Cu")
		(net "GND")
	)
	(via
		(at 100.955094 -259.73024)
		(size 0.4826)
		(drill 0.254)
		(layers "F.Cu" "B.Cu")
		(net "GND")
	)
	(via
		(at 82.823812 -409.396184)
		(size 0.4572)
		(drill 0.254)
		(layers "F.Cu" "B.Cu")
		(net "GND")
	)
	(via
		(at 152.244298 -391.830814)
		(size 0.4064)
		(drill 0.2032)
		(layers "F.Cu" "B.Cu")
		(net "GND")
	)
	(via
		(at 120.822974 -413.204152)
		(size 0.4572)
		(drill 0.254)
		(layers "F.Cu" "B.Cu")
		(net "GND")
	)
	(via
		(at 339.811106 -267.606018)
		(size 0.4064)
		(drill 0.2032)
		(layers "F.Cu" "B.Cu")
		(net "GND")
	)
	(via
		(at 339.511132 -253.39421)
		(size 0.4064)
		(drill 0.2032)
		(layers "F.Cu" "B.Cu")
		(net "GND")
	)
	(via
		(at 353.490784 -376.75693)
		(size 0.508)
		(drill 0.254)
		(layers "F.Cu" "B.Cu")
		(net "GND")
	)
	(via
		(at 265.54811 -311.23509)
		(size 0.4826)
		(drill 0.254)
		(layers "F.Cu" "B.Cu")
		(net "GND")
	)
	(via
		(at 298.354496 -379.88113)
		(size 0.508)
		(drill 0.254)
		(layers "F.Cu" "B.Cu")
		(net "GND")
	)
	(via
		(at 158.895796 -38.144958)
		(size 0.508)
		(drill 0.254)
		(layers "F.Cu" "B.Cu")
		(net "GND")
	)
	(via
		(at 360.09326 -336.499962)
		(size 0.508)
		(drill 0.254)
		(layers "F.Cu" "B.Cu")
		(net "GND")
	)
	(via
		(at 157.349698 -436.051198)
		(size 0.4572)
		(drill 0.2032)
		(layers "F.Cu" "B.Cu")
		(net "GND")
	)
	(via
		(at 351.943924 -402.309838)
		(size 0.4572)
		(drill 0.254)
		(layers "F.Cu" "B.Cu")
		(net "GND")
	)
	(via
		(at 384.11658 -402.309838)
		(size 0.4572)
		(drill 0.254)
		(layers "F.Cu" "B.Cu")
		(net "GND")
	)
	(via
		(at 342.547194 -308.092602)
		(size 0.508)
		(drill 0.254)
		(layers "F.Cu" "B.Cu")
		(net "GND")
	)
	(via
		(at 370.478558 -394.831062)
		(size 0.4064)
		(drill 0.2032)
		(layers "F.Cu" "B.Cu")
		(net "GND")
	)
	(via
		(at 183.225694 -330.872084)
		(size 0.508)
		(drill 0.254)
		(layers "F.Cu" "B.Cu")
		(net "GND")
	)
	(via
		(at 273.092164 -208.385156)
		(size 0.4826)
		(drill 0.254)
		(layers "F.Cu" "B.Cu")
		(net "GND")
	)
	(via
		(at 371.762274 -392.999722)
		(size 0.4064)
		(drill 0.2032)
		(layers "F.Cu" "B.Cu")
		(net "GND")
	)
	(via
		(at 368.004852 -274.086066)
		(size 0.4064)
		(drill 0.2032)
		(layers "F.Cu" "B.Cu")
		(net "GND")
	)
	(via
		(at 331.521054 -255.824228)
		(size 0.4064)
		(drill 0.2032)
		(layers "F.Cu" "B.Cu")
		(net "GND")
	)
	(via
		(at 329.6412 -247.724168)
		(size 0.4064)
		(drill 0.2032)
		(layers "F.Cu" "B.Cu")
		(net "GND")
	)
	(via
		(at 83.41106 -277.326344)
		(size 0.4064)
		(drill 0.2032)
		(layers "F.Cu" "B.Cu")
		(net "GND")
	)
	(via
		(at 97.511108 -285.426404)
		(size 0.4064)
		(drill 0.2032)
		(layers "F.Cu" "B.Cu")
		(net "GND")
	)
	(via
		(at 354.34524 -260.28015)
		(size 0.4826)
		(drill 0.254)
		(layers "F.Cu" "B.Cu")
		(net "GND")
	)
	(via
		(at 70.12559 -383.452116)
		(size 0.508)
		(drill 0.254)
		(layers "F.Cu" "B.Cu")
		(net "GND")
	)
	(via
		(at 372.853204 -259.729986)
		(size 0.4826)
		(drill 0.254)
		(layers "F.Cu" "B.Cu")
		(net "GND")
	)
	(via
		(at 287.570672 -411.69844)
		(size 0.508)
		(drill 0.254)
		(layers "F.Cu" "B.Cu")
		(net "GND")
	)
	(via
		(at 346.208858 -416.020504)
		(size 0.4572)
		(drill 0.254)
		(layers "F.Cu" "B.Cu")
		(net "GND")
	)
	(via
		(at 136.34974 -434.899562)
		(size 0.4572)
		(drill 0.2032)
		(layers "F.Cu" "B.Cu")
		(net "GND")
	)
	(via
		(at 382.349502 -426.69968)
		(size 0.4572)
		(drill 0.2032)
		(layers "F.Cu" "B.Cu")
		(net "GND")
	)
	(via
		(at 413.752284 -219.435172)
		(size 0.4826)
		(drill 0.254)
		(layers "F.Cu" "B.Cu")
		(net "GND")
	)
	(via
		(at 343.145618 -416.020504)
		(size 0.4572)
		(drill 0.254)
		(layers "F.Cu" "B.Cu")
		(net "GND")
	)
	(via
		(at 328.53122 -277.32609)
		(size 0.4064)
		(drill 0.2032)
		(layers "F.Cu" "B.Cu")
		(net "GND")
	)
	(via
		(at 385.564888 -222.614236)
		(size 0.4064)
		(drill 0.2032)
		(layers "F.Cu" "B.Cu")
		(net "GND")
	)
	(via
		(at 123.054618 -249.344434)
		(size 0.4064)
		(drill 0.2032)
		(layers "F.Cu" "B.Cu")
		(net "GND")
	)
	(via
		(at 49.168304 -210.085432)
		(size 0.4826)
		(drill 0.254)
		(layers "F.Cu" "B.Cu")
		(net "GND")
	)
	(via
		(at 176.072038 -268.735302)
		(size 0.4826)
		(drill 0.254)
		(layers "F.Cu" "B.Cu")
		(net "GND")
	)
	(via
		(at 413.450024 -16.9799)
		(size 0.508)
		(drill 0.254)
		(layers "F.Cu" "B.Cu")
		(net "GND")
	)
	(via
		(at 303.268126 -266.185142)
		(size 0.4826)
		(drill 0.254)
		(layers "F.Cu" "B.Cu")
		(net "GND")
	)
	(via
		(at 430.40046 -193.99631)
		(size 0.4826)
		(drill 0.254)
		(layers "F.Cu" "B.Cu")
		(net "GND")
	)
	(via
		(at 380.224792 -290.285932)
		(size 0.4064)
		(drill 0.2032)
		(layers "F.Cu" "B.Cu")
		(net "GND")
	)
	(via
		(at 131.98475 -256.634488)
		(size 0.4064)
		(drill 0.2032)
		(layers "F.Cu" "B.Cu")
		(net "GND")
	)
	(via
		(at 356.261162 -287.856168)
		(size 0.4064)
		(drill 0.2032)
		(layers "F.Cu" "B.Cu")
		(net "GND")
	)
	(via
		(at 321.702938 -419.046152)
		(size 0.4572)
		(drill 0.254)
		(layers "F.Cu" "B.Cu")
		(net "GND")
	)
	(via
		(at 86.04631 -388.328662)
		(size 0.4064)
		(drill 0.2032)
		(layers "F.Cu" "B.Cu")
		(net "GND")
	)
	(via
		(at 376.34291 -189.435486)
		(size 0.508)
		(drill 0.254)
		(layers "F.Cu" "B.Cu")
		(net "GND")
	)
	(via
		(at 128.994662 -266.796266)
		(size 0.4064)
		(drill 0.2032)
		(layers "F.Cu" "B.Cu")
		(net "GND")
	)
	(via
		(at 25.152096 -225.385376)
		(size 0.4826)
		(drill 0.254)
		(layers "F.Cu" "B.Cu")
		(net "GND")
	)
	(via
		(at 93.834712 -58.866786)
		(size 0.508)
		(drill 0.254)
		(layers "F.Cu" "B.Cu")
		(net "GND")
	)
	(via
		(at 118.354856 -242.864386)
		(size 0.4064)
		(drill 0.2032)
		(layers "F.Cu" "B.Cu")
		(net "GND")
	)
	(via
		(at 206.248 -288.285428)
		(size 0.4826)
		(drill 0.254)
		(layers "F.Cu" "B.Cu")
		(net "GND")
	)
	(via
		(at 366.294924 -234.764072)
		(size 0.4064)
		(drill 0.2032)
		(layers "F.Cu" "B.Cu")
		(net "GND")
	)
	(via
		(at 386.504942 -225.85426)
		(size 0.4064)
		(drill 0.2032)
		(layers "F.Cu" "B.Cu")
		(net "GND")
	)
	(via
		(at 113.989104 -410.760164)
		(size 0.508)
		(drill 0.254)
		(layers "F.Cu" "B.Cu")
		(net "GND")
	)
	(via
		(at 114.894614 -279.756362)
		(size 0.4064)
		(drill 0.2032)
		(layers "F.Cu" "B.Cu")
		(net "GND")
	)
	(via
		(at 406.128474 -170.53306)
		(size 0.49022)
		(drill 0.254)
		(layers "F.Cu" "B.Cu")
		(net "GND")
	)
	(via
		(at 187.060078 -236.435392)
		(size 0.4826)
		(drill 0.254)
		(layers "F.Cu" "B.Cu")
		(net "GND")
	)
	(via
		(at 132.284724 -272.466308)
		(size 0.4064)
		(drill 0.2032)
		(layers "F.Cu" "B.Cu")
		(net "GND")
	)
	(via
		(at 366.764824 -248.534174)
		(size 0.4064)
		(drill 0.2032)
		(layers "F.Cu" "B.Cu")
		(net "GND")
	)
	(via
		(at 187.060078 -281.48534)
		(size 0.4826)
		(drill 0.254)
		(layers "F.Cu" "B.Cu")
		(net "GND")
	)
	(via
		(at 305.862228 -392.999722)
		(size 0.4064)
		(drill 0.2032)
		(layers "F.Cu" "B.Cu")
		(net "GND")
	)
	(via
		(at 346.091002 -224.234248)
		(size 0.4064)
		(drill 0.2032)
		(layers "F.Cu" "B.Cu")
		(net "GND")
	)
	(via
		(at 257.825494 -139.083796)
		(size 0.508)
		(drill 0.254)
		(layers "F.Cu" "B.Cu")
		(net "GND")
	)
	(via
		(at 134.607554 -406.34666)
		(size 0.4572)
		(drill 0.254)
		(layers "F.Cu" "B.Cu")
		(net "GND")
	)
	(via
		(at 79.821024 -246.10441)
		(size 0.4064)
		(drill 0.2032)
		(layers "F.Cu" "B.Cu")
		(net "GND")
	)
	(via
		(at 125.2347 -268.416278)
		(size 0.4064)
		(drill 0.2032)
		(layers "F.Cu" "B.Cu")
		(net "GND")
	)
	(via
		(at 369.114832 -247.724168)
		(size 0.4064)
		(drill 0.2032)
		(layers "F.Cu" "B.Cu")
		(net "GND")
	)
	(via
		(at 128.694688 -244.484398)
		(size 0.4064)
		(drill 0.2032)
		(layers "F.Cu" "B.Cu")
		(net "GND")
	)
	(via
		(at 387.362446 -392.999722)
		(size 0.4064)
		(drill 0.2032)
		(layers "F.Cu" "B.Cu")
		(net "GND")
	)
	(via
		(at 91.144344 -393.927838)
		(size 0.4572)
		(drill 0.254)
		(layers "F.Cu" "B.Cu")
		(net "GND")
	)
	(via
		(at 199.202294 -389.880602)
		(size 0.508)
		(drill 0.254)
		(layers "F.Cu" "B.Cu")
		(net "GND")
	)
	(via
		(at 343.101168 -281.37612)
		(size 0.4064)
		(drill 0.2032)
		(layers "F.Cu" "B.Cu")
		(net "GND")
	)
	(via
		(at 126.644654 -291.906198)
		(size 0.4064)
		(drill 0.2032)
		(layers "F.Cu" "B.Cu")
		(net "GND")
	)
	(via
		(at 116.316506 -404.46452)
		(size 0.4064)
		(drill 0.2032)
		(layers "F.Cu" "B.Cu")
		(net "GND")
	)
	(via
		(at 292.280086 -289.985196)
		(size 0.4826)
		(drill 0.254)
		(layers "F.Cu" "B.Cu")
		(net "GND")
	)
	(via
		(at 289.564318 -219.435172)
		(size 0.4826)
		(drill 0.254)
		(layers "F.Cu" "B.Cu")
		(net "GND")
	)
	(via
		(at 105.628948 -381.94361)
		(size 0.508)
		(drill 0.254)
		(layers "F.Cu" "B.Cu")
		(net "GND")
	)
	(via
		(at 69.125084 -407.00452)
		(size 0.4064)
		(drill 0.2032)
		(layers "F.Cu" "B.Cu")
		(net "GND")
	)
	(via
		(at 136.98474 -267.606272)
		(size 0.4064)
		(drill 0.2032)
		(layers "F.Cu" "B.Cu")
		(net "GND")
	)
	(via
		(at 357.201216 -270.036036)
		(size 0.4064)
		(drill 0.2032)
		(layers "F.Cu" "B.Cu")
		(net "GND")
	)
	(via
		(at 146.742912 -238.270288)
		(size 0.4064)
		(drill 0.2032)
		(layers "F.Cu" "B.Cu")
		(net "GND")
	)
	(via
		(at 142.800832 -95.612458)
		(size 0.508)
		(drill 0.254)
		(layers "F.Cu" "B.Cu")
		(net "GND")
	)
	(via
		(at 374.754902 -252.584204)
		(size 0.4064)
		(drill 0.2032)
		(layers "F.Cu" "B.Cu")
		(net "GND")
	)
	(via
		(at 356.848918 -27.695398)
		(size 0.508)
		(drill 0.254)
		(layers "F.Cu" "B.Cu")
		(net "GND")
	)
	(via
		(at 388.68477 -270.846042)
		(size 0.4064)
		(drill 0.2032)
		(layers "F.Cu" "B.Cu")
		(net "GND")
	)
	(via
		(at 56.712358 -275.53539)
		(size 0.4826)
		(drill 0.254)
		(layers "F.Cu" "B.Cu")
		(net "GND")
	)
	(via
		(at 366.764824 -229.094284)
		(size 0.4064)
		(drill 0.2032)
		(layers "F.Cu" "B.Cu")
		(net "GND")
	)
	(via
		(at 453.408288 -13.502894)
		(size 0.508)
		(drill 0.254)
		(layers "F.Cu" "B.Cu")
		(net "GND")
	)
	(via
		(at 454.188068 -278.93518)
		(size 0.4826)
		(drill 0.254)
		(layers "F.Cu" "B.Cu")
		(net "GND")
	)
	(via
		(at 7.262368 -427.726094)
		(size 0.508)
		(drill 0.254)
		(layers "F.Cu" "B.Cu")
		(net "GND")
	)
	(via
		(at 135.274812 -236.384338)
		(size 0.4064)
		(drill 0.2032)
		(layers "F.Cu" "B.Cu")
		(net "GND")
	)
	(via
		(at 269.648178 -233.884978)
		(size 0.4826)
		(drill 0.254)
		(layers "F.Cu" "B.Cu")
		(net "GND")
	)
	(via
		(at 338.50072 -328.132694)
		(size 0.508)
		(drill 0.254)
		(layers "F.Cu" "B.Cu")
		(net "GND")
	)
	(via
		(at 340.75116 -269.22603)
		(size 0.4064)
		(drill 0.2032)
		(layers "F.Cu" "B.Cu")
		(net "GND")
	)
	(via
		(at 350.321118 -236.384084)
		(size 0.4064)
		(drill 0.2032)
		(layers "F.Cu" "B.Cu")
		(net "GND")
	)
	(via
		(at 116.116608 -391.830814)
		(size 0.4064)
		(drill 0.2032)
		(layers "F.Cu" "B.Cu")
		(net "GND")
	)
	(via
		(at 202.502008 -116.673376)
		(size 0.508)
		(drill 0.254)
		(layers "F.Cu" "B.Cu")
		(net "GND")
	)
	(via
		(at 429.571404 -397.135604)
		(size 0.508)
		(drill 0.254)
		(layers "F.Cu" "B.Cu")
		(net "GND")
	)
	(via
		(at 113.48466 -267.606272)
		(size 0.4064)
		(drill 0.2032)
		(layers "F.Cu" "B.Cu")
		(net "GND")
	)
	(via
		(at 148.030946 -404.46452)
		(size 0.4064)
		(drill 0.2032)
		(layers "F.Cu" "B.Cu")
		(net "GND")
	)
	(via
		(at 18.54581 -7.215124)
		(size 0.508)
		(drill 0.254)
		(layers "F.Cu" "B.Cu")
		(net "GND")
	)
	(via
		(at 47.784004 -269.58544)
		(size 0.4826)
		(drill 0.254)
		(layers "F.Cu" "B.Cu")
		(net "GND")
	)
	(via
		(at 348.368874 -162.28949)
		(size 0.49022)
		(drill 0.254)
		(layers "F.Cu" "B.Cu")
		(net "GND")
	)
	(via
		(at 191.160146 -261.935214)
		(size 0.4826)
		(drill 0.254)
		(layers "F.Cu" "B.Cu")
		(net "GND")
	)
	(via
		(at 349.851218 -255.014222)
		(size 0.4064)
		(drill 0.2032)
		(layers "F.Cu" "B.Cu")
		(net "GND")
	)
	(via
		(at 93.545152 -411.936184)
		(size 0.4572)
		(drill 0.254)
		(layers "F.Cu" "B.Cu")
		(net "GND")
	)
	(via
		(at 394.68298 -244.750082)
		(size 0.4064)
		(drill 0.2032)
		(layers "F.Cu" "B.Cu")
		(net "GND")
	)
	(via
		(at 138.864848 -280.566368)
		(size 0.4064)
		(drill 0.2032)
		(layers "F.Cu" "B.Cu")
		(net "GND")
	)
	(via
		(at 147.042886 -269.770352)
		(size 0.4064)
		(drill 0.2032)
		(layers "F.Cu" "B.Cu")
		(net "GND")
	)
	(via
		(at 450.088 -204.985112)
		(size 0.4826)
		(drill 0.254)
		(layers "F.Cu" "B.Cu")
		(net "GND")
	)
	(via
		(at 352.671126 -232.334054)
		(size 0.4064)
		(drill 0.2032)
		(layers "F.Cu" "B.Cu")
		(net "GND")
	)
	(via
		(at 121.644664 -245.294404)
		(size 0.4064)
		(drill 0.2032)
		(layers "F.Cu" "B.Cu")
		(net "GND")
	)
	(via
		(at 427.456092 -266.185142)
		(size 0.4826)
		(drill 0.254)
		(layers "F.Cu" "B.Cu")
		(net "GND")
	)
	(via
		(at 213.153752 -342.629998)
		(size 0.508)
		(drill 0.254)
		(layers "F.Cu" "B.Cu")
		(net "GND")
	)
	(via
		(at 43.556174 -339.814662)
		(size 0.508)
		(drill 0.254)
		(layers "F.Cu" "B.Cu")
		(net "GND")
	)
	(via
		(at 367.157 -409.321)
		(size 0.4572)
		(drill 0.254)
		(layers "F.Cu" "B.Cu")
		(net "GND")
	)
	(via
		(at 59.428126 -282.335224)
		(size 0.4826)
		(drill 0.254)
		(layers "F.Cu" "B.Cu")
		(net "GND")
	)
	(via
		(at 203.532232 -278.085296)
		(size 0.4826)
		(drill 0.254)
		(layers "F.Cu" "B.Cu")
		(net "GND")
	)
	(via
		(at 446.644268 -226.235006)
		(size 0.4826)
		(drill 0.254)
		(layers "F.Cu" "B.Cu")
		(net "GND")
	)
	(via
		(at 58.762138 -345.799918)
		(size 0.49022)
		(drill 0.254)
		(layers "F.Cu" "B.Cu")
		(net "GND")
	)
	(via
		(at 445.259968 -314.635134)
		(size 0.4826)
		(drill 0.254)
		(layers "F.Cu" "B.Cu")
		(net "GND")
	)
	(via
		(at 291.36721 -345.566238)
		(size 0.49022)
		(drill 0.254)
		(layers "F.Cu" "B.Cu")
		(net "GND")
	)
	(via
		(at 357.201216 -276.516084)
		(size 0.4064)
		(drill 0.2032)
		(layers "F.Cu" "B.Cu")
		(net "GND")
	)
	(via
		(at 34.242248 -134.86257)
		(size 0.508)
		(drill 0.254)
		(layers "F.Cu" "B.Cu")
		(net "GND")
	)
	(via
		(at 115.364768 -291.906198)
		(size 0.4064)
		(drill 0.2032)
		(layers "F.Cu" "B.Cu")
		(net "GND")
	)
	(via
		(at 14.4272 -133.15188)
		(size 0.508)
		(drill 0.254)
		(layers "F.Cu" "B.Cu")
		(net "GND")
	)
	(via
		(at 299.82414 -204.134974)
		(size 0.4826)
		(drill 0.254)
		(layers "F.Cu" "B.Cu")
		(net "GND")
	)
	(via
		(at 312.499248 -22.51329)
		(size 0.508)
		(drill 0.254)
		(layers "F.Cu" "B.Cu")
		(net "GND")
	)
	(via
		(at 173.08957 -239.410494)
		(size 0.4826)
		(drill 0.254)
		(layers "F.Cu" "B.Cu")
		(net "GND")
	)
	(via
		(at 173.35627 -296.785284)
		(size 0.4826)
		(drill 0.254)
		(layers "F.Cu" "B.Cu")
		(net "GND")
	)
	(via
		(at 347.031056 -248.534174)
		(size 0.4064)
		(drill 0.2032)
		(layers "F.Cu" "B.Cu")
		(net "GND")
	)
	(via
		(at 352.505518 -172.74032)
		(size 0.508)
		(drill 0.254)
		(layers "F.Cu" "B.Cu")
		(net "GND")
	)
	(via
		(at 290.895786 -237.285022)
		(size 0.4826)
		(drill 0.254)
		(layers "F.Cu" "B.Cu")
		(net "GND")
	)
	(via
		(at 93.450918 -248.534428)
		(size 0.4064)
		(drill 0.2032)
		(layers "F.Cu" "B.Cu")
		(net "GND")
	)
	(via
		(at 387.914896 -233.14406)
		(size 0.4064)
		(drill 0.2032)
		(layers "F.Cu" "B.Cu")
		(net "GND")
	)
	(via
		(at 437.715914 -284.034992)
		(size 0.4826)
		(drill 0.254)
		(layers "F.Cu" "B.Cu")
		(net "GND")
	)
	(via
		(at 62.912752 -403.830536)
		(size 0.4572)
		(drill 0.254)
		(layers "F.Cu" "B.Cu")
		(net "GND")
	)
	(via
		(at 161.406332 -386.449062)
		(size 0.4064)
		(drill 0.2032)
		(layers "F.Cu" "B.Cu")
		(net "GND")
	)
	(via
		(at 341.886794 -416.020504)
		(size 0.4572)
		(drill 0.254)
		(layers "F.Cu" "B.Cu")
		(net "GND")
	)
	(via
		(at 112.257586 -253.432564)
		(size 0.4826)
		(drill 0.254)
		(layers "F.Cu" "B.Cu")
		(net "GND")
	)
	(via
		(at 97.681034 -252.584458)
		(size 0.4064)
		(drill 0.2032)
		(layers "F.Cu" "B.Cu")
		(net "GND")
	)
	(via
		(at 182.963312 -87.585296)
		(size 0.508)
		(drill 0.254)
		(layers "F.Cu" "B.Cu")
		(net "GND")
	)
	(via
		(at 42.955718 -227.935282)
		(size 0.4826)
		(drill 0.254)
		(layers "F.Cu" "B.Cu")
		(net "GND")
	)
	(via
		(at 273.092164 -298.485052)
		(size 0.4826)
		(drill 0.254)
		(layers "F.Cu" "B.Cu")
		(net "GND")
	)
	(via
		(at 139.974828 -223.424496)
		(size 0.4064)
		(drill 0.2032)
		(layers "F.Cu" "B.Cu")
		(net "GND")
	)
	(via
		(at 80.291178 -253.394464)
		(size 0.4064)
		(drill 0.2032)
		(layers "F.Cu" "B.Cu")
		(net "GND")
	)
	(via
		(at 73.95845 -377.49226)
		(size 0.508)
		(drill 0.254)
		(layers "F.Cu" "B.Cu")
		(net "GND")
	)
	(via
		(at 430.17186 -218.585034)
		(size 0.4826)
		(drill 0.254)
		(layers "F.Cu" "B.Cu")
		(net "GND")
	)
	(via
		(at 283.618432 -285.310072)
		(size 0.4826)
		(drill 0.254)
		(layers "F.Cu" "B.Cu")
		(net "GND")
	)
	(via
		(at 421.790876 -329.87869)
		(size 0.508)
		(drill 0.254)
		(layers "F.Cu" "B.Cu")
		(net "GND")
	)
	(via
		(at 425.96816 -12.37488)
		(size 0.508)
		(drill 0.254)
		(layers "F.Cu" "B.Cu")
		(net "GND")
	)
	(via
		(at 403.018752 -398.542002)
		(size 0.4064)
		(drill 0.2032)
		(layers "F.Cu" "B.Cu")
		(net "GND")
	)
	(via
		(at 143.524478 -413.204152)
		(size 0.4572)
		(drill 0.254)
		(layers "F.Cu" "B.Cu")
		(net "GND")
	)
	(via
		(at 140.274802 -271.656302)
		(size 0.4064)
		(drill 0.2032)
		(layers "F.Cu" "B.Cu")
		(net "GND")
	)
	(via
		(at 394.494766 -223.424242)
		(size 0.4064)
		(drill 0.2032)
		(layers "F.Cu" "B.Cu")
		(net "GND")
	)
	(via
		(at 381.334772 -234.764072)
		(size 0.4064)
		(drill 0.2032)
		(layers "F.Cu" "B.Cu")
		(net "GND")
	)
	(via
		(at 33.363662 -430.799748)
		(size 0.508)
		(drill 0.254)
		(layers "F.Cu" "B.Cu")
		(net "GND")
	)
	(via
		(at 390.285478 -180.755544)
		(size 0.49022)
		(drill 0.254)
		(layers "F.Cu" "B.Cu")
		(net "GND")
	)
	(via
		(at 353.61118 -250.154186)
		(size 0.4064)
		(drill 0.2032)
		(layers "F.Cu" "B.Cu")
		(net "GND")
	)
	(via
		(at 12.351004 -140.30071)
		(size 0.508)
		(drill 0.254)
		(layers "F.Cu" "B.Cu")
		(net "GND")
	)
	(via
		(at 91.871038 -269.226284)
		(size 0.4064)
		(drill 0.2032)
		(layers "F.Cu" "B.Cu")
		(net "GND")
	)
	(via
		(at 336.930746 -420.952168)
		(size 0.4064)
		(drill 0.2032)
		(layers "F.Cu" "B.Cu")
		(net "GND")
	)
	(via
		(at 50.745644 -410.030168)
		(size 0.4064)
		(drill 0.2032)
		(layers "F.Cu" "B.Cu")
		(net "GND")
	)
	(via
		(at 442.5442 -242.385088)
		(size 0.4826)
		(drill 0.254)
		(layers "F.Cu" "B.Cu")
		(net "GND")
	)
	(via
		(at 318.773556 -381.68453)
		(size 0.508)
		(drill 0.254)
		(layers "F.Cu" "B.Cu")
		(net "GND")
	)
	(via
		(at 132.349748 -431.29962)
		(size 0.4572)
		(drill 0.2032)
		(layers "F.Cu" "B.Cu")
		(net "GND")
	)
	(via
		(at 369.884706 -283.806138)
		(size 0.4064)
		(drill 0.2032)
		(layers "F.Cu" "B.Cu")
		(net "GND")
	)
	(via
		(at 390.094724 -286.236156)
		(size 0.4064)
		(drill 0.2032)
		(layers "F.Cu" "B.Cu")
		(net "GND")
	)
	(via
		(at 85.887052 -409.396184)
		(size 0.4572)
		(drill 0.254)
		(layers "F.Cu" "B.Cu")
		(net "GND")
	)
	(via
		(at 347.801184 -278.136096)
		(size 0.4064)
		(drill 0.2032)
		(layers "F.Cu" "B.Cu")
		(net "GND")
	)
	(via
		(at 383.68478 -250.154186)
		(size 0.4064)
		(drill 0.2032)
		(layers "F.Cu" "B.Cu")
		(net "GND")
	)
	(via
		(at 133.394704 -233.144314)
		(size 0.4064)
		(drill 0.2032)
		(layers "F.Cu" "B.Cu")
		(net "GND")
	)
	(via
		(at 131.786122 -6.042152)
		(size 0.508)
		(drill 0.254)
		(layers "F.Cu" "B.Cu")
		(net "GND")
	)
	(via
		(at 127.035306 -407.00452)
		(size 0.4064)
		(drill 0.2032)
		(layers "F.Cu" "B.Cu")
		(net "GND")
	)
	(via
		(at 107.85094 -277.326344)
		(size 0.4064)
		(drill 0.2032)
		(layers "F.Cu" "B.Cu")
		(net "GND")
	)
	(via
		(at 180.633624 -230.0605)
		(size 0.4826)
		(drill 0.254)
		(layers "F.Cu" "B.Cu")
		(net "GND")
	)
	(via
		(at 173.571408 -387.737604)
		(size 0.508)
		(drill 0.254)
		(layers "F.Cu" "B.Cu")
		(net "GND")
	)
	(via
		(at 342.801194 -226.664266)
		(size 0.4064)
		(drill 0.2032)
		(layers "F.Cu" "B.Cu")
		(net "GND")
	)
	(via
		(at 106.611166 -225.854514)
		(size 0.4064)
		(drill 0.2032)
		(layers "F.Cu" "B.Cu")
		(net "GND")
	)
	(via
		(at 148.644102 -393.902438)
		(size 0.4572)
		(drill 0.254)
		(layers "F.Cu" "B.Cu")
		(net "GND")
	)
	(via
		(at 59.249818 -435.0512)
		(size 0.4572)
		(drill 0.2032)
		(layers "F.Cu" "B.Cu")
		(net "GND")
	)
	(via
		(at 383.21488 -231.524048)
		(size 0.4064)
		(drill 0.2032)
		(layers "F.Cu" "B.Cu")
		(net "GND")
	)
	(via
		(at 128.349756 -426.54728)
		(size 0.4572)
		(drill 0.2032)
		(layers "F.Cu" "B.Cu")
		(net "GND")
	)
	(via
		(at 446.644268 -263.634982)
		(size 0.4826)
		(drill 0.254)
		(layers "F.Cu" "B.Cu")
		(net "GND")
	)
	(via
		(at 75.45451 -177.059844)
		(size 0.49022)
		(drill 0.254)
		(layers "F.Cu" "B.Cu")
		(net "GND")
	)
	(via
		(at 249.721624 -276.227032)
		(size 0.508)
		(drill 0.254)
		(layers "F.Cu" "B.Cu")
		(net "GND")
	)
	(via
		(at 99.561142 -234.764326)
		(size 0.4064)
		(drill 0.2032)
		(layers "F.Cu" "B.Cu")
		(net "GND")
	)
	(via
		(at 434.023516 -329.790552)
		(size 0.508)
		(drill 0.254)
		(layers "F.Cu" "B.Cu")
		(net "GND")
	)
	(via
		(at 328.061066 -274.896072)
		(size 0.4064)
		(drill 0.2032)
		(layers "F.Cu" "B.Cu")
		(net "GND")
	)
	(via
		(at 457.969366 -377.29287)
		(size 0.508)
		(drill 0.254)
		(layers "F.Cu" "B.Cu")
		(net "GND")
	)
	(via
		(at 112.156494 -335.691988)
		(size 0.508)
		(drill 0.254)
		(layers "F.Cu" "B.Cu")
		(net "GND")
	)
	(via
		(at 417.393882 -362.087414)
		(size 0.508)
		(drill 0.254)
		(layers "F.Cu" "B.Cu")
		(net "GND")
	)
	(via
		(at 279.518364 -230.060246)
		(size 0.4826)
		(drill 0.254)
		(layers "F.Cu" "B.Cu")
		(net "GND")
	)
	(via
		(at 451.873366 -378.81687)
		(size 0.508)
		(drill 0.254)
		(layers "F.Cu" "B.Cu")
		(net "GND")
	)
	(via
		(at 356.409244 -377.41733)
		(size 0.508)
		(drill 0.254)
		(layers "F.Cu" "B.Cu")
		(net "GND")
	)
	(via
		(at 108.321094 -278.13635)
		(size 0.4064)
		(drill 0.2032)
		(layers "F.Cu" "B.Cu")
		(net "GND")
	)
	(via
		(at 79.848964 -404.46452)
		(size 0.4064)
		(drill 0.2032)
		(layers "F.Cu" "B.Cu")
		(net "GND")
	)
	(via
		(at 126.588266 -412.570168)
		(size 0.4064)
		(drill 0.2032)
		(layers "F.Cu" "B.Cu")
		(net "GND")
	)
	(via
		(at 400.24558 -10.16508)
		(size 0.508)
		(drill 0.254)
		(layers "F.Cu" "B.Cu")
		(net "GND")
	)
	(via
		(at 334.811116 -225.85426)
		(size 0.4064)
		(drill 0.2032)
		(layers "F.Cu" "B.Cu")
		(net "GND")
	)
	(via
		(at 428.611792 -193.10731)
		(size 0.4826)
		(drill 0.254)
		(layers "F.Cu" "B.Cu")
		(net "GND")
	)
	(via
		(at 418.88918 -380.54153)
		(size 0.508)
		(drill 0.254)
		(layers "F.Cu" "B.Cu")
		(net "GND")
	)
	(via
		(at 187.911994 -117.442742)
		(size 0.4572)
		(drill 0.254)
		(layers "F.Cu" "B.Cu")
		(net "GND")
	)
	(via
		(at 151.34971 -425.547282)
		(size 0.4572)
		(drill 0.2032)
		(layers "F.Cu" "B.Cu")
		(net "GND")
	)
	(via
		(at 375.524776 -272.466054)
		(size 0.4064)
		(drill 0.2032)
		(layers "F.Cu" "B.Cu")
		(net "GND")
	)
	(via
		(at 35.411664 -312.085228)
		(size 0.4826)
		(drill 0.254)
		(layers "F.Cu" "B.Cu")
		(net "GND")
	)
	(via
		(at 339.511132 -246.914162)
		(size 0.4064)
		(drill 0.2032)
		(layers "F.Cu" "B.Cu")
		(net "GND")
	)
	(via
		(at 358.61117 -270.846042)
		(size 0.4064)
		(drill 0.2032)
		(layers "F.Cu" "B.Cu")
		(net "GND")
	)
	(via
		(at 418.17671 -416.020504)
		(size 0.4572)
		(drill 0.254)
		(layers "F.Cu" "B.Cu")
		(net "GND")
	)
	(via
		(at 334.417924 -333.034386)
		(size 0.49022)
		(drill 0.254)
		(layers "F.Cu" "B.Cu")
		(net "GND")
	)
	(via
		(at 427.456092 -279.785064)
		(size 0.4826)
		(drill 0.254)
		(layers "F.Cu" "B.Cu")
		(net "GND")
	)
	(via
		(at 82.92465 -46.44517)
		(size 0.508)
		(drill 0.254)
		(layers "F.Cu" "B.Cu")
		(net "GND")
	)
	(via
		(at 56.083962 -358.67721)
		(size 0.508)
		(drill 0.254)
		(layers "F.Cu" "B.Cu")
		(net "GND")
	)
	(via
		(at 187.51042 -356.336092)
		(size 0.508)
		(drill 0.254)
		(layers "F.Cu" "B.Cu")
		(net "GND")
	)
	(via
		(at 436.155846 -194.88531)
		(size 0.4826)
		(drill 0.254)
		(layers "F.Cu" "B.Cu")
		(net "GND")
	)
	(via
		(at 82.465164 -407.00452)
		(size 0.4064)
		(drill 0.2032)
		(layers "F.Cu" "B.Cu")
		(net "GND")
	)
	(via
		(at 178.289458 -42.29989)
		(size 0.508)
		(drill 0.254)
		(layers "F.Cu" "B.Cu")
		(net "GND")
	)
	(via
		(at 132.44068 -27.896566)
		(size 0.508)
		(drill 0.254)
		(layers "F.Cu" "B.Cu")
		(net "GND")
	)
	(via
		(at 44.340018 -318.035432)
		(size 0.4826)
		(drill 0.254)
		(layers "F.Cu" "B.Cu")
		(net "GND")
	)
	(via
		(at 399.79727 -416.020504)
		(size 0.4572)
		(drill 0.254)
		(layers "F.Cu" "B.Cu")
		(net "GND")
	)
	(via
		(at 399.786094 -178.321208)
		(size 0.49022)
		(drill 0.254)
		(layers "F.Cu" "B.Cu")
		(net "GND")
	)
	(via
		(at 400.24812 -12.37488)
		(size 0.508)
		(drill 0.254)
		(layers "F.Cu" "B.Cu")
		(net "GND")
	)
	(via
		(at 333.230982 -264.365994)
		(size 0.4064)
		(drill 0.2032)
		(layers "F.Cu" "B.Cu")
		(net "GND")
	)
	(via
		(at 121.944638 -277.326344)
		(size 0.4064)
		(drill 0.2032)
		(layers "F.Cu" "B.Cu")
		(net "GND")
	)
	(via
		(at 59.428126 -261.935214)
		(size 0.4826)
		(drill 0.254)
		(layers "F.Cu" "B.Cu")
		(net "GND")
	)
	(via
		(at 74.22007 -175.637444)
		(size 0.49022)
		(drill 0.254)
		(layers "F.Cu" "B.Cu")
		(net "GND")
	)
	(via
		(at 19.744182 -138.293856)
		(size 0.508)
		(drill 0.254)
		(layers "F.Cu" "B.Cu")
		(net "GND")
	)
	(via
		(at 142.154656 -271.656302)
		(size 0.4064)
		(drill 0.2032)
		(layers "F.Cu" "B.Cu")
		(net "GND")
	)
	(via
		(at 35.411664 -293.38524)
		(size 0.4826)
		(drill 0.254)
		(layers "F.Cu" "B.Cu")
		(net "GND")
	)
	(via
		(at 74.071226 -390.297924)
		(size 0.508)
		(drill 0.254)
		(layers "F.Cu" "B.Cu")
		(net "GND")
	)
	(via
		(at 446.644268 -318.035178)
		(size 0.4826)
		(drill 0.254)
		(layers "F.Cu" "B.Cu")
		(net "GND")
	)
	(via
		(at 332.931008 -232.334054)
		(size 0.4064)
		(drill 0.2032)
		(layers "F.Cu" "B.Cu")
		(net "GND")
	)
	(via
		(at 324.75297 -233.409998)
		(size 0.4064)
		(drill 0.2032)
		(layers "F.Cu" "B.Cu")
		(net "GND")
	)
	(via
		(at 99.715066 -183.843168)
		(size 0.49022)
		(drill 0.254)
		(layers "F.Cu" "B.Cu")
		(net "GND")
	)
	(via
		(at 184.682892 -343.402158)
		(size 0.508)
		(drill 0.254)
		(layers "F.Cu" "B.Cu")
		(net "GND")
	)
	(via
		(at 117.884702 -229.094538)
		(size 0.4064)
		(drill 0.2032)
		(layers "F.Cu" "B.Cu")
		(net "GND")
	)
	(via
		(at 380.224792 -280.566114)
		(size 0.4064)
		(drill 0.2032)
		(layers "F.Cu" "B.Cu")
		(net "GND")
	)
	(via
		(at 128.349756 -430.147222)
		(size 0.4572)
		(drill 0.2032)
		(layers "F.Cu" "B.Cu")
		(net "GND")
	)
	(via
		(at 39.12235 -286.160464)
		(size 0.4826)
		(drill 0.254)
		(layers "F.Cu" "B.Cu")
		(net "GND")
	)
	(via
		(at 391.098024 -16.979138)
		(size 0.508)
		(drill 0.254)
		(layers "F.Cu" "B.Cu")
		(net "GND")
	)
	(via
		(at 240.858548 -370.7003)
		(size 0.508)
		(drill 0.254)
		(layers "F.Cu" "B.Cu")
		(net "GND")
	)
	(via
		(at 20.782788 -371.36705)
		(size 0.508)
		(drill 0.254)
		(layers "F.Cu" "B.Cu")
		(net "GND")
	)
	(via
		(at 356.292658 -167.507666)
		(size 0.49022)
		(drill 0.254)
		(layers "F.Cu" "B.Cu")
		(net "GND")
	)
	(via
		(at 95.48368 -37.230558)
		(size 0.508)
		(drill 0.254)
		(layers "F.Cu" "B.Cu")
		(net "GND")
	)
	(via
		(at 299.82414 -280.634948)
		(size 0.4826)
		(drill 0.254)
		(layers "F.Cu" "B.Cu")
		(net "GND")
	)
	(via
		(at 79.41691 -185.327798)
		(size 0.508)
		(drill 0.254)
		(layers "F.Cu" "B.Cu")
		(net "GND")
	)
	(via
		(at 351.419414 -345.076272)
		(size 0.508)
		(drill 0.254)
		(layers "F.Cu" "B.Cu")
		(net "GND")
	)
	(via
		(at 155.490164 -384.617722)
		(size 0.4064)
		(drill 0.2032)
		(layers "F.Cu" "B.Cu")
		(net "GND")
	)
	(via
		(at 137.45464 -271.656302)
		(size 0.4064)
		(drill 0.2032)
		(layers "F.Cu" "B.Cu")
		(net "GND")
	)
	(via
		(at 130.09118 -390.160002)
		(size 0.4064)
		(drill 0.2032)
		(layers "F.Cu" "B.Cu")
		(net "GND")
	)
	(via
		(at 63.371984 -7.20471)
		(size 0.508)
		(drill 0.254)
		(layers "F.Cu" "B.Cu")
		(net "GND")
	)
	(via
		(at 289.335718 -194.88531)
		(size 0.4826)
		(drill 0.254)
		(layers "F.Cu" "B.Cu")
		(net "GND")
	)
	(via
		(at 390.349486 -429.147224)
		(size 0.4572)
		(drill 0.2032)
		(layers "F.Cu" "B.Cu")
		(net "GND")
	)
	(via
		(at 96.74098 -233.144314)
		(size 0.4064)
		(drill 0.2032)
		(layers "F.Cu" "B.Cu")
		(net "GND")
	)
	(via
		(at 160.98647 -76.781406)
		(size 0.508)
		(drill 0.254)
		(layers "F.Cu" "B.Cu")
		(net "GND")
	)
	(via
		(at 191.160146 -255.13538)
		(size 0.4826)
		(drill 0.254)
		(layers "F.Cu" "B.Cu")
		(net "GND")
	)
	(via
		(at 174.916338 -193.996564)
		(size 0.4826)
		(drill 0.254)
		(layers "F.Cu" "B.Cu")
		(net "GND")
	)
	(via
		(at 396.509494 -179.110386)
		(size 0.49022)
		(drill 0.254)
		(layers "F.Cu" "B.Cu")
		(net "GND")
	)
	(via
		(at 350.321118 -244.484144)
		(size 0.4064)
		(drill 0.2032)
		(layers "F.Cu" "B.Cu")
		(net "GND")
	)
	(via
		(at 71.19747 -155.31719)
		(size 0.508)
		(drill 0.254)
		(layers "F.Cu" "B.Cu")
		(net "GND")
	)
	(via
		(at 204.8637 -293.38524)
		(size 0.4826)
		(drill 0.254)
		(layers "F.Cu" "B.Cu")
		(net "GND")
	)
	(via
		(at 378.514864 -228.284278)
		(size 0.4064)
		(drill 0.2032)
		(layers "F.Cu" "B.Cu")
		(net "GND")
	)
	(via
		(at 92.981018 -228.284532)
		(size 0.4064)
		(drill 0.2032)
		(layers "F.Cu" "B.Cu")
		(net "GND")
	)
	(via
		(at 428.840392 -221.985078)
		(size 0.4826)
		(drill 0.254)
		(layers "F.Cu" "B.Cu")
		(net "GND")
	)
	(via
		(at 335.078324 -333.823564)
		(size 0.49022)
		(drill 0.254)
		(layers "F.Cu" "B.Cu")
		(net "GND")
	)
	(via
		(at 423.50944 -377.41733)
		(size 0.508)
		(drill 0.254)
		(layers "F.Cu" "B.Cu")
		(net "GND")
	)
	(via
		(at 303.268126 -225.385122)
		(size 0.4826)
		(drill 0.254)
		(layers "F.Cu" "B.Cu")
		(net "GND")
	)
	(via
		(at 415.444178 -400.212814)
		(size 0.4064)
		(drill 0.2032)
		(layers "F.Cu" "B.Cu")
		(net "GND")
	)
	(via
		(at 100.971096 -222.61449)
		(size 0.4064)
		(drill 0.2032)
		(layers "F.Cu" "B.Cu")
		(net "GND")
	)
	(via
		(at 308.395624 -74.184764)
		(size 0.508)
		(drill 0.254)
		(layers "F.Cu" "B.Cu")
		(net "GND")
	)
	(via
		(at 145.349722 -433.747164)
		(size 0.4572)
		(drill 0.2032)
		(layers "F.Cu" "B.Cu")
		(net "GND")
	)
	(via
		(at 10.873486 -91.658948)
		(size 0.508)
		(drill 0.254)
		(layers "F.Cu" "B.Cu")
		(net "GND")
	)
	(via
		(at 76.812902 -246.370348)
		(size 0.4064)
		(drill 0.2032)
		(layers "F.Cu" "B.Cu")
		(net "GND")
	)
	(via
		(at 299.82414 -243.234972)
		(size 0.4826)
		(drill 0.254)
		(layers "F.Cu" "B.Cu")
		(net "GND")
	)
	(via
		(at 271.328134 -422.345612)
		(size 0.508)
		(drill 0.254)
		(layers "F.Cu" "B.Cu")
		(net "GND")
	)
	(via
		(at 190.987426 -351.886774)
		(size 0.49022)
		(drill 0.254)
		(layers "F.Cu" "B.Cu")
		(net "GND")
	)
	(via
		(at 73.24979 -426.54728)
		(size 0.4572)
		(drill 0.2032)
		(layers "F.Cu" "B.Cu")
		(net "GND")
	)
	(via
		(at 397.992854 -419.046152)
		(size 0.4572)
		(drill 0.254)
		(layers "F.Cu" "B.Cu")
		(net "GND")
	)
	(via
		(at 89.690956 -253.394464)
		(size 0.4064)
		(drill 0.2032)
		(layers "F.Cu" "B.Cu")
		(net "GND")
	)
	(via
		(at 15.209774 -387.704076)
		(size 0.49022)
		(drill 0.254)
		(layers "F.Cu" "B.Cu")
		(net "GND")
	)
	(via
		(at 458.390752 -394.429234)
		(size 0.508)
		(drill 0.254)
		(layers "F.Cu" "B.Cu")
		(net "GND")
	)
	(via
		(at 124.294646 -289.47618)
		(size 0.4064)
		(drill 0.2032)
		(layers "F.Cu" "B.Cu")
		(net "GND")
	)
	(via
		(at 387.366256 -183.171846)
		(size 0.49022)
		(drill 0.254)
		(layers "F.Cu" "B.Cu")
		(net "GND")
	)
	(via
		(at 23.629366 -433.12715)
		(size 0.508)
		(drill 0.254)
		(layers "F.Cu" "B.Cu")
		(net "GND")
	)
	(via
		(at 194.604132 -279.785318)
		(size 0.4826)
		(drill 0.254)
		(layers "F.Cu" "B.Cu")
		(net "GND")
	)
	(via
		(at 77.956156 -410.664152)
		(size 0.4572)
		(drill 0.254)
		(layers "F.Cu" "B.Cu")
		(net "GND")
	)
	(via
		(at 123.524772 -232.334308)
		(size 0.4064)
		(drill 0.2032)
		(layers "F.Cu" "B.Cu")
		(net "GND")
	)
	(via
		(at 116.304822 -272.466308)
		(size 0.4064)
		(drill 0.2032)
		(layers "F.Cu" "B.Cu")
		(net "GND")
	)
	(via
		(at 83.88096 -286.23641)
		(size 0.4064)
		(drill 0.2032)
		(layers "F.Cu" "B.Cu")
		(net "GND")
	)
	(via
		(at 128.994662 -268.416278)
		(size 0.4064)
		(drill 0.2032)
		(layers "F.Cu" "B.Cu")
		(net "GND")
	)
	(via
		(at 347.144086 -402.309838)
		(size 0.4572)
		(drill 0.254)
		(layers "F.Cu" "B.Cu")
		(net "GND")
	)
	(via
		(at 195.699126 -349.377)
		(size 0.508)
		(drill 0.254)
		(layers "F.Cu" "B.Cu")
		(net "GND")
	)
	(via
		(at 73.24979 -427.699678)
		(size 0.4572)
		(drill 0.2032)
		(layers "F.Cu" "B.Cu")
		(net "GND")
	)
	(via
		(at 80.241648 -183.894984)
		(size 0.49022)
		(drill 0.254)
		(layers "F.Cu" "B.Cu")
		(net "GND")
	)
	(via
		(at 61.893958 -345.571064)
		(size 0.49022)
		(drill 0.254)
		(layers "F.Cu" "B.Cu")
		(net "GND")
	)
	(via
		(at 334.249522 -428.851314)
		(size 0.4572)
		(drill 0.2032)
		(layers "F.Cu" "B.Cu")
		(net "GND")
	)
	(via
		(at 102.85095 -240.434368)
		(size 0.4064)
		(drill 0.2032)
		(layers "F.Cu" "B.Cu")
		(net "GND")
	)
	(via
		(at 283.455872 -351.858072)
		(size 0.508)
		(drill 0.254)
		(layers "F.Cu" "B.Cu")
		(net "GND")
	)
	(via
		(at 408.714194 -413.480504)
		(size 0.4572)
		(drill 0.254)
		(layers "F.Cu" "B.Cu")
		(net "GND")
	)
	(via
		(at 70.503288 -390.337802)
		(size 0.508)
		(drill 0.254)
		(layers "F.Cu" "B.Cu")
		(net "GND")
	)
	(via
		(at 183.132222 -113.46307)
		(size 0.4572)
		(drill 0.254)
		(layers "F.Cu" "B.Cu")
		(net "GND")
	)
	(via
		(at 83.580986 -246.10441)
		(size 0.4064)
		(drill 0.2032)
		(layers "F.Cu" "B.Cu")
		(net "GND")
	)
	(via
		(at 374.284748 -225.85426)
		(size 0.4064)
		(drill 0.2032)
		(layers "F.Cu" "B.Cu")
		(net "GND")
	)
	(via
		(at 275.807932 -293.384986)
		(size 0.4826)
		(drill 0.254)
		(layers "F.Cu" "B.Cu")
		(net "GND")
	)
	(via
		(at 388.21487 -278.136096)
		(size 0.4064)
		(drill 0.2032)
		(layers "F.Cu" "B.Cu")
		(net "GND")
	)
	(via
		(at 369.584732 -237.19409)
		(size 0.4064)
		(drill 0.2032)
		(layers "F.Cu" "B.Cu")
		(net "GND")
	)
	(via
		(at 363.500924 -336.605626)
		(size 0.508)
		(drill 0.254)
		(layers "F.Cu" "B.Cu")
		(net "GND")
	)
	(via
		(at 198.7042 -232.18521)
		(size 0.4826)
		(drill 0.254)
		(layers "F.Cu" "B.Cu")
		(net "GND")
	)
	(via
		(at 11.537442 -51.364896)
		(size 0.508)
		(drill 0.254)
		(layers "F.Cu" "B.Cu")
		(net "GND")
	)
	(via
		(at 96.27108 -245.294404)
		(size 0.4064)
		(drill 0.2032)
		(layers "F.Cu" "B.Cu")
		(net "GND")
	)
	(via
		(at 321.614546 -420.952168)
		(size 0.4064)
		(drill 0.2032)
		(layers "F.Cu" "B.Cu")
		(net "GND")
	)
	(via
		(at 337.736942 -141.150086)
		(size 0.508)
		(drill 0.254)
		(layers "F.Cu" "B.Cu")
		(net "GND")
	)
	(via
		(at 20.345654 -7.215124)
		(size 0.508)
		(drill 0.254)
		(layers "F.Cu" "B.Cu")
		(net "GND")
	)
	(via
		(at 296.879772 -194.88531)
		(size 0.4826)
		(drill 0.254)
		(layers "F.Cu" "B.Cu")
		(net "GND")
	)
	(via
		(at 12.735052 -108.15574)
		(size 0.508)
		(drill 0.254)
		(layers "F.Cu" "B.Cu")
		(net "GND")
	)
	(via
		(at 363.23905 -409.931616)
		(size 0.508)
		(drill 0.254)
		(layers "F.Cu" "B.Cu")
		(net "GND")
	)
	(via
		(at 427.456092 -273.835114)
		(size 0.4826)
		(drill 0.254)
		(layers "F.Cu" "B.Cu")
		(net "GND")
	)
	(via
		(at 171.97197 -301.88535)
		(size 0.4826)
		(drill 0.254)
		(layers "F.Cu" "B.Cu")
		(net "GND")
	)
	(via
		(at 86.401148 -236.384338)
		(size 0.4064)
		(drill 0.2032)
		(layers "F.Cu" "B.Cu")
		(net "GND")
	)
	(via
		(at 378.984764 -222.614236)
		(size 0.4064)
		(drill 0.2032)
		(layers "F.Cu" "B.Cu")
		(net "GND")
	)
	(via
		(at 427.456092 -234.735116)
		(size 0.4826)
		(drill 0.254)
		(layers "F.Cu" "B.Cu")
		(net "GND")
	)
	(via
		(at 412.367984 -262.785098)
		(size 0.4826)
		(drill 0.254)
		(layers "F.Cu" "B.Cu")
		(net "GND")
	)
	(via
		(at 167.143684 -227.935282)
		(size 0.4826)
		(drill 0.254)
		(layers "F.Cu" "B.Cu")
		(net "GND")
	)
	(via
		(at 132.284724 -274.08632)
		(size 0.4064)
		(drill 0.2032)
		(layers "F.Cu" "B.Cu")
		(net "GND")
	)
	(via
		(at 212.19795 -121.38406)
		(size 0.508)
		(drill 0.254)
		(layers "F.Cu" "B.Cu")
		(net "GND")
	)
	(via
		(at 30.484064 -76.366116)
		(size 0.508)
		(drill 0.254)
		(layers "F.Cu" "B.Cu")
		(net "GND")
	)
	(via
		(at 413.850074 -165.70706)
		(size 0.49022)
		(drill 0.254)
		(layers "F.Cu" "B.Cu")
		(net "GND")
	)
	(via
		(at 61.893958 -344.781886)
		(size 0.49022)
		(drill 0.254)
		(layers "F.Cu" "B.Cu")
		(net "GND")
	)
	(via
		(at 44.054014 -370.83873)
		(size 0.508)
		(drill 0.254)
		(layers "F.Cu" "B.Cu")
		(net "GND")
	)
	(via
		(at 120.822974 -405.098504)
		(size 0.4572)
		(drill 0.254)
		(layers "F.Cu" "B.Cu")
		(net "GND")
	)
	(via
		(at 301.231808 -111.811308)
		(size 0.508)
		(drill 0.254)
		(layers "F.Cu" "B.Cu")
		(net "GND")
	)
	(via
		(at 142.556992 -25.501346)
		(size 0.508)
		(drill 0.254)
		(layers "F.Cu" "B.Cu")
		(net "GND")
	)
	(via
		(at 362.064808 -225.85426)
		(size 0.4064)
		(drill 0.2032)
		(layers "F.Cu" "B.Cu")
		(net "GND")
	)
	(via
		(at 102.85095 -225.854514)
		(size 0.4064)
		(drill 0.2032)
		(layers "F.Cu" "B.Cu")
		(net "GND")
	)
	(via
		(at 334.341216 -231.524048)
		(size 0.4064)
		(drill 0.2032)
		(layers "F.Cu" "B.Cu")
		(net "GND")
	)
	(via
		(at 86.401148 -241.244374)
		(size 0.4064)
		(drill 0.2032)
		(layers "F.Cu" "B.Cu")
		(net "GND")
	)
	(via
		(at 95.165164 -404.46452)
		(size 0.4064)
		(drill 0.2032)
		(layers "F.Cu" "B.Cu")
		(net "GND")
	)
	(via
		(at 111.447834 -256.3876)
		(size 0.4826)
		(drill 0.254)
		(layers "F.Cu" "B.Cu")
		(net "GND")
	)
	(via
		(at 359.156 -116.931948)
		(size 0.508)
		(drill 0.254)
		(layers "F.Cu" "B.Cu")
		(net "GND")
	)
	(via
		(at 64.742314 -342.816434)
		(size 0.508)
		(drill 0.254)
		(layers "F.Cu" "B.Cu")
		(net "GND")
	)
	(via
		(at 307.368194 -215.18499)
		(size 0.4826)
		(drill 0.254)
		(layers "F.Cu" "B.Cu")
		(net "GND")
	)
	(via
		(at 84.249768 -427.851316)
		(size 0.4572)
		(drill 0.2032)
		(layers "F.Cu" "B.Cu")
		(net "GND")
	)
	(via
		(at 416.468052 -316.335156)
		(size 0.4826)
		(drill 0.254)
		(layers "F.Cu" "B.Cu")
		(net "GND")
	)
	(via
		(at 376.93473 -271.656048)
		(size 0.4064)
		(drill 0.2032)
		(layers "F.Cu" "B.Cu")
		(net "GND")
	)
	(via
		(at 326.651112 -272.466054)
		(size 0.4064)
		(drill 0.2032)
		(layers "F.Cu" "B.Cu")
		(net "GND")
	)
	(via
		(at 334.64119 -276.516084)
		(size 0.4064)
		(drill 0.2032)
		(layers "F.Cu" "B.Cu")
		(net "GND")
	)
	(via
		(at 415.083752 -312.084974)
		(size 0.4826)
		(drill 0.254)
		(layers "F.Cu" "B.Cu")
		(net "GND")
	)
	(via
		(at 454.188068 -226.235006)
		(size 0.4826)
		(drill 0.254)
		(layers "F.Cu" "B.Cu")
		(net "GND")
	)
	(via
		(at 309.39105 -398.542002)
		(size 0.4064)
		(drill 0.2032)
		(layers "F.Cu" "B.Cu")
		(net "GND")
	)
	(via
		(at 422.26611 -366.866932)
		(size 0.508)
		(drill 0.254)
		(layers "F.Cu" "B.Cu")
		(net "GND")
	)
	(via
		(at 18.992342 -303.585372)
		(size 0.4826)
		(drill 0.254)
		(layers "F.Cu" "B.Cu")
		(net "GND")
	)
	(via
		(at 89.646252 -388.328662)
		(size 0.4064)
		(drill 0.2032)
		(layers "F.Cu" "B.Cu")
		(net "GND")
	)
	(via
		(at 78.88097 -250.964446)
		(size 0.4064)
		(drill 0.2032)
		(layers "F.Cu" "B.Cu")
		(net "GND")
	)
	(via
		(at 133.289802 -12.494006)
		(size 0.508)
		(drill 0.254)
		(layers "F.Cu" "B.Cu")
		(net "GND")
	)
	(via
		(at 204.029056 -83.845908)
		(size 0.508)
		(drill 0.254)
		(layers "F.Cu" "B.Cu")
		(net "GND")
	)
	(via
		(at 129.55651 -159.114998)
		(size 0.508)
		(drill 0.254)
		(layers "F.Cu" "B.Cu")
		(net "GND")
	)
	(via
		(at 357.051864 -332.896972)
		(size 0.508)
		(drill 0.254)
		(layers "F.Cu" "B.Cu")
		(net "GND")
	)
	(via
		(at 132.284724 -282.18638)
		(size 0.4064)
		(drill 0.2032)
		(layers "F.Cu" "B.Cu")
		(net "GND")
	)
	(via
		(at 446.750186 -63.130176)
		(size 0.508)
		(drill 0.254)
		(layers "F.Cu" "B.Cu")
		(net "GND")
	)
	(via
		(at 72.102472 -405.098504)
		(size 0.4572)
		(drill 0.254)
		(layers "F.Cu" "B.Cu")
		(net "GND")
	)
	(via
		(at 423.663364 -349.964756)
		(size 0.49022)
		(drill 0.254)
		(layers "F.Cu" "B.Cu")
		(net "GND")
	)
	(via
		(at 167.86479 -104.797352)
		(size 0.508)
		(drill 0.254)
		(layers "F.Cu" "B.Cu")
		(net "GND")
	)
	(via
		(at 307.368194 -204.134974)
		(size 0.4826)
		(drill 0.254)
		(layers "F.Cu" "B.Cu")
		(net "GND")
	)
	(via
		(at 76.812902 -231.79024)
		(size 0.4064)
		(drill 0.2032)
		(layers "F.Cu" "B.Cu")
		(net "GND")
	)
	(via
		(at 435.000146 -206.685134)
		(size 0.4826)
		(drill 0.254)
		(layers "F.Cu" "B.Cu")
		(net "GND")
	)
	(via
		(at 42.955718 -284.035246)
		(size 0.4826)
		(drill 0.254)
		(layers "F.Cu" "B.Cu")
		(net "GND")
	)
	(via
		(at 397.804894 -177.57013)
		(size 0.49022)
		(drill 0.254)
		(layers "F.Cu" "B.Cu")
		(net "GND")
	)
	(via
		(at 437.325516 -331.390752)
		(size 0.508)
		(drill 0.254)
		(layers "F.Cu" "B.Cu")
		(net "GND")
	)
	(via
		(at 394.956538 -179.755038)
		(size 0.508)
		(drill 0.254)
		(layers "F.Cu" "B.Cu")
		(net "GND")
	)
	(via
		(at 339.15604 -63.904876)
		(size 0.508)
		(drill 0.254)
		(layers "F.Cu" "B.Cu")
		(net "GND")
	)
	(via
		(at 187.200286 -21.124926)
		(size 0.508)
		(drill 0.254)
		(layers "F.Cu" "B.Cu")
		(net "GND")
	)
	(via
		(at 316.383924 -333.055976)
		(size 0.49022)
		(drill 0.254)
		(layers "F.Cu" "B.Cu")
		(net "GND")
	)
	(via
		(at 338.744052 -400.212814)
		(size 0.4064)
		(drill 0.2032)
		(layers "F.Cu" "B.Cu")
		(net "GND")
	)
	(via
		(at 102.681024 -287.856422)
		(size 0.4064)
		(drill 0.2032)
		(layers "F.Cu" "B.Cu")
		(net "GND")
	)
	(via
		(at 202.147932 -252.58522)
		(size 0.4826)
		(drill 0.254)
		(layers "F.Cu" "B.Cu")
		(net "GND")
	)
	(via
		(at 429.653192 -395.042898)
		(size 0.508)
		(drill 0.254)
		(layers "F.Cu" "B.Cu")
		(net "GND")
	)
	(via
		(at 115.834668 -286.23641)
		(size 0.4064)
		(drill 0.2032)
		(layers "F.Cu" "B.Cu")
		(net "GND")
	)
	(via
		(at 264.43051 -286.16021)
		(size 0.4826)
		(drill 0.254)
		(layers "F.Cu" "B.Cu")
		(net "GND")
	)
	(via
		(at 87.171022 -262.746236)
		(size 0.4064)
		(drill 0.2032)
		(layers "F.Cu" "B.Cu")
		(net "GND")
	)
	(via
		(at 136.34974 -433.747164)
		(size 0.4572)
		(drill 0.2032)
		(layers "F.Cu" "B.Cu")
		(net "GND")
	)
	(via
		(at 179.516024 -245.785386)
		(size 0.4826)
		(drill 0.254)
		(layers "F.Cu" "B.Cu")
		(net "GND")
	)
	(via
		(at 164.427916 -272.135346)
		(size 0.4826)
		(drill 0.254)
		(layers "F.Cu" "B.Cu")
		(net "GND")
	)
	(via
		(at 58.156094 -369.69573)
		(size 0.508)
		(drill 0.254)
		(layers "F.Cu" "B.Cu")
		(net "GND")
	)
	(via
		(at 242.22202 -370.01704)
		(size 0.508)
		(drill 0.254)
		(layers "F.Cu" "B.Cu")
		(net "GND")
	)
	(via
		(at 15.59941 -422.07053)
		(size 0.508)
		(drill 0.254)
		(layers "F.Cu" "B.Cu")
		(net "GND")
	)
	(via
		(at 349.851218 -243.674138)
		(size 0.4064)
		(drill 0.2032)
		(layers "F.Cu" "B.Cu")
		(net "GND")
	)
	(via
		(at 300.38421 -344.77706)
		(size 0.49022)
		(drill 0.254)
		(layers "F.Cu" "B.Cu")
		(net "GND")
	)
	(via
		(at 25.509982 -6.598158)
		(size 0.508)
		(drill 0.254)
		(layers "F.Cu" "B.Cu")
		(net "GND")
	)
	(via
		(at 110.671102 -277.326344)
		(size 0.4064)
		(drill 0.2032)
		(layers "F.Cu" "B.Cu")
		(net "GND")
	)
	(via
		(at 141.214856 -295.956228)
		(size 0.4064)
		(drill 0.2032)
		(layers "F.Cu" "B.Cu")
		(net "GND")
	)
	(via
		(at 304.652426 -200.735184)
		(size 0.4826)
		(drill 0.254)
		(layers "F.Cu" "B.Cu")
		(net "GND")
	)
	(via
		(at 374.754902 -249.34418)
		(size 0.4064)
		(drill 0.2032)
		(layers "F.Cu" "B.Cu")
		(net "GND")
	)
	(via
		(at 194.67957 -345.63812)
		(size 0.6604)
		(drill 0.3302)
		(layers "F.Cu" "B.Cu")
		(net "GND")
	)
	(via
		(at 412.606236 -394.831062)
		(size 0.4064)
		(drill 0.2032)
		(layers "F.Cu" "B.Cu")
		(net "GND")
	)
	(via
		(at 350.890078 -162.01771)
		(size 0.49022)
		(drill 0.254)
		(layers "F.Cu" "B.Cu")
		(net "GND")
	)
	(via
		(at 342.939624 -74.184764)
		(size 0.508)
		(drill 0.254)
		(layers "F.Cu" "B.Cu")
		(net "GND")
	)
	(via
		(at 41.62425 -238.135414)
		(size 0.4826)
		(drill 0.254)
		(layers "F.Cu" "B.Cu")
		(net "GND")
	)
	(via
		(at 386.01269 -420.318184)
		(size 0.4572)
		(drill 0.254)
		(layers "F.Cu" "B.Cu")
		(net "GND")
	)
	(via
		(at 403.280118 -171.838112)
		(size 0.508)
		(drill 0.254)
		(layers "F.Cu" "B.Cu")
		(net "GND")
	)
	(via
		(at 369.717066 -415.572956)
		(size 0.508)
		(drill 0.254)
		(layers "F.Cu" "B.Cu")
		(net "GND")
	)
	(via
		(at 98.321114 -331.78496)
		(size 0.508)
		(drill 0.254)
		(layers "F.Cu" "B.Cu")
		(net "GND")
	)
	(via
		(at 135.574786 -289.47618)
		(size 0.4064)
		(drill 0.2032)
		(layers "F.Cu" "B.Cu")
		(net "GND")
	)
	(via
		(at 284.736032 -205.834996)
		(size 0.4826)
		(drill 0.254)
		(layers "F.Cu" "B.Cu")
		(net "GND")
	)
	(via
		(at 73.24979 -439.651394)
		(size 0.4572)
		(drill 0.2032)
		(layers "F.Cu" "B.Cu")
		(net "GND")
	)
	(via
		(at 21.683472 -383.86639)
		(size 0.508)
		(drill 0.254)
		(layers "F.Cu" "B.Cu")
		(net "GND")
	)
	(via
		(at 86.871048 -243.674392)
		(size 0.4064)
		(drill 0.2032)
		(layers "F.Cu" "B.Cu")
		(net "GND")
	)
	(via
		(at 164.427916 -269.58544)
		(size 0.4826)
		(drill 0.254)
		(layers "F.Cu" "B.Cu")
		(net "GND")
	)
	(via
		(at 427.456092 -264.48512)
		(size 0.4826)
		(drill 0.254)
		(layers "F.Cu" "B.Cu")
		(net "GND")
	)
	(via
		(at 327.829418 -414.752536)
		(size 0.4572)
		(drill 0.254)
		(layers "F.Cu" "B.Cu")
		(net "GND")
	)
	(via
		(at 386.349494 -425.547282)
		(size 0.4572)
		(drill 0.2032)
		(layers "F.Cu" "B.Cu")
		(net "GND")
	)
	(via
		(at 90.662506 -183.825896)
		(size 0.49022)
		(drill 0.254)
		(layers "F.Cu" "B.Cu")
		(net "GND")
	)
	(via
		(at 346.249498 -436.051198)
		(size 0.4572)
		(drill 0.2032)
		(layers "F.Cu" "B.Cu")
		(net "GND")
	)
	(via
		(at 120.49125 -390.160002)
		(size 0.4064)
		(drill 0.2032)
		(layers "F.Cu" "B.Cu")
		(net "GND")
	)
	(via
		(at 440.217814 -201.160126)
		(size 0.4826)
		(drill 0.254)
		(layers "F.Cu" "B.Cu")
		(net "GND")
	)
	(via
		(at 107.71505 -176.183544)
		(size 0.49022)
		(drill 0.254)
		(layers "F.Cu" "B.Cu")
		(net "GND")
	)
	(via
		(at 84.05114 -250.15444)
		(size 0.4064)
		(drill 0.2032)
		(layers "F.Cu" "B.Cu")
		(net "GND")
	)
	(via
		(at 415.444178 -391.23493)
		(size 0.4064)
		(drill 0.2032)
		(layers "F.Cu" "B.Cu")
		(net "GND")
	)
	(via
		(at 431.55616 -263.634982)
		(size 0.4826)
		(drill 0.254)
		(layers "F.Cu" "B.Cu")
		(net "GND")
	)
	(via
		(at 384.624834 -225.85426)
		(size 0.4064)
		(drill 0.2032)
		(layers "F.Cu" "B.Cu")
		(net "GND")
	)
	(via
		(at 415.083752 -239.835182)
		(size 0.4826)
		(drill 0.254)
		(layers "F.Cu" "B.Cu")
		(net "GND")
	)
	(via
		(at 143.797274 -410.664152)
		(size 0.4572)
		(drill 0.254)
		(layers "F.Cu" "B.Cu")
		(net "GND")
	)
	(via
		(at 52.178458 -386.449062)
		(size 0.4064)
		(drill 0.2032)
		(layers "F.Cu" "B.Cu")
		(net "GND")
	)
	(via
		(at 201.78395 -137.52195)
		(size 0.508)
		(drill 0.254)
		(layers "F.Cu" "B.Cu")
		(net "GND")
	)
	(via
		(at 43.579034 -16.979138)
		(size 0.508)
		(drill 0.254)
		(layers "F.Cu" "B.Cu")
		(net "GND")
	)
	(via
		(at 295.536366 -342.811608)
		(size 0.508)
		(drill 0.254)
		(layers "F.Cu" "B.Cu")
		(net "GND")
	)
	(via
		(at 334.8482 -163.322)
		(size 0.508)
		(drill 0.254)
		(layers "F.Cu" "B.Cu")
		(net "GND")
	)
	(via
		(at 11.180826 -385.82346)
		(size 0.6604)
		(drill 0.3302)
		(layers "F.Cu" "B.Cu")
		(net "GND")
	)
	(via
		(at 122.114818 -221.804484)
		(size 0.4064)
		(drill 0.2032)
		(layers "F.Cu" "B.Cu")
		(net "GND")
	)
	(via
		(at 167.143684 -237.285276)
		(size 0.4826)
		(drill 0.254)
		(layers "F.Cu" "B.Cu")
		(net "GND")
	)
	(via
		(at 455.305668 -201.160126)
		(size 0.4826)
		(drill 0.254)
		(layers "F.Cu" "B.Cu")
		(net "GND")
	)
	(via
		(at 405.34971 -434.899562)
		(size 0.4572)
		(drill 0.2032)
		(layers "F.Cu" "B.Cu")
		(net "GND")
	)
	(via
		(at 206.248 -299.335444)
		(size 0.4826)
		(drill 0.254)
		(layers "F.Cu" "B.Cu")
		(net "GND")
	)
	(via
		(at 152.244298 -393.927838)
		(size 0.4572)
		(drill 0.254)
		(layers "F.Cu" "B.Cu")
		(net "GND")
	)
	(via
		(at 391.777982 -420.952168)
		(size 0.4064)
		(drill 0.2032)
		(layers "F.Cu" "B.Cu")
		(net "GND")
	)
	(via
		(at 202.147932 -267.885418)
		(size 0.4826)
		(drill 0.254)
		(layers "F.Cu" "B.Cu")
		(net "GND")
	)
	(via
		(at 77.271118 -336.981292)
		(size 0.49022)
		(drill 0.254)
		(layers "F.Cu" "B.Cu")
		(net "GND")
	)
	(via
		(at 89.690956 -227.474526)
		(size 0.4064)
		(drill 0.2032)
		(layers "F.Cu" "B.Cu")
		(net "GND")
	)
	(via
		(at 385.394708 -261.935976)
		(size 0.4064)
		(drill 0.2032)
		(layers "F.Cu" "B.Cu")
		(net "GND")
	)
	(via
		(at 397.804894 -179.110386)
		(size 0.49022)
		(drill 0.254)
		(layers "F.Cu" "B.Cu")
		(net "GND")
	)
	(via
		(at 103.145082 -379.321568)
		(size 0.508)
		(drill 0.254)
		(layers "F.Cu" "B.Cu")
		(net "GND")
	)
	(via
		(at 418.12464 -4.963414)
		(size 0.508)
		(drill 0.254)
		(layers "F.Cu" "B.Cu")
		(net "GND")
	)
	(via
		(at 179.516024 -244.085364)
		(size 0.4826)
		(drill 0.254)
		(layers "F.Cu" "B.Cu")
		(net "GND")
	)
	(via
		(at 146.830034 -316.08395)
		(size 0.508)
		(drill 0.254)
		(layers "F.Cu" "B.Cu")
		(net "GND")
	)
	(via
		(at 318.21628 -402.259038)
		(size 0.4572)
		(drill 0.254)
		(layers "F.Cu" "B.Cu")
		(net "GND")
	)
	(via
		(at 40.23995 -214.33536)
		(size 0.4826)
		(drill 0.254)
		(layers "F.Cu" "B.Cu")
		(net "GND")
	)
	(via
		(at 374.284748 -237.19409)
		(size 0.4064)
		(drill 0.2032)
		(layers "F.Cu" "B.Cu")
		(net "GND")
	)
	(via
		(at 305.983894 -237.285022)
		(size 0.4826)
		(drill 0.254)
		(layers "F.Cu" "B.Cu")
		(net "GND")
	)
	(via
		(at 14.38148 -77.089)
		(size 0.508)
		(drill 0.254)
		(layers "F.Cu" "B.Cu")
		(net "GND")
	)
	(via
		(at 341.86114 -223.424242)
		(size 0.4064)
		(drill 0.2032)
		(layers "F.Cu" "B.Cu")
		(net "GND")
	)
	(via
		(at 99.861116 -289.47618)
		(size 0.4064)
		(drill 0.2032)
		(layers "F.Cu" "B.Cu")
		(net "GND")
	)
	(via
		(at 117.316504 -391.830814)
		(size 0.4064)
		(drill 0.2032)
		(layers "F.Cu" "B.Cu")
		(net "GND")
	)
	(via
		(at 454.188068 -261.93496)
		(size 0.4826)
		(drill 0.254)
		(layers "F.Cu" "B.Cu")
		(net "GND")
	)
	(via
		(at 334.249522 -427.699678)
		(size 0.4572)
		(drill 0.2032)
		(layers "F.Cu" "B.Cu")
		(net "GND")
	)
	(via
		(at 305.646836 -380.54153)
		(size 0.508)
		(drill 0.254)
		(layers "F.Cu" "B.Cu")
		(net "GND")
	)
	(via
		(at 31.468314 -344.137234)
		(size 0.508)
		(drill 0.254)
		(layers "F.Cu" "B.Cu")
		(net "GND")
	)
	(via
		(at 189.207394 -42.389298)
		(size 0.508)
		(drill 0.254)
		(layers "F.Cu" "B.Cu")
		(net "GND")
	)
	(via
		(at 194.183 -135.743696)
		(size 0.508)
		(drill 0.254)
		(layers "F.Cu" "B.Cu")
		(net "GND")
	)
	(via
		(at 118.091204 -390.160002)
		(size 0.4064)
		(drill 0.2032)
		(layers "F.Cu" "B.Cu")
		(net "GND")
	)
	(via
		(at 40.52443 -4.32943)
		(size 0.508)
		(drill 0.254)
		(layers "F.Cu" "B.Cu")
		(net "GND")
	)
	(via
		(at 394.024866 -224.234248)
		(size 0.4064)
		(drill 0.2032)
		(layers "F.Cu" "B.Cu")
		(net "GND")
	)
	(via
		(at 375.054876 -274.896072)
		(size 0.4064)
		(drill 0.2032)
		(layers "F.Cu" "B.Cu")
		(net "GND")
	)
	(via
		(at 288.180018 -255.135126)
		(size 0.4826)
		(drill 0.254)
		(layers "F.Cu" "B.Cu")
		(net "GND")
	)
	(via
		(at 99.390962 -270.846296)
		(size 0.4064)
		(drill 0.2032)
		(layers "F.Cu" "B.Cu")
		(net "GND")
	)
	(via
		(at 330.229464 -331.083412)
		(size 0.508)
		(drill 0.254)
		(layers "F.Cu" "B.Cu")
		(net "GND")
	)
	(via
		(at 362.834682 -279.756108)
		(size 0.4064)
		(drill 0.2032)
		(layers "F.Cu" "B.Cu")
		(net "GND")
	)
	(via
		(at 154.157426 -404.46452)
		(size 0.4064)
		(drill 0.2032)
		(layers "F.Cu" "B.Cu")
		(net "GND")
	)
	(via
		(at 65.628266 -170.078654)
		(size 0.49022)
		(drill 0.254)
		(layers "F.Cu" "B.Cu")
		(net "GND")
	)
	(via
		(at 79.022702 -391.77595)
		(size 0.4064)
		(drill 0.2032)
		(layers "F.Cu" "B.Cu")
		(net "GND")
	)
	(via
		(at 401.349718 -433.747164)
		(size 0.4572)
		(drill 0.2032)
		(layers "F.Cu" "B.Cu")
		(net "GND")
	)
	(via
		(at 459.076552 -375.455434)
		(size 0.6604)
		(drill 0.3302)
		(layers "F.Cu" "B.Cu")
		(net "GND")
	)
	(via
		(at 158.754826 -407.00452)
		(size 0.4064)
		(drill 0.2032)
		(layers "F.Cu" "B.Cu")
		(net "GND")
	)
	(via
		(at 386.804916 -264.365994)
		(size 0.4064)
		(drill 0.2032)
		(layers "F.Cu" "B.Cu")
		(net "GND")
	)
	(via
		(at 283.784802 -406.787604)
		(size 0.508)
		(drill 0.254)
		(layers "F.Cu" "B.Cu")
		(net "GND")
	)
	(via
		(at 439.100214 -271.284954)
		(size 0.4826)
		(drill 0.254)
		(layers "F.Cu" "B.Cu")
		(net "GND")
	)
	(via
		(at 369.114832 -229.904036)
		(size 0.4064)
		(drill 0.2032)
		(layers "F.Cu" "B.Cu")
		(net "GND")
	)
	(via
		(at 229.602538 -324.349872)
		(size 0.508)
		(drill 0.254)
		(layers "F.Cu" "B.Cu")
		(net "GND")
	)
	(via
		(at 338.401152 -286.236156)
		(size 0.4064)
		(drill 0.2032)
		(layers "F.Cu" "B.Cu")
		(net "GND")
	)
	(via
		(at 125.704854 -280.566368)
		(size 0.4064)
		(drill 0.2032)
		(layers "F.Cu" "B.Cu")
		(net "GND")
	)
	(via
		(at 428.900336 -394.534136)
		(size 0.508)
		(drill 0.254)
		(layers "F.Cu" "B.Cu")
		(net "GND")
	)
	(via
		(at 133.30047 -154.542744)
		(size 0.49022)
		(drill 0.254)
		(layers "F.Cu" "B.Cu")
		(net "GND")
	)
	(via
		(at 199.393556 -343.118948)
		(size 0.508)
		(drill 0.254)
		(layers "F.Cu" "B.Cu")
		(net "GND")
	)
	(via
		(at 113.65484 -238.00435)
		(size 0.4064)
		(drill 0.2032)
		(layers "F.Cu" "B.Cu")
		(net "GND")
	)
	(via
		(at 80.591152 -277.326344)
		(size 0.4064)
		(drill 0.2032)
		(layers "F.Cu" "B.Cu")
		(net "GND")
	)
	(via
		(at 299.82414 -267.035026)
		(size 0.4826)
		(drill 0.254)
		(layers "F.Cu" "B.Cu")
		(net "GND")
	)
	(via
		(at 179.516024 -279.785318)
		(size 0.4826)
		(drill 0.254)
		(layers "F.Cu" "B.Cu")
		(net "GND")
	)
	(via
		(at 413.349694 -432.451256)
		(size 0.4572)
		(drill 0.2032)
		(layers "F.Cu" "B.Cu")
		(net "GND")
	)
	(via
		(at 344.306144 -394.831062)
		(size 0.4064)
		(drill 0.2032)
		(layers "F.Cu" "B.Cu")
		(net "GND")
	)
	(via
		(at 65.90665 -168.36263)
		(size 0.49022)
		(drill 0.254)
		(layers "F.Cu" "B.Cu")
		(net "GND")
	)
	(via
		(at 235.0008 -285.608522)
		(size 0.508)
		(drill 0.254)
		(layers "F.Cu" "B.Cu")
		(net "GND")
	)
	(via
		(at 124.934726 -254.20447)
		(size 0.4064)
		(drill 0.2032)
		(layers "F.Cu" "B.Cu")
		(net "GND")
	)
	(via
		(at 395.046962 -315.609478)
		(size 0.508)
		(drill 0.254)
		(layers "F.Cu" "B.Cu")
		(net "GND")
	)
	(via
		(at 183.616092 -267.03528)
		(size 0.4826)
		(drill 0.254)
		(layers "F.Cu" "B.Cu")
		(net "GND")
	)
	(via
		(at 153.865834 -321.842892)
		(size 0.508)
		(drill 0.254)
		(layers "F.Cu" "B.Cu")
		(net "GND")
	)
	(via
		(at 34.080196 -284.885384)
		(size 0.4826)
		(drill 0.254)
		(layers "F.Cu" "B.Cu")
		(net "GND")
	)
	(via
		(at 391.583164 -17.61236)
		(size 0.508)
		(drill 0.254)
		(layers "F.Cu" "B.Cu")
		(net "GND")
	)
	(via
		(at 375.858278 -183.60771)
		(size 0.508)
		(drill 0.254)
		(layers "F.Cu" "B.Cu")
		(net "GND")
	)
	(via
		(at 342.249506 -436.051198)
		(size 0.4572)
		(drill 0.2032)
		(layers "F.Cu" "B.Cu")
		(net "GND")
	)
	(via
		(at 348.271084 -270.846042)
		(size 0.4064)
		(drill 0.2032)
		(layers "F.Cu" "B.Cu")
		(net "GND")
	)
	(via
		(at 425.96562 -10.16508)
		(size 0.508)
		(drill 0.254)
		(layers "F.Cu" "B.Cu")
		(net "GND")
	)
	(via
		(at 364.53064 -391.41146)
		(size 0.508)
		(drill 0.254)
		(layers "F.Cu" "B.Cu")
		(net "GND")
	)
	(via
		(at 355.491034 -230.714042)
		(size 0.4064)
		(drill 0.2032)
		(layers "F.Cu" "B.Cu")
		(net "GND")
	)
	(via
		(at 140.942822 -80.681322)
		(size 0.508)
		(drill 0.254)
		(layers "F.Cu" "B.Cu")
		(net "GND")
	)
	(via
		(at 435.000146 -292.535102)
		(size 0.4826)
		(drill 0.254)
		(layers "F.Cu" "B.Cu")
		(net "GND")
	)
	(via
		(at 271.253966 -339.776308)
		(size 0.508)
		(drill 0.254)
		(layers "F.Cu" "B.Cu")
		(net "GND")
	)
	(via
		(at 106.611166 -246.914416)
		(size 0.4064)
		(drill 0.2032)
		(layers "F.Cu" "B.Cu")
		(net "GND")
	)
	(via
		(at 327.249536 -437.49976)
		(size 0.4572)
		(drill 0.2032)
		(layers "F.Cu" "B.Cu")
		(net "GND")
	)
	(via
		(at 49.159414 -373.30253)
		(size 0.508)
		(drill 0.254)
		(layers "F.Cu" "B.Cu")
		(net "GND")
	)
	(via
		(at 190.004446 -193.996564)
		(size 0.4826)
		(drill 0.254)
		(layers "F.Cu" "B.Cu")
		(net "GND")
	)
	(via
		(at 138.564874 -251.774452)
		(size 0.4064)
		(drill 0.2032)
		(layers "F.Cu" "B.Cu")
		(net "GND")
	)
	(via
		(at 128.659636 -373.30253)
		(size 0.508)
		(drill 0.254)
		(layers "F.Cu" "B.Cu")
		(net "GND")
	)
	(via
		(at 22.41804 -6.091174)
		(size 0.508)
		(drill 0.254)
		(layers "F.Cu" "B.Cu")
		(net "GND")
	)
	(via
		(at 309.08625 -433.279804)
		(size 0.508)
		(drill 0.254)
		(layers "F.Cu" "B.Cu")
		(net "GND")
	)
	(via
		(at 240.031524 -150.776686)
		(size 0.508)
		(drill 0.254)
		(layers "F.Cu" "B.Cu")
		(net "GND")
	)
	(via
		(at 295.724072 -311.23509)
		(size 0.4826)
		(drill 0.254)
		(layers "F.Cu" "B.Cu")
		(net "GND")
	)
	(via
		(at 156.60624 -386.449062)
		(size 0.4064)
		(drill 0.2032)
		(layers "F.Cu" "B.Cu")
		(net "GND")
	)
	(via
		(at 277.192232 -263.634982)
		(size 0.4826)
		(drill 0.254)
		(layers "F.Cu" "B.Cu")
		(net "GND")
	)
	(via
		(at 126.814834 -236.384338)
		(size 0.4064)
		(drill 0.2032)
		(layers "F.Cu" "B.Cu")
		(net "GND")
	)
	(via
		(at 186.932316 -331.532484)
		(size 0.508)
		(drill 0.254)
		(layers "F.Cu" "B.Cu")
		(net "GND")
	)
	(via
		(at 304.423826 -194.88531)
		(size 0.4826)
		(drill 0.254)
		(layers "F.Cu" "B.Cu")
		(net "GND")
	)
	(via
		(at 23.114 -342.9762)
		(size 0.49022)
		(drill 0.254)
		(layers "F.Cu" "B.Cu")
		(net "GND")
	)
	(via
		(at 43.624754 -4.963414)
		(size 0.508)
		(drill 0.254)
		(layers "F.Cu" "B.Cu")
		(net "GND")
	)
	(via
		(at 151.044148 -391.830814)
		(size 0.4064)
		(drill 0.2032)
		(layers "F.Cu" "B.Cu")
		(net "GND")
	)
	(via
		(at 197.3199 -284.035246)
		(size 0.4826)
		(drill 0.254)
		(layers "F.Cu" "B.Cu")
		(net "GND")
	)
	(via
		(at 99.561142 -241.244374)
		(size 0.4064)
		(drill 0.2032)
		(layers "F.Cu" "B.Cu")
		(net "GND")
	)
	(via
		(at 442.5442 -267.885164)
		(size 0.4826)
		(drill 0.254)
		(layers "F.Cu" "B.Cu")
		(net "GND")
	)
	(via
		(at 428.840392 -219.435172)
		(size 0.4826)
		(drill 0.254)
		(layers "F.Cu" "B.Cu")
		(net "GND")
	)
	(via
		(at 292.655244 -398.924018)
		(size 0.508)
		(drill 0.254)
		(layers "F.Cu" "B.Cu")
		(net "GND")
	)
	(via
		(at 243.184934 -40.055546)
		(size 0.508)
		(drill 0.254)
		(layers "F.Cu" "B.Cu")
		(net "GND")
	)
	(via
		(at 352.671126 -237.19409)
		(size 0.4064)
		(drill 0.2032)
		(layers "F.Cu" "B.Cu")
		(net "GND")
	)
	(via
		(at 266.93241 -275.535136)
		(size 0.4826)
		(drill 0.254)
		(layers "F.Cu" "B.Cu")
		(net "GND")
	)
	(via
		(at 94.803976 -403.830536)
		(size 0.4572)
		(drill 0.254)
		(layers "F.Cu" "B.Cu")
		(net "GND")
	)
	(via
		(at 365.19104 -384.175)
		(size 0.508)
		(drill 0.254)
		(layers "F.Cu" "B.Cu")
		(net "GND")
	)
	(via
		(at 274.476464 -219.435172)
		(size 0.4826)
		(drill 0.254)
		(layers "F.Cu" "B.Cu")
		(net "GND")
	)
	(via
		(at 273.092164 -204.985112)
		(size 0.4826)
		(drill 0.254)
		(layers "F.Cu" "B.Cu")
		(net "GND")
	)
	(via
		(at 55.862474 -384.617722)
		(size 0.4064)
		(drill 0.2032)
		(layers "F.Cu" "B.Cu")
		(net "GND")
	)
	(via
		(at 306.659534 -412.212536)
		(size 0.4572)
		(drill 0.254)
		(layers "F.Cu" "B.Cu")
		(net "GND")
	)
	(via
		(at 427.915832 -331.78369)
		(size 0.508)
		(drill 0.254)
		(layers "F.Cu" "B.Cu")
		(net "GND")
	)
	(via
		(at 288.180018 -262.785098)
		(size 0.4826)
		(drill 0.254)
		(layers "F.Cu" "B.Cu")
		(net "GND")
	)
	(via
		(at 440.086496 -330.788772)
		(size 0.508)
		(drill 0.254)
		(layers "F.Cu" "B.Cu")
		(net "GND")
	)
	(via
		(at 427.907958 -365.825532)
		(size 0.508)
		(drill 0.254)
		(layers "F.Cu" "B.Cu")
		(net "GND")
	)
	(via
		(at 122.884692 -267.606272)
		(size 0.4064)
		(drill 0.2032)
		(layers "F.Cu" "B.Cu")
		(net "GND")
	)
	(via
		(at 108.02112 -233.144314)
		(size 0.4064)
		(drill 0.2032)
		(layers "F.Cu" "B.Cu")
		(net "GND")
	)
	(via
		(at 121.539 -432.054)
		(size 0.508)
		(drill 0.254)
		(layers "F.Cu" "B.Cu")
		(net "GND")
	)
	(via
		(at 78.518004 -340.134702)
		(size 0.508)
		(drill 0.254)
		(layers "F.Cu" "B.Cu")
		(net "GND")
	)
	(via
		(at 135.755634 -151.380698)
		(size 0.508)
		(drill 0.254)
		(layers "F.Cu" "B.Cu")
		(net "GND")
	)
	(via
		(at 246.634 -330.2)
		(size 0.508)
		(drill 0.254)
		(layers "F.Cu" "B.Cu")
		(net "GND")
	)
	(via
		(at 34.937954 -339.793834)
		(size 0.508)
		(drill 0.254)
		(layers "F.Cu" "B.Cu")
		(net "GND")
	)
	(via
		(at 125.418342 -388.328662)
		(size 0.4064)
		(drill 0.2032)
		(layers "F.Cu" "B.Cu")
		(net "GND")
	)
	(via
		(at 437.715914 -227.935028)
		(size 0.4826)
		(drill 0.254)
		(layers "F.Cu" "B.Cu")
		(net "GND")
	)
	(via
		(at 363.87024 -384.175)
		(size 0.508)
		(drill 0.254)
		(layers "F.Cu" "B.Cu")
		(net "GND")
	)
	(via
		(at 171.018454 -53.678328)
		(size 0.508)
		(drill 0.254)
		(layers "F.Cu" "B.Cu")
		(net "GND")
	)
	(via
		(at 117.44071 -259.330444)
		(size 0.4826)
		(drill 0.254)
		(layers "F.Cu" "B.Cu")
		(net "GND")
	)
	(via
		(at 389.655812 -177.602134)
		(size 0.508)
		(drill 0.254)
		(layers "F.Cu" "B.Cu")
		(net "GND")
	)
	(via
		(at 25.511506 -423.509694)
		(size 0.508)
		(drill 0.254)
		(layers "F.Cu" "B.Cu")
		(net "GND")
	)
	(via
		(at 435.498748 -347.235526)
		(size 0.508)
		(drill 0.254)
		(layers "F.Cu" "B.Cu")
		(net "GND")
	)
	(via
		(at 431.099468 -4.32943)
		(size 0.508)
		(drill 0.254)
		(layers "F.Cu" "B.Cu")
		(net "GND")
	)
	(via
		(at 347.031056 -224.234248)
		(size 0.4064)
		(drill 0.2032)
		(layers "F.Cu" "B.Cu")
		(net "GND")
	)
	(via
		(at 267.127736 -343.083896)
		(size 0.49022)
		(drill 0.254)
		(layers "F.Cu" "B.Cu")
		(net "GND")
	)
	(via
		(at 344.511122 -290.285932)
		(size 0.4064)
		(drill 0.2032)
		(layers "F.Cu" "B.Cu")
		(net "GND")
	)
	(via
		(at 116.004848 -230.714296)
		(size 0.4064)
		(drill 0.2032)
		(layers "F.Cu" "B.Cu")
		(net "GND")
	)
	(via
		(at 410.245814 -414.752536)
		(size 0.4572)
		(drill 0.254)
		(layers "F.Cu" "B.Cu")
		(net "GND")
	)
	(via
		(at 67.14109 -168.36263)
		(size 0.49022)
		(drill 0.254)
		(layers "F.Cu" "B.Cu")
		(net "GND")
	)
	(via
		(at 97.601786 -142.856204)
		(size 0.508)
		(drill 0.254)
		(layers "F.Cu" "B.Cu")
		(net "GND")
	)
	(via
		(at 116.004848 -235.574332)
		(size 0.4064)
		(drill 0.2032)
		(layers "F.Cu" "B.Cu")
		(net "GND")
	)
	(via
		(at 269.648178 -278.93518)
		(size 0.4826)
		(drill 0.254)
		(layers "F.Cu" "B.Cu")
		(net "GND")
	)
	(via
		(at 384.924808 -293.525956)
		(size 0.4064)
		(drill 0.2032)
		(layers "F.Cu" "B.Cu")
		(net "GND")
	)
	(via
		(at 56.786272 -405.098504)
		(size 0.4572)
		(drill 0.254)
		(layers "F.Cu" "B.Cu")
		(net "GND")
	)
	(via
		(at 34.080196 -238.135414)
		(size 0.4826)
		(drill 0.254)
		(layers "F.Cu" "B.Cu")
		(net "GND")
	)
	(via
		(at 143.264636 -240.434368)
		(size 0.4064)
		(drill 0.2032)
		(layers "F.Cu" "B.Cu")
		(net "GND")
	)
	(via
		(at 287.97631 -399.313908)
		(size 0.508)
		(drill 0.254)
		(layers "F.Cu" "B.Cu")
		(net "GND")
	)
	(via
		(at 116.987066 -173.073568)
		(size 0.49022)
		(drill 0.254)
		(layers "F.Cu" "B.Cu")
		(net "GND")
	)
	(via
		(at 29.69387 -386.80009)
		(size 0.508)
		(drill 0.254)
		(layers "F.Cu" "B.Cu")
		(net "GND")
	)
	(via
		(at 329.6412 -242.864132)
		(size 0.4064)
		(drill 0.2032)
		(layers "F.Cu" "B.Cu")
		(net "GND")
	)
	(via
		(at 388.21487 -276.516084)
		(size 0.4064)
		(drill 0.2032)
		(layers "F.Cu" "B.Cu")
		(net "GND")
	)
	(via
		(at 382.1049 -270.846042)
		(size 0.4064)
		(drill 0.2032)
		(layers "F.Cu" "B.Cu")
		(net "GND")
	)
	(via
		(at 145.444718 -272.466308)
		(size 0.4064)
		(drill 0.2032)
		(layers "F.Cu" "B.Cu")
		(net "GND")
	)
	(via
		(at 286.377634 -102.816152)
		(size 0.508)
		(drill 0.254)
		(layers "F.Cu" "B.Cu")
		(net "GND")
	)
	(via
		(at 219.743528 -83.413346)
		(size 0.508)
		(drill 0.254)
		(layers "F.Cu" "B.Cu")
		(net "GND")
	)
	(via
		(at 126.689104 -53.15839)
		(size 0.508)
		(drill 0.254)
		(layers "F.Cu" "B.Cu")
		(net "GND")
	)
	(via
		(at 139.974828 -255.824482)
		(size 0.4064)
		(drill 0.2032)
		(layers "F.Cu" "B.Cu")
		(net "GND")
	)
	(via
		(at 25.337516 -39.574978)
		(size 0.508)
		(drill 0.254)
		(layers "F.Cu" "B.Cu")
		(net "GND")
	)
	(via
		(at 167.143684 -199.8853)
		(size 0.4826)
		(drill 0.254)
		(layers "F.Cu" "B.Cu")
		(net "GND")
	)
	(via
		(at 305.983894 -284.034992)
		(size 0.4826)
		(drill 0.254)
		(layers "F.Cu" "B.Cu")
		(net "GND")
	)
	(via
		(at 50.298604 -412.570168)
		(size 0.4064)
		(drill 0.2032)
		(layers "F.Cu" "B.Cu")
		(net "GND")
	)
	(via
		(at 174.037498 -347.6498)
		(size 0.508)
		(drill 0.254)
		(layers "F.Cu" "B.Cu")
		(net "GND")
	)
	(via
		(at 419.76294 -100.260658)
		(size 0.508)
		(drill 0.254)
		(layers "F.Cu" "B.Cu")
		(net "GND")
	)
	(via
		(at 117.398546 -412.570168)
		(size 0.4064)
		(drill 0.2032)
		(layers "F.Cu" "B.Cu")
		(net "GND")
	)
	(via
		(at 307.368194 -271.284954)
		(size 0.4826)
		(drill 0.254)
		(layers "F.Cu" "B.Cu")
		(net "GND")
	)
	(via
		(at 439.100214 -196.485002)
		(size 0.4826)
		(drill 0.254)
		(layers "F.Cu" "B.Cu")
		(net "GND")
	)
	(via
		(at 82.446368 -388.328662)
		(size 0.4064)
		(drill 0.2032)
		(layers "F.Cu" "B.Cu")
		(net "GND")
	)
	(via
		(at 165.041834 -128.456944)
		(size 0.508)
		(drill 0.254)
		(layers "F.Cu" "B.Cu")
		(net "GND")
	)
	(via
		(at 120.70461 -232.334308)
		(size 0.4064)
		(drill 0.2032)
		(layers "F.Cu" "B.Cu")
		(net "GND")
	)
	(via
		(at 100.031042 -243.674392)
		(size 0.4064)
		(drill 0.2032)
		(layers "F.Cu" "B.Cu")
		(net "GND")
	)
	(via
		(at 84.009738 -334.057244)
		(size 0.49022)
		(drill 0.254)
		(layers "F.Cu" "B.Cu")
		(net "GND")
	)
	(via
		(at 67.596004 -404.46452)
		(size 0.4064)
		(drill 0.2032)
		(layers "F.Cu" "B.Cu")
		(net "GND")
	)
	(via
		(at 337.930998 -270.846042)
		(size 0.4064)
		(drill 0.2032)
		(layers "F.Cu" "B.Cu")
		(net "GND")
	)
	(via
		(at 471.037666 -67.173094)
		(size 0.508)
		(drill 0.254)
		(layers "F.Cu" "B.Cu")
		(net "GND")
	)
	(via
		(at 40.024812 -4.963414)
		(size 0.508)
		(drill 0.254)
		(layers "F.Cu" "B.Cu")
		(net "GND")
	)
	(via
		(at 357.201216 -266.796012)
		(size 0.4064)
		(drill 0.2032)
		(layers "F.Cu" "B.Cu")
		(net "GND")
	)
	(via
		(at 203.265532 -220.710252)
		(size 0.4826)
		(drill 0.254)
		(layers "F.Cu" "B.Cu")
		(net "GND")
	)
	(via
		(at 168.527984 -244.935248)
		(size 0.4826)
		(drill 0.254)
		(layers "F.Cu" "B.Cu")
		(net "GND")
	)
	(via
		(at 83.580986 -255.824482)
		(size 0.4064)
		(drill 0.2032)
		(layers "F.Cu" "B.Cu")
		(net "GND")
	)
	(via
		(at 126.814834 -234.764326)
		(size 0.4064)
		(drill 0.2032)
		(layers "F.Cu" "B.Cu")
		(net "GND")
	)
	(via
		(at 353.141026 -229.904036)
		(size 0.4064)
		(drill 0.2032)
		(layers "F.Cu" "B.Cu")
		(net "GND")
	)
	(via
		(at 141.718792 -382.54432)
		(size 0.508)
		(drill 0.254)
		(layers "F.Cu" "B.Cu")
		(net "GND")
	)
	(via
		(at 431.127154 -441.227718)
		(size 0.508)
		(drill 0.254)
		(layers "F.Cu" "B.Cu")
		(net "GND")
	)
	(via
		(at 88.506046 -183.090058)
		(size 0.49022)
		(drill 0.254)
		(layers "F.Cu" "B.Cu")
		(net "GND")
	)
	(via
		(at 167.372284 -193.996564)
		(size 0.4826)
		(drill 0.254)
		(layers "F.Cu" "B.Cu")
		(net "GND")
	)
	(via
		(at 51.766978 -430.876964)
		(size 0.508)
		(drill 0.254)
		(layers "F.Cu" "B.Cu")
		(net "GND")
	)
	(via
		(at 55.328058 -273.835368)
		(size 0.4826)
		(drill 0.254)
		(layers "F.Cu" "B.Cu")
		(net "GND")
	)
	(via
		(at 124.7648 -277.326344)
		(size 0.4064)
		(drill 0.2032)
		(layers "F.Cu" "B.Cu")
		(net "GND")
	)
	(via
		(at 326.617076 -384.299968)
		(size 0.508)
		(drill 0.254)
		(layers "F.Cu" "B.Cu")
		(net "GND")
	)
	(via
		(at 309.46217 -392.999722)
		(size 0.4064)
		(drill 0.2032)
		(layers "F.Cu" "B.Cu")
		(net "GND")
	)
	(via
		(at 331.521054 -242.864132)
		(size 0.4064)
		(drill 0.2032)
		(layers "F.Cu" "B.Cu")
		(net "GND")
	)
	(via
		(at 133.394704 -255.824482)
		(size 0.4064)
		(drill 0.2032)
		(layers "F.Cu" "B.Cu")
		(net "GND")
	)
	(via
		(at 39.12235 -230.0605)
		(size 0.4826)
		(drill 0.254)
		(layers "F.Cu" "B.Cu")
		(net "GND")
	)
	(via
		(at 171.35348 -389.958834)
		(size 0.508)
		(drill 0.254)
		(layers "F.Cu" "B.Cu")
		(net "GND")
	)
	(via
		(at 109.431074 -225.854514)
		(size 0.4064)
		(drill 0.2032)
		(layers "F.Cu" "B.Cu")
		(net "GND")
	)
	(via
		(at 381.334772 -233.14406)
		(size 0.4064)
		(drill 0.2032)
		(layers "F.Cu" "B.Cu")
		(net "GND")
	)
	(via
		(at 328.188828 -43.573954)
		(size 0.508)
		(drill 0.254)
		(layers "F.Cu" "B.Cu")
		(net "GND")
	)
	(via
		(at 445.282066 -406.4381)
		(size 0.508)
		(drill 0.254)
		(layers "F.Cu" "B.Cu")
		(net "GND")
	)
	(via
		(at 64.178688 -386.449062)
		(size 0.4064)
		(drill 0.2032)
		(layers "F.Cu" "B.Cu")
		(net "GND")
	)
	(via
		(at 289.564318 -212.635084)
		(size 0.4826)
		(drill 0.254)
		(layers "F.Cu" "B.Cu")
		(net "GND")
	)
	(via
		(at 391.504678 -293.525956)
		(size 0.4064)
		(drill 0.2032)
		(layers "F.Cu" "B.Cu")
		(net "GND")
	)
	(via
		(at 86.871048 -255.014476)
		(size 0.4064)
		(drill 0.2032)
		(layers "F.Cu" "B.Cu")
		(net "GND")
	)
	(via
		(at 105.200958 -228.284532)
		(size 0.4064)
		(drill 0.2032)
		(layers "F.Cu" "B.Cu")
		(net "GND")
	)
	(via
		(at 288.180018 -279.785064)
		(size 0.4826)
		(drill 0.254)
		(layers "F.Cu" "B.Cu")
		(net "GND")
	)
	(via
		(at 59.307222 -171.934124)
		(size 0.508)
		(drill 0.254)
		(layers "F.Cu" "B.Cu")
		(net "GND")
	)
	(via
		(at 36.665662 -418.239448)
		(size 0.508)
		(drill 0.254)
		(layers "F.Cu" "B.Cu")
		(net "GND")
	)
	(via
		(at 255.927098 -195.57492)
		(size 0.508)
		(drill 0.254)
		(layers "F.Cu" "B.Cu")
		(net "GND")
	)
	(via
		(at 94.622112 -58.892186)
		(size 0.508)
		(drill 0.254)
		(layers "F.Cu" "B.Cu")
		(net "GND")
	)
	(via
		(at 135.274812 -252.584458)
		(size 0.4064)
		(drill 0.2032)
		(layers "F.Cu" "B.Cu")
		(net "GND")
	)
	(via
		(at 102.108762 -368.37493)
		(size 0.508)
		(drill 0.254)
		(layers "F.Cu" "B.Cu")
		(net "GND")
	)
	(via
		(at 140.444728 -243.674392)
		(size 0.4064)
		(drill 0.2032)
		(layers "F.Cu" "B.Cu")
		(net "GND")
	)
	(via
		(at 123.354846 -292.716204)
		(size 0.4064)
		(drill 0.2032)
		(layers "F.Cu" "B.Cu")
		(net "GND")
	)
	(via
		(at 125.267466 -166.342568)
		(size 0.49022)
		(drill 0.254)
		(layers "F.Cu" "B.Cu")
		(net "GND")
	)
	(via
		(at 350.621092 -287.856168)
		(size 0.4064)
		(drill 0.2032)
		(layers "F.Cu" "B.Cu")
		(net "GND")
	)
	(via
		(at 121.644664 -238.814356)
		(size 0.4064)
		(drill 0.2032)
		(layers "F.Cu" "B.Cu")
		(net "GND")
	)
	(via
		(at 177.189638 -313.360308)
		(size 0.4826)
		(drill 0.254)
		(layers "F.Cu" "B.Cu")
		(net "GND")
	)
	(via
		(at 213.01202 -386.470652)
		(size 0.508)
		(drill 0.254)
		(layers "F.Cu" "B.Cu")
		(net "GND")
	)
	(via
		(at 450.088 -242.385088)
		(size 0.4826)
		(drill 0.254)
		(layers "F.Cu" "B.Cu")
		(net "GND")
	)
	(via
		(at 124.516388 -391.830814)
		(size 0.4064)
		(drill 0.2032)
		(layers "F.Cu" "B.Cu")
		(net "GND")
	)
	(via
		(at 181.504082 -149.261068)
		(size 0.508)
		(drill 0.254)
		(layers "F.Cu" "B.Cu")
		(net "GND")
	)
	(via
		(at 452.803768 -202.434952)
		(size 0.4826)
		(drill 0.254)
		(layers "F.Cu" "B.Cu")
		(net "GND")
	)
	(via
		(at 132.924804 -250.15444)
		(size 0.4064)
		(drill 0.2032)
		(layers "F.Cu" "B.Cu")
		(net "GND")
	)
	(via
		(at 45.105066 -388.29615)
		(size 0.4064)
		(drill 0.2032)
		(layers "F.Cu" "B.Cu")
		(net "GND")
	)
	(via
		(at 275.807932 -202.434952)
		(size 0.4826)
		(drill 0.254)
		(layers "F.Cu" "B.Cu")
		(net "GND")
	)
	(via
		(at 401.056094 -417.778184)
		(size 0.4572)
		(drill 0.254)
		(layers "F.Cu" "B.Cu")
		(net "GND")
	)
	(via
		(at 76.249784 -437.49976)
		(size 0.4572)
		(drill 0.2032)
		(layers "F.Cu" "B.Cu")
		(net "GND")
	)
	(via
		(at 341.090504 -378.07773)
		(size 0.508)
		(drill 0.254)
		(layers "F.Cu" "B.Cu")
		(net "GND")
	)
	(via
		(at 105.200958 -244.484398)
		(size 0.4064)
		(drill 0.2032)
		(layers "F.Cu" "B.Cu")
		(net "GND")
	)
	(via
		(at 104.9528 -409.6258)
		(size 0.508)
		(drill 0.254)
		(layers "F.Cu" "B.Cu")
		(net "GND")
	)
	(via
		(at 413.228028 -6.091174)
		(size 0.508)
		(drill 0.254)
		(layers "F.Cu" "B.Cu")
		(net "GND")
	)
	(via
		(at 331.833474 -37.92982)
		(size 0.508)
		(drill 0.254)
		(layers "F.Cu" "B.Cu")
		(net "GND")
	)
	(via
		(at 367.064798 -283.806138)
		(size 0.4064)
		(drill 0.2032)
		(layers "F.Cu" "B.Cu")
		(net "GND")
	)
	(via
		(at 40.23995 -255.13538)
		(size 0.4826)
		(drill 0.254)
		(layers "F.Cu" "B.Cu")
		(net "GND")
	)
	(via
		(at 88.281002 -252.584458)
		(size 0.4064)
		(drill 0.2032)
		(layers "F.Cu" "B.Cu")
		(net "GND")
	)
	(via
		(at 46.666404 -220.710252)
		(size 0.4826)
		(drill 0.254)
		(layers "F.Cu" "B.Cu")
		(net "GND")
	)
	(via
		(at 372.704868 -285.42615)
		(size 0.4064)
		(drill 0.2032)
		(layers "F.Cu" "B.Cu")
		(net "GND")
	)
	(via
		(at 420.59098 -378.07773)
		(size 0.508)
		(drill 0.254)
		(layers "F.Cu" "B.Cu")
		(net "GND")
	)
	(via
		(at 391.504678 -291.905944)
		(size 0.4064)
		(drill 0.2032)
		(layers "F.Cu" "B.Cu")
		(net "GND")
	)
	(via
		(at 118.824756 -230.71455)
		(size 0.4064)
		(drill 0.2032)
		(layers "F.Cu" "B.Cu")
		(net "GND")
	)
	(via
		(at 378.344938 -283.806138)
		(size 0.4064)
		(drill 0.2032)
		(layers "F.Cu" "B.Cu")
		(net "GND")
	)
	(via
		(at 393.717272 -385.514088)
		(size 0.508)
		(drill 0.254)
		(layers "F.Cu" "B.Cu")
		(net "GND")
	)
	(via
		(at 100.031042 -250.15444)
		(size 0.4064)
		(drill 0.2032)
		(layers "F.Cu" "B.Cu")
		(net "GND")
	)
	(via
		(at 125.417834 -410.664152)
		(size 0.4572)
		(drill 0.254)
		(layers "F.Cu" "B.Cu")
		(net "GND")
	)
	(via
		(at 124.22505 -164.626544)
		(size 0.49022)
		(drill 0.254)
		(layers "F.Cu" "B.Cu")
		(net "GND")
	)
	(via
		(at 218.066112 -66.645028)
		(size 0.508)
		(drill 0.254)
		(layers "F.Cu" "B.Cu")
		(net "GND")
	)
	(via
		(at 350.791018 -229.094284)
		(size 0.4064)
		(drill 0.2032)
		(layers "F.Cu" "B.Cu")
		(net "GND")
	)
	(via
		(at 47.784004 -272.135346)
		(size 0.4826)
		(drill 0.254)
		(layers "F.Cu" "B.Cu")
		(net "GND")
	)
	(via
		(at 419.650418 -165.716712)
		(size 0.508)
		(drill 0.254)
		(layers "F.Cu" "B.Cu")
		(net "GND")
	)
	(via
		(at 390.349486 -430.299622)
		(size 0.4572)
		(drill 0.2032)
		(layers "F.Cu" "B.Cu")
		(net "GND")
	)
	(via
		(at 51.884072 -253.435358)
		(size 0.4826)
		(drill 0.254)
		(layers "F.Cu" "B.Cu")
		(net "GND")
	)
	(via
		(at 79.918814 -390.160002)
		(size 0.4064)
		(drill 0.2032)
		(layers "F.Cu" "B.Cu")
		(net "GND")
	)
	(via
		(at 13.67155 -107.123484)
		(size 0.508)
		(drill 0.254)
		(layers "F.Cu" "B.Cu")
		(net "GND")
	)
	(via
		(at 98.451162 -295.146222)
		(size 0.4064)
		(drill 0.2032)
		(layers "F.Cu" "B.Cu")
		(net "GND")
	)
	(via
		(at 106.405172 -261.230364)
		(size 0.4826)
		(drill 0.254)
		(layers "F.Cu" "B.Cu")
		(net "GND")
	)
	(via
		(at 416.372294 -417.778184)
		(size 0.4572)
		(drill 0.254)
		(layers "F.Cu" "B.Cu")
		(net "GND")
	)
	(via
		(at 283.618432 -304.01006)
		(size 0.4826)
		(drill 0.254)
		(layers "F.Cu" "B.Cu")
		(net "GND")
	)
	(via
		(at 101.74097 -295.956228)
		(size 0.4064)
		(drill 0.2032)
		(layers "F.Cu" "B.Cu")
		(net "GND")
	)
	(via
		(at 92.013532 -410.664152)
		(size 0.4572)
		(drill 0.254)
		(layers "F.Cu" "B.Cu")
		(net "GND")
	)
	(via
		(at 80.57896 -64.25438)
		(size 0.508)
		(drill 0.254)
		(layers "F.Cu" "B.Cu")
		(net "GND")
	)
	(via
		(at 399.480024 -19.771106)
		(size 0.508)
		(drill 0.254)
		(layers "F.Cu" "B.Cu")
		(net "GND")
	)
	(via
		(at 423.99458 -378.07773)
		(size 0.508)
		(drill 0.254)
		(layers "F.Cu" "B.Cu")
		(net "GND")
	)
	(via
		(at 358.61117 -283.806138)
		(size 0.4064)
		(drill 0.2032)
		(layers "F.Cu" "B.Cu")
		(net "GND")
	)
	(via
		(at 386.504942 -238.814102)
		(size 0.4064)
		(drill 0.2032)
		(layers "F.Cu" "B.Cu")
		(net "GND")
	)
	(via
		(at 115.367816 -264.36828)
		(size 0.4064)
		(drill 0.2032)
		(layers "F.Cu" "B.Cu")
		(net "GND")
	)
	(via
		(at 26.536396 -315.485272)
		(size 0.4826)
		(drill 0.254)
		(layers "F.Cu" "B.Cu")
		(net "GND")
	)
	(via
		(at 118.999 -433.959)
		(size 0.508)
		(drill 0.254)
		(layers "F.Cu" "B.Cu")
		(net "GND")
	)
	(via
		(at 139.825222 -159.742124)
		(size 0.6604)
		(drill 0.3302)
		(layers "F.Cu" "B.Cu")
		(net "GND")
	)
	(via
		(at 382.1049 -274.086066)
		(size 0.4064)
		(drill 0.2032)
		(layers "F.Cu" "B.Cu")
		(net "GND")
	)
	(via
		(at 450.088 -247.485154)
		(size 0.4826)
		(drill 0.254)
		(layers "F.Cu" "B.Cu")
		(net "GND")
	)
	(via
		(at 88.82253 -72.824848)
		(size 0.508)
		(drill 0.254)
		(layers "F.Cu" "B.Cu")
		(net "GND")
	)
	(via
		(at 43.85564 -10.16508)
		(size 0.508)
		(drill 0.254)
		(layers "F.Cu" "B.Cu")
		(net "GND")
	)
	(via
		(at 176.072038 -316.33541)
		(size 0.4826)
		(drill 0.254)
		(layers "F.Cu" "B.Cu")
		(net "GND")
	)
	(via
		(at 393.084812 -243.674138)
		(size 0.4064)
		(drill 0.2032)
		(layers "F.Cu" "B.Cu")
		(net "GND")
	)
	(via
		(at 294.606472 -276.810216)
		(size 0.4826)
		(drill 0.254)
		(layers "F.Cu" "B.Cu")
		(net "GND")
	)
	(via
		(at 160.206182 -386.449062)
		(size 0.4064)
		(drill 0.2032)
		(layers "F.Cu" "B.Cu")
		(net "GND")
	)
	(via
		(at 284.736032 -299.33519)
		(size 0.4826)
		(drill 0.254)
		(layers "F.Cu" "B.Cu")
		(net "GND")
	)
	(via
		(at 18.763742 -192.218564)
		(size 0.4826)
		(drill 0.254)
		(layers "F.Cu" "B.Cu")
		(net "GND")
	)
	(via
		(at 121.644664 -240.434368)
		(size 0.4064)
		(drill 0.2032)
		(layers "F.Cu" "B.Cu")
		(net "GND")
	)
	(via
		(at 133.864858 -253.394464)
		(size 0.4064)
		(drill 0.2032)
		(layers "F.Cu" "B.Cu")
		(net "GND")
	)
	(via
		(at 383.984754 -293.525956)
		(size 0.4064)
		(drill 0.2032)
		(layers "F.Cu" "B.Cu")
		(net "GND")
	)
	(via
		(at 394.349478 -430.299622)
		(size 0.4572)
		(drill 0.2032)
		(layers "F.Cu" "B.Cu")
		(net "GND")
	)
	(via
		(at 128.054862 -294.336216)
		(size 0.4064)
		(drill 0.2032)
		(layers "F.Cu" "B.Cu")
		(net "GND")
	)
	(via
		(at 51.71567 -160.62579)
		(size 0.508)
		(drill 0.254)
		(layers "F.Cu" "B.Cu")
		(net "GND")
	)
	(via
		(at 377.367292 -382.34493)
		(size 0.508)
		(drill 0.254)
		(layers "F.Cu" "B.Cu")
		(net "GND")
	)
	(via
		(at 123.886214 -411.936184)
		(size 0.4572)
		(drill 0.254)
		(layers "F.Cu" "B.Cu")
		(net "GND")
	)
	(via
		(at 118.218458 -388.328662)
		(size 0.4064)
		(drill 0.2032)
		(layers "F.Cu" "B.Cu")
		(net "GND")
	)
	(via
		(at 109.261148 -273.276314)
		(size 0.4064)
		(drill 0.2032)
		(layers "F.Cu" "B.Cu")
		(net "GND")
	)
	(via
		(at 75.165712 -405.098504)
		(size 0.4572)
		(drill 0.254)
		(layers "F.Cu" "B.Cu")
		(net "GND")
	)
	(via
		(at 338.550758 -421.586152)
		(size 0.4572)
		(drill 0.254)
		(layers "F.Cu" "B.Cu")
		(net "GND")
	)
	(via
		(at 424.565064 -152.388824)
		(size 0.508)
		(drill 0.254)
		(layers "F.Cu" "B.Cu")
		(net "GND")
	)
	(via
		(at 9.352788 -371.36705)
		(size 0.508)
		(drill 0.254)
		(layers "F.Cu" "B.Cu")
		(net "GND")
	)
	(via
		(at 412.367984 -245.785132)
		(size 0.4826)
		(drill 0.254)
		(layers "F.Cu" "B.Cu")
		(net "GND")
	)
	(via
		(at 405.844248 -391.23493)
		(size 0.4064)
		(drill 0.2032)
		(layers "F.Cu" "B.Cu")
		(net "GND")
	)
	(via
		(at 265.54811 -262.785098)
		(size 0.4826)
		(drill 0.254)
		(layers "F.Cu" "B.Cu")
		(net "GND")
	)
	(via
		(at 187.060078 -249.18543)
		(size 0.4826)
		(drill 0.254)
		(layers "F.Cu" "B.Cu")
		(net "GND")
	)
	(via
		(at 56.599582 -4.32943)
		(size 0.508)
		(drill 0.254)
		(layers "F.Cu" "B.Cu")
		(net "GND")
	)
	(via
		(at 436.384446 -219.435172)
		(size 0.4826)
		(drill 0.254)
		(layers "F.Cu" "B.Cu")
		(net "GND")
	)
	(via
		(at 449.71208 -92.493592)
		(size 0.508)
		(drill 0.254)
		(layers "F.Cu" "B.Cu")
		(net "GND")
	)
	(via
		(at 452.803768 -305.28514)
		(size 0.4826)
		(drill 0.254)
		(layers "F.Cu" "B.Cu")
		(net "GND")
	)
	(via
		(at 426.24502 -387.703568)
		(size 0.508)
		(drill 0.254)
		(layers "F.Cu" "B.Cu")
		(net "GND")
	)
	(via
		(at 177.189638 -238.560356)
		(size 0.4826)
		(drill 0.254)
		(layers "F.Cu" "B.Cu")
		(net "GND")
	)
	(via
		(at 438.743344 -14.484096)
		(size 0.508)
		(drill 0.254)
		(layers "F.Cu" "B.Cu")
		(net "GND")
	)
	(via
		(at 213.02218 -385.713732)
		(size 0.508)
		(drill 0.254)
		(layers "F.Cu" "B.Cu")
		(net "GND")
	)
	(via
		(at 428.065692 -368.612674)
		(size 0.508)
		(drill 0.254)
		(layers "F.Cu" "B.Cu")
		(net "GND")
	)
	(via
		(at 374.0912 -398.542002)
		(size 0.4064)
		(drill 0.2032)
		(layers "F.Cu" "B.Cu")
		(net "GND")
	)
	(via
		(at 431.55616 -301.034958)
		(size 0.4826)
		(drill 0.254)
		(layers "F.Cu" "B.Cu")
		(net "GND")
	)
	(via
		(at 89.22131 -223.410272)
		(size 0.4064)
		(drill 0.2032)
		(layers "F.Cu" "B.Cu")
		(net "GND")
	)
	(via
		(at 379.138942 -210.442302)
		(size 0.508)
		(drill 0.254)
		(layers "F.Cu" "B.Cu")
		(net "GND")
	)
	(via
		(at 147.042886 -274.630388)
		(size 0.4064)
		(drill 0.2032)
		(layers "F.Cu" "B.Cu")
		(net "GND")
	)
	(via
		(at 48.714914 -344.137234)
		(size 0.508)
		(drill 0.254)
		(layers "F.Cu" "B.Cu")
		(net "GND")
	)
	(via
		(at 70.428358 -333.84998)
		(size 0.49022)
		(drill 0.254)
		(layers "F.Cu" "B.Cu")
		(net "GND")
	)
	(via
		(at 36.795964 -288.285428)
		(size 0.4826)
		(drill 0.254)
		(layers "F.Cu" "B.Cu")
		(net "GND")
	)
	(via
		(at 314.153296 -379.88113)
		(size 0.508)
		(drill 0.254)
		(layers "F.Cu" "B.Cu")
		(net "GND")
	)
	(via
		(at 21.70811 -297.635422)
		(size 0.4826)
		(drill 0.254)
		(layers "F.Cu" "B.Cu")
		(net "GND")
	)
	(via
		(at 121.004838 -277.326344)
		(size 0.4064)
		(drill 0.2032)
		(layers "F.Cu" "B.Cu")
		(net "GND")
	)
	(via
		(at 340.281006 -295.955974)
		(size 0.4064)
		(drill 0.2032)
		(layers "F.Cu" "B.Cu")
		(net "GND")
	)
	(via
		(at 144.034764 -279.756362)
		(size 0.4064)
		(drill 0.2032)
		(layers "F.Cu" "B.Cu")
		(net "GND")
	)
	(via
		(at 343.571068 -295.145968)
		(size 0.4064)
		(drill 0.2032)
		(layers "F.Cu" "B.Cu")
		(net "GND")
	)
	(via
		(at 88.506046 -183.841136)
		(size 0.49022)
		(drill 0.254)
		(layers "F.Cu" "B.Cu")
		(net "GND")
	)
	(via
		(at 95.674434 -142.84452)
		(size 0.508)
		(drill 0.254)
		(layers "F.Cu" "B.Cu")
		(net "GND")
	)
	(via
		(at 104.465882 -379.321568)
		(size 0.508)
		(drill 0.254)
		(layers "F.Cu" "B.Cu")
		(net "GND")
	)
	(via
		(at 329.6412 -252.584204)
		(size 0.4064)
		(drill 0.2032)
		(layers "F.Cu" "B.Cu")
		(net "GND")
	)
	(via
		(at 427.915832 -329.80249)
		(size 0.508)
		(drill 0.254)
		(layers "F.Cu" "B.Cu")
		(net "GND")
	)
	(via
		(at 165.545516 -286.160464)
		(size 0.4826)
		(drill 0.254)
		(layers "F.Cu" "B.Cu")
		(net "GND")
	)
	(via
		(at 50.745644 -407.00452)
		(size 0.4064)
		(drill 0.2032)
		(layers "F.Cu" "B.Cu")
		(net "GND")
	)
	(via
		(at 44.545758 -344.781886)
		(size 0.49022)
		(drill 0.254)
		(layers "F.Cu" "B.Cu")
		(net "GND")
	)
	(via
		(at 117.17909 -171.357544)
		(size 0.49022)
		(drill 0.254)
		(layers "F.Cu" "B.Cu")
		(net "GND")
	)
	(via
		(at 324.75297 -252.850142)
		(size 0.4064)
		(drill 0.2032)
		(layers "F.Cu" "B.Cu")
		(net "GND")
	)
	(via
		(at 358.311196 -238.814102)
		(size 0.4064)
		(drill 0.2032)
		(layers "F.Cu" "B.Cu")
		(net "GND")
	)
	(via
		(at 425.497498 -331.85989)
		(size 0.508)
		(drill 0.254)
		(layers "F.Cu" "B.Cu")
		(net "GND")
	)
	(via
		(at 124.22505 -163.204144)
		(size 0.49022)
		(drill 0.254)
		(layers "F.Cu" "B.Cu")
		(net "GND")
	)
	(via
		(at 347.708474 -161.538412)
		(size 0.49022)
		(drill 0.254)
		(layers "F.Cu" "B.Cu")
		(net "GND")
	)
	(via
		(at 353.141026 -231.524048)
		(size 0.4064)
		(drill 0.2032)
		(layers "F.Cu" "B.Cu")
		(net "GND")
	)
	(via
		(at 329.065128 -137.036302)
		(size 0.508)
		(drill 0.254)
		(layers "F.Cu" "B.Cu")
		(net "GND")
	)
	(via
		(at 344.981022 -271.656048)
		(size 0.4064)
		(drill 0.2032)
		(layers "F.Cu" "B.Cu")
		(net "GND")
	)
	(via
		(at 35.411664 -274.685252)
		(size 0.4826)
		(drill 0.254)
		(layers "F.Cu" "B.Cu")
		(net "GND")
	)
	(via
		(at 395.85392 -76.880212)
		(size 0.508)
		(drill 0.254)
		(layers "F.Cu" "B.Cu")
		(net "GND")
	)
	(via
		(at 329.941174 -281.37612)
		(size 0.4064)
		(drill 0.2032)
		(layers "F.Cu" "B.Cu")
		(net "GND")
	)
	(via
		(at 114.916458 -382.85293)
		(size 0.4064)
		(drill 0.2032)
		(layers "F.Cu" "B.Cu")
		(net "GND")
	)
	(via
		(at 308.914546 -12.542266)
		(size 0.508)
		(drill 0.254)
		(layers "F.Cu" "B.Cu")
		(net "GND")
	)
	(via
		(at 123.824746 -261.126224)
		(size 0.4064)
		(drill 0.2032)
		(layers "F.Cu" "B.Cu")
		(net "GND")
	)
	(via
		(at 386.804916 -282.186126)
		(size 0.4064)
		(drill 0.2032)
		(layers "F.Cu" "B.Cu")
		(net "GND")
	)
	(via
		(at 136.684766 -229.094538)
		(size 0.4064)
		(drill 0.2032)
		(layers "F.Cu" "B.Cu")
		(net "GND")
	)
	(via
		(at 81.701132 -236.384338)
		(size 0.4064)
		(drill 0.2032)
		(layers "F.Cu" "B.Cu")
		(net "GND")
	)
	(via
		(at 427.456092 -227.085144)
		(size 0.4826)
		(drill 0.254)
		(layers "F.Cu" "B.Cu")
		(net "GND")
	)
	(via
		(at 29.252164 -248.335292)
		(size 0.4826)
		(drill 0.254)
		(layers "F.Cu" "B.Cu")
		(net "GND")
	)
	(via
		(at 180.633624 -202.010264)
		(size 0.4826)
		(drill 0.254)
		(layers "F.Cu" "B.Cu")
		(net "GND")
	)
	(via
		(at 188.177678 -230.0605)
		(size 0.4826)
		(drill 0.254)
		(layers "F.Cu" "B.Cu")
		(net "GND")
	)
	(via
		(at 106.68 -423.69105)
		(size 0.508)
		(drill 0.254)
		(layers "F.Cu" "B.Cu")
		(net "GND")
	)
	(via
		(at 140.5382 -41.783)
		(size 0.508)
		(drill 0.254)
		(layers "F.Cu" "B.Cu")
		(net "GND")
	)
	(via
		(at 346.561156 -223.424242)
		(size 0.4064)
		(drill 0.2032)
		(layers "F.Cu" "B.Cu")
		(net "GND")
	)
	(via
		(at 338.101178 -241.24412)
		(size 0.4064)
		(drill 0.2032)
		(layers "F.Cu" "B.Cu")
		(net "GND")
	)
	(via
		(at 110.200948 -270.03629)
		(size 0.4064)
		(drill 0.2032)
		(layers "F.Cu" "B.Cu")
		(net "GND")
	)
	(via
		(at 38.45814 -12.37488)
		(size 0.508)
		(drill 0.254)
		(layers "F.Cu" "B.Cu")
		(net "GND")
	)
	(via
		(at 328.061066 -289.475926)
		(size 0.4064)
		(drill 0.2032)
		(layers "F.Cu" "B.Cu")
		(net "GND")
	)
	(via
		(at 171.97197 -250.885198)
		(size 0.4826)
		(drill 0.254)
		(layers "F.Cu" "B.Cu")
		(net "GND")
	)
	(via
		(at 447.919602 -429.63211)
		(size 0.508)
		(drill 0.254)
		(layers "F.Cu" "B.Cu")
		(net "GND")
	)
	(via
		(at 340.891876 -72.884792)
		(size 0.508)
		(drill 0.254)
		(layers "F.Cu" "B.Cu")
		(net "GND")
	)
	(via
		(at 180.900324 -278.085296)
		(size 0.4826)
		(drill 0.254)
		(layers "F.Cu" "B.Cu")
		(net "GND")
	)
	(via
		(at 284.736032 -272.984976)
		(size 0.4826)
		(drill 0.254)
		(layers "F.Cu" "B.Cu")
		(net "GND")
	)
	(via
		(at 299.82414 -248.335038)
		(size 0.4826)
		(drill 0.254)
		(layers "F.Cu" "B.Cu")
		(net "GND")
	)
	(via
		(at 107.85094 -265.98626)
		(size 0.4064)
		(drill 0.2032)
		(layers "F.Cu" "B.Cu")
		(net "GND")
	)
	(via
		(at 363.944916 -233.954066)
		(size 0.4064)
		(drill 0.2032)
		(layers "F.Cu" "B.Cu")
		(net "GND")
	)
	(via
		(at 143.264636 -255.014476)
		(size 0.4064)
		(drill 0.2032)
		(layers "F.Cu" "B.Cu")
		(net "GND")
	)
	(via
		(at 132.060696 -371.49913)
		(size 0.508)
		(drill 0.254)
		(layers "F.Cu" "B.Cu")
		(net "GND")
	)
	(via
		(at 426.234352 -5.597398)
		(size 0.508)
		(drill 0.254)
		(layers "F.Cu" "B.Cu")
		(net "GND")
	)
	(via
		(at 110.497874 -256.3876)
		(size 0.4826)
		(drill 0.254)
		(layers "F.Cu" "B.Cu")
		(net "GND")
	)
	(via
		(at 304.578258 -394.831062)
		(size 0.4064)
		(drill 0.2032)
		(layers "F.Cu" "B.Cu")
		(net "GND")
	)
	(via
		(at 61.108336 -403.830536)
		(size 0.4572)
		(drill 0.254)
		(layers "F.Cu" "B.Cu")
		(net "GND")
	)
	(via
		(at 336.691224 -222.614236)
		(size 0.4064)
		(drill 0.2032)
		(layers "F.Cu" "B.Cu")
		(net "GND")
	)
	(via
		(at 78.41107 -245.294404)
		(size 0.4064)
		(drill 0.2032)
		(layers "F.Cu" "B.Cu")
		(net "GND")
	)
	(via
		(at 422.627806 -314.635134)
		(size 0.4826)
		(drill 0.254)
		(layers "F.Cu" "B.Cu")
		(net "GND")
	)
	(via
		(at 349.630746 -415.362644)
		(size 0.4064)
		(drill 0.2032)
		(layers "F.Cu" "B.Cu")
		(net "GND")
	)
	(via
		(at 182.231792 -218.585288)
		(size 0.4826)
		(drill 0.254)
		(layers "F.Cu" "B.Cu")
		(net "GND")
	)
	(via
		(at 291.162486 -275.960078)
		(size 0.4826)
		(drill 0.254)
		(layers "F.Cu" "B.Cu")
		(net "GND")
	)
	(via
		(at 338.101178 -226.664266)
		(size 0.4064)
		(drill 0.2032)
		(layers "F.Cu" "B.Cu")
		(net "GND")
	)
	(via
		(at 383.21488 -239.624108)
		(size 0.4064)
		(drill 0.2032)
		(layers "F.Cu" "B.Cu")
		(net "GND")
	)
	(via
		(at 390.050274 -183.893968)
		(size 0.49022)
		(drill 0.254)
		(layers "F.Cu" "B.Cu")
		(net "GND")
	)
	(via
		(at 445.259968 -211.784946)
		(size 0.4826)
		(drill 0.254)
		(layers "F.Cu" "B.Cu")
		(net "GND")
	)
	(via
		(at 82.551016 -405.098504)
		(size 0.4572)
		(drill 0.254)
		(layers "F.Cu" "B.Cu")
		(net "GND")
	)
	(via
		(at 14.686788 -371.36705)
		(size 0.508)
		(drill 0.254)
		(layers "F.Cu" "B.Cu")
		(net "GND")
	)
	(via
		(at 435.000146 -249.185176)
		(size 0.4826)
		(drill 0.254)
		(layers "F.Cu" "B.Cu")
		(net "GND")
	)
	(via
		(at 445.259968 -286.585152)
		(size 0.4826)
		(drill 0.254)
		(layers "F.Cu" "B.Cu")
		(net "GND")
	)
	(via
		(at 83.391502 -373.96293)
		(size 0.508)
		(drill 0.254)
		(layers "F.Cu" "B.Cu")
		(net "GND")
	)
	(via
		(at 195.988432 -278.085296)
		(size 0.4826)
		(drill 0.254)
		(layers "F.Cu" "B.Cu")
		(net "GND")
	)
	(via
		(at 61.52261 -38.554152)
		(size 0.508)
		(drill 0.254)
		(layers "F.Cu" "B.Cu")
		(net "GND")
	)
	(via
		(at 419.912038 -245.785132)
		(size 0.4826)
		(drill 0.254)
		(layers "F.Cu" "B.Cu")
		(net "GND")
	)
	(via
		(at 299.72381 -346.317316)
		(size 0.49022)
		(drill 0.254)
		(layers "F.Cu" "B.Cu")
		(net "GND")
	)
	(via
		(at 356.922578 -354.45192)
		(size 0.508)
		(drill 0.254)
		(layers "F.Cu" "B.Cu")
		(net "GND")
	)
	(via
		(at 419.912038 -204.985112)
		(size 0.4826)
		(drill 0.254)
		(layers "F.Cu" "B.Cu")
		(net "GND")
	)
	(via
		(at 266.93241 -212.635084)
		(size 0.4826)
		(drill 0.254)
		(layers "F.Cu" "B.Cu")
		(net "GND")
	)
	(via
		(at 431.55616 -267.035026)
		(size 0.4826)
		(drill 0.254)
		(layers "F.Cu" "B.Cu")
		(net "GND")
	)
	(via
		(at 91.897962 -369.69573)
		(size 0.508)
		(drill 0.254)
		(layers "F.Cu" "B.Cu")
		(net "GND")
	)
	(via
		(at 99.055174 -258.830318)
		(size 0.4826)
		(drill 0.254)
		(layers "F.Cu" "B.Cu")
		(net "GND")
	)
	(via
		(at 349.211138 -285.42615)
		(size 0.4064)
		(drill 0.2032)
		(layers "F.Cu" "B.Cu")
		(net "GND")
	)
	(via
		(at 393.397994 -420.318184)
		(size 0.4572)
		(drill 0.254)
		(layers "F.Cu" "B.Cu")
		(net "GND")
	)
	(via
		(at 318.21628 -400.212814)
		(size 0.4064)
		(drill 0.2032)
		(layers "F.Cu" "B.Cu")
		(net "GND")
	)
	(via
		(at 36.795964 -215.185244)
		(size 0.4826)
		(drill 0.254)
		(layers "F.Cu" "B.Cu")
		(net "GND")
	)
	(via
		(at 65.81648 -382.85293)
		(size 0.4064)
		(drill 0.2032)
		(layers "F.Cu" "B.Cu")
		(net "GND")
	)
	(via
		(at 93.450918 -233.95432)
		(size 0.4064)
		(drill 0.2032)
		(layers "F.Cu" "B.Cu")
		(net "GND")
	)
	(via
		(at 51.734466 -5.597398)
		(size 0.508)
		(drill 0.254)
		(layers "F.Cu" "B.Cu")
		(net "GND")
	)
	(via
		(at 436.117746 -276.810216)
		(size 0.4826)
		(drill 0.254)
		(layers "F.Cu" "B.Cu")
		(net "GND")
	)
	(via
		(at 96.696784 -407.00452)
		(size 0.4064)
		(drill 0.2032)
		(layers "F.Cu" "B.Cu")
		(net "GND")
	)
	(via
		(at 169.1767 -381.42418)
		(size 0.508)
		(drill 0.254)
		(layers "F.Cu" "B.Cu")
		(net "GND")
	)
	(via
		(at 347.50121 -236.384084)
		(size 0.4064)
		(drill 0.2032)
		(layers "F.Cu" "B.Cu")
		(net "GND")
	)
	(via
		(at 17.608042 -317.185294)
		(size 0.4826)
		(drill 0.254)
		(layers "F.Cu" "B.Cu")
		(net "GND")
	)
	(via
		(at 129.74574 -12.495022)
		(size 0.508)
		(drill 0.254)
		(layers "F.Cu" "B.Cu")
		(net "GND")
	)
	(via
		(at 398.700498 -175.182784)
		(size 0.49022)
		(drill 0.254)
		(layers "F.Cu" "B.Cu")
		(net "GND")
	)
	(via
		(at 404.119334 -414.752536)
		(size 0.4572)
		(drill 0.254)
		(layers "F.Cu" "B.Cu")
		(net "GND")
	)
	(via
		(at 340.921086 -233.14406)
		(size 0.4064)
		(drill 0.2032)
		(layers "F.Cu" "B.Cu")
		(net "GND")
	)
	(via
		(at 330.618592 -385.38912)
		(size 0.508)
		(drill 0.254)
		(layers "F.Cu" "B.Cu")
		(net "GND")
	)
	(via
		(at 398.448022 -9.424924)
		(size 0.508)
		(drill 0.254)
		(layers "F.Cu" "B.Cu")
		(net "GND")
	)
	(via
		(at 36.411662 -430.799748)
		(size 0.508)
		(drill 0.254)
		(layers "F.Cu" "B.Cu")
		(net "GND")
	)
	(via
		(at 134.334758 -411.936184)
		(size 0.4572)
		(drill 0.254)
		(layers "F.Cu" "B.Cu")
		(net "GND")
	)
	(via
		(at 235.490258 -157.289754)
		(size 0.508)
		(drill 0.254)
		(layers "F.Cu" "B.Cu")
		(net "GND")
	)
	(via
		(at 109.870494 -335.691988)
		(size 0.508)
		(drill 0.254)
		(layers "F.Cu" "B.Cu")
		(net "GND")
	)
	(via
		(at 416.491674 -164.917882)
		(size 0.49022)
		(drill 0.254)
		(layers "F.Cu" "B.Cu")
		(net "GND")
	)
	(via
		(at 406.128474 -169.743882)
		(size 0.49022)
		(drill 0.254)
		(layers "F.Cu" "B.Cu")
		(net "GND")
	)
	(via
		(at 22.23008 -98.171508)
		(size 0.508)
		(drill 0.254)
		(layers "F.Cu" "B.Cu")
		(net "GND")
	)
	(via
		(at 303.5427 -411.49016)
		(size 0.508)
		(drill 0.254)
		(layers "F.Cu" "B.Cu")
		(net "GND")
	)
	(via
		(at 177.160682 -329.566524)
		(size 0.508)
		(drill 0.254)
		(layers "F.Cu" "B.Cu")
		(net "GND")
	)
	(via
		(at 398.46758 -380.54153)
		(size 0.508)
		(drill 0.254)
		(layers "F.Cu" "B.Cu")
		(net "GND")
	)
	(via
		(at 148.119338 -409.396184)
		(size 0.4572)
		(drill 0.254)
		(layers "F.Cu" "B.Cu")
		(net "GND")
	)
	(via
		(at 352.027998 -264.368026)
		(size 0.4064)
		(drill 0.2032)
		(layers "F.Cu" "B.Cu")
		(net "GND")
	)
	(via
		(at 375.716546 -400.212814)
		(size 0.4064)
		(drill 0.2032)
		(layers "F.Cu" "B.Cu")
		(net "GND")
	)
	(via
		(at 121.944638 -275.706332)
		(size 0.4064)
		(drill 0.2032)
		(layers "F.Cu" "B.Cu")
		(net "GND")
	)
	(via
		(at 388.384796 -246.914162)
		(size 0.4064)
		(drill 0.2032)
		(layers "F.Cu" "B.Cu")
		(net "GND")
	)
	(via
		(at 147.02282 -314.47105)
		(size 0.508)
		(drill 0.254)
		(layers "F.Cu" "B.Cu")
		(net "GND")
	)
	(via
		(at 352.9711 -293.525956)
		(size 0.4064)
		(drill 0.2032)
		(layers "F.Cu" "B.Cu")
		(net "GND")
	)
	(via
		(at 140.461238 -405.098504)
		(size 0.4572)
		(drill 0.254)
		(layers "F.Cu" "B.Cu")
		(net "GND")
	)
	(via
		(at 467.5378 -194.615054)
		(size 0.508)
		(drill 0.254)
		(layers "F.Cu" "B.Cu")
		(net "GND")
	)
	(via
		(at 56.220614 -339.869272)
		(size 0.508)
		(drill 0.254)
		(layers "F.Cu" "B.Cu")
		(net "GND")
	)
	(via
		(at 362.694474 -397.15313)
		(size 0.508)
		(drill 0.254)
		(layers "F.Cu" "B.Cu")
		(net "GND")
	)
	(via
		(at 98.451162 -282.18638)
		(size 0.4064)
		(drill 0.2032)
		(layers "F.Cu" "B.Cu")
		(net "GND")
	)
	(via
		(at 97.681034 -255.824482)
		(size 0.4064)
		(drill 0.2032)
		(layers "F.Cu" "B.Cu")
		(net "GND")
	)
	(via
		(at 18.992342 -212.635338)
		(size 0.4826)
		(drill 0.254)
		(layers "F.Cu" "B.Cu")
		(net "GND")
	)
	(via
		(at 412.367984 -317.18504)
		(size 0.4826)
		(drill 0.254)
		(layers "F.Cu" "B.Cu")
		(net "GND")
	)
	(via
		(at 88.580976 -279.756362)
		(size 0.4064)
		(drill 0.2032)
		(layers "F.Cu" "B.Cu")
		(net "GND")
	)
	(via
		(at 351.731072 -224.234248)
		(size 0.4064)
		(drill 0.2032)
		(layers "F.Cu" "B.Cu")
		(net "GND")
	)
	(via
		(at 151.34971 -438.651396)
		(size 0.4572)
		(drill 0.2032)
		(layers "F.Cu" "B.Cu")
		(net "GND")
	)
	(via
		(at 356.901242 -250.964192)
		(size 0.4064)
		(drill 0.2032)
		(layers "F.Cu" "B.Cu")
		(net "GND")
	)
	(via
		(at 96.706436 -386.449062)
		(size 0.4064)
		(drill 0.2032)
		(layers "F.Cu" "B.Cu")
		(net "GND")
	)
	(via
		(at 96.74098 -242.864386)
		(size 0.4064)
		(drill 0.2032)
		(layers "F.Cu" "B.Cu")
		(net "GND")
	)
	(via
		(at 419.912038 -242.385088)
		(size 0.4826)
		(drill 0.254)
		(layers "F.Cu" "B.Cu")
		(net "GND")
	)
	(via
		(at 394.982954 -285.970218)
		(size 0.4064)
		(drill 0.2032)
		(layers "F.Cu" "B.Cu")
		(net "GND")
	)
	(via
		(at 139.974828 -244.484398)
		(size 0.4064)
		(drill 0.2032)
		(layers "F.Cu" "B.Cu")
		(net "GND")
	)
	(via
		(at 145.144744 -250.15444)
		(size 0.4064)
		(drill 0.2032)
		(layers "F.Cu" "B.Cu")
		(net "GND")
	)
	(via
		(at 115.534694 -239.624362)
		(size 0.4064)
		(drill 0.2032)
		(layers "F.Cu" "B.Cu")
		(net "GND")
	)
	(via
		(at 168.527984 -299.335444)
		(size 0.4826)
		(drill 0.254)
		(layers "F.Cu" "B.Cu")
		(net "GND")
	)
	(via
		(at 133.864858 -233.95432)
		(size 0.4064)
		(drill 0.2032)
		(layers "F.Cu" "B.Cu")
		(net "GND")
	)
	(via
		(at 174.687738 -227.935282)
		(size 0.4826)
		(drill 0.254)
		(layers "F.Cu" "B.Cu")
		(net "GND")
	)
	(via
		(at 35.678364 -201.16038)
		(size 0.4826)
		(drill 0.254)
		(layers "F.Cu" "B.Cu")
		(net "GND")
	)
	(via
		(at 374.637046 -184.683146)
		(size 0.49022)
		(drill 0.254)
		(layers "F.Cu" "B.Cu")
		(net "GND")
	)
	(via
		(at 356.489 -116.427758)
		(size 0.508)
		(drill 0.254)
		(layers "F.Cu" "B.Cu")
		(net "GND")
	)
	(via
		(at 128.349756 -433.747164)
		(size 0.4572)
		(drill 0.2032)
		(layers "F.Cu" "B.Cu")
		(net "GND")
	)
	(via
		(at 342.249506 -430.147222)
		(size 0.4572)
		(drill 0.2032)
		(layers "F.Cu" "B.Cu")
		(net "GND")
	)
	(via
		(at 298.090844 -389.7122)
		(size 0.508)
		(drill 0.254)
		(layers "F.Cu" "B.Cu")
		(net "GND")
	)
	(via
		(at 85.290914 -285.426404)
		(size 0.4064)
		(drill 0.2032)
		(layers "F.Cu" "B.Cu")
		(net "GND")
	)
	(via
		(at 303.945036 -383.00533)
		(size 0.508)
		(drill 0.254)
		(layers "F.Cu" "B.Cu")
		(net "GND")
	)
	(via
		(at 16.25346 -398.177258)
		(size 0.508)
		(drill 0.254)
		(layers "F.Cu" "B.Cu")
		(net "GND")
	)
	(via
		(at 404.644098 -402.284438)
		(size 0.4572)
		(drill 0.254)
		(layers "F.Cu" "B.Cu")
		(net "GND")
	)
	(via
		(at 415.083752 -227.935028)
		(size 0.4826)
		(drill 0.254)
		(layers "F.Cu" "B.Cu")
		(net "GND")
	)
	(via
		(at 84.249768 -438.651396)
		(size 0.4572)
		(drill 0.2032)
		(layers "F.Cu" "B.Cu")
		(net "GND")
	)
	(via
		(at 379.88621 -413.480504)
		(size 0.4572)
		(drill 0.254)
		(layers "F.Cu" "B.Cu")
		(net "GND")
	)
	(via
		(at 93.450918 -240.434368)
		(size 0.4064)
		(drill 0.2032)
		(layers "F.Cu" "B.Cu")
		(net "GND")
	)
	(via
		(at 389.154924 -268.416024)
		(size 0.4064)
		(drill 0.2032)
		(layers "F.Cu" "B.Cu")
		(net "GND")
	)
	(via
		(at 369.884706 -261.12597)
		(size 0.4064)
		(drill 0.2032)
		(layers "F.Cu" "B.Cu")
		(net "GND")
	)
	(via
		(at 412.594298 -165.702996)
		(size 0.49022)
		(drill 0.254)
		(layers "F.Cu" "B.Cu")
		(net "GND")
	)
	(via
		(at 410.346144 -396.710662)
		(size 0.4064)
		(drill 0.2032)
		(layers "F.Cu" "B.Cu")
		(net "GND")
	)
	(via
		(at 381.334772 -231.524048)
		(size 0.4064)
		(drill 0.2032)
		(layers "F.Cu" "B.Cu")
		(net "GND")
	)
	(via
		(at 21.70811 -204.135228)
		(size 0.4826)
		(drill 0.254)
		(layers "F.Cu" "B.Cu")
		(net "GND")
	)
	(via
		(at 394.296138 -180.415438)
		(size 0.508)
		(drill 0.254)
		(layers "F.Cu" "B.Cu")
		(net "GND")
	)
	(via
		(at 133.864858 -232.334308)
		(size 0.4064)
		(drill 0.2032)
		(layers "F.Cu" "B.Cu")
		(net "GND")
	)
	(via
		(at 363.774736 -282.996132)
		(size 0.4064)
		(drill 0.2032)
		(layers "F.Cu" "B.Cu")
		(net "GND")
	)
	(via
		(at 332.424278 -412.212536)
		(size 0.4572)
		(drill 0.254)
		(layers "F.Cu" "B.Cu")
		(net "GND")
	)
	(via
		(at 356.261162 -284.616144)
		(size 0.4064)
		(drill 0.2032)
		(layers "F.Cu" "B.Cu")
		(net "GND")
	)
	(via
		(at 400.24558 -7.215124)
		(size 0.508)
		(drill 0.254)
		(layers "F.Cu" "B.Cu")
		(net "GND")
	)
	(via
		(at 372.116604 -400.212814)
		(size 0.4064)
		(drill 0.2032)
		(layers "F.Cu" "B.Cu")
		(net "GND")
	)
	(via
		(at 113.48466 -270.846296)
		(size 0.4064)
		(drill 0.2032)
		(layers "F.Cu" "B.Cu")
		(net "GND")
	)
	(via
		(at 351.788984 -380.54153)
		(size 0.508)
		(drill 0.254)
		(layers "F.Cu" "B.Cu")
		(net "GND")
	)
	(via
		(at 435.000146 -301.885096)
		(size 0.4826)
		(drill 0.254)
		(layers "F.Cu" "B.Cu")
		(net "GND")
	)
	(via
		(at 86.871048 -245.294404)
		(size 0.4064)
		(drill 0.2032)
		(layers "F.Cu" "B.Cu")
		(net "GND")
	)
	(via
		(at 348.341188 -345.192096)
		(size 0.508)
		(drill 0.254)
		(layers "F.Cu" "B.Cu")
		(net "GND")
	)
	(via
		(at 117.486938 -410.664152)
		(size 0.4572)
		(drill 0.254)
		(layers "F.Cu" "B.Cu")
		(net "GND")
	)
	(via
		(at 450.088 -208.385156)
		(size 0.4826)
		(drill 0.254)
		(layers "F.Cu" "B.Cu")
		(net "GND")
	)
	(via
		(at 195.988432 -275.53539)
		(size 0.4826)
		(drill 0.254)
		(layers "F.Cu" "B.Cu")
		(net "GND")
	)
	(via
		(at 163.219384 -441.227718)
		(size 0.508)
		(drill 0.254)
		(layers "F.Cu" "B.Cu")
		(net "GND")
	)
	(via
		(at 395.114272 -5.597398)
		(size 0.508)
		(drill 0.254)
		(layers "F.Cu" "B.Cu")
		(net "GND")
	)
	(via
		(at 298.70654 -229.210108)
		(size 0.4826)
		(drill 0.254)
		(layers "F.Cu" "B.Cu")
		(net "GND")
	)
	(via
		(at 41.62425 -312.935366)
		(size 0.4826)
		(drill 0.254)
		(layers "F.Cu" "B.Cu")
		(net "GND")
	)
	(via
		(at 58.310526 -304.010314)
		(size 0.4826)
		(drill 0.254)
		(layers "F.Cu" "B.Cu")
		(net "GND")
	)
	(via
		(at 397.058388 -391.41146)
		(size 0.508)
		(drill 0.254)
		(layers "F.Cu" "B.Cu")
		(net "GND")
	)
	(via
		(at 99.861116 -273.276314)
		(size 0.4064)
		(drill 0.2032)
		(layers "F.Cu" "B.Cu")
		(net "GND")
	)
	(via
		(at 390.349486 -427.851316)
		(size 0.4572)
		(drill 0.2032)
		(layers "F.Cu" "B.Cu")
		(net "GND")
	)
	(via
		(at 310.01081 -344.77706)
		(size 0.49022)
		(drill 0.254)
		(layers "F.Cu" "B.Cu")
		(net "GND")
	)
	(via
		(at 355.321108 -294.335962)
		(size 0.4064)
		(drill 0.2032)
		(layers "F.Cu" "B.Cu")
		(net "GND")
	)
	(via
		(at 123.613418 -406.370536)
		(size 0.4572)
		(drill 0.254)
		(layers "F.Cu" "B.Cu")
		(net "GND")
	)
	(via
		(at 388.384796 -243.674138)
		(size 0.4064)
		(drill 0.2032)
		(layers "F.Cu" "B.Cu")
		(net "GND")
	)
	(via
		(at 77.369924 -392.768582)
		(size 0.508)
		(drill 0.254)
		(layers "F.Cu" "B.Cu")
		(net "GND")
	)
	(via
		(at 55.254652 -406.370536)
		(size 0.4572)
		(drill 0.254)
		(layers "F.Cu" "B.Cu")
		(net "GND")
	)
	(via
		(at 70.863206 -12.37488)
		(size 0.508)
		(drill 0.254)
		(layers "F.Cu" "B.Cu")
		(net "GND")
	)
	(via
		(at 394.727176 -187.466986)
		(size 0.508)
		(drill 0.254)
		(layers "F.Cu" "B.Cu")
		(net "GND")
	)
	(via
		(at 326.351138 -240.434114)
		(size 0.4064)
		(drill 0.2032)
		(layers "F.Cu" "B.Cu")
		(net "GND")
	)
	(via
		(at 278.995886 -339.807296)
		(size 0.508)
		(drill 0.254)
		(layers "F.Cu" "B.Cu")
		(net "GND")
	)
	(via
		(at 118.65483 -279.756362)
		(size 0.4064)
		(drill 0.2032)
		(layers "F.Cu" "B.Cu")
		(net "GND")
	)
	(via
		(at 137.45464 -289.47618)
		(size 0.4064)
		(drill 0.2032)
		(layers "F.Cu" "B.Cu")
		(net "GND")
	)
	(via
		(at 218.941396 -439.90768)
		(size 0.508)
		(drill 0.254)
		(layers "F.Cu" "B.Cu")
		(net "GND")
	)
	(via
		(at 122.114818 -223.424496)
		(size 0.4064)
		(drill 0.2032)
		(layers "F.Cu" "B.Cu")
		(net "GND")
	)
	(via
		(at 390.248902 -418.412168)
		(size 0.4064)
		(drill 0.2032)
		(layers "F.Cu" "B.Cu")
		(net "GND")
	)
	(via
		(at 141.718792 -375.793)
		(size 0.508)
		(drill 0.254)
		(layers "F.Cu" "B.Cu")
		(net "GND")
	)
	(via
		(at 36.795964 -265.335258)
		(size 0.4826)
		(drill 0.254)
		(layers "F.Cu" "B.Cu")
		(net "GND")
	)
	(via
		(at 105.200958 -247.724422)
		(size 0.4064)
		(drill 0.2032)
		(layers "F.Cu" "B.Cu")
		(net "GND")
	)
	(via
		(at 191.160146 -244.935248)
		(size 0.4826)
		(drill 0.254)
		(layers "F.Cu" "B.Cu")
		(net "GND")
	)
	(via
		(at 148.392134 -413.204152)
		(size 0.4572)
		(drill 0.254)
		(layers "F.Cu" "B.Cu")
		(net "GND")
	)
	(via
		(at 171.97197 -262.785352)
		(size 0.4826)
		(drill 0.254)
		(layers "F.Cu" "B.Cu")
		(net "GND")
	)
	(via
		(at 337.631024 -233.954066)
		(size 0.4064)
		(drill 0.2032)
		(layers "F.Cu" "B.Cu")
		(net "GND")
	)
	(via
		(at 121.0056 -264.36828)
		(size 0.4064)
		(drill 0.2032)
		(layers "F.Cu" "B.Cu")
		(net "GND")
	)
	(via
		(at 419.912038 -223.6851)
		(size 0.4826)
		(drill 0.254)
		(layers "F.Cu" "B.Cu")
		(net "GND")
	)
	(via
		(at 274.476464 -278.085042)
		(size 0.4826)
		(drill 0.254)
		(layers "F.Cu" "B.Cu")
		(net "GND")
	)
	(via
		(at 33.813496 -192.218564)
		(size 0.4826)
		(drill 0.254)
		(layers "F.Cu" "B.Cu")
		(net "GND")
	)
	(via
		(at 303.189386 -335.673446)
		(size 0.508)
		(drill 0.254)
		(layers "F.Cu" "B.Cu")
		(net "GND")
	)
	(via
		(at 265.54811 -244.08511)
		(size 0.4826)
		(drill 0.254)
		(layers "F.Cu" "B.Cu")
		(net "GND")
	)
	(via
		(at 348.101666 -420.952168)
		(size 0.4064)
		(drill 0.2032)
		(layers "F.Cu" "B.Cu")
		(net "GND")
	)
	(via
		(at 60.591192 -390.160002)
		(size 0.4064)
		(drill 0.2032)
		(layers "F.Cu" "B.Cu")
		(net "GND")
	)
	(via
		(at 343.544144 -402.259038)
		(size 0.4572)
		(drill 0.254)
		(layers "F.Cu" "B.Cu")
		(net "GND")
	)
	(via
		(at 25.932384 -395.082268)
		(size 0.508)
		(drill 0.254)
		(layers "F.Cu" "B.Cu")
		(net "GND")
	)
	(via
		(at 423.672 -434.786786)
		(size 0.508)
		(drill 0.254)
		(layers "F.Cu" "B.Cu")
		(net "GND")
	)
	(via
		(at 74.61885 -382.54432)
		(size 0.508)
		(drill 0.254)
		(layers "F.Cu" "B.Cu")
		(net "GND")
	)
	(via
		(at 430.17186 -302.73498)
		(size 0.4826)
		(drill 0.254)
		(layers "F.Cu" "B.Cu")
		(net "GND")
	)
	(via
		(at 239.014 -285.637478)
		(size 0.508)
		(drill 0.254)
		(layers "F.Cu" "B.Cu")
		(net "GND")
	)
	(via
		(at 347.33103 -293.525956)
		(size 0.4064)
		(drill 0.2032)
		(layers "F.Cu" "B.Cu")
		(net "GND")
	)
	(via
		(at 118.184676 -288.666174)
		(size 0.4064)
		(drill 0.2032)
		(layers "F.Cu" "B.Cu")
		(net "GND")
	)
	(via
		(at 82.640932 -223.424496)
		(size 0.4064)
		(drill 0.2032)
		(layers "F.Cu" "B.Cu")
		(net "GND")
	)
	(via
		(at 124.7648 -283.806392)
		(size 0.4064)
		(drill 0.2032)
		(layers "F.Cu" "B.Cu")
		(net "GND")
	)
	(via
		(at 333.097124 -333.823564)
		(size 0.49022)
		(drill 0.254)
		(layers "F.Cu" "B.Cu")
		(net "GND")
	)
	(via
		(at 29.252164 -246.63527)
		(size 0.4826)
		(drill 0.254)
		(layers "F.Cu" "B.Cu")
		(net "GND")
	)
	(via
		(at 303.596294 -412.212536)
		(size 0.4572)
		(drill 0.254)
		(layers "F.Cu" "B.Cu")
		(net "GND")
	)
	(via
		(at 469.357964 -40.417496)
		(size 0.508)
		(drill 0.254)
		(layers "F.Cu" "B.Cu")
		(net "GND")
	)
	(via
		(at 329.941174 -271.656048)
		(size 0.4064)
		(drill 0.2032)
		(layers "F.Cu" "B.Cu")
		(net "GND")
	)
	(via
		(at 283.351732 -199.885046)
		(size 0.4826)
		(drill 0.254)
		(layers "F.Cu" "B.Cu")
		(net "GND")
	)
	(via
		(at 23.945596 -10.16508)
		(size 0.508)
		(drill 0.254)
		(layers "F.Cu" "B.Cu")
		(net "GND")
	)
	(via
		(at 144.100042 -76.205842)
		(size 0.508)
		(drill 0.254)
		(layers "F.Cu" "B.Cu")
		(net "GND")
	)
	(via
		(at 124.516388 -382.85293)
		(size 0.4064)
		(drill 0.2032)
		(layers "F.Cu" "B.Cu")
		(net "GND")
	)
	(via
		(at 283.618432 -229.210108)
		(size 0.4826)
		(drill 0.254)
		(layers "F.Cu" "B.Cu")
		(net "GND")
	)
	(via
		(at 363.774736 -271.656048)
		(size 0.4064)
		(drill 0.2032)
		(layers "F.Cu" "B.Cu")
		(net "GND")
	)
	(via
		(at 435.000146 -272.135092)
		(size 0.4826)
		(drill 0.254)
		(layers "F.Cu" "B.Cu")
		(net "GND")
	)
	(via
		(at 451.2056 -295.510204)
		(size 0.4826)
		(drill 0.254)
		(layers "F.Cu" "B.Cu")
		(net "GND")
	)
	(via
		(at 195.721732 -286.160464)
		(size 0.4826)
		(drill 0.254)
		(layers "F.Cu" "B.Cu")
		(net "GND")
	)
	(via
		(at 358.61117 -293.525956)
		(size 0.4064)
		(drill 0.2032)
		(layers "F.Cu" "B.Cu")
		(net "GND")
	)
	(via
		(at 421.029638 -286.16021)
		(size 0.4826)
		(drill 0.254)
		(layers "F.Cu" "B.Cu")
		(net "GND")
	)
	(via
		(at 126.644654 -274.08632)
		(size 0.4064)
		(drill 0.2032)
		(layers "F.Cu" "B.Cu")
		(net "GND")
	)
	(via
		(at 195.458334 -330.783946)
		(size 0.508)
		(drill 0.254)
		(layers "F.Cu" "B.Cu")
		(net "GND")
	)
	(via
		(at 350.585024 -169.536364)
		(size 0.508)
		(drill 0.254)
		(layers "F.Cu" "B.Cu")
		(net "GND")
	)
	(via
		(at 414.840674 -413.480504)
		(size 0.4572)
		(drill 0.254)
		(layers "F.Cu" "B.Cu")
		(net "GND")
	)
	(via
		(at 405.34971 -431.29962)
		(size 0.4572)
		(drill 0.2032)
		(layers "F.Cu" "B.Cu")
		(net "GND")
	)
	(via
		(at 123.524772 -235.574332)
		(size 0.4064)
		(drill 0.2032)
		(layers "F.Cu" "B.Cu")
		(net "GND")
	)
	(via
		(at 159.113474 -406.34666)
		(size 0.4572)
		(drill 0.254)
		(layers "F.Cu" "B.Cu")
		(net "GND")
	)
	(via
		(at 56.865774 -7.215124)
		(size 0.508)
		(drill 0.254)
		(layers "F.Cu" "B.Cu")
		(net "GND")
	)
	(via
		(at 402.045678 -7.215124)
		(size 0.508)
		(drill 0.254)
		(layers "F.Cu" "B.Cu")
		(net "GND")
	)
	(via
		(at 51.234848 -4.963414)
		(size 0.508)
		(drill 0.254)
		(layers "F.Cu" "B.Cu")
		(net "GND")
	)
	(via
		(at 387.914896 -234.764072)
		(size 0.4064)
		(drill 0.2032)
		(layers "F.Cu" "B.Cu")
		(net "GND")
	)
	(via
		(at 265.54811 -266.185142)
		(size 0.4826)
		(drill 0.254)
		(layers "F.Cu" "B.Cu")
		(net "GND")
	)
	(via
		(at 365.82477 -235.574078)
		(size 0.4064)
		(drill 0.2032)
		(layers "F.Cu" "B.Cu")
		(net "GND")
	)
	(via
		(at 82.001106 -289.47618)
		(size 0.4064)
		(drill 0.2032)
		(layers "F.Cu" "B.Cu")
		(net "GND")
	)
	(via
		(at 78.123542 -334.593946)
		(size 0.49022)
		(drill 0.254)
		(layers "F.Cu" "B.Cu")
		(net "GND")
	)
	(via
		(at 28.827984 -404.372572)
		(size 0.508)
		(drill 0.254)
		(layers "F.Cu" "B.Cu")
		(net "GND")
	)
	(via
		(at 98.664014 -333.08036)
		(size 0.508)
		(drill 0.254)
		(layers "F.Cu" "B.Cu")
		(net "GND")
	)
	(via
		(at 164.427916 -204.985366)
		(size 0.4826)
		(drill 0.254)
		(layers "F.Cu" "B.Cu")
		(net "GND")
	)
	(via
		(at 317.249556 -427.699678)
		(size 0.4572)
		(drill 0.2032)
		(layers "F.Cu" "B.Cu")
		(net "GND")
	)
	(via
		(at 195.458334 -330.123546)
		(size 0.508)
		(drill 0.254)
		(layers "F.Cu" "B.Cu")
		(net "GND")
	)
	(via
		(at 94.67342 -309.062628)
		(size 0.4064)
		(drill 0.2032)
		(layers "F.Cu" "B.Cu")
		(net "GND")
	)
	(via
		(at 364.643416 -399.314924)
		(size 0.508)
		(drill 0.254)
		(layers "F.Cu" "B.Cu")
		(net "GND")
	)
	(via
		(at 366.294924 -228.284278)
		(size 0.4064)
		(drill 0.2032)
		(layers "F.Cu" "B.Cu")
		(net "GND")
	)
	(via
		(at 135.128 -108.331)
		(size 0.508)
		(drill 0.254)
		(layers "F.Cu" "B.Cu")
		(net "GND")
	)
	(via
		(at 145.144744 -224.234502)
		(size 0.4064)
		(drill 0.2032)
		(layers "F.Cu" "B.Cu")
		(net "GND")
	)
	(via
		(at 307.368194 -232.184956)
		(size 0.4826)
		(drill 0.254)
		(layers "F.Cu" "B.Cu")
		(net "GND")
	)
	(via
		(at 80.249776 -432.747166)
		(size 0.4572)
		(drill 0.2032)
		(layers "F.Cu" "B.Cu")
		(net "GND")
	)
	(via
		(at 135.406638 -62.68212)
		(size 0.508)
		(drill 0.254)
		(layers "F.Cu" "B.Cu")
		(net "GND")
	)
	(via
		(at 383.514854 -289.475926)
		(size 0.4064)
		(drill 0.2032)
		(layers "F.Cu" "B.Cu")
		(net "GND")
	)
	(via
		(at 366.294924 -239.624108)
		(size 0.4064)
		(drill 0.2032)
		(layers "F.Cu" "B.Cu")
		(net "GND")
	)
	(via
		(at 87.504524 -410.030168)
		(size 0.4064)
		(drill 0.2032)
		(layers "F.Cu" "B.Cu")
		(net "GND")
	)
	(via
		(at 277.192232 -248.335038)
		(size 0.4826)
		(drill 0.254)
		(layers "F.Cu" "B.Cu")
		(net "GND")
	)
	(via
		(at 41.430702 -380.87046)
		(size 0.508)
		(drill 0.254)
		(layers "F.Cu" "B.Cu")
		(net "GND")
	)
	(via
		(at 64.967866 -170.867832)
		(size 0.49022)
		(drill 0.254)
		(layers "F.Cu" "B.Cu")
		(net "GND")
	)
	(via
		(at 293.516558 -18.780506)
		(size 0.508)
		(drill 0.254)
		(layers "F.Cu" "B.Cu")
		(net "GND")
	)
	(via
		(at 376.89028 -31.169102)
		(size 0.508)
		(drill 0.254)
		(layers "F.Cu" "B.Cu")
		(net "GND")
	)
	(via
		(at 50.499772 -295.9354)
		(size 0.4826)
		(drill 0.254)
		(layers "F.Cu" "B.Cu")
		(net "GND")
	)
	(via
		(at 131.716526 -382.85293)
		(size 0.4064)
		(drill 0.2032)
		(layers "F.Cu" "B.Cu")
		(net "GND")
	)
	(via
		(at 57.58307 -19.771106)
		(size 0.508)
		(drill 0.254)
		(layers "F.Cu" "B.Cu")
		(net "GND")
	)
	(via
		(at 180.900324 -203.285344)
		(size 0.4826)
		(drill 0.254)
		(layers "F.Cu" "B.Cu")
		(net "GND")
	)
	(via
		(at 32.695896 -283.185362)
		(size 0.4826)
		(drill 0.254)
		(layers "F.Cu" "B.Cu")
		(net "GND")
	)
	(via
		(at 287.939226 -339.799676)
		(size 0.508)
		(drill 0.254)
		(layers "F.Cu" "B.Cu")
		(net "GND")
	)
	(via
		(at 25.152096 -255.13538)
		(size 0.4826)
		(drill 0.254)
		(layers "F.Cu" "B.Cu")
		(net "GND")
	)
	(via
		(at 320.949828 -44.716954)
		(size 0.508)
		(drill 0.254)
		(layers "F.Cu" "B.Cu")
		(net "GND")
	)
	(via
		(at 75.165712 -411.936184)
		(size 0.4572)
		(drill 0.254)
		(layers "F.Cu" "B.Cu")
		(net "GND")
	)
	(via
		(at 342.801194 -231.524048)
		(size 0.4064)
		(drill 0.2032)
		(layers "F.Cu" "B.Cu")
		(net "GND")
	)
	(via
		(at 27.867864 -211.7852)
		(size 0.4826)
		(drill 0.254)
		(layers "F.Cu" "B.Cu")
		(net "GND")
	)
	(via
		(at 332.424278 -420.318184)
		(size 0.4572)
		(drill 0.254)
		(layers "F.Cu" "B.Cu")
		(net "GND")
	)
	(via
		(at 302.150526 -220.709998)
		(size 0.4826)
		(drill 0.254)
		(layers "F.Cu" "B.Cu")
		(net "GND")
	)
	(via
		(at 446.776602 -429.65751)
		(size 0.508)
		(drill 0.254)
		(layers "F.Cu" "B.Cu")
		(net "GND")
	)
	(via
		(at 121.174764 -244.484398)
		(size 0.4064)
		(drill 0.2032)
		(layers "F.Cu" "B.Cu")
		(net "GND")
	)
	(via
		(at 26.536396 -238.135414)
		(size 0.4826)
		(drill 0.254)
		(layers "F.Cu" "B.Cu")
		(net "GND")
	)
	(via
		(at 135.574786 -273.276314)
		(size 0.4064)
		(drill 0.2032)
		(layers "F.Cu" "B.Cu")
		(net "GND")
	)
	(via
		(at 425.129706 -210.51012)
		(size 0.4826)
		(drill 0.254)
		(layers "F.Cu" "B.Cu")
		(net "GND")
	)
	(via
		(at 24.288496 -387.704076)
		(size 0.49022)
		(drill 0.254)
		(layers "F.Cu" "B.Cu")
		(net "GND")
	)
	(via
		(at 315.24956 -435.0512)
		(size 0.4572)
		(drill 0.2032)
		(layers "F.Cu" "B.Cu")
		(net "GND")
	)
	(via
		(at 423.002964 -349.964756)
		(size 0.49022)
		(drill 0.254)
		(layers "F.Cu" "B.Cu")
		(net "GND")
	)
	(via
		(at 89.690956 -229.094538)
		(size 0.4064)
		(drill 0.2032)
		(layers "F.Cu" "B.Cu")
		(net "GND")
	)
	(via
		(at 141.854682 -250.964446)
		(size 0.4064)
		(drill 0.2032)
		(layers "F.Cu" "B.Cu")
		(net "GND")
	)
	(via
		(at 414.755584 -7.215124)
		(size 0.508)
		(drill 0.254)
		(layers "F.Cu" "B.Cu")
		(net "GND")
	)
	(via
		(at 361.894882 -276.516084)
		(size 0.4064)
		(drill 0.2032)
		(layers "F.Cu" "B.Cu")
		(net "GND")
	)
	(via
		(at 164.590984 -368.37493)
		(size 0.508)
		(drill 0.254)
		(layers "F.Cu" "B.Cu")
		(net "GND")
	)
	(via
		(at 194.604132 -249.18543)
		(size 0.4826)
		(drill 0.254)
		(layers "F.Cu" "B.Cu")
		(net "GND")
	)
	(via
		(at 319.249552 -430.299622)
		(size 0.4572)
		(drill 0.2032)
		(layers "F.Cu" "B.Cu")
		(net "GND")
	)
	(via
		(at 379.972062 -415.38652)
		(size 0.4064)
		(drill 0.2032)
		(layers "F.Cu" "B.Cu")
		(net "GND")
	)
	(via
		(at 442.5442 -298.485052)
		(size 0.4826)
		(drill 0.254)
		(layers "F.Cu" "B.Cu")
		(net "GND")
	)
	(via
		(at 166.00678 -14.824202)
		(size 0.508)
		(drill 0.254)
		(layers "F.Cu" "B.Cu")
		(net "GND")
	)
	(via
		(at 233.651044 -42.418)
		(size 0.508)
		(drill 0.254)
		(layers "F.Cu" "B.Cu")
		(net "GND")
	)
	(via
		(at 284.736032 -248.335038)
		(size 0.4826)
		(drill 0.254)
		(layers "F.Cu" "B.Cu")
		(net "GND")
	)
	(via
		(at 206.248 -263.635236)
		(size 0.4826)
		(drill 0.254)
		(layers "F.Cu" "B.Cu")
		(net "GND")
	)
	(via
		(at 433.166774 -9.425432)
		(size 0.508)
		(drill 0.254)
		(layers "F.Cu" "B.Cu")
		(net "GND")
	)
	(via
		(at 408.67584 -377.41733)
		(size 0.508)
		(drill 0.254)
		(layers "F.Cu" "B.Cu")
		(net "GND")
	)
	(via
		(at 371.955314 -420.318184)
		(size 0.4572)
		(drill 0.254)
		(layers "F.Cu" "B.Cu")
		(net "GND")
	)
	(via
		(at 420.24427 -391.23493)
		(size 0.4064)
		(drill 0.2032)
		(layers "F.Cu" "B.Cu")
		(net "GND")
	)
	(via
		(at 72.81291 -154.80538)
		(size 0.508)
		(drill 0.254)
		(layers "F.Cu" "B.Cu")
		(net "GND")
	)
	(via
		(at 173.35627 -278.085296)
		(size 0.4826)
		(drill 0.254)
		(layers "F.Cu" "B.Cu")
		(net "GND")
	)
	(via
		(at 307.368194 -250.03506)
		(size 0.4826)
		(drill 0.254)
		(layers "F.Cu" "B.Cu")
		(net "GND")
	)
	(via
		(at 288.180018 -301.885096)
		(size 0.4826)
		(drill 0.254)
		(layers "F.Cu" "B.Cu")
		(net "GND")
	)
	(via
		(at 83.88096 -265.176254)
		(size 0.4064)
		(drill 0.2032)
		(layers "F.Cu" "B.Cu")
		(net "GND")
	)
	(via
		(at 419.912038 -272.135092)
		(size 0.4826)
		(drill 0.254)
		(layers "F.Cu" "B.Cu")
		(net "GND")
	)
	(via
		(at 344.211148 -224.234248)
		(size 0.4064)
		(drill 0.2032)
		(layers "F.Cu" "B.Cu")
		(net "GND")
	)
	(via
		(at 165.545516 -230.0605)
		(size 0.4826)
		(drill 0.254)
		(layers "F.Cu" "B.Cu")
		(net "GND")
	)
	(via
		(at 117.845586 -407.00452)
		(size 0.4064)
		(drill 0.2032)
		(layers "F.Cu" "B.Cu")
		(net "GND")
	)
	(via
		(at 104.731058 -224.234502)
		(size 0.4064)
		(drill 0.2032)
		(layers "F.Cu" "B.Cu")
		(net "GND")
	)
	(via
		(at 53.03012 -6.598158)
		(size 0.508)
		(drill 0.254)
		(layers "F.Cu" "B.Cu")
		(net "GND")
	)
	(via
		(at 164.427916 -298.485306)
		(size 0.4826)
		(drill 0.254)
		(layers "F.Cu" "B.Cu")
		(net "GND")
	)
	(via
		(at 142.154656 -278.13635)
		(size 0.4064)
		(drill 0.2032)
		(layers "F.Cu" "B.Cu")
		(net "GND")
	)
	(via
		(at 345.679776 -162.305746)
		(size 0.49022)
		(drill 0.254)
		(layers "F.Cu" "B.Cu")
		(net "GND")
	)
	(via
		(at 376.908822 -418.412168)
		(size 0.4064)
		(drill 0.2032)
		(layers "F.Cu" "B.Cu")
		(net "GND")
	)
	(via
		(at 331.251306 -418.412168)
		(size 0.4064)
		(drill 0.2032)
		(layers "F.Cu" "B.Cu")
		(net "GND")
	)
	(via
		(at 290.84524 -403.564598)
		(size 0.508)
		(drill 0.254)
		(layers "F.Cu" "B.Cu")
		(net "GND")
	)
	(via
		(at 415.779966 -135.04926)
		(size 0.508)
		(drill 0.254)
		(layers "F.Cu" "B.Cu")
		(net "GND")
	)
	(via
		(at 95.54591 -185.276998)
		(size 0.508)
		(drill 0.254)
		(layers "F.Cu" "B.Cu")
		(net "GND")
	)
	(via
		(at 74.892916 -407.638504)
		(size 0.4572)
		(drill 0.254)
		(layers "F.Cu" "B.Cu")
		(net "GND")
	)
	(via
		(at 102.681024 -274.896326)
		(size 0.4064)
		(drill 0.2032)
		(layers "F.Cu" "B.Cu")
		(net "GND")
	)
	(via
		(at 86.401148 -228.284532)
		(size 0.4064)
		(drill 0.2032)
		(layers "F.Cu" "B.Cu")
		(net "GND")
	)
	(via
		(at 84.99094 -253.394464)
		(size 0.4064)
		(drill 0.2032)
		(layers "F.Cu" "B.Cu")
		(net "GND")
	)
	(via
		(at 377.762262 -392.999722)
		(size 0.4064)
		(drill 0.2032)
		(layers "F.Cu" "B.Cu")
		(net "GND")
	)
	(via
		(at 390.248902 -415.38652)
		(size 0.4064)
		(drill 0.2032)
		(layers "F.Cu" "B.Cu")
		(net "GND")
	)
	(via
		(at 409.090114 -392.999722)
		(size 0.4064)
		(drill 0.2032)
		(layers "F.Cu" "B.Cu")
		(net "GND")
	)
	(via
		(at 442.5442 -309.535068)
		(size 0.4826)
		(drill 0.254)
		(layers "F.Cu" "B.Cu")
		(net "GND")
	)
	(via
		(at 106.91114 -285.426404)
		(size 0.4064)
		(drill 0.2032)
		(layers "F.Cu" "B.Cu")
		(net "GND")
	)
	(via
		(at 119.12473 -282.18638)
		(size 0.4064)
		(drill 0.2032)
		(layers "F.Cu" "B.Cu")
		(net "GND")
	)
	(via
		(at 363.474762 -238.004096)
		(size 0.4064)
		(drill 0.2032)
		(layers "F.Cu" "B.Cu")
		(net "GND")
	)
	(via
		(at 133.694678 -289.47618)
		(size 0.4064)
		(drill 0.2032)
		(layers "F.Cu" "B.Cu")
		(net "GND")
	)
	(via
		(at 349.211138 -293.525956)
		(size 0.4064)
		(drill 0.2032)
		(layers "F.Cu" "B.Cu")
		(net "GND")
	)
	(via
		(at 419.912038 -264.48512)
		(size 0.4826)
		(drill 0.254)
		(layers "F.Cu" "B.Cu")
		(net "GND")
	)
	(via
		(at 277.192232 -246.635016)
		(size 0.4826)
		(drill 0.254)
		(layers "F.Cu" "B.Cu")
		(net "GND")
	)
	(via
		(at 328.300588 -361.085384)
		(size 0.508)
		(drill 0.254)
		(layers "F.Cu" "B.Cu")
		(net "GND")
	)
	(via
		(at 138.864848 -278.946356)
		(size 0.4064)
		(drill 0.2032)
		(layers "F.Cu" "B.Cu")
		(net "GND")
	)
	(via
		(at 291.038026 -339.809836)
		(size 0.508)
		(drill 0.254)
		(layers "F.Cu" "B.Cu")
		(net "GND")
	)
	(via
		(at 261.05104 -114.765328)
		(size 0.508)
		(drill 0.254)
		(layers "F.Cu" "B.Cu")
		(net "GND")
	)
	(via
		(at 379.574044 -299.400722)
		(size 0.508)
		(drill 0.254)
		(layers "F.Cu" "B.Cu")
		(net "GND")
	)
	(via
		(at 104.090978 -293.52621)
		(size 0.4064)
		(drill 0.2032)
		(layers "F.Cu" "B.Cu")
		(net "GND")
	)
	(via
		(at 191.677036 -27.505152)
		(size 0.508)
		(drill 0.254)
		(layers "F.Cu" "B.Cu")
		(net "GND")
	)
	(via
		(at 277.192232 -198.185024)
		(size 0.4826)
		(drill 0.254)
		(layers "F.Cu" "B.Cu")
		(net "GND")
	)
	(via
		(at 413.752284 -315.485018)
		(size 0.4826)
		(drill 0.254)
		(layers "F.Cu" "B.Cu")
		(net "GND")
	)
	(via
		(at 373.644922 -261.12597)
		(size 0.4064)
		(drill 0.2032)
		(layers "F.Cu" "B.Cu")
		(net "GND")
	)
	(via
		(at 164.427916 -236.435392)
		(size 0.4826)
		(drill 0.254)
		(layers "F.Cu" "B.Cu")
		(net "GND")
	)
	(via
		(at 331.165454 -420.318184)
		(size 0.4572)
		(drill 0.254)
		(layers "F.Cu" "B.Cu")
		(net "GND")
	)
	(via
		(at 352.671126 -242.054126)
		(size 0.4064)
		(drill 0.2032)
		(layers "F.Cu" "B.Cu")
		(net "GND")
	)
	(via
		(at 330.369672 -31.937706)
		(size 0.508)
		(drill 0.254)
		(layers "F.Cu" "B.Cu")
		(net "GND")
	)
	(via
		(at 192.277746 -210.510374)
		(size 0.4826)
		(drill 0.254)
		(layers "F.Cu" "B.Cu")
		(net "GND")
	)
	(via
		(at 338.464906 -415.38652)
		(size 0.4064)
		(drill 0.2032)
		(layers "F.Cu" "B.Cu")
		(net "GND")
	)
	(via
		(at 338.911946 -412.84652)
		(size 0.4064)
		(drill 0.2032)
		(layers "F.Cu" "B.Cu")
		(net "GND")
	)
	(via
		(at 79.401924 -407.00452)
		(size 0.4064)
		(drill 0.2032)
		(layers "F.Cu" "B.Cu")
		(net "GND")
	)
	(via
		(at 415.201862 -412.84652)
		(size 0.4064)
		(drill 0.2032)
		(layers "F.Cu" "B.Cu")
		(net "GND")
	)
	(via
		(at 347.33103 -285.42615)
		(size 0.4064)
		(drill 0.2032)
		(layers "F.Cu" "B.Cu")
		(net "GND")
	)
	(via
		(at 289.564318 -200.735184)
		(size 0.4826)
		(drill 0.254)
		(layers "F.Cu" "B.Cu")
		(net "GND")
	)
	(via
		(at 168.527984 -196.485256)
		(size 0.4826)
		(drill 0.254)
		(layers "F.Cu" "B.Cu")
		(net "GND")
	)
	(via
		(at 345.151202 -237.19409)
		(size 0.4064)
		(drill 0.2032)
		(layers "F.Cu" "B.Cu")
		(net "GND")
	)
	(via
		(at 102.261924 -32.02051)
		(size 0.508)
		(drill 0.254)
		(layers "F.Cu" "B.Cu")
		(net "GND")
	)
	(via
		(at 448.063366 -377.29287)
		(size 0.508)
		(drill 0.254)
		(layers "F.Cu" "B.Cu")
		(net "GND")
	)
	(via
		(at 352.9711 -270.846042)
		(size 0.4064)
		(drill 0.2032)
		(layers "F.Cu" "B.Cu")
		(net "GND")
	)
	(via
		(at 394.349478 -438.651396)
		(size 0.4572)
		(drill 0.2032)
		(layers "F.Cu" "B.Cu")
		(net "GND")
	)
	(via
		(at 317.380874 -417.778184)
		(size 0.4572)
		(drill 0.254)
		(layers "F.Cu" "B.Cu")
		(net "GND")
	)
	(via
		(at 467.5378 -284.023054)
		(size 0.508)
		(drill 0.254)
		(layers "F.Cu" "B.Cu")
		(net "GND")
	)
	(via
		(at 76.812902 -236.650276)
		(size 0.4064)
		(drill 0.2032)
		(layers "F.Cu" "B.Cu")
		(net "GND")
	)
	(via
		(at 45.755814 -368.37493)
		(size 0.508)
		(drill 0.254)
		(layers "F.Cu" "B.Cu")
		(net "GND")
	)
	(via
		(at 207.3656 -304.010314)
		(size 0.4826)
		(drill 0.254)
		(layers "F.Cu" "B.Cu")
		(net "GND")
	)
	(via
		(at 78.783942 -333.842868)
		(size 0.49022)
		(drill 0.254)
		(layers "F.Cu" "B.Cu")
		(net "GND")
	)
	(via
		(at 338.823554 -419.046152)
		(size 0.4572)
		(drill 0.254)
		(layers "F.Cu" "B.Cu")
		(net "GND")
	)
	(via
		(at 16.490442 -230.0605)
		(size 0.4826)
		(drill 0.254)
		(layers "F.Cu" "B.Cu")
		(net "GND")
	)
	(via
		(at 68.80987 -154.55519)
		(size 0.508)
		(drill 0.254)
		(layers "F.Cu" "B.Cu")
		(net "GND")
	)
	(via
		(at 84.249768 -425.547282)
		(size 0.4572)
		(drill 0.2032)
		(layers "F.Cu" "B.Cu")
		(net "GND")
	)
	(via
		(at 321.249548 -434.899562)
		(size 0.4572)
		(drill 0.2032)
		(layers "F.Cu" "B.Cu")
		(net "GND")
	)
	(via
		(at 100.644198 -80.138778)
		(size 0.508)
		(drill 0.254)
		(layers "F.Cu" "B.Cu")
		(net "GND")
	)
	(via
		(at 280.635964 -269.585186)
		(size 0.4826)
		(drill 0.254)
		(layers "F.Cu" "B.Cu")
		(net "GND")
	)
	(via
		(at 29.252164 -280.635202)
		(size 0.4826)
		(drill 0.254)
		(layers "F.Cu" "B.Cu")
		(net "GND")
	)
	(via
		(at 107.870244 -382.54432)
		(size 0.508)
		(drill 0.254)
		(layers "F.Cu" "B.Cu")
		(net "GND")
	)
	(via
		(at 415.083752 -202.434952)
		(size 0.4826)
		(drill 0.254)
		(layers "F.Cu" "B.Cu")
		(net "GND")
	)
	(via
		(at 402.792438 -394.25753)
		(size 0.4064)
		(drill 0.2032)
		(layers "F.Cu" "B.Cu")
		(net "GND")
	)
	(via
		(at 145.328894 -403.830536)
		(size 0.4572)
		(drill 0.254)
		(layers "F.Cu" "B.Cu")
		(net "GND")
	)
	(via
		(at 77.520546 -355.795326)
		(size 0.508)
		(drill 0.254)
		(layers "F.Cu" "B.Cu")
		(net "GND")
	)
	(via
		(at 437.325516 -330.730352)
		(size 0.508)
		(drill 0.254)
		(layers "F.Cu" "B.Cu")
		(net "GND")
	)
	(via
		(at 25.152096 -272.135346)
		(size 0.4826)
		(drill 0.254)
		(layers "F.Cu" "B.Cu")
		(net "GND")
	)
	(via
		(at 283.351732 -277.235158)
		(size 0.4826)
		(drill 0.254)
		(layers "F.Cu" "B.Cu")
		(net "GND")
	)
	(via
		(at 58.156094 -368.37493)
		(size 0.508)
		(drill 0.254)
		(layers "F.Cu" "B.Cu")
		(net "GND")
	)
	(via
		(at 189.097158 -14.826742)
		(size 0.508)
		(drill 0.254)
		(layers "F.Cu" "B.Cu")
		(net "GND")
	)
	(via
		(at 452.858378 -396.09522)
		(size 0.49022)
		(drill 0.254)
		(layers "F.Cu" "B.Cu")
		(net "GND")
	)
	(via
		(at 73.29805 -375.793)
		(size 0.508)
		(drill 0.254)
		(layers "F.Cu" "B.Cu")
		(net "GND")
	)
	(via
		(at 147.349718 -427.851316)
		(size 0.4572)
		(drill 0.2032)
		(layers "F.Cu" "B.Cu")
		(net "GND")
	)
	(via
		(at 381.334772 -242.864132)
		(size 0.4064)
		(drill 0.2032)
		(layers "F.Cu" "B.Cu")
		(net "GND")
	)
	(via
		(at 349.211138 -274.086066)
		(size 0.4064)
		(drill 0.2032)
		(layers "F.Cu" "B.Cu")
		(net "GND")
	)
	(via
		(at 47.235364 -404.46452)
		(size 0.4064)
		(drill 0.2032)
		(layers "F.Cu" "B.Cu")
		(net "GND")
	)
	(via
		(at 345.50604 -394.831062)
		(size 0.4064)
		(drill 0.2032)
		(layers "F.Cu" "B.Cu")
		(net "GND")
	)
	(via
		(at 21.70811 -244.935248)
		(size 0.4826)
		(drill 0.254)
		(layers "F.Cu" "B.Cu")
		(net "GND")
	)
	(via
		(at 336.22107 -255.824228)
		(size 0.4064)
		(drill 0.2032)
		(layers "F.Cu" "B.Cu")
		(net "GND")
	)
	(via
		(at 305.983894 -211.784946)
		(size 0.4826)
		(drill 0.254)
		(layers "F.Cu" "B.Cu")
		(net "GND")
	)
	(via
		(at 67.945 -55.992014)
		(size 0.508)
		(drill 0.254)
		(layers "F.Cu" "B.Cu")
		(net "GND")
	)
	(via
		(at 127.114808 -278.13635)
		(size 0.4064)
		(drill 0.2032)
		(layers "F.Cu" "B.Cu")
		(net "GND")
	)
	(via
		(at 150.976584 -368.37493)
		(size 0.508)
		(drill 0.254)
		(layers "F.Cu" "B.Cu")
		(net "GND")
	)
	(via
		(at 93.751146 -262.746236)
		(size 0.4064)
		(drill 0.2032)
		(layers "F.Cu" "B.Cu")
		(net "GND")
	)
	(via
		(at 134.164832 -291.906198)
		(size 0.4064)
		(drill 0.2032)
		(layers "F.Cu" "B.Cu")
		(net "GND")
	)
	(via
		(at 450.088 -269.585186)
		(size 0.4826)
		(drill 0.254)
		(layers "F.Cu" "B.Cu")
		(net "GND")
	)
	(via
		(at 295.724072 -267.885164)
		(size 0.4826)
		(drill 0.254)
		(layers "F.Cu" "B.Cu")
		(net "GND")
	)
	(via
		(at 200.09358 -366.08258)
		(size 0.6604)
		(drill 0.3302)
		(layers "F.Cu" "B.Cu")
		(net "GND")
	)
	(via
		(at 42.955718 -209.235294)
		(size 0.4826)
		(drill 0.254)
		(layers "F.Cu" "B.Cu")
		(net "GND")
	)
	(via
		(at 371.869462 -415.38652)
		(size 0.4064)
		(drill 0.2032)
		(layers "F.Cu" "B.Cu")
		(net "GND")
	)
	(via
		(at 393.397994 -412.212536)
		(size 0.4572)
		(drill 0.254)
		(layers "F.Cu" "B.Cu")
		(net "GND")
	)
	(via
		(at 151.094186 -412.570168)
		(size 0.4064)
		(drill 0.2032)
		(layers "F.Cu" "B.Cu")
		(net "GND")
	)
	(via
		(at 357.487982 -256.387346)
		(size 0.4826)
		(drill 0.254)
		(layers "F.Cu" "B.Cu")
		(net "GND")
	)
	(via
		(at 208.564226 -34.196528)
		(size 0.508)
		(drill 0.254)
		(layers "F.Cu" "B.Cu")
		(net "GND")
	)
	(via
		(at 389.79475 -252.584204)
		(size 0.4064)
		(drill 0.2032)
		(layers "F.Cu" "B.Cu")
		(net "GND")
	)
	(via
		(at 372.655846 -184.683146)
		(size 0.49022)
		(drill 0.254)
		(layers "F.Cu" "B.Cu")
		(net "GND")
	)
	(via
		(at 171.97197 -227.085398)
		(size 0.4826)
		(drill 0.254)
		(layers "F.Cu" "B.Cu")
		(net "GND")
	)
	(via
		(at 78.41107 -232.334308)
		(size 0.4064)
		(drill 0.2032)
		(layers "F.Cu" "B.Cu")
		(net "GND")
	)
	(via
		(at 144.034764 -286.23641)
		(size 0.4064)
		(drill 0.2032)
		(layers "F.Cu" "B.Cu")
		(net "GND")
	)
	(via
		(at 42.955718 -314.635388)
		(size 0.4826)
		(drill 0.254)
		(layers "F.Cu" "B.Cu")
		(net "GND")
	)
	(via
		(at 437.874918 -349.803212)
		(size 0.508)
		(drill 0.254)
		(layers "F.Cu" "B.Cu")
		(net "GND")
	)
	(via
		(at 155.349702 -435.0512)
		(size 0.4572)
		(drill 0.2032)
		(layers "F.Cu" "B.Cu")
		(net "GND")
	)
	(via
		(at 292.280086 -244.934994)
		(size 0.4826)
		(drill 0.254)
		(layers "F.Cu" "B.Cu")
		(net "GND")
	)
	(via
		(at 171.97197 -267.885418)
		(size 0.4826)
		(drill 0.254)
		(layers "F.Cu" "B.Cu")
		(net "GND")
	)
	(via
		(at 51.416458 -391.830814)
		(size 0.4064)
		(drill 0.2032)
		(layers "F.Cu" "B.Cu")
		(net "GND")
	)
	(via
		(at 396.397988 -390.92632)
		(size 0.508)
		(drill 0.254)
		(layers "F.Cu" "B.Cu")
		(net "GND")
	)
	(via
		(at 133.864858 -251.774452)
		(size 0.4064)
		(drill 0.2032)
		(layers "F.Cu" "B.Cu")
		(net "GND")
	)
	(via
		(at 168.527984 -291.685218)
		(size 0.4826)
		(drill 0.254)
		(layers "F.Cu" "B.Cu")
		(net "GND")
	)
	(via
		(at 77.112876 -269.770352)
		(size 0.4064)
		(drill 0.2032)
		(layers "F.Cu" "B.Cu")
		(net "GND")
	)
	(via
		(at 395.781276 -178.350164)
		(size 0.49022)
		(drill 0.254)
		(layers "F.Cu" "B.Cu")
		(net "GND")
	)
	(via
		(at 346.995242 -259.729986)
		(size 0.4826)
		(drill 0.254)
		(layers "F.Cu" "B.Cu")
		(net "GND")
	)
	(via
		(at 116.304822 -278.946356)
		(size 0.4064)
		(drill 0.2032)
		(layers "F.Cu" "B.Cu")
		(net "GND")
	)
	(via
		(at 454.188068 -198.185024)
		(size 0.4826)
		(drill 0.254)
		(layers "F.Cu" "B.Cu")
		(net "GND")
	)
	(via
		(at 109.347 -18.5166)
		(size 0.508)
		(drill 0.254)
		(layers "F.Cu" "B.Cu")
		(net "GND")
	)
	(via
		(at 102.211124 -290.286186)
		(size 0.4064)
		(drill 0.2032)
		(layers "F.Cu" "B.Cu")
		(net "GND")
	)
	(via
		(at 375.054876 -276.516084)
		(size 0.4064)
		(drill 0.2032)
		(layers "F.Cu" "B.Cu")
		(net "GND")
	)
	(via
		(at 329.941174 -261.935976)
		(size 0.4064)
		(drill 0.2032)
		(layers "F.Cu" "B.Cu")
		(net "GND")
	)
	(via
		(at 206.248 -213.485222)
		(size 0.4826)
		(drill 0.254)
		(layers "F.Cu" "B.Cu")
		(net "GND")
	)
	(via
		(at 291.162486 -304.01006)
		(size 0.4826)
		(drill 0.254)
		(layers "F.Cu" "B.Cu")
		(net "GND")
	)
	(via
		(at 308.598316 -431.887122)
		(size 0.508)
		(drill 0.254)
		(layers "F.Cu" "B.Cu")
		(net "GND")
	)
	(via
		(at 49.216564 -404.46452)
		(size 0.4064)
		(drill 0.2032)
		(layers "F.Cu" "B.Cu")
		(net "GND")
	)
	(via
		(at 8.590788 -372.12905)
		(size 0.508)
		(drill 0.254)
		(layers "F.Cu" "B.Cu")
		(net "GND")
	)
	(via
		(at 12.164568 -73.694798)
		(size 0.508)
		(drill 0.254)
		(layers "F.Cu" "B.Cu")
		(net "GND")
	)
	(via
		(at 21.70811 -261.935214)
		(size 0.4826)
		(drill 0.254)
		(layers "F.Cu" "B.Cu")
		(net "GND")
	)
	(via
		(at 425.327064 -154.8003)
		(size 0.508)
		(drill 0.254)
		(layers "F.Cu" "B.Cu")
		(net "GND")
	)
	(via
		(at 194.114166 -347.41612)
		(size 0.508)
		(drill 0.254)
		(layers "F.Cu" "B.Cu")
		(net "GND")
	)
	(via
		(at 333.230982 -265.986006)
		(size 0.4064)
		(drill 0.2032)
		(layers "F.Cu" "B.Cu")
		(net "GND")
	)
	(via
		(at 409.89504 -382.34493)
		(size 0.508)
		(drill 0.254)
		(layers "F.Cu" "B.Cu")
		(net "GND")
	)
	(via
		(at 121.174764 -255.824482)
		(size 0.4064)
		(drill 0.2032)
		(layers "F.Cu" "B.Cu")
		(net "GND")
	)
	(via
		(at 379.018546 -396.710662)
		(size 0.4064)
		(drill 0.2032)
		(layers "F.Cu" "B.Cu")
		(net "GND")
	)
	(via
		(at 371.46484 -225.85426)
		(size 0.4064)
		(drill 0.2032)
		(layers "F.Cu" "B.Cu")
		(net "GND")
	)
	(via
		(at 195.988432 -228.78542)
		(size 0.4826)
		(drill 0.254)
		(layers "F.Cu" "B.Cu")
		(net "GND")
	)
	(via
		(at 418.624512 -4.32943)
		(size 0.508)
		(drill 0.254)
		(layers "F.Cu" "B.Cu")
		(net "GND")
	)
	(via
		(at 58.310526 -285.310326)
		(size 0.4826)
		(drill 0.254)
		(layers "F.Cu" "B.Cu")
		(net "GND")
	)
	(via
		(at 44.340018 -243.235226)
		(size 0.4826)
		(drill 0.254)
		(layers "F.Cu" "B.Cu")
		(net "GND")
	)
	(via
		(at 137.45464 -281.376374)
		(size 0.4064)
		(drill 0.2032)
		(layers "F.Cu" "B.Cu")
		(net "GND")
	)
	(via
		(at 372.22811 -417.778184)
		(size 0.4572)
		(drill 0.254)
		(layers "F.Cu" "B.Cu")
		(net "GND")
	)
	(via
		(at 355.791008 -285.42615)
		(size 0.4064)
		(drill 0.2032)
		(layers "F.Cu" "B.Cu")
		(net "GND")
	)
	(via
		(at 100.955094 -258.830318)
		(size 0.4826)
		(drill 0.254)
		(layers "F.Cu" "B.Cu")
		(net "GND")
	)
	(via
		(at 90.461084 -289.47618)
		(size 0.4064)
		(drill 0.2032)
		(layers "F.Cu" "B.Cu")
		(net "GND")
	)
	(via
		(at 84.99094 -235.574332)
		(size 0.4064)
		(drill 0.2032)
		(layers "F.Cu" "B.Cu")
		(net "GND")
	)
	(via
		(at 206.248 -248.335292)
		(size 0.4826)
		(drill 0.254)
		(layers "F.Cu" "B.Cu")
		(net "GND")
	)
	(via
		(at 447.761868 -201.160126)
		(size 0.4826)
		(drill 0.254)
		(layers "F.Cu" "B.Cu")
		(net "GND")
	)
	(via
		(at 56.90997 -32.295084)
		(size 0.508)
		(drill 0.254)
		(layers "F.Cu" "B.Cu")
		(net "GND")
	)
	(via
		(at 446.37579 -45.69206)
		(size 0.508)
		(drill 0.254)
		(layers "F.Cu" "B.Cu")
		(net "GND")
	)
	(via
		(at 238.605314 -152.545034)
		(size 0.508)
		(drill 0.254)
		(layers "F.Cu" "B.Cu")
		(net "GND")
	)
	(via
		(at 318.81699 -35.573462)
		(size 0.508)
		(drill 0.254)
		(layers "F.Cu" "B.Cu")
		(net "GND")
	)
	(via
		(at 58.418476 -341.622634)
		(size 0.6604)
		(drill 0.3302)
		(layers "F.Cu" "B.Cu")
		(net "GND")
	)
	(via
		(at 398.17675 -6.091174)
		(size 0.508)
		(drill 0.254)
		(layers "F.Cu" "B.Cu")
		(net "GND")
	)
	(via
		(at 142.265654 -403.830536)
		(size 0.4572)
		(drill 0.254)
		(layers "F.Cu" "B.Cu")
		(net "GND")
	)
	(via
		(at 321.378326 -394.831062)
		(size 0.4064)
		(drill 0.2032)
		(layers "F.Cu" "B.Cu")
		(net "GND")
	)
	(via
		(at 297.841162 -394.858494)
		(size 0.508)
		(drill 0.254)
		(layers "F.Cu" "B.Cu")
		(net "GND")
	)
	(via
		(at 128.994662 -281.376374)
		(size 0.4064)
		(drill 0.2032)
		(layers "F.Cu" "B.Cu")
		(net "GND")
	)
	(via
		(at 164.427916 -250.885198)
		(size 0.4826)
		(drill 0.254)
		(layers "F.Cu" "B.Cu")
		(net "GND")
	)
	(via
		(at 370.759228 -114.394488)
		(size 0.508)
		(drill 0.254)
		(layers "F.Cu" "B.Cu")
		(net "GND")
	)
	(via
		(at 44.017946 -168.899332)
		(size 0.508)
		(drill 0.254)
		(layers "F.Cu" "B.Cu")
		(net "GND")
	)
	(via
		(at 78.283562 -369.69573)
		(size 0.508)
		(drill 0.254)
		(layers "F.Cu" "B.Cu")
		(net "GND")
	)
	(via
		(at 331.351128 -264.365994)
		(size 0.4064)
		(drill 0.2032)
		(layers "F.Cu" "B.Cu")
		(net "GND")
	)
	(via
		(at 114.696494 -405.098504)
		(size 0.4572)
		(drill 0.254)
		(layers "F.Cu" "B.Cu")
		(net "GND")
	)
	(via
		(at 147.042886 -271.390364)
		(size 0.4064)
		(drill 0.2032)
		(layers "F.Cu" "B.Cu")
		(net "GND")
	)
	(via
		(at 194.604132 -197.335394)
		(size 0.4826)
		(drill 0.254)
		(layers "F.Cu" "B.Cu")
		(net "GND")
	)
	(via
		(at 121.09831 -168.436798)
		(size 0.508)
		(drill 0.254)
		(layers "F.Cu" "B.Cu")
		(net "GND")
	)
	(via
		(at 95.80626 -352.475038)
		(size 0.508)
		(drill 0.254)
		(layers "F.Cu" "B.Cu")
		(net "GND")
	)
	(via
		(at 155.349702 -437.49976)
		(size 0.4572)
		(drill 0.2032)
		(layers "F.Cu" "B.Cu")
		(net "GND")
	)
	(via
		(at 130.87477 -265.176254)
		(size 0.4064)
		(drill 0.2032)
		(layers "F.Cu" "B.Cu")
		(net "GND")
	)
	(via
		(at 238.708692 -421.833548)
		(size 0.508)
		(drill 0.254)
		(layers "F.Cu" "B.Cu")
		(net "GND")
	)
	(via
		(at 140.744702 -290.286186)
		(size 0.4064)
		(drill 0.2032)
		(layers "F.Cu" "B.Cu")
		(net "GND")
	)
	(via
		(at 171.97197 -273.835368)
		(size 0.4826)
		(drill 0.254)
		(layers "F.Cu" "B.Cu")
		(net "GND")
	)
	(via
		(at 326.617076 -385.514088)
		(size 0.508)
		(drill 0.254)
		(layers "F.Cu" "B.Cu")
		(net "GND")
	)
	(via
		(at 40.23995 -269.58544)
		(size 0.4826)
		(drill 0.254)
		(layers "F.Cu" "B.Cu")
		(net "GND")
	)
	(via
		(at 164.427916 -300.185328)
		(size 0.4826)
		(drill 0.254)
		(layers "F.Cu" "B.Cu")
		(net "GND")
	)
	(via
		(at 408.98699 -414.752536)
		(size 0.4572)
		(drill 0.254)
		(layers "F.Cu" "B.Cu")
		(net "GND")
	)
	(via
		(at 440.741308 -346.882466)
		(size 0.508)
		(drill 0.254)
		(layers "F.Cu" "B.Cu")
		(net "GND")
	)
	(via
		(at 343.101168 -287.856168)
		(size 0.4064)
		(drill 0.2032)
		(layers "F.Cu" "B.Cu")
		(net "GND")
	)
	(via
		(at 134.349744 -425.547282)
		(size 0.4572)
		(drill 0.2032)
		(layers "F.Cu" "B.Cu")
		(net "GND")
	)
	(via
		(at 461.328516 -409.89885)
		(size 0.508)
		(drill 0.254)
		(layers "F.Cu" "B.Cu")
		(net "GND")
	)
	(via
		(at 109.219238 -42.2656)
		(size 0.508)
		(drill 0.254)
		(layers "F.Cu" "B.Cu")
		(net "GND")
	)
	(via
		(at 297.108372 -315.485018)
		(size 0.4826)
		(drill 0.254)
		(layers "F.Cu" "B.Cu")
		(net "GND")
	)
	(via
		(at 164.427916 -289.135312)
		(size 0.4826)
		(drill 0.254)
		(layers "F.Cu" "B.Cu")
		(net "GND")
	)
	(via
		(at 345.151202 -225.85426)
		(size 0.4064)
		(drill 0.2032)
		(layers "F.Cu" "B.Cu")
		(net "GND")
	)
	(via
		(at 347.50121 -241.24412)
		(size 0.4064)
		(drill 0.2032)
		(layers "F.Cu" "B.Cu")
		(net "GND")
	)
	(via
		(at 439.100214 -316.335156)
		(size 0.4826)
		(drill 0.254)
		(layers "F.Cu" "B.Cu")
		(net "GND")
	)
	(via
		(at 140.349732 -434.899562)
		(size 0.4572)
		(drill 0.2032)
		(layers "F.Cu" "B.Cu")
		(net "GND")
	)
	(via
		(at 123.551696 -373.96293)
		(size 0.508)
		(drill 0.254)
		(layers "F.Cu" "B.Cu")
		(net "GND")
	)
	(via
		(at 330.411074 -269.22603)
		(size 0.4064)
		(drill 0.2032)
		(layers "F.Cu" "B.Cu")
		(net "GND")
	)
	(via
		(at 116.004848 -248.534428)
		(size 0.4064)
		(drill 0.2032)
		(layers "F.Cu" "B.Cu")
		(net "GND")
	)
	(via
		(at 428.557182 -343.23528)
		(size 0.508)
		(drill 0.254)
		(layers "F.Cu" "B.Cu")
		(net "GND")
	)
	(via
		(at 71.455534 -328.10196)
		(size 0.508)
		(drill 0.254)
		(layers "F.Cu" "B.Cu")
		(net "GND")
	)
	(via
		(at 295.724072 -252.584966)
		(size 0.4826)
		(drill 0.254)
		(layers "F.Cu" "B.Cu")
		(net "GND")
	)
	(via
		(at 238.611664 -370.7384)
		(size 0.508)
		(drill 0.254)
		(layers "F.Cu" "B.Cu")
		(net "GND")
	)
	(via
		(at 73.24979 -437.34736)
		(size 0.4572)
		(drill 0.2032)
		(layers "F.Cu" "B.Cu")
		(net "GND")
	)
	(via
		(at 101.91115 -245.294404)
		(size 0.4064)
		(drill 0.2032)
		(layers "F.Cu" "B.Cu")
		(net "GND")
	)
	(via
		(at 283.351732 -314.635134)
		(size 0.4826)
		(drill 0.254)
		(layers "F.Cu" "B.Cu")
		(net "GND")
	)
	(via
		(at 151.34971 -433.899564)
		(size 0.4572)
		(drill 0.2032)
		(layers "F.Cu" "B.Cu")
		(net "GND")
	)
	(via
		(at 326.351138 -253.39421)
		(size 0.4064)
		(drill 0.2032)
		(layers "F.Cu" "B.Cu")
		(net "GND")
	)
	(via
		(at 349.851218 -238.814102)
		(size 0.4064)
		(drill 0.2032)
		(layers "F.Cu" "B.Cu")
		(net "GND")
	)
	(via
		(at 201.000614 -67.271392)
		(size 0.508)
		(drill 0.254)
		(layers "F.Cu" "B.Cu")
		(net "GND")
	)
	(via
		(at 420.10584 -377.41733)
		(size 0.508)
		(drill 0.254)
		(layers "F.Cu" "B.Cu")
		(net "GND")
	)
	(via
		(at 387.914896 -239.624108)
		(size 0.4064)
		(drill 0.2032)
		(layers "F.Cu" "B.Cu")
		(net "GND")
	)
	(via
		(at 385.316476 -402.259038)
		(size 0.4572)
		(drill 0.254)
		(layers "F.Cu" "B.Cu")
		(net "GND")
	)
	(via
		(at 295.430702 -122.349514)
		(size 0.508)
		(drill 0.254)
		(layers "F.Cu" "B.Cu")
		(net "GND")
	)
	(via
		(at 30.568138 -18.503138)
		(size 0.508)
		(drill 0.254)
		(layers "F.Cu" "B.Cu")
		(net "GND")
	)
	(via
		(at 331.351128 -280.566114)
		(size 0.4064)
		(drill 0.2032)
		(layers "F.Cu" "B.Cu")
		(net "GND")
	)
	(via
		(at 329.941174 -270.036036)
		(size 0.4064)
		(drill 0.2032)
		(layers "F.Cu" "B.Cu")
		(net "GND")
	)
	(via
		(at 345.038426 -412.84652)
		(size 0.4064)
		(drill 0.2032)
		(layers "F.Cu" "B.Cu")
		(net "GND")
	)
	(via
		(at 445.259968 -209.23504)
		(size 0.4826)
		(drill 0.254)
		(layers "F.Cu" "B.Cu")
		(net "GND")
	)
	(via
		(at 129.596642 -75.46086)
		(size 0.508)
		(drill 0.254)
		(layers "F.Cu" "B.Cu")
		(net "GND")
	)
	(via
		(at 459.158594 -44.471082)
		(size 0.508)
		(drill 0.254)
		(layers "F.Cu" "B.Cu")
		(net "GND")
	)
	(via
		(at 54.210458 -286.160464)
		(size 0.4826)
		(drill 0.254)
		(layers "F.Cu" "B.Cu")
		(net "GND")
	)
	(via
		(at 322.965318 -340.003384)
		(size 0.508)
		(drill 0.254)
		(layers "F.Cu" "B.Cu")
		(net "GND")
	)
	(via
		(at 69.241162 -176.65954)
		(size 0.508)
		(drill 0.254)
		(layers "F.Cu" "B.Cu")
		(net "GND")
	)
	(via
		(at 182.278782 -350.14535)
		(size 0.49022)
		(drill 0.254)
		(layers "F.Cu" "B.Cu")
		(net "GND")
	)
	(via
		(at 128.208278 -403.830536)
		(size 0.4572)
		(drill 0.254)
		(layers "F.Cu" "B.Cu")
		(net "GND")
	)
	(via
		(at 40.23995 -266.185396)
		(size 0.4826)
		(drill 0.254)
		(layers "F.Cu" "B.Cu")
		(net "GND")
	)
	(via
		(at 413.752284 -212.635084)
		(size 0.4826)
		(drill 0.254)
		(layers "F.Cu" "B.Cu")
		(net "GND")
	)
	(via
		(at 132.803138 -407.638504)
		(size 0.4572)
		(drill 0.254)
		(layers "F.Cu" "B.Cu")
		(net "GND")
	)
	(via
		(at 187.833 -343.415874)
		(size 0.508)
		(drill 0.254)
		(layers "F.Cu" "B.Cu")
		(net "GND")
	)
	(via
		(at 373.344694 -240.434114)
		(size 0.4064)
		(drill 0.2032)
		(layers "F.Cu" "B.Cu")
		(net "GND")
	)
	(via
		(at 74.535792 -21.840444)
		(size 0.508)
		(drill 0.254)
		(layers "F.Cu" "B.Cu")
		(net "GND")
	)
	(via
		(at 97.629218 -334.615028)
		(size 0.49022)
		(drill 0.254)
		(layers "F.Cu" "B.Cu")
		(net "GND")
	)
	(via
		(at 55.343044 -412.570168)
		(size 0.4064)
		(drill 0.2032)
		(layers "F.Cu" "B.Cu")
		(net "GND")
	)
	(via
		(at 52.667154 -347.287088)
		(size 0.49022)
		(drill 0.254)
		(layers "F.Cu" "B.Cu")
		(net "GND")
	)
	(via
		(at 320.616326 -402.309838)
		(size 0.4572)
		(drill 0.254)
		(layers "F.Cu" "B.Cu")
		(net "GND")
	)
	(via
		(at 351.091246 -274.086066)
		(size 0.4064)
		(drill 0.2032)
		(layers "F.Cu" "B.Cu")
		(net "GND")
	)
	(via
		(at 421.790876 -331.19949)
		(size 0.508)
		(drill 0.254)
		(layers "F.Cu" "B.Cu")
		(net "GND")
	)
	(via
		(at 186.67095 -421.087804)
		(size 0.508)
		(drill 0.254)
		(layers "F.Cu" "B.Cu")
		(net "GND")
	)
	(via
		(at 217.062812 -25.311354)
		(size 0.508)
		(drill 0.254)
		(layers "F.Cu" "B.Cu")
		(net "GND")
	)
	(via
		(at 130.40487 -283.806392)
		(size 0.4064)
		(drill 0.2032)
		(layers "F.Cu" "B.Cu")
		(net "GND")
	)
	(via
		(at 170.245024 -379.321568)
		(size 0.508)
		(drill 0.254)
		(layers "F.Cu" "B.Cu")
		(net "GND")
	)
	(via
		(at 420.1033 -379.22073)
		(size 0.508)
		(drill 0.254)
		(layers "F.Cu" "B.Cu")
		(net "GND")
	)
	(via
		(at 307.368194 -222.834962)
		(size 0.4826)
		(drill 0.254)
		(layers "F.Cu" "B.Cu")
		(net "GND")
	)
	(via
		(at 378.814838 -279.756108)
		(size 0.4064)
		(drill 0.2032)
		(layers "F.Cu" "B.Cu")
		(net "GND")
	)
	(via
		(at 237.861856 -317.206376)
		(size 0.508)
		(drill 0.254)
		(layers "F.Cu" "B.Cu")
		(net "GND")
	)
	(via
		(at 145.144744 -235.574332)
		(size 0.4064)
		(drill 0.2032)
		(layers "F.Cu" "B.Cu")
		(net "GND")
	)
	(via
		(at 334.341216 -255.824228)
		(size 0.4064)
		(drill 0.2032)
		(layers "F.Cu" "B.Cu")
		(net "GND")
	)
	(via
		(at 329.249532 -426.54728)
		(size 0.4572)
		(drill 0.2032)
		(layers "F.Cu" "B.Cu")
		(net "GND")
	)
	(via
		(at 9.697974 -368.767614)
		(size 0.6604)
		(drill 0.3302)
		(layers "F.Cu" "B.Cu")
		(net "GND")
	)
	(via
		(at 165.812216 -240.68532)
		(size 0.4826)
		(drill 0.254)
		(layers "F.Cu" "B.Cu")
		(net "GND")
	)
	(via
		(at 50.499772 -218.585288)
		(size 0.4826)
		(drill 0.254)
		(layers "F.Cu" "B.Cu")
		(net "GND")
	)
	(via
		(at 176.911 -134.584948)
		(size 0.508)
		(drill 0.254)
		(layers "F.Cu" "B.Cu")
		(net "GND")
	)
	(via
		(at 18.127218 -18.5039)
		(size 0.508)
		(drill 0.254)
		(layers "F.Cu" "B.Cu")
		(net "GND")
	)
	(via
		(at 353.911154 -270.846042)
		(size 0.4064)
		(drill 0.2032)
		(layers "F.Cu" "B.Cu")
		(net "GND")
	)
	(via
		(at 362.534708 -229.904036)
		(size 0.4064)
		(drill 0.2032)
		(layers "F.Cu" "B.Cu")
		(net "GND")
	)
	(via
		(at 390.050274 -184.683146)
		(size 0.49022)
		(drill 0.254)
		(layers "F.Cu" "B.Cu")
		(net "GND")
	)
	(via
		(at 84.99094 -251.774452)
		(size 0.4064)
		(drill 0.2032)
		(layers "F.Cu" "B.Cu")
		(net "GND")
	)
	(via
		(at 99.090988 -240.434368)
		(size 0.4064)
		(drill 0.2032)
		(layers "F.Cu" "B.Cu")
		(net "GND")
	)
	(via
		(at 32.320484 -402.793454)
		(size 0.508)
		(drill 0.254)
		(layers "F.Cu" "B.Cu")
		(net "GND")
	)
	(via
		(at 391.3759 -315.179202)
		(size 0.508)
		(drill 0.254)
		(layers "F.Cu" "B.Cu")
		(net "GND")
	)
	(via
		(at 72.660764 -7.215124)
		(size 0.508)
		(drill 0.254)
		(layers "F.Cu" "B.Cu")
		(net "GND")
	)
	(via
		(at 179.516024 -262.785352)
		(size 0.4826)
		(drill 0.254)
		(layers "F.Cu" "B.Cu")
		(net "GND")
	)
	(via
		(at 83.111086 -255.014476)
		(size 0.4064)
		(drill 0.2032)
		(layers "F.Cu" "B.Cu")
		(net "GND")
	)
	(via
		(at 123.617228 -50.169064)
		(size 0.508)
		(drill 0.254)
		(layers "F.Cu" "B.Cu")
		(net "GND")
	)
	(via
		(at 311.016396 -402.259038)
		(size 0.4572)
		(drill 0.254)
		(layers "F.Cu" "B.Cu")
		(net "GND")
	)
	(via
		(at 198.276972 -75.27163)
		(size 0.508)
		(drill 0.254)
		(layers "F.Cu" "B.Cu")
		(net "GND")
	)
	(via
		(at 394.982954 -284.350206)
		(size 0.4064)
		(drill 0.2032)
		(layers "F.Cu" "B.Cu")
		(net "GND")
	)
	(via
		(at 161.419032 -390.160002)
		(size 0.4064)
		(drill 0.2032)
		(layers "F.Cu" "B.Cu")
		(net "GND")
	)
	(via
		(at 145.144744 -237.194344)
		(size 0.4064)
		(drill 0.2032)
		(layers "F.Cu" "B.Cu")
		(net "GND")
	)
	(via
		(at 65.628266 -170.867832)
		(size 0.49022)
		(drill 0.254)
		(layers "F.Cu" "B.Cu")
		(net "GND")
	)
	(via
		(at 346.39123 -295.145968)
		(size 0.4064)
		(drill 0.2032)
		(layers "F.Cu" "B.Cu")
		(net "GND")
	)
	(via
		(at 427.97095 -41.087548)
		(size 0.508)
		(drill 0.254)
		(layers "F.Cu" "B.Cu")
		(net "GND")
	)
	(via
		(at 149.274784 -372.15953)
		(size 0.508)
		(drill 0.254)
		(layers "F.Cu" "B.Cu")
		(net "GND")
	)
	(via
		(at 140.349732 -432.451256)
		(size 0.4572)
		(drill 0.2032)
		(layers "F.Cu" "B.Cu")
		(net "GND")
	)
	(via
		(at 100.331016 -264.366248)
		(size 0.4064)
		(drill 0.2032)
		(layers "F.Cu" "B.Cu")
		(net "GND")
	)
	(via
		(at 431.55616 -255.135126)
		(size 0.4826)
		(drill 0.254)
		(layers "F.Cu" "B.Cu")
		(net "GND")
	)
	(via
		(at 158.840678 -403.830536)
		(size 0.4572)
		(drill 0.254)
		(layers "F.Cu" "B.Cu")
		(net "GND")
	)
	(via
		(at 157.309058 -407.638504)
		(size 0.4572)
		(drill 0.254)
		(layers "F.Cu" "B.Cu")
		(net "GND")
	)
	(via
		(at 183.932322 -117.442742)
		(size 0.4572)
		(drill 0.254)
		(layers "F.Cu" "B.Cu")
		(net "GND")
	)
	(via
		(at 304.855118 -420.318184)
		(size 0.4572)
		(drill 0.254)
		(layers "F.Cu" "B.Cu")
		(net "GND")
	)
	(via
		(at 57.58307 -18.503138)
		(size 0.508)
		(drill 0.254)
		(layers "F.Cu" "B.Cu")
		(net "GND")
	)
	(via
		(at 347.031056 -256.634234)
		(size 0.4064)
		(drill 0.2032)
		(layers "F.Cu" "B.Cu")
		(net "GND")
	)
	(via
		(at 331.351128 -283.806138)
		(size 0.4064)
		(drill 0.2032)
		(layers "F.Cu" "B.Cu")
		(net "GND")
	)
	(via
		(at 399.934684 -63.828676)
		(size 0.508)
		(drill 0.254)
		(layers "F.Cu" "B.Cu")
		(net "GND")
	)
	(via
		(at 198.7042 -215.185244)
		(size 0.4826)
		(drill 0.254)
		(layers "F.Cu" "B.Cu")
		(net "GND")
	)
	(via
		(at 375.224802 -245.29415)
		(size 0.4064)
		(drill 0.2032)
		(layers "F.Cu" "B.Cu")
		(net "GND")
	)
	(via
		(at 140.397992 -382.54432)
		(size 0.508)
		(drill 0.254)
		(layers "F.Cu" "B.Cu")
		(net "GND")
	)
	(via
		(at 447.507106 -415.092642)
		(size 0.508)
		(drill 0.254)
		(layers "F.Cu" "B.Cu")
		(net "GND")
	)
	(via
		(at 367.064798 -290.285932)
		(size 0.4064)
		(drill 0.2032)
		(layers "F.Cu" "B.Cu")
		(net "GND")
	)
	(via
		(at 426.861732 -395.14526)
		(size 0.508)
		(drill 0.254)
		(layers "F.Cu" "B.Cu")
		(net "GND")
	)
	(via
		(at 86.87562 -340.120224)
		(size 0.508)
		(drill 0.254)
		(layers "F.Cu" "B.Cu")
		(net "GND")
	)
	(via
		(at 374.754902 -226.664266)
		(size 0.4064)
		(drill 0.2032)
		(layers "F.Cu" "B.Cu")
		(net "GND")
	)
	(via
		(at 164.427916 -267.885418)
		(size 0.4826)
		(drill 0.254)
		(layers "F.Cu" "B.Cu")
		(net "GND")
	)
	(via
		(at 13.6652 -110.604554)
		(size 0.508)
		(drill 0.254)
		(layers "F.Cu" "B.Cu")
		(net "GND")
	)
	(via
		(at 110.671102 -269.226284)
		(size 0.4064)
		(drill 0.2032)
		(layers "F.Cu" "B.Cu")
		(net "GND")
	)
	(via
		(at 331.821028 -266.796012)
		(size 0.4064)
		(drill 0.2032)
		(layers "F.Cu" "B.Cu")
		(net "GND")
	)
	(via
		(at 182.660798 -353.283774)
		(size 0.49022)
		(drill 0.254)
		(layers "F.Cu" "B.Cu")
		(net "GND")
	)
	(via
		(at 291.36721 -346.317316)
		(size 0.49022)
		(drill 0.254)
		(layers "F.Cu" "B.Cu")
		(net "GND")
	)
	(via
		(at 86.401148 -231.524302)
		(size 0.4064)
		(drill 0.2032)
		(layers "F.Cu" "B.Cu")
		(net "GND")
	)
	(via
		(at 198.148194 -356.962964)
		(size 0.508)
		(drill 0.254)
		(layers "F.Cu" "B.Cu")
		(net "GND")
	)
	(via
		(at 441.335414 -392.101578)
		(size 0.508)
		(drill 0.254)
		(layers "F.Cu" "B.Cu")
		(net "GND")
	)
	(via
		(at 183.616092 -246.63527)
		(size 0.4826)
		(drill 0.254)
		(layers "F.Cu" "B.Cu")
		(net "GND")
	)
	(via
		(at 347.50121 -254.204216)
		(size 0.4064)
		(drill 0.2032)
		(layers "F.Cu" "B.Cu")
		(net "GND")
	)
	(via
		(at 361.424728 -293.525956)
		(size 0.4064)
		(drill 0.2032)
		(layers "F.Cu" "B.Cu")
		(net "GND")
	)
	(via
		(at 55.334662 -5.597398)
		(size 0.508)
		(drill 0.254)
		(layers "F.Cu" "B.Cu")
		(net "GND")
	)
	(via
		(at 243.344954 -218.283536)
		(size 0.4826)
		(drill 0.254)
		(layers "F.Cu" "B.Cu")
		(net "GND")
	)
	(via
		(at 320.521584 -333.829914)
		(size 0.49022)
		(drill 0.254)
		(layers "F.Cu" "B.Cu")
		(net "GND")
	)
	(via
		(at 89.193878 -145.90141)
		(size 0.508)
		(drill 0.254)
		(layers "F.Cu" "B.Cu")
		(net "GND")
	)
	(via
		(at 25.152096 -244.085364)
		(size 0.4826)
		(drill 0.254)
		(layers "F.Cu" "B.Cu")
		(net "GND")
	)
	(via
		(at 433.024788 -430.337722)
		(size 0.508)
		(drill 0.254)
		(layers "F.Cu" "B.Cu")
		(net "GND")
	)
	(via
		(at 335.918556 -398.542002)
		(size 0.4064)
		(drill 0.2032)
		(layers "F.Cu" "B.Cu")
		(net "GND")
	)
	(via
		(at 135.466836 -369.69573)
		(size 0.508)
		(drill 0.254)
		(layers "F.Cu" "B.Cu")
		(net "GND")
	)
	(via
		(at 112.81791 -175.828198)
		(size 0.508)
		(drill 0.254)
		(layers "F.Cu" "B.Cu")
		(net "GND")
	)
	(via
		(at 372.234714 -271.656048)
		(size 0.4064)
		(drill 0.2032)
		(layers "F.Cu" "B.Cu")
		(net "GND")
	)
	(via
		(at 296.973498 -428.527718)
		(size 0.508)
		(drill 0.254)
		(layers "F.Cu" "B.Cu")
		(net "GND")
	)
	(via
		(at 198.12 -343.789)
		(size 0.508)
		(drill 0.254)
		(layers "F.Cu" "B.Cu")
		(net "GND")
	)
	(via
		(at 334.341216 -250.964192)
		(size 0.4064)
		(drill 0.2032)
		(layers "F.Cu" "B.Cu")
		(net "GND")
	)
	(via
		(at 380.303278 -140.456158)
		(size 0.508)
		(drill 0.254)
		(layers "F.Cu" "B.Cu")
		(net "GND")
	)
	(via
		(at 298.43984 -227.935028)
		(size 0.4826)
		(drill 0.254)
		(layers "F.Cu" "B.Cu")
		(net "GND")
	)
	(via
		(at 273.092164 -300.185074)
		(size 0.4826)
		(drill 0.254)
		(layers "F.Cu" "B.Cu")
		(net "GND")
	)
	(via
		(at 339.511132 -256.634234)
		(size 0.4064)
		(drill 0.2032)
		(layers "F.Cu" "B.Cu")
		(net "GND")
	)
	(via
		(at 379.924818 -229.094284)
		(size 0.4064)
		(drill 0.2032)
		(layers "F.Cu" "B.Cu")
		(net "GND")
	)
	(via
		(at 256.767076 -323.022722)
		(size 0.508)
		(drill 0.254)
		(layers "F.Cu" "B.Cu")
		(net "GND")
	)
	(via
		(at 382.470152 -378.07773)
		(size 0.508)
		(drill 0.254)
		(layers "F.Cu" "B.Cu")
		(net "GND")
	)
	(via
		(at 89.690956 -233.95432)
		(size 0.4064)
		(drill 0.2032)
		(layers "F.Cu" "B.Cu")
		(net "GND")
	)
	(via
		(at 375.054876 -278.136096)
		(size 0.4064)
		(drill 0.2032)
		(layers "F.Cu" "B.Cu")
		(net "GND")
	)
	(via
		(at 93.491558 -333.090012)
		(size 0.49022)
		(drill 0.254)
		(layers "F.Cu" "B.Cu")
		(net "GND")
	)
	(via
		(at 335.487518 -412.212536)
		(size 0.4572)
		(drill 0.254)
		(layers "F.Cu" "B.Cu")
		(net "GND")
	)
	(via
		(at 383.16027 -189.514226)
		(size 0.508)
		(drill 0.254)
		(layers "F.Cu" "B.Cu")
		(net "GND")
	)
	(via
		(at 98.50247 -407.619708)
		(size 0.508)
		(drill 0.254)
		(layers "F.Cu" "B.Cu")
		(net "GND")
	)
	(via
		(at 304.652426 -240.685066)
		(size 0.4826)
		(drill 0.254)
		(layers "F.Cu" "B.Cu")
		(net "GND")
	)
	(via
		(at 86.701122 -294.336216)
		(size 0.4064)
		(drill 0.2032)
		(layers "F.Cu" "B.Cu")
		(net "GND")
	)
	(via
		(at 393.668758 -309.191152)
		(size 0.508)
		(drill 0.254)
		(layers "F.Cu" "B.Cu")
		(net "GND")
	)
	(via
		(at 388.68477 -293.525956)
		(size 0.4064)
		(drill 0.2032)
		(layers "F.Cu" "B.Cu")
		(net "GND")
	)
	(via
		(at 178.289458 -49.800002)
		(size 0.508)
		(drill 0.254)
		(layers "F.Cu" "B.Cu")
		(net "GND")
	)
	(via
		(at 199.8218 -210.510374)
		(size 0.4826)
		(drill 0.254)
		(layers "F.Cu" "B.Cu")
		(net "GND")
	)
	(via
		(at 187.060078 -234.73537)
		(size 0.4826)
		(drill 0.254)
		(layers "F.Cu" "B.Cu")
		(net "GND")
	)
	(via
		(at 177.189638 -210.510374)
		(size 0.4826)
		(drill 0.254)
		(layers "F.Cu" "B.Cu")
		(net "GND")
	)
	(via
		(at 391.504678 -295.145968)
		(size 0.4064)
		(drill 0.2032)
		(layers "F.Cu" "B.Cu")
		(net "GND")
	)
	(via
		(at 262.571992 -421.46601)
		(size 0.508)
		(drill 0.254)
		(layers "F.Cu" "B.Cu")
		(net "GND")
	)
	(via
		(at 106.91114 -293.52621)
		(size 0.4064)
		(drill 0.2032)
		(layers "F.Cu" "B.Cu")
		(net "GND")
	)
	(via
		(at 117.371622 -78.771242)
		(size 0.508)
		(drill 0.254)
		(layers "F.Cu" "B.Cu")
		(net "GND")
	)
	(via
		(at 333.230982 -288.66592)
		(size 0.4064)
		(drill 0.2032)
		(layers "F.Cu" "B.Cu")
		(net "GND")
	)
	(via
		(at 115.247928 -261.323074)
		(size 0.4826)
		(drill 0.254)
		(layers "F.Cu" "B.Cu")
		(net "GND")
	)
	(via
		(at 131.818126 -295.98366)
		(size 0.4064)
		(drill 0.2032)
		(layers "F.Cu" "B.Cu")
		(net "GND")
	)
	(via
		(at 167.372284 -192.218564)
		(size 0.4826)
		(drill 0.254)
		(layers "F.Cu" "B.Cu")
		(net "GND")
	)
	(via
		(at 31.578296 -239.410494)
		(size 0.4826)
		(drill 0.254)
		(layers "F.Cu" "B.Cu")
		(net "GND")
	)
	(via
		(at 369.884706 -287.045908)
		(size 0.4064)
		(drill 0.2032)
		(layers "F.Cu" "B.Cu")
		(net "GND")
	)
	(via
		(at 300.105826 -348.704662)
		(size 0.49022)
		(drill 0.254)
		(layers "F.Cu" "B.Cu")
		(net "GND")
	)
	(via
		(at 9.106408 -174.34814)
		(size 0.508)
		(drill 0.254)
		(layers "F.Cu" "B.Cu")
		(net "GND")
	)
	(via
		(at 310.87187 -346.302076)
		(size 0.49022)
		(drill 0.254)
		(layers "F.Cu" "B.Cu")
		(net "GND")
	)
	(via
		(at 388.714742 -420.952168)
		(size 0.4064)
		(drill 0.2032)
		(layers "F.Cu" "B.Cu")
		(net "GND")
	)
	(via
		(at 90.846148 -388.328662)
		(size 0.4064)
		(drill 0.2032)
		(layers "F.Cu" "B.Cu")
		(net "GND")
	)
	(via
		(at 451.2437 -194.88531)
		(size 0.4826)
		(drill 0.254)
		(layers "F.Cu" "B.Cu")
		(net "GND")
	)
	(via
		(at 283.618432 -313.360054)
		(size 0.4826)
		(drill 0.254)
		(layers "F.Cu" "B.Cu")
		(net "GND")
	)
	(via
		(at 298.871386 -347.282262)
		(size 0.49022)
		(drill 0.254)
		(layers "F.Cu" "B.Cu")
		(net "GND")
	)
	(via
		(at 366.764824 -238.814102)
		(size 0.4064)
		(drill 0.2032)
		(layers "F.Cu" "B.Cu")
		(net "GND")
	)
	(via
		(at 306.77358 -436.120794)
		(size 0.508)
		(drill 0.254)
		(layers "F.Cu" "B.Cu")
		(net "GND")
	)
	(via
		(at 126.676658 -407.638504)
		(size 0.4572)
		(drill 0.254)
		(layers "F.Cu" "B.Cu")
		(net "GND")
	)
	(via
		(at 59.428126 -272.98523)
		(size 0.4826)
		(drill 0.254)
		(layers "F.Cu" "B.Cu")
		(net "GND")
	)
	(via
		(at 387.914896 -223.424242)
		(size 0.4064)
		(drill 0.2032)
		(layers "F.Cu" "B.Cu")
		(net "GND")
	)
	(via
		(at 307.819806 -348.704662)
		(size 0.49022)
		(drill 0.254)
		(layers "F.Cu" "B.Cu")
		(net "GND")
	)
	(via
		(at 198.7042 -222.835216)
		(size 0.4826)
		(drill 0.254)
		(layers "F.Cu" "B.Cu")
		(net "GND")
	)
	(via
		(at 97.040954 -270.03629)
		(size 0.4064)
		(drill 0.2032)
		(layers "F.Cu" "B.Cu")
		(net "GND")
	)
	(via
		(at 228.092 -287.72104)
		(size 0.508)
		(drill 0.254)
		(layers "F.Cu" "B.Cu")
		(net "GND")
	)
	(via
		(at 264.43051 -239.41024)
		(size 0.4826)
		(drill 0.254)
		(layers "F.Cu" "B.Cu")
		(net "GND")
	)
	(via
		(at 36.443412 -365.76)
		(size 0.508)
		(drill 0.254)
		(layers "F.Cu" "B.Cu")
		(net "GND")
	)
	(via
		(at 141.684756 -269.226284)
		(size 0.4064)
		(drill 0.2032)
		(layers "F.Cu" "B.Cu")
		(net "GND")
	)
	(via
		(at 220.36786 -163.17468)
		(size 0.508)
		(drill 0.254)
		(layers "F.Cu" "B.Cu")
		(net "GND")
	)
	(via
		(at 315.855096 -377.41733)
		(size 0.508)
		(drill 0.254)
		(layers "F.Cu" "B.Cu")
		(net "GND")
	)
	(via
		(at 103.791004 -246.914416)
		(size 0.4064)
		(drill 0.2032)
		(layers "F.Cu" "B.Cu")
		(net "GND")
	)
	(via
		(at 304.652426 -278.085042)
		(size 0.4826)
		(drill 0.254)
		(layers "F.Cu" "B.Cu")
		(net "GND")
	)
	(via
		(at 17.608042 -244.085364)
		(size 0.4826)
		(drill 0.254)
		(layers "F.Cu" "B.Cu")
		(net "GND")
	)
	(via
		(at 376.634756 -249.34418)
		(size 0.4064)
		(drill 0.2032)
		(layers "F.Cu" "B.Cu")
		(net "GND")
	)
	(via
		(at 223.759776 -72.732138)
		(size 0.508)
		(drill 0.254)
		(layers "F.Cu" "B.Cu")
		(net "GND")
	)
	(via
		(at 328.102214 -412.212536)
		(size 0.4572)
		(drill 0.254)
		(layers "F.Cu" "B.Cu")
		(net "GND")
	)
	(via
		(at 11.324082 -424.797982)
		(size 0.508)
		(drill 0.254)
		(layers "F.Cu" "B.Cu")
		(net "GND")
	)
	(via
		(at 391.504678 -288.66592)
		(size 0.4064)
		(drill 0.2032)
		(layers "F.Cu" "B.Cu")
		(net "GND")
	)
	(via
		(at 98.451162 -277.326344)
		(size 0.4064)
		(drill 0.2032)
		(layers "F.Cu" "B.Cu")
		(net "GND")
	)
	(via
		(at 214.08771 -28.015184)
		(size 0.508)
		(drill 0.254)
		(layers "F.Cu" "B.Cu")
		(net "GND")
	)
	(via
		(at 184.645808 -164.761418)
		(size 0.508)
		(drill 0.254)
		(layers "F.Cu" "B.Cu")
		(net "GND")
	)
	(via
		(at 57.018174 -335.640172)
		(size 0.508)
		(drill 0.254)
		(layers "F.Cu" "B.Cu")
		(net "GND")
	)
	(via
		(at 428.813722 -422.605708)
		(size 0.508)
		(drill 0.254)
		(layers "F.Cu" "B.Cu")
		(net "GND")
	)
	(via
		(at 117.094 -419.1)
		(size 0.508)
		(drill 0.254)
		(layers "F.Cu" "B.Cu")
		(net "GND")
	)
	(via
		(at 352.9711 -274.086066)
		(size 0.4064)
		(drill 0.2032)
		(layers "F.Cu" "B.Cu")
		(net "GND")
	)
	(via
		(at 368.944906 -274.086066)
		(size 0.4064)
		(drill 0.2032)
		(layers "F.Cu" "B.Cu")
		(net "GND")
	)
	(via
		(at 102.38105 -229.90429)
		(size 0.4064)
		(drill 0.2032)
		(layers "F.Cu" "B.Cu")
		(net "GND")
	)
	(via
		(at 395.038072 -388.917688)
		(size 0.508)
		(drill 0.254)
		(layers "F.Cu" "B.Cu")
		(net "GND")
	)
	(via
		(at 36.795964 -207.535272)
		(size 0.4826)
		(drill 0.254)
		(layers "F.Cu" "B.Cu")
		(net "GND")
	)
	(via
		(at 402.86051 -416.020504)
		(size 0.4572)
		(drill 0.254)
		(layers "F.Cu" "B.Cu")
		(net "GND")
	)
	(via
		(at 50.499772 -237.285276)
		(size 0.4826)
		(drill 0.254)
		(layers "F.Cu" "B.Cu")
		(net "GND")
	)
	(via
		(at 209.944208 -138.077448)
		(size 0.508)
		(drill 0.254)
		(layers "F.Cu" "B.Cu")
		(net "GND")
	)
	(via
		(at 144.034764 -265.176254)
		(size 0.4064)
		(drill 0.2032)
		(layers "F.Cu" "B.Cu")
		(net "GND")
	)
	(via
		(at 367.704878 -224.234248)
		(size 0.4064)
		(drill 0.2032)
		(layers "F.Cu" "B.Cu")
		(net "GND")
	)
	(via
		(at 32.695896 -307.8353)
		(size 0.4826)
		(drill 0.254)
		(layers "F.Cu" "B.Cu")
		(net "GND")
	)
	(via
		(at 304.652426 -212.635084)
		(size 0.4826)
		(drill 0.254)
		(layers "F.Cu" "B.Cu")
		(net "GND")
	)
	(via
		(at 379.551692 -382.34493)
		(size 0.508)
		(drill 0.254)
		(layers "F.Cu" "B.Cu")
		(net "GND")
	)
	(via
		(at 124.464826 -238.814356)
		(size 0.4064)
		(drill 0.2032)
		(layers "F.Cu" "B.Cu")
		(net "GND")
	)
	(via
		(at 325.052944 -261.670038)
		(size 0.4064)
		(drill 0.2032)
		(layers "F.Cu" "B.Cu")
		(net "GND")
	)
	(via
		(at 29.252164 -235.585254)
		(size 0.4826)
		(drill 0.254)
		(layers "F.Cu" "B.Cu")
		(net "GND")
	)
	(via
		(at 173.144434 -193.085212)
		(size 0.4826)
		(drill 0.254)
		(layers "F.Cu" "B.Cu")
		(net "GND")
	)
	(via
		(at 379.554232 -380.54153)
		(size 0.508)
		(drill 0.254)
		(layers "F.Cu" "B.Cu")
		(net "GND")
	)
	(via
		(at 87.145876 -409.396184)
		(size 0.4572)
		(drill 0.254)
		(layers "F.Cu" "B.Cu")
		(net "GND")
	)
	(via
		(at 389.07593 -421.586152)
		(size 0.4572)
		(drill 0.254)
		(layers "F.Cu" "B.Cu")
		(net "GND")
	)
	(via
		(at 166.211504 -386.449062)
		(size 0.4064)
		(drill 0.2032)
		(layers "F.Cu" "B.Cu")
		(net "GND")
	)
	(via
		(at 142.154656 -276.516338)
		(size 0.4064)
		(drill 0.2032)
		(layers "F.Cu" "B.Cu")
		(net "GND")
	)
	(via
		(at 188.444378 -315.485272)
		(size 0.4826)
		(drill 0.254)
		(layers "F.Cu" "B.Cu")
		(net "GND")
	)
	(via
		(at 384.240278 -136.519158)
		(size 0.508)
		(drill 0.254)
		(layers "F.Cu" "B.Cu")
		(net "GND")
	)
	(via
		(at 320.532506 -412.84652)
		(size 0.4064)
		(drill 0.2032)
		(layers "F.Cu" "B.Cu")
		(net "GND")
	)
	(via
		(at 101.74097 -265.176254)
		(size 0.4064)
		(drill 0.2032)
		(layers "F.Cu" "B.Cu")
		(net "GND")
	)
	(via
		(at 301.231808 -109.779308)
		(size 0.508)
		(drill 0.254)
		(layers "F.Cu" "B.Cu")
		(net "GND")
	)
	(via
		(at 227.611178 -319.466468)
		(size 0.508)
		(drill 0.254)
		(layers "F.Cu" "B.Cu")
		(net "GND")
	)
	(via
		(at 411.844236 -400.212814)
		(size 0.4064)
		(drill 0.2032)
		(layers "F.Cu" "B.Cu")
		(net "GND")
	)
	(via
		(at 136.98474 -293.52621)
		(size 0.4064)
		(drill 0.2032)
		(layers "F.Cu" "B.Cu")
		(net "GND")
	)
	(via
		(at 385.739894 -416.020504)
		(size 0.4572)
		(drill 0.254)
		(layers "F.Cu" "B.Cu")
		(net "GND")
	)
	(via
		(at 425.129706 -219.860114)
		(size 0.4826)
		(drill 0.254)
		(layers "F.Cu" "B.Cu")
		(net "GND")
	)
	(via
		(at 126.34976 -435.0512)
		(size 0.4572)
		(drill 0.2032)
		(layers "F.Cu" "B.Cu")
		(net "GND")
	)
	(via
		(at 183.616092 -255.13538)
		(size 0.4826)
		(drill 0.254)
		(layers "F.Cu" "B.Cu")
		(net "GND")
	)
	(via
		(at 238.960914 -317.22568)
		(size 0.508)
		(drill 0.254)
		(layers "F.Cu" "B.Cu")
		(net "GND")
	)
	(via
		(at 345.151202 -229.094284)
		(size 0.4064)
		(drill 0.2032)
		(layers "F.Cu" "B.Cu")
		(net "GND")
	)
	(via
		(at 315.816234 -391.23493)
		(size 0.4064)
		(drill 0.2032)
		(layers "F.Cu" "B.Cu")
		(net "GND")
	)
	(via
		(at 44.541694 -369.69573)
		(size 0.508)
		(drill 0.254)
		(layers "F.Cu" "B.Cu")
		(net "GND")
	)
	(via
		(at 44.340018 -224.535238)
		(size 0.4826)
		(drill 0.254)
		(layers "F.Cu" "B.Cu")
		(net "GND")
	)
	(via
		(at 105.143046 -17.59458)
		(size 0.508)
		(drill 0.254)
		(layers "F.Cu" "B.Cu")
		(net "GND")
	)
	(via
		(at 445.608456 -25.489662)
		(size 0.508)
		(drill 0.254)
		(layers "F.Cu" "B.Cu")
		(net "GND")
	)
	(via
		(at 197.3199 -230.485442)
		(size 0.4826)
		(drill 0.254)
		(layers "F.Cu" "B.Cu")
		(net "GND")
	)
	(via
		(at 198.7042 -288.285428)
		(size 0.4826)
		(drill 0.254)
		(layers "F.Cu" "B.Cu")
		(net "GND")
	)
	(via
		(at 431.55616 -204.134974)
		(size 0.4826)
		(drill 0.254)
		(layers "F.Cu" "B.Cu")
		(net "GND")
	)
	(via
		(at 89.690956 -248.534428)
		(size 0.4064)
		(drill 0.2032)
		(layers "F.Cu" "B.Cu")
		(net "GND")
	)
	(via
		(at 307.368194 -244.934994)
		(size 0.4826)
		(drill 0.254)
		(layers "F.Cu" "B.Cu")
		(net "GND")
	)
	(via
		(at 141.429994 -38.796468)
		(size 0.508)
		(drill 0.254)
		(layers "F.Cu" "B.Cu")
		(net "GND")
	)
	(via
		(at 98.150934 -240.434368)
		(size 0.4064)
		(drill 0.2032)
		(layers "F.Cu" "B.Cu")
		(net "GND")
	)
	(via
		(at 326.351138 -246.914162)
		(size 0.4064)
		(drill 0.2032)
		(layers "F.Cu" "B.Cu")
		(net "GND")
	)
	(via
		(at 59.293252 -150.763224)
		(size 0.508)
		(drill 0.254)
		(layers "F.Cu" "B.Cu")
		(net "GND")
	)
	(via
		(at 266.93241 -306.135024)
		(size 0.4826)
		(drill 0.254)
		(layers "F.Cu" "B.Cu")
		(net "GND")
	)
	(via
		(at 234.055158 -288.200338)
		(size 0.508)
		(drill 0.254)
		(layers "F.Cu" "B.Cu")
		(net "GND")
	)
	(via
		(at 88.580976 -287.856422)
		(size 0.4064)
		(drill 0.2032)
		(layers "F.Cu" "B.Cu")
		(net "GND")
	)
	(via
		(at 85.990176 -384.617722)
		(size 0.4064)
		(drill 0.2032)
		(layers "F.Cu" "B.Cu")
		(net "GND")
	)
	(via
		(at 151.455374 -411.936184)
		(size 0.4572)
		(drill 0.254)
		(layers "F.Cu" "B.Cu")
		(net "GND")
	)
	(via
		(at 335.760314 -419.046152)
		(size 0.4572)
		(drill 0.254)
		(layers "F.Cu" "B.Cu")
		(net "GND")
	)
	(via
		(at 168.527984 -288.285428)
		(size 0.4826)
		(drill 0.254)
		(layers "F.Cu" "B.Cu")
		(net "GND")
	)
	(via
		(at 451.2056 -304.860198)
		(size 0.4826)
		(drill 0.254)
		(layers "F.Cu" "B.Cu")
		(net "GND")
	)
	(via
		(at 32.34817 -362.220256)
		(size 0.508)
		(drill 0.254)
		(layers "F.Cu" "B.Cu")
		(net "GND")
	)
	(via
		(at 131.548378 -17.654778)
		(size 0.508)
		(drill 0.254)
		(layers "F.Cu" "B.Cu")
		(net "GND")
	)
	(via
		(at 76.424536 -413.204152)
		(size 0.4572)
		(drill 0.254)
		(layers "F.Cu" "B.Cu")
		(net "GND")
	)
	(via
		(at 40.23995 -223.685354)
		(size 0.4826)
		(drill 0.254)
		(layers "F.Cu" "B.Cu")
		(net "GND")
	)
	(via
		(at 318.912494 -412.212536)
		(size 0.4572)
		(drill 0.254)
		(layers "F.Cu" "B.Cu")
		(net "GND")
	)
	(via
		(at 344.511122 -262.745982)
		(size 0.4064)
		(drill 0.2032)
		(layers "F.Cu" "B.Cu")
		(net "GND")
	)
	(via
		(at 382.349502 -433.899564)
		(size 0.4572)
		(drill 0.2032)
		(layers "F.Cu" "B.Cu")
		(net "GND")
	)
	(via
		(at 119.12473 -277.326344)
		(size 0.4064)
		(drill 0.2032)
		(layers "F.Cu" "B.Cu")
		(net "GND")
	)
	(via
		(at 328.715624 -74.184764)
		(size 0.508)
		(drill 0.254)
		(layers "F.Cu" "B.Cu")
		(net "GND")
	)
	(via
		(at 95.1611 -279.756362)
		(size 0.4064)
		(drill 0.2032)
		(layers "F.Cu" "B.Cu")
		(net "GND")
	)
	(via
		(at 266.93241 -315.485018)
		(size 0.4826)
		(drill 0.254)
		(layers "F.Cu" "B.Cu")
		(net "GND")
	)
	(via
		(at 419.401498 -330.53909)
		(size 0.508)
		(drill 0.254)
		(layers "F.Cu" "B.Cu")
		(net "GND")
	)
	(via
		(at 280.635964 -249.185176)
		(size 0.4826)
		(drill 0.254)
		(layers "F.Cu" "B.Cu")
		(net "GND")
	)
	(via
		(at 394.377672 -385.999228)
		(size 0.508)
		(drill 0.254)
		(layers "F.Cu" "B.Cu")
		(net "GND")
	)
	(via
		(at 90.249756 -432.451256)
		(size 0.4572)
		(drill 0.2032)
		(layers "F.Cu" "B.Cu")
		(net "GND")
	)
	(via
		(at 121.944638 -278.946356)
		(size 0.4064)
		(drill 0.2032)
		(layers "F.Cu" "B.Cu")
		(net "GND")
	)
	(via
		(at 67.881754 -369.03533)
		(size 0.508)
		(drill 0.254)
		(layers "F.Cu" "B.Cu")
		(net "GND")
	)
	(via
		(at 331.351128 -272.466054)
		(size 0.4064)
		(drill 0.2032)
		(layers "F.Cu" "B.Cu")
		(net "GND")
	)
	(via
		(at 445.100456 -395.306042)
		(size 0.49022)
		(drill 0.254)
		(layers "F.Cu" "B.Cu")
		(net "GND")
	)
	(via
		(at 118.184676 -293.52621)
		(size 0.4064)
		(drill 0.2032)
		(layers "F.Cu" "B.Cu")
		(net "GND")
	)
	(via
		(at 311.563766 -342.811608)
		(size 0.508)
		(drill 0.254)
		(layers "F.Cu" "B.Cu")
		(net "GND")
	)
	(via
		(at 396.375382 -415.38652)
		(size 0.4064)
		(drill 0.2032)
		(layers "F.Cu" "B.Cu")
		(net "GND")
	)
	(via
		(at 317.249556 -433.747164)
		(size 0.4572)
		(drill 0.2032)
		(layers "F.Cu" "B.Cu")
		(net "GND")
	)
	(via
		(at 359.725214 -177.871374)
		(size 0.508)
		(drill 0.254)
		(layers "F.Cu" "B.Cu")
		(net "GND")
	)
	(via
		(at 447.761868 -304.01006)
		(size 0.4826)
		(drill 0.254)
		(layers "F.Cu" "B.Cu")
		(net "GND")
	)
	(via
		(at 2.76225 -261.041134)
		(size 0.508)
		(drill 0.254)
		(layers "F.Cu" "B.Cu")
		(net "GND")
	)
	(via
		(at 393.67079 -416.020504)
		(size 0.4572)
		(drill 0.254)
		(layers "F.Cu" "B.Cu")
		(net "GND")
	)
	(via
		(at 335.487518 -421.586152)
		(size 0.4572)
		(drill 0.254)
		(layers "F.Cu" "B.Cu")
		(net "GND")
	)
	(via
		(at 357.841042 -223.424242)
		(size 0.4064)
		(drill 0.2032)
		(layers "F.Cu" "B.Cu")
		(net "GND")
	)
	(via
		(at 358.61117 -280.566114)
		(size 0.4064)
		(drill 0.2032)
		(layers "F.Cu" "B.Cu")
		(net "GND")
	)
	(via
		(at 103.151178 -274.08632)
		(size 0.4064)
		(drill 0.2032)
		(layers "F.Cu" "B.Cu")
		(net "GND")
	)
	(via
		(at 88.281002 -228.284532)
		(size 0.4064)
		(drill 0.2032)
		(layers "F.Cu" "B.Cu")
		(net "GND")
	)
	(via
		(at 164.103304 -370.83873)
		(size 0.508)
		(drill 0.254)
		(layers "F.Cu" "B.Cu")
		(net "GND")
	)
	(via
		(at 333.230982 -277.32609)
		(size 0.4064)
		(drill 0.2032)
		(layers "F.Cu" "B.Cu")
		(net "GND")
	)
	(via
		(at 144.034764 -274.896326)
		(size 0.4064)
		(drill 0.2032)
		(layers "F.Cu" "B.Cu")
		(net "GND")
	)
	(via
		(at 444.58255 -45.676058)
		(size 0.508)
		(drill 0.254)
		(layers "F.Cu" "B.Cu")
		(net "GND")
	)
	(via
		(at 130.104642 -248.534428)
		(size 0.4064)
		(drill 0.2032)
		(layers "F.Cu" "B.Cu")
		(net "GND")
	)
	(via
		(at 361.124754 -222.614236)
		(size 0.4064)
		(drill 0.2032)
		(layers "F.Cu" "B.Cu")
		(net "GND")
	)
	(via
		(at 326.297798 -421.586152)
		(size 0.4572)
		(drill 0.254)
		(layers "F.Cu" "B.Cu")
		(net "GND")
	)
	(via
		(at 412.367984 -281.485086)
		(size 0.4826)
		(drill 0.254)
		(layers "F.Cu" "B.Cu")
		(net "GND")
	)
	(via
		(at 451.4723 -306.135024)
		(size 0.4826)
		(drill 0.254)
		(layers "F.Cu" "B.Cu")
		(net "GND")
	)
	(via
		(at 81.701132 -231.524302)
		(size 0.4064)
		(drill 0.2032)
		(layers "F.Cu" "B.Cu")
		(net "GND")
	)
	(via
		(at 99.561142 -246.10441)
		(size 0.4064)
		(drill 0.2032)
		(layers "F.Cu" "B.Cu")
		(net "GND")
	)
	(via
		(at 317.46952 -335.561178)
		(size 0.49022)
		(drill 0.254)
		(layers "F.Cu" "B.Cu")
		(net "GND")
	)
	(via
		(at 341.613998 -421.586152)
		(size 0.4572)
		(drill 0.254)
		(layers "F.Cu" "B.Cu")
		(net "GND")
	)
	(via
		(at 122.584718 -243.674392)
		(size 0.4064)
		(drill 0.2032)
		(layers "F.Cu" "B.Cu")
		(net "GND")
	)
	(via
		(at 143.693642 -383.7432)
		(size 0.508)
		(drill 0.254)
		(layers "F.Cu" "B.Cu")
		(net "GND")
	)
	(via
		(at 202.147932 -217.735404)
		(size 0.4826)
		(drill 0.254)
		(layers "F.Cu" "B.Cu")
		(net "GND")
	)
	(via
		(at 332.249526 -429.147224)
		(size 0.4572)
		(drill 0.2032)
		(layers "F.Cu" "B.Cu")
		(net "GND")
	)
	(via
		(at 427.456092 -290.83508)
		(size 0.4826)
		(drill 0.254)
		(layers "F.Cu" "B.Cu")
		(net "GND")
	)
	(via
		(at 56.786272 -403.830536)
		(size 0.4572)
		(drill 0.254)
		(layers "F.Cu" "B.Cu")
		(net "GND")
	)
	(via
		(at 44.340018 -251.735336)
		(size 0.4826)
		(drill 0.254)
		(layers "F.Cu" "B.Cu")
		(net "GND")
	)
	(via
		(at 122.584718 -240.434368)
		(size 0.4064)
		(drill 0.2032)
		(layers "F.Cu" "B.Cu")
		(net "GND")
	)
	(via
		(at 364.638336 -405.52243)
		(size 0.508)
		(drill 0.254)
		(layers "F.Cu" "B.Cu")
		(net "GND")
	)
	(via
		(at 408.1907 -376.75693)
		(size 0.508)
		(drill 0.254)
		(layers "F.Cu" "B.Cu")
		(net "GND")
	)
	(via
		(at 411.777434 -412.212536)
		(size 0.4572)
		(drill 0.254)
		(layers "F.Cu" "B.Cu")
		(net "GND")
	)
	(via
		(at 69.249798 -431.29962)
		(size 0.4572)
		(drill 0.2032)
		(layers "F.Cu" "B.Cu")
		(net "GND")
	)
	(via
		(at 91.871038 -293.52621)
		(size 0.4064)
		(drill 0.2032)
		(layers "F.Cu" "B.Cu")
		(net "GND")
	)
	(via
		(at 365.82477 -243.674138)
		(size 0.4064)
		(drill 0.2032)
		(layers "F.Cu" "B.Cu")
		(net "GND")
	)
	(via
		(at 40.23995 -281.48534)
		(size 0.4826)
		(drill 0.254)
		(layers "F.Cu" "B.Cu")
		(net "GND")
	)
	(via
		(at 381.256032 -376.75693)
		(size 0.508)
		(drill 0.254)
		(layers "F.Cu" "B.Cu")
		(net "GND")
	)
	(via
		(at 132.284724 -267.606272)
		(size 0.4064)
		(drill 0.2032)
		(layers "F.Cu" "B.Cu")
		(net "GND")
	)
	(via
		(at 144.905222 -153.392124)
		(size 0.6604)
		(drill 0.3302)
		(layers "F.Cu" "B.Cu")
		(net "GND")
	)
	(via
		(at 75.367642 -370.83873)
		(size 0.508)
		(drill 0.254)
		(layers "F.Cu" "B.Cu")
		(net "GND")
	)
	(via
		(at 140.444728 -227.474526)
		(size 0.4064)
		(drill 0.2032)
		(layers "F.Cu" "B.Cu")
		(net "GND")
	)
	(via
		(at 471.037666 -50.409094)
		(size 0.508)
		(drill 0.254)
		(layers "F.Cu" "B.Cu")
		(net "GND")
	)
	(via
		(at 334.341216 -242.864132)
		(size 0.4064)
		(drill 0.2032)
		(layers "F.Cu" "B.Cu")
		(net "GND")
	)
	(via
		(at 125.704854 -261.126224)
		(size 0.4064)
		(drill 0.2032)
		(layers "F.Cu" "B.Cu")
		(net "GND")
	)
	(via
		(at 117.884702 -240.434368)
		(size 0.4064)
		(drill 0.2032)
		(layers "F.Cu" "B.Cu")
		(net "GND")
	)
	(via
		(at 381.634746 -276.516084)
		(size 0.4064)
		(drill 0.2032)
		(layers "F.Cu" "B.Cu")
		(net "GND")
	)
	(via
		(at 396.349474 -436.051198)
		(size 0.4572)
		(drill 0.2032)
		(layers "F.Cu" "B.Cu")
		(net "GND")
	)
	(via
		(at 87.15375 -185.920126)
		(size 0.508)
		(drill 0.254)
		(layers "F.Cu" "B.Cu")
		(net "GND")
	)
	(via
		(at 59.816492 -382.85293)
		(size 0.4064)
		(drill 0.2032)
		(layers "F.Cu" "B.Cu")
		(net "GND")
	)
	(via
		(at 43.222418 -210.510374)
		(size 0.4826)
		(drill 0.254)
		(layers "F.Cu" "B.Cu")
		(net "GND")
	)
	(via
		(at 404.644352 -391.23493)
		(size 0.4064)
		(drill 0.2032)
		(layers "F.Cu" "B.Cu")
		(net "GND")
	)
	(via
		(at 376.634756 -247.724168)
		(size 0.4064)
		(drill 0.2032)
		(layers "F.Cu" "B.Cu")
		(net "GND")
	)
	(via
		(at 73.276714 -331.09535)
		(size 0.508)
		(drill 0.254)
		(layers "F.Cu" "B.Cu")
		(net "GND")
	)
	(via
		(at 100.331016 -262.746236)
		(size 0.4064)
		(drill 0.2032)
		(layers "F.Cu" "B.Cu")
		(net "GND")
	)
	(via
		(at 124.218446 -388.328662)
		(size 0.4064)
		(drill 0.2032)
		(layers "F.Cu" "B.Cu")
		(net "GND")
	)
	(via
		(at 137.154666 -236.384338)
		(size 0.4064)
		(drill 0.2032)
		(layers "F.Cu" "B.Cu")
		(net "GND")
	)
	(via
		(at 403.14626 -396.710662)
		(size 0.4064)
		(drill 0.2032)
		(layers "F.Cu" "B.Cu")
		(net "GND")
	)
	(via
		(at 85.460078 -183.59501)
		(size 0.49022)
		(drill 0.254)
		(layers "F.Cu" "B.Cu")
		(net "GND")
	)
	(via
		(at 14.686788 -372.12905)
		(size 0.508)
		(drill 0.254)
		(layers "F.Cu" "B.Cu")
		(net "GND")
	)
	(via
		(at 339.873844 -379.88113)
		(size 0.508)
		(drill 0.254)
		(layers "F.Cu" "B.Cu")
		(net "GND")
	)
	(via
		(at 67.201796 -39.422324)
		(size 0.508)
		(drill 0.254)
		(layers "F.Cu" "B.Cu")
		(net "GND")
	)
	(via
		(at 431.55616 -310.384952)
		(size 0.4826)
		(drill 0.254)
		(layers "F.Cu" "B.Cu")
		(net "GND")
	)
	(via
		(at 116.304822 -285.426404)
		(size 0.4064)
		(drill 0.2032)
		(layers "F.Cu" "B.Cu")
		(net "GND")
	)
	(via
		(at 343.057226 -420.952168)
		(size 0.4064)
		(drill 0.2032)
		(layers "F.Cu" "B.Cu")
		(net "GND")
	)
	(via
		(at 89.05113 -269.226284)
		(size 0.4064)
		(drill 0.2032)
		(layers "F.Cu" "B.Cu")
		(net "GND")
	)
	(via
		(at 115.534694 -233.144314)
		(size 0.4064)
		(drill 0.2032)
		(layers "F.Cu" "B.Cu")
		(net "GND")
	)
	(via
		(at 35.678364 -210.510374)
		(size 0.4826)
		(drill 0.254)
		(layers "F.Cu" "B.Cu")
		(net "GND")
	)
	(via
		(at 51.577494 -33.314132)
		(size 0.508)
		(drill 0.254)
		(layers "F.Cu" "B.Cu")
		(net "GND")
	)
	(via
		(at 317.778384 -394.831062)
		(size 0.4064)
		(drill 0.2032)
		(layers "F.Cu" "B.Cu")
		(net "GND")
	)
	(via
		(at 145.102834 -319.909952)
		(size 0.508)
		(drill 0.254)
		(layers "F.Cu" "B.Cu")
		(net "GND")
	)
	(via
		(at 398.951704 -144.379442)
		(size 0.49022)
		(drill 0.254)
		(layers "F.Cu" "B.Cu")
		(net "GND")
	)
	(via
		(at 102.681024 -271.656302)
		(size 0.4064)
		(drill 0.2032)
		(layers "F.Cu" "B.Cu")
		(net "GND")
	)
	(via
		(at 87.118952 -390.160002)
		(size 0.4064)
		(drill 0.2032)
		(layers "F.Cu" "B.Cu")
		(net "GND")
	)
	(via
		(at 428.573692 -295.510204)
		(size 0.4826)
		(drill 0.254)
		(layers "F.Cu" "B.Cu")
		(net "GND")
	)
	(via
		(at 425.113196 -397.14805)
		(size 0.508)
		(drill 0.254)
		(layers "F.Cu" "B.Cu")
		(net "GND")
	)
	(via
		(at 78.24978 -438.499758)
		(size 0.4572)
		(drill 0.2032)
		(layers "F.Cu" "B.Cu")
		(net "GND")
	)
	(via
		(at 188.444378 -238.135414)
		(size 0.4826)
		(drill 0.254)
		(layers "F.Cu" "B.Cu")
		(net "GND")
	)
	(via
		(at 202.147932 -269.58544)
		(size 0.4826)
		(drill 0.254)
		(layers "F.Cu" "B.Cu")
		(net "GND")
	)
	(via
		(at 276.10181 -344.77706)
		(size 0.49022)
		(drill 0.254)
		(layers "F.Cu" "B.Cu")
		(net "GND")
	)
	(via
		(at 73.361296 -411.936184)
		(size 0.4572)
		(drill 0.254)
		(layers "F.Cu" "B.Cu")
		(net "GND")
	)
	(via
		(at 140.0048 -95.9231)
		(size 0.508)
		(drill 0.254)
		(layers "F.Cu" "B.Cu")
		(net "GND")
	)
	(via
		(at 347.144086 -391.23493)
		(size 0.4064)
		(drill 0.2032)
		(layers "F.Cu" "B.Cu")
		(net "GND")
	)
	(via
		(at 347.048074 -163.078668)
		(size 0.49022)
		(drill 0.254)
		(layers "F.Cu" "B.Cu")
		(net "GND")
	)
	(via
		(at 392.914886 -268.416024)
		(size 0.4064)
		(drill 0.2032)
		(layers "F.Cu" "B.Cu")
		(net "GND")
	)
	(via
		(at 384.240278 -183.615838)
		(size 0.508)
		(drill 0.254)
		(layers "F.Cu" "B.Cu")
		(net "GND")
	)
	(via
		(at 433.06111 -0.762254)
		(size 0.508)
		(drill 0.254)
		(layers "F.Cu" "B.Cu")
		(net "GND")
	)
	(via
		(at 381.804926 -256.634234)
		(size 0.4064)
		(drill 0.2032)
		(layers "F.Cu" "B.Cu")
		(net "GND")
	)
	(via
		(at 364.24489 -272.466054)
		(size 0.4064)
		(drill 0.2032)
		(layers "F.Cu" "B.Cu")
		(net "GND")
	)
	(via
		(at 58.043826 -284.035246)
		(size 0.4826)
		(drill 0.254)
		(layers "F.Cu" "B.Cu")
		(net "GND")
	)
	(via
		(at 367.064798 -282.186126)
		(size 0.4064)
		(drill 0.2032)
		(layers "F.Cu" "B.Cu")
		(net "GND")
	)
	(via
		(at 101.758242 -413.962088)
		(size 0.508)
		(drill 0.254)
		(layers "F.Cu" "B.Cu")
		(net "GND")
	)
	(via
		(at 374.284748 -229.094284)
		(size 0.4064)
		(drill 0.2032)
		(layers "F.Cu" "B.Cu")
		(net "GND")
	)
	(via
		(at 110.76686 -33.529778)
		(size 0.508)
		(drill 0.254)
		(layers "F.Cu" "B.Cu")
		(net "GND")
	)
	(via
		(at 32.695896 -216.035382)
		(size 0.4826)
		(drill 0.254)
		(layers "F.Cu" "B.Cu")
		(net "GND")
	)
	(via
		(at 414.754822 -418.412168)
		(size 0.4064)
		(drill 0.2032)
		(layers "F.Cu" "B.Cu")
		(net "GND")
	)
	(via
		(at 70.298056 -403.830536)
		(size 0.4572)
		(drill 0.254)
		(layers "F.Cu" "B.Cu")
		(net "GND")
	)
	(via
		(at 451.4723 -203.28509)
		(size 0.4826)
		(drill 0.254)
		(layers "F.Cu" "B.Cu")
		(net "GND")
	)
	(via
		(at 88.281002 -226.66452)
		(size 0.4064)
		(drill 0.2032)
		(layers "F.Cu" "B.Cu")
		(net "GND")
	)
	(via
		(at 253.042928 -107.80776)
		(size 0.508)
		(drill 0.254)
		(layers "F.Cu" "B.Cu")
		(net "GND")
	)
	(via
		(at 255.947926 -65.588388)
		(size 0.508)
		(drill 0.254)
		(layers "F.Cu" "B.Cu")
		(net "GND")
	)
	(via
		(at 25.394412 -390.8425)
		(size 0.49022)
		(drill 0.254)
		(layers "F.Cu" "B.Cu")
		(net "GND")
	)
	(via
		(at 195.721732 -314.210446)
		(size 0.4826)
		(drill 0.254)
		(layers "F.Cu" "B.Cu")
		(net "GND")
	)
	(via
		(at 94.861126 -223.424496)
		(size 0.4064)
		(drill 0.2032)
		(layers "F.Cu" "B.Cu")
		(net "GND")
	)
	(via
		(at 158.997904 -369.69573)
		(size 0.508)
		(drill 0.254)
		(layers "F.Cu" "B.Cu")
		(net "GND")
	)
	(via
		(at 346.120466 -420.952168)
		(size 0.4064)
		(drill 0.2032)
		(layers "F.Cu" "B.Cu")
		(net "GND")
	)
	(via
		(at 445.259968 -227.935028)
		(size 0.4826)
		(drill 0.254)
		(layers "F.Cu" "B.Cu")
		(net "GND")
	)
	(via
		(at 346.091002 -251.774198)
		(size 0.4064)
		(drill 0.2032)
		(layers "F.Cu" "B.Cu")
		(net "GND")
	)
	(via
		(at 191.160146 -271.285208)
		(size 0.4826)
		(drill 0.254)
		(layers "F.Cu" "B.Cu")
		(net "GND")
	)
	(via
		(at 452.803768 -237.285022)
		(size 0.4826)
		(drill 0.254)
		(layers "F.Cu" "B.Cu")
		(net "GND")
	)
	(via
		(at 421.296338 -315.485018)
		(size 0.4826)
		(drill 0.254)
		(layers "F.Cu" "B.Cu")
		(net "GND")
	)
	(via
		(at 341.906098 -394.831062)
		(size 0.4064)
		(drill 0.2032)
		(layers "F.Cu" "B.Cu")
		(net "GND")
	)
	(via
		(at 389.833104 -16.979138)
		(size 0.508)
		(drill 0.254)
		(layers "F.Cu" "B.Cu")
		(net "GND")
	)
	(via
		(at 18.992342 -219.435426)
		(size 0.4826)
		(drill 0.254)
		(layers "F.Cu" "B.Cu")
		(net "GND")
	)
	(via
		(at 459.053184 -64.778382)
		(size 0.508)
		(drill 0.254)
		(layers "F.Cu" "B.Cu")
		(net "GND")
	)
	(via
		(at 127.114808 -263.556242)
		(size 0.4064)
		(drill 0.2032)
		(layers "F.Cu" "B.Cu")
		(net "GND")
	)
	(via
		(at 20.80387 -383.209292)
		(size 0.508)
		(drill 0.254)
		(layers "F.Cu" "B.Cu")
		(net "GND")
	)
	(via
		(at 342.343994 -402.309838)
		(size 0.4572)
		(drill 0.254)
		(layers "F.Cu" "B.Cu")
		(net "GND")
	)
	(via
		(at 109.428026 -253.392432)
		(size 0.4064)
		(drill 0.2032)
		(layers "F.Cu" "B.Cu")
		(net "GND")
	)
	(via
		(at 337.931506 -287.045908)
		(size 0.4064)
		(drill 0.2032)
		(layers "F.Cu" "B.Cu")
		(net "GND")
	)
	(via
		(at 126.644654 -265.98626)
		(size 0.4064)
		(drill 0.2032)
		(layers "F.Cu" "B.Cu")
		(net "GND")
	)
	(via
		(at 390.60755 -419.046152)
		(size 0.4572)
		(drill 0.254)
		(layers "F.Cu" "B.Cu")
		(net "GND")
	)
	(via
		(at 411.349698 -438.651396)
		(size 0.4572)
		(drill 0.2032)
		(layers "F.Cu" "B.Cu")
		(net "GND")
	)
	(via
		(at 240.727992 -291.224462)
		(size 0.508)
		(drill 0.254)
		(layers "F.Cu" "B.Cu")
		(net "GND")
	)
	(via
		(at 282.020264 -278.085042)
		(size 0.4826)
		(drill 0.254)
		(layers "F.Cu" "B.Cu")
		(net "GND")
	)
	(via
		(at 378.814838 -271.656048)
		(size 0.4064)
		(drill 0.2032)
		(layers "F.Cu" "B.Cu")
		(net "GND")
	)
	(via
		(at 82.001106 -294.336216)
		(size 0.4064)
		(drill 0.2032)
		(layers "F.Cu" "B.Cu")
		(net "GND")
	)
	(via
		(at 140.274802 -282.996386)
		(size 0.4064)
		(drill 0.2032)
		(layers "F.Cu" "B.Cu")
		(net "GND")
	)
	(via
		(at 85.290914 -269.226284)
		(size 0.4064)
		(drill 0.2032)
		(layers "F.Cu" "B.Cu")
		(net "GND")
	)
	(via
		(at 360.785918 -180.35524)
		(size 0.508)
		(drill 0.254)
		(layers "F.Cu" "B.Cu")
		(net "GND")
	)
	(via
		(at 424.012106 -243.234972)
		(size 0.4826)
		(drill 0.254)
		(layers "F.Cu" "B.Cu")
		(net "GND")
	)
	(via
		(at 324.941184 -225.044254)
		(size 0.4064)
		(drill 0.2032)
		(layers "F.Cu" "B.Cu")
		(net "GND")
	)
	(via
		(at 80.291178 -233.95432)
		(size 0.4064)
		(drill 0.2032)
		(layers "F.Cu" "B.Cu")
		(net "GND")
	)
	(via
		(at 146.096228 -382.908556)
		(size 0.4064)
		(drill 0.2032)
		(layers "F.Cu" "B.Cu")
		(net "GND")
	)
	(via
		(at 133.725666 -158.470346)
		(size 0.49022)
		(drill 0.254)
		(layers "F.Cu" "B.Cu")
		(net "GND")
	)
	(via
		(at 25.152096 -249.18543)
		(size 0.4826)
		(drill 0.254)
		(layers "F.Cu" "B.Cu")
		(net "GND")
	)
	(via
		(at 87.145876 -410.664152)
		(size 0.4572)
		(drill 0.254)
		(layers "F.Cu" "B.Cu")
		(net "GND")
	)
	(via
		(at 72.102472 -411.936184)
		(size 0.4572)
		(drill 0.254)
		(layers "F.Cu" "B.Cu")
		(net "GND")
	)
	(via
		(at 331.266546 -12.542266)
		(size 0.508)
		(drill 0.254)
		(layers "F.Cu" "B.Cu")
		(net "GND")
	)
	(via
		(at 404.119334 -417.778184)
		(size 0.4572)
		(drill 0.254)
		(layers "F.Cu" "B.Cu")
		(net "GND")
	)
	(via
		(at 91.654884 -410.030168)
		(size 0.4064)
		(drill 0.2032)
		(layers "F.Cu" "B.Cu")
		(net "GND")
	)
	(via
		(at 21.463 -365.76)
		(size 0.508)
		(drill 0.254)
		(layers "F.Cu" "B.Cu")
		(net "GND")
	)
	(via
		(at 347.54947 -332.06436)
		(size 0.508)
		(drill 0.254)
		(layers "F.Cu" "B.Cu")
		(net "GND")
	)
	(via
		(at 40.23995 -233.035348)
		(size 0.4826)
		(drill 0.254)
		(layers "F.Cu" "B.Cu")
		(net "GND")
	)
	(via
		(at 157.667706 -407.00452)
		(size 0.4064)
		(drill 0.2032)
		(layers "F.Cu" "B.Cu")
		(net "GND")
	)
	(via
		(at 143.684244 -369.03533)
		(size 0.508)
		(drill 0.254)
		(layers "F.Cu" "B.Cu")
		(net "GND")
	)
	(via
		(at 71.938134 -375.917968)
		(size 0.508)
		(drill 0.254)
		(layers "F.Cu" "B.Cu")
		(net "GND")
	)
	(via
		(at 351.731072 -251.774198)
		(size 0.4064)
		(drill 0.2032)
		(layers "F.Cu" "B.Cu")
		(net "GND")
	)
	(via
		(at 116.878608 -386.449062)
		(size 0.4064)
		(drill 0.2032)
		(layers "F.Cu" "B.Cu")
		(net "GND")
	)
	(via
		(at 169.645584 -313.360308)
		(size 0.4826)
		(drill 0.254)
		(layers "F.Cu" "B.Cu")
		(net "GND")
	)
	(via
		(at 409.349702 -439.651394)
		(size 0.4572)
		(drill 0.2032)
		(layers "F.Cu" "B.Cu")
		(net "GND")
	)
	(via
		(at 387.578092 -377.41733)
		(size 0.508)
		(drill 0.254)
		(layers "F.Cu" "B.Cu")
		(net "GND")
	)
	(via
		(at 347.989906 -392.999722)
		(size 0.4064)
		(drill 0.2032)
		(layers "F.Cu" "B.Cu")
		(net "GND")
	)
	(via
		(at 183.616092 -250.035314)
		(size 0.4826)
		(drill 0.254)
		(layers "F.Cu" "B.Cu")
		(net "GND")
	)
	(via
		(at 364.294674 -178.92141)
		(size 0.49022)
		(drill 0.254)
		(layers "F.Cu" "B.Cu")
		(net "GND")
	)
	(via
		(at 103.145082 -377.132088)
		(size 0.508)
		(drill 0.254)
		(layers "F.Cu" "B.Cu")
		(net "GND")
	)
	(via
		(at 356.261162 -278.136096)
		(size 0.4064)
		(drill 0.2032)
		(layers "F.Cu" "B.Cu")
		(net "GND")
	)
	(via
		(at 138.349736 -431.451258)
		(size 0.4572)
		(drill 0.2032)
		(layers "F.Cu" "B.Cu")
		(net "GND")
	)
	(via
		(at 137.154666 -233.144314)
		(size 0.4064)
		(drill 0.2032)
		(layers "F.Cu" "B.Cu")
		(net "GND")
	)
	(via
		(at 341.691214 -283.806138)
		(size 0.4064)
		(drill 0.2032)
		(layers "F.Cu" "B.Cu")
		(net "GND")
	)
	(via
		(at 52.191412 -406.370536)
		(size 0.4572)
		(drill 0.254)
		(layers "F.Cu" "B.Cu")
		(net "GND")
	)
	(via
		(at 19.844258 -428.589948)
		(size 0.508)
		(drill 0.254)
		(layers "F.Cu" "B.Cu")
		(net "GND")
	)
	(via
		(at 263.451848 -129.77876)
		(size 0.508)
		(drill 0.254)
		(layers "F.Cu" "B.Cu")
		(net "GND")
	)
	(via
		(at 394.982954 -263.29005)
		(size 0.4064)
		(drill 0.2032)
		(layers "F.Cu" "B.Cu")
		(net "GND")
	)
	(via
		(at 121.995946 -410.030168)
		(size 0.4064)
		(drill 0.2032)
		(layers "F.Cu" "B.Cu")
		(net "GND")
	)
	(via
		(at 387.185662 -418.412168)
		(size 0.4064)
		(drill 0.2032)
		(layers "F.Cu" "B.Cu")
		(net "GND")
	)
	(via
		(at 93.751146 -277.326344)
		(size 0.4064)
		(drill 0.2032)
		(layers "F.Cu" "B.Cu")
		(net "GND")
	)
	(via
		(at 273.092164 -236.435138)
		(size 0.4826)
		(drill 0.254)
		(layers "F.Cu" "B.Cu")
		(net "GND")
	)
	(via
		(at 410.157422 -412.84652)
		(size 0.4064)
		(drill 0.2032)
		(layers "F.Cu" "B.Cu")
		(net "GND")
	)
	(via
		(at 90.481912 -403.830536)
		(size 0.4572)
		(drill 0.254)
		(layers "F.Cu" "B.Cu")
		(net "GND")
	)
	(via
		(at 386.349494 -427.851316)
		(size 0.4572)
		(drill 0.2032)
		(layers "F.Cu" "B.Cu")
		(net "GND")
	)
	(via
		(at 164.427916 -206.685388)
		(size 0.4826)
		(drill 0.254)
		(layers "F.Cu" "B.Cu")
		(net "GND")
	)
	(via
		(at 441.26404 -93.505528)
		(size 0.508)
		(drill 0.254)
		(layers "F.Cu" "B.Cu")
		(net "GND")
	)
	(via
		(at 99.090988 -248.534428)
		(size 0.4064)
		(drill 0.2032)
		(layers "F.Cu" "B.Cu")
		(net "GND")
	)
	(via
		(at 265.54811 -199.035162)
		(size 0.4826)
		(drill 0.254)
		(layers "F.Cu" "B.Cu")
		(net "GND")
	)
	(via
		(at 338.101178 -225.044254)
		(size 0.4064)
		(drill 0.2032)
		(layers "F.Cu" "B.Cu")
		(net "GND")
	)
	(via
		(at 328.53122 -262.745982)
		(size 0.4064)
		(drill 0.2032)
		(layers "F.Cu" "B.Cu")
		(net "GND")
	)
	(via
		(at 81.701132 -242.864386)
		(size 0.4064)
		(drill 0.2032)
		(layers "F.Cu" "B.Cu")
		(net "GND")
	)
	(via
		(at 32.174434 -339.812122)
		(size 0.508)
		(drill 0.254)
		(layers "F.Cu" "B.Cu")
		(net "GND")
	)
	(via
		(at 352.823018 -171.44492)
		(size 0.508)
		(drill 0.254)
		(layers "F.Cu" "B.Cu")
		(net "GND")
	)
	(via
		(at 299.72381 -344.77706)
		(size 0.49022)
		(drill 0.254)
		(layers "F.Cu" "B.Cu")
		(net "GND")
	)
	(via
		(at 21.336 -362.204)
		(size 0.508)
		(drill 0.254)
		(layers "F.Cu" "B.Cu")
		(net "GND")
	)
	(via
		(at 442.5442 -283.185108)
		(size 0.4826)
		(drill 0.254)
		(layers "F.Cu" "B.Cu")
		(net "GND")
	)
	(via
		(at 402.12264 -400.15795)
		(size 0.4064)
		(drill 0.2032)
		(layers "F.Cu" "B.Cu")
		(net "GND")
	)
	(via
		(at 304.652426 -231.335072)
		(size 0.4826)
		(drill 0.254)
		(layers "F.Cu" "B.Cu")
		(net "GND")
	)
	(via
		(at 370.82476 -280.566114)
		(size 0.4064)
		(drill 0.2032)
		(layers "F.Cu" "B.Cu")
		(net "GND")
	)
	(via
		(at 298.43984 -274.684998)
		(size 0.4826)
		(drill 0.254)
		(layers "F.Cu" "B.Cu")
		(net "GND")
	)
	(via
		(at 101.440996 -255.824482)
		(size 0.4064)
		(drill 0.2032)
		(layers "F.Cu" "B.Cu")
		(net "GND")
	)
	(via
		(at 333.867506 -420.952168)
		(size 0.4064)
		(drill 0.2032)
		(layers "F.Cu" "B.Cu")
		(net "GND")
	)
	(via
		(at 67.507612 -410.664152)
		(size 0.4572)
		(drill 0.254)
		(layers "F.Cu" "B.Cu")
		(net "GND")
	)
	(via
		(at 60.920122 -180.26761)
		(size 0.508)
		(drill 0.254)
		(layers "F.Cu" "B.Cu")
		(net "GND")
	)
	(via
		(at 450.586602 -426.96511)
		(size 0.508)
		(drill 0.254)
		(layers "F.Cu" "B.Cu")
		(net "GND")
	)
	(via
		(at 351.685352 -337.99526)
		(size 0.49022)
		(drill 0.254)
		(layers "F.Cu" "B.Cu")
		(net "GND")
	)
	(via
		(at 142.403322 -80.691482)
		(size 0.508)
		(drill 0.254)
		(layers "F.Cu" "B.Cu")
		(net "GND")
	)
	(via
		(at 344.389964 -392.999722)
		(size 0.4064)
		(drill 0.2032)
		(layers "F.Cu" "B.Cu")
		(net "GND")
	)
	(via
		(at 384.11658 -400.212814)
		(size 0.4064)
		(drill 0.2032)
		(layers "F.Cu" "B.Cu")
		(net "GND")
	)
	(via
		(at 424.438064 -6.091174)
		(size 0.508)
		(drill 0.254)
		(layers "F.Cu" "B.Cu")
		(net "GND")
	)
	(via
		(at 59.172094 -336.271616)
		(size 0.508)
		(drill 0.254)
		(layers "F.Cu" "B.Cu")
		(net "GND")
	)
	(via
		(at 306.745386 -418.412168)
		(size 0.4064)
		(drill 0.2032)
		(layers "F.Cu" "B.Cu")
		(net "GND")
	)
	(via
		(at 36.795964 -308.685438)
		(size 0.4826)
		(drill 0.254)
		(layers "F.Cu" "B.Cu")
		(net "GND")
	)
	(via
		(at 185.787538 -347.39072)
		(size 0.508)
		(drill 0.254)
		(layers "F.Cu" "B.Cu")
		(net "GND")
	)
	(via
		(at 67.148964 -410.030168)
		(size 0.4064)
		(drill 0.2032)
		(layers "F.Cu" "B.Cu")
		(net "GND")
	)
	(via
		(at 164.427916 -279.785318)
		(size 0.4826)
		(drill 0.254)
		(layers "F.Cu" "B.Cu")
		(net "GND")
	)
	(via
		(at 93.751146 -278.946356)
		(size 0.4064)
		(drill 0.2032)
		(layers "F.Cu" "B.Cu")
		(net "GND")
	)
	(via
		(at 120.618504 -388.328662)
		(size 0.4064)
		(drill 0.2032)
		(layers "F.Cu" "B.Cu")
		(net "GND")
	)
	(via
		(at 119.76481 -224.234502)
		(size 0.4064)
		(drill 0.2032)
		(layers "F.Cu" "B.Cu")
		(net "GND")
	)
	(via
		(at 18.992342 -278.085296)
		(size 0.4826)
		(drill 0.254)
		(layers "F.Cu" "B.Cu")
		(net "GND")
	)
	(via
		(at 403.349714 -433.899564)
		(size 0.4572)
		(drill 0.2032)
		(layers "F.Cu" "B.Cu")
		(net "GND")
	)
	(via
		(at 335.11109 -277.32609)
		(size 0.4064)
		(drill 0.2032)
		(layers "F.Cu" "B.Cu")
		(net "GND")
	)
	(via
		(at 290.514786 -347.282262)
		(size 0.49022)
		(drill 0.254)
		(layers "F.Cu" "B.Cu")
		(net "GND")
	)
	(via
		(at 336.249518 -430.299622)
		(size 0.4572)
		(drill 0.2032)
		(layers "F.Cu" "B.Cu")
		(net "GND")
	)
	(via
		(at 331.051154 -227.474272)
		(size 0.4064)
		(drill 0.2032)
		(layers "F.Cu" "B.Cu")
		(net "GND")
	)
	(via
		(at 422.884092 -167.391334)
		(size 0.49022)
		(drill 0.254)
		(layers "F.Cu" "B.Cu")
		(net "GND")
	)
	(via
		(at 44.70146 -111.2774)
		(size 0.508)
		(drill 0.254)
		(layers "F.Cu" "B.Cu")
		(net "GND")
	)
	(via
		(at 117.22989 -12.542266)
		(size 0.508)
		(drill 0.254)
		(layers "F.Cu" "B.Cu")
		(net "GND")
	)
	(via
		(at 284.736032 -224.534984)
		(size 0.4826)
		(drill 0.254)
		(layers "F.Cu" "B.Cu")
		(net "GND")
	)
	(via
		(at 329.6412 -246.104156)
		(size 0.4064)
		(drill 0.2032)
		(layers "F.Cu" "B.Cu")
		(net "GND")
	)
	(via
		(at 94.744286 -382.85293)
		(size 0.4064)
		(drill 0.2032)
		(layers "F.Cu" "B.Cu")
		(net "GND")
	)
	(via
		(at 107.547918 -253.392432)
		(size 0.4064)
		(drill 0.2032)
		(layers "F.Cu" "B.Cu")
		(net "GND")
	)
	(via
		(at 33.921192 -426.047154)
		(size 0.508)
		(drill 0.254)
		(layers "F.Cu" "B.Cu")
		(net "GND")
	)
	(via
		(at 415.406078 -163.201858)
		(size 0.49022)
		(drill 0.254)
		(layers "F.Cu" "B.Cu")
		(net "GND")
	)
	(via
		(at 427.56582 -387.703568)
		(size 0.508)
		(drill 0.254)
		(layers "F.Cu" "B.Cu")
		(net "GND")
	)
	(via
		(at 47.784004 -250.885198)
		(size 0.4826)
		(drill 0.254)
		(layers "F.Cu" "B.Cu")
		(net "GND")
	)
	(via
		(at 238.67618 -240.072926)
		(size 0.4826)
		(drill 0.254)
		(layers "F.Cu" "B.Cu")
		(net "GND")
	)
	(via
		(at 91.871038 -280.566368)
		(size 0.4064)
		(drill 0.2032)
		(layers "F.Cu" "B.Cu")
		(net "GND")
	)
	(via
		(at 126.814834 -252.584458)
		(size 0.4064)
		(drill 0.2032)
		(layers "F.Cu" "B.Cu")
		(net "GND")
	)
	(via
		(at 299.488606 -347.282262)
		(size 0.49022)
		(drill 0.254)
		(layers "F.Cu" "B.Cu")
		(net "GND")
	)
	(via
		(at 456.131676 -64.444626)
		(size 0.508)
		(drill 0.254)
		(layers "F.Cu" "B.Cu")
		(net "GND")
	)
	(via
		(at 151.044148 -382.85293)
		(size 0.4064)
		(drill 0.2032)
		(layers "F.Cu" "B.Cu")
		(net "GND")
	)
	(via
		(at 9.352788 -372.12905)
		(size 0.508)
		(drill 0.254)
		(layers "F.Cu" "B.Cu")
		(net "GND")
	)
	(via
		(at 343.101168 -266.796012)
		(size 0.4064)
		(drill 0.2032)
		(layers "F.Cu" "B.Cu")
		(net "GND")
	)
	(via
		(at 398.351502 -415.38652)
		(size 0.4064)
		(drill 0.2032)
		(layers "F.Cu" "B.Cu")
		(net "GND")
	)
	(via
		(at 82.374486 -354.736146)
		(size 0.508)
		(drill 0.254)
		(layers "F.Cu" "B.Cu")
		(net "GND")
	)
	(via
		(at 450.088 -199.035162)
		(size 0.4826)
		(drill 0.254)
		(layers "F.Cu" "B.Cu")
		(net "GND")
	)
	(via
		(at 179.516024 -307.8353)
		(size 0.4826)
		(drill 0.254)
		(layers "F.Cu" "B.Cu")
		(net "GND")
	)
	(via
		(at 182.67553 -54.152546)
		(size 0.508)
		(drill 0.254)
		(layers "F.Cu" "B.Cu")
		(net "GND")
	)
	(via
		(at 380.224792 -264.365994)
		(size 0.4064)
		(drill 0.2032)
		(layers "F.Cu" "B.Cu")
		(net "GND")
	)
	(via
		(at 307.368194 -263.634982)
		(size 0.4826)
		(drill 0.254)
		(layers "F.Cu" "B.Cu")
		(net "GND")
	)
	(via
		(at 269.648178 -297.635168)
		(size 0.4826)
		(drill 0.254)
		(layers "F.Cu" "B.Cu")
		(net "GND")
	)
	(via
		(at 350.151192 -265.986006)
		(size 0.4064)
		(drill 0.2032)
		(layers "F.Cu" "B.Cu")
		(net "GND")
	)
	(via
		(at 378.814838 -281.37612)
		(size 0.4064)
		(drill 0.2032)
		(layers "F.Cu" "B.Cu")
		(net "GND")
	)
	(via
		(at 97.612454 -146.671284)
		(size 0.508)
		(drill 0.254)
		(layers "F.Cu" "B.Cu")
		(net "GND")
	)
	(via
		(at 93.959934 -335.595214)
		(size 0.49022)
		(drill 0.254)
		(layers "F.Cu" "B.Cu")
		(net "GND")
	)
	(via
		(at 82.74431 -391.830814)
		(size 0.4064)
		(drill 0.2032)
		(layers "F.Cu" "B.Cu")
		(net "GND")
	)
	(via
		(at 352.031046 -267.606018)
		(size 0.4064)
		(drill 0.2032)
		(layers "F.Cu" "B.Cu")
		(net "GND")
	)
	(via
		(at 373.486934 -417.778184)
		(size 0.4572)
		(drill 0.254)
		(layers "F.Cu" "B.Cu")
		(net "GND")
	)
	(via
		(at 334.8482 -164.846)
		(size 0.508)
		(drill 0.254)
		(layers "F.Cu" "B.Cu")
		(net "GND")
	)
	(via
		(at 269.648178 -318.035178)
		(size 0.4826)
		(drill 0.254)
		(layers "F.Cu" "B.Cu")
		(net "GND")
	)
	(via
		(at 338.249514 -438.499758)
		(size 0.4572)
		(drill 0.2032)
		(layers "F.Cu" "B.Cu")
		(net "GND")
	)
	(via
		(at 346.39123 -288.66592)
		(size 0.4064)
		(drill 0.2032)
		(layers "F.Cu" "B.Cu")
		(net "GND")
	)
	(via
		(at 178.289458 -45.299884)
		(size 0.508)
		(drill 0.254)
		(layers "F.Cu" "B.Cu")
		(net "GND")
	)
	(via
		(at 350.321118 -241.24412)
		(size 0.4064)
		(drill 0.2032)
		(layers "F.Cu" "B.Cu")
		(net "GND")
	)
	(via
		(at 275.807932 -284.034992)
		(size 0.4826)
		(drill 0.254)
		(layers "F.Cu" "B.Cu")
		(net "GND")
	)
	(via
		(at 384.624834 -240.434114)
		(size 0.4064)
		(drill 0.2032)
		(layers "F.Cu" "B.Cu")
		(net "GND")
	)
	(via
		(at 372.316502 -420.952168)
		(size 0.4064)
		(drill 0.2032)
		(layers "F.Cu" "B.Cu")
		(net "GND")
	)
	(via
		(at 128.349756 -438.499758)
		(size 0.4572)
		(drill 0.2032)
		(layers "F.Cu" "B.Cu")
		(net "GND")
	)
	(via
		(at 307.368194 -226.235006)
		(size 0.4826)
		(drill 0.254)
		(layers "F.Cu" "B.Cu")
		(net "GND")
	)
	(via
		(at 35.387534 -347.287088)
		(size 0.49022)
		(drill 0.254)
		(layers "F.Cu" "B.Cu")
		(net "GND")
	)
	(via
		(at 86.871048 -230.71455)
		(size 0.4064)
		(drill 0.2032)
		(layers "F.Cu" "B.Cu")
		(net "GND")
	)
	(via
		(at 318.551306 -420.952168)
		(size 0.4064)
		(drill 0.2032)
		(layers "F.Cu" "B.Cu")
		(net "GND")
	)
	(via
		(at 209.422746 -36.880292)
		(size 0.508)
		(drill 0.254)
		(layers "F.Cu" "B.Cu")
		(net "GND")
	)
	(via
		(at 130.87477 -289.47618)
		(size 0.4064)
		(drill 0.2032)
		(layers "F.Cu" "B.Cu")
		(net "GND")
	)
	(via
		(at 445.259968 -218.585034)
		(size 0.4826)
		(drill 0.254)
		(layers "F.Cu" "B.Cu")
		(net "GND")
	)
	(via
		(at 394.68298 -243.13007)
		(size 0.4064)
		(drill 0.2032)
		(layers "F.Cu" "B.Cu")
		(net "GND")
	)
	(via
		(at 106.596942 -336.695034)
		(size 0.508)
		(drill 0.254)
		(layers "F.Cu" "B.Cu")
		(net "GND")
	)
	(via
		(at 272.264632 -345.86164)
		(size 0.49022)
		(drill 0.254)
		(layers "F.Cu" "B.Cu")
		(net "GND")
	)
	(via
		(at 222.537782 -24.27732)
		(size 0.508)
		(drill 0.254)
		(layers "F.Cu" "B.Cu")
		(net "GND")
	)
	(via
		(at 129.989834 -50.692304)
		(size 0.508)
		(drill 0.254)
		(layers "F.Cu" "B.Cu")
		(net "GND")
	)
	(via
		(at 56.712358 -287.43529)
		(size 0.4826)
		(drill 0.254)
		(layers "F.Cu" "B.Cu")
		(net "GND")
	)
	(via
		(at 367.28019 -29.706062)
		(size 0.508)
		(drill 0.254)
		(layers "F.Cu" "B.Cu")
		(net "GND")
	)
	(via
		(at 135.274812 -246.10441)
		(size 0.4064)
		(drill 0.2032)
		(layers "F.Cu" "B.Cu")
		(net "GND")
	)
	(via
		(at 339.511132 -243.674138)
		(size 0.4064)
		(drill 0.2032)
		(layers "F.Cu" "B.Cu")
		(net "GND")
	)
	(via
		(at 355.321108 -295.955974)
		(size 0.4064)
		(drill 0.2032)
		(layers "F.Cu" "B.Cu")
		(net "GND")
	)
	(via
		(at 386.361432 -380.54153)
		(size 0.508)
		(drill 0.254)
		(layers "F.Cu" "B.Cu")
		(net "GND")
	)
	(via
		(at 383.514854 -266.796012)
		(size 0.4064)
		(drill 0.2032)
		(layers "F.Cu" "B.Cu")
		(net "GND")
	)
	(via
		(at 380.224792 -293.525956)
		(size 0.4064)
		(drill 0.2032)
		(layers "F.Cu" "B.Cu")
		(net "GND")
	)
	(via
		(at 344.981022 -273.27606)
		(size 0.4064)
		(drill 0.2032)
		(layers "F.Cu" "B.Cu")
		(net "GND")
	)
	(via
		(at 258.054094 -140.825728)
		(size 0.508)
		(drill 0.254)
		(layers "F.Cu" "B.Cu")
		(net "GND")
	)
	(via
		(at 156.746194 -388.328662)
		(size 0.4064)
		(drill 0.2032)
		(layers "F.Cu" "B.Cu")
		(net "GND")
	)
	(via
		(at 180.396134 -343.404952)
		(size 0.508)
		(drill 0.254)
		(layers "F.Cu" "B.Cu")
		(net "GND")
	)
	(via
		(at 162.176714 -409.396184)
		(size 0.4572)
		(drill 0.254)
		(layers "F.Cu" "B.Cu")
		(net "GND")
	)
	(via
		(at 391.674858 -250.964192)
		(size 0.4064)
		(drill 0.2032)
		(layers "F.Cu" "B.Cu")
		(net "GND")
	)
	(via
		(at 79.848964 -412.570168)
		(size 0.4064)
		(drill 0.2032)
		(layers "F.Cu" "B.Cu")
		(net "GND")
	)
	(via
		(at 398.215104 -19.771106)
		(size 0.508)
		(drill 0.254)
		(layers "F.Cu" "B.Cu")
		(net "GND")
	)
	(via
		(at 91.897962 -368.37493)
		(size 0.508)
		(drill 0.254)
		(layers "F.Cu" "B.Cu")
		(net "GND")
	)
	(via
		(at 87.801958 -333.039212)
		(size 0.49022)
		(drill 0.254)
		(layers "F.Cu" "B.Cu")
		(net "GND")
	)
	(via
		(at 374.584722 -270.846042)
		(size 0.4064)
		(drill 0.2032)
		(layers "F.Cu" "B.Cu")
		(net "GND")
	)
	(via
		(at 51.348894 -369.69573)
		(size 0.508)
		(drill 0.254)
		(layers "F.Cu" "B.Cu")
		(net "GND")
	)
	(via
		(at 92.17533 -180.687472)
		(size 0.49022)
		(drill 0.254)
		(layers "F.Cu" "B.Cu")
		(net "GND")
	)
	(via
		(at 108.02112 -234.764326)
		(size 0.4064)
		(drill 0.2032)
		(layers "F.Cu" "B.Cu")
		(net "GND")
	)
	(via
		(at 431.55616 -282.33497)
		(size 0.4826)
		(drill 0.254)
		(layers "F.Cu" "B.Cu")
		(net "GND")
	)
	(via
		(at 42.354754 -371.49913)
		(size 0.508)
		(drill 0.254)
		(layers "F.Cu" "B.Cu")
		(net "GND")
	)
	(via
		(at 413.485584 -239.41024)
		(size 0.4826)
		(drill 0.254)
		(layers "F.Cu" "B.Cu")
		(net "GND")
	)
	(via
		(at 19.75866 -136.603232)
		(size 0.508)
		(drill 0.254)
		(layers "F.Cu" "B.Cu")
		(net "GND")
	)
	(via
		(at 455.305668 -304.01006)
		(size 0.4826)
		(drill 0.254)
		(layers "F.Cu" "B.Cu")
		(net "GND")
	)
	(via
		(at 348.271084 -280.566114)
		(size 0.4064)
		(drill 0.2032)
		(layers "F.Cu" "B.Cu")
		(net "GND")
	)
	(via
		(at 269.609824 -103.26624)
		(size 0.508)
		(drill 0.254)
		(layers "F.Cu" "B.Cu")
		(net "GND")
	)
	(via
		(at 95.1611 -261.93623)
		(size 0.4064)
		(drill 0.2032)
		(layers "F.Cu" "B.Cu")
		(net "GND")
	)
	(via
		(at 416.468052 -263.634982)
		(size 0.4826)
		(drill 0.254)
		(layers "F.Cu" "B.Cu")
		(net "GND")
	)
	(via
		(at 25.479502 -5.597398)
		(size 0.508)
		(drill 0.254)
		(layers "F.Cu" "B.Cu")
		(net "GND")
	)
	(via
		(at 282.020264 -238.13516)
		(size 0.4826)
		(drill 0.254)
		(layers "F.Cu" "B.Cu")
		(net "GND")
	)
	(via
		(at 277.192232 -196.485002)
		(size 0.4826)
		(drill 0.254)
		(layers "F.Cu" "B.Cu")
		(net "GND")
	)
	(via
		(at 76.802742 -333.05369)
		(size 0.49022)
		(drill 0.254)
		(layers "F.Cu" "B.Cu")
		(net "GND")
	)
	(via
		(at 302.637952 -23.14575)
		(size 0.508)
		(drill 0.254)
		(layers "F.Cu" "B.Cu")
		(net "GND")
	)
	(via
		(at 129.651506 -404.46452)
		(size 0.4064)
		(drill 0.2032)
		(layers "F.Cu" "B.Cu")
		(net "GND")
	)
	(via
		(at 51.884072 -289.98545)
		(size 0.4826)
		(drill 0.254)
		(layers "F.Cu" "B.Cu")
		(net "GND")
	)
	(via
		(at 393.048236 -9.424924)
		(size 0.508)
		(drill 0.254)
		(layers "F.Cu" "B.Cu")
		(net "GND")
	)
	(via
		(at 149.349714 -433.747164)
		(size 0.4572)
		(drill 0.2032)
		(layers "F.Cu" "B.Cu")
		(net "GND")
	)
	(via
		(at 269.648178 -205.834996)
		(size 0.4826)
		(drill 0.254)
		(layers "F.Cu" "B.Cu")
		(net "GND")
	)
	(via
		(at 378.344938 -293.525956)
		(size 0.4064)
		(drill 0.2032)
		(layers "F.Cu" "B.Cu")
		(net "GND")
	)
	(via
		(at 457.969366 -378.05487)
		(size 0.508)
		(drill 0.254)
		(layers "F.Cu" "B.Cu")
		(net "GND")
	)
	(via
		(at 89.690956 -230.714296)
		(size 0.4064)
		(drill 0.2032)
		(layers "F.Cu" "B.Cu")
		(net "GND")
	)
	(via
		(at 106.405172 -258.38023)
		(size 0.4826)
		(drill 0.254)
		(layers "F.Cu" "B.Cu")
		(net "GND")
	)
	(via
		(at 97.491042 -368.37493)
		(size 0.508)
		(drill 0.254)
		(layers "F.Cu" "B.Cu")
		(net "GND")
	)
	(via
		(at 114.95151 -165.820598)
		(size 0.508)
		(drill 0.254)
		(layers "F.Cu" "B.Cu")
		(net "GND")
	)
	(via
		(at 179.516024 -250.885198)
		(size 0.4826)
		(drill 0.254)
		(layers "F.Cu" "B.Cu")
		(net "GND")
	)
	(via
		(at 413.704024 -149.502114)
		(size 0.508)
		(drill 0.254)
		(layers "F.Cu" "B.Cu")
		(net "GND")
	)
	(via
		(at 84.249768 -436.347362)
		(size 0.4572)
		(drill 0.2032)
		(layers "F.Cu" "B.Cu")
		(net "GND")
	)
	(via
		(at 338.249514 -426.54728)
		(size 0.4572)
		(drill 0.2032)
		(layers "F.Cu" "B.Cu")
		(net "GND")
	)
	(via
		(at 284.736032 -251.735082)
		(size 0.4826)
		(drill 0.254)
		(layers "F.Cu" "B.Cu")
		(net "GND")
	)
	(via
		(at 133.394704 -249.344434)
		(size 0.4064)
		(drill 0.2032)
		(layers "F.Cu" "B.Cu")
		(net "GND")
	)
	(via
		(at 2.76225 -233.101134)
		(size 0.508)
		(drill 0.254)
		(layers "F.Cu" "B.Cu")
		(net "GND")
	)
	(via
		(at 16.972788 -370.60505)
		(size 0.508)
		(drill 0.254)
		(layers "F.Cu" "B.Cu")
		(net "GND")
	)
	(via
		(at 454.188068 -248.335038)
		(size 0.4826)
		(drill 0.254)
		(layers "F.Cu" "B.Cu")
		(net "GND")
	)
	(via
		(at 115.045236 -373.30253)
		(size 0.508)
		(drill 0.254)
		(layers "F.Cu" "B.Cu")
		(net "GND")
	)
	(via
		(at 383.514854 -291.095938)
		(size 0.4064)
		(drill 0.2032)
		(layers "F.Cu" "B.Cu")
		(net "GND")
	)
	(via
		(at 115.834668 -273.276314)
		(size 0.4064)
		(drill 0.2032)
		(layers "F.Cu" "B.Cu")
		(net "GND")
	)
	(via
		(at 176.072038 -263.635236)
		(size 0.4826)
		(drill 0.254)
		(layers "F.Cu" "B.Cu")
		(net "GND")
	)
	(via
		(at 81.292192 -411.936184)
		(size 0.4572)
		(drill 0.254)
		(layers "F.Cu" "B.Cu")
		(net "GND")
	)
	(via
		(at 284.736032 -198.185024)
		(size 0.4826)
		(drill 0.254)
		(layers "F.Cu" "B.Cu")
		(net "GND")
	)
	(via
		(at 59.249818 -426.69968)
		(size 0.4572)
		(drill 0.2032)
		(layers "F.Cu" "B.Cu")
		(net "GND")
	)
	(via
		(at 179.27701 -420.349172)
		(size 0.508)
		(drill 0.254)
		(layers "F.Cu" "B.Cu")
		(net "GND")
	)
	(via
		(at 202.147932 -214.33536)
		(size 0.4826)
		(drill 0.254)
		(layers "F.Cu" "B.Cu")
		(net "GND")
	)
	(via
		(at 304.620676 -437.170322)
		(size 0.508)
		(drill 0.254)
		(layers "F.Cu" "B.Cu")
		(net "GND")
	)
	(via
		(at 135.274812 -226.66452)
		(size 0.4064)
		(drill 0.2032)
		(layers "F.Cu" "B.Cu")
		(net "GND")
	)
	(via
		(at 284.736032 -222.834962)
		(size 0.4826)
		(drill 0.254)
		(layers "F.Cu" "B.Cu")
		(net "GND")
	)
	(via
		(at 36.795964 -233.885232)
		(size 0.4826)
		(drill 0.254)
		(layers "F.Cu" "B.Cu")
		(net "GND")
	)
	(via
		(at 49.168304 -228.78542)
		(size 0.4826)
		(drill 0.254)
		(layers "F.Cu" "B.Cu")
		(net "GND")
	)
	(via
		(at 57.416446 -391.830814)
		(size 0.4064)
		(drill 0.2032)
		(layers "F.Cu" "B.Cu")
		(net "GND")
	)
	(via
		(at 9.568434 -384.864356)
		(size 0.508)
		(drill 0.254)
		(layers "F.Cu" "B.Cu")
		(net "GND")
	)
	(via
		(at 454.188068 -308.685184)
		(size 0.4826)
		(drill 0.254)
		(layers "F.Cu" "B.Cu")
		(net "GND")
	)
	(via
		(at 266.93241 -210.085178)
		(size 0.4826)
		(drill 0.254)
		(layers "F.Cu" "B.Cu")
		(net "GND")
	)
	(via
		(at 109.731048 -267.606272)
		(size 0.4064)
		(drill 0.2032)
		(layers "F.Cu" "B.Cu")
		(net "GND")
	)
	(via
		(at 417.903914 -412.212536)
		(size 0.4572)
		(drill 0.254)
		(layers "F.Cu" "B.Cu")
		(net "GND")
	)
	(via
		(at 232.857802 -246.975122)
		(size 0.508)
		(drill 0.254)
		(layers "F.Cu" "B.Cu")
		(net "GND")
	)
	(via
		(at 121.8184 -388.328662)
		(size 0.4064)
		(drill 0.2032)
		(layers "F.Cu" "B.Cu")
		(net "GND")
	)
	(via
		(at 298.43984 -286.585152)
		(size 0.4826)
		(drill 0.254)
		(layers "F.Cu" "B.Cu")
		(net "GND")
	)
	(via
		(at 70.265798 -387.084062)
		(size 0.508)
		(drill 0.254)
		(layers "F.Cu" "B.Cu")
		(net "GND")
	)
	(via
		(at 324.543928 -62.634876)
		(size 0.508)
		(drill 0.254)
		(layers "F.Cu" "B.Cu")
		(net "GND")
	)
	(via
		(at 74.153014 -328.010012)
		(size 0.508)
		(drill 0.254)
		(layers "F.Cu" "B.Cu")
		(net "GND")
	)
	(via
		(at 197.10654 -350.7105)
		(size 0.508)
		(drill 0.254)
		(layers "F.Cu" "B.Cu")
		(net "GND")
	)
	(via
		(at 283.351732 -237.285022)
		(size 0.4826)
		(drill 0.254)
		(layers "F.Cu" "B.Cu")
		(net "GND")
	)
	(via
		(at 56.786272 -411.936184)
		(size 0.4572)
		(drill 0.254)
		(layers "F.Cu" "B.Cu")
		(net "GND")
	)
	(via
		(at 124.7648 -272.466308)
		(size 0.4064)
		(drill 0.2032)
		(layers "F.Cu" "B.Cu")
		(net "GND")
	)
	(via
		(at 369.114832 -252.584204)
		(size 0.4064)
		(drill 0.2032)
		(layers "F.Cu" "B.Cu")
		(net "GND")
	)
	(via
		(at 9.106408 -168.77792)
		(size 0.508)
		(drill 0.254)
		(layers "F.Cu" "B.Cu")
		(net "GND")
	)
	(via
		(at 20.782788 -372.12905)
		(size 0.508)
		(drill 0.254)
		(layers "F.Cu" "B.Cu")
		(net "GND")
	)
	(via
		(at 379.554232 -379.22073)
		(size 0.508)
		(drill 0.254)
		(layers "F.Cu" "B.Cu")
		(net "GND")
	)
	(via
		(at 308.191154 -416.020504)
		(size 0.4572)
		(drill 0.254)
		(layers "F.Cu" "B.Cu")
		(net "GND")
	)
	(via
		(at 347.708474 -162.28949)
		(size 0.49022)
		(drill 0.254)
		(layers "F.Cu" "B.Cu")
		(net "GND")
	)
	(via
		(at 239.282224 -370.084604)
		(size 0.508)
		(drill 0.254)
		(layers "F.Cu" "B.Cu")
		(net "GND")
	)
	(via
		(at 31.578296 -304.860452)
		(size 0.4826)
		(drill 0.254)
		(layers "F.Cu" "B.Cu")
		(net "GND")
	)
	(via
		(at 384.924808 -264.365994)
		(size 0.4064)
		(drill 0.2032)
		(layers "F.Cu" "B.Cu")
		(net "GND")
	)
	(via
		(at 121.944638 -272.466308)
		(size 0.4064)
		(drill 0.2032)
		(layers "F.Cu" "B.Cu")
		(net "GND")
	)
	(via
		(at 93.491558 -333.87919)
		(size 0.49022)
		(drill 0.254)
		(layers "F.Cu" "B.Cu")
		(net "GND")
	)
	(via
		(at 297.108372 -287.435036)
		(size 0.4826)
		(drill 0.254)
		(layers "F.Cu" "B.Cu")
		(net "GND")
	)
	(via
		(at 91.322906 -183.825896)
		(size 0.49022)
		(drill 0.254)
		(layers "F.Cu" "B.Cu")
		(net "GND")
	)
	(via
		(at 114.59464 -229.90429)
		(size 0.4064)
		(drill 0.2032)
		(layers "F.Cu" "B.Cu")
		(net "GND")
	)
	(via
		(at 345.565984 -334.610202)
		(size 0.49022)
		(drill 0.254)
		(layers "F.Cu" "B.Cu")
		(net "GND")
	)
	(via
		(at 110.371128 -237.194344)
		(size 0.4064)
		(drill 0.2032)
		(layers "F.Cu" "B.Cu")
		(net "GND")
	)
	(via
		(at 350.151192 -282.186126)
		(size 0.4064)
		(drill 0.2032)
		(layers "F.Cu" "B.Cu")
		(net "GND")
	)
	(via
		(at 442.109098 -393.178284)
		(size 0.508)
		(drill 0.254)
		(layers "F.Cu" "B.Cu")
		(net "GND")
	)
	(via
		(at 333.230982 -269.22603)
		(size 0.4064)
		(drill 0.2032)
		(layers "F.Cu" "B.Cu")
		(net "GND")
	)
	(via
		(at 222.875348 -35.44316)
		(size 0.508)
		(drill 0.254)
		(layers "F.Cu" "B.Cu")
		(net "GND")
	)
	(via
		(at 142.154656 -289.47618)
		(size 0.4064)
		(drill 0.2032)
		(layers "F.Cu" "B.Cu")
		(net "GND")
	)
	(via
		(at 93.272356 -406.34666)
		(size 0.4572)
		(drill 0.254)
		(layers "F.Cu" "B.Cu")
		(net "GND")
	)
	(via
		(at 120.70461 -225.854514)
		(size 0.4064)
		(drill 0.2032)
		(layers "F.Cu" "B.Cu")
		(net "GND")
	)
	(via
		(at 118.932706 -407.00452)
		(size 0.4064)
		(drill 0.2032)
		(layers "F.Cu" "B.Cu")
		(net "GND")
	)
	(via
		(at 125.45949 -164.626544)
		(size 0.49022)
		(drill 0.254)
		(layers "F.Cu" "B.Cu")
		(net "GND")
	)
	(via
		(at 418.917882 -363.611414)
		(size 0.508)
		(drill 0.254)
		(layers "F.Cu" "B.Cu")
		(net "GND")
	)
	(via
		(at 397.323818 -318.302132)
		(size 0.508)
		(drill 0.254)
		(layers "F.Cu" "B.Cu")
		(net "GND")
	)
	(via
		(at 439.100214 -216.885012)
		(size 0.4826)
		(drill 0.254)
		(layers "F.Cu" "B.Cu")
		(net "GND")
	)
	(via
		(at 45.658278 -12.37488)
		(size 0.508)
		(drill 0.254)
		(layers "F.Cu" "B.Cu")
		(net "GND")
	)
	(via
		(at 370.524786 -229.094284)
		(size 0.4064)
		(drill 0.2032)
		(layers "F.Cu" "B.Cu")
		(net "GND")
	)
	(via
		(at 187.060078 -290.835334)
		(size 0.4826)
		(drill 0.254)
		(layers "F.Cu" "B.Cu")
		(net "GND")
	)
	(via
		(at 140.66012 -32.29356)
		(size 0.508)
		(drill 0.254)
		(layers "F.Cu" "B.Cu")
		(net "GND")
	)
	(via
		(at 25.016968 -387.704076)
		(size 0.49022)
		(drill 0.254)
		(layers "F.Cu" "B.Cu")
		(net "GND")
	)
	(via
		(at 130.012694 -403.830536)
		(size 0.4572)
		(drill 0.254)
		(layers "F.Cu" "B.Cu")
		(net "GND")
	)
	(via
		(at 18.163794 -366.872266)
		(size 0.508)
		(drill 0.254)
		(layers "F.Cu" "B.Cu")
		(net "GND")
	)
	(via
		(at 161.699956 -130.199638)
		(size 0.508)
		(drill 0.254)
		(layers "F.Cu" "B.Cu")
		(net "GND")
	)
	(via
		(at 109.280706 -401.758404)
		(size 0.508)
		(drill 0.254)
		(layers "F.Cu" "B.Cu")
		(net "GND")
	)
	(via
		(at 388.916418 -391.23493)
		(size 0.4064)
		(drill 0.2032)
		(layers "F.Cu" "B.Cu")
		(net "GND")
	)
	(via
		(at 108.961174 -249.344434)
		(size 0.4064)
		(drill 0.2032)
		(layers "F.Cu" "B.Cu")
		(net "GND")
	)
	(via
		(at 248.689114 -319.466468)
		(size 0.508)
		(drill 0.254)
		(layers "F.Cu" "B.Cu")
		(net "GND")
	)
	(via
		(at 407.819098 -398.542002)
		(size 0.4064)
		(drill 0.2032)
		(layers "F.Cu" "B.Cu")
		(net "GND")
	)
	(via
		(at 32.097218 -16.9799)
		(size 0.508)
		(drill 0.254)
		(layers "F.Cu" "B.Cu")
		(net "GND")
	)
	(via
		(at 152.190704 -368.37493)
		(size 0.508)
		(drill 0.254)
		(layers "F.Cu" "B.Cu")
		(net "GND")
	)
	(via
		(at 135.574786 -284.616398)
		(size 0.4064)
		(drill 0.2032)
		(layers "F.Cu" "B.Cu")
		(net "GND")
	)
	(via
		(at 141.854682 -247.724422)
		(size 0.4064)
		(drill 0.2032)
		(layers "F.Cu" "B.Cu")
		(net "GND")
	)
	(via
		(at 387.914896 -236.384084)
		(size 0.4064)
		(drill 0.2032)
		(layers "F.Cu" "B.Cu")
		(net "GND")
	)
	(via
		(at 414.79978 -19.13636)
		(size 0.508)
		(drill 0.254)
		(layers "F.Cu" "B.Cu")
		(net "GND")
	)
	(via
		(at 320.318384 -396.710662)
		(size 0.4064)
		(drill 0.2032)
		(layers "F.Cu" "B.Cu")
		(net "GND")
	)
	(via
		(at 124.294646 -261.93623)
		(size 0.4064)
		(drill 0.2032)
		(layers "F.Cu" "B.Cu")
		(net "GND")
	)
	(via
		(at 42.091102 -375.793)
		(size 0.508)
		(drill 0.254)
		(layers "F.Cu" "B.Cu")
		(net "GND")
	)
	(via
		(at 91.571064 -245.294404)
		(size 0.4064)
		(drill 0.2032)
		(layers "F.Cu" "B.Cu")
		(net "GND")
	)
	(via
		(at 347.801184 -265.176)
		(size 0.4064)
		(drill 0.2032)
		(layers "F.Cu" "B.Cu")
		(net "GND")
	)
	(via
		(at 10.876788 -372.12905)
		(size 0.508)
		(drill 0.254)
		(layers "F.Cu" "B.Cu")
		(net "GND")
	)
	(via
		(at 117.244622 -265.98626)
		(size 0.4064)
		(drill 0.2032)
		(layers "F.Cu" "B.Cu")
		(net "GND")
	)
	(via
		(at 320.171318 -420.318184)
		(size 0.4572)
		(drill 0.254)
		(layers "F.Cu" "B.Cu")
		(net "GND")
	)
	(via
		(at 407.449274 -170.53306)
		(size 0.49022)
		(drill 0.254)
		(layers "F.Cu" "B.Cu")
		(net "GND")
	)
	(via
		(at 434.221382 -342.54948)
		(size 0.508)
		(drill 0.254)
		(layers "F.Cu" "B.Cu")
		(net "GND")
	)
	(via
		(at 373.845582 -418.412168)
		(size 0.4064)
		(drill 0.2032)
		(layers "F.Cu" "B.Cu")
		(net "GND")
	)
	(via
		(at 131.34467 -269.226284)
		(size 0.4064)
		(drill 0.2032)
		(layers "F.Cu" "B.Cu")
		(net "GND")
	)
	(via
		(at 61.233558 -346.322142)
		(size 0.49022)
		(drill 0.254)
		(layers "F.Cu" "B.Cu")
		(net "GND")
	)
	(via
		(at 464.537806 -412.134812)
		(size 0.508)
		(drill 0.254)
		(layers "F.Cu" "B.Cu")
		(net "GND")
	)
	(via
		(at 96.74098 -236.384338)
		(size 0.4064)
		(drill 0.2032)
		(layers "F.Cu" "B.Cu")
		(net "GND")
	)
	(via
		(at 55.918608 -388.328662)
		(size 0.4064)
		(drill 0.2032)
		(layers "F.Cu" "B.Cu")
		(net "GND")
	)
	(via
		(at 265.179048 -68.239386)
		(size 0.508)
		(drill 0.254)
		(layers "F.Cu" "B.Cu")
		(net "GND")
	)
	(via
		(at 180.900324 -287.43529)
		(size 0.4826)
		(drill 0.254)
		(layers "F.Cu" "B.Cu")
		(net "GND")
	)
	(via
		(at 339.511132 -235.574078)
		(size 0.4064)
		(drill 0.2032)
		(layers "F.Cu" "B.Cu")
		(net "GND")
	)
	(via
		(at 402.86051 -414.752536)
		(size 0.4572)
		(drill 0.254)
		(layers "F.Cu" "B.Cu")
		(net "GND")
	)
	(via
		(at 378.116592 -400.212814)
		(size 0.4064)
		(drill 0.2032)
		(layers "F.Cu" "B.Cu")
		(net "GND")
	)
	(via
		(at 165.812216 -303.585372)
		(size 0.4826)
		(drill 0.254)
		(layers "F.Cu" "B.Cu")
		(net "GND")
	)
	(via
		(at 454.188068 -289.985196)
		(size 0.4826)
		(drill 0.254)
		(layers "F.Cu" "B.Cu")
		(net "GND")
	)
	(via
		(at 184.732168 -116.642642)
		(size 0.4572)
		(drill 0.254)
		(layers "F.Cu" "B.Cu")
		(net "GND")
	)
	(via
		(at 191.911986 -115.842796)
		(size 0.4572)
		(drill 0.254)
		(layers "F.Cu" "B.Cu")
		(net "GND")
	)
	(via
		(at 122.442986 -404.46452)
		(size 0.4064)
		(drill 0.2032)
		(layers "F.Cu" "B.Cu")
		(net "GND")
	)
	(via
		(at 110.671102 -270.846296)
		(size 0.4064)
		(drill 0.2032)
		(layers "F.Cu" "B.Cu")
		(net "GND")
	)
	(via
		(at 333.867506 -412.84652)
		(size 0.4064)
		(drill 0.2032)
		(layers "F.Cu" "B.Cu")
		(net "GND")
	)
	(via
		(at 339.993986 -420.952168)
		(size 0.4064)
		(drill 0.2032)
		(layers "F.Cu" "B.Cu")
		(net "GND")
	)
	(via
		(at 388.384796 -235.574078)
		(size 0.4064)
		(drill 0.2032)
		(layers "F.Cu" "B.Cu")
		(net "GND")
	)
	(via
		(at 381.804926 -246.914162)
		(size 0.4064)
		(drill 0.2032)
		(layers "F.Cu" "B.Cu")
		(net "GND")
	)
	(via
		(at 299.82414 -207.535018)
		(size 0.4826)
		(drill 0.254)
		(layers "F.Cu" "B.Cu")
		(net "GND")
	)
	(via
		(at 116.18214 -258.795266)
		(size 0.4826)
		(drill 0.254)
		(layers "F.Cu" "B.Cu")
		(net "GND")
	)
	(via
		(at 102.85095 -246.914416)
		(size 0.4064)
		(drill 0.2032)
		(layers "F.Cu" "B.Cu")
		(net "GND")
	)
	(via
		(at 283.72181 -345.566238)
		(size 0.49022)
		(drill 0.254)
		(layers "F.Cu" "B.Cu")
		(net "GND")
	)
	(via
		(at 82.374486 -354.101146)
		(size 0.508)
		(drill 0.254)
		(layers "F.Cu" "B.Cu")
		(net "GND")
	)
	(via
		(at 94.488 -213.451948)
		(size 0.508)
		(drill 0.254)
		(layers "F.Cu" "B.Cu")
		(net "GND")
	)
	(via
		(at 381.638048 -295.983406)
		(size 0.4064)
		(drill 0.2032)
		(layers "F.Cu" "B.Cu")
		(net "GND")
	)
	(via
		(at 266.93241 -303.585118)
		(size 0.4826)
		(drill 0.254)
		(layers "F.Cu" "B.Cu")
		(net "GND")
	)
	(via
		(at 300.190662 -396.679674)
		(size 0.508)
		(drill 0.254)
		(layers "F.Cu" "B.Cu")
		(net "GND")
	)
	(via
		(at 372.234714 -282.996132)
		(size 0.4064)
		(drill 0.2032)
		(layers "F.Cu" "B.Cu")
		(net "GND")
	)
	(via
		(at 446.016126 -63.887096)
		(size 0.508)
		(drill 0.254)
		(layers "F.Cu" "B.Cu")
		(net "GND")
	)
	(via
		(at 439.100214 -198.185024)
		(size 0.4826)
		(drill 0.254)
		(layers "F.Cu" "B.Cu")
		(net "GND")
	)
	(via
		(at 124.464826 -245.294404)
		(size 0.4064)
		(drill 0.2032)
		(layers "F.Cu" "B.Cu")
		(net "GND")
	)
	(via
		(at 27.867864 -284.035246)
		(size 0.4826)
		(drill 0.254)
		(layers "F.Cu" "B.Cu")
		(net "GND")
	)
	(via
		(at 328.231246 -255.014222)
		(size 0.4064)
		(drill 0.2032)
		(layers "F.Cu" "B.Cu")
		(net "GND")
	)
	(via
		(at 410.381958 -164.715952)
		(size 0.508)
		(drill 0.254)
		(layers "F.Cu" "B.Cu")
		(net "GND")
	)
	(via
		(at 354.34397 -391.23493)
		(size 0.4064)
		(drill 0.2032)
		(layers "F.Cu" "B.Cu")
		(net "GND")
	)
	(via
		(at 155.349702 -427.851316)
		(size 0.4572)
		(drill 0.2032)
		(layers "F.Cu" "B.Cu")
		(net "GND")
	)
	(via
		(at 315.576966 -113.60277)
		(size 0.508)
		(drill 0.254)
		(layers "F.Cu" "B.Cu")
		(net "GND")
	)
	(via
		(at 187.060078 -318.885316)
		(size 0.4826)
		(drill 0.254)
		(layers "F.Cu" "B.Cu")
		(net "GND")
	)
	(via
		(at 429.604678 -428.858172)
		(size 0.508)
		(drill 0.254)
		(layers "F.Cu" "B.Cu")
		(net "GND")
	)
	(via
		(at 413.752284 -228.785166)
		(size 0.4826)
		(drill 0.254)
		(layers "F.Cu" "B.Cu")
		(net "GND")
	)
	(via
		(at 125.0442 -30.832806)
		(size 0.508)
		(drill 0.254)
		(layers "F.Cu" "B.Cu")
		(net "GND")
	)
	(via
		(at 378.814838 -286.236156)
		(size 0.4064)
		(drill 0.2032)
		(layers "F.Cu" "B.Cu")
		(net "GND")
	)
	(via
		(at 118.184676 -285.426404)
		(size 0.4064)
		(drill 0.2032)
		(layers "F.Cu" "B.Cu")
		(net "GND")
	)
	(via
		(at 22.186138 -18.247106)
		(size 0.508)
		(drill 0.254)
		(layers "F.Cu" "B.Cu")
		(net "GND")
	)
	(via
		(at 124.294646 -284.616398)
		(size 0.4064)
		(drill 0.2032)
		(layers "F.Cu" "B.Cu")
		(net "GND")
	)
	(via
		(at 460.267812 -405.56815)
		(size 0.508)
		(drill 0.254)
		(layers "F.Cu" "B.Cu")
		(net "GND")
	)
	(via
		(at 29.079444 -5.597398)
		(size 0.508)
		(drill 0.254)
		(layers "F.Cu" "B.Cu")
		(net "GND")
	)
	(via
		(at 388.68477 -265.986006)
		(size 0.4064)
		(drill 0.2032)
		(layers "F.Cu" "B.Cu")
		(net "GND")
	)
	(via
		(at 393.602972 -398.719802)
		(size 0.508)
		(drill 0.254)
		(layers "F.Cu" "B.Cu")
		(net "GND")
	)
	(via
		(at 120.571514 -77.742542)
		(size 0.508)
		(drill 0.254)
		(layers "F.Cu" "B.Cu")
		(net "GND")
	)
	(via
		(at 412.367984 -272.135092)
		(size 0.4826)
		(drill 0.254)
		(layers "F.Cu" "B.Cu")
		(net "GND")
	)
	(via
		(at 338.318856 -398.542002)
		(size 0.4064)
		(drill 0.2032)
		(layers "F.Cu" "B.Cu")
		(net "GND")
	)
	(via
		(at 155.691586 -410.030168)
		(size 0.4064)
		(drill 0.2032)
		(layers "F.Cu" "B.Cu")
		(net "GND")
	)
	(via
		(at 431.55616 -233.884978)
		(size 0.4826)
		(drill 0.254)
		(layers "F.Cu" "B.Cu")
		(net "GND")
	)
	(via
		(at 385.094734 -236.384084)
		(size 0.4064)
		(drill 0.2032)
		(layers "F.Cu" "B.Cu")
		(net "GND")
	)
	(via
		(at 288.180018 -249.185176)
		(size 0.4826)
		(drill 0.254)
		(layers "F.Cu" "B.Cu")
		(net "GND")
	)
	(via
		(at 78.04277 -419.0365)
		(size 0.508)
		(drill 0.254)
		(layers "F.Cu" "B.Cu")
		(net "GND")
	)
	(via
		(at 130.516376 -393.927838)
		(size 0.4572)
		(drill 0.254)
		(layers "F.Cu" "B.Cu")
		(net "GND")
	)
	(via
		(at 367.153952 -379.22073)
		(size 0.508)
		(drill 0.254)
		(layers "F.Cu" "B.Cu")
		(net "GND")
	)
	(via
		(at 419.912038 -216.035128)
		(size 0.4826)
		(drill 0.254)
		(layers "F.Cu" "B.Cu")
		(net "GND")
	)
	(via
		(at 47.945294 -373.30253)
		(size 0.508)
		(drill 0.254)
		(layers "F.Cu" "B.Cu")
		(net "GND")
	)
	(via
		(at 388.384796 -255.014222)
		(size 0.4064)
		(drill 0.2032)
		(layers "F.Cu" "B.Cu")
		(net "GND")
	)
	(via
		(at 216.943432 -23.172928)
		(size 0.508)
		(drill 0.254)
		(layers "F.Cu" "B.Cu")
		(net "GND")
	)
	(via
		(at 274.476464 -275.535136)
		(size 0.4826)
		(drill 0.254)
		(layers "F.Cu" "B.Cu")
		(net "GND")
	)
	(via
		(at 190.999872 -356.462584)
		(size 0.508)
		(drill 0.254)
		(layers "F.Cu" "B.Cu")
		(net "GND")
	)
	(via
		(at 275.44141 -344.77706)
		(size 0.49022)
		(drill 0.254)
		(layers "F.Cu" "B.Cu")
		(net "GND")
	)
	(via
		(at 311.791096 -398.542002)
		(size 0.4064)
		(drill 0.2032)
		(layers "F.Cu" "B.Cu")
		(net "GND")
	)
	(via
		(at 157.044136 -391.830814)
		(size 0.4064)
		(drill 0.2032)
		(layers "F.Cu" "B.Cu")
		(net "GND")
	)
	(via
		(at 415.006282 -394.831062)
		(size 0.4064)
		(drill 0.2032)
		(layers "F.Cu" "B.Cu")
		(net "GND")
	)
	(via
		(at 194.604132 -245.785386)
		(size 0.4826)
		(drill 0.254)
		(layers "F.Cu" "B.Cu")
		(net "GND")
	)
	(via
		(at 242.796314 -316.46368)
		(size 0.508)
		(drill 0.254)
		(layers "F.Cu" "B.Cu")
		(net "GND")
	)
	(via
		(at 342.249506 -438.499758)
		(size 0.4572)
		(drill 0.2032)
		(layers "F.Cu" "B.Cu")
		(net "GND")
	)
	(via
		(at 143.349726 -436.347362)
		(size 0.4572)
		(drill 0.2032)
		(layers "F.Cu" "B.Cu")
		(net "GND")
	)
	(via
		(at 189.94501 -349.381572)
		(size 0.49022)
		(drill 0.254)
		(layers "F.Cu" "B.Cu")
		(net "GND")
	)
	(via
		(at 326.651112 -282.186126)
		(size 0.4064)
		(drill 0.2032)
		(layers "F.Cu" "B.Cu")
		(net "GND")
	)
	(via
		(at 202.147932 -307.8353)
		(size 0.4826)
		(drill 0.254)
		(layers "F.Cu" "B.Cu")
		(net "GND")
	)
	(via
		(at 191.160146 -207.535272)
		(size 0.4826)
		(drill 0.254)
		(layers "F.Cu" "B.Cu")
		(net "GND")
	)
	(via
		(at 169.645584 -201.16038)
		(size 0.4826)
		(drill 0.254)
		(layers "F.Cu" "B.Cu")
		(net "GND")
	)
	(via
		(at 361.033568 -411.913324)
		(size 0.508)
		(drill 0.254)
		(layers "F.Cu" "B.Cu")
		(net "GND")
	)
	(via
		(at 25.152096 -292.535356)
		(size 0.4826)
		(drill 0.254)
		(layers "F.Cu" "B.Cu")
		(net "GND")
	)
	(via
		(at 195.988432 -303.585372)
		(size 0.4826)
		(drill 0.254)
		(layers "F.Cu" "B.Cu")
		(net "GND")
	)
	(via
		(at 95.54591 -186.597798)
		(size 0.508)
		(drill 0.254)
		(layers "F.Cu" "B.Cu")
		(net "GND")
	)
	(via
		(at 297.108372 -306.135024)
		(size 0.4826)
		(drill 0.254)
		(layers "F.Cu" "B.Cu")
		(net "GND")
	)
	(via
		(at 55.328058 -279.785318)
		(size 0.4826)
		(drill 0.254)
		(layers "F.Cu" "B.Cu")
		(net "GND")
	)
	(via
		(at 430.553876 -18.247868)
		(size 0.508)
		(drill 0.254)
		(layers "F.Cu" "B.Cu")
		(net "GND")
	)
	(via
		(at 288.180018 -300.185074)
		(size 0.4826)
		(drill 0.254)
		(layers "F.Cu" "B.Cu")
		(net "GND")
	)
	(via
		(at 16.837406 -76.544678)
		(size 0.508)
		(drill 0.254)
		(layers "F.Cu" "B.Cu")
		(net "GND")
	)
	(via
		(at 58.668158 -12.37488)
		(size 0.508)
		(drill 0.254)
		(layers "F.Cu" "B.Cu")
		(net "GND")
	)
	(via
		(at 422.627806 -218.585034)
		(size 0.4826)
		(drill 0.254)
		(layers "F.Cu" "B.Cu")
		(net "GND")
	)
	(via
		(at 108.790994 -291.906198)
		(size 0.4064)
		(drill 0.2032)
		(layers "F.Cu" "B.Cu")
		(net "GND")
	)
	(via
		(at 244.853714 -316.46368)
		(size 0.508)
		(drill 0.254)
		(layers "F.Cu" "B.Cu")
		(net "GND")
	)
	(via
		(at 30.877002 -6.091174)
		(size 0.508)
		(drill 0.254)
		(layers "F.Cu" "B.Cu")
		(net "GND")
	)
	(via
		(at 288.180018 -269.585186)
		(size 0.4826)
		(drill 0.254)
		(layers "F.Cu" "B.Cu")
		(net "GND")
	)
	(via
		(at 454.188068 -255.135126)
		(size 0.4826)
		(drill 0.254)
		(layers "F.Cu" "B.Cu")
		(net "GND")
	)
	(via
		(at 348.911164 -243.674138)
		(size 0.4064)
		(drill 0.2032)
		(layers "F.Cu" "B.Cu")
		(net "GND")
	)
	(via
		(at 80.591152 -291.906198)
		(size 0.4064)
		(drill 0.2032)
		(layers "F.Cu" "B.Cu")
		(net "GND")
	)
	(via
		(at 48.855376 -413.204152)
		(size 0.4572)
		(drill 0.254)
		(layers "F.Cu" "B.Cu")
		(net "GND")
	)
	(via
		(at 12.863068 -395.592554)
		(size 0.508)
		(drill 0.254)
		(layers "F.Cu" "B.Cu")
		(net "GND")
	)
	(via
		(at 280.635964 -252.584966)
		(size 0.4826)
		(drill 0.254)
		(layers "F.Cu" "B.Cu")
		(net "GND")
	)
	(via
		(at 82.940906 -294.336216)
		(size 0.4064)
		(drill 0.2032)
		(layers "F.Cu" "B.Cu")
		(net "GND")
	)
	(via
		(at 444.672974 -413.1945)
		(size 0.508)
		(drill 0.254)
		(layers "F.Cu" "B.Cu")
		(net "GND")
	)
	(via
		(at 61.022484 -407.00452)
		(size 0.4064)
		(drill 0.2032)
		(layers "F.Cu" "B.Cu")
		(net "GND")
	)
	(via
		(at 48.855376 -405.098504)
		(size 0.4572)
		(drill 0.254)
		(layers "F.Cu" "B.Cu")
		(net "GND")
	)
	(via
		(at 427.456092 -289.135058)
		(size 0.4826)
		(drill 0.254)
		(layers "F.Cu" "B.Cu")
		(net "GND")
	)
	(via
		(at 171.97197 -290.835334)
		(size 0.4826)
		(drill 0.254)
		(layers "F.Cu" "B.Cu")
		(net "GND")
	)
	(via
		(at 124.7648 -280.566368)
		(size 0.4064)
		(drill 0.2032)
		(layers "F.Cu" "B.Cu")
		(net "GND")
	)
	(via
		(at 188.444378 -210.085432)
		(size 0.4826)
		(drill 0.254)
		(layers "F.Cu" "B.Cu")
		(net "GND")
	)
	(via
		(at 111.578136 -264.862564)
		(size 0.4826)
		(drill 0.254)
		(layers "F.Cu" "B.Cu")
		(net "GND")
	)
	(via
		(at 17.608042 -264.485374)
		(size 0.4826)
		(drill 0.254)
		(layers "F.Cu" "B.Cu")
		(net "GND")
	)
	(via
		(at 364.24489 -278.946102)
		(size 0.4064)
		(drill 0.2032)
		(layers "F.Cu" "B.Cu")
		(net "GND")
	)
	(via
		(at 49.168304 -200.735438)
		(size 0.4826)
		(drill 0.254)
		(layers "F.Cu" "B.Cu")
		(net "GND")
	)
	(via
		(at 406.012142 -420.952168)
		(size 0.4064)
		(drill 0.2032)
		(layers "F.Cu" "B.Cu")
		(net "GND")
	)
	(via
		(at 361.380278 -183.793638)
		(size 0.508)
		(drill 0.254)
		(layers "F.Cu" "B.Cu")
		(net "GND")
	)
	(via
		(at 329.297792 -390.92632)
		(size 0.508)
		(drill 0.254)
		(layers "F.Cu" "B.Cu")
		(net "GND")
	)
	(via
		(at 334.341216 -241.24412)
		(size 0.4064)
		(drill 0.2032)
		(layers "F.Cu" "B.Cu")
		(net "GND")
	)
	(via
		(at 350.291654 -360.329734)
		(size 0.508)
		(drill 0.254)
		(layers "F.Cu" "B.Cu")
		(net "GND")
	)
	(via
		(at 160.2486 -30.20568)
		(size 0.508)
		(drill 0.254)
		(layers "F.Cu" "B.Cu")
		(net "GND")
	)
	(via
		(at 27.867864 -286.585406)
		(size 0.4826)
		(drill 0.254)
		(layers "F.Cu" "B.Cu")
		(net "GND")
	)
	(via
		(at 22.8981 -333.89824)
		(size 0.508)
		(drill 0.254)
		(layers "F.Cu" "B.Cu")
		(net "GND")
	)
	(via
		(at 76.424536 -403.830536)
		(size 0.4572)
		(drill 0.254)
		(layers "F.Cu" "B.Cu")
		(net "GND")
	)
	(via
		(at 390.094724 -274.896072)
		(size 0.4064)
		(drill 0.2032)
		(layers "F.Cu" "B.Cu")
		(net "GND")
	)
	(via
		(at 378.514864 -225.044254)
		(size 0.4064)
		(drill 0.2032)
		(layers "F.Cu" "B.Cu")
		(net "GND")
	)
	(via
		(at 295.724072 -255.135126)
		(size 0.4826)
		(drill 0.254)
		(layers "F.Cu" "B.Cu")
		(net "GND")
	)
	(via
		(at 188.177678 -239.410494)
		(size 0.4826)
		(drill 0.254)
		(layers "F.Cu" "B.Cu")
		(net "GND")
	)
	(via
		(at 436.384446 -212.635084)
		(size 0.4826)
		(drill 0.254)
		(layers "F.Cu" "B.Cu")
		(net "GND")
	)
	(via
		(at 132.924804 -224.234502)
		(size 0.4064)
		(drill 0.2032)
		(layers "F.Cu" "B.Cu")
		(net "GND")
	)
	(via
		(at 385.394708 -281.37612)
		(size 0.4064)
		(drill 0.2032)
		(layers "F.Cu" "B.Cu")
		(net "GND")
	)
	(via
		(at 187.060078 -264.485374)
		(size 0.4826)
		(drill 0.254)
		(layers "F.Cu" "B.Cu")
		(net "GND")
	)
	(via
		(at 72.825864 -10.16508)
		(size 0.508)
		(drill 0.254)
		(layers "F.Cu" "B.Cu")
		(net "GND")
	)
	(via
		(at 138.864848 -267.606272)
		(size 0.4064)
		(drill 0.2032)
		(layers "F.Cu" "B.Cu")
		(net "GND")
	)
	(via
		(at 344.249502 -430.299622)
		(size 0.4572)
		(drill 0.2032)
		(layers "F.Cu" "B.Cu")
		(net "GND")
	)
	(via
		(at 394.377672 -387.218428)
		(size 0.508)
		(drill 0.254)
		(layers "F.Cu" "B.Cu")
		(net "GND")
	)
	(via
		(at 354.851208 -280.566114)
		(size 0.4064)
		(drill 0.2032)
		(layers "F.Cu" "B.Cu")
		(net "GND")
	)
	(via
		(at 83.685634 -328.111612)
		(size 0.508)
		(drill 0.254)
		(layers "F.Cu" "B.Cu")
		(net "GND")
	)
	(via
		(at 440.217814 -219.860114)
		(size 0.4826)
		(drill 0.254)
		(layers "F.Cu" "B.Cu")
		(net "GND")
	)
	(via
		(at 97.040954 -287.856422)
		(size 0.4064)
		(drill 0.2032)
		(layers "F.Cu" "B.Cu")
		(net "GND")
	)
	(via
		(at 386.804916 -267.606018)
		(size 0.4064)
		(drill 0.2032)
		(layers "F.Cu" "B.Cu")
		(net "GND")
	)
	(via
		(at 166.245032 -438.912)
		(size 0.508)
		(drill 0.254)
		(layers "F.Cu" "B.Cu")
		(net "GND")
	)
	(via
		(at 350.621092 -274.896072)
		(size 0.4064)
		(drill 0.2032)
		(layers "F.Cu" "B.Cu")
		(net "GND")
	)
	(via
		(at 49.658016 -417.921186)
		(size 0.508)
		(drill 0.254)
		(layers "F.Cu" "B.Cu")
		(net "GND")
	)
	(via
		(at 43.247564 -341.525352)
		(size 0.6604)
		(drill 0.3302)
		(layers "F.Cu" "B.Cu")
		(net "GND")
	)
	(via
		(at 324.75297 -236.650022)
		(size 0.4064)
		(drill 0.2032)
		(layers "F.Cu" "B.Cu")
		(net "GND")
	)
	(via
		(at 128.994662 -289.47618)
		(size 0.4064)
		(drill 0.2032)
		(layers "F.Cu" "B.Cu")
		(net "GND")
	)
	(via
		(at 157.349698 -437.34736)
		(size 0.4572)
		(drill 0.2032)
		(layers "F.Cu" "B.Cu")
		(net "GND")
	)
	(via
		(at 140.349732 -436.051198)
		(size 0.4572)
		(drill 0.2032)
		(layers "F.Cu" "B.Cu")
		(net "GND")
	)
	(via
		(at 437.715914 -305.28514)
		(size 0.4826)
		(drill 0.254)
		(layers "F.Cu" "B.Cu")
		(net "GND")
	)
	(via
		(at 428.573692 -276.810216)
		(size 0.4826)
		(drill 0.254)
		(layers "F.Cu" "B.Cu")
		(net "GND")
	)
	(via
		(at 370.69649 -420.318184)
		(size 0.4572)
		(drill 0.254)
		(layers "F.Cu" "B.Cu")
		(net "GND")
	)
	(via
		(at 141.854682 -236.384338)
		(size 0.4064)
		(drill 0.2032)
		(layers "F.Cu" "B.Cu")
		(net "GND")
	)
	(via
		(at 32.960056 -403.498304)
		(size 0.508)
		(drill 0.254)
		(layers "F.Cu" "B.Cu")
		(net "GND")
	)
	(via
		(at 432.084734 -162.981132)
		(size 0.508)
		(drill 0.254)
		(layers "F.Cu" "B.Cu")
		(net "GND")
	)
	(via
		(at 467.5378 -401.371054)
		(size 0.508)
		(drill 0.254)
		(layers "F.Cu" "B.Cu")
		(net "GND")
	)
	(via
		(at 88.281002 -255.824482)
		(size 0.4064)
		(drill 0.2032)
		(layers "F.Cu" "B.Cu")
		(net "GND")
	)
	(via
		(at 425.73194 -98.850958)
		(size 0.6604)
		(drill 0.3302)
		(layers "F.Cu" "B.Cu")
		(net "GND")
	)
	(via
		(at 306.250594 -201.160126)
		(size 0.4826)
		(drill 0.254)
		(layers "F.Cu" "B.Cu")
		(net "GND")
	)
	(via
		(at 40.258238 -12.37488)
		(size 0.508)
		(drill 0.254)
		(layers "F.Cu" "B.Cu")
		(net "GND")
	)
	(via
		(at 346.208858 -419.046152)
		(size 0.4572)
		(drill 0.254)
		(layers "F.Cu" "B.Cu")
		(net "GND")
	)
	(via
		(at 136.34974 -439.651394)
		(size 0.4572)
		(drill 0.2032)
		(layers "F.Cu" "B.Cu")
		(net "GND")
	)
	(via
		(at 427.456092 -298.485052)
		(size 0.4826)
		(drill 0.254)
		(layers "F.Cu" "B.Cu")
		(net "GND")
	)
	(via
		(at 18.992342 -296.785284)
		(size 0.4826)
		(drill 0.254)
		(layers "F.Cu" "B.Cu")
		(net "GND")
	)
	(via
		(at 213.665562 -345.789504)
		(size 0.508)
		(drill 0.254)
		(layers "F.Cu" "B.Cu")
		(net "GND")
	)
	(via
		(at 51.346354 -371.49913)
		(size 0.508)
		(drill 0.254)
		(layers "F.Cu" "B.Cu")
		(net "GND")
	)
	(via
		(at 91.571064 -242.05438)
		(size 0.4064)
		(drill 0.2032)
		(layers "F.Cu" "B.Cu")
		(net "GND")
	)
	(via
		(at 387.274816 -294.335962)
		(size 0.4064)
		(drill 0.2032)
		(layers "F.Cu" "B.Cu")
		(net "GND")
	)
	(via
		(at 47.235364 -412.570168)
		(size 0.4064)
		(drill 0.2032)
		(layers "F.Cu" "B.Cu")
		(net "GND")
	)
	(via
		(at 171.97197 -317.185294)
		(size 0.4826)
		(drill 0.254)
		(layers "F.Cu" "B.Cu")
		(net "GND")
	)
	(via
		(at 444.329566 -422.390824)
		(size 0.508)
		(drill 0.254)
		(layers "F.Cu" "B.Cu")
		(net "GND")
	)
	(via
		(at 265.4554 -108.472986)
		(size 0.508)
		(drill 0.254)
		(layers "F.Cu" "B.Cu")
		(net "GND")
	)
	(via
		(at 386.349494 -433.899564)
		(size 0.4572)
		(drill 0.2032)
		(layers "F.Cu" "B.Cu")
		(net "GND")
	)
	(via
		(at 436.852822 -408.01036)
		(size 0.508)
		(drill 0.254)
		(layers "F.Cu" "B.Cu")
		(net "GND")
	)
	(via
		(at 114.264694 -385.87553)
		(size 0.4064)
		(drill 0.2032)
		(layers "F.Cu" "B.Cu")
		(net "GND")
	)
	(via
		(at 340.921086 -250.964192)
		(size 0.4064)
		(drill 0.2032)
		(layers "F.Cu" "B.Cu")
		(net "GND")
	)
	(via
		(at 377.995942 -418.412168)
		(size 0.4064)
		(drill 0.2032)
		(layers "F.Cu" "B.Cu")
		(net "GND")
	)
	(via
		(at 176.072038 -278.935434)
		(size 0.4826)
		(drill 0.254)
		(layers "F.Cu" "B.Cu")
		(net "GND")
	)
	(via
		(at 307.062124 -392.999722)
		(size 0.4064)
		(drill 0.2032)
		(layers "F.Cu" "B.Cu")
		(net "GND")
	)
	(via
		(at 164.427916 -311.235344)
		(size 0.4826)
		(drill 0.254)
		(layers "F.Cu" "B.Cu")
		(net "GND")
	)
	(via
		(at 325.052944 -282.730194)
		(size 0.4064)
		(drill 0.2032)
		(layers "F.Cu" "B.Cu")
		(net "GND")
	)
	(via
		(at 39.12235 -295.510458)
		(size 0.4826)
		(drill 0.254)
		(layers "F.Cu" "B.Cu")
		(net "GND")
	)
	(via
		(at 174.037498 -346.9894)
		(size 0.508)
		(drill 0.254)
		(layers "F.Cu" "B.Cu")
		(net "GND")
	)
	(via
		(at 284.736032 -204.134974)
		(size 0.4826)
		(drill 0.254)
		(layers "F.Cu" "B.Cu")
		(net "GND")
	)
	(via
		(at 44.545758 -345.571064)
		(size 0.49022)
		(drill 0.254)
		(layers "F.Cu" "B.Cu")
		(net "GND")
	)
	(via
		(at 356.77221 -257.744976)
		(size 0.4826)
		(drill 0.254)
		(layers "F.Cu" "B.Cu")
		(net "GND")
	)
	(via
		(at 394.68298 -238.270034)
		(size 0.4064)
		(drill 0.2032)
		(layers "F.Cu" "B.Cu")
		(net "GND")
	)
	(via
		(at 314.406026 -412.84652)
		(size 0.4064)
		(drill 0.2032)
		(layers "F.Cu" "B.Cu")
		(net "GND")
	)
	(via
		(at 40.409114 -343.476834)
		(size 0.508)
		(drill 0.254)
		(layers "F.Cu" "B.Cu")
		(net "GND")
	)
	(via
		(at 326.651112 -265.986006)
		(size 0.4064)
		(drill 0.2032)
		(layers "F.Cu" "B.Cu")
		(net "GND")
	)
	(via
		(at 31.578296 -276.81047)
		(size 0.4826)
		(drill 0.254)
		(layers "F.Cu" "B.Cu")
		(net "GND")
	)
	(via
		(at 363.944916 -237.19409)
		(size 0.4064)
		(drill 0.2032)
		(layers "F.Cu" "B.Cu")
		(net "GND")
	)
	(via
		(at 185.039 -135.600948)
		(size 0.508)
		(drill 0.254)
		(layers "F.Cu" "B.Cu")
		(net "GND")
	)
	(via
		(at 341.428324 -333.085186)
		(size 0.49022)
		(drill 0.254)
		(layers "F.Cu" "B.Cu")
		(net "GND")
	)
	(via
		(at 390.094724 -282.996132)
		(size 0.4064)
		(drill 0.2032)
		(layers "F.Cu" "B.Cu")
		(net "GND")
	)
	(via
		(at 353.61118 -246.914162)
		(size 0.4064)
		(drill 0.2032)
		(layers "F.Cu" "B.Cu")
		(net "GND")
	)
	(via
		(at 338.58708 -331.068934)
		(size 0.508)
		(drill 0.254)
		(layers "F.Cu" "B.Cu")
		(net "GND")
	)
	(via
		(at 71.723758 -333.060802)
		(size 0.49022)
		(drill 0.254)
		(layers "F.Cu" "B.Cu")
		(net "GND")
	)
	(via
		(at 448.665346 -63.083694)
		(size 0.508)
		(drill 0.254)
		(layers "F.Cu" "B.Cu")
		(net "GND")
	)
	(via
		(at 193.254122 -6.042152)
		(size 0.508)
		(drill 0.254)
		(layers "F.Cu" "B.Cu")
		(net "GND")
	)
	(via
		(at 363.944916 -232.334054)
		(size 0.4064)
		(drill 0.2032)
		(layers "F.Cu" "B.Cu")
		(net "GND")
	)
	(via
		(at 107.85094 -282.18638)
		(size 0.4064)
		(drill 0.2032)
		(layers "F.Cu" "B.Cu")
		(net "GND")
	)
	(via
		(at 89.367106 -184.615074)
		(size 0.49022)
		(drill 0.254)
		(layers "F.Cu" "B.Cu")
		(net "GND")
	)
	(via
		(at 117.704108 -58.41238)
		(size 0.508)
		(drill 0.254)
		(layers "F.Cu" "B.Cu")
		(net "GND")
	)
	(via
		(at 424.757342 -360.824018)
		(size 0.508)
		(drill 0.254)
		(layers "F.Cu" "B.Cu")
		(net "GND")
	)
	(via
		(at 331.821028 -270.036036)
		(size 0.4064)
		(drill 0.2032)
		(layers "F.Cu" "B.Cu")
		(net "GND")
	)
	(via
		(at 179.516024 -273.835368)
		(size 0.4826)
		(drill 0.254)
		(layers "F.Cu" "B.Cu")
		(net "GND")
	)
	(via
		(at 187.060078 -262.785352)
		(size 0.4826)
		(drill 0.254)
		(layers "F.Cu" "B.Cu")
		(net "GND")
	)
	(via
		(at 334.249522 -430.147222)
		(size 0.4572)
		(drill 0.2032)
		(layers "F.Cu" "B.Cu")
		(net "GND")
	)
	(via
		(at 420.862252 -167.391334)
		(size 0.49022)
		(drill 0.254)
		(layers "F.Cu" "B.Cu")
		(net "GND")
	)
	(via
		(at 331.821028 -261.935976)
		(size 0.4064)
		(drill 0.2032)
		(layers "F.Cu" "B.Cu")
		(net "GND")
	)
	(via
		(at 300.065694 -392.1252)
		(size 0.508)
		(drill 0.254)
		(layers "F.Cu" "B.Cu")
		(net "GND")
	)
	(via
		(at 58.043826 -211.7852)
		(size 0.4826)
		(drill 0.254)
		(layers "F.Cu" "B.Cu")
		(net "GND")
	)
	(via
		(at 265.54811 -214.335106)
		(size 0.4826)
		(drill 0.254)
		(layers "F.Cu" "B.Cu")
		(net "GND")
	)
	(via
		(at 324.766178 -419.046152)
		(size 0.4572)
		(drill 0.254)
		(layers "F.Cu" "B.Cu")
		(net "GND")
	)
	(via
		(at 421.777414 -432.876198)
		(size 0.508)
		(drill 0.254)
		(layers "F.Cu" "B.Cu")
		(net "GND")
	)
	(via
		(at 303.276 -363.982)
		(size 0.508)
		(drill 0.254)
		(layers "F.Cu" "B.Cu")
		(net "GND")
	)
	(via
		(at 383.21488 -244.484144)
		(size 0.4064)
		(drill 0.2032)
		(layers "F.Cu" "B.Cu")
		(net "GND")
	)
	(via
		(at 366.124744 -285.42615)
		(size 0.4064)
		(drill 0.2032)
		(layers "F.Cu" "B.Cu")
		(net "GND")
	)
	(via
		(at 84.99094 -230.714296)
		(size 0.4064)
		(drill 0.2032)
		(layers "F.Cu" "B.Cu")
		(net "GND")
	)
	(via
		(at 83.41106 -269.226284)
		(size 0.4064)
		(drill 0.2032)
		(layers "F.Cu" "B.Cu")
		(net "GND")
	)
	(via
		(at 20.114768 -4.963414)
		(size 0.508)
		(drill 0.254)
		(layers "F.Cu" "B.Cu")
		(net "GND")
	)
	(via
		(at 104.82961 -64.55791)
		(size 0.508)
		(drill 0.254)
		(layers "F.Cu" "B.Cu")
		(net "GND")
	)
	(via
		(at 183.616092 -291.685218)
		(size 0.4826)
		(drill 0.254)
		(layers "F.Cu" "B.Cu")
		(net "GND")
	)
	(via
		(at 336.521044 -274.896072)
		(size 0.4064)
		(drill 0.2032)
		(layers "F.Cu" "B.Cu")
		(net "GND")
	)
	(via
		(at 335.281016 -249.34418)
		(size 0.4064)
		(drill 0.2032)
		(layers "F.Cu" "B.Cu")
		(net "GND")
	)
	(via
		(at 82.531204 -177.602134)
		(size 0.508)
		(drill 0.254)
		(layers "F.Cu" "B.Cu")
		(net "GND")
	)
	(via
		(at 80.591152 -272.466308)
		(size 0.4064)
		(drill 0.2032)
		(layers "F.Cu" "B.Cu")
		(net "GND")
	)
	(via
		(at 115.364768 -293.52621)
		(size 0.4064)
		(drill 0.2032)
		(layers "F.Cu" "B.Cu")
		(net "GND")
	)
	(via
		(at 47.37862 -386.449062)
		(size 0.4064)
		(drill 0.2032)
		(layers "F.Cu" "B.Cu")
		(net "GND")
	)
	(via
		(at 129.739898 -410.664152)
		(size 0.4572)
		(drill 0.254)
		(layers "F.Cu" "B.Cu")
		(net "GND")
	)
	(via
		(at 419.912038 -283.185108)
		(size 0.4826)
		(drill 0.254)
		(layers "F.Cu" "B.Cu")
		(net "GND")
	)
	(via
		(at 144.034764 -271.656302)
		(size 0.4064)
		(drill 0.2032)
		(layers "F.Cu" "B.Cu")
		(net "GND")
	)
	(via
		(at 372.704868 -274.086066)
		(size 0.4064)
		(drill 0.2032)
		(layers "F.Cu" "B.Cu")
		(net "GND")
	)
	(via
		(at 402.31441 -5.597398)
		(size 0.508)
		(drill 0.254)
		(layers "F.Cu" "B.Cu")
		(net "GND")
	)
	(via
		(at 18.828258 -428.589948)
		(size 0.508)
		(drill 0.254)
		(layers "F.Cu" "B.Cu")
		(net "GND")
	)
	(via
		(at 335.11109 -295.145968)
		(size 0.4064)
		(drill 0.2032)
		(layers "F.Cu" "B.Cu")
		(net "GND")
	)
	(via
		(at 283.351732 -286.585152)
		(size 0.4826)
		(drill 0.254)
		(layers "F.Cu" "B.Cu")
		(net "GND")
	)
	(via
		(at 78.24978 -434.899562)
		(size 0.4572)
		(drill 0.2032)
		(layers "F.Cu" "B.Cu")
		(net "GND")
	)
	(via
		(at 280.635964 -262.785098)
		(size 0.4826)
		(drill 0.254)
		(layers "F.Cu" "B.Cu")
		(net "GND")
	)
	(via
		(at 110.671102 -288.666174)
		(size 0.4064)
		(drill 0.2032)
		(layers "F.Cu" "B.Cu")
		(net "GND")
	)
	(via
		(at 23.622 -363.347)
		(size 0.508)
		(drill 0.254)
		(layers "F.Cu" "B.Cu")
		(net "GND")
	)
	(via
		(at 15.98422 -71.847964)
		(size 0.508)
		(drill 0.254)
		(layers "F.Cu" "B.Cu")
		(net "GND")
	)
	(via
		(at 458.390752 -392.651234)
		(size 0.508)
		(drill 0.254)
		(layers "F.Cu" "B.Cu")
		(net "GND")
	)
	(via
		(at 413.303974 -367.796064)
		(size 0.508)
		(drill 0.254)
		(layers "F.Cu" "B.Cu")
		(net "GND")
	)
	(via
		(at 303.268126 -269.585186)
		(size 0.4826)
		(drill 0.254)
		(layers "F.Cu" "B.Cu")
		(net "GND")
	)
	(via
		(at 386.516372 -391.23493)
		(size 0.4064)
		(drill 0.2032)
		(layers "F.Cu" "B.Cu")
		(net "GND")
	)
	(via
		(at 28.134564 -294.66032)
		(size 0.4826)
		(drill 0.254)
		(layers "F.Cu" "B.Cu")
		(net "GND")
	)
	(via
		(at 114.696494 -411.936184)
		(size 0.4572)
		(drill 0.254)
		(layers "F.Cu" "B.Cu")
		(net "GND")
	)
	(via
		(at 59.249818 -425.547282)
		(size 0.4572)
		(drill 0.2032)
		(layers "F.Cu" "B.Cu")
		(net "GND")
	)
	(via
		(at 284.736032 -265.335004)
		(size 0.4826)
		(drill 0.254)
		(layers "F.Cu" "B.Cu")
		(net "GND")
	)
	(via
		(at 352.031046 -295.145968)
		(size 0.4064)
		(drill 0.2032)
		(layers "F.Cu" "B.Cu")
		(net "GND")
	)
	(via
		(at 371.678454 -394.831062)
		(size 0.4064)
		(drill 0.2032)
		(layers "F.Cu" "B.Cu")
		(net "GND")
	)
	(via
		(at 428.573692 -286.16021)
		(size 0.4826)
		(drill 0.254)
		(layers "F.Cu" "B.Cu")
		(net "GND")
	)
	(via
		(at 378.344938 -288.66592)
		(size 0.4064)
		(drill 0.2032)
		(layers "F.Cu" "B.Cu")
		(net "GND")
	)
	(via
		(at 76.785724 -412.570168)
		(size 0.4064)
		(drill 0.2032)
		(layers "F.Cu" "B.Cu")
		(net "GND")
	)
	(via
		(at 82.001106 -282.996386)
		(size 0.4064)
		(drill 0.2032)
		(layers "F.Cu" "B.Cu")
		(net "GND")
	)
	(via
		(at 345.621102 -249.34418)
		(size 0.4064)
		(drill 0.2032)
		(layers "F.Cu" "B.Cu")
		(net "GND")
	)
	(via
		(at 337.689444 -379.88113)
		(size 0.508)
		(drill 0.254)
		(layers "F.Cu" "B.Cu")
		(net "GND")
	)
	(via
		(at 327.829418 -419.046152)
		(size 0.4572)
		(drill 0.254)
		(layers "F.Cu" "B.Cu")
		(net "GND")
	)
	(via
		(at 340.921086 -225.044254)
		(size 0.4064)
		(drill 0.2032)
		(layers "F.Cu" "B.Cu")
		(net "GND")
	)
	(via
		(at 307.368194 -243.234972)
		(size 0.4826)
		(drill 0.254)
		(layers "F.Cu" "B.Cu")
		(net "GND")
	)
	(via
		(at 436.917592 -5.81914)
		(size 0.508)
		(drill 0.254)
		(layers "F.Cu" "B.Cu")
		(net "GND")
	)
	(via
		(at 344.211148 -242.054126)
		(size 0.4064)
		(drill 0.2032)
		(layers "F.Cu" "B.Cu")
		(net "GND")
	)
	(via
		(at 8.428736 -132.91439)
		(size 0.508)
		(drill 0.254)
		(layers "F.Cu" "B.Cu")
		(net "GND")
	)
	(via
		(at 367.234724 -250.964192)
		(size 0.4064)
		(drill 0.2032)
		(layers "F.Cu" "B.Cu")
		(net "GND")
	)
	(via
		(at 336.22107 -241.24412)
		(size 0.4064)
		(drill 0.2032)
		(layers "F.Cu" "B.Cu")
		(net "GND")
	)
	(via
		(at 188.444378 -275.53539)
		(size 0.4826)
		(drill 0.254)
		(layers "F.Cu" "B.Cu")
		(net "GND")
	)
	(via
		(at 376.93473 -268.416024)
		(size 0.4064)
		(drill 0.2032)
		(layers "F.Cu" "B.Cu")
		(net "GND")
	)
	(via
		(at 32.948372 -9.424924)
		(size 0.508)
		(drill 0.254)
		(layers "F.Cu" "B.Cu")
		(net "GND")
	)
	(via
		(at 277.192232 -291.684964)
		(size 0.4826)
		(drill 0.254)
		(layers "F.Cu" "B.Cu")
		(net "GND")
	)
	(via
		(at 15.570708 -401.319238)
		(size 0.508)
		(drill 0.254)
		(layers "F.Cu" "B.Cu")
		(net "GND")
	)
	(via
		(at 120.908826 -407.00452)
		(size 0.4064)
		(drill 0.2032)
		(layers "F.Cu" "B.Cu")
		(net "GND")
	)
	(via
		(at 186.932316 -330.211684)
		(size 0.508)
		(drill 0.254)
		(layers "F.Cu" "B.Cu")
		(net "GND")
	)
	(via
		(at 363.304836 -267.606018)
		(size 0.4064)
		(drill 0.2032)
		(layers "F.Cu" "B.Cu")
		(net "GND")
	)
	(via
		(at 59.249818 -427.851316)
		(size 0.4572)
		(drill 0.2032)
		(layers "F.Cu" "B.Cu")
		(net "GND")
	)
	(via
		(at 405.068024 -18.503138)
		(size 0.508)
		(drill 0.254)
		(layers "F.Cu" "B.Cu")
		(net "GND")
	)
	(via
		(at 450.088 -225.385122)
		(size 0.4826)
		(drill 0.254)
		(layers "F.Cu" "B.Cu")
		(net "GND")
	)
	(via
		(at 307.368194 -278.93518)
		(size 0.4826)
		(drill 0.254)
		(layers "F.Cu" "B.Cu")
		(net "GND")
	)
	(via
		(at 203.303632 -192.218564)
		(size 0.4826)
		(drill 0.254)
		(layers "F.Cu" "B.Cu")
		(net "GND")
	)
	(via
		(at 174.687738 -314.635388)
		(size 0.4826)
		(drill 0.254)
		(layers "F.Cu" "B.Cu")
		(net "GND")
	)
	(via
		(at 88.580976 -271.656302)
		(size 0.4064)
		(drill 0.2032)
		(layers "F.Cu" "B.Cu")
		(net "GND")
	)
	(via
		(at 379.924818 -253.39421)
		(size 0.4064)
		(drill 0.2032)
		(layers "F.Cu" "B.Cu")
		(net "GND")
	)
	(via
		(at 162.22853 -350.077278)
		(size 0.508)
		(drill 0.254)
		(layers "F.Cu" "B.Cu")
		(net "GND")
	)
	(via
		(at 86.863174 -335.544414)
		(size 0.49022)
		(drill 0.254)
		(layers "F.Cu" "B.Cu")
		(net "GND")
	)
	(via
		(at 35.640264 -192.218564)
		(size 0.4826)
		(drill 0.254)
		(layers "F.Cu" "B.Cu")
		(net "GND")
	)
	(via
		(at 80.591152 -283.806392)
		(size 0.4064)
		(drill 0.2032)
		(layers "F.Cu" "B.Cu")
		(net "GND")
	)
	(via
		(at 363.944916 -248.534174)
		(size 0.4064)
		(drill 0.2032)
		(layers "F.Cu" "B.Cu")
		(net "GND")
	)
	(via
		(at 183.610504 -409.281122)
		(size 0.508)
		(drill 0.254)
		(layers "F.Cu" "B.Cu")
		(net "GND")
	)
	(via
		(at 388.060692 -379.88113)
		(size 0.508)
		(drill 0.254)
		(layers "F.Cu" "B.Cu")
		(net "GND")
	)
	(via
		(at 351.685352 -338.784438)
		(size 0.49022)
		(drill 0.254)
		(layers "F.Cu" "B.Cu")
		(net "GND")
	)
	(via
		(at 371.93474 -242.864132)
		(size 0.4064)
		(drill 0.2032)
		(layers "F.Cu" "B.Cu")
		(net "GND")
	)
	(via
		(at 409.391104 -19.771106)
		(size 0.508)
		(drill 0.254)
		(layers "F.Cu" "B.Cu")
		(net "GND")
	)
	(via
		(at 144.20469 -250.15444)
		(size 0.4064)
		(drill 0.2032)
		(layers "F.Cu" "B.Cu")
		(net "GND")
	)
	(via
		(at 375.524776 -275.706078)
		(size 0.4064)
		(drill 0.2032)
		(layers "F.Cu" "B.Cu")
		(net "GND")
	)
	(via
		(at 421.361616 -343.272618)
		(size 0.508)
		(drill 0.254)
		(layers "F.Cu" "B.Cu")
		(net "GND")
	)
	(via
		(at 97.511108 -274.08632)
		(size 0.4064)
		(drill 0.2032)
		(layers "F.Cu" "B.Cu")
		(net "GND")
	)
	(via
		(at 340.24951 -433.899564)
		(size 0.4572)
		(drill 0.2032)
		(layers "F.Cu" "B.Cu")
		(net "GND")
	)
	(via
		(at 332.931008 -233.954066)
		(size 0.4064)
		(drill 0.2032)
		(layers "F.Cu" "B.Cu")
		(net "GND")
	)
	(via
		(at 386.504942 -242.054126)
		(size 0.4064)
		(drill 0.2032)
		(layers "F.Cu" "B.Cu")
		(net "GND")
	)
	(via
		(at 108.839 -419.1)
		(size 0.508)
		(drill 0.254)
		(layers "F.Cu" "B.Cu")
		(net "GND")
	)
	(via
		(at 290.04641 -344.77706)
		(size 0.49022)
		(drill 0.254)
		(layers "F.Cu" "B.Cu")
		(net "GND")
	)
	(via
		(at 129.164842 -224.234502)
		(size 0.4064)
		(drill 0.2032)
		(layers "F.Cu" "B.Cu")
		(net "GND")
	)
	(via
		(at 135.574786 -294.336216)
		(size 0.4064)
		(drill 0.2032)
		(layers "F.Cu" "B.Cu")
		(net "GND")
	)
	(via
		(at 80.591152 -282.18638)
		(size 0.4064)
		(drill 0.2032)
		(layers "F.Cu" "B.Cu")
		(net "GND")
	)
	(via
		(at 56.357774 -335.640172)
		(size 0.508)
		(drill 0.254)
		(layers "F.Cu" "B.Cu")
		(net "GND")
	)
	(via
		(at 388.384796 -233.954066)
		(size 0.4064)
		(drill 0.2032)
		(layers "F.Cu" "B.Cu")
		(net "GND")
	)
	(via
		(at 44.340018 -289.98545)
		(size 0.4826)
		(drill 0.254)
		(layers "F.Cu" "B.Cu")
		(net "GND")
	)
	(via
		(at 365.18469 -270.846042)
		(size 0.4064)
		(drill 0.2032)
		(layers "F.Cu" "B.Cu")
		(net "GND")
	)
	(via
		(at 356.901242 -249.34418)
		(size 0.4064)
		(drill 0.2032)
		(layers "F.Cu" "B.Cu")
		(net "GND")
	)
	(via
		(at 103.791004 -243.674392)
		(size 0.4064)
		(drill 0.2032)
		(layers "F.Cu" "B.Cu")
		(net "GND")
	)
	(via
		(at 337.92668 -331.068934)
		(size 0.508)
		(drill 0.254)
		(layers "F.Cu" "B.Cu")
		(net "GND")
	)
	(via
		(at 387.914896 -228.284278)
		(size 0.4064)
		(drill 0.2032)
		(layers "F.Cu" "B.Cu")
		(net "GND")
	)
	(via
		(at 123.971304 -89.00668)
		(size 0.508)
		(drill 0.254)
		(layers "F.Cu" "B.Cu")
		(net "GND")
	)
	(via
		(at 391.974832 -281.37612)
		(size 0.4064)
		(drill 0.2032)
		(layers "F.Cu" "B.Cu")
		(net "GND")
	)
	(via
		(at 144.381982 -105.624884)
		(size 0.508)
		(drill 0.254)
		(layers "F.Cu" "B.Cu")
		(net "GND")
	)
	(via
		(at 127.71501 -27.173936)
		(size 0.508)
		(drill 0.254)
		(layers "F.Cu" "B.Cu")
		(net "GND")
	)
	(via
		(at 361.737402 -348.80296)
		(size 0.508)
		(drill 0.254)
		(layers "F.Cu" "B.Cu")
		(net "GND")
	)
	(via
		(at 122.081798 -413.204152)
		(size 0.4572)
		(drill 0.254)
		(layers "F.Cu" "B.Cu")
		(net "GND")
	)
	(via
		(at 424.958764 -349.175578)
		(size 0.49022)
		(drill 0.254)
		(layers "F.Cu" "B.Cu")
		(net "GND")
	)
	(via
		(at 337.686904 -381.68453)
		(size 0.508)
		(drill 0.254)
		(layers "F.Cu" "B.Cu")
		(net "GND")
	)
	(via
		(at 165.545516 -304.860452)
		(size 0.4826)
		(drill 0.254)
		(layers "F.Cu" "B.Cu")
		(net "GND")
	)
	(via
		(at 333.955898 -416.020504)
		(size 0.4572)
		(drill 0.254)
		(layers "F.Cu" "B.Cu")
		(net "GND")
	)
	(via
		(at 111.910114 -173.867572)
		(size 0.508)
		(drill 0.254)
		(layers "F.Cu" "B.Cu")
		(net "GND")
	)
	(via
		(at 101.82987 -405.407114)
		(size 0.508)
		(drill 0.254)
		(layers "F.Cu" "B.Cu")
		(net "GND")
	)
	(via
		(at 381.339852 -209.587338)
		(size 0.508)
		(drill 0.254)
		(layers "F.Cu" "B.Cu")
		(net "GND")
	)
	(via
		(at 43.66895 -438.805574)
		(size 0.508)
		(drill 0.254)
		(layers "F.Cu" "B.Cu")
		(net "GND")
	)
	(via
		(at 6.829298 -137.61847)
		(size 0.508)
		(drill 0.254)
		(layers "F.Cu" "B.Cu")
		(net "GND")
	)
	(via
		(at 116.304822 -277.326344)
		(size 0.4064)
		(drill 0.2032)
		(layers "F.Cu" "B.Cu")
		(net "GND")
	)
	(via
		(at 51.416458 -382.85293)
		(size 0.4064)
		(drill 0.2032)
		(layers "F.Cu" "B.Cu")
		(net "GND")
	)
	(via
		(at 89.518998 -390.160002)
		(size 0.4064)
		(drill 0.2032)
		(layers "F.Cu" "B.Cu")
		(net "GND")
	)
	(via
		(at 333.066644 -379.88113)
		(size 0.508)
		(drill 0.254)
		(layers "F.Cu" "B.Cu")
		(net "GND")
	)
	(via
		(at 122.651266 -167.131746)
		(size 0.49022)
		(drill 0.254)
		(layers "F.Cu" "B.Cu")
		(net "GND")
	)
	(via
		(at 2.76225 -294.569134)
		(size 0.508)
		(drill 0.254)
		(layers "F.Cu" "B.Cu")
		(net "GND")
	)
	(via
		(at 413.29864 -377.41733)
		(size 0.508)
		(drill 0.254)
		(layers "F.Cu" "B.Cu")
		(net "GND")
	)
	(via
		(at 139.974828 -249.344434)
		(size 0.4064)
		(drill 0.2032)
		(layers "F.Cu" "B.Cu")
		(net "GND")
	)
	(via
		(at 323.249544 -427.851316)
		(size 0.4572)
		(drill 0.2032)
		(layers "F.Cu" "B.Cu")
		(net "GND")
	)
	(via
		(at 421.8051 -378.07773)
		(size 0.508)
		(drill 0.254)
		(layers "F.Cu" "B.Cu")
		(net "GND")
	)
	(via
		(at 100.832158 -55.03799)
		(size 0.508)
		(drill 0.254)
		(layers "F.Cu" "B.Cu")
		(net "GND")
	)
	(via
		(at 32.695896 -311.235344)
		(size 0.4826)
		(drill 0.254)
		(layers "F.Cu" "B.Cu")
		(net "GND")
	)
	(via
		(at 384.924808 -278.946102)
		(size 0.4064)
		(drill 0.2032)
		(layers "F.Cu" "B.Cu")
		(net "GND")
	)
	(via
		(at 23.71471 -4.963414)
		(size 0.508)
		(drill 0.254)
		(layers "F.Cu" "B.Cu")
		(net "GND")
	)
	(via
		(at 233.64952 -290.415726)
		(size 0.508)
		(drill 0.254)
		(layers "F.Cu" "B.Cu")
		(net "GND")
	)
	(via
		(at 110.200948 -284.616398)
		(size 0.4064)
		(drill 0.2032)
		(layers "F.Cu" "B.Cu")
		(net "GND")
	)
	(via
		(at 455.305668 -313.360054)
		(size 0.4826)
		(drill 0.254)
		(layers "F.Cu" "B.Cu")
		(net "GND")
	)
	(via
		(at 432.67376 -238.560102)
		(size 0.4826)
		(drill 0.254)
		(layers "F.Cu" "B.Cu")
		(net "GND")
	)
	(via
		(at 77.066902 -371.49913)
		(size 0.508)
		(drill 0.254)
		(layers "F.Cu" "B.Cu")
		(net "GND")
	)
	(via
		(at 123.066556 -373.30253)
		(size 0.508)
		(drill 0.254)
		(layers "F.Cu" "B.Cu")
		(net "GND")
	)
	(via
		(at 277.192232 -224.534984)
		(size 0.4826)
		(drill 0.254)
		(layers "F.Cu" "B.Cu")
		(net "GND")
	)
	(via
		(at 138.864848 -274.08632)
		(size 0.4064)
		(drill 0.2032)
		(layers "F.Cu" "B.Cu")
		(net "GND")
	)
	(via
		(at 302.150526 -314.210192)
		(size 0.4826)
		(drill 0.254)
		(layers "F.Cu" "B.Cu")
		(net "GND")
	)
	(via
		(at 192.56121 -349.381572)
		(size 0.49022)
		(drill 0.254)
		(layers "F.Cu" "B.Cu")
		(net "GND")
	)
	(via
		(at 425.497498 -331.19949)
		(size 0.508)
		(drill 0.254)
		(layers "F.Cu" "B.Cu")
		(net "GND")
	)
	(via
		(at 165.812216 -284.885384)
		(size 0.4826)
		(drill 0.254)
		(layers "F.Cu" "B.Cu")
		(net "GND")
	)
	(via
		(at 128.349756 -432.451256)
		(size 0.4572)
		(drill 0.2032)
		(layers "F.Cu" "B.Cu")
		(net "GND")
	)
	(via
		(at 294.972994 -393.243816)
		(size 0.508)
		(drill 0.254)
		(layers "F.Cu" "B.Cu")
		(net "GND")
	)
	(via
		(at 411.001718 -167.672512)
		(size 0.508)
		(drill 0.254)
		(layers "F.Cu" "B.Cu")
		(net "GND")
	)
	(via
		(at 388.68477 -277.32609)
		(size 0.4064)
		(drill 0.2032)
		(layers "F.Cu" "B.Cu")
		(net "GND")
	)
	(via
		(at 410.245814 -417.778184)
		(size 0.4572)
		(drill 0.254)
		(layers "F.Cu" "B.Cu")
		(net "GND")
	)
	(via
		(at 93.280992 -279.756362)
		(size 0.4064)
		(drill 0.2032)
		(layers "F.Cu" "B.Cu")
		(net "GND")
	)
	(via
		(at 107.257342 -336.695034)
		(size 0.508)
		(drill 0.254)
		(layers "F.Cu" "B.Cu")
		(net "GND")
	)
	(via
		(at 314.2234 -366.395)
		(size 0.508)
		(drill 0.254)
		(layers "F.Cu" "B.Cu")
		(net "GND")
	)
	(via
		(at 417.043616 -342.536018)
		(size 0.508)
		(drill 0.254)
		(layers "F.Cu" "B.Cu")
		(net "GND")
	)
	(via
		(at 87.544402 -391.830814)
		(size 0.4064)
		(drill 0.2032)
		(layers "F.Cu" "B.Cu")
		(net "GND")
	)
	(via
		(at 238.960914 -316.46368)
		(size 0.508)
		(drill 0.254)
		(layers "F.Cu" "B.Cu")
		(net "GND")
	)
	(via
		(at 364.884716 -229.094284)
		(size 0.4064)
		(drill 0.2032)
		(layers "F.Cu" "B.Cu")
		(net "GND")
	)
	(via
		(at 21.70811 -243.235226)
		(size 0.4826)
		(drill 0.254)
		(layers "F.Cu" "B.Cu")
		(net "GND")
	)
	(via
		(at 412.367984 -283.185108)
		(size 0.4826)
		(drill 0.254)
		(layers "F.Cu" "B.Cu")
		(net "GND")
	)
	(via
		(at 371.764814 -262.745982)
		(size 0.4064)
		(drill 0.2032)
		(layers "F.Cu" "B.Cu")
		(net "GND")
	)
	(via
		(at 116.56187 -171.357544)
		(size 0.49022)
		(drill 0.254)
		(layers "F.Cu" "B.Cu")
		(net "GND")
	)
	(via
		(at 203.265532 -230.0605)
		(size 0.4826)
		(drill 0.254)
		(layers "F.Cu" "B.Cu")
		(net "GND")
	)
	(via
		(at 83.580986 -244.484398)
		(size 0.4064)
		(drill 0.2032)
		(layers "F.Cu" "B.Cu")
		(net "GND")
	)
	(via
		(at 105.664762 -338.00415)
		(size 0.49022)
		(drill 0.254)
		(layers "F.Cu" "B.Cu")
		(net "GND")
	)
	(via
		(at 78.505558 -335.558892)
		(size 0.49022)
		(drill 0.254)
		(layers "F.Cu" "B.Cu")
		(net "GND")
	)
	(via
		(at 63.24981 -436.347362)
		(size 0.4572)
		(drill 0.2032)
		(layers "F.Cu" "B.Cu")
		(net "GND")
	)
	(via
		(at 389.668258 -182.177944)
		(size 0.49022)
		(drill 0.254)
		(layers "F.Cu" "B.Cu")
		(net "GND")
	)
	(via
		(at 318.21628 -391.23493)
		(size 0.4064)
		(drill 0.2032)
		(layers "F.Cu" "B.Cu")
		(net "GND")
	)
	(via
		(at 219.325952 -44.788328)
		(size 0.508)
		(drill 0.254)
		(layers "F.Cu" "B.Cu")
		(net "GND")
	)
	(via
		(at 61.249814 -439.651394)
		(size 0.4572)
		(drill 0.2032)
		(layers "F.Cu" "B.Cu")
		(net "GND")
	)
	(via
		(at 145.349722 -428.851314)
		(size 0.4572)
		(drill 0.2032)
		(layers "F.Cu" "B.Cu")
		(net "GND")
	)
	(via
		(at 78.283562 -368.37493)
		(size 0.508)
		(drill 0.254)
		(layers "F.Cu" "B.Cu")
		(net "GND")
	)
	(via
		(at 467.5378 -233.731054)
		(size 0.508)
		(drill 0.254)
		(layers "F.Cu" "B.Cu")
		(net "GND")
	)
	(via
		(at 20.59051 -238.560356)
		(size 0.4826)
		(drill 0.254)
		(layers "F.Cu" "B.Cu")
		(net "GND")
	)
	(via
		(at 171.97197 -281.48534)
		(size 0.4826)
		(drill 0.254)
		(layers "F.Cu" "B.Cu")
		(net "GND")
	)
	(via
		(at 119.018558 -413.204152)
		(size 0.4572)
		(drill 0.254)
		(layers "F.Cu" "B.Cu")
		(net "GND")
	)
	(via
		(at 357.201216 -281.37612)
		(size 0.4064)
		(drill 0.2032)
		(layers "F.Cu" "B.Cu")
		(net "GND")
	)
	(via
		(at 126.814834 -254.20447)
		(size 0.4064)
		(drill 0.2032)
		(layers "F.Cu" "B.Cu")
		(net "GND")
	)
	(via
		(at 268.530578 -229.210108)
		(size 0.4826)
		(drill 0.254)
		(layers "F.Cu" "B.Cu")
		(net "GND")
	)
	(via
		(at 33.813496 -193.107564)
		(size 0.4826)
		(drill 0.254)
		(layers "F.Cu" "B.Cu")
		(net "GND")
	)
	(via
		(at 138.09472 -225.044508)
		(size 0.4064)
		(drill 0.2032)
		(layers "F.Cu" "B.Cu")
		(net "GND")
	)
	(via
		(at 378.344938 -287.046162)
		(size 0.4064)
		(drill 0.2032)
		(layers "F.Cu" "B.Cu")
		(net "GND")
	)
	(via
		(at 80.120998 -270.03629)
		(size 0.4064)
		(drill 0.2032)
		(layers "F.Cu" "B.Cu")
		(net "GND")
	)
	(via
		(at 179.516024 -255.13538)
		(size 0.4826)
		(drill 0.254)
		(layers "F.Cu" "B.Cu")
		(net "GND")
	)
	(via
		(at 185.6486 -342.704674)
		(size 0.508)
		(drill 0.254)
		(layers "F.Cu" "B.Cu")
		(net "GND")
	)
	(via
		(at 431.55616 -224.534984)
		(size 0.4826)
		(drill 0.254)
		(layers "F.Cu" "B.Cu")
		(net "GND")
	)
	(via
		(at 207.626204 -123.756928)
		(size 0.508)
		(drill 0.254)
		(layers "F.Cu" "B.Cu")
		(net "GND")
	)
	(via
		(at 46.373034 -18.5039)
		(size 0.508)
		(drill 0.254)
		(layers "F.Cu" "B.Cu")
		(net "GND")
	)
	(via
		(at 99.715066 -183.09209)
		(size 0.49022)
		(drill 0.254)
		(layers "F.Cu" "B.Cu")
		(net "GND")
	)
	(via
		(at 146.742912 -254.470408)
		(size 0.4064)
		(drill 0.2032)
		(layers "F.Cu" "B.Cu")
		(net "GND")
	)
	(via
		(at 287.062418 -239.41024)
		(size 0.4826)
		(drill 0.254)
		(layers "F.Cu" "B.Cu")
		(net "GND")
	)
	(via
		(at 78.41107 -230.71455)
		(size 0.4064)
		(drill 0.2032)
		(layers "F.Cu" "B.Cu")
		(net "GND")
	)
	(via
		(at 157.783784 -369.69573)
		(size 0.508)
		(drill 0.254)
		(layers "F.Cu" "B.Cu")
		(net "GND")
	)
	(via
		(at 145.144744 -227.474526)
		(size 0.4064)
		(drill 0.2032)
		(layers "F.Cu" "B.Cu")
		(net "GND")
	)
	(via
		(at 338.249514 -427.699678)
		(size 0.4572)
		(drill 0.2032)
		(layers "F.Cu" "B.Cu")
		(net "GND")
	)
	(via
		(at 297.049952 -352.227134)
		(size 0.508)
		(drill 0.254)
		(layers "F.Cu" "B.Cu")
		(net "GND")
	)
	(via
		(at 128.994662 -279.756362)
		(size 0.4064)
		(drill 0.2032)
		(layers "F.Cu" "B.Cu")
		(net "GND")
	)
	(via
		(at 195.988432 -296.785284)
		(size 0.4826)
		(drill 0.254)
		(layers "F.Cu" "B.Cu")
		(net "GND")
	)
	(via
		(at 415.146236 -396.710662)
		(size 0.4064)
		(drill 0.2032)
		(layers "F.Cu" "B.Cu")
		(net "GND")
	)
	(via
		(at 62.998604 -410.030168)
		(size 0.4064)
		(drill 0.2032)
		(layers "F.Cu" "B.Cu")
		(net "GND")
	)
	(via
		(at 283.618432 -294.660066)
		(size 0.4826)
		(drill 0.254)
		(layers "F.Cu" "B.Cu")
		(net "GND")
	)
	(via
		(at 388.68477 -261.12597)
		(size 0.4064)
		(drill 0.2032)
		(layers "F.Cu" "B.Cu")
		(net "GND")
	)
	(via
		(at 73.24979 -436.051452)
		(size 0.4572)
		(drill 0.2032)
		(layers "F.Cu" "B.Cu")
		(net "GND")
	)
	(via
		(at 311.906666 -344.767408)
		(size 0.508)
		(drill 0.254)
		(layers "F.Cu" "B.Cu")
		(net "GND")
	)
	(via
		(at 421.361616 -342.536018)
		(size 0.508)
		(drill 0.254)
		(layers "F.Cu" "B.Cu")
		(net "GND")
	)
	(via
		(at 108.378752 -405.892762)
		(size 0.508)
		(drill 0.254)
		(layers "F.Cu" "B.Cu")
		(net "GND")
	)
	(via
		(at 442.844174 -410.6037)
		(size 0.508)
		(drill 0.254)
		(layers "F.Cu" "B.Cu")
		(net "GND")
	)
	(via
		(at 325.124826 -418.412168)
		(size 0.4064)
		(drill 0.2032)
		(layers "F.Cu" "B.Cu")
		(net "GND")
	)
	(via
		(at 255.927098 -211.672424)
		(size 0.508)
		(drill 0.254)
		(layers "F.Cu" "B.Cu")
		(net "GND")
	)
	(via
		(at 437.715914 -274.684998)
		(size 0.4826)
		(drill 0.254)
		(layers "F.Cu" "B.Cu")
		(net "GND")
	)
	(via
		(at 110.76686 -32.513778)
		(size 0.508)
		(drill 0.254)
		(layers "F.Cu" "B.Cu")
		(net "GND")
	)
	(via
		(at 128.994662 -282.996386)
		(size 0.4064)
		(drill 0.2032)
		(layers "F.Cu" "B.Cu")
		(net "GND")
	)
	(via
		(at 133.065266 -158.470346)
		(size 0.49022)
		(drill 0.254)
		(layers "F.Cu" "B.Cu")
		(net "GND")
	)
	(via
		(at 395.11478 -313.935872)
		(size 0.508)
		(drill 0.254)
		(layers "F.Cu" "B.Cu")
		(net "GND")
	)
	(via
		(at 99.390962 -290.286186)
		(size 0.4064)
		(drill 0.2032)
		(layers "F.Cu" "B.Cu")
		(net "GND")
	)
	(via
		(at 342.33104 -250.154186)
		(size 0.4064)
		(drill 0.2032)
		(layers "F.Cu" "B.Cu")
		(net "GND")
	)
	(via
		(at 99.561142 -228.284532)
		(size 0.4064)
		(drill 0.2032)
		(layers "F.Cu" "B.Cu")
		(net "GND")
	)
	(via
		(at 397.288512 -399.34515)
		(size 0.508)
		(drill 0.254)
		(layers "F.Cu" "B.Cu")
		(net "GND")
	)
	(via
		(at 299.82414 -272.984976)
		(size 0.4826)
		(drill 0.254)
		(layers "F.Cu" "B.Cu")
		(net "GND")
	)
	(via
		(at 430.17186 -274.684998)
		(size 0.4826)
		(drill 0.254)
		(layers "F.Cu" "B.Cu")
		(net "GND")
	)
	(via
		(at 123.354846 -266.796266)
		(size 0.4064)
		(drill 0.2032)
		(layers "F.Cu" "B.Cu")
		(net "GND")
	)
	(via
		(at 158.754826 -410.030168)
		(size 0.4064)
		(drill 0.2032)
		(layers "F.Cu" "B.Cu")
		(net "GND")
	)
	(via
		(at 102.681024 -282.996386)
		(size 0.4064)
		(drill 0.2032)
		(layers "F.Cu" "B.Cu")
		(net "GND")
	)
	(via
		(at 349.851218 -251.774198)
		(size 0.4064)
		(drill 0.2032)
		(layers "F.Cu" "B.Cu")
		(net "GND")
	)
	(via
		(at 66.745358 -390.160002)
		(size 0.4064)
		(drill 0.2032)
		(layers "F.Cu" "B.Cu")
		(net "GND")
	)
	(via
		(at 376.634756 -233.14406)
		(size 0.4064)
		(drill 0.2032)
		(layers "F.Cu" "B.Cu")
		(net "GND")
	)
	(via
		(at 194.914774 -425.854876)
		(size 0.508)
		(drill 0.254)
		(layers "F.Cu" "B.Cu")
		(net "GND")
	)
	(via
		(at 42.299636 -4.963414)
		(size 0.508)
		(drill 0.254)
		(layers "F.Cu" "B.Cu")
		(net "GND")
	)
	(via
		(at 304.97526 -351.681288)
		(size 0.508)
		(drill 0.254)
		(layers "F.Cu" "B.Cu")
		(net "GND")
	)
	(via
		(at 68.447158 -333.84998)
		(size 0.49022)
		(drill 0.254)
		(layers "F.Cu" "B.Cu")
		(net "GND")
	)
	(via
		(at 138.929618 -410.664152)
		(size 0.4572)
		(drill 0.254)
		(layers "F.Cu" "B.Cu")
		(net "GND")
	)
	(via
		(at 43.66895 -433.940712)
		(size 0.508)
		(drill 0.254)
		(layers "F.Cu" "B.Cu")
		(net "GND")
	)
	(via
		(at 242.704366 -155.960318)
		(size 0.508)
		(drill 0.254)
		(layers "F.Cu" "B.Cu")
		(net "GND")
	)
	(via
		(at 396.349474 -434.899562)
		(size 0.4572)
		(drill 0.2032)
		(layers "F.Cu" "B.Cu")
		(net "GND")
	)
	(via
		(at 353.141026 -239.624108)
		(size 0.4064)
		(drill 0.2032)
		(layers "F.Cu" "B.Cu")
		(net "GND")
	)
	(via
		(at 69.532754 -336.988404)
		(size 0.49022)
		(drill 0.254)
		(layers "F.Cu" "B.Cu")
		(net "GND")
	)
	(via
		(at 79.07401 -184.692798)
		(size 0.508)
		(drill 0.254)
		(layers "F.Cu" "B.Cu")
		(net "GND")
	)
	(via
		(at 292.280086 -235.585)
		(size 0.4826)
		(drill 0.254)
		(layers "F.Cu" "B.Cu")
		(net "GND")
	)
	(via
		(at 447.761868 -313.360054)
		(size 0.4826)
		(drill 0.254)
		(layers "F.Cu" "B.Cu")
		(net "GND")
	)
	(via
		(at 115.534694 -234.764326)
		(size 0.4064)
		(drill 0.2032)
		(layers "F.Cu" "B.Cu")
		(net "GND")
	)
	(via
		(at 124.7648 -290.286186)
		(size 0.4064)
		(drill 0.2032)
		(layers "F.Cu" "B.Cu")
		(net "GND")
	)
	(via
		(at 35.41776 -111.506)
		(size 0.508)
		(drill 0.254)
		(layers "F.Cu" "B.Cu")
		(net "GND")
	)
	(via
		(at 116.553742 -78.783942)
		(size 0.508)
		(drill 0.254)
		(layers "F.Cu" "B.Cu")
		(net "GND")
	)
	(via
		(at 51.188874 -435.61)
		(size 0.508)
		(drill 0.254)
		(layers "F.Cu" "B.Cu")
		(net "GND")
	)
	(via
		(at 84.249768 -432.747166)
		(size 0.4572)
		(drill 0.2032)
		(layers "F.Cu" "B.Cu")
		(net "GND")
	)
	(via
		(at 159.444436 -393.927838)
		(size 0.4572)
		(drill 0.254)
		(layers "F.Cu" "B.Cu")
		(net "GND")
	)
	(via
		(at 439.100214 -267.035026)
		(size 0.4826)
		(drill 0.254)
		(layers "F.Cu" "B.Cu")
		(net "GND")
	)
	(via
		(at 275.807932 -230.485188)
		(size 0.4826)
		(drill 0.254)
		(layers "F.Cu" "B.Cu")
		(net "GND")
	)
	(via
		(at 411.349698 -436.347362)
		(size 0.4572)
		(drill 0.2032)
		(layers "F.Cu" "B.Cu")
		(net "GND")
	)
	(via
		(at 56.513476 -406.370536)
		(size 0.4572)
		(drill 0.254)
		(layers "F.Cu" "B.Cu")
		(net "GND")
	)
	(via
		(at 59.428126 -310.385206)
		(size 0.4826)
		(drill 0.254)
		(layers "F.Cu" "B.Cu")
		(net "GND")
	)
	(via
		(at 230.310436 -157.320742)
		(size 0.508)
		(drill 0.254)
		(layers "F.Cu" "B.Cu")
		(net "GND")
	)
	(via
		(at 324.766178 -417.778184)
		(size 0.4572)
		(drill 0.254)
		(layers "F.Cu" "B.Cu")
		(net "GND")
	)
	(via
		(at 416.468052 -251.735082)
		(size 0.4826)
		(drill 0.254)
		(layers "F.Cu" "B.Cu")
		(net "GND")
	)
	(via
		(at 111.332264 -259.845302)
		(size 0.4826)
		(drill 0.254)
		(layers "F.Cu" "B.Cu")
		(net "GND")
	)
	(via
		(at 352.846132 -396.710662)
		(size 0.4064)
		(drill 0.2032)
		(layers "F.Cu" "B.Cu")
		(net "GND")
	)
	(via
		(at 151.819102 -390.160002)
		(size 0.4064)
		(drill 0.2032)
		(layers "F.Cu" "B.Cu")
		(net "GND")
	)
	(via
		(at 17.649444 -422.104312)
		(size 0.508)
		(drill 0.254)
		(layers "F.Cu" "B.Cu")
		(net "GND")
	)
	(via
		(at 427.456092 -199.035162)
		(size 0.4826)
		(drill 0.254)
		(layers "F.Cu" "B.Cu")
		(net "GND")
	)
	(via
		(at 389.79475 -225.044254)
		(size 0.4064)
		(drill 0.2032)
		(layers "F.Cu" "B.Cu")
		(net "GND")
	)
	(via
		(at 173.08957 -220.710252)
		(size 0.4826)
		(drill 0.254)
		(layers "F.Cu" "B.Cu")
		(net "GND")
	)
	(via
		(at 383.21488 -236.384084)
		(size 0.4064)
		(drill 0.2032)
		(layers "F.Cu" "B.Cu")
		(net "GND")
	)
	(via
		(at 128.891284 -390.160002)
		(size 0.4064)
		(drill 0.2032)
		(layers "F.Cu" "B.Cu")
		(net "GND")
	)
	(via
		(at 288.180018 -223.6851)
		(size 0.4826)
		(drill 0.254)
		(layers "F.Cu" "B.Cu")
		(net "GND")
	)
	(via
		(at 358.65308 -391.834116)
		(size 0.508)
		(drill 0.254)
		(layers "F.Cu" "B.Cu")
		(net "GND")
	)
	(via
		(at 466.760814 -40.45585)
		(size 0.508)
		(drill 0.254)
		(layers "F.Cu" "B.Cu")
		(net "GND")
	)
	(via
		(at 122.116596 -391.830814)
		(size 0.4064)
		(drill 0.2032)
		(layers "F.Cu" "B.Cu")
		(net "GND")
	)
	(via
		(at 155.895294 -200.766172)
		(size 0.508)
		(drill 0.254)
		(layers "F.Cu" "B.Cu")
		(net "GND")
	)
	(via
		(at 98.50247 -408.381708)
		(size 0.508)
		(drill 0.254)
		(layers "F.Cu" "B.Cu")
		(net "GND")
	)
	(via
		(at 396.349474 -428.851314)
		(size 0.4572)
		(drill 0.2032)
		(layers "F.Cu" "B.Cu")
		(net "GND")
	)
	(via
		(at 445.282066 -405.5491)
		(size 0.508)
		(drill 0.254)
		(layers "F.Cu" "B.Cu")
		(net "GND")
	)
	(via
		(at 73.914 -3.76428)
		(size 0.508)
		(drill 0.254)
		(layers "F.Cu" "B.Cu")
		(net "GND")
	)
	(via
		(at 22.535388 -372.12905)
		(size 0.508)
		(drill 0.254)
		(layers "F.Cu" "B.Cu")
		(net "GND")
	)
	(via
		(at 115.834668 -281.376374)
		(size 0.4064)
		(drill 0.2032)
		(layers "F.Cu" "B.Cu")
		(net "GND")
	)
	(via
		(at 82.172302 -373.96293)
		(size 0.508)
		(drill 0.254)
		(layers "F.Cu" "B.Cu")
		(net "GND")
	)
	(via
		(at 182.67553 -43.909742)
		(size 0.508)
		(drill 0.254)
		(layers "F.Cu" "B.Cu")
		(net "GND")
	)
	(via
		(at 66.872104 -8.79475)
		(size 0.508)
		(drill 0.254)
		(layers "F.Cu" "B.Cu")
		(net "GND")
	)
	(via
		(at 141.982444 -371.49913)
		(size 0.508)
		(drill 0.254)
		(layers "F.Cu" "B.Cu")
		(net "GND")
	)
	(via
		(at 64.742314 -344.137234)
		(size 0.508)
		(drill 0.254)
		(layers "F.Cu" "B.Cu")
		(net "GND")
	)
	(via
		(at 393.384786 -280.566114)
		(size 0.4064)
		(drill 0.2032)
		(layers "F.Cu" "B.Cu")
		(net "GND")
	)
	(via
		(at 74.22007 -177.059844)
		(size 0.49022)
		(drill 0.254)
		(layers "F.Cu" "B.Cu")
		(net "GND")
	)
	(via
		(at 340.921086 -246.104156)
		(size 0.4064)
		(drill 0.2032)
		(layers "F.Cu" "B.Cu")
		(net "GND")
	)
	(via
		(at 424.012106 -246.635016)
		(size 0.4826)
		(drill 0.254)
		(layers "F.Cu" "B.Cu")
		(net "GND")
	)
	(via
		(at 86.701122 -271.656302)
		(size 0.4064)
		(drill 0.2032)
		(layers "F.Cu" "B.Cu")
		(net "GND")
	)
	(via
		(at 188.444378 -212.635338)
		(size 0.4826)
		(drill 0.254)
		(layers "F.Cu" "B.Cu")
		(net "GND")
	)
	(via
		(at 84.84616 -388.328662)
		(size 0.4064)
		(drill 0.2032)
		(layers "F.Cu" "B.Cu")
		(net "GND")
	)
	(via
		(at 370.524786 -255.014222)
		(size 0.4064)
		(drill 0.2032)
		(layers "F.Cu" "B.Cu")
		(net "GND")
	)
	(via
		(at 417.844224 -391.23493)
		(size 0.4064)
		(drill 0.2032)
		(layers "F.Cu" "B.Cu")
		(net "GND")
	)
	(via
		(at 36.795964 -204.135228)
		(size 0.4826)
		(drill 0.254)
		(layers "F.Cu" "B.Cu")
		(net "GND")
	)
	(via
		(at 197.3199 -221.135194)
		(size 0.4826)
		(drill 0.254)
		(layers "F.Cu" "B.Cu")
		(net "GND")
	)
	(via
		(at 121.995946 -407.00452)
		(size 0.4064)
		(drill 0.2032)
		(layers "F.Cu" "B.Cu")
		(net "GND")
	)
	(via
		(at 415.779966 -134.16026)
		(size 0.508)
		(drill 0.254)
		(layers "F.Cu" "B.Cu")
		(net "GND")
	)
	(via
		(at 382.916684 -402.309838)
		(size 0.4572)
		(drill 0.254)
		(layers "F.Cu" "B.Cu")
		(net "GND")
	)
	(via
		(at 36.795964 -301.035212)
		(size 0.4826)
		(drill 0.254)
		(layers "F.Cu" "B.Cu")
		(net "GND")
	)
	(via
		(at 130.218434 -388.328662)
		(size 0.4064)
		(drill 0.2032)
		(layers "F.Cu" "B.Cu")
		(net "GND")
	)
	(via
		(at 426.51172 -347.870526)
		(size 0.508)
		(drill 0.254)
		(layers "F.Cu" "B.Cu")
		(net "GND")
	)
	(via
		(at 359.518204 -264.86231)
		(size 0.4826)
		(drill 0.254)
		(layers "F.Cu" "B.Cu")
		(net "GND")
	)
	(via
		(at 21.69033 -425.528994)
		(size 0.508)
		(drill 0.254)
		(layers "F.Cu" "B.Cu")
		(net "GND")
	)
	(via
		(at 375.524776 -283.806138)
		(size 0.4064)
		(drill 0.2032)
		(layers "F.Cu" "B.Cu")
		(net "GND")
	)
	(via
		(at 450.088 -266.185142)
		(size 0.4826)
		(drill 0.254)
		(layers "F.Cu" "B.Cu")
		(net "GND")
	)
	(via
		(at 130.349752 -425.547282)
		(size 0.4572)
		(drill 0.2032)
		(layers "F.Cu" "B.Cu")
		(net "GND")
	)
	(via
		(at 41.40073 -421.989758)
		(size 0.508)
		(drill 0.254)
		(layers "F.Cu" "B.Cu")
		(net "GND")
	)
	(via
		(at 132.803138 -406.370536)
		(size 0.4572)
		(drill 0.254)
		(layers "F.Cu" "B.Cu")
		(net "GND")
	)
	(via
		(at 321.249548 -427.699678)
		(size 0.4572)
		(drill 0.2032)
		(layers "F.Cu" "B.Cu")
		(net "GND")
	)
	(via
		(at 298.43984 -305.28514)
		(size 0.4826)
		(drill 0.254)
		(layers "F.Cu" "B.Cu")
		(net "GND")
	)
	(via
		(at 176.072038 -248.335292)
		(size 0.4826)
		(drill 0.254)
		(layers "F.Cu" "B.Cu")
		(net "GND")
	)
	(via
		(at 100.031042 -237.194344)
		(size 0.4064)
		(drill 0.2032)
		(layers "F.Cu" "B.Cu")
		(net "GND")
	)
	(via
		(at 120.70461 -235.574332)
		(size 0.4064)
		(drill 0.2032)
		(layers "F.Cu" "B.Cu")
		(net "GND")
	)
	(via
		(at 230.759 -235.585)
		(size 0.508)
		(drill 0.254)
		(layers "F.Cu" "B.Cu")
		(net "GND")
	)
	(via
		(at 36.004754 -348.709488)
		(size 0.49022)
		(drill 0.254)
		(layers "F.Cu" "B.Cu")
		(net "GND")
	)
	(via
		(at 283.72181 -344.77706)
		(size 0.49022)
		(drill 0.254)
		(layers "F.Cu" "B.Cu")
		(net "GND")
	)
	(via
		(at 51.118516 -388.328662)
		(size 0.4064)
		(drill 0.2032)
		(layers "F.Cu" "B.Cu")
		(net "GND")
	)
	(via
		(at 235.961682 -329.173078)
		(size 0.508)
		(drill 0.254)
		(layers "F.Cu" "B.Cu")
		(net "GND")
	)
	(via
		(at 183.616092 -308.685438)
		(size 0.4826)
		(drill 0.254)
		(layers "F.Cu" "B.Cu")
		(net "GND")
	)
	(via
		(at 378.814838 -274.896072)
		(size 0.4064)
		(drill 0.2032)
		(layers "F.Cu" "B.Cu")
		(net "GND")
	)
	(via
		(at 61.074554 -373.96293)
		(size 0.508)
		(drill 0.254)
		(layers "F.Cu" "B.Cu")
		(net "GND")
	)
	(via
		(at 182.67553 -49.878742)
		(size 0.508)
		(drill 0.254)
		(layers "F.Cu" "B.Cu")
		(net "GND")
	)
	(via
		(at 125.404626 -235.574332)
		(size 0.4064)
		(drill 0.2032)
		(layers "F.Cu" "B.Cu")
		(net "GND")
	)
	(via
		(at 414.244282 -402.309838)
		(size 0.4572)
		(drill 0.254)
		(layers "F.Cu" "B.Cu")
		(net "GND")
	)
	(via
		(at 359.518204 -263.84631)
		(size 0.4826)
		(drill 0.254)
		(layers "F.Cu" "B.Cu")
		(net "GND")
	)
	(via
		(at 107.870244 -375.793)
		(size 0.508)
		(drill 0.254)
		(layers "F.Cu" "B.Cu")
		(net "GND")
	)
	(via
		(at 53.284374 -347.287088)
		(size 0.49022)
		(drill 0.254)
		(layers "F.Cu" "B.Cu")
		(net "GND")
	)
	(via
		(at 191.26581 -349.381572)
		(size 0.49022)
		(drill 0.254)
		(layers "F.Cu" "B.Cu")
		(net "GND")
	)
	(via
		(at 418.265102 -412.84652)
		(size 0.4064)
		(drill 0.2032)
		(layers "F.Cu" "B.Cu")
		(net "GND")
	)
	(via
		(at 398.714468 -5.597398)
		(size 0.508)
		(drill 0.254)
		(layers "F.Cu" "B.Cu")
		(net "GND")
	)
	(via
		(at 354.34524 -257.430016)
		(size 0.4826)
		(drill 0.254)
		(layers "F.Cu" "B.Cu")
		(net "GND")
	)
	(via
		(at 174.771304 -331.522324)
		(size 0.508)
		(drill 0.254)
		(layers "F.Cu" "B.Cu")
		(net "GND")
	)
	(via
		(at 67.249802 -429.147224)
		(size 0.4572)
		(drill 0.2032)
		(layers "F.Cu" "B.Cu")
		(net "GND")
	)
	(via
		(at 467.5378 -222.555054)
		(size 0.508)
		(drill 0.254)
		(layers "F.Cu" "B.Cu")
		(net "GND")
	)
	(via
		(at 124.7648 -274.08632)
		(size 0.4064)
		(drill 0.2032)
		(layers "F.Cu" "B.Cu")
		(net "GND")
	)
	(via
		(at 91.571064 -235.574332)
		(size 0.4064)
		(drill 0.2032)
		(layers "F.Cu" "B.Cu")
		(net "GND")
	)
	(via
		(at 311.254394 -414.752536)
		(size 0.4572)
		(drill 0.254)
		(layers "F.Cu" "B.Cu")
		(net "GND")
	)
	(via
		(at 302.54067 -345.550998)
		(size 0.49022)
		(drill 0.254)
		(layers "F.Cu" "B.Cu")
		(net "GND")
	)
	(via
		(at 332.931008 -255.014222)
		(size 0.4064)
		(drill 0.2032)
		(layers "F.Cu" "B.Cu")
		(net "GND")
	)
	(via
		(at 372.704868 -270.846042)
		(size 0.4064)
		(drill 0.2032)
		(layers "F.Cu" "B.Cu")
		(net "GND")
	)
	(via
		(at 438.488836 -170.26763)
		(size 0.508)
		(drill 0.254)
		(layers "F.Cu" "B.Cu")
		(net "GND")
	)
	(via
		(at 277.192232 -222.834962)
		(size 0.4826)
		(drill 0.254)
		(layers "F.Cu" "B.Cu")
		(net "GND")
	)
	(via
		(at 326.297798 -420.318184)
		(size 0.4572)
		(drill 0.254)
		(layers "F.Cu" "B.Cu")
		(net "GND")
	)
	(via
		(at 386.01269 -412.212536)
		(size 0.4572)
		(drill 0.254)
		(layers "F.Cu" "B.Cu")
		(net "GND")
	)
	(via
		(at 239.014 -283.199078)
		(size 0.508)
		(drill 0.254)
		(layers "F.Cu" "B.Cu")
		(net "GND")
	)
	(via
		(at 387.716522 -391.23493)
		(size 0.4064)
		(drill 0.2032)
		(layers "F.Cu" "B.Cu")
		(net "GND")
	)
	(via
		(at 375.662952 -376.75693)
		(size 0.508)
		(drill 0.254)
		(layers "F.Cu" "B.Cu")
		(net "GND")
	)
	(via
		(at 203.532232 -284.885384)
		(size 0.4826)
		(drill 0.254)
		(layers "F.Cu" "B.Cu")
		(net "GND")
	)
	(via
		(at 153.349706 -427.699678)
		(size 0.4572)
		(drill 0.2032)
		(layers "F.Cu" "B.Cu")
		(net "GND")
	)
	(via
		(at 165.083744 -145.84299)
		(size 0.508)
		(drill 0.254)
		(layers "F.Cu" "B.Cu")
		(net "GND")
	)
	(via
		(at 317.249556 -431.29962)
		(size 0.4572)
		(drill 0.2032)
		(layers "F.Cu" "B.Cu")
		(net "GND")
	)
	(via
		(at 341.22106 -281.37612)
		(size 0.4064)
		(drill 0.2032)
		(layers "F.Cu" "B.Cu")
		(net "GND")
	)
	(via
		(at 332.249526 -426.69968)
		(size 0.4572)
		(drill 0.2032)
		(layers "F.Cu" "B.Cu")
		(net "GND")
	)
	(via
		(at 329.6412 -225.044254)
		(size 0.4064)
		(drill 0.2032)
		(layers "F.Cu" "B.Cu")
		(net "GND")
	)
	(via
		(at 82.925666 -184.683146)
		(size 0.49022)
		(drill 0.254)
		(layers "F.Cu" "B.Cu")
		(net "GND")
	)
	(via
		(at 427.456092 -300.185074)
		(size 0.4826)
		(drill 0.254)
		(layers "F.Cu" "B.Cu")
		(net "GND")
	)
	(via
		(at 352.335338 -414.752536)
		(size 0.4572)
		(drill 0.254)
		(layers "F.Cu" "B.Cu")
		(net "GND")
	)
	(via
		(at 297.108372 -275.535136)
		(size 0.4826)
		(drill 0.254)
		(layers "F.Cu" "B.Cu")
		(net "GND")
	)
	(via
		(at 108.64342 -390.297924)
		(size 0.508)
		(drill 0.254)
		(layers "F.Cu" "B.Cu")
		(net "GND")
	)
	(via
		(at 126.814834 -246.10441)
		(size 0.4064)
		(drill 0.2032)
		(layers "F.Cu" "B.Cu")
		(net "GND")
	)
	(via
		(at 390.094724 -265.176)
		(size 0.4064)
		(drill 0.2032)
		(layers "F.Cu" "B.Cu")
		(net "GND")
	)
	(via
		(at 126.949454 -405.098504)
		(size 0.4572)
		(drill 0.254)
		(layers "F.Cu" "B.Cu")
		(net "GND")
	)
	(via
		(at 404.089362 -4.963414)
		(size 0.508)
		(drill 0.254)
		(layers "F.Cu" "B.Cu")
		(net "GND")
	)
	(via
		(at 353.911154 -288.66592)
		(size 0.4064)
		(drill 0.2032)
		(layers "F.Cu" "B.Cu")
		(net "GND")
	)
	(via
		(at 129.464816 -293.52621)
		(size 0.4064)
		(drill 0.2032)
		(layers "F.Cu" "B.Cu")
		(net "GND")
	)
	(via
		(at 91.717368 -340.044532)
		(size 0.508)
		(drill 0.254)
		(layers "F.Cu" "B.Cu")
		(net "GND")
	)
	(via
		(at 353.141026 -250.964192)
		(size 0.4064)
		(drill 0.2032)
		(layers "F.Cu" "B.Cu")
		(net "GND")
	)
	(via
		(at 382.1049 -283.806138)
		(size 0.4064)
		(drill 0.2032)
		(layers "F.Cu" "B.Cu")
		(net "GND")
	)
	(via
		(at 136.34974 -427.699678)
		(size 0.4572)
		(drill 0.2032)
		(layers "F.Cu" "B.Cu")
		(net "GND")
	)
	(via
		(at 422.16451 -19.771868)
		(size 0.508)
		(drill 0.254)
		(layers "F.Cu" "B.Cu")
		(net "GND")
	)
	(via
		(at 341.989918 -392.999722)
		(size 0.4064)
		(drill 0.2032)
		(layers "F.Cu" "B.Cu")
		(net "GND")
	)
	(via
		(at 373.644922 -277.32609)
		(size 0.4064)
		(drill 0.2032)
		(layers "F.Cu" "B.Cu")
		(net "GND")
	)
	(via
		(at 40.23995 -311.235344)
		(size 0.4826)
		(drill 0.254)
		(layers "F.Cu" "B.Cu")
		(net "GND")
	)
	(via
		(at 338.58708 -332.389734)
		(size 0.508)
		(drill 0.254)
		(layers "F.Cu" "B.Cu")
		(net "GND")
	)
	(via
		(at 62.752732 -341.626952)
		(size 0.6604)
		(drill 0.3302)
		(layers "F.Cu" "B.Cu")
		(net "GND")
	)
	(via
		(at 105.200958 -249.344434)
		(size 0.4064)
		(drill 0.2032)
		(layers "F.Cu" "B.Cu")
		(net "GND")
	)
	(via
		(at 344.494104 -383.00533)
		(size 0.508)
		(drill 0.254)
		(layers "F.Cu" "B.Cu")
		(net "GND")
	)
	(via
		(at 130.574796 -241.244374)
		(size 0.4064)
		(drill 0.2032)
		(layers "F.Cu" "B.Cu")
		(net "GND")
	)
	(via
		(at 376.93473 -263.555988)
		(size 0.4064)
		(drill 0.2032)
		(layers "F.Cu" "B.Cu")
		(net "GND")
	)
	(via
		(at 103.92791 -180.755798)
		(size 0.508)
		(drill 0.254)
		(layers "F.Cu" "B.Cu")
		(net "GND")
	)
	(via
		(at 269.648178 -215.18499)
		(size 0.4826)
		(drill 0.254)
		(layers "F.Cu" "B.Cu")
		(net "GND")
	)
	(via
		(at 78.711044 -283.806392)
		(size 0.4064)
		(drill 0.2032)
		(layers "F.Cu" "B.Cu")
		(net "GND")
	)
	(via
		(at 143.264636 -250.15444)
		(size 0.4064)
		(drill 0.2032)
		(layers "F.Cu" "B.Cu")
		(net "GND")
	)
	(via
		(at 168.527984 -318.035432)
		(size 0.4826)
		(drill 0.254)
		(layers "F.Cu" "B.Cu")
		(net "GND")
	)
	(via
		(at 20.32381 -230.485442)
		(size 0.4826)
		(drill 0.254)
		(layers "F.Cu" "B.Cu")
		(net "GND")
	)
	(via
		(at 76.812902 -233.410252)
		(size 0.4064)
		(drill 0.2032)
		(layers "F.Cu" "B.Cu")
		(net "GND")
	)
	(via
		(at 44.340018 -246.63527)
		(size 0.4826)
		(drill 0.254)
		(layers "F.Cu" "B.Cu")
		(net "GND")
	)
	(via
		(at 179.516024 -301.88535)
		(size 0.4826)
		(drill 0.254)
		(layers "F.Cu" "B.Cu")
		(net "GND")
	)
	(via
		(at 423.002964 -350.715834)
		(size 0.49022)
		(drill 0.254)
		(layers "F.Cu" "B.Cu")
		(net "GND")
	)
	(via
		(at 50.216562 -393.927838)
		(size 0.4572)
		(drill 0.254)
		(layers "F.Cu" "B.Cu")
		(net "GND")
	)
	(via
		(at 353.165918 -172.74032)
		(size 0.508)
		(drill 0.254)
		(layers "F.Cu" "B.Cu")
		(net "GND")
	)
	(via
		(at 284.736032 -268.735048)
		(size 0.4826)
		(drill 0.254)
		(layers "F.Cu" "B.Cu")
		(net "GND")
	)
	(via
		(at 107.85094 -272.466308)
		(size 0.4064)
		(drill 0.2032)
		(layers "F.Cu" "B.Cu")
		(net "GND")
	)
	(via
		(at 108.02112 -231.524302)
		(size 0.4064)
		(drill 0.2032)
		(layers "F.Cu" "B.Cu")
		(net "GND")
	)
	(via
		(at 83.111086 -237.194344)
		(size 0.4064)
		(drill 0.2032)
		(layers "F.Cu" "B.Cu")
		(net "GND")
	)
	(via
		(at 110.76686 -30.481778)
		(size 0.508)
		(drill 0.254)
		(layers "F.Cu" "B.Cu")
		(net "GND")
	)
	(via
		(at 87.280242 -373.30253)
		(size 0.508)
		(drill 0.254)
		(layers "F.Cu" "B.Cu")
		(net "GND")
	)
	(via
		(at 451.4723 -231.335072)
		(size 0.4826)
		(drill 0.254)
		(layers "F.Cu" "B.Cu")
		(net "GND")
	)
	(via
		(at 245.59387 -289.552126)
		(size 0.508)
		(drill 0.254)
		(layers "F.Cu" "B.Cu")
		(net "GND")
	)
	(via
		(at 447.931286 -63.078614)
		(size 0.508)
		(drill 0.254)
		(layers "F.Cu" "B.Cu")
		(net "GND")
	)
	(via
		(at 127.584708 -261.126224)
		(size 0.4064)
		(drill 0.2032)
		(layers "F.Cu" "B.Cu")
		(net "GND")
	)
	(via
		(at 93.185996 -34.329878)
		(size 0.508)
		(drill 0.254)
		(layers "F.Cu" "B.Cu")
		(net "GND")
	)
	(via
		(at 181.666896 -390.927082)
		(size 0.508)
		(drill 0.254)
		(layers "F.Cu" "B.Cu")
		(net "GND")
	)
	(via
		(at 273.092164 -214.335106)
		(size 0.4826)
		(drill 0.254)
		(layers "F.Cu" "B.Cu")
		(net "GND")
	)
	(via
		(at 96.571054 -293.52621)
		(size 0.4064)
		(drill 0.2032)
		(layers "F.Cu" "B.Cu")
		(net "GND")
	)
	(via
		(at 425.497498 -329.87869)
		(size 0.508)
		(drill 0.254)
		(layers "F.Cu" "B.Cu")
		(net "GND")
	)
	(via
		(at 345.451176 -280.566114)
		(size 0.4064)
		(drill 0.2032)
		(layers "F.Cu" "B.Cu")
		(net "GND")
	)
	(via
		(at 136.98474 -272.466308)
		(size 0.4064)
		(drill 0.2032)
		(layers "F.Cu" "B.Cu")
		(net "GND")
	)
	(via
		(at 194.604132 -234.73537)
		(size 0.4826)
		(drill 0.254)
		(layers "F.Cu" "B.Cu")
		(net "GND")
	)
	(via
		(at 424.168062 -9.424924)
		(size 0.508)
		(drill 0.254)
		(layers "F.Cu" "B.Cu")
		(net "GND")
	)
	(via
		(at 36.795964 -268.735302)
		(size 0.4826)
		(drill 0.254)
		(layers "F.Cu" "B.Cu")
		(net "GND")
	)
	(via
		(at 353.441 -270.036036)
		(size 0.4064)
		(drill 0.2032)
		(layers "F.Cu" "B.Cu")
		(net "GND")
	)
	(via
		(at 325.052944 -279.49017)
		(size 0.4064)
		(drill 0.2032)
		(layers "F.Cu" "B.Cu")
		(net "GND")
	)
	(via
		(at 264.96772 -138.944858)
		(size 0.508)
		(drill 0.254)
		(layers "F.Cu" "B.Cu")
		(net "GND")
	)
	(via
		(at 277.192232 -301.034958)
		(size 0.4826)
		(drill 0.254)
		(layers "F.Cu" "B.Cu")
		(net "GND")
	)
	(via
		(at 198.7042 -224.535238)
		(size 0.4826)
		(drill 0.254)
		(layers "F.Cu" "B.Cu")
		(net "GND")
	)
	(via
		(at 295.724072 -249.185176)
		(size 0.4826)
		(drill 0.254)
		(layers "F.Cu" "B.Cu")
		(net "GND")
	)
	(via
		(at 91.871038 -278.946356)
		(size 0.4064)
		(drill 0.2032)
		(layers "F.Cu" "B.Cu")
		(net "GND")
	)
	(via
		(at 388.384796 -250.154186)
		(size 0.4064)
		(drill 0.2032)
		(layers "F.Cu" "B.Cu")
		(net "GND")
	)
	(via
		(at 151.694642 -79.79283)
		(size 0.508)
		(drill 0.254)
		(layers "F.Cu" "B.Cu")
		(net "GND")
	)
	(via
		(at 130.40487 -274.08632)
		(size 0.4064)
		(drill 0.2032)
		(layers "F.Cu" "B.Cu")
		(net "GND")
	)
	(via
		(at 337.930998 -280.566114)
		(size 0.4064)
		(drill 0.2032)
		(layers "F.Cu" "B.Cu")
		(net "GND")
	)
	(via
		(at 194.604132 -317.185294)
		(size 0.4826)
		(drill 0.254)
		(layers "F.Cu" "B.Cu")
		(net "GND")
	)
	(via
		(at 122.884692 -288.666174)
		(size 0.4064)
		(drill 0.2032)
		(layers "F.Cu" "B.Cu")
		(net "GND")
	)
	(via
		(at 331.821028 -279.756108)
		(size 0.4064)
		(drill 0.2032)
		(layers "F.Cu" "B.Cu")
		(net "GND")
	)
	(via
		(at 421.8051 -376.75693)
		(size 0.508)
		(drill 0.254)
		(layers "F.Cu" "B.Cu")
		(net "GND")
	)
	(via
		(at 148.644356 -391.830814)
		(size 0.4064)
		(drill 0.2032)
		(layers "F.Cu" "B.Cu")
		(net "GND")
	)
	(via
		(at 234.61472 -340.23808)
		(size 0.508)
		(drill 0.254)
		(layers "F.Cu" "B.Cu")
		(net "GND")
	)
	(via
		(at 329.722226 -420.952168)
		(size 0.4064)
		(drill 0.2032)
		(layers "F.Cu" "B.Cu")
		(net "GND")
	)
	(via
		(at 73.937114 -331.75575)
		(size 0.508)
		(drill 0.254)
		(layers "F.Cu" "B.Cu")
		(net "GND")
	)
	(via
		(at 331.051154 -255.014222)
		(size 0.4064)
		(drill 0.2032)
		(layers "F.Cu" "B.Cu")
		(net "GND")
	)
	(via
		(at 73.283064 -39.89451)
		(size 0.508)
		(drill 0.254)
		(layers "F.Cu" "B.Cu")
		(net "GND")
	)
	(via
		(at 467.5378 -149.911054)
		(size 0.508)
		(drill 0.254)
		(layers "F.Cu" "B.Cu")
		(net "GND")
	)
	(via
		(at 306.216304 -391.23493)
		(size 0.4064)
		(drill 0.2032)
		(layers "F.Cu" "B.Cu")
		(net "GND")
	)
	(via
		(at 107.257342 -337.355434)
		(size 0.508)
		(drill 0.254)
		(layers "F.Cu" "B.Cu")
		(net "GND")
	)
	(via
		(at 94.488 -210.530948)
		(size 0.508)
		(drill 0.254)
		(layers "F.Cu" "B.Cu")
		(net "GND")
	)
	(via
		(at 60.578492 -386.449062)
		(size 0.4064)
		(drill 0.2032)
		(layers "F.Cu" "B.Cu")
		(net "GND")
	)
	(via
		(at 386.804916 -287.046162)
		(size 0.4064)
		(drill 0.2032)
		(layers "F.Cu" "B.Cu")
		(net "GND")
	)
	(via
		(at 415.11347 -419.046152)
		(size 0.4572)
		(drill 0.254)
		(layers "F.Cu" "B.Cu")
		(net "GND")
	)
	(via
		(at 395.20241 -421.586152)
		(size 0.4572)
		(drill 0.254)
		(layers "F.Cu" "B.Cu")
		(net "GND")
	)
	(via
		(at 168.527984 -272.98523)
		(size 0.4826)
		(drill 0.254)
		(layers "F.Cu" "B.Cu")
		(net "GND")
	)
	(via
		(at 343.101168 -271.656048)
		(size 0.4064)
		(drill 0.2032)
		(layers "F.Cu" "B.Cu")
		(net "GND")
	)
	(via
		(at 445.259968 -274.684998)
		(size 0.4826)
		(drill 0.254)
		(layers "F.Cu" "B.Cu")
		(net "GND")
	)
	(via
		(at 371.46484 -235.574078)
		(size 0.4064)
		(drill 0.2032)
		(layers "F.Cu" "B.Cu")
		(net "GND")
	)
	(via
		(at 424.315636 -424.217846)
		(size 0.508)
		(drill 0.254)
		(layers "F.Cu" "B.Cu")
		(net "GND")
	)
	(via
		(at 441.064396 -34.278062)
		(size 0.508)
		(drill 0.254)
		(layers "F.Cu" "B.Cu")
		(net "GND")
	)
	(via
		(at 300.105826 -347.282262)
		(size 0.49022)
		(drill 0.254)
		(layers "F.Cu" "B.Cu")
		(net "GND")
	)
	(via
		(at 126.05512 -33.386268)
		(size 0.508)
		(drill 0.254)
		(layers "F.Cu" "B.Cu")
		(net "GND")
	)
	(via
		(at 371.93474 -236.384084)
		(size 0.4064)
		(drill 0.2032)
		(layers "F.Cu" "B.Cu")
		(net "GND")
	)
	(via
		(at 47.784004 -273.835368)
		(size 0.4826)
		(drill 0.254)
		(layers "F.Cu" "B.Cu")
		(net "GND")
	)
	(via
		(at 118.184676 -274.08632)
		(size 0.4064)
		(drill 0.2032)
		(layers "F.Cu" "B.Cu")
		(net "GND")
	)
	(via
		(at 143.56461 -264.366248)
		(size 0.4064)
		(drill 0.2032)
		(layers "F.Cu" "B.Cu")
		(net "GND")
	)
	(via
		(at 36.795964 -235.585254)
		(size 0.4826)
		(drill 0.254)
		(layers "F.Cu" "B.Cu")
		(net "GND")
	)
	(via
		(at 293.943786 -344.781124)
		(size 0.49022)
		(drill 0.254)
		(layers "F.Cu" "B.Cu")
		(net "GND")
	)
	(via
		(at 36.641278 -19.13636)
		(size 0.508)
		(drill 0.254)
		(layers "F.Cu" "B.Cu")
		(net "GND")
	)
	(via
		(at 126.814834 -247.724422)
		(size 0.4064)
		(drill 0.2032)
		(layers "F.Cu" "B.Cu")
		(net "GND")
	)
	(via
		(at 344.677238 -420.318184)
		(size 0.4572)
		(drill 0.254)
		(layers "F.Cu" "B.Cu")
		(net "GND")
	)
	(via
		(at 284.736032 -253.435104)
		(size 0.4826)
		(drill 0.254)
		(layers "F.Cu" "B.Cu")
		(net "GND")
	)
	(via
		(at 365.18469 -280.566114)
		(size 0.4064)
		(drill 0.2032)
		(layers "F.Cu" "B.Cu")
		(net "GND")
	)
	(via
		(at 120.56237 -384.617722)
		(size 0.4064)
		(drill 0.2032)
		(layers "F.Cu" "B.Cu")
		(net "GND")
	)
	(via
		(at 133.864858 -227.474526)
		(size 0.4064)
		(drill 0.2032)
		(layers "F.Cu" "B.Cu")
		(net "GND")
	)
	(via
		(at 405.64816 -12.37488)
		(size 0.508)
		(drill 0.254)
		(layers "F.Cu" "B.Cu")
		(net "GND")
	)
	(via
		(at 90.461084 -273.276314)
		(size 0.4064)
		(drill 0.2032)
		(layers "F.Cu" "B.Cu")
		(net "GND")
	)
	(via
		(at 74.892916 -410.664152)
		(size 0.4572)
		(drill 0.254)
		(layers "F.Cu" "B.Cu")
		(net "GND")
	)
	(via
		(at 149.490176 -384.617722)
		(size 0.4064)
		(drill 0.2032)
		(layers "F.Cu" "B.Cu")
		(net "GND")
	)
	(via
		(at 349.976948 -123.330208)
		(size 0.508)
		(drill 0.254)
		(layers "F.Cu" "B.Cu")
		(net "GND")
	)
	(via
		(at 373.644922 -288.66592)
		(size 0.4064)
		(drill 0.2032)
		(layers "F.Cu" "B.Cu")
		(net "GND")
	)
	(via
		(at 165.812216 -312.935366)
		(size 0.4826)
		(drill 0.254)
		(layers "F.Cu" "B.Cu")
		(net "GND")
	)
	(via
		(at 407.349706 -437.49976)
		(size 0.4572)
		(drill 0.2032)
		(layers "F.Cu" "B.Cu")
		(net "GND")
	)
	(via
		(at 446.644268 -272.984976)
		(size 0.4826)
		(drill 0.254)
		(layers "F.Cu" "B.Cu")
		(net "GND")
	)
	(via
		(at 306.298346 -420.952168)
		(size 0.4064)
		(drill 0.2032)
		(layers "F.Cu" "B.Cu")
		(net "GND")
	)
	(via
		(at 386.804916 -274.086066)
		(size 0.4064)
		(drill 0.2032)
		(layers "F.Cu" "B.Cu")
		(net "GND")
	)
	(via
		(at 326.667876 -72.884792)
		(size 0.508)
		(drill 0.254)
		(layers "F.Cu" "B.Cu")
		(net "GND")
	)
	(via
		(at 82.249772 -438.499758)
		(size 0.4572)
		(drill 0.2032)
		(layers "F.Cu" "B.Cu")
		(net "GND")
	)
	(via
		(at 132.404866 -157.681168)
		(size 0.49022)
		(drill 0.254)
		(layers "F.Cu" "B.Cu")
		(net "GND")
	)
	(via
		(at 363.774736 -268.416024)
		(size 0.4064)
		(drill 0.2032)
		(layers "F.Cu" "B.Cu")
		(net "GND")
	)
	(via
		(at 164.427916 -208.38541)
		(size 0.4826)
		(drill 0.254)
		(layers "F.Cu" "B.Cu")
		(net "GND")
	)
	(via
		(at 382.1049 -278.946102)
		(size 0.4064)
		(drill 0.2032)
		(layers "F.Cu" "B.Cu")
		(net "GND")
	)
	(via
		(at 326.297798 -413.480504)
		(size 0.4572)
		(drill 0.254)
		(layers "F.Cu" "B.Cu")
		(net "GND")
	)
	(via
		(at 78.41107 -256.634488)
		(size 0.4064)
		(drill 0.2032)
		(layers "F.Cu" "B.Cu")
		(net "GND")
	)
	(via
		(at 321.21348 -331.090524)
		(size 0.508)
		(drill 0.254)
		(layers "F.Cu" "B.Cu")
		(net "GND")
	)
	(via
		(at 59.816746 -393.927838)
		(size 0.4572)
		(drill 0.254)
		(layers "F.Cu" "B.Cu")
		(net "GND")
	)
	(via
		(at 104.465882 -375.917968)
		(size 0.508)
		(drill 0.254)
		(layers "F.Cu" "B.Cu")
		(net "GND")
	)
	(via
		(at 416.468052 -265.335004)
		(size 0.4826)
		(drill 0.254)
		(layers "F.Cu" "B.Cu")
		(net "GND")
	)
	(via
		(at 67.249802 -430.299622)
		(size 0.4572)
		(drill 0.2032)
		(layers "F.Cu" "B.Cu")
		(net "GND")
	)
	(via
		(at 347.740478 -413.480504)
		(size 0.4572)
		(drill 0.254)
		(layers "F.Cu" "B.Cu")
		(net "GND")
	)
	(via
		(at 337.930998 -267.606018)
		(size 0.4064)
		(drill 0.2032)
		(layers "F.Cu" "B.Cu")
		(net "GND")
	)
	(via
		(at 93.631004 -410.030168)
		(size 0.4064)
		(drill 0.2032)
		(layers "F.Cu" "B.Cu")
		(net "GND")
	)
	(via
		(at 149.923754 -407.638504)
		(size 0.4572)
		(drill 0.254)
		(layers "F.Cu" "B.Cu")
		(net "GND")
	)
	(via
		(at 246.105426 -282.391358)
		(size 0.508)
		(drill 0.254)
		(layers "F.Cu" "B.Cu")
		(net "GND")
	)
	(via
		(at 265.54811 -298.485052)
		(size 0.4826)
		(drill 0.254)
		(layers "F.Cu" "B.Cu")
		(net "GND")
	)
	(via
		(at 110.949994 -186.981338)
		(size 0.508)
		(drill 0.254)
		(layers "F.Cu" "B.Cu")
		(net "GND")
	)
	(via
		(at 95.1611 -263.556242)
		(size 0.4064)
		(drill 0.2032)
		(layers "F.Cu" "B.Cu")
		(net "GND")
	)
	(via
		(at 146.742912 -241.510312)
		(size 0.4064)
		(drill 0.2032)
		(layers "F.Cu" "B.Cu")
		(net "GND")
	)
	(via
		(at 96.715834 -133.325362)
		(size 0.508)
		(drill 0.254)
		(layers "F.Cu" "B.Cu")
		(net "GND")
	)
	(via
		(at 303.235106 -412.84652)
		(size 0.4064)
		(drill 0.2032)
		(layers "F.Cu" "B.Cu")
		(net "GND")
	)
	(via
		(at 139.997434 -296.590212)
		(size 0.508)
		(drill 0.254)
		(layers "F.Cu" "B.Cu")
		(net "GND")
	)
	(via
		(at 277.192232 -278.93518)
		(size 0.4826)
		(drill 0.254)
		(layers "F.Cu" "B.Cu")
		(net "GND")
	)
	(via
		(at 446.644268 -246.635016)
		(size 0.4826)
		(drill 0.254)
		(layers "F.Cu" "B.Cu")
		(net "GND")
	)
	(via
		(at 298.43984 -211.784946)
		(size 0.4826)
		(drill 0.254)
		(layers "F.Cu" "B.Cu")
		(net "GND")
	)
	(via
		(at 55.328058 -204.985366)
		(size 0.4826)
		(drill 0.254)
		(layers "F.Cu" "B.Cu")
		(net "GND")
	)
	(via
		(at 281.759406 -339.789008)
		(size 0.508)
		(drill 0.254)
		(layers "F.Cu" "B.Cu")
		(net "GND")
	)
	(via
		(at 26.536396 -228.78542)
		(size 0.4826)
		(drill 0.254)
		(layers "F.Cu" "B.Cu")
		(net "GND")
	)
	(via
		(at 237.312708 -146.892772)
		(size 0.508)
		(drill 0.254)
		(layers "F.Cu" "B.Cu")
		(net "GND")
	)
	(via
		(at 61.791342 -390.160002)
		(size 0.4064)
		(drill 0.2032)
		(layers "F.Cu" "B.Cu")
		(net "GND")
	)
	(via
		(at 48.855376 -411.936184)
		(size 0.4572)
		(drill 0.254)
		(layers "F.Cu" "B.Cu")
		(net "GND")
	)
	(via
		(at 369.884706 -275.706078)
		(size 0.4064)
		(drill 0.2032)
		(layers "F.Cu" "B.Cu")
		(net "GND")
	)
	(via
		(at 163.819078 -390.160002)
		(size 0.4064)
		(drill 0.2032)
		(layers "F.Cu" "B.Cu")
		(net "GND")
	)
	(via
		(at 393.084812 -225.85426)
		(size 0.4064)
		(drill 0.2032)
		(layers "F.Cu" "B.Cu")
		(net "GND")
	)
	(via
		(at 90.249756 -437.34736)
		(size 0.4572)
		(drill 0.2032)
		(layers "F.Cu" "B.Cu")
		(net "GND")
	)
	(via
		(at 168.527984 -250.035314)
		(size 0.4826)
		(drill 0.254)
		(layers "F.Cu" "B.Cu")
		(net "GND")
	)
	(via
		(at 223.829118 -279.643078)
		(size 0.508)
		(drill 0.254)
		(layers "F.Cu" "B.Cu")
		(net "GND")
	)
	(via
		(at 300.053756 -379.22073)
		(size 0.508)
		(drill 0.254)
		(layers "F.Cu" "B.Cu")
		(net "GND")
	)
	(via
		(at 160.372298 -409.396184)
		(size 0.4572)
		(drill 0.254)
		(layers "F.Cu" "B.Cu")
		(net "GND")
	)
	(via
		(at 328.701146 -223.424242)
		(size 0.4064)
		(drill 0.2032)
		(layers "F.Cu" "B.Cu")
		(net "GND")
	)
	(via
		(at 269.741396 -439.90768)
		(size 0.508)
		(drill 0.254)
		(layers "F.Cu" "B.Cu")
		(net "GND")
	)
	(via
		(at 119.362474 -384.617722)
		(size 0.4064)
		(drill 0.2032)
		(layers "F.Cu" "B.Cu")
		(net "GND")
	)
	(via
		(at 409.44419 -391.23493)
		(size 0.4064)
		(drill 0.2032)
		(layers "F.Cu" "B.Cu")
		(net "GND")
	)
	(via
		(at 131.98475 -248.534428)
		(size 0.4064)
		(drill 0.2032)
		(layers "F.Cu" "B.Cu")
		(net "GND")
	)
	(via
		(at 382.208278 -136.494012)
		(size 0.508)
		(drill 0.254)
		(layers "F.Cu" "B.Cu")
		(net "GND")
	)
	(via
		(at 338.401152 -263.555988)
		(size 0.4064)
		(drill 0.2032)
		(layers "F.Cu" "B.Cu")
		(net "GND")
	)
	(via
		(at 305.127914 -414.752536)
		(size 0.4572)
		(drill 0.254)
		(layers "F.Cu" "B.Cu")
		(net "GND")
	)
	(via
		(at 127.114808 -286.23641)
		(size 0.4064)
		(drill 0.2032)
		(layers "F.Cu" "B.Cu")
		(net "GND")
	)
	(via
		(at 114.83086 -33.529778)
		(size 0.508)
		(drill 0.254)
		(layers "F.Cu" "B.Cu")
		(net "GND")
	)
	(via
		(at 329.249532 -438.499758)
		(size 0.4572)
		(drill 0.2032)
		(layers "F.Cu" "B.Cu")
		(net "GND")
	)
	(via
		(at 356.538022 -261.32282)
		(size 0.4826)
		(drill 0.254)
		(layers "F.Cu" "B.Cu")
		(net "GND")
	)
	(via
		(at 41.62425 -219.435426)
		(size 0.4826)
		(drill 0.254)
		(layers "F.Cu" "B.Cu")
		(net "GND")
	)
	(via
		(at 32.695896 -197.335394)
		(size 0.4826)
		(drill 0.254)
		(layers "F.Cu" "B.Cu")
		(net "GND")
	)
	(via
		(at 47.784004 -197.335394)
		(size 0.4826)
		(drill 0.254)
		(layers "F.Cu" "B.Cu")
		(net "GND")
	)
	(via
		(at 343.143586 -340.166198)
		(size 0.508)
		(drill 0.254)
		(layers "F.Cu" "B.Cu")
		(net "GND")
	)
	(via
		(at 102.852982 -341.927688)
		(size 0.49022)
		(drill 0.254)
		(layers "F.Cu" "B.Cu")
		(net "GND")
	)
	(via
		(at 451.4723 -221.985078)
		(size 0.4826)
		(drill 0.254)
		(layers "F.Cu" "B.Cu")
		(net "GND")
	)
	(via
		(at 449.43268 -4.954524)
		(size 0.508)
		(drill 0.254)
		(layers "F.Cu" "B.Cu")
		(net "GND")
	)
	(via
		(at 297.430444 -385.87426)
		(size 0.508)
		(drill 0.254)
		(layers "F.Cu" "B.Cu")
		(net "GND")
	)
	(via
		(at 47.596552 -403.830536)
		(size 0.4572)
		(drill 0.254)
		(layers "F.Cu" "B.Cu")
		(net "GND")
	)
	(via
		(at 15.5575 -100.620068)
		(size 0.508)
		(drill 0.254)
		(layers "F.Cu" "B.Cu")
		(net "GND")
	)
	(via
		(at 413.044132 -400.212814)
		(size 0.4064)
		(drill 0.2032)
		(layers "F.Cu" "B.Cu")
		(net "GND")
	)
	(via
		(at 132.284724 -280.566368)
		(size 0.4064)
		(drill 0.2032)
		(layers "F.Cu" "B.Cu")
		(net "GND")
	)
	(via
		(at 16.490442 -304.860452)
		(size 0.4826)
		(drill 0.254)
		(layers "F.Cu" "B.Cu")
		(net "GND")
	)
	(via
		(at 256.442972 -100.61575)
		(size 0.508)
		(drill 0.254)
		(layers "F.Cu" "B.Cu")
		(net "GND")
	)
	(via
		(at 136.225026 -407.00452)
		(size 0.4064)
		(drill 0.2032)
		(layers "F.Cu" "B.Cu")
		(net "GND")
	)
	(via
		(at 101.27107 -261.126224)
		(size 0.4064)
		(drill 0.2032)
		(layers "F.Cu" "B.Cu")
		(net "GND")
	)
	(via
		(at 58.310526 -219.860368)
		(size 0.4826)
		(drill 0.254)
		(layers "F.Cu" "B.Cu")
		(net "GND")
	)
	(via
		(at 174.687738 -211.7852)
		(size 0.4826)
		(drill 0.254)
		(layers "F.Cu" "B.Cu")
		(net "GND")
	)
	(via
		(at 59.249818 -436.347362)
		(size 0.4572)
		(drill 0.2032)
		(layers "F.Cu" "B.Cu")
		(net "GND")
	)
	(via
		(at 36.795964 -282.335224)
		(size 0.4826)
		(drill 0.254)
		(layers "F.Cu" "B.Cu")
		(net "GND")
	)
	(via
		(at 327.937876 -387.703568)
		(size 0.508)
		(drill 0.254)
		(layers "F.Cu" "B.Cu")
		(net "GND")
	)
	(via
		(at 34.080196 -287.43529)
		(size 0.4826)
		(drill 0.254)
		(layers "F.Cu" "B.Cu")
		(net "GND")
	)
	(via
		(at 105.500932 -291.096192)
		(size 0.4064)
		(drill 0.2032)
		(layers "F.Cu" "B.Cu")
		(net "GND")
	)
	(via
		(at 59.912758 -344.781886)
		(size 0.49022)
		(drill 0.254)
		(layers "F.Cu" "B.Cu")
		(net "GND")
	)
	(via
		(at 392.349482 -434.899562)
		(size 0.4572)
		(drill 0.2032)
		(layers "F.Cu" "B.Cu")
		(net "GND")
	)
	(via
		(at 426.851826 -438.61355)
		(size 0.508)
		(drill 0.254)
		(layers "F.Cu" "B.Cu")
		(net "GND")
	)
	(via
		(at 85.887052 -410.664152)
		(size 0.4572)
		(drill 0.254)
		(layers "F.Cu" "B.Cu")
		(net "GND")
	)
	(via
		(at 65.085214 -344.772234)
		(size 0.508)
		(drill 0.254)
		(layers "F.Cu" "B.Cu")
		(net "GND")
	)
	(via
		(at 423.18178 -17.61236)
		(size 0.508)
		(drill 0.254)
		(layers "F.Cu" "B.Cu")
		(net "GND")
	)
	(via
		(at 135.574786 -268.416278)
		(size 0.4064)
		(drill 0.2032)
		(layers "F.Cu" "B.Cu")
		(net "GND")
	)
	(via
		(at 361.124754 -227.474272)
		(size 0.4064)
		(drill 0.2032)
		(layers "F.Cu" "B.Cu")
		(net "GND")
	)
	(via
		(at 361.424728 -274.086066)
		(size 0.4064)
		(drill 0.2032)
		(layers "F.Cu" "B.Cu")
		(net "GND")
	)
	(via
		(at 187.060078 -250.885198)
		(size 0.4826)
		(drill 0.254)
		(layers "F.Cu" "B.Cu")
		(net "GND")
	)
	(via
		(at 313.779154 -441.227718)
		(size 0.508)
		(drill 0.254)
		(layers "F.Cu" "B.Cu")
		(net "GND")
	)
	(via
		(at 35.411664 -211.7852)
		(size 0.4826)
		(drill 0.254)
		(layers "F.Cu" "B.Cu")
		(net "GND")
	)
	(via
		(at 432.505358 -437.792622)
		(size 0.508)
		(drill 0.254)
		(layers "F.Cu" "B.Cu")
		(net "GND")
	)
	(via
		(at 144.967706 -412.570168)
		(size 0.4064)
		(drill 0.2032)
		(layers "F.Cu" "B.Cu")
		(net "GND")
	)
	(via
		(at 90.790268 -384.617722)
		(size 0.4064)
		(drill 0.2032)
		(layers "F.Cu" "B.Cu")
		(net "GND")
	)
	(via
		(at 235.205016 -241.989864)
		(size 0.4826)
		(drill 0.254)
		(layers "F.Cu" "B.Cu")
		(net "GND")
	)
	(via
		(at 436.855108 -346.305886)
		(size 0.508)
		(drill 0.254)
		(layers "F.Cu" "B.Cu")
		(net "GND")
	)
	(via
		(at 127.284734 -242.05438)
		(size 0.4064)
		(drill 0.2032)
		(layers "F.Cu" "B.Cu")
		(net "GND")
	)
	(via
		(at 281.74061 -344.77706)
		(size 0.49022)
		(drill 0.254)
		(layers "F.Cu" "B.Cu")
		(net "GND")
	)
	(via
		(at 67.249802 -435.0512)
		(size 0.4572)
		(drill 0.2032)
		(layers "F.Cu" "B.Cu")
		(net "GND")
	)
	(via
		(at 454.188068 -288.285174)
		(size 0.4826)
		(drill 0.254)
		(layers "F.Cu" "B.Cu")
		(net "GND")
	)
	(via
		(at 97.981008 -261.93623)
		(size 0.4064)
		(drill 0.2032)
		(layers "F.Cu" "B.Cu")
		(net "GND")
	)
	(via
		(at 84.99094 -255.014476)
		(size 0.4064)
		(drill 0.2032)
		(layers "F.Cu" "B.Cu")
		(net "GND")
	)
	(via
		(at 337.930998 -261.12597)
		(size 0.4064)
		(drill 0.2032)
		(layers "F.Cu" "B.Cu")
		(net "GND")
	)
	(via
		(at 422.627806 -277.235158)
		(size 0.4826)
		(drill 0.254)
		(layers "F.Cu" "B.Cu")
		(net "GND")
	)
	(via
		(at 352.335338 -417.778184)
		(size 0.4572)
		(drill 0.254)
		(layers "F.Cu" "B.Cu")
		(net "GND")
	)
	(via
		(at 294.606472 -220.709998)
		(size 0.4826)
		(drill 0.254)
		(layers "F.Cu" "B.Cu")
		(net "GND")
	)
	(via
		(at 139.857226 -388.77113)
		(size 0.508)
		(drill 0.254)
		(layers "F.Cu" "B.Cu")
		(net "GND")
	)
	(via
		(at 326.125332 -391.834116)
		(size 0.508)
		(drill 0.254)
		(layers "F.Cu" "B.Cu")
		(net "GND")
	)
	(via
		(at 197.3199 -314.635388)
		(size 0.4826)
		(drill 0.254)
		(layers "F.Cu" "B.Cu")
		(net "GND")
	)
	(via
		(at 347.97111 -246.914162)
		(size 0.4064)
		(drill 0.2032)
		(layers "F.Cu" "B.Cu")
		(net "GND")
	)
	(via
		(at 191.160146 -267.03528)
		(size 0.4826)
		(drill 0.254)
		(layers "F.Cu" "B.Cu")
		(net "GND")
	)
	(via
		(at 11.960606 -383.608072)
		(size 0.508)
		(drill 0.254)
		(layers "F.Cu" "B.Cu")
		(net "GND")
	)
	(via
		(at 375.36247 -392.999722)
		(size 0.4064)
		(drill 0.2032)
		(layers "F.Cu" "B.Cu")
		(net "GND")
	)
	(via
		(at 187.060078 -199.035416)
		(size 0.4826)
		(drill 0.254)
		(layers "F.Cu" "B.Cu")
		(net "GND")
	)
	(via
		(at 358.141016 -284.616144)
		(size 0.4064)
		(drill 0.2032)
		(layers "F.Cu" "B.Cu")
		(net "GND")
	)
	(via
		(at 346.39123 -282.186126)
		(size 0.4064)
		(drill 0.2032)
		(layers "F.Cu" "B.Cu")
		(net "GND")
	)
	(via
		(at 139.334748 -294.336216)
		(size 0.4064)
		(drill 0.2032)
		(layers "F.Cu" "B.Cu")
		(net "GND")
	)
	(via
		(at 77.112876 -273.010376)
		(size 0.4064)
		(drill 0.2032)
		(layers "F.Cu" "B.Cu")
		(net "GND")
	)
	(via
		(at 191.160146 -265.335258)
		(size 0.4826)
		(drill 0.254)
		(layers "F.Cu" "B.Cu")
		(net "GND")
	)
	(via
		(at 206.248 -282.335224)
		(size 0.4826)
		(drill 0.254)
		(layers "F.Cu" "B.Cu")
		(net "GND")
	)
	(via
		(at 198.7042 -310.385206)
		(size 0.4826)
		(drill 0.254)
		(layers "F.Cu" "B.Cu")
		(net "GND")
	)
	(via
		(at 304.809398 -41.906698)
		(size 0.508)
		(drill 0.254)
		(layers "F.Cu" "B.Cu")
		(net "GND")
	)
	(via
		(at 44.12234 -112.09782)
		(size 0.508)
		(drill 0.254)
		(layers "F.Cu" "B.Cu")
		(net "GND")
	)
	(via
		(at 450.088 -223.6851)
		(size 0.4826)
		(drill 0.254)
		(layers "F.Cu" "B.Cu")
		(net "GND")
	)
	(via
		(at 288.180018 -208.385156)
		(size 0.4826)
		(drill 0.254)
		(layers "F.Cu" "B.Cu")
		(net "GND")
	)
	(via
		(at 130.574796 -226.66452)
		(size 0.4064)
		(drill 0.2032)
		(layers "F.Cu" "B.Cu")
		(net "GND")
	)
	(via
		(at 427.47311 -0.762254)
		(size 0.508)
		(drill 0.254)
		(layers "F.Cu" "B.Cu")
		(net "GND")
	)
	(via
		(at 238.380778 -289.012122)
		(size 0.508)
		(drill 0.254)
		(layers "F.Cu" "B.Cu")
		(net "GND")
	)
	(via
		(at 334.249522 -431.29962)
		(size 0.4572)
		(drill 0.2032)
		(layers "F.Cu" "B.Cu")
		(net "GND")
	)
	(via
		(at 115.064794 -250.15444)
		(size 0.4064)
		(drill 0.2032)
		(layers "F.Cu" "B.Cu")
		(net "GND")
	)
	(via
		(at 116.004848 -245.294404)
		(size 0.4064)
		(drill 0.2032)
		(layers "F.Cu" "B.Cu")
		(net "GND")
	)
	(via
		(at 154.380184 -373.30253)
		(size 0.508)
		(drill 0.254)
		(layers "F.Cu" "B.Cu")
		(net "GND")
	)
	(via
		(at 330.229464 -332.404212)
		(size 0.508)
		(drill 0.254)
		(layers "F.Cu" "B.Cu")
		(net "GND")
	)
	(via
		(at 332.249526 -437.49976)
		(size 0.4572)
		(drill 0.2032)
		(layers "F.Cu" "B.Cu")
		(net "GND")
	)
	(via
		(at 326.351138 -245.29415)
		(size 0.4064)
		(drill 0.2032)
		(layers "F.Cu" "B.Cu")
		(net "GND")
	)
	(via
		(at 162.640518 -99.33559)
		(size 0.508)
		(drill 0.254)
		(layers "F.Cu" "B.Cu")
		(net "GND")
	)
	(via
		(at 412.05023 -414.752536)
		(size 0.4572)
		(drill 0.254)
		(layers "F.Cu" "B.Cu")
		(net "GND")
	)
	(via
		(at 414.510474 -164.917882)
		(size 0.49022)
		(drill 0.254)
		(layers "F.Cu" "B.Cu")
		(net "GND")
	)
	(via
		(at 188.444378 -312.935366)
		(size 0.4826)
		(drill 0.254)
		(layers "F.Cu" "B.Cu")
		(net "GND")
	)
	(via
		(at 69.647054 -147.187412)
		(size 0.508)
		(drill 0.254)
		(layers "F.Cu" "B.Cu")
		(net "GND")
	)
	(via
		(at 379.924818 -237.19409)
		(size 0.4064)
		(drill 0.2032)
		(layers "F.Cu" "B.Cu")
		(net "GND")
	)
	(via
		(at 82.465164 -410.030168)
		(size 0.4064)
		(drill 0.2032)
		(layers "F.Cu" "B.Cu")
		(net "GND")
	)
	(via
		(at 277.120604 -419.869874)
		(size 0.508)
		(drill 0.254)
		(layers "F.Cu" "B.Cu")
		(net "GND")
	)
	(via
		(at 452.803768 -274.684998)
		(size 0.4826)
		(drill 0.254)
		(layers "F.Cu" "B.Cu")
		(net "GND")
	)
	(via
		(at 310.752236 -383.00533)
		(size 0.508)
		(drill 0.254)
		(layers "F.Cu" "B.Cu")
		(net "GND")
	)
	(via
		(at 419.912038 -262.785098)
		(size 0.4826)
		(drill 0.254)
		(layers "F.Cu" "B.Cu")
		(net "GND")
	)
	(via
		(at 315.24956 -426.69968)
		(size 0.4572)
		(drill 0.2032)
		(layers "F.Cu" "B.Cu")
		(net "GND")
	)
	(via
		(at 184.733692 -219.860368)
		(size 0.4826)
		(drill 0.254)
		(layers "F.Cu" "B.Cu")
		(net "GND")
	)
	(via
		(at 419.401498 -331.85989)
		(size 0.508)
		(drill 0.254)
		(layers "F.Cu" "B.Cu")
		(net "GND")
	)
	(via
		(at 447.891154 -441.227718)
		(size 0.508)
		(drill 0.254)
		(layers "F.Cu" "B.Cu")
		(net "GND")
	)
	(via
		(at 370.82476 -267.606018)
		(size 0.4064)
		(drill 0.2032)
		(layers "F.Cu" "B.Cu")
		(net "GND")
	)
	(via
		(at 349.189802 -392.999722)
		(size 0.4064)
		(drill 0.2032)
		(layers "F.Cu" "B.Cu")
		(net "GND")
	)
	(via
		(at 137.45464 -284.616398)
		(size 0.4064)
		(drill 0.2032)
		(layers "F.Cu" "B.Cu")
		(net "GND")
	)
	(via
		(at 355.791008 -265.986006)
		(size 0.4064)
		(drill 0.2032)
		(layers "F.Cu" "B.Cu")
		(net "GND")
	)
	(via
		(at 454.188068 -207.535018)
		(size 0.4826)
		(drill 0.254)
		(layers "F.Cu" "B.Cu")
		(net "GND")
	)
	(via
		(at 295.724072 -283.185108)
		(size 0.4826)
		(drill 0.254)
		(layers "F.Cu" "B.Cu")
		(net "GND")
	)
	(via
		(at 449.535804 -396.889986)
		(size 0.508)
		(drill 0.254)
		(layers "F.Cu" "B.Cu")
		(net "GND")
	)
	(via
		(at 32.325056 -403.498304)
		(size 0.508)
		(drill 0.254)
		(layers "F.Cu" "B.Cu")
		(net "GND")
	)
	(via
		(at 354.098098 -171.431204)
		(size 0.49022)
		(drill 0.254)
		(layers "F.Cu" "B.Cu")
		(net "GND")
	)
	(via
		(at 430.40046 -192.21831)
		(size 0.4826)
		(drill 0.254)
		(layers "F.Cu" "B.Cu")
		(net "GND")
	)
	(via
		(at 407.946098 -396.710662)
		(size 0.4064)
		(drill 0.2032)
		(layers "F.Cu" "B.Cu")
		(net "GND")
	)
	(via
		(at 122.354594 -410.664152)
		(size 0.4572)
		(drill 0.254)
		(layers "F.Cu" "B.Cu")
		(net "GND")
	)
	(via
		(at 100.971096 -235.574332)
		(size 0.4064)
		(drill 0.2032)
		(layers "F.Cu" "B.Cu")
		(net "GND")
	)
	(via
		(at 446.750186 -63.892176)
		(size 0.508)
		(drill 0.254)
		(layers "F.Cu" "B.Cu")
		(net "GND")
	)
	(via
		(at 344.950034 -414.752536)
		(size 0.4572)
		(drill 0.254)
		(layers "F.Cu" "B.Cu")
		(net "GND")
	)
	(via
		(at 347.50121 -247.724168)
		(size 0.4064)
		(drill 0.2032)
		(layers "F.Cu" "B.Cu")
		(net "GND")
	)
	(via
		(at 467.5378 -138.735054)
		(size 0.508)
		(drill 0.254)
		(layers "F.Cu" "B.Cu")
		(net "GND")
	)
	(via
		(at 90.249756 -433.747164)
		(size 0.4572)
		(drill 0.2032)
		(layers "F.Cu" "B.Cu")
		(net "GND")
	)
	(via
		(at 140.744702 -277.326344)
		(size 0.4064)
		(drill 0.2032)
		(layers "F.Cu" "B.Cu")
		(net "GND")
	)
	(via
		(at 274.476464 -294.235124)
		(size 0.4826)
		(drill 0.254)
		(layers "F.Cu" "B.Cu")
		(net "GND")
	)
	(via
		(at 340.075266 -340.53526)
		(size 0.508)
		(drill 0.254)
		(layers "F.Cu" "B.Cu")
		(net "GND")
	)
	(via
		(at 306.250594 -219.860114)
		(size 0.4826)
		(drill 0.254)
		(layers "F.Cu" "B.Cu")
		(net "GND")
	)
	(via
		(at 85.290914 -278.946356)
		(size 0.4064)
		(drill 0.2032)
		(layers "F.Cu" "B.Cu")
		(net "GND")
	)
	(via
		(at 421.029638 -239.41024)
		(size 0.4826)
		(drill 0.254)
		(layers "F.Cu" "B.Cu")
		(net "GND")
	)
	(via
		(at 70.570852 -410.664152)
		(size 0.4572)
		(drill 0.254)
		(layers "F.Cu" "B.Cu")
		(net "GND")
	)
	(via
		(at 76.249784 -433.899564)
		(size 0.4572)
		(drill 0.2032)
		(layers "F.Cu" "B.Cu")
		(net "GND")
	)
	(via
		(at 132.349748 -427.699678)
		(size 0.4572)
		(drill 0.2032)
		(layers "F.Cu" "B.Cu")
		(net "GND")
	)
	(via
		(at 51.884072 -216.885266)
		(size 0.4826)
		(drill 0.254)
		(layers "F.Cu" "B.Cu")
		(net "GND")
	)
	(via
		(at 375.054876 -263.555988)
		(size 0.4064)
		(drill 0.2032)
		(layers "F.Cu" "B.Cu")
		(net "GND")
	)
	(via
		(at 2.76225 -400.741134)
		(size 0.508)
		(drill 0.254)
		(layers "F.Cu" "B.Cu")
		(net "GND")
	)
	(via
		(at 403.349714 -438.651396)
		(size 0.4572)
		(drill 0.2032)
		(layers "F.Cu" "B.Cu")
		(net "GND")
	)
	(via
		(at 384.624834 -229.094284)
		(size 0.4064)
		(drill 0.2032)
		(layers "F.Cu" "B.Cu")
		(net "GND")
	)
	(via
		(at 126.814834 -233.144314)
		(size 0.4064)
		(drill 0.2032)
		(layers "F.Cu" "B.Cu")
		(net "GND")
	)
	(via
		(at 415.48304 -377.41733)
		(size 0.508)
		(drill 0.254)
		(layers "F.Cu" "B.Cu")
		(net "GND")
	)
	(via
		(at 446.644268 -253.435104)
		(size 0.4826)
		(drill 0.254)
		(layers "F.Cu" "B.Cu")
		(net "GND")
	)
	(via
		(at 80.291178 -256.634488)
		(size 0.4064)
		(drill 0.2032)
		(layers "F.Cu" "B.Cu")
		(net "GND")
	)
	(via
		(at 399.79727 -417.778184)
		(size 0.4572)
		(drill 0.254)
		(layers "F.Cu" "B.Cu")
		(net "GND")
	)
	(via
		(at 156.050234 -406.370536)
		(size 0.4572)
		(drill 0.254)
		(layers "F.Cu" "B.Cu")
		(net "GND")
	)
	(via
		(at 335.11109 -287.045908)
		(size 0.4064)
		(drill 0.2032)
		(layers "F.Cu" "B.Cu")
		(net "GND")
	)
	(via
		(at 454.188068 -232.184956)
		(size 0.4826)
		(drill 0.254)
		(layers "F.Cu" "B.Cu")
		(net "GND")
	)
	(via
		(at 320.963036 -378.07773)
		(size 0.508)
		(drill 0.254)
		(layers "F.Cu" "B.Cu")
		(net "GND")
	)
	(via
		(at 8.447278 -137.25398)
		(size 0.508)
		(drill 0.254)
		(layers "F.Cu" "B.Cu")
		(net "GND")
	)
	(via
		(at 47.460154 -373.96293)
		(size 0.508)
		(drill 0.254)
		(layers "F.Cu" "B.Cu")
		(net "GND")
	)
	(via
		(at 128.174496 -373.96293)
		(size 0.508)
		(drill 0.254)
		(layers "F.Cu" "B.Cu")
		(net "GND")
	)
	(via
		(at 183.616092 -207.535272)
		(size 0.4826)
		(drill 0.254)
		(layers "F.Cu" "B.Cu")
		(net "GND")
	)
	(via
		(at 393.084812 -242.054126)
		(size 0.4064)
		(drill 0.2032)
		(layers "F.Cu" "B.Cu")
		(net "GND")
	)
	(via
		(at 10.16 -82.169)
		(size 0.508)
		(drill 0.254)
		(layers "F.Cu" "B.Cu")
		(net "GND")
	)
	(via
		(at 167.143684 -314.635388)
		(size 0.4826)
		(drill 0.254)
		(layers "F.Cu" "B.Cu")
		(net "GND")
	)
	(via
		(at 445.360552 -7.215124)
		(size 0.508)
		(drill 0.254)
		(layers "F.Cu" "B.Cu")
		(net "GND")
	)
	(via
		(at 16.124174 -387.704076)
		(size 0.49022)
		(drill 0.254)
		(layers "F.Cu" "B.Cu")
		(net "GND")
	)
	(via
		(at 333.955898 -419.046152)
		(size 0.4572)
		(drill 0.254)
		(layers "F.Cu" "B.Cu")
		(net "GND")
	)
	(via
		(at 340.718902 -398.542002)
		(size 0.4064)
		(drill 0.2032)
		(layers "F.Cu" "B.Cu")
		(net "GND")
	)
	(via
		(at 204.8637 -227.935282)
		(size 0.4826)
		(drill 0.254)
		(layers "F.Cu" "B.Cu")
		(net "GND")
	)
	(via
		(at 31.415482 -5.597398)
		(size 0.508)
		(drill 0.254)
		(layers "F.Cu" "B.Cu")
		(net "GND")
	)
	(via
		(at 98.150934 -225.854514)
		(size 0.4064)
		(drill 0.2032)
		(layers "F.Cu" "B.Cu")
		(net "GND")
	)
	(via
		(at 269.648178 -216.885012)
		(size 0.4826)
		(drill 0.254)
		(layers "F.Cu" "B.Cu")
		(net "GND")
	)
	(via
		(at 80.344264 -391.830814)
		(size 0.4064)
		(drill 0.2032)
		(layers "F.Cu" "B.Cu")
		(net "GND")
	)
	(via
		(at 372.93423 -180.755544)
		(size 0.49022)
		(drill 0.254)
		(layers "F.Cu" "B.Cu")
		(net "GND")
	)
	(via
		(at 396.349474 -426.54728)
		(size 0.4572)
		(drill 0.2032)
		(layers "F.Cu" "B.Cu")
		(net "GND")
	)
	(via
		(at 416.468052 -246.635016)
		(size 0.4826)
		(drill 0.254)
		(layers "F.Cu" "B.Cu")
		(net "GND")
	)
	(via
		(at 344.249502 -429.147224)
		(size 0.4572)
		(drill 0.2032)
		(layers "F.Cu" "B.Cu")
		(net "GND")
	)
	(via
		(at 202.31862 -332.805786)
		(size 0.508)
		(drill 0.254)
		(layers "F.Cu" "B.Cu")
		(net "GND")
	)
	(via
		(at 388.21487 -274.896072)
		(size 0.4064)
		(drill 0.2032)
		(layers "F.Cu" "B.Cu")
		(net "GND")
	)
	(via
		(at 352.744278 -175.487838)
		(size 0.508)
		(drill 0.254)
		(layers "F.Cu" "B.Cu")
		(net "GND")
	)
	(via
		(at 54.210458 -276.81047)
		(size 0.4826)
		(drill 0.254)
		(layers "F.Cu" "B.Cu")
		(net "GND")
	)
	(via
		(at 298.70654 -201.160126)
		(size 0.4826)
		(drill 0.254)
		(layers "F.Cu" "B.Cu")
		(net "GND")
	)
	(via
		(at 13.31087 -384.76809)
		(size 0.508)
		(drill 0.254)
		(layers "F.Cu" "B.Cu")
		(net "GND")
	)
	(via
		(at 369.584732 -230.714296)
		(size 0.4064)
		(drill 0.2032)
		(layers "F.Cu" "B.Cu")
		(net "GND")
	)
	(via
		(at 138.864848 -272.466308)
		(size 0.4064)
		(drill 0.2032)
		(layers "F.Cu" "B.Cu")
		(net "GND")
	)
	(via
		(at 20.59051 -285.310326)
		(size 0.4826)
		(drill 0.254)
		(layers "F.Cu" "B.Cu")
		(net "GND")
	)
	(via
		(at 331.251306 -415.38652)
		(size 0.4064)
		(drill 0.2032)
		(layers "F.Cu" "B.Cu")
		(net "GND")
	)
	(via
		(at 84.99094 -250.15444)
		(size 0.4064)
		(drill 0.2032)
		(layers "F.Cu" "B.Cu")
		(net "GND")
	)
	(via
		(at 403.845522 -10.16508)
		(size 0.508)
		(drill 0.254)
		(layers "F.Cu" "B.Cu")
		(net "GND")
	)
	(via
		(at 84.249768 -433.899564)
		(size 0.4572)
		(drill 0.2032)
		(layers "F.Cu" "B.Cu")
		(net "GND")
	)
	(via
		(at 288.180018 -245.785132)
		(size 0.4826)
		(drill 0.254)
		(layers "F.Cu" "B.Cu")
		(net "GND")
	)
	(via
		(at 81.701132 -241.244374)
		(size 0.4064)
		(drill 0.2032)
		(layers "F.Cu" "B.Cu")
		(net "GND")
	)
	(via
		(at 151.34971 -430.299622)
		(size 0.4572)
		(drill 0.2032)
		(layers "F.Cu" "B.Cu")
		(net "GND")
	)
	(via
		(at 31.468314 -342.816434)
		(size 0.508)
		(drill 0.254)
		(layers "F.Cu" "B.Cu")
		(net "GND")
	)
	(via
		(at 273.092164 -292.535102)
		(size 0.4826)
		(drill 0.254)
		(layers "F.Cu" "B.Cu")
		(net "GND")
	)
	(via
		(at 130.349752 -436.347362)
		(size 0.4572)
		(drill 0.2032)
		(layers "F.Cu" "B.Cu")
		(net "GND")
	)
	(via
		(at 253.823216 -327.46061)
		(size 0.762)
		(drill 0.254)
		(layers "F.Cu" "B.Cu")
		(net "GND")
	)
	(via
		(at 425.57954 -349.179642)
		(size 0.49022)
		(drill 0.254)
		(layers "F.Cu" "B.Cu")
		(net "GND")
	)
	(via
		(at 445.259968 -239.835182)
		(size 0.4826)
		(drill 0.254)
		(layers "F.Cu" "B.Cu")
		(net "GND")
	)
	(via
		(at 98.344228 -393.902438)
		(size 0.4572)
		(drill 0.254)
		(layers "F.Cu" "B.Cu")
		(net "GND")
	)
	(via
		(at 116.304822 -274.08632)
		(size 0.4064)
		(drill 0.2032)
		(layers "F.Cu" "B.Cu")
		(net "GND")
	)
	(via
		(at 329.297792 -384.175)
		(size 0.508)
		(drill 0.254)
		(layers "F.Cu" "B.Cu")
		(net "GND")
	)
	(via
		(at 333.401162 -225.044254)
		(size 0.4064)
		(drill 0.2032)
		(layers "F.Cu" "B.Cu")
		(net "GND")
	)
	(via
		(at 381.334772 -228.284278)
		(size 0.4064)
		(drill 0.2032)
		(layers "F.Cu" "B.Cu")
		(net "GND")
	)
	(via
		(at 96.74098 -228.284532)
		(size 0.4064)
		(drill 0.2032)
		(layers "F.Cu" "B.Cu")
		(net "GND")
	)
	(via
		(at 358.141016 -281.37612)
		(size 0.4064)
		(drill 0.2032)
		(layers "F.Cu" "B.Cu")
		(net "GND")
	)
	(via
		(at 297.108372 -238.13516)
		(size 0.4826)
		(drill 0.254)
		(layers "F.Cu" "B.Cu")
		(net "GND")
	)
	(via
		(at 390.281668 -76.408026)
		(size 0.508)
		(drill 0.254)
		(layers "F.Cu" "B.Cu")
		(net "GND")
	)
	(via
		(at 105.00995 -121.676668)
		(size 0.508)
		(drill 0.254)
		(layers "F.Cu" "B.Cu")
		(net "GND")
	)
	(via
		(at 44.340018 -268.735302)
		(size 0.4826)
		(drill 0.254)
		(layers "F.Cu" "B.Cu")
		(net "GND")
	)
	(via
		(at 266.93241 -312.935112)
		(size 0.4826)
		(drill 0.254)
		(layers "F.Cu" "B.Cu")
		(net "GND")
	)
	(via
		(at 314.044838 -412.212536)
		(size 0.4572)
		(drill 0.254)
		(layers "F.Cu" "B.Cu")
		(net "GND")
	)
	(via
		(at 86.249764 -430.147222)
		(size 0.4572)
		(drill 0.2032)
		(layers "F.Cu" "B.Cu")
		(net "GND")
	)
	(via
		(at 415.312352 -192.21831)
		(size 0.4826)
		(drill 0.254)
		(layers "F.Cu" "B.Cu")
		(net "GND")
	)
	(via
		(at 42.074338 -345.799918)
		(size 0.49022)
		(drill 0.254)
		(layers "F.Cu" "B.Cu")
		(net "GND")
	)
	(via
		(at 40.09644 -436.499)
		(size 0.508)
		(drill 0.254)
		(layers "F.Cu" "B.Cu")
		(net "GND")
	)
	(via
		(at 111.767366 -61.056774)
		(size 0.508)
		(drill 0.254)
		(layers "F.Cu" "B.Cu")
		(net "GND")
	)
	(via
		(at 337.84032 -328.132694)
		(size 0.508)
		(drill 0.254)
		(layers "F.Cu" "B.Cu")
		(net "GND")
	)
	(via
		(at 53.265832 -10.16508)
		(size 0.508)
		(drill 0.254)
		(layers "F.Cu" "B.Cu")
		(net "GND")
	)
	(via
		(at 124.294646 -273.276314)
		(size 0.4064)
		(drill 0.2032)
		(layers "F.Cu" "B.Cu")
		(net "GND")
	)
	(via
		(at 50.386996 -409.396184)
		(size 0.4572)
		(drill 0.254)
		(layers "F.Cu" "B.Cu")
		(net "GND")
	)
	(via
		(at 391.466832 -376.75693)
		(size 0.508)
		(drill 0.254)
		(layers "F.Cu" "B.Cu")
		(net "GND")
	)
	(via
		(at 131.545584 -12.495022)
		(size 0.508)
		(drill 0.254)
		(layers "F.Cu" "B.Cu")
		(net "GND")
	)
	(via
		(at 389.344662 -142.307056)
		(size 0.508)
		(drill 0.254)
		(layers "F.Cu" "B.Cu")
		(net "GND")
	)
	(via
		(at 282.020264 -203.28509)
		(size 0.4826)
		(drill 0.254)
		(layers "F.Cu" "B.Cu")
		(net "GND")
	)
	(via
		(at 338.401152 -271.656048)
		(size 0.4064)
		(drill 0.2032)
		(layers "F.Cu" "B.Cu")
		(net "GND")
	)
	(via
		(at 391.974832 -291.095938)
		(size 0.4064)
		(drill 0.2032)
		(layers "F.Cu" "B.Cu")
		(net "GND")
	)
	(via
		(at 198.7042 -198.185278)
		(size 0.4826)
		(drill 0.254)
		(layers "F.Cu" "B.Cu")
		(net "GND")
	)
	(via
		(at 403.349714 -427.851316)
		(size 0.4572)
		(drill 0.2032)
		(layers "F.Cu" "B.Cu")
		(net "GND")
	)
	(via
		(at 98.150934 -237.194344)
		(size 0.4064)
		(drill 0.2032)
		(layers "F.Cu" "B.Cu")
		(net "GND")
	)
	(via
		(at 326.651112 -262.745982)
		(size 0.4064)
		(drill 0.2032)
		(layers "F.Cu" "B.Cu")
		(net "GND")
	)
	(via
		(at 140.349732 -431.29962)
		(size 0.4572)
		(drill 0.2032)
		(layers "F.Cu" "B.Cu")
		(net "GND")
	)
	(via
		(at 29.69387 -384.26009)
		(size 0.508)
		(drill 0.254)
		(layers "F.Cu" "B.Cu")
		(net "GND")
	)
	(via
		(at 157.94609 -388.328662)
		(size 0.4064)
		(drill 0.2032)
		(layers "F.Cu" "B.Cu")
		(net "GND")
	)
	(via
		(at 431.55616 -316.335156)
		(size 0.4826)
		(drill 0.254)
		(layers "F.Cu" "B.Cu")
		(net "GND")
	)
	(via
		(at 115.932204 -166.781734)
		(size 0.508)
		(drill 0.254)
		(layers "F.Cu" "B.Cu")
		(net "GND")
	)
	(via
		(at 202.147932 -300.185328)
		(size 0.4826)
		(drill 0.254)
		(layers "F.Cu" "B.Cu")
		(net "GND")
	)
	(via
		(at 98.150934 -229.094538)
		(size 0.4064)
		(drill 0.2032)
		(layers "F.Cu" "B.Cu")
		(net "GND")
	)
	(via
		(at 130.104642 -230.71455)
		(size 0.4064)
		(drill 0.2032)
		(layers "F.Cu" "B.Cu")
		(net "GND")
	)
	(via
		(at 202.147932 -233.035348)
		(size 0.4826)
		(drill 0.254)
		(layers "F.Cu" "B.Cu")
		(net "GND")
	)
	(via
		(at 303.235106 -420.952168)
		(size 0.4064)
		(drill 0.2032)
		(layers "F.Cu" "B.Cu")
		(net "GND")
	)
	(via
		(at 151.694642 -77.74686)
		(size 0.508)
		(drill 0.254)
		(layers "F.Cu" "B.Cu")
		(net "GND")
	)
	(via
		(at 103.470202 -341.927688)
		(size 0.49022)
		(drill 0.254)
		(layers "F.Cu" "B.Cu")
		(net "GND")
	)
	(via
		(at 84.832952 -150.020782)
		(size 0.508)
		(drill 0.254)
		(layers "F.Cu" "B.Cu")
		(net "GND")
	)
	(via
		(at 88.83904 -355.968046)
		(size 0.508)
		(drill 0.254)
		(layers "F.Cu" "B.Cu")
		(net "GND")
	)
	(via
		(at 340.921086 -242.864132)
		(size 0.4064)
		(drill 0.2032)
		(layers "F.Cu" "B.Cu")
		(net "GND")
	)
	(via
		(at 367.704878 -225.85426)
		(size 0.4064)
		(drill 0.2032)
		(layers "F.Cu" "B.Cu")
		(net "GND")
	)
	(via
		(at 179.516024 -236.435392)
		(size 0.4826)
		(drill 0.254)
		(layers "F.Cu" "B.Cu")
		(net "GND")
	)
	(via
		(at 140.670534 -19.689064)
		(size 0.508)
		(drill 0.254)
		(layers "F.Cu" "B.Cu")
		(net "GND")
	)
	(via
		(at 216.97315 -72.015858)
		(size 0.508)
		(drill 0.254)
		(layers "F.Cu" "B.Cu")
		(net "GND")
	)
	(via
		(at 451.2437 -192.21831)
		(size 0.4826)
		(drill 0.254)
		(layers "F.Cu" "B.Cu")
		(net "GND")
	)
	(via
		(at 277.192232 -213.484968)
		(size 0.4826)
		(drill 0.254)
		(layers "F.Cu" "B.Cu")
		(net "GND")
	)
	(via
		(at 187.060078 -244.085364)
		(size 0.4826)
		(drill 0.254)
		(layers "F.Cu" "B.Cu")
		(net "GND")
	)
	(via
		(at 95.54591 -185.937398)
		(size 0.508)
		(drill 0.254)
		(layers "F.Cu" "B.Cu")
		(net "GND")
	)
	(via
		(at 73.24979 -431.299874)
		(size 0.4572)
		(drill 0.2032)
		(layers "F.Cu" "B.Cu")
		(net "GND")
	)
	(via
		(at 433.90947 -172.64888)
		(size 0.508)
		(drill 0.254)
		(layers "F.Cu" "B.Cu")
		(net "GND")
	)
	(via
		(at 65.703196 -406.370536)
		(size 0.4572)
		(drill 0.254)
		(layers "F.Cu" "B.Cu")
		(net "GND")
	)
	(via
		(at 153.872184 -108.09859)
		(size 0.508)
		(drill 0.254)
		(layers "F.Cu" "B.Cu")
		(net "GND")
	)
	(via
		(at 405.92375 -417.778184)
		(size 0.4572)
		(drill 0.254)
		(layers "F.Cu" "B.Cu")
		(net "GND")
	)
	(via
		(at 347.33103 -290.285932)
		(size 0.4064)
		(drill 0.2032)
		(layers "F.Cu" "B.Cu")
		(net "GND")
	)
	(via
		(at 131.98475 -250.15444)
		(size 0.4064)
		(drill 0.2032)
		(layers "F.Cu" "B.Cu")
		(net "GND")
	)
	(via
		(at 269.648178 -226.235006)
		(size 0.4826)
		(drill 0.254)
		(layers "F.Cu" "B.Cu")
		(net "GND")
	)
	(via
		(at 102.38105 -226.66452)
		(size 0.4064)
		(drill 0.2032)
		(layers "F.Cu" "B.Cu")
		(net "GND")
	)
	(via
		(at 435.000146 -227.085144)
		(size 0.4826)
		(drill 0.254)
		(layers "F.Cu" "B.Cu")
		(net "GND")
	)
	(via
		(at 136.98474 -261.126224)
		(size 0.4064)
		(drill 0.2032)
		(layers "F.Cu" "B.Cu")
		(net "GND")
	)
	(via
		(at 87.418672 -413.204152)
		(size 0.4572)
		(drill 0.254)
		(layers "F.Cu" "B.Cu")
		(net "GND")
	)
	(via
		(at 37.681662 -418.239448)
		(size 0.508)
		(drill 0.254)
		(layers "F.Cu" "B.Cu")
		(net "GND")
	)
	(via
		(at 462.316576 -101.105208)
		(size 0.508)
		(drill 0.254)
		(layers "F.Cu" "B.Cu")
		(net "GND")
	)
	(via
		(at 99.390962 -282.18638)
		(size 0.4064)
		(drill 0.2032)
		(layers "F.Cu" "B.Cu")
		(net "GND")
	)
	(via
		(at 180.671724 -193.085212)
		(size 0.4826)
		(drill 0.254)
		(layers "F.Cu" "B.Cu")
		(net "GND")
	)
	(via
		(at 163.275264 -145.84299)
		(size 0.508)
		(drill 0.254)
		(layers "F.Cu" "B.Cu")
		(net "GND")
	)
	(via
		(at 51.884072 -271.285208)
		(size 0.4826)
		(drill 0.254)
		(layers "F.Cu" "B.Cu")
		(net "GND")
	)
	(via
		(at 20.614386 -4.32943)
		(size 0.508)
		(drill 0.254)
		(layers "F.Cu" "B.Cu")
		(net "GND")
	)
	(via
		(at 413.349694 -437.34736)
		(size 0.4572)
		(drill 0.2032)
		(layers "F.Cu" "B.Cu")
		(net "GND")
	)
	(via
		(at 344.211148 -251.774198)
		(size 0.4064)
		(drill 0.2032)
		(layers "F.Cu" "B.Cu")
		(net "GND")
	)
	(via
		(at 436.384446 -200.735184)
		(size 0.4826)
		(drill 0.254)
		(layers "F.Cu" "B.Cu")
		(net "GND")
	)
	(via
		(at 259.705094 -141.968728)
		(size 0.508)
		(drill 0.254)
		(layers "F.Cu" "B.Cu")
		(net "GND")
	)
	(via
		(at 344.199718 -165.04412)
		(size 0.508)
		(drill 0.254)
		(layers "F.Cu" "B.Cu")
		(net "GND")
	)
	(via
		(at 194.114166 -348.71152)
		(size 0.508)
		(drill 0.254)
		(layers "F.Cu" "B.Cu")
		(net "GND")
	)
	(via
		(at 154.346148 -388.328662)
		(size 0.4064)
		(drill 0.2032)
		(layers "F.Cu" "B.Cu")
		(net "GND")
	)
	(via
		(at 99.090988 -224.234502)
		(size 0.4064)
		(drill 0.2032)
		(layers "F.Cu" "B.Cu")
		(net "GND")
	)
	(via
		(at 273.092164 -301.885096)
		(size 0.4826)
		(drill 0.254)
		(layers "F.Cu" "B.Cu")
		(net "GND")
	)
	(via
		(at 156.507434 -198.212456)
		(size 0.508)
		(drill 0.254)
		(layers "F.Cu" "B.Cu")
		(net "GND")
	)
	(via
		(at 350.151192 -287.045908)
		(size 0.4064)
		(drill 0.2032)
		(layers "F.Cu" "B.Cu")
		(net "GND")
	)
	(via
		(at 442.5442 -255.135126)
		(size 0.4826)
		(drill 0.254)
		(layers "F.Cu" "B.Cu")
		(net "GND")
	)
	(via
		(at 195.721732 -295.510458)
		(size 0.4826)
		(drill 0.254)
		(layers "F.Cu" "B.Cu")
		(net "GND")
	)
	(via
		(at 256.884932 -49.612296)
		(size 0.508)
		(drill 0.254)
		(layers "F.Cu" "B.Cu")
		(net "GND")
	)
	(via
		(at 49.647094 -372.15953)
		(size 0.508)
		(drill 0.254)
		(layers "F.Cu" "B.Cu")
		(net "GND")
	)
	(via
		(at 446.644268 -205.834996)
		(size 0.4826)
		(drill 0.254)
		(layers "F.Cu" "B.Cu")
		(net "GND")
	)
	(via
		(at 371.955314 -413.480504)
		(size 0.4572)
		(drill 0.254)
		(layers "F.Cu" "B.Cu")
		(net "GND")
	)
	(via
		(at 51.99507 -19.771106)
		(size 0.508)
		(drill 0.254)
		(layers "F.Cu" "B.Cu")
		(net "GND")
	)
	(via
		(at 320.2813 -333.06004)
		(size 0.49022)
		(drill 0.254)
		(layers "F.Cu" "B.Cu")
		(net "GND")
	)
	(via
		(at 411.349698 -429.147224)
		(size 0.4572)
		(drill 0.2032)
		(layers "F.Cu" "B.Cu")
		(net "GND")
	)
	(via
		(at 342.801194 -236.384084)
		(size 0.4064)
		(drill 0.2032)
		(layers "F.Cu" "B.Cu")
		(net "GND")
	)
	(via
		(at 104.52481 -406.310846)
		(size 0.508)
		(drill 0.254)
		(layers "F.Cu" "B.Cu")
		(net "GND")
	)
	(via
		(at 181.407562 -52.884578)
		(size 0.508)
		(drill 0.254)
		(layers "F.Cu" "B.Cu")
		(net "GND")
	)
	(via
		(at 108.02112 -236.384338)
		(size 0.4064)
		(drill 0.2032)
		(layers "F.Cu" "B.Cu")
		(net "GND")
	)
	(via
		(at 89.99093 -291.906198)
		(size 0.4064)
		(drill 0.2032)
		(layers "F.Cu" "B.Cu")
		(net "GND")
	)
	(via
		(at 391.204704 -225.85426)
		(size 0.4064)
		(drill 0.2032)
		(layers "F.Cu" "B.Cu")
		(net "GND")
	)
	(via
		(at 95.1611 -284.616398)
		(size 0.4064)
		(drill 0.2032)
		(layers "F.Cu" "B.Cu")
		(net "GND")
	)
	(via
		(at 406.97658 -58.30062)
		(size 0.508)
		(drill 0.254)
		(layers "F.Cu" "B.Cu")
		(net "GND")
	)
	(via
		(at 206.248 -308.685438)
		(size 0.4826)
		(drill 0.254)
		(layers "F.Cu" "B.Cu")
		(net "GND")
	)
	(via
		(at 348.271084 -264.365994)
		(size 0.4064)
		(drill 0.2032)
		(layers "F.Cu" "B.Cu")
		(net "GND")
	)
	(via
		(at 411.349698 -427.851316)
		(size 0.4572)
		(drill 0.2032)
		(layers "F.Cu" "B.Cu")
		(net "GND")
	)
	(via
		(at 336.521044 -276.516084)
		(size 0.4064)
		(drill 0.2032)
		(layers "F.Cu" "B.Cu")
		(net "GND")
	)
	(via
		(at 451.4723 -303.585118)
		(size 0.4826)
		(drill 0.254)
		(layers "F.Cu" "B.Cu")
		(net "GND")
	)
	(via
		(at 86.88705 -73.13295)
		(size 0.508)
		(drill 0.254)
		(layers "F.Cu" "B.Cu")
		(net "GND")
	)
	(via
		(at 177.70094 -401.452842)
		(size 0.508)
		(drill 0.254)
		(layers "F.Cu" "B.Cu")
		(net "GND")
	)
	(via
		(at 345.645994 -396.710662)
		(size 0.4064)
		(drill 0.2032)
		(layers "F.Cu" "B.Cu")
		(net "GND")
	)
	(via
		(at 386.804916 -262.745982)
		(size 0.4064)
		(drill 0.2032)
		(layers "F.Cu" "B.Cu")
		(net "GND")
	)
	(via
		(at 89.690956 -235.574332)
		(size 0.4064)
		(drill 0.2032)
		(layers "F.Cu" "B.Cu")
		(net "GND")
	)
	(via
		(at 447.65468 -4.325874)
		(size 0.508)
		(drill 0.254)
		(layers "F.Cu" "B.Cu")
		(net "GND")
	)
	(via
		(at 125.716538 -382.85293)
		(size 0.4064)
		(drill 0.2032)
		(layers "F.Cu" "B.Cu")
		(net "GND")
	)
	(via
		(at 388.21487 -294.335962)
		(size 0.4064)
		(drill 0.2032)
		(layers "F.Cu" "B.Cu")
		(net "GND")
	)
	(via
		(at 124.464826 -232.334308)
		(size 0.4064)
		(drill 0.2032)
		(layers "F.Cu" "B.Cu")
		(net "GND")
	)
	(via
		(at 390.094724 -284.616144)
		(size 0.4064)
		(drill 0.2032)
		(layers "F.Cu" "B.Cu")
		(net "GND")
	)
	(via
		(at 439.100214 -213.484968)
		(size 0.4826)
		(drill 0.254)
		(layers "F.Cu" "B.Cu")
		(net "GND")
	)
	(via
		(at 398.465294 -178.321208)
		(size 0.49022)
		(drill 0.254)
		(layers "F.Cu" "B.Cu")
		(net "GND")
	)
	(via
		(at 143.73479 -242.864386)
		(size 0.4064)
		(drill 0.2032)
		(layers "F.Cu" "B.Cu")
		(net "GND")
	)
	(via
		(at 394.982954 -287.59023)
		(size 0.4064)
		(drill 0.2032)
		(layers "F.Cu" "B.Cu")
		(net "GND")
	)
	(via
		(at 99.090988 -233.95432)
		(size 0.4064)
		(drill 0.2032)
		(layers "F.Cu" "B.Cu")
		(net "GND")
	)
	(via
		(at 117.44071 -257.43027)
		(size 0.4826)
		(drill 0.254)
		(layers "F.Cu" "B.Cu")
		(net "GND")
	)
	(via
		(at 324.366636 -378.07773)
		(size 0.508)
		(drill 0.254)
		(layers "F.Cu" "B.Cu")
		(net "GND")
	)
	(via
		(at 324.677786 -420.952168)
		(size 0.4064)
		(drill 0.2032)
		(layers "F.Cu" "B.Cu")
		(net "GND")
	)
	(via
		(at 424.012106 -316.335156)
		(size 0.4826)
		(drill 0.254)
		(layers "F.Cu" "B.Cu")
		(net "GND")
	)
	(via
		(at 269.648178 -198.185024)
		(size 0.4826)
		(drill 0.254)
		(layers "F.Cu" "B.Cu")
		(net "GND")
	)
	(via
		(at 35.411664 -314.635388)
		(size 0.4826)
		(drill 0.254)
		(layers "F.Cu" "B.Cu")
		(net "GND")
	)
	(via
		(at 189.410848 -54.04104)
		(size 0.508)
		(drill 0.254)
		(layers "F.Cu" "B.Cu")
		(net "GND")
	)
	(via
		(at 450.057774 -32.623506)
		(size 0.508)
		(drill 0.254)
		(layers "F.Cu" "B.Cu")
		(net "GND")
	)
	(via
		(at 369.584732 -245.29415)
		(size 0.4064)
		(drill 0.2032)
		(layers "F.Cu" "B.Cu")
		(net "GND")
	)
	(via
		(at 116.304822 -270.846296)
		(size 0.4064)
		(drill 0.2032)
		(layers "F.Cu" "B.Cu")
		(net "GND")
	)
	(via
		(at 402.948902 -412.84652)
		(size 0.4064)
		(drill 0.2032)
		(layers "F.Cu" "B.Cu")
		(net "GND")
	)
	(via
		(at 310.981598 -412.212536)
		(size 0.4572)
		(drill 0.254)
		(layers "F.Cu" "B.Cu")
		(net "GND")
	)
	(via
		(at 25.152096 -242.385342)
		(size 0.4826)
		(drill 0.254)
		(layers "F.Cu" "B.Cu")
		(net "GND")
	)
	(via
		(at 130.349752 -431.451258)
		(size 0.4572)
		(drill 0.2032)
		(layers "F.Cu" "B.Cu")
		(net "GND")
	)
	(via
		(at 40.23995 -250.885198)
		(size 0.4826)
		(drill 0.254)
		(layers "F.Cu" "B.Cu")
		(net "GND")
	)
	(via
		(at 236.992414 -334.24368)
		(size 0.508)
		(drill 0.254)
		(layers "F.Cu" "B.Cu")
		(net "GND")
	)
	(via
		(at 288.180018 -252.584966)
		(size 0.4826)
		(drill 0.254)
		(layers "F.Cu" "B.Cu")
		(net "GND")
	)
	(via
		(at 162.889184 -372.15953)
		(size 0.508)
		(drill 0.254)
		(layers "F.Cu" "B.Cu")
		(net "GND")
	)
	(via
		(at 113.582196 -257.74523)
		(size 0.4826)
		(drill 0.254)
		(layers "F.Cu" "B.Cu")
		(net "GND")
	)
	(via
		(at 143.56461 -272.466308)
		(size 0.4064)
		(drill 0.2032)
		(layers "F.Cu" "B.Cu")
		(net "GND")
	)
	(via
		(at 154.389836 -56.543194)
		(size 0.508)
		(drill 0.254)
		(layers "F.Cu" "B.Cu")
		(net "GND")
	)
	(via
		(at 346.249498 -433.747164)
		(size 0.4572)
		(drill 0.2032)
		(layers "F.Cu" "B.Cu")
		(net "GND")
	)
	(via
		(at 381.41783 -416.020504)
		(size 0.4572)
		(drill 0.254)
		(layers "F.Cu" "B.Cu")
		(net "GND")
	)
	(via
		(at 206.248 -244.935248)
		(size 0.4826)
		(drill 0.254)
		(layers "F.Cu" "B.Cu")
		(net "GND")
	)
	(via
		(at 25.479502 -4.32943)
		(size 0.508)
		(drill 0.254)
		(layers "F.Cu" "B.Cu")
		(net "GND")
	)
	(via
		(at 369.584732 -242.054126)
		(size 0.4064)
		(drill 0.2032)
		(layers "F.Cu" "B.Cu")
		(net "GND")
	)
	(via
		(at 378.814838 -270.036036)
		(size 0.4064)
		(drill 0.2032)
		(layers "F.Cu" "B.Cu")
		(net "GND")
	)
	(via
		(at 182.332122 -118.242842)
		(size 0.4572)
		(drill 0.254)
		(layers "F.Cu" "B.Cu")
		(net "GND")
	)
	(via
		(at 347.50121 -246.104156)
		(size 0.4064)
		(drill 0.2032)
		(layers "F.Cu" "B.Cu")
		(net "GND")
	)
	(via
		(at 323.234558 -412.212536)
		(size 0.4572)
		(drill 0.254)
		(layers "F.Cu" "B.Cu")
		(net "GND")
	)
	(via
		(at 140.274802 -261.93623)
		(size 0.4064)
		(drill 0.2032)
		(layers "F.Cu" "B.Cu")
		(net "GND")
	)
	(via
		(at 421.067738 -193.10731)
		(size 0.4826)
		(drill 0.254)
		(layers "F.Cu" "B.Cu")
		(net "GND")
	)
	(via
		(at 83.994244 -404.46452)
		(size 0.4064)
		(drill 0.2032)
		(layers "F.Cu" "B.Cu")
		(net "GND")
	)
	(via
		(at 367.704878 -229.094284)
		(size 0.4064)
		(drill 0.2032)
		(layers "F.Cu" "B.Cu")
		(net "GND")
	)
	(via
		(at 40.283384 -441.227718)
		(size 0.508)
		(drill 0.254)
		(layers "F.Cu" "B.Cu")
		(net "GND")
	)
	(via
		(at 95.076772 -409.396184)
		(size 0.4572)
		(drill 0.254)
		(layers "F.Cu" "B.Cu")
		(net "GND")
	)
	(via
		(at 31.578296 -230.0605)
		(size 0.4826)
		(drill 0.254)
		(layers "F.Cu" "B.Cu")
		(net "GND")
	)
	(via
		(at 171.97197 -249.18543)
		(size 0.4826)
		(drill 0.254)
		(layers "F.Cu" "B.Cu")
		(net "GND")
	)
	(via
		(at 140.461238 -411.936184)
		(size 0.4572)
		(drill 0.254)
		(layers "F.Cu" "B.Cu")
		(net "GND")
	)
	(via
		(at 108.530644 -375.30786)
		(size 0.508)
		(drill 0.254)
		(layers "F.Cu" "B.Cu")
		(net "GND")
	)
	(via
		(at 415.28492 -18.503138)
		(size 0.508)
		(drill 0.254)
		(layers "F.Cu" "B.Cu")
		(net "GND")
	)
	(via
		(at 87.141558 -333.82839)
		(size 0.49022)
		(drill 0.254)
		(layers "F.Cu" "B.Cu")
		(net "GND")
	)
	(via
		(at 416.468052 -280.634948)
		(size 0.4826)
		(drill 0.254)
		(layers "F.Cu" "B.Cu")
		(net "GND")
	)
	(via
		(at 174.687738 -199.8853)
		(size 0.4826)
		(drill 0.254)
		(layers "F.Cu" "B.Cu")
		(net "GND")
	)
	(via
		(at 59.249818 -432.747166)
		(size 0.4572)
		(drill 0.2032)
		(layers "F.Cu" "B.Cu")
		(net "GND")
	)
	(via
		(at 307.669946 -339.87867)
		(size 0.508)
		(drill 0.254)
		(layers "F.Cu" "B.Cu")
		(net "GND")
	)
	(via
		(at 255.927098 -206.718408)
		(size 0.508)
		(drill 0.254)
		(layers "F.Cu" "B.Cu")
		(net "GND")
	)
	(via
		(at 424.012106 -291.684964)
		(size 0.4826)
		(drill 0.254)
		(layers "F.Cu" "B.Cu")
		(net "GND")
	)
	(via
		(at 302.14316 -122.349514)
		(size 0.508)
		(drill 0.254)
		(layers "F.Cu" "B.Cu")
		(net "GND")
	)
	(via
		(at 9.963404 -100.417884)
		(size 0.508)
		(drill 0.254)
		(layers "F.Cu" "B.Cu")
		(net "GND")
	)
	(via
		(at 105.671112 -240.434368)
		(size 0.4064)
		(drill 0.2032)
		(layers "F.Cu" "B.Cu")
		(net "GND")
	)
	(via
		(at 98.478848 -37.450014)
		(size 0.508)
		(drill 0.254)
		(layers "F.Cu" "B.Cu")
		(net "GND")
	)
	(via
		(at 11.895836 -91.658948)
		(size 0.508)
		(drill 0.254)
		(layers "F.Cu" "B.Cu")
		(net "GND")
	)
	(via
		(at 446.644268 -316.335156)
		(size 0.4826)
		(drill 0.254)
		(layers "F.Cu" "B.Cu")
		(net "GND")
	)
	(via
		(at 370.524786 -251.774198)
		(size 0.4064)
		(drill 0.2032)
		(layers "F.Cu" "B.Cu")
		(net "GND")
	)
	(via
		(at 103.088186 -339.540342)
		(size 0.49022)
		(drill 0.254)
		(layers "F.Cu" "B.Cu")
		(net "GND")
	)
	(via
		(at 99.177094 -68.756276)
		(size 0.508)
		(drill 0.254)
		(layers "F.Cu" "B.Cu")
		(net "GND")
	)
	(via
		(at 65.249806 -428.851314)
		(size 0.4572)
		(drill 0.2032)
		(layers "F.Cu" "B.Cu")
		(net "GND")
	)
	(via
		(at 129.739898 -407.638504)
		(size 0.4572)
		(drill 0.254)
		(layers "F.Cu" "B.Cu")
		(net "GND")
	)
	(via
		(at 321.702938 -414.752536)
		(size 0.4572)
		(drill 0.254)
		(layers "F.Cu" "B.Cu")
		(net "GND")
	)
	(via
		(at 49.016666 -382.85293)
		(size 0.4064)
		(drill 0.2032)
		(layers "F.Cu" "B.Cu")
		(net "GND")
	)
	(via
		(at 143.797274 -407.638504)
		(size 0.4572)
		(drill 0.254)
		(layers "F.Cu" "B.Cu")
		(net "GND")
	)
	(via
		(at 327.761092 -255.824228)
		(size 0.4064)
		(drill 0.2032)
		(layers "F.Cu" "B.Cu")
		(net "GND")
	)
	(via
		(at 143.524478 -403.830536)
		(size 0.4572)
		(drill 0.254)
		(layers "F.Cu" "B.Cu")
		(net "GND")
	)
	(via
		(at 372.704868 -265.986006)
		(size 0.4064)
		(drill 0.2032)
		(layers "F.Cu" "B.Cu")
		(net "GND")
	)
	(via
		(at 437.944514 -193.99631)
		(size 0.4826)
		(drill 0.254)
		(layers "F.Cu" "B.Cu")
		(net "GND")
	)
	(via
		(at 177.1396 -87.823294)
		(size 0.508)
		(drill 0.254)
		(layers "F.Cu" "B.Cu")
		(net "GND")
	)
	(via
		(at 76.785724 -404.46452)
		(size 0.4064)
		(drill 0.2032)
		(layers "F.Cu" "B.Cu")
		(net "GND")
	)
	(via
		(at 259.762244 -136.703054)
		(size 0.508)
		(drill 0.254)
		(layers "F.Cu" "B.Cu")
		(net "GND")
	)
	(via
		(at 106.596942 -337.355434)
		(size 0.508)
		(drill 0.254)
		(layers "F.Cu" "B.Cu")
		(net "GND")
	)
	(via
		(at 342.801194 -238.004096)
		(size 0.4064)
		(drill 0.2032)
		(layers "F.Cu" "B.Cu")
		(net "GND")
	)
	(via
		(at 182.231792 -274.685252)
		(size 0.4826)
		(drill 0.254)
		(layers "F.Cu" "B.Cu")
		(net "GND")
	)
	(via
		(at 448.063366 -378.05487)
		(size 0.508)
		(drill 0.254)
		(layers "F.Cu" "B.Cu")
		(net "GND")
	)
	(via
		(at 471.037666 -61.585094)
		(size 0.508)
		(drill 0.254)
		(layers "F.Cu" "B.Cu")
		(net "GND")
	)
	(via
		(at 107.022138 -415.713672)
		(size 0.508)
		(drill 0.254)
		(layers "F.Cu" "B.Cu")
		(net "GND")
	)
	(via
		(at 161.109152 -194.728084)
		(size 0.508)
		(drill 0.254)
		(layers "F.Cu" "B.Cu")
		(net "GND")
	)
	(via
		(at 208.05521 -29.266642)
		(size 0.508)
		(drill 0.254)
		(layers "F.Cu" "B.Cu")
		(net "GND")
	)
	(via
		(at 140.744702 -274.08632)
		(size 0.4064)
		(drill 0.2032)
		(layers "F.Cu" "B.Cu")
		(net "GND")
	)
	(via
		(at 424.012106 -250.03506)
		(size 0.4826)
		(drill 0.254)
		(layers "F.Cu" "B.Cu")
		(net "GND")
	)
	(via
		(at 309.722774 -412.212536)
		(size 0.4572)
		(drill 0.254)
		(layers "F.Cu" "B.Cu")
		(net "GND")
	)
	(via
		(at 235.031534 -51.663346)
		(size 0.508)
		(drill 0.254)
		(layers "F.Cu" "B.Cu")
		(net "GND")
	)
	(via
		(at 174.687738 -305.285394)
		(size 0.4826)
		(drill 0.254)
		(layers "F.Cu" "B.Cu")
		(net "GND")
	)
	(via
		(at 108.961174 -244.484398)
		(size 0.4064)
		(drill 0.2032)
		(layers "F.Cu" "B.Cu")
		(net "GND")
	)
	(via
		(at 318.365124 -334.596232)
		(size 0.49022)
		(drill 0.254)
		(layers "F.Cu" "B.Cu")
		(net "GND")
	)
	(via
		(at 116.962428 -384.617722)
		(size 0.4064)
		(drill 0.2032)
		(layers "F.Cu" "B.Cu")
		(net "GND")
	)
	(via
		(at 86.701122 -281.376374)
		(size 0.4064)
		(drill 0.2032)
		(layers "F.Cu" "B.Cu")
		(net "GND")
	)
	(via
		(at 102.235762 -340.505288)
		(size 0.49022)
		(drill 0.254)
		(layers "F.Cu" "B.Cu")
		(net "GND")
	)
	(via
		(at 272.094706 -121.83237)
		(size 0.508)
		(drill 0.254)
		(layers "F.Cu" "B.Cu")
		(net "GND")
	)
	(via
		(at 134.607554 -410.664152)
		(size 0.4572)
		(drill 0.254)
		(layers "F.Cu" "B.Cu")
		(net "GND")
	)
	(via
		(at 239.014 -287.415478)
		(size 0.508)
		(drill 0.254)
		(layers "F.Cu" "B.Cu")
		(net "GND")
	)
	(via
		(at 65.703196 -409.396184)
		(size 0.4572)
		(drill 0.254)
		(layers "F.Cu" "B.Cu")
		(net "GND")
	)
	(via
		(at 325.399908 -333.838042)
		(size 0.49022)
		(drill 0.254)
		(layers "F.Cu" "B.Cu")
		(net "GND")
	)
	(via
		(at 27.867864 -237.285276)
		(size 0.4826)
		(drill 0.254)
		(layers "F.Cu" "B.Cu")
		(net "GND")
	)
	(via
		(at 336.827876 -72.884792)
		(size 0.508)
		(drill 0.254)
		(layers "F.Cu" "B.Cu")
		(net "GND")
	)
	(via
		(at 332.931008 -230.714042)
		(size 0.4064)
		(drill 0.2032)
		(layers "F.Cu" "B.Cu")
		(net "GND")
	)
	(via
		(at 344.860118 -163.72332)
		(size 0.508)
		(drill 0.254)
		(layers "F.Cu" "B.Cu")
		(net "GND")
	)
	(via
		(at 207.3656 -313.360308)
		(size 0.4826)
		(drill 0.254)
		(layers "F.Cu" "B.Cu")
		(net "GND")
	)
	(via
		(at 193.002916 -330.795884)
		(size 0.508)
		(drill 0.254)
		(layers "F.Cu" "B.Cu")
		(net "GND")
	)
	(via
		(at 312.513218 -414.752536)
		(size 0.4572)
		(drill 0.254)
		(layers "F.Cu" "B.Cu")
		(net "GND")
	)
	(via
		(at 431.55616 -261.93496)
		(size 0.4826)
		(drill 0.254)
		(layers "F.Cu" "B.Cu")
		(net "GND")
	)
	(via
		(at 451.4723 -315.485018)
		(size 0.4826)
		(drill 0.254)
		(layers "F.Cu" "B.Cu")
		(net "GND")
	)
	(via
		(at 126.470156 -369.69573)
		(size 0.508)
		(drill 0.254)
		(layers "F.Cu" "B.Cu")
		(net "GND")
	)
	(via
		(at 116.316506 -412.570168)
		(size 0.4064)
		(drill 0.2032)
		(layers "F.Cu" "B.Cu")
		(net "GND")
	)
	(via
		(at 127.584708 -272.466308)
		(size 0.4064)
		(drill 0.2032)
		(layers "F.Cu" "B.Cu")
		(net "GND")
	)
	(via
		(at 384.624834 -243.674138)
		(size 0.4064)
		(drill 0.2032)
		(layers "F.Cu" "B.Cu")
		(net "GND")
	)
	(via
		(at 336.22107 -228.284278)
		(size 0.4064)
		(drill 0.2032)
		(layers "F.Cu" "B.Cu")
		(net "GND")
	)
	(via
		(at 331.351128 -274.086066)
		(size 0.4064)
		(drill 0.2032)
		(layers "F.Cu" "B.Cu")
		(net "GND")
	)
	(via
		(at 422.15054 -351.68078)
		(size 0.49022)
		(drill 0.254)
		(layers "F.Cu" "B.Cu")
		(net "GND")
	)
	(via
		(at 54.302914 -17.613122)
		(size 0.508)
		(drill 0.254)
		(layers "F.Cu" "B.Cu")
		(net "GND")
	)
	(via
		(at 347.031056 -230.714296)
		(size 0.4064)
		(drill 0.2032)
		(layers "F.Cu" "B.Cu")
		(net "GND")
	)
	(via
		(at 346.091002 -222.614236)
		(size 0.4064)
		(drill 0.2032)
		(layers "F.Cu" "B.Cu")
		(net "GND")
	)
	(via
		(at 142.669514 -80.028542)
		(size 0.508)
		(drill 0.254)
		(layers "F.Cu" "B.Cu")
		(net "GND")
	)
	(via
		(at 338.498942 -141.150086)
		(size 0.508)
		(drill 0.254)
		(layers "F.Cu" "B.Cu")
		(net "GND")
	)
	(via
		(at 77.68971 -151.63038)
		(size 0.6604)
		(drill 0.3302)
		(layers "F.Cu" "B.Cu")
		(net "GND")
	)
	(via
		(at 341.144098 -402.309838)
		(size 0.4572)
		(drill 0.254)
		(layers "F.Cu" "B.Cu")
		(net "GND")
	)
	(via
		(at 414.755584 -10.16508)
		(size 0.508)
		(drill 0.254)
		(layers "F.Cu" "B.Cu")
		(net "GND")
	)
	(via
		(at 346.091002 -229.094284)
		(size 0.4064)
		(drill 0.2032)
		(layers "F.Cu" "B.Cu")
		(net "GND")
	)
	(via
		(at 331.521054 -229.904036)
		(size 0.4064)
		(drill 0.2032)
		(layers "F.Cu" "B.Cu")
		(net "GND")
	)
	(via
		(at 77.001116 -228.284532)
		(size 0.4064)
		(drill 0.2032)
		(layers "F.Cu" "B.Cu")
		(net "GND")
	)
	(via
		(at 370.69649 -421.586152)
		(size 0.4572)
		(drill 0.254)
		(layers "F.Cu" "B.Cu")
		(net "GND")
	)
	(via
		(at 337.631024 -230.714042)
		(size 0.4064)
		(drill 0.2032)
		(layers "F.Cu" "B.Cu")
		(net "GND")
	)
	(via
		(at 391.504678 -277.32609)
		(size 0.4064)
		(drill 0.2032)
		(layers "F.Cu" "B.Cu")
		(net "GND")
	)
	(via
		(at 390.902698 -180.755544)
		(size 0.49022)
		(drill 0.254)
		(layers "F.Cu" "B.Cu")
		(net "GND")
	)
	(via
		(at 47.784004 -255.13538)
		(size 0.4826)
		(drill 0.254)
		(layers "F.Cu" "B.Cu")
		(net "GND")
	)
	(via
		(at 119.208042 -77.793342)
		(size 0.508)
		(drill 0.254)
		(layers "F.Cu" "B.Cu")
		(net "GND")
	)
	(via
		(at 355.18725 -356.536752)
		(size 0.508)
		(drill 0.254)
		(layers "F.Cu" "B.Cu")
		(net "GND")
	)
	(via
		(at 450.088 -197.33514)
		(size 0.4826)
		(drill 0.254)
		(layers "F.Cu" "B.Cu")
		(net "GND")
	)
	(via
		(at 327.761092 -250.964192)
		(size 0.4064)
		(drill 0.2032)
		(layers "F.Cu" "B.Cu")
		(net "GND")
	)
	(via
		(at 413.349694 -436.051198)
		(size 0.4572)
		(drill 0.2032)
		(layers "F.Cu" "B.Cu")
		(net "GND")
	)
	(via
		(at 47.784004 -298.485306)
		(size 0.4826)
		(drill 0.254)
		(layers "F.Cu" "B.Cu")
		(net "GND")
	)
	(via
		(at 114.12474 -225.854514)
		(size 0.4064)
		(drill 0.2032)
		(layers "F.Cu" "B.Cu")
		(net "GND")
	)
	(via
		(at 336.344006 -391.23493)
		(size 0.4064)
		(drill 0.2032)
		(layers "F.Cu" "B.Cu")
		(net "GND")
	)
	(via
		(at 337.930998 -293.525956)
		(size 0.4064)
		(drill 0.2032)
		(layers "F.Cu" "B.Cu")
		(net "GND")
	)
	(via
		(at 59.428126 -280.635202)
		(size 0.4826)
		(drill 0.254)
		(layers "F.Cu" "B.Cu")
		(net "GND")
	)
	(via
		(at 357.201216 -268.416024)
		(size 0.4064)
		(drill 0.2032)
		(layers "F.Cu" "B.Cu")
		(net "GND")
	)
	(via
		(at 241.529108 -370.046504)
		(size 0.508)
		(drill 0.254)
		(layers "F.Cu" "B.Cu")
		(net "GND")
	)
	(via
		(at 59.428126 -253.435358)
		(size 0.4826)
		(drill 0.254)
		(layers "F.Cu" "B.Cu")
		(net "GND")
	)
	(via
		(at 455.835766 -49.104042)
		(size 0.508)
		(drill 0.254)
		(layers "F.Cu" "B.Cu")
		(net "GND")
	)
	(via
		(at 63.989712 -0.762254)
		(size 0.508)
		(drill 0.254)
		(layers "F.Cu" "B.Cu")
		(net "GND")
	)
	(via
		(at 130.305048 -156.908246)
		(size 0.49022)
		(drill 0.254)
		(layers "F.Cu" "B.Cu")
		(net "GND")
	)
	(via
		(at 435.000146 -255.135126)
		(size 0.4826)
		(drill 0.254)
		(layers "F.Cu" "B.Cu")
		(net "GND")
	)
	(via
		(at 431.55616 -268.735048)
		(size 0.4826)
		(drill 0.254)
		(layers "F.Cu" "B.Cu")
		(net "GND")
	)
	(via
		(at 314.761372 -32.572706)
		(size 0.508)
		(drill 0.254)
		(layers "F.Cu" "B.Cu")
		(net "GND")
	)
	(via
		(at 370.956078 -428.03064)
		(size 0.508)
		(drill 0.254)
		(layers "F.Cu" "B.Cu")
		(net "GND")
	)
	(via
		(at 329.6412 -241.24412)
		(size 0.4064)
		(drill 0.2032)
		(layers "F.Cu" "B.Cu")
		(net "GND")
	)
	(via
		(at 165.812216 -306.135278)
		(size 0.4826)
		(drill 0.254)
		(layers "F.Cu" "B.Cu")
		(net "GND")
	)
	(via
		(at 328.231246 -229.094284)
		(size 0.4064)
		(drill 0.2032)
		(layers "F.Cu" "B.Cu")
		(net "GND")
	)
	(via
		(at 121.653046 -15.247366)
		(size 0.508)
		(drill 0.254)
		(layers "F.Cu" "B.Cu")
		(net "GND")
	)
	(via
		(at 361.124754 -235.574078)
		(size 0.4064)
		(drill 0.2032)
		(layers "F.Cu" "B.Cu")
		(net "GND")
	)
	(via
		(at 413.485584 -276.810216)
		(size 0.4826)
		(drill 0.254)
		(layers "F.Cu" "B.Cu")
		(net "GND")
	)
	(via
		(at 127.584708 -287.046162)
		(size 0.4064)
		(drill 0.2032)
		(layers "F.Cu" "B.Cu")
		(net "GND")
	)
	(via
		(at 457.607924 -61.960252)
		(size 0.6604)
		(drill 0.3302)
		(layers "F.Cu" "B.Cu")
		(net "GND")
	)
	(via
		(at 245.59387 -292.803326)
		(size 0.508)
		(drill 0.254)
		(layers "F.Cu" "B.Cu")
		(net "GND")
	)
	(via
		(at 341.390986 -253.39421)
		(size 0.4064)
		(drill 0.2032)
		(layers "F.Cu" "B.Cu")
		(net "GND")
	)
	(via
		(at 341.390986 -225.85426)
		(size 0.4064)
		(drill 0.2032)
		(layers "F.Cu" "B.Cu")
		(net "GND")
	)
	(via
		(at 333.230982 -261.12597)
		(size 0.4064)
		(drill 0.2032)
		(layers "F.Cu" "B.Cu")
		(net "GND")
	)
	(via
		(at 416.283902 -420.952168)
		(size 0.4064)
		(drill 0.2032)
		(layers "F.Cu" "B.Cu")
		(net "GND")
	)
	(via
		(at 84.99094 -229.094538)
		(size 0.4064)
		(drill 0.2032)
		(layers "F.Cu" "B.Cu")
		(net "GND")
	)
	(via
		(at 124.7648 -265.98626)
		(size 0.4064)
		(drill 0.2032)
		(layers "F.Cu" "B.Cu")
		(net "GND")
	)
	(via
		(at 348.013274 -414.72866)
		(size 0.4572)
		(drill 0.254)
		(layers "F.Cu" "B.Cu")
		(net "GND")
	)
	(via
		(at 167.143684 -295.9354)
		(size 0.4826)
		(drill 0.254)
		(layers "F.Cu" "B.Cu")
		(net "GND")
	)
	(via
		(at 399.349722 -435.0512)
		(size 0.4572)
		(drill 0.2032)
		(layers "F.Cu" "B.Cu")
		(net "GND")
	)
	(via
		(at 51.884072 -316.33541)
		(size 0.4826)
		(drill 0.254)
		(layers "F.Cu" "B.Cu")
		(net "GND")
	)
	(via
		(at 241.681 -236.45495)
		(size 0.508)
		(drill 0.254)
		(layers "F.Cu" "B.Cu")
		(net "GND")
	)
	(via
		(at 334.228694 -421.586152)
		(size 0.4572)
		(drill 0.254)
		(layers "F.Cu" "B.Cu")
		(net "GND")
	)
	(via
		(at 303.978818 -434.914294)
		(size 0.508)
		(drill 0.254)
		(layers "F.Cu" "B.Cu")
		(net "GND")
	)
	(via
		(at 340.921086 -228.284278)
		(size 0.4064)
		(drill 0.2032)
		(layers "F.Cu" "B.Cu")
		(net "GND")
	)
	(via
		(at 378.514864 -238.004096)
		(size 0.4064)
		(drill 0.2032)
		(layers "F.Cu" "B.Cu")
		(net "GND")
	)
	(via
		(at 62.216538 -382.85293)
		(size 0.4064)
		(drill 0.2032)
		(layers "F.Cu" "B.Cu")
		(net "GND")
	)
	(via
		(at 70.617334 -375.917968)
		(size 0.508)
		(drill 0.254)
		(layers "F.Cu" "B.Cu")
		(net "GND")
	)
	(via
		(at 325.24954 -433.747164)
		(size 0.4572)
		(drill 0.2032)
		(layers "F.Cu" "B.Cu")
		(net "GND")
	)
	(via
		(at 424.9674 -32.197548)
		(size 0.508)
		(drill 0.254)
		(layers "F.Cu" "B.Cu")
		(net "GND")
	)
	(via
		(at 126.676658 -410.664152)
		(size 0.4572)
		(drill 0.254)
		(layers "F.Cu" "B.Cu")
		(net "GND")
	)
	(via
		(at 82.306414 -386.449062)
		(size 0.4064)
		(drill 0.2032)
		(layers "F.Cu" "B.Cu")
		(net "GND")
	)
	(via
		(at 381.804926 -245.29415)
		(size 0.4064)
		(drill 0.2032)
		(layers "F.Cu" "B.Cu")
		(net "GND")
	)
	(via
		(at 58.616596 -391.830814)
		(size 0.4064)
		(drill 0.2032)
		(layers "F.Cu" "B.Cu")
		(net "GND")
	)
	(via
		(at 43.885358 -345.571064)
		(size 0.49022)
		(drill 0.254)
		(layers "F.Cu" "B.Cu")
		(net "GND")
	)
	(via
		(at 320.521584 -334.580992)
		(size 0.49022)
		(drill 0.254)
		(layers "F.Cu" "B.Cu")
		(net "GND")
	)
	(via
		(at 411.456886 -77.913484)
		(size 0.508)
		(drill 0.254)
		(layers "F.Cu" "B.Cu")
		(net "GND")
	)
	(via
		(at 43.71848 -105.8164)
		(size 0.508)
		(drill 0.254)
		(layers "F.Cu" "B.Cu")
		(net "GND")
	)
	(via
		(at 97.917508 -423.457116)
		(size 0.508)
		(drill 0.254)
		(layers "F.Cu" "B.Cu")
		(net "GND")
	)
	(via
		(at 334.811116 -229.094284)
		(size 0.4064)
		(drill 0.2032)
		(layers "F.Cu" "B.Cu")
		(net "GND")
	)
	(via
		(at 54.752494 -374.62333)
		(size 0.508)
		(drill 0.254)
		(layers "F.Cu" "B.Cu")
		(net "GND")
	)
	(via
		(at 439.100214 -272.984976)
		(size 0.4826)
		(drill 0.254)
		(layers "F.Cu" "B.Cu")
		(net "GND")
	)
	(via
		(at 339.811106 -283.806138)
		(size 0.4064)
		(drill 0.2032)
		(layers "F.Cu" "B.Cu")
		(net "GND")
	)
	(via
		(at 113.966752 -331.710538)
		(size 0.508)
		(drill 0.254)
		(layers "F.Cu" "B.Cu")
		(net "GND")
	)
	(via
		(at 397.403574 -396.828264)
		(size 0.508)
		(drill 0.254)
		(layers "F.Cu" "B.Cu")
		(net "GND")
	)
	(via
		(at 308.19217 -358.791256)
		(size 0.508)
		(drill 0.254)
		(layers "F.Cu" "B.Cu")
		(net "GND")
	)
	(via
		(at 128.481074 -407.638504)
		(size 0.4572)
		(drill 0.254)
		(layers "F.Cu" "B.Cu")
		(net "GND")
	)
	(via
		(at 428.840392 -210.085178)
		(size 0.4826)
		(drill 0.254)
		(layers "F.Cu" "B.Cu")
		(net "GND")
	)
	(via
		(at 325.24954 -431.29962)
		(size 0.4572)
		(drill 0.2032)
		(layers "F.Cu" "B.Cu")
		(net "GND")
	)
	(via
		(at 350.791018 -232.334054)
		(size 0.4064)
		(drill 0.2032)
		(layers "F.Cu" "B.Cu")
		(net "GND")
	)
	(via
		(at 412.367984 -255.135126)
		(size 0.4826)
		(drill 0.254)
		(layers "F.Cu" "B.Cu")
		(net "GND")
	)
	(via
		(at 62.912752 -413.204152)
		(size 0.4572)
		(drill 0.254)
		(layers "F.Cu" "B.Cu")
		(net "GND")
	)
	(via
		(at 331.351128 -267.606018)
		(size 0.4064)
		(drill 0.2032)
		(layers "F.Cu" "B.Cu")
		(net "GND")
	)
	(via
		(at 148.392134 -403.830536)
		(size 0.4572)
		(drill 0.254)
		(layers "F.Cu" "B.Cu")
		(net "GND")
	)
	(via
		(at 437.715914 -218.585034)
		(size 0.4826)
		(drill 0.254)
		(layers "F.Cu" "B.Cu")
		(net "GND")
	)
	(via
		(at 228.092 -284.262576)
		(size 0.508)
		(drill 0.254)
		(layers "F.Cu" "B.Cu")
		(net "GND")
	)
	(via
		(at 264.386314 -103.272844)
		(size 0.508)
		(drill 0.254)
		(layers "F.Cu" "B.Cu")
		(net "GND")
	)
	(via
		(at 413.309054 -416.020504)
		(size 0.4572)
		(drill 0.254)
		(layers "F.Cu" "B.Cu")
		(net "GND")
	)
	(via
		(at 208.929986 -134.842504)
		(size 0.508)
		(drill 0.254)
		(layers "F.Cu" "B.Cu")
		(net "GND")
	)
	(via
		(at 129.21361 -158.479998)
		(size 0.508)
		(drill 0.254)
		(layers "F.Cu" "B.Cu")
		(net "GND")
	)
	(via
		(at 191.588644 -67.645026)
		(size 0.508)
		(drill 0.254)
		(layers "F.Cu" "B.Cu")
		(net "GND")
	)
	(via
		(at 74.602086 -179.565046)
		(size 0.49022)
		(drill 0.254)
		(layers "F.Cu" "B.Cu")
		(net "GND")
	)
	(via
		(at 356.731062 -291.905944)
		(size 0.4064)
		(drill 0.2032)
		(layers "F.Cu" "B.Cu")
		(net "GND")
	)
	(via
		(at 100.397818 -345.089734)
		(size 0.508)
		(drill 0.254)
		(layers "F.Cu" "B.Cu")
		(net "GND")
	)
	(via
		(at 432.085496 -110.1471)
		(size 0.508)
		(drill 0.254)
		(layers "F.Cu" "B.Cu")
		(net "GND")
	)
	(via
		(at 123.316492 -382.85293)
		(size 0.4064)
		(drill 0.2032)
		(layers "F.Cu" "B.Cu")
		(net "GND")
	)
	(via
		(at 129.873756 -374.62333)
		(size 0.508)
		(drill 0.254)
		(layers "F.Cu" "B.Cu")
		(net "GND")
	)
	(via
		(at 82.54365 -182.177944)
		(size 0.49022)
		(drill 0.254)
		(layers "F.Cu" "B.Cu")
		(net "GND")
	)
	(via
		(at 73.87971 -154.80538)
		(size 0.508)
		(drill 0.254)
		(layers "F.Cu" "B.Cu")
		(net "GND")
	)
	(via
		(at 2.76225 -166.045134)
		(size 0.508)
		(drill 0.254)
		(layers "F.Cu" "B.Cu")
		(net "GND")
	)
	(via
		(at 453.334374 -399.233644)
		(size 0.49022)
		(drill 0.254)
		(layers "F.Cu" "B.Cu")
		(net "GND")
	)
	(via
		(at 146.554698 -228.284532)
		(size 0.4064)
		(drill 0.2032)
		(layers "F.Cu" "B.Cu")
		(net "GND")
	)
	(via
		(at 36.795964 -263.635236)
		(size 0.4826)
		(drill 0.254)
		(layers "F.Cu" "B.Cu")
		(net "GND")
	)
	(via
		(at 23.715218 -18.503138)
		(size 0.508)
		(drill 0.254)
		(layers "F.Cu" "B.Cu")
		(net "GND")
	)
	(via
		(at 341.691214 -262.745982)
		(size 0.4064)
		(drill 0.2032)
		(layers "F.Cu" "B.Cu")
		(net "GND")
	)
	(via
		(at 393.312142 -418.412168)
		(size 0.4064)
		(drill 0.2032)
		(layers "F.Cu" "B.Cu")
		(net "GND")
	)
	(via
		(at 351.731072 -240.434114)
		(size 0.4064)
		(drill 0.2032)
		(layers "F.Cu" "B.Cu")
		(net "GND")
	)
	(via
		(at 374.754902 -250.964192)
		(size 0.4064)
		(drill 0.2032)
		(layers "F.Cu" "B.Cu")
		(net "GND")
	)
	(via
		(at 118.824756 -232.334308)
		(size 0.4064)
		(drill 0.2032)
		(layers "F.Cu" "B.Cu")
		(net "GND")
	)
	(via
		(at 138.377676 -377.617228)
		(size 0.508)
		(drill 0.254)
		(layers "F.Cu" "B.Cu")
		(net "GND")
	)
	(via
		(at 390.349486 -438.651396)
		(size 0.4572)
		(drill 0.2032)
		(layers "F.Cu" "B.Cu")
		(net "GND")
	)
	(via
		(at 442.805566 -423.914824)
		(size 0.508)
		(drill 0.254)
		(layers "F.Cu" "B.Cu")
		(net "GND")
	)
	(via
		(at 126.644654 -277.326344)
		(size 0.4064)
		(drill 0.2032)
		(layers "F.Cu" "B.Cu")
		(net "GND")
	)
	(via
		(at 130.349752 -438.651396)
		(size 0.4572)
		(drill 0.2032)
		(layers "F.Cu" "B.Cu")
		(net "GND")
	)
	(via
		(at 273.092164 -255.135126)
		(size 0.4826)
		(drill 0.254)
		(layers "F.Cu" "B.Cu")
		(net "GND")
	)
	(via
		(at 152.313386 -315.400436)
		(size 0.508)
		(drill 0.254)
		(layers "F.Cu" "B.Cu")
		(net "GND")
	)
	(via
		(at 414.9979 -376.75693)
		(size 0.508)
		(drill 0.254)
		(layers "F.Cu" "B.Cu")
		(net "GND")
	)
	(via
		(at 163.325048 -51.285902)
		(size 0.508)
		(drill 0.254)
		(layers "F.Cu" "B.Cu")
		(net "GND")
	)
	(via
		(at 105.671112 -251.774452)
		(size 0.4064)
		(drill 0.2032)
		(layers "F.Cu" "B.Cu")
		(net "GND")
	)
	(via
		(at 44.340018 -316.33541)
		(size 0.4826)
		(drill 0.254)
		(layers "F.Cu" "B.Cu")
		(net "GND")
	)
	(via
		(at 183.225694 -329.576684)
		(size 0.508)
		(drill 0.254)
		(layers "F.Cu" "B.Cu")
		(net "GND")
	)
	(via
		(at 133.864858 -245.294404)
		(size 0.4064)
		(drill 0.2032)
		(layers "F.Cu" "B.Cu")
		(net "GND")
	)
	(via
		(at 111.578136 -263.846564)
		(size 0.4826)
		(drill 0.254)
		(layers "F.Cu" "B.Cu")
		(net "GND")
	)
	(via
		(at 382.1049 -275.706078)
		(size 0.4064)
		(drill 0.2032)
		(layers "F.Cu" "B.Cu")
		(net "GND")
	)
	(via
		(at 28.134564 -219.860368)
		(size 0.4826)
		(drill 0.254)
		(layers "F.Cu" "B.Cu")
		(net "GND")
	)
	(via
		(at 321.614546 -412.84652)
		(size 0.4064)
		(drill 0.2032)
		(layers "F.Cu" "B.Cu")
		(net "GND")
	)
	(via
		(at 392.349482 -428.851314)
		(size 0.4572)
		(drill 0.2032)
		(layers "F.Cu" "B.Cu")
		(net "GND")
	)
	(via
		(at 99.390962 -283.806392)
		(size 0.4064)
		(drill 0.2032)
		(layers "F.Cu" "B.Cu")
		(net "GND")
	)
	(via
		(at 48.939704 -192.218564)
		(size 0.4826)
		(drill 0.254)
		(layers "F.Cu" "B.Cu")
		(net "GND")
	)
	(via
		(at 351.589848 -392.999722)
		(size 0.4064)
		(drill 0.2032)
		(layers "F.Cu" "B.Cu")
		(net "GND")
	)
	(via
		(at 423.23766 -366.875314)
		(size 0.508)
		(drill 0.254)
		(layers "F.Cu" "B.Cu")
		(net "GND")
	)
	(via
		(at 388.21487 -271.656048)
		(size 0.4064)
		(drill 0.2032)
		(layers "F.Cu" "B.Cu")
		(net "GND")
	)
	(via
		(at 336.22107 -250.964192)
		(size 0.4064)
		(drill 0.2032)
		(layers "F.Cu" "B.Cu")
		(net "GND")
	)
	(via
		(at 123.135136 -257.930396)
		(size 0.4826)
		(drill 0.254)
		(layers "F.Cu" "B.Cu")
		(net "GND")
	)
	(via
		(at 316.8523 -335.561178)
		(size 0.49022)
		(drill 0.254)
		(layers "F.Cu" "B.Cu")
		(net "GND")
	)
	(via
		(at 387.914896 -231.524048)
		(size 0.4064)
		(drill 0.2032)
		(layers "F.Cu" "B.Cu")
		(net "GND")
	)
	(via
		(at 390.094724 -270.036036)
		(size 0.4064)
		(drill 0.2032)
		(layers "F.Cu" "B.Cu")
		(net "GND")
	)
	(via
		(at 460.248762 -408.27325)
		(size 0.508)
		(drill 0.254)
		(layers "F.Cu" "B.Cu")
		(net "GND")
	)
	(via
		(at 290.895786 -230.485188)
		(size 0.4826)
		(drill 0.254)
		(layers "F.Cu" "B.Cu")
		(net "GND")
	)
	(via
		(at 128.208278 -411.936184)
		(size 0.4572)
		(drill 0.254)
		(layers "F.Cu" "B.Cu")
		(net "GND")
	)
	(via
		(at 178.33213 -114.262916)
		(size 0.4572)
		(drill 0.254)
		(layers "F.Cu" "B.Cu")
		(net "GND")
	)
	(via
		(at 126.34468 -237.194344)
		(size 0.4064)
		(drill 0.2032)
		(layers "F.Cu" "B.Cu")
		(net "GND")
	)
	(via
		(at 192.577466 -389.880602)
		(size 0.508)
		(drill 0.254)
		(layers "F.Cu" "B.Cu")
		(net "GND")
	)
	(via
		(at 286.562546 -12.542266)
		(size 0.508)
		(drill 0.254)
		(layers "F.Cu" "B.Cu")
		(net "GND")
	)
	(via
		(at 59.620658 -145.087594)
		(size 0.508)
		(drill 0.254)
		(layers "F.Cu" "B.Cu")
		(net "GND")
	)
	(via
		(at 378.116592 -402.259038)
		(size 0.4572)
		(drill 0.254)
		(layers "F.Cu" "B.Cu")
		(net "GND")
	)
	(via
		(at 83.391502 -369.03533)
		(size 0.508)
		(drill 0.254)
		(layers "F.Cu" "B.Cu")
		(net "GND")
	)
	(via
		(at 296.879772 -192.21831)
		(size 0.4826)
		(drill 0.254)
		(layers "F.Cu" "B.Cu")
		(net "GND")
	)
	(via
		(at 80.249776 -433.899564)
		(size 0.4572)
		(drill 0.2032)
		(layers "F.Cu" "B.Cu")
		(net "GND")
	)
	(via
		(at 133.394704 -234.764326)
		(size 0.4064)
		(drill 0.2032)
		(layers "F.Cu" "B.Cu")
		(net "GND")
	)
	(via
		(at 337.543902 -402.284438)
		(size 0.4572)
		(drill 0.254)
		(layers "F.Cu" "B.Cu")
		(net "GND")
	)
	(via
		(at 114.894614 -281.376374)
		(size 0.4064)
		(drill 0.2032)
		(layers "F.Cu" "B.Cu")
		(net "GND")
	)
	(via
		(at 337.461098 -294.335962)
		(size 0.4064)
		(drill 0.2032)
		(layers "F.Cu" "B.Cu")
		(net "GND")
	)
	(via
		(at 234.41152 -291.228526)
		(size 0.508)
		(drill 0.254)
		(layers "F.Cu" "B.Cu")
		(net "GND")
	)
	(via
		(at 376.634756 -231.524048)
		(size 0.4064)
		(drill 0.2032)
		(layers "F.Cu" "B.Cu")
		(net "GND")
	)
	(via
		(at 80.120998 -266.796266)
		(size 0.4064)
		(drill 0.2032)
		(layers "F.Cu" "B.Cu")
		(net "GND")
	)
	(via
		(at 21.70811 -271.285208)
		(size 0.4826)
		(drill 0.254)
		(layers "F.Cu" "B.Cu")
		(net "GND")
	)
	(via
		(at 362.834682 -273.27606)
		(size 0.4064)
		(drill 0.2032)
		(layers "F.Cu" "B.Cu")
		(net "GND")
	)
	(via
		(at 361.594908 -229.904036)
		(size 0.4064)
		(drill 0.2032)
		(layers "F.Cu" "B.Cu")
		(net "GND")
	)
	(via
		(at 173.08957 -286.160464)
		(size 0.4826)
		(drill 0.254)
		(layers "F.Cu" "B.Cu")
		(net "GND")
	)
	(via
		(at 422.627806 -239.835182)
		(size 0.4826)
		(drill 0.254)
		(layers "F.Cu" "B.Cu")
		(net "GND")
	)
	(via
		(at 324.766178 -414.72866)
		(size 0.4572)
		(drill 0.254)
		(layers "F.Cu" "B.Cu")
		(net "GND")
	)
	(via
		(at 389.79475 -247.724168)
		(size 0.4064)
		(drill 0.2032)
		(layers "F.Cu" "B.Cu")
		(net "GND")
	)
	(via
		(at 290.895786 -314.635134)
		(size 0.4826)
		(drill 0.254)
		(layers "F.Cu" "B.Cu")
		(net "GND")
	)
	(via
		(at 36.004754 -347.287088)
		(size 0.49022)
		(drill 0.254)
		(layers "F.Cu" "B.Cu")
		(net "GND")
	)
	(via
		(at 104.635808 -31.254954)
		(size 0.508)
		(drill 0.254)
		(layers "F.Cu" "B.Cu")
		(net "GND")
	)
	(via
		(at 358.61117 -275.706078)
		(size 0.4064)
		(drill 0.2032)
		(layers "F.Cu" "B.Cu")
		(net "GND")
	)
	(via
		(at 113.184686 -232.334308)
		(size 0.4064)
		(drill 0.2032)
		(layers "F.Cu" "B.Cu")
		(net "GND")
	)
	(via
		(at 367.064798 -277.32609)
		(size 0.4064)
		(drill 0.2032)
		(layers "F.Cu" "B.Cu")
		(net "GND")
	)
	(via
		(at 72.584818 -334.585818)
		(size 0.49022)
		(drill 0.254)
		(layers "F.Cu" "B.Cu")
		(net "GND")
	)
	(via
		(at 100.971096 -224.234502)
		(size 0.4064)
		(drill 0.2032)
		(layers "F.Cu" "B.Cu")
		(net "GND")
	)
	(via
		(at 99.090988 -235.574332)
		(size 0.4064)
		(drill 0.2032)
		(layers "F.Cu" "B.Cu")
		(net "GND")
	)
	(via
		(at 17.608042 -234.73537)
		(size 0.4826)
		(drill 0.254)
		(layers "F.Cu" "B.Cu")
		(net "GND")
	)
	(via
		(at 229.527354 -328.638662)
		(size 0.508)
		(drill 0.254)
		(layers "F.Cu" "B.Cu")
		(net "GND")
	)
	(via
		(at 191.160146 -280.635202)
		(size 0.4826)
		(drill 0.254)
		(layers "F.Cu" "B.Cu")
		(net "GND")
	)
	(via
		(at 405.565102 -415.38652)
		(size 0.4064)
		(drill 0.2032)
		(layers "F.Cu" "B.Cu")
		(net "GND")
	)
	(via
		(at 332.4098 -149.9362)
		(size 0.508)
		(drill 0.254)
		(layers "F.Cu" "B.Cu")
		(net "GND")
	)
	(via
		(at 424.012106 -261.93496)
		(size 0.4826)
		(drill 0.254)
		(layers "F.Cu" "B.Cu")
		(net "GND")
	)
	(via
		(at 413.934148 -17.613122)
		(size 0.508)
		(drill 0.254)
		(layers "F.Cu" "B.Cu")
		(net "GND")
	)
	(via
		(at 161.179764 -103.593392)
		(size 0.508)
		(drill 0.254)
		(layers "F.Cu" "B.Cu")
		(net "GND")
	)
	(via
		(at 395.781276 -177.599086)
		(size 0.49022)
		(drill 0.254)
		(layers "F.Cu" "B.Cu")
		(net "GND")
	)
	(via
		(at 467.5378 -244.907054)
		(size 0.508)
		(drill 0.254)
		(layers "F.Cu" "B.Cu")
		(net "GND")
	)
	(via
		(at 184.855358 -349.360236)
		(size 0.49022)
		(drill 0.254)
		(layers "F.Cu" "B.Cu")
		(net "GND")
	)
	(via
		(at 132.799074 -112.702848)
		(size 0.508)
		(drill 0.254)
		(layers "F.Cu" "B.Cu")
		(net "GND")
	)
	(via
		(at 103.621078 -268.416278)
		(size 0.4064)
		(drill 0.2032)
		(layers "F.Cu" "B.Cu")
		(net "GND")
	)
	(via
		(at 361.124754 -229.094284)
		(size 0.4064)
		(drill 0.2032)
		(layers "F.Cu" "B.Cu")
		(net "GND")
	)
	(via
		(at 381.058674 -183.893968)
		(size 0.49022)
		(drill 0.254)
		(layers "F.Cu" "B.Cu")
		(net "GND")
	)
	(via
		(at 191.160146 -278.935434)
		(size 0.4826)
		(drill 0.254)
		(layers "F.Cu" "B.Cu")
		(net "GND")
	)
	(via
		(at 439.100214 -282.33497)
		(size 0.4826)
		(drill 0.254)
		(layers "F.Cu" "B.Cu")
		(net "GND")
	)
	(via
		(at 344.704924 -333.085186)
		(size 0.49022)
		(drill 0.254)
		(layers "F.Cu" "B.Cu")
		(net "GND")
	)
	(via
		(at 448.312794 -54.98846)
		(size 0.508)
		(drill 0.254)
		(layers "F.Cu" "B.Cu")
		(net "GND")
	)
	(via
		(at 329.1205 -328.097134)
		(size 0.508)
		(drill 0.254)
		(layers "F.Cu" "B.Cu")
		(net "GND")
	)
	(via
		(at 47.784004 -208.38541)
		(size 0.4826)
		(drill 0.254)
		(layers "F.Cu" "B.Cu")
		(net "GND")
	)
	(via
		(at 333.529686 -305.028092)
		(size 0.508)
		(drill 0.254)
		(layers "F.Cu" "B.Cu")
		(net "GND")
	)
	(via
		(at 357.368094 -253.392178)
		(size 0.4064)
		(drill 0.2032)
		(layers "F.Cu" "B.Cu")
		(net "GND")
	)
	(via
		(at 107.339384 -441.227718)
		(size 0.508)
		(drill 0.254)
		(layers "F.Cu" "B.Cu")
		(net "GND")
	)
	(via
		(at 176.072038 -196.485256)
		(size 0.4826)
		(drill 0.254)
		(layers "F.Cu" "B.Cu")
		(net "GND")
	)
	(via
		(at 381.41783 -419.046152)
		(size 0.4572)
		(drill 0.254)
		(layers "F.Cu" "B.Cu")
		(net "GND")
	)
	(via
		(at 325.580756 -376.75693)
		(size 0.508)
		(drill 0.254)
		(layers "F.Cu" "B.Cu")
		(net "GND")
	)
	(via
		(at 342.749124 -333.874364)
		(size 0.49022)
		(drill 0.254)
		(layers "F.Cu" "B.Cu")
		(net "GND")
	)
	(via
		(at 105.031032 -278.946356)
		(size 0.4064)
		(drill 0.2032)
		(layers "F.Cu" "B.Cu")
		(net "GND")
	)
	(via
		(at 450.088 -281.485086)
		(size 0.4826)
		(drill 0.254)
		(layers "F.Cu" "B.Cu")
		(net "GND")
	)
	(via
		(at 46.666404 -295.510458)
		(size 0.4826)
		(drill 0.254)
		(layers "F.Cu" "B.Cu")
		(net "GND")
	)
	(via
		(at 89.690956 -246.914416)
		(size 0.4064)
		(drill 0.2032)
		(layers "F.Cu" "B.Cu")
		(net "GND")
	)
	(via
		(at 81.701132 -229.90429)
		(size 0.4064)
		(drill 0.2032)
		(layers "F.Cu" "B.Cu")
		(net "GND")
	)
	(via
		(at 43.222418 -275.960332)
		(size 0.4826)
		(drill 0.254)
		(layers "F.Cu" "B.Cu")
		(net "GND")
	)
	(via
		(at 199.8218 -294.66032)
		(size 0.4826)
		(drill 0.254)
		(layers "F.Cu" "B.Cu")
		(net "GND")
	)
	(via
		(at 379.066552 -381.68453)
		(size 0.508)
		(drill 0.254)
		(layers "F.Cu" "B.Cu")
		(net "GND")
	)
	(via
		(at 128.955292 -77.50683)
		(size 0.508)
		(drill 0.254)
		(layers "F.Cu" "B.Cu")
		(net "GND")
	)
	(via
		(at 381.291338 -398.542002)
		(size 0.4064)
		(drill 0.2032)
		(layers "F.Cu" "B.Cu")
		(net "GND")
	)
	(via
		(at 299.82414 -299.33519)
		(size 0.4826)
		(drill 0.254)
		(layers "F.Cu" "B.Cu")
		(net "GND")
	)
	(via
		(at 187.060078 -233.035348)
		(size 0.4826)
		(drill 0.254)
		(layers "F.Cu" "B.Cu")
		(net "GND")
	)
	(via
		(at 370.35486 -294.335962)
		(size 0.4064)
		(drill 0.2032)
		(layers "F.Cu" "B.Cu")
		(net "GND")
	)
	(via
		(at 143.73479 -255.824482)
		(size 0.4064)
		(drill 0.2032)
		(layers "F.Cu" "B.Cu")
		(net "GND")
	)
	(via
		(at 71.249794 -431.451258)
		(size 0.4572)
		(drill 0.2032)
		(layers "F.Cu" "B.Cu")
		(net "GND")
	)
	(via
		(at 143.797274 -406.370536)
		(size 0.4572)
		(drill 0.254)
		(layers "F.Cu" "B.Cu")
		(net "GND")
	)
	(via
		(at 179.281582 -414.926272)
		(size 0.508)
		(drill 0.254)
		(layers "F.Cu" "B.Cu")
		(net "GND")
	)
	(via
		(at 388.384796 -248.534174)
		(size 0.4064)
		(drill 0.2032)
		(layers "F.Cu" "B.Cu")
		(net "GND")
	)
	(via
		(at 374.284748 -256.634234)
		(size 0.4064)
		(drill 0.2032)
		(layers "F.Cu" "B.Cu")
		(net "GND")
	)
	(via
		(at 359.798366 -333.5274)
		(size 0.6604)
		(drill 0.3302)
		(layers "F.Cu" "B.Cu")
		(net "GND")
	)
	(via
		(at 75.165712 -413.204152)
		(size 0.4572)
		(drill 0.254)
		(layers "F.Cu" "B.Cu")
		(net "GND")
	)
	(via
		(at 342.801194 -242.864132)
		(size 0.4064)
		(drill 0.2032)
		(layers "F.Cu" "B.Cu")
		(net "GND")
	)
	(via
		(at 144.504664 -269.226284)
		(size 0.4064)
		(drill 0.2032)
		(layers "F.Cu" "B.Cu")
		(net "GND")
	)
	(via
		(at 87.171022 -274.08632)
		(size 0.4064)
		(drill 0.2032)
		(layers "F.Cu" "B.Cu")
		(net "GND")
	)
	(via
		(at 354.046028 -396.710662)
		(size 0.4064)
		(drill 0.2032)
		(layers "F.Cu" "B.Cu")
		(net "GND")
	)
	(via
		(at 47.5615 -32.937196)
		(size 0.508)
		(drill 0.254)
		(layers "F.Cu" "B.Cu")
		(net "GND")
	)
	(via
		(at 387.716522 -400.212814)
		(size 0.4064)
		(drill 0.2032)
		(layers "F.Cu" "B.Cu")
		(net "GND")
	)
	(via
		(at 348.911164 -224.234248)
		(size 0.4064)
		(drill 0.2032)
		(layers "F.Cu" "B.Cu")
		(net "GND")
	)
	(via
		(at 437.978042 -425.94911)
		(size 0.508)
		(drill 0.254)
		(layers "F.Cu" "B.Cu")
		(net "GND")
	)
	(via
		(at 21.623782 -412.850584)
		(size 0.508)
		(drill 0.254)
		(layers "F.Cu" "B.Cu")
		(net "GND")
	)
	(via
		(at 82.74431 -393.927838)
		(size 0.4572)
		(drill 0.254)
		(layers "F.Cu" "B.Cu")
		(net "GND")
	)
	(via
		(at 398.083278 -176.605184)
		(size 0.49022)
		(drill 0.254)
		(layers "F.Cu" "B.Cu")
		(net "GND")
	)
	(via
		(at 401.056094 -419.046152)
		(size 0.4572)
		(drill 0.254)
		(layers "F.Cu" "B.Cu")
		(net "GND")
	)
	(via
		(at 179.516024 -311.235344)
		(size 0.4826)
		(drill 0.254)
		(layers "F.Cu" "B.Cu")
		(net "GND")
	)
	(via
		(at 274.476464 -212.635084)
		(size 0.4826)
		(drill 0.254)
		(layers "F.Cu" "B.Cu")
		(net "GND")
	)
	(via
		(at 310.09717 -362.601256)
		(size 0.508)
		(drill 0.254)
		(layers "F.Cu" "B.Cu")
		(net "GND")
	)
	(via
		(at 374.114822 -261.935976)
		(size 0.4064)
		(drill 0.2032)
		(layers "F.Cu" "B.Cu")
		(net "GND")
	)
	(via
		(at 419.912038 -300.185074)
		(size 0.4826)
		(drill 0.254)
		(layers "F.Cu" "B.Cu")
		(net "GND")
	)
	(via
		(at 140.274802 -273.276314)
		(size 0.4064)
		(drill 0.2032)
		(layers "F.Cu" "B.Cu")
		(net "GND")
	)
	(via
		(at 165.812216 -231.335326)
		(size 0.4826)
		(drill 0.254)
		(layers "F.Cu" "B.Cu")
		(net "GND")
	)
	(via
		(at 306.659534 -420.318184)
		(size 0.4572)
		(drill 0.254)
		(layers "F.Cu" "B.Cu")
		(net "GND")
	)
	(via
		(at 357.671116 -291.905944)
		(size 0.4064)
		(drill 0.2032)
		(layers "F.Cu" "B.Cu")
		(net "GND")
	)
	(via
		(at 72.60971 -151.63038)
		(size 0.6604)
		(drill 0.3302)
		(layers "F.Cu" "B.Cu")
		(net "GND")
	)
	(via
		(at 333.230982 -285.42615)
		(size 0.4064)
		(drill 0.2032)
		(layers "F.Cu" "B.Cu")
		(net "GND")
	)
	(via
		(at 180.929026 -166.358316)
		(size 0.508)
		(drill 0.254)
		(layers "F.Cu" "B.Cu")
		(net "GND")
	)
	(via
		(at 391.674858 -228.284278)
		(size 0.4064)
		(drill 0.2032)
		(layers "F.Cu" "B.Cu")
		(net "GND")
	)
	(via
		(at 390.349486 -431.451258)
		(size 0.4572)
		(drill 0.2032)
		(layers "F.Cu" "B.Cu")
		(net "GND")
	)
	(via
		(at 334.64119 -271.656048)
		(size 0.4064)
		(drill 0.2032)
		(layers "F.Cu" "B.Cu")
		(net "GND")
	)
	(via
		(at 77.112876 -282.730448)
		(size 0.4064)
		(drill 0.2032)
		(layers "F.Cu" "B.Cu")
		(net "GND")
	)
	(via
		(at 105.971086 -293.52621)
		(size 0.4064)
		(drill 0.2032)
		(layers "F.Cu" "B.Cu")
		(net "GND")
	)
	(via
		(at 119.71655 -382.85293)
		(size 0.4064)
		(drill 0.2032)
		(layers "F.Cu" "B.Cu")
		(net "GND")
	)
	(via
		(at 124.294646 -270.03629)
		(size 0.4064)
		(drill 0.2032)
		(layers "F.Cu" "B.Cu")
		(net "GND")
	)
	(via
		(at 309.449978 -416.020504)
		(size 0.4572)
		(drill 0.254)
		(layers "F.Cu" "B.Cu")
		(net "GND")
	)
	(via
		(at 439.100214 -261.93496)
		(size 0.4826)
		(drill 0.254)
		(layers "F.Cu" "B.Cu")
		(net "GND")
	)
	(via
		(at 82.001106 -261.93623)
		(size 0.4064)
		(drill 0.2032)
		(layers "F.Cu" "B.Cu")
		(net "GND")
	)
	(via
		(at 97.629218 -333.86395)
		(size 0.49022)
		(drill 0.254)
		(layers "F.Cu" "B.Cu")
		(net "GND")
	)
	(via
		(at 61.62802 -351.862898)
		(size 0.508)
		(drill 0.254)
		(layers "F.Cu" "B.Cu")
		(net "GND")
	)
	(via
		(at 74.892916 -409.396184)
		(size 0.4572)
		(drill 0.254)
		(layers "F.Cu" "B.Cu")
		(net "GND")
	)
	(via
		(at 121.174764 -233.144314)
		(size 0.4064)
		(drill 0.2032)
		(layers "F.Cu" "B.Cu")
		(net "GND")
	)
	(via
		(at 87.81415 -186.580526)
		(size 0.508)
		(drill 0.254)
		(layers "F.Cu" "B.Cu")
		(net "GND")
	)
	(via
		(at 371.606318 -34.637472)
		(size 0.508)
		(drill 0.254)
		(layers "F.Cu" "B.Cu")
		(net "GND")
	)
	(via
		(at 103.321104 -250.964446)
		(size 0.4064)
		(drill 0.2032)
		(layers "F.Cu" "B.Cu")
		(net "GND")
	)
	(via
		(at 414.363154 -441.227718)
		(size 0.508)
		(drill 0.254)
		(layers "F.Cu" "B.Cu")
		(net "GND")
	)
	(via
		(at 353.61118 -237.19409)
		(size 0.4064)
		(drill 0.2032)
		(layers "F.Cu" "B.Cu")
		(net "GND")
	)
	(via
		(at 342.249506 -427.699678)
		(size 0.4572)
		(drill 0.2032)
		(layers "F.Cu" "B.Cu")
		(net "GND")
	)
	(via
		(at 327.249536 -427.851316)
		(size 0.4572)
		(drill 0.2032)
		(layers "F.Cu" "B.Cu")
		(net "GND")
	)
	(via
		(at 339.562694 -310.418226)
		(size 0.508)
		(drill 0.254)
		(layers "F.Cu" "B.Cu")
		(net "GND")
	)
	(via
		(at 95.076772 -410.664152)
		(size 0.4572)
		(drill 0.254)
		(layers "F.Cu" "B.Cu")
		(net "GND")
	)
	(via
		(at 28.619958 -345.571064)
		(size 0.49022)
		(drill 0.254)
		(layers "F.Cu" "B.Cu")
		(net "GND")
	)
	(via
		(at 163.106354 -419.090094)
		(size 0.508)
		(drill 0.254)
		(layers "F.Cu" "B.Cu")
		(net "GND")
	)
	(via
		(at 421.296338 -240.685066)
		(size 0.4826)
		(drill 0.254)
		(layers "F.Cu" "B.Cu")
		(net "GND")
	)
	(via
		(at 269.648178 -235.585)
		(size 0.4826)
		(drill 0.254)
		(layers "F.Cu" "B.Cu")
		(net "GND")
	)
	(via
		(at 387.914896 -241.24412)
		(size 0.4064)
		(drill 0.2032)
		(layers "F.Cu" "B.Cu")
		(net "GND")
	)
	(via
		(at 314.761372 -34.858706)
		(size 0.508)
		(drill 0.254)
		(layers "F.Cu" "B.Cu")
		(net "GND")
	)
	(via
		(at 427.456092 -269.585186)
		(size 0.4826)
		(drill 0.254)
		(layers "F.Cu" "B.Cu")
		(net "GND")
	)
	(via
		(at 131.55041 -10.733278)
		(size 0.508)
		(drill 0.254)
		(layers "F.Cu" "B.Cu")
		(net "GND")
	)
	(via
		(at 329.249532 -431.29962)
		(size 0.4572)
		(drill 0.2032)
		(layers "F.Cu" "B.Cu")
		(net "GND")
	)
	(via
		(at 417.585652 -229.210108)
		(size 0.4826)
		(drill 0.254)
		(layers "F.Cu" "B.Cu")
		(net "GND")
	)
	(via
		(at 29.299662 -430.769014)
		(size 0.508)
		(drill 0.254)
		(layers "F.Cu" "B.Cu")
		(net "GND")
	)
	(via
		(at 269.648178 -255.135126)
		(size 0.4826)
		(drill 0.254)
		(layers "F.Cu" "B.Cu")
		(net "GND")
	)
	(via
		(at 332.931008 -240.434114)
		(size 0.4064)
		(drill 0.2032)
		(layers "F.Cu" "B.Cu")
		(net "GND")
	)
	(via
		(at 347.986858 -160.573466)
		(size 0.49022)
		(drill 0.254)
		(layers "F.Cu" "B.Cu")
		(net "GND")
	)
	(via
		(at 324.75297 -251.23013)
		(size 0.4064)
		(drill 0.2032)
		(layers "F.Cu" "B.Cu")
		(net "GND")
	)
	(via
		(at 205.802484 -343.404952)
		(size 0.508)
		(drill 0.254)
		(layers "F.Cu" "B.Cu")
		(net "GND")
	)
	(via
		(at 331.821028 -286.236156)
		(size 0.4064)
		(drill 0.2032)
		(layers "F.Cu" "B.Cu")
		(net "GND")
	)
	(via
		(at 399.34642 -389.382)
		(size 0.508)
		(drill 0.254)
		(layers "F.Cu" "B.Cu")
		(net "GND")
	)
	(via
		(at 353.841812 -338.769198)
		(size 0.49022)
		(drill 0.254)
		(layers "F.Cu" "B.Cu")
		(net "GND")
	)
	(via
		(at 86.249764 -426.54728)
		(size 0.4572)
		(drill 0.2032)
		(layers "F.Cu" "B.Cu")
		(net "GND")
	)
	(via
		(at 362.04906 -415.415984)
		(size 0.508)
		(drill 0.254)
		(layers "F.Cu" "B.Cu")
		(net "GND")
	)
	(via
		(at 79.185516 -30.853888)
		(size 0.508)
		(drill 0.254)
		(layers "F.Cu" "B.Cu")
		(net "GND")
	)
	(via
		(at 352.744278 -176.122838)
		(size 0.508)
		(drill 0.254)
		(layers "F.Cu" "B.Cu")
		(net "GND")
	)
	(via
		(at 340.355174 -412.212536)
		(size 0.4572)
		(drill 0.254)
		(layers "F.Cu" "B.Cu")
		(net "GND")
	)
	(via
		(at 99.480878 -138.891264)
		(size 0.508)
		(drill 0.254)
		(layers "F.Cu" "B.Cu")
		(net "GND")
	)
	(via
		(at 32.695896 -247.485408)
		(size 0.4826)
		(drill 0.254)
		(layers "F.Cu" "B.Cu")
		(net "GND")
	)
	(via
		(at 397.058388 -383.68986)
		(size 0.508)
		(drill 0.254)
		(layers "F.Cu" "B.Cu")
		(net "GND")
	)
	(via
		(at 121.474738 -281.376374)
		(size 0.4064)
		(drill 0.2032)
		(layers "F.Cu" "B.Cu")
		(net "GND")
	)
	(via
		(at 103.145082 -380.535688)
		(size 0.508)
		(drill 0.254)
		(layers "F.Cu" "B.Cu")
		(net "GND")
	)
	(via
		(at 64.54013 -53.14569)
		(size 0.508)
		(drill 0.254)
		(layers "F.Cu" "B.Cu")
		(net "GND")
	)
	(via
		(at 72.646286 -179.565046)
		(size 0.49022)
		(drill 0.254)
		(layers "F.Cu" "B.Cu")
		(net "GND")
	)
	(via
		(at 279.518364 -314.210192)
		(size 0.4826)
		(drill 0.254)
		(layers "F.Cu" "B.Cu")
		(net "GND")
	)
	(via
		(at 308.757574 -24.090884)
		(size 0.508)
		(drill 0.254)
		(layers "F.Cu" "B.Cu")
		(net "GND")
	)
	(via
		(at 397.469106 -394.858494)
		(size 0.508)
		(drill 0.254)
		(layers "F.Cu" "B.Cu")
		(net "GND")
	)
	(via
		(at 328.53122 -287.045908)
		(size 0.4064)
		(drill 0.2032)
		(layers "F.Cu" "B.Cu")
		(net "GND")
	)
	(via
		(at 206.188818 -352.591116)
		(size 0.508)
		(drill 0.254)
		(layers "F.Cu" "B.Cu")
		(net "GND")
	)
	(via
		(at 352.031046 -291.905944)
		(size 0.4064)
		(drill 0.2032)
		(layers "F.Cu" "B.Cu")
		(net "GND")
	)
	(via
		(at 350.151192 -280.566114)
		(size 0.4064)
		(drill 0.2032)
		(layers "F.Cu" "B.Cu")
		(net "GND")
	)
	(via
		(at 27.299158 -345.571064)
		(size 0.49022)
		(drill 0.254)
		(layers "F.Cu" "B.Cu")
		(net "GND")
	)
	(via
		(at 130.104642 -229.094538)
		(size 0.4064)
		(drill 0.2032)
		(layers "F.Cu" "B.Cu")
		(net "GND")
	)
	(via
		(at 416.468052 -278.93518)
		(size 0.4826)
		(drill 0.254)
		(layers "F.Cu" "B.Cu")
		(net "GND")
	)
	(via
		(at 108.901484 -386.518658)
		(size 0.508)
		(drill 0.254)
		(layers "F.Cu" "B.Cu")
		(net "GND")
	)
	(via
		(at 325.052944 -268.150086)
		(size 0.4064)
		(drill 0.2032)
		(layers "F.Cu" "B.Cu")
		(net "GND")
	)
	(via
		(at 61.893958 -346.322142)
		(size 0.49022)
		(drill 0.254)
		(layers "F.Cu" "B.Cu")
		(net "GND")
	)
	(via
		(at 410.157422 -420.952168)
		(size 0.4064)
		(drill 0.2032)
		(layers "F.Cu" "B.Cu")
		(net "GND")
	)
	(via
		(at 198.7042 -205.83525)
		(size 0.4826)
		(drill 0.254)
		(layers "F.Cu" "B.Cu")
		(net "GND")
	)
	(via
		(at 90.16111 -249.344434)
		(size 0.4064)
		(drill 0.2032)
		(layers "F.Cu" "B.Cu")
		(net "GND")
	)
	(via
		(at 68.366894 -368.37493)
		(size 0.508)
		(drill 0.254)
		(layers "F.Cu" "B.Cu")
		(net "GND")
	)
	(via
		(at 101.035866 -184.632346)
		(size 0.49022)
		(drill 0.254)
		(layers "F.Cu" "B.Cu")
		(net "GND")
	)
	(via
		(at 340.082378 -414.752536)
		(size 0.4572)
		(drill 0.254)
		(layers "F.Cu" "B.Cu")
		(net "GND")
	)
	(via
		(at 437.715914 -221.13494)
		(size 0.4826)
		(drill 0.254)
		(layers "F.Cu" "B.Cu")
		(net "GND")
	)
	(via
		(at 443.9285 -284.88513)
		(size 0.4826)
		(drill 0.254)
		(layers "F.Cu" "B.Cu")
		(net "GND")
	)
	(via
		(at 338.401152 -276.516084)
		(size 0.4064)
		(drill 0.2032)
		(layers "F.Cu" "B.Cu")
		(net "GND")
	)
	(via
		(at 115.955318 -405.098504)
		(size 0.4572)
		(drill 0.254)
		(layers "F.Cu" "B.Cu")
		(net "GND")
	)
	(via
		(at 48.054514 -343.476834)
		(size 0.508)
		(drill 0.254)
		(layers "F.Cu" "B.Cu")
		(net "GND")
	)
	(via
		(at 88.677496 -413.204152)
		(size 0.4572)
		(drill 0.254)
		(layers "F.Cu" "B.Cu")
		(net "GND")
	)
	(via
		(at 374.584722 -264.365994)
		(size 0.4064)
		(drill 0.2032)
		(layers "F.Cu" "B.Cu")
		(net "GND")
	)
	(via
		(at 408.271726 -142.57782)
		(size 0.508)
		(drill 0.254)
		(layers "F.Cu" "B.Cu")
		(net "GND")
	)
	(via
		(at 125.5268 -40.3352)
		(size 0.508)
		(drill 0.254)
		(layers "F.Cu" "B.Cu")
		(net "GND")
	)
	(via
		(at 400.16684 -379.88113)
		(size 0.508)
		(drill 0.254)
		(layers "F.Cu" "B.Cu")
		(net "GND")
	)
	(via
		(at 335.90611 -394.831062)
		(size 0.4064)
		(drill 0.2032)
		(layers "F.Cu" "B.Cu")
		(net "GND")
	)
	(via
		(at 248.689114 -316.46368)
		(size 0.508)
		(drill 0.254)
		(layers "F.Cu" "B.Cu")
		(net "GND")
	)
	(via
		(at 80.291178 -240.434368)
		(size 0.4064)
		(drill 0.2032)
		(layers "F.Cu" "B.Cu")
		(net "GND")
	)
	(via
		(at 331.351128 -265.986006)
		(size 0.4064)
		(drill 0.2032)
		(layers "F.Cu" "B.Cu")
		(net "GND")
	)
	(via
		(at 105.971086 -282.18638)
		(size 0.4064)
		(drill 0.2032)
		(layers "F.Cu" "B.Cu")
		(net "GND")
	)
	(via
		(at 393.67079 -417.778184)
		(size 0.4572)
		(drill 0.254)
		(layers "F.Cu" "B.Cu")
		(net "GND")
	)
	(via
		(at 56.712358 -240.68532)
		(size 0.4826)
		(drill 0.254)
		(layers "F.Cu" "B.Cu")
		(net "GND")
	)
	(via
		(at 367.064798 -275.706078)
		(size 0.4064)
		(drill 0.2032)
		(layers "F.Cu" "B.Cu")
		(net "GND")
	)
	(via
		(at 99.861116 -286.23641)
		(size 0.4064)
		(drill 0.2032)
		(layers "F.Cu" "B.Cu")
		(net "GND")
	)
	(via
		(at 346.25788 -331.119734)
		(size 0.508)
		(drill 0.254)
		(layers "F.Cu" "B.Cu")
		(net "GND")
	)
	(via
		(at 133.864858 -255.014476)
		(size 0.4064)
		(drill 0.2032)
		(layers "F.Cu" "B.Cu")
		(net "GND")
	)
	(via
		(at 17.608042 -225.385376)
		(size 0.4826)
		(drill 0.254)
		(layers "F.Cu" "B.Cu")
		(net "GND")
	)
	(via
		(at 5.229098 -133.08838)
		(size 0.508)
		(drill 0.254)
		(layers "F.Cu" "B.Cu")
		(net "GND")
	)
	(via
		(at 385.094734 -238.004096)
		(size 0.4064)
		(drill 0.2032)
		(layers "F.Cu" "B.Cu")
		(net "GND")
	)
	(via
		(at 376.493278 -144.266158)
		(size 0.508)
		(drill 0.254)
		(layers "F.Cu" "B.Cu")
		(net "GND")
	)
	(via
		(at 44.340018 -198.185278)
		(size 0.4826)
		(drill 0.254)
		(layers "F.Cu" "B.Cu")
		(net "GND")
	)
	(via
		(at 35.395662 -430.799748)
		(size 0.508)
		(drill 0.254)
		(layers "F.Cu" "B.Cu")
		(net "GND")
	)
	(via
		(at 32.695896 -233.035348)
		(size 0.4826)
		(drill 0.254)
		(layers "F.Cu" "B.Cu")
		(net "GND")
	)
	(via
		(at 382.349502 -437.49976)
		(size 0.4572)
		(drill 0.2032)
		(layers "F.Cu" "B.Cu")
		(net "GND")
	)
	(via
		(at 75.165712 -403.830536)
		(size 0.4572)
		(drill 0.254)
		(layers "F.Cu" "B.Cu")
		(net "GND")
	)
	(via
		(at 187.111894 -123.04268)
		(size 0.4572)
		(drill 0.254)
		(layers "F.Cu" "B.Cu")
		(net "GND")
	)
	(via
		(at 338.98332 -362.01096)
		(size 0.508)
		(drill 0.254)
		(layers "F.Cu" "B.Cu")
		(net "GND")
	)
	(via
		(at 431.55616 -299.33519)
		(size 0.4826)
		(drill 0.254)
		(layers "F.Cu" "B.Cu")
		(net "GND")
	)
	(via
		(at 363.944916 -235.574078)
		(size 0.4064)
		(drill 0.2032)
		(layers "F.Cu" "B.Cu")
		(net "GND")
	)
	(via
		(at 90.16111 -247.724422)
		(size 0.4064)
		(drill 0.2032)
		(layers "F.Cu" "B.Cu")
		(net "GND")
	)
	(via
		(at 58.043826 -277.235412)
		(size 0.4826)
		(drill 0.254)
		(layers "F.Cu" "B.Cu")
		(net "GND")
	)
	(via
		(at 255.634744 -44.918122)
		(size 0.508)
		(drill 0.254)
		(layers "F.Cu" "B.Cu")
		(net "GND")
	)
	(via
		(at 111.332264 -258.795266)
		(size 0.4826)
		(drill 0.254)
		(layers "F.Cu" "B.Cu")
		(net "GND")
	)
	(via
		(at 355.961188 -242.864132)
		(size 0.4064)
		(drill 0.2032)
		(layers "F.Cu" "B.Cu")
		(net "GND")
	)
	(via
		(at 114.83086 -29.465778)
		(size 0.508)
		(drill 0.254)
		(layers "F.Cu" "B.Cu")
		(net "GND")
	)
	(via
		(at 331.838046 -23.41499)
		(size 0.508)
		(drill 0.254)
		(layers "F.Cu" "B.Cu")
		(net "GND")
	)
	(via
		(at 217.000836 -70.133718)
		(size 0.508)
		(drill 0.254)
		(layers "F.Cu" "B.Cu")
		(net "GND")
	)
	(via
		(at 59.488324 -412.570168)
		(size 0.4064)
		(drill 0.2032)
		(layers "F.Cu" "B.Cu")
		(net "GND")
	)
	(via
		(at 268.263878 -227.935028)
		(size 0.4826)
		(drill 0.254)
		(layers "F.Cu" "B.Cu")
		(net "GND")
	)
	(via
		(at 103.748586 -338.000086)
		(size 0.49022)
		(drill 0.254)
		(layers "F.Cu" "B.Cu")
		(net "GND")
	)
	(via
		(at 95.890842 -310.457596)
		(size 0.4064)
		(drill 0.2032)
		(layers "F.Cu" "B.Cu")
		(net "GND")
	)
	(via
		(at 230.117396 -439.90768)
		(size 0.508)
		(drill 0.254)
		(layers "F.Cu" "B.Cu")
		(net "GND")
	)
	(via
		(at 127.584708 -283.806392)
		(size 0.4064)
		(drill 0.2032)
		(layers "F.Cu" "B.Cu")
		(net "GND")
	)
	(via
		(at 341.390986 -229.094284)
		(size 0.4064)
		(drill 0.2032)
		(layers "F.Cu" "B.Cu")
		(net "GND")
	)
	(via
		(at 331.051154 -245.29415)
		(size 0.4064)
		(drill 0.2032)
		(layers "F.Cu" "B.Cu")
		(net "GND")
	)
	(via
		(at 265.54811 -292.535102)
		(size 0.4826)
		(drill 0.254)
		(layers "F.Cu" "B.Cu")
		(net "GND")
	)
	(via
		(at 347.801184 -271.656048)
		(size 0.4064)
		(drill 0.2032)
		(layers "F.Cu" "B.Cu")
		(net "GND")
	)
	(via
		(at 73.719944 -412.570168)
		(size 0.4064)
		(drill 0.2032)
		(layers "F.Cu" "B.Cu")
		(net "GND")
	)
	(via
		(at 167.143684 -284.035246)
		(size 0.4826)
		(drill 0.254)
		(layers "F.Cu" "B.Cu")
		(net "GND")
	)
	(via
		(at 110.949994 -186.315858)
		(size 0.508)
		(drill 0.254)
		(layers "F.Cu" "B.Cu")
		(net "GND")
	)
	(via
		(at 305.983894 -293.384986)
		(size 0.4826)
		(drill 0.254)
		(layers "F.Cu" "B.Cu")
		(net "GND")
	)
	(via
		(at 363.474762 -234.764072)
		(size 0.4064)
		(drill 0.2032)
		(layers "F.Cu" "B.Cu")
		(net "GND")
	)
	(via
		(at 327.277476 -385.999228)
		(size 0.508)
		(drill 0.254)
		(layers "F.Cu" "B.Cu")
		(net "GND")
	)
	(via
		(at 130.214116 -24.121618)
		(size 0.508)
		(drill 0.254)
		(layers "F.Cu" "B.Cu")
		(net "GND")
	)
	(via
		(at 87.340948 -249.344434)
		(size 0.4064)
		(drill 0.2032)
		(layers "F.Cu" "B.Cu")
		(net "GND")
	)
	(via
		(at 111.156496 -369.03533)
		(size 0.508)
		(drill 0.254)
		(layers "F.Cu" "B.Cu")
		(net "GND")
	)
	(via
		(at 450.561202 -422.01211)
		(size 0.508)
		(drill 0.254)
		(layers "F.Cu" "B.Cu")
		(net "GND")
	)
	(via
		(at 442.5442 -208.385156)
		(size 0.4826)
		(drill 0.254)
		(layers "F.Cu" "B.Cu")
		(net "GND")
	)
	(via
		(at 283.351732 -218.585034)
		(size 0.4826)
		(drill 0.254)
		(layers "F.Cu" "B.Cu")
		(net "GND")
	)
	(via
		(at 379.570234 -150.993348)
		(size 0.508)
		(drill 0.254)
		(layers "F.Cu" "B.Cu")
		(net "GND")
	)
	(via
		(at 59.428126 -246.63527)
		(size 0.4826)
		(drill 0.254)
		(layers "F.Cu" "B.Cu")
		(net "GND")
	)
	(via
		(at 183.366664 -362.963206)
		(size 0.508)
		(drill 0.254)
		(layers "F.Cu" "B.Cu")
		(net "GND")
	)
	(via
		(at 416.289236 -5.597398)
		(size 0.508)
		(drill 0.254)
		(layers "F.Cu" "B.Cu")
		(net "GND")
	)
	(via
		(at 368.855752 -378.07773)
		(size 0.508)
		(drill 0.254)
		(layers "F.Cu" "B.Cu")
		(net "GND")
	)
	(via
		(at 302.150526 -211.360004)
		(size 0.4826)
		(drill 0.254)
		(layers "F.Cu" "B.Cu")
		(net "GND")
	)
	(via
		(at 93.280992 -270.03629)
		(size 0.4064)
		(drill 0.2032)
		(layers "F.Cu" "B.Cu")
		(net "GND")
	)
	(via
		(at 326.351138 -250.154186)
		(size 0.4064)
		(drill 0.2032)
		(layers "F.Cu" "B.Cu")
		(net "GND")
	)
	(via
		(at 312.00217 -360.696256)
		(size 0.508)
		(drill 0.254)
		(layers "F.Cu" "B.Cu")
		(net "GND")
	)
	(via
		(at 132.714746 -412.570168)
		(size 0.4064)
		(drill 0.2032)
		(layers "F.Cu" "B.Cu")
		(net "GND")
	)
	(via
		(at 188.177678 -220.710252)
		(size 0.4826)
		(drill 0.254)
		(layers "F.Cu" "B.Cu")
		(net "GND")
	)
	(via
		(at 292.280086 -232.184956)
		(size 0.4826)
		(drill 0.254)
		(layers "F.Cu" "B.Cu")
		(net "GND")
	)
	(via
		(at 276.074632 -313.360054)
		(size 0.4826)
		(drill 0.254)
		(layers "F.Cu" "B.Cu")
		(net "GND")
	)
	(via
		(at 280.635964 -289.135058)
		(size 0.4826)
		(drill 0.254)
		(layers "F.Cu" "B.Cu")
		(net "GND")
	)
	(via
		(at 391.204704 -224.234248)
		(size 0.4064)
		(drill 0.2032)
		(layers "F.Cu" "B.Cu")
		(net "GND")
	)
	(via
		(at 385.178808 -63.429896)
		(size 0.508)
		(drill 0.254)
		(layers "F.Cu" "B.Cu")
		(net "GND")
	)
	(via
		(at 348.604078 -159.151066)
		(size 0.49022)
		(drill 0.254)
		(layers "F.Cu" "B.Cu")
		(net "GND")
	)
	(via
		(at 140.375386 -410.030168)
		(size 0.4064)
		(drill 0.2032)
		(layers "F.Cu" "B.Cu")
		(net "GND")
	)
	(via
		(at 86.401148 -225.044508)
		(size 0.4064)
		(drill 0.2032)
		(layers "F.Cu" "B.Cu")
		(net "GND")
	)
	(via
		(at 78.783942 -333.05369)
		(size 0.49022)
		(drill 0.254)
		(layers "F.Cu" "B.Cu")
		(net "GND")
	)
	(via
		(at 221.738444 -191.376554)
		(size 0.508)
		(drill 0.254)
		(layers "F.Cu" "B.Cu")
		(net "GND")
	)
	(via
		(at 399.349722 -426.69968)
		(size 0.4572)
		(drill 0.2032)
		(layers "F.Cu" "B.Cu")
		(net "GND")
	)
	(via
		(at 2.76225 -227.513134)
		(size 0.508)
		(drill 0.254)
		(layers "F.Cu" "B.Cu")
		(net "GND")
	)
	(via
		(at 18.992342 -312.935366)
		(size 0.4826)
		(drill 0.254)
		(layers "F.Cu" "B.Cu")
		(net "GND")
	)
	(via
		(at 253.932944 -40.117522)
		(size 0.508)
		(drill 0.254)
		(layers "F.Cu" "B.Cu")
		(net "GND")
	)
	(via
		(at 182.660798 -351.861374)
		(size 0.49022)
		(drill 0.254)
		(layers "F.Cu" "B.Cu")
		(net "GND")
	)
	(via
		(at 452.803768 -293.384986)
		(size 0.4826)
		(drill 0.254)
		(layers "F.Cu" "B.Cu")
		(net "GND")
	)
	(via
		(at 180.900324 -303.585372)
		(size 0.4826)
		(drill 0.254)
		(layers "F.Cu" "B.Cu")
		(net "GND")
	)
	(via
		(at 444.440056 -396.09522)
		(size 0.49022)
		(drill 0.254)
		(layers "F.Cu" "B.Cu")
		(net "GND")
	)
	(via
		(at 134.94512 -53.574188)
		(size 0.508)
		(drill 0.254)
		(layers "F.Cu" "B.Cu")
		(net "GND")
	)
	(via
		(at 131.98475 -255.014476)
		(size 0.4064)
		(drill 0.2032)
		(layers "F.Cu" "B.Cu")
		(net "GND")
	)
	(via
		(at 343.409524 -333.874364)
		(size 0.49022)
		(drill 0.254)
		(layers "F.Cu" "B.Cu")
		(net "GND")
	)
	(via
		(at 89.46515 -189.552326)
		(size 0.508)
		(drill 0.254)
		(layers "F.Cu" "B.Cu")
		(net "GND")
	)
	(via
		(at 364.98276 -394.786358)
		(size 0.508)
		(drill 0.254)
		(layers "F.Cu" "B.Cu")
		(net "GND")
	)
	(via
		(at 140.274802 -270.03629)
		(size 0.4064)
		(drill 0.2032)
		(layers "F.Cu" "B.Cu")
		(net "GND")
	)
	(via
		(at 102.85095 -235.574332)
		(size 0.4064)
		(drill 0.2032)
		(layers "F.Cu" "B.Cu")
		(net "GND")
	)
	(via
		(at 52.902358 -345.571064)
		(size 0.49022)
		(drill 0.254)
		(layers "F.Cu" "B.Cu")
		(net "GND")
	)
	(via
		(at 291.162486 -313.360054)
		(size 0.4826)
		(drill 0.254)
		(layers "F.Cu" "B.Cu")
		(net "GND")
	)
	(via
		(at 108.09097 -20.831556)
		(size 0.508)
		(drill 0.254)
		(layers "F.Cu" "B.Cu")
		(net "GND")
	)
	(via
		(at 56.712358 -200.735438)
		(size 0.4826)
		(drill 0.254)
		(layers "F.Cu" "B.Cu")
		(net "GND")
	)
	(via
		(at 199.8218 -238.560356)
		(size 0.4826)
		(drill 0.254)
		(layers "F.Cu" "B.Cu")
		(net "GND")
	)
	(via
		(at 373.174768 -266.796012)
		(size 0.4064)
		(drill 0.2032)
		(layers "F.Cu" "B.Cu")
		(net "GND")
	)
	(via
		(at 331.351128 -277.32609)
		(size 0.4064)
		(drill 0.2032)
		(layers "F.Cu" "B.Cu")
		(net "GND")
	)
	(via
		(at 372.874794 -254.204216)
		(size 0.4064)
		(drill 0.2032)
		(layers "F.Cu" "B.Cu")
		(net "GND")
	)
	(via
		(at 424.323764 -349.175578)
		(size 0.49022)
		(drill 0.254)
		(layers "F.Cu" "B.Cu")
		(net "GND")
	)
	(via
		(at 123.054618 -252.584458)
		(size 0.4064)
		(drill 0.2032)
		(layers "F.Cu" "B.Cu")
		(net "GND")
	)
	(via
		(at 140.444728 -238.814356)
		(size 0.4064)
		(drill 0.2032)
		(layers "F.Cu" "B.Cu")
		(net "GND")
	)
	(via
		(at 17.608042 -273.835368)
		(size 0.4826)
		(drill 0.254)
		(layers "F.Cu" "B.Cu")
		(net "GND")
	)
	(via
		(at 292.280086 -213.484968)
		(size 0.4826)
		(drill 0.254)
		(layers "F.Cu" "B.Cu")
		(net "GND")
	)
	(via
		(at 113.184686 -233.95432)
		(size 0.4064)
		(drill 0.2032)
		(layers "F.Cu" "B.Cu")
		(net "GND")
	)
	(via
		(at 399.524474 -413.480504)
		(size 0.4572)
		(drill 0.254)
		(layers "F.Cu" "B.Cu")
		(net "GND")
	)
	(via
		(at 347.33103 -287.046162)
		(size 0.4064)
		(drill 0.2032)
		(layers "F.Cu" "B.Cu")
		(net "GND")
	)
	(via
		(at 382.470152 -376.75693)
		(size 0.508)
		(drill 0.254)
		(layers "F.Cu" "B.Cu")
		(net "GND")
	)
	(via
		(at 81.844134 -328.10196)
		(size 0.508)
		(drill 0.254)
		(layers "F.Cu" "B.Cu")
		(net "GND")
	)
	(via
		(at 443.344554 -30.37459)
		(size 0.508)
		(drill 0.254)
		(layers "F.Cu" "B.Cu")
		(net "GND")
	)
	(via
		(at 58.272426 -192.218564)
		(size 0.4826)
		(drill 0.254)
		(layers "F.Cu" "B.Cu")
		(net "GND")
	)
	(via
		(at 407.349706 -430.299622)
		(size 0.4572)
		(drill 0.2032)
		(layers "F.Cu" "B.Cu")
		(net "GND")
	)
	(via
		(at 349.211138 -262.745982)
		(size 0.4064)
		(drill 0.2032)
		(layers "F.Cu" "B.Cu")
		(net "GND")
	)
	(via
		(at 416.64509 -420.318184)
		(size 0.4572)
		(drill 0.254)
		(layers "F.Cu" "B.Cu")
		(net "GND")
	)
	(via
		(at 403.884638 -316.679072)
		(size 0.508)
		(drill 0.254)
		(layers "F.Cu" "B.Cu")
		(net "GND")
	)
	(via
		(at 123.824746 -293.52621)
		(size 0.4064)
		(drill 0.2032)
		(layers "F.Cu" "B.Cu")
		(net "GND")
	)
	(via
		(at 104.731058 -243.674392)
		(size 0.4064)
		(drill 0.2032)
		(layers "F.Cu" "B.Cu")
		(net "GND")
	)
	(via
		(at 55.328058 -272.135346)
		(size 0.4826)
		(drill 0.254)
		(layers "F.Cu" "B.Cu")
		(net "GND")
	)
	(via
		(at 130.40487 -291.906198)
		(size 0.4064)
		(drill 0.2032)
		(layers "F.Cu" "B.Cu")
		(net "GND")
	)
	(via
		(at 169.645584 -294.66032)
		(size 0.4826)
		(drill 0.254)
		(layers "F.Cu" "B.Cu")
		(net "GND")
	)
	(via
		(at 20.32381 -286.585406)
		(size 0.4826)
		(drill 0.254)
		(layers "F.Cu" "B.Cu")
		(net "GND")
	)
	(via
		(at 284.736032 -215.18499)
		(size 0.4826)
		(drill 0.254)
		(layers "F.Cu" "B.Cu")
		(net "GND")
	)
	(via
		(at 59.428126 -318.035432)
		(size 0.4826)
		(drill 0.254)
		(layers "F.Cu" "B.Cu")
		(net "GND")
	)
	(via
		(at 343.504266 -418.412168)
		(size 0.4064)
		(drill 0.2032)
		(layers "F.Cu" "B.Cu")
		(net "GND")
	)
	(via
		(at 335.6102 -162.56)
		(size 0.508)
		(drill 0.254)
		(layers "F.Cu" "B.Cu")
		(net "GND")
	)
	(via
		(at 290.603178 -424.463972)
		(size 0.508)
		(drill 0.254)
		(layers "F.Cu" "B.Cu")
		(net "GND")
	)
	(via
		(at 164.427916 -255.13538)
		(size 0.4826)
		(drill 0.254)
		(layers "F.Cu" "B.Cu")
		(net "GND")
	)
	(via
		(at 358.952546 -417.55568)
		(size 0.508)
		(drill 0.254)
		(layers "F.Cu" "B.Cu")
		(net "GND")
	)
	(via
		(at 128.994662 -292.716204)
		(size 0.4064)
		(drill 0.2032)
		(layers "F.Cu" "B.Cu")
		(net "GND")
	)
	(via
		(at 444.885572 -399.233644)
		(size 0.49022)
		(drill 0.254)
		(layers "F.Cu" "B.Cu")
		(net "GND")
	)
	(via
		(at 292.280086 -282.33497)
		(size 0.4826)
		(drill 0.254)
		(layers "F.Cu" "B.Cu")
		(net "GND")
	)
	(via
		(at 391.204704 -229.094284)
		(size 0.4064)
		(drill 0.2032)
		(layers "F.Cu" "B.Cu")
		(net "GND")
	)
	(via
		(at 106.91114 -282.18638)
		(size 0.4064)
		(drill 0.2032)
		(layers "F.Cu" "B.Cu")
		(net "GND")
	)
	(via
		(at 402.096224 -391.290556)
		(size 0.4064)
		(drill 0.2032)
		(layers "F.Cu" "B.Cu")
		(net "GND")
	)
	(via
		(at 391.204704 -230.714296)
		(size 0.4064)
		(drill 0.2032)
		(layers "F.Cu" "B.Cu")
		(net "GND")
	)
	(via
		(at 108.02112 -241.244374)
		(size 0.4064)
		(drill 0.2032)
		(layers "F.Cu" "B.Cu")
		(net "GND")
	)
	(via
		(at 98.981514 -331.78496)
		(size 0.508)
		(drill 0.254)
		(layers "F.Cu" "B.Cu")
		(net "GND")
	)
	(via
		(at 450.243702 -391.457688)
		(size 0.508)
		(drill 0.254)
		(layers "F.Cu" "B.Cu")
		(net "GND")
	)
	(via
		(at 363.004862 -224.234248)
		(size 0.4064)
		(drill 0.2032)
		(layers "F.Cu" "B.Cu")
		(net "GND")
	)
	(via
		(at 467.5378 -278.435054)
		(size 0.508)
		(drill 0.254)
		(layers "F.Cu" "B.Cu")
		(net "GND")
	)
	(via
		(at 416.468052 -272.984976)
		(size 0.4826)
		(drill 0.254)
		(layers "F.Cu" "B.Cu")
		(net "GND")
	)
	(via
		(at 367.064798 -288.66592)
		(size 0.4064)
		(drill 0.2032)
		(layers "F.Cu" "B.Cu")
		(net "GND")
	)
	(via
		(at 135.274812 -238.00435)
		(size 0.4064)
		(drill 0.2032)
		(layers "F.Cu" "B.Cu")
		(net "GND")
	)
	(via
		(at 87.171022 -272.466308)
		(size 0.4064)
		(drill 0.2032)
		(layers "F.Cu" "B.Cu")
		(net "GND")
	)
	(via
		(at 386.541518 -186.648598)
		(size 0.508)
		(drill 0.254)
		(layers "F.Cu" "B.Cu")
		(net "GND")
	)
	(via
		(at 328.061066 -279.756108)
		(size 0.4064)
		(drill 0.2032)
		(layers "F.Cu" "B.Cu")
		(net "GND")
	)
	(via
		(at 315.24956 -432.747166)
		(size 0.4572)
		(drill 0.2032)
		(layers "F.Cu" "B.Cu")
		(net "GND")
	)
	(via
		(at 36.621974 -348.709488)
		(size 0.49022)
		(drill 0.254)
		(layers "F.Cu" "B.Cu")
		(net "GND")
	)
	(via
		(at 177.189638 -219.860368)
		(size 0.4826)
		(drill 0.254)
		(layers "F.Cu" "B.Cu")
		(net "GND")
	)
	(via
		(at 353.906074 -394.831062)
		(size 0.4064)
		(drill 0.2032)
		(layers "F.Cu" "B.Cu")
		(net "GND")
	)
	(via
		(at 353.61118 -225.85426)
		(size 0.4064)
		(drill 0.2032)
		(layers "F.Cu" "B.Cu")
		(net "GND")
	)
	(via
		(at 140.914882 -225.044508)
		(size 0.4064)
		(drill 0.2032)
		(layers "F.Cu" "B.Cu")
		(net "GND")
	)
	(via
		(at 126.34976 -437.49976)
		(size 0.4572)
		(drill 0.2032)
		(layers "F.Cu" "B.Cu")
		(net "GND")
	)
	(via
		(at 168.527984 -216.885266)
		(size 0.4826)
		(drill 0.254)
		(layers "F.Cu" "B.Cu")
		(net "GND")
	)
	(via
		(at 374.754902 -239.624108)
		(size 0.4064)
		(drill 0.2032)
		(layers "F.Cu" "B.Cu")
		(net "GND")
	)
	(via
		(at 96.719136 -390.160002)
		(size 0.4064)
		(drill 0.2032)
		(layers "F.Cu" "B.Cu")
		(net "GND")
	)
	(via
		(at 454.188068 -297.635168)
		(size 0.4826)
		(drill 0.254)
		(layers "F.Cu" "B.Cu")
		(net "GND")
	)
	(via
		(at 102.211124 -274.08632)
		(size 0.4064)
		(drill 0.2032)
		(layers "F.Cu" "B.Cu")
		(net "GND")
	)
	(via
		(at 96.768158 -333.090012)
		(size 0.49022)
		(drill 0.254)
		(layers "F.Cu" "B.Cu")
		(net "GND")
	)
	(via
		(at 216.611454 -73.294748)
		(size 0.508)
		(drill 0.254)
		(layers "F.Cu" "B.Cu")
		(net "GND")
	)
	(via
		(at 419.401498 -329.87869)
		(size 0.508)
		(drill 0.254)
		(layers "F.Cu" "B.Cu")
		(net "GND")
	)
	(via
		(at 384.624834 -235.574078)
		(size 0.4064)
		(drill 0.2032)
		(layers "F.Cu" "B.Cu")
		(net "GND")
	)
	(via
		(at 47.784004 -206.685388)
		(size 0.4826)
		(drill 0.254)
		(layers "F.Cu" "B.Cu")
		(net "GND")
	)
	(via
		(at 325.24954 -439.651394)
		(size 0.4572)
		(drill 0.2032)
		(layers "F.Cu" "B.Cu")
		(net "GND")
	)
	(via
		(at 111.64189 -12.542266)
		(size 0.508)
		(drill 0.254)
		(layers "F.Cu" "B.Cu")
		(net "GND")
	)
	(via
		(at 416.468052 -226.235006)
		(size 0.4826)
		(drill 0.254)
		(layers "F.Cu" "B.Cu")
		(net "GND")
	)
	(via
		(at 168.527984 -280.635202)
		(size 0.4826)
		(drill 0.254)
		(layers "F.Cu" "B.Cu")
		(net "GND")
	)
	(via
		(at 139.974828 -250.964446)
		(size 0.4064)
		(drill 0.2032)
		(layers "F.Cu" "B.Cu")
		(net "GND")
	)
	(via
		(at 394.72997 -188.116718)
		(size 0.508)
		(drill 0.254)
		(layers "F.Cu" "B.Cu")
		(net "GND")
	)
	(via
		(at 28.259278 -17.61236)
		(size 0.508)
		(drill 0.254)
		(layers "F.Cu" "B.Cu")
		(net "GND")
	)
	(via
		(at 394.982954 -274.630134)
		(size 0.4064)
		(drill 0.2032)
		(layers "F.Cu" "B.Cu")
		(net "GND")
	)
	(via
		(at 187.060078 -273.835368)
		(size 0.4826)
		(drill 0.254)
		(layers "F.Cu" "B.Cu")
		(net "GND")
	)
	(via
		(at 146.742912 -243.130324)
		(size 0.4064)
		(drill 0.2032)
		(layers "F.Cu" "B.Cu")
		(net "GND")
	)
	(via
		(at 345.621102 -221.80423)
		(size 0.4064)
		(drill 0.2032)
		(layers "F.Cu" "B.Cu")
		(net "GND")
	)
	(via
		(at 143.349726 -432.747166)
		(size 0.4572)
		(drill 0.2032)
		(layers "F.Cu" "B.Cu")
		(net "GND")
	)
	(via
		(at 194.604132 -267.885418)
		(size 0.4826)
		(drill 0.254)
		(layers "F.Cu" "B.Cu")
		(net "GND")
	)
	(via
		(at 50.298604 -404.46452)
		(size 0.4064)
		(drill 0.2032)
		(layers "F.Cu" "B.Cu")
		(net "GND")
	)
	(via
		(at 270.157956 -186.285886)
		(size 0.508)
		(drill 0.254)
		(layers "F.Cu" "B.Cu")
		(net "GND")
	)
	(via
		(at 149.923754 -406.370536)
		(size 0.4572)
		(drill 0.254)
		(layers "F.Cu" "B.Cu")
		(net "GND")
	)
	(via
		(at 387.578092 -382.34493)
		(size 0.508)
		(drill 0.254)
		(layers "F.Cu" "B.Cu")
		(net "GND")
	)
	(via
		(at 138.382756 -370.83873)
		(size 0.508)
		(drill 0.254)
		(layers "F.Cu" "B.Cu")
		(net "GND")
	)
	(via
		(at 102.211124 -293.52621)
		(size 0.4064)
		(drill 0.2032)
		(layers "F.Cu" "B.Cu")
		(net "GND")
	)
	(via
		(at 324.543928 -61.364876)
		(size 0.508)
		(drill 0.254)
		(layers "F.Cu" "B.Cu")
		(net "GND")
	)
	(via
		(at 164.427916 -214.33536)
		(size 0.4826)
		(drill 0.254)
		(layers "F.Cu" "B.Cu")
		(net "GND")
	)
	(via
		(at 321.601084 -30.739588)
		(size 0.508)
		(drill 0.254)
		(layers "F.Cu" "B.Cu")
		(net "GND")
	)
	(via
		(at 303.268126 -206.685134)
		(size 0.4826)
		(drill 0.254)
		(layers "F.Cu" "B.Cu")
		(net "GND")
	)
	(via
		(at 372.655846 -183.14289)
		(size 0.49022)
		(drill 0.254)
		(layers "F.Cu" "B.Cu")
		(net "GND")
	)
	(via
		(at 88.24976 -430.299622)
		(size 0.4572)
		(drill 0.2032)
		(layers "F.Cu" "B.Cu")
		(net "GND")
	)
	(via
		(at 383.21488 -233.14406)
		(size 0.4064)
		(drill 0.2032)
		(layers "F.Cu" "B.Cu")
		(net "GND")
	)
	(via
		(at 63.955422 -25.614884)
		(size 0.508)
		(drill 0.254)
		(layers "F.Cu" "B.Cu")
		(net "GND")
	)
	(via
		(at 113.579148 -172.315886)
		(size 0.49022)
		(drill 0.254)
		(layers "F.Cu" "B.Cu")
		(net "GND")
	)
	(via
		(at 381.634746 -266.796012)
		(size 0.4064)
		(drill 0.2032)
		(layers "F.Cu" "B.Cu")
		(net "GND")
	)
	(via
		(at 394.982954 -271.39011)
		(size 0.4064)
		(drill 0.2032)
		(layers "F.Cu" "B.Cu")
		(net "GND")
	)
	(via
		(at 49.168304 -212.635338)
		(size 0.4826)
		(drill 0.254)
		(layers "F.Cu" "B.Cu")
		(net "GND")
	)
	(via
		(at 91.871038 -261.126224)
		(size 0.4064)
		(drill 0.2032)
		(layers "F.Cu" "B.Cu")
		(net "GND")
	)
	(via
		(at 126.814834 -229.90429)
		(size 0.4064)
		(drill 0.2032)
		(layers "F.Cu" "B.Cu")
		(net "GND")
	)
	(via
		(at 422.627806 -199.885046)
		(size 0.4826)
		(drill 0.254)
		(layers "F.Cu" "B.Cu")
		(net "GND")
	)
	(via
		(at 388.384796 -240.434114)
		(size 0.4064)
		(drill 0.2032)
		(layers "F.Cu" "B.Cu")
		(net "GND")
	)
	(via
		(at 163.044124 -391.830814)
		(size 0.4064)
		(drill 0.2032)
		(layers "F.Cu" "B.Cu")
		(net "GND")
	)
	(via
		(at 393.384786 -264.365994)
		(size 0.4064)
		(drill 0.2032)
		(layers "F.Cu" "B.Cu")
		(net "GND")
	)
	(via
		(at 428.840392 -275.535136)
		(size 0.4826)
		(drill 0.254)
		(layers "F.Cu" "B.Cu")
		(net "GND")
	)
	(via
		(at 289.564318 -228.785166)
		(size 0.4826)
		(drill 0.254)
		(layers "F.Cu" "B.Cu")
		(net "GND")
	)
	(via
		(at 288.180018 -225.385122)
		(size 0.4826)
		(drill 0.254)
		(layers "F.Cu" "B.Cu")
		(net "GND")
	)
	(via
		(at 168.527984 -248.335292)
		(size 0.4826)
		(drill 0.254)
		(layers "F.Cu" "B.Cu")
		(net "GND")
	)
	(via
		(at 314.155836 -376.75693)
		(size 0.508)
		(drill 0.254)
		(layers "F.Cu" "B.Cu")
		(net "GND")
	)
	(via
		(at 102.793546 -387.084062)
		(size 0.508)
		(drill 0.254)
		(layers "F.Cu" "B.Cu")
		(net "GND")
	)
	(via
		(at 83.88096 -279.756362)
		(size 0.4064)
		(drill 0.2032)
		(layers "F.Cu" "B.Cu")
		(net "GND")
	)
	(via
		(at 161.844228 -391.830814)
		(size 0.4064)
		(drill 0.2032)
		(layers "F.Cu" "B.Cu")
		(net "GND")
	)
	(via
		(at 363.87024 -385.38912)
		(size 0.508)
		(drill 0.254)
		(layers "F.Cu" "B.Cu")
		(net "GND")
	)
	(via
		(at 289.564318 -287.435036)
		(size 0.4826)
		(drill 0.254)
		(layers "F.Cu" "B.Cu")
		(net "GND")
	)
	(via
		(at 343.13114 -335.590388)
		(size 0.49022)
		(drill 0.254)
		(layers "F.Cu" "B.Cu")
		(net "GND")
	)
	(via
		(at 113.954814 -284.616398)
		(size 0.4064)
		(drill 0.2032)
		(layers "F.Cu" "B.Cu")
		(net "GND")
	)
	(via
		(at 300.99 -354.711)
		(size 0.508)
		(drill 0.254)
		(layers "F.Cu" "B.Cu")
		(net "GND")
	)
	(via
		(at 87.171022 -288.666174)
		(size 0.4064)
		(drill 0.2032)
		(layers "F.Cu" "B.Cu")
		(net "GND")
	)
	(via
		(at 55.791354 -390.160002)
		(size 0.4064)
		(drill 0.2032)
		(layers "F.Cu" "B.Cu")
		(net "GND")
	)
	(via
		(at 273.092164 -318.885062)
		(size 0.4826)
		(drill 0.254)
		(layers "F.Cu" "B.Cu")
		(net "GND")
	)
	(via
		(at 145.444718 -274.08632)
		(size 0.4064)
		(drill 0.2032)
		(layers "F.Cu" "B.Cu")
		(net "GND")
	)
	(via
		(at 277.192232 -265.335004)
		(size 0.4826)
		(drill 0.254)
		(layers "F.Cu" "B.Cu")
		(net "GND")
	)
	(via
		(at 145.868644 -369.03533)
		(size 0.508)
		(drill 0.254)
		(layers "F.Cu" "B.Cu")
		(net "GND")
	)
	(via
		(at 352.671126 -229.094284)
		(size 0.4064)
		(drill 0.2032)
		(layers "F.Cu" "B.Cu")
		(net "GND")
	)
	(via
		(at 133.394704 -225.044508)
		(size 0.4064)
		(drill 0.2032)
		(layers "F.Cu" "B.Cu")
		(net "GND")
	)
	(via
		(at 101.440996 -249.344434)
		(size 0.4064)
		(drill 0.2032)
		(layers "F.Cu" "B.Cu")
		(net "GND")
	)
	(via
		(at 82.551016 -413.204152)
		(size 0.4572)
		(drill 0.254)
		(layers "F.Cu" "B.Cu")
		(net "GND")
	)
	(via
		(at 340.826852 -161.981134)
		(size 0.49022)
		(drill 0.254)
		(layers "F.Cu" "B.Cu")
		(net "GND")
	)
	(via
		(at 164.427916 -290.835334)
		(size 0.4826)
		(drill 0.254)
		(layers "F.Cu" "B.Cu")
		(net "GND")
	)
	(via
		(at 374.284748 -255.014222)
		(size 0.4064)
		(drill 0.2032)
		(layers "F.Cu" "B.Cu")
		(net "GND")
	)
	(via
		(at 96.20631 -186.597798)
		(size 0.508)
		(drill 0.254)
		(layers "F.Cu" "B.Cu")
		(net "GND")
	)
	(via
		(at 251.721874 -134.257796)
		(size 0.508)
		(drill 0.254)
		(layers "F.Cu" "B.Cu")
		(net "GND")
	)
	(via
		(at 273.092164 -217.73515)
		(size 0.4826)
		(drill 0.254)
		(layers "F.Cu" "B.Cu")
		(net "GND")
	)
	(via
		(at 366.594898 -279.756108)
		(size 0.4064)
		(drill 0.2032)
		(layers "F.Cu" "B.Cu")
		(net "GND")
	)
	(via
		(at 108.712 -416.687)
		(size 0.508)
		(drill 0.254)
		(layers "F.Cu" "B.Cu")
		(net "GND")
	)
	(via
		(at 97.511108 -293.52621)
		(size 0.4064)
		(drill 0.2032)
		(layers "F.Cu" "B.Cu")
		(net "GND")
	)
	(via
		(at 205.83144 -112.288066)
		(size 0.508)
		(drill 0.254)
		(layers "F.Cu" "B.Cu")
		(net "GND")
	)
	(via
		(at 323.249544 -435.0512)
		(size 0.4572)
		(drill 0.2032)
		(layers "F.Cu" "B.Cu")
		(net "GND")
	)
	(via
		(at 295.184576 -421.142668)
		(size 0.508)
		(drill 0.254)
		(layers "F.Cu" "B.Cu")
		(net "GND")
	)
	(via
		(at 372.11635 -402.284438)
		(size 0.4572)
		(drill 0.254)
		(layers "F.Cu" "B.Cu")
		(net "GND")
	)
	(via
		(at 163.325048 -50.625502)
		(size 0.508)
		(drill 0.254)
		(layers "F.Cu" "B.Cu")
		(net "GND")
	)
	(via
		(at 285.945834 -419.656006)
		(size 0.4572)
		(drill 0.254)
		(layers "F.Cu" "B.Cu")
		(net "GND")
	)
	(via
		(at 339.511132 -222.614236)
		(size 0.4064)
		(drill 0.2032)
		(layers "F.Cu" "B.Cu")
		(net "GND")
	)
	(via
		(at 37.408358 -435.048914)
		(size 0.508)
		(drill 0.254)
		(layers "F.Cu" "B.Cu")
		(net "GND")
	)
	(via
		(at 430.008792 -349.200978)
		(size 0.49022)
		(drill 0.254)
		(layers "F.Cu" "B.Cu")
		(net "GND")
	)
	(via
		(at 160.730946 -406.980644)
		(size 0.4064)
		(drill 0.2032)
		(layers "F.Cu" "B.Cu")
		(net "GND")
	)
	(via
		(at 350.791018 -235.574078)
		(size 0.4064)
		(drill 0.2032)
		(layers "F.Cu" "B.Cu")
		(net "GND")
	)
	(via
		(at 62.773814 -373.30253)
		(size 0.508)
		(drill 0.254)
		(layers "F.Cu" "B.Cu")
		(net "GND")
	)
	(via
		(at 100.031042 -232.334308)
		(size 0.4064)
		(drill 0.2032)
		(layers "F.Cu" "B.Cu")
		(net "GND")
	)
	(via
		(at 43.871134 -363.263434)
		(size 0.508)
		(drill 0.254)
		(layers "F.Cu" "B.Cu")
		(net "GND")
	)
	(via
		(at 78.711044 -280.566368)
		(size 0.4064)
		(drill 0.2032)
		(layers "F.Cu" "B.Cu")
		(net "GND")
	)
	(via
		(at 117.759734 -413.204152)
		(size 0.4572)
		(drill 0.254)
		(layers "F.Cu" "B.Cu")
		(net "GND")
	)
	(via
		(at 355.021134 -249.34418)
		(size 0.4064)
		(drill 0.2032)
		(layers "F.Cu" "B.Cu")
		(net "GND")
	)
	(via
		(at 392.571478 -183.615838)
		(size 0.49022)
		(drill 0.254)
		(layers "F.Cu" "B.Cu")
		(net "GND")
	)
	(via
		(at 140.867384 -441.227718)
		(size 0.508)
		(drill 0.254)
		(layers "F.Cu" "B.Cu")
		(net "GND")
	)
	(via
		(at 331.351128 -275.706078)
		(size 0.4064)
		(drill 0.2032)
		(layers "F.Cu" "B.Cu")
		(net "GND")
	)
	(via
		(at 101.925628 -388.892542)
		(size 0.508)
		(drill 0.254)
		(layers "F.Cu" "B.Cu")
		(net "GND")
	)
	(via
		(at 97.040954 -289.47618)
		(size 0.4064)
		(drill 0.2032)
		(layers "F.Cu" "B.Cu")
		(net "GND")
	)
	(via
		(at 40.770302 -375.793)
		(size 0.508)
		(drill 0.254)
		(layers "F.Cu" "B.Cu")
		(net "GND")
	)
	(via
		(at 381.334772 -254.204216)
		(size 0.4064)
		(drill 0.2032)
		(layers "F.Cu" "B.Cu")
		(net "GND")
	)
	(via
		(at 143.73479 -228.284532)
		(size 0.4064)
		(drill 0.2032)
		(layers "F.Cu" "B.Cu")
		(net "GND")
	)
	(via
		(at 164.958014 -44.958762)
		(size 0.508)
		(drill 0.254)
		(layers "F.Cu" "B.Cu")
		(net "GND")
	)
	(via
		(at 279.893268 -100.421694)
		(size 0.508)
		(drill 0.254)
		(layers "F.Cu" "B.Cu")
		(net "GND")
	)
	(via
		(at 407.349706 -425.547282)
		(size 0.4572)
		(drill 0.2032)
		(layers "F.Cu" "B.Cu")
		(net "GND")
	)
	(via
		(at 93.280992 -261.93623)
		(size 0.4064)
		(drill 0.2032)
		(layers "F.Cu" "B.Cu")
		(net "GND")
	)
	(via
		(at 89.99093 -274.08632)
		(size 0.4064)
		(drill 0.2032)
		(layers "F.Cu" "B.Cu")
		(net "GND")
	)
	(via
		(at 264.43051 -295.510204)
		(size 0.4826)
		(drill 0.254)
		(layers "F.Cu" "B.Cu")
		(net "GND")
	)
	(via
		(at 347.740478 -421.586152)
		(size 0.4572)
		(drill 0.254)
		(layers "F.Cu" "B.Cu")
		(net "GND")
	)
	(via
		(at 51.884072 -265.335258)
		(size 0.4826)
		(drill 0.254)
		(layers "F.Cu" "B.Cu")
		(net "GND")
	)
	(via
		(at 384.349498 -437.34736)
		(size 0.4572)
		(drill 0.2032)
		(layers "F.Cu" "B.Cu")
		(net "GND")
	)
	(via
		(at 191.389 -171.6532)
		(size 0.508)
		(drill 0.254)
		(layers "F.Cu" "B.Cu")
		(net "GND")
	)
	(via
		(at 25.488138 -345.799918)
		(size 0.49022)
		(drill 0.254)
		(layers "F.Cu" "B.Cu")
		(net "GND")
	)
	(via
		(at 431.092356 -110.14837)
		(size 0.508)
		(drill 0.254)
		(layers "F.Cu" "B.Cu")
		(net "GND")
	)
	(via
		(at 336.22107 -249.34418)
		(size 0.4064)
		(drill 0.2032)
		(layers "F.Cu" "B.Cu")
		(net "GND")
	)
	(via
		(at 136.680956 -369.69573)
		(size 0.508)
		(drill 0.254)
		(layers "F.Cu" "B.Cu")
		(net "GND")
	)
	(via
		(at 299.82414 -301.034958)
		(size 0.4826)
		(drill 0.254)
		(layers "F.Cu" "B.Cu")
		(net "GND")
	)
	(via
		(at 171.97197 -272.135346)
		(size 0.4826)
		(drill 0.254)
		(layers "F.Cu" "B.Cu")
		(net "GND")
	)
	(via
		(at 195.988432 -306.135278)
		(size 0.4826)
		(drill 0.254)
		(layers "F.Cu" "B.Cu")
		(net "GND")
	)
	(via
		(at 87.171022 -269.226284)
		(size 0.4064)
		(drill 0.2032)
		(layers "F.Cu" "B.Cu")
		(net "GND")
	)
	(via
		(at 380.224792 -265.986006)
		(size 0.4064)
		(drill 0.2032)
		(layers "F.Cu" "B.Cu")
		(net "GND")
	)
	(via
		(at 45.871384 -441.227718)
		(size 0.508)
		(drill 0.254)
		(layers "F.Cu" "B.Cu")
		(net "GND")
	)
	(via
		(at 382.478534 -394.831062)
		(size 0.4064)
		(drill 0.2032)
		(layers "F.Cu" "B.Cu")
		(net "GND")
	)
	(via
		(at 418.917882 -360.538014)
		(size 0.508)
		(drill 0.254)
		(layers "F.Cu" "B.Cu")
		(net "GND")
	)
	(via
		(at 369.414806 -282.996132)
		(size 0.4064)
		(drill 0.2032)
		(layers "F.Cu" "B.Cu")
		(net "GND")
	)
	(via
		(at 85.290914 -277.326344)
		(size 0.4064)
		(drill 0.2032)
		(layers "F.Cu" "B.Cu")
		(net "GND")
	)
	(via
		(at 398.465294 -179.110386)
		(size 0.49022)
		(drill 0.254)
		(layers "F.Cu" "B.Cu")
		(net "GND")
	)
	(via
		(at 140.444728 -248.534428)
		(size 0.4064)
		(drill 0.2032)
		(layers "F.Cu" "B.Cu")
		(net "GND")
	)
	(via
		(at 36.795964 -224.535238)
		(size 0.4826)
		(drill 0.254)
		(layers "F.Cu" "B.Cu")
		(net "GND")
	)
	(via
		(at 404.39213 -421.586152)
		(size 0.4572)
		(drill 0.254)
		(layers "F.Cu" "B.Cu")
		(net "GND")
	)
	(via
		(at 26.307796 -192.218564)
		(size 0.4826)
		(drill 0.254)
		(layers "F.Cu" "B.Cu")
		(net "GND")
	)
	(via
		(at 375.054876 -281.37612)
		(size 0.4064)
		(drill 0.2032)
		(layers "F.Cu" "B.Cu")
		(net "GND")
	)
	(via
		(at 176.072038 -288.285428)
		(size 0.4826)
		(drill 0.254)
		(layers "F.Cu" "B.Cu")
		(net "GND")
	)
	(via
		(at 103.787956 -253.392432)
		(size 0.4064)
		(drill 0.2032)
		(layers "F.Cu" "B.Cu")
		(net "GND")
	)
	(via
		(at 439.100214 -310.384952)
		(size 0.4826)
		(drill 0.254)
		(layers "F.Cu" "B.Cu")
		(net "GND")
	)
	(via
		(at 92.981018 -250.964446)
		(size 0.4064)
		(drill 0.2032)
		(layers "F.Cu" "B.Cu")
		(net "GND")
	)
	(via
		(at 443.625732 -397.811244)
		(size 0.49022)
		(drill 0.254)
		(layers "F.Cu" "B.Cu")
		(net "GND")
	)
	(via
		(at 197.3199 -312.085228)
		(size 0.4826)
		(drill 0.254)
		(layers "F.Cu" "B.Cu")
		(net "GND")
	)
	(via
		(at 391.674858 -241.24412)
		(size 0.4064)
		(drill 0.2032)
		(layers "F.Cu" "B.Cu")
		(net "GND")
	)
	(via
		(at 178.289458 -54.299866)
		(size 0.508)
		(drill 0.254)
		(layers "F.Cu" "B.Cu")
		(net "GND")
	)
	(via
		(at 198.7042 -299.335444)
		(size 0.4826)
		(drill 0.254)
		(layers "F.Cu" "B.Cu")
		(net "GND")
	)
	(via
		(at 408.98699 -419.046152)
		(size 0.4572)
		(drill 0.254)
		(layers "F.Cu" "B.Cu")
		(net "GND")
	)
	(via
		(at 49.009554 -396.366492)
		(size 0.508)
		(drill 0.254)
		(layers "F.Cu" "B.Cu")
		(net "GND")
	)
	(via
		(at 50.499772 -202.435206)
		(size 0.4826)
		(drill 0.254)
		(layers "F.Cu" "B.Cu")
		(net "GND")
	)
	(via
		(at 51.753516 -151.174196)
		(size 0.508)
		(drill 0.254)
		(layers "F.Cu" "B.Cu")
		(net "GND")
	)
	(via
		(at 186.447938 -348.05112)
		(size 0.508)
		(drill 0.254)
		(layers "F.Cu" "B.Cu")
		(net "GND")
	)
	(via
		(at 336.373724 -333.034386)
		(size 0.49022)
		(drill 0.254)
		(layers "F.Cu" "B.Cu")
		(net "GND")
	)
	(via
		(at 390.349486 -435.0512)
		(size 0.4572)
		(drill 0.2032)
		(layers "F.Cu" "B.Cu")
		(net "GND")
	)
	(via
		(at 240.80724 -226.432872)
		(size 0.4826)
		(drill 0.254)
		(layers "F.Cu" "B.Cu")
		(net "GND")
	)
	(via
		(at 108.321094 -289.47618)
		(size 0.4064)
		(drill 0.2032)
		(layers "F.Cu" "B.Cu")
		(net "GND")
	)
	(via
		(at 102.681024 -273.276314)
		(size 0.4064)
		(drill 0.2032)
		(layers "F.Cu" "B.Cu")
		(net "GND")
	)
	(via
		(at 87.057484 -404.46452)
		(size 0.4064)
		(drill 0.2032)
		(layers "F.Cu" "B.Cu")
		(net "GND")
	)
	(via
		(at 47.784004 -236.435392)
		(size 0.4826)
		(drill 0.254)
		(layers "F.Cu" "B.Cu")
		(net "GND")
	)
	(via
		(at 251.347224 -275.363432)
		(size 0.508)
		(drill 0.254)
		(layers "F.Cu" "B.Cu")
		(net "GND")
	)
	(via
		(at 331.821028 -263.555988)
		(size 0.4064)
		(drill 0.2032)
		(layers "F.Cu" "B.Cu")
		(net "GND")
	)
	(via
		(at 339.511132 -233.954066)
		(size 0.4064)
		(drill 0.2032)
		(layers "F.Cu" "B.Cu")
		(net "GND")
	)
	(via
		(at 54.266592 -359.730548)
		(size 0.508)
		(drill 0.254)
		(layers "F.Cu" "B.Cu")
		(net "GND")
	)
	(via
		(at 305.216306 -420.952168)
		(size 0.4064)
		(drill 0.2032)
		(layers "F.Cu" "B.Cu")
		(net "GND")
	)
	(via
		(at 40.23995 -290.835334)
		(size 0.4826)
		(drill 0.254)
		(layers "F.Cu" "B.Cu")
		(net "GND")
	)
	(via
		(at 337.96732 -362.01096)
		(size 0.508)
		(drill 0.254)
		(layers "F.Cu" "B.Cu")
		(net "GND")
	)
	(via
		(at 350.151192 -290.285932)
		(size 0.4064)
		(drill 0.2032)
		(layers "F.Cu" "B.Cu")
		(net "GND")
	)
	(via
		(at 413.752284 -287.435036)
		(size 0.4826)
		(drill 0.254)
		(layers "F.Cu" "B.Cu")
		(net "GND")
	)
	(via
		(at 428.840392 -303.585118)
		(size 0.4826)
		(drill 0.254)
		(layers "F.Cu" "B.Cu")
		(net "GND")
	)
	(via
		(at 106.611166 -237.194344)
		(size 0.4064)
		(drill 0.2032)
		(layers "F.Cu" "B.Cu")
		(net "GND")
	)
	(via
		(at 201.291952 -95.872808)
		(size 0.508)
		(drill 0.254)
		(layers "F.Cu" "B.Cu")
		(net "GND")
	)
	(via
		(at 381.634746 -271.656048)
		(size 0.4064)
		(drill 0.2032)
		(layers "F.Cu" "B.Cu")
		(net "GND")
	)
	(via
		(at 392.067796 -193.131694)
		(size 0.508)
		(drill 0.254)
		(layers "F.Cu" "B.Cu")
		(net "GND")
	)
	(via
		(at 198.7042 -248.335292)
		(size 0.4826)
		(drill 0.254)
		(layers "F.Cu" "B.Cu")
		(net "GND")
	)
	(via
		(at 165.168072 -121.701814)
		(size 0.508)
		(drill 0.254)
		(layers "F.Cu" "B.Cu")
		(net "GND")
	)
	(via
		(at 44.18584 -101.74224)
		(size 0.508)
		(drill 0.254)
		(layers "F.Cu" "B.Cu")
		(net "GND")
	)
	(via
		(at 345.451176 -282.186126)
		(size 0.4064)
		(drill 0.2032)
		(layers "F.Cu" "B.Cu")
		(net "GND")
	)
	(via
		(at 67.234816 -411.936184)
		(size 0.4572)
		(drill 0.254)
		(layers "F.Cu" "B.Cu")
		(net "GND")
	)
	(via
		(at 77.112876 -281.110436)
		(size 0.4064)
		(drill 0.2032)
		(layers "F.Cu" "B.Cu")
		(net "GND")
	)
	(via
		(at 381.334772 -255.824228)
		(size 0.4064)
		(drill 0.2032)
		(layers "F.Cu" "B.Cu")
		(net "GND")
	)
	(via
		(at 0.762254 -32.303212)
		(size 0.508)
		(drill 0.254)
		(layers "F.Cu" "B.Cu")
		(net "GND")
	)
	(via
		(at 89.85504 -355.968046)
		(size 0.508)
		(drill 0.254)
		(layers "F.Cu" "B.Cu")
		(net "GND")
	)
	(via
		(at 25.969722 -429.072802)
		(size 0.508)
		(drill 0.254)
		(layers "F.Cu" "B.Cu")
		(net "GND")
	)
	(via
		(at 397.76654 -170.99534)
		(size 0.508)
		(drill 0.254)
		(layers "F.Cu" "B.Cu")
		(net "GND")
	)
	(via
		(at 89.99093 -270.846296)
		(size 0.4064)
		(drill 0.2032)
		(layers "F.Cu" "B.Cu")
		(net "GND")
	)
	(via
		(at 107.851194 -287.04667)
		(size 0.4064)
		(drill 0.2032)
		(layers "F.Cu" "B.Cu")
		(net "GND")
	)
	(via
		(at 183.616092 -196.485256)
		(size 0.4826)
		(drill 0.254)
		(layers "F.Cu" "B.Cu")
		(net "GND")
	)
	(via
		(at 363.474762 -249.34418)
		(size 0.4064)
		(drill 0.2032)
		(layers "F.Cu" "B.Cu")
		(net "GND")
	)
	(via
		(at 357.841042 -238.004096)
		(size 0.4064)
		(drill 0.2032)
		(layers "F.Cu" "B.Cu")
		(net "GND")
	)
	(via
		(at 392.953748 -319.650872)
		(size 0.508)
		(drill 0.254)
		(layers "F.Cu" "B.Cu")
		(net "GND")
	)
	(via
		(at 94.861126 -250.964446)
		(size 0.4064)
		(drill 0.2032)
		(layers "F.Cu" "B.Cu")
		(net "GND")
	)
	(via
		(at 418.086794 -6.091174)
		(size 0.508)
		(drill 0.254)
		(layers "F.Cu" "B.Cu")
		(net "GND")
	)
	(via
		(at 206.248 -268.735302)
		(size 0.4826)
		(drill 0.254)
		(layers "F.Cu" "B.Cu")
		(net "GND")
	)
	(via
		(at 409.335478 -169.45991)
		(size 0.49022)
		(drill 0.254)
		(layers "F.Cu" "B.Cu")
		(net "GND")
	)
	(via
		(at 38.950138 -16.9799)
		(size 0.508)
		(drill 0.254)
		(layers "F.Cu" "B.Cu")
		(net "GND")
	)
	(via
		(at 162.162744 -343.122758)
		(size 0.508)
		(drill 0.254)
		(layers "F.Cu" "B.Cu")
		(net "GND")
	)
	(via
		(at 187.51804 -140.62075)
		(size 0.508)
		(drill 0.254)
		(layers "F.Cu" "B.Cu")
		(net "GND")
	)
	(via
		(at 402.86178 -176.35982)
		(size 0.508)
		(drill 0.254)
		(layers "F.Cu" "B.Cu")
		(net "GND")
	)
	(via
		(at 273.664172 -105.857802)
		(size 0.508)
		(drill 0.254)
		(layers "F.Cu" "B.Cu")
		(net "GND")
	)
	(via
		(at 384.924808 -267.606018)
		(size 0.4064)
		(drill 0.2032)
		(layers "F.Cu" "B.Cu")
		(net "GND")
	)
	(via
		(at 116.304822 -275.706332)
		(size 0.4064)
		(drill 0.2032)
		(layers "F.Cu" "B.Cu")
		(net "GND")
	)
	(via
		(at 411.691582 -418.412168)
		(size 0.4064)
		(drill 0.2032)
		(layers "F.Cu" "B.Cu")
		(net "GND")
	)
	(via
		(at 420.87292 -19.771868)
		(size 0.508)
		(drill 0.254)
		(layers "F.Cu" "B.Cu")
		(net "GND")
	)
	(via
		(at 280.67 -427.261528)
		(size 0.508)
		(drill 0.254)
		(layers "F.Cu" "B.Cu")
		(net "GND")
	)
	(via
		(at 320.963036 -376.75693)
		(size 0.508)
		(drill 0.254)
		(layers "F.Cu" "B.Cu")
		(net "GND")
	)
	(via
		(at 124.7648 -282.18638)
		(size 0.4064)
		(drill 0.2032)
		(layers "F.Cu" "B.Cu")
		(net "GND")
	)
	(via
		(at 100.496878 -138.911076)
		(size 0.508)
		(drill 0.254)
		(layers "F.Cu" "B.Cu")
		(net "GND")
	)
	(via
		(at 302.54067 -346.302076)
		(size 0.49022)
		(drill 0.254)
		(layers "F.Cu" "B.Cu")
		(net "GND")
	)
	(via
		(at 416.491674 -165.70706)
		(size 0.49022)
		(drill 0.254)
		(layers "F.Cu" "B.Cu")
		(net "GND")
	)
	(via
		(at 105.031032 -283.806392)
		(size 0.4064)
		(drill 0.2032)
		(layers "F.Cu" "B.Cu")
		(net "GND")
	)
	(via
		(at 125.716538 -391.830814)
		(size 0.4064)
		(drill 0.2032)
		(layers "F.Cu" "B.Cu")
		(net "GND")
	)
	(via
		(at 80.079342 -333.05369)
		(size 0.49022)
		(drill 0.254)
		(layers "F.Cu" "B.Cu")
		(net "GND")
	)
	(via
		(at 372.116604 -391.23493)
		(size 0.4064)
		(drill 0.2032)
		(layers "F.Cu" "B.Cu")
		(net "GND")
	)
	(via
		(at 118.354856 -226.66452)
		(size 0.4064)
		(drill 0.2032)
		(layers "F.Cu" "B.Cu")
		(net "GND")
	)
	(via
		(at 103.088186 -338.000086)
		(size 0.49022)
		(drill 0.254)
		(layers "F.Cu" "B.Cu")
		(net "GND")
	)
	(via
		(at 50.659792 -413.204152)
		(size 0.4572)
		(drill 0.254)
		(layers "F.Cu" "B.Cu")
		(net "GND")
	)
	(via
		(at 83.111086 -256.634488)
		(size 0.4064)
		(drill 0.2032)
		(layers "F.Cu" "B.Cu")
		(net "GND")
	)
	(via
		(at 467.5378 -133.147054)
		(size 0.508)
		(drill 0.254)
		(layers "F.Cu" "B.Cu")
		(net "GND")
	)
	(via
		(at 135.866378 -406.34666)
		(size 0.4572)
		(drill 0.254)
		(layers "F.Cu" "B.Cu")
		(net "GND")
	)
	(via
		(at 145.144744 -230.71455)
		(size 0.4064)
		(drill 0.2032)
		(layers "F.Cu" "B.Cu")
		(net "GND")
	)
	(via
		(at 396.397988 -384.175)
		(size 0.508)
		(drill 0.254)
		(layers "F.Cu" "B.Cu")
		(net "GND")
	)
	(via
		(at 135.274812 -255.824482)
		(size 0.4064)
		(drill 0.2032)
		(layers "F.Cu" "B.Cu")
		(net "GND")
	)
	(via
		(at 171.35348 -391.69975)
		(size 0.508)
		(drill 0.254)
		(layers "F.Cu" "B.Cu")
		(net "GND")
	)
	(via
		(at 183.616092 -268.735302)
		(size 0.4826)
		(drill 0.254)
		(layers "F.Cu" "B.Cu")
		(net "GND")
	)
	(via
		(at 335.738724 -333.034386)
		(size 0.49022)
		(drill 0.254)
		(layers "F.Cu" "B.Cu")
		(net "GND")
	)
	(via
		(at 196.581776 -79.397352)
		(size 0.508)
		(drill 0.254)
		(layers "F.Cu" "B.Cu")
		(net "GND")
	)
	(via
		(at 51.884072 -233.885232)
		(size 0.4826)
		(drill 0.254)
		(layers "F.Cu" "B.Cu")
		(net "GND")
	)
	(via
		(at 79.760572 -410.664152)
		(size 0.4572)
		(drill 0.254)
		(layers "F.Cu" "B.Cu")
		(net "GND")
	)
	(via
		(at 49.128172 -410.664152)
		(size 0.4572)
		(drill 0.254)
		(layers "F.Cu" "B.Cu")
		(net "GND")
	)
	(via
		(at 183.896254 -161.74466)
		(size 0.508)
		(drill 0.254)
		(layers "F.Cu" "B.Cu")
		(net "GND")
	)
	(via
		(at 247.298464 -80.682592)
		(size 0.508)
		(drill 0.254)
		(layers "F.Cu" "B.Cu")
		(net "GND")
	)
	(via
		(at 273.092164 -266.185142)
		(size 0.4826)
		(drill 0.254)
		(layers "F.Cu" "B.Cu")
		(net "GND")
	)
	(via
		(at 160.372298 -410.664152)
		(size 0.4572)
		(drill 0.254)
		(layers "F.Cu" "B.Cu")
		(net "GND")
	)
	(via
		(at 76.812902 -244.750336)
		(size 0.4064)
		(drill 0.2032)
		(layers "F.Cu" "B.Cu")
		(net "GND")
	)
	(via
		(at 359.994454 -268.00556)
		(size 0.4826)
		(drill 0.254)
		(layers "F.Cu" "B.Cu")
		(net "GND")
	)
	(via
		(at 95.590106 -384.617722)
		(size 0.4064)
		(drill 0.2032)
		(layers "F.Cu" "B.Cu")
		(net "GND")
	)
	(via
		(at 416.644328 -400.212814)
		(size 0.4064)
		(drill 0.2032)
		(layers "F.Cu" "B.Cu")
		(net "GND")
	)
	(via
		(at 216.46896 -119.620284)
		(size 0.508)
		(drill 0.254)
		(layers "F.Cu" "B.Cu")
		(net "GND")
	)
	(via
		(at 88.281002 -238.00435)
		(size 0.4064)
		(drill 0.2032)
		(layers "F.Cu" "B.Cu")
		(net "GND")
	)
	(via
		(at 436.117746 -304.860198)
		(size 0.4826)
		(drill 0.254)
		(layers "F.Cu" "B.Cu")
		(net "GND")
	)
	(via
		(at 406.406858 -166.605458)
		(size 0.49022)
		(drill 0.254)
		(layers "F.Cu" "B.Cu")
		(net "GND")
	)
	(via
		(at 301.755556 -376.75693)
		(size 0.508)
		(drill 0.254)
		(layers "F.Cu" "B.Cu")
		(net "GND")
	)
	(via
		(at 134.164832 -277.326344)
		(size 0.4064)
		(drill 0.2032)
		(layers "F.Cu" "B.Cu")
		(net "GND")
	)
	(via
		(at 145.144744 -251.774452)
		(size 0.4064)
		(drill 0.2032)
		(layers "F.Cu" "B.Cu")
		(net "GND")
	)
	(via
		(at 361.522264 -257.744976)
		(size 0.4826)
		(drill 0.254)
		(layers "F.Cu" "B.Cu")
		(net "GND")
	)
	(via
		(at 267.80617 -65.709292)
		(size 0.508)
		(drill 0.254)
		(layers "F.Cu" "B.Cu")
		(net "GND")
	)
	(via
		(at 348.271084 -285.42615)
		(size 0.4064)
		(drill 0.2032)
		(layers "F.Cu" "B.Cu")
		(net "GND")
	)
	(via
		(at 62.639956 -407.638504)
		(size 0.4572)
		(drill 0.254)
		(layers "F.Cu" "B.Cu")
		(net "GND")
	)
	(via
		(at 369.584732 -243.674138)
		(size 0.4064)
		(drill 0.2032)
		(layers "F.Cu" "B.Cu")
		(net "GND")
	)
	(via
		(at 100.331016 -285.426404)
		(size 0.4064)
		(drill 0.2032)
		(layers "F.Cu" "B.Cu")
		(net "GND")
	)
	(via
		(at 98.150934 -255.014476)
		(size 0.4064)
		(drill 0.2032)
		(layers "F.Cu" "B.Cu")
		(net "GND")
	)
	(via
		(at 356.909878 -168.930066)
		(size 0.49022)
		(drill 0.254)
		(layers "F.Cu" "B.Cu")
		(net "GND")
	)
	(via
		(at 61.381132 -410.664152)
		(size 0.4572)
		(drill 0.254)
		(layers "F.Cu" "B.Cu")
		(net "GND")
	)
	(via
		(at 376.93473 -294.335962)
		(size 0.4064)
		(drill 0.2032)
		(layers "F.Cu" "B.Cu")
		(net "GND")
	)
	(via
		(at 176.072038 -244.935248)
		(size 0.4826)
		(drill 0.254)
		(layers "F.Cu" "B.Cu")
		(net "GND")
	)
	(via
		(at 140.274802 -263.556242)
		(size 0.4064)
		(drill 0.2032)
		(layers "F.Cu" "B.Cu")
		(net "GND")
	)
	(via
		(at 310.981598 -421.586152)
		(size 0.4572)
		(drill 0.254)
		(layers "F.Cu" "B.Cu")
		(net "GND")
	)
	(via
		(at 350.621092 -281.37612)
		(size 0.4064)
		(drill 0.2032)
		(layers "F.Cu" "B.Cu")
		(net "GND")
	)
	(via
		(at 363.187996 -261.32282)
		(size 0.4826)
		(drill 0.254)
		(layers "F.Cu" "B.Cu")
		(net "GND")
	)
	(via
		(at 73.634092 -409.396184)
		(size 0.4572)
		(drill 0.254)
		(layers "F.Cu" "B.Cu")
		(net "GND")
	)
	(via
		(at 331.051154 -242.054126)
		(size 0.4064)
		(drill 0.2032)
		(layers "F.Cu" "B.Cu")
		(net "GND")
	)
	(via
		(at 70.212204 -410.030168)
		(size 0.4064)
		(drill 0.2032)
		(layers "F.Cu" "B.Cu")
		(net "GND")
	)
	(via
		(at 382.349502 -425.547282)
		(size 0.4572)
		(drill 0.2032)
		(layers "F.Cu" "B.Cu")
		(net "GND")
	)
	(via
		(at 155.594304 -374.62333)
		(size 0.508)
		(drill 0.254)
		(layers "F.Cu" "B.Cu")
		(net "GND")
	)
	(via
		(at 419.912038 -247.485154)
		(size 0.4826)
		(drill 0.254)
		(layers "F.Cu" "B.Cu")
		(net "GND")
	)
	(via
		(at 158.68904 -107.840526)
		(size 0.508)
		(drill 0.254)
		(layers "F.Cu" "B.Cu")
		(net "GND")
	)
	(via
		(at 115.834668 -271.656302)
		(size 0.4064)
		(drill 0.2032)
		(layers "F.Cu" "B.Cu")
		(net "GND")
	)
	(via
		(at 358.793288 -395.466062)
		(size 0.508)
		(drill 0.254)
		(layers "F.Cu" "B.Cu")
		(net "GND")
	)
	(via
		(at 309.808626 -418.412168)
		(size 0.4064)
		(drill 0.2032)
		(layers "F.Cu" "B.Cu")
		(net "GND")
	)
	(via
		(at 446.644268 -291.684964)
		(size 0.4826)
		(drill 0.254)
		(layers "F.Cu" "B.Cu")
		(net "GND")
	)
	(via
		(at 307.368194 -198.185024)
		(size 0.4826)
		(drill 0.254)
		(layers "F.Cu" "B.Cu")
		(net "GND")
	)
	(via
		(at 454.159366 -376.53087)
		(size 0.508)
		(drill 0.254)
		(layers "F.Cu" "B.Cu")
		(net "GND")
	)
	(via
		(at 44.124626 -5.597398)
		(size 0.508)
		(drill 0.254)
		(layers "F.Cu" "B.Cu")
		(net "GND")
	)
	(via
		(at 149.844252 -393.927838)
		(size 0.4572)
		(drill 0.254)
		(layers "F.Cu" "B.Cu")
		(net "GND")
	)
	(via
		(at 128.962404 -384.617722)
		(size 0.4064)
		(drill 0.2032)
		(layers "F.Cu" "B.Cu")
		(net "GND")
	)
	(via
		(at 26.509218 -18.247106)
		(size 0.508)
		(drill 0.254)
		(layers "F.Cu" "B.Cu")
		(net "GND")
	)
	(via
		(at 140.274802 -294.336216)
		(size 0.4064)
		(drill 0.2032)
		(layers "F.Cu" "B.Cu")
		(net "GND")
	)
	(via
		(at 213.832948 -99.172014)
		(size 0.508)
		(drill 0.254)
		(layers "F.Cu" "B.Cu")
		(net "GND")
	)
	(via
		(at 326.50303 -398.719802)
		(size 0.508)
		(drill 0.254)
		(layers "F.Cu" "B.Cu")
		(net "GND")
	)
	(via
		(at 187.060078 -311.235344)
		(size 0.4826)
		(drill 0.254)
		(layers "F.Cu" "B.Cu")
		(net "GND")
	)
	(via
		(at 116.004848 -229.094538)
		(size 0.4064)
		(drill 0.2032)
		(layers "F.Cu" "B.Cu")
		(net "GND")
	)
	(via
		(at 55.969154 -371.49913)
		(size 0.508)
		(drill 0.254)
		(layers "F.Cu" "B.Cu")
		(net "GND")
	)
	(via
		(at 21.70811 -291.685218)
		(size 0.4826)
		(drill 0.254)
		(layers "F.Cu" "B.Cu")
		(net "GND")
	)
	(via
		(at 381.334772 -236.384084)
		(size 0.4064)
		(drill 0.2032)
		(layers "F.Cu" "B.Cu")
		(net "GND")
	)
	(via
		(at 193.598546 -32.939736)
		(size 0.508)
		(drill 0.254)
		(layers "F.Cu" "B.Cu")
		(net "GND")
	)
	(via
		(at 366.294924 -242.864132)
		(size 0.4064)
		(drill 0.2032)
		(layers "F.Cu" "B.Cu")
		(net "GND")
	)
	(via
		(at 130.104642 -255.014476)
		(size 0.4064)
		(drill 0.2032)
		(layers "F.Cu" "B.Cu")
		(net "GND")
	)
	(via
		(at 203.265532 -304.860452)
		(size 0.4826)
		(drill 0.254)
		(layers "F.Cu" "B.Cu")
		(net "GND")
	)
	(via
		(at 45.389546 -5.597398)
		(size 0.508)
		(drill 0.254)
		(layers "F.Cu" "B.Cu")
		(net "GND")
	)
	(via
		(at 347.031056 -245.29415)
		(size 0.4064)
		(drill 0.2032)
		(layers "F.Cu" "B.Cu")
		(net "GND")
	)
	(via
		(at 2.76225 -205.161134)
		(size 0.508)
		(drill 0.254)
		(layers "F.Cu" "B.Cu")
		(net "GND")
	)
	(via
		(at 111.974884 -400.437604)
		(size 0.508)
		(drill 0.254)
		(layers "F.Cu" "B.Cu")
		(net "GND")
	)
	(via
		(at 25.152096 -234.73537)
		(size 0.4826)
		(drill 0.254)
		(layers "F.Cu" "B.Cu")
		(net "GND")
	)
	(via
		(at 411.7467 -170.629072)
		(size 0.508)
		(drill 0.254)
		(layers "F.Cu" "B.Cu")
		(net "GND")
	)
	(via
		(at 24.134572 -389.4201)
		(size 0.49022)
		(drill 0.254)
		(layers "F.Cu" "B.Cu")
		(net "GND")
	)
	(via
		(at 21.70811 -246.63527)
		(size 0.4826)
		(drill 0.254)
		(layers "F.Cu" "B.Cu")
		(net "GND")
	)
	(via
		(at 223.759776 -71.970138)
		(size 0.508)
		(drill 0.254)
		(layers "F.Cu" "B.Cu")
		(net "GND")
	)
	(via
		(at 365.82477 -229.094284)
		(size 0.4064)
		(drill 0.2032)
		(layers "F.Cu" "B.Cu")
		(net "GND")
	)
	(via
		(at 284.054804 -404.905972)
		(size 0.508)
		(drill 0.254)
		(layers "F.Cu" "B.Cu")
		(net "GND")
	)
	(via
		(at 124.7648 -264.366248)
		(size 0.4064)
		(drill 0.2032)
		(layers "F.Cu" "B.Cu")
		(net "GND")
	)
	(via
		(at 171.97197 -236.435392)
		(size 0.4826)
		(drill 0.254)
		(layers "F.Cu" "B.Cu")
		(net "GND")
	)
	(via
		(at 31.777178 -432.477164)
		(size 0.508)
		(drill 0.254)
		(layers "F.Cu" "B.Cu")
		(net "GND")
	)
	(via
		(at 233.075988 -225.43643)
		(size 0.508)
		(drill 0.254)
		(layers "F.Cu" "B.Cu")
		(net "GND")
	)
	(via
		(at 195.721732 -276.81047)
		(size 0.4826)
		(drill 0.254)
		(layers "F.Cu" "B.Cu")
		(net "GND")
	)
	(via
		(at 315.849254 -420.318184)
		(size 0.4572)
		(drill 0.254)
		(layers "F.Cu" "B.Cu")
		(net "GND")
	)
	(via
		(at 339.511132 -229.094284)
		(size 0.4064)
		(drill 0.2032)
		(layers "F.Cu" "B.Cu")
		(net "GND")
	)
	(via
		(at 138.349736 -432.747166)
		(size 0.4572)
		(drill 0.2032)
		(layers "F.Cu" "B.Cu")
		(net "GND")
	)
	(via
		(at 58.26252 -384.617722)
		(size 0.4064)
		(drill 0.2032)
		(layers "F.Cu" "B.Cu")
		(net "GND")
	)
	(via
		(at 36.73094 -109.10824)
		(size 0.508)
		(drill 0.254)
		(layers "F.Cu" "B.Cu")
		(net "GND")
	)
	(via
		(at 157.89021 -384.617722)
		(size 0.4064)
		(drill 0.2032)
		(layers "F.Cu" "B.Cu")
		(net "GND")
	)
	(via
		(at 442.5442 -307.835046)
		(size 0.4826)
		(drill 0.254)
		(layers "F.Cu" "B.Cu")
		(net "GND")
	)
	(via
		(at 417.043616 -343.272618)
		(size 0.508)
		(drill 0.254)
		(layers "F.Cu" "B.Cu")
		(net "GND")
	)
	(via
		(at 341.428324 -333.874364)
		(size 0.49022)
		(drill 0.254)
		(layers "F.Cu" "B.Cu")
		(net "GND")
	)
	(via
		(at 119.2784 -386.449062)
		(size 0.4064)
		(drill 0.2032)
		(layers "F.Cu" "B.Cu")
		(net "GND")
	)
	(via
		(at 130.104642 -235.574332)
		(size 0.4064)
		(drill 0.2032)
		(layers "F.Cu" "B.Cu")
		(net "GND")
	)
	(via
		(at 309.361586 -412.84652)
		(size 0.4064)
		(drill 0.2032)
		(layers "F.Cu" "B.Cu")
		(net "GND")
	)
	(via
		(at 17.608042 -289.135312)
		(size 0.4826)
		(drill 0.254)
		(layers "F.Cu" "B.Cu")
		(net "GND")
	)
	(via
		(at 325.038974 -413.480504)
		(size 0.4572)
		(drill 0.254)
		(layers "F.Cu" "B.Cu")
		(net "GND")
	)
	(via
		(at 79.821024 -241.244374)
		(size 0.4064)
		(drill 0.2032)
		(layers "F.Cu" "B.Cu")
		(net "GND")
	)
	(via
		(at 124.7648 -288.666174)
		(size 0.4064)
		(drill 0.2032)
		(layers "F.Cu" "B.Cu")
		(net "GND")
	)
	(via
		(at 350.791018 -225.85426)
		(size 0.4064)
		(drill 0.2032)
		(layers "F.Cu" "B.Cu")
		(net "GND")
	)
	(via
		(at 139.34694 -14.72946)
		(size 0.508)
		(drill 0.254)
		(layers "F.Cu" "B.Cu")
		(net "GND")
	)
	(via
		(at 427.456092 -225.385122)
		(size 0.4826)
		(drill 0.254)
		(layers "F.Cu" "B.Cu")
		(net "GND")
	)
	(via
		(at 407.094182 -412.84652)
		(size 0.4064)
		(drill 0.2032)
		(layers "F.Cu" "B.Cu")
		(net "GND")
	)
	(via
		(at 58.310526 -201.16038)
		(size 0.4826)
		(drill 0.254)
		(layers "F.Cu" "B.Cu")
		(net "GND")
	)
	(via
		(at 74.602086 -178.02479)
		(size 0.49022)
		(drill 0.254)
		(layers "F.Cu" "B.Cu")
		(net "GND")
	)
	(via
		(at 176.072038 -289.98545)
		(size 0.4826)
		(drill 0.254)
		(layers "F.Cu" "B.Cu")
		(net "GND")
	)
	(via
		(at 82.249772 -428.851314)
		(size 0.4572)
		(drill 0.2032)
		(layers "F.Cu" "B.Cu")
		(net "GND")
	)
	(via
		(at 419.912038 -298.485052)
		(size 0.4826)
		(drill 0.254)
		(layers "F.Cu" "B.Cu")
		(net "GND")
	)
	(via
		(at 336.22107 -233.14406)
		(size 0.4064)
		(drill 0.2032)
		(layers "F.Cu" "B.Cu")
		(net "GND")
	)
	(via
		(at 375.054876 -291.095938)
		(size 0.4064)
		(drill 0.2032)
		(layers "F.Cu" "B.Cu")
		(net "GND")
	)
	(via
		(at 329.241912 -103.66375)
		(size 0.508)
		(drill 0.254)
		(layers "F.Cu" "B.Cu")
		(net "GND")
	)
	(via
		(at 368.644678 -250.154186)
		(size 0.4064)
		(drill 0.2032)
		(layers "F.Cu" "B.Cu")
		(net "GND")
	)
	(via
		(at 181.618382 -350.14535)
		(size 0.49022)
		(drill 0.254)
		(layers "F.Cu" "B.Cu")
		(net "GND")
	)
	(via
		(at 417.10229 -105.207308)
		(size 0.508)
		(drill 0.254)
		(layers "F.Cu" "B.Cu")
		(net "GND")
	)
	(via
		(at 107.081066 -249.344434)
		(size 0.4064)
		(drill 0.2032)
		(layers "F.Cu" "B.Cu")
		(net "GND")
	)
	(via
		(at 40.255698 -7.215124)
		(size 0.508)
		(drill 0.254)
		(layers "F.Cu" "B.Cu")
		(net "GND")
	)
	(via
		(at 332.931008 -250.154186)
		(size 0.4064)
		(drill 0.2032)
		(layers "F.Cu" "B.Cu")
		(net "GND")
	)
	(via
		(at 394.576808 -6.091174)
		(size 0.508)
		(drill 0.254)
		(layers "F.Cu" "B.Cu")
		(net "GND")
	)
	(via
		(at 458.260196 -64.449706)
		(size 0.508)
		(drill 0.254)
		(layers "F.Cu" "B.Cu")
		(net "GND")
	)
	(via
		(at 117.884702 -235.574332)
		(size 0.4064)
		(drill 0.2032)
		(layers "F.Cu" "B.Cu")
		(net "GND")
	)
	(via
		(at 41.508934 -361.993434)
		(size 0.508)
		(drill 0.254)
		(layers "F.Cu" "B.Cu")
		(net "GND")
	)
	(via
		(at 133.161786 -410.030168)
		(size 0.4064)
		(drill 0.2032)
		(layers "F.Cu" "B.Cu")
		(net "GND")
	)
	(via
		(at 149.54631 -388.328662)
		(size 0.4064)
		(drill 0.2032)
		(layers "F.Cu" "B.Cu")
		(net "GND")
	)
	(via
		(at 325.411084 -224.234248)
		(size 0.4064)
		(drill 0.2032)
		(layers "F.Cu" "B.Cu")
		(net "GND")
	)
	(via
		(at 334.341216 -238.004096)
		(size 0.4064)
		(drill 0.2032)
		(layers "F.Cu" "B.Cu")
		(net "GND")
	)
	(via
		(at 344.249502 -426.69968)
		(size 0.4572)
		(drill 0.2032)
		(layers "F.Cu" "B.Cu")
		(net "GND")
	)
	(via
		(at 350.151192 -264.365994)
		(size 0.4064)
		(drill 0.2032)
		(layers "F.Cu" "B.Cu")
		(net "GND")
	)
	(via
		(at 382.94945 -420.318184)
		(size 0.4572)
		(drill 0.254)
		(layers "F.Cu" "B.Cu")
		(net "GND")
	)
	(via
		(at 292.280086 -263.634982)
		(size 0.4826)
		(drill 0.254)
		(layers "F.Cu" "B.Cu")
		(net "GND")
	)
	(via
		(at 108.961174 -247.724422)
		(size 0.4064)
		(drill 0.2032)
		(layers "F.Cu" "B.Cu")
		(net "GND")
	)
	(via
		(at 131.98475 -245.294404)
		(size 0.4064)
		(drill 0.2032)
		(layers "F.Cu" "B.Cu")
		(net "GND")
	)
	(via
		(at 288.180018 -234.735116)
		(size 0.4826)
		(drill 0.254)
		(layers "F.Cu" "B.Cu")
		(net "GND")
	)
	(via
		(at 212.376258 -15.920974)
		(size 0.508)
		(drill 0.254)
		(layers "F.Cu" "B.Cu")
		(net "GND")
	)
	(via
		(at 305.778408 -394.831062)
		(size 0.4064)
		(drill 0.2032)
		(layers "F.Cu" "B.Cu")
		(net "GND")
	)
	(via
		(at 206.248 -267.03528)
		(size 0.4826)
		(drill 0.254)
		(layers "F.Cu" "B.Cu")
		(net "GND")
	)
	(via
		(at 435.000146 -199.035162)
		(size 0.4826)
		(drill 0.254)
		(layers "F.Cu" "B.Cu")
		(net "GND")
	)
	(via
		(at 358.56037 -397.274542)
		(size 0.508)
		(drill 0.254)
		(layers "F.Cu" "B.Cu")
		(net "GND")
	)
	(via
		(at 77.888338 -335.558892)
		(size 0.49022)
		(drill 0.254)
		(layers "F.Cu" "B.Cu")
		(net "GND")
	)
	(via
		(at 59.428126 -232.18521)
		(size 0.4826)
		(drill 0.254)
		(layers "F.Cu" "B.Cu")
		(net "GND")
	)
	(via
		(at 54.210458 -295.510458)
		(size 0.4826)
		(drill 0.254)
		(layers "F.Cu" "B.Cu")
		(net "GND")
	)
	(via
		(at 107.85094 -283.806392)
		(size 0.4064)
		(drill 0.2032)
		(layers "F.Cu" "B.Cu")
		(net "GND")
	)
	(via
		(at 374.754902 -255.824228)
		(size 0.4064)
		(drill 0.2032)
		(layers "F.Cu" "B.Cu")
		(net "GND")
	)
	(via
		(at 454.188068 -250.03506)
		(size 0.4826)
		(drill 0.254)
		(layers "F.Cu" "B.Cu")
		(net "GND")
	)
	(via
		(at 36.837112 -369.49507)
		(size 0.508)
		(drill 0.254)
		(layers "F.Cu" "B.Cu")
		(net "GND")
	)
	(via
		(at 304.701448 -431.884836)
		(size 0.508)
		(drill 0.254)
		(layers "F.Cu" "B.Cu")
		(net "GND")
	)
	(via
		(at 354.551234 -246.914162)
		(size 0.4064)
		(drill 0.2032)
		(layers "F.Cu" "B.Cu")
		(net "GND")
	)
	(via
		(at 439.100214 -246.635016)
		(size 0.4826)
		(drill 0.254)
		(layers "F.Cu" "B.Cu")
		(net "GND")
	)
	(via
		(at 133.694678 -284.616398)
		(size 0.4064)
		(drill 0.2032)
		(layers "F.Cu" "B.Cu")
		(net "GND")
	)
	(via
		(at 394.614654 -4.963414)
		(size 0.508)
		(drill 0.254)
		(layers "F.Cu" "B.Cu")
		(net "GND")
	)
	(via
		(at 343.101168 -279.756108)
		(size 0.4064)
		(drill 0.2032)
		(layers "F.Cu" "B.Cu")
		(net "GND")
	)
	(via
		(at 371.93474 -234.764072)
		(size 0.4064)
		(drill 0.2032)
		(layers "F.Cu" "B.Cu")
		(net "GND")
	)
	(via
		(at 42.091102 -382.54432)
		(size 0.508)
		(drill 0.254)
		(layers "F.Cu" "B.Cu")
		(net "GND")
	)
	(via
		(at 307.309266 -431.891186)
		(size 0.508)
		(drill 0.254)
		(layers "F.Cu" "B.Cu")
		(net "GND")
	)
	(via
		(at 4.236974 -368.767614)
		(size 0.6604)
		(drill 0.3302)
		(layers "F.Cu" "B.Cu")
		(net "GND")
	)
	(via
		(at 114.297968 -256.3876)
		(size 0.4826)
		(drill 0.254)
		(layers "F.Cu" "B.Cu")
		(net "GND")
	)
	(via
		(at 436.852822 -409.68676)
		(size 0.508)
		(drill 0.254)
		(layers "F.Cu" "B.Cu")
		(net "GND")
	)
	(via
		(at 412.367984 -311.23509)
		(size 0.4826)
		(drill 0.254)
		(layers "F.Cu" "B.Cu")
		(net "GND")
	)
	(via
		(at 85.461094 -225.044508)
		(size 0.4064)
		(drill 0.2032)
		(layers "F.Cu" "B.Cu")
		(net "GND")
	)
	(via
		(at 21.70811 -235.585254)
		(size 0.4826)
		(drill 0.254)
		(layers "F.Cu" "B.Cu")
		(net "GND")
	)
	(via
		(at 351.007172 -423.648378)
		(size 0.508)
		(drill 0.254)
		(layers "F.Cu" "B.Cu")
		(net "GND")
	)
	(via
		(at 176.072038 -232.18521)
		(size 0.4826)
		(drill 0.254)
		(layers "F.Cu" "B.Cu")
		(net "GND")
	)
	(via
		(at 165.365684 -149.1742)
		(size 0.508)
		(drill 0.254)
		(layers "F.Cu" "B.Cu")
		(net "GND")
	)
	(via
		(at 431.55616 -222.834962)
		(size 0.4826)
		(drill 0.254)
		(layers "F.Cu" "B.Cu")
		(net "GND")
	)
	(via
		(at 367.064798 -285.42615)
		(size 0.4064)
		(drill 0.2032)
		(layers "F.Cu" "B.Cu")
		(net "GND")
	)
	(via
		(at 70.43293 -180.209698)
		(size 0.508)
		(drill 0.254)
		(layers "F.Cu" "B.Cu")
		(net "GND")
	)
	(via
		(at 387.632702 -412.84652)
		(size 0.4064)
		(drill 0.2032)
		(layers "F.Cu" "B.Cu")
		(net "GND")
	)
	(via
		(at 134.334758 -225.044508)
		(size 0.4064)
		(drill 0.2032)
		(layers "F.Cu" "B.Cu")
		(net "GND")
	)
	(via
		(at 134.164832 -287.046416)
		(size 0.4064)
		(drill 0.2032)
		(layers "F.Cu" "B.Cu")
		(net "GND")
	)
	(via
		(at 362.834682 -284.616144)
		(size 0.4064)
		(drill 0.2032)
		(layers "F.Cu" "B.Cu")
		(net "GND")
	)
	(via
		(at 391.504678 -278.946102)
		(size 0.4064)
		(drill 0.2032)
		(layers "F.Cu" "B.Cu")
		(net "GND")
	)
	(via
		(at 93.10624 -386.449062)
		(size 0.4064)
		(drill 0.2032)
		(layers "F.Cu" "B.Cu")
		(net "GND")
	)
	(via
		(at 88.744298 -391.830814)
		(size 0.4064)
		(drill 0.2032)
		(layers "F.Cu" "B.Cu")
		(net "GND")
	)
	(via
		(at 301.169578 -116.891308)
		(size 0.508)
		(drill 0.254)
		(layers "F.Cu" "B.Cu")
		(net "GND")
	)
	(via
		(at 440.086496 -331.449172)
		(size 0.508)
		(drill 0.254)
		(layers "F.Cu" "B.Cu")
		(net "GND")
	)
	(via
		(at 369.114832 -244.484144)
		(size 0.4064)
		(drill 0.2032)
		(layers "F.Cu" "B.Cu")
		(net "GND")
	)
	(via
		(at 239.014 -284.977078)
		(size 0.508)
		(drill 0.254)
		(layers "F.Cu" "B.Cu")
		(net "GND")
	)
	(via
		(at 420.613078 -367.059464)
		(size 0.508)
		(drill 0.254)
		(layers "F.Cu" "B.Cu")
		(net "GND")
	)
	(via
		(at 144.504664 -293.52621)
		(size 0.4064)
		(drill 0.2032)
		(layers "F.Cu" "B.Cu")
		(net "GND")
	)
	(via
		(at 322.603876 -72.884792)
		(size 0.508)
		(drill 0.254)
		(layers "F.Cu" "B.Cu")
		(net "GND")
	)
	(via
		(at 87.280242 -374.62333)
		(size 0.508)
		(drill 0.254)
		(layers "F.Cu" "B.Cu")
		(net "GND")
	)
	(via
		(at 58.463434 -336.271616)
		(size 0.508)
		(drill 0.254)
		(layers "F.Cu" "B.Cu")
		(net "GND")
	)
	(via
		(at 44.340018 -253.435358)
		(size 0.4826)
		(drill 0.254)
		(layers "F.Cu" "B.Cu")
		(net "GND")
	)
	(via
		(at 427.456092 -233.035094)
		(size 0.4826)
		(drill 0.254)
		(layers "F.Cu" "B.Cu")
		(net "GND")
	)
	(via
		(at 402.048218 -9.424924)
		(size 0.508)
		(drill 0.254)
		(layers "F.Cu" "B.Cu")
		(net "GND")
	)
	(via
		(at 107.436666 -180.111146)
		(size 0.49022)
		(drill 0.254)
		(layers "F.Cu" "B.Cu")
		(net "GND")
	)
	(via
		(at 198.7042 -289.98545)
		(size 0.4826)
		(drill 0.254)
		(layers "F.Cu" "B.Cu")
		(net "GND")
	)
	(via
		(at 393.084812 -227.474272)
		(size 0.4064)
		(drill 0.2032)
		(layers "F.Cu" "B.Cu")
		(net "GND")
	)
	(via
		(at 93.545152 -413.204152)
		(size 0.4572)
		(drill 0.254)
		(layers "F.Cu" "B.Cu")
		(net "GND")
	)
	(via
		(at 34.82848 -369.506754)
		(size 0.508)
		(drill 0.254)
		(layers "F.Cu" "B.Cu")
		(net "GND")
	)
	(via
		(at 42.091102 -381.3302)
		(size 0.508)
		(drill 0.254)
		(layers "F.Cu" "B.Cu")
		(net "GND")
	)
	(via
		(at 434.221382 -343.28608)
		(size 0.508)
		(drill 0.254)
		(layers "F.Cu" "B.Cu")
		(net "GND")
	)
	(via
		(at 435.000146 -250.884944)
		(size 0.4826)
		(drill 0.254)
		(layers "F.Cu" "B.Cu")
		(net "GND")
	)
	(via
		(at 430.17186 -227.935028)
		(size 0.4826)
		(drill 0.254)
		(layers "F.Cu" "B.Cu")
		(net "GND")
	)
	(via
		(at 451.2056 -230.060246)
		(size 0.4826)
		(drill 0.254)
		(layers "F.Cu" "B.Cu")
		(net "GND")
	)
	(via
		(at 443.6618 -276.810216)
		(size 0.4826)
		(drill 0.254)
		(layers "F.Cu" "B.Cu")
		(net "GND")
	)
	(via
		(at 118.184676 -280.566368)
		(size 0.4064)
		(drill 0.2032)
		(layers "F.Cu" "B.Cu")
		(net "GND")
	)
	(via
		(at 280.635964 -204.985112)
		(size 0.4826)
		(drill 0.254)
		(layers "F.Cu" "B.Cu")
		(net "GND")
	)
	(via
		(at 207.3656 -294.66032)
		(size 0.4826)
		(drill 0.254)
		(layers "F.Cu" "B.Cu")
		(net "GND")
	)
	(via
		(at 149.304248 -120.485662)
		(size 0.508)
		(drill 0.254)
		(layers "F.Cu" "B.Cu")
		(net "GND")
	)
	(via
		(at 128.694688 -225.044508)
		(size 0.4064)
		(drill 0.2032)
		(layers "F.Cu" "B.Cu")
		(net "GND")
	)
	(via
		(at 403.803104 -19.771106)
		(size 0.508)
		(drill 0.254)
		(layers "F.Cu" "B.Cu")
		(net "GND")
	)
	(via
		(at 203.532232 -200.735438)
		(size 0.4826)
		(drill 0.254)
		(layers "F.Cu" "B.Cu")
		(net "GND")
	)
	(via
		(at 344.981022 -287.856168)
		(size 0.4064)
		(drill 0.2032)
		(layers "F.Cu" "B.Cu")
		(net "GND")
	)
	(via
		(at 9.760204 -421.400986)
		(size 0.508)
		(drill 0.254)
		(layers "F.Cu" "B.Cu")
		(net "GND")
	)
	(via
		(at 152.187656 -109.781086)
		(size 0.508)
		(drill 0.254)
		(layers "F.Cu" "B.Cu")
		(net "GND")
	)
	(via
		(at 17.608042 -197.335394)
		(size 0.4826)
		(drill 0.254)
		(layers "F.Cu" "B.Cu")
		(net "GND")
	)
	(via
		(at 310.578246 -394.831062)
		(size 0.4064)
		(drill 0.2032)
		(layers "F.Cu" "B.Cu")
		(net "GND")
	)
	(via
		(at 279.518364 -202.01001)
		(size 0.4826)
		(drill 0.254)
		(layers "F.Cu" "B.Cu")
		(net "GND")
	)
	(via
		(at 101.27107 -274.08632)
		(size 0.4064)
		(drill 0.2032)
		(layers "F.Cu" "B.Cu")
		(net "GND")
	)
	(via
		(at 64.171576 -405.098504)
		(size 0.4572)
		(drill 0.254)
		(layers "F.Cu" "B.Cu")
		(net "GND")
	)
	(via
		(at 334.79994 -336.961988)
		(size 0.49022)
		(drill 0.254)
		(layers "F.Cu" "B.Cu")
		(net "GND")
	)
	(via
		(at 337.544156 -391.23493)
		(size 0.4064)
		(drill 0.2032)
		(layers "F.Cu" "B.Cu")
		(net "GND")
	)
	(via
		(at 132.284724 -269.226284)
		(size 0.4064)
		(drill 0.2032)
		(layers "F.Cu" "B.Cu")
		(net "GND")
	)
	(via
		(at 435.000146 -281.485086)
		(size 0.4826)
		(drill 0.254)
		(layers "F.Cu" "B.Cu")
		(net "GND")
	)
	(via
		(at 331.367384 -379.22073)
		(size 0.508)
		(drill 0.254)
		(layers "F.Cu" "B.Cu")
		(net "GND")
	)
	(via
		(at 99.561142 -236.384338)
		(size 0.4064)
		(drill 0.2032)
		(layers "F.Cu" "B.Cu")
		(net "GND")
	)
	(via
		(at 171.97197 -318.885316)
		(size 0.4826)
		(drill 0.254)
		(layers "F.Cu" "B.Cu")
		(net "GND")
	)
	(via
		(at 90.16111 -225.044508)
		(size 0.4064)
		(drill 0.2032)
		(layers "F.Cu" "B.Cu")
		(net "GND")
	)
	(via
		(at 50.90287 -160.62579)
		(size 0.508)
		(drill 0.254)
		(layers "F.Cu" "B.Cu")
		(net "GND")
	)
	(via
		(at 47.168054 -339.814662)
		(size 0.508)
		(drill 0.254)
		(layers "F.Cu" "B.Cu")
		(net "GND")
	)
	(via
		(at 20.32381 -314.635388)
		(size 0.4826)
		(drill 0.254)
		(layers "F.Cu" "B.Cu")
		(net "GND")
	)
	(via
		(at 447.314066 -396.90167)
		(size 0.49022)
		(drill 0.254)
		(layers "F.Cu" "B.Cu")
		(net "GND")
	)
	(via
		(at 168.527984 -205.83525)
		(size 0.4826)
		(drill 0.254)
		(layers "F.Cu" "B.Cu")
		(net "GND")
	)
	(via
		(at 136.680956 -368.37493)
		(size 0.508)
		(drill 0.254)
		(layers "F.Cu" "B.Cu")
		(net "GND")
	)
	(via
		(at 169.268394 -17.654778)
		(size 0.508)
		(drill 0.254)
		(layers "F.Cu" "B.Cu")
		(net "GND")
	)
	(via
		(at 419.912038 -244.08511)
		(size 0.4826)
		(drill 0.254)
		(layers "F.Cu" "B.Cu")
		(net "GND")
	)
	(via
		(at 99.090988 -246.914416)
		(size 0.4064)
		(drill 0.2032)
		(layers "F.Cu" "B.Cu")
		(net "GND")
	)
	(via
		(at 84.249768 -429.147224)
		(size 0.4572)
		(drill 0.2032)
		(layers "F.Cu" "B.Cu")
		(net "GND")
	)
	(via
		(at 163.77793 -350.077278)
		(size 0.508)
		(drill 0.254)
		(layers "F.Cu" "B.Cu")
		(net "GND")
	)
	(via
		(at 357.371142 -224.234248)
		(size 0.4064)
		(drill 0.2032)
		(layers "F.Cu" "B.Cu")
		(net "GND")
	)
	(via
		(at 404.7871 -383.00533)
		(size 0.508)
		(drill 0.254)
		(layers "F.Cu" "B.Cu")
		(net "GND")
	)
	(via
		(at 21.70811 -216.885266)
		(size 0.4826)
		(drill 0.254)
		(layers "F.Cu" "B.Cu")
		(net "GND")
	)
	(via
		(at 306.386738 -414.752536)
		(size 0.4572)
		(drill 0.254)
		(layers "F.Cu" "B.Cu")
		(net "GND")
	)
	(via
		(at 164.427916 -199.035416)
		(size 0.4826)
		(drill 0.254)
		(layers "F.Cu" "B.Cu")
		(net "GND")
	)
	(via
		(at 179.516024 -197.335394)
		(size 0.4826)
		(drill 0.254)
		(layers "F.Cu" "B.Cu")
		(net "GND")
	)
	(via
		(at 442.49848 -437.74741)
		(size 0.508)
		(drill 0.254)
		(layers "F.Cu" "B.Cu")
		(net "GND")
	)
	(via
		(at 419.796722 -415.38652)
		(size 0.4064)
		(drill 0.2032)
		(layers "F.Cu" "B.Cu")
		(net "GND")
	)
	(via
		(at 133.394704 -241.244374)
		(size 0.4064)
		(drill 0.2032)
		(layers "F.Cu" "B.Cu")
		(net "GND")
	)
	(via
		(at 326.351138 -235.574078)
		(size 0.4064)
		(drill 0.2032)
		(layers "F.Cu" "B.Cu")
		(net "GND")
	)
	(via
		(at 386.349494 -437.49976)
		(size 0.4572)
		(drill 0.2032)
		(layers "F.Cu" "B.Cu")
		(net "GND")
	)
	(via
		(at 187.060078 -307.8353)
		(size 0.4826)
		(drill 0.254)
		(layers "F.Cu" "B.Cu")
		(net "GND")
	)
	(via
		(at 377.549918 -185.327798)
		(size 0.508)
		(drill 0.254)
		(layers "F.Cu" "B.Cu")
		(net "GND")
	)
	(via
		(at 143.73479 -233.144314)
		(size 0.4064)
		(drill 0.2032)
		(layers "F.Cu" "B.Cu")
		(net "GND")
	)
	(via
		(at 436.384446 -287.435036)
		(size 0.4826)
		(drill 0.254)
		(layers "F.Cu" "B.Cu")
		(net "GND")
	)
	(via
		(at 104.5972 -55.9308)
		(size 0.508)
		(drill 0.254)
		(layers "F.Cu" "B.Cu")
		(net "GND")
	)
	(via
		(at 36.795964 -299.335444)
		(size 0.4826)
		(drill 0.254)
		(layers "F.Cu" "B.Cu")
		(net "GND")
	)
	(via
		(at 105.200958 -231.524302)
		(size 0.4064)
		(drill 0.2032)
		(layers "F.Cu" "B.Cu")
		(net "GND")
	)
	(via
		(at 387.54431 -416.020504)
		(size 0.4572)
		(drill 0.254)
		(layers "F.Cu" "B.Cu")
		(net "GND")
	)
	(via
		(at 29.348176 -9.424924)
		(size 0.508)
		(drill 0.254)
		(layers "F.Cu" "B.Cu")
		(net "GND")
	)
	(via
		(at 389.389874 -184.683146)
		(size 0.49022)
		(drill 0.254)
		(layers "F.Cu" "B.Cu")
		(net "GND")
	)
	(via
		(at 365.35487 -250.964192)
		(size 0.4064)
		(drill 0.2032)
		(layers "F.Cu" "B.Cu")
		(net "GND")
	)
	(via
		(at 350.621092 -289.475926)
		(size 0.4064)
		(drill 0.2032)
		(layers "F.Cu" "B.Cu")
		(net "GND")
	)
	(via
		(at 58.045096 -405.098504)
		(size 0.4572)
		(drill 0.254)
		(layers "F.Cu" "B.Cu")
		(net "GND")
	)
	(via
		(at 373.344694 -224.234248)
		(size 0.4064)
		(drill 0.2032)
		(layers "F.Cu" "B.Cu")
		(net "GND")
	)
	(via
		(at 162.265106 -412.570168)
		(size 0.4064)
		(drill 0.2032)
		(layers "F.Cu" "B.Cu")
		(net "GND")
	)
	(via
		(at 96.571054 -261.126224)
		(size 0.4064)
		(drill 0.2032)
		(layers "F.Cu" "B.Cu")
		(net "GND")
	)
	(via
		(at 38.48354 -425.909994)
		(size 0.508)
		(drill 0.254)
		(layers "F.Cu" "B.Cu")
		(net "GND")
	)
	(via
		(at 16.598138 -18.247106)
		(size 0.508)
		(drill 0.254)
		(layers "F.Cu" "B.Cu")
		(net "GND")
	)
	(via
		(at 105.031032 -280.566368)
		(size 0.4064)
		(drill 0.2032)
		(layers "F.Cu" "B.Cu")
		(net "GND")
	)
	(via
		(at 95.331026 -222.61449)
		(size 0.4064)
		(drill 0.2032)
		(layers "F.Cu" "B.Cu")
		(net "GND")
	)
	(via
		(at 176.072038 -272.98523)
		(size 0.4826)
		(drill 0.254)
		(layers "F.Cu" "B.Cu")
		(net "GND")
	)
	(via
		(at 133.075934 -413.204152)
		(size 0.4572)
		(drill 0.254)
		(layers "F.Cu" "B.Cu")
		(net "GND")
	)
	(via
		(at 335.195418 -26.727658)
		(size 0.508)
		(drill 0.254)
		(layers "F.Cu" "B.Cu")
		(net "GND")
	)
	(via
		(at 315.576458 -416.020504)
		(size 0.4572)
		(drill 0.254)
		(layers "F.Cu" "B.Cu")
		(net "GND")
	)
	(via
		(at 32.695896 -272.135346)
		(size 0.4826)
		(drill 0.254)
		(layers "F.Cu" "B.Cu")
		(net "GND")
	)
	(via
		(at 126.34976 -433.899564)
		(size 0.4572)
		(drill 0.2032)
		(layers "F.Cu" "B.Cu")
		(net "GND")
	)
	(via
		(at 120.916446 -391.830814)
		(size 0.4064)
		(drill 0.2032)
		(layers "F.Cu" "B.Cu")
		(net "GND")
	)
	(via
		(at 346.561156 -225.044254)
		(size 0.4064)
		(drill 0.2032)
		(layers "F.Cu" "B.Cu")
		(net "GND")
	)
	(via
		(at 130.574796 -252.584458)
		(size 0.4064)
		(drill 0.2032)
		(layers "F.Cu" "B.Cu")
		(net "GND")
	)
	(via
		(at 288.180018 -289.135058)
		(size 0.4826)
		(drill 0.254)
		(layers "F.Cu" "B.Cu")
		(net "GND")
	)
	(via
		(at 384.624834 -250.154186)
		(size 0.4064)
		(drill 0.2032)
		(layers "F.Cu" "B.Cu")
		(net "GND")
	)
	(via
		(at 20.436078 -17.61236)
		(size 0.508)
		(drill 0.254)
		(layers "F.Cu" "B.Cu")
		(net "GND")
	)
	(via
		(at 233.016044 -45.593)
		(size 0.508)
		(drill 0.254)
		(layers "F.Cu" "B.Cu")
		(net "GND")
	)
	(via
		(at 134.164832 -285.426404)
		(size 0.4064)
		(drill 0.2032)
		(layers "F.Cu" "B.Cu")
		(net "GND")
	)
	(via
		(at 190.987426 -353.309174)
		(size 0.49022)
		(drill 0.254)
		(layers "F.Cu" "B.Cu")
		(net "GND")
	)
	(via
		(at 109.261148 -266.796266)
		(size 0.4064)
		(drill 0.2032)
		(layers "F.Cu" "B.Cu")
		(net "GND")
	)
	(via
		(at 386.349494 -431.451258)
		(size 0.4572)
		(drill 0.2032)
		(layers "F.Cu" "B.Cu")
		(net "GND")
	)
	(via
		(at 405.012906 -329.003152)
		(size 0.508)
		(drill 0.254)
		(layers "F.Cu" "B.Cu")
		(net "GND")
	)
	(via
		(at 320.616326 -400.212814)
		(size 0.4064)
		(drill 0.2032)
		(layers "F.Cu" "B.Cu")
		(net "GND")
	)
	(via
		(at 147.349718 -430.299622)
		(size 0.4572)
		(drill 0.2032)
		(layers "F.Cu" "B.Cu")
		(net "GND")
	)
	(via
		(at 31.578296 -211.360258)
		(size 0.4826)
		(drill 0.254)
		(layers "F.Cu" "B.Cu")
		(net "GND")
	)
	(via
		(at 94.00286 -177.160428)
		(size 0.508)
		(drill 0.254)
		(layers "F.Cu" "B.Cu")
		(net "GND")
	)
	(via
		(at 125.404626 -229.094538)
		(size 0.4064)
		(drill 0.2032)
		(layers "F.Cu" "B.Cu")
		(net "GND")
	)
	(via
		(at 149.349714 -428.851314)
		(size 0.4572)
		(drill 0.2032)
		(layers "F.Cu" "B.Cu")
		(net "GND")
	)
	(via
		(at 427.456092 -309.535068)
		(size 0.4826)
		(drill 0.254)
		(layers "F.Cu" "B.Cu")
		(net "GND")
	)
	(via
		(at 388.21487 -279.756108)
		(size 0.4064)
		(drill 0.2032)
		(layers "F.Cu" "B.Cu")
		(net "GND")
	)
	(via
		(at 51.884072 -291.685218)
		(size 0.4826)
		(drill 0.254)
		(layers "F.Cu" "B.Cu")
		(net "GND")
	)
	(via
		(at 86.701122 -279.756362)
		(size 0.4064)
		(drill 0.2032)
		(layers "F.Cu" "B.Cu")
		(net "GND")
	)
	(via
		(at 382.1049 -261.12597)
		(size 0.4064)
		(drill 0.2032)
		(layers "F.Cu" "B.Cu")
		(net "GND")
	)
	(via
		(at 292.280086 -233.884978)
		(size 0.4826)
		(drill 0.254)
		(layers "F.Cu" "B.Cu")
		(net "GND")
	)
	(via
		(at 80.249776 -426.69968)
		(size 0.4572)
		(drill 0.2032)
		(layers "F.Cu" "B.Cu")
		(net "GND")
	)
	(via
		(at 366.764824 -245.29415)
		(size 0.4064)
		(drill 0.2032)
		(layers "F.Cu" "B.Cu")
		(net "GND")
	)
	(via
		(at 364.884716 -243.674138)
		(size 0.4064)
		(drill 0.2032)
		(layers "F.Cu" "B.Cu")
		(net "GND")
	)
	(via
		(at 399.349722 -433.899564)
		(size 0.4572)
		(drill 0.2032)
		(layers "F.Cu" "B.Cu")
		(net "GND")
	)
	(via
		(at 47.054516 -428.46498)
		(size 0.508)
		(drill 0.254)
		(layers "F.Cu" "B.Cu")
		(net "GND")
	)
	(via
		(at 213.995 -332.74)
		(size 0.508)
		(drill 0.254)
		(layers "F.Cu" "B.Cu")
		(net "GND")
	)
	(via
		(at 204.8637 -211.7852)
		(size 0.4826)
		(drill 0.254)
		(layers "F.Cu" "B.Cu")
		(net "GND")
	)
	(via
		(at 4.194048 -135.42137)
		(size 0.508)
		(drill 0.254)
		(layers "F.Cu" "B.Cu")
		(net "GND")
	)
	(via
		(at 321.702938 -417.778184)
		(size 0.4572)
		(drill 0.254)
		(layers "F.Cu" "B.Cu")
		(net "GND")
	)
	(via
		(at 162.176714 -407.638504)
		(size 0.4572)
		(drill 0.254)
		(layers "F.Cu" "B.Cu")
		(net "GND")
	)
	(via
		(at 408.59456 -162.72764)
		(size 0.508)
		(drill 0.254)
		(layers "F.Cu" "B.Cu")
		(net "GND")
	)
	(via
		(at 64.05753 -36.65728)
		(size 0.508)
		(drill 0.254)
		(layers "F.Cu" "B.Cu")
		(net "GND")
	)
	(via
		(at 363.00791 -253.392178)
		(size 0.4064)
		(drill 0.2032)
		(layers "F.Cu" "B.Cu")
		(net "GND")
	)
	(via
		(at 117.971824 -23.647654)
		(size 0.508)
		(drill 0.254)
		(layers "F.Cu" "B.Cu")
		(net "GND")
	)
	(via
		(at 437.2356 -95.113348)
		(size 0.508)
		(drill 0.254)
		(layers "F.Cu" "B.Cu")
		(net "GND")
	)
	(via
		(at 102.427786 -338.000086)
		(size 0.49022)
		(drill 0.254)
		(layers "F.Cu" "B.Cu")
		(net "GND")
	)
	(via
		(at 92.981018 -236.384338)
		(size 0.4064)
		(drill 0.2032)
		(layers "F.Cu" "B.Cu")
		(net "GND")
	)
	(via
		(at 386.504942 -248.534174)
		(size 0.4064)
		(drill 0.2032)
		(layers "F.Cu" "B.Cu")
		(net "GND")
	)
	(via
		(at 88.390222 -384.617722)
		(size 0.4064)
		(drill 0.2032)
		(layers "F.Cu" "B.Cu")
		(net "GND")
	)
	(via
		(at 126.814834 -244.484398)
		(size 0.4064)
		(drill 0.2032)
		(layers "F.Cu" "B.Cu")
		(net "GND")
	)
	(via
		(at 116.326666 -173.073568)
		(size 0.49022)
		(drill 0.254)
		(layers "F.Cu" "B.Cu")
		(net "GND")
	)
	(via
		(at 40.23995 -267.885418)
		(size 0.4826)
		(drill 0.254)
		(layers "F.Cu" "B.Cu")
		(net "GND")
	)
	(via
		(at 345.8337 -17.085056)
		(size 0.508)
		(drill 0.254)
		(layers "F.Cu" "B.Cu")
		(net "GND")
	)
	(via
		(at 102.211124 -267.606272)
		(size 0.4064)
		(drill 0.2032)
		(layers "F.Cu" "B.Cu")
		(net "GND")
	)
	(via
		(at 344.981022 -291.095938)
		(size 0.4064)
		(drill 0.2032)
		(layers "F.Cu" "B.Cu")
		(net "GND")
	)
	(via
		(at 447.761868 -275.960078)
		(size 0.4826)
		(drill 0.254)
		(layers "F.Cu" "B.Cu")
		(net "GND")
	)
	(via
		(at 174.46117 -11.100054)
		(size 0.508)
		(drill 0.254)
		(layers "F.Cu" "B.Cu")
		(net "GND")
	)
	(via
		(at 107.329478 -388.77113)
		(size 0.508)
		(drill 0.254)
		(layers "F.Cu" "B.Cu")
		(net "GND")
	)
	(via
		(at 365.18469 -265.986006)
		(size 0.4064)
		(drill 0.2032)
		(layers "F.Cu" "B.Cu")
		(net "GND")
	)
	(via
		(at 436.384446 -303.585118)
		(size 0.4826)
		(drill 0.254)
		(layers "F.Cu" "B.Cu")
		(net "GND")
	)
	(via
		(at 86.871048 -250.15444)
		(size 0.4064)
		(drill 0.2032)
		(layers "F.Cu" "B.Cu")
		(net "GND")
	)
	(via
		(at 315.595 -363.23905)
		(size 0.508)
		(drill 0.254)
		(layers "F.Cu" "B.Cu")
		(net "GND")
	)
	(via
		(at 394.982954 -282.730194)
		(size 0.4064)
		(drill 0.2032)
		(layers "F.Cu" "B.Cu")
		(net "GND")
	)
	(via
		(at 416.468052 -235.585)
		(size 0.4826)
		(drill 0.254)
		(layers "F.Cu" "B.Cu")
		(net "GND")
	)
	(via
		(at 299.82414 -246.635016)
		(size 0.4826)
		(drill 0.254)
		(layers "F.Cu" "B.Cu")
		(net "GND")
	)
	(via
		(at 49.276 -434.939948)
		(size 0.508)
		(drill 0.254)
		(layers "F.Cu" "B.Cu")
		(net "GND")
	)
	(via
		(at 412.367984 -216.035128)
		(size 0.4826)
		(drill 0.254)
		(layers "F.Cu" "B.Cu")
		(net "GND")
	)
	(via
		(at 93.769434 -144.74952)
		(size 0.508)
		(drill 0.254)
		(layers "F.Cu" "B.Cu")
		(net "GND")
	)
	(via
		(at 2.76225 -132.517134)
		(size 0.508)
		(drill 0.254)
		(layers "F.Cu" "B.Cu")
		(net "GND")
	)
	(via
		(at 110.671102 -295.146222)
		(size 0.4064)
		(drill 0.2032)
		(layers "F.Cu" "B.Cu")
		(net "GND")
	)
	(via
		(at 385.129278 -142.234158)
		(size 0.508)
		(drill 0.254)
		(layers "F.Cu" "B.Cu")
		(net "GND")
	)
	(via
		(at 111.641636 -369.69573)
		(size 0.508)
		(drill 0.254)
		(layers "F.Cu" "B.Cu")
		(net "GND")
	)
	(via
		(at 298.43984 -293.384986)
		(size 0.4826)
		(drill 0.254)
		(layers "F.Cu" "B.Cu")
		(net "GND")
	)
	(via
		(at 155.349702 -436.347362)
		(size 0.4572)
		(drill 0.2032)
		(layers "F.Cu" "B.Cu")
		(net "GND")
	)
	(via
		(at 347.97111 -225.85426)
		(size 0.4064)
		(drill 0.2032)
		(layers "F.Cu" "B.Cu")
		(net "GND")
	)
	(via
		(at 102.681024 -286.23641)
		(size 0.4064)
		(drill 0.2032)
		(layers "F.Cu" "B.Cu")
		(net "GND")
	)
	(via
		(at 134.349744 -431.451258)
		(size 0.4572)
		(drill 0.2032)
		(layers "F.Cu" "B.Cu")
		(net "GND")
	)
	(via
		(at 126.34976 -432.747166)
		(size 0.4572)
		(drill 0.2032)
		(layers "F.Cu" "B.Cu")
		(net "GND")
	)
	(via
		(at 17.608042 -255.13538)
		(size 0.4826)
		(drill 0.254)
		(layers "F.Cu" "B.Cu")
		(net "GND")
	)
	(via
		(at 349.18396 -412.84652)
		(size 0.4064)
		(drill 0.2032)
		(layers "F.Cu" "B.Cu")
		(net "GND")
	)
	(via
		(at 428.840392 -287.435036)
		(size 0.4826)
		(drill 0.254)
		(layers "F.Cu" "B.Cu")
		(net "GND")
	)
	(via
		(at 265.54811 -250.884944)
		(size 0.4826)
		(drill 0.254)
		(layers "F.Cu" "B.Cu")
		(net "GND")
	)
	(via
		(at 413.946086 -396.710662)
		(size 0.4064)
		(drill 0.2032)
		(layers "F.Cu" "B.Cu")
		(net "GND")
	)
	(via
		(at 44.340018 -196.485256)
		(size 0.4826)
		(drill 0.254)
		(layers "F.Cu" "B.Cu")
		(net "GND")
	)
	(via
		(at 59.428126 -316.33541)
		(size 0.4826)
		(drill 0.254)
		(layers "F.Cu" "B.Cu")
		(net "GND")
	)
	(via
		(at 23.715218 -19.771106)
		(size 0.508)
		(drill 0.254)
		(layers "F.Cu" "B.Cu")
		(net "GND")
	)
	(via
		(at 80.931004 -404.46452)
		(size 0.4064)
		(drill 0.2032)
		(layers "F.Cu" "B.Cu")
		(net "GND")
	)
	(via
		(at 39.12235 -304.860452)
		(size 0.4826)
		(drill 0.254)
		(layers "F.Cu" "B.Cu")
		(net "GND")
	)
	(via
		(at 114.560096 -373.96293)
		(size 0.508)
		(drill 0.254)
		(layers "F.Cu" "B.Cu")
		(net "GND")
	)
	(via
		(at 136.98474 -282.18638)
		(size 0.4064)
		(drill 0.2032)
		(layers "F.Cu" "B.Cu")
		(net "GND")
	)
	(via
		(at 364.53064 -385.87426)
		(size 0.508)
		(drill 0.254)
		(layers "F.Cu" "B.Cu")
		(net "GND")
	)
	(via
		(at 307.39461 -345.566238)
		(size 0.49022)
		(drill 0.254)
		(layers "F.Cu" "B.Cu")
		(net "GND")
	)
	(via
		(at 228.092 -285.991808)
		(size 0.508)
		(drill 0.254)
		(layers "F.Cu" "B.Cu")
		(net "GND")
	)
	(via
		(at 78.41107 -242.05438)
		(size 0.4064)
		(drill 0.2032)
		(layers "F.Cu" "B.Cu")
		(net "GND")
	)
	(via
		(at 111.165894 -384.66268)
		(size 0.508)
		(drill 0.254)
		(layers "F.Cu" "B.Cu")
		(net "GND")
	)
	(via
		(at 86.401148 -252.584458)
		(size 0.4064)
		(drill 0.2032)
		(layers "F.Cu" "B.Cu")
		(net "GND")
	)
	(via
		(at 121.653046 -16.50365)
		(size 0.508)
		(drill 0.254)
		(layers "F.Cu" "B.Cu")
		(net "GND")
	)
	(via
		(at 170.594274 -429.459644)
		(size 0.508)
		(drill 0.254)
		(layers "F.Cu" "B.Cu")
		(net "GND")
	)
	(via
		(at 370.524786 -224.234248)
		(size 0.4064)
		(drill 0.2032)
		(layers "F.Cu" "B.Cu")
		(net "GND")
	)
	(via
		(at 128.116584 -391.830814)
		(size 0.4064)
		(drill 0.2032)
		(layers "F.Cu" "B.Cu")
		(net "GND")
	)
	(via
		(at 174.687738 -209.235294)
		(size 0.4826)
		(drill 0.254)
		(layers "F.Cu" "B.Cu")
		(net "GND")
	)
	(via
		(at 417.692078 -164.65931)
		(size 0.49022)
		(drill 0.254)
		(layers "F.Cu" "B.Cu")
		(net "GND")
	)
	(via
		(at 112.808512 -406.4508)
		(size 0.508)
		(drill 0.254)
		(layers "F.Cu" "B.Cu")
		(net "GND")
	)
	(via
		(at 428.573692 -304.860198)
		(size 0.4826)
		(drill 0.254)
		(layers "F.Cu" "B.Cu")
		(net "GND")
	)
	(via
		(at 305.983894 -314.635134)
		(size 0.4826)
		(drill 0.254)
		(layers "F.Cu" "B.Cu")
		(net "GND")
	)
	(via
		(at 114.894614 -270.03629)
		(size 0.4064)
		(drill 0.2032)
		(layers "F.Cu" "B.Cu")
		(net "GND")
	)
	(via
		(at 164.99459 -7.441692)
		(size 0.508)
		(drill 0.254)
		(layers "F.Cu" "B.Cu")
		(net "GND")
	)
	(via
		(at 339.876384 -376.75693)
		(size 0.508)
		(drill 0.254)
		(layers "F.Cu" "B.Cu")
		(net "GND")
	)
	(via
		(at 32.605218 -52.639214)
		(size 0.508)
		(drill 0.254)
		(layers "F.Cu" "B.Cu")
		(net "GND")
	)
	(via
		(at 65.81648 -393.902438)
		(size 0.4572)
		(drill 0.254)
		(layers "F.Cu" "B.Cu")
		(net "GND")
	)
	(via
		(at 94.744286 -391.830814)
		(size 0.4064)
		(drill 0.2032)
		(layers "F.Cu" "B.Cu")
		(net "GND")
	)
	(via
		(at 177.201068 -186.283854)
		(size 0.4826)
		(drill 0.254)
		(layers "F.Cu" "B.Cu")
		(net "GND")
	)
	(via
		(at 297.108372 -303.585118)
		(size 0.4826)
		(drill 0.254)
		(layers "F.Cu" "B.Cu")
		(net "GND")
	)
	(via
		(at 81.701132 -238.00435)
		(size 0.4064)
		(drill 0.2032)
		(layers "F.Cu" "B.Cu")
		(net "GND")
	)
	(via
		(at 349.851218 -250.154186)
		(size 0.4064)
		(drill 0.2032)
		(layers "F.Cu" "B.Cu")
		(net "GND")
	)
	(via
		(at 101.91115 -224.234502)
		(size 0.4064)
		(drill 0.2032)
		(layers "F.Cu" "B.Cu")
		(net "GND")
	)
	(via
		(at 390.094724 -263.555988)
		(size 0.4064)
		(drill 0.2032)
		(layers "F.Cu" "B.Cu")
		(net "GND")
	)
	(via
		(at 338.101178 -236.384084)
		(size 0.4064)
		(drill 0.2032)
		(layers "F.Cu" "B.Cu")
		(net "GND")
	)
	(via
		(at 77.632814 -388.29615)
		(size 0.4064)
		(drill 0.2032)
		(layers "F.Cu" "B.Cu")
		(net "GND")
	)
	(via
		(at 336.249518 -429.147224)
		(size 0.4572)
		(drill 0.2032)
		(layers "F.Cu" "B.Cu")
		(net "GND")
	)
	(via
		(at 341.22106 -286.236156)
		(size 0.4064)
		(drill 0.2032)
		(layers "F.Cu" "B.Cu")
		(net "GND")
	)
	(via
		(at 50.499772 -277.235412)
		(size 0.4826)
		(drill 0.254)
		(layers "F.Cu" "B.Cu")
		(net "GND")
	)
	(via
		(at 427.456092 -292.535102)
		(size 0.4826)
		(drill 0.254)
		(layers "F.Cu" "B.Cu")
		(net "GND")
	)
	(via
		(at 131.271518 -403.830536)
		(size 0.4572)
		(drill 0.254)
		(layers "F.Cu" "B.Cu")
		(net "GND")
	)
	(via
		(at 283.958284 -372.86057)
		(size 0.4572)
		(drill 0.254)
		(layers "F.Cu" "B.Cu")
		(net "GND")
	)
	(via
		(at 20.32381 -211.7852)
		(size 0.4826)
		(drill 0.254)
		(layers "F.Cu" "B.Cu")
		(net "GND")
	)
	(via
		(at 344.681048 -229.904036)
		(size 0.4064)
		(drill 0.2032)
		(layers "F.Cu" "B.Cu")
		(net "GND")
	)
	(via
		(at 83.41106 -261.126224)
		(size 0.4064)
		(drill 0.2032)
		(layers "F.Cu" "B.Cu")
		(net "GND")
	)
	(via
		(at 459.116684 -15.098522)
		(size 0.508)
		(drill 0.254)
		(layers "F.Cu" "B.Cu")
		(net "GND")
	)
	(via
		(at 34.080196 -294.235378)
		(size 0.4826)
		(drill 0.254)
		(layers "F.Cu" "B.Cu")
		(net "GND")
	)
	(via
		(at 330.618592 -389.7122)
		(size 0.508)
		(drill 0.254)
		(layers "F.Cu" "B.Cu")
		(net "GND")
	)
	(via
		(at 48.321468 -420.78529)
		(size 0.508)
		(drill 0.254)
		(layers "F.Cu" "B.Cu")
		(net "GND")
	)
	(via
		(at 393.084812 -245.29415)
		(size 0.4064)
		(drill 0.2032)
		(layers "F.Cu" "B.Cu")
		(net "GND")
	)
	(via
		(at 152.190704 -369.69573)
		(size 0.508)
		(drill 0.254)
		(layers "F.Cu" "B.Cu")
		(net "GND")
	)
	(via
		(at 185.027316 -429.384714)
		(size 0.508)
		(drill 0.254)
		(layers "F.Cu" "B.Cu")
		(net "GND")
	)
	(via
		(at 397.992854 -416.020504)
		(size 0.4572)
		(drill 0.254)
		(layers "F.Cu" "B.Cu")
		(net "GND")
	)
	(via
		(at 121.944638 -287.046162)
		(size 0.4064)
		(drill 0.2032)
		(layers "F.Cu" "B.Cu")
		(net "GND")
	)
	(via
		(at 349.704152 -338.784438)
		(size 0.49022)
		(drill 0.254)
		(layers "F.Cu" "B.Cu")
		(net "GND")
	)
	(via
		(at 27.959558 -344.781886)
		(size 0.49022)
		(drill 0.254)
		(layers "F.Cu" "B.Cu")
		(net "GND")
	)
	(via
		(at 202.147932 -206.685388)
		(size 0.4826)
		(drill 0.254)
		(layers "F.Cu" "B.Cu")
		(net "GND")
	)
	(via
		(at 372.747032 -379.22073)
		(size 0.508)
		(drill 0.254)
		(layers "F.Cu" "B.Cu")
		(net "GND")
	)
	(via
		(at 340.281006 -268.416024)
		(size 0.4064)
		(drill 0.2032)
		(layers "F.Cu" "B.Cu")
		(net "GND")
	)
	(via
		(at 2.76225 -244.277134)
		(size 0.508)
		(drill 0.254)
		(layers "F.Cu" "B.Cu")
		(net "GND")
	)
	(via
		(at 24.214582 -4.32943)
		(size 0.508)
		(drill 0.254)
		(layers "F.Cu" "B.Cu")
		(net "GND")
	)
	(via
		(at 379.924818 -225.85426)
		(size 0.4064)
		(drill 0.2032)
		(layers "F.Cu" "B.Cu")
		(net "GND")
	)
	(via
		(at 337.631024 -225.85426)
		(size 0.4064)
		(drill 0.2032)
		(layers "F.Cu" "B.Cu")
		(net "GND")
	)
	(via
		(at 298.70654 -304.01006)
		(size 0.4826)
		(drill 0.254)
		(layers "F.Cu" "B.Cu")
		(net "GND")
	)
	(via
		(at 462.120996 -104.249728)
		(size 0.508)
		(drill 0.254)
		(layers "F.Cu" "B.Cu")
		(net "GND")
	)
	(via
		(at 431.038 -17.613122)
		(size 0.508)
		(drill 0.254)
		(layers "F.Cu" "B.Cu")
		(net "GND")
	)
	(via
		(at 105.189528 -348.547436)
		(size 0.508)
		(drill 0.254)
		(layers "F.Cu" "B.Cu")
		(net "GND")
	)
	(via
		(at 340.482682 -307.087524)
		(size 0.508)
		(drill 0.254)
		(layers "F.Cu" "B.Cu")
		(net "GND")
	)
	(via
		(at 106.694478 -388.77113)
		(size 0.508)
		(drill 0.254)
		(layers "F.Cu" "B.Cu")
		(net "GND")
	)
	(via
		(at 142.154656 -268.416278)
		(size 0.4064)
		(drill 0.2032)
		(layers "F.Cu" "B.Cu")
		(net "GND")
	)
	(via
		(at 444.490856 -396.884398)
		(size 0.49022)
		(drill 0.254)
		(layers "F.Cu" "B.Cu")
		(net "GND")
	)
	(via
		(at 138.349736 -426.69968)
		(size 0.4572)
		(drill 0.2032)
		(layers "F.Cu" "B.Cu")
		(net "GND")
	)
	(via
		(at 453.032368 -193.99631)
		(size 0.4826)
		(drill 0.254)
		(layers "F.Cu" "B.Cu")
		(net "GND")
	)
	(via
		(at 47.664624 -18.5039)
		(size 0.508)
		(drill 0.254)
		(layers "F.Cu" "B.Cu")
		(net "GND")
	)
	(via
		(at 402.619718 -172.498512)
		(size 0.508)
		(drill 0.254)
		(layers "F.Cu" "B.Cu")
		(net "GND")
	)
	(via
		(at 191.160146 -241.535204)
		(size 0.4826)
		(drill 0.254)
		(layers "F.Cu" "B.Cu")
		(net "GND")
	)
	(via
		(at 63.118492 -388.328662)
		(size 0.4064)
		(drill 0.2032)
		(layers "F.Cu" "B.Cu")
		(net "GND")
	)
	(via
		(at 382.1049 -262.745982)
		(size 0.4064)
		(drill 0.2032)
		(layers "F.Cu" "B.Cu")
		(net "GND")
	)
	(via
		(at 121.367296 -373.96293)
		(size 0.508)
		(drill 0.254)
		(layers "F.Cu" "B.Cu")
		(net "GND")
	)
	(via
		(at 136.684766 -255.014476)
		(size 0.4064)
		(drill 0.2032)
		(layers "F.Cu" "B.Cu")
		(net "GND")
	)
	(via
		(at 55.328058 -311.235344)
		(size 0.4826)
		(drill 0.254)
		(layers "F.Cu" "B.Cu")
		(net "GND")
	)
	(via
		(at 76.972922 -20.161504)
		(size 0.508)
		(drill 0.254)
		(layers "F.Cu" "B.Cu")
		(net "GND")
	)
	(via
		(at 157.781244 -371.49913)
		(size 0.508)
		(drill 0.254)
		(layers "F.Cu" "B.Cu")
		(net "GND")
	)
	(via
		(at 443.6618 -220.709998)
		(size 0.4826)
		(drill 0.254)
		(layers "F.Cu" "B.Cu")
		(net "GND")
	)
	(via
		(at 66.288666 -170.078654)
		(size 0.49022)
		(drill 0.254)
		(layers "F.Cu" "B.Cu")
		(net "GND")
	)
	(via
		(at 23.622 -365.76)
		(size 0.508)
		(drill 0.254)
		(layers "F.Cu" "B.Cu")
		(net "GND")
	)
	(via
		(at 71.088758 -333.060802)
		(size 0.49022)
		(drill 0.254)
		(layers "F.Cu" "B.Cu")
		(net "GND")
	)
	(via
		(at 13.864336 -2.11709)
		(size 0.508)
		(drill 0.254)
		(layers "F.Cu" "B.Cu")
		(net "GND")
	)
	(via
		(at 389.07593 -412.212536)
		(size 0.4572)
		(drill 0.254)
		(layers "F.Cu" "B.Cu")
		(net "GND")
	)
	(via
		(at 109.191044 -377.00712)
		(size 0.508)
		(drill 0.254)
		(layers "F.Cu" "B.Cu")
		(net "GND")
	)
	(via
		(at 456.931522 -53.097176)
		(size 0.508)
		(drill 0.254)
		(layers "F.Cu" "B.Cu")
		(net "GND")
	)
	(via
		(at 445.282066 -407.1747)
		(size 0.508)
		(drill 0.254)
		(layers "F.Cu" "B.Cu")
		(net "GND")
	)
	(via
		(at 153.018998 -390.160002)
		(size 0.4064)
		(drill 0.2032)
		(layers "F.Cu" "B.Cu")
		(net "GND")
	)
	(via
		(at 126.588266 -404.46452)
		(size 0.4064)
		(drill 0.2032)
		(layers "F.Cu" "B.Cu")
		(net "GND")
	)
	(via
		(at 358.05364 -411.442662)
		(size 0.508)
		(drill 0.254)
		(layers "F.Cu" "B.Cu")
		(net "GND")
	)
	(via
		(at 82.292698 -331.088238)
		(size 0.508)
		(drill 0.254)
		(layers "F.Cu" "B.Cu")
		(net "GND")
	)
	(via
		(at 178.289458 -55.79999)
		(size 0.508)
		(drill 0.254)
		(layers "F.Cu" "B.Cu")
		(net "GND")
	)
	(via
		(at 215.678004 -134.655052)
		(size 0.508)
		(drill 0.254)
		(layers "F.Cu" "B.Cu")
		(net "GND")
	)
	(via
		(at 16.581374 -388.493254)
		(size 0.49022)
		(drill 0.254)
		(layers "F.Cu" "B.Cu")
		(net "GND")
	)
	(via
		(at 34.080196 -212.635338)
		(size 0.4826)
		(drill 0.254)
		(layers "F.Cu" "B.Cu")
		(net "GND")
	)
	(via
		(at 107.647994 -256.3876)
		(size 0.4826)
		(drill 0.254)
		(layers "F.Cu" "B.Cu")
		(net "GND")
	)
	(via
		(at 424.012106 -241.53495)
		(size 0.4826)
		(drill 0.254)
		(layers "F.Cu" "B.Cu")
		(net "GND")
	)
	(via
		(at 138.864848 -290.286186)
		(size 0.4064)
		(drill 0.2032)
		(layers "F.Cu" "B.Cu")
		(net "GND")
	)
	(via
		(at 407.448258 -9.424924)
		(size 0.508)
		(drill 0.254)
		(layers "F.Cu" "B.Cu")
		(net "GND")
	)
	(via
		(at 389.683752 -394.831062)
		(size 0.4064)
		(drill 0.2032)
		(layers "F.Cu" "B.Cu")
		(net "GND")
	)
	(via
		(at 315.369956 -376.75693)
		(size 0.508)
		(drill 0.254)
		(layers "F.Cu" "B.Cu")
		(net "GND")
	)
	(via
		(at 36.795964 -318.035432)
		(size 0.4826)
		(drill 0.254)
		(layers "F.Cu" "B.Cu")
		(net "GND")
	)
	(via
		(at 308.321964 -115.665504)
		(size 0.508)
		(drill 0.254)
		(layers "F.Cu" "B.Cu")
		(net "GND")
	)
	(via
		(at 331.821028 -287.856168)
		(size 0.4064)
		(drill 0.2032)
		(layers "F.Cu" "B.Cu")
		(net "GND")
	)
	(via
		(at 97.511108 -288.666174)
		(size 0.4064)
		(drill 0.2032)
		(layers "F.Cu" "B.Cu")
		(net "GND")
	)
	(via
		(at 22.58187 -384.51409)
		(size 0.508)
		(drill 0.254)
		(layers "F.Cu" "B.Cu")
		(net "GND")
	)
	(via
		(at 404.119334 -419.046152)
		(size 0.4572)
		(drill 0.254)
		(layers "F.Cu" "B.Cu")
		(net "GND")
	)
	(via
		(at 341.691214 -278.946102)
		(size 0.4064)
		(drill 0.2032)
		(layers "F.Cu" "B.Cu")
		(net "GND")
	)
	(via
		(at 361.380278 -184.428638)
		(size 0.508)
		(drill 0.254)
		(layers "F.Cu" "B.Cu")
		(net "GND")
	)
	(via
		(at 44.545758 -346.322142)
		(size 0.49022)
		(drill 0.254)
		(layers "F.Cu" "B.Cu")
		(net "GND")
	)
	(via
		(at 21.70811 -263.635236)
		(size 0.4826)
		(drill 0.254)
		(layers "F.Cu" "B.Cu")
		(net "GND")
	)
	(via
		(at 99.561142 -255.824482)
		(size 0.4064)
		(drill 0.2032)
		(layers "F.Cu" "B.Cu")
		(net "GND")
	)
	(via
		(at 130.104642 -245.294404)
		(size 0.4064)
		(drill 0.2032)
		(layers "F.Cu" "B.Cu")
		(net "GND")
	)
	(via
		(at 96.133158 -333.090012)
		(size 0.49022)
		(drill 0.254)
		(layers "F.Cu" "B.Cu")
		(net "GND")
	)
	(via
		(at 424.012106 -205.834996)
		(size 0.4826)
		(drill 0.254)
		(layers "F.Cu" "B.Cu")
		(net "GND")
	)
	(via
		(at 133.277356 -368.37493)
		(size 0.508)
		(drill 0.254)
		(layers "F.Cu" "B.Cu")
		(net "GND")
	)
	(via
		(at 426.499782 -343.26068)
		(size 0.508)
		(drill 0.254)
		(layers "F.Cu" "B.Cu")
		(net "GND")
	)
	(via
		(at 378.081794 -412.212536)
		(size 0.4572)
		(drill 0.254)
		(layers "F.Cu" "B.Cu")
		(net "GND")
	)
	(via
		(at 78.711044 -265.98626)
		(size 0.4064)
		(drill 0.2032)
		(layers "F.Cu" "B.Cu")
		(net "GND")
	)
	(via
		(at 384.87858 -394.831062)
		(size 0.4064)
		(drill 0.2032)
		(layers "F.Cu" "B.Cu")
		(net "GND")
	)
	(via
		(at 341.390986 -255.014222)
		(size 0.4064)
		(drill 0.2032)
		(layers "F.Cu" "B.Cu")
		(net "GND")
	)
	(via
		(at 326.45477 -340.129876)
		(size 0.508)
		(drill 0.254)
		(layers "F.Cu" "B.Cu")
		(net "GND")
	)
	(via
		(at 419.144958 -342.536018)
		(size 0.508)
		(drill 0.254)
		(layers "F.Cu" "B.Cu")
		(net "GND")
	)
	(via
		(at 119.82196 -351.04578)
		(size 0.6604)
		(drill 0.3302)
		(layers "F.Cu" "B.Cu")
		(net "GND")
	)
	(via
		(at 71.277734 -381.020828)
		(size 0.508)
		(drill 0.254)
		(layers "F.Cu" "B.Cu")
		(net "GND")
	)
	(via
		(at 134.164832 -261.126224)
		(size 0.4064)
		(drill 0.2032)
		(layers "F.Cu" "B.Cu")
		(net "GND")
	)
	(via
		(at 342.249506 -434.899562)
		(size 0.4572)
		(drill 0.2032)
		(layers "F.Cu" "B.Cu")
		(net "GND")
	)
	(via
		(at 413.2961 -380.54153)
		(size 0.508)
		(drill 0.254)
		(layers "F.Cu" "B.Cu")
		(net "GND")
	)
	(via
		(at 83.111086 -232.334308)
		(size 0.4064)
		(drill 0.2032)
		(layers "F.Cu" "B.Cu")
		(net "GND")
	)
	(via
		(at 317.4111 -328.097134)
		(size 0.508)
		(drill 0.254)
		(layers "F.Cu" "B.Cu")
		(net "GND")
	)
	(via
		(at 392.70559 -193.781426)
		(size 0.508)
		(drill 0.254)
		(layers "F.Cu" "B.Cu")
		(net "GND")
	)
	(via
		(at 8.932418 -409.072334)
		(size 0.508)
		(drill 0.254)
		(layers "F.Cu" "B.Cu")
		(net "GND")
	)
	(via
		(at 432.67376 -229.210108)
		(size 0.4826)
		(drill 0.254)
		(layers "F.Cu" "B.Cu")
		(net "GND")
	)
	(via
		(at 382.1049 -287.046162)
		(size 0.4064)
		(drill 0.2032)
		(layers "F.Cu" "B.Cu")
		(net "GND")
	)
	(via
		(at 171.336208 -343.404952)
		(size 0.508)
		(drill 0.254)
		(layers "F.Cu" "B.Cu")
		(net "GND")
	)
	(via
		(at 292.280086 -278.93518)
		(size 0.4826)
		(drill 0.254)
		(layers "F.Cu" "B.Cu")
		(net "GND")
	)
	(via
		(at 451.099936 -64.459866)
		(size 0.508)
		(drill 0.254)
		(layers "F.Cu" "B.Cu")
		(net "GND")
	)
	(via
		(at 110.671102 -280.566368)
		(size 0.4064)
		(drill 0.2032)
		(layers "F.Cu" "B.Cu")
		(net "GND")
	)
	(via
		(at 49.168304 -312.935366)
		(size 0.4826)
		(drill 0.254)
		(layers "F.Cu" "B.Cu")
		(net "GND")
	)
	(via
		(at 179.516024 -249.18543)
		(size 0.4826)
		(drill 0.254)
		(layers "F.Cu" "B.Cu")
		(net "GND")
	)
	(via
		(at 346.09532 -362.01096)
		(size 0.508)
		(drill 0.254)
		(layers "F.Cu" "B.Cu")
		(net "GND")
	)
	(via
		(at 382.5748 -268.416024)
		(size 0.4064)
		(drill 0.2032)
		(layers "F.Cu" "B.Cu")
		(net "GND")
	)
	(via
		(at 136.34974 -431.29962)
		(size 0.4572)
		(drill 0.2032)
		(layers "F.Cu" "B.Cu")
		(net "GND")
	)
	(via
		(at 61.381132 -406.370536)
		(size 0.4572)
		(drill 0.254)
		(layers "F.Cu" "B.Cu")
		(net "GND")
	)
	(via
		(at 320.090546 -12.542266)
		(size 0.508)
		(drill 0.254)
		(layers "F.Cu" "B.Cu")
		(net "GND")
	)
	(via
		(at 203.532232 -221.985332)
		(size 0.4826)
		(drill 0.254)
		(layers "F.Cu" "B.Cu")
		(net "GND")
	)
	(via
		(at 137.45464 -276.516338)
		(size 0.4064)
		(drill 0.2032)
		(layers "F.Cu" "B.Cu")
		(net "GND")
	)
	(via
		(at 184.897776 -22.598888)
		(size 0.508)
		(drill 0.254)
		(layers "F.Cu" "B.Cu")
		(net "GND")
	)
	(via
		(at 114.405156 -23.465536)
		(size 0.508)
		(drill 0.254)
		(layers "F.Cu" "B.Cu")
		(net "GND")
	)
	(via
		(at 323.249544 -437.49976)
		(size 0.4572)
		(drill 0.2032)
		(layers "F.Cu" "B.Cu")
		(net "GND")
	)
	(via
		(at 376.93473 -287.856168)
		(size 0.4064)
		(drill 0.2032)
		(layers "F.Cu" "B.Cu")
		(net "GND")
	)
	(via
		(at 356.261162 -286.236156)
		(size 0.4064)
		(drill 0.2032)
		(layers "F.Cu" "B.Cu")
		(net "GND")
	)
	(via
		(at 331.351128 -285.42615)
		(size 0.4064)
		(drill 0.2032)
		(layers "F.Cu" "B.Cu")
		(net "GND")
	)
	(via
		(at 430.008792 -349.990156)
		(size 0.49022)
		(drill 0.254)
		(layers "F.Cu" "B.Cu")
		(net "GND")
	)
	(via
		(at 405.34971 -427.699678)
		(size 0.4572)
		(drill 0.2032)
		(layers "F.Cu" "B.Cu")
		(net "GND")
	)
	(via
		(at 71.138288 -390.337802)
		(size 0.508)
		(drill 0.254)
		(layers "F.Cu" "B.Cu")
		(net "GND")
	)
	(via
		(at 393.67079 -414.752536)
		(size 0.4572)
		(drill 0.254)
		(layers "F.Cu" "B.Cu")
		(net "GND")
	)
	(via
		(at 400.16938 -378.07773)
		(size 0.508)
		(drill 0.254)
		(layers "F.Cu" "B.Cu")
		(net "GND")
	)
	(via
		(at 73.546462 -30.938724)
		(size 0.508)
		(drill 0.254)
		(layers "F.Cu" "B.Cu")
		(net "GND")
	)
	(via
		(at 71.897748 -178.048666)
		(size 0.49022)
		(drill 0.254)
		(layers "F.Cu" "B.Cu")
		(net "GND")
	)
	(via
		(at 356.222808 -163.27755)
		(size 0.508)
		(drill 0.254)
		(layers "F.Cu" "B.Cu")
		(net "GND")
	)
	(via
		(at 471.037666 -72.761094)
		(size 0.508)
		(drill 0.254)
		(layers "F.Cu" "B.Cu")
		(net "GND")
	)
	(via
		(at 47.784004 -281.48534)
		(size 0.4826)
		(drill 0.254)
		(layers "F.Cu" "B.Cu")
		(net "GND")
	)
	(via
		(at 72.344534 -333.064866)
		(size 0.49022)
		(drill 0.254)
		(layers "F.Cu" "B.Cu")
		(net "GND")
	)
	(via
		(at 416.468052 -297.635168)
		(size 0.4826)
		(drill 0.254)
		(layers "F.Cu" "B.Cu")
		(net "GND")
	)
	(via
		(at 291.132006 -348.704662)
		(size 0.49022)
		(drill 0.254)
		(layers "F.Cu" "B.Cu")
		(net "GND")
	)
	(via
		(at 341.390986 -240.434114)
		(size 0.4064)
		(drill 0.2032)
		(layers "F.Cu" "B.Cu")
		(net "GND")
	)
	(via
		(at 119.71655 -393.927838)
		(size 0.4572)
		(drill 0.254)
		(layers "F.Cu" "B.Cu")
		(net "GND")
	)
	(via
		(at 91.740736 -403.830536)
		(size 0.4572)
		(drill 0.254)
		(layers "F.Cu" "B.Cu")
		(net "GND")
	)
	(via
		(at 70.617334 -380.535688)
		(size 0.508)
		(drill 0.254)
		(layers "F.Cu" "B.Cu")
		(net "GND")
	)
	(via
		(at 281.791664 -192.21831)
		(size 0.4826)
		(drill 0.254)
		(layers "F.Cu" "B.Cu")
		(net "GND")
	)
	(via
		(at 147.042886 -279.490424)
		(size 0.4064)
		(drill 0.2032)
		(layers "F.Cu" "B.Cu")
		(net "GND")
	)
	(via
		(at 331.521054 -239.624108)
		(size 0.4064)
		(drill 0.2032)
		(layers "F.Cu" "B.Cu")
		(net "GND")
	)
	(via
		(at 143.56461 -277.326344)
		(size 0.4064)
		(drill 0.2032)
		(layers "F.Cu" "B.Cu")
		(net "GND")
	)
	(via
		(at 123.824746 -291.906198)
		(size 0.4064)
		(drill 0.2032)
		(layers "F.Cu" "B.Cu")
		(net "GND")
	)
	(via
		(at 63.416434 -391.830814)
		(size 0.4064)
		(drill 0.2032)
		(layers "F.Cu" "B.Cu")
		(net "GND")
	)
	(via
		(at 319.118234 -396.710662)
		(size 0.4064)
		(drill 0.2032)
		(layers "F.Cu" "B.Cu")
		(net "GND")
	)
	(via
		(at 392.349482 -427.699678)
		(size 0.4572)
		(drill 0.2032)
		(layers "F.Cu" "B.Cu")
		(net "GND")
	)
	(via
		(at 100.031042 -253.394464)
		(size 0.4064)
		(drill 0.2032)
		(layers "F.Cu" "B.Cu")
		(net "GND")
	)
	(via
		(at 405.844248 -402.309838)
		(size 0.4572)
		(drill 0.254)
		(layers "F.Cu" "B.Cu")
		(net "GND")
	)
	(via
		(at 329.249532 -430.147222)
		(size 0.4572)
		(drill 0.2032)
		(layers "F.Cu" "B.Cu")
		(net "GND")
	)
	(via
		(at 410.29001 -392.999722)
		(size 0.4064)
		(drill 0.2032)
		(layers "F.Cu" "B.Cu")
		(net "GND")
	)
	(via
		(at 350.803718 -412.212536)
		(size 0.4572)
		(drill 0.254)
		(layers "F.Cu" "B.Cu")
		(net "GND")
	)
	(via
		(at 49.5681 -437.642)
		(size 0.508)
		(drill 0.254)
		(layers "F.Cu" "B.Cu")
		(net "GND")
	)
	(via
		(at 362.834682 -281.37612)
		(size 0.4064)
		(drill 0.2032)
		(layers "F.Cu" "B.Cu")
		(net "GND")
	)
	(via
		(at 387.716522 -402.309838)
		(size 0.4572)
		(drill 0.254)
		(layers "F.Cu" "B.Cu")
		(net "GND")
	)
	(via
		(at 378.344938 -262.745982)
		(size 0.4064)
		(drill 0.2032)
		(layers "F.Cu" "B.Cu")
		(net "GND")
	)
	(via
		(at 455.43978 -6.350254)
		(size 0.508)
		(drill 0.254)
		(layers "F.Cu" "B.Cu")
		(net "GND")
	)
	(via
		(at 164.427916 -266.185396)
		(size 0.4826)
		(drill 0.254)
		(layers "F.Cu" "B.Cu")
		(net "GND")
	)
	(via
		(at 183.616092 -261.935214)
		(size 0.4826)
		(drill 0.254)
		(layers "F.Cu" "B.Cu")
		(net "GND")
	)
	(via
		(at 230.275638 -159.620204)
		(size 0.508)
		(drill 0.254)
		(layers "F.Cu" "B.Cu")
		(net "GND")
	)
	(via
		(at 352.505518 -172.07992)
		(size 0.508)
		(drill 0.254)
		(layers "F.Cu" "B.Cu")
		(net "GND")
	)
	(via
		(at 335.760314 -414.752536)
		(size 0.4572)
		(drill 0.254)
		(layers "F.Cu" "B.Cu")
		(net "GND")
	)
	(via
		(at 347.307154 -441.227718)
		(size 0.508)
		(drill 0.254)
		(layers "F.Cu" "B.Cu")
		(net "GND")
	)
	(via
		(at 2.76225 -104.577134)
		(size 0.508)
		(drill 0.254)
		(layers "F.Cu" "B.Cu")
		(net "GND")
	)
	(via
		(at 86.871048 -253.394464)
		(size 0.4064)
		(drill 0.2032)
		(layers "F.Cu" "B.Cu")
		(net "GND")
	)
	(via
		(at 21.70811 -241.535204)
		(size 0.4826)
		(drill 0.254)
		(layers "F.Cu" "B.Cu")
		(net "GND")
	)
	(via
		(at 43.871134 -363.898434)
		(size 0.508)
		(drill 0.254)
		(layers "F.Cu" "B.Cu")
		(net "GND")
	)
	(via
		(at 66.391282 -33.981644)
		(size 0.508)
		(drill 0.254)
		(layers "F.Cu" "B.Cu")
		(net "GND")
	)
	(via
		(at 269.648178 -261.93496)
		(size 0.4826)
		(drill 0.254)
		(layers "F.Cu" "B.Cu")
		(net "GND")
	)
	(via
		(at 29.345636 -10.16508)
		(size 0.508)
		(drill 0.254)
		(layers "F.Cu" "B.Cu")
		(net "GND")
	)
	(via
		(at 147.042886 -266.530328)
		(size 0.4064)
		(drill 0.2032)
		(layers "F.Cu" "B.Cu")
		(net "GND")
	)
	(via
		(at 378.344938 -264.365994)
		(size 0.4064)
		(drill 0.2032)
		(layers "F.Cu" "B.Cu")
		(net "GND")
	)
	(via
		(at 389.79475 -254.204216)
		(size 0.4064)
		(drill 0.2032)
		(layers "F.Cu" "B.Cu")
		(net "GND")
	)
	(via
		(at 125.145038 -403.830536)
		(size 0.4572)
		(drill 0.254)
		(layers "F.Cu" "B.Cu")
		(net "GND")
	)
	(via
		(at 382.571498 -180.755544)
		(size 0.49022)
		(drill 0.254)
		(layers "F.Cu" "B.Cu")
		(net "GND")
	)
	(via
		(at 368.944906 -267.606018)
		(size 0.4064)
		(drill 0.2032)
		(layers "F.Cu" "B.Cu")
		(net "GND")
	)
	(via
		(at 367.504726 -26.702766)
		(size 0.508)
		(drill 0.254)
		(layers "F.Cu" "B.Cu")
		(net "GND")
	)
	(via
		(at 427.768258 -12.37488)
		(size 0.508)
		(drill 0.254)
		(layers "F.Cu" "B.Cu")
		(net "GND")
	)
	(via
		(at 416.468052 -233.884978)
		(size 0.4826)
		(drill 0.254)
		(layers "F.Cu" "B.Cu")
		(net "GND")
	)
	(via
		(at 456.051666 -103.646224)
		(size 0.508)
		(drill 0.254)
		(layers "F.Cu" "B.Cu")
		(net "GND")
	)
	(via
		(at 186.312048 -108.662978)
		(size 0.4572)
		(drill 0.254)
		(layers "F.Cu" "B.Cu")
		(net "GND")
	)
	(via
		(at 314.044838 -413.480504)
		(size 0.4572)
		(drill 0.254)
		(layers "F.Cu" "B.Cu")
		(net "GND")
	)
	(via
		(at 299.82414 -222.834962)
		(size 0.4826)
		(drill 0.254)
		(layers "F.Cu" "B.Cu")
		(net "GND")
	)
	(via
		(at 95.800926 -225.044508)
		(size 0.4064)
		(drill 0.2032)
		(layers "F.Cu" "B.Cu")
		(net "GND")
	)
	(via
		(at 39.12235 -239.410494)
		(size 0.4826)
		(drill 0.254)
		(layers "F.Cu" "B.Cu")
		(net "GND")
	)
	(via
		(at 376.634756 -234.764072)
		(size 0.4064)
		(drill 0.2032)
		(layers "F.Cu" "B.Cu")
		(net "GND")
	)
	(via
		(at 39.55796 -439.350404)
		(size 0.508)
		(drill 0.254)
		(layers "F.Cu" "B.Cu")
		(net "GND")
	)
	(via
		(at 385.394708 -265.176)
		(size 0.4064)
		(drill 0.2032)
		(layers "F.Cu" "B.Cu")
		(net "GND")
	)
	(via
		(at 113.184686 -229.094538)
		(size 0.4064)
		(drill 0.2032)
		(layers "F.Cu" "B.Cu")
		(net "GND")
	)
	(via
		(at 83.580986 -239.624362)
		(size 0.4064)
		(drill 0.2032)
		(layers "F.Cu" "B.Cu")
		(net "GND")
	)
	(via
		(at 431.989992 -350.741234)
		(size 0.49022)
		(drill 0.254)
		(layers "F.Cu" "B.Cu")
		(net "GND")
	)
	(via
		(at 356.894384 -376.75693)
		(size 0.508)
		(drill 0.254)
		(layers "F.Cu" "B.Cu")
		(net "GND")
	)
	(via
		(at 61.559694 -374.62333)
		(size 0.508)
		(drill 0.254)
		(layers "F.Cu" "B.Cu")
		(net "GND")
	)
	(via
		(at 124.294646 -281.376374)
		(size 0.4064)
		(drill 0.2032)
		(layers "F.Cu" "B.Cu")
		(net "GND")
	)
	(via
		(at 298.70654 -313.360054)
		(size 0.4826)
		(drill 0.254)
		(layers "F.Cu" "B.Cu")
		(net "GND")
	)
	(via
		(at 33.474914 -339.803994)
		(size 0.508)
		(drill 0.254)
		(layers "F.Cu" "B.Cu")
		(net "GND")
	)
	(via
		(at 410.656024 -19.771106)
		(size 0.508)
		(drill 0.254)
		(layers "F.Cu" "B.Cu")
		(net "GND")
	)
	(via
		(at 378.04471 -250.154186)
		(size 0.4064)
		(drill 0.2032)
		(layers "F.Cu" "B.Cu")
		(net "GND")
	)
	(via
		(at 178.249834 -342.769952)
		(size 0.508)
		(drill 0.254)
		(layers "F.Cu" "B.Cu")
		(net "GND")
	)
	(via
		(at 427.97095 -39.055548)
		(size 0.508)
		(drill 0.254)
		(layers "F.Cu" "B.Cu")
		(net "GND")
	)
	(via
		(at 90.575384 -441.227718)
		(size 0.508)
		(drill 0.254)
		(layers "F.Cu" "B.Cu")
		(net "GND")
	)
	(via
		(at 394.68298 -256.090166)
		(size 0.4064)
		(drill 0.2032)
		(layers "F.Cu" "B.Cu")
		(net "GND")
	)
	(via
		(at 118.184676 -270.846296)
		(size 0.4064)
		(drill 0.2032)
		(layers "F.Cu" "B.Cu")
		(net "GND")
	)
	(via
		(at 145.144744 -243.674392)
		(size 0.4064)
		(drill 0.2032)
		(layers "F.Cu" "B.Cu")
		(net "GND")
	)
	(via
		(at 303.268126 -318.885062)
		(size 0.4826)
		(drill 0.254)
		(layers "F.Cu" "B.Cu")
		(net "GND")
	)
	(via
		(at 88.281002 -247.724422)
		(size 0.4064)
		(drill 0.2032)
		(layers "F.Cu" "B.Cu")
		(net "GND")
	)
	(via
		(at 303.232566 -344.132408)
		(size 0.508)
		(drill 0.254)
		(layers "F.Cu" "B.Cu")
		(net "GND")
	)
	(via
		(at 419.912038 -249.185176)
		(size 0.4826)
		(drill 0.254)
		(layers "F.Cu" "B.Cu")
		(net "GND")
	)
	(via
		(at 339.811106 -261.12597)
		(size 0.4064)
		(drill 0.2032)
		(layers "F.Cu" "B.Cu")
		(net "GND")
	)
	(via
		(at 124.934726 -223.424496)
		(size 0.4064)
		(drill 0.2032)
		(layers "F.Cu" "B.Cu")
		(net "GND")
	)
	(via
		(at 297.108372 -203.28509)
		(size 0.4826)
		(drill 0.254)
		(layers "F.Cu" "B.Cu")
		(net "GND")
	)
	(via
		(at 269.648178 -253.435104)
		(size 0.4826)
		(drill 0.254)
		(layers "F.Cu" "B.Cu")
		(net "GND")
	)
	(via
		(at 2.76225 -311.333134)
		(size 0.508)
		(drill 0.254)
		(layers "F.Cu" "B.Cu")
		(net "GND")
	)
	(via
		(at 191.160146 -235.585254)
		(size 0.4826)
		(drill 0.254)
		(layers "F.Cu" "B.Cu")
		(net "GND")
	)
	(via
		(at 35.411664 -239.835436)
		(size 0.4826)
		(drill 0.254)
		(layers "F.Cu" "B.Cu")
		(net "GND")
	)
	(via
		(at 178.706272 -350.386904)
		(size 0.49022)
		(drill 0.254)
		(layers "F.Cu" "B.Cu")
		(net "GND")
	)
	(via
		(at 404.78964 -379.88113)
		(size 0.508)
		(drill 0.254)
		(layers "F.Cu" "B.Cu")
		(net "GND")
	)
	(via
		(at 196.589396 -439.90768)
		(size 0.508)
		(drill 0.254)
		(layers "F.Cu" "B.Cu")
		(net "GND")
	)
	(via
		(at 292.02761 -344.77706)
		(size 0.49022)
		(drill 0.254)
		(layers "F.Cu" "B.Cu")
		(net "GND")
	)
	(via
		(at 424.012106 -253.435104)
		(size 0.4826)
		(drill 0.254)
		(layers "F.Cu" "B.Cu")
		(net "GND")
	)
	(via
		(at 127.436372 -61.101732)
		(size 0.508)
		(drill 0.254)
		(layers "F.Cu" "B.Cu")
		(net "GND")
	)
	(via
		(at 107.85094 -267.606272)
		(size 0.4064)
		(drill 0.2032)
		(layers "F.Cu" "B.Cu")
		(net "GND")
	)
	(via
		(at 113.184686 -248.534428)
		(size 0.4064)
		(drill 0.2032)
		(layers "F.Cu" "B.Cu")
		(net "GND")
	)
	(via
		(at 331.821028 -274.896072)
		(size 0.4064)
		(drill 0.2032)
		(layers "F.Cu" "B.Cu")
		(net "GND")
	)
	(via
		(at 183.616092 -263.635236)
		(size 0.4826)
		(drill 0.254)
		(layers "F.Cu" "B.Cu")
		(net "GND")
	)
	(via
		(at 372.404894 -229.094284)
		(size 0.4064)
		(drill 0.2032)
		(layers "F.Cu" "B.Cu")
		(net "GND")
	)
	(via
		(at 301.019718 -145.238978)
		(size 0.508)
		(drill 0.254)
		(layers "F.Cu" "B.Cu")
		(net "GND")
	)
	(via
		(at 462.446624 -98.564954)
		(size 0.508)
		(drill 0.254)
		(layers "F.Cu" "B.Cu")
		(net "GND")
	)
	(via
		(at 399.349722 -431.451258)
		(size 0.4572)
		(drill 0.2032)
		(layers "F.Cu" "B.Cu")
		(net "GND")
	)
	(via
		(at 143.264636 -253.394464)
		(size 0.4064)
		(drill 0.2032)
		(layers "F.Cu" "B.Cu")
		(net "GND")
	)
	(via
		(at 92.34424 -382.85293)
		(size 0.4064)
		(drill 0.2032)
		(layers "F.Cu" "B.Cu")
		(net "GND")
	)
	(via
		(at 215.826594 -53.863748)
		(size 0.508)
		(drill 0.254)
		(layers "F.Cu" "B.Cu")
		(net "GND")
	)
	(via
		(at 64.262508 -384.617722)
		(size 0.4064)
		(drill 0.2032)
		(layers "F.Cu" "B.Cu")
		(net "GND")
	)
	(via
		(at 88.281002 -236.384338)
		(size 0.4064)
		(drill 0.2032)
		(layers "F.Cu" "B.Cu")
		(net "GND")
	)
	(via
		(at 430.17186 -277.235158)
		(size 0.4826)
		(drill 0.254)
		(layers "F.Cu" "B.Cu")
		(net "GND")
	)
	(via
		(at 307.368194 -216.885012)
		(size 0.4826)
		(drill 0.254)
		(layers "F.Cu" "B.Cu")
		(net "GND")
	)
	(via
		(at 101.27107 -277.326344)
		(size 0.4064)
		(drill 0.2032)
		(layers "F.Cu" "B.Cu")
		(net "GND")
	)
	(via
		(at 127.284734 -230.71455)
		(size 0.4064)
		(drill 0.2032)
		(layers "F.Cu" "B.Cu")
		(net "GND")
	)
	(via
		(at 198.7042 -265.335258)
		(size 0.4826)
		(drill 0.254)
		(layers "F.Cu" "B.Cu")
		(net "GND")
	)
	(via
		(at 347.801184 -282.996132)
		(size 0.4064)
		(drill 0.2032)
		(layers "F.Cu" "B.Cu")
		(net "GND")
	)
	(via
		(at 111.508794 -188.294518)
		(size 0.508)
		(drill 0.254)
		(layers "F.Cu" "B.Cu")
		(net "GND")
	)
	(via
		(at 78.84795 -61.95695)
		(size 0.508)
		(drill 0.254)
		(layers "F.Cu" "B.Cu")
		(net "GND")
	)
	(via
		(at 126.689104 -54.17439)
		(size 0.508)
		(drill 0.254)
		(layers "F.Cu" "B.Cu")
		(net "GND")
	)
	(via
		(at 101.91115 -255.014476)
		(size 0.4064)
		(drill 0.2032)
		(layers "F.Cu" "B.Cu")
		(net "GND")
	)
	(via
		(at 305.483006 -336.304128)
		(size 0.508)
		(drill 0.254)
		(layers "F.Cu" "B.Cu")
		(net "GND")
	)
	(via
		(at 39.12235 -211.360258)
		(size 0.4826)
		(drill 0.254)
		(layers "F.Cu" "B.Cu")
		(net "GND")
	)
	(via
		(at 206.248 -241.535204)
		(size 0.4826)
		(drill 0.254)
		(layers "F.Cu" "B.Cu")
		(net "GND")
	)
	(via
		(at 439.100214 -301.034958)
		(size 0.4826)
		(drill 0.254)
		(layers "F.Cu" "B.Cu")
		(net "GND")
	)
	(via
		(at 301.169578 -118.179088)
		(size 0.508)
		(drill 0.254)
		(layers "F.Cu" "B.Cu")
		(net "GND")
	)
	(via
		(at 419.912038 -318.885062)
		(size 0.4826)
		(drill 0.254)
		(layers "F.Cu" "B.Cu")
		(net "GND")
	)
	(via
		(at 127.114808 -287.856422)
		(size 0.4064)
		(drill 0.2032)
		(layers "F.Cu" "B.Cu")
		(net "GND")
	)
	(via
		(at 151.182578 -406.370536)
		(size 0.4572)
		(drill 0.254)
		(layers "F.Cu" "B.Cu")
		(net "GND")
	)
	(via
		(at 127.114808 -276.516338)
		(size 0.4064)
		(drill 0.2032)
		(layers "F.Cu" "B.Cu")
		(net "GND")
	)
	(via
		(at 43.222418 -201.16038)
		(size 0.4826)
		(drill 0.254)
		(layers "F.Cu" "B.Cu")
		(net "GND")
	)
	(via
		(at 369.14963 -257.930142)
		(size 0.4826)
		(drill 0.254)
		(layers "F.Cu" "B.Cu")
		(net "GND")
	)
	(via
		(at 25.634188 -386.914898)
		(size 0.49022)
		(drill 0.254)
		(layers "F.Cu" "B.Cu")
		(net "GND")
	)
	(via
		(at 366.594898 -287.856168)
		(size 0.4064)
		(drill 0.2032)
		(layers "F.Cu" "B.Cu")
		(net "GND")
	)
	(via
		(at 173.232064 -390.923018)
		(size 0.508)
		(drill 0.254)
		(layers "F.Cu" "B.Cu")
		(net "GND")
	)
	(via
		(at 368.644932 -229.094284)
		(size 0.4064)
		(drill 0.2032)
		(layers "F.Cu" "B.Cu")
		(net "GND")
	)
	(via
		(at 77.112876 -266.530328)
		(size 0.4064)
		(drill 0.2032)
		(layers "F.Cu" "B.Cu")
		(net "GND")
	)
	(via
		(at 390.094724 -261.935976)
		(size 0.4064)
		(drill 0.2032)
		(layers "F.Cu" "B.Cu")
		(net "GND")
	)
	(via
		(at 2.76225 -266.629134)
		(size 0.508)
		(drill 0.254)
		(layers "F.Cu" "B.Cu")
		(net "GND")
	)
	(via
		(at 388.916418 -402.284438)
		(size 0.4572)
		(drill 0.254)
		(layers "F.Cu" "B.Cu")
		(net "GND")
	)
	(via
		(at 369.884706 -269.22603)
		(size 0.4064)
		(drill 0.2032)
		(layers "F.Cu" "B.Cu")
		(net "GND")
	)
	(via
		(at 141.058392 -380.87046)
		(size 0.508)
		(drill 0.254)
		(layers "F.Cu" "B.Cu")
		(net "GND")
	)
	(via
		(at 110.200948 -279.756362)
		(size 0.4064)
		(drill 0.2032)
		(layers "F.Cu" "B.Cu")
		(net "GND")
	)
	(via
		(at 445.853566 -425.438824)
		(size 0.508)
		(drill 0.254)
		(layers "F.Cu" "B.Cu")
		(net "GND")
	)
	(via
		(at 116.326666 -172.32249)
		(size 0.49022)
		(drill 0.254)
		(layers "F.Cu" "B.Cu")
		(net "GND")
	)
	(via
		(at 31.612078 -17.613122)
		(size 0.508)
		(drill 0.254)
		(layers "F.Cu" "B.Cu")
		(net "GND")
	)
	(via
		(at 388.34949 -439.651394)
		(size 0.4572)
		(drill 0.2032)
		(layers "F.Cu" "B.Cu")
		(net "GND")
	)
	(via
		(at 203.532232 -275.53539)
		(size 0.4826)
		(drill 0.254)
		(layers "F.Cu" "B.Cu")
		(net "GND")
	)
	(via
		(at 48.578516 -386.449062)
		(size 0.4064)
		(drill 0.2032)
		(layers "F.Cu" "B.Cu")
		(net "GND")
	)
	(via
		(at 89.647522 -308.48554)
		(size 0.508)
		(drill 0.254)
		(layers "F.Cu" "B.Cu")
		(net "GND")
	)
	(via
		(at 367.064798 -278.946102)
		(size 0.4064)
		(drill 0.2032)
		(layers "F.Cu" "B.Cu")
		(net "GND")
	)
	(via
		(at 288.180018 -281.485086)
		(size 0.4826)
		(drill 0.254)
		(layers "F.Cu" "B.Cu")
		(net "GND")
	)
	(via
		(at 130.574796 -247.724422)
		(size 0.4064)
		(drill 0.2032)
		(layers "F.Cu" "B.Cu")
		(net "GND")
	)
	(via
		(at 446.644268 -297.635168)
		(size 0.4826)
		(drill 0.254)
		(layers "F.Cu" "B.Cu")
		(net "GND")
	)
	(via
		(at 390.734804 -249.34418)
		(size 0.4064)
		(drill 0.2032)
		(layers "F.Cu" "B.Cu")
		(net "GND")
	)
	(via
		(at 143.56461 -278.946356)
		(size 0.4064)
		(drill 0.2032)
		(layers "F.Cu" "B.Cu")
		(net "GND")
	)
	(via
		(at 371.93474 -229.904036)
		(size 0.4064)
		(drill 0.2032)
		(layers "F.Cu" "B.Cu")
		(net "GND")
	)
	(via
		(at 74.892916 -406.370536)
		(size 0.4572)
		(drill 0.254)
		(layers "F.Cu" "B.Cu")
		(net "GND")
	)
	(via
		(at 299.82414 -213.484968)
		(size 0.4826)
		(drill 0.254)
		(layers "F.Cu" "B.Cu")
		(net "GND")
	)
	(via
		(at 364.294674 -178.170332)
		(size 0.49022)
		(drill 0.254)
		(layers "F.Cu" "B.Cu")
		(net "GND")
	)
	(via
		(at 88.494362 -374.62333)
		(size 0.508)
		(drill 0.254)
		(layers "F.Cu" "B.Cu")
		(net "GND")
	)
	(via
		(at 343.145618 -417.778184)
		(size 0.4572)
		(drill 0.254)
		(layers "F.Cu" "B.Cu")
		(net "GND")
	)
	(via
		(at 398.700498 -176.605184)
		(size 0.49022)
		(drill 0.254)
		(layers "F.Cu" "B.Cu")
		(net "GND")
	)
	(via
		(at 233.495088 -251.442728)
		(size 0.508)
		(drill 0.254)
		(layers "F.Cu" "B.Cu")
		(net "GND")
	)
	(via
		(at 95.944182 -382.85293)
		(size 0.4064)
		(drill 0.2032)
		(layers "F.Cu" "B.Cu")
		(net "GND")
	)
	(via
		(at 126.34976 -425.547282)
		(size 0.4572)
		(drill 0.2032)
		(layers "F.Cu" "B.Cu")
		(net "GND")
	)
	(via
		(at 21.70811 -306.985416)
		(size 0.4826)
		(drill 0.254)
		(layers "F.Cu" "B.Cu")
		(net "GND")
	)
	(via
		(at 384.349498 -431.29962)
		(size 0.4572)
		(drill 0.2032)
		(layers "F.Cu" "B.Cu")
		(net "GND")
	)
	(via
		(at 40.494966 -6.598158)
		(size 0.508)
		(drill 0.254)
		(layers "F.Cu" "B.Cu")
		(net "GND")
	)
	(via
		(at 2.76225 -110.165134)
		(size 0.508)
		(drill 0.254)
		(layers "F.Cu" "B.Cu")
		(net "GND")
	)
	(via
		(at 331.051154 -243.674138)
		(size 0.4064)
		(drill 0.2032)
		(layers "F.Cu" "B.Cu")
		(net "GND")
	)
	(via
		(at 20.67687 -386.80009)
		(size 0.508)
		(drill 0.254)
		(layers "F.Cu" "B.Cu")
		(net "GND")
	)
	(via
		(at 59.307222 -173.839124)
		(size 0.6604)
		(drill 0.3302)
		(layers "F.Cu" "B.Cu")
		(net "GND")
	)
	(via
		(at 353.918774 -398.542002)
		(size 0.4064)
		(drill 0.2032)
		(layers "F.Cu" "B.Cu")
		(net "GND")
	)
	(via
		(at 372.747032 -380.54153)
		(size 0.508)
		(drill 0.254)
		(layers "F.Cu" "B.Cu")
		(net "GND")
	)
	(via
		(at 107.85094 -288.666174)
		(size 0.4064)
		(drill 0.2032)
		(layers "F.Cu" "B.Cu")
		(net "GND")
	)
	(via
		(at 81.701132 -226.66452)
		(size 0.4064)
		(drill 0.2032)
		(layers "F.Cu" "B.Cu")
		(net "GND")
	)
	(via
		(at 346.249498 -431.29962)
		(size 0.4572)
		(drill 0.2032)
		(layers "F.Cu" "B.Cu")
		(net "GND")
	)
	(via
		(at 326.651112 -275.706078)
		(size 0.4064)
		(drill 0.2032)
		(layers "F.Cu" "B.Cu")
		(net "GND")
	)
	(via
		(at 453.964294 -399.233644)
		(size 0.49022)
		(drill 0.254)
		(layers "F.Cu" "B.Cu")
		(net "GND")
	)
	(via
		(at 163.435538 -407.638504)
		(size 0.4572)
		(drill 0.254)
		(layers "F.Cu" "B.Cu")
		(net "GND")
	)
	(via
		(at 96.335596 -410.664152)
		(size 0.4572)
		(drill 0.254)
		(layers "F.Cu" "B.Cu")
		(net "GND")
	)
	(via
		(at 395.038072 -387.703568)
		(size 0.508)
		(drill 0.254)
		(layers "F.Cu" "B.Cu")
		(net "GND")
	)
	(via
		(at 337.291934 -421.586152)
		(size 0.4572)
		(drill 0.254)
		(layers "F.Cu" "B.Cu")
		(net "GND")
	)
	(via
		(at 427.456092 -262.785098)
		(size 0.4826)
		(drill 0.254)
		(layers "F.Cu" "B.Cu")
		(net "GND")
	)
	(via
		(at 17.380458 -417.68014)
		(size 0.508)
		(drill 0.254)
		(layers "F.Cu" "B.Cu")
		(net "GND")
	)
	(via
		(at 70.16242 -340.141814)
		(size 0.508)
		(drill 0.254)
		(layers "F.Cu" "B.Cu")
		(net "GND")
	)
	(via
		(at 97.511108 -282.18638)
		(size 0.4064)
		(drill 0.2032)
		(layers "F.Cu" "B.Cu")
		(net "GND")
	)
	(via
		(at 326.351138 -238.814102)
		(size 0.4064)
		(drill 0.2032)
		(layers "F.Cu" "B.Cu")
		(net "GND")
	)
	(via
		(at 233.172 -235.712)
		(size 0.508)
		(drill 0.254)
		(layers "F.Cu" "B.Cu")
		(net "GND")
	)
	(via
		(at 170.245024 -377.132088)
		(size 0.508)
		(drill 0.254)
		(layers "F.Cu" "B.Cu")
		(net "GND")
	)
	(via
		(at 299.82414 -235.585)
		(size 0.4826)
		(drill 0.254)
		(layers "F.Cu" "B.Cu")
		(net "GND")
	)
	(via
		(at 113.187988 -253.392432)
		(size 0.4064)
		(drill 0.2032)
		(layers "F.Cu" "B.Cu")
		(net "GND")
	)
	(via
		(at 21.632418 -413.99587)
		(size 0.508)
		(drill 0.254)
		(layers "F.Cu" "B.Cu")
		(net "GND")
	)
	(via
		(at 58.310526 -210.510374)
		(size 0.4826)
		(drill 0.254)
		(layers "F.Cu" "B.Cu")
		(net "GND")
	)
	(via
		(at 347.33103 -272.466054)
		(size 0.4064)
		(drill 0.2032)
		(layers "F.Cu" "B.Cu")
		(net "GND")
	)
	(via
		(at 343.571068 -269.22603)
		(size 0.4064)
		(drill 0.2032)
		(layers "F.Cu" "B.Cu")
		(net "GND")
	)
	(via
		(at 86.401148 -233.144314)
		(size 0.4064)
		(drill 0.2032)
		(layers "F.Cu" "B.Cu")
		(net "GND")
	)
	(via
		(at 123.994672 -234.764326)
		(size 0.4064)
		(drill 0.2032)
		(layers "F.Cu" "B.Cu")
		(net "GND")
	)
	(via
		(at 137.45464 -261.93623)
		(size 0.4064)
		(drill 0.2032)
		(layers "F.Cu" "B.Cu")
		(net "GND")
	)
	(via
		(at 287.062418 -220.709998)
		(size 0.4826)
		(drill 0.254)
		(layers "F.Cu" "B.Cu")
		(net "GND")
	)
	(via
		(at 230.834946 -250.263914)
		(size 0.4826)
		(drill 0.254)
		(layers "F.Cu" "B.Cu")
		(net "GND")
	)
	(via
		(at 78.123542 -333.842868)
		(size 0.49022)
		(drill 0.254)
		(layers "F.Cu" "B.Cu")
		(net "GND")
	)
	(via
		(at 336.95132 -362.01096)
		(size 0.508)
		(drill 0.254)
		(layers "F.Cu" "B.Cu")
		(net "GND")
	)
	(via
		(at 62.639956 -410.664152)
		(size 0.4572)
		(drill 0.254)
		(layers "F.Cu" "B.Cu")
		(net "GND")
	)
	(via
		(at 425.407074 -343.221564)
		(size 0.508)
		(drill 0.254)
		(layers "F.Cu" "B.Cu")
		(net "GND")
	)
	(via
		(at 273.092164 -309.535068)
		(size 0.4826)
		(drill 0.254)
		(layers "F.Cu" "B.Cu")
		(net "GND")
	)
	(via
		(at 77.463142 -333.842868)
		(size 0.49022)
		(drill 0.254)
		(layers "F.Cu" "B.Cu")
		(net "GND")
	)
	(via
		(at 380.516384 -400.212814)
		(size 0.4064)
		(drill 0.2032)
		(layers "F.Cu" "B.Cu")
		(net "GND")
	)
	(via
		(at 130.40487 -272.466308)
		(size 0.4064)
		(drill 0.2032)
		(layers "F.Cu" "B.Cu")
		(net "GND")
	)
	(via
		(at 314.317634 -416.020504)
		(size 0.4572)
		(drill 0.254)
		(layers "F.Cu" "B.Cu")
		(net "GND")
	)
	(via
		(at 428.283116 -110.27664)
		(size 0.508)
		(drill 0.254)
		(layers "F.Cu" "B.Cu")
		(net "GND")
	)
	(via
		(at 427.370494 -394.392404)
		(size 0.508)
		(drill 0.254)
		(layers "F.Cu" "B.Cu")
		(net "GND")
	)
	(via
		(at 49.168304 -219.435426)
		(size 0.4826)
		(drill 0.254)
		(layers "F.Cu" "B.Cu")
		(net "GND")
	)
	(via
		(at 344.211148 -248.534174)
		(size 0.4064)
		(drill 0.2032)
		(layers "F.Cu" "B.Cu")
		(net "GND")
	)
	(via
		(at 394.377672 -383.814828)
		(size 0.508)
		(drill 0.254)
		(layers "F.Cu" "B.Cu")
		(net "GND")
	)
	(via
		(at 72.188324 -410.030168)
		(size 0.4064)
		(drill 0.2032)
		(layers "F.Cu" "B.Cu")
		(net "GND")
	)
	(via
		(at 109.815122 -125.551438)
		(size 0.508)
		(drill 0.254)
		(layers "F.Cu" "B.Cu")
		(net "GND")
	)
	(via
		(at 83.88096 -268.416278)
		(size 0.4064)
		(drill 0.2032)
		(layers "F.Cu" "B.Cu")
		(net "GND")
	)
	(via
		(at 392.011154 -441.227718)
		(size 0.508)
		(drill 0.254)
		(layers "F.Cu" "B.Cu")
		(net "GND")
	)
	(via
		(at 117.244622 -277.326344)
		(size 0.4064)
		(drill 0.2032)
		(layers "F.Cu" "B.Cu")
		(net "GND")
	)
	(via
		(at 308.279546 -412.84652)
		(size 0.4064)
		(drill 0.2032)
		(layers "F.Cu" "B.Cu")
		(net "GND")
	)
	(via
		(at 395.439138 -396.1765)
		(size 0.508)
		(drill 0.254)
		(layers "F.Cu" "B.Cu")
		(net "GND")
	)
	(via
		(at 124.607066 -165.59149)
		(size 0.49022)
		(drill 0.254)
		(layers "F.Cu" "B.Cu")
		(net "GND")
	)
	(via
		(at 38.722046 -412.387288)
		(size 0.4572)
		(drill 0.254)
		(layers "F.Cu" "B.Cu")
		(net "GND")
	)
	(via
		(at 165.812216 -219.435426)
		(size 0.4826)
		(drill 0.254)
		(layers "F.Cu" "B.Cu")
		(net "GND")
	)
	(via
		(at 40.23995 -264.485374)
		(size 0.4826)
		(drill 0.254)
		(layers "F.Cu" "B.Cu")
		(net "GND")
	)
	(via
		(at 136.98474 -283.806392)
		(size 0.4064)
		(drill 0.2032)
		(layers "F.Cu" "B.Cu")
		(net "GND")
	)
	(via
		(at 233.750104 -228.740716)
		(size 0.4826)
		(drill 0.254)
		(layers "F.Cu" "B.Cu")
		(net "GND")
	)
	(via
		(at 81.632298 -331.088238)
		(size 0.508)
		(drill 0.254)
		(layers "F.Cu" "B.Cu")
		(net "GND")
	)
	(via
		(at 56.513476 -410.664152)
		(size 0.4572)
		(drill 0.254)
		(layers "F.Cu" "B.Cu")
		(net "GND")
	)
	(via
		(at 415.083752 -277.235158)
		(size 0.4826)
		(drill 0.254)
		(layers "F.Cu" "B.Cu")
		(net "GND")
	)
	(via
		(at 96.74098 -244.484398)
		(size 0.4064)
		(drill 0.2032)
		(layers "F.Cu" "B.Cu")
		(net "GND")
	)
	(via
		(at 82.292698 -331.748638)
		(size 0.508)
		(drill 0.254)
		(layers "F.Cu" "B.Cu")
		(net "GND")
	)
	(via
		(at 198.325232 -106.64571)
		(size 0.508)
		(drill 0.254)
		(layers "F.Cu" "B.Cu")
		(net "GND")
	)
	(via
		(at 320.960496 -379.88113)
		(size 0.508)
		(drill 0.254)
		(layers "F.Cu" "B.Cu")
		(net "GND")
	)
	(via
		(at 353.441 -266.796012)
		(size 0.4064)
		(drill 0.2032)
		(layers "F.Cu" "B.Cu")
		(net "GND")
	)
	(via
		(at 207.765396 -439.90768)
		(size 0.508)
		(drill 0.254)
		(layers "F.Cu" "B.Cu")
		(net "GND")
	)
	(via
		(at 418.17671 -417.778184)
		(size 0.4572)
		(drill 0.254)
		(layers "F.Cu" "B.Cu")
		(net "GND")
	)
	(via
		(at 126.644654 -270.846296)
		(size 0.4064)
		(drill 0.2032)
		(layers "F.Cu" "B.Cu")
		(net "GND")
	)
	(via
		(at 144.034764 -291.096192)
		(size 0.4064)
		(drill 0.2032)
		(layers "F.Cu" "B.Cu")
		(net "GND")
	)
	(via
		(at 32.605218 -51.369214)
		(size 0.508)
		(drill 0.254)
		(layers "F.Cu" "B.Cu")
		(net "GND")
	)
	(via
		(at 234.674664 -214.37346)
		(size 0.4826)
		(drill 0.254)
		(layers "F.Cu" "B.Cu")
		(net "GND")
	)
	(via
		(at 111.641636 -368.37493)
		(size 0.508)
		(drill 0.254)
		(layers "F.Cu" "B.Cu")
		(net "GND")
	)
	(via
		(at 53.284374 -348.709488)
		(size 0.49022)
		(drill 0.254)
		(layers "F.Cu" "B.Cu")
		(net "GND")
	)
	(via
		(at 391.504678 -282.186126)
		(size 0.4064)
		(drill 0.2032)
		(layers "F.Cu" "B.Cu")
		(net "GND")
	)
	(via
		(at 90.16111 -231.524302)
		(size 0.4064)
		(drill 0.2032)
		(layers "F.Cu" "B.Cu")
		(net "GND")
	)
	(via
		(at 264.43051 -202.01001)
		(size 0.4826)
		(drill 0.254)
		(layers "F.Cu" "B.Cu")
		(net "GND")
	)
	(via
		(at 271.974564 -220.709998)
		(size 0.4826)
		(drill 0.254)
		(layers "F.Cu" "B.Cu")
		(net "GND")
	)
	(via
		(at 38.45814 -9.424924)
		(size 0.508)
		(drill 0.254)
		(layers "F.Cu" "B.Cu")
		(net "GND")
	)
	(via
		(at 397.804894 -178.321208)
		(size 0.49022)
		(drill 0.254)
		(layers "F.Cu" "B.Cu")
		(net "GND")
	)
	(via
		(at 418.17671 -419.046152)
		(size 0.4572)
		(drill 0.254)
		(layers "F.Cu" "B.Cu")
		(net "GND")
	)
	(via
		(at 202.147932 -309.535322)
		(size 0.4826)
		(drill 0.254)
		(layers "F.Cu" "B.Cu")
		(net "GND")
	)
	(via
		(at 128.694688 -226.66452)
		(size 0.4064)
		(drill 0.2032)
		(layers "F.Cu" "B.Cu")
		(net "GND")
	)
	(via
		(at 431.568098 -331.78369)
		(size 0.508)
		(drill 0.254)
		(layers "F.Cu" "B.Cu")
		(net "GND")
	)
	(via
		(at 415.083752 -230.485188)
		(size 0.4826)
		(drill 0.254)
		(layers "F.Cu" "B.Cu")
		(net "GND")
	)
	(via
		(at 430.17186 -211.784946)
		(size 0.4826)
		(drill 0.254)
		(layers "F.Cu" "B.Cu")
		(net "GND")
	)
	(via
		(at 442.5442 -234.735116)
		(size 0.4826)
		(drill 0.254)
		(layers "F.Cu" "B.Cu")
		(net "GND")
	)
	(via
		(at 122.8852 -68.69176)
		(size 0.508)
		(drill 0.254)
		(layers "F.Cu" "B.Cu")
		(net "GND")
	)
	(via
		(at 140.349732 -428.851314)
		(size 0.4572)
		(drill 0.2032)
		(layers "F.Cu" "B.Cu")
		(net "GND")
	)
	(via
		(at 136.139174 -405.098504)
		(size 0.4572)
		(drill 0.254)
		(layers "F.Cu" "B.Cu")
		(net "GND")
	)
	(via
		(at 444.007748 -337.360006)
		(size 0.6604)
		(drill 0.3302)
		(layers "F.Cu" "B.Cu")
		(net "GND")
	)
	(via
		(at 183.366664 -359.902506)
		(size 0.508)
		(drill 0.254)
		(layers "F.Cu" "B.Cu")
		(net "GND")
	)
	(via
		(at 147.02282 -309.521352)
		(size 0.508)
		(drill 0.254)
		(layers "F.Cu" "B.Cu")
		(net "GND")
	)
	(via
		(at 47.784004 -245.785386)
		(size 0.4826)
		(drill 0.254)
		(layers "F.Cu" "B.Cu")
		(net "GND")
	)
	(via
		(at 52.823872 -419.89502)
		(size 0.508)
		(drill 0.254)
		(layers "F.Cu" "B.Cu")
		(net "GND")
	)
	(via
		(at 99.090988 -245.294404)
		(size 0.4064)
		(drill 0.2032)
		(layers "F.Cu" "B.Cu")
		(net "GND")
	)
	(via
		(at 266.365736 -343.083896)
		(size 0.49022)
		(drill 0.254)
		(layers "F.Cu" "B.Cu")
		(net "GND")
	)
	(via
		(at 394.956538 -181.075838)
		(size 0.508)
		(drill 0.254)
		(layers "F.Cu" "B.Cu")
		(net "GND")
	)
	(via
		(at 37.07384 -111.4552)
		(size 0.508)
		(drill 0.254)
		(layers "F.Cu" "B.Cu")
		(net "GND")
	)
	(via
		(at 89.506298 -386.449062)
		(size 0.4064)
		(drill 0.2032)
		(layers "F.Cu" "B.Cu")
		(net "GND")
	)
	(via
		(at 437.715914 -302.73498)
		(size 0.4826)
		(drill 0.254)
		(layers "F.Cu" "B.Cu")
		(net "GND")
	)
	(via
		(at 41.508934 -363.898434)
		(size 0.508)
		(drill 0.254)
		(layers "F.Cu" "B.Cu")
		(net "GND")
	)
	(via
		(at 193.002916 -329.500484)
		(size 0.508)
		(drill 0.254)
		(layers "F.Cu" "B.Cu")
		(net "GND")
	)
	(via
		(at 224.79 -332.105)
		(size 0.508)
		(drill 0.254)
		(layers "F.Cu" "B.Cu")
		(net "GND")
	)
	(via
		(at 38.816534 -344.78595)
		(size 0.49022)
		(drill 0.254)
		(layers "F.Cu" "B.Cu")
		(net "GND")
	)
	(via
		(at 406.597104 -16.9799)
		(size 0.508)
		(drill 0.254)
		(layers "F.Cu" "B.Cu")
		(net "GND")
	)
	(via
		(at 121.944638 -270.846296)
		(size 0.4064)
		(drill 0.2032)
		(layers "F.Cu" "B.Cu")
		(net "GND")
	)
	(via
		(at 107.85094 -285.426404)
		(size 0.4064)
		(drill 0.2032)
		(layers "F.Cu" "B.Cu")
		(net "GND")
	)
	(via
		(at 447.321432 -395.310106)
		(size 0.49022)
		(drill 0.254)
		(layers "F.Cu" "B.Cu")
		(net "GND")
	)
	(via
		(at 280.635964 -217.73515)
		(size 0.4826)
		(drill 0.254)
		(layers "F.Cu" "B.Cu")
		(net "GND")
	)
	(via
		(at 213.433152 -73.048622)
		(size 0.508)
		(drill 0.254)
		(layers "F.Cu" "B.Cu")
		(net "GND")
	)
	(via
		(at 416.468052 -216.885012)
		(size 0.4826)
		(drill 0.254)
		(layers "F.Cu" "B.Cu")
		(net "GND")
	)
	(via
		(at 406.788874 -168.992804)
		(size 0.49022)
		(drill 0.254)
		(layers "F.Cu" "B.Cu")
		(net "GND")
	)
	(via
		(at 352.9711 -282.186126)
		(size 0.4064)
		(drill 0.2032)
		(layers "F.Cu" "B.Cu")
		(net "GND")
	)
	(via
		(at 86.871048 -233.95432)
		(size 0.4064)
		(drill 0.2032)
		(layers "F.Cu" "B.Cu")
		(net "GND")
	)
	(via
		(at 123.824746 -282.18638)
		(size 0.4064)
		(drill 0.2032)
		(layers "F.Cu" "B.Cu")
		(net "GND")
	)
	(via
		(at 99.090988 -229.094538)
		(size 0.4064)
		(drill 0.2032)
		(layers "F.Cu" "B.Cu")
		(net "GND")
	)
	(via
		(at 422.627806 -286.585152)
		(size 0.4826)
		(drill 0.254)
		(layers "F.Cu" "B.Cu")
		(net "GND")
	)
	(via
		(at 70.860666 -7.215124)
		(size 0.508)
		(drill 0.254)
		(layers "F.Cu" "B.Cu")
		(net "GND")
	)
	(via
		(at 277.192232 -233.884978)
		(size 0.4826)
		(drill 0.254)
		(layers "F.Cu" "B.Cu")
		(net "GND")
	)
	(via
		(at 368.205004 -395.42974)
		(size 0.4064)
		(drill 0.2032)
		(layers "F.Cu" "B.Cu")
		(net "GND")
	)
	(via
		(at 192.395856 -72.158098)
		(size 0.508)
		(drill 0.254)
		(layers "F.Cu" "B.Cu")
		(net "GND")
	)
	(via
		(at 183.616092 -243.235226)
		(size 0.4826)
		(drill 0.254)
		(layers "F.Cu" "B.Cu")
		(net "GND")
	)
	(via
		(at 391.371074 -184.683146)
		(size 0.49022)
		(drill 0.254)
		(layers "F.Cu" "B.Cu")
		(net "GND")
	)
	(via
		(at 305.983894 -209.23504)
		(size 0.4826)
		(drill 0.254)
		(layers "F.Cu" "B.Cu")
		(net "GND")
	)
	(via
		(at 335.11109 -282.186126)
		(size 0.4064)
		(drill 0.2032)
		(layers "F.Cu" "B.Cu")
		(net "GND")
	)
	(via
		(at 378.962412 -392.999722)
		(size 0.4064)
		(drill 0.2032)
		(layers "F.Cu" "B.Cu")
		(net "GND")
	)
	(via
		(at 142.00886 -368.85499)
		(size 0.508)
		(drill 0.254)
		(layers "F.Cu" "B.Cu")
		(net "GND")
	)
	(via
		(at 393.048236 -12.37488)
		(size 0.508)
		(drill 0.254)
		(layers "F.Cu" "B.Cu")
		(net "GND")
	)
	(via
		(at 101.91115 -243.674392)
		(size 0.4064)
		(drill 0.2032)
		(layers "F.Cu" "B.Cu")
		(net "GND")
	)
	(via
		(at 361.124754 -251.774198)
		(size 0.4064)
		(drill 0.2032)
		(layers "F.Cu" "B.Cu")
		(net "GND")
	)
	(via
		(at 446.644268 -278.93518)
		(size 0.4826)
		(drill 0.254)
		(layers "F.Cu" "B.Cu")
		(net "GND")
	)
	(via
		(at 92.340938 -334.108044)
		(size 0.49022)
		(drill 0.254)
		(layers "F.Cu" "B.Cu")
		(net "GND")
	)
	(via
		(at 127.114808 -282.996386)
		(size 0.4064)
		(drill 0.2032)
		(layers "F.Cu" "B.Cu")
		(net "GND")
	)
	(via
		(at 167.090344 -343.122758)
		(size 0.508)
		(drill 0.254)
		(layers "F.Cu" "B.Cu")
		(net "GND")
	)
	(via
		(at 356.901242 -241.24412)
		(size 0.4064)
		(drill 0.2032)
		(layers "F.Cu" "B.Cu")
		(net "GND")
	)
	(via
		(at 271.974564 -295.510204)
		(size 0.4826)
		(drill 0.254)
		(layers "F.Cu" "B.Cu")
		(net "GND")
	)
	(via
		(at 355.791008 -287.046162)
		(size 0.4064)
		(drill 0.2032)
		(layers "F.Cu" "B.Cu")
		(net "GND")
	)
	(via
		(at 88.111076 -293.52621)
		(size 0.4064)
		(drill 0.2032)
		(layers "F.Cu" "B.Cu")
		(net "GND")
	)
	(via
		(at 126.174754 -261.93623)
		(size 0.4064)
		(drill 0.2032)
		(layers "F.Cu" "B.Cu")
		(net "GND")
	)
	(via
		(at 363.944916 -227.474272)
		(size 0.4064)
		(drill 0.2032)
		(layers "F.Cu" "B.Cu")
		(net "GND")
	)
	(via
		(at 351.261172 -250.964192)
		(size 0.4064)
		(drill 0.2032)
		(layers "F.Cu" "B.Cu")
		(net "GND")
	)
	(via
		(at 310.662066 -392.999722)
		(size 0.4064)
		(drill 0.2032)
		(layers "F.Cu" "B.Cu")
		(net "GND")
	)
	(via
		(at 337.291934 -413.480504)
		(size 0.4572)
		(drill 0.254)
		(layers "F.Cu" "B.Cu")
		(net "GND")
	)
	(via
		(at 121.004838 -282.18638)
		(size 0.4064)
		(drill 0.2032)
		(layers "F.Cu" "B.Cu")
		(net "GND")
	)
	(via
		(at 156.96819 -99.155758)
		(size 0.508)
		(drill 0.254)
		(layers "F.Cu" "B.Cu")
		(net "GND")
	)
	(via
		(at 65.249806 -432.451256)
		(size 0.4572)
		(drill 0.2032)
		(layers "F.Cu" "B.Cu")
		(net "GND")
	)
	(via
		(at 59.391296 -390.160002)
		(size 0.4064)
		(drill 0.2032)
		(layers "F.Cu" "B.Cu")
		(net "GND")
	)
	(via
		(at 246.35587 -289.552126)
		(size 0.508)
		(drill 0.254)
		(layers "F.Cu" "B.Cu")
		(net "GND")
	)
	(via
		(at 324.739508 -333.838042)
		(size 0.49022)
		(drill 0.254)
		(layers "F.Cu" "B.Cu")
		(net "GND")
	)
	(via
		(at 41.430702 -383.027428)
		(size 0.508)
		(drill 0.254)
		(layers "F.Cu" "B.Cu")
		(net "GND")
	)
	(via
		(at 331.821028 -292.71595)
		(size 0.4064)
		(drill 0.2032)
		(layers "F.Cu" "B.Cu")
		(net "GND")
	)
	(via
		(at 453.797924 -58.150252)
		(size 0.6604)
		(drill 0.3302)
		(layers "F.Cu" "B.Cu")
		(net "GND")
	)
	(via
		(at 137.670794 -409.396184)
		(size 0.4572)
		(drill 0.254)
		(layers "F.Cu" "B.Cu")
		(net "GND")
	)
	(via
		(at 393.312142 -415.38652)
		(size 0.4064)
		(drill 0.2032)
		(layers "F.Cu" "B.Cu")
		(net "GND")
	)
	(via
		(at 375.41835 -396.710662)
		(size 0.4064)
		(drill 0.2032)
		(layers "F.Cu" "B.Cu")
		(net "GND")
	)
	(via
		(at 268.530578 -285.310072)
		(size 0.4826)
		(drill 0.254)
		(layers "F.Cu" "B.Cu")
		(net "GND")
	)
	(via
		(at 450.088 -214.335106)
		(size 0.4826)
		(drill 0.254)
		(layers "F.Cu" "B.Cu")
		(net "GND")
	)
	(via
		(at 87.168228 -148.94941)
		(size 0.508)
		(drill 0.254)
		(layers "F.Cu" "B.Cu")
		(net "GND")
	)
	(via
		(at 112.09528 -77.25918)
		(size 0.508)
		(drill 0.254)
		(layers "F.Cu" "B.Cu")
		(net "GND")
	)
	(via
		(at 121.944638 -283.806392)
		(size 0.4064)
		(drill 0.2032)
		(layers "F.Cu" "B.Cu")
		(net "GND")
	)
	(via
		(at 25.394412 -389.4201)
		(size 0.49022)
		(drill 0.254)
		(layers "F.Cu" "B.Cu")
		(net "GND")
	)
	(via
		(at 450.83476 -423.935398)
		(size 0.508)
		(drill 0.254)
		(layers "F.Cu" "B.Cu")
		(net "GND")
	)
	(via
		(at 312.978292 -394.831062)
		(size 0.4064)
		(drill 0.2032)
		(layers "F.Cu" "B.Cu")
		(net "GND")
	)
	(via
		(at 56.454294 -370.83873)
		(size 0.508)
		(drill 0.254)
		(layers "F.Cu" "B.Cu")
		(net "GND")
	)
	(via
		(at 212.493098 -329.014582)
		(size 0.508)
		(drill 0.254)
		(layers "F.Cu" "B.Cu")
		(net "GND")
	)
	(via
		(at 122.884692 -265.98626)
		(size 0.4064)
		(drill 0.2032)
		(layers "F.Cu" "B.Cu")
		(net "GND")
	)
	(via
		(at 341.01532 -362.01096)
		(size 0.508)
		(drill 0.254)
		(layers "F.Cu" "B.Cu")
		(net "GND")
	)
	(via
		(at 138.929618 -407.638504)
		(size 0.4572)
		(drill 0.254)
		(layers "F.Cu" "B.Cu")
		(net "GND")
	)
	(via
		(at 381.804926 -229.094284)
		(size 0.4064)
		(drill 0.2032)
		(layers "F.Cu" "B.Cu")
		(net "GND")
	)
	(via
		(at 128.694688 -242.864386)
		(size 0.4064)
		(drill 0.2032)
		(layers "F.Cu" "B.Cu")
		(net "GND")
	)
	(via
		(at 35.411664 -305.285394)
		(size 0.4826)
		(drill 0.254)
		(layers "F.Cu" "B.Cu")
		(net "GND")
	)
	(via
		(at 86.701122 -286.23641)
		(size 0.4064)
		(drill 0.2032)
		(layers "F.Cu" "B.Cu")
		(net "GND")
	)
	(via
		(at 21.70811 -267.03528)
		(size 0.4826)
		(drill 0.254)
		(layers "F.Cu" "B.Cu")
		(net "GND")
	)
	(via
		(at 374.932702 -418.412168)
		(size 0.4064)
		(drill 0.2032)
		(layers "F.Cu" "B.Cu")
		(net "GND")
	)
	(via
		(at 218.079574 -385.716272)
		(size 0.508)
		(drill 0.254)
		(layers "F.Cu" "B.Cu")
		(net "GND")
	)
	(via
		(at 437.715914 -295.935146)
		(size 0.4826)
		(drill 0.254)
		(layers "F.Cu" "B.Cu")
		(net "GND")
	)
	(via
		(at 368.643662 -29.504132)
		(size 0.508)
		(drill 0.254)
		(layers "F.Cu" "B.Cu")
		(net "GND")
	)
	(via
		(at 362.534708 -233.14406)
		(size 0.4064)
		(drill 0.2032)
		(layers "F.Cu" "B.Cu")
		(net "GND")
	)
	(via
		(at 312.00217 -362.601256)
		(size 0.508)
		(drill 0.254)
		(layers "F.Cu" "B.Cu")
		(net "GND")
	)
	(via
		(at 450.088 -292.535102)
		(size 0.4826)
		(drill 0.254)
		(layers "F.Cu" "B.Cu")
		(net "GND")
	)
	(via
		(at 307.368194 -306.985162)
		(size 0.4826)
		(drill 0.254)
		(layers "F.Cu" "B.Cu")
		(net "GND")
	)
	(via
		(at 25.152096 -206.685388)
		(size 0.4826)
		(drill 0.254)
		(layers "F.Cu" "B.Cu")
		(net "GND")
	)
	(via
		(at 304.652426 -210.085178)
		(size 0.4826)
		(drill 0.254)
		(layers "F.Cu" "B.Cu")
		(net "GND")
	)
	(via
		(at 329.941174 -278.136096)
		(size 0.4064)
		(drill 0.2032)
		(layers "F.Cu" "B.Cu")
		(net "GND")
	)
	(via
		(at 51.918616 -403.830536)
		(size 0.4572)
		(drill 0.254)
		(layers "F.Cu" "B.Cu")
		(net "GND")
	)
	(via
		(at 169.645584 -238.560356)
		(size 0.4826)
		(drill 0.254)
		(layers "F.Cu" "B.Cu")
		(net "GND")
	)
	(via
		(at 347.97111 -237.19409)
		(size 0.4064)
		(drill 0.2032)
		(layers "F.Cu" "B.Cu")
		(net "GND")
	)
	(via
		(at 351.406968 -341.922862)
		(size 0.49022)
		(drill 0.254)
		(layers "F.Cu" "B.Cu")
		(net "GND")
	)
	(via
		(at 324.651624 -74.184764)
		(size 0.508)
		(drill 0.254)
		(layers "F.Cu" "B.Cu")
		(net "GND")
	)
	(via
		(at 49.430178 -6.598158)
		(size 0.508)
		(drill 0.254)
		(layers "F.Cu" "B.Cu")
		(net "GND")
	)
	(via
		(at 414.754822 -415.38652)
		(size 0.4064)
		(drill 0.2032)
		(layers "F.Cu" "B.Cu")
		(net "GND")
	)
	(via
		(at 416.644328 -391.23493)
		(size 0.4064)
		(drill 0.2032)
		(layers "F.Cu" "B.Cu")
		(net "GND")
	)
	(via
		(at 90.461084 -266.796266)
		(size 0.4064)
		(drill 0.2032)
		(layers "F.Cu" "B.Cu")
		(net "GND")
	)
	(via
		(at 24.034496 -202.010264)
		(size 0.4826)
		(drill 0.254)
		(layers "F.Cu" "B.Cu")
		(net "GND")
	)
	(via
		(at 456.171046 -52.21732)
		(size 0.508)
		(drill 0.254)
		(layers "F.Cu" "B.Cu")
		(net "GND")
	)
	(via
		(at 85.291168 -287.04667)
		(size 0.4064)
		(drill 0.2032)
		(layers "F.Cu" "B.Cu")
		(net "GND")
	)
	(via
		(at 338.101178 -238.004096)
		(size 0.4064)
		(drill 0.2032)
		(layers "F.Cu" "B.Cu")
		(net "GND")
	)
	(via
		(at 325.24954 -436.051198)
		(size 0.4572)
		(drill 0.2032)
		(layers "F.Cu" "B.Cu")
		(net "GND")
	)
	(via
		(at 288.922968 -428.05096)
		(size 0.508)
		(drill 0.254)
		(layers "F.Cu" "B.Cu")
		(net "GND")
	)
	(via
		(at 133.348222 -17.654778)
		(size 0.508)
		(drill 0.254)
		(layers "F.Cu" "B.Cu")
		(net "GND")
	)
	(via
		(at 451.833996 -65.226946)
		(size 0.508)
		(drill 0.254)
		(layers "F.Cu" "B.Cu")
		(net "GND")
	)
	(via
		(at 349.704152 -337.99526)
		(size 0.49022)
		(drill 0.254)
		(layers "F.Cu" "B.Cu")
		(net "GND")
	)
	(via
		(at 366.8268 -389.44296)
		(size 0.508)
		(drill 0.254)
		(layers "F.Cu" "B.Cu")
		(net "GND")
	)
	(via
		(at 373.344694 -222.614236)
		(size 0.4064)
		(drill 0.2032)
		(layers "F.Cu" "B.Cu")
		(net "GND")
	)
	(via
		(at 21.70811 -251.735336)
		(size 0.4826)
		(drill 0.254)
		(layers "F.Cu" "B.Cu")
		(net "GND")
	)
	(via
		(at 329.6412 -229.904036)
		(size 0.4064)
		(drill 0.2032)
		(layers "F.Cu" "B.Cu")
		(net "GND")
	)
	(via
		(at 292.280086 -308.685184)
		(size 0.4826)
		(drill 0.254)
		(layers "F.Cu" "B.Cu")
		(net "GND")
	)
	(via
		(at 90.16111 -223.424496)
		(size 0.4064)
		(drill 0.2032)
		(layers "F.Cu" "B.Cu")
		(net "GND")
	)
	(via
		(at 353.607878 -253.392178)
		(size 0.4064)
		(drill 0.2032)
		(layers "F.Cu" "B.Cu")
		(net "GND")
	)
	(via
		(at 105.671112 -243.674392)
		(size 0.4064)
		(drill 0.2032)
		(layers "F.Cu" "B.Cu")
		(net "GND")
	)
	(via
		(at 441.86856 -435.199282)
		(size 0.508)
		(drill 0.254)
		(layers "F.Cu" "B.Cu")
		(net "GND")
	)
	(via
		(at 61.469524 -404.46452)
		(size 0.4064)
		(drill 0.2032)
		(layers "F.Cu" "B.Cu")
		(net "GND")
	)
	(via
		(at 421.029638 -202.01001)
		(size 0.4826)
		(drill 0.254)
		(layers "F.Cu" "B.Cu")
		(net "GND")
	)
	(via
		(at 78.711044 -270.846296)
		(size 0.4064)
		(drill 0.2032)
		(layers "F.Cu" "B.Cu")
		(net "GND")
	)
	(via
		(at 378.04471 -233.954066)
		(size 0.4064)
		(drill 0.2032)
		(layers "F.Cu" "B.Cu")
		(net "GND")
	)
	(via
		(at 418.36594 -110.280958)
		(size 0.508)
		(drill 0.254)
		(layers "F.Cu" "B.Cu")
		(net "GND")
	)
	(via
		(at 392.349482 -437.34736)
		(size 0.4572)
		(drill 0.2032)
		(layers "F.Cu" "B.Cu")
		(net "GND")
	)
	(via
		(at 222.965518 -279.643078)
		(size 0.508)
		(drill 0.254)
		(layers "F.Cu" "B.Cu")
		(net "GND")
	)
	(via
		(at 140.274802 -266.796266)
		(size 0.4064)
		(drill 0.2032)
		(layers "F.Cu" "B.Cu")
		(net "GND")
	)
	(via
		(at 167.994584 -368.37493)
		(size 0.508)
		(drill 0.254)
		(layers "F.Cu" "B.Cu")
		(net "GND")
	)
	(via
		(at 439.100214 -243.234972)
		(size 0.4826)
		(drill 0.254)
		(layers "F.Cu" "B.Cu")
		(net "GND")
	)
	(via
		(at 155.777438 -413.204152)
		(size 0.4572)
		(drill 0.254)
		(layers "F.Cu" "B.Cu")
		(net "GND")
	)
	(via
		(at 278.504142 -123.035314)
		(size 0.508)
		(drill 0.254)
		(layers "F.Cu" "B.Cu")
		(net "GND")
	)
	(via
		(at 436.852822 -407.17216)
		(size 0.508)
		(drill 0.254)
		(layers "F.Cu" "B.Cu")
		(net "GND")
	)
	(via
		(at 330.064364 -397.485108)
		(size 0.508)
		(drill 0.254)
		(layers "F.Cu" "B.Cu")
		(net "GND")
	)
	(via
		(at 81.701132 -247.724422)
		(size 0.4064)
		(drill 0.2032)
		(layers "F.Cu" "B.Cu")
		(net "GND")
	)
	(via
		(at 351.731072 -250.154186)
		(size 0.4064)
		(drill 0.2032)
		(layers "F.Cu" "B.Cu")
		(net "GND")
	)
	(via
		(at 342.801194 -250.964192)
		(size 0.4064)
		(drill 0.2032)
		(layers "F.Cu" "B.Cu")
		(net "GND")
	)
	(via
		(at 173.20133 -20.881848)
		(size 0.508)
		(drill 0.254)
		(layers "F.Cu" "B.Cu")
		(net "GND")
	)
	(via
		(at 342.749124 -334.625442)
		(size 0.49022)
		(drill 0.254)
		(layers "F.Cu" "B.Cu")
		(net "GND")
	)
	(via
		(at 442.767466 -397.148812)
		(size 0.6604)
		(drill 0.3302)
		(layers "F.Cu" "B.Cu")
		(net "GND")
	)
	(via
		(at 427.42104 -384.090926)
		(size 0.508)
		(drill 0.254)
		(layers "F.Cu" "B.Cu")
		(net "GND")
	)
	(via
		(at 317.46952 -336.983578)
		(size 0.49022)
		(drill 0.254)
		(layers "F.Cu" "B.Cu")
		(net "GND")
	)
	(via
		(at 67.609466 -170.078654)
		(size 0.49022)
		(drill 0.254)
		(layers "F.Cu" "B.Cu")
		(net "GND")
	)
	(via
		(at 21.70811 -248.335292)
		(size 0.4826)
		(drill 0.254)
		(layers "F.Cu" "B.Cu")
		(net "GND")
	)
	(via
		(at 102.681024 -289.47618)
		(size 0.4064)
		(drill 0.2032)
		(layers "F.Cu" "B.Cu")
		(net "GND")
	)
	(via
		(at 117.316504 -382.85293)
		(size 0.4064)
		(drill 0.2032)
		(layers "F.Cu" "B.Cu")
		(net "GND")
	)
	(via
		(at 459.158594 -45.233082)
		(size 0.508)
		(drill 0.254)
		(layers "F.Cu" "B.Cu")
		(net "GND")
	)
	(via
		(at 99.561142 -242.864386)
		(size 0.4064)
		(drill 0.2032)
		(layers "F.Cu" "B.Cu")
		(net "GND")
	)
	(via
		(at 104.090978 -270.846296)
		(size 0.4064)
		(drill 0.2032)
		(layers "F.Cu" "B.Cu")
		(net "GND")
	)
	(via
		(at 375.524776 -280.566114)
		(size 0.4064)
		(drill 0.2032)
		(layers "F.Cu" "B.Cu")
		(net "GND")
	)
	(via
		(at 402.86178 -176.99482)
		(size 0.508)
		(drill 0.254)
		(layers "F.Cu" "B.Cu")
		(net "GND")
	)
	(via
		(at 173.08957 -230.0605)
		(size 0.4826)
		(drill 0.254)
		(layers "F.Cu" "B.Cu")
		(net "GND")
	)
	(via
		(at 350.172528 -341.922862)
		(size 0.49022)
		(drill 0.254)
		(layers "F.Cu" "B.Cu")
		(net "GND")
	)
	(via
		(at 121.474738 -278.13635)
		(size 0.4064)
		(drill 0.2032)
		(layers "F.Cu" "B.Cu")
		(net "GND")
	)
	(via
		(at 381.804926 -233.954066)
		(size 0.4064)
		(drill 0.2032)
		(layers "F.Cu" "B.Cu")
		(net "GND")
	)
	(via
		(at 191.148716 -329.500484)
		(size 0.6604)
		(drill 0.3302)
		(layers "F.Cu" "B.Cu")
		(net "GND")
	)
	(via
		(at 360.337862 -256.387346)
		(size 0.4826)
		(drill 0.254)
		(layers "F.Cu" "B.Cu")
		(net "GND")
	)
	(via
		(at 98.046286 -388.328662)
		(size 0.4064)
		(drill 0.2032)
		(layers "F.Cu" "B.Cu")
		(net "GND")
	)
	(via
		(at 63.062358 -384.617722)
		(size 0.4064)
		(drill 0.2032)
		(layers "F.Cu" "B.Cu")
		(net "GND")
	)
	(via
		(at 427.709584 -350.20631)
		(size 0.49022)
		(drill 0.254)
		(layers "F.Cu" "B.Cu")
		(net "GND")
	)
	(via
		(at 72.663304 -12.37488)
		(size 0.508)
		(drill 0.254)
		(layers "F.Cu" "B.Cu")
		(net "GND")
	)
	(via
		(at 430.553876 -16.9799)
		(size 0.508)
		(drill 0.254)
		(layers "F.Cu" "B.Cu")
		(net "GND")
	)
	(via
		(at 183.616092 -215.185244)
		(size 0.4826)
		(drill 0.254)
		(layers "F.Cu" "B.Cu")
		(net "GND")
	)
	(via
		(at 92.340938 -268.416278)
		(size 0.4064)
		(drill 0.2032)
		(layers "F.Cu" "B.Cu")
		(net "GND")
	)
	(via
		(at 146.792442 -385.87553)
		(size 0.4064)
		(drill 0.2032)
		(layers "F.Cu" "B.Cu")
		(net "GND")
	)
	(via
		(at 334.811116 -250.154186)
		(size 0.4064)
		(drill 0.2032)
		(layers "F.Cu" "B.Cu")
		(net "GND")
	)
	(via
		(at 90.63101 -224.234502)
		(size 0.4064)
		(drill 0.2032)
		(layers "F.Cu" "B.Cu")
		(net "GND")
	)
	(via
		(at 44.340018 -244.935248)
		(size 0.4826)
		(drill 0.254)
		(layers "F.Cu" "B.Cu")
		(net "GND")
	)
	(via
		(at 50.216562 -391.830814)
		(size 0.4064)
		(drill 0.2032)
		(layers "F.Cu" "B.Cu")
		(net "GND")
	)
	(via
		(at 79.651098 -293.52621)
		(size 0.4064)
		(drill 0.2032)
		(layers "F.Cu" "B.Cu")
		(net "GND")
	)
	(via
		(at 303.816258 -391.23493)
		(size 0.4064)
		(drill 0.2032)
		(layers "F.Cu" "B.Cu")
		(net "GND")
	)
	(via
		(at 118.354856 -234.764326)
		(size 0.4064)
		(drill 0.2032)
		(layers "F.Cu" "B.Cu")
		(net "GND")
	)
	(via
		(at 152.986994 -406.370536)
		(size 0.4572)
		(drill 0.254)
		(layers "F.Cu" "B.Cu")
		(net "GND")
	)
	(via
		(at 391.974832 -284.616144)
		(size 0.4064)
		(drill 0.2032)
		(layers "F.Cu" "B.Cu")
		(net "GND")
	)
	(via
		(at 69.581014 -368.37493)
		(size 0.508)
		(drill 0.254)
		(layers "F.Cu" "B.Cu")
		(net "GND")
	)
	(via
		(at 13.038582 -416.812984)
		(size 0.508)
		(drill 0.254)
		(layers "F.Cu" "B.Cu")
		(net "GND")
	)
	(via
		(at 145.349722 -434.899562)
		(size 0.4572)
		(drill 0.2032)
		(layers "F.Cu" "B.Cu")
		(net "GND")
	)
	(via
		(at 79.487776 -411.936184)
		(size 0.4572)
		(drill 0.254)
		(layers "F.Cu" "B.Cu")
		(net "GND")
	)
	(via
		(at 117.44071 -258.38023)
		(size 0.4826)
		(drill 0.254)
		(layers "F.Cu" "B.Cu")
		(net "GND")
	)
	(via
		(at 118.932706 -410.030168)
		(size 0.4064)
		(drill 0.2032)
		(layers "F.Cu" "B.Cu")
		(net "GND")
	)
	(via
		(at 88.677496 -411.936184)
		(size 0.4572)
		(drill 0.254)
		(layers "F.Cu" "B.Cu")
		(net "GND")
	)
	(via
		(at 49.016412 -393.902438)
		(size 0.4572)
		(drill 0.254)
		(layers "F.Cu" "B.Cu")
		(net "GND")
	)
	(via
		(at 401.349718 -428.851314)
		(size 0.4572)
		(drill 0.2032)
		(layers "F.Cu" "B.Cu")
		(net "GND")
	)
	(via
		(at 423.803064 -152.388824)
		(size 0.508)
		(drill 0.254)
		(layers "F.Cu" "B.Cu")
		(net "GND")
	)
	(via
		(at 422.627806 -227.935028)
		(size 0.4826)
		(drill 0.254)
		(layers "F.Cu" "B.Cu")
		(net "GND")
	)
	(via
		(at 261.005066 -141.968728)
		(size 0.508)
		(drill 0.254)
		(layers "F.Cu" "B.Cu")
		(net "GND")
	)
	(via
		(at 90.209116 -406.370536)
		(size 0.4572)
		(drill 0.254)
		(layers "F.Cu" "B.Cu")
		(net "GND")
	)
	(via
		(at 337.019138 -419.046152)
		(size 0.4572)
		(drill 0.254)
		(layers "F.Cu" "B.Cu")
		(net "GND")
	)
	(via
		(at 97.144332 -391.830814)
		(size 0.4064)
		(drill 0.2032)
		(layers "F.Cu" "B.Cu")
		(net "GND")
	)
	(via
		(at 218.783154 -15.664688)
		(size 0.508)
		(drill 0.254)
		(layers "F.Cu" "B.Cu")
		(net "GND")
	)
	(via
		(at 86.701122 -274.896326)
		(size 0.4064)
		(drill 0.2032)
		(layers "F.Cu" "B.Cu")
		(net "GND")
	)
	(via
		(at 146.122644 -391.77595)
		(size 0.4064)
		(drill 0.2032)
		(layers "F.Cu" "B.Cu")
		(net "GND")
	)
	(via
		(at 379.525022 -412.84652)
		(size 0.4064)
		(drill 0.2032)
		(layers "F.Cu" "B.Cu")
		(net "GND")
	)
	(via
		(at 273.092164 -269.585186)
		(size 0.4826)
		(drill 0.254)
		(layers "F.Cu" "B.Cu")
		(net "GND")
	)
	(via
		(at 126.34468 -256.634488)
		(size 0.4064)
		(drill 0.2032)
		(layers "F.Cu" "B.Cu")
		(net "GND")
	)
	(via
		(at 126.916434 -391.830814)
		(size 0.4064)
		(drill 0.2032)
		(layers "F.Cu" "B.Cu")
		(net "GND")
	)
	(via
		(at 163.486846 -171.394374)
		(size 0.508)
		(drill 0.254)
		(layers "F.Cu" "B.Cu")
		(net "GND")
	)
	(via
		(at 121.48693 -32.51708)
		(size 0.508)
		(drill 0.254)
		(layers "F.Cu" "B.Cu")
		(net "GND")
	)
	(via
		(at 154.726386 -315.019436)
		(size 0.508)
		(drill 0.254)
		(layers "F.Cu" "B.Cu")
		(net "GND")
	)
	(via
		(at 138.864848 -287.046416)
		(size 0.4064)
		(drill 0.2032)
		(layers "F.Cu" "B.Cu")
		(net "GND")
	)
	(via
		(at 73.29805 -381.3302)
		(size 0.508)
		(drill 0.254)
		(layers "F.Cu" "B.Cu")
		(net "GND")
	)
	(via
		(at 137.45464 -266.796266)
		(size 0.4064)
		(drill 0.2032)
		(layers "F.Cu" "B.Cu")
		(net "GND")
	)
	(via
		(at 87.811102 -224.234502)
		(size 0.4064)
		(drill 0.2032)
		(layers "F.Cu" "B.Cu")
		(net "GND")
	)
	(via
		(at 113.184686 -230.71455)
		(size 0.4064)
		(drill 0.2032)
		(layers "F.Cu" "B.Cu")
		(net "GND")
	)
	(via
		(at 188.731906 -417.404804)
		(size 0.508)
		(drill 0.254)
		(layers "F.Cu" "B.Cu")
		(net "GND")
	)
	(via
		(at 59.428126 -306.985416)
		(size 0.4826)
		(drill 0.254)
		(layers "F.Cu" "B.Cu")
		(net "GND")
	)
	(via
		(at 42.955718 -302.735234)
		(size 0.4826)
		(drill 0.254)
		(layers "F.Cu" "B.Cu")
		(net "GND")
	)
	(via
		(at 67.234816 -405.098504)
		(size 0.4572)
		(drill 0.254)
		(layers "F.Cu" "B.Cu")
		(net "GND")
	)
	(via
		(at 326.351138 -243.674138)
		(size 0.4064)
		(drill 0.2032)
		(layers "F.Cu" "B.Cu")
		(net "GND")
	)
	(via
		(at 55.328058 -234.73537)
		(size 0.4826)
		(drill 0.254)
		(layers "F.Cu" "B.Cu")
		(net "GND")
	)
	(via
		(at 334.283304 -376.75693)
		(size 0.508)
		(drill 0.254)
		(layers "F.Cu" "B.Cu")
		(net "GND")
	)
	(via
		(at 367.639092 -379.88113)
		(size 0.508)
		(drill 0.254)
		(layers "F.Cu" "B.Cu")
		(net "GND")
	)
	(via
		(at 389.79475 -228.284278)
		(size 0.4064)
		(drill 0.2032)
		(layers "F.Cu" "B.Cu")
		(net "GND")
	)
	(via
		(at 163.435538 -409.396184)
		(size 0.4572)
		(drill 0.254)
		(layers "F.Cu" "B.Cu")
		(net "GND")
	)
	(via
		(at 106.91114 -295.146222)
		(size 0.4064)
		(drill 0.2032)
		(layers "F.Cu" "B.Cu")
		(net "GND")
	)
	(via
		(at 145.349722 -438.499758)
		(size 0.4572)
		(drill 0.2032)
		(layers "F.Cu" "B.Cu")
		(net "GND")
	)
	(via
		(at 351.024952 -338.784438)
		(size 0.49022)
		(drill 0.254)
		(layers "F.Cu" "B.Cu")
		(net "GND")
	)
	(via
		(at 40.23995 -206.685388)
		(size 0.4826)
		(drill 0.254)
		(layers "F.Cu" "B.Cu")
		(net "GND")
	)
	(via
		(at 329.911964 -333.039212)
		(size 0.508)
		(drill 0.254)
		(layers "F.Cu" "B.Cu")
		(net "GND")
	)
	(via
		(at 245.59387 -292.041326)
		(size 0.508)
		(drill 0.254)
		(layers "F.Cu" "B.Cu")
		(net "GND")
	)
	(via
		(at 240.740692 -421.833548)
		(size 0.508)
		(drill 0.254)
		(layers "F.Cu" "B.Cu")
		(net "GND")
	)
	(via
		(at 120.550178 -406.370536)
		(size 0.4572)
		(drill 0.254)
		(layers "F.Cu" "B.Cu")
		(net "GND")
	)
	(via
		(at 450.088 -217.73515)
		(size 0.4826)
		(drill 0.254)
		(layers "F.Cu" "B.Cu")
		(net "GND")
	)
	(via
		(at 127.284734 -238.814356)
		(size 0.4064)
		(drill 0.2032)
		(layers "F.Cu" "B.Cu")
		(net "GND")
	)
	(via
		(at 113.184686 -246.914416)
		(size 0.4064)
		(drill 0.2032)
		(layers "F.Cu" "B.Cu")
		(net "GND")
	)
	(via
		(at 351.645982 -396.710662)
		(size 0.4064)
		(drill 0.2032)
		(layers "F.Cu" "B.Cu")
		(net "GND")
	)
	(via
		(at 126.34976 -426.69968)
		(size 0.4572)
		(drill 0.2032)
		(layers "F.Cu" "B.Cu")
		(net "GND")
	)
	(via
		(at 131.544314 -406.370536)
		(size 0.4572)
		(drill 0.254)
		(layers "F.Cu" "B.Cu")
		(net "GND")
	)
	(via
		(at 76.249784 -427.851316)
		(size 0.4572)
		(drill 0.2032)
		(layers "F.Cu" "B.Cu")
		(net "GND")
	)
	(via
		(at 311.966356 -383.00533)
		(size 0.508)
		(drill 0.254)
		(layers "F.Cu" "B.Cu")
		(net "GND")
	)
	(via
		(at 130.87477 -284.616398)
		(size 0.4064)
		(drill 0.2032)
		(layers "F.Cu" "B.Cu")
		(net "GND")
	)
	(via
		(at 417.585652 -238.560102)
		(size 0.4826)
		(drill 0.254)
		(layers "F.Cu" "B.Cu")
		(net "GND")
	)
	(via
		(at 336.991198 -269.22603)
		(size 0.4064)
		(drill 0.2032)
		(layers "F.Cu" "B.Cu")
		(net "GND")
	)
	(via
		(at 386.504942 -256.634234)
		(size 0.4064)
		(drill 0.2032)
		(layers "F.Cu" "B.Cu")
		(net "GND")
	)
	(via
		(at 43.85818 -12.37488)
		(size 0.508)
		(drill 0.254)
		(layers "F.Cu" "B.Cu")
		(net "GND")
	)
	(via
		(at 339.943948 -391.23493)
		(size 0.4064)
		(drill 0.2032)
		(layers "F.Cu" "B.Cu")
		(net "GND")
	)
	(via
		(at 88.16594 -355.171248)
		(size 0.508)
		(drill 0.254)
		(layers "F.Cu" "B.Cu")
		(net "GND")
	)
	(via
		(at 90.461084 -274.896326)
		(size 0.4064)
		(drill 0.2032)
		(layers "F.Cu" "B.Cu")
		(net "GND")
	)
	(via
		(at 140.54836 -17.654778)
		(size 0.508)
		(drill 0.254)
		(layers "F.Cu" "B.Cu")
		(net "GND")
	)
	(via
		(at 35.411664 -284.035246)
		(size 0.4826)
		(drill 0.254)
		(layers "F.Cu" "B.Cu")
		(net "GND")
	)
	(via
		(at 391.204704 -255.014222)
		(size 0.4064)
		(drill 0.2032)
		(layers "F.Cu" "B.Cu")
		(net "GND")
	)
	(via
		(at 218.076018 -386.439664)
		(size 0.508)
		(drill 0.254)
		(layers "F.Cu" "B.Cu")
		(net "GND")
	)
	(via
		(at 149.492716 -58.236358)
		(size 0.508)
		(drill 0.254)
		(layers "F.Cu" "B.Cu")
		(net "GND")
	)
	(via
		(at 295.218866 -344.767408)
		(size 0.508)
		(drill 0.254)
		(layers "F.Cu" "B.Cu")
		(net "GND")
	)
	(via
		(at 52.241958 -345.571064)
		(size 0.49022)
		(drill 0.254)
		(layers "F.Cu" "B.Cu")
		(net "GND")
	)
	(via
		(at 187.060078 -266.185396)
		(size 0.4826)
		(drill 0.254)
		(layers "F.Cu" "B.Cu")
		(net "GND")
	)
	(via
		(at 21.879306 -5.597398)
		(size 0.508)
		(drill 0.254)
		(layers "F.Cu" "B.Cu")
		(net "GND")
	)
	(via
		(at 107.425744 -57.949338)
		(size 0.508)
		(drill 0.254)
		(layers "F.Cu" "B.Cu")
		(net "GND")
	)
	(via
		(at 79.760572 -409.396184)
		(size 0.4572)
		(drill 0.254)
		(layers "F.Cu" "B.Cu")
		(net "GND")
	)
	(via
		(at 35.678364 -285.310326)
		(size 0.4826)
		(drill 0.254)
		(layers "F.Cu" "B.Cu")
		(net "GND")
	)
	(via
		(at 123.524772 -246.914416)
		(size 0.4064)
		(drill 0.2032)
		(layers "F.Cu" "B.Cu")
		(net "GND")
	)
	(via
		(at 383.21488 -249.34418)
		(size 0.4064)
		(drill 0.2032)
		(layers "F.Cu" "B.Cu")
		(net "GND")
	)
	(via
		(at 179.516024 -234.73537)
		(size 0.4826)
		(drill 0.254)
		(layers "F.Cu" "B.Cu")
		(net "GND")
	)
	(via
		(at 322.061586 -415.38652)
		(size 0.4064)
		(drill 0.2032)
		(layers "F.Cu" "B.Cu")
		(net "GND")
	)
	(via
		(at 173.35627 -306.135278)
		(size 0.4826)
		(drill 0.254)
		(layers "F.Cu" "B.Cu")
		(net "GND")
	)
	(via
		(at 83.111086 -250.15444)
		(size 0.4064)
		(drill 0.2032)
		(layers "F.Cu" "B.Cu")
		(net "GND")
	)
	(via
		(at 306.216304 -400.212814)
		(size 0.4064)
		(drill 0.2032)
		(layers "F.Cu" "B.Cu")
		(net "GND")
	)
	(via
		(at 19.392138 -18.5039)
		(size 0.508)
		(drill 0.254)
		(layers "F.Cu" "B.Cu")
		(net "GND")
	)
	(via
		(at 183.616092 -222.835216)
		(size 0.4826)
		(drill 0.254)
		(layers "F.Cu" "B.Cu")
		(net "GND")
	)
	(via
		(at 206.063088 -351.219008)
		(size 0.508)
		(drill 0.254)
		(layers "F.Cu" "B.Cu")
		(net "GND")
	)
	(via
		(at 368.644678 -224.234248)
		(size 0.4064)
		(drill 0.2032)
		(layers "F.Cu" "B.Cu")
		(net "GND")
	)
	(via
		(at 332.338426 -415.38652)
		(size 0.4064)
		(drill 0.2032)
		(layers "F.Cu" "B.Cu")
		(net "GND")
	)
	(via
		(at 186.312048 -113.46307)
		(size 0.4572)
		(drill 0.254)
		(layers "F.Cu" "B.Cu")
		(net "GND")
	)
	(via
		(at 31.578296 -202.010264)
		(size 0.4826)
		(drill 0.254)
		(layers "F.Cu" "B.Cu")
		(net "GND")
	)
	(via
		(at 84.987892 -221.504764)
		(size 0.4064)
		(drill 0.2032)
		(layers "F.Cu" "B.Cu")
		(net "GND")
	)
	(via
		(at 101.91115 -246.914416)
		(size 0.4064)
		(drill 0.2032)
		(layers "F.Cu" "B.Cu")
		(net "GND")
	)
	(via
		(at 369.340892 -377.41733)
		(size 0.508)
		(drill 0.254)
		(layers "F.Cu" "B.Cu")
		(net "GND")
	)
	(via
		(at 57.071514 -344.137234)
		(size 0.508)
		(drill 0.254)
		(layers "F.Cu" "B.Cu")
		(net "GND")
	)
	(via
		(at 202.147932 -250.885198)
		(size 0.4826)
		(drill 0.254)
		(layers "F.Cu" "B.Cu")
		(net "GND")
	)
	(via
		(at 110.013496 -57.20207)
		(size 0.508)
		(drill 0.254)
		(layers "F.Cu" "B.Cu")
		(net "GND")
	)
	(via
		(at 418.599366 -440.412886)
		(size 0.508)
		(drill 0.254)
		(layers "F.Cu" "B.Cu")
		(net "GND")
	)
	(via
		(at 194.604132 -290.835334)
		(size 0.4826)
		(drill 0.254)
		(layers "F.Cu" "B.Cu")
		(net "GND")
	)
	(via
		(at 136.044686 -293.52621)
		(size 0.4064)
		(drill 0.2032)
		(layers "F.Cu" "B.Cu")
		(net "GND")
	)
	(via
		(at 161.170366 -171.42206)
		(size 0.508)
		(drill 0.254)
		(layers "F.Cu" "B.Cu")
		(net "GND")
	)
	(via
		(at 92.981018 -252.584458)
		(size 0.4064)
		(drill 0.2032)
		(layers "F.Cu" "B.Cu")
		(net "GND")
	)
	(via
		(at 419.430454 -346.39631)
		(size 0.6604)
		(drill 0.3302)
		(layers "F.Cu" "B.Cu")
		(net "GND")
	)
	(via
		(at 388.729474 -184.683146)
		(size 0.49022)
		(drill 0.254)
		(layers "F.Cu" "B.Cu")
		(net "GND")
	)
	(via
		(at 121.004838 -270.846296)
		(size 0.4064)
		(drill 0.2032)
		(layers "F.Cu" "B.Cu")
		(net "GND")
	)
	(via
		(at 127.116078 -166.04361)
		(size 0.49022)
		(drill 0.254)
		(layers "F.Cu" "B.Cu")
		(net "GND")
	)
	(via
		(at 88.580976 -284.616398)
		(size 0.4064)
		(drill 0.2032)
		(layers "F.Cu" "B.Cu")
		(net "GND")
	)
	(via
		(at 367.156492 -377.41733)
		(size 0.508)
		(drill 0.254)
		(layers "F.Cu" "B.Cu")
		(net "GND")
	)
	(via
		(at 88.496902 -371.49913)
		(size 0.508)
		(drill 0.254)
		(layers "F.Cu" "B.Cu")
		(net "GND")
	)
	(via
		(at 392.614912 -221.80423)
		(size 0.4064)
		(drill 0.2032)
		(layers "F.Cu" "B.Cu")
		(net "GND")
	)
	(via
		(at 409.391104 -18.503138)
		(size 0.508)
		(drill 0.254)
		(layers "F.Cu" "B.Cu")
		(net "GND")
	)
	(via
		(at 126.174754 -279.756362)
		(size 0.4064)
		(drill 0.2032)
		(layers "F.Cu" "B.Cu")
		(net "GND")
	)
	(via
		(at 120.43791 -167.776398)
		(size 0.508)
		(drill 0.254)
		(layers "F.Cu" "B.Cu")
		(net "GND")
	)
	(via
		(at 94.861126 -228.284532)
		(size 0.4064)
		(drill 0.2032)
		(layers "F.Cu" "B.Cu")
		(net "GND")
	)
	(via
		(at 344.211148 -250.154186)
		(size 0.4064)
		(drill 0.2032)
		(layers "F.Cu" "B.Cu")
		(net "GND")
	)
	(via
		(at 298.43984 -221.13494)
		(size 0.4826)
		(drill 0.254)
		(layers "F.Cu" "B.Cu")
		(net "GND")
	)
	(via
		(at 412.955486 -7.215124)
		(size 0.508)
		(drill 0.254)
		(layers "F.Cu" "B.Cu")
		(net "GND")
	)
	(via
		(at 87.106252 -386.449062)
		(size 0.4064)
		(drill 0.2032)
		(layers "F.Cu" "B.Cu")
		(net "GND")
	)
	(via
		(at 92.101924 -412.570168)
		(size 0.4064)
		(drill 0.2032)
		(layers "F.Cu" "B.Cu")
		(net "GND")
	)
	(via
		(at 127.114808 -266.796266)
		(size 0.4064)
		(drill 0.2032)
		(layers "F.Cu" "B.Cu")
		(net "GND")
	)
	(via
		(at 334.64119 -284.616144)
		(size 0.4064)
		(drill 0.2032)
		(layers "F.Cu" "B.Cu")
		(net "GND")
	)
	(via
		(at 63.579248 -170.20032)
		(size 0.508)
		(drill 0.254)
		(layers "F.Cu" "B.Cu")
		(net "GND")
	)
	(via
		(at 71.741284 -412.570168)
		(size 0.4064)
		(drill 0.2032)
		(layers "F.Cu" "B.Cu")
		(net "GND")
	)
	(via
		(at 413.044386 -402.309838)
		(size 0.4572)
		(drill 0.254)
		(layers "F.Cu" "B.Cu")
		(net "GND")
	)
	(via
		(at 454.188068 -216.885012)
		(size 0.4826)
		(drill 0.254)
		(layers "F.Cu" "B.Cu")
		(net "GND")
	)
	(via
		(at 21.70811 -272.98523)
		(size 0.4826)
		(drill 0.254)
		(layers "F.Cu" "B.Cu")
		(net "GND")
	)
	(via
		(at 126.955296 -369.03533)
		(size 0.508)
		(drill 0.254)
		(layers "F.Cu" "B.Cu")
		(net "GND")
	)
	(via
		(at 64.268096 -149.243288)
		(size 0.6604)
		(drill 0.3302)
		(layers "F.Cu" "B.Cu")
		(net "GND")
	)
	(via
		(at 311.563766 -343.472008)
		(size 0.508)
		(drill 0.254)
		(layers "F.Cu" "B.Cu")
		(net "GND")
	)
	(via
		(at 206.248 -265.335258)
		(size 0.4826)
		(drill 0.254)
		(layers "F.Cu" "B.Cu")
		(net "GND")
	)
	(via
		(at 92.340938 -294.336216)
		(size 0.4064)
		(drill 0.2032)
		(layers "F.Cu" "B.Cu")
		(net "GND")
	)
	(via
		(at 188.712094 -111.86287)
		(size 0.4572)
		(drill 0.254)
		(layers "F.Cu" "B.Cu")
		(net "GND")
	)
	(via
		(at 435.000146 -307.835046)
		(size 0.4826)
		(drill 0.254)
		(layers "F.Cu" "B.Cu")
		(net "GND")
	)
	(via
		(at 350.321118 -228.284278)
		(size 0.4064)
		(drill 0.2032)
		(layers "F.Cu" "B.Cu")
		(net "GND")
	)
	(via
		(at 350.151192 -269.22603)
		(size 0.4064)
		(drill 0.2032)
		(layers "F.Cu" "B.Cu")
		(net "GND")
	)
	(via
		(at 145.444718 -288.666174)
		(size 0.4064)
		(drill 0.2032)
		(layers "F.Cu" "B.Cu")
		(net "GND")
	)
	(via
		(at 163.168076 -33.317688)
		(size 0.508)
		(drill 0.254)
		(layers "F.Cu" "B.Cu")
		(net "GND")
	)
	(via
		(at 235.0008 -287.386522)
		(size 0.508)
		(drill 0.254)
		(layers "F.Cu" "B.Cu")
		(net "GND")
	)
	(via
		(at 347.50121 -249.34418)
		(size 0.4064)
		(drill 0.2032)
		(layers "F.Cu" "B.Cu")
		(net "GND")
	)
	(via
		(at 341.22106 -289.475926)
		(size 0.4064)
		(drill 0.2032)
		(layers "F.Cu" "B.Cu")
		(net "GND")
	)
	(via
		(at 337.234784 -334.559402)
		(size 0.49022)
		(drill 0.254)
		(layers "F.Cu" "B.Cu")
		(net "GND")
	)
	(via
		(at 59.428126 -301.035212)
		(size 0.4826)
		(drill 0.254)
		(layers "F.Cu" "B.Cu")
		(net "GND")
	)
	(via
		(at 359.206546 -12.542266)
		(size 0.508)
		(drill 0.254)
		(layers "F.Cu" "B.Cu")
		(net "GND")
	)
	(via
		(at 342.794844 -382.34493)
		(size 0.508)
		(drill 0.254)
		(layers "F.Cu" "B.Cu")
		(net "GND")
	)
	(via
		(at 288.180018 -318.885062)
		(size 0.4826)
		(drill 0.254)
		(layers "F.Cu" "B.Cu")
		(net "GND")
	)
	(via
		(at 280.635964 -311.23509)
		(size 0.4826)
		(drill 0.254)
		(layers "F.Cu" "B.Cu")
		(net "GND")
	)
	(via
		(at 192.277746 -294.66032)
		(size 0.4826)
		(drill 0.254)
		(layers "F.Cu" "B.Cu")
		(net "GND")
	)
	(via
		(at 365.615474 -178.92141)
		(size 0.49022)
		(drill 0.254)
		(layers "F.Cu" "B.Cu")
		(net "GND")
	)
	(via
		(at 319.416176 -391.23493)
		(size 0.4064)
		(drill 0.2032)
		(layers "F.Cu" "B.Cu")
		(net "GND")
	)
	(via
		(at 32.695896 -208.38541)
		(size 0.4826)
		(drill 0.254)
		(layers "F.Cu" "B.Cu")
		(net "GND")
	)
	(via
		(at 62.77991 -172.172884)
		(size 0.508)
		(drill 0.254)
		(layers "F.Cu" "B.Cu")
		(net "GND")
	)
	(via
		(at 367.064798 -270.846042)
		(size 0.4064)
		(drill 0.2032)
		(layers "F.Cu" "B.Cu")
		(net "GND")
	)
	(via
		(at 429.29683 -6.091174)
		(size 0.508)
		(drill 0.254)
		(layers "F.Cu" "B.Cu")
		(net "GND")
	)
	(via
		(at 329.361038 -413.480504)
		(size 0.4572)
		(drill 0.254)
		(layers "F.Cu" "B.Cu")
		(net "GND")
	)
	(via
		(at 239.014 -283.859478)
		(size 0.508)
		(drill 0.254)
		(layers "F.Cu" "B.Cu")
		(net "GND")
	)
	(via
		(at 70.428358 -333.060802)
		(size 0.49022)
		(drill 0.254)
		(layers "F.Cu" "B.Cu")
		(net "GND")
	)
	(via
		(at 82.249772 -439.651394)
		(size 0.4572)
		(drill 0.2032)
		(layers "F.Cu" "B.Cu")
		(net "GND")
	)
	(via
		(at 438.2516 -94.503748)
		(size 0.508)
		(drill 0.254)
		(layers "F.Cu" "B.Cu")
		(net "GND")
	)
	(via
		(at 85.614256 -413.204152)
		(size 0.4572)
		(drill 0.254)
		(layers "F.Cu" "B.Cu")
		(net "GND")
	)
	(via
		(at 115.534694 -228.284532)
		(size 0.4064)
		(drill 0.2032)
		(layers "F.Cu" "B.Cu")
		(net "GND")
	)
	(via
		(at 409.349702 -436.051198)
		(size 0.4572)
		(drill 0.2032)
		(layers "F.Cu" "B.Cu")
		(net "GND")
	)
	(via
		(at 403.090126 -392.999722)
		(size 0.4064)
		(drill 0.2032)
		(layers "F.Cu" "B.Cu")
		(net "GND")
	)
	(via
		(at 107.62742 -63.39078)
		(size 0.508)
		(drill 0.254)
		(layers "F.Cu" "B.Cu")
		(net "GND")
	)
	(via
		(at 71.938134 -380.535688)
		(size 0.508)
		(drill 0.254)
		(layers "F.Cu" "B.Cu")
		(net "GND")
	)
	(via
		(at 303.268126 -233.035094)
		(size 0.4826)
		(drill 0.254)
		(layers "F.Cu" "B.Cu")
		(net "GND")
	)
	(via
		(at 34.080196 -275.53539)
		(size 0.4826)
		(drill 0.254)
		(layers "F.Cu" "B.Cu")
		(net "GND")
	)
	(via
		(at 168.527984 -271.285208)
		(size 0.4826)
		(drill 0.254)
		(layers "F.Cu" "B.Cu")
		(net "GND")
	)
	(via
		(at 331.351128 -261.12597)
		(size 0.4064)
		(drill 0.2032)
		(layers "F.Cu" "B.Cu")
		(net "GND")
	)
	(via
		(at 315.24956 -431.451258)
		(size 0.4572)
		(drill 0.2032)
		(layers "F.Cu" "B.Cu")
		(net "GND")
	)
	(via
		(at 171.97197 -204.985366)
		(size 0.4826)
		(drill 0.254)
		(layers "F.Cu" "B.Cu")
		(net "GND")
	)
	(via
		(at 436.93334 -364.57382)
		(size 0.508)
		(drill 0.254)
		(layers "F.Cu" "B.Cu")
		(net "GND")
	)
	(via
		(at 324.75297 -247.990106)
		(size 0.4064)
		(drill 0.2032)
		(layers "F.Cu" "B.Cu")
		(net "GND")
	)
	(via
		(at 32.695896 -204.985366)
		(size 0.4826)
		(drill 0.254)
		(layers "F.Cu" "B.Cu")
		(net "GND")
	)
	(via
		(at 433.690776 -103.38943)
		(size 0.508)
		(drill 0.254)
		(layers "F.Cu" "B.Cu")
		(net "GND")
	)
	(via
		(at 405.546306 -396.710662)
		(size 0.4064)
		(drill 0.2032)
		(layers "F.Cu" "B.Cu")
		(net "GND")
	)
	(via
		(at 132.284724 -277.326344)
		(size 0.4064)
		(drill 0.2032)
		(layers "F.Cu" "B.Cu")
		(net "GND")
	)
	(via
		(at 289.564318 -221.985078)
		(size 0.4826)
		(drill 0.254)
		(layers "F.Cu" "B.Cu")
		(net "GND")
	)
	(via
		(at 360.86669 -396.1765)
		(size 0.508)
		(drill 0.254)
		(layers "F.Cu" "B.Cu")
		(net "GND")
	)
	(via
		(at 340.921086 -241.24412)
		(size 0.4064)
		(drill 0.2032)
		(layers "F.Cu" "B.Cu")
		(net "GND")
	)
	(via
		(at 446.644268 -255.135126)
		(size 0.4826)
		(drill 0.254)
		(layers "F.Cu" "B.Cu")
		(net "GND")
	)
	(via
		(at 203.532232 -306.135278)
		(size 0.4826)
		(drill 0.254)
		(layers "F.Cu" "B.Cu")
		(net "GND")
	)
	(via
		(at 306.250594 -210.51012)
		(size 0.4826)
		(drill 0.254)
		(layers "F.Cu" "B.Cu")
		(net "GND")
	)
	(via
		(at 165.545516 -202.010264)
		(size 0.4826)
		(drill 0.254)
		(layers "F.Cu" "B.Cu")
		(net "GND")
	)
	(via
		(at 375.018554 -420.318184)
		(size 0.4572)
		(drill 0.254)
		(layers "F.Cu" "B.Cu")
		(net "GND")
	)
	(via
		(at 76.105512 -37.897562)
		(size 0.508)
		(drill 0.254)
		(layers "F.Cu" "B.Cu")
		(net "GND")
	)
	(via
		(at 81.190084 -384.617722)
		(size 0.4064)
		(drill 0.2032)
		(layers "F.Cu" "B.Cu")
		(net "GND")
	)
	(via
		(at 307.368194 -267.035026)
		(size 0.4826)
		(drill 0.254)
		(layers "F.Cu" "B.Cu")
		(net "GND")
	)
	(via
		(at 195.988432 -240.68532)
		(size 0.4826)
		(drill 0.254)
		(layers "F.Cu" "B.Cu")
		(net "GND")
	)
	(via
		(at 342.088724 -333.085186)
		(size 0.49022)
		(drill 0.254)
		(layers "F.Cu" "B.Cu")
		(net "GND")
	)
	(via
		(at 399.349722 -436.347362)
		(size 0.4572)
		(drill 0.2032)
		(layers "F.Cu" "B.Cu")
		(net "GND")
	)
	(via
		(at 334.64119 -286.236156)
		(size 0.4064)
		(drill 0.2032)
		(layers "F.Cu" "B.Cu")
		(net "GND")
	)
	(via
		(at 80.291178 -224.234502)
		(size 0.4064)
		(drill 0.2032)
		(layers "F.Cu" "B.Cu")
		(net "GND")
	)
	(via
		(at 207.3656 -285.310326)
		(size 0.4826)
		(drill 0.254)
		(layers "F.Cu" "B.Cu")
		(net "GND")
	)
	(via
		(at 383.514854 -276.516084)
		(size 0.4064)
		(drill 0.2032)
		(layers "F.Cu" "B.Cu")
		(net "GND")
	)
	(via
		(at 108.321094 -274.896326)
		(size 0.4064)
		(drill 0.2032)
		(layers "F.Cu" "B.Cu")
		(net "GND")
	)
	(via
		(at 376.93473 -273.27606)
		(size 0.4064)
		(drill 0.2032)
		(layers "F.Cu" "B.Cu")
		(net "GND")
	)
	(via
		(at 422.76776 -353.10318)
		(size 0.49022)
		(drill 0.254)
		(layers "F.Cu" "B.Cu")
		(net "GND")
	)
	(via
		(at 442.5442 -249.185176)
		(size 0.4826)
		(drill 0.254)
		(layers "F.Cu" "B.Cu")
		(net "GND")
	)
	(via
		(at 357.487982 -261.32282)
		(size 0.4826)
		(drill 0.254)
		(layers "F.Cu" "B.Cu")
		(net "GND")
	)
	(via
		(at 176.072038 -282.335224)
		(size 0.4826)
		(drill 0.254)
		(layers "F.Cu" "B.Cu")
		(net "GND")
	)
	(via
		(at 387.914896 -250.964192)
		(size 0.4064)
		(drill 0.2032)
		(layers "F.Cu" "B.Cu")
		(net "GND")
	)
	(via
		(at 18.90776 -387.70179)
		(size 0.49022)
		(drill 0.254)
		(layers "F.Cu" "B.Cu")
		(net "GND")
	)
	(via
		(at 338.101178 -252.584204)
		(size 0.4064)
		(drill 0.2032)
		(layers "F.Cu" "B.Cu")
		(net "GND")
	)
	(via
		(at 363.187996 -256.387346)
		(size 0.4826)
		(drill 0.254)
		(layers "F.Cu" "B.Cu")
		(net "GND")
	)
	(via
		(at 275.807932 -227.935028)
		(size 0.4826)
		(drill 0.254)
		(layers "F.Cu" "B.Cu")
		(net "GND")
	)
	(via
		(at 152.244298 -382.85293)
		(size 0.4064)
		(drill 0.2032)
		(layers "F.Cu" "B.Cu")
		(net "GND")
	)
	(via
		(at 176.072038 -310.385206)
		(size 0.4826)
		(drill 0.254)
		(layers "F.Cu" "B.Cu")
		(net "GND")
	)
	(via
		(at 157.309058 -409.396184)
		(size 0.4572)
		(drill 0.254)
		(layers "F.Cu" "B.Cu")
		(net "GND")
	)
	(via
		(at 344.860118 -165.04412)
		(size 0.508)
		(drill 0.254)
		(layers "F.Cu" "B.Cu")
		(net "GND")
	)
	(via
		(at 121.004838 -288.666174)
		(size 0.4064)
		(drill 0.2032)
		(layers "F.Cu" "B.Cu")
		(net "GND")
	)
	(via
		(at 213.353396 -439.90768)
		(size 0.508)
		(drill 0.254)
		(layers "F.Cu" "B.Cu")
		(net "GND")
	)
	(via
		(at 381.804926 -255.014222)
		(size 0.4064)
		(drill 0.2032)
		(layers "F.Cu" "B.Cu")
		(net "GND")
	)
	(via
		(at 174.687738 -293.38524)
		(size 0.4826)
		(drill 0.254)
		(layers "F.Cu" "B.Cu")
		(net "GND")
	)
	(via
		(at 415.083752 -314.635134)
		(size 0.4826)
		(drill 0.254)
		(layers "F.Cu" "B.Cu")
		(net "GND")
	)
	(via
		(at 435.000146 -269.585186)
		(size 0.4826)
		(drill 0.254)
		(layers "F.Cu" "B.Cu")
		(net "GND")
	)
	(via
		(at 61.249814 -430.147222)
		(size 0.4572)
		(drill 0.2032)
		(layers "F.Cu" "B.Cu")
		(net "GND")
	)
	(via
		(at 17.608042 -267.885418)
		(size 0.4826)
		(drill 0.254)
		(layers "F.Cu" "B.Cu")
		(net "GND")
	)
	(via
		(at 357.201216 -284.616144)
		(size 0.4064)
		(drill 0.2032)
		(layers "F.Cu" "B.Cu")
		(net "GND")
	)
	(via
		(at 400.469862 -401.150582)
		(size 0.508)
		(drill 0.254)
		(layers "F.Cu" "B.Cu")
		(net "GND")
	)
	(via
		(at 202.165204 -439.907172)
		(size 0.508)
		(drill 0.254)
		(layers "F.Cu" "B.Cu")
		(net "GND")
	)
	(via
		(at 81.019396 -410.664152)
		(size 0.4572)
		(drill 0.254)
		(layers "F.Cu" "B.Cu")
		(net "GND")
	)
	(via
		(at 380.224792 -267.606018)
		(size 0.4064)
		(drill 0.2032)
		(layers "F.Cu" "B.Cu")
		(net "GND")
	)
	(via
		(at 449.246752 -394.429234)
		(size 0.508)
		(drill 0.254)
		(layers "F.Cu" "B.Cu")
		(net "GND")
	)
	(via
		(at 117.44071 -260.280404)
		(size 0.4826)
		(drill 0.254)
		(layers "F.Cu" "B.Cu")
		(net "GND")
	)
	(via
		(at 350.621092 -278.136096)
		(size 0.4064)
		(drill 0.2032)
		(layers "F.Cu" "B.Cu")
		(net "GND")
	)
	(via
		(at 81.975198 -333.044038)
		(size 0.508)
		(drill 0.254)
		(layers "F.Cu" "B.Cu")
		(net "GND")
	)
	(via
		(at 135.466836 -368.37493)
		(size 0.508)
		(drill 0.254)
		(layers "F.Cu" "B.Cu")
		(net "GND")
	)
	(via
		(at 216.460578 -58.389012)
		(size 0.508)
		(drill 0.254)
		(layers "F.Cu" "B.Cu")
		(net "GND")
	)
	(via
		(at 308.191154 -441.227718)
		(size 0.508)
		(drill 0.254)
		(layers "F.Cu" "B.Cu")
		(net "GND")
	)
	(via
		(at 431.724054 -356.28199)
		(size 0.508)
		(drill 0.254)
		(layers "F.Cu" "B.Cu")
		(net "GND")
	)
	(via
		(at 142.324836 -224.234502)
		(size 0.4064)
		(drill 0.2032)
		(layers "F.Cu" "B.Cu")
		(net "GND")
	)
	(via
		(at 406.181306 -355.717856)
		(size 0.508)
		(drill 0.254)
		(layers "F.Cu" "B.Cu")
		(net "GND")
	)
	(via
		(at 142.62481 -293.52621)
		(size 0.4064)
		(drill 0.2032)
		(layers "F.Cu" "B.Cu")
		(net "GND")
	)
	(via
		(at 89.28989 -12.542266)
		(size 0.508)
		(drill 0.254)
		(layers "F.Cu" "B.Cu")
		(net "GND")
	)
	(via
		(at 336.22107 -231.524048)
		(size 0.4064)
		(drill 0.2032)
		(layers "F.Cu" "B.Cu")
		(net "GND")
	)
	(via
		(at 24.034496 -211.360258)
		(size 0.4826)
		(drill 0.254)
		(layers "F.Cu" "B.Cu")
		(net "GND")
	)
	(via
		(at 397.144494 -179.110386)
		(size 0.49022)
		(drill 0.254)
		(layers "F.Cu" "B.Cu")
		(net "GND")
	)
	(via
		(at 126.34976 -431.451258)
		(size 0.4572)
		(drill 0.2032)
		(layers "F.Cu" "B.Cu")
		(net "GND")
	)
	(via
		(at 355.791008 -282.186126)
		(size 0.4064)
		(drill 0.2032)
		(layers "F.Cu" "B.Cu")
		(net "GND")
	)
	(via
		(at 55.328058 -252.58522)
		(size 0.4826)
		(drill 0.254)
		(layers "F.Cu" "B.Cu")
		(net "GND")
	)
	(via
		(at 90.662506 -184.615074)
		(size 0.49022)
		(drill 0.254)
		(layers "F.Cu" "B.Cu")
		(net "GND")
	)
	(via
		(at 106.948986 -398.568672)
		(size 0.508)
		(drill 0.254)
		(layers "F.Cu" "B.Cu")
		(net "GND")
	)
	(via
		(at 416.468052 -222.834962)
		(size 0.4826)
		(drill 0.254)
		(layers "F.Cu" "B.Cu")
		(net "GND")
	)
	(via
		(at 288.180018 -309.535068)
		(size 0.4826)
		(drill 0.254)
		(layers "F.Cu" "B.Cu")
		(net "GND")
	)
	(via
		(at 332.53299 -18.985992)
		(size 0.508)
		(drill 0.254)
		(layers "F.Cu" "B.Cu")
		(net "GND")
	)
	(via
		(at 29.252164 -255.13538)
		(size 0.4826)
		(drill 0.254)
		(layers "F.Cu" "B.Cu")
		(net "GND")
	)
	(via
		(at 115.94465 -169.935144)
		(size 0.49022)
		(drill 0.254)
		(layers "F.Cu" "B.Cu")
		(net "GND")
	)
	(via
		(at 337.234784 -333.808324)
		(size 0.49022)
		(drill 0.254)
		(layers "F.Cu" "B.Cu")
		(net "GND")
	)
	(via
		(at 317.704724 -333.055976)
		(size 0.49022)
		(drill 0.254)
		(layers "F.Cu" "B.Cu")
		(net "GND")
	)
	(via
		(at 83.41106 -283.806392)
		(size 0.4064)
		(drill 0.2032)
		(layers "F.Cu" "B.Cu")
		(net "GND")
	)
	(via
		(at 446.644268 -267.035026)
		(size 0.4826)
		(drill 0.254)
		(layers "F.Cu" "B.Cu")
		(net "GND")
	)
	(via
		(at 39.056818 -346.306902)
		(size 0.49022)
		(drill 0.254)
		(layers "F.Cu" "B.Cu")
		(net "GND")
	)
	(via
		(at 64.960754 -371.49913)
		(size 0.508)
		(drill 0.254)
		(layers "F.Cu" "B.Cu")
		(net "GND")
	)
	(via
		(at 318.74587 -359.924604)
		(size 0.508)
		(drill 0.254)
		(layers "F.Cu" "B.Cu")
		(net "GND")
	)
	(via
		(at 113.954814 -281.376374)
		(size 0.4064)
		(drill 0.2032)
		(layers "F.Cu" "B.Cu")
		(net "GND")
	)
	(via
		(at 197.5866 -193.996564)
		(size 0.4826)
		(drill 0.254)
		(layers "F.Cu" "B.Cu")
		(net "GND")
	)
	(via
		(at 381.634746 -294.335962)
		(size 0.4064)
		(drill 0.2032)
		(layers "F.Cu" "B.Cu")
		(net "GND")
	)
	(via
		(at 299.82414 -268.735048)
		(size 0.4826)
		(drill 0.254)
		(layers "F.Cu" "B.Cu")
		(net "GND")
	)
	(via
		(at 416.64509 -421.586152)
		(size 0.4572)
		(drill 0.254)
		(layers "F.Cu" "B.Cu")
		(net "GND")
	)
	(via
		(at 347.031056 -229.094284)
		(size 0.4064)
		(drill 0.2032)
		(layers "F.Cu" "B.Cu")
		(net "GND")
	)
	(via
		(at 440.086496 -330.128372)
		(size 0.508)
		(drill 0.254)
		(layers "F.Cu" "B.Cu")
		(net "GND")
	)
	(via
		(at 361.424728 -275.706078)
		(size 0.4064)
		(drill 0.2032)
		(layers "F.Cu" "B.Cu")
		(net "GND")
	)
	(via
		(at 362.238036 -261.32282)
		(size 0.4826)
		(drill 0.254)
		(layers "F.Cu" "B.Cu")
		(net "GND")
	)
	(via
		(at 108.636816 -389.103108)
		(size 0.508)
		(drill 0.254)
		(layers "F.Cu" "B.Cu")
		(net "GND")
	)
	(via
		(at 138.564874 -248.534428)
		(size 0.4064)
		(drill 0.2032)
		(layers "F.Cu" "B.Cu")
		(net "GND")
	)
	(via
		(at 124.464826 -248.534428)
		(size 0.4064)
		(drill 0.2032)
		(layers "F.Cu" "B.Cu")
		(net "GND")
	)
	(via
		(at 32.695896 -250.885198)
		(size 0.4826)
		(drill 0.254)
		(layers "F.Cu" "B.Cu")
		(net "GND")
	)
	(via
		(at 326.651112 -293.525956)
		(size 0.4064)
		(drill 0.2032)
		(layers "F.Cu" "B.Cu")
		(net "GND")
	)
	(via
		(at 283.618432 -210.51012)
		(size 0.4826)
		(drill 0.254)
		(layers "F.Cu" "B.Cu")
		(net "GND")
	)
	(via
		(at 399.349722 -432.747166)
		(size 0.4572)
		(drill 0.2032)
		(layers "F.Cu" "B.Cu")
		(net "GND")
	)
	(via
		(at 114.59464 -238.00435)
		(size 0.4064)
		(drill 0.2032)
		(layers "F.Cu" "B.Cu")
		(net "GND")
	)
	(via
		(at 147.82419 -102.694232)
		(size 0.508)
		(drill 0.254)
		(layers "F.Cu" "B.Cu")
		(net "GND")
	)
	(via
		(at 90.16111 -242.864386)
		(size 0.4064)
		(drill 0.2032)
		(layers "F.Cu" "B.Cu")
		(net "GND")
	)
	(via
		(at 306.659534 -413.480504)
		(size 0.4572)
		(drill 0.254)
		(layers "F.Cu" "B.Cu")
		(net "GND")
	)
	(via
		(at 443.9285 -210.085178)
		(size 0.4826)
		(drill 0.254)
		(layers "F.Cu" "B.Cu")
		(net "GND")
	)
	(via
		(at 32.695896 -317.185294)
		(size 0.4826)
		(drill 0.254)
		(layers "F.Cu" "B.Cu")
		(net "GND")
	)
	(via
		(at 424.012106 -263.634982)
		(size 0.4826)
		(drill 0.254)
		(layers "F.Cu" "B.Cu")
		(net "GND")
	)
	(via
		(at 387.914896 -255.824228)
		(size 0.4064)
		(drill 0.2032)
		(layers "F.Cu" "B.Cu")
		(net "GND")
	)
	(via
		(at 291.162486 -238.560102)
		(size 0.4826)
		(drill 0.254)
		(layers "F.Cu" "B.Cu")
		(net "GND")
	)
	(via
		(at 337.019138 -416.020504)
		(size 0.4572)
		(drill 0.254)
		(layers "F.Cu" "B.Cu")
		(net "GND")
	)
	(via
		(at 247.825006 -39.1033)
		(size 0.508)
		(drill 0.254)
		(layers "F.Cu" "B.Cu")
		(net "GND")
	)
	(via
		(at 431.55616 -248.335038)
		(size 0.4826)
		(drill 0.254)
		(layers "F.Cu" "B.Cu")
		(net "GND")
	)
	(via
		(at 315.02096 -340.252812)
		(size 0.508)
		(drill 0.254)
		(layers "F.Cu" "B.Cu")
		(net "GND")
	)
	(via
		(at 142.324836 -250.15444)
		(size 0.4064)
		(drill 0.2032)
		(layers "F.Cu" "B.Cu")
		(net "GND")
	)
	(via
		(at 379.88621 -420.318184)
		(size 0.4572)
		(drill 0.254)
		(layers "F.Cu" "B.Cu")
		(net "GND")
	)
	(via
		(at 84.441284 -407.00452)
		(size 0.4064)
		(drill 0.2032)
		(layers "F.Cu" "B.Cu")
		(net "GND")
	)
	(via
		(at 165.812216 -275.53539)
		(size 0.4826)
		(drill 0.254)
		(layers "F.Cu" "B.Cu")
		(net "GND")
	)
	(via
		(at 121.82602 -36.053268)
		(size 0.508)
		(drill 0.254)
		(layers "F.Cu" "B.Cu")
		(net "GND")
	)
	(via
		(at 145.349722 -427.699678)
		(size 0.4572)
		(drill 0.2032)
		(layers "F.Cu" "B.Cu")
		(net "GND")
	)
	(via
		(at 310.631586 -344.781124)
		(size 0.49022)
		(drill 0.254)
		(layers "F.Cu" "B.Cu")
		(net "GND")
	)
	(via
		(at 128.224788 -224.234502)
		(size 0.4064)
		(drill 0.2032)
		(layers "F.Cu" "B.Cu")
		(net "GND")
	)
	(via
		(at 140.744702 -295.146222)
		(size 0.4064)
		(drill 0.2032)
		(layers "F.Cu" "B.Cu")
		(net "GND")
	)
	(via
		(at 369.114832 -249.34418)
		(size 0.4064)
		(drill 0.2032)
		(layers "F.Cu" "B.Cu")
		(net "GND")
	)
	(via
		(at 280.635964 -208.385156)
		(size 0.4826)
		(drill 0.254)
		(layers "F.Cu" "B.Cu")
		(net "GND")
	)
	(via
		(at 392.065002 -192.481962)
		(size 0.508)
		(drill 0.254)
		(layers "F.Cu" "B.Cu")
		(net "GND")
	)
	(via
		(at 153.402538 -319.67805)
		(size 0.508)
		(drill 0.254)
		(layers "F.Cu" "B.Cu")
		(net "GND")
	)
	(via
		(at 179.516024 -206.685388)
		(size 0.4826)
		(drill 0.254)
		(layers "F.Cu" "B.Cu")
		(net "GND")
	)
	(via
		(at 394.929614 -417.778184)
		(size 0.4572)
		(drill 0.254)
		(layers "F.Cu" "B.Cu")
		(net "GND")
	)
	(via
		(at 413.523684 -193.10731)
		(size 0.4826)
		(drill 0.254)
		(layers "F.Cu" "B.Cu")
		(net "GND")
	)
	(via
		(at 41.62425 -303.585372)
		(size 0.4826)
		(drill 0.254)
		(layers "F.Cu" "B.Cu")
		(net "GND")
	)
	(via
		(at 138.864848 -261.126224)
		(size 0.4064)
		(drill 0.2032)
		(layers "F.Cu" "B.Cu")
		(net "GND")
	)
	(via
		(at 143.73479 -238.00435)
		(size 0.4064)
		(drill 0.2032)
		(layers "F.Cu" "B.Cu")
		(net "GND")
	)
	(via
		(at 447.761868 -219.860114)
		(size 0.4826)
		(drill 0.254)
		(layers "F.Cu" "B.Cu")
		(net "GND")
	)
	(via
		(at 341.22106 -276.516084)
		(size 0.4064)
		(drill 0.2032)
		(layers "F.Cu" "B.Cu")
		(net "GND")
	)
	(via
		(at 329.6412 -250.964192)
		(size 0.4064)
		(drill 0.2032)
		(layers "F.Cu" "B.Cu")
		(net "GND")
	)
	(via
		(at 323.249544 -436.347362)
		(size 0.4572)
		(drill 0.2032)
		(layers "F.Cu" "B.Cu")
		(net "GND")
	)
	(via
		(at 94.488 -215.737948)
		(size 0.508)
		(drill 0.254)
		(layers "F.Cu" "B.Cu")
		(net "GND")
	)
	(via
		(at 424.012106 -310.384952)
		(size 0.4826)
		(drill 0.254)
		(layers "F.Cu" "B.Cu")
		(net "GND")
	)
	(via
		(at 343.409524 -333.085186)
		(size 0.49022)
		(drill 0.254)
		(layers "F.Cu" "B.Cu")
		(net "GND")
	)
	(via
		(at 47.784004 -307.8353)
		(size 0.4826)
		(drill 0.254)
		(layers "F.Cu" "B.Cu")
		(net "GND")
	)
	(via
		(at 287.230566 -342.811608)
		(size 0.508)
		(drill 0.254)
		(layers "F.Cu" "B.Cu")
		(net "GND")
	)
	(via
		(at 371.294914 -268.416024)
		(size 0.4064)
		(drill 0.2032)
		(layers "F.Cu" "B.Cu")
		(net "GND")
	)
	(via
		(at 81.701132 -250.964446)
		(size 0.4064)
		(drill 0.2032)
		(layers "F.Cu" "B.Cu")
		(net "GND")
	)
	(via
		(at 307.368194 -251.735082)
		(size 0.4826)
		(drill 0.254)
		(layers "F.Cu" "B.Cu")
		(net "GND")
	)
	(via
		(at 401.3835 -376.75693)
		(size 0.508)
		(drill 0.254)
		(layers "F.Cu" "B.Cu")
		(net "GND")
	)
	(via
		(at 324.75297 -249.610118)
		(size 0.4064)
		(drill 0.2032)
		(layers "F.Cu" "B.Cu")
		(net "GND")
	)
	(via
		(at 176.072038 -226.23526)
		(size 0.4826)
		(drill 0.254)
		(layers "F.Cu" "B.Cu")
		(net "GND")
	)
	(via
		(at 222.152718 -276.366478)
		(size 0.508)
		(drill 0.254)
		(layers "F.Cu" "B.Cu")
		(net "GND")
	)
	(via
		(at 77.867764 -412.570168)
		(size 0.4064)
		(drill 0.2032)
		(layers "F.Cu" "B.Cu")
		(net "GND")
	)
	(via
		(at 268.263878 -230.485188)
		(size 0.4826)
		(drill 0.254)
		(layers "F.Cu" "B.Cu")
		(net "GND")
	)
	(via
		(at 90.249756 -439.651394)
		(size 0.4572)
		(drill 0.2032)
		(layers "F.Cu" "B.Cu")
		(net "GND")
	)
	(via
		(at 343.418414 -412.212536)
		(size 0.4572)
		(drill 0.254)
		(layers "F.Cu" "B.Cu")
		(net "GND")
	)
	(via
		(at 305.983894 -295.935146)
		(size 0.4826)
		(drill 0.254)
		(layers "F.Cu" "B.Cu")
		(net "GND")
	)
	(via
		(at 376.493278 -142.361158)
		(size 0.508)
		(drill 0.254)
		(layers "F.Cu" "B.Cu")
		(net "GND")
	)
	(via
		(at 357.841042 -236.384084)
		(size 0.4064)
		(drill 0.2032)
		(layers "F.Cu" "B.Cu")
		(net "GND")
	)
	(via
		(at 372.704868 -280.566114)
		(size 0.4064)
		(drill 0.2032)
		(layers "F.Cu" "B.Cu")
		(net "GND")
	)
	(via
		(at 373.344694 -246.914162)
		(size 0.4064)
		(drill 0.2032)
		(layers "F.Cu" "B.Cu")
		(net "GND")
	)
	(via
		(at 145.056098 -407.638504)
		(size 0.4572)
		(drill 0.254)
		(layers "F.Cu" "B.Cu")
		(net "GND")
	)
	(via
		(at 346.705936 -394.831062)
		(size 0.4064)
		(drill 0.2032)
		(layers "F.Cu" "B.Cu")
		(net "GND")
	)
	(via
		(at 428.840392 -200.735184)
		(size 0.4826)
		(drill 0.254)
		(layers "F.Cu" "B.Cu")
		(net "GND")
	)
	(via
		(at 386.198618 -184.692798)
		(size 0.508)
		(drill 0.254)
		(layers "F.Cu" "B.Cu")
		(net "GND")
	)
	(via
		(at 156.138626 -404.46452)
		(size 0.4064)
		(drill 0.2032)
		(layers "F.Cu" "B.Cu")
		(net "GND")
	)
	(via
		(at 393.084812 -255.014222)
		(size 0.4064)
		(drill 0.2032)
		(layers "F.Cu" "B.Cu")
		(net "GND")
	)
	(via
		(at 133.864858 -238.814356)
		(size 0.4064)
		(drill 0.2032)
		(layers "F.Cu" "B.Cu")
		(net "GND")
	)
	(via
		(at 124.464826 -240.434368)
		(size 0.4064)
		(drill 0.2032)
		(layers "F.Cu" "B.Cu")
		(net "GND")
	)
	(via
		(at 425.734734 -4.963414)
		(size 0.508)
		(drill 0.254)
		(layers "F.Cu" "B.Cu")
		(net "GND")
	)
	(via
		(at 88.580976 -291.096192)
		(size 0.4064)
		(drill 0.2032)
		(layers "F.Cu" "B.Cu")
		(net "GND")
	)
	(via
		(at 80.344264 -393.902438)
		(size 0.4572)
		(drill 0.254)
		(layers "F.Cu" "B.Cu")
		(net "GND")
	)
	(via
		(at 299.82414 -308.685184)
		(size 0.4826)
		(drill 0.254)
		(layers "F.Cu" "B.Cu")
		(net "GND")
	)
	(via
		(at 326.651112 -291.905944)
		(size 0.4064)
		(drill 0.2032)
		(layers "F.Cu" "B.Cu")
		(net "GND")
	)
	(via
		(at 218.299284 -326.209152)
		(size 0.508)
		(drill 0.254)
		(layers "F.Cu" "B.Cu")
		(net "GND")
	)
	(via
		(at 319.261236 -379.22073)
		(size 0.508)
		(drill 0.254)
		(layers "F.Cu" "B.Cu")
		(net "GND")
	)
	(via
		(at 307.368194 -297.635168)
		(size 0.4826)
		(drill 0.254)
		(layers "F.Cu" "B.Cu")
		(net "GND")
	)
	(via
		(at 83.876642 -368.37493)
		(size 0.508)
		(drill 0.254)
		(layers "F.Cu" "B.Cu")
		(net "GND")
	)
	(via
		(at 273.092164 -216.035128)
		(size 0.4826)
		(drill 0.254)
		(layers "F.Cu" "B.Cu")
		(net "GND")
	)
	(via
		(at 396.686024 -16.979138)
		(size 0.508)
		(drill 0.254)
		(layers "F.Cu" "B.Cu")
		(net "GND")
	)
	(via
		(at 179.516024 -281.48534)
		(size 0.4826)
		(drill 0.254)
		(layers "F.Cu" "B.Cu")
		(net "GND")
	)
	(via
		(at 102.397814 -36.6522)
		(size 0.508)
		(drill 0.254)
		(layers "F.Cu" "B.Cu")
		(net "GND")
	)
	(via
		(at 98.150934 -250.15444)
		(size 0.4064)
		(drill 0.2032)
		(layers "F.Cu" "B.Cu")
		(net "GND")
	)
	(via
		(at 332.249526 -427.851316)
		(size 0.4572)
		(drill 0.2032)
		(layers "F.Cu" "B.Cu")
		(net "GND")
	)
	(via
		(at 353.141026 -246.104156)
		(size 0.4064)
		(drill 0.2032)
		(layers "F.Cu" "B.Cu")
		(net "GND")
	)
	(via
		(at 82.925666 -183.893968)
		(size 0.49022)
		(drill 0.254)
		(layers "F.Cu" "B.Cu")
		(net "GND")
	)
	(via
		(at 273.092164 -223.6851)
		(size 0.4826)
		(drill 0.254)
		(layers "F.Cu" "B.Cu")
		(net "GND")
	)
	(via
		(at 181.407562 -54.152546)
		(size 0.508)
		(drill 0.254)
		(layers "F.Cu" "B.Cu")
		(net "GND")
	)
	(via
		(at 98.394266 -184.632346)
		(size 0.49022)
		(drill 0.254)
		(layers "F.Cu" "B.Cu")
		(net "GND")
	)
	(via
		(at 362.316014 -347.834458)
		(size 0.508)
		(drill 0.254)
		(layers "F.Cu" "B.Cu")
		(net "GND")
	)
	(via
		(at 203.265532 -276.81047)
		(size 0.4826)
		(drill 0.254)
		(layers "F.Cu" "B.Cu")
		(net "GND")
	)
	(via
		(at 0.762254 -43.479212)
		(size 0.508)
		(drill 0.254)
		(layers "F.Cu" "B.Cu")
		(net "GND")
	)
	(via
		(at 393.084812 -235.574078)
		(size 0.4064)
		(drill 0.2032)
		(layers "F.Cu" "B.Cu")
		(net "GND")
	)
	(via
		(at 412.367984 -199.035162)
		(size 0.4826)
		(drill 0.254)
		(layers "F.Cu" "B.Cu")
		(net "GND")
	)
	(via
		(at 202.849734 -79.444342)
		(size 0.508)
		(drill 0.254)
		(layers "F.Cu" "B.Cu")
		(net "GND")
	)
	(via
		(at 396.73403 -417.778184)
		(size 0.4572)
		(drill 0.254)
		(layers "F.Cu" "B.Cu")
		(net "GND")
	)
	(via
		(at 148.21027 -116.31295)
		(size 0.508)
		(drill 0.254)
		(layers "F.Cu" "B.Cu")
		(net "GND")
	)
	(via
		(at 165.44417 -391.830814)
		(size 0.4064)
		(drill 0.2032)
		(layers "F.Cu" "B.Cu")
		(net "GND")
	)
	(via
		(at 391.974832 -266.796012)
		(size 0.4064)
		(drill 0.2032)
		(layers "F.Cu" "B.Cu")
		(net "GND")
	)
	(via
		(at 103.791004 -229.094538)
		(size 0.4064)
		(drill 0.2032)
		(layers "F.Cu" "B.Cu")
		(net "GND")
	)
	(via
		(at 27.867864 -305.285394)
		(size 0.4826)
		(drill 0.254)
		(layers "F.Cu" "B.Cu")
		(net "GND")
	)
	(via
		(at 389.79475 -250.964192)
		(size 0.4064)
		(drill 0.2032)
		(layers "F.Cu" "B.Cu")
		(net "GND")
	)
	(via
		(at 125.704854 -274.08632)
		(size 0.4064)
		(drill 0.2032)
		(layers "F.Cu" "B.Cu")
		(net "GND")
	)
	(via
		(at 2.76225 -277.805134)
		(size 0.508)
		(drill 0.254)
		(layers "F.Cu" "B.Cu")
		(net "GND")
	)
	(via
		(at 376.93473 -279.756108)
		(size 0.4064)
		(drill 0.2032)
		(layers "F.Cu" "B.Cu")
		(net "GND")
	)
	(via
		(at 163.190174 -46.954948)
		(size 0.508)
		(drill 0.254)
		(layers "F.Cu" "B.Cu")
		(net "GND")
	)
	(via
		(at 89.99093 -285.426404)
		(size 0.4064)
		(drill 0.2032)
		(layers "F.Cu" "B.Cu")
		(net "GND")
	)
	(via
		(at 40.23995 -289.135312)
		(size 0.4826)
		(drill 0.254)
		(layers "F.Cu" "B.Cu")
		(net "GND")
	)
	(via
		(at 184.732168 -107.063032)
		(size 0.4572)
		(drill 0.254)
		(layers "F.Cu" "B.Cu")
		(net "GND")
	)
	(via
		(at 282.020264 -275.535136)
		(size 0.4826)
		(drill 0.254)
		(layers "F.Cu" "B.Cu")
		(net "GND")
	)
	(via
		(at 123.524772 -240.434368)
		(size 0.4064)
		(drill 0.2032)
		(layers "F.Cu" "B.Cu")
		(net "GND")
	)
	(via
		(at 410.656024 -18.503138)
		(size 0.508)
		(drill 0.254)
		(layers "F.Cu" "B.Cu")
		(net "GND")
	)
	(via
		(at 139.952222 -156.567124)
		(size 0.508)
		(drill 0.254)
		(layers "F.Cu" "B.Cu")
		(net "GND")
	)
	(via
		(at 20.32381 -221.135194)
		(size 0.4826)
		(drill 0.254)
		(layers "F.Cu" "B.Cu")
		(net "GND")
	)
	(via
		(at 101.91115 -251.774452)
		(size 0.4064)
		(drill 0.2032)
		(layers "F.Cu" "B.Cu")
		(net "GND")
	)
	(via
		(at 59.428126 -255.13538)
		(size 0.4826)
		(drill 0.254)
		(layers "F.Cu" "B.Cu")
		(net "GND")
	)
	(via
		(at 337.377786 -415.38652)
		(size 0.4064)
		(drill 0.2032)
		(layers "F.Cu" "B.Cu")
		(net "GND")
	)
	(via
		(at 173.35627 -303.585372)
		(size 0.4826)
		(drill 0.254)
		(layers "F.Cu" "B.Cu")
		(net "GND")
	)
	(via
		(at 139.82827 -29.053028)
		(size 0.508)
		(drill 0.254)
		(layers "F.Cu" "B.Cu")
		(net "GND")
	)
	(via
		(at 181.426358 -353.283774)
		(size 0.49022)
		(drill 0.254)
		(layers "F.Cu" "B.Cu")
		(net "GND")
	)
	(via
		(at 249.721624 -279.503632)
		(size 0.508)
		(drill 0.254)
		(layers "F.Cu" "B.Cu")
		(net "GND")
	)
	(via
		(at 149.349714 -436.051198)
		(size 0.4572)
		(drill 0.2032)
		(layers "F.Cu" "B.Cu")
		(net "GND")
	)
	(via
		(at 286.749236 -428.9044)
		(size 0.508)
		(drill 0.254)
		(layers "F.Cu" "B.Cu")
		(net "GND")
	)
	(via
		(at 97.488502 -371.49913)
		(size 0.508)
		(drill 0.254)
		(layers "F.Cu" "B.Cu")
		(net "GND")
	)
	(via
		(at 277.192232 -244.934994)
		(size 0.4826)
		(drill 0.254)
		(layers "F.Cu" "B.Cu")
		(net "GND")
	)
	(via
		(at 369.414806 -266.796012)
		(size 0.4064)
		(drill 0.2032)
		(layers "F.Cu" "B.Cu")
		(net "GND")
	)
	(via
		(at 464.537806 -423.310812)
		(size 0.508)
		(drill 0.254)
		(layers "F.Cu" "B.Cu")
		(net "GND")
	)
	(via
		(at 194.604132 -311.235344)
		(size 0.4826)
		(drill 0.254)
		(layers "F.Cu" "B.Cu")
		(net "GND")
	)
	(via
		(at 319.249552 -429.147224)
		(size 0.4572)
		(drill 0.2032)
		(layers "F.Cu" "B.Cu")
		(net "GND")
	)
	(via
		(at 341.22106 -284.616144)
		(size 0.4064)
		(drill 0.2032)
		(layers "F.Cu" "B.Cu")
		(net "GND")
	)
	(via
		(at 119.291354 -410.664152)
		(size 0.4572)
		(drill 0.254)
		(layers "F.Cu" "B.Cu")
		(net "GND")
	)
	(via
		(at 467.5378 -256.083054)
		(size 0.508)
		(drill 0.254)
		(layers "F.Cu" "B.Cu")
		(net "GND")
	)
	(via
		(at 409.075382 -420.952168)
		(size 0.4064)
		(drill 0.2032)
		(layers "F.Cu" "B.Cu")
		(net "GND")
	)
	(via
		(at 93.280992 -286.23641)
		(size 0.4064)
		(drill 0.2032)
		(layers "F.Cu" "B.Cu")
		(net "GND")
	)
	(via
		(at 149.349714 -439.651394)
		(size 0.4572)
		(drill 0.2032)
		(layers "F.Cu" "B.Cu")
		(net "GND")
	)
	(via
		(at 204.8637 -302.735234)
		(size 0.4826)
		(drill 0.254)
		(layers "F.Cu" "B.Cu")
		(net "GND")
	)
	(via
		(at 124.7648 -275.706332)
		(size 0.4064)
		(drill 0.2032)
		(layers "F.Cu" "B.Cu")
		(net "GND")
	)
	(via
		(at 358.483154 -441.227718)
		(size 0.508)
		(drill 0.254)
		(layers "F.Cu" "B.Cu")
		(net "GND")
	)
	(via
		(at 342.801194 -254.204216)
		(size 0.4064)
		(drill 0.2032)
		(layers "F.Cu" "B.Cu")
		(net "GND")
	)
	(via
		(at 88.591644 -407.00452)
		(size 0.4064)
		(drill 0.2032)
		(layers "F.Cu" "B.Cu")
		(net "GND")
	)
	(via
		(at 368.004852 -285.42615)
		(size 0.4064)
		(drill 0.2032)
		(layers "F.Cu" "B.Cu")
		(net "GND")
	)
	(via
		(at 264.43051 -314.210192)
		(size 0.4826)
		(drill 0.254)
		(layers "F.Cu" "B.Cu")
		(net "GND")
	)
	(via
		(at 136.684766 -230.71455)
		(size 0.4064)
		(drill 0.2032)
		(layers "F.Cu" "B.Cu")
		(net "GND")
	)
	(via
		(at 97.511108 -277.326344)
		(size 0.4064)
		(drill 0.2032)
		(layers "F.Cu" "B.Cu")
		(net "GND")
	)
	(via
		(at 110.34268 -60.94222)
		(size 0.508)
		(drill 0.254)
		(layers "F.Cu" "B.Cu")
		(net "GND")
	)
	(via
		(at 51.884072 -232.18521)
		(size 0.4826)
		(drill 0.254)
		(layers "F.Cu" "B.Cu")
		(net "GND")
	)
	(via
		(at 63.258954 -373.96293)
		(size 0.508)
		(drill 0.254)
		(layers "F.Cu" "B.Cu")
		(net "GND")
	)
	(via
		(at 180.721 -91.658948)
		(size 0.508)
		(drill 0.254)
		(layers "F.Cu" "B.Cu")
		(net "GND")
	)
	(via
		(at 268.263878 -218.585034)
		(size 0.4826)
		(drill 0.254)
		(layers "F.Cu" "B.Cu")
		(net "GND")
	)
	(via
		(at 436.117746 -286.16021)
		(size 0.4826)
		(drill 0.254)
		(layers "F.Cu" "B.Cu")
		(net "GND")
	)
	(via
		(at 35.678364 -229.210362)
		(size 0.4826)
		(drill 0.254)
		(layers "F.Cu" "B.Cu")
		(net "GND")
	)
	(via
		(at 350.364552 -338.784438)
		(size 0.49022)
		(drill 0.254)
		(layers "F.Cu" "B.Cu")
		(net "GND")
	)
	(via
		(at 87.15375 -185.259726)
		(size 0.508)
		(drill 0.254)
		(layers "F.Cu" "B.Cu")
		(net "GND")
	)
	(via
		(at 150.86965 -41.76776)
		(size 0.508)
		(drill 0.254)
		(layers "F.Cu" "B.Cu")
		(net "GND")
	)
	(via
		(at 334.64119 -291.095938)
		(size 0.4064)
		(drill 0.2032)
		(layers "F.Cu" "B.Cu")
		(net "GND")
	)
	(via
		(at 124.7648 -287.046162)
		(size 0.4064)
		(drill 0.2032)
		(layers "F.Cu" "B.Cu")
		(net "GND")
	)
	(via
		(at 308.61635 -391.23493)
		(size 0.4064)
		(drill 0.2032)
		(layers "F.Cu" "B.Cu")
		(net "GND")
	)
	(via
		(at 43.222418 -285.310326)
		(size 0.4826)
		(drill 0.254)
		(layers "F.Cu" "B.Cu")
		(net "GND")
	)
	(via
		(at 133.694678 -265.176254)
		(size 0.4064)
		(drill 0.2032)
		(layers "F.Cu" "B.Cu")
		(net "GND")
	)
	(via
		(at 83.16087 -180.755544)
		(size 0.49022)
		(drill 0.254)
		(layers "F.Cu" "B.Cu")
		(net "GND")
	)
	(via
		(at 335.11109 -264.365994)
		(size 0.4064)
		(drill 0.2032)
		(layers "F.Cu" "B.Cu")
		(net "GND")
	)
	(via
		(at 158.840678 -405.098504)
		(size 0.4572)
		(drill 0.254)
		(layers "F.Cu" "B.Cu")
		(net "GND")
	)
	(via
		(at 180.633624 -220.710252)
		(size 0.4826)
		(drill 0.254)
		(layers "F.Cu" "B.Cu")
		(net "GND")
	)
	(via
		(at 65.703196 -407.638504)
		(size 0.4572)
		(drill 0.254)
		(layers "F.Cu" "B.Cu")
		(net "GND")
	)
	(via
		(at 162.428428 -149.221952)
		(size 0.508)
		(drill 0.254)
		(layers "F.Cu" "B.Cu")
		(net "GND")
	)
	(via
		(at 381.334772 -221.80423)
		(size 0.4064)
		(drill 0.2032)
		(layers "F.Cu" "B.Cu")
		(net "GND")
	)
	(via
		(at 253.506224 -133.063996)
		(size 0.508)
		(drill 0.254)
		(layers "F.Cu" "B.Cu")
		(net "GND")
	)
	(via
		(at 312.424826 -412.84652)
		(size 0.4064)
		(drill 0.2032)
		(layers "F.Cu" "B.Cu")
		(net "GND")
	)
	(via
		(at 39.453312 -424.202098)
		(size 0.508)
		(drill 0.254)
		(layers "F.Cu" "B.Cu")
		(net "GND")
	)
	(via
		(at 48.054514 -344.137234)
		(size 0.508)
		(drill 0.254)
		(layers "F.Cu" "B.Cu")
		(net "GND")
	)
	(via
		(at 198.7042 -280.635202)
		(size 0.4826)
		(drill 0.254)
		(layers "F.Cu" "B.Cu")
		(net "GND")
	)
	(via
		(at 334.812386 -340.115398)
		(size 0.508)
		(drill 0.254)
		(layers "F.Cu" "B.Cu")
		(net "GND")
	)
	(via
		(at 211.899754 -116.732812)
		(size 0.508)
		(drill 0.254)
		(layers "F.Cu" "B.Cu")
		(net "GND")
	)
	(via
		(at 133.694678 -294.336216)
		(size 0.4064)
		(drill 0.2032)
		(layers "F.Cu" "B.Cu")
		(net "GND")
	)
	(via
		(at 405.915368 -4.32943)
		(size 0.508)
		(drill 0.254)
		(layers "F.Cu" "B.Cu")
		(net "GND")
	)
	(via
		(at 51.99507 -18.503138)
		(size 0.508)
		(drill 0.254)
		(layers "F.Cu" "B.Cu")
		(net "GND")
	)
	(via
		(at 156.25826 -17.915382)
		(size 0.508)
		(drill 0.254)
		(layers "F.Cu" "B.Cu")
		(net "GND")
	)
	(via
		(at 419.401498 -331.19949)
		(size 0.508)
		(drill 0.254)
		(layers "F.Cu" "B.Cu")
		(net "GND")
	)
	(via
		(at 173.35627 -212.635338)
		(size 0.4826)
		(drill 0.254)
		(layers "F.Cu" "B.Cu")
		(net "GND")
	)
	(via
		(at 292.280086 -250.03506)
		(size 0.4826)
		(drill 0.254)
		(layers "F.Cu" "B.Cu")
		(net "GND")
	)
	(via
		(at 97.144332 -382.85293)
		(size 0.4064)
		(drill 0.2032)
		(layers "F.Cu" "B.Cu")
		(net "GND")
	)
	(via
		(at 361.594908 -223.424242)
		(size 0.4064)
		(drill 0.2032)
		(layers "F.Cu" "B.Cu")
		(net "GND")
	)
	(via
		(at 171.97197 -279.785318)
		(size 0.4826)
		(drill 0.254)
		(layers "F.Cu" "B.Cu")
		(net "GND")
	)
	(via
		(at 374.584722 -282.186126)
		(size 0.4064)
		(drill 0.2032)
		(layers "F.Cu" "B.Cu")
		(net "GND")
	)
	(via
		(at 155.84424 -382.85293)
		(size 0.4064)
		(drill 0.2032)
		(layers "F.Cu" "B.Cu")
		(net "GND")
	)
	(via
		(at 378.514864 -246.104156)
		(size 0.4064)
		(drill 0.2032)
		(layers "F.Cu" "B.Cu")
		(net "GND")
	)
	(via
		(at 92.572078 -301.779686)
		(size 0.508)
		(drill 0.254)
		(layers "F.Cu" "B.Cu")
		(net "GND")
	)
	(via
		(at 68.979034 -163.778184)
		(size 0.508)
		(drill 0.254)
		(layers "F.Cu" "B.Cu")
		(net "GND")
	)
	(via
		(at 202.147932 -279.785318)
		(size 0.4826)
		(drill 0.254)
		(layers "F.Cu" "B.Cu")
		(net "GND")
	)
	(via
		(at 326.651112 -287.045908)
		(size 0.4064)
		(drill 0.2032)
		(layers "F.Cu" "B.Cu")
		(net "GND")
	)
	(via
		(at 29.252164 -226.23526)
		(size 0.4826)
		(drill 0.254)
		(layers "F.Cu" "B.Cu")
		(net "GND")
	)
	(via
		(at 446.644268 -233.884978)
		(size 0.4826)
		(drill 0.254)
		(layers "F.Cu" "B.Cu")
		(net "GND")
	)
	(via
		(at 16.25346 -398.888458)
		(size 0.508)
		(drill 0.254)
		(layers "F.Cu" "B.Cu")
		(net "GND")
	)
	(via
		(at 64.478154 -369.03533)
		(size 0.508)
		(drill 0.254)
		(layers "F.Cu" "B.Cu")
		(net "GND")
	)
	(via
		(at 195.988432 -212.635338)
		(size 0.4826)
		(drill 0.254)
		(layers "F.Cu" "B.Cu")
		(net "GND")
	)
	(via
		(at 52.191412 -390.160002)
		(size 0.4064)
		(drill 0.2032)
		(layers "F.Cu" "B.Cu")
		(net "GND")
	)
	(via
		(at 89.99093 -275.706332)
		(size 0.4064)
		(drill 0.2032)
		(layers "F.Cu" "B.Cu")
		(net "GND")
	)
	(via
		(at 347.50121 -255.824228)
		(size 0.4064)
		(drill 0.2032)
		(layers "F.Cu" "B.Cu")
		(net "GND")
	)
	(via
		(at 96.271842 -58.076846)
		(size 0.508)
		(drill 0.254)
		(layers "F.Cu" "B.Cu")
		(net "GND")
	)
	(via
		(at 34.080196 -306.135278)
		(size 0.4826)
		(drill 0.254)
		(layers "F.Cu" "B.Cu")
		(net "GND")
	)
	(via
		(at 378.04471 -253.39421)
		(size 0.4064)
		(drill 0.2032)
		(layers "F.Cu" "B.Cu")
		(net "GND")
	)
	(via
		(at 410.38018 -381.68453)
		(size 0.508)
		(drill 0.254)
		(layers "F.Cu" "B.Cu")
		(net "GND")
	)
	(via
		(at 451.2056 -276.810216)
		(size 0.4826)
		(drill 0.254)
		(layers "F.Cu" "B.Cu")
		(net "GND")
	)
	(via
		(at 112.15751 -174.507398)
		(size 0.508)
		(drill 0.254)
		(layers "F.Cu" "B.Cu")
		(net "GND")
	)
	(via
		(at 64.686434 -163.103052)
		(size 0.508)
		(drill 0.254)
		(layers "F.Cu" "B.Cu")
		(net "GND")
	)
	(via
		(at 383.514854 -261.935976)
		(size 0.4064)
		(drill 0.2032)
		(layers "F.Cu" "B.Cu")
		(net "GND")
	)
	(via
		(at 386.504942 -230.714042)
		(size 0.4064)
		(drill 0.2032)
		(layers "F.Cu" "B.Cu")
		(net "GND")
	)
	(via
		(at 274.476464 -240.685066)
		(size 0.4826)
		(drill 0.254)
		(layers "F.Cu" "B.Cu")
		(net "GND")
	)
	(via
		(at 86.481158 -333.82839)
		(size 0.49022)
		(drill 0.254)
		(layers "F.Cu" "B.Cu")
		(net "GND")
	)
	(via
		(at 25.152096 -236.435392)
		(size 0.4826)
		(drill 0.254)
		(layers "F.Cu" "B.Cu")
		(net "GND")
	)
	(via
		(at 112.773714 -182.076598)
		(size 0.508)
		(drill 0.254)
		(layers "F.Cu" "B.Cu")
		(net "GND")
	)
	(via
		(at 332.697074 -416.020504)
		(size 0.4572)
		(drill 0.254)
		(layers "F.Cu" "B.Cu")
		(net "GND")
	)
	(via
		(at 135.574786 -278.13635)
		(size 0.4064)
		(drill 0.2032)
		(layers "F.Cu" "B.Cu")
		(net "GND")
	)
	(via
		(at 53.562758 -346.322142)
		(size 0.49022)
		(drill 0.254)
		(layers "F.Cu" "B.Cu")
		(net "GND")
	)
	(via
		(at 105.500932 -270.03629)
		(size 0.4064)
		(drill 0.2032)
		(layers "F.Cu" "B.Cu")
		(net "GND")
	)
	(via
		(at 269.648178 -232.184956)
		(size 0.4826)
		(drill 0.254)
		(layers "F.Cu" "B.Cu")
		(net "GND")
	)
	(via
		(at 380.091188 -398.542002)
		(size 0.4064)
		(drill 0.2032)
		(layers "F.Cu" "B.Cu")
		(net "GND")
	)
	(via
		(at 445.7319 -77.19822)
		(size 0.508)
		(drill 0.254)
		(layers "F.Cu" "B.Cu")
		(net "GND")
	)
	(via
		(at 49.168304 -240.68532)
		(size 0.4826)
		(drill 0.254)
		(layers "F.Cu" "B.Cu")
		(net "GND")
	)
	(via
		(at 307.918358 -421.586152)
		(size 0.4572)
		(drill 0.254)
		(layers "F.Cu" "B.Cu")
		(net "GND")
	)
	(via
		(at 369.414806 -273.27606)
		(size 0.4064)
		(drill 0.2032)
		(layers "F.Cu" "B.Cu")
		(net "GND")
	)
	(via
		(at 49.778666 -27.803348)
		(size 0.508)
		(drill 0.254)
		(layers "F.Cu" "B.Cu")
		(net "GND")
	)
	(via
		(at 96.27108 -242.05438)
		(size 0.4064)
		(drill 0.2032)
		(layers "F.Cu" "B.Cu")
		(net "GND")
	)
	(via
		(at 355.58476 -415.830258)
		(size 0.508)
		(drill 0.254)
		(layers "F.Cu" "B.Cu")
		(net "GND")
	)
	(via
		(at 130.40487 -269.226284)
		(size 0.4064)
		(drill 0.2032)
		(layers "F.Cu" "B.Cu")
		(net "GND")
	)
	(via
		(at 130.349752 -430.299622)
		(size 0.4572)
		(drill 0.2032)
		(layers "F.Cu" "B.Cu")
		(net "GND")
	)
	(via
		(at 407.349706 -429.147224)
		(size 0.4572)
		(drill 0.2032)
		(layers "F.Cu" "B.Cu")
		(net "GND")
	)
	(via
		(at 128.994662 -270.03629)
		(size 0.4064)
		(drill 0.2032)
		(layers "F.Cu" "B.Cu")
		(net "GND")
	)
	(via
		(at 114.916458 -391.830814)
		(size 0.4064)
		(drill 0.2032)
		(layers "F.Cu" "B.Cu")
		(net "GND")
	)
	(via
		(at 176.072038 -235.585254)
		(size 0.4826)
		(drill 0.254)
		(layers "F.Cu" "B.Cu")
		(net "GND")
	)
	(via
		(at 71.277734 -377.617228)
		(size 0.508)
		(drill 0.254)
		(layers "F.Cu" "B.Cu")
		(net "GND")
	)
	(via
		(at 140.274802 -276.516338)
		(size 0.4064)
		(drill 0.2032)
		(layers "F.Cu" "B.Cu")
		(net "GND")
	)
	(via
		(at 306.386738 -419.046152)
		(size 0.4572)
		(drill 0.254)
		(layers "F.Cu" "B.Cu")
		(net "GND")
	)
	(via
		(at 338.101178 -233.14406)
		(size 0.4064)
		(drill 0.2032)
		(layers "F.Cu" "B.Cu")
		(net "GND")
	)
	(via
		(at 35.411664 -202.435206)
		(size 0.4826)
		(drill 0.254)
		(layers "F.Cu" "B.Cu")
		(net "GND")
	)
	(via
		(at 347.33103 -274.086066)
		(size 0.4064)
		(drill 0.2032)
		(layers "F.Cu" "B.Cu")
		(net "GND")
	)
	(via
		(at 291.162486 -285.310072)
		(size 0.4826)
		(drill 0.254)
		(layers "F.Cu" "B.Cu")
		(net "GND")
	)
	(via
		(at 127.212344 -30.249368)
		(size 0.508)
		(drill 0.254)
		(layers "F.Cu" "B.Cu")
		(net "GND")
	)
	(via
		(at 100.56749 -182.127144)
		(size 0.49022)
		(drill 0.254)
		(layers "F.Cu" "B.Cu")
		(net "GND")
	)
	(via
		(at 198.631556 -342.864948)
		(size 0.508)
		(drill 0.254)
		(layers "F.Cu" "B.Cu")
		(net "GND")
	)
	(via
		(at 145.349722 -431.29962)
		(size 0.4572)
		(drill 0.2032)
		(layers "F.Cu" "B.Cu")
		(net "GND")
	)
	(via
		(at 146.948906 -412.570168)
		(size 0.4064)
		(drill 0.2032)
		(layers "F.Cu" "B.Cu")
		(net "GND")
	)
	(via
		(at 277.192232 -299.33519)
		(size 0.4826)
		(drill 0.254)
		(layers "F.Cu" "B.Cu")
		(net "GND")
	)
	(via
		(at 183.616092 -251.735336)
		(size 0.4826)
		(drill 0.254)
		(layers "F.Cu" "B.Cu")
		(net "GND")
	)
	(via
		(at 427.456092 -318.885062)
		(size 0.4826)
		(drill 0.254)
		(layers "F.Cu" "B.Cu")
		(net "GND")
	)
	(via
		(at 327.203308 -103.058214)
		(size 0.508)
		(drill 0.254)
		(layers "F.Cu" "B.Cu")
		(net "GND")
	)
	(via
		(at 166.591742 -362.926376)
		(size 0.508)
		(drill 0.254)
		(layers "F.Cu" "B.Cu")
		(net "GND")
	)
	(via
		(at 71.249794 -436.347362)
		(size 0.4572)
		(drill 0.2032)
		(layers "F.Cu" "B.Cu")
		(net "GND")
	)
	(via
		(at 18.763742 -193.107564)
		(size 0.4826)
		(drill 0.254)
		(layers "F.Cu" "B.Cu")
		(net "GND")
	)
	(via
		(at 116.228114 -406.370536)
		(size 0.4572)
		(drill 0.254)
		(layers "F.Cu" "B.Cu")
		(net "GND")
	)
	(via
		(at 367.234724 -249.34418)
		(size 0.4064)
		(drill 0.2032)
		(layers "F.Cu" "B.Cu")
		(net "GND")
	)
	(via
		(at 94.861126 -238.00435)
		(size 0.4064)
		(drill 0.2032)
		(layers "F.Cu" "B.Cu")
		(net "GND")
	)
	(via
		(at 202.147932 -283.185362)
		(size 0.4826)
		(drill 0.254)
		(layers "F.Cu" "B.Cu")
		(net "GND")
	)
	(via
		(at 112.81791 -174.507398)
		(size 0.508)
		(drill 0.254)
		(layers "F.Cu" "B.Cu")
		(net "GND")
	)
	(via
		(at 415.083752 -199.885046)
		(size 0.4826)
		(drill 0.254)
		(layers "F.Cu" "B.Cu")
		(net "GND")
	)
	(via
		(at 348.604078 -160.573466)
		(size 0.49022)
		(drill 0.254)
		(layers "F.Cu" "B.Cu")
		(net "GND")
	)
	(via
		(at 337.987132 -137.909046)
		(size 0.508)
		(drill 0.254)
		(layers "F.Cu" "B.Cu")
		(net "GND")
	)
	(via
		(at 104.58831 -182.076598)
		(size 0.508)
		(drill 0.254)
		(layers "F.Cu" "B.Cu")
		(net "GND")
	)
	(via
		(at 53.808884 -410.030168)
		(size 0.4064)
		(drill 0.2032)
		(layers "F.Cu" "B.Cu")
		(net "GND")
	)
	(via
		(at 121.644664 -248.534428)
		(size 0.4064)
		(drill 0.2032)
		(layers "F.Cu" "B.Cu")
		(net "GND")
	)
	(via
		(at 251.102622 -48.094138)
		(size 0.508)
		(drill 0.254)
		(layers "F.Cu" "B.Cu")
		(net "GND")
	)
	(via
		(at 183.599582 -349.356172)
		(size 0.49022)
		(drill 0.254)
		(layers "F.Cu" "B.Cu")
		(net "GND")
	)
	(via
		(at 268.492478 -192.21831)
		(size 0.4826)
		(drill 0.254)
		(layers "F.Cu" "B.Cu")
		(net "GND")
	)
	(via
		(at 47.362618 -345.555824)
		(size 0.49022)
		(drill 0.254)
		(layers "F.Cu" "B.Cu")
		(net "GND")
	)
	(via
		(at 384.349498 -427.699678)
		(size 0.4572)
		(drill 0.2032)
		(layers "F.Cu" "B.Cu")
		(net "GND")
	)
	(via
		(at 81.293462 -22.556724)
		(size 0.508)
		(drill 0.254)
		(layers "F.Cu" "B.Cu")
		(net "GND")
	)
	(via
		(at 42.9133 -104.8893)
		(size 0.508)
		(drill 0.254)
		(layers "F.Cu" "B.Cu")
		(net "GND")
	)
	(via
		(at 324.739508 -333.048864)
		(size 0.49022)
		(drill 0.254)
		(layers "F.Cu" "B.Cu")
		(net "GND")
	)
	(via
		(at 17.641062 -19.137122)
		(size 0.508)
		(drill 0.254)
		(layers "F.Cu" "B.Cu")
		(net "GND")
	)
	(via
		(at 99.177094 -69.899276)
		(size 0.508)
		(drill 0.254)
		(layers "F.Cu" "B.Cu")
		(net "GND")
	)
	(via
		(at 58.272426 -193.832226)
		(size 0.4826)
		(drill 0.254)
		(layers "F.Cu" "B.Cu")
		(net "GND")
	)
	(via
		(at 392.349482 -431.29962)
		(size 0.4572)
		(drill 0.2032)
		(layers "F.Cu" "B.Cu")
		(net "GND")
	)
	(via
		(at 351.076514 -419.046152)
		(size 0.4572)
		(drill 0.254)
		(layers "F.Cu" "B.Cu")
		(net "GND")
	)
	(via
		(at 336.521044 -261.935976)
		(size 0.4064)
		(drill 0.2032)
		(layers "F.Cu" "B.Cu")
		(net "GND")
	)
	(via
		(at 336.051144 -293.525956)
		(size 0.4064)
		(drill 0.2032)
		(layers "F.Cu" "B.Cu")
		(net "GND")
	)
	(via
		(at 321.816222 -402.284438)
		(size 0.4572)
		(drill 0.254)
		(layers "F.Cu" "B.Cu")
		(net "GND")
	)
	(via
		(at 187.060078 -317.185294)
		(size 0.4826)
		(drill 0.254)
		(layers "F.Cu" "B.Cu")
		(net "GND")
	)
	(via
		(at 106.030014 -417.562284)
		(size 0.508)
		(drill 0.254)
		(layers "F.Cu" "B.Cu")
		(net "GND")
	)
	(via
		(at 17.608042 -216.035382)
		(size 0.4826)
		(drill 0.254)
		(layers "F.Cu" "B.Cu")
		(net "GND")
	)
	(via
		(at 349.681038 -266.796012)
		(size 0.4064)
		(drill 0.2032)
		(layers "F.Cu" "B.Cu")
		(net "GND")
	)
	(via
		(at 45.039788 -380.57328)
		(size 0.508)
		(drill 0.254)
		(layers "F.Cu" "B.Cu")
		(net "GND")
	)
	(via
		(at 94.18955 -189.526926)
		(size 0.508)
		(drill 0.254)
		(layers "F.Cu" "B.Cu")
		(net "GND")
	)
	(via
		(at 92.981018 -255.824482)
		(size 0.4064)
		(drill 0.2032)
		(layers "F.Cu" "B.Cu")
		(net "GND")
	)
	(via
		(at 427.17212 -348.530926)
		(size 0.508)
		(drill 0.254)
		(layers "F.Cu" "B.Cu")
		(net "GND")
	)
	(via
		(at 430.17186 -199.885046)
		(size 0.4826)
		(drill 0.254)
		(layers "F.Cu" "B.Cu")
		(net "GND")
	)
	(via
		(at 323.507354 -417.778184)
		(size 0.4572)
		(drill 0.254)
		(layers "F.Cu" "B.Cu")
		(net "GND")
	)
	(via
		(at 93.450918 -250.15444)
		(size 0.4064)
		(drill 0.2032)
		(layers "F.Cu" "B.Cu")
		(net "GND")
	)
	(via
		(at 138.564874 -242.05438)
		(size 0.4064)
		(drill 0.2032)
		(layers "F.Cu" "B.Cu")
		(net "GND")
	)
	(via
		(at 366.764824 -242.054126)
		(size 0.4064)
		(drill 0.2032)
		(layers "F.Cu" "B.Cu")
		(net "GND")
	)
	(via
		(at 187.931552 -356.831646)
		(size 0.508)
		(drill 0.254)
		(layers "F.Cu" "B.Cu")
		(net "GND")
	)
	(via
		(at 153.444194 -391.830814)
		(size 0.4064)
		(drill 0.2032)
		(layers "F.Cu" "B.Cu")
		(net "GND")
	)
	(via
		(at 341.691214 -277.32609)
		(size 0.4064)
		(drill 0.2032)
		(layers "F.Cu" "B.Cu")
		(net "GND")
	)
	(via
		(at 96.335596 -407.638504)
		(size 0.4572)
		(drill 0.254)
		(layers "F.Cu" "B.Cu")
		(net "GND")
	)
	(via
		(at 164.465 -427.4439)
		(size 0.508)
		(drill 0.254)
		(layers "F.Cu" "B.Cu")
		(net "GND")
	)
	(via
		(at 312.451496 -382.34493)
		(size 0.508)
		(drill 0.254)
		(layers "F.Cu" "B.Cu")
		(net "GND")
	)
	(via
		(at 107.85094 -290.286186)
		(size 0.4064)
		(drill 0.2032)
		(layers "F.Cu" "B.Cu")
		(net "GND")
	)
	(via
		(at 417.844224 -402.259038)
		(size 0.4572)
		(drill 0.254)
		(layers "F.Cu" "B.Cu")
		(net "GND")
	)
	(via
		(at 427.56582 -388.917688)
		(size 0.508)
		(drill 0.254)
		(layers "F.Cu" "B.Cu")
		(net "GND")
	)
	(via
		(at 305.983894 -227.935028)
		(size 0.4826)
		(drill 0.254)
		(layers "F.Cu" "B.Cu")
		(net "GND")
	)
	(via
		(at 302.300386 -344.781124)
		(size 0.49022)
		(drill 0.254)
		(layers "F.Cu" "B.Cu")
		(net "GND")
	)
	(via
		(at 103.92791 -182.076598)
		(size 0.508)
		(drill 0.254)
		(layers "F.Cu" "B.Cu")
		(net "GND")
	)
	(via
		(at 153.598372 -65.420748)
		(size 0.508)
		(drill 0.254)
		(layers "F.Cu" "B.Cu")
		(net "GND")
	)
	(via
		(at 176.192688 -8.301736)
		(size 0.508)
		(drill 0.254)
		(layers "F.Cu" "B.Cu")
		(net "GND")
	)
	(via
		(at 269.648178 -316.335156)
		(size 0.4826)
		(drill 0.254)
		(layers "F.Cu" "B.Cu")
		(net "GND")
	)
	(via
		(at 237.616238 -49.76495)
		(size 0.508)
		(drill 0.254)
		(layers "F.Cu" "B.Cu")
		(net "GND")
	)
	(via
		(at 355.791008 -283.806138)
		(size 0.4064)
		(drill 0.2032)
		(layers "F.Cu" "B.Cu")
		(net "GND")
	)
	(via
		(at 130.87477 -270.03629)
		(size 0.4064)
		(drill 0.2032)
		(layers "F.Cu" "B.Cu")
		(net "GND")
	)
	(via
		(at 401.255992 -136.231376)
		(size 0.508)
		(drill 0.254)
		(layers "F.Cu" "B.Cu")
		(net "GND")
	)
	(via
		(at 47.596552 -405.098504)
		(size 0.4572)
		(drill 0.254)
		(layers "F.Cu" "B.Cu")
		(net "GND")
	)
	(via
		(at 392.749278 -178.078638)
		(size 0.508)
		(drill 0.254)
		(layers "F.Cu" "B.Cu")
		(net "GND")
	)
	(via
		(at 81.701132 -225.044508)
		(size 0.4064)
		(drill 0.2032)
		(layers "F.Cu" "B.Cu")
		(net "GND")
	)
	(via
		(at 80.591152 -293.52621)
		(size 0.4064)
		(drill 0.2032)
		(layers "F.Cu" "B.Cu")
		(net "GND")
	)
	(via
		(at 115.955318 -411.936184)
		(size 0.4572)
		(drill 0.254)
		(layers "F.Cu" "B.Cu")
		(net "GND")
	)
	(via
		(at 374.754902 -247.724168)
		(size 0.4064)
		(drill 0.2032)
		(layers "F.Cu" "B.Cu")
		(net "GND")
	)
	(via
		(at 119.291354 -407.638504)
		(size 0.4572)
		(drill 0.254)
		(layers "F.Cu" "B.Cu")
		(net "GND")
	)
	(via
		(at 375.054876 -286.236156)
		(size 0.4064)
		(drill 0.2032)
		(layers "F.Cu" "B.Cu")
		(net "GND")
	)
	(via
		(at 27.867864 -312.085228)
		(size 0.4826)
		(drill 0.254)
		(layers "F.Cu" "B.Cu")
		(net "GND")
	)
	(via
		(at 130.878072 -295.98366)
		(size 0.4064)
		(drill 0.2032)
		(layers "F.Cu" "B.Cu")
		(net "GND")
	)
	(via
		(at 419.912038 -225.385122)
		(size 0.4826)
		(drill 0.254)
		(layers "F.Cu" "B.Cu")
		(net "GND")
	)
	(via
		(at 419.951154 -441.227718)
		(size 0.508)
		(drill 0.254)
		(layers "F.Cu" "B.Cu")
		(net "GND")
	)
	(via
		(at 98.451162 -267.606272)
		(size 0.4064)
		(drill 0.2032)
		(layers "F.Cu" "B.Cu")
		(net "GND")
	)
	(via
		(at 140.444728 -240.434368)
		(size 0.4064)
		(drill 0.2032)
		(layers "F.Cu" "B.Cu")
		(net "GND")
	)
	(via
		(at 107.38104 -294.336216)
		(size 0.4064)
		(drill 0.2032)
		(layers "F.Cu" "B.Cu")
		(net "GND")
	)
	(via
		(at 44.19092 -388.297674)
		(size 0.508)
		(drill 0.254)
		(layers "F.Cu" "B.Cu")
		(net "GND")
	)
	(via
		(at 388.384796 -227.474272)
		(size 0.4064)
		(drill 0.2032)
		(layers "F.Cu" "B.Cu")
		(net "GND")
	)
	(via
		(at 147.042886 -277.870412)
		(size 0.4064)
		(drill 0.2032)
		(layers "F.Cu" "B.Cu")
		(net "GND")
	)
	(via
		(at 446.471802 -417.41471)
		(size 0.508)
		(drill 0.254)
		(layers "F.Cu" "B.Cu")
		(net "GND")
	)
	(via
		(at 124.7648 -285.426404)
		(size 0.4064)
		(drill 0.2032)
		(layers "F.Cu" "B.Cu")
		(net "GND")
	)
	(via
		(at 179.516024 -216.035382)
		(size 0.4826)
		(drill 0.254)
		(layers "F.Cu" "B.Cu")
		(net "GND")
	)
	(via
		(at 105.671112 -250.15444)
		(size 0.4064)
		(drill 0.2032)
		(layers "F.Cu" "B.Cu")
		(net "GND")
	)
	(via
		(at 122.354594 -409.396184)
		(size 0.4572)
		(drill 0.254)
		(layers "F.Cu" "B.Cu")
		(net "GND")
	)
	(via
		(at 66.288666 -169.327576)
		(size 0.49022)
		(drill 0.254)
		(layers "F.Cu" "B.Cu")
		(net "GND")
	)
	(via
		(at 416.289998 -392.999722)
		(size 0.4064)
		(drill 0.2032)
		(layers "F.Cu" "B.Cu")
		(net "GND")
	)
	(via
		(at 21.70811 -215.185244)
		(size 0.4826)
		(drill 0.254)
		(layers "F.Cu" "B.Cu")
		(net "GND")
	)
	(via
		(at 388.384796 -242.054126)
		(size 0.4064)
		(drill 0.2032)
		(layers "F.Cu" "B.Cu")
		(net "GND")
	)
	(via
		(at 248.845832 -421.48125)
		(size 0.508)
		(drill 0.254)
		(layers "F.Cu" "B.Cu")
		(net "GND")
	)
	(via
		(at 318.773556 -383.00533)
		(size 0.508)
		(drill 0.254)
		(layers "F.Cu" "B.Cu")
		(net "GND")
	)
	(via
		(at 353.165918 -173.40072)
		(size 0.508)
		(drill 0.254)
		(layers "F.Cu" "B.Cu")
		(net "GND")
	)
	(via
		(at 185.6486 -343.441274)
		(size 0.508)
		(drill 0.254)
		(layers "F.Cu" "B.Cu")
		(net "GND")
	)
	(via
		(at 378.04471 -238.814102)
		(size 0.4064)
		(drill 0.2032)
		(layers "F.Cu" "B.Cu")
		(net "GND")
	)
	(via
		(at 118.184676 -277.326344)
		(size 0.4064)
		(drill 0.2032)
		(layers "F.Cu" "B.Cu")
		(net "GND")
	)
	(via
		(at 280.635964 -264.48512)
		(size 0.4826)
		(drill 0.254)
		(layers "F.Cu" "B.Cu")
		(net "GND")
	)
	(via
		(at 128.994662 -276.516338)
		(size 0.4064)
		(drill 0.2032)
		(layers "F.Cu" "B.Cu")
		(net "GND")
	)
	(via
		(at 353.43084 -262.18007)
		(size 0.4826)
		(drill 0.254)
		(layers "F.Cu" "B.Cu")
		(net "GND")
	)
	(via
		(at 91.871038 -288.666174)
		(size 0.4064)
		(drill 0.2032)
		(layers "F.Cu" "B.Cu")
		(net "GND")
	)
	(via
		(at 161.187384 -373.30253)
		(size 0.508)
		(drill 0.254)
		(layers "F.Cu" "B.Cu")
		(net "GND")
	)
	(via
		(at 384.42138 -299.27931)
		(size 0.508)
		(drill 0.254)
		(layers "F.Cu" "B.Cu")
		(net "GND")
	)
	(via
		(at 253.506224 -131.626356)
		(size 0.508)
		(drill 0.254)
		(layers "F.Cu" "B.Cu")
		(net "GND")
	)
	(via
		(at 28.35402 -351.862898)
		(size 0.508)
		(drill 0.254)
		(layers "F.Cu" "B.Cu")
		(net "GND")
	)
	(via
		(at 419.04412 -402.309838)
		(size 0.4572)
		(drill 0.254)
		(layers "F.Cu" "B.Cu")
		(net "GND")
	)
	(via
		(at 367.476278 -178.62931)
		(size 0.508)
		(drill 0.254)
		(layers "F.Cu" "B.Cu")
		(net "GND")
	)
	(via
		(at 173.35627 -219.435426)
		(size 0.4826)
		(drill 0.254)
		(layers "F.Cu" "B.Cu")
		(net "GND")
	)
	(via
		(at 355.491034 -243.674138)
		(size 0.4064)
		(drill 0.2032)
		(layers "F.Cu" "B.Cu")
		(net "GND")
	)
	(via
		(at 84.99094 -224.234502)
		(size 0.4064)
		(drill 0.2032)
		(layers "F.Cu" "B.Cu")
		(net "GND")
	)
	(via
		(at 81.292192 -413.204152)
		(size 0.4572)
		(drill 0.254)
		(layers "F.Cu" "B.Cu")
		(net "GND")
	)
	(via
		(at 361.124754 -242.054126)
		(size 0.4064)
		(drill 0.2032)
		(layers "F.Cu" "B.Cu")
		(net "GND")
	)
	(via
		(at 24.034496 -314.210446)
		(size 0.4826)
		(drill 0.254)
		(layers "F.Cu" "B.Cu")
		(net "GND")
	)
	(via
		(at 89.8398 -139.164822)
		(size 0.508)
		(drill 0.254)
		(layers "F.Cu" "B.Cu")
		(net "GND")
	)
	(via
		(at 127.584708 -269.226284)
		(size 0.4064)
		(drill 0.2032)
		(layers "F.Cu" "B.Cu")
		(net "GND")
	)
	(via
		(at 121.004838 -274.08632)
		(size 0.4064)
		(drill 0.2032)
		(layers "F.Cu" "B.Cu")
		(net "GND")
	)
	(via
		(at 428.009558 -4.963414)
		(size 0.508)
		(drill 0.254)
		(layers "F.Cu" "B.Cu")
		(net "GND")
	)
	(via
		(at 454.033636 -64.457326)
		(size 0.508)
		(drill 0.254)
		(layers "F.Cu" "B.Cu")
		(net "GND")
	)
	(via
		(at 188.712094 -118.242842)
		(size 0.4572)
		(drill 0.254)
		(layers "F.Cu" "B.Cu")
		(net "GND")
	)
	(via
		(at 326.651112 -285.42615)
		(size 0.4064)
		(drill 0.2032)
		(layers "F.Cu" "B.Cu")
		(net "GND")
	)
	(via
		(at 282.020264 -294.235124)
		(size 0.4826)
		(drill 0.254)
		(layers "F.Cu" "B.Cu")
		(net "GND")
	)
	(via
		(at 90.481912 -413.204152)
		(size 0.4572)
		(drill 0.254)
		(layers "F.Cu" "B.Cu")
		(net "GND")
	)
	(via
		(at 349.211138 -291.905944)
		(size 0.4064)
		(drill 0.2032)
		(layers "F.Cu" "B.Cu")
		(net "GND")
	)
	(via
		(at 277.192232 -282.33497)
		(size 0.4826)
		(drill 0.254)
		(layers "F.Cu" "B.Cu")
		(net "GND")
	)
	(via
		(at 431.711608 -353.12858)
		(size 0.49022)
		(drill 0.254)
		(layers "F.Cu" "B.Cu")
		(net "GND")
	)
	(via
		(at 437.715914 -199.885046)
		(size 0.4826)
		(drill 0.254)
		(layers "F.Cu" "B.Cu")
		(net "GND")
	)
	(via
		(at 164.427916 -234.73537)
		(size 0.4826)
		(drill 0.254)
		(layers "F.Cu" "B.Cu")
		(net "GND")
	)
	(via
		(at 318.776096 -379.88113)
		(size 0.508)
		(drill 0.254)
		(layers "F.Cu" "B.Cu")
		(net "GND")
	)
	(via
		(at 325.24954 -428.851314)
		(size 0.4572)
		(drill 0.2032)
		(layers "F.Cu" "B.Cu")
		(net "GND")
	)
	(via
		(at 104.58831 -181.416198)
		(size 0.508)
		(drill 0.254)
		(layers "F.Cu" "B.Cu")
		(net "GND")
	)
	(via
		(at 87.171022 -278.946356)
		(size 0.4064)
		(drill 0.2032)
		(layers "F.Cu" "B.Cu")
		(net "GND")
	)
	(via
		(at 265.54811 -223.6851)
		(size 0.4826)
		(drill 0.254)
		(layers "F.Cu" "B.Cu")
		(net "GND")
	)
	(via
		(at 31.811214 -344.772234)
		(size 0.508)
		(drill 0.254)
		(layers "F.Cu" "B.Cu")
		(net "GND")
	)
	(via
		(at 174.687738 -312.085228)
		(size 0.4826)
		(drill 0.254)
		(layers "F.Cu" "B.Cu")
		(net "GND")
	)
	(via
		(at 143.73479 -231.524302)
		(size 0.4064)
		(drill 0.2032)
		(layers "F.Cu" "B.Cu")
		(net "GND")
	)
	(via
		(at 25.152096 -273.835368)
		(size 0.4826)
		(drill 0.254)
		(layers "F.Cu" "B.Cu")
		(net "GND")
	)
	(via
		(at 376.93473 -265.176)
		(size 0.4064)
		(drill 0.2032)
		(layers "F.Cu" "B.Cu")
		(net "GND")
	)
	(via
		(at 335.98993 -392.999722)
		(size 0.4064)
		(drill 0.2032)
		(layers "F.Cu" "B.Cu")
		(net "GND")
	)
	(via
		(at 421.029638 -314.210192)
		(size 0.4826)
		(drill 0.254)
		(layers "F.Cu" "B.Cu")
		(net "GND")
	)
	(via
		(at 108.02112 -242.864386)
		(size 0.4064)
		(drill 0.2032)
		(layers "F.Cu" "B.Cu")
		(net "GND")
	)
	(via
		(at 59.428126 -244.935248)
		(size 0.4826)
		(drill 0.254)
		(layers "F.Cu" "B.Cu")
		(net "GND")
	)
	(via
		(at 48.769524 -407.00452)
		(size 0.4064)
		(drill 0.2032)
		(layers "F.Cu" "B.Cu")
		(net "GND")
	)
	(via
		(at 330.880974 -294.335962)
		(size 0.4064)
		(drill 0.2032)
		(layers "F.Cu" "B.Cu")
		(net "GND")
	)
	(via
		(at 42.055796 -10.16508)
		(size 0.508)
		(drill 0.254)
		(layers "F.Cu" "B.Cu")
		(net "GND")
	)
	(via
		(at 388.21487 -292.71595)
		(size 0.4064)
		(drill 0.2032)
		(layers "F.Cu" "B.Cu")
		(net "GND")
	)
	(via
		(at 183.616092 -310.385206)
		(size 0.4826)
		(drill 0.254)
		(layers "F.Cu" "B.Cu")
		(net "GND")
	)
	(via
		(at 439.703718 -436.94731)
		(size 0.508)
		(drill 0.254)
		(layers "F.Cu" "B.Cu")
		(net "GND")
	)
	(via
		(at 370.35486 -261.935976)
		(size 0.4064)
		(drill 0.2032)
		(layers "F.Cu" "B.Cu")
		(net "GND")
	)
	(via
		(at 388.34949 -438.499758)
		(size 0.4572)
		(drill 0.2032)
		(layers "F.Cu" "B.Cu")
		(net "GND")
	)
	(via
		(at 345.679776 -161.554668)
		(size 0.49022)
		(drill 0.254)
		(layers "F.Cu" "B.Cu")
		(net "GND")
	)
	(via
		(at 346.195904 -380.54153)
		(size 0.508)
		(drill 0.254)
		(layers "F.Cu" "B.Cu")
		(net "GND")
	)
	(via
		(at 88.580976 -289.47618)
		(size 0.4064)
		(drill 0.2032)
		(layers "F.Cu" "B.Cu")
		(net "GND")
	)
	(via
		(at 91.871038 -291.906198)
		(size 0.4064)
		(drill 0.2032)
		(layers "F.Cu" "B.Cu")
		(net "GND")
	)
	(via
		(at 208.38287 -79.20482)
		(size 0.508)
		(drill 0.254)
		(layers "F.Cu" "B.Cu")
		(net "GND")
	)
	(via
		(at 304.652426 -228.785166)
		(size 0.4826)
		(drill 0.254)
		(layers "F.Cu" "B.Cu")
		(net "GND")
	)
	(via
		(at 297.108372 -284.88513)
		(size 0.4826)
		(drill 0.254)
		(layers "F.Cu" "B.Cu")
		(net "GND")
	)
	(via
		(at 114.59464 -247.724422)
		(size 0.4064)
		(drill 0.2032)
		(layers "F.Cu" "B.Cu")
		(net "GND")
	)
	(via
		(at 344.041222 -268.416024)
		(size 0.4064)
		(drill 0.2032)
		(layers "F.Cu" "B.Cu")
		(net "GND")
	)
	(via
		(at 128.569466 -404.46452)
		(size 0.4064)
		(drill 0.2032)
		(layers "F.Cu" "B.Cu")
		(net "GND")
	)
	(via
		(at 351.261172 -221.80423)
		(size 0.4064)
		(drill 0.2032)
		(layers "F.Cu" "B.Cu")
		(net "GND")
	)
	(via
		(at 47.784004 -262.785352)
		(size 0.4826)
		(drill 0.254)
		(layers "F.Cu" "B.Cu")
		(net "GND")
	)
	(via
		(at 27.867864 -202.435206)
		(size 0.4826)
		(drill 0.254)
		(layers "F.Cu" "B.Cu")
		(net "GND")
	)
	(via
		(at 399.125694 -179.110386)
		(size 0.49022)
		(drill 0.254)
		(layers "F.Cu" "B.Cu")
		(net "GND")
	)
	(via
		(at 58.616596 -382.85293)
		(size 0.4064)
		(drill 0.2032)
		(layers "F.Cu" "B.Cu")
		(net "GND")
	)
	(via
		(at 307.368194 -207.535018)
		(size 0.4826)
		(drill 0.254)
		(layers "F.Cu" "B.Cu")
		(net "GND")
	)
	(via
		(at 391.674858 -226.664266)
		(size 0.4064)
		(drill 0.2032)
		(layers "F.Cu" "B.Cu")
		(net "GND")
	)
	(via
		(at 298.43984 -237.285022)
		(size 0.4826)
		(drill 0.254)
		(layers "F.Cu" "B.Cu")
		(net "GND")
	)
	(via
		(at 103.791004 -251.774452)
		(size 0.4064)
		(drill 0.2032)
		(layers "F.Cu" "B.Cu")
		(net "GND")
	)
	(via
		(at 347.801184 -286.236156)
		(size 0.4064)
		(drill 0.2032)
		(layers "F.Cu" "B.Cu")
		(net "GND")
	)
	(via
		(at 326.570594 -416.020504)
		(size 0.4572)
		(drill 0.254)
		(layers "F.Cu" "B.Cu")
		(net "GND")
	)
	(via
		(at 99.561142 -252.584458)
		(size 0.4064)
		(drill 0.2032)
		(layers "F.Cu" "B.Cu")
		(net "GND")
	)
	(via
		(at 40.23995 -236.435392)
		(size 0.4826)
		(drill 0.254)
		(layers "F.Cu" "B.Cu")
		(net "GND")
	)
	(via
		(at 386.804916 -288.66592)
		(size 0.4064)
		(drill 0.2032)
		(layers "F.Cu" "B.Cu")
		(net "GND")
	)
	(via
		(at 139.202414 -405.098504)
		(size 0.4572)
		(drill 0.254)
		(layers "F.Cu" "B.Cu")
		(net "GND")
	)
	(via
		(at 44.340018 -215.185244)
		(size 0.4826)
		(drill 0.254)
		(layers "F.Cu" "B.Cu")
		(net "GND")
	)
	(via
		(at 335.078324 -334.574642)
		(size 0.49022)
		(drill 0.254)
		(layers "F.Cu" "B.Cu")
		(net "GND")
	)
	(via
		(at 50.499772 -312.085228)
		(size 0.4826)
		(drill 0.254)
		(layers "F.Cu" "B.Cu")
		(net "GND")
	)
	(via
		(at 383.518156 -295.983406)
		(size 0.4064)
		(drill 0.2032)
		(layers "F.Cu" "B.Cu")
		(net "GND")
	)
	(via
		(at 143.264636 -238.814356)
		(size 0.4064)
		(drill 0.2032)
		(layers "F.Cu" "B.Cu")
		(net "GND")
	)
	(via
		(at 67.249802 -433.899564)
		(size 0.4572)
		(drill 0.2032)
		(layers "F.Cu" "B.Cu")
		(net "GND")
	)
	(via
		(at 38.195758 -344.781886)
		(size 0.49022)
		(drill 0.254)
		(layers "F.Cu" "B.Cu")
		(net "GND")
	)
	(via
		(at 331.821028 -271.656048)
		(size 0.4064)
		(drill 0.2032)
		(layers "F.Cu" "B.Cu")
		(net "GND")
	)
	(via
		(at 365.19104 -389.7122)
		(size 0.508)
		(drill 0.254)
		(layers "F.Cu" "B.Cu")
		(net "GND")
	)
	(via
		(at 388.68477 -278.946102)
		(size 0.4064)
		(drill 0.2032)
		(layers "F.Cu" "B.Cu")
		(net "GND")
	)
	(via
		(at 358.61117 -269.22603)
		(size 0.4064)
		(drill 0.2032)
		(layers "F.Cu" "B.Cu")
		(net "GND")
	)
	(via
		(at 398.215104 -18.503138)
		(size 0.508)
		(drill 0.254)
		(layers "F.Cu" "B.Cu")
		(net "GND")
	)
	(via
		(at 105.671112 -235.574332)
		(size 0.4064)
		(drill 0.2032)
		(layers "F.Cu" "B.Cu")
		(net "GND")
	)
	(via
		(at 364.065058 -417.394898)
		(size 0.508)
		(drill 0.254)
		(layers "F.Cu" "B.Cu")
		(net "GND")
	)
	(via
		(at 214.95385 -85.23605)
		(size 0.508)
		(drill 0.254)
		(layers "F.Cu" "B.Cu")
		(net "GND")
	)
	(via
		(at 107.550966 -229.094538)
		(size 0.4064)
		(drill 0.2032)
		(layers "F.Cu" "B.Cu")
		(net "GND")
	)
	(via
		(at 375.524776 -262.745982)
		(size 0.4064)
		(drill 0.2032)
		(layers "F.Cu" "B.Cu")
		(net "GND")
	)
	(via
		(at 29.252164 -205.83525)
		(size 0.4826)
		(drill 0.254)
		(layers "F.Cu" "B.Cu")
		(net "GND")
	)
	(via
		(at 147.349718 -433.899564)
		(size 0.4572)
		(drill 0.2032)
		(layers "F.Cu" "B.Cu")
		(net "GND")
	)
	(via
		(at 403.349714 -426.69968)
		(size 0.4572)
		(drill 0.2032)
		(layers "F.Cu" "B.Cu")
		(net "GND")
	)
	(via
		(at 388.34949 -431.29962)
		(size 0.4572)
		(drill 0.2032)
		(layers "F.Cu" "B.Cu")
		(net "GND")
	)
	(via
		(at 90.196162 -372.15953)
		(size 0.508)
		(drill 0.254)
		(layers "F.Cu" "B.Cu")
		(net "GND")
	)
	(via
		(at 354.551234 -225.85426)
		(size 0.4064)
		(drill 0.2032)
		(layers "F.Cu" "B.Cu")
		(net "GND")
	)
	(via
		(at 353.911154 -291.905944)
		(size 0.4064)
		(drill 0.2032)
		(layers "F.Cu" "B.Cu")
		(net "GND")
	)
	(via
		(at 339.811106 -293.525956)
		(size 0.4064)
		(drill 0.2032)
		(layers "F.Cu" "B.Cu")
		(net "GND")
	)
	(via
		(at 32.695896 -269.58544)
		(size 0.4826)
		(drill 0.254)
		(layers "F.Cu" "B.Cu")
		(net "GND")
	)
	(via
		(at 153.349706 -439.651394)
		(size 0.4572)
		(drill 0.2032)
		(layers "F.Cu" "B.Cu")
		(net "GND")
	)
	(via
		(at 340.31936 -18.50644)
		(size 0.508)
		(drill 0.254)
		(layers "F.Cu" "B.Cu")
		(net "GND")
	)
	(via
		(at 275.175472 -351.858072)
		(size 0.508)
		(drill 0.254)
		(layers "F.Cu" "B.Cu")
		(net "GND")
	)
	(via
		(at 107.550966 -243.674392)
		(size 0.4064)
		(drill 0.2032)
		(layers "F.Cu" "B.Cu")
		(net "GND")
	)
	(via
		(at 320.949828 -43.700954)
		(size 0.508)
		(drill 0.254)
		(layers "F.Cu" "B.Cu")
		(net "GND")
	)
	(via
		(at 140.744702 -293.52621)
		(size 0.4064)
		(drill 0.2032)
		(layers "F.Cu" "B.Cu")
		(net "GND")
	)
	(via
		(at 54.210458 -202.010264)
		(size 0.4826)
		(drill 0.254)
		(layers "F.Cu" "B.Cu")
		(net "GND")
	)
	(via
		(at 146.742912 -235.030264)
		(size 0.4064)
		(drill 0.2032)
		(layers "F.Cu" "B.Cu")
		(net "GND")
	)
	(via
		(at 92.344494 -393.927838)
		(size 0.4572)
		(drill 0.254)
		(layers "F.Cu" "B.Cu")
		(net "GND")
	)
	(via
		(at 194.604132 -262.785352)
		(size 0.4826)
		(drill 0.254)
		(layers "F.Cu" "B.Cu")
		(net "GND")
	)
	(via
		(at 114.335306 -404.46452)
		(size 0.4064)
		(drill 0.2032)
		(layers "F.Cu" "B.Cu")
		(net "GND")
	)
	(via
		(at 2.76225 -249.865134)
		(size 0.508)
		(drill 0.254)
		(layers "F.Cu" "B.Cu")
		(net "GND")
	)
	(via
		(at 30.786578 -345.614244)
		(size 0.49022)
		(drill 0.254)
		(layers "F.Cu" "B.Cu")
		(net "GND")
	)
	(via
		(at 136.98474 -269.226284)
		(size 0.4064)
		(drill 0.2032)
		(layers "F.Cu" "B.Cu")
		(net "GND")
	)
	(via
		(at 389.161782 -415.38652)
		(size 0.4064)
		(drill 0.2032)
		(layers "F.Cu" "B.Cu")
		(net "GND")
	)
	(via
		(at 435.000146 -223.6851)
		(size 0.4826)
		(drill 0.254)
		(layers "F.Cu" "B.Cu")
		(net "GND")
	)
	(via
		(at 122.116596 -393.877038)
		(size 0.4572)
		(drill 0.254)
		(layers "F.Cu" "B.Cu")
		(net "GND")
	)
	(via
		(at 119.458486 -429.006)
		(size 0.508)
		(drill 0.254)
		(layers "F.Cu" "B.Cu")
		(net "GND")
	)
	(via
		(at 378.514864 -236.384084)
		(size 0.4064)
		(drill 0.2032)
		(layers "F.Cu" "B.Cu")
		(net "GND")
	)
	(via
		(at 415.7472 -111.501428)
		(size 0.508)
		(drill 0.254)
		(layers "F.Cu" "B.Cu")
		(net "GND")
	)
	(via
		(at 81.192878 -176.88941)
		(size 0.508)
		(drill 0.254)
		(layers "F.Cu" "B.Cu")
		(net "GND")
	)
	(via
		(at 186.569096 -25.084532)
		(size 0.508)
		(drill 0.254)
		(layers "F.Cu" "B.Cu")
		(net "GND")
	)
	(via
		(at 151.182578 -407.638504)
		(size 0.4572)
		(drill 0.254)
		(layers "F.Cu" "B.Cu")
		(net "GND")
	)
	(via
		(at 183.932322 -112.66297)
		(size 0.4572)
		(drill 0.254)
		(layers "F.Cu" "B.Cu")
		(net "GND")
	)
	(via
		(at 253.089664 -46.875192)
		(size 0.508)
		(drill 0.254)
		(layers "F.Cu" "B.Cu")
		(net "GND")
	)
	(via
		(at 27.867864 -199.8853)
		(size 0.4826)
		(drill 0.254)
		(layers "F.Cu" "B.Cu")
		(net "GND")
	)
	(via
		(at 326.442324 -335.554066)
		(size 0.49022)
		(drill 0.254)
		(layers "F.Cu" "B.Cu")
		(net "GND")
	)
	(via
		(at 202.147932 -317.185294)
		(size 0.4826)
		(drill 0.254)
		(layers "F.Cu" "B.Cu")
		(net "GND")
	)
	(via
		(at 191.160146 -213.485222)
		(size 0.4826)
		(drill 0.254)
		(layers "F.Cu" "B.Cu")
		(net "GND")
	)
	(via
		(at 375.018554 -412.212536)
		(size 0.4572)
		(drill 0.254)
		(layers "F.Cu" "B.Cu")
		(net "GND")
	)
	(via
		(at 0.762254 -49.067212)
		(size 0.508)
		(drill 0.254)
		(layers "F.Cu" "B.Cu")
		(net "GND")
	)
	(via
		(at 292.150546 -12.542266)
		(size 0.508)
		(drill 0.254)
		(layers "F.Cu" "B.Cu")
		(net "GND")
	)
	(via
		(at 235.0008 -281.392122)
		(size 0.508)
		(drill 0.254)
		(layers "F.Cu" "B.Cu")
		(net "GND")
	)
	(via
		(at 393.384786 -283.806138)
		(size 0.4064)
		(drill 0.2032)
		(layers "F.Cu" "B.Cu")
		(net "GND")
	)
	(via
		(at 384.208274 -420.318184)
		(size 0.4572)
		(drill 0.254)
		(layers "F.Cu" "B.Cu")
		(net "GND")
	)
	(via
		(at 391.974832 -261.935976)
		(size 0.4064)
		(drill 0.2032)
		(layers "F.Cu" "B.Cu")
		(net "GND")
	)
	(via
		(at 222.07093 -41.620948)
		(size 0.508)
		(drill 0.254)
		(layers "F.Cu" "B.Cu")
		(net "GND")
	)
	(via
		(at 328.061066 -271.656048)
		(size 0.4064)
		(drill 0.2032)
		(layers "F.Cu" "B.Cu")
		(net "GND")
	)
	(via
		(at 107.550966 -235.574332)
		(size 0.4064)
		(drill 0.2032)
		(layers "F.Cu" "B.Cu")
		(net "GND")
	)
	(via
		(at 342.801194 -241.24412)
		(size 0.4064)
		(drill 0.2032)
		(layers "F.Cu" "B.Cu")
		(net "GND")
	)
	(via
		(at 362.534708 -238.004096)
		(size 0.4064)
		(drill 0.2032)
		(layers "F.Cu" "B.Cu")
		(net "GND")
	)
	(via
		(at 113.48466 -278.946356)
		(size 0.4064)
		(drill 0.2032)
		(layers "F.Cu" "B.Cu")
		(net "GND")
	)
	(via
		(at 338.823554 -416.020504)
		(size 0.4572)
		(drill 0.254)
		(layers "F.Cu" "B.Cu")
		(net "GND")
	)
	(via
		(at 255.927098 -209.487008)
		(size 0.508)
		(drill 0.254)
		(layers "F.Cu" "B.Cu")
		(net "GND")
	)
	(via
		(at 333.230982 -283.806138)
		(size 0.4064)
		(drill 0.2032)
		(layers "F.Cu" "B.Cu")
		(net "GND")
	)
	(via
		(at 77.463142 -333.05369)
		(size 0.49022)
		(drill 0.254)
		(layers "F.Cu" "B.Cu")
		(net "GND")
	)
	(via
		(at 49.216564 -412.570168)
		(size 0.4064)
		(drill 0.2032)
		(layers "F.Cu" "B.Cu")
		(net "GND")
	)
	(via
		(at 90.706194 -386.449062)
		(size 0.4064)
		(drill 0.2032)
		(layers "F.Cu" "B.Cu")
		(net "GND")
	)
	(via
		(at 195.458334 -331.444346)
		(size 0.508)
		(drill 0.254)
		(layers "F.Cu" "B.Cu")
		(net "GND")
	)
	(via
		(at 350.151192 -285.42615)
		(size 0.4064)
		(drill 0.2032)
		(layers "F.Cu" "B.Cu")
		(net "GND")
	)
	(via
		(at 21.773388 -369.84305)
		(size 0.508)
		(drill 0.254)
		(layers "F.Cu" "B.Cu")
		(net "GND")
	)
	(via
		(at 43.693334 -347.287088)
		(size 0.49022)
		(drill 0.254)
		(layers "F.Cu" "B.Cu")
		(net "GND")
	)
	(via
		(at 345.451176 -293.525956)
		(size 0.4064)
		(drill 0.2032)
		(layers "F.Cu" "B.Cu")
		(net "GND")
	)
	(via
		(at 280.635964 -273.835114)
		(size 0.4826)
		(drill 0.254)
		(layers "F.Cu" "B.Cu")
		(net "GND")
	)
	(via
		(at 147.09013 -384.617722)
		(size 0.4064)
		(drill 0.2032)
		(layers "F.Cu" "B.Cu")
		(net "GND")
	)
	(via
		(at 156.050234 -407.638504)
		(size 0.4572)
		(drill 0.254)
		(layers "F.Cu" "B.Cu")
		(net "GND")
	)
	(via
		(at 401.349718 -439.651394)
		(size 0.4572)
		(drill 0.2032)
		(layers "F.Cu" "B.Cu")
		(net "GND")
	)
	(via
		(at 365.380778 -257.430016)
		(size 0.4826)
		(drill 0.254)
		(layers "F.Cu" "B.Cu")
		(net "GND")
	)
	(via
		(at 307.368194 -310.384952)
		(size 0.4826)
		(drill 0.254)
		(layers "F.Cu" "B.Cu")
		(net "GND")
	)
	(via
		(at 358.311196 -230.714296)
		(size 0.4064)
		(drill 0.2032)
		(layers "F.Cu" "B.Cu")
		(net "GND")
	)
	(via
		(at 20.59051 -313.360308)
		(size 0.4826)
		(drill 0.254)
		(layers "F.Cu" "B.Cu")
		(net "GND")
	)
	(via
		(at 290.70681 -345.566238)
		(size 0.49022)
		(drill 0.254)
		(layers "F.Cu" "B.Cu")
		(net "GND")
	)
	(via
		(at 443.195964 -391.055606)
		(size 0.508)
		(drill 0.254)
		(layers "F.Cu" "B.Cu")
		(net "GND")
	)
	(via
		(at 381.954278 -182.220616)
		(size 0.49022)
		(drill 0.254)
		(layers "F.Cu" "B.Cu")
		(net "GND")
	)
	(via
		(at 179.516024 -292.535356)
		(size 0.4826)
		(drill 0.254)
		(layers "F.Cu" "B.Cu")
		(net "GND")
	)
	(via
		(at 388.063232 -376.75693)
		(size 0.508)
		(drill 0.254)
		(layers "F.Cu" "B.Cu")
		(net "GND")
	)
	(via
		(at 116.18214 -257.74523)
		(size 0.4826)
		(drill 0.254)
		(layers "F.Cu" "B.Cu")
		(net "GND")
	)
	(via
		(at 105.659936 -128.784096)
		(size 0.508)
		(drill 0.254)
		(layers "F.Cu" "B.Cu")
		(net "GND")
	)
	(via
		(at 419.435534 -419.046152)
		(size 0.4572)
		(drill 0.254)
		(layers "F.Cu" "B.Cu")
		(net "GND")
	)
	(via
		(at 239.98428 -293.654226)
		(size 0.508)
		(drill 0.254)
		(layers "F.Cu" "B.Cu")
		(net "GND")
	)
	(via
		(at 411.349698 -430.299622)
		(size 0.4572)
		(drill 0.2032)
		(layers "F.Cu" "B.Cu")
		(net "GND")
	)
	(via
		(at 64.268096 -144.163288)
		(size 0.6604)
		(drill 0.3302)
		(layers "F.Cu" "B.Cu")
		(net "GND")
	)
	(via
		(at 412.513018 -149.472396)
		(size 0.508)
		(drill 0.254)
		(layers "F.Cu" "B.Cu")
		(net "GND")
	)
	(via
		(at 341.975186 -412.84652)
		(size 0.4064)
		(drill 0.2032)
		(layers "F.Cu" "B.Cu")
		(net "GND")
	)
	(via
		(at 436.384446 -284.88513)
		(size 0.4826)
		(drill 0.254)
		(layers "F.Cu" "B.Cu")
		(net "GND")
	)
	(via
		(at 314.317634 -414.752536)
		(size 0.4572)
		(drill 0.254)
		(layers "F.Cu" "B.Cu")
		(net "GND")
	)
	(via
		(at 104.310688 -396.53718)
		(size 0.508)
		(drill 0.254)
		(layers "F.Cu" "B.Cu")
		(net "GND")
	)
	(via
		(at 386.804916 -285.42615)
		(size 0.4064)
		(drill 0.2032)
		(layers "F.Cu" "B.Cu")
		(net "GND")
	)
	(via
		(at 26.536396 -306.135278)
		(size 0.4826)
		(drill 0.254)
		(layers "F.Cu" "B.Cu")
		(net "GND")
	)
	(via
		(at 135.274812 -242.864386)
		(size 0.4064)
		(drill 0.2032)
		(layers "F.Cu" "B.Cu")
		(net "GND")
	)
	(via
		(at 399.818606 -396.679674)
		(size 0.508)
		(drill 0.254)
		(layers "F.Cu" "B.Cu")
		(net "GND")
	)
	(via
		(at 105.279444 -31.541466)
		(size 0.508)
		(drill 0.254)
		(layers "F.Cu" "B.Cu")
		(net "GND")
	)
	(via
		(at 12.92352 -361.178602)
		(size 0.508)
		(drill 0.254)
		(layers "F.Cu" "B.Cu")
		(net "GND")
	)
	(via
		(at 365.807498 -175.782986)
		(size 0.49022)
		(drill 0.254)
		(layers "F.Cu" "B.Cu")
		(net "GND")
	)
	(via
		(at 363.304582 -293.525956)
		(size 0.4064)
		(drill 0.2032)
		(layers "F.Cu" "B.Cu")
		(net "GND")
	)
	(via
		(at 160.70453 -348.553278)
		(size 0.508)
		(drill 0.254)
		(layers "F.Cu" "B.Cu")
		(net "GND")
	)
	(via
		(at 309.816246 -400.212814)
		(size 0.4064)
		(drill 0.2032)
		(layers "F.Cu" "B.Cu")
		(net "GND")
	)
	(via
		(at 156.050234 -409.396184)
		(size 0.4572)
		(drill 0.254)
		(layers "F.Cu" "B.Cu")
		(net "GND")
	)
	(via
		(at 456.02271 -50.182018)
		(size 0.508)
		(drill 0.254)
		(layers "F.Cu" "B.Cu")
		(net "GND")
	)
	(via
		(at 84.05114 -224.234502)
		(size 0.4064)
		(drill 0.2032)
		(layers "F.Cu" "B.Cu")
		(net "GND")
	)
	(via
		(at 118.824756 -238.814356)
		(size 0.4064)
		(drill 0.2032)
		(layers "F.Cu" "B.Cu")
		(net "GND")
	)
	(via
		(at 36.795964 -241.535204)
		(size 0.4826)
		(drill 0.254)
		(layers "F.Cu" "B.Cu")
		(net "GND")
	)
	(via
		(at 256.7051 -332.867)
		(size 0.508)
		(drill 0.254)
		(layers "F.Cu" "B.Cu")
		(net "GND")
	)
	(via
		(at 80.291178 -250.15444)
		(size 0.4064)
		(drill 0.2032)
		(layers "F.Cu" "B.Cu")
		(net "GND")
	)
	(via
		(at 101.91115 -240.434368)
		(size 0.4064)
		(drill 0.2032)
		(layers "F.Cu" "B.Cu")
		(net "GND")
	)
	(via
		(at 101.440996 -221.804484)
		(size 0.4064)
		(drill 0.2032)
		(layers "F.Cu" "B.Cu")
		(net "GND")
	)
	(via
		(at 305.161696 -379.88113)
		(size 0.508)
		(drill 0.254)
		(layers "F.Cu" "B.Cu")
		(net "GND")
	)
	(via
		(at 437.944514 -192.21831)
		(size 0.4826)
		(drill 0.254)
		(layers "F.Cu" "B.Cu")
		(net "GND")
	)
	(via
		(at 100.331016 -277.326344)
		(size 0.4064)
		(drill 0.2032)
		(layers "F.Cu" "B.Cu")
		(net "GND")
	)
	(via
		(at 21.70811 -316.33541)
		(size 0.4826)
		(drill 0.254)
		(layers "F.Cu" "B.Cu")
		(net "GND")
	)
	(via
		(at 303.945036 -381.68453)
		(size 0.508)
		(drill 0.254)
		(layers "F.Cu" "B.Cu")
		(net "GND")
	)
	(via
		(at 338.101178 -244.484144)
		(size 0.4064)
		(drill 0.2032)
		(layers "F.Cu" "B.Cu")
		(net "GND")
	)
	(via
		(at 372.874794 -223.424242)
		(size 0.4064)
		(drill 0.2032)
		(layers "F.Cu" "B.Cu")
		(net "GND")
	)
	(via
		(at 202.147932 -289.135312)
		(size 0.4826)
		(drill 0.254)
		(layers "F.Cu" "B.Cu")
		(net "GND")
	)
	(via
		(at 361.594908 -236.384084)
		(size 0.4064)
		(drill 0.2032)
		(layers "F.Cu" "B.Cu")
		(net "GND")
	)
	(via
		(at 118.354856 -238.00435)
		(size 0.4064)
		(drill 0.2032)
		(layers "F.Cu" "B.Cu")
		(net "GND")
	)
	(via
		(at 139.974828 -239.624362)
		(size 0.4064)
		(drill 0.2032)
		(layers "F.Cu" "B.Cu")
		(net "GND")
	)
	(via
		(at 81.701132 -239.624362)
		(size 0.4064)
		(drill 0.2032)
		(layers "F.Cu" "B.Cu")
		(net "GND")
	)
	(via
		(at 100.331016 -265.98626)
		(size 0.4064)
		(drill 0.2032)
		(layers "F.Cu" "B.Cu")
		(net "GND")
	)
	(via
		(at 246.35587 -290.415726)
		(size 0.508)
		(drill 0.254)
		(layers "F.Cu" "B.Cu")
		(net "GND")
	)
	(via
		(at 136.139174 -413.204152)
		(size 0.4572)
		(drill 0.254)
		(layers "F.Cu" "B.Cu")
		(net "GND")
	)
	(via
		(at 361.124754 -240.434114)
		(size 0.4064)
		(drill 0.2032)
		(layers "F.Cu" "B.Cu")
		(net "GND")
	)
	(via
		(at 121.944638 -288.666174)
		(size 0.4064)
		(drill 0.2032)
		(layers "F.Cu" "B.Cu")
		(net "GND")
	)
	(via
		(at 380.807722 -204.092302)
		(size 0.508)
		(drill 0.254)
		(layers "F.Cu" "B.Cu")
		(net "GND")
	)
	(via
		(at 328.492358 -101.88575)
		(size 0.508)
		(drill 0.254)
		(layers "F.Cu" "B.Cu")
		(net "GND")
	)
	(via
		(at 436.384446 -275.535136)
		(size 0.4826)
		(drill 0.254)
		(layers "F.Cu" "B.Cu")
		(net "GND")
	)
	(via
		(at 149.349714 -427.699678)
		(size 0.4572)
		(drill 0.2032)
		(layers "F.Cu" "B.Cu")
		(net "GND")
	)
	(via
		(at 55.343044 -404.46452)
		(size 0.4064)
		(drill 0.2032)
		(layers "F.Cu" "B.Cu")
		(net "GND")
	)
	(via
		(at 412.367984 -236.435138)
		(size 0.4826)
		(drill 0.254)
		(layers "F.Cu" "B.Cu")
		(net "GND")
	)
	(via
		(at 442.007752 -395.318234)
		(size 0.508)
		(drill 0.254)
		(layers "F.Cu" "B.Cu")
		(net "GND")
	)
	(via
		(at 381.804926 -237.19409)
		(size 0.4064)
		(drill 0.2032)
		(layers "F.Cu" "B.Cu")
		(net "GND")
	)
	(via
		(at 66.210434 -339.883496)
		(size 0.508)
		(drill 0.254)
		(layers "F.Cu" "B.Cu")
		(net "GND")
	)
	(via
		(at 386.504942 -243.674138)
		(size 0.4064)
		(drill 0.2032)
		(layers "F.Cu" "B.Cu")
		(net "GND")
	)
	(via
		(at 100.56749 -180.704744)
		(size 0.49022)
		(drill 0.254)
		(layers "F.Cu" "B.Cu")
		(net "GND")
	)
	(via
		(at 133.864858 -237.194344)
		(size 0.4064)
		(drill 0.2032)
		(layers "F.Cu" "B.Cu")
		(net "GND")
	)
	(via
		(at 82.912204 -412.570168)
		(size 0.4064)
		(drill 0.2032)
		(layers "F.Cu" "B.Cu")
		(net "GND")
	)
	(via
		(at 53.509672 -4.963414)
		(size 0.508)
		(drill 0.254)
		(layers "F.Cu" "B.Cu")
		(net "GND")
	)
	(via
		(at 358.311196 -227.474272)
		(size 0.4064)
		(drill 0.2032)
		(layers "F.Cu" "B.Cu")
		(net "GND")
	)
	(via
		(at 32.695896 -289.135312)
		(size 0.4826)
		(drill 0.254)
		(layers "F.Cu" "B.Cu")
		(net "GND")
	)
	(via
		(at 69.57187 -155.31719)
		(size 0.508)
		(drill 0.254)
		(layers "F.Cu" "B.Cu")
		(net "GND")
	)
	(via
		(at 374.754902 -228.284278)
		(size 0.4064)
		(drill 0.2032)
		(layers "F.Cu" "B.Cu")
		(net "GND")
	)
	(via
		(at 187.060078 -267.885418)
		(size 0.4826)
		(drill 0.254)
		(layers "F.Cu" "B.Cu")
		(net "GND")
	)
	(via
		(at 344.681048 -234.764072)
		(size 0.4064)
		(drill 0.2032)
		(layers "F.Cu" "B.Cu")
		(net "GND")
	)
	(via
		(at 49.168304 -284.885384)
		(size 0.4826)
		(drill 0.254)
		(layers "F.Cu" "B.Cu")
		(net "GND")
	)
	(via
		(at 115.534694 -229.90429)
		(size 0.4064)
		(drill 0.2032)
		(layers "F.Cu" "B.Cu")
		(net "GND")
	)
	(via
		(at 136.34974 -437.34736)
		(size 0.4572)
		(drill 0.2032)
		(layers "F.Cu" "B.Cu")
		(net "GND")
	)
	(via
		(at 109.939836 -370.83873)
		(size 0.508)
		(drill 0.254)
		(layers "F.Cu" "B.Cu")
		(net "GND")
	)
	(via
		(at 327.277476 -383.814828)
		(size 0.508)
		(drill 0.254)
		(layers "F.Cu" "B.Cu")
		(net "GND")
	)
	(via
		(at 102.593902 -369.03533)
		(size 0.508)
		(drill 0.254)
		(layers "F.Cu" "B.Cu")
		(net "GND")
	)
	(via
		(at 284.736032 -226.235006)
		(size 0.4826)
		(drill 0.254)
		(layers "F.Cu" "B.Cu")
		(net "GND")
	)
	(via
		(at 128.994662 -261.93623)
		(size 0.4064)
		(drill 0.2032)
		(layers "F.Cu" "B.Cu")
		(net "GND")
	)
	(via
		(at 276.081744 -94.115128)
		(size 0.508)
		(drill 0.254)
		(layers "F.Cu" "B.Cu")
		(net "GND")
	)
	(via
		(at 411.349698 -432.747166)
		(size 0.4572)
		(drill 0.2032)
		(layers "F.Cu" "B.Cu")
		(net "GND")
	)
	(via
		(at 284.736032 -291.684964)
		(size 0.4826)
		(drill 0.254)
		(layers "F.Cu" "B.Cu")
		(net "GND")
	)
	(via
		(at 303.268126 -199.035162)
		(size 0.4826)
		(drill 0.254)
		(layers "F.Cu" "B.Cu")
		(net "GND")
	)
	(via
		(at 41.62425 -287.43529)
		(size 0.4826)
		(drill 0.254)
		(layers "F.Cu" "B.Cu")
		(net "GND")
	)
	(via
		(at 326.351138 -232.334054)
		(size 0.4064)
		(drill 0.2032)
		(layers "F.Cu" "B.Cu")
		(net "GND")
	)
	(via
		(at 222.363538 -76.581)
		(size 0.508)
		(drill 0.254)
		(layers "F.Cu" "B.Cu")
		(net "GND")
	)
	(via
		(at 419.912038 -290.83508)
		(size 0.4826)
		(drill 0.254)
		(layers "F.Cu" "B.Cu")
		(net "GND")
	)
	(via
		(at 79.487776 -405.098504)
		(size 0.4572)
		(drill 0.254)
		(layers "F.Cu" "B.Cu")
		(net "GND")
	)
	(via
		(at 388.34949 -437.34736)
		(size 0.4572)
		(drill 0.2032)
		(layers "F.Cu" "B.Cu")
		(net "GND")
	)
	(via
		(at 34.080196 -315.485272)
		(size 0.4826)
		(drill 0.254)
		(layers "F.Cu" "B.Cu")
		(net "GND")
	)
	(via
		(at 334.18272 -335.539588)
		(size 0.49022)
		(drill 0.254)
		(layers "F.Cu" "B.Cu")
		(net "GND")
	)
	(via
		(at 44.340018 -267.03528)
		(size 0.4826)
		(drill 0.254)
		(layers "F.Cu" "B.Cu")
		(net "GND")
	)
	(via
		(at 89.690956 -251.774452)
		(size 0.4064)
		(drill 0.2032)
		(layers "F.Cu" "B.Cu")
		(net "GND")
	)
	(via
		(at 363.474762 -236.384084)
		(size 0.4064)
		(drill 0.2032)
		(layers "F.Cu" "B.Cu")
		(net "GND")
	)
	(via
		(at 245.69801 -288.4297)
		(size 0.508)
		(drill 0.254)
		(layers "F.Cu" "B.Cu")
		(net "GND")
	)
	(via
		(at 109.261148 -270.03629)
		(size 0.4064)
		(drill 0.2032)
		(layers "F.Cu" "B.Cu")
		(net "GND")
	)
	(via
		(at 113.989104 -412.055564)
		(size 0.508)
		(drill 0.254)
		(layers "F.Cu" "B.Cu")
		(net "GND")
	)
	(via
		(at 236.455204 -168.856914)
		(size 0.508)
		(drill 0.254)
		(layers "F.Cu" "B.Cu")
		(net "GND")
	)
	(via
		(at 187.060078 -279.785318)
		(size 0.4826)
		(drill 0.254)
		(layers "F.Cu" "B.Cu")
		(net "GND")
	)
	(via
		(at 59.249818 -438.651396)
		(size 0.4572)
		(drill 0.2032)
		(layers "F.Cu" "B.Cu")
		(net "GND")
	)
	(via
		(at 4.150868 -131.305554)
		(size 0.508)
		(drill 0.254)
		(layers "F.Cu" "B.Cu")
		(net "GND")
	)
	(via
		(at 124.464826 -230.714296)
		(size 0.4064)
		(drill 0.2032)
		(layers "F.Cu" "B.Cu")
		(net "GND")
	)
	(via
		(at 259.562346 -32.40786)
		(size 0.508)
		(drill 0.254)
		(layers "F.Cu" "B.Cu")
		(net "GND")
	)
	(via
		(at 440.19851 -392.117834)
		(size 0.6604)
		(drill 0.3302)
		(layers "F.Cu" "B.Cu")
		(net "GND")
	)
	(via
		(at 462.357978 -94.952566)
		(size 0.508)
		(drill 0.254)
		(layers "F.Cu" "B.Cu")
		(net "GND")
	)
	(via
		(at 205.0923 -192.218564)
		(size 0.4826)
		(drill 0.254)
		(layers "F.Cu" "B.Cu")
		(net "GND")
	)
	(via
		(at 185.787538 -348.71152)
		(size 0.508)
		(drill 0.254)
		(layers "F.Cu" "B.Cu")
		(net "GND")
	)
	(via
		(at 32.695896 -262.785352)
		(size 0.4826)
		(drill 0.254)
		(layers "F.Cu" "B.Cu")
		(net "GND")
	)
	(via
		(at 348.525846 -339.06206)
		(size 0.49022)
		(drill 0.254)
		(layers "F.Cu" "B.Cu")
		(net "GND")
	)
	(via
		(at 172.684948 -103.96728)
		(size 0.508)
		(drill 0.254)
		(layers "F.Cu" "B.Cu")
		(net "GND")
	)
	(via
		(at 326.351138 -227.474272)
		(size 0.4064)
		(drill 0.2032)
		(layers "F.Cu" "B.Cu")
		(net "GND")
	)
	(via
		(at 393.717272 -388.917688)
		(size 0.508)
		(drill 0.254)
		(layers "F.Cu" "B.Cu")
		(net "GND")
	)
	(via
		(at 97.511108 -280.566368)
		(size 0.4064)
		(drill 0.2032)
		(layers "F.Cu" "B.Cu")
		(net "GND")
	)
	(via
		(at 96.977708 -183.831484)
		(size 0.49022)
		(drill 0.254)
		(layers "F.Cu" "B.Cu")
		(net "GND")
	)
	(via
		(at 143.797274 -409.396184)
		(size 0.4572)
		(drill 0.254)
		(layers "F.Cu" "B.Cu")
		(net "GND")
	)
	(via
		(at 346.091002 -225.85426)
		(size 0.4064)
		(drill 0.2032)
		(layers "F.Cu" "B.Cu")
		(net "GND")
	)
	(via
		(at 334.811116 -256.634234)
		(size 0.4064)
		(drill 0.2032)
		(layers "F.Cu" "B.Cu")
		(net "GND")
	)
	(via
		(at 409.349702 -434.899562)
		(size 0.4572)
		(drill 0.2032)
		(layers "F.Cu" "B.Cu")
		(net "GND")
	)
	(via
		(at 25.152096 -233.035348)
		(size 0.4826)
		(drill 0.254)
		(layers "F.Cu" "B.Cu")
		(net "GND")
	)
	(via
		(at 446.644268 -204.134974)
		(size 0.4826)
		(drill 0.254)
		(layers "F.Cu" "B.Cu")
		(net "GND")
	)
	(via
		(at 11.066526 -12.542266)
		(size 0.508)
		(drill 0.254)
		(layers "F.Cu" "B.Cu")
		(net "GND")
	)
	(via
		(at 306.250594 -229.210108)
		(size 0.4826)
		(drill 0.254)
		(layers "F.Cu" "B.Cu")
		(net "GND")
	)
	(via
		(at 78.996286 -382.908556)
		(size 0.4064)
		(drill 0.2032)
		(layers "F.Cu" "B.Cu")
		(net "GND")
	)
	(via
		(at 214.662004 -134.655052)
		(size 0.508)
		(drill 0.254)
		(layers "F.Cu" "B.Cu")
		(net "GND")
	)
	(via
		(at 364.24489 -270.846042)
		(size 0.4064)
		(drill 0.2032)
		(layers "F.Cu" "B.Cu")
		(net "GND")
	)
	(via
		(at 75.943714 -184.492392)
		(size 0.508)
		(drill 0.254)
		(layers "F.Cu" "B.Cu")
		(net "GND")
	)
	(via
		(at 96.74098 -231.524302)
		(size 0.4064)
		(drill 0.2032)
		(layers "F.Cu" "B.Cu")
		(net "GND")
	)
	(via
		(at 305.127914 -417.778184)
		(size 0.4572)
		(drill 0.254)
		(layers "F.Cu" "B.Cu")
		(net "GND")
	)
	(via
		(at 133.864858 -243.674392)
		(size 0.4064)
		(drill 0.2032)
		(layers "F.Cu" "B.Cu")
		(net "GND")
	)
	(via
		(at 143.524478 -411.936184)
		(size 0.4572)
		(drill 0.254)
		(layers "F.Cu" "B.Cu")
		(net "GND")
	)
	(via
		(at 99.861116 -287.856422)
		(size 0.4064)
		(drill 0.2032)
		(layers "F.Cu" "B.Cu")
		(net "GND")
	)
	(via
		(at 303.892966 -343.472008)
		(size 0.508)
		(drill 0.254)
		(layers "F.Cu" "B.Cu")
		(net "GND")
	)
	(via
		(at 413.349694 -434.899562)
		(size 0.4572)
		(drill 0.2032)
		(layers "F.Cu" "B.Cu")
		(net "GND")
	)
	(via
		(at 418.677598 -368.633502)
		(size 0.508)
		(drill 0.254)
		(layers "F.Cu" "B.Cu")
		(net "GND")
	)
	(via
		(at 354.704904 -376.75693)
		(size 0.508)
		(drill 0.254)
		(layers "F.Cu" "B.Cu")
		(net "GND")
	)
	(via
		(at 187.060078 -245.785386)
		(size 0.4826)
		(drill 0.254)
		(layers "F.Cu" "B.Cu")
		(net "GND")
	)
	(via
		(at 401.32889 -412.212536)
		(size 0.4572)
		(drill 0.254)
		(layers "F.Cu" "B.Cu")
		(net "GND")
	)
	(via
		(at 404.030942 -412.84652)
		(size 0.4064)
		(drill 0.2032)
		(layers "F.Cu" "B.Cu")
		(net "GND")
	)
	(via
		(at 338.464906 -418.412168)
		(size 0.4064)
		(drill 0.2032)
		(layers "F.Cu" "B.Cu")
		(net "GND")
	)
	(via
		(at 97.040954 -273.276314)
		(size 0.4064)
		(drill 0.2032)
		(layers "F.Cu" "B.Cu")
		(net "GND")
	)
	(via
		(at 408.714194 -412.212536)
		(size 0.4572)
		(drill 0.254)
		(layers "F.Cu" "B.Cu")
		(net "GND")
	)
	(via
		(at 134.695946 -412.570168)
		(size 0.4064)
		(drill 0.2032)
		(layers "F.Cu" "B.Cu")
		(net "GND")
	)
	(via
		(at 88.677496 -403.830536)
		(size 0.4572)
		(drill 0.254)
		(layers "F.Cu" "B.Cu")
		(net "GND")
	)
	(via
		(at 128.349756 -439.651394)
		(size 0.4572)
		(drill 0.2032)
		(layers "F.Cu" "B.Cu")
		(net "GND")
	)
	(via
		(at 308.05501 -344.77706)
		(size 0.49022)
		(drill 0.254)
		(layers "F.Cu" "B.Cu")
		(net "GND")
	)
	(via
		(at 198.820532 -356.933246)
		(size 0.508)
		(drill 0.254)
		(layers "F.Cu" "B.Cu")
		(net "GND")
	)
	(via
		(at 90.6399 -139.164822)
		(size 0.508)
		(drill 0.254)
		(layers "F.Cu" "B.Cu")
		(net "GND")
	)
	(via
		(at 454.188068 -306.985162)
		(size 0.4826)
		(drill 0.254)
		(layers "F.Cu" "B.Cu")
		(net "GND")
	)
	(via
		(at 355.961188 -234.764072)
		(size 0.4064)
		(drill 0.2032)
		(layers "F.Cu" "B.Cu")
		(net "GND")
	)
	(via
		(at 47.784004 -233.035348)
		(size 0.4826)
		(drill 0.254)
		(layers "F.Cu" "B.Cu")
		(net "GND")
	)
	(via
		(at 113.340896 -369.03533)
		(size 0.508)
		(drill 0.254)
		(layers "F.Cu" "B.Cu")
		(net "GND")
	)
	(via
		(at 392.349482 -436.051198)
		(size 0.4572)
		(drill 0.2032)
		(layers "F.Cu" "B.Cu")
		(net "GND")
	)
	(via
		(at 423.002964 -349.175578)
		(size 0.49022)
		(drill 0.254)
		(layers "F.Cu" "B.Cu")
		(net "GND")
	)
	(via
		(at 93.54439 -382.85293)
		(size 0.4064)
		(drill 0.2032)
		(layers "F.Cu" "B.Cu")
		(net "GND")
	)
	(via
		(at 140.274802 -278.13635)
		(size 0.4064)
		(drill 0.2032)
		(layers "F.Cu" "B.Cu")
		(net "GND")
	)
	(via
		(at 188.444378 -287.43529)
		(size 0.4826)
		(drill 0.254)
		(layers "F.Cu" "B.Cu")
		(net "GND")
	)
	(via
		(at 124.464826 -224.234502)
		(size 0.4064)
		(drill 0.2032)
		(layers "F.Cu" "B.Cu")
		(net "GND")
	)
	(via
		(at 94.861126 -246.10441)
		(size 0.4064)
		(drill 0.2032)
		(layers "F.Cu" "B.Cu")
		(net "GND")
	)
	(via
		(at 337.631024 -253.39421)
		(size 0.4064)
		(drill 0.2032)
		(layers "F.Cu" "B.Cu")
		(net "GND")
	)
	(via
		(at 108.02112 -238.00435)
		(size 0.4064)
		(drill 0.2032)
		(layers "F.Cu" "B.Cu")
		(net "GND")
	)
	(via
		(at 123.946666 -167.131746)
		(size 0.49022)
		(drill 0.254)
		(layers "F.Cu" "B.Cu")
		(net "GND")
	)
	(via
		(at 389.347964 -17.61236)
		(size 0.508)
		(drill 0.254)
		(layers "F.Cu" "B.Cu")
		(net "GND")
	)
	(via
		(at 388.34949 -432.451256)
		(size 0.4572)
		(drill 0.2032)
		(layers "F.Cu" "B.Cu")
		(net "GND")
	)
	(via
		(at 136.139174 -403.830536)
		(size 0.4572)
		(drill 0.254)
		(layers "F.Cu" "B.Cu")
		(net "GND")
	)
	(via
		(at 343.279984 -381.68453)
		(size 0.508)
		(drill 0.254)
		(layers "F.Cu" "B.Cu")
		(net "GND")
	)
	(via
		(at 36.795964 -310.385206)
		(size 0.4826)
		(drill 0.254)
		(layers "F.Cu" "B.Cu")
		(net "GND")
	)
	(via
		(at 81.701132 -254.20447)
		(size 0.4064)
		(drill 0.2032)
		(layers "F.Cu" "B.Cu")
		(net "GND")
	)
	(via
		(at 381.804926 -235.574078)
		(size 0.4064)
		(drill 0.2032)
		(layers "F.Cu" "B.Cu")
		(net "GND")
	)
	(via
		(at 255.122172 -420.65067)
		(size 0.508)
		(drill 0.254)
		(layers "F.Cu" "B.Cu")
		(net "GND")
	)
	(via
		(at 409.349702 -432.451256)
		(size 0.4572)
		(drill 0.2032)
		(layers "F.Cu" "B.Cu")
		(net "GND")
	)
	(via
		(at 406.788874 -169.743882)
		(size 0.49022)
		(drill 0.254)
		(layers "F.Cu" "B.Cu")
		(net "GND")
	)
	(via
		(at 89.944448 -393.927838)
		(size 0.4572)
		(drill 0.254)
		(layers "F.Cu" "B.Cu")
		(net "GND")
	)
	(via
		(at 90.719148 -390.160002)
		(size 0.4064)
		(drill 0.2032)
		(layers "F.Cu" "B.Cu")
		(net "GND")
	)
	(via
		(at 124.294646 -282.996386)
		(size 0.4064)
		(drill 0.2032)
		(layers "F.Cu" "B.Cu")
		(net "GND")
	)
	(via
		(at 371.764814 -280.566114)
		(size 0.4064)
		(drill 0.2032)
		(layers "F.Cu" "B.Cu")
		(net "GND")
	)
	(via
		(at 90.16111 -255.824482)
		(size 0.4064)
		(drill 0.2032)
		(layers "F.Cu" "B.Cu")
		(net "GND")
	)
	(via
		(at 442.5442 -236.435138)
		(size 0.4826)
		(drill 0.254)
		(layers "F.Cu" "B.Cu")
		(net "GND")
	)
	(via
		(at 408.109674 -170.53306)
		(size 0.49022)
		(drill 0.254)
		(layers "F.Cu" "B.Cu")
		(net "GND")
	)
	(via
		(at 362.834682 -270.036036)
		(size 0.4064)
		(drill 0.2032)
		(layers "F.Cu" "B.Cu")
		(net "GND")
	)
	(via
		(at 56.865774 -10.16508)
		(size 0.508)
		(drill 0.254)
		(layers "F.Cu" "B.Cu")
		(net "GND")
	)
	(via
		(at 126.174754 -292.716204)
		(size 0.4064)
		(drill 0.2032)
		(layers "F.Cu" "B.Cu")
		(net "GND")
	)
	(via
		(at 429.834548 -5.597398)
		(size 0.508)
		(drill 0.254)
		(layers "F.Cu" "B.Cu")
		(net "GND")
	)
	(via
		(at 287.581086 -424.696382)
		(size 0.508)
		(drill 0.254)
		(layers "F.Cu" "B.Cu")
		(net "GND")
	)
	(via
		(at 78.711044 -278.946356)
		(size 0.4064)
		(drill 0.2032)
		(layers "F.Cu" "B.Cu")
		(net "GND")
	)
	(via
		(at 217.386662 -385.745736)
		(size 0.508)
		(drill 0.254)
		(layers "F.Cu" "B.Cu")
		(net "GND")
	)
	(via
		(at 331.521054 -246.104156)
		(size 0.4064)
		(drill 0.2032)
		(layers "F.Cu" "B.Cu")
		(net "GND")
	)
	(via
		(at 252.33884 -90.10015)
		(size 0.508)
		(drill 0.254)
		(layers "F.Cu" "B.Cu")
		(net "GND")
	)
	(via
		(at 41.78935 -4.32943)
		(size 0.508)
		(drill 0.254)
		(layers "F.Cu" "B.Cu")
		(net "GND")
	)
	(via
		(at 128.994662 -291.096192)
		(size 0.4064)
		(drill 0.2032)
		(layers "F.Cu" "B.Cu")
		(net "GND")
	)
	(via
		(at 100.894642 -369.69573)
		(size 0.508)
		(drill 0.254)
		(layers "F.Cu" "B.Cu")
		(net "GND")
	)
	(via
		(at 122.884692 -280.566368)
		(size 0.4064)
		(drill 0.2032)
		(layers "F.Cu" "B.Cu")
		(net "GND")
	)
	(via
		(at 198.7042 -291.685218)
		(size 0.4826)
		(drill 0.254)
		(layers "F.Cu" "B.Cu")
		(net "GND")
	)
	(via
		(at 360.337862 -261.32282)
		(size 0.4826)
		(drill 0.254)
		(layers "F.Cu" "B.Cu")
		(net "GND")
	)
	(via
		(at 412.367984 -290.83508)
		(size 0.4826)
		(drill 0.254)
		(layers "F.Cu" "B.Cu")
		(net "GND")
	)
	(via
		(at 416.526472 -137.780776)
		(size 0.508)
		(drill 0.254)
		(layers "F.Cu" "B.Cu")
		(net "GND")
	)
	(via
		(at 388.384796 -230.714296)
		(size 0.4064)
		(drill 0.2032)
		(layers "F.Cu" "B.Cu")
		(net "GND")
	)
	(via
		(at 369.414806 -284.616144)
		(size 0.4064)
		(drill 0.2032)
		(layers "F.Cu" "B.Cu")
		(net "GND")
	)
	(via
		(at 276.074632 -285.310072)
		(size 0.4826)
		(drill 0.254)
		(layers "F.Cu" "B.Cu")
		(net "GND")
	)
	(via
		(at 313.958986 -415.38652)
		(size 0.4064)
		(drill 0.2032)
		(layers "F.Cu" "B.Cu")
		(net "GND")
	)
	(via
		(at 257.608324 -129.617216)
		(size 0.508)
		(drill 0.254)
		(layers "F.Cu" "B.Cu")
		(net "GND")
	)
	(via
		(at 371.764814 -288.66592)
		(size 0.4064)
		(drill 0.2032)
		(layers "F.Cu" "B.Cu")
		(net "GND")
	)
	(via
		(at 421.146224 -396.710662)
		(size 0.4064)
		(drill 0.2032)
		(layers "F.Cu" "B.Cu")
		(net "GND")
	)
	(via
		(at 43.184318 -192.218564)
		(size 0.4826)
		(drill 0.254)
		(layers "F.Cu" "B.Cu")
		(net "GND")
	)
	(via
		(at 288.180018 -317.18504)
		(size 0.4826)
		(drill 0.254)
		(layers "F.Cu" "B.Cu")
		(net "GND")
	)
	(via
		(at 352.696526 -418.412168)
		(size 0.4064)
		(drill 0.2032)
		(layers "F.Cu" "B.Cu")
		(net "GND")
	)
	(via
		(at 386.804916 -277.32609)
		(size 0.4064)
		(drill 0.2032)
		(layers "F.Cu" "B.Cu")
		(net "GND")
	)
	(via
		(at 373.845582 -415.38652)
		(size 0.4064)
		(drill 0.2032)
		(layers "F.Cu" "B.Cu")
		(net "GND")
	)
	(via
		(at 55.328058 -233.035348)
		(size 0.4826)
		(drill 0.254)
		(layers "F.Cu" "B.Cu")
		(net "GND")
	)
	(via
		(at 12.52982 -383.320798)
		(size 0.508)
		(drill 0.254)
		(layers "F.Cu" "B.Cu")
		(net "GND")
	)
	(via
		(at 69.249798 -427.699678)
		(size 0.4572)
		(drill 0.2032)
		(layers "F.Cu" "B.Cu")
		(net "GND")
	)
	(via
		(at 246.301514 -319.466468)
		(size 0.508)
		(drill 0.254)
		(layers "F.Cu" "B.Cu")
		(net "GND")
	)
	(via
		(at 336.249518 -431.451258)
		(size 0.4572)
		(drill 0.2032)
		(layers "F.Cu" "B.Cu")
		(net "GND")
	)
	(via
		(at 427.530006 -6.598158)
		(size 0.508)
		(drill 0.254)
		(layers "F.Cu" "B.Cu")
		(net "GND")
	)
	(via
		(at 140.744702 -264.366248)
		(size 0.4064)
		(drill 0.2032)
		(layers "F.Cu" "B.Cu")
		(net "GND")
	)
	(via
		(at 2.76225 -87.813134)
		(size 0.508)
		(drill 0.254)
		(layers "F.Cu" "B.Cu")
		(net "GND")
	)
	(via
		(at 125.291342 -390.160002)
		(size 0.4064)
		(drill 0.2032)
		(layers "F.Cu" "B.Cu")
		(net "GND")
	)
	(via
		(at 407.890218 -392.999722)
		(size 0.4064)
		(drill 0.2032)
		(layers "F.Cu" "B.Cu")
		(net "GND")
	)
	(via
		(at 350.621092 -284.616144)
		(size 0.4064)
		(drill 0.2032)
		(layers "F.Cu" "B.Cu")
		(net "GND")
	)
	(via
		(at 89.038684 -404.46452)
		(size 0.4064)
		(drill 0.2032)
		(layers "F.Cu" "B.Cu")
		(net "GND")
	)
	(via
		(at 454.188068 -265.335004)
		(size 0.4826)
		(drill 0.254)
		(layers "F.Cu" "B.Cu")
		(net "GND")
	)
	(via
		(at 143.56334 -31.958026)
		(size 0.508)
		(drill 0.254)
		(layers "F.Cu" "B.Cu")
		(net "GND")
	)
	(via
		(at 412.367984 -269.585186)
		(size 0.4826)
		(drill 0.254)
		(layers "F.Cu" "B.Cu")
		(net "GND")
	)
	(via
		(at 118.354856 -246.10441)
		(size 0.4064)
		(drill 0.2032)
		(layers "F.Cu" "B.Cu")
		(net "GND")
	)
	(via
		(at 9.760204 -420.136066)
		(size 0.508)
		(drill 0.254)
		(layers "F.Cu" "B.Cu")
		(net "GND")
	)
	(via
		(at 334.768444 -377.41733)
		(size 0.508)
		(drill 0.254)
		(layers "F.Cu" "B.Cu")
		(net "GND")
	)
	(via
		(at 417.490148 -392.999722)
		(size 0.4064)
		(drill 0.2032)
		(layers "F.Cu" "B.Cu")
		(net "GND")
	)
	(via
		(at 74.83729 -177.059844)
		(size 0.49022)
		(drill 0.254)
		(layers "F.Cu" "B.Cu")
		(net "GND")
	)
	(via
		(at 439.100214 -222.834962)
		(size 0.4826)
		(drill 0.254)
		(layers "F.Cu" "B.Cu")
		(net "GND")
	)
	(via
		(at 93.450918 -224.234502)
		(size 0.4064)
		(drill 0.2032)
		(layers "F.Cu" "B.Cu")
		(net "GND")
	)
	(via
		(at 84.441284 -410.030168)
		(size 0.4064)
		(drill 0.2032)
		(layers "F.Cu" "B.Cu")
		(net "GND")
	)
	(via
		(at 33.362138 -18.247868)
		(size 0.508)
		(drill 0.254)
		(layers "F.Cu" "B.Cu")
		(net "GND")
	)
	(via
		(at 85.290914 -275.706332)
		(size 0.4064)
		(drill 0.2032)
		(layers "F.Cu" "B.Cu")
		(net "GND")
	)
	(via
		(at 123.066556 -374.62333)
		(size 0.508)
		(drill 0.254)
		(layers "F.Cu" "B.Cu")
		(net "GND")
	)
	(via
		(at 120.47855 -386.449062)
		(size 0.4064)
		(drill 0.2032)
		(layers "F.Cu" "B.Cu")
		(net "GND")
	)
	(via
		(at 307.368194 -261.93496)
		(size 0.4826)
		(drill 0.254)
		(layers "F.Cu" "B.Cu")
		(net "GND")
	)
	(via
		(at 425.129706 -229.210108)
		(size 0.4826)
		(drill 0.254)
		(layers "F.Cu" "B.Cu")
		(net "GND")
	)
	(via
		(at 8.590788 -369.84305)
		(size 0.508)
		(drill 0.254)
		(layers "F.Cu" "B.Cu")
		(net "GND")
	)
	(via
		(at 431.329592 -349.200978)
		(size 0.49022)
		(drill 0.254)
		(layers "F.Cu" "B.Cu")
		(net "GND")
	)
	(via
		(at 361.103418 -179.72024)
		(size 0.508)
		(drill 0.254)
		(layers "F.Cu" "B.Cu")
		(net "GND")
	)
	(via
		(at 173.495208 -343.420192)
		(size 0.508)
		(drill 0.254)
		(layers "F.Cu" "B.Cu")
		(net "GND")
	)
	(via
		(at 394.982954 -266.530074)
		(size 0.4064)
		(drill 0.2032)
		(layers "F.Cu" "B.Cu")
		(net "GND")
	)
	(via
		(at 151.34971 -436.347362)
		(size 0.4572)
		(drill 0.2032)
		(layers "F.Cu" "B.Cu")
		(net "GND")
	)
	(via
		(at 303.268126 -311.23509)
		(size 0.4826)
		(drill 0.254)
		(layers "F.Cu" "B.Cu")
		(net "GND")
	)
	(via
		(at 26.536396 -210.085432)
		(size 0.4826)
		(drill 0.254)
		(layers "F.Cu" "B.Cu")
		(net "GND")
	)
	(via
		(at 374.284748 -251.774198)
		(size 0.4064)
		(drill 0.2032)
		(layers "F.Cu" "B.Cu")
		(net "GND")
	)
	(via
		(at 461.417924 -61.960252)
		(size 0.6604)
		(drill 0.3302)
		(layers "F.Cu" "B.Cu")
		(net "GND")
	)
	(via
		(at 34.080196 -219.435426)
		(size 0.4826)
		(drill 0.254)
		(layers "F.Cu" "B.Cu")
		(net "GND")
	)
	(via
		(at 381.634746 -291.095938)
		(size 0.4064)
		(drill 0.2032)
		(layers "F.Cu" "B.Cu")
		(net "GND")
	)
	(via
		(at 372.93423 -182.177944)
		(size 0.49022)
		(drill 0.254)
		(layers "F.Cu" "B.Cu")
		(net "GND")
	)
	(via
		(at 88.950292 -409.396184)
		(size 0.4572)
		(drill 0.254)
		(layers "F.Cu" "B.Cu")
		(net "GND")
	)
	(via
		(at 187.060078 -272.135346)
		(size 0.4826)
		(drill 0.254)
		(layers "F.Cu" "B.Cu")
		(net "GND")
	)
	(via
		(at 96.101154 -294.336216)
		(size 0.4064)
		(drill 0.2032)
		(layers "F.Cu" "B.Cu")
		(net "GND")
	)
	(via
		(at 363.004862 -225.85426)
		(size 0.4064)
		(drill 0.2032)
		(layers "F.Cu" "B.Cu")
		(net "GND")
	)
	(via
		(at 130.40487 -293.52621)
		(size 0.4064)
		(drill 0.2032)
		(layers "F.Cu" "B.Cu")
		(net "GND")
	)
	(via
		(at 77.001116 -226.66452)
		(size 0.4064)
		(drill 0.2032)
		(layers "F.Cu" "B.Cu")
		(net "GND")
	)
	(via
		(at 311.342786 -412.84652)
		(size 0.4064)
		(drill 0.2032)
		(layers "F.Cu" "B.Cu")
		(net "GND")
	)
	(via
		(at 384.89128 -398.542002)
		(size 0.4064)
		(drill 0.2032)
		(layers "F.Cu" "B.Cu")
		(net "GND")
	)
	(via
		(at 123.524772 -224.234502)
		(size 0.4064)
		(drill 0.2032)
		(layers "F.Cu" "B.Cu")
		(net "GND")
	)
	(via
		(at 41.8211 -388.4549)
		(size 0.508)
		(drill 0.254)
		(layers "F.Cu" "B.Cu")
		(net "GND")
	)
	(via
		(at 357.201216 -273.27606)
		(size 0.4064)
		(drill 0.2032)
		(layers "F.Cu" "B.Cu")
		(net "GND")
	)
	(via
		(at 102.38105 -239.624362)
		(size 0.4064)
		(drill 0.2032)
		(layers "F.Cu" "B.Cu")
		(net "GND")
	)
	(via
		(at 32.948372 -12.37488)
		(size 0.508)
		(drill 0.254)
		(layers "F.Cu" "B.Cu")
		(net "GND")
	)
	(via
		(at 24.034496 -304.860452)
		(size 0.4826)
		(drill 0.254)
		(layers "F.Cu" "B.Cu")
		(net "GND")
	)
	(via
		(at 424.012106 -248.335038)
		(size 0.4826)
		(drill 0.254)
		(layers "F.Cu" "B.Cu")
		(net "GND")
	)
	(via
		(at 167.777668 -416.094926)
		(size 0.508)
		(drill 0.254)
		(layers "F.Cu" "B.Cu")
		(net "GND")
	)
	(via
		(at 450.088 -216.035128)
		(size 0.4826)
		(drill 0.254)
		(layers "F.Cu" "B.Cu")
		(net "GND")
	)
	(via
		(at 351.4852 -428.091092)
		(size 0.508)
		(drill 0.254)
		(layers "F.Cu" "B.Cu")
		(net "GND")
	)
	(via
		(at 373.644922 -285.42615)
		(size 0.4064)
		(drill 0.2032)
		(layers "F.Cu" "B.Cu")
		(net "GND")
	)
	(via
		(at 350.321118 -247.724168)
		(size 0.4064)
		(drill 0.2032)
		(layers "F.Cu" "B.Cu")
		(net "GND")
	)
	(via
		(at 351.943924 -391.23493)
		(size 0.4064)
		(drill 0.2032)
		(layers "F.Cu" "B.Cu")
		(net "GND")
	)
	(via
		(at 30.706314 -132.388864)
		(size 0.508)
		(drill 0.254)
		(layers "F.Cu" "B.Cu")
		(net "GND")
	)
	(via
		(at 185.000392 -350.731328)
		(size 0.49022)
		(drill 0.254)
		(layers "F.Cu" "B.Cu")
		(net "GND")
	)
	(via
		(at 346.681044 -379.88113)
		(size 0.508)
		(drill 0.254)
		(layers "F.Cu" "B.Cu")
		(net "GND")
	)
	(via
		(at 338.805012 -161.981134)
		(size 0.49022)
		(drill 0.254)
		(layers "F.Cu" "B.Cu")
		(net "GND")
	)
	(via
		(at 99.715066 -184.632346)
		(size 0.49022)
		(drill 0.254)
		(layers "F.Cu" "B.Cu")
		(net "GND")
	)
	(via
		(at 113.81486 -29.465778)
		(size 0.508)
		(drill 0.254)
		(layers "F.Cu" "B.Cu")
		(net "GND")
	)
	(via
		(at 374.218454 -396.710662)
		(size 0.4064)
		(drill 0.2032)
		(layers "F.Cu" "B.Cu")
		(net "GND")
	)
	(via
		(at 117.244622 -267.606272)
		(size 0.4064)
		(drill 0.2032)
		(layers "F.Cu" "B.Cu")
		(net "GND")
	)
	(via
		(at 340.24951 -429.147224)
		(size 0.4572)
		(drill 0.2032)
		(layers "F.Cu" "B.Cu")
		(net "GND")
	)
	(via
		(at 128.955292 -75.46086)
		(size 0.508)
		(drill 0.254)
		(layers "F.Cu" "B.Cu")
		(net "GND")
	)
	(via
		(at 273.092164 -267.885164)
		(size 0.4826)
		(drill 0.254)
		(layers "F.Cu" "B.Cu")
		(net "GND")
	)
	(via
		(at 191.160146 -205.83525)
		(size 0.4826)
		(drill 0.254)
		(layers "F.Cu" "B.Cu")
		(net "GND")
	)
	(via
		(at 289.564318 -303.585118)
		(size 0.4826)
		(drill 0.254)
		(layers "F.Cu" "B.Cu")
		(net "GND")
	)
	(via
		(at 229.590346 -325.425562)
		(size 0.508)
		(drill 0.254)
		(layers "F.Cu" "B.Cu")
		(net "GND")
	)
	(via
		(at 51.416458 -393.877038)
		(size 0.4572)
		(drill 0.254)
		(layers "F.Cu" "B.Cu")
		(net "GND")
	)
	(via
		(at 359.805224 -387.218428)
		(size 0.508)
		(drill 0.254)
		(layers "F.Cu" "B.Cu")
		(net "GND")
	)
	(via
		(at 445.637666 -402.81987)
		(size 0.508)
		(drill 0.254)
		(layers "F.Cu" "B.Cu")
		(net "GND")
	)
	(via
		(at 142.348204 -17.654778)
		(size 0.508)
		(drill 0.254)
		(layers "F.Cu" "B.Cu")
		(net "GND")
	)
	(via
		(at 292.68801 -344.77706)
		(size 0.49022)
		(drill 0.254)
		(layers "F.Cu" "B.Cu")
		(net "GND")
	)
	(via
		(at 113.48466 -283.806392)
		(size 0.4064)
		(drill 0.2032)
		(layers "F.Cu" "B.Cu")
		(net "GND")
	)
	(via
		(at 102.211124 -272.466308)
		(size 0.4064)
		(drill 0.2032)
		(layers "F.Cu" "B.Cu")
		(net "GND")
	)
	(via
		(at 55.328058 -309.535322)
		(size 0.4826)
		(drill 0.254)
		(layers "F.Cu" "B.Cu")
		(net "GND")
	)
	(via
		(at 318.08674 -336.983578)
		(size 0.49022)
		(drill 0.254)
		(layers "F.Cu" "B.Cu")
		(net "GND")
	)
	(via
		(at 125.506226 -412.570168)
		(size 0.4064)
		(drill 0.2032)
		(layers "F.Cu" "B.Cu")
		(net "GND")
	)
	(via
		(at 35.75685 -416.06089)
		(size 0.4572)
		(drill 0.254)
		(layers "F.Cu" "B.Cu")
		(net "GND")
	)
	(via
		(at 206.248 -316.33541)
		(size 0.4826)
		(drill 0.254)
		(layers "F.Cu" "B.Cu")
		(net "GND")
	)
	(via
		(at 103.151178 -291.906198)
		(size 0.4064)
		(drill 0.2032)
		(layers "F.Cu" "B.Cu")
		(net "GND")
	)
	(via
		(at 351.786444 -382.34493)
		(size 0.508)
		(drill 0.254)
		(layers "F.Cu" "B.Cu")
		(net "GND")
	)
	(via
		(at 277.192232 -306.985162)
		(size 0.4826)
		(drill 0.254)
		(layers "F.Cu" "B.Cu")
		(net "GND")
	)
	(via
		(at 457.97343 -49.122838)
		(size 0.508)
		(drill 0.254)
		(layers "F.Cu" "B.Cu")
		(net "GND")
	)
	(via
		(at 83.41106 -282.18638)
		(size 0.4064)
		(drill 0.2032)
		(layers "F.Cu" "B.Cu")
		(net "GND")
	)
	(via
		(at 407.445718 -7.215124)
		(size 0.508)
		(drill 0.254)
		(layers "F.Cu" "B.Cu")
		(net "GND")
	)
	(via
		(at 121.644664 -230.71455)
		(size 0.4064)
		(drill 0.2032)
		(layers "F.Cu" "B.Cu")
		(net "GND")
	)
	(via
		(at 347.50121 -239.624108)
		(size 0.4064)
		(drill 0.2032)
		(layers "F.Cu" "B.Cu")
		(net "GND")
	)
	(via
		(at 197.3199 -286.585406)
		(size 0.4826)
		(drill 0.254)
		(layers "F.Cu" "B.Cu")
		(net "GND")
	)
	(via
		(at 124.464826 -250.15444)
		(size 0.4064)
		(drill 0.2032)
		(layers "F.Cu" "B.Cu")
		(net "GND")
	)
	(via
		(at 65.614804 -404.46452)
		(size 0.4064)
		(drill 0.2032)
		(layers "F.Cu" "B.Cu")
		(net "GND")
	)
	(via
		(at 447.321432 -396.099284)
		(size 0.49022)
		(drill 0.254)
		(layers "F.Cu" "B.Cu")
		(net "GND")
	)
	(via
		(at 135.704834 -163.357052)
		(size 0.508)
		(drill 0.254)
		(layers "F.Cu" "B.Cu")
		(net "GND")
	)
	(via
		(at 2.76225 -154.869134)
		(size 0.508)
		(drill 0.254)
		(layers "F.Cu" "B.Cu")
		(net "GND")
	)
	(via
		(at 184.733692 -285.310326)
		(size 0.4826)
		(drill 0.254)
		(layers "F.Cu" "B.Cu")
		(net "GND")
	)
	(via
		(at 81.530952 -295.146222)
		(size 0.4064)
		(drill 0.2032)
		(layers "F.Cu" "B.Cu")
		(net "GND")
	)
	(via
		(at 399.349722 -438.651396)
		(size 0.4572)
		(drill 0.2032)
		(layers "F.Cu" "B.Cu")
		(net "GND")
	)
	(via
		(at 318.998346 -415.38652)
		(size 0.4064)
		(drill 0.2032)
		(layers "F.Cu" "B.Cu")
		(net "GND")
	)
	(via
		(at 293.329106 -339.809836)
		(size 0.508)
		(drill 0.254)
		(layers "F.Cu" "B.Cu")
		(net "GND")
	)
	(via
		(at 352.706178 -394.831062)
		(size 0.4064)
		(drill 0.2032)
		(layers "F.Cu" "B.Cu")
		(net "GND")
	)
	(via
		(at 446.177924 -58.150252)
		(size 0.6604)
		(drill 0.3302)
		(layers "F.Cu" "B.Cu")
		(net "GND")
	)
	(via
		(at 188.444378 -200.735438)
		(size 0.4826)
		(drill 0.254)
		(layers "F.Cu" "B.Cu")
		(net "GND")
	)
	(via
		(at 179.93233 -120.642634)
		(size 0.4572)
		(drill 0.254)
		(layers "F.Cu" "B.Cu")
		(net "GND")
	)
	(via
		(at 398.445482 -7.215124)
		(size 0.508)
		(drill 0.254)
		(layers "F.Cu" "B.Cu")
		(net "GND")
	)
	(via
		(at 371.764814 -291.905944)
		(size 0.4064)
		(drill 0.2032)
		(layers "F.Cu" "B.Cu")
		(net "GND")
	)
	(via
		(at 101.27107 -295.146222)
		(size 0.4064)
		(drill 0.2032)
		(layers "F.Cu" "B.Cu")
		(net "GND")
	)
	(via
		(at 354.551234 -232.334054)
		(size 0.4064)
		(drill 0.2032)
		(layers "F.Cu" "B.Cu")
		(net "GND")
	)
	(via
		(at 274.476464 -287.435036)
		(size 0.4826)
		(drill 0.254)
		(layers "F.Cu" "B.Cu")
		(net "GND")
	)
	(via
		(at 75.262486 -179.565046)
		(size 0.49022)
		(drill 0.254)
		(layers "F.Cu" "B.Cu")
		(net "GND")
	)
	(via
		(at 337.930998 -288.66592)
		(size 0.4064)
		(drill 0.2032)
		(layers "F.Cu" "B.Cu")
		(net "GND")
	)
	(via
		(at 413.485584 -230.060246)
		(size 0.4826)
		(drill 0.254)
		(layers "F.Cu" "B.Cu")
		(net "GND")
	)
	(via
		(at 216.8652 -67.324478)
		(size 0.508)
		(drill 0.254)
		(layers "F.Cu" "B.Cu")
		(net "GND")
	)
	(via
		(at 367.064798 -274.086066)
		(size 0.4064)
		(drill 0.2032)
		(layers "F.Cu" "B.Cu")
		(net "GND")
	)
	(via
		(at 280.635964 -283.185108)
		(size 0.4826)
		(drill 0.254)
		(layers "F.Cu" "B.Cu")
		(net "GND")
	)
	(via
		(at 121.539 -435.483)
		(size 0.508)
		(drill 0.254)
		(layers "F.Cu" "B.Cu")
		(net "GND")
	)
	(via
		(at 346.208858 -414.752536)
		(size 0.4572)
		(drill 0.254)
		(layers "F.Cu" "B.Cu")
		(net "GND")
	)
	(via
		(at 326.211946 -418.412168)
		(size 0.4064)
		(drill 0.2032)
		(layers "F.Cu" "B.Cu")
		(net "GND")
	)
	(via
		(at 85.628734 -336.966814)
		(size 0.49022)
		(drill 0.254)
		(layers "F.Cu" "B.Cu")
		(net "GND")
	)
	(via
		(at 331.051154 -230.714296)
		(size 0.4064)
		(drill 0.2032)
		(layers "F.Cu" "B.Cu")
		(net "GND")
	)
	(via
		(at 287.230566 -344.132408)
		(size 0.508)
		(drill 0.254)
		(layers "F.Cu" "B.Cu")
		(net "GND")
	)
	(via
		(at 436.852822 -405.11476)
		(size 0.508)
		(drill 0.254)
		(layers "F.Cu" "B.Cu")
		(net "GND")
	)
	(via
		(at 326.060308 -334.58912)
		(size 0.49022)
		(drill 0.254)
		(layers "F.Cu" "B.Cu")
		(net "GND")
	)
	(via
		(at 318.912494 -413.480504)
		(size 0.4572)
		(drill 0.254)
		(layers "F.Cu" "B.Cu")
		(net "GND")
	)
	(via
		(at 132.562346 -384.617722)
		(size 0.4064)
		(drill 0.2032)
		(layers "F.Cu" "B.Cu")
		(net "GND")
	)
	(via
		(at 91.21394 -355.171248)
		(size 0.508)
		(drill 0.254)
		(layers "F.Cu" "B.Cu")
		(net "GND")
	)
	(via
		(at 54.981856 -413.204152)
		(size 0.4572)
		(drill 0.254)
		(layers "F.Cu" "B.Cu")
		(net "GND")
	)
	(via
		(at 388.803134 -414.752536)
		(size 0.4572)
		(drill 0.254)
		(layers "F.Cu" "B.Cu")
		(net "GND")
	)
	(via
		(at 168.527984 -243.235226)
		(size 0.4826)
		(drill 0.254)
		(layers "F.Cu" "B.Cu")
		(net "GND")
	)
	(via
		(at 132.491226 -390.160002)
		(size 0.4064)
		(drill 0.2032)
		(layers "F.Cu" "B.Cu")
		(net "GND")
	)
	(via
		(at 134.607554 -409.396184)
		(size 0.4572)
		(drill 0.254)
		(layers "F.Cu" "B.Cu")
		(net "GND")
	)
	(via
		(at 53.268372 -9.424924)
		(size 0.508)
		(drill 0.254)
		(layers "F.Cu" "B.Cu")
		(net "GND")
	)
	(via
		(at 422.856406 -193.99631)
		(size 0.4826)
		(drill 0.254)
		(layers "F.Cu" "B.Cu")
		(net "GND")
	)
	(via
		(at 443.6999 -192.21831)
		(size 0.4826)
		(drill 0.254)
		(layers "F.Cu" "B.Cu")
		(net "GND")
	)
	(via
		(at 71.829676 -406.370536)
		(size 0.4572)
		(drill 0.254)
		(layers "F.Cu" "B.Cu")
		(net "GND")
	)
	(via
		(at 401.414742 -415.38652)
		(size 0.4064)
		(drill 0.2032)
		(layers "F.Cu" "B.Cu")
		(net "GND")
	)
	(via
		(at 153.349706 -434.899562)
		(size 0.4572)
		(drill 0.2032)
		(layers "F.Cu" "B.Cu")
		(net "GND")
	)
	(via
		(at 451.833996 -64.464946)
		(size 0.508)
		(drill 0.254)
		(layers "F.Cu" "B.Cu")
		(net "GND")
	)
	(via
		(at 381.634746 -268.416024)
		(size 0.4064)
		(drill 0.2032)
		(layers "F.Cu" "B.Cu")
		(net "GND")
	)
	(via
		(at 339.84565 -299.211746)
		(size 0.508)
		(drill 0.254)
		(layers "F.Cu" "B.Cu")
		(net "GND")
	)
	(via
		(at 203.497434 -341.192612)
		(size 0.508)
		(drill 0.254)
		(layers "F.Cu" "B.Cu")
		(net "GND")
	)
	(via
		(at 365.82477 -246.914162)
		(size 0.4064)
		(drill 0.2032)
		(layers "F.Cu" "B.Cu")
		(net "GND")
	)
	(via
		(at 257.379724 -133.641084)
		(size 0.508)
		(drill 0.254)
		(layers "F.Cu" "B.Cu")
		(net "GND")
	)
	(via
		(at 432.67376 -313.360054)
		(size 0.4826)
		(drill 0.254)
		(layers "F.Cu" "B.Cu")
		(net "GND")
	)
	(via
		(at 25.152096 -216.035382)
		(size 0.4826)
		(drill 0.254)
		(layers "F.Cu" "B.Cu")
		(net "GND")
	)
	(via
		(at 77.112876 -294.070278)
		(size 0.4064)
		(drill 0.2032)
		(layers "F.Cu" "B.Cu")
		(net "GND")
	)
	(via
		(at 86.249764 -436.051198)
		(size 0.4572)
		(drill 0.2032)
		(layers "F.Cu" "B.Cu")
		(net "GND")
	)
	(via
		(at 40.409114 -344.137234)
		(size 0.508)
		(drill 0.254)
		(layers "F.Cu" "B.Cu")
		(net "GND")
	)
	(via
		(at 65.614804 -412.570168)
		(size 0.4064)
		(drill 0.2032)
		(layers "F.Cu" "B.Cu")
		(net "GND")
	)
	(via
		(at 288.930842 -401.181062)
		(size 0.508)
		(drill 0.254)
		(layers "F.Cu" "B.Cu")
		(net "GND")
	)
	(via
		(at 337.544156 -400.212814)
		(size 0.4064)
		(drill 0.2032)
		(layers "F.Cu" "B.Cu")
		(net "GND")
	)
	(via
		(at 28.134564 -313.360308)
		(size 0.4826)
		(drill 0.254)
		(layers "F.Cu" "B.Cu")
		(net "GND")
	)
	(via
		(at 319.3923 -328.097134)
		(size 0.508)
		(drill 0.254)
		(layers "F.Cu" "B.Cu")
		(net "GND")
	)
	(via
		(at 349.105982 -394.831062)
		(size 0.4064)
		(drill 0.2032)
		(layers "F.Cu" "B.Cu")
		(net "GND")
	)
	(via
		(at 331.351128 -287.045908)
		(size 0.4064)
		(drill 0.2032)
		(layers "F.Cu" "B.Cu")
		(net "GND")
	)
	(via
		(at 326.720708 -334.58912)
		(size 0.49022)
		(drill 0.254)
		(layers "F.Cu" "B.Cu")
		(net "GND")
	)
	(via
		(at 451.873366 -377.29287)
		(size 0.508)
		(drill 0.254)
		(layers "F.Cu" "B.Cu")
		(net "GND")
	)
	(via
		(at 334.64119 -265.176)
		(size 0.4064)
		(drill 0.2032)
		(layers "F.Cu" "B.Cu")
		(net "GND")
	)
	(via
		(at 343.101168 -282.996132)
		(size 0.4064)
		(drill 0.2032)
		(layers "F.Cu" "B.Cu")
		(net "GND")
	)
	(via
		(at 19.876262 -19.137122)
		(size 0.508)
		(drill 0.254)
		(layers "F.Cu" "B.Cu")
		(net "GND")
	)
	(via
		(at 9.271 -82.169)
		(size 0.508)
		(drill 0.254)
		(layers "F.Cu" "B.Cu")
		(net "GND")
	)
	(via
		(at 413.485584 -211.360004)
		(size 0.4826)
		(drill 0.254)
		(layers "F.Cu" "B.Cu")
		(net "GND")
	)
	(via
		(at 43.03776 -111.35106)
		(size 0.508)
		(drill 0.254)
		(layers "F.Cu" "B.Cu")
		(net "GND")
	)
	(via
		(at 275.807932 -286.585152)
		(size 0.4826)
		(drill 0.254)
		(layers "F.Cu" "B.Cu")
		(net "GND")
	)
	(via
		(at 40.23995 -317.185294)
		(size 0.4826)
		(drill 0.254)
		(layers "F.Cu" "B.Cu")
		(net "GND")
	)
	(via
		(at 459.340966 -55.584598)
		(size 0.508)
		(drill 0.254)
		(layers "F.Cu" "B.Cu")
		(net "GND")
	)
	(via
		(at 273.092164 -317.18504)
		(size 0.4826)
		(drill 0.254)
		(layers "F.Cu" "B.Cu")
		(net "GND")
	)
	(via
		(at 154.245818 -410.664152)
		(size 0.4572)
		(drill 0.254)
		(layers "F.Cu" "B.Cu")
		(net "GND")
	)
	(via
		(at 279.518364 -220.709998)
		(size 0.4826)
		(drill 0.254)
		(layers "F.Cu" "B.Cu")
		(net "GND")
	)
	(via
		(at 376.634756 -225.044254)
		(size 0.4064)
		(drill 0.2032)
		(layers "F.Cu" "B.Cu")
		(net "GND")
	)
	(via
		(at 387.914896 -229.904036)
		(size 0.4064)
		(drill 0.2032)
		(layers "F.Cu" "B.Cu")
		(net "GND")
	)
	(via
		(at 91.571064 -230.71455)
		(size 0.4064)
		(drill 0.2032)
		(layers "F.Cu" "B.Cu")
		(net "GND")
	)
	(via
		(at 304.662078 -392.999722)
		(size 0.4064)
		(drill 0.2032)
		(layers "F.Cu" "B.Cu")
		(net "GND")
	)
	(via
		(at 370.994686 -250.964192)
		(size 0.4064)
		(drill 0.2032)
		(layers "F.Cu" "B.Cu")
		(net "GND")
	)
	(via
		(at 298.70654 -294.660066)
		(size 0.4826)
		(drill 0.254)
		(layers "F.Cu" "B.Cu")
		(net "GND")
	)
	(via
		(at 365.18469 -274.086066)
		(size 0.4064)
		(drill 0.2032)
		(layers "F.Cu" "B.Cu")
		(net "GND")
	)
	(via
		(at 171.97197 -252.58522)
		(size 0.4826)
		(drill 0.254)
		(layers "F.Cu" "B.Cu")
		(net "GND")
	)
	(via
		(at 94.718124 -407.00452)
		(size 0.4064)
		(drill 0.2032)
		(layers "F.Cu" "B.Cu")
		(net "GND")
	)
	(via
		(at 467.5378 -317.551054)
		(size 0.508)
		(drill 0.254)
		(layers "F.Cu" "B.Cu")
		(net "GND")
	)
	(via
		(at 116.004848 -243.674392)
		(size 0.4064)
		(drill 0.2032)
		(layers "F.Cu" "B.Cu")
		(net "GND")
	)
	(via
		(at 97.705672 -119.869204)
		(size 0.508)
		(drill 0.254)
		(layers "F.Cu" "B.Cu")
		(net "GND")
	)
	(via
		(at 351.685352 -339.535516)
		(size 0.49022)
		(drill 0.254)
		(layers "F.Cu" "B.Cu")
		(net "GND")
	)
	(via
		(at 339.511132 -230.714296)
		(size 0.4064)
		(drill 0.2032)
		(layers "F.Cu" "B.Cu")
		(net "GND")
	)
	(via
		(at 59.297824 -152.805892)
		(size 0.508)
		(drill 0.254)
		(layers "F.Cu" "B.Cu")
		(net "GND")
	)
	(via
		(at 419.912038 -217.73515)
		(size 0.4826)
		(drill 0.254)
		(layers "F.Cu" "B.Cu")
		(net "GND")
	)
	(via
		(at 157.57906 -9.345676)
		(size 0.508)
		(drill 0.254)
		(layers "F.Cu" "B.Cu")
		(net "GND")
	)
	(via
		(at 264.38606 -186.872118)
		(size 0.508)
		(drill 0.254)
		(layers "F.Cu" "B.Cu")
		(net "GND")
	)
	(via
		(at 122.952002 -79.744824)
		(size 0.508)
		(drill 0.254)
		(layers "F.Cu" "B.Cu")
		(net "GND")
	)
	(via
		(at 86.31555 -189.552326)
		(size 0.508)
		(drill 0.254)
		(layers "F.Cu" "B.Cu")
		(net "GND")
	)
	(via
		(at 97.040954 -271.656302)
		(size 0.4064)
		(drill 0.2032)
		(layers "F.Cu" "B.Cu")
		(net "GND")
	)
	(via
		(at 354.551234 -224.234248)
		(size 0.4064)
		(drill 0.2032)
		(layers "F.Cu" "B.Cu")
		(net "GND")
	)
	(via
		(at 58.587894 -339.883496)
		(size 0.508)
		(drill 0.254)
		(layers "F.Cu" "B.Cu")
		(net "GND")
	)
	(via
		(at 413.349694 -431.29962)
		(size 0.4572)
		(drill 0.2032)
		(layers "F.Cu" "B.Cu")
		(net "GND")
	)
	(via
		(at 138.349736 -425.547282)
		(size 0.4572)
		(drill 0.2032)
		(layers "F.Cu" "B.Cu")
		(net "GND")
	)
	(via
		(at 418.07892 -18.247106)
		(size 0.508)
		(drill 0.254)
		(layers "F.Cu" "B.Cu")
		(net "GND")
	)
	(via
		(at 427.97095 -38.039548)
		(size 0.508)
		(drill 0.254)
		(layers "F.Cu" "B.Cu")
		(net "GND")
	)
	(via
		(at 327.381108 -333.048864)
		(size 0.49022)
		(drill 0.254)
		(layers "F.Cu" "B.Cu")
		(net "GND")
	)
	(via
		(at 319.249552 -433.899564)
		(size 0.4572)
		(drill 0.2032)
		(layers "F.Cu" "B.Cu")
		(net "GND")
	)
	(via
		(at 356.901242 -247.724168)
		(size 0.4064)
		(drill 0.2032)
		(layers "F.Cu" "B.Cu")
		(net "GND")
	)
	(via
		(at 108.02112 -247.724422)
		(size 0.4064)
		(drill 0.2032)
		(layers "F.Cu" "B.Cu")
		(net "GND")
	)
	(via
		(at 89.99093 -278.946356)
		(size 0.4064)
		(drill 0.2032)
		(layers "F.Cu" "B.Cu")
		(net "GND")
	)
	(via
		(at 268.263878 -274.684998)
		(size 0.4826)
		(drill 0.254)
		(layers "F.Cu" "B.Cu")
		(net "GND")
	)
	(via
		(at 154.245818 -409.396184)
		(size 0.4572)
		(drill 0.254)
		(layers "F.Cu" "B.Cu")
		(net "GND")
	)
	(via
		(at 290.895786 -284.034992)
		(size 0.4826)
		(drill 0.254)
		(layers "F.Cu" "B.Cu")
		(net "GND")
	)
	(via
		(at 334.341216 -252.584204)
		(size 0.4064)
		(drill 0.2032)
		(layers "F.Cu" "B.Cu")
		(net "GND")
	)
	(via
		(at 309.743602 -339.882988)
		(size 0.508)
		(drill 0.254)
		(layers "F.Cu" "B.Cu")
		(net "GND")
	)
	(via
		(at 123.524772 -225.854514)
		(size 0.4064)
		(drill 0.2032)
		(layers "F.Cu" "B.Cu")
		(net "GND")
	)
	(via
		(at 186.447938 -348.71152)
		(size 0.508)
		(drill 0.254)
		(layers "F.Cu" "B.Cu")
		(net "GND")
	)
	(via
		(at 98.451162 -270.846296)
		(size 0.4064)
		(drill 0.2032)
		(layers "F.Cu" "B.Cu")
		(net "GND")
	)
	(via
		(at 73.634092 -407.638504)
		(size 0.4572)
		(drill 0.254)
		(layers "F.Cu" "B.Cu")
		(net "GND")
	)
	(via
		(at 343.418414 -421.586152)
		(size 0.4572)
		(drill 0.254)
		(layers "F.Cu" "B.Cu")
		(net "GND")
	)
	(via
		(at 44.340018 -308.685438)
		(size 0.4826)
		(drill 0.254)
		(layers "F.Cu" "B.Cu")
		(net "GND")
	)
	(via
		(at 376.93473 -278.136096)
		(size 0.4064)
		(drill 0.2032)
		(layers "F.Cu" "B.Cu")
		(net "GND")
	)
	(via
		(at 389.79475 -236.384084)
		(size 0.4064)
		(drill 0.2032)
		(layers "F.Cu" "B.Cu")
		(net "GND")
	)
	(via
		(at 170.18 -118.324376)
		(size 0.508)
		(drill 0.254)
		(layers "F.Cu" "B.Cu")
		(net "GND")
	)
	(via
		(at 349.381064 -250.964192)
		(size 0.4064)
		(drill 0.2032)
		(layers "F.Cu" "B.Cu")
		(net "GND")
	)
	(via
		(at 26.536396 -221.985332)
		(size 0.4826)
		(drill 0.254)
		(layers "F.Cu" "B.Cu")
		(net "GND")
	)
	(via
		(at 366.764824 -250.154186)
		(size 0.4064)
		(drill 0.2032)
		(layers "F.Cu" "B.Cu")
		(net "GND")
	)
	(via
		(at 340.921086 -255.824228)
		(size 0.4064)
		(drill 0.2032)
		(layers "F.Cu" "B.Cu")
		(net "GND")
	)
	(via
		(at 364.53064 -383.68986)
		(size 0.508)
		(drill 0.254)
		(layers "F.Cu" "B.Cu")
		(net "GND")
	)
	(via
		(at 60.818522 -175.51781)
		(size 0.508)
		(drill 0.254)
		(layers "F.Cu" "B.Cu")
		(net "GND")
	)
	(via
		(at 140.744702 -269.226284)
		(size 0.4064)
		(drill 0.2032)
		(layers "F.Cu" "B.Cu")
		(net "GND")
	)
	(via
		(at 318.551306 -412.84652)
		(size 0.4064)
		(drill 0.2032)
		(layers "F.Cu" "B.Cu")
		(net "GND")
	)
	(via
		(at 330.229464 -331.743812)
		(size 0.508)
		(drill 0.254)
		(layers "F.Cu" "B.Cu")
		(net "GND")
	)
	(via
		(at 93.54439 -391.830814)
		(size 0.4064)
		(drill 0.2032)
		(layers "F.Cu" "B.Cu")
		(net "GND")
	)
	(via
		(at 391.217658 -311.822592)
		(size 0.508)
		(drill 0.254)
		(layers "F.Cu" "B.Cu")
		(net "GND")
	)
	(via
		(at 81.701132 -249.344434)
		(size 0.4064)
		(drill 0.2032)
		(layers "F.Cu" "B.Cu")
		(net "GND")
	)
	(via
		(at 379.924818 -242.054126)
		(size 0.4064)
		(drill 0.2032)
		(layers "F.Cu" "B.Cu")
		(net "GND")
	)
	(via
		(at 415.492692 -139.436856)
		(size 0.508)
		(drill 0.254)
		(layers "F.Cu" "B.Cu")
		(net "GND")
	)
	(via
		(at 300.538896 -379.88113)
		(size 0.508)
		(drill 0.254)
		(layers "F.Cu" "B.Cu")
		(net "GND")
	)
	(via
		(at 446.667636 -20.254722)
		(size 0.508)
		(drill 0.254)
		(layers "F.Cu" "B.Cu")
		(net "GND")
	)
	(via
		(at 330.2508 -150.0124)
		(size 0.508)
		(drill 0.254)
		(layers "F.Cu" "B.Cu")
		(net "GND")
	)
	(via
		(at 189.775846 -293.38524)
		(size 0.4826)
		(drill 0.254)
		(layers "F.Cu" "B.Cu")
		(net "GND")
	)
	(via
		(at 132.349748 -436.051198)
		(size 0.4572)
		(drill 0.2032)
		(layers "F.Cu" "B.Cu")
		(net "GND")
	)
	(via
		(at 381.145034 -412.212536)
		(size 0.4572)
		(drill 0.254)
		(layers "F.Cu" "B.Cu")
		(net "GND")
	)
	(via
		(at 180.937916 -427.298866)
		(size 0.508)
		(drill 0.254)
		(layers "F.Cu" "B.Cu")
		(net "GND")
	)
	(via
		(at 450.057774 -31.353506)
		(size 0.508)
		(drill 0.254)
		(layers "F.Cu" "B.Cu")
		(net "GND")
	)
	(via
		(at 235.768896 -67.074288)
		(size 0.508)
		(drill 0.254)
		(layers "F.Cu" "B.Cu")
		(net "GND")
	)
	(via
		(at 13.29182 -383.320798)
		(size 0.508)
		(drill 0.254)
		(layers "F.Cu" "B.Cu")
		(net "GND")
	)
	(via
		(at 364.955074 -178.170332)
		(size 0.49022)
		(drill 0.254)
		(layers "F.Cu" "B.Cu")
		(net "GND")
	)
	(via
		(at 97.040954 -276.516338)
		(size 0.4064)
		(drill 0.2032)
		(layers "F.Cu" "B.Cu")
		(net "GND")
	)
	(via
		(at 90.196162 -370.83873)
		(size 0.508)
		(drill 0.254)
		(layers "F.Cu" "B.Cu")
		(net "GND")
	)
	(via
		(at 451.4723 -312.935112)
		(size 0.4826)
		(drill 0.254)
		(layers "F.Cu" "B.Cu")
		(net "GND")
	)
	(via
		(at 374.114822 -279.756108)
		(size 0.4064)
		(drill 0.2032)
		(layers "F.Cu" "B.Cu")
		(net "GND")
	)
	(via
		(at 411.349698 -431.451258)
		(size 0.4572)
		(drill 0.2032)
		(layers "F.Cu" "B.Cu")
		(net "GND")
	)
	(via
		(at 104.731058 -248.534428)
		(size 0.4064)
		(drill 0.2032)
		(layers "F.Cu" "B.Cu")
		(net "GND")
	)
	(via
		(at 405.34971 -438.499758)
		(size 0.4572)
		(drill 0.2032)
		(layers "F.Cu" "B.Cu")
		(net "GND")
	)
	(via
		(at 62.551564 -412.570168)
		(size 0.4064)
		(drill 0.2032)
		(layers "F.Cu" "B.Cu")
		(net "GND")
	)
	(via
		(at 396.349474 -437.34736)
		(size 0.4572)
		(drill 0.2032)
		(layers "F.Cu" "B.Cu")
		(net "GND")
	)
	(via
		(at 179.516024 -217.735404)
		(size 0.4826)
		(drill 0.254)
		(layers "F.Cu" "B.Cu")
		(net "GND")
	)
	(via
		(at 177.189638 -304.010314)
		(size 0.4826)
		(drill 0.254)
		(layers "F.Cu" "B.Cu")
		(net "GND")
	)
	(via
		(at 339.511132 -245.29415)
		(size 0.4064)
		(drill 0.2032)
		(layers "F.Cu" "B.Cu")
		(net "GND")
	)
	(via
		(at 51.884072 -235.585254)
		(size 0.4826)
		(drill 0.254)
		(layers "F.Cu" "B.Cu")
		(net "GND")
	)
	(via
		(at 140.955522 -81.423002)
		(size 0.508)
		(drill 0.254)
		(layers "F.Cu" "B.Cu")
		(net "GND")
	)
	(via
		(at 182.332122 -111.86287)
		(size 0.4572)
		(drill 0.254)
		(layers "F.Cu" "B.Cu")
		(net "GND")
	)
	(via
		(at 275.807932 -221.13494)
		(size 0.4826)
		(drill 0.254)
		(layers "F.Cu" "B.Cu")
		(net "GND")
	)
	(via
		(at 176.732184 -123.84278)
		(size 0.4572)
		(drill 0.254)
		(layers "F.Cu" "B.Cu")
		(net "GND")
	)
	(via
		(at 381.059182 -415.38652)
		(size 0.4064)
		(drill 0.2032)
		(layers "F.Cu" "B.Cu")
		(net "GND")
	)
	(via
		(at 161.844228 -393.877038)
		(size 0.4572)
		(drill 0.254)
		(layers "F.Cu" "B.Cu")
		(net "GND")
	)
	(via
		(at 394.68298 -231.789986)
		(size 0.4064)
		(drill 0.2032)
		(layers "F.Cu" "B.Cu")
		(net "GND")
	)
	(via
		(at 420.58844 -379.88113)
		(size 0.508)
		(drill 0.254)
		(layers "F.Cu" "B.Cu")
		(net "GND")
	)
	(via
		(at 307.368194 -248.335038)
		(size 0.4826)
		(drill 0.254)
		(layers "F.Cu" "B.Cu")
		(net "GND")
	)
	(via
		(at 29.05887 -385.14909)
		(size 0.508)
		(drill 0.254)
		(layers "F.Cu" "B.Cu")
		(net "GND")
	)
	(via
		(at 123.994672 -246.10441)
		(size 0.4064)
		(drill 0.2032)
		(layers "F.Cu" "B.Cu")
		(net "GND")
	)
	(via
		(at 349.336614 -361.002072)
		(size 0.508)
		(drill 0.254)
		(layers "F.Cu" "B.Cu")
		(net "GND")
	)
	(via
		(at 437.886602 -422.52011)
		(size 0.508)
		(drill 0.254)
		(layers "F.Cu" "B.Cu")
		(net "GND")
	)
	(via
		(at 230.96728 -56.964834)
		(size 0.508)
		(drill 0.254)
		(layers "F.Cu" "B.Cu")
		(net "GND")
	)
	(via
		(at 344.249502 -433.899564)
		(size 0.4572)
		(drill 0.2032)
		(layers "F.Cu" "B.Cu")
		(net "GND")
	)
	(via
		(at 401.814538 -4.963414)
		(size 0.508)
		(drill 0.254)
		(layers "F.Cu" "B.Cu")
		(net "GND")
	)
	(via
		(at 439.111644 -7.164832)
		(size 0.508)
		(drill 0.254)
		(layers "F.Cu" "B.Cu")
		(net "GND")
	)
	(via
		(at 322.08978 -328.072496)
		(size 0.508)
		(drill 0.254)
		(layers "F.Cu" "B.Cu")
		(net "GND")
	)
	(via
		(at 99.390962 -275.706332)
		(size 0.4064)
		(drill 0.2032)
		(layers "F.Cu" "B.Cu")
		(net "GND")
	)
	(via
		(at 274.12061 -345.566238)
		(size 0.49022)
		(drill 0.254)
		(layers "F.Cu" "B.Cu")
		(net "GND")
	)
	(via
		(at 102.235762 -341.927688)
		(size 0.49022)
		(drill 0.254)
		(layers "F.Cu" "B.Cu")
		(net "GND")
	)
	(via
		(at 101.91115 -248.534428)
		(size 0.4064)
		(drill 0.2032)
		(layers "F.Cu" "B.Cu")
		(net "GND")
	)
	(via
		(at 370.994686 -254.204216)
		(size 0.4064)
		(drill 0.2032)
		(layers "F.Cu" "B.Cu")
		(net "GND")
	)
	(via
		(at 288.180018 -247.485154)
		(size 0.4826)
		(drill 0.254)
		(layers "F.Cu" "B.Cu")
		(net "GND")
	)
	(via
		(at 129.634742 -249.344434)
		(size 0.4064)
		(drill 0.2032)
		(layers "F.Cu" "B.Cu")
		(net "GND")
	)
	(via
		(at 317.704724 -334.596232)
		(size 0.49022)
		(drill 0.254)
		(layers "F.Cu" "B.Cu")
		(net "GND")
	)
	(via
		(at 113.184686 -227.474526)
		(size 0.4064)
		(drill 0.2032)
		(layers "F.Cu" "B.Cu")
		(net "GND")
	)
	(via
		(at 144.674844 -221.804484)
		(size 0.4064)
		(drill 0.2032)
		(layers "F.Cu" "B.Cu")
		(net "GND")
	)
	(via
		(at 123.84786 -26.916126)
		(size 0.508)
		(drill 0.254)
		(layers "F.Cu" "B.Cu")
		(net "GND")
	)
	(via
		(at 392.140948 -19.137122)
		(size 0.508)
		(drill 0.254)
		(layers "F.Cu" "B.Cu")
		(net "GND")
	)
	(via
		(at 323.562726 -334.0862)
		(size 0.508)
		(drill 0.254)
		(layers "F.Cu" "B.Cu")
		(net "GND")
	)
	(via
		(at 130.574796 -225.044508)
		(size 0.4064)
		(drill 0.2032)
		(layers "F.Cu" "B.Cu")
		(net "GND")
	)
	(via
		(at 105.031032 -272.466308)
		(size 0.4064)
		(drill 0.2032)
		(layers "F.Cu" "B.Cu")
		(net "GND")
	)
	(via
		(at 134.726172 -34.841434)
		(size 0.508)
		(drill 0.254)
		(layers "F.Cu" "B.Cu")
		(net "GND")
	)
	(via
		(at 71.829676 -407.638504)
		(size 0.4572)
		(drill 0.254)
		(layers "F.Cu" "B.Cu")
		(net "GND")
	)
	(via
		(at 100.375466 -183.843168)
		(size 0.49022)
		(drill 0.254)
		(layers "F.Cu" "B.Cu")
		(net "GND")
	)
	(via
		(at 383.514854 -286.236156)
		(size 0.4064)
		(drill 0.2032)
		(layers "F.Cu" "B.Cu")
		(net "GND")
	)
	(via
		(at 305.127914 -416.020504)
		(size 0.4572)
		(drill 0.254)
		(layers "F.Cu" "B.Cu")
		(net "GND")
	)
	(via
		(at 339.15604 -60.094876)
		(size 0.508)
		(drill 0.254)
		(layers "F.Cu" "B.Cu")
		(net "GND")
	)
	(via
		(at 372.234714 -284.616144)
		(size 0.4064)
		(drill 0.2032)
		(layers "F.Cu" "B.Cu")
		(net "GND")
	)
	(via
		(at 406.111964 -17.613122)
		(size 0.508)
		(drill 0.254)
		(layers "F.Cu" "B.Cu")
		(net "GND")
	)
	(via
		(at 382.94945 -412.212536)
		(size 0.4572)
		(drill 0.254)
		(layers "F.Cu" "B.Cu")
		(net "GND")
	)
	(via
		(at 387.914896 -244.484144)
		(size 0.4064)
		(drill 0.2032)
		(layers "F.Cu" "B.Cu")
		(net "GND")
	)
	(via
		(at 405.92375 -414.752536)
		(size 0.4572)
		(drill 0.254)
		(layers "F.Cu" "B.Cu")
		(net "GND")
	)
	(via
		(at 259.564632 -327.437496)
		(size 0.508)
		(drill 0.254)
		(layers "F.Cu" "B.Cu")
		(net "GND")
	)
	(via
		(at 85.975444 -412.570168)
		(size 0.4064)
		(drill 0.2032)
		(layers "F.Cu" "B.Cu")
		(net "GND")
	)
	(via
		(at 92.1385 -340.540086)
		(size 0.508)
		(drill 0.254)
		(layers "F.Cu" "B.Cu")
		(net "GND")
	)
	(via
		(at 303.164494 -394.25753)
		(size 0.4064)
		(drill 0.2032)
		(layers "F.Cu" "B.Cu")
		(net "GND")
	)
	(via
		(at 355.190044 -377.41733)
		(size 0.508)
		(drill 0.254)
		(layers "F.Cu" "B.Cu")
		(net "GND")
	)
	(via
		(at 332.461108 -223.424242)
		(size 0.4064)
		(drill 0.2032)
		(layers "F.Cu" "B.Cu")
		(net "GND")
	)
	(via
		(at 370.994686 -252.584204)
		(size 0.4064)
		(drill 0.2032)
		(layers "F.Cu" "B.Cu")
		(net "GND")
	)
	(via
		(at 454.188068 -280.634948)
		(size 0.4826)
		(drill 0.254)
		(layers "F.Cu" "B.Cu")
		(net "GND")
	)
	(via
		(at 421.296338 -228.785166)
		(size 0.4826)
		(drill 0.254)
		(layers "F.Cu" "B.Cu")
		(net "GND")
	)
	(via
		(at 347.97111 -232.334054)
		(size 0.4064)
		(drill 0.2032)
		(layers "F.Cu" "B.Cu")
		(net "GND")
	)
	(via
		(at 341.390986 -256.634234)
		(size 0.4064)
		(drill 0.2032)
		(layers "F.Cu" "B.Cu")
		(net "GND")
	)
	(via
		(at 306.020216 -429.60925)
		(size 0.508)
		(drill 0.254)
		(layers "F.Cu" "B.Cu")
		(net "GND")
	)
	(via
		(at 431.597816 -19.13636)
		(size 0.508)
		(drill 0.254)
		(layers "F.Cu" "B.Cu")
		(net "GND")
	)
	(via
		(at 187.911994 -116.642642)
		(size 0.4572)
		(drill 0.254)
		(layers "F.Cu" "B.Cu")
		(net "GND")
	)
	(via
		(at 78.841346 -355.739446)
		(size 0.508)
		(drill 0.254)
		(layers "F.Cu" "B.Cu")
		(net "GND")
	)
	(via
		(at 344.860118 -164.38372)
		(size 0.508)
		(drill 0.254)
		(layers "F.Cu" "B.Cu")
		(net "GND")
	)
	(via
		(at 427.456092 -301.885096)
		(size 0.4826)
		(drill 0.254)
		(layers "F.Cu" "B.Cu")
		(net "GND")
	)
	(via
		(at 413.819086 -398.542002)
		(size 0.4064)
		(drill 0.2032)
		(layers "F.Cu" "B.Cu")
		(net "GND")
	)
	(via
		(at 179.516024 -318.885316)
		(size 0.4826)
		(drill 0.254)
		(layers "F.Cu" "B.Cu")
		(net "GND")
	)
	(via
		(at 384.154934 -249.34418)
		(size 0.4064)
		(drill 0.2032)
		(layers "F.Cu" "B.Cu")
		(net "GND")
	)
	(via
		(at 454.188068 -318.035178)
		(size 0.4826)
		(drill 0.254)
		(layers "F.Cu" "B.Cu")
		(net "GND")
	)
	(via
		(at 123.613418 -410.664152)
		(size 0.4572)
		(drill 0.254)
		(layers "F.Cu" "B.Cu")
		(net "GND")
	)
	(via
		(at 88.580976 -266.796266)
		(size 0.4064)
		(drill 0.2032)
		(layers "F.Cu" "B.Cu")
		(net "GND")
	)
	(via
		(at 59.576716 -406.370536)
		(size 0.4572)
		(drill 0.254)
		(layers "F.Cu" "B.Cu")
		(net "GND")
	)
	(via
		(at 344.249502 -435.0512)
		(size 0.4572)
		(drill 0.2032)
		(layers "F.Cu" "B.Cu")
		(net "GND")
	)
	(via
		(at 224.529396 -439.90768)
		(size 0.508)
		(drill 0.254)
		(layers "F.Cu" "B.Cu")
		(net "GND")
	)
	(via
		(at 158.997904 -368.37493)
		(size 0.508)
		(drill 0.254)
		(layers "F.Cu" "B.Cu")
		(net "GND")
	)
	(via
		(at 86.249764 -431.29962)
		(size 0.4572)
		(drill 0.2032)
		(layers "F.Cu" "B.Cu")
		(net "GND")
	)
	(via
		(at 128.694688 -246.10441)
		(size 0.4064)
		(drill 0.2032)
		(layers "F.Cu" "B.Cu")
		(net "GND")
	)
	(via
		(at 256.232406 -125.38837)
		(size 0.508)
		(drill 0.254)
		(layers "F.Cu" "B.Cu")
		(net "GND")
	)
	(via
		(at 74.813414 -328.010012)
		(size 0.508)
		(drill 0.254)
		(layers "F.Cu" "B.Cu")
		(net "GND")
	)
	(via
		(at 391.866374 -419.046152)
		(size 0.4572)
		(drill 0.254)
		(layers "F.Cu" "B.Cu")
		(net "GND")
	)
	(via
		(at 44.340018 -233.885232)
		(size 0.4826)
		(drill 0.254)
		(layers "F.Cu" "B.Cu")
		(net "GND")
	)
	(via
		(at 27.774138 -16.979138)
		(size 0.508)
		(drill 0.254)
		(layers "F.Cu" "B.Cu")
		(net "GND")
	)
	(via
		(at 371.45087 -15.637002)
		(size 0.508)
		(drill 0.254)
		(layers "F.Cu" "B.Cu")
		(net "GND")
	)
	(via
		(at 280.635964 -223.6851)
		(size 0.4826)
		(drill 0.254)
		(layers "F.Cu" "B.Cu")
		(net "GND")
	)
	(via
		(at 381.334772 -252.584204)
		(size 0.4064)
		(drill 0.2032)
		(layers "F.Cu" "B.Cu")
		(net "GND")
	)
	(via
		(at 79.6925 -385.87553)
		(size 0.4064)
		(drill 0.2032)
		(layers "F.Cu" "B.Cu")
		(net "GND")
	)
	(via
		(at 86.401148 -250.964446)
		(size 0.4064)
		(drill 0.2032)
		(layers "F.Cu" "B.Cu")
		(net "GND")
	)
	(via
		(at 178.289458 -51.299872)
		(size 0.508)
		(drill 0.254)
		(layers "F.Cu" "B.Cu")
		(net "GND")
	)
	(via
		(at 168.527984 -251.735336)
		(size 0.4826)
		(drill 0.254)
		(layers "F.Cu" "B.Cu")
		(net "GND")
	)
	(via
		(at 268.263878 -211.784946)
		(size 0.4826)
		(drill 0.254)
		(layers "F.Cu" "B.Cu")
		(net "GND")
	)
	(via
		(at 112.397794 -261.323074)
		(size 0.4826)
		(drill 0.254)
		(layers "F.Cu" "B.Cu")
		(net "GND")
	)
	(via
		(at 244.605048 -289.435794)
		(size 0.508)
		(drill 0.254)
		(layers "F.Cu" "B.Cu")
		(net "GND")
	)
	(via
		(at 363.474762 -228.284278)
		(size 0.4064)
		(drill 0.2032)
		(layers "F.Cu" "B.Cu")
		(net "GND")
	)
	(via
		(at 118.824756 -224.234502)
		(size 0.4064)
		(drill 0.2032)
		(layers "F.Cu" "B.Cu")
		(net "GND")
	)
	(via
		(at 195.759832 -192.218564)
		(size 0.4826)
		(drill 0.254)
		(layers "F.Cu" "B.Cu")
		(net "GND")
	)
	(via
		(at 115.534694 -242.864386)
		(size 0.4064)
		(drill 0.2032)
		(layers "F.Cu" "B.Cu")
		(net "GND")
	)
	(via
		(at 334.249522 -436.051198)
		(size 0.4572)
		(drill 0.2032)
		(layers "F.Cu" "B.Cu")
		(net "GND")
	)
	(via
		(at 282.020264 -240.685066)
		(size 0.4826)
		(drill 0.254)
		(layers "F.Cu" "B.Cu")
		(net "GND")
	)
	(via
		(at 174.916338 -192.218564)
		(size 0.4826)
		(drill 0.254)
		(layers "F.Cu" "B.Cu")
		(net "GND")
	)
	(via
		(at 445.87795 -54.972458)
		(size 0.508)
		(drill 0.254)
		(layers "F.Cu" "B.Cu")
		(net "GND")
	)
	(via
		(at 376.634756 -236.384084)
		(size 0.4064)
		(drill 0.2032)
		(layers "F.Cu" "B.Cu")
		(net "GND")
	)
	(via
		(at 140.444728 -255.014476)
		(size 0.4064)
		(drill 0.2032)
		(layers "F.Cu" "B.Cu")
		(net "GND")
	)
	(via
		(at 326.720708 -333.838042)
		(size 0.49022)
		(drill 0.254)
		(layers "F.Cu" "B.Cu")
		(net "GND")
	)
	(via
		(at 253.973076 -321.850004)
		(size 0.508)
		(drill 0.254)
		(layers "F.Cu" "B.Cu")
		(net "GND")
	)
	(via
		(at 365.18469 -291.905944)
		(size 0.4064)
		(drill 0.2032)
		(layers "F.Cu" "B.Cu")
		(net "GND")
	)
	(via
		(at 32.352996 -399.478246)
		(size 0.508)
		(drill 0.254)
		(layers "F.Cu" "B.Cu")
		(net "GND")
	)
	(via
		(at 230.96728 -58.764932)
		(size 0.508)
		(drill 0.254)
		(layers "F.Cu" "B.Cu")
		(net "GND")
	)
	(via
		(at 59.849512 -411.936184)
		(size 0.4572)
		(drill 0.254)
		(layers "F.Cu" "B.Cu")
		(net "GND")
	)
	(via
		(at 83.580986 -236.384338)
		(size 0.4064)
		(drill 0.2032)
		(layers "F.Cu" "B.Cu")
		(net "GND")
	)
	(via
		(at 319.249552 -435.0512)
		(size 0.4572)
		(drill 0.2032)
		(layers "F.Cu" "B.Cu")
		(net "GND")
	)
	(via
		(at 104.9274 -408.3304)
		(size 0.508)
		(drill 0.254)
		(layers "F.Cu" "B.Cu")
		(net "GND")
	)
	(via
		(at 375.524776 -293.525956)
		(size 0.4064)
		(drill 0.2032)
		(layers "F.Cu" "B.Cu")
		(net "GND")
	)
	(via
		(at 424.165522 -7.215124)
		(size 0.508)
		(drill 0.254)
		(layers "F.Cu" "B.Cu")
		(net "GND")
	)
	(via
		(at 173.08957 -295.510458)
		(size 0.4826)
		(drill 0.254)
		(layers "F.Cu" "B.Cu")
		(net "GND")
	)
	(via
		(at 349.381064 -252.584204)
		(size 0.4064)
		(drill 0.2032)
		(layers "F.Cu" "B.Cu")
		(net "GND")
	)
	(via
		(at 52.191412 -409.396184)
		(size 0.4572)
		(drill 0.254)
		(layers "F.Cu" "B.Cu")
		(net "GND")
	)
	(via
		(at 78.711044 -261.126224)
		(size 0.4064)
		(drill 0.2032)
		(layers "F.Cu" "B.Cu")
		(net "GND")
	)
	(via
		(at 331.521054 -231.524048)
		(size 0.4064)
		(drill 0.2032)
		(layers "F.Cu" "B.Cu")
		(net "GND")
	)
	(via
		(at 174.78248 -385.978654)
		(size 0.508)
		(drill 0.254)
		(layers "F.Cu" "B.Cu")
		(net "GND")
	)
	(via
		(at 334.341216 -226.664266)
		(size 0.4064)
		(drill 0.2032)
		(layers "F.Cu" "B.Cu")
		(net "GND")
	)
	(via
		(at 382.91643 -391.23493)
		(size 0.4064)
		(drill 0.2032)
		(layers "F.Cu" "B.Cu")
		(net "GND")
	)
	(via
		(at 37.685218 -16.9799)
		(size 0.508)
		(drill 0.254)
		(layers "F.Cu" "B.Cu")
		(net "GND")
	)
	(via
		(at 394.84554 -7.215124)
		(size 0.508)
		(drill 0.254)
		(layers "F.Cu" "B.Cu")
		(net "GND")
	)
	(via
		(at 384.349498 -436.051198)
		(size 0.4572)
		(drill 0.2032)
		(layers "F.Cu" "B.Cu")
		(net "GND")
	)
	(via
		(at 119.76481 -240.434368)
		(size 0.4064)
		(drill 0.2032)
		(layers "F.Cu" "B.Cu")
		(net "GND")
	)
	(via
		(at 21.336 -357.632)
		(size 0.508)
		(drill 0.254)
		(layers "F.Cu" "B.Cu")
		(net "GND")
	)
	(via
		(at 429.22952 -399.305018)
		(size 0.508)
		(drill 0.254)
		(layers "F.Cu" "B.Cu")
		(net "GND")
	)
	(via
		(at 16.784574 -387.704076)
		(size 0.49022)
		(drill 0.254)
		(layers "F.Cu" "B.Cu")
		(net "GND")
	)
	(via
		(at 266.93241 -200.735184)
		(size 0.4826)
		(drill 0.254)
		(layers "F.Cu" "B.Cu")
		(net "GND")
	)
	(via
		(at 156.081984 -370.83873)
		(size 0.508)
		(drill 0.254)
		(layers "F.Cu" "B.Cu")
		(net "GND")
	)
	(via
		(at 413.349694 -426.54728)
		(size 0.4572)
		(drill 0.2032)
		(layers "F.Cu" "B.Cu")
		(net "GND")
	)
	(via
		(at 59.428126 -205.83525)
		(size 0.4826)
		(drill 0.254)
		(layers "F.Cu" "B.Cu")
		(net "GND")
	)
	(via
		(at 411.777434 -420.318184)
		(size 0.4572)
		(drill 0.254)
		(layers "F.Cu" "B.Cu")
		(net "GND")
	)
	(via
		(at 455.633582 -395.27353)
		(size 0.49022)
		(drill 0.254)
		(layers "F.Cu" "B.Cu")
		(net "GND")
	)
	(via
		(at 365.939832 -379.22073)
		(size 0.508)
		(drill 0.254)
		(layers "F.Cu" "B.Cu")
		(net "GND")
	)
	(via
		(at 67.249802 -437.49976)
		(size 0.4572)
		(drill 0.2032)
		(layers "F.Cu" "B.Cu")
		(net "GND")
	)
	(via
		(at 23.948136 -12.37488)
		(size 0.508)
		(drill 0.254)
		(layers "F.Cu" "B.Cu")
		(net "GND")
	)
	(via
		(at 424.012106 -224.534984)
		(size 0.4826)
		(drill 0.254)
		(layers "F.Cu" "B.Cu")
		(net "GND")
	)
	(via
		(at 140.744702 -283.806392)
		(size 0.4064)
		(drill 0.2032)
		(layers "F.Cu" "B.Cu")
		(net "GND")
	)
	(via
		(at 90.683842 -369.69573)
		(size 0.508)
		(drill 0.254)
		(layers "F.Cu" "B.Cu")
		(net "GND")
	)
	(via
		(at 24.999696 -388.493254)
		(size 0.49022)
		(drill 0.254)
		(layers "F.Cu" "B.Cu")
		(net "GND")
	)
	(via
		(at 435.181248 -349.191326)
		(size 0.508)
		(drill 0.254)
		(layers "F.Cu" "B.Cu")
		(net "GND")
	)
	(via
		(at 77.112876 -292.450266)
		(size 0.4064)
		(drill 0.2032)
		(layers "F.Cu" "B.Cu")
		(net "GND")
	)
	(via
		(at 305.016154 -402.284438)
		(size 0.4572)
		(drill 0.254)
		(layers "F.Cu" "B.Cu")
		(net "GND")
	)
	(via
		(at 339.811106 -275.706078)
		(size 0.4064)
		(drill 0.2032)
		(layers "F.Cu" "B.Cu")
		(net "GND")
	)
	(via
		(at 185.453274 -15.432278)
		(size 0.508)
		(drill 0.254)
		(layers "F.Cu" "B.Cu")
		(net "GND")
	)
	(via
		(at 275.230082 -100.37953)
		(size 0.508)
		(drill 0.254)
		(layers "F.Cu" "B.Cu")
		(net "GND")
	)
	(via
		(at 360.197654 -252.41631)
		(size 0.4826)
		(drill 0.254)
		(layers "F.Cu" "B.Cu")
		(net "GND")
	)
	(via
		(at 229.871778 -316.46368)
		(size 0.508)
		(drill 0.254)
		(layers "F.Cu" "B.Cu")
		(net "GND")
	)
	(via
		(at 337.161124 -225.044254)
		(size 0.4064)
		(drill 0.2032)
		(layers "F.Cu" "B.Cu")
		(net "GND")
	)
	(via
		(at 337.118706 -398.542002)
		(size 0.4064)
		(drill 0.2032)
		(layers "F.Cu" "B.Cu")
		(net "GND")
	)
	(via
		(at 295.724072 -245.785132)
		(size 0.4826)
		(drill 0.254)
		(layers "F.Cu" "B.Cu")
		(net "GND")
	)
	(via
		(at 104.731058 -230.71455)
		(size 0.4064)
		(drill 0.2032)
		(layers "F.Cu" "B.Cu")
		(net "GND")
	)
	(via
		(at 399.693638 -392.1252)
		(size 0.508)
		(drill 0.254)
		(layers "F.Cu" "B.Cu")
		(net "GND")
	)
	(via
		(at 179.516024 -267.885418)
		(size 0.4826)
		(drill 0.254)
		(layers "F.Cu" "B.Cu")
		(net "GND")
	)
	(via
		(at 206.248 -278.935434)
		(size 0.4826)
		(drill 0.254)
		(layers "F.Cu" "B.Cu")
		(net "GND")
	)
	(via
		(at 207.3656 -275.960332)
		(size 0.4826)
		(drill 0.254)
		(layers "F.Cu" "B.Cu")
		(net "GND")
	)
	(via
		(at 104.465882 -377.132088)
		(size 0.508)
		(drill 0.254)
		(layers "F.Cu" "B.Cu")
		(net "GND")
	)
	(via
		(at 198.631556 -342.001348)
		(size 0.508)
		(drill 0.254)
		(layers "F.Cu" "B.Cu")
		(net "GND")
	)
	(via
		(at 150.012146 -412.570168)
		(size 0.4064)
		(drill 0.2032)
		(layers "F.Cu" "B.Cu")
		(net "GND")
	)
	(via
		(at 382.588262 -420.952168)
		(size 0.4064)
		(drill 0.2032)
		(layers "F.Cu" "B.Cu")
		(net "GND")
	)
	(via
		(at 255.927098 -200.528936)
		(size 0.508)
		(drill 0.254)
		(layers "F.Cu" "B.Cu")
		(net "GND")
	)
	(via
		(at 344.511122 -293.525956)
		(size 0.4064)
		(drill 0.2032)
		(layers "F.Cu" "B.Cu")
		(net "GND")
	)
	(via
		(at 459.081632 -390.962642)
		(size 0.508)
		(drill 0.254)
		(layers "F.Cu" "B.Cu")
		(net "GND")
	)
	(via
		(at 230.275638 -147.24253)
		(size 0.508)
		(drill 0.254)
		(layers "F.Cu" "B.Cu")
		(net "GND")
	)
	(via
		(at 340.24951 -430.299622)
		(size 0.4572)
		(drill 0.2032)
		(layers "F.Cu" "B.Cu")
		(net "GND")
	)
	(via
		(at 97.211134 -240.434368)
		(size 0.4064)
		(drill 0.2032)
		(layers "F.Cu" "B.Cu")
		(net "GND")
	)
	(via
		(at 388.562342 -392.999722)
		(size 0.4064)
		(drill 0.2032)
		(layers "F.Cu" "B.Cu")
		(net "GND")
	)
	(via
		(at 168.186862 -438.840372)
		(size 0.508)
		(drill 0.254)
		(layers "F.Cu" "B.Cu")
		(net "GND")
	)
	(via
		(at 336.521044 -271.656048)
		(size 0.4064)
		(drill 0.2032)
		(layers "F.Cu" "B.Cu")
		(net "GND")
	)
	(via
		(at 90.209116 -407.638504)
		(size 0.4572)
		(drill 0.254)
		(layers "F.Cu" "B.Cu")
		(net "GND")
	)
	(via
		(at 190.60541 -350.17075)
		(size 0.49022)
		(drill 0.254)
		(layers "F.Cu" "B.Cu")
		(net "GND")
	)
	(via
		(at 28.134564 -238.560356)
		(size 0.4826)
		(drill 0.254)
		(layers "F.Cu" "B.Cu")
		(net "GND")
	)
	(via
		(at 108.757466 -179.321968)
		(size 0.49022)
		(drill 0.254)
		(layers "F.Cu" "B.Cu")
		(net "GND")
	)
	(via
		(at 70.909434 -184.146952)
		(size 0.508)
		(drill 0.254)
		(layers "F.Cu" "B.Cu")
		(net "GND")
	)
	(via
		(at 211.10321 -29.266642)
		(size 0.508)
		(drill 0.254)
		(layers "F.Cu" "B.Cu")
		(net "GND")
	)
	(via
		(at 415.083752 -286.585152)
		(size 0.4826)
		(drill 0.254)
		(layers "F.Cu" "B.Cu")
		(net "GND")
	)
	(via
		(at 373.75973 -420.318184)
		(size 0.4572)
		(drill 0.254)
		(layers "F.Cu" "B.Cu")
		(net "GND")
	)
	(via
		(at 130.516376 -391.830814)
		(size 0.4064)
		(drill 0.2032)
		(layers "F.Cu" "B.Cu")
		(net "GND")
	)
	(via
		(at 454.188068 -235.585)
		(size 0.4826)
		(drill 0.254)
		(layers "F.Cu" "B.Cu")
		(net "GND")
	)
	(via
		(at 121.474738 -268.416278)
		(size 0.4064)
		(drill 0.2032)
		(layers "F.Cu" "B.Cu")
		(net "GND")
	)
	(via
		(at 383.21488 -246.104156)
		(size 0.4064)
		(drill 0.2032)
		(layers "F.Cu" "B.Cu")
		(net "GND")
	)
	(via
		(at 94.803976 -413.204152)
		(size 0.4572)
		(drill 0.254)
		(layers "F.Cu" "B.Cu")
		(net "GND")
	)
	(via
		(at 66.038984 -7.20471)
		(size 0.508)
		(drill 0.254)
		(layers "F.Cu" "B.Cu")
		(net "GND")
	)
	(via
		(at 73.109328 -171.2341)
		(size 0.508)
		(drill 0.254)
		(layers "F.Cu" "B.Cu")
		(net "GND")
	)
	(via
		(at 55.328058 -199.035416)
		(size 0.4826)
		(drill 0.254)
		(layers "F.Cu" "B.Cu")
		(net "GND")
	)
	(via
		(at 180.957982 -350.14535)
		(size 0.49022)
		(drill 0.254)
		(layers "F.Cu" "B.Cu")
		(net "GND")
	)
	(via
		(at 271.974564 -304.860198)
		(size 0.4826)
		(drill 0.254)
		(layers "F.Cu" "B.Cu")
		(net "GND")
	)
	(via
		(at 442.5442 -290.83508)
		(size 0.4826)
		(drill 0.254)
		(layers "F.Cu" "B.Cu")
		(net "GND")
	)
	(via
		(at 345.565984 -333.859124)
		(size 0.49022)
		(drill 0.254)
		(layers "F.Cu" "B.Cu")
		(net "GND")
	)
	(via
		(at 441.230004 -355.914452)
		(size 0.508)
		(drill 0.254)
		(layers "F.Cu" "B.Cu")
		(net "GND")
	)
	(via
		(at 401.009104 -18.247106)
		(size 0.508)
		(drill 0.254)
		(layers "F.Cu" "B.Cu")
		(net "GND")
	)
	(via
		(at 138.390376 -111.684054)
		(size 0.508)
		(drill 0.254)
		(layers "F.Cu" "B.Cu")
		(net "GND")
	)
	(via
		(at 450.088 -289.135058)
		(size 0.4826)
		(drill 0.254)
		(layers "F.Cu" "B.Cu")
		(net "GND")
	)
	(via
		(at 65.975992 -403.830536)
		(size 0.4572)
		(drill 0.254)
		(layers "F.Cu" "B.Cu")
		(net "GND")
	)
	(via
		(at 367.16589 -392.1252)
		(size 0.508)
		(drill 0.254)
		(layers "F.Cu" "B.Cu")
		(net "GND")
	)
	(via
		(at 112.09528 -75.73518)
		(size 0.508)
		(drill 0.254)
		(layers "F.Cu" "B.Cu")
		(net "GND")
	)
	(via
		(at 437.877966 -420.231824)
		(size 0.508)
		(drill 0.254)
		(layers "F.Cu" "B.Cu")
		(net "GND")
	)
	(via
		(at 413.2961 -379.22073)
		(size 0.508)
		(drill 0.254)
		(layers "F.Cu" "B.Cu")
		(net "GND")
	)
	(via
		(at 152.218136 -8.347964)
		(size 0.508)
		(drill 0.254)
		(layers "F.Cu" "B.Cu")
		(net "GND")
	)
	(via
		(at 344.211148 -230.714296)
		(size 0.4064)
		(drill 0.2032)
		(layers "F.Cu" "B.Cu")
		(net "GND")
	)
	(via
		(at 90.567764 -410.030168)
		(size 0.4064)
		(drill 0.2032)
		(layers "F.Cu" "B.Cu")
		(net "GND")
	)
	(via
		(at 343.101168 -268.416024)
		(size 0.4064)
		(drill 0.2032)
		(layers "F.Cu" "B.Cu")
		(net "GND")
	)
	(via
		(at 88.281002 -254.20447)
		(size 0.4064)
		(drill 0.2032)
		(layers "F.Cu" "B.Cu")
		(net "GND")
	)
	(via
		(at 439.100214 -215.18499)
		(size 0.4826)
		(drill 0.254)
		(layers "F.Cu" "B.Cu")
		(net "GND")
	)
	(via
		(at 231.11206 -241.355118)
		(size 0.4826)
		(drill 0.254)
		(layers "F.Cu" "B.Cu")
		(net "GND")
	)
	(via
		(at 146.43354 -31.958026)
		(size 0.508)
		(drill 0.254)
		(layers "F.Cu" "B.Cu")
		(net "GND")
	)
	(via
		(at 229.888796 -318.052958)
		(size 0.508)
		(drill 0.254)
		(layers "F.Cu" "B.Cu")
		(net "GND")
	)
	(via
		(at 164.427916 -318.885316)
		(size 0.4826)
		(drill 0.254)
		(layers "F.Cu" "B.Cu")
		(net "GND")
	)
	(via
		(at 112.79886 -29.465778)
		(size 0.508)
		(drill 0.254)
		(layers "F.Cu" "B.Cu")
		(net "GND")
	)
	(via
		(at 58.043826 -314.635388)
		(size 0.4826)
		(drill 0.254)
		(layers "F.Cu" "B.Cu")
		(net "GND")
	)
	(via
		(at 147.042886 -284.35046)
		(size 0.4064)
		(drill 0.2032)
		(layers "F.Cu" "B.Cu")
		(net "GND")
	)
	(via
		(at 201.68362 -332.805786)
		(size 0.508)
		(drill 0.254)
		(layers "F.Cu" "B.Cu")
		(net "GND")
	)
	(via
		(at 134.349744 -429.147224)
		(size 0.4572)
		(drill 0.2032)
		(layers "F.Cu" "B.Cu")
		(net "GND")
	)
	(via
		(at 378.04471 -224.234248)
		(size 0.4064)
		(drill 0.2032)
		(layers "F.Cu" "B.Cu")
		(net "GND")
	)
	(via
		(at 138.564874 -224.234502)
		(size 0.4064)
		(drill 0.2032)
		(layers "F.Cu" "B.Cu")
		(net "GND")
	)
	(via
		(at 104.731058 -242.05438)
		(size 0.4064)
		(drill 0.2032)
		(layers "F.Cu" "B.Cu")
		(net "GND")
	)
	(via
		(at 92.981018 -246.10441)
		(size 0.4064)
		(drill 0.2032)
		(layers "F.Cu" "B.Cu")
		(net "GND")
	)
	(via
		(at 123.994672 -242.864386)
		(size 0.4064)
		(drill 0.2032)
		(layers "F.Cu" "B.Cu")
		(net "GND")
	)
	(via
		(at 393.384786 -272.466054)
		(size 0.4064)
		(drill 0.2032)
		(layers "F.Cu" "B.Cu")
		(net "GND")
	)
	(via
		(at 361.124754 -250.154186)
		(size 0.4064)
		(drill 0.2032)
		(layers "F.Cu" "B.Cu")
		(net "GND")
	)
	(via
		(at 191.160146 -248.335292)
		(size 0.4826)
		(drill 0.254)
		(layers "F.Cu" "B.Cu")
		(net "GND")
	)
	(via
		(at 140.444728 -225.854514)
		(size 0.4064)
		(drill 0.2032)
		(layers "F.Cu" "B.Cu")
		(net "GND")
	)
	(via
		(at 416.218878 -398.542002)
		(size 0.4064)
		(drill 0.2032)
		(layers "F.Cu" "B.Cu")
		(net "GND")
	)
	(via
		(at 233.64952 -292.803326)
		(size 0.508)
		(drill 0.254)
		(layers "F.Cu" "B.Cu")
		(net "GND")
	)
	(via
		(at 108.02112 -229.90429)
		(size 0.4064)
		(drill 0.2032)
		(layers "F.Cu" "B.Cu")
		(net "GND")
	)
	(via
		(at 329.941174 -273.27606)
		(size 0.4064)
		(drill 0.2032)
		(layers "F.Cu" "B.Cu")
		(net "GND")
	)
	(via
		(at 330.880974 -268.416024)
		(size 0.4064)
		(drill 0.2032)
		(layers "F.Cu" "B.Cu")
		(net "GND")
	)
	(via
		(at 111.153956 -372.15953)
		(size 0.508)
		(drill 0.254)
		(layers "F.Cu" "B.Cu")
		(net "GND")
	)
	(via
		(at 17.608042 -281.48534)
		(size 0.4826)
		(drill 0.254)
		(layers "F.Cu" "B.Cu")
		(net "GND")
	)
	(via
		(at 161.903918 -413.204152)
		(size 0.4572)
		(drill 0.254)
		(layers "F.Cu" "B.Cu")
		(net "GND")
	)
	(via
		(at 72.3392 -387.7945)
		(size 0.508)
		(drill 0.254)
		(layers "F.Cu" "B.Cu")
		(net "GND")
	)
	(via
		(at 45.658278 -9.424924)
		(size 0.508)
		(drill 0.254)
		(layers "F.Cu" "B.Cu")
		(net "GND")
	)
	(via
		(at 334.811116 -253.39421)
		(size 0.4064)
		(drill 0.2032)
		(layers "F.Cu" "B.Cu")
		(net "GND")
	)
	(via
		(at 99.391216 -287.04667)
		(size 0.4064)
		(drill 0.2032)
		(layers "F.Cu" "B.Cu")
		(net "GND")
	)
	(via
		(at 318.639698 -419.046152)
		(size 0.4572)
		(drill 0.254)
		(layers "F.Cu" "B.Cu")
		(net "GND")
	)
	(via
		(at 128.994662 -287.856422)
		(size 0.4064)
		(drill 0.2032)
		(layers "F.Cu" "B.Cu")
		(net "GND")
	)
	(via
		(at 376.634756 -244.484144)
		(size 0.4064)
		(drill 0.2032)
		(layers "F.Cu" "B.Cu")
		(net "GND")
	)
	(via
		(at 187.071 -135.600948)
		(size 0.508)
		(drill 0.254)
		(layers "F.Cu" "B.Cu")
		(net "GND")
	)
	(via
		(at 146.084798 -224.234502)
		(size 0.4064)
		(drill 0.2032)
		(layers "F.Cu" "B.Cu")
		(net "GND")
	)
	(via
		(at 188.444378 -203.285344)
		(size 0.4826)
		(drill 0.254)
		(layers "F.Cu" "B.Cu")
		(net "GND")
	)
	(via
		(at 351.354136 -359.657142)
		(size 0.508)
		(drill 0.254)
		(layers "F.Cu" "B.Cu")
		(net "GND")
	)
	(via
		(at 398.351502 -418.412168)
		(size 0.4064)
		(drill 0.2032)
		(layers "F.Cu" "B.Cu")
		(net "GND")
	)
	(via
		(at 167.496744 -430.453038)
		(size 0.508)
		(drill 0.254)
		(layers "F.Cu" "B.Cu")
		(net "GND")
	)
	(via
		(at 288.180018 -272.135092)
		(size 0.4826)
		(drill 0.254)
		(layers "F.Cu" "B.Cu")
		(net "GND")
	)
	(via
		(at 56.712358 -221.985332)
		(size 0.4826)
		(drill 0.254)
		(layers "F.Cu" "B.Cu")
		(net "GND")
	)
	(via
		(at 22.148292 -9.424924)
		(size 0.508)
		(drill 0.254)
		(layers "F.Cu" "B.Cu")
		(net "GND")
	)
	(via
		(at 309.816246 -391.23493)
		(size 0.4064)
		(drill 0.2032)
		(layers "F.Cu" "B.Cu")
		(net "GND")
	)
	(via
		(at 452.803768 -284.034992)
		(size 0.4826)
		(drill 0.254)
		(layers "F.Cu" "B.Cu")
		(net "GND")
	)
	(via
		(at 356.894384 -378.07773)
		(size 0.508)
		(drill 0.254)
		(layers "F.Cu" "B.Cu")
		(net "GND")
	)
	(via
		(at 109.261148 -268.416278)
		(size 0.4064)
		(drill 0.2032)
		(layers "F.Cu" "B.Cu")
		(net "GND")
	)
	(via
		(at 108.94949 -177.605944)
		(size 0.49022)
		(drill 0.254)
		(layers "F.Cu" "B.Cu")
		(net "GND")
	)
	(via
		(at 51.753516 -153.231596)
		(size 0.508)
		(drill 0.254)
		(layers "F.Cu" "B.Cu")
		(net "GND")
	)
	(via
		(at 78.24978 -427.699678)
		(size 0.4572)
		(drill 0.2032)
		(layers "F.Cu" "B.Cu")
		(net "GND")
	)
	(via
		(at 70.428358 -334.601058)
		(size 0.49022)
		(drill 0.254)
		(layers "F.Cu" "B.Cu")
		(net "GND")
	)
	(via
		(at 115.666266 -173.862746)
		(size 0.49022)
		(drill 0.254)
		(layers "F.Cu" "B.Cu")
		(net "GND")
	)
	(via
		(at 44.85894 -112.11052)
		(size 0.508)
		(drill 0.254)
		(layers "F.Cu" "B.Cu")
		(net "GND")
	)
	(via
		(at 178.852576 -31.140908)
		(size 0.508)
		(drill 0.254)
		(layers "F.Cu" "B.Cu")
		(net "GND")
	)
	(via
		(at 93.280992 -281.376374)
		(size 0.4064)
		(drill 0.2032)
		(layers "F.Cu" "B.Cu")
		(net "GND")
	)
	(via
		(at 87.82304 -355.968046)
		(size 0.508)
		(drill 0.254)
		(layers "F.Cu" "B.Cu")
		(net "GND")
	)
	(via
		(at 100.031042 -255.014476)
		(size 0.4064)
		(drill 0.2032)
		(layers "F.Cu" "B.Cu")
		(net "GND")
	)
	(via
		(at 43.871134 -361.993434)
		(size 0.508)
		(drill 0.254)
		(layers "F.Cu" "B.Cu")
		(net "GND")
	)
	(via
		(at 376.908822 -415.38652)
		(size 0.4064)
		(drill 0.2032)
		(layers "F.Cu" "B.Cu")
		(net "GND")
	)
	(via
		(at 93.280992 -274.896326)
		(size 0.4064)
		(drill 0.2032)
		(layers "F.Cu" "B.Cu")
		(net "GND")
	)
	(via
		(at 338.401152 -261.935976)
		(size 0.4064)
		(drill 0.2032)
		(layers "F.Cu" "B.Cu")
		(net "GND")
	)
	(via
		(at 24.034496 -286.160464)
		(size 0.4826)
		(drill 0.254)
		(layers "F.Cu" "B.Cu")
		(net "GND")
	)
	(via
		(at 353.61118 -232.334054)
		(size 0.4064)
		(drill 0.2032)
		(layers "F.Cu" "B.Cu")
		(net "GND")
	)
	(via
		(at 141.904466 -412.570168)
		(size 0.4064)
		(drill 0.2032)
		(layers "F.Cu" "B.Cu")
		(net "GND")
	)
	(via
		(at 447.761868 -229.210108)
		(size 0.4826)
		(drill 0.254)
		(layers "F.Cu" "B.Cu")
		(net "GND")
	)
	(via
		(at 82.001106 -279.756362)
		(size 0.4064)
		(drill 0.2032)
		(layers "F.Cu" "B.Cu")
		(net "GND")
	)
	(via
		(at 333.097124 -333.034386)
		(size 0.49022)
		(drill 0.254)
		(layers "F.Cu" "B.Cu")
		(net "GND")
	)
	(via
		(at 137.45464 -286.23641)
		(size 0.4064)
		(drill 0.2032)
		(layers "F.Cu" "B.Cu")
		(net "GND")
	)
	(via
		(at 82.551016 -411.936184)
		(size 0.4572)
		(drill 0.254)
		(layers "F.Cu" "B.Cu")
		(net "GND")
	)
	(via
		(at 90.461084 -265.176254)
		(size 0.4064)
		(drill 0.2032)
		(layers "F.Cu" "B.Cu")
		(net "GND")
	)
	(via
		(at 414.655 -96.901)
		(size 0.508)
		(drill 0.254)
		(layers "F.Cu" "B.Cu")
		(net "GND")
	)
	(via
		(at 383.21488 -241.24412)
		(size 0.4064)
		(drill 0.2032)
		(layers "F.Cu" "B.Cu")
		(net "GND")
	)
	(via
		(at 109.417866 -180.111146)
		(size 0.49022)
		(drill 0.254)
		(layers "F.Cu" "B.Cu")
		(net "GND")
	)
	(via
		(at 416.64509 -413.480504)
		(size 0.4572)
		(drill 0.254)
		(layers "F.Cu" "B.Cu")
		(net "GND")
	)
	(via
		(at 442.5442 -289.135058)
		(size 0.4826)
		(drill 0.254)
		(layers "F.Cu" "B.Cu")
		(net "GND")
	)
	(via
		(at 344.211148 -233.954066)
		(size 0.4064)
		(drill 0.2032)
		(layers "F.Cu" "B.Cu")
		(net "GND")
	)
	(via
		(at 59.428126 -263.635236)
		(size 0.4826)
		(drill 0.254)
		(layers "F.Cu" "B.Cu")
		(net "GND")
	)
	(via
		(at 300.38421 -346.317316)
		(size 0.49022)
		(drill 0.254)
		(layers "F.Cu" "B.Cu")
		(net "GND")
	)
	(via
		(at 265.54811 -255.135126)
		(size 0.4826)
		(drill 0.254)
		(layers "F.Cu" "B.Cu")
		(net "GND")
	)
	(via
		(at 131.578096 -369.03533)
		(size 0.508)
		(drill 0.254)
		(layers "F.Cu" "B.Cu")
		(net "GND")
	)
	(via
		(at 136.574022 -388.892542)
		(size 0.508)
		(drill 0.254)
		(layers "F.Cu" "B.Cu")
		(net "GND")
	)
	(via
		(at 251.347224 -279.503632)
		(size 0.508)
		(drill 0.254)
		(layers "F.Cu" "B.Cu")
		(net "GND")
	)
	(via
		(at 452.704454 -397.811244)
		(size 0.49022)
		(drill 0.254)
		(layers "F.Cu" "B.Cu")
		(net "GND")
	)
	(via
		(at 435.000146 -273.835114)
		(size 0.4826)
		(drill 0.254)
		(layers "F.Cu" "B.Cu")
		(net "GND")
	)
	(via
		(at 59.816492 -391.830814)
		(size 0.4064)
		(drill 0.2032)
		(layers "F.Cu" "B.Cu")
		(net "GND")
	)
	(via
		(at 364.122208 -258.795012)
		(size 0.4826)
		(drill 0.254)
		(layers "F.Cu" "B.Cu")
		(net "GND")
	)
	(via
		(at 191.160146 -232.18521)
		(size 0.4826)
		(drill 0.254)
		(layers "F.Cu" "B.Cu")
		(net "GND")
	)
	(via
		(at 124.464826 -233.95432)
		(size 0.4064)
		(drill 0.2032)
		(layers "F.Cu" "B.Cu")
		(net "GND")
	)
	(via
		(at 113.48466 -275.706332)
		(size 0.4064)
		(drill 0.2032)
		(layers "F.Cu" "B.Cu")
		(net "GND")
	)
	(via
		(at 83.88096 -270.03629)
		(size 0.4064)
		(drill 0.2032)
		(layers "F.Cu" "B.Cu")
		(net "GND")
	)
	(via
		(at 355.491034 -251.774198)
		(size 0.4064)
		(drill 0.2032)
		(layers "F.Cu" "B.Cu")
		(net "GND")
	)
	(via
		(at 339.811106 -274.086066)
		(size 0.4064)
		(drill 0.2032)
		(layers "F.Cu" "B.Cu")
		(net "GND")
	)
	(via
		(at 346.091002 -255.014222)
		(size 0.4064)
		(drill 0.2032)
		(layers "F.Cu" "B.Cu")
		(net "GND")
	)
	(via
		(at 158.840678 -413.204152)
		(size 0.4572)
		(drill 0.254)
		(layers "F.Cu" "B.Cu")
		(net "GND")
	)
	(via
		(at 378.35459 -416.020504)
		(size 0.4572)
		(drill 0.254)
		(layers "F.Cu" "B.Cu")
		(net "GND")
	)
	(via
		(at 425.678854 -349.908876)
		(size 0.49022)
		(drill 0.254)
		(layers "F.Cu" "B.Cu")
		(net "GND")
	)
	(via
		(at 80.591152 -278.946356)
		(size 0.4064)
		(drill 0.2032)
		(layers "F.Cu" "B.Cu")
		(net "GND")
	)
	(via
		(at 140.349732 -430.147222)
		(size 0.4572)
		(drill 0.2032)
		(layers "F.Cu" "B.Cu")
		(net "GND")
	)
	(via
		(at 338.249514 -436.051198)
		(size 0.4572)
		(drill 0.2032)
		(layers "F.Cu" "B.Cu")
		(net "GND")
	)
	(via
		(at 58.043826 -227.935282)
		(size 0.4826)
		(drill 0.254)
		(layers "F.Cu" "B.Cu")
		(net "GND")
	)
	(via
		(at 193.55562 -423.820082)
		(size 0.508)
		(drill 0.254)
		(layers "F.Cu" "B.Cu")
		(net "GND")
	)
	(via
		(at 347.031056 -227.474272)
		(size 0.4064)
		(drill 0.2032)
		(layers "F.Cu" "B.Cu")
		(net "GND")
	)
	(via
		(at 64.616584 -382.85293)
		(size 0.4064)
		(drill 0.2032)
		(layers "F.Cu" "B.Cu")
		(net "GND")
	)
	(via
		(at 68.678044 -404.46452)
		(size 0.4064)
		(drill 0.2032)
		(layers "F.Cu" "B.Cu")
		(net "GND")
	)
	(via
		(at 335.760314 -416.020504)
		(size 0.4572)
		(drill 0.254)
		(layers "F.Cu" "B.Cu")
		(net "GND")
	)
	(via
		(at 133.694678 -270.03629)
		(size 0.4064)
		(drill 0.2032)
		(layers "F.Cu" "B.Cu")
		(net "GND")
	)
	(via
		(at 453.518778 -395.306042)
		(size 0.49022)
		(drill 0.254)
		(layers "F.Cu" "B.Cu")
		(net "GND")
	)
	(via
		(at 439.512456 -45.107352)
		(size 0.508)
		(drill 0.254)
		(layers "F.Cu" "B.Cu")
		(net "GND")
	)
	(via
		(at 331.051154 -233.954066)
		(size 0.4064)
		(drill 0.2032)
		(layers "F.Cu" "B.Cu")
		(net "GND")
	)
	(via
		(at 331.051154 -246.914162)
		(size 0.4064)
		(drill 0.2032)
		(layers "F.Cu" "B.Cu")
		(net "GND")
	)
	(via
		(at 41.62425 -278.085296)
		(size 0.4826)
		(drill 0.254)
		(layers "F.Cu" "B.Cu")
		(net "GND")
	)
	(via
		(at 144.169384 -368.37493)
		(size 0.508)
		(drill 0.254)
		(layers "F.Cu" "B.Cu")
		(net "GND")
	)
	(via
		(at 446.016126 -63.125096)
		(size 0.508)
		(drill 0.254)
		(layers "F.Cu" "B.Cu")
		(net "GND")
	)
	(via
		(at 383.514854 -268.416024)
		(size 0.4064)
		(drill 0.2032)
		(layers "F.Cu" "B.Cu")
		(net "GND")
	)
	(via
		(at 422.621964 -19.137122)
		(size 0.508)
		(drill 0.254)
		(layers "F.Cu" "B.Cu")
		(net "GND")
	)
	(via
		(at 165.677596 -414.112964)
		(size 0.508)
		(drill 0.254)
		(layers "F.Cu" "B.Cu")
		(net "GND")
	)
	(via
		(at 78.75651 -185.988198)
		(size 0.508)
		(drill 0.254)
		(layers "F.Cu" "B.Cu")
		(net "GND")
	)
	(via
		(at 392.627104 -18.5039)
		(size 0.508)
		(drill 0.254)
		(layers "F.Cu" "B.Cu")
		(net "GND")
	)
	(via
		(at 350.791018 -240.434114)
		(size 0.4064)
		(drill 0.2032)
		(layers "F.Cu" "B.Cu")
		(net "GND")
	)
	(via
		(at 414.499806 -132.45592)
		(size 0.508)
		(drill 0.254)
		(layers "F.Cu" "B.Cu")
		(net "GND")
	)
	(via
		(at 120.064784 -274.08632)
		(size 0.4064)
		(drill 0.2032)
		(layers "F.Cu" "B.Cu")
		(net "GND")
	)
	(via
		(at 344.681048 -233.14406)
		(size 0.4064)
		(drill 0.2032)
		(layers "F.Cu" "B.Cu")
		(net "GND")
	)
	(via
		(at 171.97197 -247.485408)
		(size 0.4826)
		(drill 0.254)
		(layers "F.Cu" "B.Cu")
		(net "GND")
	)
	(via
		(at 385.864862 -269.22603)
		(size 0.4064)
		(drill 0.2032)
		(layers "F.Cu" "B.Cu")
		(net "GND")
	)
	(via
		(at 61.108336 -413.204152)
		(size 0.4572)
		(drill 0.254)
		(layers "F.Cu" "B.Cu")
		(net "GND")
	)
	(via
		(at 401.349718 -434.899562)
		(size 0.4572)
		(drill 0.2032)
		(layers "F.Cu" "B.Cu")
		(net "GND")
	)
	(via
		(at 28.134564 -229.210362)
		(size 0.4826)
		(drill 0.254)
		(layers "F.Cu" "B.Cu")
		(net "GND")
	)
	(via
		(at 328.061066 -266.796012)
		(size 0.4064)
		(drill 0.2032)
		(layers "F.Cu" "B.Cu")
		(net "GND")
	)
	(via
		(at 104.257856 -255.82245)
		(size 0.4064)
		(drill 0.2032)
		(layers "F.Cu" "B.Cu")
		(net "GND")
	)
	(via
		(at 354.551234 -235.574078)
		(size 0.4064)
		(drill 0.2032)
		(layers "F.Cu" "B.Cu")
		(net "GND")
	)
	(via
		(at 299.82414 -233.884978)
		(size 0.4826)
		(drill 0.254)
		(layers "F.Cu" "B.Cu")
		(net "GND")
	)
	(via
		(at 402.86051 -417.778184)
		(size 0.4572)
		(drill 0.254)
		(layers "F.Cu" "B.Cu")
		(net "GND")
	)
	(via
		(at 346.249498 -428.851314)
		(size 0.4572)
		(drill 0.2032)
		(layers "F.Cu" "B.Cu")
		(net "GND")
	)
	(via
		(at 377.852432 -383.00533)
		(size 0.508)
		(drill 0.254)
		(layers "F.Cu" "B.Cu")
		(net "GND")
	)
	(via
		(at 349.851218 -237.19409)
		(size 0.4064)
		(drill 0.2032)
		(layers "F.Cu" "B.Cu")
		(net "GND")
	)
	(via
		(at 456.595734 -49.116742)
		(size 0.508)
		(drill 0.254)
		(layers "F.Cu" "B.Cu")
		(net "GND")
	)
	(via
		(at 339.811106 -288.66592)
		(size 0.4064)
		(drill 0.2032)
		(layers "F.Cu" "B.Cu")
		(net "GND")
	)
	(via
		(at 380.694946 -294.335962)
		(size 0.4064)
		(drill 0.2032)
		(layers "F.Cu" "B.Cu")
		(net "GND")
	)
	(via
		(at 435.000146 -289.135058)
		(size 0.4826)
		(drill 0.254)
		(layers "F.Cu" "B.Cu")
		(net "GND")
	)
	(via
		(at 388.68477 -285.42615)
		(size 0.4064)
		(drill 0.2032)
		(layers "F.Cu" "B.Cu")
		(net "GND")
	)
	(via
		(at 187.111894 -112.66297)
		(size 0.4572)
		(drill 0.254)
		(layers "F.Cu" "B.Cu")
		(net "GND")
	)
	(via
		(at 83.41106 -295.146222)
		(size 0.4064)
		(drill 0.2032)
		(layers "F.Cu" "B.Cu")
		(net "GND")
	)
	(via
		(at 274.78101 -344.77706)
		(size 0.49022)
		(drill 0.254)
		(layers "F.Cu" "B.Cu")
		(net "GND")
	)
	(via
		(at 361.424728 -295.145968)
		(size 0.4064)
		(drill 0.2032)
		(layers "F.Cu" "B.Cu")
		(net "GND")
	)
	(via
		(at 50.499772 -293.38524)
		(size 0.4826)
		(drill 0.254)
		(layers "F.Cu" "B.Cu")
		(net "GND")
	)
	(via
		(at 350.803718 -413.480504)
		(size 0.4572)
		(drill 0.254)
		(layers "F.Cu" "B.Cu")
		(net "GND")
	)
	(via
		(at 437.962802 -427.09211)
		(size 0.508)
		(drill 0.254)
		(layers "F.Cu" "B.Cu")
		(net "GND")
	)
	(via
		(at 165.545516 -295.510458)
		(size 0.4826)
		(drill 0.254)
		(layers "F.Cu" "B.Cu")
		(net "GND")
	)
	(via
		(at 87.171022 -291.906198)
		(size 0.4064)
		(drill 0.2032)
		(layers "F.Cu" "B.Cu")
		(net "GND")
	)
	(via
		(at 130.40487 -261.126224)
		(size 0.4064)
		(drill 0.2032)
		(layers "F.Cu" "B.Cu")
		(net "GND")
	)
	(via
		(at 184.733692 -210.510374)
		(size 0.4826)
		(drill 0.254)
		(layers "F.Cu" "B.Cu")
		(net "GND")
	)
	(via
		(at 96.74098 -234.764326)
		(size 0.4064)
		(drill 0.2032)
		(layers "F.Cu" "B.Cu")
		(net "GND")
	)
	(via
		(at 379.316488 -391.23493)
		(size 0.4064)
		(drill 0.2032)
		(layers "F.Cu" "B.Cu")
		(net "GND")
	)
	(via
		(at 450.088 -317.18504)
		(size 0.4826)
		(drill 0.254)
		(layers "F.Cu" "B.Cu")
		(net "GND")
	)
	(via
		(at 86.249764 -438.499758)
		(size 0.4572)
		(drill 0.2032)
		(layers "F.Cu" "B.Cu")
		(net "GND")
	)
	(via
		(at 344.981022 -286.236156)
		(size 0.4064)
		(drill 0.2032)
		(layers "F.Cu" "B.Cu")
		(net "GND")
	)
	(via
		(at 133.91769 -154.542744)
		(size 0.49022)
		(drill 0.254)
		(layers "F.Cu" "B.Cu")
		(net "GND")
	)
	(via
		(at 85.614256 -403.830536)
		(size 0.4572)
		(drill 0.254)
		(layers "F.Cu" "B.Cu")
		(net "GND")
	)
	(via
		(at 147.572984 -373.30253)
		(size 0.508)
		(drill 0.254)
		(layers "F.Cu" "B.Cu")
		(net "GND")
	)
	(via
		(at 229.798626 -234.135168)
		(size 0.4826)
		(drill 0.254)
		(layers "F.Cu" "B.Cu")
		(net "GND")
	)
	(via
		(at 173.12767 -194.885564)
		(size 0.4826)
		(drill 0.254)
		(layers "F.Cu" "B.Cu")
		(net "GND")
	)
	(via
		(at 51.705002 -6.598158)
		(size 0.508)
		(drill 0.254)
		(layers "F.Cu" "B.Cu")
		(net "GND")
	)
	(via
		(at 268.530578 -304.01006)
		(size 0.4826)
		(drill 0.254)
		(layers "F.Cu" "B.Cu")
		(net "GND")
	)
	(via
		(at 131.575556 -370.83873)
		(size 0.508)
		(drill 0.254)
		(layers "F.Cu" "B.Cu")
		(net "GND")
	)
	(via
		(at 180.900324 -240.68532)
		(size 0.4826)
		(drill 0.254)
		(layers "F.Cu" "B.Cu")
		(net "GND")
	)
	(via
		(at 336.521044 -270.036036)
		(size 0.4064)
		(drill 0.2032)
		(layers "F.Cu" "B.Cu")
		(net "GND")
	)
	(via
		(at 467.5378 -289.611054)
		(size 0.508)
		(drill 0.254)
		(layers "F.Cu" "B.Cu")
		(net "GND")
	)
	(via
		(at 16.25346 -397.440658)
		(size 0.508)
		(drill 0.254)
		(layers "F.Cu" "B.Cu")
		(net "GND")
	)
	(via
		(at 320.171318 -413.480504)
		(size 0.4572)
		(drill 0.254)
		(layers "F.Cu" "B.Cu")
		(net "GND")
	)
	(via
		(at 77.112876 -276.2504)
		(size 0.4064)
		(drill 0.2032)
		(layers "F.Cu" "B.Cu")
		(net "GND")
	)
	(via
		(at 319.249552 -438.651396)
		(size 0.4572)
		(drill 0.2032)
		(layers "F.Cu" "B.Cu")
		(net "GND")
	)
	(via
		(at 357.841042 -244.484144)
		(size 0.4064)
		(drill 0.2032)
		(layers "F.Cu" "B.Cu")
		(net "GND")
	)
	(via
		(at 170.905424 -377.617228)
		(size 0.508)
		(drill 0.254)
		(layers "F.Cu" "B.Cu")
		(net "GND")
	)
	(via
		(at 96.27108 -224.234502)
		(size 0.4064)
		(drill 0.2032)
		(layers "F.Cu" "B.Cu")
		(net "GND")
	)
	(via
		(at 117.475 -432.054)
		(size 0.508)
		(drill 0.254)
		(layers "F.Cu" "B.Cu")
		(net "GND")
	)
	(via
		(at 136.98474 -262.746236)
		(size 0.4064)
		(drill 0.2032)
		(layers "F.Cu" "B.Cu")
		(net "GND")
	)
	(via
		(at 368.944906 -285.42615)
		(size 0.4064)
		(drill 0.2032)
		(layers "F.Cu" "B.Cu")
		(net "GND")
	)
	(via
		(at 132.349748 -434.899562)
		(size 0.4572)
		(drill 0.2032)
		(layers "F.Cu" "B.Cu")
		(net "GND")
	)
	(via
		(at 352.671126 -246.914162)
		(size 0.4064)
		(drill 0.2032)
		(layers "F.Cu" "B.Cu")
		(net "GND")
	)
	(via
		(at 363.774736 -266.796012)
		(size 0.4064)
		(drill 0.2032)
		(layers "F.Cu" "B.Cu")
		(net "GND")
	)
	(via
		(at 338.249514 -434.899562)
		(size 0.4572)
		(drill 0.2032)
		(layers "F.Cu" "B.Cu")
		(net "GND")
	)
	(via
		(at 350.597724 -168.863264)
		(size 0.508)
		(drill 0.254)
		(layers "F.Cu" "B.Cu")
		(net "GND")
	)
	(via
		(at 355.40696 -333.24292)
		(size 0.508)
		(drill 0.254)
		(layers "F.Cu" "B.Cu")
		(net "GND")
	)
	(via
		(at 412.367984 -223.6851)
		(size 0.4826)
		(drill 0.254)
		(layers "F.Cu" "B.Cu")
		(net "GND")
	)
	(via
		(at 135.574786 -286.23641)
		(size 0.4064)
		(drill 0.2032)
		(layers "F.Cu" "B.Cu")
		(net "GND")
	)
	(via
		(at 352.9711 -288.66592)
		(size 0.4064)
		(drill 0.2032)
		(layers "F.Cu" "B.Cu")
		(net "GND")
	)
	(via
		(at 376.93473 -291.095938)
		(size 0.4064)
		(drill 0.2032)
		(layers "F.Cu" "B.Cu")
		(net "GND")
	)
	(via
		(at 56.425084 -412.570168)
		(size 0.4064)
		(drill 0.2032)
		(layers "F.Cu" "B.Cu")
		(net "GND")
	)
	(via
		(at 155.596844 -371.49913)
		(size 0.508)
		(drill 0.254)
		(layers "F.Cu" "B.Cu")
		(net "GND")
	)
	(via
		(at 294.606472 -202.01001)
		(size 0.4826)
		(drill 0.254)
		(layers "F.Cu" "B.Cu")
		(net "GND")
	)
	(via
		(at 288.180018 -233.035094)
		(size 0.4826)
		(drill 0.254)
		(layers "F.Cu" "B.Cu")
		(net "GND")
	)
	(via
		(at 116.94795 -253.392432)
		(size 0.4064)
		(drill 0.2032)
		(layers "F.Cu" "B.Cu")
		(net "GND")
	)
	(via
		(at 355.321108 -337.350608)
		(size 0.508)
		(drill 0.254)
		(layers "F.Cu" "B.Cu")
		(net "GND")
	)
	(via
		(at 390.60755 -414.72866)
		(size 0.4572)
		(drill 0.254)
		(layers "F.Cu" "B.Cu")
		(net "GND")
	)
	(via
		(at 103.185722 -25.419304)
		(size 0.508)
		(drill 0.254)
		(layers "F.Cu" "B.Cu")
		(net "GND")
	)
	(via
		(at 115.469162 -336.304382)
		(size 0.508)
		(drill 0.254)
		(layers "F.Cu" "B.Cu")
		(net "GND")
	)
	(via
		(at 333.4258 -401.217384)
		(size 0.508)
		(drill 0.254)
		(layers "F.Cu" "B.Cu")
		(net "GND")
	)
	(via
		(at 176.072038 -255.13538)
		(size 0.4826)
		(drill 0.254)
		(layers "F.Cu" "B.Cu")
		(net "GND")
	)
	(via
		(at 52.049934 -348.709488)
		(size 0.49022)
		(drill 0.254)
		(layers "F.Cu" "B.Cu")
		(net "GND")
	)
	(via
		(at 412.05023 -416.020504)
		(size 0.4572)
		(drill 0.254)
		(layers "F.Cu" "B.Cu")
		(net "GND")
	)
	(via
		(at 315.24956 -425.547282)
		(size 0.4572)
		(drill 0.2032)
		(layers "F.Cu" "B.Cu")
		(net "GND")
	)
	(via
		(at 113.582196 -258.795266)
		(size 0.4826)
		(drill 0.254)
		(layers "F.Cu" "B.Cu")
		(net "GND")
	)
	(via
		(at 375.202958 -204.085952)
		(size 0.508)
		(drill 0.254)
		(layers "F.Cu" "B.Cu")
		(net "GND")
	)
	(via
		(at 122.884692 -277.326344)
		(size 0.4064)
		(drill 0.2032)
		(layers "F.Cu" "B.Cu")
		(net "GND")
	)
	(via
		(at 453.032368 -192.21831)
		(size 0.4826)
		(drill 0.254)
		(layers "F.Cu" "B.Cu")
		(net "GND")
	)
	(via
		(at 198.7042 -263.635236)
		(size 0.4826)
		(drill 0.254)
		(layers "F.Cu" "B.Cu")
		(net "GND")
	)
	(via
		(at 78.711044 -264.366248)
		(size 0.4064)
		(drill 0.2032)
		(layers "F.Cu" "B.Cu")
		(net "GND")
	)
	(via
		(at 95.1611 -278.13635)
		(size 0.4064)
		(drill 0.2032)
		(layers "F.Cu" "B.Cu")
		(net "GND")
	)
	(via
		(at 388.68477 -274.086066)
		(size 0.4064)
		(drill 0.2032)
		(layers "F.Cu" "B.Cu")
		(net "GND")
	)
	(via
		(at 454.188068 -215.18499)
		(size 0.4826)
		(drill 0.254)
		(layers "F.Cu" "B.Cu")
		(net "GND")
	)
	(via
		(at 32.668718 -396.499588)
		(size 0.508)
		(drill 0.254)
		(layers "F.Cu" "B.Cu")
		(net "GND")
	)
	(via
		(at 33.492694 -168.899332)
		(size 0.508)
		(drill 0.254)
		(layers "F.Cu" "B.Cu")
		(net "GND")
	)
	(via
		(at 318.912494 -421.586152)
		(size 0.4572)
		(drill 0.254)
		(layers "F.Cu" "B.Cu")
		(net "GND")
	)
	(via
		(at 361.894882 -270.036036)
		(size 0.4064)
		(drill 0.2032)
		(layers "F.Cu" "B.Cu")
		(net "GND")
	)
	(via
		(at 26.536396 -312.935366)
		(size 0.4826)
		(drill 0.254)
		(layers "F.Cu" "B.Cu")
		(net "GND")
	)
	(via
		(at 365.654844 -268.416024)
		(size 0.4064)
		(drill 0.2032)
		(layers "F.Cu" "B.Cu")
		(net "GND")
	)
	(via
		(at 395.063218 -317.011812)
		(size 0.508)
		(drill 0.254)
		(layers "F.Cu" "B.Cu")
		(net "GND")
	)
	(via
		(at 271.974564 -211.360004)
		(size 0.4826)
		(drill 0.254)
		(layers "F.Cu" "B.Cu")
		(net "GND")
	)
	(via
		(at 375.456958 -207.521302)
		(size 0.508)
		(drill 0.254)
		(layers "F.Cu" "B.Cu")
		(net "GND")
	)
	(via
		(at 349.851218 -246.914162)
		(size 0.4064)
		(drill 0.2032)
		(layers "F.Cu" "B.Cu")
		(net "GND")
	)
	(via
		(at 344.74404 -402.284438)
		(size 0.4572)
		(drill 0.254)
		(layers "F.Cu" "B.Cu")
		(net "GND")
	)
	(via
		(at 304.652426 -221.985078)
		(size 0.4826)
		(drill 0.254)
		(layers "F.Cu" "B.Cu")
		(net "GND")
	)
	(via
		(at 36.049712 -0.762254)
		(size 0.508)
		(drill 0.254)
		(layers "F.Cu" "B.Cu")
		(net "GND")
	)
	(via
		(at 346.481654 -413.480504)
		(size 0.4572)
		(drill 0.254)
		(layers "F.Cu" "B.Cu")
		(net "GND")
	)
	(via
		(at 384.659632 -383.00533)
		(size 0.508)
		(drill 0.254)
		(layers "F.Cu" "B.Cu")
		(net "GND")
	)
	(via
		(at 299.82414 -216.885012)
		(size 0.4826)
		(drill 0.254)
		(layers "F.Cu" "B.Cu")
		(net "GND")
	)
	(via
		(at 288.180018 -307.835046)
		(size 0.4826)
		(drill 0.254)
		(layers "F.Cu" "B.Cu")
		(net "GND")
	)
	(via
		(at 187.060078 -252.58522)
		(size 0.4826)
		(drill 0.254)
		(layers "F.Cu" "B.Cu")
		(net "GND")
	)
	(via
		(at 290.895786 -312.084974)
		(size 0.4826)
		(drill 0.254)
		(layers "F.Cu" "B.Cu")
		(net "GND")
	)
	(via
		(at 76.5937 -385.58216)
		(size 0.508)
		(drill 0.254)
		(layers "F.Cu" "B.Cu")
		(net "GND")
	)
	(via
		(at 183.132222 -117.442742)
		(size 0.4572)
		(drill 0.254)
		(layers "F.Cu" "B.Cu")
		(net "GND")
	)
	(via
		(at 112.525556 -23.465536)
		(size 0.508)
		(drill 0.254)
		(layers "F.Cu" "B.Cu")
		(net "GND")
	)
	(via
		(at 439.100214 -232.184956)
		(size 0.4826)
		(drill 0.254)
		(layers "F.Cu" "B.Cu")
		(net "GND")
	)
	(via
		(at 430.17186 -284.034992)
		(size 0.4826)
		(drill 0.254)
		(layers "F.Cu" "B.Cu")
		(net "GND")
	)
	(via
		(at 193.4972 -342.679274)
		(size 0.508)
		(drill 0.254)
		(layers "F.Cu" "B.Cu")
		(net "GND")
	)
	(via
		(at 430.17186 -237.285022)
		(size 0.4826)
		(drill 0.254)
		(layers "F.Cu" "B.Cu")
		(net "GND")
	)
	(via
		(at 191.160146 -224.535238)
		(size 0.4826)
		(drill 0.254)
		(layers "F.Cu" "B.Cu")
		(net "GND")
	)
	(via
		(at 332.697074 -419.046152)
		(size 0.4572)
		(drill 0.254)
		(layers "F.Cu" "B.Cu")
		(net "GND")
	)
	(via
		(at 400.518122 -171.30395)
		(size 0.508)
		(drill 0.254)
		(layers "F.Cu" "B.Cu")
		(net "GND")
	)
	(via
		(at 347.801184 -289.475926)
		(size 0.4064)
		(drill 0.2032)
		(layers "F.Cu" "B.Cu")
		(net "GND")
	)
	(via
		(at 442.769752 -392.143234)
		(size 0.508)
		(drill 0.254)
		(layers "F.Cu" "B.Cu")
		(net "GND")
	)
	(via
		(at 361.594908 -250.964192)
		(size 0.4064)
		(drill 0.2032)
		(layers "F.Cu" "B.Cu")
		(net "GND")
	)
	(via
		(at 38.180772 -59.318144)
		(size 0.508)
		(drill 0.254)
		(layers "F.Cu" "B.Cu")
		(net "GND")
	)
	(via
		(at 206.248 -204.135228)
		(size 0.4826)
		(drill 0.254)
		(layers "F.Cu" "B.Cu")
		(net "GND")
	)
	(via
		(at 62.919864 -18.25371)
		(size 0.508)
		(drill 0.254)
		(layers "F.Cu" "B.Cu")
		(net "GND")
	)
	(via
		(at 445.259968 -312.084974)
		(size 0.4826)
		(drill 0.254)
		(layers "F.Cu" "B.Cu")
		(net "GND")
	)
	(via
		(at 178.943 -141.188948)
		(size 0.508)
		(drill 0.254)
		(layers "F.Cu" "B.Cu")
		(net "GND")
	)
	(via
		(at 99.090988 -237.194344)
		(size 0.4064)
		(drill 0.2032)
		(layers "F.Cu" "B.Cu")
		(net "GND")
	)
	(via
		(at 381.804926 -248.534174)
		(size 0.4064)
		(drill 0.2032)
		(layers "F.Cu" "B.Cu")
		(net "GND")
	)
	(via
		(at 130.40487 -262.746236)
		(size 0.4064)
		(drill 0.2032)
		(layers "F.Cu" "B.Cu")
		(net "GND")
	)
	(via
		(at 415.170874 -164.166804)
		(size 0.49022)
		(drill 0.254)
		(layers "F.Cu" "B.Cu")
		(net "GND")
	)
	(via
		(at 92.981018 -226.66452)
		(size 0.4064)
		(drill 0.2032)
		(layers "F.Cu" "B.Cu")
		(net "GND")
	)
	(via
		(at 378.210318 -186.648598)
		(size 0.508)
		(drill 0.254)
		(layers "F.Cu" "B.Cu")
		(net "GND")
	)
	(via
		(at 154.518614 -411.936184)
		(size 0.4572)
		(drill 0.254)
		(layers "F.Cu" "B.Cu")
		(net "GND")
	)
	(via
		(at 133.394704 -238.00435)
		(size 0.4064)
		(drill 0.2032)
		(layers "F.Cu" "B.Cu")
		(net "GND")
	)
	(via
		(at 49.665636 -10.16508)
		(size 0.508)
		(drill 0.254)
		(layers "F.Cu" "B.Cu")
		(net "GND")
	)
	(via
		(at 136.80948 -23.695406)
		(size 0.508)
		(drill 0.254)
		(layers "F.Cu" "B.Cu")
		(net "GND")
	)
	(via
		(at 416.730942 -418.412168)
		(size 0.4064)
		(drill 0.2032)
		(layers "F.Cu" "B.Cu")
		(net "GND")
	)
	(via
		(at 50.430938 -345.799918)
		(size 0.49022)
		(drill 0.254)
		(layers "F.Cu" "B.Cu")
		(net "GND")
	)
	(via
		(at 413.78378 -378.07773)
		(size 0.508)
		(drill 0.254)
		(layers "F.Cu" "B.Cu")
		(net "GND")
	)
	(via
		(at 118.354856 -229.90429)
		(size 0.4064)
		(drill 0.2032)
		(layers "F.Cu" "B.Cu")
		(net "GND")
	)
	(via
		(at 351.731072 -222.614236)
		(size 0.4064)
		(drill 0.2032)
		(layers "F.Cu" "B.Cu")
		(net "GND")
	)
	(via
		(at 172.648626 -15.002764)
		(size 0.508)
		(drill 0.254)
		(layers "F.Cu" "B.Cu")
		(net "GND")
	)
	(via
		(at 83.580986 -241.244374)
		(size 0.4064)
		(drill 0.2032)
		(layers "F.Cu" "B.Cu")
		(net "GND")
	)
	(via
		(at 51.08448 -423.825162)
		(size 0.508)
		(drill 0.254)
		(layers "F.Cu" "B.Cu")
		(net "GND")
	)
	(via
		(at 417.585652 -313.360054)
		(size 0.4826)
		(drill 0.254)
		(layers "F.Cu" "B.Cu")
		(net "GND")
	)
	(via
		(at 143.73479 -246.10441)
		(size 0.4064)
		(drill 0.2032)
		(layers "F.Cu" "B.Cu")
		(net "GND")
	)
	(via
		(at 20.32381 -277.235412)
		(size 0.4826)
		(drill 0.254)
		(layers "F.Cu" "B.Cu")
		(net "GND")
	)
	(via
		(at 38.4556 -10.16508)
		(size 0.508)
		(drill 0.254)
		(layers "F.Cu" "B.Cu")
		(net "GND")
	)
	(via
		(at 174.892208 -20.108164)
		(size 0.508)
		(drill 0.254)
		(layers "F.Cu" "B.Cu")
		(net "GND")
	)
	(via
		(at 372.234714 -276.516084)
		(size 0.4064)
		(drill 0.2032)
		(layers "F.Cu" "B.Cu")
		(net "GND")
	)
	(via
		(at 331.821028 -278.136096)
		(size 0.4064)
		(drill 0.2032)
		(layers "F.Cu" "B.Cu")
		(net "GND")
	)
	(via
		(at 113.65484 -236.384338)
		(size 0.4064)
		(drill 0.2032)
		(layers "F.Cu" "B.Cu")
		(net "GND")
	)
	(via
		(at 371.155468 -32.573468)
		(size 0.508)
		(drill 0.254)
		(layers "F.Cu" "B.Cu")
		(net "GND")
	)
	(via
		(at 56.411114 -343.476834)
		(size 0.508)
		(drill 0.254)
		(layers "F.Cu" "B.Cu")
		(net "GND")
	)
	(via
		(at 97.981008 -266.796266)
		(size 0.4064)
		(drill 0.2032)
		(layers "F.Cu" "B.Cu")
		(net "GND")
	)
	(via
		(at 195.759832 -194.885564)
		(size 0.4826)
		(drill 0.254)
		(layers "F.Cu" "B.Cu")
		(net "GND")
	)
	(via
		(at 303.459896 -382.34493)
		(size 0.508)
		(drill 0.254)
		(layers "F.Cu" "B.Cu")
		(net "GND")
	)
	(via
		(at 341.619332 -21.680932)
		(size 0.508)
		(drill 0.254)
		(layers "F.Cu" "B.Cu")
		(net "GND")
	)
	(via
		(at 145.056098 -410.664152)
		(size 0.4572)
		(drill 0.254)
		(layers "F.Cu" "B.Cu")
		(net "GND")
	)
	(via
		(at 282.208986 -348.704662)
		(size 0.49022)
		(drill 0.254)
		(layers "F.Cu" "B.Cu")
		(net "GND")
	)
	(via
		(at 312.216292 -391.23493)
		(size 0.4064)
		(drill 0.2032)
		(layers "F.Cu" "B.Cu")
		(net "GND")
	)
	(via
		(at 307.348636 -378.07773)
		(size 0.508)
		(drill 0.254)
		(layers "F.Cu" "B.Cu")
		(net "GND")
	)
	(via
		(at 380.224792 -285.42615)
		(size 0.4064)
		(drill 0.2032)
		(layers "F.Cu" "B.Cu")
		(net "GND")
	)
	(via
		(at 164.590984 -369.69573)
		(size 0.508)
		(drill 0.254)
		(layers "F.Cu" "B.Cu")
		(net "GND")
	)
	(via
		(at 179.516024 -298.485306)
		(size 0.4826)
		(drill 0.254)
		(layers "F.Cu" "B.Cu")
		(net "GND")
	)
	(via
		(at 344.199718 -164.38372)
		(size 0.508)
		(drill 0.254)
		(layers "F.Cu" "B.Cu")
		(net "GND")
	)
	(via
		(at 162.889184 -370.83873)
		(size 0.508)
		(drill 0.254)
		(layers "F.Cu" "B.Cu")
		(net "GND")
	)
	(via
		(at 190.004446 -192.218564)
		(size 0.4826)
		(drill 0.254)
		(layers "F.Cu" "B.Cu")
		(net "GND")
	)
	(via
		(at 130.87477 -279.756362)
		(size 0.4064)
		(drill 0.2032)
		(layers "F.Cu" "B.Cu")
		(net "GND")
	)
	(via
		(at 451.4723 -210.085178)
		(size 0.4826)
		(drill 0.254)
		(layers "F.Cu" "B.Cu")
		(net "GND")
	)
	(via
		(at 380.698248 -295.983406)
		(size 0.4064)
		(drill 0.2032)
		(layers "F.Cu" "B.Cu")
		(net "GND")
	)
	(via
		(at 149.923754 -410.664152)
		(size 0.4572)
		(drill 0.254)
		(layers "F.Cu" "B.Cu")
		(net "GND")
	)
	(via
		(at 124.7648 -269.226284)
		(size 0.4064)
		(drill 0.2032)
		(layers "F.Cu" "B.Cu")
		(net "GND")
	)
	(via
		(at 312.224166 -342.811608)
		(size 0.508)
		(drill 0.254)
		(layers "F.Cu" "B.Cu")
		(net "GND")
	)
	(via
		(at 53.378608 -386.449062)
		(size 0.4064)
		(drill 0.2032)
		(layers "F.Cu" "B.Cu")
		(net "GND")
	)
	(via
		(at 112.79886 -33.529778)
		(size 0.508)
		(drill 0.254)
		(layers "F.Cu" "B.Cu")
		(net "GND")
	)
	(via
		(at 200.28662 -332.805786)
		(size 0.508)
		(drill 0.254)
		(layers "F.Cu" "B.Cu")
		(net "GND")
	)
	(via
		(at 120.70461 -224.234502)
		(size 0.4064)
		(drill 0.2032)
		(layers "F.Cu" "B.Cu")
		(net "GND")
	)
	(via
		(at 341.528146 -418.412168)
		(size 0.4064)
		(drill 0.2032)
		(layers "F.Cu" "B.Cu")
		(net "GND")
	)
	(via
		(at 404.119334 -416.020504)
		(size 0.4572)
		(drill 0.254)
		(layers "F.Cu" "B.Cu")
		(net "GND")
	)
	(via
		(at 376.916442 -400.212814)
		(size 0.4064)
		(drill 0.2032)
		(layers "F.Cu" "B.Cu")
		(net "GND")
	)
	(via
		(at 88.744298 -382.85293)
		(size 0.4064)
		(drill 0.2032)
		(layers "F.Cu" "B.Cu")
		(net "GND")
	)
	(via
		(at 137.186924 -166.96055)
		(size 0.508)
		(drill 0.254)
		(layers "F.Cu" "B.Cu")
		(net "GND")
	)
	(via
		(at 347.003624 -74.184764)
		(size 0.508)
		(drill 0.254)
		(layers "F.Cu" "B.Cu")
		(net "GND")
	)
	(via
		(at 14.16177 -384.01879)
		(size 0.508)
		(drill 0.254)
		(layers "F.Cu" "B.Cu")
		(net "GND")
	)
	(via
		(at 391.974832 -286.236156)
		(size 0.4064)
		(drill 0.2032)
		(layers "F.Cu" "B.Cu")
		(net "GND")
	)
	(via
		(at 389.79475 -239.624108)
		(size 0.4064)
		(drill 0.2032)
		(layers "F.Cu" "B.Cu")
		(net "GND")
	)
	(via
		(at 340.921086 -226.664266)
		(size 0.4064)
		(drill 0.2032)
		(layers "F.Cu" "B.Cu")
		(net "GND")
	)
	(via
		(at 346.413074 -163.078668)
		(size 0.49022)
		(drill 0.254)
		(layers "F.Cu" "B.Cu")
		(net "GND")
	)
	(via
		(at 83.111086 -243.674392)
		(size 0.4064)
		(drill 0.2032)
		(layers "F.Cu" "B.Cu")
		(net "GND")
	)
	(via
		(at 330.369672 -32.953706)
		(size 0.508)
		(drill 0.254)
		(layers "F.Cu" "B.Cu")
		(net "GND")
	)
	(via
		(at 386.504942 -245.29415)
		(size 0.4064)
		(drill 0.2032)
		(layers "F.Cu" "B.Cu")
		(net "GND")
	)
	(via
		(at 146.587718 -403.830536)
		(size 0.4572)
		(drill 0.254)
		(layers "F.Cu" "B.Cu")
		(net "GND")
	)
	(via
		(at 229.871778 -317.22568)
		(size 0.508)
		(drill 0.254)
		(layers "F.Cu" "B.Cu")
		(net "GND")
	)
	(via
		(at 148.119338 -406.370536)
		(size 0.4572)
		(drill 0.254)
		(layers "F.Cu" "B.Cu")
		(net "GND")
	)
	(via
		(at 31.514034 -339.812122)
		(size 0.508)
		(drill 0.254)
		(layers "F.Cu" "B.Cu")
		(net "GND")
	)
	(via
		(at 299.731938 -389.444738)
		(size 0.508)
		(drill 0.254)
		(layers "F.Cu" "B.Cu")
		(net "GND")
	)
	(via
		(at 64.475614 -370.83873)
		(size 0.508)
		(drill 0.254)
		(layers "F.Cu" "B.Cu")
		(net "GND")
	)
	(via
		(at 375.694702 -223.424242)
		(size 0.4064)
		(drill 0.2032)
		(layers "F.Cu" "B.Cu")
		(net "GND")
	)
	(via
		(at 11.435588 -114.072924)
		(size 0.508)
		(drill 0.254)
		(layers "F.Cu" "B.Cu")
		(net "GND")
	)
	(via
		(at 280.529792 -345.86672)
		(size 0.49022)
		(drill 0.254)
		(layers "F.Cu" "B.Cu")
		(net "GND")
	)
	(via
		(at 139.825222 -143.232124)
		(size 0.6604)
		(drill 0.3302)
		(layers "F.Cu" "B.Cu")
		(net "GND")
	)
	(via
		(at 416.023298 -161.779458)
		(size 0.49022)
		(drill 0.254)
		(layers "F.Cu" "B.Cu")
		(net "GND")
	)
	(via
		(at 125.040136 -257.930396)
		(size 0.4826)
		(drill 0.254)
		(layers "F.Cu" "B.Cu")
		(net "GND")
	)
	(via
		(at 435.000146 -290.83508)
		(size 0.4826)
		(drill 0.254)
		(layers "F.Cu" "B.Cu")
		(net "GND")
	)
	(via
		(at 391.204704 -248.534174)
		(size 0.4064)
		(drill 0.2032)
		(layers "F.Cu" "B.Cu")
		(net "GND")
	)
	(via
		(at 73.95845 -383.02946)
		(size 0.508)
		(drill 0.254)
		(layers "F.Cu" "B.Cu")
		(net "GND")
	)
	(via
		(at 50.766472 -294.66032)
		(size 0.4826)
		(drill 0.254)
		(layers "F.Cu" "B.Cu")
		(net "GND")
	)
	(via
		(at 18.992342 -287.43529)
		(size 0.4826)
		(drill 0.254)
		(layers "F.Cu" "B.Cu")
		(net "GND")
	)
	(via
		(at 447.16065 -7.215124)
		(size 0.508)
		(drill 0.254)
		(layers "F.Cu" "B.Cu")
		(net "GND")
	)
	(via
		(at 86.249764 -432.451256)
		(size 0.4572)
		(drill 0.2032)
		(layers "F.Cu" "B.Cu")
		(net "GND")
	)
	(via
		(at 84.99094 -242.05438)
		(size 0.4064)
		(drill 0.2032)
		(layers "F.Cu" "B.Cu")
		(net "GND")
	)
	(via
		(at 151.34971 -435.0512)
		(size 0.4572)
		(drill 0.2032)
		(layers "F.Cu" "B.Cu")
		(net "GND")
	)
	(via
		(at 76.185522 -20.136104)
		(size 0.508)
		(drill 0.254)
		(layers "F.Cu" "B.Cu")
		(net "GND")
	)
	(via
		(at 451.4723 -284.88513)
		(size 0.4826)
		(drill 0.254)
		(layers "F.Cu" "B.Cu")
		(net "GND")
	)
	(via
		(at 118.824756 -227.474526)
		(size 0.4064)
		(drill 0.2032)
		(layers "F.Cu" "B.Cu")
		(net "GND")
	)
	(via
		(at 51.884072 -255.13538)
		(size 0.4826)
		(drill 0.254)
		(layers "F.Cu" "B.Cu")
		(net "GND")
	)
	(via
		(at 454.159366 -378.05487)
		(size 0.508)
		(drill 0.254)
		(layers "F.Cu" "B.Cu")
		(net "GND")
	)
	(via
		(at 93.450918 -256.634488)
		(size 0.4064)
		(drill 0.2032)
		(layers "F.Cu" "B.Cu")
		(net "GND")
	)
	(via
		(at 118.929912 -17.784064)
		(size 0.508)
		(drill 0.254)
		(layers "F.Cu" "B.Cu")
		(net "GND")
	)
	(via
		(at 63.24981 -438.651396)
		(size 0.4572)
		(drill 0.2032)
		(layers "F.Cu" "B.Cu")
		(net "GND")
	)
	(via
		(at 367.92027 -401.25015)
		(size 0.508)
		(drill 0.254)
		(layers "F.Cu" "B.Cu")
		(net "GND")
	)
	(via
		(at 198.7042 -251.735336)
		(size 0.4826)
		(drill 0.254)
		(layers "F.Cu" "B.Cu")
		(net "GND")
	)
	(via
		(at 102.577392 -410.299916)
		(size 0.508)
		(drill 0.254)
		(layers "F.Cu" "B.Cu")
		(net "GND")
	)
	(via
		(at 403.006306 -394.831062)
		(size 0.4064)
		(drill 0.2032)
		(layers "F.Cu" "B.Cu")
		(net "GND")
	)
	(via
		(at 202.550776 -68.953126)
		(size 0.508)
		(drill 0.254)
		(layers "F.Cu" "B.Cu")
		(net "GND")
	)
	(via
		(at 169.693844 -369.03533)
		(size 0.508)
		(drill 0.254)
		(layers "F.Cu" "B.Cu")
		(net "GND")
	)
	(via
		(at 359.061766 -353.968812)
		(size 0.6604)
		(drill 0.3302)
		(layers "F.Cu" "B.Cu")
		(net "GND")
	)
	(via
		(at 107.71505 -177.605944)
		(size 0.49022)
		(drill 0.254)
		(layers "F.Cu" "B.Cu")
		(net "GND")
	)
	(via
		(at 176.072038 -291.685218)
		(size 0.4826)
		(drill 0.254)
		(layers "F.Cu" "B.Cu")
		(net "GND")
	)
	(via
		(at 332.249526 -436.347362)
		(size 0.4572)
		(drill 0.2032)
		(layers "F.Cu" "B.Cu")
		(net "GND")
	)
	(via
		(at 21.70811 -250.035314)
		(size 0.4826)
		(drill 0.254)
		(layers "F.Cu" "B.Cu")
		(net "GND")
	)
	(via
		(at 353.141026 -242.864132)
		(size 0.4064)
		(drill 0.2032)
		(layers "F.Cu" "B.Cu")
		(net "GND")
	)
	(via
		(at 363.474762 -233.14406)
		(size 0.4064)
		(drill 0.2032)
		(layers "F.Cu" "B.Cu")
		(net "GND")
	)
	(via
		(at 419.912038 -236.435138)
		(size 0.4826)
		(drill 0.254)
		(layers "F.Cu" "B.Cu")
		(net "GND")
	)
	(via
		(at 29.69387 -383.37109)
		(size 0.508)
		(drill 0.254)
		(layers "F.Cu" "B.Cu")
		(net "GND")
	)
	(via
		(at 93.602302 -373.96293)
		(size 0.508)
		(drill 0.254)
		(layers "F.Cu" "B.Cu")
		(net "GND")
	)
	(via
		(at 363.774736 -276.516084)
		(size 0.4064)
		(drill 0.2032)
		(layers "F.Cu" "B.Cu")
		(net "GND")
	)
	(via
		(at 40.23995 -300.185328)
		(size 0.4826)
		(drill 0.254)
		(layers "F.Cu" "B.Cu")
		(net "GND")
	)
	(via
		(at 326.351138 -256.634234)
		(size 0.4064)
		(drill 0.2032)
		(layers "F.Cu" "B.Cu")
		(net "GND")
	)
	(via
		(at 88.580976 -278.13635)
		(size 0.4064)
		(drill 0.2032)
		(layers "F.Cu" "B.Cu")
		(net "GND")
	)
	(via
		(at 424.165522 -10.16508)
		(size 0.508)
		(drill 0.254)
		(layers "F.Cu" "B.Cu")
		(net "GND")
	)
	(via
		(at 198.7042 -241.535204)
		(size 0.4826)
		(drill 0.254)
		(layers "F.Cu" "B.Cu")
		(net "GND")
	)
	(via
		(at 139.974828 -246.10441)
		(size 0.4064)
		(drill 0.2032)
		(layers "F.Cu" "B.Cu")
		(net "GND")
	)
	(via
		(at 130.848354 -55.922164)
		(size 0.508)
		(drill 0.254)
		(layers "F.Cu" "B.Cu")
		(net "GND")
	)
	(via
		(at 295.724072 -317.18504)
		(size 0.4826)
		(drill 0.254)
		(layers "F.Cu" "B.Cu")
		(net "GND")
	)
	(via
		(at 49.938178 -6.091174)
		(size 0.508)
		(drill 0.254)
		(layers "F.Cu" "B.Cu")
		(net "GND")
	)
	(via
		(at 454.188068 -291.684964)
		(size 0.4826)
		(drill 0.254)
		(layers "F.Cu" "B.Cu")
		(net "GND")
	)
	(via
		(at 429.565562 -7.215124)
		(size 0.508)
		(drill 0.254)
		(layers "F.Cu" "B.Cu")
		(net "GND")
	)
	(via
		(at 117.244622 -280.566368)
		(size 0.4064)
		(drill 0.2032)
		(layers "F.Cu" "B.Cu")
		(net "GND")
	)
	(via
		(at 397.904462 -412.84652)
		(size 0.4064)
		(drill 0.2032)
		(layers "F.Cu" "B.Cu")
		(net "GND")
	)
	(via
		(at 421.296338 -212.635084)
		(size 0.4826)
		(drill 0.254)
		(layers "F.Cu" "B.Cu")
		(net "GND")
	)
	(via
		(at 304.590958 -398.542002)
		(size 0.4064)
		(drill 0.2032)
		(layers "F.Cu" "B.Cu")
		(net "GND")
	)
	(via
		(at 454.188068 -213.484968)
		(size 0.4826)
		(drill 0.254)
		(layers "F.Cu" "B.Cu")
		(net "GND")
	)
	(via
		(at 276.53742 -129.377948)
		(size 0.508)
		(drill 0.254)
		(layers "F.Cu" "B.Cu")
		(net "GND")
	)
	(via
		(at 130.40487 -282.18638)
		(size 0.4064)
		(drill 0.2032)
		(layers "F.Cu" "B.Cu")
		(net "GND")
	)
	(via
		(at 49.065434 -339.827362)
		(size 0.508)
		(drill 0.254)
		(layers "F.Cu" "B.Cu")
		(net "GND")
	)
	(via
		(at 310.981598 -420.318184)
		(size 0.4572)
		(drill 0.254)
		(layers "F.Cu" "B.Cu")
		(net "GND")
	)
	(via
		(at 448.15379 -45.69206)
		(size 0.508)
		(drill 0.254)
		(layers "F.Cu" "B.Cu")
		(net "GND")
	)
	(via
		(at 97.981008 -263.556242)
		(size 0.4064)
		(drill 0.2032)
		(layers "F.Cu" "B.Cu")
		(net "GND")
	)
	(via
		(at 94.861126 -225.044508)
		(size 0.4064)
		(drill 0.2032)
		(layers "F.Cu" "B.Cu")
		(net "GND")
	)
	(via
		(at 339.511132 -225.85426)
		(size 0.4064)
		(drill 0.2032)
		(layers "F.Cu" "B.Cu")
		(net "GND")
	)
	(via
		(at 337.930998 -285.42615)
		(size 0.4064)
		(drill 0.2032)
		(layers "F.Cu" "B.Cu")
		(net "GND")
	)
	(via
		(at 367.153952 -380.54153)
		(size 0.508)
		(drill 0.254)
		(layers "F.Cu" "B.Cu")
		(net "GND")
	)
	(via
		(at 355.321108 -336.029808)
		(size 0.508)
		(drill 0.254)
		(layers "F.Cu" "B.Cu")
		(net "GND")
	)
	(via
		(at 105.671112 -246.914416)
		(size 0.4064)
		(drill 0.2032)
		(layers "F.Cu" "B.Cu")
		(net "GND")
	)
	(via
		(at 326.617076 -388.917688)
		(size 0.508)
		(drill 0.254)
		(layers "F.Cu" "B.Cu")
		(net "GND")
	)
	(via
		(at 91.990164 -384.617722)
		(size 0.4064)
		(drill 0.2032)
		(layers "F.Cu" "B.Cu")
		(net "GND")
	)
	(via
		(at 350.795082 -259.729986)
		(size 0.4826)
		(drill 0.254)
		(layers "F.Cu" "B.Cu")
		(net "GND")
	)
	(via
		(at 90.461084 -294.336216)
		(size 0.4064)
		(drill 0.2032)
		(layers "F.Cu" "B.Cu")
		(net "GND")
	)
	(via
		(at 140.444728 -230.71455)
		(size 0.4064)
		(drill 0.2032)
		(layers "F.Cu" "B.Cu")
		(net "GND")
	)
	(via
		(at 80.249776 -425.547282)
		(size 0.4572)
		(drill 0.2032)
		(layers "F.Cu" "B.Cu")
		(net "GND")
	)
	(via
		(at 128.89611 -159.775398)
		(size 0.508)
		(drill 0.254)
		(layers "F.Cu" "B.Cu")
		(net "GND")
	)
	(via
		(at 186.932316 -330.872084)
		(size 0.508)
		(drill 0.254)
		(layers "F.Cu" "B.Cu")
		(net "GND")
	)
	(via
		(at 415.444432 -402.309838)
		(size 0.4572)
		(drill 0.254)
		(layers "F.Cu" "B.Cu")
		(net "GND")
	)
	(via
		(at 50.728372 -193.996564)
		(size 0.4826)
		(drill 0.254)
		(layers "F.Cu" "B.Cu")
		(net "GND")
	)
	(via
		(at 313.031886 -339.87867)
		(size 0.508)
		(drill 0.254)
		(layers "F.Cu" "B.Cu")
		(net "GND")
	)
	(via
		(at 244.85219 -44.997116)
		(size 0.508)
		(drill 0.254)
		(layers "F.Cu" "B.Cu")
		(net "GND")
	)
	(via
		(at 35.678364 -219.860368)
		(size 0.4826)
		(drill 0.254)
		(layers "F.Cu" "B.Cu")
		(net "GND")
	)
	(via
		(at 78.711044 -267.606272)
		(size 0.4064)
		(drill 0.2032)
		(layers "F.Cu" "B.Cu")
		(net "GND")
	)
	(via
		(at 331.165454 -421.586152)
		(size 0.4572)
		(drill 0.254)
		(layers "F.Cu" "B.Cu")
		(net "GND")
	)
	(via
		(at 454.188068 -243.234972)
		(size 0.4826)
		(drill 0.254)
		(layers "F.Cu" "B.Cu")
		(net "GND")
	)
	(via
		(at 336.22107 -254.204216)
		(size 0.4064)
		(drill 0.2032)
		(layers "F.Cu" "B.Cu")
		(net "GND")
	)
	(via
		(at 359.805224 -383.814828)
		(size 0.508)
		(drill 0.254)
		(layers "F.Cu" "B.Cu")
		(net "GND")
	)
	(via
		(at 323.249544 -426.69968)
		(size 0.4572)
		(drill 0.2032)
		(layers "F.Cu" "B.Cu")
		(net "GND")
	)
	(via
		(at 445.709802 -416.98291)
		(size 0.508)
		(drill 0.254)
		(layers "F.Cu" "B.Cu")
		(net "GND")
	)
	(via
		(at 184.733692 -313.360308)
		(size 0.4826)
		(drill 0.254)
		(layers "F.Cu" "B.Cu")
		(net "GND")
	)
	(via
		(at 302.184054 -43.989498)
		(size 0.508)
		(drill 0.254)
		(layers "F.Cu" "B.Cu")
		(net "GND")
	)
	(via
		(at 373.174768 -263.555988)
		(size 0.4064)
		(drill 0.2032)
		(layers "F.Cu" "B.Cu")
		(net "GND")
	)
	(via
		(at 20.076922 -6.091174)
		(size 0.508)
		(drill 0.254)
		(layers "F.Cu" "B.Cu")
		(net "GND")
	)
	(via
		(at 102.681024 -276.516338)
		(size 0.4064)
		(drill 0.2032)
		(layers "F.Cu" "B.Cu")
		(net "GND")
	)
	(via
		(at 323.595746 -412.84652)
		(size 0.4064)
		(drill 0.2032)
		(layers "F.Cu" "B.Cu")
		(net "GND")
	)
	(via
		(at 433.347876 -19.771106)
		(size 0.508)
		(drill 0.254)
		(layers "F.Cu" "B.Cu")
		(net "GND")
	)
	(via
		(at 269.648178 -268.735048)
		(size 0.4826)
		(drill 0.254)
		(layers "F.Cu" "B.Cu")
		(net "GND")
	)
	(via
		(at 317.249556 -436.051198)
		(size 0.4572)
		(drill 0.2032)
		(layers "F.Cu" "B.Cu")
		(net "GND")
	)
	(via
		(at 33.691322 -434.808884)
		(size 0.508)
		(drill 0.254)
		(layers "F.Cu" "B.Cu")
		(net "GND")
	)
	(via
		(at 270.192754 -420.073836)
		(size 0.508)
		(drill 0.254)
		(layers "F.Cu" "B.Cu")
		(net "GND")
	)
	(via
		(at 56.872124 -407.00452)
		(size 0.4064)
		(drill 0.2032)
		(layers "F.Cu" "B.Cu")
		(net "GND")
	)
	(via
		(at 121.644664 -235.574332)
		(size 0.4064)
		(drill 0.2032)
		(layers "F.Cu" "B.Cu")
		(net "GND")
	)
	(via
		(at 345.151202 -243.674138)
		(size 0.4064)
		(drill 0.2032)
		(layers "F.Cu" "B.Cu")
		(net "GND")
	)
	(via
		(at 335.848706 -420.952168)
		(size 0.4064)
		(drill 0.2032)
		(layers "F.Cu" "B.Cu")
		(net "GND")
	)
	(via
		(at 179.516024 -290.835334)
		(size 0.4826)
		(drill 0.254)
		(layers "F.Cu" "B.Cu")
		(net "GND")
	)
	(via
		(at 433.165504 -7.215124)
		(size 0.508)
		(drill 0.254)
		(layers "F.Cu" "B.Cu")
		(net "GND")
	)
	(via
		(at 384.208274 -412.212536)
		(size 0.4572)
		(drill 0.254)
		(layers "F.Cu" "B.Cu")
		(net "GND")
	)
	(via
		(at 375.018554 -413.480504)
		(size 0.4572)
		(drill 0.254)
		(layers "F.Cu" "B.Cu")
		(net "GND")
	)
	(via
		(at 34.406078 -19.13636)
		(size 0.508)
		(drill 0.254)
		(layers "F.Cu" "B.Cu")
		(net "GND")
	)
	(via
		(at 180.671724 -192.218564)
		(size 0.4826)
		(drill 0.254)
		(layers "F.Cu" "B.Cu")
		(net "GND")
	)
	(via
		(at 344.981022 -278.136096)
		(size 0.4064)
		(drill 0.2032)
		(layers "F.Cu" "B.Cu")
		(net "GND")
	)
	(via
		(at 422.627806 -202.434952)
		(size 0.4826)
		(drill 0.254)
		(layers "F.Cu" "B.Cu")
		(net "GND")
	)
	(via
		(at 59.849512 -413.204152)
		(size 0.4572)
		(drill 0.254)
		(layers "F.Cu" "B.Cu")
		(net "GND")
	)
	(via
		(at 65.550034 -339.883496)
		(size 0.508)
		(drill 0.254)
		(layers "F.Cu" "B.Cu")
		(net "GND")
	)
	(via
		(at 394.349478 -435.0512)
		(size 0.4572)
		(drill 0.2032)
		(layers "F.Cu" "B.Cu")
		(net "GND")
	)
	(via
		(at 2.76225 -115.753134)
		(size 0.508)
		(drill 0.254)
		(layers "F.Cu" "B.Cu")
		(net "GND")
	)
	(via
		(at 109.454696 -371.49913)
		(size 0.508)
		(drill 0.254)
		(layers "F.Cu" "B.Cu")
		(net "GND")
	)
	(via
		(at 29.69387 -386.03809)
		(size 0.508)
		(drill 0.254)
		(layers "F.Cu" "B.Cu")
		(net "GND")
	)
	(via
		(at 35.649662 -418.239448)
		(size 0.508)
		(drill 0.254)
		(layers "F.Cu" "B.Cu")
		(net "GND")
	)
	(via
		(at 44.340018 -288.285428)
		(size 0.4826)
		(drill 0.254)
		(layers "F.Cu" "B.Cu")
		(net "GND")
	)
	(via
		(at 459.325218 -57.49925)
		(size 0.508)
		(drill 0.254)
		(layers "F.Cu" "B.Cu")
		(net "GND")
	)
	(via
		(at 437.874918 -350.651572)
		(size 0.508)
		(drill 0.254)
		(layers "F.Cu" "B.Cu")
		(net "GND")
	)
	(via
		(at 104.408986 -338.000086)
		(size 0.49022)
		(drill 0.254)
		(layers "F.Cu" "B.Cu")
		(net "GND")
	)
	(via
		(at 76.249784 -438.651396)
		(size 0.4572)
		(drill 0.2032)
		(layers "F.Cu" "B.Cu")
		(net "GND")
	)
	(via
		(at 138.564874 -225.854514)
		(size 0.4064)
		(drill 0.2032)
		(layers "F.Cu" "B.Cu")
		(net "GND")
	)
	(via
		(at 384.924808 -291.905944)
		(size 0.4064)
		(drill 0.2032)
		(layers "F.Cu" "B.Cu")
		(net "GND")
	)
	(via
		(at 67.609466 -170.867832)
		(size 0.49022)
		(drill 0.254)
		(layers "F.Cu" "B.Cu")
		(net "GND")
	)
	(via
		(at 194.774566 -348.71152)
		(size 0.508)
		(drill 0.254)
		(layers "F.Cu" "B.Cu")
		(net "GND")
	)
	(via
		(at 121.539 -420.497)
		(size 0.508)
		(drill 0.254)
		(layers "F.Cu" "B.Cu")
		(net "GND")
	)
	(via
		(at 181.640988 -389.478012)
		(size 0.508)
		(drill 0.254)
		(layers "F.Cu" "B.Cu")
		(net "GND")
	)
	(via
		(at 214.469218 -386.437632)
		(size 0.508)
		(drill 0.254)
		(layers "F.Cu" "B.Cu")
		(net "GND")
	)
	(via
		(at 295.724072 -269.585186)
		(size 0.4826)
		(drill 0.254)
		(layers "F.Cu" "B.Cu")
		(net "GND")
	)
	(via
		(at 393.084812 -237.19409)
		(size 0.4064)
		(drill 0.2032)
		(layers "F.Cu" "B.Cu")
		(net "GND")
	)
	(via
		(at 452.619364 -32.639254)
		(size 0.508)
		(drill 0.254)
		(layers "F.Cu" "B.Cu")
		(net "GND")
	)
	(via
		(at 83.41106 -275.706332)
		(size 0.4064)
		(drill 0.2032)
		(layers "F.Cu" "B.Cu")
		(net "GND")
	)
	(via
		(at 42.049954 -18.503138)
		(size 0.508)
		(drill 0.254)
		(layers "F.Cu" "B.Cu")
		(net "GND")
	)
	(via
		(at 353.573334 -358.23144)
		(size 0.508)
		(drill 0.254)
		(layers "F.Cu" "B.Cu")
		(net "GND")
	)
	(via
		(at 334.341216 -236.384084)
		(size 0.4064)
		(drill 0.2032)
		(layers "F.Cu" "B.Cu")
		(net "GND")
	)
	(via
		(at 54.223158 -344.781886)
		(size 0.49022)
		(drill 0.254)
		(layers "F.Cu" "B.Cu")
		(net "GND")
	)
	(via
		(at 126.644654 -280.566368)
		(size 0.4064)
		(drill 0.2032)
		(layers "F.Cu" "B.Cu")
		(net "GND")
	)
	(via
		(at 187.911994 -113.46307)
		(size 0.4572)
		(drill 0.254)
		(layers "F.Cu" "B.Cu")
		(net "GND")
	)
	(via
		(at 396.397988 -389.7122)
		(size 0.508)
		(drill 0.254)
		(layers "F.Cu" "B.Cu")
		(net "GND")
	)
	(via
		(at 137.154666 -226.66452)
		(size 0.4064)
		(drill 0.2032)
		(layers "F.Cu" "B.Cu")
		(net "GND")
	)
	(via
		(at 90.461084 -261.93623)
		(size 0.4064)
		(drill 0.2032)
		(layers "F.Cu" "B.Cu")
		(net "GND")
	)
	(via
		(at 195.598542 -36.433252)
		(size 0.508)
		(drill 0.254)
		(layers "F.Cu" "B.Cu")
		(net "GND")
	)
	(via
		(at 98.150934 -232.334308)
		(size 0.4064)
		(drill 0.2032)
		(layers "F.Cu" "B.Cu")
		(net "GND")
	)
	(via
		(at 339.811106 -265.986006)
		(size 0.4064)
		(drill 0.2032)
		(layers "F.Cu" "B.Cu")
		(net "GND")
	)
	(via
		(at 390.349486 -436.347362)
		(size 0.4572)
		(drill 0.2032)
		(layers "F.Cu" "B.Cu")
		(net "GND")
	)
	(via
		(at 61.249814 -434.899562)
		(size 0.4572)
		(drill 0.2032)
		(layers "F.Cu" "B.Cu")
		(net "GND")
	)
	(via
		(at 130.361436 -372.15953)
		(size 0.508)
		(drill 0.254)
		(layers "F.Cu" "B.Cu")
		(net "GND")
	)
	(via
		(at 37.32022 -112.23498)
		(size 0.508)
		(drill 0.254)
		(layers "F.Cu" "B.Cu")
		(net "GND")
	)
	(via
		(at 138.349736 -433.899564)
		(size 0.4572)
		(drill 0.2032)
		(layers "F.Cu" "B.Cu")
		(net "GND")
	)
	(via
		(at 321.249548 -436.051198)
		(size 0.4572)
		(drill 0.2032)
		(layers "F.Cu" "B.Cu")
		(net "GND")
	)
	(via
		(at 388.384796 -251.774198)
		(size 0.4064)
		(drill 0.2032)
		(layers "F.Cu" "B.Cu")
		(net "GND")
	)
	(via
		(at 381.324612 -177.602134)
		(size 0.508)
		(drill 0.254)
		(layers "F.Cu" "B.Cu")
		(net "GND")
	)
	(via
		(at 421.682164 -349.964756)
		(size 0.49022)
		(drill 0.254)
		(layers "F.Cu" "B.Cu")
		(net "GND")
	)
	(via
		(at 416.468052 -267.035026)
		(size 0.4826)
		(drill 0.254)
		(layers "F.Cu" "B.Cu")
		(net "GND")
	)
	(via
		(at 123.069096 -371.49913)
		(size 0.508)
		(drill 0.254)
		(layers "F.Cu" "B.Cu")
		(net "GND")
	)
	(via
		(at 179.516024 -223.685354)
		(size 0.4826)
		(drill 0.254)
		(layers "F.Cu" "B.Cu")
		(net "GND")
	)
	(via
		(at 334.811116 -248.534174)
		(size 0.4064)
		(drill 0.2032)
		(layers "F.Cu" "B.Cu")
		(net "GND")
	)
	(via
		(at 123.946666 -165.59149)
		(size 0.49022)
		(drill 0.254)
		(layers "F.Cu" "B.Cu")
		(net "GND")
	)
	(via
		(at 342.249506 -437.34736)
		(size 0.4572)
		(drill 0.2032)
		(layers "F.Cu" "B.Cu")
		(net "GND")
	)
	(via
		(at 143.349726 -430.299622)
		(size 0.4572)
		(drill 0.2032)
		(layers "F.Cu" "B.Cu")
		(net "GND")
	)
	(via
		(at 34.891218 -19.771106)
		(size 0.508)
		(drill 0.254)
		(layers "F.Cu" "B.Cu")
		(net "GND")
	)
	(via
		(at 131.98475 -225.854514)
		(size 0.4064)
		(drill 0.2032)
		(layers "F.Cu" "B.Cu")
		(net "GND")
	)
	(via
		(at 280.635964 -233.035094)
		(size 0.4826)
		(drill 0.254)
		(layers "F.Cu" "B.Cu")
		(net "GND")
	)
	(via
		(at 48.662336 -384.617722)
		(size 0.4064)
		(drill 0.2032)
		(layers "F.Cu" "B.Cu")
		(net "GND")
	)
	(via
		(at 372.704868 -272.466054)
		(size 0.4064)
		(drill 0.2032)
		(layers "F.Cu" "B.Cu")
		(net "GND")
	)
	(via
		(at 381.716534 -400.212814)
		(size 0.4064)
		(drill 0.2032)
		(layers "F.Cu" "B.Cu")
		(net "GND")
	)
	(via
		(at 337.930998 -264.365994)
		(size 0.4064)
		(drill 0.2032)
		(layers "F.Cu" "B.Cu")
		(net "GND")
	)
	(via
		(at 22.264116 -95.510604)
		(size 0.508)
		(drill 0.254)
		(layers "F.Cu" "B.Cu")
		(net "GND")
	)
	(via
		(at 348.271084 -293.525956)
		(size 0.4064)
		(drill 0.2032)
		(layers "F.Cu" "B.Cu")
		(net "GND")
	)
	(via
		(at 133.394704 -226.66452)
		(size 0.4064)
		(drill 0.2032)
		(layers "F.Cu" "B.Cu")
		(net "GND")
	)
	(via
		(at 355.961188 -236.384084)
		(size 0.4064)
		(drill 0.2032)
		(layers "F.Cu" "B.Cu")
		(net "GND")
	)
	(via
		(at 138.864848 -264.366248)
		(size 0.4064)
		(drill 0.2032)
		(layers "F.Cu" "B.Cu")
		(net "GND")
	)
	(via
		(at 265.54811 -309.535068)
		(size 0.4826)
		(drill 0.254)
		(layers "F.Cu" "B.Cu")
		(net "GND")
	)
	(via
		(at 422.721024 -429.461676)
		(size 0.508)
		(drill 0.254)
		(layers "F.Cu" "B.Cu")
		(net "GND")
	)
	(via
		(at 171.97197 -206.685388)
		(size 0.4826)
		(drill 0.254)
		(layers "F.Cu" "B.Cu")
		(net "GND")
	)
	(via
		(at 274.734528 -164.808916)
		(size 0.508)
		(drill 0.254)
		(layers "F.Cu" "B.Cu")
		(net "GND")
	)
	(via
		(at 414.730692 -138.319256)
		(size 0.508)
		(drill 0.254)
		(layers "F.Cu" "B.Cu")
		(net "GND")
	)
	(via
		(at 388.21487 -270.036036)
		(size 0.4064)
		(drill 0.2032)
		(layers "F.Cu" "B.Cu")
		(net "GND")
	)
	(via
		(at 316.60846 -122.758708)
		(size 0.508)
		(drill 0.254)
		(layers "F.Cu" "B.Cu")
		(net "GND")
	)
	(via
		(at 375.224802 -238.814102)
		(size 0.4064)
		(drill 0.2032)
		(layers "F.Cu" "B.Cu")
		(net "GND")
	)
	(via
		(at 372.704868 -282.186126)
		(size 0.4064)
		(drill 0.2032)
		(layers "F.Cu" "B.Cu")
		(net "GND")
	)
	(via
		(at 56.483758 -193.107564)
		(size 0.4826)
		(drill 0.254)
		(layers "F.Cu" "B.Cu")
		(net "GND")
	)
	(via
		(at 145.349722 -432.451256)
		(size 0.4572)
		(drill 0.2032)
		(layers "F.Cu" "B.Cu")
		(net "GND")
	)
	(via
		(at 68.672456 -30.07741)
		(size 0.508)
		(drill 0.254)
		(layers "F.Cu" "B.Cu")
		(net "GND")
	)
	(via
		(at 444.885572 -397.811244)
		(size 0.49022)
		(drill 0.254)
		(layers "F.Cu" "B.Cu")
		(net "GND")
	)
	(via
		(at 160.70453 -347.003878)
		(size 0.508)
		(drill 0.254)
		(layers "F.Cu" "B.Cu")
		(net "GND")
	)
	(via
		(at 199.8218 -275.960332)
		(size 0.4826)
		(drill 0.254)
		(layers "F.Cu" "B.Cu")
		(net "GND")
	)
	(via
		(at 295.724072 -279.785064)
		(size 0.4826)
		(drill 0.254)
		(layers "F.Cu" "B.Cu")
		(net "GND")
	)
	(via
		(at 99.390962 -274.08632)
		(size 0.4064)
		(drill 0.2032)
		(layers "F.Cu" "B.Cu")
		(net "GND")
	)
	(via
		(at 450.529452 -424.93311)
		(size 0.508)
		(drill 0.254)
		(layers "F.Cu" "B.Cu")
		(net "GND")
	)
	(via
		(at 402.587714 -421.586152)
		(size 0.4572)
		(drill 0.254)
		(layers "F.Cu" "B.Cu")
		(net "GND")
	)
	(via
		(at 191.677036 -26.743152)
		(size 0.508)
		(drill 0.254)
		(layers "F.Cu" "B.Cu")
		(net "GND")
	)
	(via
		(at 284.63113 -419.617398)
		(size 0.4572)
		(drill 0.254)
		(layers "F.Cu" "B.Cu")
		(net "GND")
	)
	(via
		(at 56.259222 -171.934124)
		(size 0.508)
		(drill 0.254)
		(layers "F.Cu" "B.Cu")
		(net "GND")
	)
	(via
		(at 192.577466 -376.440446)
		(size 0.508)
		(drill 0.254)
		(layers "F.Cu" "B.Cu")
		(net "GND")
	)
	(via
		(at 386.516372 -400.212814)
		(size 0.4064)
		(drill 0.2032)
		(layers "F.Cu" "B.Cu")
		(net "GND")
	)
	(via
		(at 386.804916 -265.986006)
		(size 0.4064)
		(drill 0.2032)
		(layers "F.Cu" "B.Cu")
		(net "GND")
	)
	(via
		(at 88.306402 -386.449062)
		(size 0.4064)
		(drill 0.2032)
		(layers "F.Cu" "B.Cu")
		(net "GND")
	)
	(via
		(at 368.004852 -288.66592)
		(size 0.4064)
		(drill 0.2032)
		(layers "F.Cu" "B.Cu")
		(net "GND")
	)
	(via
		(at 62.776354 -371.49913)
		(size 0.508)
		(drill 0.254)
		(layers "F.Cu" "B.Cu")
		(net "GND")
	)
	(via
		(at 46.666404 -202.010264)
		(size 0.4826)
		(drill 0.254)
		(layers "F.Cu" "B.Cu")
		(net "GND")
	)
	(via
		(at 82.001106 -266.796266)
		(size 0.4064)
		(drill 0.2032)
		(layers "F.Cu" "B.Cu")
		(net "GND")
	)
	(via
		(at 282.020264 -212.635084)
		(size 0.4826)
		(drill 0.254)
		(layers "F.Cu" "B.Cu")
		(net "GND")
	)
	(via
		(at 265.54811 -225.385122)
		(size 0.4826)
		(drill 0.254)
		(layers "F.Cu" "B.Cu")
		(net "GND")
	)
	(via
		(at 128.349756 -428.851314)
		(size 0.4572)
		(drill 0.2032)
		(layers "F.Cu" "B.Cu")
		(net "GND")
	)
	(via
		(at 467.5378 -88.443054)
		(size 0.508)
		(drill 0.254)
		(layers "F.Cu" "B.Cu")
		(net "GND")
	)
	(via
		(at 26.024078 -17.61236)
		(size 0.508)
		(drill 0.254)
		(layers "F.Cu" "B.Cu")
		(net "GND")
	)
	(via
		(at 326.617076 -387.703568)
		(size 0.508)
		(drill 0.254)
		(layers "F.Cu" "B.Cu")
		(net "GND")
	)
	(via
		(at 241.767106 -206.43342)
		(size 0.508)
		(drill 0.254)
		(layers "F.Cu" "B.Cu")
		(net "GND")
	)
	(via
		(at 287.216088 -417.005262)
		(size 0.4572)
		(drill 0.254)
		(layers "F.Cu" "B.Cu")
		(net "GND")
	)
	(via
		(at 415.406078 -161.779458)
		(size 0.49022)
		(drill 0.254)
		(layers "F.Cu" "B.Cu")
		(net "GND")
	)
	(via
		(at 413.349694 -430.147222)
		(size 0.4572)
		(drill 0.2032)
		(layers "F.Cu" "B.Cu")
		(net "GND")
	)
	(via
		(at 128.994662 -286.23641)
		(size 0.4064)
		(drill 0.2032)
		(layers "F.Cu" "B.Cu")
		(net "GND")
	)
	(via
		(at 47.784004 -300.185328)
		(size 0.4826)
		(drill 0.254)
		(layers "F.Cu" "B.Cu")
		(net "GND")
	)
	(via
		(at 100.409502 -369.03533)
		(size 0.508)
		(drill 0.254)
		(layers "F.Cu" "B.Cu")
		(net "GND")
	)
	(via
		(at 407.445718 -10.16508)
		(size 0.508)
		(drill 0.254)
		(layers "F.Cu" "B.Cu")
		(net "GND")
	)
	(via
		(at 91.871038 -270.846296)
		(size 0.4064)
		(drill 0.2032)
		(layers "F.Cu" "B.Cu")
		(net "GND")
	)
	(via
		(at 432.67376 -219.860114)
		(size 0.4826)
		(drill 0.254)
		(layers "F.Cu" "B.Cu")
		(net "GND")
	)
	(via
		(at 182.308246 -420.349934)
		(size 0.508)
		(drill 0.254)
		(layers "F.Cu" "B.Cu")
		(net "GND")
	)
	(via
		(at 249.721624 -278.640032)
		(size 0.508)
		(drill 0.254)
		(layers "F.Cu" "B.Cu")
		(net "GND")
	)
	(via
		(at 21.70811 -255.13538)
		(size 0.4826)
		(drill 0.254)
		(layers "F.Cu" "B.Cu")
		(net "GND")
	)
	(via
		(at 353.141026 -238.004096)
		(size 0.4064)
		(drill 0.2032)
		(layers "F.Cu" "B.Cu")
		(net "GND")
	)
	(via
		(at 388.68477 -287.045908)
		(size 0.4064)
		(drill 0.2032)
		(layers "F.Cu" "B.Cu")
		(net "GND")
	)
	(via
		(at 248.132092 -422.15181)
		(size 0.508)
		(drill 0.254)
		(layers "F.Cu" "B.Cu")
		(net "GND")
	)
	(via
		(at 111.610394 -186.981338)
		(size 0.508)
		(drill 0.254)
		(layers "F.Cu" "B.Cu")
		(net "GND")
	)
	(via
		(at 55.016654 -391.830814)
		(size 0.4064)
		(drill 0.2032)
		(layers "F.Cu" "B.Cu")
		(net "GND")
	)
	(via
		(at 40.255698 -10.16508)
		(size 0.508)
		(drill 0.254)
		(layers "F.Cu" "B.Cu")
		(net "GND")
	)
	(via
		(at 268.263878 -239.835182)
		(size 0.4826)
		(drill 0.254)
		(layers "F.Cu" "B.Cu")
		(net "GND")
	)
	(via
		(at 351.728024 -253.392178)
		(size 0.4064)
		(drill 0.2032)
		(layers "F.Cu" "B.Cu")
		(net "GND")
	)
	(via
		(at 16.972788 -371.36705)
		(size 0.508)
		(drill 0.254)
		(layers "F.Cu" "B.Cu")
		(net "GND")
	)
	(via
		(at 353.005644 -377.41733)
		(size 0.508)
		(drill 0.254)
		(layers "F.Cu" "B.Cu")
		(net "GND")
	)
	(via
		(at 420.158164 -12.37488)
		(size 0.508)
		(drill 0.254)
		(layers "F.Cu" "B.Cu")
		(net "GND")
	)
	(via
		(at 454.188068 -299.33519)
		(size 0.4826)
		(drill 0.254)
		(layers "F.Cu" "B.Cu")
		(net "GND")
	)
	(via
		(at 25.152096 -245.785386)
		(size 0.4826)
		(drill 0.254)
		(layers "F.Cu" "B.Cu")
		(net "GND")
	)
	(via
		(at 450.088 -290.83508)
		(size 0.4826)
		(drill 0.254)
		(layers "F.Cu" "B.Cu")
		(net "GND")
	)
	(via
		(at 134.164832 -275.706332)
		(size 0.4064)
		(drill 0.2032)
		(layers "F.Cu" "B.Cu")
		(net "GND")
	)
	(via
		(at 420.155624 -10.16508)
		(size 0.508)
		(drill 0.254)
		(layers "F.Cu" "B.Cu")
		(net "GND")
	)
	(via
		(at 357.527098 -167.507666)
		(size 0.49022)
		(drill 0.254)
		(layers "F.Cu" "B.Cu")
		(net "GND")
	)
	(via
		(at 403.280118 -171.177712)
		(size 0.508)
		(drill 0.254)
		(layers "F.Cu" "B.Cu")
		(net "GND")
	)
	(via
		(at 345.621102 -254.204216)
		(size 0.4064)
		(drill 0.2032)
		(layers "F.Cu" "B.Cu")
		(net "GND")
	)
	(via
		(at 41.363392 -426.556678)
		(size 0.508)
		(drill 0.254)
		(layers "F.Cu" "B.Cu")
		(net "GND")
	)
	(via
		(at 371.764814 -293.525956)
		(size 0.4064)
		(drill 0.2032)
		(layers "F.Cu" "B.Cu")
		(net "GND")
	)
	(via
		(at 189.775846 -284.035246)
		(size 0.4826)
		(drill 0.254)
		(layers "F.Cu" "B.Cu")
		(net "GND")
	)
	(via
		(at 101.143054 -393.335002)
		(size 0.508)
		(drill 0.254)
		(layers "F.Cu" "B.Cu")
		(net "GND")
	)
	(via
		(at 350.151192 -274.086066)
		(size 0.4064)
		(drill 0.2032)
		(layers "F.Cu" "B.Cu")
		(net "GND")
	)
	(via
		(at 289.564318 -284.88513)
		(size 0.4826)
		(drill 0.254)
		(layers "F.Cu" "B.Cu")
		(net "GND")
	)
	(via
		(at 428.840392 -296.78503)
		(size 0.4826)
		(drill 0.254)
		(layers "F.Cu" "B.Cu")
		(net "GND")
	)
	(via
		(at 364.24489 -275.706078)
		(size 0.4064)
		(drill 0.2032)
		(layers "F.Cu" "B.Cu")
		(net "GND")
	)
	(via
		(at 435.000146 -264.48512)
		(size 0.4826)
		(drill 0.254)
		(layers "F.Cu" "B.Cu")
		(net "GND")
	)
	(via
		(at 236.676692 -421.833548)
		(size 0.508)
		(drill 0.254)
		(layers "F.Cu" "B.Cu")
		(net "GND")
	)
	(via
		(at 21.70811 -288.285428)
		(size 0.4826)
		(drill 0.254)
		(layers "F.Cu" "B.Cu")
		(net "GND")
	)
	(via
		(at 391.204704 -245.29415)
		(size 0.4064)
		(drill 0.2032)
		(layers "F.Cu" "B.Cu")
		(net "GND")
	)
	(via
		(at 136.684766 -250.15444)
		(size 0.4064)
		(drill 0.2032)
		(layers "F.Cu" "B.Cu")
		(net "GND")
	)
	(via
		(at 347.50121 -226.664266)
		(size 0.4064)
		(drill 0.2032)
		(layers "F.Cu" "B.Cu")
		(net "GND")
	)
	(via
		(at 151.34971 -431.451258)
		(size 0.4572)
		(drill 0.2032)
		(layers "F.Cu" "B.Cu")
		(net "GND")
	)
	(via
		(at 41.450768 -351.736406)
		(size 0.508)
		(drill 0.254)
		(layers "F.Cu" "B.Cu")
		(net "GND")
	)
	(via
		(at 284.736032 -280.634948)
		(size 0.4826)
		(drill 0.254)
		(layers "F.Cu" "B.Cu")
		(net "GND")
	)
	(via
		(at 122.584718 -255.014476)
		(size 0.4064)
		(drill 0.2032)
		(layers "F.Cu" "B.Cu")
		(net "GND")
	)
	(via
		(at 157.349698 -433.747164)
		(size 0.4572)
		(drill 0.2032)
		(layers "F.Cu" "B.Cu")
		(net "GND")
	)
	(via
		(at 404.118064 -6.091174)
		(size 0.508)
		(drill 0.254)
		(layers "F.Cu" "B.Cu")
		(net "GND")
	)
	(via
		(at 147.349718 -437.49976)
		(size 0.4572)
		(drill 0.2032)
		(layers "F.Cu" "B.Cu")
		(net "GND")
	)
	(via
		(at 334.331564 -143.386556)
		(size 0.508)
		(drill 0.254)
		(layers "F.Cu" "B.Cu")
		(net "GND")
	)
	(via
		(at 415.312352 -193.99631)
		(size 0.4826)
		(drill 0.254)
		(layers "F.Cu" "B.Cu")
		(net "GND")
	)
	(via
		(at 23.568914 -340.690708)
		(size 0.508)
		(drill 0.254)
		(layers "F.Cu" "B.Cu")
		(net "GND")
	)
	(via
		(at 294.606472 -239.41024)
		(size 0.4826)
		(drill 0.254)
		(layers "F.Cu" "B.Cu")
		(net "GND")
	)
	(via
		(at 442.5442 -204.985112)
		(size 0.4826)
		(drill 0.254)
		(layers "F.Cu" "B.Cu")
		(net "GND")
	)
	(via
		(at 55.328058 -264.485374)
		(size 0.4826)
		(drill 0.254)
		(layers "F.Cu" "B.Cu")
		(net "GND")
	)
	(via
		(at 50.766472 -275.960332)
		(size 0.4826)
		(drill 0.254)
		(layers "F.Cu" "B.Cu")
		(net "GND")
	)
	(via
		(at 323.249544 -430.299622)
		(size 0.4572)
		(drill 0.2032)
		(layers "F.Cu" "B.Cu")
		(net "GND")
	)
	(via
		(at 244.870732 -318.052958)
		(size 0.508)
		(drill 0.254)
		(layers "F.Cu" "B.Cu")
		(net "GND")
	)
	(via
		(at 25.152096 -197.335394)
		(size 0.4826)
		(drill 0.254)
		(layers "F.Cu" "B.Cu")
		(net "GND")
	)
	(via
		(at 43.85564 -7.215124)
		(size 0.508)
		(drill 0.254)
		(layers "F.Cu" "B.Cu")
		(net "GND")
	)
	(via
		(at 105.500932 -279.756362)
		(size 0.4064)
		(drill 0.2032)
		(layers "F.Cu" "B.Cu")
		(net "GND")
	)
	(via
		(at 46.507654 -339.814662)
		(size 0.508)
		(drill 0.254)
		(layers "F.Cu" "B.Cu")
		(net "GND")
	)
	(via
		(at 364.573058 -175.782986)
		(size 0.49022)
		(drill 0.254)
		(layers "F.Cu" "B.Cu")
		(net "GND")
	)
	(via
		(at 390.094724 -294.335962)
		(size 0.4064)
		(drill 0.2032)
		(layers "F.Cu" "B.Cu")
		(net "GND")
	)
	(via
		(at 165.812216 -315.485272)
		(size 0.4826)
		(drill 0.254)
		(layers "F.Cu" "B.Cu")
		(net "GND")
	)
	(via
		(at 276.074632 -201.160126)
		(size 0.4826)
		(drill 0.254)
		(layers "F.Cu" "B.Cu")
		(net "GND")
	)
	(via
		(at 344.950034 -417.778184)
		(size 0.4572)
		(drill 0.254)
		(layers "F.Cu" "B.Cu")
		(net "GND")
	)
	(via
		(at 78.711044 -272.466308)
		(size 0.4064)
		(drill 0.2032)
		(layers "F.Cu" "B.Cu")
		(net "GND")
	)
	(via
		(at 359.387902 -256.387346)
		(size 0.4826)
		(drill 0.254)
		(layers "F.Cu" "B.Cu")
		(net "GND")
	)
	(via
		(at 159.483044 -369.03533)
		(size 0.508)
		(drill 0.254)
		(layers "F.Cu" "B.Cu")
		(net "GND")
	)
	(via
		(at 102.154736 -128.803654)
		(size 0.508)
		(drill 0.254)
		(layers "F.Cu" "B.Cu")
		(net "GND")
	)
	(via
		(at 327.937876 -385.514088)
		(size 0.508)
		(drill 0.254)
		(layers "F.Cu" "B.Cu")
		(net "GND")
	)
	(via
		(at 325.24954 -430.147222)
		(size 0.4572)
		(drill 0.2032)
		(layers "F.Cu" "B.Cu")
		(net "GND")
	)
	(via
		(at 182.278782 -350.896428)
		(size 0.49022)
		(drill 0.254)
		(layers "F.Cu" "B.Cu")
		(net "GND")
	)
	(via
		(at 378.81814 -295.983406)
		(size 0.4064)
		(drill 0.2032)
		(layers "F.Cu" "B.Cu")
		(net "GND")
	)
	(via
		(at 378.814838 -265.176)
		(size 0.4064)
		(drill 0.2032)
		(layers "F.Cu" "B.Cu")
		(net "GND")
	)
	(via
		(at 375.054876 -268.416024)
		(size 0.4064)
		(drill 0.2032)
		(layers "F.Cu" "B.Cu")
		(net "GND")
	)
	(via
		(at 374.584722 -277.32609)
		(size 0.4064)
		(drill 0.2032)
		(layers "F.Cu" "B.Cu")
		(net "GND")
	)
	(via
		(at 191.160146 -306.985416)
		(size 0.4826)
		(drill 0.254)
		(layers "F.Cu" "B.Cu")
		(net "GND")
	)
	(via
		(at 396.349474 -427.699678)
		(size 0.4572)
		(drill 0.2032)
		(layers "F.Cu" "B.Cu")
		(net "GND")
	)
	(via
		(at 277.357586 -344.781124)
		(size 0.49022)
		(drill 0.254)
		(layers "F.Cu" "B.Cu")
		(net "GND")
	)
	(via
		(at 66.52387 -168.36263)
		(size 0.49022)
		(drill 0.254)
		(layers "F.Cu" "B.Cu")
		(net "GND")
	)
	(via
		(at 427.17212 -347.870526)
		(size 0.508)
		(drill 0.254)
		(layers "F.Cu" "B.Cu")
		(net "GND")
	)
	(via
		(at 118.184676 -291.906198)
		(size 0.4064)
		(drill 0.2032)
		(layers "F.Cu" "B.Cu")
		(net "GND")
	)
	(via
		(at 138.864848 -283.806392)
		(size 0.4064)
		(drill 0.2032)
		(layers "F.Cu" "B.Cu")
		(net "GND")
	)
	(via
		(at 130.349752 -427.851316)
		(size 0.4572)
		(drill 0.2032)
		(layers "F.Cu" "B.Cu")
		(net "GND")
	)
	(via
		(at 382.1049 -265.986006)
		(size 0.4064)
		(drill 0.2032)
		(layers "F.Cu" "B.Cu")
		(net "GND")
	)
	(via
		(at 307.368194 -289.985196)
		(size 0.4826)
		(drill 0.254)
		(layers "F.Cu" "B.Cu")
		(net "GND")
	)
	(via
		(at 21.747734 -394.200126)
		(size 0.508)
		(drill 0.254)
		(layers "F.Cu" "B.Cu")
		(net "GND")
	)
	(via
		(at 59.428126 -215.185244)
		(size 0.4826)
		(drill 0.254)
		(layers "F.Cu" "B.Cu")
		(net "GND")
	)
	(via
		(at 379.924818 -256.634234)
		(size 0.4064)
		(drill 0.2032)
		(layers "F.Cu" "B.Cu")
		(net "GND")
	)
	(via
		(at 51.884072 -267.03528)
		(size 0.4826)
		(drill 0.254)
		(layers "F.Cu" "B.Cu")
		(net "GND")
	)
	(via
		(at 370.524786 -232.334054)
		(size 0.4064)
		(drill 0.2032)
		(layers "F.Cu" "B.Cu")
		(net "GND")
	)
	(via
		(at 83.111086 -245.294404)
		(size 0.4064)
		(drill 0.2032)
		(layers "F.Cu" "B.Cu")
		(net "GND")
	)
	(via
		(at 419.81374 -103.480108)
		(size 0.508)
		(drill 0.254)
		(layers "F.Cu" "B.Cu")
		(net "GND")
	)
	(via
		(at 195.83146 -343.405714)
		(size 0.508)
		(drill 0.254)
		(layers "F.Cu" "B.Cu")
		(net "GND")
	)
	(via
		(at 379.924818 -245.29415)
		(size 0.4064)
		(drill 0.2032)
		(layers "F.Cu" "B.Cu")
		(net "GND")
	)
	(via
		(at 48.054514 -342.816434)
		(size 0.508)
		(drill 0.254)
		(layers "F.Cu" "B.Cu")
		(net "GND")
	)
	(via
		(at 434.838348 -347.235526)
		(size 0.508)
		(drill 0.254)
		(layers "F.Cu" "B.Cu")
		(net "GND")
	)
	(via
		(at 145.444718 -265.98626)
		(size 0.4064)
		(drill 0.2032)
		(layers "F.Cu" "B.Cu")
		(net "GND")
	)
	(via
		(at 143.349726 -429.147224)
		(size 0.4572)
		(drill 0.2032)
		(layers "F.Cu" "B.Cu")
		(net "GND")
	)
	(via
		(at 182.67553 -52.884578)
		(size 0.508)
		(drill 0.254)
		(layers "F.Cu" "B.Cu")
		(net "GND")
	)
	(via
		(at 107.550966 -248.534428)
		(size 0.4064)
		(drill 0.2032)
		(layers "F.Cu" "B.Cu")
		(net "GND")
	)
	(via
		(at 132.284724 -261.126224)
		(size 0.4064)
		(drill 0.2032)
		(layers "F.Cu" "B.Cu")
		(net "GND")
	)
	(via
		(at 134.164832 -272.466308)
		(size 0.4064)
		(drill 0.2032)
		(layers "F.Cu" "B.Cu")
		(net "GND")
	)
	(via
		(at 167.143684 -305.285394)
		(size 0.4826)
		(drill 0.254)
		(layers "F.Cu" "B.Cu")
		(net "GND")
	)
	(via
		(at 176.072038 -241.535204)
		(size 0.4826)
		(drill 0.254)
		(layers "F.Cu" "B.Cu")
		(net "GND")
	)
	(via
		(at 2.76225 -272.217134)
		(size 0.508)
		(drill 0.254)
		(layers "F.Cu" "B.Cu")
		(net "GND")
	)
	(via
		(at 350.621092 -282.996132)
		(size 0.4064)
		(drill 0.2032)
		(layers "F.Cu" "B.Cu")
		(net "GND")
	)
	(via
		(at 451.098666 -395.42847)
		(size 0.508)
		(drill 0.254)
		(layers "F.Cu" "B.Cu")
		(net "GND")
	)
	(via
		(at 93.450918 -225.854514)
		(size 0.4064)
		(drill 0.2032)
		(layers "F.Cu" "B.Cu")
		(net "GND")
	)
	(via
		(at 382.274826 -225.044254)
		(size 0.4064)
		(drill 0.2032)
		(layers "F.Cu" "B.Cu")
		(net "GND")
	)
	(via
		(at 354.660708 -337.350608)
		(size 0.508)
		(drill 0.254)
		(layers "F.Cu" "B.Cu")
		(net "GND")
	)
	(via
		(at 355.111304 -394.831062)
		(size 0.4064)
		(drill 0.2032)
		(layers "F.Cu" "B.Cu")
		(net "GND")
	)
	(via
		(at 388.21487 -266.796012)
		(size 0.4064)
		(drill 0.2032)
		(layers "F.Cu" "B.Cu")
		(net "GND")
	)
	(via
		(at 395.20241 -420.318184)
		(size 0.4572)
		(drill 0.254)
		(layers "F.Cu" "B.Cu")
		(net "GND")
	)
	(via
		(at 90.563954 -328.13752)
		(size 0.508)
		(drill 0.254)
		(layers "F.Cu" "B.Cu")
		(net "GND")
	)
	(via
		(at 464.065366 -376.53087)
		(size 0.508)
		(drill 0.254)
		(layers "F.Cu" "B.Cu")
		(net "GND")
	)
	(via
		(at 57.109614 -4.963414)
		(size 0.508)
		(drill 0.254)
		(layers "F.Cu" "B.Cu")
		(net "GND")
	)
	(via
		(at 369.231418 -38.650164)
		(size 0.508)
		(drill 0.254)
		(layers "F.Cu" "B.Cu")
		(net "GND")
	)
	(via
		(at 349.029274 -162.28949)
		(size 0.49022)
		(drill 0.254)
		(layers "F.Cu" "B.Cu")
		(net "GND")
	)
	(via
		(at 269.648178 -204.134974)
		(size 0.4826)
		(drill 0.254)
		(layers "F.Cu" "B.Cu")
		(net "GND")
	)
	(via
		(at 85.160358 -333.039212)
		(size 0.49022)
		(drill 0.254)
		(layers "F.Cu" "B.Cu")
		(net "GND")
	)
	(via
		(at 91.549982 -74.68362)
		(size 0.508)
		(drill 0.254)
		(layers "F.Cu" "B.Cu")
		(net "GND")
	)
	(via
		(at 129.55651 -160.435798)
		(size 0.508)
		(drill 0.254)
		(layers "F.Cu" "B.Cu")
		(net "GND")
	)
	(via
		(at 163.806378 -386.449062)
		(size 0.4064)
		(drill 0.2032)
		(layers "F.Cu" "B.Cu")
		(net "GND")
	)
	(via
		(at 213.995 -330.708)
		(size 0.508)
		(drill 0.254)
		(layers "F.Cu" "B.Cu")
		(net "GND")
	)
	(via
		(at 159.726122 -6.042152)
		(size 0.508)
		(drill 0.254)
		(layers "F.Cu" "B.Cu")
		(net "GND")
	)
	(via
		(at 317.249556 -437.34736)
		(size 0.4572)
		(drill 0.2032)
		(layers "F.Cu" "B.Cu")
		(net "GND")
	)
	(via
		(at 269.648178 -291.684964)
		(size 0.4826)
		(drill 0.254)
		(layers "F.Cu" "B.Cu")
		(net "GND")
	)
	(via
		(at 415.831274 -165.70706)
		(size 0.49022)
		(drill 0.254)
		(layers "F.Cu" "B.Cu")
		(net "GND")
	)
	(via
		(at 138.651742 -81.069942)
		(size 0.508)
		(drill 0.254)
		(layers "F.Cu" "B.Cu")
		(net "GND")
	)
	(via
		(at 306.781454 -342.52535)
		(size 0.6604)
		(drill 0.3302)
		(layers "F.Cu" "B.Cu")
		(net "GND")
	)
	(via
		(at 355.791008 -274.086066)
		(size 0.4064)
		(drill 0.2032)
		(layers "F.Cu" "B.Cu")
		(net "GND")
	)
	(via
		(at 83.41106 -278.946356)
		(size 0.4064)
		(drill 0.2032)
		(layers "F.Cu" "B.Cu")
		(net "GND")
	)
	(via
		(at 96.571054 -278.946356)
		(size 0.4064)
		(drill 0.2032)
		(layers "F.Cu" "B.Cu")
		(net "GND")
	)
	(via
		(at 74.064622 -388.468108)
		(size 0.508)
		(drill 0.254)
		(layers "F.Cu" "B.Cu")
		(net "GND")
	)
	(via
		(at 97.211134 -246.914416)
		(size 0.4064)
		(drill 0.2032)
		(layers "F.Cu" "B.Cu")
		(net "GND")
	)
	(via
		(at 277.192232 -226.235006)
		(size 0.4826)
		(drill 0.254)
		(layers "F.Cu" "B.Cu")
		(net "GND")
	)
	(via
		(at 116.774722 -292.716204)
		(size 0.4064)
		(drill 0.2032)
		(layers "F.Cu" "B.Cu")
		(net "GND")
	)
	(via
		(at 187.356496 -25.109932)
		(size 0.508)
		(drill 0.254)
		(layers "F.Cu" "B.Cu")
		(net "GND")
	)
	(via
		(at 165.583616 -194.885564)
		(size 0.4826)
		(drill 0.254)
		(layers "F.Cu" "B.Cu")
		(net "GND")
	)
	(via
		(at 388.68477 -291.905944)
		(size 0.4064)
		(drill 0.2032)
		(layers "F.Cu" "B.Cu")
		(net "GND")
	)
	(via
		(at 342.249506 -432.451256)
		(size 0.4572)
		(drill 0.2032)
		(layers "F.Cu" "B.Cu")
		(net "GND")
	)
	(via
		(at 12.661392 -133.14934)
		(size 0.508)
		(drill 0.254)
		(layers "F.Cu" "B.Cu")
		(net "GND")
	)
	(via
		(at 295.724072 -292.535102)
		(size 0.4826)
		(drill 0.254)
		(layers "F.Cu" "B.Cu")
		(net "GND")
	)
	(via
		(at 143.524478 -405.098504)
		(size 0.4572)
		(drill 0.254)
		(layers "F.Cu" "B.Cu")
		(net "GND")
	)
	(via
		(at 376.82297 -412.212536)
		(size 0.4572)
		(drill 0.254)
		(layers "F.Cu" "B.Cu")
		(net "GND")
	)
	(via
		(at 268.651736 -343.083896)
		(size 0.49022)
		(drill 0.254)
		(layers "F.Cu" "B.Cu")
		(net "GND")
	)
	(via
		(at 139.974828 -238.00435)
		(size 0.4064)
		(drill 0.2032)
		(layers "F.Cu" "B.Cu")
		(net "GND")
	)
	(via
		(at 307.368194 -255.135126)
		(size 0.4826)
		(drill 0.254)
		(layers "F.Cu" "B.Cu")
		(net "GND")
	)
	(via
		(at 109.731048 -265.98626)
		(size 0.4064)
		(drill 0.2032)
		(layers "F.Cu" "B.Cu")
		(net "GND")
	)
	(via
		(at 2.76225 -177.221134)
		(size 0.508)
		(drill 0.254)
		(layers "F.Cu" "B.Cu")
		(net "GND")
	)
	(via
		(at 410.51861 -421.586152)
		(size 0.4572)
		(drill 0.254)
		(layers "F.Cu" "B.Cu")
		(net "GND")
	)
	(via
		(at 325.052944 -290.83)
		(size 0.4064)
		(drill 0.2032)
		(layers "F.Cu" "B.Cu")
		(net "GND")
	)
	(via
		(at 141.274038 -390.953498)
		(size 0.508)
		(drill 0.254)
		(layers "F.Cu" "B.Cu")
		(net "GND")
	)
	(via
		(at 307.368194 -288.285174)
		(size 0.4826)
		(drill 0.254)
		(layers "F.Cu" "B.Cu")
		(net "GND")
	)
	(via
		(at 443.6618 -202.01001)
		(size 0.4826)
		(drill 0.254)
		(layers "F.Cu" "B.Cu")
		(net "GND")
	)
	(via
		(at 357.142796 -401.717002)
		(size 0.508)
		(drill 0.254)
		(layers "F.Cu" "B.Cu")
		(net "GND")
	)
	(via
		(at 114.74196 -351.04578)
		(size 0.6604)
		(drill 0.3302)
		(layers "F.Cu" "B.Cu")
		(net "GND")
	)
	(via
		(at 127.284734 -233.95432)
		(size 0.4064)
		(drill 0.2032)
		(layers "F.Cu" "B.Cu")
		(net "GND")
	)
	(via
		(at 269.648178 -310.384952)
		(size 0.4826)
		(drill 0.254)
		(layers "F.Cu" "B.Cu")
		(net "GND")
	)
	(via
		(at 303.268126 -279.785064)
		(size 0.4826)
		(drill 0.254)
		(layers "F.Cu" "B.Cu")
		(net "GND")
	)
	(via
		(at 134.164832 -264.366248)
		(size 0.4064)
		(drill 0.2032)
		(layers "F.Cu" "B.Cu")
		(net "GND")
	)
	(via
		(at 381.334772 -225.044254)
		(size 0.4064)
		(drill 0.2032)
		(layers "F.Cu" "B.Cu")
		(net "GND")
	)
	(via
		(at 161.3408 -105.51795)
		(size 0.508)
		(drill 0.254)
		(layers "F.Cu" "B.Cu")
		(net "GND")
	)
	(via
		(at 30.44317 -366.030256)
		(size 0.508)
		(drill 0.254)
		(layers "F.Cu" "B.Cu")
		(net "GND")
	)
	(via
		(at 121.004838 -291.906198)
		(size 0.4064)
		(drill 0.2032)
		(layers "F.Cu" "B.Cu")
		(net "GND")
	)
	(via
		(at 183.616092 -232.18521)
		(size 0.4826)
		(drill 0.254)
		(layers "F.Cu" "B.Cu")
		(net "GND")
	)
	(via
		(at 101.50475 -121.696226)
		(size 0.508)
		(drill 0.254)
		(layers "F.Cu" "B.Cu")
		(net "GND")
	)
	(via
		(at 390.564878 -293.525956)
		(size 0.4064)
		(drill 0.2032)
		(layers "F.Cu" "B.Cu")
		(net "GND")
	)
	(via
		(at 79.821024 -221.804484)
		(size 0.4064)
		(drill 0.2032)
		(layers "F.Cu" "B.Cu")
		(net "GND")
	)
	(via
		(at 223.829118 -276.366478)
		(size 0.508)
		(drill 0.254)
		(layers "F.Cu" "B.Cu")
		(net "GND")
	)
	(via
		(at 291.916612 -403.721062)
		(size 0.508)
		(drill 0.254)
		(layers "F.Cu" "B.Cu")
		(net "GND")
	)
	(via
		(at 457.21016 -41.755822)
		(size 0.508)
		(drill 0.254)
		(layers "F.Cu" "B.Cu")
		(net "GND")
	)
	(via
		(at 361.124754 -233.954066)
		(size 0.4064)
		(drill 0.2032)
		(layers "F.Cu" "B.Cu")
		(net "GND")
	)
	(via
		(at 399.693638 -393.04468)
		(size 0.508)
		(drill 0.254)
		(layers "F.Cu" "B.Cu")
		(net "GND")
	)
	(via
		(at 33.02 -436.7403)
		(size 0.508)
		(drill 0.254)
		(layers "F.Cu" "B.Cu")
		(net "GND")
	)
	(via
		(at 431.55616 -232.184956)
		(size 0.4826)
		(drill 0.254)
		(layers "F.Cu" "B.Cu")
		(net "GND")
	)
	(via
		(at 387.914896 -247.724168)
		(size 0.4064)
		(drill 0.2032)
		(layers "F.Cu" "B.Cu")
		(net "GND")
	)
	(via
		(at 138.564874 -246.914416)
		(size 0.4064)
		(drill 0.2032)
		(layers "F.Cu" "B.Cu")
		(net "GND")
	)
	(via
		(at 265.54811 -318.885062)
		(size 0.4826)
		(drill 0.254)
		(layers "F.Cu" "B.Cu")
		(net "GND")
	)
	(via
		(at 59.428126 -233.885232)
		(size 0.4826)
		(drill 0.254)
		(layers "F.Cu" "B.Cu")
		(net "GND")
	)
	(via
		(at 307.368194 -241.53495)
		(size 0.4826)
		(drill 0.254)
		(layers "F.Cu" "B.Cu")
		(net "GND")
	)
	(via
		(at 250.62688 -36.882324)
		(size 0.508)
		(drill 0.254)
		(layers "F.Cu" "B.Cu")
		(net "GND")
	)
	(via
		(at 428.840392 -203.28509)
		(size 0.4826)
		(drill 0.254)
		(layers "F.Cu" "B.Cu")
		(net "GND")
	)
	(via
		(at 160.644332 -393.927838)
		(size 0.4572)
		(drill 0.254)
		(layers "F.Cu" "B.Cu")
		(net "GND")
	)
	(via
		(at 83.111086 -230.71455)
		(size 0.4064)
		(drill 0.2032)
		(layers "F.Cu" "B.Cu")
		(net "GND")
	)
	(via
		(at 358.311196 -222.614236)
		(size 0.4064)
		(drill 0.2032)
		(layers "F.Cu" "B.Cu")
		(net "GND")
	)
	(via
		(at 413.752284 -306.135024)
		(size 0.4826)
		(drill 0.254)
		(layers "F.Cu" "B.Cu")
		(net "GND")
	)
	(via
		(at 91.571064 -240.434368)
		(size 0.4064)
		(drill 0.2032)
		(layers "F.Cu" "B.Cu")
		(net "GND")
	)
	(via
		(at 339.888068 -300.137068)
		(size 0.508)
		(drill 0.254)
		(layers "F.Cu" "B.Cu")
		(net "GND")
	)
	(via
		(at 236.45495 -218.67495)
		(size 0.508)
		(drill 0.254)
		(layers "F.Cu" "B.Cu")
		(net "GND")
	)
	(via
		(at 8.556244 -97.521776)
		(size 0.508)
		(drill 0.254)
		(layers "F.Cu" "B.Cu")
		(net "GND")
	)
	(via
		(at 215.937084 -386.400294)
		(size 0.508)
		(drill 0.254)
		(layers "F.Cu" "B.Cu")
		(net "GND")
	)
	(via
		(at 77.069442 -368.37493)
		(size 0.508)
		(drill 0.254)
		(layers "F.Cu" "B.Cu")
		(net "GND")
	)
	(via
		(at 234.47375 -288.809684)
		(size 0.508)
		(drill 0.254)
		(layers "F.Cu" "B.Cu")
		(net "GND")
	)
	(via
		(at 65.65138 -196.95414)
		(size 0.508)
		(drill 0.254)
		(layers "F.Cu" "B.Cu")
		(net "GND")
	)
	(via
		(at 133.864858 -248.534428)
		(size 0.4064)
		(drill 0.2032)
		(layers "F.Cu" "B.Cu")
		(net "GND")
	)
	(via
		(at 283.351732 -274.684998)
		(size 0.4826)
		(drill 0.254)
		(layers "F.Cu" "B.Cu")
		(net "GND")
	)
	(via
		(at 435.000146 -216.035128)
		(size 0.4826)
		(drill 0.254)
		(layers "F.Cu" "B.Cu")
		(net "GND")
	)
	(via
		(at 434.004212 -350.677734)
		(size 0.49022)
		(drill 0.254)
		(layers "F.Cu" "B.Cu")
		(net "GND")
	)
	(via
		(at 75.262486 -178.775868)
		(size 0.49022)
		(drill 0.254)
		(layers "F.Cu" "B.Cu")
		(net "GND")
	)
	(via
		(at 331.521054 -225.044254)
		(size 0.4064)
		(drill 0.2032)
		(layers "F.Cu" "B.Cu")
		(net "GND")
	)
	(via
		(at 381.337058 -182.220616)
		(size 0.49022)
		(drill 0.254)
		(layers "F.Cu" "B.Cu")
		(net "GND")
	)
	(via
		(at 57.119774 -358.31399)
		(size 0.508)
		(drill 0.254)
		(layers "F.Cu" "B.Cu")
		(net "GND")
	)
	(via
		(at 344.211148 -238.814102)
		(size 0.4064)
		(drill 0.2032)
		(layers "F.Cu" "B.Cu")
		(net "GND")
	)
	(via
		(at 34.919158 -345.571064)
		(size 0.49022)
		(drill 0.254)
		(layers "F.Cu" "B.Cu")
		(net "GND")
	)
	(via
		(at 363.774736 -278.136096)
		(size 0.4064)
		(drill 0.2032)
		(layers "F.Cu" "B.Cu")
		(net "GND")
	)
	(via
		(at 387.914896 -242.864132)
		(size 0.4064)
		(drill 0.2032)
		(layers "F.Cu" "B.Cu")
		(net "GND")
	)
	(via
		(at 418.07892 -16.979138)
		(size 0.508)
		(drill 0.254)
		(layers "F.Cu" "B.Cu")
		(net "GND")
	)
	(via
		(at 333.230982 -295.145968)
		(size 0.4064)
		(drill 0.2032)
		(layers "F.Cu" "B.Cu")
		(net "GND")
	)
	(via
		(at 388.68477 -290.285932)
		(size 0.4064)
		(drill 0.2032)
		(layers "F.Cu" "B.Cu")
		(net "GND")
	)
	(via
		(at 116.944648 -222.61449)
		(size 0.4064)
		(drill 0.2032)
		(layers "F.Cu" "B.Cu")
		(net "GND")
	)
	(via
		(at 246.047768 -55.775606)
		(size 0.508)
		(drill 0.254)
		(layers "F.Cu" "B.Cu")
		(net "GND")
	)
	(via
		(at 427.499272 -5.597398)
		(size 0.508)
		(drill 0.254)
		(layers "F.Cu" "B.Cu")
		(net "GND")
	)
	(via
		(at 338.550758 -413.480504)
		(size 0.4572)
		(drill 0.254)
		(layers "F.Cu" "B.Cu")
		(net "GND")
	)
	(via
		(at 142.64132 -315.65596)
		(size 0.508)
		(drill 0.254)
		(layers "F.Cu" "B.Cu")
		(net "GND")
	)
	(via
		(at 451.2056 -211.360004)
		(size 0.4826)
		(drill 0.254)
		(layers "F.Cu" "B.Cu")
		(net "GND")
	)
	(via
		(at 311.342786 -420.952168)
		(size 0.4064)
		(drill 0.2032)
		(layers "F.Cu" "B.Cu")
		(net "GND")
	)
	(via
		(at 105.971086 -285.426404)
		(size 0.4064)
		(drill 0.2032)
		(layers "F.Cu" "B.Cu")
		(net "GND")
	)
	(via
		(at 74.882502 -371.49913)
		(size 0.508)
		(drill 0.254)
		(layers "F.Cu" "B.Cu")
		(net "GND")
	)
	(via
		(at 374.16867 -180.755544)
		(size 0.49022)
		(drill 0.254)
		(layers "F.Cu" "B.Cu")
		(net "GND")
	)
	(via
		(at 17.608042 -249.18543)
		(size 0.4826)
		(drill 0.254)
		(layers "F.Cu" "B.Cu")
		(net "GND")
	)
	(via
		(at 444.716154 -54.972458)
		(size 0.508)
		(drill 0.254)
		(layers "F.Cu" "B.Cu")
		(net "GND")
	)
	(via
		(at 202.147932 -318.885316)
		(size 0.4826)
		(drill 0.254)
		(layers "F.Cu" "B.Cu")
		(net "GND")
	)
	(via
		(at 106.611166 -243.674392)
		(size 0.4064)
		(drill 0.2032)
		(layers "F.Cu" "B.Cu")
		(net "GND")
	)
	(via
		(at 83.580986 -250.964446)
		(size 0.4064)
		(drill 0.2032)
		(layers "F.Cu" "B.Cu")
		(net "GND")
	)
	(via
		(at 366.294924 -244.484144)
		(size 0.4064)
		(drill 0.2032)
		(layers "F.Cu" "B.Cu")
		(net "GND")
	)
	(via
		(at 320.444114 -417.778184)
		(size 0.4572)
		(drill 0.254)
		(layers "F.Cu" "B.Cu")
		(net "GND")
	)
	(via
		(at 399.693638 -393.96416)
		(size 0.508)
		(drill 0.254)
		(layers "F.Cu" "B.Cu")
		(net "GND")
	)
	(via
		(at 231.319578 -318.704468)
		(size 0.508)
		(drill 0.254)
		(layers "F.Cu" "B.Cu")
		(net "GND")
	)
	(via
		(at 349.183706 -420.952168)
		(size 0.4064)
		(drill 0.2032)
		(layers "F.Cu" "B.Cu")
		(net "GND")
	)
	(via
		(at 369.594892 -400.15795)
		(size 0.4064)
		(drill 0.2032)
		(layers "F.Cu" "B.Cu")
		(net "GND")
	)
	(via
		(at 49.6062 -430.504092)
		(size 0.508)
		(drill 0.254)
		(layers "F.Cu" "B.Cu")
		(net "GND")
	)
	(via
		(at 128.694688 -231.524302)
		(size 0.4064)
		(drill 0.2032)
		(layers "F.Cu" "B.Cu")
		(net "GND")
	)
	(via
		(at 280.974546 -12.542266)
		(size 0.508)
		(drill 0.254)
		(layers "F.Cu" "B.Cu")
		(net "GND")
	)
	(via
		(at 134.248906 -410.030168)
		(size 0.4064)
		(drill 0.2032)
		(layers "F.Cu" "B.Cu")
		(net "GND")
	)
	(via
		(at 114.83086 -31.497778)
		(size 0.508)
		(drill 0.254)
		(layers "F.Cu" "B.Cu")
		(net "GND")
	)
	(via
		(at 113.184686 -242.05438)
		(size 0.4064)
		(drill 0.2032)
		(layers "F.Cu" "B.Cu")
		(net "GND")
	)
	(via
		(at 419.435534 -417.778184)
		(size 0.4572)
		(drill 0.254)
		(layers "F.Cu" "B.Cu")
		(net "GND")
	)
	(via
		(at 133.864858 -240.434368)
		(size 0.4064)
		(drill 0.2032)
		(layers "F.Cu" "B.Cu")
		(net "GND")
	)
	(via
		(at 115.546886 -336.987134)
		(size 0.508)
		(drill 0.254)
		(layers "F.Cu" "B.Cu")
		(net "GND")
	)
	(via
		(at 127.284734 -227.474526)
		(size 0.4064)
		(drill 0.2032)
		(layers "F.Cu" "B.Cu")
		(net "GND")
	)
	(via
		(at 356.414578 -30.210252)
		(size 0.508)
		(drill 0.254)
		(layers "F.Cu" "B.Cu")
		(net "GND")
	)
	(via
		(at 307.368194 -205.834996)
		(size 0.4826)
		(drill 0.254)
		(layers "F.Cu" "B.Cu")
		(net "GND")
	)
	(via
		(at 338.249514 -428.851314)
		(size 0.4572)
		(drill 0.2032)
		(layers "F.Cu" "B.Cu")
		(net "GND")
	)
	(via
		(at 158.39567 -58.109358)
		(size 0.508)
		(drill 0.254)
		(layers "F.Cu" "B.Cu")
		(net "GND")
	)
	(via
		(at 103.14305 -416.814)
		(size 0.508)
		(drill 0.254)
		(layers "F.Cu" "B.Cu")
		(net "GND")
	)
	(via
		(at 336.249518 -437.49976)
		(size 0.4572)
		(drill 0.2032)
		(layers "F.Cu" "B.Cu")
		(net "GND")
	)
	(via
		(at 101.440996 -252.584458)
		(size 0.4064)
		(drill 0.2032)
		(layers "F.Cu" "B.Cu")
		(net "GND")
	)
	(via
		(at 393.759182 -412.84652)
		(size 0.4064)
		(drill 0.2032)
		(layers "F.Cu" "B.Cu")
		(net "GND")
	)
	(via
		(at 408.628342 -418.412168)
		(size 0.4064)
		(drill 0.2032)
		(layers "F.Cu" "B.Cu")
		(net "GND")
	)
	(via
		(at 135.744712 -224.234502)
		(size 0.4064)
		(drill 0.2032)
		(layers "F.Cu" "B.Cu")
		(net "GND")
	)
	(via
		(at 50.431954 -16.979138)
		(size 0.508)
		(drill 0.254)
		(layers "F.Cu" "B.Cu")
		(net "GND")
	)
	(via
		(at 51.468274 -12.37488)
		(size 0.508)
		(drill 0.254)
		(layers "F.Cu" "B.Cu")
		(net "GND")
	)
	(via
		(at 20.67687 -385.27609)
		(size 0.508)
		(drill 0.254)
		(layers "F.Cu" "B.Cu")
		(net "GND")
	)
	(via
		(at 442.5442 -214.335106)
		(size 0.4826)
		(drill 0.254)
		(layers "F.Cu" "B.Cu")
		(net "GND")
	)
	(via
		(at 137.312146 -407.00452)
		(size 0.4064)
		(drill 0.2032)
		(layers "F.Cu" "B.Cu")
		(net "GND")
	)
	(via
		(at 235.705396 -439.90768)
		(size 0.508)
		(drill 0.254)
		(layers "F.Cu" "B.Cu")
		(net "GND")
	)
	(via
		(at 95.1611 -291.096192)
		(size 0.4064)
		(drill 0.2032)
		(layers "F.Cu" "B.Cu")
		(net "GND")
	)
	(via
		(at 70.03288 -388.892542)
		(size 0.508)
		(drill 0.254)
		(layers "F.Cu" "B.Cu")
		(net "GND")
	)
	(via
		(at 47.784004 -227.085398)
		(size 0.4826)
		(drill 0.254)
		(layers "F.Cu" "B.Cu")
		(net "GND")
	)
	(via
		(at 134.164832 -280.566368)
		(size 0.4064)
		(drill 0.2032)
		(layers "F.Cu" "B.Cu")
		(net "GND")
	)
	(via
		(at 152.986994 -407.638504)
		(size 0.4572)
		(drill 0.254)
		(layers "F.Cu" "B.Cu")
		(net "GND")
	)
	(via
		(at 115.064794 -224.234502)
		(size 0.4064)
		(drill 0.2032)
		(layers "F.Cu" "B.Cu")
		(net "GND")
	)
	(via
		(at 397.599154 -441.227718)
		(size 0.508)
		(drill 0.254)
		(layers "F.Cu" "B.Cu")
		(net "GND")
	)
	(via
		(at 394.929614 -419.046152)
		(size 0.4572)
		(drill 0.254)
		(layers "F.Cu" "B.Cu")
		(net "GND")
	)
	(via
		(at 115.834668 -291.096192)
		(size 0.4064)
		(drill 0.2032)
		(layers "F.Cu" "B.Cu")
		(net "GND")
	)
	(via
		(at 41.36136 -425.265088)
		(size 0.508)
		(drill 0.254)
		(layers "F.Cu" "B.Cu")
		(net "GND")
	)
	(via
		(at 38.374828 -364.909862)
		(size 0.508)
		(drill 0.254)
		(layers "F.Cu" "B.Cu")
		(net "GND")
	)
	(via
		(at 120.550178 -409.396184)
		(size 0.4572)
		(drill 0.254)
		(layers "F.Cu" "B.Cu")
		(net "GND")
	)
	(via
		(at 357.671116 -267.606018)
		(size 0.4064)
		(drill 0.2032)
		(layers "F.Cu" "B.Cu")
		(net "GND")
	)
	(via
		(at 183.616092 -226.23526)
		(size 0.4826)
		(drill 0.254)
		(layers "F.Cu" "B.Cu")
		(net "GND")
	)
	(via
		(at 330.80071 -360.350308)
		(size 0.508)
		(drill 0.254)
		(layers "F.Cu" "B.Cu")
		(net "GND")
	)
	(via
		(at 135.274812 -239.624362)
		(size 0.4064)
		(drill 0.2032)
		(layers "F.Cu" "B.Cu")
		(net "GND")
	)
	(via
		(at 67.249802 -436.347362)
		(size 0.4572)
		(drill 0.2032)
		(layers "F.Cu" "B.Cu")
		(net "GND")
	)
	(via
		(at 71.249794 -437.49976)
		(size 0.4572)
		(drill 0.2032)
		(layers "F.Cu" "B.Cu")
		(net "GND")
	)
	(via
		(at 105.971086 -280.566368)
		(size 0.4064)
		(drill 0.2032)
		(layers "F.Cu" "B.Cu")
		(net "GND")
	)
	(via
		(at 355.491034 -238.814102)
		(size 0.4064)
		(drill 0.2032)
		(layers "F.Cu" "B.Cu")
		(net "GND")
	)
	(via
		(at 85.290914 -280.566368)
		(size 0.4064)
		(drill 0.2032)
		(layers "F.Cu" "B.Cu")
		(net "GND")
	)
	(via
		(at 327.121012 -295.955974)
		(size 0.4064)
		(drill 0.2032)
		(layers "F.Cu" "B.Cu")
		(net "GND")
	)
	(via
		(at 297.430444 -389.25246)
		(size 0.508)
		(drill 0.254)
		(layers "F.Cu" "B.Cu")
		(net "GND")
	)
	(via
		(at 295.536366 -344.132408)
		(size 0.508)
		(drill 0.254)
		(layers "F.Cu" "B.Cu")
		(net "GND")
	)
	(via
		(at 339.511132 -242.054126)
		(size 0.4064)
		(drill 0.2032)
		(layers "F.Cu" "B.Cu")
		(net "GND")
	)
	(via
		(at 62.639956 -409.396184)
		(size 0.4572)
		(drill 0.254)
		(layers "F.Cu" "B.Cu")
		(net "GND")
	)
	(via
		(at 59.51855 -388.328662)
		(size 0.4064)
		(drill 0.2032)
		(layers "F.Cu" "B.Cu")
		(net "GND")
	)
	(via
		(at 386.504942 -222.614236)
		(size 0.4064)
		(drill 0.2032)
		(layers "F.Cu" "B.Cu")
		(net "GND")
	)
	(via
		(at 127.818388 -388.328662)
		(size 0.4064)
		(drill 0.2032)
		(layers "F.Cu" "B.Cu")
		(net "GND")
	)
	(via
		(at 418.690044 -392.999722)
		(size 0.4064)
		(drill 0.2032)
		(layers "F.Cu" "B.Cu")
		(net "GND")
	)
	(via
		(at 206.138526 -98.469196)
		(size 0.508)
		(drill 0.254)
		(layers "F.Cu" "B.Cu")
		(net "GND")
	)
	(via
		(at 404.39213 -412.212536)
		(size 0.4572)
		(drill 0.254)
		(layers "F.Cu" "B.Cu")
		(net "GND")
	)
	(via
		(at 59.428126 -308.685438)
		(size 0.4826)
		(drill 0.254)
		(layers "F.Cu" "B.Cu")
		(net "GND")
	)
	(via
		(at 380.864872 -250.154186)
		(size 0.4064)
		(drill 0.2032)
		(layers "F.Cu" "B.Cu")
		(net "GND")
	)
	(via
		(at 313.828684 -19.124422)
		(size 0.508)
		(drill 0.254)
		(layers "F.Cu" "B.Cu")
		(net "GND")
	)
	(via
		(at 436.384446 -296.78503)
		(size 0.4826)
		(drill 0.254)
		(layers "F.Cu" "B.Cu")
		(net "GND")
	)
	(via
		(at 332.931008 -248.534174)
		(size 0.4064)
		(drill 0.2032)
		(layers "F.Cu" "B.Cu")
		(net "GND")
	)
	(via
		(at 78.41107 -246.914416)
		(size 0.4064)
		(drill 0.2032)
		(layers "F.Cu" "B.Cu")
		(net "GND")
	)
	(via
		(at 79.821024 -228.284532)
		(size 0.4064)
		(drill 0.2032)
		(layers "F.Cu" "B.Cu")
		(net "GND")
	)
	(via
		(at 325.825104 -336.976466)
		(size 0.49022)
		(drill 0.254)
		(layers "F.Cu" "B.Cu")
		(net "GND")
	)
	(via
		(at 180.900324 -284.885384)
		(size 0.4826)
		(drill 0.254)
		(layers "F.Cu" "B.Cu")
		(net "GND")
	)
	(via
		(at 358.141016 -273.27606)
		(size 0.4064)
		(drill 0.2032)
		(layers "F.Cu" "B.Cu")
		(net "GND")
	)
	(via
		(at 43.871134 -362.628434)
		(size 0.508)
		(drill 0.254)
		(layers "F.Cu" "B.Cu")
		(net "GND")
	)
	(via
		(at 103.791004 -250.15444)
		(size 0.4064)
		(drill 0.2032)
		(layers "F.Cu" "B.Cu")
		(net "GND")
	)
	(via
		(at 329.297792 -385.38912)
		(size 0.508)
		(drill 0.254)
		(layers "F.Cu" "B.Cu")
		(net "GND")
	)
	(via
		(at 288.27222 -351.73158)
		(size 0.508)
		(drill 0.254)
		(layers "F.Cu" "B.Cu")
		(net "GND")
	)
	(via
		(at 292.280086 -306.985162)
		(size 0.4826)
		(drill 0.254)
		(layers "F.Cu" "B.Cu")
		(net "GND")
	)
	(via
		(at 364.794546 -12.542266)
		(size 0.508)
		(drill 0.254)
		(layers "F.Cu" "B.Cu")
		(net "GND")
	)
	(via
		(at 381.145034 -413.480504)
		(size 0.4572)
		(drill 0.254)
		(layers "F.Cu" "B.Cu")
		(net "GND")
	)
	(via
		(at 378.814838 -284.616144)
		(size 0.4064)
		(drill 0.2032)
		(layers "F.Cu" "B.Cu")
		(net "GND")
	)
	(via
		(at 420.312596 -356.265226)
		(size 0.508)
		(drill 0.254)
		(layers "F.Cu" "B.Cu")
		(net "GND")
	)
	(via
		(at 384.924808 -283.806138)
		(size 0.4064)
		(drill 0.2032)
		(layers "F.Cu" "B.Cu")
		(net "GND")
	)
	(via
		(at 67.249802 -438.651396)
		(size 0.4572)
		(drill 0.2032)
		(layers "F.Cu" "B.Cu")
		(net "GND")
	)
	(via
		(at 334.64119 -289.475926)
		(size 0.4064)
		(drill 0.2032)
		(layers "F.Cu" "B.Cu")
		(net "GND")
	)
	(via
		(at 347.547946 -362.01096)
		(size 0.508)
		(drill 0.254)
		(layers "F.Cu" "B.Cu")
		(net "GND")
	)
	(via
		(at 357.841042 -241.24412)
		(size 0.4064)
		(drill 0.2032)
		(layers "F.Cu" "B.Cu")
		(net "GND")
	)
	(via
		(at 356.048056 -355.581712)
		(size 0.508)
		(drill 0.254)
		(layers "F.Cu" "B.Cu")
		(net "GND")
	)
	(via
		(at 17.083278 -17.61236)
		(size 0.508)
		(drill 0.254)
		(layers "F.Cu" "B.Cu")
		(net "GND")
	)
	(via
		(at 467.5378 -116.383054)
		(size 0.508)
		(drill 0.254)
		(layers "F.Cu" "B.Cu")
		(net "GND")
	)
	(via
		(at 79.987902 -373.96293)
		(size 0.508)
		(drill 0.254)
		(layers "F.Cu" "B.Cu")
		(net "GND")
	)
	(via
		(at 368.644678 -246.914162)
		(size 0.4064)
		(drill 0.2032)
		(layers "F.Cu" "B.Cu")
		(net "GND")
	)
	(via
		(at 374.754902 -236.384084)
		(size 0.4064)
		(drill 0.2032)
		(layers "F.Cu" "B.Cu")
		(net "GND")
	)
	(via
		(at 334.249522 -438.499758)
		(size 0.4572)
		(drill 0.2032)
		(layers "F.Cu" "B.Cu")
		(net "GND")
	)
	(via
		(at 428.840392 -212.635084)
		(size 0.4826)
		(drill 0.254)
		(layers "F.Cu" "B.Cu")
		(net "GND")
	)
	(via
		(at 329.249532 -432.451256)
		(size 0.4572)
		(drill 0.2032)
		(layers "F.Cu" "B.Cu")
		(net "GND")
	)
	(via
		(at 133.8453 -390.160002)
		(size 0.4064)
		(drill 0.2032)
		(layers "F.Cu" "B.Cu")
		(net "GND")
	)
	(via
		(at 344.249502 -427.851316)
		(size 0.4572)
		(drill 0.2032)
		(layers "F.Cu" "B.Cu")
		(net "GND")
	)
	(via
		(at 136.98474 -278.946356)
		(size 0.4064)
		(drill 0.2032)
		(layers "F.Cu" "B.Cu")
		(net "GND")
	)
	(via
		(at 58.317892 -409.396184)
		(size 0.4572)
		(drill 0.254)
		(layers "F.Cu" "B.Cu")
		(net "GND")
	)
	(via
		(at 378.514864 -255.824228)
		(size 0.4064)
		(drill 0.2032)
		(layers "F.Cu" "B.Cu")
		(net "GND")
	)
	(via
		(at 130.662172 -37.889434)
		(size 0.508)
		(drill 0.254)
		(layers "F.Cu" "B.Cu")
		(net "GND")
	)
	(via
		(at 379.924818 -238.814102)
		(size 0.4064)
		(drill 0.2032)
		(layers "F.Cu" "B.Cu")
		(net "GND")
	)
	(via
		(at 436.384446 -278.085042)
		(size 0.4826)
		(drill 0.254)
		(layers "F.Cu" "B.Cu")
		(net "GND")
	)
	(via
		(at 32.695896 -214.33536)
		(size 0.4826)
		(drill 0.254)
		(layers "F.Cu" "B.Cu")
		(net "GND")
	)
	(via
		(at 372.404894 -242.054126)
		(size 0.4064)
		(drill 0.2032)
		(layers "F.Cu" "B.Cu")
		(net "GND")
	)
	(via
		(at 183.616092 -253.435358)
		(size 0.4826)
		(drill 0.254)
		(layers "F.Cu" "B.Cu")
		(net "GND")
	)
	(via
		(at 95.1611 -287.856422)
		(size 0.4064)
		(drill 0.2032)
		(layers "F.Cu" "B.Cu")
		(net "GND")
	)
	(via
		(at 2.76225 -216.337134)
		(size 0.508)
		(drill 0.254)
		(layers "F.Cu" "B.Cu")
		(net "GND")
	)
	(via
		(at 20.59051 -275.960332)
		(size 0.4826)
		(drill 0.254)
		(layers "F.Cu" "B.Cu")
		(net "GND")
	)
	(via
		(at 78.24978 -432.451256)
		(size 0.4572)
		(drill 0.2032)
		(layers "F.Cu" "B.Cu")
		(net "GND")
	)
	(via
		(at 171.565824 -379.321568)
		(size 0.508)
		(drill 0.254)
		(layers "F.Cu" "B.Cu")
		(net "GND")
	)
	(via
		(at 419.912038 -309.535068)
		(size 0.4826)
		(drill 0.254)
		(layers "F.Cu" "B.Cu")
		(net "GND")
	)
	(via
		(at 119.622062 -78.395322)
		(size 0.508)
		(drill 0.254)
		(layers "F.Cu" "B.Cu")
		(net "GND")
	)
	(via
		(at 459.29804 -54.160928)
		(size 0.508)
		(drill 0.254)
		(layers "F.Cu" "B.Cu")
		(net "GND")
	)
	(via
		(at 224.653348 -367.531396)
		(size 0.508)
		(drill 0.254)
		(layers "F.Cu" "B.Cu")
		(net "GND")
	)
	(via
		(at 299.82414 -196.485002)
		(size 0.4826)
		(drill 0.254)
		(layers "F.Cu" "B.Cu")
		(net "GND")
	)
	(via
		(at 450.088 -272.135092)
		(size 0.4826)
		(drill 0.254)
		(layers "F.Cu" "B.Cu")
		(net "GND")
	)
	(via
		(at 309.047896 -377.41733)
		(size 0.508)
		(drill 0.254)
		(layers "F.Cu" "B.Cu")
		(net "GND")
	)
	(via
		(at 371.075204 -259.729986)
		(size 0.4826)
		(drill 0.254)
		(layers "F.Cu" "B.Cu")
		(net "GND")
	)
	(via
		(at 32.945832 -10.16508)
		(size 0.508)
		(drill 0.254)
		(layers "F.Cu" "B.Cu")
		(net "GND")
	)
	(via
		(at 113.65484 -233.144314)
		(size 0.4064)
		(drill 0.2032)
		(layers "F.Cu" "B.Cu")
		(net "GND")
	)
	(via
		(at 274.78101 -346.317316)
		(size 0.49022)
		(drill 0.254)
		(layers "F.Cu" "B.Cu")
		(net "GND")
	)
	(via
		(at 336.22107 -246.104156)
		(size 0.4064)
		(drill 0.2032)
		(layers "F.Cu" "B.Cu")
		(net "GND")
	)
	(via
		(at 126.34468 -243.674392)
		(size 0.4064)
		(drill 0.2032)
		(layers "F.Cu" "B.Cu")
		(net "GND")
	)
	(via
		(at 130.574796 -238.00435)
		(size 0.4064)
		(drill 0.2032)
		(layers "F.Cu" "B.Cu")
		(net "GND")
	)
	(via
		(at 40.785034 -19.771106)
		(size 0.508)
		(drill 0.254)
		(layers "F.Cu" "B.Cu")
		(net "GND")
	)
	(via
		(at 135.574786 -270.03629)
		(size 0.4064)
		(drill 0.2032)
		(layers "F.Cu" "B.Cu")
		(net "GND")
	)
	(via
		(at 104.82961 -66.58991)
		(size 0.508)
		(drill 0.254)
		(layers "F.Cu" "B.Cu")
		(net "GND")
	)
	(via
		(at 394.494766 -226.664266)
		(size 0.4064)
		(drill 0.2032)
		(layers "F.Cu" "B.Cu")
		(net "GND")
	)
	(via
		(at 25.152096 -311.235344)
		(size 0.4826)
		(drill 0.254)
		(layers "F.Cu" "B.Cu")
		(net "GND")
	)
	(via
		(at 76.812902 -249.610372)
		(size 0.4064)
		(drill 0.2032)
		(layers "F.Cu" "B.Cu")
		(net "GND")
	)
	(via
		(at 259.063744 -52.662582)
		(size 0.508)
		(drill 0.254)
		(layers "F.Cu" "B.Cu")
		(net "GND")
	)
	(via
		(at 49.91862 -388.328662)
		(size 0.4064)
		(drill 0.2032)
		(layers "F.Cu" "B.Cu")
		(net "GND")
	)
	(via
		(at 118.824756 -233.95432)
		(size 0.4064)
		(drill 0.2032)
		(layers "F.Cu" "B.Cu")
		(net "GND")
	)
	(via
		(at 66.177414 -368.37493)
		(size 0.508)
		(drill 0.254)
		(layers "F.Cu" "B.Cu")
		(net "GND")
	)
	(via
		(at 376.550174 -419.046152)
		(size 0.4572)
		(drill 0.254)
		(layers "F.Cu" "B.Cu")
		(net "GND")
	)
	(via
		(at 446.668906 -21.247862)
		(size 0.508)
		(drill 0.254)
		(layers "F.Cu" "B.Cu")
		(net "GND")
	)
	(via
		(at 352.9711 -272.466054)
		(size 0.4064)
		(drill 0.2032)
		(layers "F.Cu" "B.Cu")
		(net "GND")
	)
	(via
		(at 370.335302 -420.952168)
		(size 0.4064)
		(drill 0.2032)
		(layers "F.Cu" "B.Cu")
		(net "GND")
	)
	(via
		(at 402.083778 -327.395332)
		(size 0.508)
		(drill 0.254)
		(layers "F.Cu" "B.Cu")
		(net "GND")
	)
	(via
		(at 424.012106 -299.33519)
		(size 0.4826)
		(drill 0.254)
		(layers "F.Cu" "B.Cu")
		(net "GND")
	)
	(via
		(at 452.803768 -295.935146)
		(size 0.4826)
		(drill 0.254)
		(layers "F.Cu" "B.Cu")
		(net "GND")
	)
	(via
		(at 142.154656 -279.756362)
		(size 0.4064)
		(drill 0.2032)
		(layers "F.Cu" "B.Cu")
		(net "GND")
	)
	(via
		(at 450.088 -249.185176)
		(size 0.4826)
		(drill 0.254)
		(layers "F.Cu" "B.Cu")
		(net "GND")
	)
	(via
		(at 386.504942 -233.954066)
		(size 0.4064)
		(drill 0.2032)
		(layers "F.Cu" "B.Cu")
		(net "GND")
	)
	(via
		(at 353.911154 -285.42615)
		(size 0.4064)
		(drill 0.2032)
		(layers "F.Cu" "B.Cu")
		(net "GND")
	)
	(via
		(at 335.401666 -415.38652)
		(size 0.4064)
		(drill 0.2032)
		(layers "F.Cu" "B.Cu")
		(net "GND")
	)
	(via
		(at 83.41106 -274.08632)
		(size 0.4064)
		(drill 0.2032)
		(layers "F.Cu" "B.Cu")
		(net "GND")
	)
	(via
		(at 92.046298 -388.328662)
		(size 0.4064)
		(drill 0.2032)
		(layers "F.Cu" "B.Cu")
		(net "GND")
	)
	(via
		(at 165.109144 -343.122758)
		(size 0.508)
		(drill 0.254)
		(layers "F.Cu" "B.Cu")
		(net "GND")
	)
	(via
		(at 40.258238 -9.424924)
		(size 0.508)
		(drill 0.254)
		(layers "F.Cu" "B.Cu")
		(net "GND")
	)
	(via
		(at 339.511132 -240.434114)
		(size 0.4064)
		(drill 0.2032)
		(layers "F.Cu" "B.Cu")
		(net "GND")
	)
	(via
		(at 174.771304 -330.201524)
		(size 0.508)
		(drill 0.254)
		(layers "F.Cu" "B.Cu")
		(net "GND")
	)
	(via
		(at 369.895628 -144.520158)
		(size 0.508)
		(drill 0.254)
		(layers "F.Cu" "B.Cu")
		(net "GND")
	)
	(via
		(at 89.99093 -272.466308)
		(size 0.4064)
		(drill 0.2032)
		(layers "F.Cu" "B.Cu")
		(net "GND")
	)
	(via
		(at 333.701136 -295.955974)
		(size 0.4064)
		(drill 0.2032)
		(layers "F.Cu" "B.Cu")
		(net "GND")
	)
	(via
		(at 347.50121 -242.864132)
		(size 0.4064)
		(drill 0.2032)
		(layers "F.Cu" "B.Cu")
		(net "GND")
	)
	(via
		(at 302.997362 -423.234104)
		(size 0.508)
		(drill 0.254)
		(layers "F.Cu" "B.Cu")
		(net "GND")
	)
	(via
		(at 131.06908 -28.38958)
		(size 0.508)
		(drill 0.254)
		(layers "F.Cu" "B.Cu")
		(net "GND")
	)
	(via
		(at 76.697332 -410.664152)
		(size 0.4572)
		(drill 0.254)
		(layers "F.Cu" "B.Cu")
		(net "GND")
	)
	(via
		(at 385.881118 -185.988198)
		(size 0.508)
		(drill 0.254)
		(layers "F.Cu" "B.Cu")
		(net "GND")
	)
	(via
		(at 124.182632 -61.659516)
		(size 0.508)
		(drill 0.254)
		(layers "F.Cu" "B.Cu")
		(net "GND")
	)
	(via
		(at 180.900324 -228.78542)
		(size 0.4826)
		(drill 0.254)
		(layers "F.Cu" "B.Cu")
		(net "GND")
	)
	(via
		(at 93.751146 -272.466308)
		(size 0.4064)
		(drill 0.2032)
		(layers "F.Cu" "B.Cu")
		(net "GND")
	)
	(via
		(at 28.134564 -210.510374)
		(size 0.4826)
		(drill 0.254)
		(layers "F.Cu" "B.Cu")
		(net "GND")
	)
	(via
		(at 235.492036 -48.104044)
		(size 0.508)
		(drill 0.254)
		(layers "F.Cu" "B.Cu")
		(net "GND")
	)
	(via
		(at 2.76225 -210.749134)
		(size 0.508)
		(drill 0.254)
		(layers "F.Cu" "B.Cu")
		(net "GND")
	)
	(via
		(at 113.48466 -265.98626)
		(size 0.4064)
		(drill 0.2032)
		(layers "F.Cu" "B.Cu")
		(net "GND")
	)
	(via
		(at 421.88511 -0.762254)
		(size 0.508)
		(drill 0.254)
		(layers "F.Cu" "B.Cu")
		(net "GND")
	)
	(via
		(at 34.379662 -430.799748)
		(size 0.508)
		(drill 0.254)
		(layers "F.Cu" "B.Cu")
		(net "GND")
	)
	(via
		(at 32.695896 -279.785318)
		(size 0.4826)
		(drill 0.254)
		(layers "F.Cu" "B.Cu")
		(net "GND")
	)
	(via
		(at 105.279444 -32.405066)
		(size 0.508)
		(drill 0.254)
		(layers "F.Cu" "B.Cu")
		(net "GND")
	)
	(via
		(at 116.228114 -409.396184)
		(size 0.4572)
		(drill 0.254)
		(layers "F.Cu" "B.Cu")
		(net "GND")
	)
	(via
		(at 125.145038 -405.098504)
		(size 0.4572)
		(drill 0.254)
		(layers "F.Cu" "B.Cu")
		(net "GND")
	)
	(via
		(at 136.684766 -245.294404)
		(size 0.4064)
		(drill 0.2032)
		(layers "F.Cu" "B.Cu")
		(net "GND")
	)
	(via
		(at 415.492692 -141.824456)
		(size 0.508)
		(drill 0.254)
		(layers "F.Cu" "B.Cu")
		(net "GND")
	)
	(via
		(at 136.34974 -436.051198)
		(size 0.4572)
		(drill 0.2032)
		(layers "F.Cu" "B.Cu")
		(net "GND")
	)
	(via
		(at 344.069924 -333.085186)
		(size 0.49022)
		(drill 0.254)
		(layers "F.Cu" "B.Cu")
		(net "GND")
	)
	(via
		(at 194.604132 -236.435392)
		(size 0.4826)
		(drill 0.254)
		(layers "F.Cu" "B.Cu")
		(net "GND")
	)
	(via
		(at 76.812902 -241.510312)
		(size 0.4064)
		(drill 0.2032)
		(layers "F.Cu" "B.Cu")
		(net "GND")
	)
	(via
		(at 391.674858 -236.384084)
		(size 0.4064)
		(drill 0.2032)
		(layers "F.Cu" "B.Cu")
		(net "GND")
	)
	(via
		(at 436.384446 -228.785166)
		(size 0.4826)
		(drill 0.254)
		(layers "F.Cu" "B.Cu")
		(net "GND")
	)
	(via
		(at 339.511132 -250.154186)
		(size 0.4064)
		(drill 0.2032)
		(layers "F.Cu" "B.Cu")
		(net "GND")
	)
	(via
		(at 131.973066 -52.68849)
		(size 0.508)
		(drill 0.254)
		(layers "F.Cu" "B.Cu")
		(net "GND")
	)
	(via
		(at 328.122026 -397.15313)
		(size 0.508)
		(drill 0.254)
		(layers "F.Cu" "B.Cu")
		(net "GND")
	)
	(via
		(at 323.234558 -421.586152)
		(size 0.4572)
		(drill 0.254)
		(layers "F.Cu" "B.Cu")
		(net "GND")
	)
	(via
		(at 398.26565 -420.318184)
		(size 0.4572)
		(drill 0.254)
		(layers "F.Cu" "B.Cu")
		(net "GND")
	)
	(via
		(at 356.901242 -233.14406)
		(size 0.4064)
		(drill 0.2032)
		(layers "F.Cu" "B.Cu")
		(net "GND")
	)
	(via
		(at 98.451162 -285.426404)
		(size 0.4064)
		(drill 0.2032)
		(layers "F.Cu" "B.Cu")
		(net "GND")
	)
	(via
		(at 317.108078 -413.480504)
		(size 0.4572)
		(drill 0.254)
		(layers "F.Cu" "B.Cu")
		(net "GND")
	)
	(via
		(at 357.335074 -170.64609)
		(size 0.49022)
		(drill 0.254)
		(layers "F.Cu" "B.Cu")
		(net "GND")
	)
	(via
		(at 50.766472 -219.860368)
		(size 0.4826)
		(drill 0.254)
		(layers "F.Cu" "B.Cu")
		(net "GND")
	)
	(via
		(at 367.919 -406.654)
		(size 0.4572)
		(drill 0.254)
		(layers "F.Cu" "B.Cu")
		(net "GND")
	)
	(via
		(at 391.466832 -378.07773)
		(size 0.508)
		(drill 0.254)
		(layers "F.Cu" "B.Cu")
		(net "GND")
	)
	(via
		(at 304.652426 -284.88513)
		(size 0.4826)
		(drill 0.254)
		(layers "F.Cu" "B.Cu")
		(net "GND")
	)
	(via
		(at 138.564874 -255.014476)
		(size 0.4064)
		(drill 0.2032)
		(layers "F.Cu" "B.Cu")
		(net "GND")
	)
	(via
		(at 354.851208 -270.846042)
		(size 0.4064)
		(drill 0.2032)
		(layers "F.Cu" "B.Cu")
		(net "GND")
	)
	(via
		(at 161.926016 -115.405408)
		(size 0.508)
		(drill 0.254)
		(layers "F.Cu" "B.Cu")
		(net "GND")
	)
	(via
		(at 414.758124 -12.37488)
		(size 0.508)
		(drill 0.254)
		(layers "F.Cu" "B.Cu")
		(net "GND")
	)
	(via
		(at 22.528784 -387.037326)
		(size 0.508)
		(drill 0.254)
		(layers "F.Cu" "B.Cu")
		(net "GND")
	)
	(via
		(at 151.053292 -77.74686)
		(size 0.508)
		(drill 0.254)
		(layers "F.Cu" "B.Cu")
		(net "GND")
	)
	(via
		(at 168.527984 -213.485222)
		(size 0.4826)
		(drill 0.254)
		(layers "F.Cu" "B.Cu")
		(net "GND")
	)
	(via
		(at 119.507 -425.21505)
		(size 0.508)
		(drill 0.254)
		(layers "F.Cu" "B.Cu")
		(net "GND")
	)
	(via
		(at 370.560092 -382.34493)
		(size 0.508)
		(drill 0.254)
		(layers "F.Cu" "B.Cu")
		(net "GND")
	)
	(via
		(at 138.564874 -245.294404)
		(size 0.4064)
		(drill 0.2032)
		(layers "F.Cu" "B.Cu")
		(net "GND")
	)
	(via
		(at 156.96819 -96.412558)
		(size 0.508)
		(drill 0.254)
		(layers "F.Cu" "B.Cu")
		(net "GND")
	)
	(via
		(at 125.256036 -369.69573)
		(size 0.508)
		(drill 0.254)
		(layers "F.Cu" "B.Cu")
		(net "GND")
	)
	(via
		(at 50.499772 -314.635388)
		(size 0.4826)
		(drill 0.254)
		(layers "F.Cu" "B.Cu")
		(net "GND")
	)
	(via
		(at 458.52969 -53.0733)
		(size 0.508)
		(drill 0.254)
		(layers "F.Cu" "B.Cu")
		(net "GND")
	)
	(via
		(at 69.767958 -333.84998)
		(size 0.49022)
		(drill 0.254)
		(layers "F.Cu" "B.Cu")
		(net "GND")
	)
	(via
		(at 53.25999 -19.771106)
		(size 0.508)
		(drill 0.254)
		(layers "F.Cu" "B.Cu")
		(net "GND")
	)
	(via
		(at 51.581558 -345.571064)
		(size 0.49022)
		(drill 0.254)
		(layers "F.Cu" "B.Cu")
		(net "GND")
	)
	(via
		(at 301.73295 -365.8616)
		(size 0.508)
		(drill 0.254)
		(layers "F.Cu" "B.Cu")
		(net "GND")
	)
	(via
		(at 191.160146 -288.285428)
		(size 0.4826)
		(drill 0.254)
		(layers "F.Cu" "B.Cu")
		(net "GND")
	)
	(via
		(at 130.104642 -225.854514)
		(size 0.4064)
		(drill 0.2032)
		(layers "F.Cu" "B.Cu")
		(net "GND")
	)
	(via
		(at 376.93473 -266.796012)
		(size 0.4064)
		(drill 0.2032)
		(layers "F.Cu" "B.Cu")
		(net "GND")
	)
	(via
		(at 416.468052 -261.93496)
		(size 0.4826)
		(drill 0.254)
		(layers "F.Cu" "B.Cu")
		(net "GND")
	)
	(via
		(at 367.704878 -240.434114)
		(size 0.4064)
		(drill 0.2032)
		(layers "F.Cu" "B.Cu")
		(net "GND")
	)
	(via
		(at 394.693902 -75.722226)
		(size 0.508)
		(drill 0.254)
		(layers "F.Cu" "B.Cu")
		(net "GND")
	)
	(via
		(at 113.184686 -250.15444)
		(size 0.4064)
		(drill 0.2032)
		(layers "F.Cu" "B.Cu")
		(net "GND")
	)
	(via
		(at 28.096464 -193.996564)
		(size 0.4826)
		(drill 0.254)
		(layers "F.Cu" "B.Cu")
		(net "GND")
	)
	(via
		(at 70.75043 -179.574698)
		(size 0.508)
		(drill 0.254)
		(layers "F.Cu" "B.Cu")
		(net "GND")
	)
	(via
		(at 428.573692 -239.41024)
		(size 0.4826)
		(drill 0.254)
		(layers "F.Cu" "B.Cu")
		(net "GND")
	)
	(via
		(at 337.736942 -139.524486)
		(size 0.508)
		(drill 0.254)
		(layers "F.Cu" "B.Cu")
		(net "GND")
	)
	(via
		(at 151.182578 -410.664152)
		(size 0.4572)
		(drill 0.254)
		(layers "F.Cu" "B.Cu")
		(net "GND")
	)
	(via
		(at 24.184864 -6.598158)
		(size 0.508)
		(drill 0.254)
		(layers "F.Cu" "B.Cu")
		(net "GND")
	)
	(via
		(at 61.249814 -431.29962)
		(size 0.4572)
		(drill 0.2032)
		(layers "F.Cu" "B.Cu")
		(net "GND")
	)
	(via
		(at 128.694688 -234.764326)
		(size 0.4064)
		(drill 0.2032)
		(layers "F.Cu" "B.Cu")
		(net "GND")
	)
	(via
		(at 406.4889 -380.54153)
		(size 0.508)
		(drill 0.254)
		(layers "F.Cu" "B.Cu")
		(net "GND")
	)
	(via
		(at 384.11658 -391.23493)
		(size 0.4064)
		(drill 0.2032)
		(layers "F.Cu" "B.Cu")
		(net "GND")
	)
	(via
		(at 398.43964 -325.99884)
		(size 0.508)
		(drill 0.254)
		(layers "F.Cu" "B.Cu")
		(net "GND")
	)
	(via
		(at 408.244294 -402.309838)
		(size 0.4572)
		(drill 0.254)
		(layers "F.Cu" "B.Cu")
		(net "GND")
	)
	(via
		(at 73.29805 -377.00712)
		(size 0.508)
		(drill 0.254)
		(layers "F.Cu" "B.Cu")
		(net "GND")
	)
	(via
		(at 80.291178 -235.574332)
		(size 0.4064)
		(drill 0.2032)
		(layers "F.Cu" "B.Cu")
		(net "GND")
	)
	(via
		(at 108.51515 -121.65711)
		(size 0.508)
		(drill 0.254)
		(layers "F.Cu" "B.Cu")
		(net "GND")
	)
	(via
		(at 318.81699 -36.208462)
		(size 0.508)
		(drill 0.254)
		(layers "F.Cu" "B.Cu")
		(net "GND")
	)
	(via
		(at 66.949066 -170.867832)
		(size 0.49022)
		(drill 0.254)
		(layers "F.Cu" "B.Cu")
		(net "GND")
	)
	(via
		(at 116.304822 -280.566368)
		(size 0.4064)
		(drill 0.2032)
		(layers "F.Cu" "B.Cu")
		(net "GND")
	)
	(via
		(at 320.616326 -391.23493)
		(size 0.4064)
		(drill 0.2032)
		(layers "F.Cu" "B.Cu")
		(net "GND")
	)
	(via
		(at 461.993996 -107.678728)
		(size 0.508)
		(drill 0.254)
		(layers "F.Cu" "B.Cu")
		(net "GND")
	)
	(via
		(at 99.861116 -261.93623)
		(size 0.4064)
		(drill 0.2032)
		(layers "F.Cu" "B.Cu")
		(net "GND")
	)
	(via
		(at 394.982954 -269.770098)
		(size 0.4064)
		(drill 0.2032)
		(layers "F.Cu" "B.Cu")
		(net "GND")
	)
	(via
		(at 36.239958 -345.571064)
		(size 0.49022)
		(drill 0.254)
		(layers "F.Cu" "B.Cu")
		(net "GND")
	)
	(via
		(at 145.349722 -426.54728)
		(size 0.4572)
		(drill 0.2032)
		(layers "F.Cu" "B.Cu")
		(net "GND")
	)
	(via
		(at 416.468052 -310.384952)
		(size 0.4826)
		(drill 0.254)
		(layers "F.Cu" "B.Cu")
		(net "GND")
	)
	(via
		(at 363.774736 -270.036036)
		(size 0.4064)
		(drill 0.2032)
		(layers "F.Cu" "B.Cu")
		(net "GND")
	)
	(via
		(at 206.375 -128.016)
		(size 0.508)
		(drill 0.254)
		(layers "F.Cu" "B.Cu")
		(net "GND")
	)
	(via
		(at 367.064798 -265.986006)
		(size 0.4064)
		(drill 0.2032)
		(layers "F.Cu" "B.Cu")
		(net "GND")
	)
	(via
		(at 2.76225 -389.565134)
		(size 0.508)
		(drill 0.254)
		(layers "F.Cu" "B.Cu")
		(net "GND")
	)
	(via
		(at 106.957114 -333.049626)
		(size 0.508)
		(drill 0.254)
		(layers "F.Cu" "B.Cu")
		(net "GND")
	)
	(via
		(at 333.230982 -293.525956)
		(size 0.4064)
		(drill 0.2032)
		(layers "F.Cu" "B.Cu")
		(net "GND")
	)
	(via
		(at 342.343994 -391.23493)
		(size 0.4064)
		(drill 0.2032)
		(layers "F.Cu" "B.Cu")
		(net "GND")
	)
	(via
		(at 324.75297 -239.890046)
		(size 0.4064)
		(drill 0.2032)
		(layers "F.Cu" "B.Cu")
		(net "GND")
	)
	(via
		(at 409.349702 -428.851314)
		(size 0.4572)
		(drill 0.2032)
		(layers "F.Cu" "B.Cu")
		(net "GND")
	)
	(via
		(at 407.783538 -327.341992)
		(size 0.508)
		(drill 0.254)
		(layers "F.Cu" "B.Cu")
		(net "GND")
	)
	(via
		(at 164.427916 -233.035348)
		(size 0.4826)
		(drill 0.254)
		(layers "F.Cu" "B.Cu")
		(net "GND")
	)
	(via
		(at 413.752284 -294.235124)
		(size 0.4826)
		(drill 0.254)
		(layers "F.Cu" "B.Cu")
		(net "GND")
	)
	(via
		(at 353.141026 -236.384084)
		(size 0.4064)
		(drill 0.2032)
		(layers "F.Cu" "B.Cu")
		(net "GND")
	)
	(via
		(at 137.924794 -295.146222)
		(size 0.4064)
		(drill 0.2032)
		(layers "F.Cu" "B.Cu")
		(net "GND")
	)
	(via
		(at 345.58986 -392.999722)
		(size 0.4064)
		(drill 0.2032)
		(layers "F.Cu" "B.Cu")
		(net "GND")
	)
	(via
		(at 375.694702 -225.044254)
		(size 0.4064)
		(drill 0.2032)
		(layers "F.Cu" "B.Cu")
		(net "GND")
	)
	(via
		(at 412.74619 -396.710662)
		(size 0.4064)
		(drill 0.2032)
		(layers "F.Cu" "B.Cu")
		(net "GND")
	)
	(via
		(at 370.524786 -237.19409)
		(size 0.4064)
		(drill 0.2032)
		(layers "F.Cu" "B.Cu")
		(net "GND")
	)
	(via
		(at 315.462158 -392.999722)
		(size 0.4064)
		(drill 0.2032)
		(layers "F.Cu" "B.Cu")
		(net "GND")
	)
	(via
		(at 62.551564 -404.46452)
		(size 0.4064)
		(drill 0.2032)
		(layers "F.Cu" "B.Cu")
		(net "GND")
	)
	(via
		(at 342.088724 -333.874364)
		(size 0.49022)
		(drill 0.254)
		(layers "F.Cu" "B.Cu")
		(net "GND")
	)
	(via
		(at 424.012106 -207.535018)
		(size 0.4826)
		(drill 0.254)
		(layers "F.Cu" "B.Cu")
		(net "GND")
	)
	(via
		(at 282.942792 -435.417976)
		(size 0.508)
		(drill 0.254)
		(layers "F.Cu" "B.Cu")
		(net "GND")
	)
	(via
		(at 2.76225 -182.809134)
		(size 0.508)
		(drill 0.254)
		(layers "F.Cu" "B.Cu")
		(net "GND")
	)
	(via
		(at 140.89761 -389.017256)
		(size 0.508)
		(drill 0.254)
		(layers "F.Cu" "B.Cu")
		(net "GND")
	)
	(via
		(at 71.249794 -435.0512)
		(size 0.4572)
		(drill 0.2032)
		(layers "F.Cu" "B.Cu")
		(net "GND")
	)
	(via
		(at 287.08223 -419.656006)
		(size 0.4572)
		(drill 0.254)
		(layers "F.Cu" "B.Cu")
		(net "GND")
	)
	(via
		(at 411.141164 -19.13636)
		(size 0.508)
		(drill 0.254)
		(layers "F.Cu" "B.Cu")
		(net "GND")
	)
	(via
		(at 380.398274 -184.683146)
		(size 0.49022)
		(drill 0.254)
		(layers "F.Cu" "B.Cu")
		(net "GND")
	)
	(via
		(at 44.340018 -271.285208)
		(size 0.4826)
		(drill 0.254)
		(layers "F.Cu" "B.Cu")
		(net "GND")
	)
	(via
		(at 87.47125 -184.624726)
		(size 0.508)
		(drill 0.254)
		(layers "F.Cu" "B.Cu")
		(net "GND")
	)
	(via
		(at 114.74196 -330.72578)
		(size 0.6604)
		(drill 0.3302)
		(layers "F.Cu" "B.Cu")
		(net "GND")
	)
	(via
		(at 295.724072 -250.884944)
		(size 0.4826)
		(drill 0.254)
		(layers "F.Cu" "B.Cu")
		(net "GND")
	)
	(via
		(at 427.456092 -214.335106)
		(size 0.4826)
		(drill 0.254)
		(layers "F.Cu" "B.Cu")
		(net "GND")
	)
	(via
		(at 52.52847 -158.08579)
		(size 0.508)
		(drill 0.254)
		(layers "F.Cu" "B.Cu")
		(net "GND")
	)
	(via
		(at 145.444718 -291.906198)
		(size 0.4064)
		(drill 0.2032)
		(layers "F.Cu" "B.Cu")
		(net "GND")
	)
	(via
		(at 327.761092 -225.044254)
		(size 0.4064)
		(drill 0.2032)
		(layers "F.Cu" "B.Cu")
		(net "GND")
	)
	(via
		(at 206.248 -261.935214)
		(size 0.4826)
		(drill 0.254)
		(layers "F.Cu" "B.Cu")
		(net "GND")
	)
	(via
		(at 128.569466 -412.570168)
		(size 0.4064)
		(drill 0.2032)
		(layers "F.Cu" "B.Cu")
		(net "GND")
	)
	(via
		(at 28.134564 -285.310326)
		(size 0.4826)
		(drill 0.254)
		(layers "F.Cu" "B.Cu")
		(net "GND")
	)
	(via
		(at 36.795964 -306.985416)
		(size 0.4826)
		(drill 0.254)
		(layers "F.Cu" "B.Cu")
		(net "GND")
	)
	(via
		(at 89.690956 -240.434368)
		(size 0.4064)
		(drill 0.2032)
		(layers "F.Cu" "B.Cu")
		(net "GND")
	)
	(via
		(at 121.174764 -249.344434)
		(size 0.4064)
		(drill 0.2032)
		(layers "F.Cu" "B.Cu")
		(net "GND")
	)
	(via
		(at 417.818062 -415.38652)
		(size 0.4064)
		(drill 0.2032)
		(layers "F.Cu" "B.Cu")
		(net "GND")
	)
	(via
		(at 340.082378 -417.778184)
		(size 0.4572)
		(drill 0.254)
		(layers "F.Cu" "B.Cu")
		(net "GND")
	)
	(via
		(at 412.07944 -382.34493)
		(size 0.508)
		(drill 0.254)
		(layers "F.Cu" "B.Cu")
		(net "GND")
	)
	(via
		(at 56.99125 -390.160002)
		(size 0.4064)
		(drill 0.2032)
		(layers "F.Cu" "B.Cu")
		(net "GND")
	)
	(via
		(at 382.349502 -432.747166)
		(size 0.4572)
		(drill 0.2032)
		(layers "F.Cu" "B.Cu")
		(net "GND")
	)
	(via
		(at 389.277352 -376.75693)
		(size 0.508)
		(drill 0.254)
		(layers "F.Cu" "B.Cu")
		(net "GND")
	)
	(via
		(at 350.377252 -164.140134)
		(size 0.6604)
		(drill 0.3302)
		(layers "F.Cu" "B.Cu")
		(net "GND")
	)
	(via
		(at 388.21487 -286.236156)
		(size 0.4064)
		(drill 0.2032)
		(layers "F.Cu" "B.Cu")
		(net "GND")
	)
	(via
		(at 424.012106 -271.284954)
		(size 0.4826)
		(drill 0.254)
		(layers "F.Cu" "B.Cu")
		(net "GND")
	)
	(via
		(at 351.561146 -266.796012)
		(size 0.4064)
		(drill 0.2032)
		(layers "F.Cu" "B.Cu")
		(net "GND")
	)
	(via
		(at 373.398542 -412.84652)
		(size 0.4064)
		(drill 0.2032)
		(layers "F.Cu" "B.Cu")
		(net "GND")
	)
	(via
		(at 283.351732 -227.935028)
		(size 0.4826)
		(drill 0.254)
		(layers "F.Cu" "B.Cu")
		(net "GND")
	)
	(via
		(at 151.053292 -79.79283)
		(size 0.508)
		(drill 0.254)
		(layers "F.Cu" "B.Cu")
		(net "GND")
	)
	(via
		(at 136.684766 -243.674392)
		(size 0.4064)
		(drill 0.2032)
		(layers "F.Cu" "B.Cu")
		(net "GND")
	)
	(via
		(at 252.778006 -69.596508)
		(size 0.508)
		(drill 0.254)
		(layers "F.Cu" "B.Cu")
		(net "GND")
	)
	(via
		(at 32.605218 -50.099214)
		(size 0.508)
		(drill 0.254)
		(layers "F.Cu" "B.Cu")
		(net "GND")
	)
	(via
		(at 132.284724 -275.706332)
		(size 0.4064)
		(drill 0.2032)
		(layers "F.Cu" "B.Cu")
		(net "GND")
	)
	(via
		(at 42.955718 -237.285276)
		(size 0.4826)
		(drill 0.254)
		(layers "F.Cu" "B.Cu")
		(net "GND")
	)
	(via
		(at 325.052944 -264.910062)
		(size 0.4064)
		(drill 0.2032)
		(layers "F.Cu" "B.Cu")
		(net "GND")
	)
	(via
		(at 176.072038 -205.83525)
		(size 0.4826)
		(drill 0.254)
		(layers "F.Cu" "B.Cu")
		(net "GND")
	)
	(via
		(at 386.804916 -269.22603)
		(size 0.4064)
		(drill 0.2032)
		(layers "F.Cu" "B.Cu")
		(net "GND")
	)
	(via
		(at 337.631024 -229.094284)
		(size 0.4064)
		(drill 0.2032)
		(layers "F.Cu" "B.Cu")
		(net "GND")
	)
	(via
		(at 157.966664 -118.132352)
		(size 0.508)
		(drill 0.254)
		(layers "F.Cu" "B.Cu")
		(net "GND")
	)
	(via
		(at 204.8637 -230.485442)
		(size 0.4826)
		(drill 0.254)
		(layers "F.Cu" "B.Cu")
		(net "GND")
	)
	(via
		(at 31.148274 -12.37488)
		(size 0.508)
		(drill 0.254)
		(layers "F.Cu" "B.Cu")
		(net "GND")
	)
	(via
		(at 91.571064 -256.634488)
		(size 0.4064)
		(drill 0.2032)
		(layers "F.Cu" "B.Cu")
		(net "GND")
	)
	(via
		(at 390.094724 -268.416024)
		(size 0.4064)
		(drill 0.2032)
		(layers "F.Cu" "B.Cu")
		(net "GND")
	)
	(via
		(at 119.12473 -288.666174)
		(size 0.4064)
		(drill 0.2032)
		(layers "F.Cu" "B.Cu")
		(net "GND")
	)
	(via
		(at 343.101168 -284.616144)
		(size 0.4064)
		(drill 0.2032)
		(layers "F.Cu" "B.Cu")
		(net "GND")
	)
	(via
		(at 244.409722 -45.698918)
		(size 0.508)
		(drill 0.254)
		(layers "F.Cu" "B.Cu")
		(net "GND")
	)
	(via
		(at 369.114832 -242.864132)
		(size 0.4064)
		(drill 0.2032)
		(layers "F.Cu" "B.Cu")
		(net "GND")
	)
	(via
		(at 135.744712 -222.61449)
		(size 0.4064)
		(drill 0.2032)
		(layers "F.Cu" "B.Cu")
		(net "GND")
	)
	(via
		(at 454.188068 -253.435104)
		(size 0.4826)
		(drill 0.254)
		(layers "F.Cu" "B.Cu")
		(net "GND")
	)
	(via
		(at 318.97828 -394.831062)
		(size 0.4064)
		(drill 0.2032)
		(layers "F.Cu" "B.Cu")
		(net "GND")
	)
	(via
		(at 17.608042 -309.535322)
		(size 0.4826)
		(drill 0.254)
		(layers "F.Cu" "B.Cu")
		(net "GND")
	)
	(via
		(at 371.869462 -418.412168)
		(size 0.4064)
		(drill 0.2032)
		(layers "F.Cu" "B.Cu")
		(net "GND")
	)
	(via
		(at 213.68258 -386.483352)
		(size 0.508)
		(drill 0.254)
		(layers "F.Cu" "B.Cu")
		(net "GND")
	)
	(via
		(at 347.33103 -270.846042)
		(size 0.4064)
		(drill 0.2032)
		(layers "F.Cu" "B.Cu")
		(net "GND")
	)
	(via
		(at 110.671102 -282.18638)
		(size 0.4064)
		(drill 0.2032)
		(layers "F.Cu" "B.Cu")
		(net "GND")
	)
	(via
		(at 140.744702 -278.946356)
		(size 0.4064)
		(drill 0.2032)
		(layers "F.Cu" "B.Cu")
		(net "GND")
	)
	(via
		(at 355.791008 -280.566114)
		(size 0.4064)
		(drill 0.2032)
		(layers "F.Cu" "B.Cu")
		(net "GND")
	)
	(via
		(at 418.5158 -425.253912)
		(size 0.508)
		(drill 0.254)
		(layers "F.Cu" "B.Cu")
		(net "GND")
	)
	(via
		(at 336.046064 -396.710662)
		(size 0.4064)
		(drill 0.2032)
		(layers "F.Cu" "B.Cu")
		(net "GND")
	)
	(via
		(at 367.534698 -294.335962)
		(size 0.4064)
		(drill 0.2032)
		(layers "F.Cu" "B.Cu")
		(net "GND")
	)
	(via
		(at 238.252 -331.343)
		(size 0.508)
		(drill 0.254)
		(layers "F.Cu" "B.Cu")
		(net "GND")
	)
	(via
		(at 259.44195 -102.85095)
		(size 0.508)
		(drill 0.254)
		(layers "F.Cu" "B.Cu")
		(net "GND")
	)
	(via
		(at 126.34468 -232.334308)
		(size 0.4064)
		(drill 0.2032)
		(layers "F.Cu" "B.Cu")
		(net "GND")
	)
	(via
		(at 366.294924 -229.904036)
		(size 0.4064)
		(drill 0.2032)
		(layers "F.Cu" "B.Cu")
		(net "GND")
	)
	(via
		(at 133.694678 -287.856422)
		(size 0.4064)
		(drill 0.2032)
		(layers "F.Cu" "B.Cu")
		(net "GND")
	)
	(via
		(at 83.41106 -290.286186)
		(size 0.4064)
		(drill 0.2032)
		(layers "F.Cu" "B.Cu")
		(net "GND")
	)
	(via
		(at 82.471006 -269.226284)
		(size 0.4064)
		(drill 0.2032)
		(layers "F.Cu" "B.Cu")
		(net "GND")
	)
	(via
		(at 309.37581 -344.77706)
		(size 0.49022)
		(drill 0.254)
		(layers "F.Cu" "B.Cu")
		(net "GND")
	)
	(via
		(at 439.100214 -204.134974)
		(size 0.4826)
		(drill 0.254)
		(layers "F.Cu" "B.Cu")
		(net "GND")
	)
	(via
		(at 135.574786 -261.93623)
		(size 0.4064)
		(drill 0.2032)
		(layers "F.Cu" "B.Cu")
		(net "GND")
	)
	(via
		(at 344.681048 -231.524048)
		(size 0.4064)
		(drill 0.2032)
		(layers "F.Cu" "B.Cu")
		(net "GND")
	)
	(via
		(at 320.085466 -418.412168)
		(size 0.4064)
		(drill 0.2032)
		(layers "F.Cu" "B.Cu")
		(net "GND")
	)
	(via
		(at 348.343982 -400.212814)
		(size 0.4064)
		(drill 0.2032)
		(layers "F.Cu" "B.Cu")
		(net "GND")
	)
	(via
		(at 34.080196 -210.085432)
		(size 0.4826)
		(drill 0.254)
		(layers "F.Cu" "B.Cu")
		(net "GND")
	)
	(via
		(at 238.890556 -233.206036)
		(size 0.4826)
		(drill 0.254)
		(layers "F.Cu" "B.Cu")
		(net "GND")
	)
	(via
		(at 167.143684 -211.7852)
		(size 0.4826)
		(drill 0.254)
		(layers "F.Cu" "B.Cu")
		(net "GND")
	)
	(via
		(at 125.404626 -225.854514)
		(size 0.4064)
		(drill 0.2032)
		(layers "F.Cu" "B.Cu")
		(net "GND")
	)
	(via
		(at 20.32381 -312.085228)
		(size 0.4826)
		(drill 0.254)
		(layers "F.Cu" "B.Cu")
		(net "GND")
	)
	(via
		(at 419.04412 -400.212814)
		(size 0.4064)
		(drill 0.2032)
		(layers "F.Cu" "B.Cu")
		(net "GND")
	)
	(via
		(at 120.43791 -168.436798)
		(size 0.508)
		(drill 0.254)
		(layers "F.Cu" "B.Cu")
		(net "GND")
	)
	(via
		(at 295.536366 -343.472008)
		(size 0.508)
		(drill 0.254)
		(layers "F.Cu" "B.Cu")
		(net "GND")
	)
	(via
		(at 451.4723 -278.085042)
		(size 0.4826)
		(drill 0.254)
		(layers "F.Cu" "B.Cu")
		(net "GND")
	)
	(via
		(at 135.574786 -266.796266)
		(size 0.4064)
		(drill 0.2032)
		(layers "F.Cu" "B.Cu")
		(net "GND")
	)
	(via
		(at 22.671278 -17.61236)
		(size 0.508)
		(drill 0.254)
		(layers "F.Cu" "B.Cu")
		(net "GND")
	)
	(via
		(at 332.461108 -221.80423)
		(size 0.4064)
		(drill 0.2032)
		(layers "F.Cu" "B.Cu")
		(net "GND")
	)
	(via
		(at 92.811092 -269.226284)
		(size 0.4064)
		(drill 0.2032)
		(layers "F.Cu" "B.Cu")
		(net "GND")
	)
	(via
		(at 329.6412 -236.384084)
		(size 0.4064)
		(drill 0.2032)
		(layers "F.Cu" "B.Cu")
		(net "GND")
	)
	(via
		(at 184.58688 -146.02714)
		(size 0.508)
		(drill 0.254)
		(layers "F.Cu" "B.Cu")
		(net "GND")
	)
	(via
		(at 50.386996 -406.370536)
		(size 0.4572)
		(drill 0.254)
		(layers "F.Cu" "B.Cu")
		(net "GND")
	)
	(via
		(at 143.264636 -224.234502)
		(size 0.4064)
		(drill 0.2032)
		(layers "F.Cu" "B.Cu")
		(net "GND")
	)
	(via
		(at 29.69387 -387.68909)
		(size 0.508)
		(drill 0.254)
		(layers "F.Cu" "B.Cu")
		(net "GND")
	)
	(via
		(at 303.326546 -12.542266)
		(size 0.508)
		(drill 0.254)
		(layers "F.Cu" "B.Cu")
		(net "GND")
	)
	(via
		(at 86.871048 -229.094538)
		(size 0.4064)
		(drill 0.2032)
		(layers "F.Cu" "B.Cu")
		(net "GND")
	)
	(via
		(at 344.981022 -274.896072)
		(size 0.4064)
		(drill 0.2032)
		(layers "F.Cu" "B.Cu")
		(net "GND")
	)
	(via
		(at 452.803768 -239.835182)
		(size 0.4826)
		(drill 0.254)
		(layers "F.Cu" "B.Cu")
		(net "GND")
	)
	(via
		(at 147.087844 -373.96293)
		(size 0.508)
		(drill 0.254)
		(layers "F.Cu" "B.Cu")
		(net "GND")
	)
	(via
		(at 146.183096 -66.337434)
		(size 0.508)
		(drill 0.254)
		(layers "F.Cu" "B.Cu")
		(net "GND")
	)
	(via
		(at 435.498748 -347.895926)
		(size 0.508)
		(drill 0.254)
		(layers "F.Cu" "B.Cu")
		(net "GND")
	)
	(via
		(at 86.401148 -247.724422)
		(size 0.4064)
		(drill 0.2032)
		(layers "F.Cu" "B.Cu")
		(net "GND")
	)
	(via
		(at 281.791664 -193.10731)
		(size 0.4826)
		(drill 0.254)
		(layers "F.Cu" "B.Cu")
		(net "GND")
	)
	(via
		(at 415.7472 -109.215428)
		(size 0.508)
		(drill 0.254)
		(layers "F.Cu" "B.Cu")
		(net "GND")
	)
	(via
		(at 79.990188 -384.617722)
		(size 0.4064)
		(drill 0.2032)
		(layers "F.Cu" "B.Cu")
		(net "GND")
	)
	(via
		(at 57.402222 -175.744124)
		(size 0.6604)
		(drill 0.3302)
		(layers "F.Cu" "B.Cu")
		(net "GND")
	)
	(via
		(at 471.037666 -33.645094)
		(size 0.508)
		(drill 0.254)
		(layers "F.Cu" "B.Cu")
		(net "GND")
	)
	(via
		(at 135.274812 -249.344434)
		(size 0.4064)
		(drill 0.2032)
		(layers "F.Cu" "B.Cu")
		(net "GND")
	)
	(via
		(at 135.574786 -279.756362)
		(size 0.4064)
		(drill 0.2032)
		(layers "F.Cu" "B.Cu")
		(net "GND")
	)
	(via
		(at 411.319218 -165.716712)
		(size 0.508)
		(drill 0.254)
		(layers "F.Cu" "B.Cu")
		(net "GND")
	)
	(via
		(at 95.194374 -335.595214)
		(size 0.49022)
		(drill 0.254)
		(layers "F.Cu" "B.Cu")
		(net "GND")
	)
	(via
		(at 90.16111 -238.00435)
		(size 0.4064)
		(drill 0.2032)
		(layers "F.Cu" "B.Cu")
		(net "GND")
	)
	(via
		(at 55.328058 -262.785352)
		(size 0.4826)
		(drill 0.254)
		(layers "F.Cu" "B.Cu")
		(net "GND")
	)
	(via
		(at 328.53122 -293.525956)
		(size 0.4064)
		(drill 0.2032)
		(layers "F.Cu" "B.Cu")
		(net "GND")
	)
	(via
		(at 397.904462 -420.952168)
		(size 0.4064)
		(drill 0.2032)
		(layers "F.Cu" "B.Cu")
		(net "GND")
	)
	(via
		(at 48.769524 -410.030168)
		(size 0.4064)
		(drill 0.2032)
		(layers "F.Cu" "B.Cu")
		(net "GND")
	)
	(via
		(at 376.148092 -377.41733)
		(size 0.508)
		(drill 0.254)
		(layers "F.Cu" "B.Cu")
		(net "GND")
	)
	(via
		(at 180.633624 -211.360258)
		(size 0.4826)
		(drill 0.254)
		(layers "F.Cu" "B.Cu")
		(net "GND")
	)
	(via
		(at 9.277096 -101.095302)
		(size 0.508)
		(drill 0.254)
		(layers "F.Cu" "B.Cu")
		(net "GND")
	)
	(via
		(at 471.037666 -44.821094)
		(size 0.508)
		(drill 0.254)
		(layers "F.Cu" "B.Cu")
		(net "GND")
	)
	(via
		(at 384.9624 -392.999722)
		(size 0.4064)
		(drill 0.2032)
		(layers "F.Cu" "B.Cu")
		(net "GND")
	)
	(via
		(at 29.280358 -344.781886)
		(size 0.49022)
		(drill 0.254)
		(layers "F.Cu" "B.Cu")
		(net "GND")
	)
	(via
		(at 353.141026 -234.764072)
		(size 0.4064)
		(drill 0.2032)
		(layers "F.Cu" "B.Cu")
		(net "GND")
	)
	(via
		(at 29.252164 -289.98545)
		(size 0.4826)
		(drill 0.254)
		(layers "F.Cu" "B.Cu")
		(net "GND")
	)
	(via
		(at 132.916422 -393.902438)
		(size 0.4572)
		(drill 0.254)
		(layers "F.Cu" "B.Cu")
		(net "GND")
	)
	(via
		(at 185.663332 -18.037556)
		(size 0.508)
		(drill 0.254)
		(layers "F.Cu" "B.Cu")
		(net "GND")
	)
	(via
		(at 385.394708 -271.656048)
		(size 0.4064)
		(drill 0.2032)
		(layers "F.Cu" "B.Cu")
		(net "GND")
	)
	(via
		(at 298.70654 -285.310072)
		(size 0.4826)
		(drill 0.254)
		(layers "F.Cu" "B.Cu")
		(net "GND")
	)
	(via
		(at 416.468052 -204.134974)
		(size 0.4826)
		(drill 0.254)
		(layers "F.Cu" "B.Cu")
		(net "GND")
	)
	(via
		(at 134.634732 -294.336216)
		(size 0.4064)
		(drill 0.2032)
		(layers "F.Cu" "B.Cu")
		(net "GND")
	)
	(via
		(at 446.884552 -375.455434)
		(size 0.6604)
		(drill 0.3302)
		(layers "F.Cu" "B.Cu")
		(net "GND")
	)
	(via
		(at 131.98475 -242.05438)
		(size 0.4064)
		(drill 0.2032)
		(layers "F.Cu" "B.Cu")
		(net "GND")
	)
	(via
		(at 335.11109 -269.22603)
		(size 0.4064)
		(drill 0.2032)
		(layers "F.Cu" "B.Cu")
		(net "GND")
	)
	(via
		(at 334.341216 -246.104156)
		(size 0.4064)
		(drill 0.2032)
		(layers "F.Cu" "B.Cu")
		(net "GND")
	)
	(via
		(at 277.192232 -288.285174)
		(size 0.4826)
		(drill 0.254)
		(layers "F.Cu" "B.Cu")
		(net "GND")
	)
	(via
		(at 183.616092 -289.98545)
		(size 0.4826)
		(drill 0.254)
		(layers "F.Cu" "B.Cu")
		(net "GND")
	)
	(via
		(at 384.349498 -433.747164)
		(size 0.4572)
		(drill 0.2032)
		(layers "F.Cu" "B.Cu")
		(net "GND")
	)
	(via
		(at 140.714222 -156.567124)
		(size 0.508)
		(drill 0.254)
		(layers "F.Cu" "B.Cu")
		(net "GND")
	)
	(via
		(at 128.694688 -228.284532)
		(size 0.4064)
		(drill 0.2032)
		(layers "F.Cu" "B.Cu")
		(net "GND")
	)
	(via
		(at 204.8637 -305.285394)
		(size 0.4826)
		(drill 0.254)
		(layers "F.Cu" "B.Cu")
		(net "GND")
	)
	(via
		(at 455.305668 -294.660066)
		(size 0.4826)
		(drill 0.254)
		(layers "F.Cu" "B.Cu")
		(net "GND")
	)
	(via
		(at 119.418354 -388.328662)
		(size 0.4064)
		(drill 0.2032)
		(layers "F.Cu" "B.Cu")
		(net "GND")
	)
	(via
		(at 85.290914 -270.846296)
		(size 0.4064)
		(drill 0.2032)
		(layers "F.Cu" "B.Cu")
		(net "GND")
	)
	(via
		(at 337.930998 -269.22603)
		(size 0.4064)
		(drill 0.2032)
		(layers "F.Cu" "B.Cu")
		(net "GND")
	)
	(via
		(at 349.221298 -160.573466)
		(size 0.49022)
		(drill 0.254)
		(layers "F.Cu" "B.Cu")
		(net "GND")
	)
	(via
		(at 150.012146 -404.46452)
		(size 0.4064)
		(drill 0.2032)
		(layers "F.Cu" "B.Cu")
		(net "GND")
	)
	(via
		(at 96.571054 -272.466308)
		(size 0.4064)
		(drill 0.2032)
		(layers "F.Cu" "B.Cu")
		(net "GND")
	)
	(via
		(at 334.283304 -378.07773)
		(size 0.508)
		(drill 0.254)
		(layers "F.Cu" "B.Cu")
		(net "GND")
	)
	(via
		(at 354.447602 -357.357172)
		(size 0.508)
		(drill 0.254)
		(layers "F.Cu" "B.Cu")
		(net "GND")
	)
	(via
		(at 100.331016 -280.566368)
		(size 0.4064)
		(drill 0.2032)
		(layers "F.Cu" "B.Cu")
		(net "GND")
	)
	(via
		(at 130.1623 -384.617722)
		(size 0.4064)
		(drill 0.2032)
		(layers "F.Cu" "B.Cu")
		(net "GND")
	)
	(via
		(at 444.23711 -0.762254)
		(size 0.508)
		(drill 0.254)
		(layers "F.Cu" "B.Cu")
		(net "GND")
	)
	(via
		(at 123.994672 -231.524302)
		(size 0.4064)
		(drill 0.2032)
		(layers "F.Cu" "B.Cu")
		(net "GND")
	)
	(via
		(at 321.87388 -331.750924)
		(size 0.508)
		(drill 0.254)
		(layers "F.Cu" "B.Cu")
		(net "GND")
	)
	(via
		(at 363.474762 -244.484144)
		(size 0.4064)
		(drill 0.2032)
		(layers "F.Cu" "B.Cu")
		(net "GND")
	)
	(via
		(at 106.405172 -255.53035)
		(size 0.4826)
		(drill 0.254)
		(layers "F.Cu" "B.Cu")
		(net "GND")
	)
	(via
		(at 455.306684 -22.718522)
		(size 0.6604)
		(drill 0.3302)
		(layers "F.Cu" "B.Cu")
		(net "GND")
	)
	(via
		(at 454.188068 -233.884978)
		(size 0.4826)
		(drill 0.254)
		(layers "F.Cu" "B.Cu")
		(net "GND")
	)
	(via
		(at 154.138122 -6.042152)
		(size 0.508)
		(drill 0.254)
		(layers "F.Cu" "B.Cu")
		(net "GND")
	)
	(via
		(at 106.01071 -414.14573)
		(size 0.508)
		(drill 0.254)
		(layers "F.Cu" "B.Cu")
		(net "GND")
	)
	(via
		(at 303.189386 -336.308446)
		(size 0.508)
		(drill 0.254)
		(layers "F.Cu" "B.Cu")
		(net "GND")
	)
	(via
		(at 107.870244 -377.00712)
		(size 0.508)
		(drill 0.254)
		(layers "F.Cu" "B.Cu")
		(net "GND")
	)
	(via
		(at 345.792298 -163.074604)
		(size 0.49022)
		(drill 0.254)
		(layers "F.Cu" "B.Cu")
		(net "GND")
	)
	(via
		(at 85.887052 -406.370536)
		(size 0.4572)
		(drill 0.254)
		(layers "F.Cu" "B.Cu")
		(net "GND")
	)
	(via
		(at 139.974828 -247.724422)
		(size 0.4064)
		(drill 0.2032)
		(layers "F.Cu" "B.Cu")
		(net "GND")
	)
	(via
		(at 258.057396 -439.90768)
		(size 0.508)
		(drill 0.254)
		(layers "F.Cu" "B.Cu")
		(net "GND")
	)
	(via
		(at 73.937114 -332.41615)
		(size 0.508)
		(drill 0.254)
		(layers "F.Cu" "B.Cu")
		(net "GND")
	)
	(via
		(at 36.23564 -111.48822)
		(size 0.508)
		(drill 0.254)
		(layers "F.Cu" "B.Cu")
		(net "GND")
	)
	(via
		(at 420.155624 -7.215124)
		(size 0.508)
		(drill 0.254)
		(layers "F.Cu" "B.Cu")
		(net "GND")
	)
	(via
		(at 251.854462 -55.069486)
		(size 0.508)
		(drill 0.254)
		(layers "F.Cu" "B.Cu")
		(net "GND")
	)
	(via
		(at 205.333854 -86.78418)
		(size 0.508)
		(drill 0.254)
		(layers "F.Cu" "B.Cu")
		(net "GND")
	)
	(via
		(at 58.043826 -202.435206)
		(size 0.4826)
		(drill 0.254)
		(layers "F.Cu" "B.Cu")
		(net "GND")
	)
	(via
		(at 114.15776 -332.330044)
		(size 0.508)
		(drill 0.254)
		(layers "F.Cu" "B.Cu")
		(net "GND")
	)
	(via
		(at 395.288262 -415.38652)
		(size 0.4064)
		(drill 0.2032)
		(layers "F.Cu" "B.Cu")
		(net "GND")
	)
	(via
		(at 390.695942 -412.84652)
		(size 0.4064)
		(drill 0.2032)
		(layers "F.Cu" "B.Cu")
		(net "GND")
	)
	(via
		(at 370.82476 -274.086066)
		(size 0.4064)
		(drill 0.2032)
		(layers "F.Cu" "B.Cu")
		(net "GND")
	)
	(via
		(at 110.671102 -274.08632)
		(size 0.4064)
		(drill 0.2032)
		(layers "F.Cu" "B.Cu")
		(net "GND")
	)
	(via
		(at 62.5475 -51.90744)
		(size 0.508)
		(drill 0.254)
		(layers "F.Cu" "B.Cu")
		(net "GND")
	)
	(via
		(at 397.718788 -384.175)
		(size 0.508)
		(drill 0.254)
		(layers "F.Cu" "B.Cu")
		(net "GND")
	)
	(via
		(at 291.162486 -229.210108)
		(size 0.4826)
		(drill 0.254)
		(layers "F.Cu" "B.Cu")
		(net "GND")
	)
	(via
		(at 393.084812 -256.634234)
		(size 0.4064)
		(drill 0.2032)
		(layers "F.Cu" "B.Cu")
		(net "GND")
	)
	(via
		(at 191.657224 -72.129904)
		(size 0.508)
		(drill 0.254)
		(layers "F.Cu" "B.Cu")
		(net "GND")
	)
	(via
		(at 283.351732 -202.434952)
		(size 0.4826)
		(drill 0.254)
		(layers "F.Cu" "B.Cu")
		(net "GND")
	)
	(via
		(at 280.635964 -245.785132)
		(size 0.4826)
		(drill 0.254)
		(layers "F.Cu" "B.Cu")
		(net "GND")
	)
	(via
		(at 2.76225 -322.509134)
		(size 0.508)
		(drill 0.254)
		(layers "F.Cu" "B.Cu")
		(net "GND")
	)
	(via
		(at 331.051154 -225.85426)
		(size 0.4064)
		(drill 0.2032)
		(layers "F.Cu" "B.Cu")
		(net "GND")
	)
	(via
		(at 108.321094 -291.096192)
		(size 0.4064)
		(drill 0.2032)
		(layers "F.Cu" "B.Cu")
		(net "GND")
	)
	(via
		(at 101.91115 -253.394464)
		(size 0.4064)
		(drill 0.2032)
		(layers "F.Cu" "B.Cu")
		(net "GND")
	)
	(via
		(at 390.334754 -421.586152)
		(size 0.4572)
		(drill 0.254)
		(layers "F.Cu" "B.Cu")
		(net "GND")
	)
	(via
		(at 102.855014 -259.73024)
		(size 0.4826)
		(drill 0.254)
		(layers "F.Cu" "B.Cu")
		(net "GND")
	)
	(via
		(at 282.020264 -231.335072)
		(size 0.4826)
		(drill 0.254)
		(layers "F.Cu" "B.Cu")
		(net "GND")
	)
	(via
		(at 81.701132 -233.144314)
		(size 0.4064)
		(drill 0.2032)
		(layers "F.Cu" "B.Cu")
		(net "GND")
	)
	(via
		(at 339.943948 -402.259038)
		(size 0.4572)
		(drill 0.254)
		(layers "F.Cu" "B.Cu")
		(net "GND")
	)
	(via
		(at 341.390986 -224.234248)
		(size 0.4064)
		(drill 0.2032)
		(layers "F.Cu" "B.Cu")
		(net "GND")
	)
	(via
		(at 56.411114 -344.137234)
		(size 0.508)
		(drill 0.254)
		(layers "F.Cu" "B.Cu")
		(net "GND")
	)
	(via
		(at 124.90196 -345.96578)
		(size 0.6604)
		(drill 0.3302)
		(layers "F.Cu" "B.Cu")
		(net "GND")
	)
	(via
		(at 453.964294 -397.811244)
		(size 0.49022)
		(drill 0.254)
		(layers "F.Cu" "B.Cu")
		(net "GND")
	)
	(via
		(at 126.34468 -255.014476)
		(size 0.4064)
		(drill 0.2032)
		(layers "F.Cu" "B.Cu")
		(net "GND")
	)
	(via
		(at 143.885666 -404.46452)
		(size 0.4064)
		(drill 0.2032)
		(layers "F.Cu" "B.Cu")
		(net "GND")
	)
	(via
		(at 304.809398 -40.890698)
		(size 0.508)
		(drill 0.254)
		(layers "F.Cu" "B.Cu")
		(net "GND")
	)
	(via
		(at 418.40404 -379.88113)
		(size 0.508)
		(drill 0.254)
		(layers "F.Cu" "B.Cu")
		(net "GND")
	)
	(via
		(at 416.5092 -110.739428)
		(size 0.508)
		(drill 0.254)
		(layers "F.Cu" "B.Cu")
		(net "GND")
	)
	(via
		(at 336.249518 -433.899564)
		(size 0.4572)
		(drill 0.2032)
		(layers "F.Cu" "B.Cu")
		(net "GND")
	)
	(via
		(at 344.249502 -431.451258)
		(size 0.4572)
		(drill 0.2032)
		(layers "F.Cu" "B.Cu")
		(net "GND")
	)
	(via
		(at 116.004848 -242.05438)
		(size 0.4064)
		(drill 0.2032)
		(layers "F.Cu" "B.Cu")
		(net "GND")
	)
	(via
		(at 125.716538 -393.927838)
		(size 0.4572)
		(drill 0.254)
		(layers "F.Cu" "B.Cu")
		(net "GND")
	)
	(via
		(at 312.459624 -74.184764)
		(size 0.508)
		(drill 0.254)
		(layers "F.Cu" "B.Cu")
		(net "GND")
	)
	(via
		(at 280.635964 -317.18504)
		(size 0.4826)
		(drill 0.254)
		(layers "F.Cu" "B.Cu")
		(net "GND")
	)
	(via
		(at 327.249536 -438.651396)
		(size 0.4572)
		(drill 0.2032)
		(layers "F.Cu" "B.Cu")
		(net "GND")
	)
	(via
		(at 398.68475 -6.598158)
		(size 0.508)
		(drill 0.254)
		(layers "F.Cu" "B.Cu")
		(net "GND")
	)
	(via
		(at 337.631024 -246.914162)
		(size 0.4064)
		(drill 0.2032)
		(layers "F.Cu" "B.Cu")
		(net "GND")
	)
	(via
		(at 277.192232 -268.735048)
		(size 0.4826)
		(drill 0.254)
		(layers "F.Cu" "B.Cu")
		(net "GND")
	)
	(via
		(at 318.912494 -420.318184)
		(size 0.4572)
		(drill 0.254)
		(layers "F.Cu" "B.Cu")
		(net "GND")
	)
	(via
		(at 296.547286 -339.822536)
		(size 0.508)
		(drill 0.254)
		(layers "F.Cu" "B.Cu")
		(net "GND")
	)
	(via
		(at 415.024316 -5.597398)
		(size 0.508)
		(drill 0.254)
		(layers "F.Cu" "B.Cu")
		(net "GND")
	)
	(via
		(at 74.71791 -154.83078)
		(size 0.508)
		(drill 0.254)
		(layers "F.Cu" "B.Cu")
		(net "GND")
	)
	(via
		(at 168.807384 -441.227718)
		(size 0.508)
		(drill 0.254)
		(layers "F.Cu" "B.Cu")
		(net "GND")
	)
	(via
		(at 341.144098 -400.212814)
		(size 0.4064)
		(drill 0.2032)
		(layers "F.Cu" "B.Cu")
		(net "GND")
	)
	(via
		(at 449.125086 -395.224)
		(size 0.508)
		(drill 0.254)
		(layers "F.Cu" "B.Cu")
		(net "GND")
	)
	(via
		(at 373.644922 -282.186126)
		(size 0.4064)
		(drill 0.2032)
		(layers "F.Cu" "B.Cu")
		(net "GND")
	)
	(via
		(at 70.38467 -154.55519)
		(size 0.508)
		(drill 0.254)
		(layers "F.Cu" "B.Cu")
		(net "GND")
	)
	(via
		(at 204.576934 -335.599278)
		(size 0.6604)
		(drill 0.3302)
		(layers "F.Cu" "B.Cu")
		(net "GND")
	)
	(via
		(at 183.616092 -235.585254)
		(size 0.4826)
		(drill 0.254)
		(layers "F.Cu" "B.Cu")
		(net "GND")
	)
	(via
		(at 326.658986 -412.84652)
		(size 0.4064)
		(drill 0.2032)
		(layers "F.Cu" "B.Cu")
		(net "GND")
	)
	(via
		(at 102.224078 -183.54421)
		(size 0.49022)
		(drill 0.254)
		(layers "F.Cu" "B.Cu")
		(net "GND")
	)
	(via
		(at 140.274802 -291.096192)
		(size 0.4064)
		(drill 0.2032)
		(layers "F.Cu" "B.Cu")
		(net "GND")
	)
	(via
		(at 36.795964 -248.335292)
		(size 0.4826)
		(drill 0.254)
		(layers "F.Cu" "B.Cu")
		(net "GND")
	)
	(via
		(at 145.444718 -275.706332)
		(size 0.4064)
		(drill 0.2032)
		(layers "F.Cu" "B.Cu")
		(net "GND")
	)
	(via
		(at 124.464826 -253.394464)
		(size 0.4064)
		(drill 0.2032)
		(layers "F.Cu" "B.Cu")
		(net "GND")
	)
	(via
		(at 248.144792 -421.48125)
		(size 0.508)
		(drill 0.254)
		(layers "F.Cu" "B.Cu")
		(net "GND")
	)
	(via
		(at 328.188828 -46.748954)
		(size 0.508)
		(drill 0.254)
		(layers "F.Cu" "B.Cu")
		(net "GND")
	)
	(via
		(at 370.524786 -246.914162)
		(size 0.4064)
		(drill 0.2032)
		(layers "F.Cu" "B.Cu")
		(net "GND")
	)
	(via
		(at 394.376148 -19.137122)
		(size 0.508)
		(drill 0.254)
		(layers "F.Cu" "B.Cu")
		(net "GND")
	)
	(via
		(at 385.394708 -270.036036)
		(size 0.4064)
		(drill 0.2032)
		(layers "F.Cu" "B.Cu")
		(net "GND")
	)
	(via
		(at 118.65483 -289.47618)
		(size 0.4064)
		(drill 0.2032)
		(layers "F.Cu" "B.Cu")
		(net "GND")
	)
	(via
		(at 385.864862 -293.525956)
		(size 0.4064)
		(drill 0.2032)
		(layers "F.Cu" "B.Cu")
		(net "GND")
	)
	(via
		(at 425.2087 -378.07773)
		(size 0.508)
		(drill 0.254)
		(layers "F.Cu" "B.Cu")
		(net "GND")
	)
	(via
		(at 191.160146 -196.485256)
		(size 0.4826)
		(drill 0.254)
		(layers "F.Cu" "B.Cu")
		(net "GND")
	)
	(via
		(at 344.211148 -245.29415)
		(size 0.4064)
		(drill 0.2032)
		(layers "F.Cu" "B.Cu")
		(net "GND")
	)
	(via
		(at 153.258266 -17.910048)
		(size 0.508)
		(drill 0.254)
		(layers "F.Cu" "B.Cu")
		(net "GND")
	)
	(via
		(at 332.249526 -432.747166)
		(size 0.4572)
		(drill 0.2032)
		(layers "F.Cu" "B.Cu")
		(net "GND")
	)
	(via
		(at 351.301304 -381.68453)
		(size 0.508)
		(drill 0.254)
		(layers "F.Cu" "B.Cu")
		(net "GND")
	)
	(via
		(at 349.602044 -382.34493)
		(size 0.508)
		(drill 0.254)
		(layers "F.Cu" "B.Cu")
		(net "GND")
	)
	(via
		(at 353.601528 -337.999324)
		(size 0.49022)
		(drill 0.254)
		(layers "F.Cu" "B.Cu")
		(net "GND")
	)
	(via
		(at 179.516024 -309.535322)
		(size 0.4826)
		(drill 0.254)
		(layers "F.Cu" "B.Cu")
		(net "GND")
	)
	(via
		(at 131.678172 -34.841434)
		(size 0.508)
		(drill 0.254)
		(layers "F.Cu" "B.Cu")
		(net "GND")
	)
	(via
		(at 401.349718 -437.34736)
		(size 0.4572)
		(drill 0.2032)
		(layers "F.Cu" "B.Cu")
		(net "GND")
	)
	(via
		(at 56.411114 -342.816434)
		(size 0.508)
		(drill 0.254)
		(layers "F.Cu" "B.Cu")
		(net "GND")
	)
	(via
		(at 80.120998 -276.516338)
		(size 0.4064)
		(drill 0.2032)
		(layers "F.Cu" "B.Cu")
		(net "GND")
	)
	(via
		(at 84.246466 -183.893968)
		(size 0.49022)
		(drill 0.254)
		(layers "F.Cu" "B.Cu")
		(net "GND")
	)
	(via
		(at 136.684766 -238.814356)
		(size 0.4064)
		(drill 0.2032)
		(layers "F.Cu" "B.Cu")
		(net "GND")
	)
	(via
		(at 29.345636 -7.215124)
		(size 0.508)
		(drill 0.254)
		(layers "F.Cu" "B.Cu")
		(net "GND")
	)
	(via
		(at 127.584708 -290.286186)
		(size 0.4064)
		(drill 0.2032)
		(layers "F.Cu" "B.Cu")
		(net "GND")
	)
	(via
		(at 407.806144 -394.831062)
		(size 0.4064)
		(drill 0.2032)
		(layers "F.Cu" "B.Cu")
		(net "GND")
	)
	(via
		(at 324.75297 -246.370094)
		(size 0.4064)
		(drill 0.2032)
		(layers "F.Cu" "B.Cu")
		(net "GND")
	)
	(via
		(at 90.683842 -368.37493)
		(size 0.508)
		(drill 0.254)
		(layers "F.Cu" "B.Cu")
		(net "GND")
	)
	(via
		(at 78.88097 -225.044508)
		(size 0.4064)
		(drill 0.2032)
		(layers "F.Cu" "B.Cu")
		(net "GND")
	)
	(via
		(at 85.290914 -267.606272)
		(size 0.4064)
		(drill 0.2032)
		(layers "F.Cu" "B.Cu")
		(net "GND")
	)
	(via
		(at 76.249784 -435.0512)
		(size 0.4572)
		(drill 0.2032)
		(layers "F.Cu" "B.Cu")
		(net "GND")
	)
	(via
		(at 125.267466 -167.131746)
		(size 0.49022)
		(drill 0.254)
		(layers "F.Cu" "B.Cu")
		(net "GND")
	)
	(via
		(at 46.666404 -314.210446)
		(size 0.4826)
		(drill 0.254)
		(layers "F.Cu" "B.Cu")
		(net "GND")
	)
	(via
		(at 71.741284 -404.46452)
		(size 0.4064)
		(drill 0.2032)
		(layers "F.Cu" "B.Cu")
		(net "GND")
	)
	(via
		(at 252.20041 -71.218806)
		(size 0.508)
		(drill 0.254)
		(layers "F.Cu" "B.Cu")
		(net "GND")
	)
	(via
		(at 467.5378 -272.847054)
		(size 0.508)
		(drill 0.254)
		(layers "F.Cu" "B.Cu")
		(net "GND")
	)
	(via
		(at 355.021134 -223.424242)
		(size 0.4064)
		(drill 0.2032)
		(layers "F.Cu" "B.Cu")
		(net "GND")
	)
	(via
		(at 109.869986 -413.385)
		(size 0.508)
		(drill 0.254)
		(layers "F.Cu" "B.Cu")
		(net "GND")
	)
	(via
		(at 443.6999 -194.88531)
		(size 0.4826)
		(drill 0.254)
		(layers "F.Cu" "B.Cu")
		(net "GND")
	)
	(via
		(at 287.193736 -418.325046)
		(size 0.4572)
		(drill 0.254)
		(layers "F.Cu" "B.Cu")
		(net "GND")
	)
	(via
		(at 402.587714 -413.480504)
		(size 0.4572)
		(drill 0.254)
		(layers "F.Cu" "B.Cu")
		(net "GND")
	)
	(via
		(at 25.152096 -298.485306)
		(size 0.4826)
		(drill 0.254)
		(layers "F.Cu" "B.Cu")
		(net "GND")
	)
	(via
		(at 386.098542 -418.412168)
		(size 0.4064)
		(drill 0.2032)
		(layers "F.Cu" "B.Cu")
		(net "GND")
	)
	(via
		(at 245.03888 -36.882324)
		(size 0.508)
		(drill 0.254)
		(layers "F.Cu" "B.Cu")
		(net "GND")
	)
	(via
		(at 354.851208 -277.32609)
		(size 0.4064)
		(drill 0.2032)
		(layers "F.Cu" "B.Cu")
		(net "GND")
	)
	(via
		(at 358.61117 -277.32609)
		(size 0.4064)
		(drill 0.2032)
		(layers "F.Cu" "B.Cu")
		(net "GND")
	)
	(via
		(at 327.937876 -384.299968)
		(size 0.508)
		(drill 0.254)
		(layers "F.Cu" "B.Cu")
		(net "GND")
	)
	(via
		(at 105.705402 -404.9903)
		(size 0.508)
		(drill 0.254)
		(layers "F.Cu" "B.Cu")
		(net "GND")
	)
	(via
		(at 368.644678 -232.334054)
		(size 0.4064)
		(drill 0.2032)
		(layers "F.Cu" "B.Cu")
		(net "GND")
	)
	(via
		(at 50.499772 -305.285394)
		(size 0.4826)
		(drill 0.254)
		(layers "F.Cu" "B.Cu")
		(net "GND")
	)
	(via
		(at 376.93473 -274.896072)
		(size 0.4064)
		(drill 0.2032)
		(layers "F.Cu" "B.Cu")
		(net "GND")
	)
	(via
		(at 419.34384 -18.247106)
		(size 0.508)
		(drill 0.254)
		(layers "F.Cu" "B.Cu")
		(net "GND")
	)
	(via
		(at 298.43984 -302.73498)
		(size 0.4826)
		(drill 0.254)
		(layers "F.Cu" "B.Cu")
		(net "GND")
	)
	(via
		(at 133.710172 -34.841434)
		(size 0.508)
		(drill 0.254)
		(layers "F.Cu" "B.Cu")
		(net "GND")
	)
	(via
		(at 116.004848 -238.814356)
		(size 0.4064)
		(drill 0.2032)
		(layers "F.Cu" "B.Cu")
		(net "GND")
	)
	(via
		(at 17.608042 -301.88535)
		(size 0.4826)
		(drill 0.254)
		(layers "F.Cu" "B.Cu")
		(net "GND")
	)
	(via
		(at 391.674858 -246.104156)
		(size 0.4064)
		(drill 0.2032)
		(layers "F.Cu" "B.Cu")
		(net "GND")
	)
	(via
		(at 273.092164 -272.135092)
		(size 0.4826)
		(drill 0.254)
		(layers "F.Cu" "B.Cu")
		(net "GND")
	)
	(via
		(at 204.8637 -295.9354)
		(size 0.4826)
		(drill 0.254)
		(layers "F.Cu" "B.Cu")
		(net "GND")
	)
	(via
		(at 372.234714 -261.935976)
		(size 0.4064)
		(drill 0.2032)
		(layers "F.Cu" "B.Cu")
		(net "GND")
	)
	(via
		(at 329.941174 -274.896072)
		(size 0.4064)
		(drill 0.2032)
		(layers "F.Cu" "B.Cu")
		(net "GND")
	)
	(via
		(at 167.655748 -170.881294)
		(size 0.508)
		(drill 0.254)
		(layers "F.Cu" "B.Cu")
		(net "GND")
	)
	(via
		(at 428.840392 -240.685066)
		(size 0.4826)
		(drill 0.254)
		(layers "F.Cu" "B.Cu")
		(net "GND")
	)
	(via
		(at 425.696888 -6.091174)
		(size 0.508)
		(drill 0.254)
		(layers "F.Cu" "B.Cu")
		(net "GND")
	)
	(via
		(at 198.12 -346.329)
		(size 0.508)
		(drill 0.254)
		(layers "F.Cu" "B.Cu")
		(net "GND")
	)
	(via
		(at 327.761092 -226.664266)
		(size 0.4064)
		(drill 0.2032)
		(layers "F.Cu" "B.Cu")
		(net "GND")
	)
	(via
		(at 135.574786 -287.856422)
		(size 0.4064)
		(drill 0.2032)
		(layers "F.Cu" "B.Cu")
		(net "GND")
	)
	(via
		(at 371.294914 -266.796012)
		(size 0.4064)
		(drill 0.2032)
		(layers "F.Cu" "B.Cu")
		(net "GND")
	)
	(via
		(at 180.671724 -194.885564)
		(size 0.4826)
		(drill 0.254)
		(layers "F.Cu" "B.Cu")
		(net "GND")
	)
	(via
		(at 192.277746 -304.010314)
		(size 0.4826)
		(drill 0.254)
		(layers "F.Cu" "B.Cu")
		(net "GND")
	)
	(via
		(at 56.21655 -391.830814)
		(size 0.4064)
		(drill 0.2032)
		(layers "F.Cu" "B.Cu")
		(net "GND")
	)
	(via
		(at 120.70461 -243.674392)
		(size 0.4064)
		(drill 0.2032)
		(layers "F.Cu" "B.Cu")
		(net "GND")
	)
	(via
		(at 283.618432 -238.560102)
		(size 0.4826)
		(drill 0.254)
		(layers "F.Cu" "B.Cu")
		(net "GND")
	)
	(via
		(at 327.761092 -241.24412)
		(size 0.4064)
		(drill 0.2032)
		(layers "F.Cu" "B.Cu")
		(net "GND")
	)
	(via
		(at 179.516024 -242.385342)
		(size 0.4826)
		(drill 0.254)
		(layers "F.Cu" "B.Cu")
		(net "GND")
	)
	(via
		(at 354.660708 -336.690208)
		(size 0.508)
		(drill 0.254)
		(layers "F.Cu" "B.Cu")
		(net "GND")
	)
	(via
		(at 124.934726 -252.584458)
		(size 0.4064)
		(drill 0.2032)
		(layers "F.Cu" "B.Cu")
		(net "GND")
	)
	(via
		(at 345.921076 -261.935976)
		(size 0.4064)
		(drill 0.2032)
		(layers "F.Cu" "B.Cu")
		(net "GND")
	)
	(via
		(at 403.349714 -436.347362)
		(size 0.4572)
		(drill 0.2032)
		(layers "F.Cu" "B.Cu")
		(net "GND")
	)
	(via
		(at 150.98522 -117.7544)
		(size 0.508)
		(drill 0.254)
		(layers "F.Cu" "B.Cu")
		(net "GND")
	)
	(via
		(at 408.109674 -169.743882)
		(size 0.49022)
		(drill 0.254)
		(layers "F.Cu" "B.Cu")
		(net "GND")
	)
	(via
		(at 318.998346 -418.412168)
		(size 0.4064)
		(drill 0.2032)
		(layers "F.Cu" "B.Cu")
		(net "GND")
	)
	(via
		(at 9.106408 -179.254912)
		(size 0.508)
		(drill 0.254)
		(layers "F.Cu" "B.Cu")
		(net "GND")
	)
	(via
		(at 80.120998 -274.896326)
		(size 0.4064)
		(drill 0.2032)
		(layers "F.Cu" "B.Cu")
		(net "GND")
	)
	(via
		(at 134.349744 -438.651396)
		(size 0.4572)
		(drill 0.2032)
		(layers "F.Cu" "B.Cu")
		(net "GND")
	)
	(via
		(at 291.162486 -210.51012)
		(size 0.4826)
		(drill 0.254)
		(layers "F.Cu" "B.Cu")
		(net "GND")
	)
	(via
		(at 26.509218 -16.979138)
		(size 0.508)
		(drill 0.254)
		(layers "F.Cu" "B.Cu")
		(net "GND")
	)
	(via
		(at 329.6412 -244.484144)
		(size 0.4064)
		(drill 0.2032)
		(layers "F.Cu" "B.Cu")
		(net "GND")
	)
	(via
		(at 443.9285 -306.135024)
		(size 0.4826)
		(drill 0.254)
		(layers "F.Cu" "B.Cu")
		(net "GND")
	)
	(via
		(at 268.263878 -312.084974)
		(size 0.4826)
		(drill 0.254)
		(layers "F.Cu" "B.Cu")
		(net "GND")
	)
	(via
		(at 413.349694 -428.851314)
		(size 0.4572)
		(drill 0.2032)
		(layers "F.Cu" "B.Cu")
		(net "GND")
	)
	(via
		(at 137.154666 -242.864386)
		(size 0.4064)
		(drill 0.2032)
		(layers "F.Cu" "B.Cu")
		(net "GND")
	)
	(via
		(at 99.95027 -180.704744)
		(size 0.49022)
		(drill 0.254)
		(layers "F.Cu" "B.Cu")
		(net "GND")
	)
	(via
		(at 2.76225 -149.281134)
		(size 0.508)
		(drill 0.254)
		(layers "F.Cu" "B.Cu")
		(net "GND")
	)
	(via
		(at 446.644268 -196.485002)
		(size 0.4826)
		(drill 0.254)
		(layers "F.Cu" "B.Cu")
		(net "GND")
	)
	(via
		(at 163.435538 -410.664152)
		(size 0.4572)
		(drill 0.254)
		(layers "F.Cu" "B.Cu")
		(net "GND")
	)
	(via
		(at 80.344264 -382.85293)
		(size 0.4064)
		(drill 0.2032)
		(layers "F.Cu" "B.Cu")
		(net "GND")
	)
	(via
		(at 146.854672 -294.336216)
		(size 0.4064)
		(drill 0.2032)
		(layers "F.Cu" "B.Cu")
		(net "GND")
	)
	(via
		(at 138.841226 -412.570168)
		(size 0.4064)
		(drill 0.2032)
		(layers "F.Cu" "B.Cu")
		(net "GND")
	)
	(via
		(at 125.040136 -259.73024)
		(size 0.4826)
		(drill 0.254)
		(layers "F.Cu" "B.Cu")
		(net "GND")
	)
	(via
		(at 57.071514 -342.816434)
		(size 0.508)
		(drill 0.254)
		(layers "F.Cu" "B.Cu")
		(net "GND")
	)
	(via
		(at 436.117746 -220.709998)
		(size 0.4826)
		(drill 0.254)
		(layers "F.Cu" "B.Cu")
		(net "GND")
	)
	(via
		(at 55.328058 -225.385376)
		(size 0.4826)
		(drill 0.254)
		(layers "F.Cu" "B.Cu")
		(net "GND")
	)
	(via
		(at 346.60078 -333.075534)
		(size 0.508)
		(drill 0.254)
		(layers "F.Cu" "B.Cu")
		(net "GND")
	)
	(via
		(at 217.762836 -70.133718)
		(size 0.508)
		(drill 0.254)
		(layers "F.Cu" "B.Cu")
		(net "GND")
	)
	(via
		(at 369.884706 -277.32609)
		(size 0.4064)
		(drill 0.2032)
		(layers "F.Cu" "B.Cu")
		(net "GND")
	)
	(via
		(at 114.59464 -233.144314)
		(size 0.4064)
		(drill 0.2032)
		(layers "F.Cu" "B.Cu")
		(net "GND")
	)
	(via
		(at 165.545516 -211.360258)
		(size 0.4826)
		(drill 0.254)
		(layers "F.Cu" "B.Cu")
		(net "GND")
	)
	(via
		(at 77.112876 -289.210242)
		(size 0.4064)
		(drill 0.2032)
		(layers "F.Cu" "B.Cu")
		(net "GND")
	)
	(via
		(at 417.585652 -275.960078)
		(size 0.4826)
		(drill 0.254)
		(layers "F.Cu" "B.Cu")
		(net "GND")
	)
	(via
		(at 96.20631 -185.937398)
		(size 0.508)
		(drill 0.254)
		(layers "F.Cu" "B.Cu")
		(net "GND")
	)
	(via
		(at 307.368194 -233.884978)
		(size 0.4826)
		(drill 0.254)
		(layers "F.Cu" "B.Cu")
		(net "GND")
	)
	(via
		(at 415.742882 -137.821416)
		(size 0.508)
		(drill 0.254)
		(layers "F.Cu" "B.Cu")
		(net "GND")
	)
	(via
		(at 289.243008 -412.655258)
		(size 0.508)
		(drill 0.254)
		(layers "F.Cu" "B.Cu")
		(net "GND")
	)
	(via
		(at 120.550178 -407.638504)
		(size 0.4572)
		(drill 0.254)
		(layers "F.Cu" "B.Cu")
		(net "GND")
	)
	(via
		(at 358.645206 -348.26956)
		(size 0.6604)
		(drill 0.3302)
		(layers "F.Cu" "B.Cu")
		(net "GND")
	)
	(via
		(at 78.24978 -428.851314)
		(size 0.4572)
		(drill 0.2032)
		(layers "F.Cu" "B.Cu")
		(net "GND")
	)
	(via
		(at 371.955314 -412.212536)
		(size 0.4572)
		(drill 0.254)
		(layers "F.Cu" "B.Cu")
		(net "GND")
	)
	(via
		(at 319.249552 -436.347362)
		(size 0.4572)
		(drill 0.2032)
		(layers "F.Cu" "B.Cu")
		(net "GND")
	)
	(via
		(at 159.113474 -407.638504)
		(size 0.4572)
		(drill 0.254)
		(layers "F.Cu" "B.Cu")
		(net "GND")
	)
	(via
		(at 83.41106 -265.98626)
		(size 0.4064)
		(drill 0.2032)
		(layers "F.Cu" "B.Cu")
		(net "GND")
	)
	(via
		(at 155.561538 -319.67805)
		(size 0.508)
		(drill 0.254)
		(layers "F.Cu" "B.Cu")
		(net "GND")
	)
	(via
		(at 32.695896 -266.185396)
		(size 0.4826)
		(drill 0.254)
		(layers "F.Cu" "B.Cu")
		(net "GND")
	)
	(via
		(at 61.845444 -5.84327)
		(size 0.508)
		(drill 0.254)
		(layers "F.Cu" "B.Cu")
		(net "GND")
	)
	(via
		(at 363.307884 -264.368026)
		(size 0.4064)
		(drill 0.2032)
		(layers "F.Cu" "B.Cu")
		(net "GND")
	)
	(via
		(at 321.87388 -331.090524)
		(size 0.508)
		(drill 0.254)
		(layers "F.Cu" "B.Cu")
		(net "GND")
	)
	(via
		(at 32.695896 -301.88535)
		(size 0.4826)
		(drill 0.254)
		(layers "F.Cu" "B.Cu")
		(net "GND")
	)
	(via
		(at 40.23995 -273.835368)
		(size 0.4826)
		(drill 0.254)
		(layers "F.Cu" "B.Cu")
		(net "GND")
	)
	(via
		(at 413.58185 -412.212536)
		(size 0.4572)
		(drill 0.254)
		(layers "F.Cu" "B.Cu")
		(net "GND")
	)
	(via
		(at 127.691134 -390.160002)
		(size 0.4064)
		(drill 0.2032)
		(layers "F.Cu" "B.Cu")
		(net "GND")
	)
	(via
		(at 117.884702 -225.854514)
		(size 0.4064)
		(drill 0.2032)
		(layers "F.Cu" "B.Cu")
		(net "GND")
	)
	(via
		(at 342.442546 -12.542266)
		(size 0.508)
		(drill 0.254)
		(layers "F.Cu" "B.Cu")
		(net "GND")
	)
	(via
		(at 144.732756 -387.04774)
		(size 0.4064)
		(drill 0.2032)
		(layers "F.Cu" "B.Cu")
		(net "GND")
	)
	(via
		(at 100.331016 -282.18638)
		(size 0.4064)
		(drill 0.2032)
		(layers "F.Cu" "B.Cu")
		(net "GND")
	)
	(via
		(at 177.189638 -275.960332)
		(size 0.4826)
		(drill 0.254)
		(layers "F.Cu" "B.Cu")
		(net "GND")
	)
	(via
		(at 198.7042 -278.935434)
		(size 0.4826)
		(drill 0.254)
		(layers "F.Cu" "B.Cu")
		(net "GND")
	)
	(via
		(at 280.635964 -242.385088)
		(size 0.4826)
		(drill 0.254)
		(layers "F.Cu" "B.Cu")
		(net "GND")
	)
	(via
		(at 298.66844 -193.99631)
		(size 0.4826)
		(drill 0.254)
		(layers "F.Cu" "B.Cu")
		(net "GND")
	)
	(via
		(at 378.814838 -289.475926)
		(size 0.4064)
		(drill 0.2032)
		(layers "F.Cu" "B.Cu")
		(net "GND")
	)
	(via
		(at 341.22106 -279.756108)
		(size 0.4064)
		(drill 0.2032)
		(layers "F.Cu" "B.Cu")
		(net "GND")
	)
	(via
		(at 188.177678 -314.210446)
		(size 0.4826)
		(drill 0.254)
		(layers "F.Cu" "B.Cu")
		(net "GND")
	)
	(via
		(at 167.143684 -230.485442)
		(size 0.4826)
		(drill 0.254)
		(layers "F.Cu" "B.Cu")
		(net "GND")
	)
	(via
		(at 392.614912 -225.044254)
		(size 0.4064)
		(drill 0.2032)
		(layers "F.Cu" "B.Cu")
		(net "GND")
	)
	(via
		(at 406.358598 -75.013312)
		(size 0.508)
		(drill 0.254)
		(layers "F.Cu" "B.Cu")
		(net "GND")
	)
	(via
		(at 102.07752 -176.83988)
		(size 0.508)
		(drill 0.254)
		(layers "F.Cu" "B.Cu")
		(net "GND")
	)
	(via
		(at 315.378338 -394.831062)
		(size 0.4064)
		(drill 0.2032)
		(layers "F.Cu" "B.Cu")
		(net "GND")
	)
	(via
		(at 375.29135 -416.020504)
		(size 0.4572)
		(drill 0.254)
		(layers "F.Cu" "B.Cu")
		(net "GND")
	)
	(via
		(at 86.871048 -248.534428)
		(size 0.4064)
		(drill 0.2032)
		(layers "F.Cu" "B.Cu")
		(net "GND")
	)
	(via
		(at 11.3284 -71.210678)
		(size 0.508)
		(drill 0.254)
		(layers "F.Cu" "B.Cu")
		(net "GND")
	)
	(via
		(at 113.48466 -295.146222)
		(size 0.4064)
		(drill 0.2032)
		(layers "F.Cu" "B.Cu")
		(net "GND")
	)
	(via
		(at 450.088 -245.785132)
		(size 0.4826)
		(drill 0.254)
		(layers "F.Cu" "B.Cu")
		(net "GND")
	)
	(via
		(at 305.983894 -302.73498)
		(size 0.4826)
		(drill 0.254)
		(layers "F.Cu" "B.Cu")
		(net "GND")
	)
	(via
		(at 95.472758 -333.090012)
		(size 0.49022)
		(drill 0.254)
		(layers "F.Cu" "B.Cu")
		(net "GND")
	)
	(via
		(at 21.70811 -205.83525)
		(size 0.4826)
		(drill 0.254)
		(layers "F.Cu" "B.Cu")
		(net "GND")
	)
	(via
		(at 118.824756 -245.294404)
		(size 0.4064)
		(drill 0.2032)
		(layers "F.Cu" "B.Cu")
		(net "GND")
	)
	(via
		(at 100.971096 -237.194344)
		(size 0.4064)
		(drill 0.2032)
		(layers "F.Cu" "B.Cu")
		(net "GND")
	)
	(via
		(at 144.166844 -371.49913)
		(size 0.508)
		(drill 0.254)
		(layers "F.Cu" "B.Cu")
		(net "GND")
	)
	(via
		(at 418.618924 -398.542002)
		(size 0.4064)
		(drill 0.2032)
		(layers "F.Cu" "B.Cu")
		(net "GND")
	)
	(via
		(at 38.722046 -413.646112)
		(size 0.4572)
		(drill 0.254)
		(layers "F.Cu" "B.Cu")
		(net "GND")
	)
	(via
		(at 368.944906 -282.186126)
		(size 0.4064)
		(drill 0.2032)
		(layers "F.Cu" "B.Cu")
		(net "GND")
	)
	(via
		(at 346.91828 -331.119734)
		(size 0.508)
		(drill 0.254)
		(layers "F.Cu" "B.Cu")
		(net "GND")
	)
	(via
		(at 372.404894 -233.954066)
		(size 0.4064)
		(drill 0.2032)
		(layers "F.Cu" "B.Cu")
		(net "GND")
	)
	(via
		(at 88.281002 -233.144314)
		(size 0.4064)
		(drill 0.2032)
		(layers "F.Cu" "B.Cu")
		(net "GND")
	)
	(via
		(at 105.200958 -241.244374)
		(size 0.4064)
		(drill 0.2032)
		(layers "F.Cu" "B.Cu")
		(net "GND")
	)
	(via
		(at 393.384786 -275.706078)
		(size 0.4064)
		(drill 0.2032)
		(layers "F.Cu" "B.Cu")
		(net "GND")
	)
	(via
		(at 126.491238 -390.160002)
		(size 0.4064)
		(drill 0.2032)
		(layers "F.Cu" "B.Cu")
		(net "GND")
	)
	(via
		(at 443.982602 -417.05911)
		(size 0.508)
		(drill 0.254)
		(layers "F.Cu" "B.Cu")
		(net "GND")
	)
	(via
		(at 78.711044 -282.18638)
		(size 0.4064)
		(drill 0.2032)
		(layers "F.Cu" "B.Cu")
		(net "GND")
	)
	(via
		(at 326.651112 -269.22603)
		(size 0.4064)
		(drill 0.2032)
		(layers "F.Cu" "B.Cu")
		(net "GND")
	)
	(via
		(at 294.875966 -343.472008)
		(size 0.508)
		(drill 0.254)
		(layers "F.Cu" "B.Cu")
		(net "GND")
	)
	(via
		(at 29.05887 -386.03809)
		(size 0.508)
		(drill 0.254)
		(layers "F.Cu" "B.Cu")
		(net "GND")
	)
	(via
		(at 171.97197 -311.235344)
		(size 0.4826)
		(drill 0.254)
		(layers "F.Cu" "B.Cu")
		(net "GND")
	)
	(via
		(at 399.68424 -377.41733)
		(size 0.508)
		(drill 0.254)
		(layers "F.Cu" "B.Cu")
		(net "GND")
	)
	(via
		(at 376.6185 -396.710662)
		(size 0.4064)
		(drill 0.2032)
		(layers "F.Cu" "B.Cu")
		(net "GND")
	)
	(via
		(at 391.974832 -274.896072)
		(size 0.4064)
		(drill 0.2032)
		(layers "F.Cu" "B.Cu")
		(net "GND")
	)
	(via
		(at 76.812902 -238.270288)
		(size 0.4064)
		(drill 0.2032)
		(layers "F.Cu" "B.Cu")
		(net "GND")
	)
	(via
		(at 432.67376 -285.310072)
		(size 0.4826)
		(drill 0.254)
		(layers "F.Cu" "B.Cu")
		(net "GND")
	)
	(via
		(at 84.52104 -223.424496)
		(size 0.4064)
		(drill 0.2032)
		(layers "F.Cu" "B.Cu")
		(net "GND")
	)
	(via
		(at 361.942634 -397.323056)
		(size 0.508)
		(drill 0.254)
		(layers "F.Cu" "B.Cu")
		(net "GND")
	)
	(via
		(at 133.394704 -229.90429)
		(size 0.4064)
		(drill 0.2032)
		(layers "F.Cu" "B.Cu")
		(net "GND")
	)
	(via
		(at 351.03943 -433.841652)
		(size 0.508)
		(drill 0.254)
		(layers "F.Cu" "B.Cu")
		(net "GND")
	)
	(via
		(at 402.274024 -18.247106)
		(size 0.508)
		(drill 0.254)
		(layers "F.Cu" "B.Cu")
		(net "GND")
	)
	(via
		(at 336.249518 -436.347362)
		(size 0.4572)
		(drill 0.2032)
		(layers "F.Cu" "B.Cu")
		(net "GND")
	)
	(via
		(at 96.571054 -290.286186)
		(size 0.4064)
		(drill 0.2032)
		(layers "F.Cu" "B.Cu")
		(net "GND")
	)
	(via
		(at 91.372436 -73.347072)
		(size 0.508)
		(drill 0.254)
		(layers "F.Cu" "B.Cu")
		(net "GND")
	)
	(via
		(at 265.54811 -272.135092)
		(size 0.4826)
		(drill 0.254)
		(layers "F.Cu" "B.Cu")
		(net "GND")
	)
	(via
		(at 29.252164 -261.935214)
		(size 0.4826)
		(drill 0.254)
		(layers "F.Cu" "B.Cu")
		(net "GND")
	)
	(via
		(at 339.511132 -237.19409)
		(size 0.4064)
		(drill 0.2032)
		(layers "F.Cu" "B.Cu")
		(net "GND")
	)
	(via
		(at 415.083752 -293.384986)
		(size 0.4826)
		(drill 0.254)
		(layers "F.Cu" "B.Cu")
		(net "GND")
	)
	(via
		(at 64.050418 -346.306902)
		(size 0.49022)
		(drill 0.254)
		(layers "F.Cu" "B.Cu")
		(net "GND")
	)
	(via
		(at 116.944648 -243.674392)
		(size 0.4064)
		(drill 0.2032)
		(layers "F.Cu" "B.Cu")
		(net "GND")
	)
	(via
		(at 146.855688 -58.773822)
		(size 0.508)
		(drill 0.254)
		(layers "F.Cu" "B.Cu")
		(net "GND")
	)
	(via
		(at 189.35065 -329.500484)
		(size 0.508)
		(drill 0.254)
		(layers "F.Cu" "B.Cu")
		(net "GND")
	)
	(via
		(at 183.616092 -204.135228)
		(size 0.4826)
		(drill 0.254)
		(layers "F.Cu" "B.Cu")
		(net "GND")
	)
	(via
		(at 72.584818 -333.83474)
		(size 0.49022)
		(drill 0.254)
		(layers "F.Cu" "B.Cu")
		(net "GND")
	)
	(via
		(at 400.523964 -17.61236)
		(size 0.508)
		(drill 0.254)
		(layers "F.Cu" "B.Cu")
		(net "GND")
	)
	(via
		(at 348.013274 -419.046152)
		(size 0.4572)
		(drill 0.254)
		(layers "F.Cu" "B.Cu")
		(net "GND")
	)
	(via
		(at 371.764814 -261.12597)
		(size 0.4064)
		(drill 0.2032)
		(layers "F.Cu" "B.Cu")
		(net "GND")
	)
	(via
		(at 41.62425 -203.285344)
		(size 0.4826)
		(drill 0.254)
		(layers "F.Cu" "B.Cu")
		(net "GND")
	)
	(via
		(at 284.736032 -278.93518)
		(size 0.4826)
		(drill 0.254)
		(layers "F.Cu" "B.Cu")
		(net "GND")
	)
	(via
		(at 141.46911 -386.476494)
		(size 0.508)
		(drill 0.254)
		(layers "F.Cu" "B.Cu")
		(net "GND")
	)
	(via
		(at 450.088 -234.735116)
		(size 0.4826)
		(drill 0.254)
		(layers "F.Cu" "B.Cu")
		(net "GND")
	)
	(via
		(at 141.854682 -252.584458)
		(size 0.4064)
		(drill 0.2032)
		(layers "F.Cu" "B.Cu")
		(net "GND")
	)
	(via
		(at 147.042886 -292.450266)
		(size 0.4064)
		(drill 0.2032)
		(layers "F.Cu" "B.Cu")
		(net "GND")
	)
	(via
		(at 388.21487 -261.935976)
		(size 0.4064)
		(drill 0.2032)
		(layers "F.Cu" "B.Cu")
		(net "GND")
	)
	(via
		(at 335.11109 -274.086066)
		(size 0.4064)
		(drill 0.2032)
		(layers "F.Cu" "B.Cu")
		(net "GND")
	)
	(via
		(at 442.5442 -273.835114)
		(size 0.4826)
		(drill 0.254)
		(layers "F.Cu" "B.Cu")
		(net "GND")
	)
	(via
		(at 358.001824 -390.619488)
		(size 0.508)
		(drill 0.254)
		(layers "F.Cu" "B.Cu")
		(net "GND")
	)
	(via
		(at 194.604132 -266.185396)
		(size 0.4826)
		(drill 0.254)
		(layers "F.Cu" "B.Cu")
		(net "GND")
	)
	(via
		(at 451.2056 -202.01001)
		(size 0.4826)
		(drill 0.254)
		(layers "F.Cu" "B.Cu")
		(net "GND")
	)
	(via
		(at 157.783784 -368.37493)
		(size 0.508)
		(drill 0.254)
		(layers "F.Cu" "B.Cu")
		(net "GND")
	)
	(via
		(at 425.129706 -238.560102)
		(size 0.4826)
		(drill 0.254)
		(layers "F.Cu" "B.Cu")
		(net "GND")
	)
	(via
		(at 99.561142 -249.344434)
		(size 0.4064)
		(drill 0.2032)
		(layers "F.Cu" "B.Cu")
		(net "GND")
	)
	(via
		(at 372.404894 -232.334054)
		(size 0.4064)
		(drill 0.2032)
		(layers "F.Cu" "B.Cu")
		(net "GND")
	)
	(via
		(at 265.54811 -245.785132)
		(size 0.4826)
		(drill 0.254)
		(layers "F.Cu" "B.Cu")
		(net "GND")
	)
	(via
		(at 147.042886 -268.15034)
		(size 0.4064)
		(drill 0.2032)
		(layers "F.Cu" "B.Cu")
		(net "GND")
	)
	(via
		(at 82.249772 -430.147222)
		(size 0.4572)
		(drill 0.2032)
		(layers "F.Cu" "B.Cu")
		(net "GND")
	)
	(via
		(at 464.537806 -428.898812)
		(size 0.508)
		(drill 0.254)
		(layers "F.Cu" "B.Cu")
		(net "GND")
	)
	(via
		(at 337.930998 -278.946102)
		(size 0.4064)
		(drill 0.2032)
		(layers "F.Cu" "B.Cu")
		(net "GND")
	)
	(via
		(at 215.06815 -322.52539)
		(size 0.508)
		(drill 0.254)
		(layers "F.Cu" "B.Cu")
		(net "GND")
	)
	(via
		(at 18.992342 -228.78542)
		(size 0.4826)
		(drill 0.254)
		(layers "F.Cu" "B.Cu")
		(net "GND")
	)
	(via
		(at 374.584722 -267.606018)
		(size 0.4064)
		(drill 0.2032)
		(layers "F.Cu" "B.Cu")
		(net "GND")
	)
	(via
		(at 87.171022 -277.326344)
		(size 0.4064)
		(drill 0.2032)
		(layers "F.Cu" "B.Cu")
		(net "GND")
	)
	(via
		(at 417.419028 -398.542002)
		(size 0.4064)
		(drill 0.2032)
		(layers "F.Cu" "B.Cu")
		(net "GND")
	)
	(via
		(at 135.866378 -409.396184)
		(size 0.4572)
		(drill 0.254)
		(layers "F.Cu" "B.Cu")
		(net "GND")
	)
	(via
		(at 424.012106 -301.034958)
		(size 0.4826)
		(drill 0.254)
		(layers "F.Cu" "B.Cu")
		(net "GND")
	)
	(via
		(at 38.220142 -6.598158)
		(size 0.508)
		(drill 0.254)
		(layers "F.Cu" "B.Cu")
		(net "GND")
	)
	(via
		(at 321.249548 -430.147222)
		(size 0.4572)
		(drill 0.2032)
		(layers "F.Cu" "B.Cu")
		(net "GND")
	)
	(via
		(at 140.444728 -256.634488)
		(size 0.4064)
		(drill 0.2032)
		(layers "F.Cu" "B.Cu")
		(net "GND")
	)
	(via
		(at 379.88621 -412.212536)
		(size 0.4572)
		(drill 0.254)
		(layers "F.Cu" "B.Cu")
		(net "GND")
	)
	(via
		(at 275.807932 -305.28514)
		(size 0.4826)
		(drill 0.254)
		(layers "F.Cu" "B.Cu")
		(net "GND")
	)
	(via
		(at 284.736032 -271.284954)
		(size 0.4826)
		(drill 0.254)
		(layers "F.Cu" "B.Cu")
		(net "GND")
	)
	(via
		(at 150.488904 -370.83873)
		(size 0.508)
		(drill 0.254)
		(layers "F.Cu" "B.Cu")
		(net "GND")
	)
	(via
		(at 338.498942 -138.660886)
		(size 0.508)
		(drill 0.254)
		(layers "F.Cu" "B.Cu")
		(net "GND")
	)
	(via
		(at 308.318154 -396.710662)
		(size 0.4064)
		(drill 0.2032)
		(layers "F.Cu" "B.Cu")
		(net "GND")
	)
	(via
		(at 63.24981 -435.0512)
		(size 0.4572)
		(drill 0.2032)
		(layers "F.Cu" "B.Cu")
		(net "GND")
	)
	(via
		(at 63.24981 -425.547282)
		(size 0.4572)
		(drill 0.2032)
		(layers "F.Cu" "B.Cu")
		(net "GND")
	)
	(via
		(at 342.547194 -309.489602)
		(size 0.508)
		(drill 0.254)
		(layers "F.Cu" "B.Cu")
		(net "GND")
	)
	(via
		(at 351.024952 -339.535516)
		(size 0.49022)
		(drill 0.254)
		(layers "F.Cu" "B.Cu")
		(net "GND")
	)
	(via
		(at 127.584708 -275.706332)
		(size 0.4064)
		(drill 0.2032)
		(layers "F.Cu" "B.Cu")
		(net "GND")
	)
	(via
		(at 362.534708 -247.724168)
		(size 0.4064)
		(drill 0.2032)
		(layers "F.Cu" "B.Cu")
		(net "GND")
	)
	(via
		(at 396.648178 -12.37488)
		(size 0.508)
		(drill 0.254)
		(layers "F.Cu" "B.Cu")
		(net "GND")
	)
	(via
		(at 139.974828 -228.284532)
		(size 0.4064)
		(drill 0.2032)
		(layers "F.Cu" "B.Cu")
		(net "GND")
	)
	(via
		(at 307.368194 -253.435104)
		(size 0.4826)
		(drill 0.254)
		(layers "F.Cu" "B.Cu")
		(net "GND")
	)
	(via
		(at 92.013532 -407.638504)
		(size 0.4572)
		(drill 0.254)
		(layers "F.Cu" "B.Cu")
		(net "GND")
	)
	(via
		(at 366.294924 -247.724168)
		(size 0.4064)
		(drill 0.2032)
		(layers "F.Cu" "B.Cu")
		(net "GND")
	)
	(via
		(at 300.99 -355.854)
		(size 0.508)
		(drill 0.254)
		(layers "F.Cu" "B.Cu")
		(net "GND")
	)
	(via
		(at 327.937876 -388.917688)
		(size 0.508)
		(drill 0.254)
		(layers "F.Cu" "B.Cu")
		(net "GND")
	)
	(via
		(at 40.642794 -422.638982)
		(size 0.508)
		(drill 0.254)
		(layers "F.Cu" "B.Cu")
		(net "GND")
	)
	(via
		(at 456.131676 -65.206626)
		(size 0.508)
		(drill 0.254)
		(layers "F.Cu" "B.Cu")
		(net "GND")
	)
	(via
		(at 126.478538 -386.449062)
		(size 0.4064)
		(drill 0.2032)
		(layers "F.Cu" "B.Cu")
		(net "GND")
	)
	(via
		(at 348.271084 -262.745982)
		(size 0.4064)
		(drill 0.2032)
		(layers "F.Cu" "B.Cu")
		(net "GND")
	)
	(via
		(at 99.320604 -177.551334)
		(size 0.508)
		(drill 0.254)
		(layers "F.Cu" "B.Cu")
		(net "GND")
	)
	(via
		(at 193.6242 -47.98314)
		(size 0.508)
		(drill 0.254)
		(layers "F.Cu" "B.Cu")
		(net "GND")
	)
	(via
		(at 342.03132 -362.01096)
		(size 0.508)
		(drill 0.254)
		(layers "F.Cu" "B.Cu")
		(net "GND")
	)
	(via
		(at 149.349714 -438.499758)
		(size 0.4572)
		(drill 0.2032)
		(layers "F.Cu" "B.Cu")
		(net "GND")
	)
	(via
		(at 98.451162 -280.566368)
		(size 0.4064)
		(drill 0.2032)
		(layers "F.Cu" "B.Cu")
		(net "GND")
	)
	(via
		(at 129.83718 -57.882028)
		(size 0.508)
		(drill 0.254)
		(layers "F.Cu" "B.Cu")
		(net "GND")
	)
	(via
		(at 81.019396 -407.638504)
		(size 0.4572)
		(drill 0.254)
		(layers "F.Cu" "B.Cu")
		(net "GND")
	)
	(via
		(at 303.849786 -336.308446)
		(size 0.508)
		(drill 0.254)
		(layers "F.Cu" "B.Cu")
		(net "GND")
	)
	(via
		(at 422.180766 -401.873212)
		(size 0.508)
		(drill 0.254)
		(layers "F.Cu" "B.Cu")
		(net "GND")
	)
	(via
		(at 242.593114 -318.704468)
		(size 0.508)
		(drill 0.254)
		(layers "F.Cu" "B.Cu")
		(net "GND")
	)
	(via
		(at 333.701136 -294.335962)
		(size 0.4064)
		(drill 0.2032)
		(layers "F.Cu" "B.Cu")
		(net "GND")
	)
	(via
		(at 467.5378 -306.375054)
		(size 0.508)
		(drill 0.254)
		(layers "F.Cu" "B.Cu")
		(net "GND")
	)
	(via
		(at 34.080196 -303.585372)
		(size 0.4826)
		(drill 0.254)
		(layers "F.Cu" "B.Cu")
		(net "GND")
	)
	(via
		(at 59.428126 -289.98545)
		(size 0.4826)
		(drill 0.254)
		(layers "F.Cu" "B.Cu")
		(net "GND")
	)
	(via
		(at 74.959464 -355.760528)
		(size 0.508)
		(drill 0.254)
		(layers "F.Cu" "B.Cu")
		(net "GND")
	)
	(via
		(at 29.252164 -207.535272)
		(size 0.4826)
		(drill 0.254)
		(layers "F.Cu" "B.Cu")
		(net "GND")
	)
	(via
		(at 182.231792 -237.285276)
		(size 0.4826)
		(drill 0.254)
		(layers "F.Cu" "B.Cu")
		(net "GND")
	)
	(via
		(at 446.644268 -299.33519)
		(size 0.4826)
		(drill 0.254)
		(layers "F.Cu" "B.Cu")
		(net "GND")
	)
	(via
		(at 32.695896 -273.835368)
		(size 0.4826)
		(drill 0.254)
		(layers "F.Cu" "B.Cu")
		(net "GND")
	)
	(via
		(at 329.249532 -439.651394)
		(size 0.4572)
		(drill 0.2032)
		(layers "F.Cu" "B.Cu")
		(net "GND")
	)
	(via
		(at 136.34974 -432.451256)
		(size 0.4572)
		(drill 0.2032)
		(layers "F.Cu" "B.Cu")
		(net "GND")
	)
	(via
		(at 352.031046 -293.525956)
		(size 0.4064)
		(drill 0.2032)
		(layers "F.Cu" "B.Cu")
		(net "GND")
	)
	(via
		(at 285.01721 -344.77706)
		(size 0.49022)
		(drill 0.254)
		(layers "F.Cu" "B.Cu")
		(net "GND")
	)
	(via
		(at 396.645638 -10.16508)
		(size 0.508)
		(drill 0.254)
		(layers "F.Cu" "B.Cu")
		(net "GND")
	)
	(via
		(at 78.88097 -221.804484)
		(size 0.4064)
		(drill 0.2032)
		(layers "F.Cu" "B.Cu")
		(net "GND")
	)
	(via
		(at 25.152096 -289.135312)
		(size 0.4826)
		(drill 0.254)
		(layers "F.Cu" "B.Cu")
		(net "GND")
	)
	(via
		(at 157.04439 -393.927838)
		(size 0.4572)
		(drill 0.254)
		(layers "F.Cu" "B.Cu")
		(net "GND")
	)
	(via
		(at 339.654134 -340.039706)
		(size 0.508)
		(drill 0.254)
		(layers "F.Cu" "B.Cu")
		(net "GND")
	)
	(via
		(at 115.834668 -284.616398)
		(size 0.4064)
		(drill 0.2032)
		(layers "F.Cu" "B.Cu")
		(net "GND")
	)
	(via
		(at 329.722226 -412.84652)
		(size 0.4064)
		(drill 0.2032)
		(layers "F.Cu" "B.Cu")
		(net "GND")
	)
	(via
		(at 59.428126 -278.935434)
		(size 0.4826)
		(drill 0.254)
		(layers "F.Cu" "B.Cu")
		(net "GND")
	)
	(via
		(at 303.824386 -336.943446)
		(size 0.508)
		(drill 0.254)
		(layers "F.Cu" "B.Cu")
		(net "GND")
	)
	(via
		(at 412.367984 -309.535068)
		(size 0.4826)
		(drill 0.254)
		(layers "F.Cu" "B.Cu")
		(net "GND")
	)
	(via
		(at 294.574214 -424.118786)
		(size 0.508)
		(drill 0.254)
		(layers "F.Cu" "B.Cu")
		(net "GND")
	)
	(via
		(at 381.954278 -180.755544)
		(size 0.49022)
		(drill 0.254)
		(layers "F.Cu" "B.Cu")
		(net "GND")
	)
	(via
		(at 326.570594 -417.778184)
		(size 0.4572)
		(drill 0.254)
		(layers "F.Cu" "B.Cu")
		(net "GND")
	)
	(via
		(at 280.635964 -234.735116)
		(size 0.4826)
		(drill 0.254)
		(layers "F.Cu" "B.Cu")
		(net "GND")
	)
	(via
		(at 52.813712 -0.762254)
		(size 0.508)
		(drill 0.254)
		(layers "F.Cu" "B.Cu")
		(net "GND")
	)
	(via
		(at 286.570166 -344.132408)
		(size 0.508)
		(drill 0.254)
		(layers "F.Cu" "B.Cu")
		(net "GND")
	)
	(via
		(at 351.059242 -155.98902)
		(size 0.508)
		(drill 0.254)
		(layers "F.Cu" "B.Cu")
		(net "GND")
	)
	(via
		(at 359.33126 -336.499962)
		(size 0.508)
		(drill 0.254)
		(layers "F.Cu" "B.Cu")
		(net "GND")
	)
	(via
		(at 303.268126 -307.835046)
		(size 0.4826)
		(drill 0.254)
		(layers "F.Cu" "B.Cu")
		(net "GND")
	)
	(via
		(at 436.117746 -295.510204)
		(size 0.4826)
		(drill 0.254)
		(layers "F.Cu" "B.Cu")
		(net "GND")
	)
	(via
		(at 47.784004 -225.385376)
		(size 0.4826)
		(drill 0.254)
		(layers "F.Cu" "B.Cu")
		(net "GND")
	)
	(via
		(at 338.249514 -437.34736)
		(size 0.4572)
		(drill 0.2032)
		(layers "F.Cu" "B.Cu")
		(net "GND")
	)
	(via
		(at 74.535792 -20.951444)
		(size 0.508)
		(drill 0.254)
		(layers "F.Cu" "B.Cu")
		(net "GND")
	)
	(via
		(at 339.511132 -224.234248)
		(size 0.4064)
		(drill 0.2032)
		(layers "F.Cu" "B.Cu")
		(net "GND")
	)
	(via
		(at 52.52847 -160.62579)
		(size 0.508)
		(drill 0.254)
		(layers "F.Cu" "B.Cu")
		(net "GND")
	)
	(via
		(at 118.781576 -89.767918)
		(size 0.508)
		(drill 0.254)
		(layers "F.Cu" "B.Cu")
		(net "GND")
	)
	(via
		(at 329.569064 -331.083412)
		(size 0.508)
		(drill 0.254)
		(layers "F.Cu" "B.Cu")
		(net "GND")
	)
	(via
		(at 364.955074 -179.710588)
		(size 0.49022)
		(drill 0.254)
		(layers "F.Cu" "B.Cu")
		(net "GND")
	)
	(via
		(at 308.757574 -23.201884)
		(size 0.508)
		(drill 0.254)
		(layers "F.Cu" "B.Cu")
		(net "GND")
	)
	(via
		(at 191.160146 -233.885232)
		(size 0.4826)
		(drill 0.254)
		(layers "F.Cu" "B.Cu")
		(net "GND")
	)
	(via
		(at 394.84554 -10.16508)
		(size 0.508)
		(drill 0.254)
		(layers "F.Cu" "B.Cu")
		(net "GND")
	)
	(via
		(at 96.27108 -237.194344)
		(size 0.4064)
		(drill 0.2032)
		(layers "F.Cu" "B.Cu")
		(net "GND")
	)
	(via
		(at 116.205508 -22.100794)
		(size 0.508)
		(drill 0.254)
		(layers "F.Cu" "B.Cu")
		(net "GND")
	)
	(via
		(at 403.747478 -318.205612)
		(size 0.508)
		(drill 0.254)
		(layers "F.Cu" "B.Cu")
		(net "GND")
	)
	(via
		(at 152.986994 -410.664152)
		(size 0.4572)
		(drill 0.254)
		(layers "F.Cu" "B.Cu")
		(net "GND")
	)
	(via
		(at 115.534694 -247.724422)
		(size 0.4064)
		(drill 0.2032)
		(layers "F.Cu" "B.Cu")
		(net "GND")
	)
	(via
		(at 445.259968 -302.73498)
		(size 0.4826)
		(drill 0.254)
		(layers "F.Cu" "B.Cu")
		(net "GND")
	)
	(via
		(at 89.99093 -290.286186)
		(size 0.4064)
		(drill 0.2032)
		(layers "F.Cu" "B.Cu")
		(net "GND")
	)
	(via
		(at 105.500932 -276.516338)
		(size 0.4064)
		(drill 0.2032)
		(layers "F.Cu" "B.Cu")
		(net "GND")
	)
	(via
		(at 405.27224 -382.34493)
		(size 0.508)
		(drill 0.254)
		(layers "F.Cu" "B.Cu")
		(net "GND")
	)
	(via
		(at 303.715166 -150.119588)
		(size 0.508)
		(drill 0.254)
		(layers "F.Cu" "B.Cu")
		(net "GND")
	)
	(via
		(at 93.545152 -403.830536)
		(size 0.4572)
		(drill 0.254)
		(layers "F.Cu" "B.Cu")
		(net "GND")
	)
	(via
		(at 436.715154 -441.227718)
		(size 0.508)
		(drill 0.254)
		(layers "F.Cu" "B.Cu")
		(net "GND")
	)
	(via
		(at 94.151958 -333.090012)
		(size 0.49022)
		(drill 0.254)
		(layers "F.Cu" "B.Cu")
		(net "GND")
	)
	(via
		(at 280.635964 -307.835046)
		(size 0.4826)
		(drill 0.254)
		(layers "F.Cu" "B.Cu")
		(net "GND")
	)
	(via
		(at 419.890194 -392.999722)
		(size 0.4064)
		(drill 0.2032)
		(layers "F.Cu" "B.Cu")
		(net "GND")
	)
	(via
		(at 372.259352 -383.00533)
		(size 0.508)
		(drill 0.254)
		(layers "F.Cu" "B.Cu")
		(net "GND")
	)
	(via
		(at 125.417834 -409.396184)
		(size 0.4572)
		(drill 0.254)
		(layers "F.Cu" "B.Cu")
		(net "GND")
	)
	(via
		(at 339.589872 -392.999722)
		(size 0.4064)
		(drill 0.2032)
		(layers "F.Cu" "B.Cu")
		(net "GND")
	)
	(via
		(at 174.188882 -20.007072)
		(size 0.508)
		(drill 0.254)
		(layers "F.Cu" "B.Cu")
		(net "GND")
	)
	(via
		(at 373.344694 -235.574078)
		(size 0.4064)
		(drill 0.2032)
		(layers "F.Cu" "B.Cu")
		(net "GND")
	)
	(via
		(at 105.905046 -338.774024)
		(size 0.49022)
		(drill 0.254)
		(layers "F.Cu" "B.Cu")
		(net "GND")
	)
	(via
		(at 391.204704 -233.954066)
		(size 0.4064)
		(drill 0.2032)
		(layers "F.Cu" "B.Cu")
		(net "GND")
	)
	(via
		(at 299.82414 -289.985196)
		(size 0.4826)
		(drill 0.254)
		(layers "F.Cu" "B.Cu")
		(net "GND")
	)
	(via
		(at 399.979388 -5.597398)
		(size 0.508)
		(drill 0.254)
		(layers "F.Cu" "B.Cu")
		(net "GND")
	)
	(via
		(at 141.854682 -225.044508)
		(size 0.4064)
		(drill 0.2032)
		(layers "F.Cu" "B.Cu")
		(net "GND")
	)
	(via
		(at 401.041616 -183.85536)
		(size 0.508)
		(drill 0.254)
		(layers "F.Cu" "B.Cu")
		(net "GND")
	)
	(via
		(at 90.249756 -427.699678)
		(size 0.4572)
		(drill 0.2032)
		(layers "F.Cu" "B.Cu")
		(net "GND")
	)
	(via
		(at 331.351128 -278.946102)
		(size 0.4064)
		(drill 0.2032)
		(layers "F.Cu" "B.Cu")
		(net "GND")
	)
	(via
		(at 399.524474 -421.586152)
		(size 0.4572)
		(drill 0.254)
		(layers "F.Cu" "B.Cu")
		(net "GND")
	)
	(via
		(at 381.634746 -278.136096)
		(size 0.4064)
		(drill 0.2032)
		(layers "F.Cu" "B.Cu")
		(net "GND")
	)
	(via
		(at 157.1244 -40.8305)
		(size 0.508)
		(drill 0.254)
		(layers "F.Cu" "B.Cu")
		(net "GND")
	)
	(via
		(at 347.931232 -22.247098)
		(size 0.508)
		(drill 0.254)
		(layers "F.Cu" "B.Cu")
		(net "GND")
	)
	(via
		(at 119.379746 -404.46452)
		(size 0.4064)
		(drill 0.2032)
		(layers "F.Cu" "B.Cu")
		(net "GND")
	)
	(via
		(at 406.4889 -379.22073)
		(size 0.508)
		(drill 0.254)
		(layers "F.Cu" "B.Cu")
		(net "GND")
	)
	(via
		(at 81.832196 -24.757888)
		(size 0.6604)
		(drill 0.3302)
		(layers "F.Cu" "B.Cu")
		(net "GND")
	)
	(via
		(at 402.048218 -12.37488)
		(size 0.508)
		(drill 0.254)
		(layers "F.Cu" "B.Cu")
		(net "GND")
	)
	(via
		(at 454.159366 -378.81687)
		(size 0.508)
		(drill 0.254)
		(layers "F.Cu" "B.Cu")
		(net "GND")
	)
	(via
		(at 55.328058 -318.885316)
		(size 0.4826)
		(drill 0.254)
		(layers "F.Cu" "B.Cu")
		(net "GND")
	)
	(via
		(at 130.361436 -370.83873)
		(size 0.508)
		(drill 0.254)
		(layers "F.Cu" "B.Cu")
		(net "GND")
	)
	(via
		(at 89.99093 -265.98626)
		(size 0.4064)
		(drill 0.2032)
		(layers "F.Cu" "B.Cu")
		(net "GND")
	)
	(via
		(at 361.124754 -245.29415)
		(size 0.4064)
		(drill 0.2032)
		(layers "F.Cu" "B.Cu")
		(net "GND")
	)
	(via
		(at 69.577712 -0.762254)
		(size 0.508)
		(drill 0.254)
		(layers "F.Cu" "B.Cu")
		(net "GND")
	)
	(via
		(at 195.721732 -202.010264)
		(size 0.4826)
		(drill 0.254)
		(layers "F.Cu" "B.Cu")
		(net "GND")
	)
	(via
		(at 206.54645 -107.362498)
		(size 0.508)
		(drill 0.254)
		(layers "F.Cu" "B.Cu")
		(net "GND")
	)
	(via
		(at 372.234714 -273.27606)
		(size 0.4064)
		(drill 0.2032)
		(layers "F.Cu" "B.Cu")
		(net "GND")
	)
	(via
		(at 112.205008 -388.29615)
		(size 0.4064)
		(drill 0.2032)
		(layers "F.Cu" "B.Cu")
		(net "GND")
	)
	(via
		(at 420.24427 -400.212814)
		(size 0.4064)
		(drill 0.2032)
		(layers "F.Cu" "B.Cu")
		(net "GND")
	)
	(via
		(at 54.981856 -403.830536)
		(size 0.4572)
		(drill 0.254)
		(layers "F.Cu" "B.Cu")
		(net "GND")
	)
	(via
		(at 58.5597 -352.23196)
		(size 0.508)
		(drill 0.254)
		(layers "F.Cu" "B.Cu")
		(net "GND")
	)
	(via
		(at 233.86288 -36.882324)
		(size 0.508)
		(drill 0.254)
		(layers "F.Cu" "B.Cu")
		(net "GND")
	)
	(via
		(at 17.608042 -227.085398)
		(size 0.4826)
		(drill 0.254)
		(layers "F.Cu" "B.Cu")
		(net "GND")
	)
	(via
		(at 59.428126 -207.535272)
		(size 0.4826)
		(drill 0.254)
		(layers "F.Cu" "B.Cu")
		(net "GND")
	)
	(via
		(at 280.635964 -298.485052)
		(size 0.4826)
		(drill 0.254)
		(layers "F.Cu" "B.Cu")
		(net "GND")
	)
	(via
		(at 375.694702 -221.80423)
		(size 0.4064)
		(drill 0.2032)
		(layers "F.Cu" "B.Cu")
		(net "GND")
	)
	(via
		(at 455.306684 -15.098522)
		(size 0.6604)
		(drill 0.3302)
		(layers "F.Cu" "B.Cu")
		(net "GND")
	)
	(via
		(at 59.428126 -235.585254)
		(size 0.4826)
		(drill 0.254)
		(layers "F.Cu" "B.Cu")
		(net "GND")
	)
	(via
		(at 224.72396 -80.264)
		(size 0.508)
		(drill 0.254)
		(layers "F.Cu" "B.Cu")
		(net "GND")
	)
	(via
		(at 368.474752 -292.71595)
		(size 0.4064)
		(drill 0.2032)
		(layers "F.Cu" "B.Cu")
		(net "GND")
	)
	(via
		(at 140.66012 -30.15996)
		(size 0.508)
		(drill 0.254)
		(layers "F.Cu" "B.Cu")
		(net "GND")
	)
	(via
		(at 414.776412 -158.626048)
		(size 0.508)
		(drill 0.254)
		(layers "F.Cu" "B.Cu")
		(net "GND")
	)
	(via
		(at 237.616238 -58.764932)
		(size 0.508)
		(drill 0.254)
		(layers "F.Cu" "B.Cu")
		(net "GND")
	)
	(via
		(at 381.719074 -183.893968)
		(size 0.49022)
		(drill 0.254)
		(layers "F.Cu" "B.Cu")
		(net "GND")
	)
	(via
		(at 237.654846 -150.050754)
		(size 0.508)
		(drill 0.254)
		(layers "F.Cu" "B.Cu")
		(net "GND")
	)
	(via
		(at 85.290914 -261.126224)
		(size 0.4064)
		(drill 0.2032)
		(layers "F.Cu" "B.Cu")
		(net "GND")
	)
	(via
		(at 27.867864 -230.485442)
		(size 0.4826)
		(drill 0.254)
		(layers "F.Cu" "B.Cu")
		(net "GND")
	)
	(via
		(at 278.950166 -343.472008)
		(size 0.508)
		(drill 0.254)
		(layers "F.Cu" "B.Cu")
		(net "GND")
	)
	(via
		(at 202.147932 -311.235344)
		(size 0.4826)
		(drill 0.254)
		(layers "F.Cu" "B.Cu")
		(net "GND")
	)
	(via
		(at 394.377672 -389.402828)
		(size 0.508)
		(drill 0.254)
		(layers "F.Cu" "B.Cu")
		(net "GND")
	)
	(via
		(at 174.771812 -171.575222)
		(size 0.508)
		(drill 0.254)
		(layers "F.Cu" "B.Cu")
		(net "GND")
	)
	(via
		(at 41.62425 -284.885384)
		(size 0.4826)
		(drill 0.254)
		(layers "F.Cu" "B.Cu")
		(net "GND")
	)
	(via
		(at 336.22107 -226.664266)
		(size 0.4064)
		(drill 0.2032)
		(layers "F.Cu" "B.Cu")
		(net "GND")
	)
	(via
		(at 36.795964 -291.685218)
		(size 0.4826)
		(drill 0.254)
		(layers "F.Cu" "B.Cu")
		(net "GND")
	)
	(via
		(at 294.647874 -404.155402)
		(size 0.508)
		(drill 0.254)
		(layers "F.Cu" "B.Cu")
		(net "GND")
	)
	(via
		(at 123.92152 -33.386268)
		(size 0.508)
		(drill 0.254)
		(layers "F.Cu" "B.Cu")
		(net "GND")
	)
	(via
		(at 121.474738 -286.23641)
		(size 0.4064)
		(drill 0.2032)
		(layers "F.Cu" "B.Cu")
		(net "GND")
	)
	(via
		(at 384.390392 -64.504316)
		(size 0.508)
		(drill 0.254)
		(layers "F.Cu" "B.Cu")
		(net "GND")
	)
	(via
		(at 303.268126 -234.735116)
		(size 0.4826)
		(drill 0.254)
		(layers "F.Cu" "B.Cu")
		(net "GND")
	)
	(via
		(at 203.265532 -202.010264)
		(size 0.4826)
		(drill 0.254)
		(layers "F.Cu" "B.Cu")
		(net "GND")
	)
	(via
		(at 350.791018 -224.234248)
		(size 0.4064)
		(drill 0.2032)
		(layers "F.Cu" "B.Cu")
		(net "GND")
	)
	(via
		(at 266.93241 -238.13516)
		(size 0.4826)
		(drill 0.254)
		(layers "F.Cu" "B.Cu")
		(net "GND")
	)
	(via
		(at 145.444718 -287.046162)
		(size 0.4064)
		(drill 0.2032)
		(layers "F.Cu" "B.Cu")
		(net "GND")
	)
	(via
		(at 122.49277 -32.339788)
		(size 0.508)
		(drill 0.254)
		(layers "F.Cu" "B.Cu")
		(net "GND")
	)
	(via
		(at 435.931818 -349.295212)
		(size 0.508)
		(drill 0.254)
		(layers "F.Cu" "B.Cu")
		(net "GND")
	)
	(via
		(at 415.083752 -305.28514)
		(size 0.4826)
		(drill 0.254)
		(layers "F.Cu" "B.Cu")
		(net "GND")
	)
	(via
		(at 99.111562 -386.449062)
		(size 0.4064)
		(drill 0.2032)
		(layers "F.Cu" "B.Cu")
		(net "GND")
	)
	(via
		(at 346.249498 -427.699678)
		(size 0.4572)
		(drill 0.2032)
		(layers "F.Cu" "B.Cu")
		(net "GND")
	)
	(via
		(at 110.371128 -238.814356)
		(size 0.4064)
		(drill 0.2032)
		(layers "F.Cu" "B.Cu")
		(net "GND")
	)
	(via
		(at 274.476464 -312.935112)
		(size 0.4826)
		(drill 0.254)
		(layers "F.Cu" "B.Cu")
		(net "GND")
	)
	(via
		(at 371.93474 -226.664266)
		(size 0.4064)
		(drill 0.2032)
		(layers "F.Cu" "B.Cu")
		(net "GND")
	)
	(via
		(at 188.444378 -284.885384)
		(size 0.4826)
		(drill 0.254)
		(layers "F.Cu" "B.Cu")
		(net "GND")
	)
	(via
		(at 452.803768 -199.885046)
		(size 0.4826)
		(drill 0.254)
		(layers "F.Cu" "B.Cu")
		(net "GND")
	)
	(via
		(at 393.384786 -265.986006)
		(size 0.4064)
		(drill 0.2032)
		(layers "F.Cu" "B.Cu")
		(net "GND")
	)
	(via
		(at 176.072038 -271.285208)
		(size 0.4826)
		(drill 0.254)
		(layers "F.Cu" "B.Cu")
		(net "GND")
	)
	(via
		(at 361.124754 -230.714296)
		(size 0.4064)
		(drill 0.2032)
		(layers "F.Cu" "B.Cu")
		(net "GND")
	)
	(via
		(at 306.978304 -394.831062)
		(size 0.4064)
		(drill 0.2032)
		(layers "F.Cu" "B.Cu")
		(net "GND")
	)
	(via
		(at 206.248 -226.23526)
		(size 0.4826)
		(drill 0.254)
		(layers "F.Cu" "B.Cu")
		(net "GND")
	)
	(via
		(at 470.837768 -78.345538)
		(size 0.508)
		(drill 0.254)
		(layers "F.Cu" "B.Cu")
		(net "GND")
	)
	(via
		(at 303.268126 -292.535102)
		(size 0.4826)
		(drill 0.254)
		(layers "F.Cu" "B.Cu")
		(net "GND")
	)
	(via
		(at 424.012106 -251.735082)
		(size 0.4826)
		(drill 0.254)
		(layers "F.Cu" "B.Cu")
		(net "GND")
	)
	(via
		(at 59.935364 -410.030168)
		(size 0.4064)
		(drill 0.2032)
		(layers "F.Cu" "B.Cu")
		(net "GND")
	)
	(via
		(at 276.074632 -238.560102)
		(size 0.4826)
		(drill 0.254)
		(layers "F.Cu" "B.Cu")
		(net "GND")
	)
	(via
		(at 342.801194 -246.104156)
		(size 0.4064)
		(drill 0.2032)
		(layers "F.Cu" "B.Cu")
		(net "GND")
	)
	(via
		(at 376.82297 -421.586152)
		(size 0.4572)
		(drill 0.254)
		(layers "F.Cu" "B.Cu")
		(net "GND")
	)
	(via
		(at 413.349694 -427.699678)
		(size 0.4572)
		(drill 0.2032)
		(layers "F.Cu" "B.Cu")
		(net "GND")
	)
	(via
		(at 117.44071 -262.180324)
		(size 0.4826)
		(drill 0.254)
		(layers "F.Cu" "B.Cu")
		(net "GND")
	)
	(via
		(at 179.516024 -289.135312)
		(size 0.4826)
		(drill 0.254)
		(layers "F.Cu" "B.Cu")
		(net "GND")
	)
	(via
		(at 78.41107 -233.95432)
		(size 0.4064)
		(drill 0.2032)
		(layers "F.Cu" "B.Cu")
		(net "GND")
	)
	(via
		(at 47.784004 -292.535356)
		(size 0.4826)
		(drill 0.254)
		(layers "F.Cu" "B.Cu")
		(net "GND")
	)
	(via
		(at 92.643706 -184.615074)
		(size 0.49022)
		(drill 0.254)
		(layers "F.Cu" "B.Cu")
		(net "GND")
	)
	(via
		(at 301.800768 -149.672802)
		(size 0.508)
		(drill 0.254)
		(layers "F.Cu" "B.Cu")
		(net "GND")
	)
	(via
		(at 168.527984 -278.935434)
		(size 0.4826)
		(drill 0.254)
		(layers "F.Cu" "B.Cu")
		(net "GND")
	)
	(via
		(at 443.357508 -167.662352)
		(size 0.508)
		(drill 0.254)
		(layers "F.Cu" "B.Cu")
		(net "GND")
	)
	(via
		(at 132.284724 -262.746236)
		(size 0.4064)
		(drill 0.2032)
		(layers "F.Cu" "B.Cu")
		(net "GND")
	)
	(via
		(at 419.82898 -17.61236)
		(size 0.508)
		(drill 0.254)
		(layers "F.Cu" "B.Cu")
		(net "GND")
	)
	(via
		(at 93.450918 -230.714296)
		(size 0.4064)
		(drill 0.2032)
		(layers "F.Cu" "B.Cu")
		(net "GND")
	)
	(via
		(at 283.351732 -284.034992)
		(size 0.4826)
		(drill 0.254)
		(layers "F.Cu" "B.Cu")
		(net "GND")
	)
	(via
		(at 199.206358 -388.160514)
		(size 0.508)
		(drill 0.254)
		(layers "F.Cu" "B.Cu")
		(net "GND")
	)
	(via
		(at 83.388962 -370.83873)
		(size 0.508)
		(drill 0.254)
		(layers "F.Cu" "B.Cu")
		(net "GND")
	)
	(via
		(at 27.314652 -4.963414)
		(size 0.508)
		(drill 0.254)
		(layers "F.Cu" "B.Cu")
		(net "GND")
	)
	(via
		(at 327.741026 -420.952168)
		(size 0.4064)
		(drill 0.2032)
		(layers "F.Cu" "B.Cu")
		(net "GND")
	)
	(via
		(at 191.160146 -226.23526)
		(size 0.4826)
		(drill 0.254)
		(layers "F.Cu" "B.Cu")
		(net "GND")
	)
	(via
		(at 366.594898 -276.516084)
		(size 0.4064)
		(drill 0.2032)
		(layers "F.Cu" "B.Cu")
		(net "GND")
	)
	(via
		(at 340.24951 -432.747166)
		(size 0.4572)
		(drill 0.2032)
		(layers "F.Cu" "B.Cu")
		(net "GND")
	)
	(via
		(at 289.564318 -294.235124)
		(size 0.4826)
		(drill 0.254)
		(layers "F.Cu" "B.Cu")
		(net "GND")
	)
	(via
		(at 101.440996 -223.424496)
		(size 0.4064)
		(drill 0.2032)
		(layers "F.Cu" "B.Cu")
		(net "GND")
	)
	(via
		(at 114.696494 -403.830536)
		(size 0.4572)
		(drill 0.254)
		(layers "F.Cu" "B.Cu")
		(net "GND")
	)
	(via
		(at 366.764824 -230.714296)
		(size 0.4064)
		(drill 0.2032)
		(layers "F.Cu" "B.Cu")
		(net "GND")
	)
	(via
		(at 412.185104 -16.9799)
		(size 0.508)
		(drill 0.254)
		(layers "F.Cu" "B.Cu")
		(net "GND")
	)
	(via
		(at 126.814834 -241.244374)
		(size 0.4064)
		(drill 0.2032)
		(layers "F.Cu" "B.Cu")
		(net "GND")
	)
	(via
		(at 128.122426 -407.00452)
		(size 0.4064)
		(drill 0.2032)
		(layers "F.Cu" "B.Cu")
		(net "GND")
	)
	(via
		(at 345.451176 -288.66592)
		(size 0.4064)
		(drill 0.2032)
		(layers "F.Cu" "B.Cu")
		(net "GND")
	)
	(via
		(at 108.321094 -282.996386)
		(size 0.4064)
		(drill 0.2032)
		(layers "F.Cu" "B.Cu")
		(net "GND")
	)
	(via
		(at 389.716518 -309.074312)
		(size 0.508)
		(drill 0.254)
		(layers "F.Cu" "B.Cu")
		(net "GND")
	)
	(via
		(at 368.945668 -264.368026)
		(size 0.4064)
		(drill 0.2032)
		(layers "F.Cu" "B.Cu")
		(net "GND")
	)
	(via
		(at 238.859314 -218.426538)
		(size 0.4826)
		(drill 0.254)
		(layers "F.Cu" "B.Cu")
		(net "GND")
	)
	(via
		(at 321.249548 -439.651394)
		(size 0.4572)
		(drill 0.2032)
		(layers "F.Cu" "B.Cu")
		(net "GND")
	)
	(via
		(at 62.912752 -405.098504)
		(size 0.4572)
		(drill 0.254)
		(layers "F.Cu" "B.Cu")
		(net "GND")
	)
	(via
		(at 416.254692 -141.062456)
		(size 0.508)
		(drill 0.254)
		(layers "F.Cu" "B.Cu")
		(net "GND")
	)
	(via
		(at 101.91115 -232.334308)
		(size 0.4064)
		(drill 0.2032)
		(layers "F.Cu" "B.Cu")
		(net "GND")
	)
	(via
		(at 379.613414 -419.046152)
		(size 0.4572)
		(drill 0.254)
		(layers "F.Cu" "B.Cu")
		(net "GND")
	)
	(via
		(at 107.85094 -270.846296)
		(size 0.4064)
		(drill 0.2032)
		(layers "F.Cu" "B.Cu")
		(net "GND")
	)
	(via
		(at 126.814834 -228.284532)
		(size 0.4064)
		(drill 0.2032)
		(layers "F.Cu" "B.Cu")
		(net "GND")
	)
	(via
		(at 202.147932 -301.88535)
		(size 0.4826)
		(drill 0.254)
		(layers "F.Cu" "B.Cu")
		(net "GND")
	)
	(via
		(at 16.31569 -389.4201)
		(size 0.49022)
		(drill 0.254)
		(layers "F.Cu" "B.Cu")
		(net "GND")
	)
	(via
		(at 338.02828 -133.39191)
		(size 0.508)
		(drill 0.254)
		(layers "F.Cu" "B.Cu")
		(net "GND")
	)
	(via
		(at 84.79282 -354.659946)
		(size 0.508)
		(drill 0.254)
		(layers "F.Cu" "B.Cu")
		(net "GND")
	)
	(via
		(at 79.180944 -295.956228)
		(size 0.4064)
		(drill 0.2032)
		(layers "F.Cu" "B.Cu")
		(net "GND")
	)
	(via
		(at 335.987644 -382.34493)
		(size 0.508)
		(drill 0.254)
		(layers "F.Cu" "B.Cu")
		(net "GND")
	)
	(via
		(at 132.284724 -287.046162)
		(size 0.4064)
		(drill 0.2032)
		(layers "F.Cu" "B.Cu")
		(net "GND")
	)
	(via
		(at 133.394704 -250.964446)
		(size 0.4064)
		(drill 0.2032)
		(layers "F.Cu" "B.Cu")
		(net "GND")
	)
	(via
		(at 372.655846 -183.893968)
		(size 0.49022)
		(drill 0.254)
		(layers "F.Cu" "B.Cu")
		(net "GND")
	)
	(via
		(at 280.635964 -206.685134)
		(size 0.4826)
		(drill 0.254)
		(layers "F.Cu" "B.Cu")
		(net "GND")
	)
	(via
		(at 370.994686 -255.824228)
		(size 0.4064)
		(drill 0.2032)
		(layers "F.Cu" "B.Cu")
		(net "GND")
	)
	(via
		(at 379.866906 -33.334198)
		(size 0.508)
		(drill 0.254)
		(layers "F.Cu" "B.Cu")
		(net "GND")
	)
	(via
		(at 248.689114 -318.704468)
		(size 0.508)
		(drill 0.254)
		(layers "F.Cu" "B.Cu")
		(net "GND")
	)
	(via
		(at 101.440996 -254.20447)
		(size 0.4064)
		(drill 0.2032)
		(layers "F.Cu" "B.Cu")
		(net "GND")
	)
	(via
		(at 328.231246 -256.634234)
		(size 0.4064)
		(drill 0.2032)
		(layers "F.Cu" "B.Cu")
		(net "GND")
	)
	(via
		(at 14.19987 -384.76809)
		(size 0.508)
		(drill 0.254)
		(layers "F.Cu" "B.Cu")
		(net "GND")
	)
	(via
		(at 374.754902 -241.24412)
		(size 0.4064)
		(drill 0.2032)
		(layers "F.Cu" "B.Cu")
		(net "GND")
	)
	(via
		(at 427.456092 -307.835046)
		(size 0.4826)
		(drill 0.254)
		(layers "F.Cu" "B.Cu")
		(net "GND")
	)
	(via
		(at 416.468052 -232.184956)
		(size 0.4826)
		(drill 0.254)
		(layers "F.Cu" "B.Cu")
		(net "GND")
	)
	(via
		(at 103.118412 -349.959676)
		(size 0.508)
		(drill 0.254)
		(layers "F.Cu" "B.Cu")
		(net "GND")
	)
	(via
		(at 94.488 -209.895948)
		(size 0.508)
		(drill 0.254)
		(layers "F.Cu" "B.Cu")
		(net "GND")
	)
	(via
		(at 127.802894 -38.07333)
		(size 0.508)
		(drill 0.254)
		(layers "F.Cu" "B.Cu")
		(net "GND")
	)
	(via
		(at 64.616584 -391.830814)
		(size 0.4064)
		(drill 0.2032)
		(layers "F.Cu" "B.Cu")
		(net "GND")
	)
	(via
		(at 315.576458 -417.778184)
		(size 0.4572)
		(drill 0.254)
		(layers "F.Cu" "B.Cu")
		(net "GND")
	)
	(via
		(at 142.238222 -156.567124)
		(size 0.508)
		(drill 0.254)
		(layers "F.Cu" "B.Cu")
		(net "GND")
	)
	(via
		(at 23.676864 -6.091174)
		(size 0.508)
		(drill 0.254)
		(layers "F.Cu" "B.Cu")
		(net "GND")
	)
	(via
		(at 153.075386 -412.570168)
		(size 0.4064)
		(drill 0.2032)
		(layers "F.Cu" "B.Cu")
		(net "GND")
	)
	(via
		(at 120.148096 -369.03533)
		(size 0.508)
		(drill 0.254)
		(layers "F.Cu" "B.Cu")
		(net "GND")
	)
	(via
		(at 282.448254 -436.623714)
		(size 0.508)
		(drill 0.254)
		(layers "F.Cu" "B.Cu")
		(net "GND")
	)
	(via
		(at 415.083752 -302.73498)
		(size 0.4826)
		(drill 0.254)
		(layers "F.Cu" "B.Cu")
		(net "GND")
	)
	(via
		(at 137.154666 -250.964446)
		(size 0.4064)
		(drill 0.2032)
		(layers "F.Cu" "B.Cu")
		(net "GND")
	)
	(via
		(at 320.477896 -377.41733)
		(size 0.508)
		(drill 0.254)
		(layers "F.Cu" "B.Cu")
		(net "GND")
	)
	(via
		(at 382.1049 -290.285932)
		(size 0.4064)
		(drill 0.2032)
		(layers "F.Cu" "B.Cu")
		(net "GND")
	)
	(via
		(at 326.651112 -277.32609)
		(size 0.4064)
		(drill 0.2032)
		(layers "F.Cu" "B.Cu")
		(net "GND")
	)
	(via
		(at 119.379746 -412.570168)
		(size 0.4064)
		(drill 0.2032)
		(layers "F.Cu" "B.Cu")
		(net "GND")
	)
	(via
		(at 173.35627 -231.335326)
		(size 0.4826)
		(drill 0.254)
		(layers "F.Cu" "B.Cu")
		(net "GND")
	)
	(via
		(at 345.151202 -246.914162)
		(size 0.4064)
		(drill 0.2032)
		(layers "F.Cu" "B.Cu")
		(net "GND")
	)
	(via
		(at 92.981018 -247.724422)
		(size 0.4064)
		(drill 0.2032)
		(layers "F.Cu" "B.Cu")
		(net "GND")
	)
	(via
		(at 159.006286 -386.449062)
		(size 0.4064)
		(drill 0.2032)
		(layers "F.Cu" "B.Cu")
		(net "GND")
	)
	(via
		(at 369.884706 -290.285932)
		(size 0.4064)
		(drill 0.2032)
		(layers "F.Cu" "B.Cu")
		(net "GND")
	)
	(via
		(at 130.662172 -38.905434)
		(size 0.508)
		(drill 0.254)
		(layers "F.Cu" "B.Cu")
		(net "GND")
	)
	(via
		(at 128.122426 -410.030168)
		(size 0.4064)
		(drill 0.2032)
		(layers "F.Cu" "B.Cu")
		(net "GND")
	)
	(via
		(at 109.261148 -287.856422)
		(size 0.4064)
		(drill 0.2032)
		(layers "F.Cu" "B.Cu")
		(net "GND")
	)
	(via
		(at 130.012694 -405.098504)
		(size 0.4572)
		(drill 0.254)
		(layers "F.Cu" "B.Cu")
		(net "GND")
	)
	(via
		(at 22.145752 -10.16508)
		(size 0.508)
		(drill 0.254)
		(layers "F.Cu" "B.Cu")
		(net "GND")
	)
	(via
		(at 326.181212 -294.335962)
		(size 0.4064)
		(drill 0.2032)
		(layers "F.Cu" "B.Cu")
		(net "GND")
	)
	(via
		(at 113.184686 -240.434368)
		(size 0.4064)
		(drill 0.2032)
		(layers "F.Cu" "B.Cu")
		(net "GND")
	)
	(via
		(at 370.82476 -285.42615)
		(size 0.4064)
		(drill 0.2032)
		(layers "F.Cu" "B.Cu")
		(net "GND")
	)
	(via
		(at 96.27108 -255.014476)
		(size 0.4064)
		(drill 0.2032)
		(layers "F.Cu" "B.Cu")
		(net "GND")
	)
	(via
		(at 235.940854 -322.683632)
		(size 0.508)
		(drill 0.254)
		(layers "F.Cu" "B.Cu")
		(net "GND")
	)
	(via
		(at 400.967702 -412.84652)
		(size 0.4064)
		(drill 0.2032)
		(layers "F.Cu" "B.Cu")
		(net "GND")
	)
	(via
		(at 331.521054 -254.204216)
		(size 0.4064)
		(drill 0.2032)
		(layers "F.Cu" "B.Cu")
		(net "GND")
	)
	(via
		(at 161.844228 -382.85293)
		(size 0.4064)
		(drill 0.2032)
		(layers "F.Cu" "B.Cu")
		(net "GND")
	)
	(via
		(at 327.741026 -412.84652)
		(size 0.4064)
		(drill 0.2032)
		(layers "F.Cu" "B.Cu")
		(net "GND")
	)
	(via
		(at 121.174764 -239.624362)
		(size 0.4064)
		(drill 0.2032)
		(layers "F.Cu" "B.Cu")
		(net "GND")
	)
	(via
		(at 145.414746 -407.00452)
		(size 0.4064)
		(drill 0.2032)
		(layers "F.Cu" "B.Cu")
		(net "GND")
	)
	(via
		(at 370.82476 -277.32609)
		(size 0.4064)
		(drill 0.2032)
		(layers "F.Cu" "B.Cu")
		(net "GND")
	)
	(via
		(at 171.97197 -300.185328)
		(size 0.4826)
		(drill 0.254)
		(layers "F.Cu" "B.Cu")
		(net "GND")
	)
	(via
		(at 364.24489 -269.22603)
		(size 0.4064)
		(drill 0.2032)
		(layers "F.Cu" "B.Cu")
		(net "GND")
	)
	(via
		(at 20.59051 -210.510374)
		(size 0.4826)
		(drill 0.254)
		(layers "F.Cu" "B.Cu")
		(net "GND")
	)
	(via
		(at 123.054618 -255.824482)
		(size 0.4064)
		(drill 0.2032)
		(layers "F.Cu" "B.Cu")
		(net "GND")
	)
	(via
		(at 72.102472 -413.204152)
		(size 0.4572)
		(drill 0.254)
		(layers "F.Cu" "B.Cu")
		(net "GND")
	)
	(via
		(at 95.1611 -265.176254)
		(size 0.4064)
		(drill 0.2032)
		(layers "F.Cu" "B.Cu")
		(net "GND")
	)
	(via
		(at 28.53817 -366.030256)
		(size 0.508)
		(drill 0.254)
		(layers "F.Cu" "B.Cu")
		(net "GND")
	)
	(via
		(at 168.527984 -235.585254)
		(size 0.4826)
		(drill 0.254)
		(layers "F.Cu" "B.Cu")
		(net "GND")
	)
	(via
		(at 228.092 -283.602176)
		(size 0.508)
		(drill 0.254)
		(layers "F.Cu" "B.Cu")
		(net "GND")
	)
	(via
		(at 55.328058 -223.685354)
		(size 0.4826)
		(drill 0.254)
		(layers "F.Cu" "B.Cu")
		(net "GND")
	)
	(via
		(at 98.150934 -253.394464)
		(size 0.4064)
		(drill 0.2032)
		(layers "F.Cu" "B.Cu")
		(net "GND")
	)
	(via
		(at 399.53311 -0.762254)
		(size 0.508)
		(drill 0.254)
		(layers "F.Cu" "B.Cu")
		(net "GND")
	)
	(via
		(at 194.604132 -273.835368)
		(size 0.4826)
		(drill 0.254)
		(layers "F.Cu" "B.Cu")
		(net "GND")
	)
	(via
		(at 93.921072 -223.424496)
		(size 0.4064)
		(drill 0.2032)
		(layers "F.Cu" "B.Cu")
		(net "GND")
	)
	(via
		(at 145.144744 -238.814356)
		(size 0.4064)
		(drill 0.2032)
		(layers "F.Cu" "B.Cu")
		(net "GND")
	)
	(via
		(at 116.944648 -232.334308)
		(size 0.4064)
		(drill 0.2032)
		(layers "F.Cu" "B.Cu")
		(net "GND")
	)
	(via
		(at 347.33103 -280.566114)
		(size 0.4064)
		(drill 0.2032)
		(layers "F.Cu" "B.Cu")
		(net "GND")
	)
	(via
		(at 364.573058 -177.205386)
		(size 0.49022)
		(drill 0.254)
		(layers "F.Cu" "B.Cu")
		(net "GND")
	)
	(via
		(at 343.101168 -270.036036)
		(size 0.4064)
		(drill 0.2032)
		(layers "F.Cu" "B.Cu")
		(net "GND")
	)
	(via
		(at 406.394412 -163.452048)
		(size 0.508)
		(drill 0.254)
		(layers "F.Cu" "B.Cu")
		(net "GND")
	)
	(via
		(at 376.93473 -276.516084)
		(size 0.4064)
		(drill 0.2032)
		(layers "F.Cu" "B.Cu")
		(net "GND")
	)
	(via
		(at 51.581558 -344.781886)
		(size 0.49022)
		(drill 0.254)
		(layers "F.Cu" "B.Cu")
		(net "GND")
	)
	(via
		(at 27.784806 -6.598158)
		(size 0.508)
		(drill 0.254)
		(layers "F.Cu" "B.Cu")
		(net "GND")
	)
	(via
		(at 428.573692 -211.360004)
		(size 0.4826)
		(drill 0.254)
		(layers "F.Cu" "B.Cu")
		(net "GND")
	)
	(via
		(at 89.221056 -225.044508)
		(size 0.4064)
		(drill 0.2032)
		(layers "F.Cu" "B.Cu")
		(net "GND")
	)
	(via
		(at 32.680402 -4.32943)
		(size 0.508)
		(drill 0.254)
		(layers "F.Cu" "B.Cu")
		(net "GND")
	)
	(via
		(at 20.32381 -284.035246)
		(size 0.4826)
		(drill 0.254)
		(layers "F.Cu" "B.Cu")
		(net "GND")
	)
	(via
		(at 61.249814 -438.499758)
		(size 0.4572)
		(drill 0.2032)
		(layers "F.Cu" "B.Cu")
		(net "GND")
	)
	(via
		(at 274.12061 -344.77706)
		(size 0.49022)
		(drill 0.254)
		(layers "F.Cu" "B.Cu")
		(net "GND")
	)
	(via
		(at 299.82414 -306.985162)
		(size 0.4826)
		(drill 0.254)
		(layers "F.Cu" "B.Cu")
		(net "GND")
	)
	(via
		(at 95.518986 -390.160002)
		(size 0.4064)
		(drill 0.2032)
		(layers "F.Cu" "B.Cu")
		(net "GND")
	)
	(via
		(at 353.867466 -440.211972)
		(size 0.508)
		(drill 0.254)
		(layers "F.Cu" "B.Cu")
		(net "GND")
	)
	(via
		(at 369.114832 -228.284278)
		(size 0.4064)
		(drill 0.2032)
		(layers "F.Cu" "B.Cu")
		(net "GND")
	)
	(via
		(at 130.87477 -266.796266)
		(size 0.4064)
		(drill 0.2032)
		(layers "F.Cu" "B.Cu")
		(net "GND")
	)
	(via
		(at 274.78101 -345.566238)
		(size 0.49022)
		(drill 0.254)
		(layers "F.Cu" "B.Cu")
		(net "GND")
	)
	(via
		(at 185.3946 -24.91486)
		(size 0.508)
		(drill 0.254)
		(layers "F.Cu" "B.Cu")
		(net "GND")
	)
	(via
		(at 189.263274 -17.654778)
		(size 0.508)
		(drill 0.254)
		(layers "F.Cu" "B.Cu")
		(net "GND")
	)
	(via
		(at 145.328894 -413.204152)
		(size 0.4572)
		(drill 0.254)
		(layers "F.Cu" "B.Cu")
		(net "GND")
	)
	(via
		(at 382.1049 -288.66592)
		(size 0.4064)
		(drill 0.2032)
		(layers "F.Cu" "B.Cu")
		(net "GND")
	)
	(via
		(at 369.414806 -291.095938)
		(size 0.4064)
		(drill 0.2032)
		(layers "F.Cu" "B.Cu")
		(net "GND")
	)
	(via
		(at 162.378136 -427.494446)
		(size 0.508)
		(drill 0.254)
		(layers "F.Cu" "B.Cu")
		(net "GND")
	)
	(via
		(at 54.981856 -411.936184)
		(size 0.4572)
		(drill 0.254)
		(layers "F.Cu" "B.Cu")
		(net "GND")
	)
	(via
		(at 353.61118 -224.234248)
		(size 0.4064)
		(drill 0.2032)
		(layers "F.Cu" "B.Cu")
		(net "GND")
	)
	(via
		(at 182.05958 -388.990586)
		(size 0.508)
		(drill 0.254)
		(layers "F.Cu" "B.Cu")
		(net "GND")
	)
	(via
		(at 346.25788 -331.780134)
		(size 0.508)
		(drill 0.254)
		(layers "F.Cu" "B.Cu")
		(net "GND")
	)
	(via
		(at 339.511132 -238.814102)
		(size 0.4064)
		(drill 0.2032)
		(layers "F.Cu" "B.Cu")
		(net "GND")
	)
	(via
		(at 133.694678 -292.716204)
		(size 0.4064)
		(drill 0.2032)
		(layers "F.Cu" "B.Cu")
		(net "GND")
	)
	(via
		(at 323.595746 -420.952168)
		(size 0.4064)
		(drill 0.2032)
		(layers "F.Cu" "B.Cu")
		(net "GND")
	)
	(via
		(at 446.644268 -215.18499)
		(size 0.4826)
		(drill 0.254)
		(layers "F.Cu" "B.Cu")
		(net "GND")
	)
	(via
		(at 177.137568 -152.828244)
		(size 0.508)
		(drill 0.254)
		(layers "F.Cu" "B.Cu")
		(net "GND")
	)
	(via
		(at 127.114808 -284.616398)
		(size 0.4064)
		(drill 0.2032)
		(layers "F.Cu" "B.Cu")
		(net "GND")
	)
	(via
		(at 349.976948 -129.807208)
		(size 0.508)
		(drill 0.254)
		(layers "F.Cu" "B.Cu")
		(net "GND")
	)
	(via
		(at 180.633624 -276.81047)
		(size 0.4826)
		(drill 0.254)
		(layers "F.Cu" "B.Cu")
		(net "GND")
	)
	(via
		(at 274.476464 -306.135024)
		(size 0.4826)
		(drill 0.254)
		(layers "F.Cu" "B.Cu")
		(net "GND")
	)
	(via
		(at 316.383924 -333.845154)
		(size 0.49022)
		(drill 0.254)
		(layers "F.Cu" "B.Cu")
		(net "GND")
	)
	(via
		(at 383.224278 -136.513824)
		(size 0.508)
		(drill 0.254)
		(layers "F.Cu" "B.Cu")
		(net "GND")
	)
	(via
		(at 45.206158 -345.571064)
		(size 0.49022)
		(drill 0.254)
		(layers "F.Cu" "B.Cu")
		(net "GND")
	)
	(via
		(at 34.080196 -228.78542)
		(size 0.4826)
		(drill 0.254)
		(layers "F.Cu" "B.Cu")
		(net "GND")
	)
	(via
		(at 32.695896 -223.685354)
		(size 0.4826)
		(drill 0.254)
		(layers "F.Cu" "B.Cu")
		(net "GND")
	)
	(via
		(at 304.652426 -238.13516)
		(size 0.4826)
		(drill 0.254)
		(layers "F.Cu" "B.Cu")
		(net "GND")
	)
	(via
		(at 151.34971 -437.49976)
		(size 0.4572)
		(drill 0.2032)
		(layers "F.Cu" "B.Cu")
		(net "GND")
	)
	(via
		(at 353.144074 -402.309838)
		(size 0.4572)
		(drill 0.254)
		(layers "F.Cu" "B.Cu")
		(net "GND")
	)
	(via
		(at 56.21655 -382.85293)
		(size 0.4064)
		(drill 0.2032)
		(layers "F.Cu" "B.Cu")
		(net "GND")
	)
	(via
		(at 366.294924 -231.524048)
		(size 0.4064)
		(drill 0.2032)
		(layers "F.Cu" "B.Cu")
		(net "GND")
	)
	(via
		(at 443.9285 -212.635084)
		(size 0.4826)
		(drill 0.254)
		(layers "F.Cu" "B.Cu")
		(net "GND")
	)
	(via
		(at 88.281002 -239.624362)
		(size 0.4064)
		(drill 0.2032)
		(layers "F.Cu" "B.Cu")
		(net "GND")
	)
	(via
		(at 88.111076 -295.146222)
		(size 0.4064)
		(drill 0.2032)
		(layers "F.Cu" "B.Cu")
		(net "GND")
	)
	(via
		(at 428.611792 -192.21831)
		(size 0.4826)
		(drill 0.254)
		(layers "F.Cu" "B.Cu")
		(net "GND")
	)
	(via
		(at 42.955718 -230.485442)
		(size 0.4826)
		(drill 0.254)
		(layers "F.Cu" "B.Cu")
		(net "GND")
	)
	(via
		(at 365.981234 -33.049972)
		(size 0.508)
		(drill 0.254)
		(layers "F.Cu" "B.Cu")
		(net "GND")
	)
	(via
		(at 163.42233 -348.705678)
		(size 0.508)
		(drill 0.254)
		(layers "F.Cu" "B.Cu")
		(net "GND")
	)
	(via
		(at 431.3682 -9.424924)
		(size 0.508)
		(drill 0.254)
		(layers "F.Cu" "B.Cu")
		(net "GND")
	)
	(via
		(at 120.916446 -393.927838)
		(size 0.4572)
		(drill 0.254)
		(layers "F.Cu" "B.Cu")
		(net "GND")
	)
	(via
		(at 369.584732 -233.954066)
		(size 0.4064)
		(drill 0.2032)
		(layers "F.Cu" "B.Cu")
		(net "GND")
	)
	(via
		(at 314.616338 -402.309838)
		(size 0.4572)
		(drill 0.254)
		(layers "F.Cu" "B.Cu")
		(net "GND")
	)
	(via
		(at 104.08793 -262.748268)
		(size 0.4064)
		(drill 0.2032)
		(layers "F.Cu" "B.Cu")
		(net "GND")
	)
	(via
		(at 359.3973 -351.775268)
		(size 0.508)
		(drill 0.254)
		(layers "F.Cu" "B.Cu")
		(net "GND")
	)
	(via
		(at 343.118694 -398.542002)
		(size 0.4064)
		(drill 0.2032)
		(layers "F.Cu" "B.Cu")
		(net "GND")
	)
	(via
		(at 160.645094 -405.098504)
		(size 0.4572)
		(drill 0.254)
		(layers "F.Cu" "B.Cu")
		(net "GND")
	)
	(via
		(at 378.442982 -420.952168)
		(size 0.4064)
		(drill 0.2032)
		(layers "F.Cu" "B.Cu")
		(net "GND")
	)
	(via
		(at 306.860956 -379.22073)
		(size 0.508)
		(drill 0.254)
		(layers "F.Cu" "B.Cu")
		(net "GND")
	)
	(via
		(at 330.34224 -394.782294)
		(size 0.508)
		(drill 0.254)
		(layers "F.Cu" "B.Cu")
		(net "GND")
	)
	(via
		(at 67.14109 -166.94023)
		(size 0.49022)
		(drill 0.254)
		(layers "F.Cu" "B.Cu")
		(net "GND")
	)
	(via
		(at 269.648178 -196.485002)
		(size 0.4826)
		(drill 0.254)
		(layers "F.Cu" "B.Cu")
		(net "GND")
	)
	(via
		(at 442.5442 -264.48512)
		(size 0.4826)
		(drill 0.254)
		(layers "F.Cu" "B.Cu")
		(net "GND")
	)
	(via
		(at 151.551894 -47.94885)
		(size 0.508)
		(drill 0.254)
		(layers "F.Cu" "B.Cu")
		(net "GND")
	)
	(via
		(at 424.012106 -235.585)
		(size 0.4826)
		(drill 0.254)
		(layers "F.Cu" "B.Cu")
		(net "GND")
	)
	(via
		(at 2.76225 -255.453134)
		(size 0.508)
		(drill 0.254)
		(layers "F.Cu" "B.Cu")
		(net "GND")
	)
	(via
		(at 412.367984 -206.685134)
		(size 0.4826)
		(drill 0.254)
		(layers "F.Cu" "B.Cu")
		(net "GND")
	)
	(via
		(at 265.43381 -112.878616)
		(size 0.508)
		(drill 0.254)
		(layers "F.Cu" "B.Cu")
		(net "GND")
	)
	(via
		(at 358.523032 -352.649536)
		(size 0.508)
		(drill 0.254)
		(layers "F.Cu" "B.Cu")
		(net "GND")
	)
	(via
		(at 88.580976 -286.23641)
		(size 0.4064)
		(drill 0.2032)
		(layers "F.Cu" "B.Cu")
		(net "GND")
	)
	(via
		(at 24.288496 -386.914898)
		(size 0.49022)
		(drill 0.254)
		(layers "F.Cu" "B.Cu")
		(net "GND")
	)
	(via
		(at 349.245936 -396.710662)
		(size 0.4064)
		(drill 0.2032)
		(layers "F.Cu" "B.Cu")
		(net "GND")
	)
	(via
		(at 419.993318 -166.351712)
		(size 0.508)
		(drill 0.254)
		(layers "F.Cu" "B.Cu")
		(net "GND")
	)
	(via
		(at 102.211124 -270.846296)
		(size 0.4064)
		(drill 0.2032)
		(layers "F.Cu" "B.Cu")
		(net "GND")
	)
	(via
		(at 402.045678 -10.16508)
		(size 0.508)
		(drill 0.254)
		(layers "F.Cu" "B.Cu")
		(net "GND")
	)
	(via
		(at 122.584718 -224.234502)
		(size 0.4064)
		(drill 0.2032)
		(layers "F.Cu" "B.Cu")
		(net "GND")
	)
	(via
		(at 69.249798 -438.499758)
		(size 0.4572)
		(drill 0.2032)
		(layers "F.Cu" "B.Cu")
		(net "GND")
	)
	(via
		(at 145.144744 -233.95432)
		(size 0.4064)
		(drill 0.2032)
		(layers "F.Cu" "B.Cu")
		(net "GND")
	)
	(via
		(at 156.69006 -384.617722)
		(size 0.4064)
		(drill 0.2032)
		(layers "F.Cu" "B.Cu")
		(net "GND")
	)
	(via
		(at 394.237972 -398.719802)
		(size 0.508)
		(drill 0.254)
		(layers "F.Cu" "B.Cu")
		(net "GND")
	)
	(via
		(at 355.08057 -401.873212)
		(size 0.508)
		(drill 0.254)
		(layers "F.Cu" "B.Cu")
		(net "GND")
	)
	(via
		(at 56.712358 -315.485272)
		(size 0.4826)
		(drill 0.254)
		(layers "F.Cu" "B.Cu")
		(net "GND")
	)
	(via
		(at 274.545806 -347.282262)
		(size 0.49022)
		(drill 0.254)
		(layers "F.Cu" "B.Cu")
		(net "GND")
	)
	(via
		(at 220.829124 -191.399414)
		(size 0.508)
		(drill 0.254)
		(layers "F.Cu" "B.Cu")
		(net "GND")
	)
	(via
		(at 88.24976 -433.899564)
		(size 0.4572)
		(drill 0.2032)
		(layers "F.Cu" "B.Cu")
		(net "GND")
	)
	(via
		(at 340.845902 -396.710662)
		(size 0.4064)
		(drill 0.2032)
		(layers "F.Cu" "B.Cu")
		(net "GND")
	)
	(via
		(at 43.222418 -238.560356)
		(size 0.4826)
		(drill 0.254)
		(layers "F.Cu" "B.Cu")
		(net "GND")
	)
	(via
		(at 155.349702 -433.899564)
		(size 0.4572)
		(drill 0.2032)
		(layers "F.Cu" "B.Cu")
		(net "GND")
	)
	(via
		(at 411.662118 -167.672512)
		(size 0.508)
		(drill 0.254)
		(layers "F.Cu" "B.Cu")
		(net "GND")
	)
	(via
		(at 76.697332 -407.638504)
		(size 0.4572)
		(drill 0.254)
		(layers "F.Cu" "B.Cu")
		(net "GND")
	)
	(via
		(at 138.049 -117.729)
		(size 0.508)
		(drill 0.254)
		(layers "F.Cu" "B.Cu")
		(net "GND")
	)
	(via
		(at 114.59464 -244.484398)
		(size 0.4064)
		(drill 0.2032)
		(layers "F.Cu" "B.Cu")
		(net "GND")
	)
	(via
		(at 82.640932 -225.044508)
		(size 0.4064)
		(drill 0.2032)
		(layers "F.Cu" "B.Cu")
		(net "GND")
	)
	(via
		(at 379.924818 -251.774198)
		(size 0.4064)
		(drill 0.2032)
		(layers "F.Cu" "B.Cu")
		(net "GND")
	)
	(via
		(at 323.881496 -377.41733)
		(size 0.508)
		(drill 0.254)
		(layers "F.Cu" "B.Cu")
		(net "GND")
	)
	(via
		(at 106.753152 -62.022736)
		(size 0.508)
		(drill 0.254)
		(layers "F.Cu" "B.Cu")
		(net "GND")
	)
	(via
		(at 308.279546 -420.952168)
		(size 0.4064)
		(drill 0.2032)
		(layers "F.Cu" "B.Cu")
		(net "GND")
	)
	(via
		(at 435.000146 -317.18504)
		(size 0.4826)
		(drill 0.254)
		(layers "F.Cu" "B.Cu")
		(net "GND")
	)
	(via
		(at 70.149974 -335.566004)
		(size 0.49022)
		(drill 0.254)
		(layers "F.Cu" "B.Cu")
		(net "GND")
	)
	(via
		(at 437.886602 -423.66311)
		(size 0.508)
		(drill 0.254)
		(layers "F.Cu" "B.Cu")
		(net "GND")
	)
	(via
		(at 333.632556 -395.42974)
		(size 0.4064)
		(drill 0.2032)
		(layers "F.Cu" "B.Cu")
		(net "GND")
	)
	(via
		(at 162.690048 -384.617722)
		(size 0.4064)
		(drill 0.2032)
		(layers "F.Cu" "B.Cu")
		(net "GND")
	)
	(via
		(at 137.670794 -410.664152)
		(size 0.4572)
		(drill 0.254)
		(layers "F.Cu" "B.Cu")
		(net "GND")
	)
	(via
		(at 287.626298 -156.377132)
		(size 0.508)
		(drill 0.254)
		(layers "F.Cu" "B.Cu")
		(net "GND")
	)
	(via
		(at 135.93318 -29.87802)
		(size 0.508)
		(drill 0.254)
		(layers "F.Cu" "B.Cu")
		(net "GND")
	)
	(via
		(at 47.816516 -382.85293)
		(size 0.4064)
		(drill 0.2032)
		(layers "F.Cu" "B.Cu")
		(net "GND")
	)
	(via
		(at 414.840674 -421.586152)
		(size 0.4572)
		(drill 0.254)
		(layers "F.Cu" "B.Cu")
		(net "GND")
	)
	(via
		(at 26.536396 -287.43529)
		(size 0.4826)
		(drill 0.254)
		(layers "F.Cu" "B.Cu")
		(net "GND")
	)
	(via
		(at 430.17186 -202.434952)
		(size 0.4826)
		(drill 0.254)
		(layers "F.Cu" "B.Cu")
		(net "GND")
	)
	(via
		(at 312.786014 -412.212536)
		(size 0.4572)
		(drill 0.254)
		(layers "F.Cu" "B.Cu")
		(net "GND")
	)
	(via
		(at 114.916458 -393.902438)
		(size 0.4572)
		(drill 0.254)
		(layers "F.Cu" "B.Cu")
		(net "GND")
	)
	(via
		(at 95.1611 -268.416278)
		(size 0.4064)
		(drill 0.2032)
		(layers "F.Cu" "B.Cu")
		(net "GND")
	)
	(via
		(at 91.571064 -224.234502)
		(size 0.4064)
		(drill 0.2032)
		(layers "F.Cu" "B.Cu")
		(net "GND")
	)
	(via
		(at 366.124744 -270.846042)
		(size 0.4064)
		(drill 0.2032)
		(layers "F.Cu" "B.Cu")
		(net "GND")
	)
	(via
		(at 439.100214 -253.435104)
		(size 0.4826)
		(drill 0.254)
		(layers "F.Cu" "B.Cu")
		(net "GND")
	)
	(via
		(at 2.76225 -316.921134)
		(size 0.508)
		(drill 0.254)
		(layers "F.Cu" "B.Cu")
		(net "GND")
	)
	(via
		(at 273.664172 -104.475788)
		(size 0.508)
		(drill 0.254)
		(layers "F.Cu" "B.Cu")
		(net "GND")
	)
	(via
		(at 145.144744 -232.334308)
		(size 0.4064)
		(drill 0.2032)
		(layers "F.Cu" "B.Cu")
		(net "GND")
	)
	(via
		(at 61.381132 -409.396184)
		(size 0.4572)
		(drill 0.254)
		(layers "F.Cu" "B.Cu")
		(net "GND")
	)
	(via
		(at 388.916418 -400.212814)
		(size 0.4064)
		(drill 0.2032)
		(layers "F.Cu" "B.Cu")
		(net "GND")
	)
	(via
		(at 127.584708 -262.746236)
		(size 0.4064)
		(drill 0.2032)
		(layers "F.Cu" "B.Cu")
		(net "GND")
	)
	(via
		(at 343.145618 -414.752536)
		(size 0.4572)
		(drill 0.254)
		(layers "F.Cu" "B.Cu")
		(net "GND")
	)
	(via
		(at 337.189826 -392.999722)
		(size 0.4064)
		(drill 0.2032)
		(layers "F.Cu" "B.Cu")
		(net "GND")
	)
	(via
		(at 17.608042 -311.235344)
		(size 0.4826)
		(drill 0.254)
		(layers "F.Cu" "B.Cu")
		(net "GND")
	)
	(via
		(at 385.094734 -223.424242)
		(size 0.4064)
		(drill 0.2032)
		(layers "F.Cu" "B.Cu")
		(net "GND")
	)
	(via
		(at 292.280086 -261.93496)
		(size 0.4826)
		(drill 0.254)
		(layers "F.Cu" "B.Cu")
		(net "GND")
	)
	(via
		(at 438.555384 -15.693136)
		(size 0.508)
		(drill 0.254)
		(layers "F.Cu" "B.Cu")
		(net "GND")
	)
	(via
		(at 40.091614 -344.772234)
		(size 0.508)
		(drill 0.254)
		(layers "F.Cu" "B.Cu")
		(net "GND")
	)
	(via
		(at 191.160146 -251.735336)
		(size 0.4826)
		(drill 0.254)
		(layers "F.Cu" "B.Cu")
		(net "GND")
	)
	(via
		(at 126.814834 -231.524302)
		(size 0.4064)
		(drill 0.2032)
		(layers "F.Cu" "B.Cu")
		(net "GND")
	)
	(via
		(at 120.43791 -169.097198)
		(size 0.508)
		(drill 0.254)
		(layers "F.Cu" "B.Cu")
		(net "GND")
	)
	(via
		(at 413.485584 -304.860198)
		(size 0.4826)
		(drill 0.254)
		(layers "F.Cu" "B.Cu")
		(net "GND")
	)
	(via
		(at 396.349474 -433.747164)
		(size 0.4572)
		(drill 0.2032)
		(layers "F.Cu" "B.Cu")
		(net "GND")
	)
	(via
		(at 412.367984 -197.33514)
		(size 0.4826)
		(drill 0.254)
		(layers "F.Cu" "B.Cu")
		(net "GND")
	)
	(via
		(at 459.843632 -390.962642)
		(size 0.508)
		(drill 0.254)
		(layers "F.Cu" "B.Cu")
		(net "GND")
	)
	(via
		(at 33.362138 -16.9799)
		(size 0.508)
		(drill 0.254)
		(layers "F.Cu" "B.Cu")
		(net "GND")
	)
	(via
		(at 370.491004 -398.542002)
		(size 0.4064)
		(drill 0.2032)
		(layers "F.Cu" "B.Cu")
		(net "GND")
	)
	(via
		(at 452.197978 -395.306042)
		(size 0.49022)
		(drill 0.254)
		(layers "F.Cu" "B.Cu")
		(net "GND")
	)
	(via
		(at 329.7809 -328.097134)
		(size 0.508)
		(drill 0.254)
		(layers "F.Cu" "B.Cu")
		(net "GND")
	)
	(via
		(at 119.12473 -270.846296)
		(size 0.4064)
		(drill 0.2032)
		(layers "F.Cu" "B.Cu")
		(net "GND")
	)
	(via
		(at 91.871038 -267.606272)
		(size 0.4064)
		(drill 0.2032)
		(layers "F.Cu" "B.Cu")
		(net "GND")
	)
	(via
		(at 192.277746 -238.560356)
		(size 0.4826)
		(drill 0.254)
		(layers "F.Cu" "B.Cu")
		(net "GND")
	)
	(via
		(at 143.349726 -437.49976)
		(size 0.4572)
		(drill 0.2032)
		(layers "F.Cu" "B.Cu")
		(net "GND")
	)
	(via
		(at 131.98475 -251.774452)
		(size 0.4064)
		(drill 0.2032)
		(layers "F.Cu" "B.Cu")
		(net "GND")
	)
	(via
		(at 154.518614 -413.204152)
		(size 0.4572)
		(drill 0.254)
		(layers "F.Cu" "B.Cu")
		(net "GND")
	)
	(via
		(at 90.16111 -241.244374)
		(size 0.4064)
		(drill 0.2032)
		(layers "F.Cu" "B.Cu")
		(net "GND")
	)
	(via
		(at 154.644344 -382.85293)
		(size 0.4064)
		(drill 0.2032)
		(layers "F.Cu" "B.Cu")
		(net "GND")
	)
	(via
		(at 108.321094 -287.856422)
		(size 0.4064)
		(drill 0.2032)
		(layers "F.Cu" "B.Cu")
		(net "GND")
	)
	(via
		(at 109.261148 -281.376374)
		(size 0.4064)
		(drill 0.2032)
		(layers "F.Cu" "B.Cu")
		(net "GND")
	)
	(via
		(at 51.766978 -427.017942)
		(size 0.508)
		(drill 0.254)
		(layers "F.Cu" "B.Cu")
		(net "GND")
	)
	(via
		(at 44.124626 -4.32943)
		(size 0.508)
		(drill 0.254)
		(layers "F.Cu" "B.Cu")
		(net "GND")
	)
	(via
		(at 396.589504 -145.353532)
		(size 0.49022)
		(drill 0.254)
		(layers "F.Cu" "B.Cu")
		(net "GND")
	)
	(via
		(at 344.681048 -236.384084)
		(size 0.4064)
		(drill 0.2032)
		(layers "F.Cu" "B.Cu")
		(net "GND")
	)
	(via
		(at 304.652426 -294.235124)
		(size 0.4826)
		(drill 0.254)
		(layers "F.Cu" "B.Cu")
		(net "GND")
	)
	(via
		(at 354.851208 -288.66592)
		(size 0.4064)
		(drill 0.2032)
		(layers "F.Cu" "B.Cu")
		(net "GND")
	)
	(via
		(at 362.999274 -179.710588)
		(size 0.49022)
		(drill 0.254)
		(layers "F.Cu" "B.Cu")
		(net "GND")
	)
	(via
		(at 326.297798 -412.212536)
		(size 0.4572)
		(drill 0.254)
		(layers "F.Cu" "B.Cu")
		(net "GND")
	)
	(via
		(at 95.1611 -289.47618)
		(size 0.4064)
		(drill 0.2032)
		(layers "F.Cu" "B.Cu")
		(net "GND")
	)
	(via
		(at 415.779966 -133.27126)
		(size 0.508)
		(drill 0.254)
		(layers "F.Cu" "B.Cu")
		(net "GND")
	)
	(via
		(at 141.274038 -390.318498)
		(size 0.508)
		(drill 0.254)
		(layers "F.Cu" "B.Cu")
		(net "GND")
	)
	(via
		(at 348.382844 -377.41733)
		(size 0.508)
		(drill 0.254)
		(layers "F.Cu" "B.Cu")
		(net "GND")
	)
	(via
		(at 376.46483 -269.22603)
		(size 0.4064)
		(drill 0.2032)
		(layers "F.Cu" "B.Cu")
		(net "GND")
	)
	(via
		(at 118.65483 -273.276314)
		(size 0.4064)
		(drill 0.2032)
		(layers "F.Cu" "B.Cu")
		(net "GND")
	)
	(via
		(at 369.895628 -147.568158)
		(size 0.508)
		(drill 0.254)
		(layers "F.Cu" "B.Cu")
		(net "GND")
	)
	(via
		(at 378.398278 -144.266158)
		(size 0.508)
		(drill 0.254)
		(layers "F.Cu" "B.Cu")
		(net "GND")
	)
	(via
		(at 412.138622 -412.84652)
		(size 0.4064)
		(drill 0.2032)
		(layers "F.Cu" "B.Cu")
		(net "GND")
	)
	(via
		(at 69.39788 -388.892542)
		(size 0.508)
		(drill 0.254)
		(layers "F.Cu" "B.Cu")
		(net "GND")
	)
	(via
		(at 32.695896 -245.785386)
		(size 0.4826)
		(drill 0.254)
		(layers "F.Cu" "B.Cu")
		(net "GND")
	)
	(via
		(at 338.101178 -223.424242)
		(size 0.4064)
		(drill 0.2032)
		(layers "F.Cu" "B.Cu")
		(net "GND")
	)
	(via
		(at 27.299158 -344.781886)
		(size 0.49022)
		(drill 0.254)
		(layers "F.Cu" "B.Cu")
		(net "GND")
	)
	(via
		(at 297.215052 -345.8972)
		(size 0.49022)
		(drill 0.254)
		(layers "F.Cu" "B.Cu")
		(net "GND")
	)
	(via
		(at 328.231246 -253.39421)
		(size 0.4064)
		(drill 0.2032)
		(layers "F.Cu" "B.Cu")
		(net "GND")
	)
	(via
		(at 198.7042 -267.03528)
		(size 0.4826)
		(drill 0.254)
		(layers "F.Cu" "B.Cu")
		(net "GND")
	)
	(via
		(at 357.671116 -265.986006)
		(size 0.4064)
		(drill 0.2032)
		(layers "F.Cu" "B.Cu")
		(net "GND")
	)
	(via
		(at 451.2437 -193.10731)
		(size 0.4826)
		(drill 0.254)
		(layers "F.Cu" "B.Cu")
		(net "GND")
	)
	(via
		(at 34.080196 -312.935366)
		(size 0.4826)
		(drill 0.254)
		(layers "F.Cu" "B.Cu")
		(net "GND")
	)
	(via
		(at 161.34334 -437.27243)
		(size 0.508)
		(drill 0.254)
		(layers "F.Cu" "B.Cu")
		(net "GND")
	)
	(via
		(at 467.5378 -166.675054)
		(size 0.508)
		(drill 0.254)
		(layers "F.Cu" "B.Cu")
		(net "GND")
	)
	(via
		(at 378.081794 -413.480504)
		(size 0.4572)
		(drill 0.254)
		(layers "F.Cu" "B.Cu")
		(net "GND")
	)
	(via
		(at 94.861126 -229.90429)
		(size 0.4064)
		(drill 0.2032)
		(layers "F.Cu" "B.Cu")
		(net "GND")
	)
	(via
		(at 439.703718 -433.09921)
		(size 0.508)
		(drill 0.254)
		(layers "F.Cu" "B.Cu")
		(net "GND")
	)
	(via
		(at 142.351506 -410.030168)
		(size 0.4064)
		(drill 0.2032)
		(layers "F.Cu" "B.Cu")
		(net "GND")
	)
	(via
		(at 235.08335 -288.333688)
		(size 0.508)
		(drill 0.254)
		(layers "F.Cu" "B.Cu")
		(net "GND")
	)
	(via
		(at 329.6412 -254.204216)
		(size 0.4064)
		(drill 0.2032)
		(layers "F.Cu" "B.Cu")
		(net "GND")
	)
	(via
		(at 349.272098 -419.046152)
		(size 0.4572)
		(drill 0.254)
		(layers "F.Cu" "B.Cu")
		(net "GND")
	)
	(via
		(at 126.34468 -229.094538)
		(size 0.4064)
		(drill 0.2032)
		(layers "F.Cu" "B.Cu")
		(net "GND")
	)
	(via
		(at 28.134564 -275.960332)
		(size 0.4826)
		(drill 0.254)
		(layers "F.Cu" "B.Cu")
		(net "GND")
	)
	(via
		(at 186.055 -135.600948)
		(size 0.508)
		(drill 0.254)
		(layers "F.Cu" "B.Cu")
		(net "GND")
	)
	(via
		(at 337.736942 -138.660886)
		(size 0.508)
		(drill 0.254)
		(layers "F.Cu" "B.Cu")
		(net "GND")
	)
	(via
		(at 385.394708 -291.095938)
		(size 0.4064)
		(drill 0.2032)
		(layers "F.Cu" "B.Cu")
		(net "GND")
	)
	(via
		(at 79.906368 -386.449062)
		(size 0.4064)
		(drill 0.2032)
		(layers "F.Cu" "B.Cu")
		(net "GND")
	)
	(via
		(at 40.23995 -292.535356)
		(size 0.4826)
		(drill 0.254)
		(layers "F.Cu" "B.Cu")
		(net "GND")
	)
	(via
		(at 412.618936 -398.542002)
		(size 0.4064)
		(drill 0.2032)
		(layers "F.Cu" "B.Cu")
		(net "GND")
	)
	(via
		(at 215.937084 -385.733798)
		(size 0.508)
		(drill 0.254)
		(layers "F.Cu" "B.Cu")
		(net "GND")
	)
	(via
		(at 2.76225 -221.925134)
		(size 0.508)
		(drill 0.254)
		(layers "F.Cu" "B.Cu")
		(net "GND")
	)
	(via
		(at 388.364222 -6.63321)
		(size 0.508)
		(drill 0.254)
		(layers "F.Cu" "B.Cu")
		(net "GND")
	)
	(via
		(at 413.806132 -394.831062)
		(size 0.4064)
		(drill 0.2032)
		(layers "F.Cu" "B.Cu")
		(net "GND")
	)
	(via
		(at 70.935342 -25.193244)
		(size 0.508)
		(drill 0.254)
		(layers "F.Cu" "B.Cu")
		(net "GND")
	)
	(via
		(at 346.567506 -415.38652)
		(size 0.4064)
		(drill 0.2032)
		(layers "F.Cu" "B.Cu")
		(net "GND")
	)
	(via
		(at 312.224166 -343.472008)
		(size 0.508)
		(drill 0.254)
		(layers "F.Cu" "B.Cu")
		(net "GND")
	)
	(via
		(at 82.249772 -432.451256)
		(size 0.4572)
		(drill 0.2032)
		(layers "F.Cu" "B.Cu")
		(net "GND")
	)
	(via
		(at 371.46484 -232.334054)
		(size 0.4064)
		(drill 0.2032)
		(layers "F.Cu" "B.Cu")
		(net "GND")
	)
	(via
		(at 137.759186 -412.570168)
		(size 0.4064)
		(drill 0.2032)
		(layers "F.Cu" "B.Cu")
		(net "GND")
	)
	(via
		(at 439.100214 -244.934994)
		(size 0.4826)
		(drill 0.254)
		(layers "F.Cu" "B.Cu")
		(net "GND")
	)
	(via
		(at 115.834668 -268.416278)
		(size 0.4064)
		(drill 0.2032)
		(layers "F.Cu" "B.Cu")
		(net "GND")
	)
	(via
		(at 146.742912 -246.370348)
		(size 0.4064)
		(drill 0.2032)
		(layers "F.Cu" "B.Cu")
		(net "GND")
	)
	(via
		(at 299.82414 -291.684964)
		(size 0.4826)
		(drill 0.254)
		(layers "F.Cu" "B.Cu")
		(net "GND")
	)
	(via
		(at 366.594898 -286.236156)
		(size 0.4064)
		(drill 0.2032)
		(layers "F.Cu" "B.Cu")
		(net "GND")
	)
	(via
		(at 84.082636 -406.370536)
		(size 0.4572)
		(drill 0.254)
		(layers "F.Cu" "B.Cu")
		(net "GND")
	)
	(via
		(at 16.205708 -401.319238)
		(size 0.508)
		(drill 0.254)
		(layers "F.Cu" "B.Cu")
		(net "GND")
	)
	(via
		(at 345.451176 -291.905944)
		(size 0.4064)
		(drill 0.2032)
		(layers "F.Cu" "B.Cu")
		(net "GND")
	)
	(via
		(at 455.02703 -50.164238)
		(size 0.508)
		(drill 0.254)
		(layers "F.Cu" "B.Cu")
		(net "GND")
	)
	(via
		(at 264.478516 -133.063996)
		(size 0.508)
		(drill 0.254)
		(layers "F.Cu" "B.Cu")
		(net "GND")
	)
	(via
		(at 127.114808 -289.47618)
		(size 0.4064)
		(drill 0.2032)
		(layers "F.Cu" "B.Cu")
		(net "GND")
	)
	(via
		(at 115.94465 -171.357544)
		(size 0.49022)
		(drill 0.254)
		(layers "F.Cu" "B.Cu")
		(net "GND")
	)
	(via
		(at 206.248 -216.885266)
		(size 0.4826)
		(drill 0.254)
		(layers "F.Cu" "B.Cu")
		(net "GND")
	)
	(via
		(at 70.43293 -181.530498)
		(size 0.508)
		(drill 0.254)
		(layers "F.Cu" "B.Cu")
		(net "GND")
	)
	(via
		(at 123.824746 -280.566368)
		(size 0.4064)
		(drill 0.2032)
		(layers "F.Cu" "B.Cu")
		(net "GND")
	)
	(via
		(at 152.675844 -369.03533)
		(size 0.508)
		(drill 0.254)
		(layers "F.Cu" "B.Cu")
		(net "GND")
	)
	(via
		(at 427.456092 -197.33514)
		(size 0.4826)
		(drill 0.254)
		(layers "F.Cu" "B.Cu")
		(net "GND")
	)
	(via
		(at 338.401152 -273.27606)
		(size 0.4064)
		(drill 0.2032)
		(layers "F.Cu" "B.Cu")
		(net "GND")
	)
	(via
		(at 2.76225 -238.689134)
		(size 0.508)
		(drill 0.254)
		(layers "F.Cu" "B.Cu")
		(net "GND")
	)
	(via
		(at 375.224802 -233.954066)
		(size 0.4064)
		(drill 0.2032)
		(layers "F.Cu" "B.Cu")
		(net "GND")
	)
	(via
		(at 40.23995 -301.88535)
		(size 0.4826)
		(drill 0.254)
		(layers "F.Cu" "B.Cu")
		(net "GND")
	)
	(via
		(at 339.582252 -164.140134)
		(size 0.6604)
		(drill 0.3302)
		(layers "F.Cu" "B.Cu")
		(net "GND")
	)
	(via
		(at 105.500932 -274.896326)
		(size 0.4064)
		(drill 0.2032)
		(layers "F.Cu" "B.Cu")
		(net "GND")
	)
	(via
		(at 233.016044 -44.323)
		(size 0.508)
		(drill 0.254)
		(layers "F.Cu" "B.Cu")
		(net "GND")
	)
	(via
		(at 369.414806 -263.555988)
		(size 0.4064)
		(drill 0.2032)
		(layers "F.Cu" "B.Cu")
		(net "GND")
	)
	(via
		(at 333.230982 -272.466054)
		(size 0.4064)
		(drill 0.2032)
		(layers "F.Cu" "B.Cu")
		(net "GND")
	)
	(via
		(at 353.144074 -391.23493)
		(size 0.4064)
		(drill 0.2032)
		(layers "F.Cu" "B.Cu")
		(net "GND")
	)
	(via
		(at 134.334758 -405.098504)
		(size 0.4572)
		(drill 0.254)
		(layers "F.Cu" "B.Cu")
		(net "GND")
	)
	(via
		(at 165.805104 -368.37493)
		(size 0.508)
		(drill 0.254)
		(layers "F.Cu" "B.Cu")
		(net "GND")
	)
	(via
		(at 132.284724 -265.98626)
		(size 0.4064)
		(drill 0.2032)
		(layers "F.Cu" "B.Cu")
		(net "GND")
	)
	(via
		(at 188.444378 -231.335326)
		(size 0.4826)
		(drill 0.254)
		(layers "F.Cu" "B.Cu")
		(net "GND")
	)
	(via
		(at 44.340018 -299.335444)
		(size 0.4826)
		(drill 0.254)
		(layers "F.Cu" "B.Cu")
		(net "GND")
	)
	(via
		(at 191.160146 -301.035212)
		(size 0.4826)
		(drill 0.254)
		(layers "F.Cu" "B.Cu")
		(net "GND")
	)
	(via
		(at 97.681034 -225.044508)
		(size 0.4064)
		(drill 0.2032)
		(layers "F.Cu" "B.Cu")
		(net "GND")
	)
	(via
		(at 411.40634 -394.831062)
		(size 0.4064)
		(drill 0.2032)
		(layers "F.Cu" "B.Cu")
		(net "GND")
	)
	(via
		(at 147.042886 -264.910316)
		(size 0.4064)
		(drill 0.2032)
		(layers "F.Cu" "B.Cu")
		(net "GND")
	)
	(via
		(at 155.349702 -438.651396)
		(size 0.4572)
		(drill 0.2032)
		(layers "F.Cu" "B.Cu")
		(net "GND")
	)
	(via
		(at 36.795964 -246.63527)
		(size 0.4826)
		(drill 0.254)
		(layers "F.Cu" "B.Cu")
		(net "GND")
	)
	(via
		(at 80.291178 -248.534428)
		(size 0.4064)
		(drill 0.2032)
		(layers "F.Cu" "B.Cu")
		(net "GND")
	)
	(via
		(at 312.00217 -358.791256)
		(size 0.508)
		(drill 0.254)
		(layers "F.Cu" "B.Cu")
		(net "GND")
	)
	(via
		(at 352.696526 -415.38652)
		(size 0.4064)
		(drill 0.2032)
		(layers "F.Cu" "B.Cu")
		(net "GND")
	)
	(via
		(at 137.924794 -293.52621)
		(size 0.4064)
		(drill 0.2032)
		(layers "F.Cu" "B.Cu")
		(net "GND")
	)
	(via
		(at 356.261162 -279.756108)
		(size 0.4064)
		(drill 0.2032)
		(layers "F.Cu" "B.Cu")
		(net "GND")
	)
	(via
		(at 88.580976 -294.336216)
		(size 0.4064)
		(drill 0.2032)
		(layers "F.Cu" "B.Cu")
		(net "GND")
	)
	(via
		(at 83.88096 -294.336216)
		(size 0.4064)
		(drill 0.2032)
		(layers "F.Cu" "B.Cu")
		(net "GND")
	)
	(via
		(at 25.152096 -301.88535)
		(size 0.4826)
		(drill 0.254)
		(layers "F.Cu" "B.Cu")
		(net "GND")
	)
	(via
		(at 84.249768 -430.299622)
		(size 0.4572)
		(drill 0.2032)
		(layers "F.Cu" "B.Cu")
		(net "GND")
	)
	(via
		(at 348.101666 -412.84652)
		(size 0.4064)
		(drill 0.2032)
		(layers "F.Cu" "B.Cu")
		(net "GND")
	)
	(via
		(at 454.188068 -246.635016)
		(size 0.4826)
		(drill 0.254)
		(layers "F.Cu" "B.Cu")
		(net "GND")
	)
	(via
		(at 47.362618 -346.306902)
		(size 0.49022)
		(drill 0.254)
		(layers "F.Cu" "B.Cu")
		(net "GND")
	)
	(via
		(at 382.1049 -269.22603)
		(size 0.4064)
		(drill 0.2032)
		(layers "F.Cu" "B.Cu")
		(net "GND")
	)
	(via
		(at 381.804926 -227.474272)
		(size 0.4064)
		(drill 0.2032)
		(layers "F.Cu" "B.Cu")
		(net "GND")
	)
	(via
		(at 432.67376 -275.960078)
		(size 0.4826)
		(drill 0.254)
		(layers "F.Cu" "B.Cu")
		(net "GND")
	)
	(via
		(at 317.022226 -415.38652)
		(size 0.4064)
		(drill 0.2032)
		(layers "F.Cu" "B.Cu")
		(net "GND")
	)
	(via
		(at 174.687738 -218.585288)
		(size 0.4826)
		(drill 0.254)
		(layers "F.Cu" "B.Cu")
		(net "GND")
	)
	(via
		(at 390.710674 -184.683146)
		(size 0.49022)
		(drill 0.254)
		(layers "F.Cu" "B.Cu")
		(net "GND")
	)
	(via
		(at 197.3199 -218.585288)
		(size 0.4826)
		(drill 0.254)
		(layers "F.Cu" "B.Cu")
		(net "GND")
	)
	(via
		(at 437.715914 -314.635134)
		(size 0.4826)
		(drill 0.254)
		(layers "F.Cu" "B.Cu")
		(net "GND")
	)
	(via
		(at 323.249544 -431.451258)
		(size 0.4572)
		(drill 0.2032)
		(layers "F.Cu" "B.Cu")
		(net "GND")
	)
	(via
		(at 146.587718 -411.936184)
		(size 0.4572)
		(drill 0.254)
		(layers "F.Cu" "B.Cu")
		(net "GND")
	)
	(via
		(at 413.752284 -221.985078)
		(size 0.4826)
		(drill 0.254)
		(layers "F.Cu" "B.Cu")
		(net "GND")
	)
	(via
		(at 165.812216 -228.78542)
		(size 0.4826)
		(drill 0.254)
		(layers "F.Cu" "B.Cu")
		(net "GND")
	)
	(via
		(at 452.803768 -218.585034)
		(size 0.4826)
		(drill 0.254)
		(layers "F.Cu" "B.Cu")
		(net "GND")
	)
	(via
		(at 94.803976 -405.098504)
		(size 0.4572)
		(drill 0.254)
		(layers "F.Cu" "B.Cu")
		(net "GND")
	)
	(via
		(at 422.627806 -305.28514)
		(size 0.4826)
		(drill 0.254)
		(layers "F.Cu" "B.Cu")
		(net "GND")
	)
	(via
		(at 106.611166 -229.094538)
		(size 0.4064)
		(drill 0.2032)
		(layers "F.Cu" "B.Cu")
		(net "GND")
	)
	(via
		(at 303.268126 -227.085144)
		(size 0.4826)
		(drill 0.254)
		(layers "F.Cu" "B.Cu")
		(net "GND")
	)
	(via
		(at 346.516706 -306.819046)
		(size 0.508)
		(drill 0.254)
		(layers "F.Cu" "B.Cu")
		(net "GND")
	)
	(via
		(at 0.762254 -65.831212)
		(size 0.508)
		(drill 0.254)
		(layers "F.Cu" "B.Cu")
		(net "GND")
	)
	(via
		(at 367.064798 -287.045908)
		(size 0.4064)
		(drill 0.2032)
		(layers "F.Cu" "B.Cu")
		(net "GND")
	)
	(via
		(at 411.49016 -392.999722)
		(size 0.4064)
		(drill 0.2032)
		(layers "F.Cu" "B.Cu")
		(net "GND")
	)
	(via
		(at 360.197654 -254.44831)
		(size 0.4826)
		(drill 0.254)
		(layers "F.Cu" "B.Cu")
		(net "GND")
	)
	(via
		(at 53.723032 -405.098504)
		(size 0.4572)
		(drill 0.254)
		(layers "F.Cu" "B.Cu")
		(net "GND")
	)
	(via
		(at 104.731058 -238.814356)
		(size 0.4064)
		(drill 0.2032)
		(layers "F.Cu" "B.Cu")
		(net "GND")
	)
	(via
		(at 146.742912 -239.8903)
		(size 0.4064)
		(drill 0.2032)
		(layers "F.Cu" "B.Cu")
		(net "GND")
	)
	(via
		(at 315.24956 -427.851316)
		(size 0.4572)
		(drill 0.2032)
		(layers "F.Cu" "B.Cu")
		(net "GND")
	)
	(via
		(at 348.343982 -391.23493)
		(size 0.4064)
		(drill 0.2032)
		(layers "F.Cu" "B.Cu")
		(net "GND")
	)
	(via
		(at 107.081066 -250.964446)
		(size 0.4064)
		(drill 0.2032)
		(layers "F.Cu" "B.Cu")
		(net "GND")
	)
	(via
		(at 175.900334 -38.730428)
		(size 0.508)
		(drill 0.254)
		(layers "F.Cu" "B.Cu")
		(net "GND")
	)
	(via
		(at 249.54357 -67.254374)
		(size 0.508)
		(drill 0.254)
		(layers "F.Cu" "B.Cu")
		(net "GND")
	)
	(via
		(at 393.084812 -238.814102)
		(size 0.4064)
		(drill 0.2032)
		(layers "F.Cu" "B.Cu")
		(net "GND")
	)
	(via
		(at 365.380778 -258.379976)
		(size 0.4826)
		(drill 0.254)
		(layers "F.Cu" "B.Cu")
		(net "GND")
	)
	(via
		(at 288.180018 -298.485052)
		(size 0.4826)
		(drill 0.254)
		(layers "F.Cu" "B.Cu")
		(net "GND")
	)
	(via
		(at 393.222226 -190.995808)
		(size 0.508)
		(drill 0.254)
		(layers "F.Cu" "B.Cu")
		(net "GND")
	)
	(via
		(at 181.407562 -48.22571)
		(size 0.508)
		(drill 0.254)
		(layers "F.Cu" "B.Cu")
		(net "GND")
	)
	(via
		(at 105.968038 -264.36828)
		(size 0.4064)
		(drill 0.2032)
		(layers "F.Cu" "B.Cu")
		(net "GND")
	)
	(via
		(at 348.271084 -291.905944)
		(size 0.4064)
		(drill 0.2032)
		(layers "F.Cu" "B.Cu")
		(net "GND")
	)
	(via
		(at 333.230982 -267.606018)
		(size 0.4064)
		(drill 0.2032)
		(layers "F.Cu" "B.Cu")
		(net "GND")
	)
	(via
		(at 454.179178 -395.306042)
		(size 0.49022)
		(drill 0.254)
		(layers "F.Cu" "B.Cu")
		(net "GND")
	)
	(via
		(at 203.532232 -212.635338)
		(size 0.4826)
		(drill 0.254)
		(layers "F.Cu" "B.Cu")
		(net "GND")
	)
	(via
		(at 83.77809 -180.755544)
		(size 0.49022)
		(drill 0.254)
		(layers "F.Cu" "B.Cu")
		(net "GND")
	)
	(via
		(at 464.065366 -377.29287)
		(size 0.508)
		(drill 0.254)
		(layers "F.Cu" "B.Cu")
		(net "GND")
	)
	(via
		(at 132.284724 -283.806392)
		(size 0.4064)
		(drill 0.2032)
		(layers "F.Cu" "B.Cu")
		(net "GND")
	)
	(via
		(at 27.867864 -221.135194)
		(size 0.4826)
		(drill 0.254)
		(layers "F.Cu" "B.Cu")
		(net "GND")
	)
	(via
		(at 353.441 -289.475926)
		(size 0.4064)
		(drill 0.2032)
		(layers "F.Cu" "B.Cu")
		(net "GND")
	)
	(via
		(at 194.604132 -281.48534)
		(size 0.4826)
		(drill 0.254)
		(layers "F.Cu" "B.Cu")
		(net "GND")
	)
	(via
		(at 88.281002 -234.764326)
		(size 0.4064)
		(drill 0.2032)
		(layers "F.Cu" "B.Cu")
		(net "GND")
	)
	(via
		(at 454.188068 -205.834996)
		(size 0.4826)
		(drill 0.254)
		(layers "F.Cu" "B.Cu")
		(net "GND")
	)
	(via
		(at 369.414806 -289.475926)
		(size 0.4064)
		(drill 0.2032)
		(layers "F.Cu" "B.Cu")
		(net "GND")
	)
	(via
		(at 206.248 -253.435358)
		(size 0.4826)
		(drill 0.254)
		(layers "F.Cu" "B.Cu")
		(net "GND")
	)
	(via
		(at 424.012106 -196.485002)
		(size 0.4826)
		(drill 0.254)
		(layers "F.Cu" "B.Cu")
		(net "GND")
	)
	(via
		(at 439.100214 -306.985162)
		(size 0.4826)
		(drill 0.254)
		(layers "F.Cu" "B.Cu")
		(net "GND")
	)
	(via
		(at 102.85095 -224.234502)
		(size 0.4064)
		(drill 0.2032)
		(layers "F.Cu" "B.Cu")
		(net "GND")
	)
	(via
		(at 149.272244 -373.96293)
		(size 0.508)
		(drill 0.254)
		(layers "F.Cu" "B.Cu")
		(net "GND")
	)
	(via
		(at 338.823554 -417.778184)
		(size 0.4572)
		(drill 0.254)
		(layers "F.Cu" "B.Cu")
		(net "GND")
	)
	(via
		(at 126.676658 -409.396184)
		(size 0.4572)
		(drill 0.254)
		(layers "F.Cu" "B.Cu")
		(net "GND")
	)
	(via
		(at 346.091002 -240.434114)
		(size 0.4064)
		(drill 0.2032)
		(layers "F.Cu" "B.Cu")
		(net "GND")
	)
	(via
		(at 82.265266 -183.893968)
		(size 0.49022)
		(drill 0.254)
		(layers "F.Cu" "B.Cu")
		(net "GND")
	)
	(via
		(at 392.07059 -193.781426)
		(size 0.508)
		(drill 0.254)
		(layers "F.Cu" "B.Cu")
		(net "GND")
	)
	(via
		(at 131.271518 -413.204152)
		(size 0.4572)
		(drill 0.254)
		(layers "F.Cu" "B.Cu")
		(net "GND")
	)
	(via
		(at 380.224792 -282.186126)
		(size 0.4064)
		(drill 0.2032)
		(layers "F.Cu" "B.Cu")
		(net "GND")
	)
	(via
		(at 200.013824 -12.542266)
		(size 0.508)
		(drill 0.254)
		(layers "F.Cu" "B.Cu")
		(net "GND")
	)
	(via
		(at 394.84808 -12.37488)
		(size 0.508)
		(drill 0.254)
		(layers "F.Cu" "B.Cu")
		(net "GND")
	)
	(via
		(at 25.152096 -227.085398)
		(size 0.4826)
		(drill 0.254)
		(layers "F.Cu" "B.Cu")
		(net "GND")
	)
	(via
		(at 335.114646 -402.734018)
		(size 0.508)
		(drill 0.254)
		(layers "F.Cu" "B.Cu")
		(net "GND")
	)
	(via
		(at 356.261162 -291.095938)
		(size 0.4064)
		(drill 0.2032)
		(layers "F.Cu" "B.Cu")
		(net "GND")
	)
	(via
		(at 63.810134 -344.78595)
		(size 0.49022)
		(drill 0.254)
		(layers "F.Cu" "B.Cu")
		(net "GND")
	)
	(via
		(at 273.092164 -290.83508)
		(size 0.4826)
		(drill 0.254)
		(layers "F.Cu" "B.Cu")
		(net "GND")
	)
	(via
		(at 230.96728 -55.16499)
		(size 0.508)
		(drill 0.254)
		(layers "F.Cu" "B.Cu")
		(net "GND")
	)
	(via
		(at 381.804926 -242.054126)
		(size 0.4064)
		(drill 0.2032)
		(layers "F.Cu" "B.Cu")
		(net "GND")
	)
	(via
		(at 72.06107 -155.31719)
		(size 0.508)
		(drill 0.254)
		(layers "F.Cu" "B.Cu")
		(net "GND")
	)
	(via
		(at 419.946328 -396.710662)
		(size 0.4064)
		(drill 0.2032)
		(layers "F.Cu" "B.Cu")
		(net "GND")
	)
	(via
		(at 164.427916 -217.735404)
		(size 0.4826)
		(drill 0.254)
		(layers "F.Cu" "B.Cu")
		(net "GND")
	)
	(via
		(at 97.491042 -369.69573)
		(size 0.508)
		(drill 0.254)
		(layers "F.Cu" "B.Cu")
		(net "GND")
	)
	(via
		(at 321.249548 -428.851314)
		(size 0.4572)
		(drill 0.2032)
		(layers "F.Cu" "B.Cu")
		(net "GND")
	)
	(via
		(at 391.504678 -283.806138)
		(size 0.4064)
		(drill 0.2032)
		(layers "F.Cu" "B.Cu")
		(net "GND")
	)
	(via
		(at 155.84424 -393.902438)
		(size 0.4572)
		(drill 0.254)
		(layers "F.Cu" "B.Cu")
		(net "GND")
	)
	(via
		(at 98.451162 -261.126224)
		(size 0.4064)
		(drill 0.2032)
		(layers "F.Cu" "B.Cu")
		(net "GND")
	)
	(via
		(at 143.73479 -247.724422)
		(size 0.4064)
		(drill 0.2032)
		(layers "F.Cu" "B.Cu")
		(net "GND")
	)
	(via
		(at 56.483758 -192.218564)
		(size 0.4826)
		(drill 0.254)
		(layers "F.Cu" "B.Cu")
		(net "GND")
	)
	(via
		(at 431.55616 -253.435104)
		(size 0.4826)
		(drill 0.254)
		(layers "F.Cu" "B.Cu")
		(net "GND")
	)
	(via
		(at 137.717276 -377.132088)
		(size 0.508)
		(drill 0.254)
		(layers "F.Cu" "B.Cu")
		(net "GND")
	)
	(via
		(at 424.012106 -272.984976)
		(size 0.4826)
		(drill 0.254)
		(layers "F.Cu" "B.Cu")
		(net "GND")
	)
	(via
		(at 295.724072 -223.6851)
		(size 0.4826)
		(drill 0.254)
		(layers "F.Cu" "B.Cu")
		(net "GND")
	)
	(via
		(at 372.234714 -289.475926)
		(size 0.4064)
		(drill 0.2032)
		(layers "F.Cu" "B.Cu")
		(net "GND")
	)
	(via
		(at 223.829118 -278.779478)
		(size 0.508)
		(drill 0.254)
		(layers "F.Cu" "B.Cu")
		(net "GND")
	)
	(via
		(at 302.923448 -426.82414)
		(size 0.508)
		(drill 0.254)
		(layers "F.Cu" "B.Cu")
		(net "GND")
	)
	(via
		(at 126.916688 -393.927838)
		(size 0.4572)
		(drill 0.254)
		(layers "F.Cu" "B.Cu")
		(net "GND")
	)
	(via
		(at 447.931286 -63.840614)
		(size 0.508)
		(drill 0.254)
		(layers "F.Cu" "B.Cu")
		(net "GND")
	)
	(via
		(at 445.125094 -64.855598)
		(size 0.508)
		(drill 0.254)
		(layers "F.Cu" "B.Cu")
		(net "GND")
	)
	(via
		(at 82.940906 -268.416278)
		(size 0.4064)
		(drill 0.2032)
		(layers "F.Cu" "B.Cu")
		(net "GND")
	)
	(via
		(at 181.407562 -51.14671)
		(size 0.508)
		(drill 0.254)
		(layers "F.Cu" "B.Cu")
		(net "GND")
	)
	(via
		(at 47.816516 -391.830814)
		(size 0.4064)
		(drill 0.2032)
		(layers "F.Cu" "B.Cu")
		(net "GND")
	)
	(via
		(at 284.736032 -250.03506)
		(size 0.4826)
		(drill 0.254)
		(layers "F.Cu" "B.Cu")
		(net "GND")
	)
	(via
		(at 25.660096 -388.493254)
		(size 0.49022)
		(drill 0.254)
		(layers "F.Cu" "B.Cu")
		(net "GND")
	)
	(via
		(at 117.884702 -232.334308)
		(size 0.4064)
		(drill 0.2032)
		(layers "F.Cu" "B.Cu")
		(net "GND")
	)
	(via
		(at 425.73194 -106.470958)
		(size 0.6604)
		(drill 0.3302)
		(layers "F.Cu" "B.Cu")
		(net "GND")
	)
	(via
		(at 269.648178 -265.335004)
		(size 0.4826)
		(drill 0.254)
		(layers "F.Cu" "B.Cu")
		(net "GND")
	)
	(via
		(at 42.055796 -7.215124)
		(size 0.508)
		(drill 0.254)
		(layers "F.Cu" "B.Cu")
		(net "GND")
	)
	(via
		(at 352.335338 -416.020504)
		(size 0.4572)
		(drill 0.254)
		(layers "F.Cu" "B.Cu")
		(net "GND")
	)
	(via
		(at 116.263674 -60.347352)
		(size 0.508)
		(drill 0.254)
		(layers "F.Cu" "B.Cu")
		(net "GND")
	)
	(via
		(at 51.884072 -278.935434)
		(size 0.4826)
		(drill 0.254)
		(layers "F.Cu" "B.Cu")
		(net "GND")
	)
	(via
		(at 99.054666 -183.09209)
		(size 0.49022)
		(drill 0.254)
		(layers "F.Cu" "B.Cu")
		(net "GND")
	)
	(via
		(at 457.628752 -395.191234)
		(size 0.508)
		(drill 0.254)
		(layers "F.Cu" "B.Cu")
		(net "GND")
	)
	(via
		(at 118.446296 -371.49913)
		(size 0.508)
		(drill 0.254)
		(layers "F.Cu" "B.Cu")
		(net "GND")
	)
	(via
		(at 369.584732 -240.434114)
		(size 0.4064)
		(drill 0.2032)
		(layers "F.Cu" "B.Cu")
		(net "GND")
	)
	(via
		(at 222.123 -83.312)
		(size 0.508)
		(drill 0.254)
		(layers "F.Cu" "B.Cu")
		(net "GND")
	)
	(via
		(at 108.961174 -241.244374)
		(size 0.4064)
		(drill 0.2032)
		(layers "F.Cu" "B.Cu")
		(net "GND")
	)
	(via
		(at 104.731058 -237.194344)
		(size 0.4064)
		(drill 0.2032)
		(layers "F.Cu" "B.Cu")
		(net "GND")
	)
	(via
		(at 172.593 -133.815836)
		(size 0.508)
		(drill 0.254)
		(layers "F.Cu" "B.Cu")
		(net "GND")
	)
	(via
		(at 320.587624 -74.184764)
		(size 0.508)
		(drill 0.254)
		(layers "F.Cu" "B.Cu")
		(net "GND")
	)
	(via
		(at 333.230982 -275.706078)
		(size 0.4064)
		(drill 0.2032)
		(layers "F.Cu" "B.Cu")
		(net "GND")
	)
	(via
		(at 103.151178 -270.846296)
		(size 0.4064)
		(drill 0.2032)
		(layers "F.Cu" "B.Cu")
		(net "GND")
	)
	(via
		(at 391.504678 -272.466054)
		(size 0.4064)
		(drill 0.2032)
		(layers "F.Cu" "B.Cu")
		(net "GND")
	)
	(via
		(at 121.174764 -229.90429)
		(size 0.4064)
		(drill 0.2032)
		(layers "F.Cu" "B.Cu")
		(net "GND")
	)
	(via
		(at 408.77617 -150.569676)
		(size 0.508)
		(drill 0.254)
		(layers "F.Cu" "B.Cu")
		(net "GND")
	)
	(via
		(at 136.98474 -274.08632)
		(size 0.4064)
		(drill 0.2032)
		(layers "F.Cu" "B.Cu")
		(net "GND")
	)
	(via
		(at 416.558222 -12.37488)
		(size 0.508)
		(drill 0.254)
		(layers "F.Cu" "B.Cu")
		(net "GND")
	)
	(via
		(at 168.69918 -113.210594)
		(size 0.508)
		(drill 0.254)
		(layers "F.Cu" "B.Cu")
		(net "GND")
	)
	(via
		(at 44.340018 -301.035212)
		(size 0.4826)
		(drill 0.254)
		(layers "F.Cu" "B.Cu")
		(net "GND")
	)
	(via
		(at 121.474738 -287.856422)
		(size 0.4064)
		(drill 0.2032)
		(layers "F.Cu" "B.Cu")
		(net "GND")
	)
	(via
		(at 342.801194 -247.724168)
		(size 0.4064)
		(drill 0.2032)
		(layers "F.Cu" "B.Cu")
		(net "GND")
	)
	(via
		(at 58.317892 -410.664152)
		(size 0.4572)
		(drill 0.254)
		(layers "F.Cu" "B.Cu")
		(net "GND")
	)
	(via
		(at 446.644268 -232.184956)
		(size 0.4826)
		(drill 0.254)
		(layers "F.Cu" "B.Cu")
		(net "GND")
	)
	(via
		(at 112.276636 -251.400564)
		(size 0.4826)
		(drill 0.254)
		(layers "F.Cu" "B.Cu")
		(net "GND")
	)
	(via
		(at 416.254692 -138.573256)
		(size 0.508)
		(drill 0.254)
		(layers "F.Cu" "B.Cu")
		(net "GND")
	)
	(via
		(at 372.853204 -257.930142)
		(size 0.4826)
		(drill 0.254)
		(layers "F.Cu" "B.Cu")
		(net "GND")
	)
	(via
		(at 353.441 -282.996132)
		(size 0.4064)
		(drill 0.2032)
		(layers "F.Cu" "B.Cu")
		(net "GND")
	)
	(via
		(at 276.036532 -193.99631)
		(size 0.4826)
		(drill 0.254)
		(layers "F.Cu" "B.Cu")
		(net "GND")
	)
	(via
		(at 80.969866 -184.683146)
		(size 0.49022)
		(drill 0.254)
		(layers "F.Cu" "B.Cu")
		(net "GND")
	)
	(via
		(at 206.248 -224.535238)
		(size 0.4826)
		(drill 0.254)
		(layers "F.Cu" "B.Cu")
		(net "GND")
	)
	(via
		(at 318.99098 -398.542002)
		(size 0.4064)
		(drill 0.2032)
		(layers "F.Cu" "B.Cu")
		(net "GND")
	)
	(via
		(at 321.87388 -332.411324)
		(size 0.508)
		(drill 0.254)
		(layers "F.Cu" "B.Cu")
		(net "GND")
	)
	(via
		(at 117.316504 -393.927838)
		(size 0.4572)
		(drill 0.254)
		(layers "F.Cu" "B.Cu")
		(net "GND")
	)
	(via
		(at 268.263878 -305.28514)
		(size 0.4826)
		(drill 0.254)
		(layers "F.Cu" "B.Cu")
		(net "GND")
	)
	(via
		(at 103.145082 -375.917968)
		(size 0.508)
		(drill 0.254)
		(layers "F.Cu" "B.Cu")
		(net "GND")
	)
	(via
		(at 356.21595 -418.981128)
		(size 0.508)
		(drill 0.254)
		(layers "F.Cu" "B.Cu")
		(net "GND")
	)
	(via
		(at 299.82414 -241.53495)
		(size 0.4826)
		(drill 0.254)
		(layers "F.Cu" "B.Cu")
		(net "GND")
	)
	(via
		(at 255.927098 -201.163936)
		(size 0.508)
		(drill 0.254)
		(layers "F.Cu" "B.Cu")
		(net "GND")
	)
	(via
		(at 59.302396 -154.84856)
		(size 0.508)
		(drill 0.254)
		(layers "F.Cu" "B.Cu")
		(net "GND")
	)
	(via
		(at 133.161786 -407.00452)
		(size 0.4064)
		(drill 0.2032)
		(layers "F.Cu" "B.Cu")
		(net "GND")
	)
	(via
		(at 353.61118 -235.574078)
		(size 0.4064)
		(drill 0.2032)
		(layers "F.Cu" "B.Cu")
		(net "GND")
	)
	(via
		(at 133.394704 -254.20447)
		(size 0.4064)
		(drill 0.2032)
		(layers "F.Cu" "B.Cu")
		(net "GND")
	)
	(via
		(at 391.777982 -412.84652)
		(size 0.4064)
		(drill 0.2032)
		(layers "F.Cu" "B.Cu")
		(net "GND")
	)
	(via
		(at 144.034764 -276.516338)
		(size 0.4064)
		(drill 0.2032)
		(layers "F.Cu" "B.Cu")
		(net "GND")
	)
	(via
		(at 360.216704 -251.40031)
		(size 0.4826)
		(drill 0.254)
		(layers "F.Cu" "B.Cu")
		(net "GND")
	)
	(via
		(at 18.54581 -10.16508)
		(size 0.508)
		(drill 0.254)
		(layers "F.Cu" "B.Cu")
		(net "GND")
	)
	(via
		(at 364.560612 -172.629576)
		(size 0.508)
		(drill 0.254)
		(layers "F.Cu" "B.Cu")
		(net "GND")
	)
	(via
		(at 361.62869 -390.32561)
		(size 0.508)
		(drill 0.254)
		(layers "F.Cu" "B.Cu")
		(net "GND")
	)
	(via
		(at 424.012106 -226.235006)
		(size 0.4826)
		(drill 0.254)
		(layers "F.Cu" "B.Cu")
		(net "GND")
	)
	(via
		(at 139.974828 -252.584458)
		(size 0.4064)
		(drill 0.2032)
		(layers "F.Cu" "B.Cu")
		(net "GND")
	)
	(via
		(at 430.477168 -353.12858)
		(size 0.49022)
		(drill 0.254)
		(layers "F.Cu" "B.Cu")
		(net "GND")
	)
	(via
		(at 235.453682 -153.606754)
		(size 0.508)
		(drill 0.254)
		(layers "F.Cu" "B.Cu")
		(net "GND")
	)
	(via
		(at 83.77809 -182.177944)
		(size 0.49022)
		(drill 0.254)
		(layers "F.Cu" "B.Cu")
		(net "GND")
	)
	(via
		(at 103.151178 -288.666174)
		(size 0.4064)
		(drill 0.2032)
		(layers "F.Cu" "B.Cu")
		(net "GND")
	)
	(via
		(at 165.006274 -386.449062)
		(size 0.4064)
		(drill 0.2032)
		(layers "F.Cu" "B.Cu")
		(net "GND")
	)
	(via
		(at 159.444182 -382.85293)
		(size 0.4064)
		(drill 0.2032)
		(layers "F.Cu" "B.Cu")
		(net "GND")
	)
	(via
		(at 348.911164 -232.334054)
		(size 0.4064)
		(drill 0.2032)
		(layers "F.Cu" "B.Cu")
		(net "GND")
	)
	(via
		(at 378.514864 -231.524048)
		(size 0.4064)
		(drill 0.2032)
		(layers "F.Cu" "B.Cu")
		(net "GND")
	)
	(via
		(at 89.107518 -141.794992)
		(size 0.508)
		(drill 0.254)
		(layers "F.Cu" "B.Cu")
		(net "GND")
	)
	(via
		(at 268.263878 -302.73498)
		(size 0.4826)
		(drill 0.254)
		(layers "F.Cu" "B.Cu")
		(net "GND")
	)
	(via
		(at 149.349714 -434.899562)
		(size 0.4572)
		(drill 0.2032)
		(layers "F.Cu" "B.Cu")
		(net "GND")
	)
	(via
		(at 424.012106 -255.135126)
		(size 0.4826)
		(drill 0.254)
		(layers "F.Cu" "B.Cu")
		(net "GND")
	)
	(via
		(at 340.441026 -418.412168)
		(size 0.4064)
		(drill 0.2032)
		(layers "F.Cu" "B.Cu")
		(net "GND")
	)
	(via
		(at 23.622 -364.617)
		(size 0.508)
		(drill 0.254)
		(layers "F.Cu" "B.Cu")
		(net "GND")
	)
	(via
		(at 119.12473 -269.226284)
		(size 0.4064)
		(drill 0.2032)
		(layers "F.Cu" "B.Cu")
		(net "GND")
	)
	(via
		(at 203.532232 -210.085432)
		(size 0.4826)
		(drill 0.254)
		(layers "F.Cu" "B.Cu")
		(net "GND")
	)
	(via
		(at 395.084808 -6.598158)
		(size 0.508)
		(drill 0.254)
		(layers "F.Cu" "B.Cu")
		(net "GND")
	)
	(via
		(at 140.744702 -262.746236)
		(size 0.4064)
		(drill 0.2032)
		(layers "F.Cu" "B.Cu")
		(net "GND")
	)
	(via
		(at 386.804916 -280.566114)
		(size 0.4064)
		(drill 0.2032)
		(layers "F.Cu" "B.Cu")
		(net "GND")
	)
	(via
		(at 436.663846 -432.61026)
		(size 0.508)
		(drill 0.254)
		(layers "F.Cu" "B.Cu")
		(net "GND")
	)
	(via
		(at 374.754902 -234.764072)
		(size 0.4064)
		(drill 0.2032)
		(layers "F.Cu" "B.Cu")
		(net "GND")
	)
	(via
		(at 344.249502 -432.747166)
		(size 0.4572)
		(drill 0.2032)
		(layers "F.Cu" "B.Cu")
		(net "GND")
	)
	(via
		(at 376.550174 -417.778184)
		(size 0.4572)
		(drill 0.254)
		(layers "F.Cu" "B.Cu")
		(net "GND")
	)
	(via
		(at 419.912038 -307.835046)
		(size 0.4826)
		(drill 0.254)
		(layers "F.Cu" "B.Cu")
		(net "GND")
	)
	(via
		(at 139.974828 -225.044508)
		(size 0.4064)
		(drill 0.2032)
		(layers "F.Cu" "B.Cu")
		(net "GND")
	)
	(via
		(at 98.75647 -309.47868)
		(size 0.4064)
		(drill 0.2032)
		(layers "F.Cu" "B.Cu")
		(net "GND")
	)
	(via
		(at 155.349702 -426.69968)
		(size 0.4572)
		(drill 0.2032)
		(layers "F.Cu" "B.Cu")
		(net "GND")
	)
	(via
		(at 360.992928 -407.956004)
		(size 0.508)
		(drill 0.254)
		(layers "F.Cu" "B.Cu")
		(net "GND")
	)
	(via
		(at 332.424278 -413.480504)
		(size 0.4572)
		(drill 0.254)
		(layers "F.Cu" "B.Cu")
		(net "GND")
	)
	(via
		(at 355.791008 -267.606018)
		(size 0.4064)
		(drill 0.2032)
		(layers "F.Cu" "B.Cu")
		(net "GND")
	)
	(via
		(at 430.17186 -239.835182)
		(size 0.4826)
		(drill 0.254)
		(layers "F.Cu" "B.Cu")
		(net "GND")
	)
	(via
		(at 318.539876 -72.884792)
		(size 0.508)
		(drill 0.254)
		(layers "F.Cu" "B.Cu")
		(net "GND")
	)
	(via
		(at 94.861126 -241.244374)
		(size 0.4064)
		(drill 0.2032)
		(layers "F.Cu" "B.Cu")
		(net "GND")
	)
	(via
		(at 347.801184 -284.616144)
		(size 0.4064)
		(drill 0.2032)
		(layers "F.Cu" "B.Cu")
		(net "GND")
	)
	(via
		(at 277.192232 -255.135126)
		(size 0.4826)
		(drill 0.254)
		(layers "F.Cu" "B.Cu")
		(net "GND")
	)
	(via
		(at 70.38467 -155.31719)
		(size 0.508)
		(drill 0.254)
		(layers "F.Cu" "B.Cu")
		(net "GND")
	)
	(via
		(at 61.016642 -391.830814)
		(size 0.4064)
		(drill 0.2032)
		(layers "F.Cu" "B.Cu")
		(net "GND")
	)
	(via
		(at 347.801184 -270.036036)
		(size 0.4064)
		(drill 0.2032)
		(layers "F.Cu" "B.Cu")
		(net "GND")
	)
	(via
		(at 416.468052 -282.33497)
		(size 0.4826)
		(drill 0.254)
		(layers "F.Cu" "B.Cu")
		(net "GND")
	)
	(via
		(at 361.594908 -247.724168)
		(size 0.4064)
		(drill 0.2032)
		(layers "F.Cu" "B.Cu")
		(net "GND")
	)
	(via
		(at 138.564874 -230.714296)
		(size 0.4064)
		(drill 0.2032)
		(layers "F.Cu" "B.Cu")
		(net "GND")
	)
	(via
		(at 446.644268 -207.535018)
		(size 0.4826)
		(drill 0.254)
		(layers "F.Cu" "B.Cu")
		(net "GND")
	)
	(via
		(at 66.949066 -170.078654)
		(size 0.49022)
		(drill 0.254)
		(layers "F.Cu" "B.Cu")
		(net "GND")
	)
	(via
		(at 94.861126 -244.484398)
		(size 0.4064)
		(drill 0.2032)
		(layers "F.Cu" "B.Cu")
		(net "GND")
	)
	(via
		(at 180.900324 -210.085432)
		(size 0.4826)
		(drill 0.254)
		(layers "F.Cu" "B.Cu")
		(net "GND")
	)
	(via
		(at 52.049934 -347.287088)
		(size 0.49022)
		(drill 0.254)
		(layers "F.Cu" "B.Cu")
		(net "GND")
	)
	(via
		(at 178.682142 -422.402254)
		(size 0.508)
		(drill 0.254)
		(layers "F.Cu" "B.Cu")
		(net "GND")
	)
	(via
		(at 120.534684 -292.716204)
		(size 0.4064)
		(drill 0.2032)
		(layers "F.Cu" "B.Cu")
		(net "GND")
	)
	(via
		(at 146.587718 -413.204152)
		(size 0.4572)
		(drill 0.254)
		(layers "F.Cu" "B.Cu")
		(net "GND")
	)
	(via
		(at 134.248906 -407.00452)
		(size 0.4064)
		(drill 0.2032)
		(layers "F.Cu" "B.Cu")
		(net "GND")
	)
	(via
		(at 62.77991 -171.512484)
		(size 0.508)
		(drill 0.254)
		(layers "F.Cu" "B.Cu")
		(net "GND")
	)
	(via
		(at 333.529686 -303.631092)
		(size 0.508)
		(drill 0.254)
		(layers "F.Cu" "B.Cu")
		(net "GND")
	)
	(via
		(at 331.351128 -288.66592)
		(size 0.4064)
		(drill 0.2032)
		(layers "F.Cu" "B.Cu")
		(net "GND")
	)
	(via
		(at 307.368194 -308.685184)
		(size 0.4826)
		(drill 0.254)
		(layers "F.Cu" "B.Cu")
		(net "GND")
	)
	(via
		(at 88.580976 -265.176254)
		(size 0.4064)
		(drill 0.2032)
		(layers "F.Cu" "B.Cu")
		(net "GND")
	)
	(via
		(at 122.584718 -237.194344)
		(size 0.4064)
		(drill 0.2032)
		(layers "F.Cu" "B.Cu")
		(net "GND")
	)
	(via
		(at 131.98475 -229.094538)
		(size 0.4064)
		(drill 0.2032)
		(layers "F.Cu" "B.Cu")
		(net "GND")
	)
	(via
		(at 111.153956 -370.83873)
		(size 0.508)
		(drill 0.254)
		(layers "F.Cu" "B.Cu")
		(net "GND")
	)
	(via
		(at 347.897704 -378.07773)
		(size 0.508)
		(drill 0.254)
		(layers "F.Cu" "B.Cu")
		(net "GND")
	)
	(via
		(at 356.261162 -289.475926)
		(size 0.4064)
		(drill 0.2032)
		(layers "F.Cu" "B.Cu")
		(net "GND")
	)
	(via
		(at 55.328058 -227.085398)
		(size 0.4826)
		(drill 0.254)
		(layers "F.Cu" "B.Cu")
		(net "GND")
	)
	(via
		(at 341.22106 -266.796012)
		(size 0.4064)
		(drill 0.2032)
		(layers "F.Cu" "B.Cu")
		(net "GND")
	)
	(via
		(at 377.10491 -224.234248)
		(size 0.4064)
		(drill 0.2032)
		(layers "F.Cu" "B.Cu")
		(net "GND")
	)
	(via
		(at 147.018756 -390.160002)
		(size 0.4064)
		(drill 0.2032)
		(layers "F.Cu" "B.Cu")
		(net "GND")
	)
	(via
		(at 15.333218 -18.247106)
		(size 0.508)
		(drill 0.254)
		(layers "F.Cu" "B.Cu")
		(net "GND")
	)
	(via
		(at 426.009816 -19.13636)
		(size 0.508)
		(drill 0.254)
		(layers "F.Cu" "B.Cu")
		(net "GND")
	)
	(via
		(at 397.387318 -76.055728)
		(size 0.508)
		(drill 0.254)
		(layers "F.Cu" "B.Cu")
		(net "GND")
	)
	(via
		(at 415.083752 -237.285022)
		(size 0.4826)
		(drill 0.254)
		(layers "F.Cu" "B.Cu")
		(net "GND")
	)
	(via
		(at 130.48869 -158.466282)
		(size 0.49022)
		(drill 0.254)
		(layers "F.Cu" "B.Cu")
		(net "GND")
	)
	(via
		(at 454.611994 -45.233082)
		(size 0.508)
		(drill 0.254)
		(layers "F.Cu" "B.Cu")
		(net "GND")
	)
	(via
		(at 134.164832 -270.846296)
		(size 0.4064)
		(drill 0.2032)
		(layers "F.Cu" "B.Cu")
		(net "GND")
	)
	(via
		(at 121.644664 -242.05438)
		(size 0.4064)
		(drill 0.2032)
		(layers "F.Cu" "B.Cu")
		(net "GND")
	)
	(via
		(at 335.11109 -278.946102)
		(size 0.4064)
		(drill 0.2032)
		(layers "F.Cu" "B.Cu")
		(net "GND")
	)
	(via
		(at 348.911164 -225.85426)
		(size 0.4064)
		(drill 0.2032)
		(layers "F.Cu" "B.Cu")
		(net "GND")
	)
	(via
		(at 162.176714 -406.370536)
		(size 0.4572)
		(drill 0.254)
		(layers "F.Cu" "B.Cu")
		(net "GND")
	)
	(via
		(at 337.631024 -235.574078)
		(size 0.4064)
		(drill 0.2032)
		(layers "F.Cu" "B.Cu")
		(net "GND")
	)
	(via
		(at 151.300434 -316.404752)
		(size 0.508)
		(drill 0.254)
		(layers "F.Cu" "B.Cu")
		(net "GND")
	)
	(via
		(at 114.894614 -273.276314)
		(size 0.4064)
		(drill 0.2032)
		(layers "F.Cu" "B.Cu")
		(net "GND")
	)
	(via
		(at 32.945832 -7.215124)
		(size 0.508)
		(drill 0.254)
		(layers "F.Cu" "B.Cu")
		(net "GND")
	)
	(via
		(at 58.138568 -351.736406)
		(size 0.508)
		(drill 0.254)
		(layers "F.Cu" "B.Cu")
		(net "GND")
	)
	(via
		(at 340.281006 -294.335962)
		(size 0.4064)
		(drill 0.2032)
		(layers "F.Cu" "B.Cu")
		(net "GND")
	)
	(via
		(at 427.456092 -247.485154)
		(size 0.4826)
		(drill 0.254)
		(layers "F.Cu" "B.Cu")
		(net "GND")
	)
	(via
		(at 332.697074 -414.752536)
		(size 0.4572)
		(drill 0.254)
		(layers "F.Cu" "B.Cu")
		(net "GND")
	)
	(via
		(at 35.678364 -238.560356)
		(size 0.4826)
		(drill 0.254)
		(layers "F.Cu" "B.Cu")
		(net "GND")
	)
	(via
		(at 302.150526 -239.41024)
		(size 0.4826)
		(drill 0.254)
		(layers "F.Cu" "B.Cu")
		(net "GND")
	)
	(via
		(at 427.456092 -242.385088)
		(size 0.4826)
		(drill 0.254)
		(layers "F.Cu" "B.Cu")
		(net "GND")
	)
	(via
		(at 133.694678 -282.996386)
		(size 0.4064)
		(drill 0.2032)
		(layers "F.Cu" "B.Cu")
		(net "GND")
	)
	(via
		(at 26.638758 -345.571064)
		(size 0.49022)
		(drill 0.254)
		(layers "F.Cu" "B.Cu")
		(net "GND")
	)
	(via
		(at 356.901242 -244.484144)
		(size 0.4064)
		(drill 0.2032)
		(layers "F.Cu" "B.Cu")
		(net "GND")
	)
	(via
		(at 401.349718 -438.499758)
		(size 0.4572)
		(drill 0.2032)
		(layers "F.Cu" "B.Cu")
		(net "GND")
	)
	(via
		(at 454.188068 -267.035026)
		(size 0.4826)
		(drill 0.254)
		(layers "F.Cu" "B.Cu")
		(net "GND")
	)
	(via
		(at 59.428126 -268.735302)
		(size 0.4826)
		(drill 0.254)
		(layers "F.Cu" "B.Cu")
		(net "GND")
	)
	(via
		(at 137.479786 -390.368028)
		(size 0.508)
		(drill 0.254)
		(layers "F.Cu" "B.Cu")
		(net "GND")
	)
	(via
		(at 56.483758 -194.885564)
		(size 0.4826)
		(drill 0.254)
		(layers "F.Cu" "B.Cu")
		(net "GND")
	)
	(via
		(at 424.012106 -233.884978)
		(size 0.4826)
		(drill 0.254)
		(layers "F.Cu" "B.Cu")
		(net "GND")
	)
	(via
		(at 191.160146 -316.33541)
		(size 0.4826)
		(drill 0.254)
		(layers "F.Cu" "B.Cu")
		(net "GND")
	)
	(via
		(at 372.853204 -258.830064)
		(size 0.4826)
		(drill 0.254)
		(layers "F.Cu" "B.Cu")
		(net "GND")
	)
	(via
		(at 49.70526 -105.50906)
		(size 0.508)
		(drill 0.254)
		(layers "F.Cu" "B.Cu")
		(net "GND")
	)
	(via
		(at 89.52103 -268.416278)
		(size 0.4064)
		(drill 0.2032)
		(layers "F.Cu" "B.Cu")
		(net "GND")
	)
	(via
		(at 75.367642 -372.15953)
		(size 0.508)
		(drill 0.254)
		(layers "F.Cu" "B.Cu")
		(net "GND")
	)
	(via
		(at 343.101168 -286.236156)
		(size 0.4064)
		(drill 0.2032)
		(layers "F.Cu" "B.Cu")
		(net "GND")
	)
	(via
		(at 51.884072 -205.83525)
		(size 0.4826)
		(drill 0.254)
		(layers "F.Cu" "B.Cu")
		(net "GND")
	)
	(via
		(at 369.414806 -270.036036)
		(size 0.4064)
		(drill 0.2032)
		(layers "F.Cu" "B.Cu")
		(net "GND")
	)
	(via
		(at 295.724072 -281.485086)
		(size 0.4826)
		(drill 0.254)
		(layers "F.Cu" "B.Cu")
		(net "GND")
	)
	(via
		(at 313.668156 -379.22073)
		(size 0.508)
		(drill 0.254)
		(layers "F.Cu" "B.Cu")
		(net "GND")
	)
	(via
		(at 148.787104 -374.62333)
		(size 0.508)
		(drill 0.254)
		(layers "F.Cu" "B.Cu")
		(net "GND")
	)
	(via
		(at 106.405172 -256.48031)
		(size 0.4826)
		(drill 0.254)
		(layers "F.Cu" "B.Cu")
		(net "GND")
	)
	(via
		(at 368.205004 -396.67815)
		(size 0.4064)
		(drill 0.2032)
		(layers "F.Cu" "B.Cu")
		(net "GND")
	)
	(via
		(at 309.361586 -420.952168)
		(size 0.4064)
		(drill 0.2032)
		(layers "F.Cu" "B.Cu")
		(net "GND")
	)
	(via
		(at 242.218464 -370.740432)
		(size 0.508)
		(drill 0.254)
		(layers "F.Cu" "B.Cu")
		(net "GND")
	)
	(via
		(at 412.138622 -420.952168)
		(size 0.4064)
		(drill 0.2032)
		(layers "F.Cu" "B.Cu")
		(net "GND")
	)
	(via
		(at 41.62425 -296.785284)
		(size 0.4826)
		(drill 0.254)
		(layers "F.Cu" "B.Cu")
		(net "GND")
	)
	(via
		(at 343.544144 -400.212814)
		(size 0.4064)
		(drill 0.2032)
		(layers "F.Cu" "B.Cu")
		(net "GND")
	)
	(via
		(at 328.102214 -420.318184)
		(size 0.4572)
		(drill 0.254)
		(layers "F.Cu" "B.Cu")
		(net "GND")
	)
	(via
		(at 440.203082 -166.124636)
		(size 0.508)
		(drill 0.254)
		(layers "F.Cu" "B.Cu")
		(net "GND")
	)
	(via
		(at 149.349714 -432.451256)
		(size 0.4572)
		(drill 0.2032)
		(layers "F.Cu" "B.Cu")
		(net "GND")
	)
	(via
		(at 103.151178 -277.326344)
		(size 0.4064)
		(drill 0.2032)
		(layers "F.Cu" "B.Cu")
		(net "GND")
	)
	(via
		(at 138.564874 -253.394464)
		(size 0.4064)
		(drill 0.2032)
		(layers "F.Cu" "B.Cu")
		(net "GND")
	)
	(via
		(at 115.869466 -410.030168)
		(size 0.4064)
		(drill 0.2032)
		(layers "F.Cu" "B.Cu")
		(net "GND")
	)
	(via
		(at 427.456092 -204.985112)
		(size 0.4826)
		(drill 0.254)
		(layers "F.Cu" "B.Cu")
		(net "GND")
	)
	(via
		(at 345.921076 -266.796012)
		(size 0.4064)
		(drill 0.2032)
		(layers "F.Cu" "B.Cu")
		(net "GND")
	)
	(via
		(at 141.854682 -239.624362)
		(size 0.4064)
		(drill 0.2032)
		(layers "F.Cu" "B.Cu")
		(net "GND")
	)
	(via
		(at 318.08801 -359.93959)
		(size 0.508)
		(drill 0.254)
		(layers "F.Cu" "B.Cu")
		(net "GND")
	)
	(via
		(at 367.704878 -232.334054)
		(size 0.4064)
		(drill 0.2032)
		(layers "F.Cu" "B.Cu")
		(net "GND")
	)
	(via
		(at 351.731072 -235.574078)
		(size 0.4064)
		(drill 0.2032)
		(layers "F.Cu" "B.Cu")
		(net "GND")
	)
	(via
		(at 115.666266 -172.32249)
		(size 0.49022)
		(drill 0.254)
		(layers "F.Cu" "B.Cu")
		(net "GND")
	)
	(via
		(at 145.444718 -270.846296)
		(size 0.4064)
		(drill 0.2032)
		(layers "F.Cu" "B.Cu")
		(net "GND")
	)
	(via
		(at 107.85094 -275.706332)
		(size 0.4064)
		(drill 0.2032)
		(layers "F.Cu" "B.Cu")
		(net "GND")
	)
	(via
		(at 342.51392 -337.012788)
		(size 0.49022)
		(drill 0.254)
		(layers "F.Cu" "B.Cu")
		(net "GND")
	)
	(via
		(at 137.154666 -252.584458)
		(size 0.4064)
		(drill 0.2032)
		(layers "F.Cu" "B.Cu")
		(net "GND")
	)
	(via
		(at 400.14398 -318.20358)
		(size 0.508)
		(drill 0.254)
		(layers "F.Cu" "B.Cu")
		(net "GND")
	)
	(via
		(at 358.311196 -233.954066)
		(size 0.4064)
		(drill 0.2032)
		(layers "F.Cu" "B.Cu")
		(net "GND")
	)
	(via
		(at 317.044324 -333.845154)
		(size 0.49022)
		(drill 0.254)
		(layers "F.Cu" "B.Cu")
		(net "GND")
	)
	(via
		(at 215.376506 -67.333368)
		(size 0.508)
		(drill 0.254)
		(layers "F.Cu" "B.Cu")
		(net "GND")
	)
	(via
		(at 442.5442 -250.884944)
		(size 0.4826)
		(drill 0.254)
		(layers "F.Cu" "B.Cu")
		(net "GND")
	)
	(via
		(at 467.5378 -367.843054)
		(size 0.508)
		(drill 0.254)
		(layers "F.Cu" "B.Cu")
		(net "GND")
	)
	(via
		(at 430.555908 -431.532538)
		(size 0.508)
		(drill 0.254)
		(layers "F.Cu" "B.Cu")
		(net "GND")
	)
	(via
		(at 92.860622 -157.891988)
		(size 0.508)
		(drill 0.254)
		(layers "F.Cu" "B.Cu")
		(net "GND")
	)
	(via
		(at 391.866374 -414.72866)
		(size 0.4572)
		(drill 0.254)
		(layers "F.Cu" "B.Cu")
		(net "GND")
	)
	(via
		(at 101.91115 -242.05438)
		(size 0.4064)
		(drill 0.2032)
		(layers "F.Cu" "B.Cu")
		(net "GND")
	)
	(via
		(at 32.695896 -267.885418)
		(size 0.4826)
		(drill 0.254)
		(layers "F.Cu" "B.Cu")
		(net "GND")
	)
	(via
		(at 343.418414 -420.318184)
		(size 0.4572)
		(drill 0.254)
		(layers "F.Cu" "B.Cu")
		(net "GND")
	)
	(via
		(at 64.085724 -407.00452)
		(size 0.4064)
		(drill 0.2032)
		(layers "F.Cu" "B.Cu")
		(net "GND")
	)
	(via
		(at 235.902754 -321.652138)
		(size 0.508)
		(drill 0.254)
		(layers "F.Cu" "B.Cu")
		(net "GND")
	)
	(via
		(at 103.748586 -338.789264)
		(size 0.49022)
		(drill 0.254)
		(layers "F.Cu" "B.Cu")
		(net "GND")
	)
	(via
		(at 29.252164 -243.235226)
		(size 0.4826)
		(drill 0.254)
		(layers "F.Cu" "B.Cu")
		(net "GND")
	)
	(via
		(at 118.65483 -271.656302)
		(size 0.4064)
		(drill 0.2032)
		(layers "F.Cu" "B.Cu")
		(net "GND")
	)
	(via
		(at 436.578502 -343.2429)
		(size 0.508)
		(drill 0.254)
		(layers "F.Cu" "B.Cu")
		(net "GND")
	)
	(via
		(at 332.249526 -435.0512)
		(size 0.4572)
		(drill 0.2032)
		(layers "F.Cu" "B.Cu")
		(net "GND")
	)
	(via
		(at 79.444342 -333.05369)
		(size 0.49022)
		(drill 0.254)
		(layers "F.Cu" "B.Cu")
		(net "GND")
	)
	(via
		(at 359.272332 -257.744976)
		(size 0.4826)
		(drill 0.254)
		(layers "F.Cu" "B.Cu")
		(net "GND")
	)
	(via
		(at 228.047296 -230.909622)
		(size 0.4826)
		(drill 0.254)
		(layers "F.Cu" "B.Cu")
		(net "GND")
	)
	(via
		(at 330.369672 -37.017706)
		(size 0.508)
		(drill 0.254)
		(layers "F.Cu" "B.Cu")
		(net "GND")
	)
	(via
		(at 110.371128 -229.094538)
		(size 0.4064)
		(drill 0.2032)
		(layers "F.Cu" "B.Cu")
		(net "GND")
	)
	(via
		(at 410.21889 -398.542002)
		(size 0.4064)
		(drill 0.2032)
		(layers "F.Cu" "B.Cu")
		(net "GND")
	)
	(via
		(at 42.90314 -105.64622)
		(size 0.508)
		(drill 0.254)
		(layers "F.Cu" "B.Cu")
		(net "GND")
	)
	(via
		(at 192.775586 -81.177384)
		(size 0.508)
		(drill 0.254)
		(layers "F.Cu" "B.Cu")
		(net "GND")
	)
	(via
		(at 36.795964 -289.98545)
		(size 0.4826)
		(drill 0.254)
		(layers "F.Cu" "B.Cu")
		(net "GND")
	)
	(via
		(at 330.581 -223.424242)
		(size 0.4064)
		(drill 0.2032)
		(layers "F.Cu" "B.Cu")
		(net "GND")
	)
	(via
		(at 343.740994 -225.044254)
		(size 0.4064)
		(drill 0.2032)
		(layers "F.Cu" "B.Cu")
		(net "GND")
	)
	(via
		(at 380.078488 -394.831062)
		(size 0.4064)
		(drill 0.2032)
		(layers "F.Cu" "B.Cu")
		(net "GND")
	)
	(via
		(at 333.632556 -396.67815)
		(size 0.4064)
		(drill 0.2032)
		(layers "F.Cu" "B.Cu")
		(net "GND")
	)
	(via
		(at 263.05383 -196.489828)
		(size 0.508)
		(drill 0.254)
		(layers "F.Cu" "B.Cu")
		(net "GND")
	)
	(via
		(at 344.446098 -396.710662)
		(size 0.4064)
		(drill 0.2032)
		(layers "F.Cu" "B.Cu")
		(net "GND")
	)
	(via
		(at 146.587718 -405.098504)
		(size 0.4572)
		(drill 0.254)
		(layers "F.Cu" "B.Cu")
		(net "GND")
	)
	(via
		(at 343.101168 -291.095938)
		(size 0.4064)
		(drill 0.2032)
		(layers "F.Cu" "B.Cu")
		(net "GND")
	)
	(via
		(at 388.21487 -268.416024)
		(size 0.4064)
		(drill 0.2032)
		(layers "F.Cu" "B.Cu")
		(net "GND")
	)
	(via
		(at 172.352208 -345.797632)
		(size 0.6604)
		(drill 0.3302)
		(layers "F.Cu" "B.Cu")
		(net "GND")
	)
	(via
		(at 279.518364 -286.16021)
		(size 0.4826)
		(drill 0.254)
		(layers "F.Cu" "B.Cu")
		(net "GND")
	)
	(via
		(at 176.072038 -318.035432)
		(size 0.4826)
		(drill 0.254)
		(layers "F.Cu" "B.Cu")
		(net "GND")
	)
	(via
		(at 230.937562 -246.560086)
		(size 0.4826)
		(drill 0.254)
		(layers "F.Cu" "B.Cu")
		(net "GND")
	)
	(via
		(at 299.448728 -428.421292)
		(size 0.508)
		(drill 0.254)
		(layers "F.Cu" "B.Cu")
		(net "GND")
	)
	(via
		(at 312.990992 -398.542002)
		(size 0.4064)
		(drill 0.2032)
		(layers "F.Cu" "B.Cu")
		(net "GND")
	)
	(via
		(at 305.558952 -345.81846)
		(size 0.49022)
		(drill 0.254)
		(layers "F.Cu" "B.Cu")
		(net "GND")
	)
	(via
		(at 151.053292 -75.70089)
		(size 0.508)
		(drill 0.254)
		(layers "F.Cu" "B.Cu")
		(net "GND")
	)
	(via
		(at 108.757466 -180.111146)
		(size 0.49022)
		(drill 0.254)
		(layers "F.Cu" "B.Cu")
		(net "GND")
	)
	(via
		(at 448.490086 -395.2367)
		(size 0.508)
		(drill 0.254)
		(layers "F.Cu" "B.Cu")
		(net "GND")
	)
	(via
		(at 328.102214 -421.586152)
		(size 0.4572)
		(drill 0.254)
		(layers "F.Cu" "B.Cu")
		(net "GND")
	)
	(via
		(at 79.02321 -308.379622)
		(size 0.4064)
		(drill 0.2032)
		(layers "F.Cu" "B.Cu")
		(net "GND")
	)
	(via
		(at 283.618432 -201.160126)
		(size 0.4826)
		(drill 0.254)
		(layers "F.Cu" "B.Cu")
		(net "GND")
	)
	(via
		(at 88.281002 -246.10441)
		(size 0.4064)
		(drill 0.2032)
		(layers "F.Cu" "B.Cu")
		(net "GND")
	)
	(via
		(at 446.644268 -282.33497)
		(size 0.4826)
		(drill 0.254)
		(layers "F.Cu" "B.Cu")
		(net "GND")
	)
	(via
		(at 366.594898 -291.095938)
		(size 0.4064)
		(drill 0.2032)
		(layers "F.Cu" "B.Cu")
		(net "GND")
	)
	(via
		(at 373.344694 -232.334054)
		(size 0.4064)
		(drill 0.2032)
		(layers "F.Cu" "B.Cu")
		(net "GND")
	)
	(via
		(at 108.636816 -388.468108)
		(size 0.508)
		(drill 0.254)
		(layers "F.Cu" "B.Cu")
		(net "GND")
	)
	(via
		(at 233.651044 -43.688)
		(size 0.508)
		(drill 0.254)
		(layers "F.Cu" "B.Cu")
		(net "GND")
	)
	(via
		(at 397.729964 -19.13636)
		(size 0.508)
		(drill 0.254)
		(layers "F.Cu" "B.Cu")
		(net "GND")
	)
	(via
		(at 85.575902 -369.03533)
		(size 0.508)
		(drill 0.254)
		(layers "F.Cu" "B.Cu")
		(net "GND")
	)
	(via
		(at 102.211124 -264.366248)
		(size 0.4064)
		(drill 0.2032)
		(layers "F.Cu" "B.Cu")
		(net "GND")
	)
	(via
		(at 143.693642 -384.66268)
		(size 0.508)
		(drill 0.254)
		(layers "F.Cu" "B.Cu")
		(net "GND")
	)
	(via
		(at 391.098024 -18.247106)
		(size 0.508)
		(drill 0.254)
		(layers "F.Cu" "B.Cu")
		(net "GND")
	)
	(via
		(at 77.956156 -407.638504)
		(size 0.4572)
		(drill 0.254)
		(layers "F.Cu" "B.Cu")
		(net "GND")
	)
	(via
		(at 123.316492 -391.830814)
		(size 0.4064)
		(drill 0.2032)
		(layers "F.Cu" "B.Cu")
		(net "GND")
	)
	(via
		(at 336.913982 -308.440836)
		(size 0.508)
		(drill 0.254)
		(layers "F.Cu" "B.Cu")
		(net "GND")
	)
	(via
		(at 385.739894 -419.046152)
		(size 0.4572)
		(drill 0.254)
		(layers "F.Cu" "B.Cu")
		(net "GND")
	)
	(via
		(at 88.591644 -410.030168)
		(size 0.4064)
		(drill 0.2032)
		(layers "F.Cu" "B.Cu")
		(net "GND")
	)
	(via
		(at 128.694688 -236.384338)
		(size 0.4064)
		(drill 0.2032)
		(layers "F.Cu" "B.Cu")
		(net "GND")
	)
	(via
		(at 73.937114 -331.09535)
		(size 0.508)
		(drill 0.254)
		(layers "F.Cu" "B.Cu")
		(net "GND")
	)
	(via
		(at 40.23995 -283.185362)
		(size 0.4826)
		(drill 0.254)
		(layers "F.Cu" "B.Cu")
		(net "GND")
	)
	(via
		(at 82.374486 -355.396546)
		(size 0.508)
		(drill 0.254)
		(layers "F.Cu" "B.Cu")
		(net "GND")
	)
	(via
		(at 414.9979 -378.07773)
		(size 0.508)
		(drill 0.254)
		(layers "F.Cu" "B.Cu")
		(net "GND")
	)
	(via
		(at 356.77221 -258.795012)
		(size 0.4826)
		(drill 0.254)
		(layers "F.Cu" "B.Cu")
		(net "GND")
	)
	(via
		(at 78.711044 -287.046162)
		(size 0.4064)
		(drill 0.2032)
		(layers "F.Cu" "B.Cu")
		(net "GND")
	)
	(via
		(at 20.4216 -406.96515)
		(size 0.508)
		(drill 0.254)
		(layers "F.Cu" "B.Cu")
		(net "GND")
	)
	(via
		(at 372.234714 -287.856168)
		(size 0.4064)
		(drill 0.2032)
		(layers "F.Cu" "B.Cu")
		(net "GND")
	)
	(via
		(at 431.55616 -272.984976)
		(size 0.4826)
		(drill 0.254)
		(layers "F.Cu" "B.Cu")
		(net "GND")
	)
	(via
		(at 90.16111 -229.90429)
		(size 0.4064)
		(drill 0.2032)
		(layers "F.Cu" "B.Cu")
		(net "GND")
	)
	(via
		(at 390.094724 -281.37612)
		(size 0.4064)
		(drill 0.2032)
		(layers "F.Cu" "B.Cu")
		(net "GND")
	)
	(via
		(at 27.107134 -347.287088)
		(size 0.49022)
		(drill 0.254)
		(layers "F.Cu" "B.Cu")
		(net "GND")
	)
	(via
		(at 155.691586 -407.00452)
		(size 0.4064)
		(drill 0.2032)
		(layers "F.Cu" "B.Cu")
		(net "GND")
	)
	(via
		(at 346.195904 -379.22073)
		(size 0.508)
		(drill 0.254)
		(layers "F.Cu" "B.Cu")
		(net "GND")
	)
	(via
		(at 422.223692 -167.391334)
		(size 0.49022)
		(drill 0.254)
		(layers "F.Cu" "B.Cu")
		(net "GND")
	)
	(via
		(at 110.200948 -276.516338)
		(size 0.4064)
		(drill 0.2032)
		(layers "F.Cu" "B.Cu")
		(net "GND")
	)
	(via
		(at 375.29135 -417.778184)
		(size 0.4572)
		(drill 0.254)
		(layers "F.Cu" "B.Cu")
		(net "GND")
	)
	(via
		(at 80.120998 -265.176254)
		(size 0.4064)
		(drill 0.2032)
		(layers "F.Cu" "B.Cu")
		(net "GND")
	)
	(via
		(at 287.062418 -202.01001)
		(size 0.4826)
		(drill 0.254)
		(layers "F.Cu" "B.Cu")
		(net "GND")
	)
	(via
		(at 190.886334 -421.426132)
		(size 0.508)
		(drill 0.254)
		(layers "F.Cu" "B.Cu")
		(net "GND")
	)
	(via
		(at 437.425846 -435.67731)
		(size 0.508)
		(drill 0.254)
		(layers "F.Cu" "B.Cu")
		(net "GND")
	)
	(via
		(at 342.801194 -234.764072)
		(size 0.4064)
		(drill 0.2032)
		(layers "F.Cu" "B.Cu")
		(net "GND")
	)
	(via
		(at 347.50121 -233.14406)
		(size 0.4064)
		(drill 0.2032)
		(layers "F.Cu" "B.Cu")
		(net "GND")
	)
	(via
		(at 35.411664 -295.9354)
		(size 0.4826)
		(drill 0.254)
		(layers "F.Cu" "B.Cu")
		(net "GND")
	)
	(via
		(at 164.244274 -391.830814)
		(size 0.4064)
		(drill 0.2032)
		(layers "F.Cu" "B.Cu")
		(net "GND")
	)
	(via
		(at 134.164832 -265.98626)
		(size 0.4064)
		(drill 0.2032)
		(layers "F.Cu" "B.Cu")
		(net "GND")
	)
	(via
		(at 338.101178 -229.904036)
		(size 0.4064)
		(drill 0.2032)
		(layers "F.Cu" "B.Cu")
		(net "GND")
	)
	(via
		(at 89.690956 -224.234502)
		(size 0.4064)
		(drill 0.2032)
		(layers "F.Cu" "B.Cu")
		(net "GND")
	)
	(via
		(at 76.424536 -411.936184)
		(size 0.4572)
		(drill 0.254)
		(layers "F.Cu" "B.Cu")
		(net "GND")
	)
	(via
		(at 331.051154 -250.154186)
		(size 0.4064)
		(drill 0.2032)
		(layers "F.Cu" "B.Cu")
		(net "GND")
	)
	(via
		(at 57.4167 -393.927838)
		(size 0.4572)
		(drill 0.254)
		(layers "F.Cu" "B.Cu")
		(net "GND")
	)
	(via
		(at 101.27107 -280.566368)
		(size 0.4064)
		(drill 0.2032)
		(layers "F.Cu" "B.Cu")
		(net "GND")
	)
	(via
		(at 140.444728 -235.574332)
		(size 0.4064)
		(drill 0.2032)
		(layers "F.Cu" "B.Cu")
		(net "GND")
	)
	(via
		(at 238.993934 -317.971678)
		(size 0.508)
		(drill 0.254)
		(layers "F.Cu" "B.Cu")
		(net "GND")
	)
	(via
		(at 77.112876 -274.630388)
		(size 0.4064)
		(drill 0.2032)
		(layers "F.Cu" "B.Cu")
		(net "GND")
	)
	(via
		(at 115.834668 -282.996386)
		(size 0.4064)
		(drill 0.2032)
		(layers "F.Cu" "B.Cu")
		(net "GND")
	)
	(via
		(at 48.591216 -390.160002)
		(size 0.4064)
		(drill 0.2032)
		(layers "F.Cu" "B.Cu")
		(net "GND")
	)
	(via
		(at 266.93241 -240.685066)
		(size 0.4826)
		(drill 0.254)
		(layers "F.Cu" "B.Cu")
		(net "GND")
	)
	(via
		(at 280.635964 -244.08511)
		(size 0.4826)
		(drill 0.254)
		(layers "F.Cu" "B.Cu")
		(net "GND")
	)
	(via
		(at 93.280992 -289.47618)
		(size 0.4064)
		(drill 0.2032)
		(layers "F.Cu" "B.Cu")
		(net "GND")
	)
	(via
		(at 40.52443 -5.597398)
		(size 0.508)
		(drill 0.254)
		(layers "F.Cu" "B.Cu")
		(net "GND")
	)
	(via
		(at 139.222226 -388.77113)
		(size 0.508)
		(drill 0.254)
		(layers "F.Cu" "B.Cu")
		(net "GND")
	)
	(via
		(at 352.9711 -277.32609)
		(size 0.4064)
		(drill 0.2032)
		(layers "F.Cu" "B.Cu")
		(net "GND")
	)
	(via
		(at 412.367984 -208.385156)
		(size 0.4826)
		(drill 0.254)
		(layers "F.Cu" "B.Cu")
		(net "GND")
	)
	(via
		(at 160.644332 -391.830814)
		(size 0.4064)
		(drill 0.2032)
		(layers "F.Cu" "B.Cu")
		(net "GND")
	)
	(via
		(at 381.634746 -286.236156)
		(size 0.4064)
		(drill 0.2032)
		(layers "F.Cu" "B.Cu")
		(net "GND")
	)
	(via
		(at 104.090978 -291.906198)
		(size 0.4064)
		(drill 0.2032)
		(layers "F.Cu" "B.Cu")
		(net "GND")
	)
	(via
		(at 290.895786 -302.73498)
		(size 0.4826)
		(drill 0.254)
		(layers "F.Cu" "B.Cu")
		(net "GND")
	)
	(via
		(at 178.289458 -46.800008)
		(size 0.508)
		(drill 0.254)
		(layers "F.Cu" "B.Cu")
		(net "GND")
	)
	(via
		(at 326.060308 -333.838042)
		(size 0.49022)
		(drill 0.254)
		(layers "F.Cu" "B.Cu")
		(net "GND")
	)
	(via
		(at 442.5442 -318.885062)
		(size 0.4826)
		(drill 0.254)
		(layers "F.Cu" "B.Cu")
		(net "GND")
	)
	(via
		(at 130.012694 -411.936184)
		(size 0.4572)
		(drill 0.254)
		(layers "F.Cu" "B.Cu")
		(net "GND")
	)
	(via
		(at 388.384796 -238.814102)
		(size 0.4064)
		(drill 0.2032)
		(layers "F.Cu" "B.Cu")
		(net "GND")
	)
	(via
		(at 31.945072 -398.460976)
		(size 0.508)
		(drill 0.254)
		(layers "F.Cu" "B.Cu")
		(net "GND")
	)
	(via
		(at 133.053074 -26.144474)
		(size 0.508)
		(drill 0.254)
		(layers "F.Cu" "B.Cu")
		(net "GND")
	)
	(via
		(at 167.143684 -274.685252)
		(size 0.4826)
		(drill 0.254)
		(layers "F.Cu" "B.Cu")
		(net "GND")
	)
	(via
		(at 142.154656 -292.716204)
		(size 0.4064)
		(drill 0.2032)
		(layers "F.Cu" "B.Cu")
		(net "GND")
	)
	(via
		(at 443.851792 -30.838902)
		(size 0.508)
		(drill 0.254)
		(layers "F.Cu" "B.Cu")
		(net "GND")
	)
	(via
		(at 340.082378 -416.020504)
		(size 0.4572)
		(drill 0.254)
		(layers "F.Cu" "B.Cu")
		(net "GND")
	)
	(via
		(at 130.40487 -267.606272)
		(size 0.4064)
		(drill 0.2032)
		(layers "F.Cu" "B.Cu")
		(net "GND")
	)
	(via
		(at 120.70461 -240.434368)
		(size 0.4064)
		(drill 0.2032)
		(layers "F.Cu" "B.Cu")
		(net "GND")
	)
	(via
		(at 176.072038 -267.03528)
		(size 0.4826)
		(drill 0.254)
		(layers "F.Cu" "B.Cu")
		(net "GND")
	)
	(via
		(at 333.230982 -282.186126)
		(size 0.4064)
		(drill 0.2032)
		(layers "F.Cu" "B.Cu")
		(net "GND")
	)
	(via
		(at 391.082022 -135.943848)
		(size 0.508)
		(drill 0.254)
		(layers "F.Cu" "B.Cu")
		(net "GND")
	)
	(via
		(at 438.555384 -16.328136)
		(size 0.508)
		(drill 0.254)
		(layers "F.Cu" "B.Cu")
		(net "GND")
	)
	(via
		(at 343.279984 -383.00533)
		(size 0.508)
		(drill 0.254)
		(layers "F.Cu" "B.Cu")
		(net "GND")
	)
	(via
		(at 180.633624 -295.510458)
		(size 0.4826)
		(drill 0.254)
		(layers "F.Cu" "B.Cu")
		(net "GND")
	)
	(via
		(at 134.726172 -37.889434)
		(size 0.508)
		(drill 0.254)
		(layers "F.Cu" "B.Cu")
		(net "GND")
	)
	(via
		(at 379.924818 -246.914162)
		(size 0.4064)
		(drill 0.2032)
		(layers "F.Cu" "B.Cu")
		(net "GND")
	)
	(via
		(at 329.6412 -228.284278)
		(size 0.4064)
		(drill 0.2032)
		(layers "F.Cu" "B.Cu")
		(net "GND")
	)
	(via
		(at 304.769266 -418.412168)
		(size 0.4064)
		(drill 0.2032)
		(layers "F.Cu" "B.Cu")
		(net "GND")
	)
	(via
		(at 295.724072 -206.685134)
		(size 0.4826)
		(drill 0.254)
		(layers "F.Cu" "B.Cu")
		(net "GND")
	)
	(via
		(at 73.275444 -410.030168)
		(size 0.4064)
		(drill 0.2032)
		(layers "F.Cu" "B.Cu")
		(net "GND")
	)
	(via
		(at 326.658986 -420.952168)
		(size 0.4064)
		(drill 0.2032)
		(layers "F.Cu" "B.Cu")
		(net "GND")
	)
	(via
		(at 343.04732 -362.01096)
		(size 0.508)
		(drill 0.254)
		(layers "F.Cu" "B.Cu")
		(net "GND")
	)
	(via
		(at 288.180018 -264.48512)
		(size 0.4826)
		(drill 0.254)
		(layers "F.Cu" "B.Cu")
		(net "GND")
	)
	(via
		(at 265.54811 -301.885096)
		(size 0.4826)
		(drill 0.254)
		(layers "F.Cu" "B.Cu")
		(net "GND")
	)
	(via
		(at 94.30639 -386.449062)
		(size 0.4064)
		(drill 0.2032)
		(layers "F.Cu" "B.Cu")
		(net "GND")
	)
	(via
		(at 105.671112 -232.334308)
		(size 0.4064)
		(drill 0.2032)
		(layers "F.Cu" "B.Cu")
		(net "GND")
	)
	(via
		(at 381.334772 -239.624108)
		(size 0.4064)
		(drill 0.2032)
		(layers "F.Cu" "B.Cu")
		(net "GND")
	)
	(via
		(at 192.712086 -111.063024)
		(size 0.4572)
		(drill 0.254)
		(layers "F.Cu" "B.Cu")
		(net "GND")
	)
	(via
		(at 409.349702 -426.54728)
		(size 0.4572)
		(drill 0.2032)
		(layers "F.Cu" "B.Cu")
		(net "GND")
	)
	(via
		(at 69.249798 -437.34736)
		(size 0.4572)
		(drill 0.2032)
		(layers "F.Cu" "B.Cu")
		(net "GND")
	)
	(via
		(at 58.3184 -388.328662)
		(size 0.4064)
		(drill 0.2032)
		(layers "F.Cu" "B.Cu")
		(net "GND")
	)
	(via
		(at 369.14963 -258.830064)
		(size 0.4826)
		(drill 0.254)
		(layers "F.Cu" "B.Cu")
		(net "GND")
	)
	(via
		(at 95.1611 -271.656302)
		(size 0.4064)
		(drill 0.2032)
		(layers "F.Cu" "B.Cu")
		(net "GND")
	)
	(via
		(at 383.514854 -273.27606)
		(size 0.4064)
		(drill 0.2032)
		(layers "F.Cu" "B.Cu")
		(net "GND")
	)
	(via
		(at 419.993318 -167.012112)
		(size 0.508)
		(drill 0.254)
		(layers "F.Cu" "B.Cu")
		(net "GND")
	)
	(via
		(at 288.180018 -266.185142)
		(size 0.4826)
		(drill 0.254)
		(layers "F.Cu" "B.Cu")
		(net "GND")
	)
	(via
		(at 199.8218 -219.860368)
		(size 0.4826)
		(drill 0.254)
		(layers "F.Cu" "B.Cu")
		(net "GND")
	)
	(via
		(at 49.159414 -374.62333)
		(size 0.508)
		(drill 0.254)
		(layers "F.Cu" "B.Cu")
		(net "GND")
	)
	(via
		(at 417.903914 -413.480504)
		(size 0.4572)
		(drill 0.254)
		(layers "F.Cu" "B.Cu")
		(net "GND")
	)
	(via
		(at 283.464 -424.441366)
		(size 0.508)
		(drill 0.254)
		(layers "F.Cu" "B.Cu")
		(net "GND")
	)
	(via
		(at 56.054498 -132.703062)
		(size 0.508)
		(drill 0.254)
		(layers "F.Cu" "B.Cu")
		(net "GND")
	)
	(via
		(at 100.031042 -246.914416)
		(size 0.4064)
		(drill 0.2032)
		(layers "F.Cu" "B.Cu")
		(net "GND")
	)
	(via
		(at 454.188068 -272.984976)
		(size 0.4826)
		(drill 0.254)
		(layers "F.Cu" "B.Cu")
		(net "GND")
	)
	(via
		(at 396.375382 -418.412168)
		(size 0.4064)
		(drill 0.2032)
		(layers "F.Cu" "B.Cu")
		(net "GND")
	)
	(via
		(at 110.371128 -248.534428)
		(size 0.4064)
		(drill 0.2032)
		(layers "F.Cu" "B.Cu")
		(net "GND")
	)
	(via
		(at 236.987334 -237.230666)
		(size 0.508)
		(drill 0.254)
		(layers "F.Cu" "B.Cu")
		(net "GND")
	)
	(via
		(at 329.941174 -287.856168)
		(size 0.4064)
		(drill 0.2032)
		(layers "F.Cu" "B.Cu")
		(net "GND")
	)
	(via
		(at 131.565142 -53.847492)
		(size 0.508)
		(drill 0.254)
		(layers "F.Cu" "B.Cu")
		(net "GND")
	)
	(via
		(at 370.524786 -240.434114)
		(size 0.4064)
		(drill 0.2032)
		(layers "F.Cu" "B.Cu")
		(net "GND")
	)
	(via
		(at 171.97197 -244.085364)
		(size 0.4826)
		(drill 0.254)
		(layers "F.Cu" "B.Cu")
		(net "GND")
	)
	(via
		(at 329.941174 -282.996132)
		(size 0.4064)
		(drill 0.2032)
		(layers "F.Cu" "B.Cu")
		(net "GND")
	)
	(via
		(at 183.616092 -271.285208)
		(size 0.4826)
		(drill 0.254)
		(layers "F.Cu" "B.Cu")
		(net "GND")
	)
	(via
		(at 55.068216 -9.424924)
		(size 0.508)
		(drill 0.254)
		(layers "F.Cu" "B.Cu")
		(net "GND")
	)
	(via
		(at 103.92791 -181.416198)
		(size 0.508)
		(drill 0.254)
		(layers "F.Cu" "B.Cu")
		(net "GND")
	)
	(via
		(at 353.990656 -170.675046)
		(size 0.49022)
		(drill 0.254)
		(layers "F.Cu" "B.Cu")
		(net "GND")
	)
	(via
		(at 29.05887 -386.80009)
		(size 0.508)
		(drill 0.254)
		(layers "F.Cu" "B.Cu")
		(net "GND")
	)
	(via
		(at 122.002042 -73.919842)
		(size 0.508)
		(drill 0.254)
		(layers "F.Cu" "B.Cu")
		(net "GND")
	)
	(via
		(at 127.678434 -386.449062)
		(size 0.4064)
		(drill 0.2032)
		(layers "F.Cu" "B.Cu")
		(net "GND")
	)
	(via
		(at 331.367384 -380.54153)
		(size 0.508)
		(drill 0.254)
		(layers "F.Cu" "B.Cu")
		(net "GND")
	)
	(via
		(at 428.573692 -202.01001)
		(size 0.4826)
		(drill 0.254)
		(layers "F.Cu" "B.Cu")
		(net "GND")
	)
	(via
		(at 338.875624 -74.184764)
		(size 0.508)
		(drill 0.254)
		(layers "F.Cu" "B.Cu")
		(net "GND")
	)
	(via
		(at 155.406344 -386.449062)
		(size 0.4064)
		(drill 0.2032)
		(layers "F.Cu" "B.Cu")
		(net "GND")
	)
	(via
		(at 142.154656 -291.096192)
		(size 0.4064)
		(drill 0.2032)
		(layers "F.Cu" "B.Cu")
		(net "GND")
	)
	(via
		(at 107.85094 -269.226284)
		(size 0.4064)
		(drill 0.2032)
		(layers "F.Cu" "B.Cu")
		(net "GND")
	)
	(via
		(at 428.840392 -284.88513)
		(size 0.4826)
		(drill 0.254)
		(layers "F.Cu" "B.Cu")
		(net "GND")
	)
	(via
		(at 89.690956 -243.674392)
		(size 0.4064)
		(drill 0.2032)
		(layers "F.Cu" "B.Cu")
		(net "GND")
	)
	(via
		(at 99.33305 -182.127144)
		(size 0.49022)
		(drill 0.254)
		(layers "F.Cu" "B.Cu")
		(net "GND")
	)
	(via
		(at 73.24979 -430.147476)
		(size 0.4572)
		(drill 0.2032)
		(layers "F.Cu" "B.Cu")
		(net "GND")
	)
	(via
		(at 120.461786 -412.570168)
		(size 0.4064)
		(drill 0.2032)
		(layers "F.Cu" "B.Cu")
		(net "GND")
	)
	(via
		(at 55.328058 -208.38541)
		(size 0.4826)
		(drill 0.254)
		(layers "F.Cu" "B.Cu")
		(net "GND")
	)
	(via
		(at 443.6999 -193.10731)
		(size 0.4826)
		(drill 0.254)
		(layers "F.Cu" "B.Cu")
		(net "GND")
	)
	(via
		(at 269.648178 -308.685184)
		(size 0.4826)
		(drill 0.254)
		(layers "F.Cu" "B.Cu")
		(net "GND")
	)
	(via
		(at 443.779656 -395.306042)
		(size 0.49022)
		(drill 0.254)
		(layers "F.Cu" "B.Cu")
		(net "GND")
	)
	(via
		(at 309.722774 -413.480504)
		(size 0.4572)
		(drill 0.254)
		(layers "F.Cu" "B.Cu")
		(net "GND")
	)
	(via
		(at 82.001106 -281.376374)
		(size 0.4064)
		(drill 0.2032)
		(layers "F.Cu" "B.Cu")
		(net "GND")
	)
	(via
		(at 22.535388 -369.84305)
		(size 0.508)
		(drill 0.254)
		(layers "F.Cu" "B.Cu")
		(net "GND")
	)
	(via
		(at 137.154666 -238.00435)
		(size 0.4064)
		(drill 0.2032)
		(layers "F.Cu" "B.Cu")
		(net "GND")
	)
	(via
		(at 373.174768 -265.176)
		(size 0.4064)
		(drill 0.2032)
		(layers "F.Cu" "B.Cu")
		(net "GND")
	)
	(via
		(at 83.994244 -412.570168)
		(size 0.4064)
		(drill 0.2032)
		(layers "F.Cu" "B.Cu")
		(net "GND")
	)
	(via
		(at 325.052944 -271.39011)
		(size 0.4064)
		(drill 0.2032)
		(layers "F.Cu" "B.Cu")
		(net "GND")
	)
	(via
		(at 339.506052 -394.831062)
		(size 0.4064)
		(drill 0.2032)
		(layers "F.Cu" "B.Cu")
		(net "GND")
	)
	(via
		(at 84.706206 -386.449062)
		(size 0.4064)
		(drill 0.2032)
		(layers "F.Cu" "B.Cu")
		(net "GND")
	)
	(via
		(at 363.944916 -230.714042)
		(size 0.4064)
		(drill 0.2032)
		(layers "F.Cu" "B.Cu")
		(net "GND")
	)
	(via
		(at 125.927866 -167.131746)
		(size 0.49022)
		(drill 0.254)
		(layers "F.Cu" "B.Cu")
		(net "GND")
	)
	(via
		(at 342.749124 -333.085186)
		(size 0.49022)
		(drill 0.254)
		(layers "F.Cu" "B.Cu")
		(net "GND")
	)
	(via
		(at 435.000146 -245.785132)
		(size 0.4826)
		(drill 0.254)
		(layers "F.Cu" "B.Cu")
		(net "GND")
	)
	(via
		(at 375.662952 -378.07773)
		(size 0.508)
		(drill 0.254)
		(layers "F.Cu" "B.Cu")
		(net "GND")
	)
	(via
		(at 116.004848 -232.334308)
		(size 0.4064)
		(drill 0.2032)
		(layers "F.Cu" "B.Cu")
		(net "GND")
	)
	(via
		(at 438.277 -97.450148)
		(size 0.508)
		(drill 0.254)
		(layers "F.Cu" "B.Cu")
		(net "GND")
	)
	(via
		(at 321.51828 -396.710662)
		(size 0.4064)
		(drill 0.2032)
		(layers "F.Cu" "B.Cu")
		(net "GND")
	)
	(via
		(at 150.746206 -388.328662)
		(size 0.4064)
		(drill 0.2032)
		(layers "F.Cu" "B.Cu")
		(net "GND")
	)
	(via
		(at 89.298018 -333.81315)
		(size 0.49022)
		(drill 0.254)
		(layers "F.Cu" "B.Cu")
		(net "GND")
	)
	(via
		(at 136.34974 -438.499758)
		(size 0.4572)
		(drill 0.2032)
		(layers "F.Cu" "B.Cu")
		(net "GND")
	)
	(via
		(at 348.895162 -257.930142)
		(size 0.4826)
		(drill 0.254)
		(layers "F.Cu" "B.Cu")
		(net "GND")
	)
	(via
		(at 407.094182 -420.952168)
		(size 0.4064)
		(drill 0.2032)
		(layers "F.Cu" "B.Cu")
		(net "GND")
	)
	(via
		(at 101.91115 -235.574332)
		(size 0.4064)
		(drill 0.2032)
		(layers "F.Cu" "B.Cu")
		(net "GND")
	)
	(via
		(at 59.249818 -437.49976)
		(size 0.4572)
		(drill 0.2032)
		(layers "F.Cu" "B.Cu")
		(net "GND")
	)
	(via
		(at 431.55616 -306.985162)
		(size 0.4826)
		(drill 0.254)
		(layers "F.Cu" "B.Cu")
		(net "GND")
	)
	(via
		(at 46.468538 -382.908048)
		(size 0.4064)
		(drill 0.2032)
		(layers "F.Cu" "B.Cu")
		(net "GND")
	)
	(via
		(at 377.852432 -381.68453)
		(size 0.508)
		(drill 0.254)
		(layers "F.Cu" "B.Cu")
		(net "GND")
	)
	(via
		(at 307.368194 -280.634948)
		(size 0.4826)
		(drill 0.254)
		(layers "F.Cu" "B.Cu")
		(net "GND")
	)
	(via
		(at 361.894882 -273.27606)
		(size 0.4064)
		(drill 0.2032)
		(layers "F.Cu" "B.Cu")
		(net "GND")
	)
	(via
		(at 118.148862 -78.771242)
		(size 0.508)
		(drill 0.254)
		(layers "F.Cu" "B.Cu")
		(net "GND")
	)
	(via
		(at 103.791004 -224.234502)
		(size 0.4064)
		(drill 0.2032)
		(layers "F.Cu" "B.Cu")
		(net "GND")
	)
	(via
		(at 467.5378 -390.195054)
		(size 0.508)
		(drill 0.254)
		(layers "F.Cu" "B.Cu")
		(net "GND")
	)
	(via
		(at 44.340018 -232.18521)
		(size 0.4826)
		(drill 0.254)
		(layers "F.Cu" "B.Cu")
		(net "GND")
	)
	(via
		(at 89.193878 -142.85341)
		(size 0.508)
		(drill 0.254)
		(layers "F.Cu" "B.Cu")
		(net "GND")
	)
	(via
		(at 93.183964 -404.46452)
		(size 0.4064)
		(drill 0.2032)
		(layers "F.Cu" "B.Cu")
		(net "GND")
	)
	(via
		(at 430.17186 -305.28514)
		(size 0.4826)
		(drill 0.254)
		(layers "F.Cu" "B.Cu")
		(net "GND")
	)
	(via
		(at 90.16111 -246.10441)
		(size 0.4064)
		(drill 0.2032)
		(layers "F.Cu" "B.Cu")
		(net "GND")
	)
	(via
		(at 121.874788 -166.356284)
		(size 0.49022)
		(drill 0.254)
		(layers "F.Cu" "B.Cu")
		(net "GND")
	)
	(via
		(at 343.740994 -223.424242)
		(size 0.4064)
		(drill 0.2032)
		(layers "F.Cu" "B.Cu")
		(net "GND")
	)
	(via
		(at 294.606472 -304.860198)
		(size 0.4826)
		(drill 0.254)
		(layers "F.Cu" "B.Cu")
		(net "GND")
	)
	(via
		(at 16.598138 -16.979138)
		(size 0.508)
		(drill 0.254)
		(layers "F.Cu" "B.Cu")
		(net "GND")
	)
	(via
		(at 113.954814 -270.03629)
		(size 0.4064)
		(drill 0.2032)
		(layers "F.Cu" "B.Cu")
		(net "GND")
	)
	(via
		(at 97.511108 -291.906198)
		(size 0.4064)
		(drill 0.2032)
		(layers "F.Cu" "B.Cu")
		(net "GND")
	)
	(via
		(at 421.029638 -220.709998)
		(size 0.4826)
		(drill 0.254)
		(layers "F.Cu" "B.Cu")
		(net "GND")
	)
	(via
		(at 384.349498 -428.851314)
		(size 0.4572)
		(drill 0.2032)
		(layers "F.Cu" "B.Cu")
		(net "GND")
	)
	(via
		(at 8.923782 -407.262584)
		(size 0.508)
		(drill 0.254)
		(layers "F.Cu" "B.Cu")
		(net "GND")
	)
	(via
		(at 157.349698 -430.147222)
		(size 0.4572)
		(drill 0.2032)
		(layers "F.Cu" "B.Cu")
		(net "GND")
	)
	(via
		(at 331.165454 -413.480504)
		(size 0.4572)
		(drill 0.254)
		(layers "F.Cu" "B.Cu")
		(net "GND")
	)
	(via
		(at 446.644268 -235.585)
		(size 0.4826)
		(drill 0.254)
		(layers "F.Cu" "B.Cu")
		(net "GND")
	)
	(via
		(at 414.758124 -9.424924)
		(size 0.508)
		(drill 0.254)
		(layers "F.Cu" "B.Cu")
		(net "GND")
	)
	(via
		(at 13.656818 -410.31287)
		(size 0.508)
		(drill 0.254)
		(layers "F.Cu" "B.Cu")
		(net "GND")
	)
	(via
		(at 413.485584 -286.16021)
		(size 0.4826)
		(drill 0.254)
		(layers "F.Cu" "B.Cu")
		(net "GND")
	)
	(via
		(at 362.271056 -178.950366)
		(size 0.49022)
		(drill 0.254)
		(layers "F.Cu" "B.Cu")
		(net "GND")
	)
	(via
		(at 142.154656 -265.176254)
		(size 0.4064)
		(drill 0.2032)
		(layers "F.Cu" "B.Cu")
		(net "GND")
	)
	(via
		(at 327.761092 -252.584204)
		(size 0.4064)
		(drill 0.2032)
		(layers "F.Cu" "B.Cu")
		(net "GND")
	)
	(via
		(at 352.027998 -262.748014)
		(size 0.4064)
		(drill 0.2032)
		(layers "F.Cu" "B.Cu")
		(net "GND")
	)
	(via
		(at 183.132222 -115.842796)
		(size 0.4572)
		(drill 0.254)
		(layers "F.Cu" "B.Cu")
		(net "GND")
	)
	(via
		(at 219.6338 -212.3694)
		(size 0.508)
		(drill 0.254)
		(layers "F.Cu" "B.Cu")
		(net "GND")
	)
	(via
		(at 66.583814 -386.449062)
		(size 0.4064)
		(drill 0.2032)
		(layers "F.Cu" "B.Cu")
		(net "GND")
	)
	(via
		(at 416.468052 -308.685184)
		(size 0.4826)
		(drill 0.254)
		(layers "F.Cu" "B.Cu")
		(net "GND")
	)
	(via
		(at 155.777438 -403.830536)
		(size 0.4572)
		(drill 0.254)
		(layers "F.Cu" "B.Cu")
		(net "GND")
	)
	(via
		(at 87.544402 -382.85293)
		(size 0.4064)
		(drill 0.2032)
		(layers "F.Cu" "B.Cu")
		(net "GND")
	)
	(via
		(at 17.608042 -279.785318)
		(size 0.4826)
		(drill 0.254)
		(layers "F.Cu" "B.Cu")
		(net "GND")
	)
	(via
		(at 314.475876 -71.265542)
		(size 0.508)
		(drill 0.254)
		(layers "F.Cu" "B.Cu")
		(net "GND")
	)
	(via
		(at 358.311196 -224.234248)
		(size 0.4064)
		(drill 0.2032)
		(layers "F.Cu" "B.Cu")
		(net "GND")
	)
	(via
		(at 437.425846 -439.52541)
		(size 0.508)
		(drill 0.254)
		(layers "F.Cu" "B.Cu")
		(net "GND")
	)
	(via
		(at 145.328894 -405.098504)
		(size 0.4572)
		(drill 0.254)
		(layers "F.Cu" "B.Cu")
		(net "GND")
	)
	(via
		(at 120.305322 -78.405482)
		(size 0.508)
		(drill 0.254)
		(layers "F.Cu" "B.Cu")
		(net "GND")
	)
	(via
		(at 177.160682 -330.201524)
		(size 0.508)
		(drill 0.254)
		(layers "F.Cu" "B.Cu")
		(net "GND")
	)
	(via
		(at 189.226952 -12.461748)
		(size 0.508)
		(drill 0.254)
		(layers "F.Cu" "B.Cu")
		(net "GND")
	)
	(via
		(at 124.90196 -351.04578)
		(size 0.6604)
		(drill 0.3302)
		(layers "F.Cu" "B.Cu")
		(net "GND")
	)
	(via
		(at 101.91115 -250.15444)
		(size 0.4064)
		(drill 0.2032)
		(layers "F.Cu" "B.Cu")
		(net "GND")
	)
	(via
		(at 142.467584 -372.15953)
		(size 0.508)
		(drill 0.254)
		(layers "F.Cu" "B.Cu")
		(net "GND")
	)
	(via
		(at 183.616092 -272.98523)
		(size 0.4826)
		(drill 0.254)
		(layers "F.Cu" "B.Cu")
		(net "GND")
	)
	(via
		(at 334.811116 -224.234248)
		(size 0.4064)
		(drill 0.2032)
		(layers "F.Cu" "B.Cu")
		(net "GND")
	)
	(via
		(at 299.82414 -251.735082)
		(size 0.4826)
		(drill 0.254)
		(layers "F.Cu" "B.Cu")
		(net "GND")
	)
	(via
		(at 78.75651 -185.327798)
		(size 0.508)
		(drill 0.254)
		(layers "F.Cu" "B.Cu")
		(net "GND")
	)
	(via
		(at 54.981856 -405.098504)
		(size 0.4572)
		(drill 0.254)
		(layers "F.Cu" "B.Cu")
		(net "GND")
	)
	(via
		(at 345.451176 -277.32609)
		(size 0.4064)
		(drill 0.2032)
		(layers "F.Cu" "B.Cu")
		(net "GND")
	)
	(via
		(at 353.441 -281.37612)
		(size 0.4064)
		(drill 0.2032)
		(layers "F.Cu" "B.Cu")
		(net "GND")
	)
	(via
		(at 41.62425 -306.135278)
		(size 0.4826)
		(drill 0.254)
		(layers "F.Cu" "B.Cu")
		(net "GND")
	)
	(via
		(at 379.763274 -184.683146)
		(size 0.49022)
		(drill 0.254)
		(layers "F.Cu" "B.Cu")
		(net "GND")
	)
	(via
		(at 380.224792 -275.706078)
		(size 0.4064)
		(drill 0.2032)
		(layers "F.Cu" "B.Cu")
		(net "GND")
	)
	(via
		(at 132.284724 -290.286186)
		(size 0.4064)
		(drill 0.2032)
		(layers "F.Cu" "B.Cu")
		(net "GND")
	)
	(via
		(at 154.644344 -391.830814)
		(size 0.4064)
		(drill 0.2032)
		(layers "F.Cu" "B.Cu")
		(net "GND")
	)
	(via
		(at 357.335074 -171.435268)
		(size 0.49022)
		(drill 0.254)
		(layers "F.Cu" "B.Cu")
		(net "GND")
	)
	(via
		(at 355.353874 -171.435268)
		(size 0.49022)
		(drill 0.254)
		(layers "F.Cu" "B.Cu")
		(net "GND")
	)
	(via
		(at 356.901242 -238.004096)
		(size 0.4064)
		(drill 0.2032)
		(layers "F.Cu" "B.Cu")
		(net "GND")
	)
	(via
		(at 101.035866 -183.843168)
		(size 0.49022)
		(drill 0.254)
		(layers "F.Cu" "B.Cu")
		(net "GND")
	)
	(via
		(at 369.414806 -265.176)
		(size 0.4064)
		(drill 0.2032)
		(layers "F.Cu" "B.Cu")
		(net "GND")
	)
	(via
		(at 240.07953 -370.701062)
		(size 0.508)
		(drill 0.254)
		(layers "F.Cu" "B.Cu")
		(net "GND")
	)
	(via
		(at 117.244622 -274.08632)
		(size 0.4064)
		(drill 0.2032)
		(layers "F.Cu" "B.Cu")
		(net "GND")
	)
	(via
		(at 64.191388 -390.160002)
		(size 0.4064)
		(drill 0.2032)
		(layers "F.Cu" "B.Cu")
		(net "GND")
	)
	(via
		(at 41.39565 -193.107564)
		(size 0.4826)
		(drill 0.254)
		(layers "F.Cu" "B.Cu")
		(net "GND")
	)
	(via
		(at 91.571064 -253.394464)
		(size 0.4064)
		(drill 0.2032)
		(layers "F.Cu" "B.Cu")
		(net "GND")
	)
	(via
		(at 102.38105 -231.524302)
		(size 0.4064)
		(drill 0.2032)
		(layers "F.Cu" "B.Cu")
		(net "GND")
	)
	(via
		(at 109.900974 -229.90429)
		(size 0.4064)
		(drill 0.2032)
		(layers "F.Cu" "B.Cu")
		(net "GND")
	)
	(via
		(at 334.811116 -233.954066)
		(size 0.4064)
		(drill 0.2032)
		(layers "F.Cu" "B.Cu")
		(net "GND")
	)
	(via
		(at 128.994662 -265.176254)
		(size 0.4064)
		(drill 0.2032)
		(layers "F.Cu" "B.Cu")
		(net "GND")
	)
	(via
		(at 457.994766 -92.022422)
		(size 0.508)
		(drill 0.254)
		(layers "F.Cu" "B.Cu")
		(net "GND")
	)
	(via
		(at 142.556992 -27.17419)
		(size 0.508)
		(drill 0.254)
		(layers "F.Cu" "B.Cu")
		(net "GND")
	)
	(via
		(at 303.268126 -317.18504)
		(size 0.4826)
		(drill 0.254)
		(layers "F.Cu" "B.Cu")
		(net "GND")
	)
	(via
		(at 256.75971 -324.045072)
		(size 0.508)
		(drill 0.254)
		(layers "F.Cu" "B.Cu")
		(net "GND")
	)
	(via
		(at 288.180018 -273.835114)
		(size 0.4826)
		(drill 0.254)
		(layers "F.Cu" "B.Cu")
		(net "GND")
	)
	(via
		(at 351.518728 -398.542002)
		(size 0.4064)
		(drill 0.2032)
		(layers "F.Cu" "B.Cu")
		(net "GND")
	)
	(via
		(at 340.355174 -413.480504)
		(size 0.4572)
		(drill 0.254)
		(layers "F.Cu" "B.Cu")
		(net "GND")
	)
	(via
		(at 103.805482 -378.836428)
		(size 0.508)
		(drill 0.254)
		(layers "F.Cu" "B.Cu")
		(net "GND")
	)
	(via
		(at 203.265532 -239.410494)
		(size 0.4826)
		(drill 0.254)
		(layers "F.Cu" "B.Cu")
		(net "GND")
	)
	(via
		(at 404.030942 -420.952168)
		(size 0.4064)
		(drill 0.2032)
		(layers "F.Cu" "B.Cu")
		(net "GND")
	)
	(via
		(at 450.317616 -402.59127)
		(size 0.508)
		(drill 0.254)
		(layers "F.Cu" "B.Cu")
		(net "GND")
	)
	(via
		(at 416.555682 -10.16508)
		(size 0.508)
		(drill 0.254)
		(layers "F.Cu" "B.Cu")
		(net "GND")
	)
	(via
		(at 86.249764 -439.651394)
		(size 0.4572)
		(drill 0.2032)
		(layers "F.Cu" "B.Cu")
		(net "GND")
	)
	(via
		(at 182.231792 -209.235294)
		(size 0.4826)
		(drill 0.254)
		(layers "F.Cu" "B.Cu")
		(net "GND")
	)
	(via
		(at 335.11109 -283.806138)
		(size 0.4064)
		(drill 0.2032)
		(layers "F.Cu" "B.Cu")
		(net "GND")
	)
	(via
		(at 365.380778 -259.33019)
		(size 0.4826)
		(drill 0.254)
		(layers "F.Cu" "B.Cu")
		(net "GND")
	)
	(via
		(at 295.724072 -204.985112)
		(size 0.4826)
		(drill 0.254)
		(layers "F.Cu" "B.Cu")
		(net "GND")
	)
	(via
		(at 378.081794 -421.586152)
		(size 0.4572)
		(drill 0.254)
		(layers "F.Cu" "B.Cu")
		(net "GND")
	)
	(via
		(at 442.297566 -378.05487)
		(size 0.508)
		(drill 0.254)
		(layers "F.Cu" "B.Cu")
		(net "GND")
	)
	(via
		(at 133.075934 -411.936184)
		(size 0.4572)
		(drill 0.254)
		(layers "F.Cu" "B.Cu")
		(net "GND")
	)
	(via
		(at 395.222222 -397.15313)
		(size 0.508)
		(drill 0.254)
		(layers "F.Cu" "B.Cu")
		(net "GND")
	)
	(via
		(at 413.523684 -194.88531)
		(size 0.4826)
		(drill 0.254)
		(layers "F.Cu" "B.Cu")
		(net "GND")
	)
	(via
		(at 325.24954 -427.699678)
		(size 0.4572)
		(drill 0.2032)
		(layers "F.Cu" "B.Cu")
		(net "GND")
	)
	(via
		(at 389.668258 -180.755544)
		(size 0.49022)
		(drill 0.254)
		(layers "F.Cu" "B.Cu")
		(net "GND")
	)
	(via
		(at 372.22811 -416.020504)
		(size 0.4572)
		(drill 0.254)
		(layers "F.Cu" "B.Cu")
		(net "GND")
	)
	(via
		(at 452.803768 -209.23504)
		(size 0.4826)
		(drill 0.254)
		(layers "F.Cu" "B.Cu")
		(net "GND")
	)
	(via
		(at 320.444114 -414.752536)
		(size 0.4572)
		(drill 0.254)
		(layers "F.Cu" "B.Cu")
		(net "GND")
	)
	(via
		(at 151.281892 -317.77305)
		(size 0.508)
		(drill 0.254)
		(layers "F.Cu" "B.Cu")
		(net "GND")
	)
	(via
		(at 327.249536 -430.299622)
		(size 0.4572)
		(drill 0.2032)
		(layers "F.Cu" "B.Cu")
		(net "GND")
	)
	(via
		(at 146.948906 -404.46452)
		(size 0.4064)
		(drill 0.2032)
		(layers "F.Cu" "B.Cu")
		(net "GND")
	)
	(via
		(at 100.894642 -368.37493)
		(size 0.508)
		(drill 0.254)
		(layers "F.Cu" "B.Cu")
		(net "GND")
	)
	(via
		(at 104.521 -419.989)
		(size 0.508)
		(drill 0.254)
		(layers "F.Cu" "B.Cu")
		(net "GND")
	)
	(via
		(at 145.773394 -53.897784)
		(size 0.508)
		(drill 0.254)
		(layers "F.Cu" "B.Cu")
		(net "GND")
	)
	(via
		(at 341.691214 -291.905944)
		(size 0.4064)
		(drill 0.2032)
		(layers "F.Cu" "B.Cu")
		(net "GND")
	)
	(via
		(at 397.681704 -144.379442)
		(size 0.49022)
		(drill 0.254)
		(layers "F.Cu" "B.Cu")
		(net "GND")
	)
	(via
		(at 316.7507 -328.097134)
		(size 0.508)
		(drill 0.254)
		(layers "F.Cu" "B.Cu")
		(net "GND")
	)
	(via
		(at 442.5442 -245.785132)
		(size 0.4826)
		(drill 0.254)
		(layers "F.Cu" "B.Cu")
		(net "GND")
	)
	(via
		(at 348.030546 -12.542266)
		(size 0.508)
		(drill 0.254)
		(layers "F.Cu" "B.Cu")
		(net "GND")
	)
	(via
		(at 277.37562 -438.401714)
		(size 0.508)
		(drill 0.254)
		(layers "F.Cu" "B.Cu")
		(net "GND")
	)
	(via
		(at 404.644352 -400.212814)
		(size 0.4064)
		(drill 0.2032)
		(layers "F.Cu" "B.Cu")
		(net "GND")
	)
	(via
		(at 89.690956 -238.814356)
		(size 0.4064)
		(drill 0.2032)
		(layers "F.Cu" "B.Cu")
		(net "GND")
	)
	(via
		(at 147.444206 -393.902438)
		(size 0.4572)
		(drill 0.254)
		(layers "F.Cu" "B.Cu")
		(net "GND")
	)
	(via
		(at 110.200948 -273.276314)
		(size 0.4064)
		(drill 0.2032)
		(layers "F.Cu" "B.Cu")
		(net "GND")
	)
	(via
		(at 18.125186 -386.889244)
		(size 0.49022)
		(drill 0.254)
		(layers "F.Cu" "B.Cu")
		(net "GND")
	)
	(via
		(at 399.480024 -18.503138)
		(size 0.508)
		(drill 0.254)
		(layers "F.Cu" "B.Cu")
		(net "GND")
	)
	(via
		(at 74.61885 -377.00712)
		(size 0.508)
		(drill 0.254)
		(layers "F.Cu" "B.Cu")
		(net "GND")
	)
	(via
		(at 129.596642 -77.50683)
		(size 0.508)
		(drill 0.254)
		(layers "F.Cu" "B.Cu")
		(net "GND")
	)
	(via
		(at 202.147932 -204.985366)
		(size 0.4826)
		(drill 0.254)
		(layers "F.Cu" "B.Cu")
		(net "GND")
	)
	(via
		(at 409.741116 -175.447452)
		(size 0.508)
		(drill 0.254)
		(layers "F.Cu" "B.Cu")
		(net "GND")
	)
	(via
		(at 333.230982 -291.905944)
		(size 0.4064)
		(drill 0.2032)
		(layers "F.Cu" "B.Cu")
		(net "GND")
	)
	(via
		(at 132.45465 -249.344434)
		(size 0.4064)
		(drill 0.2032)
		(layers "F.Cu" "B.Cu")
		(net "GND")
	)
	(via
		(at 171.97197 -223.685354)
		(size 0.4826)
		(drill 0.254)
		(layers "F.Cu" "B.Cu")
		(net "GND")
	)
	(via
		(at 49.168304 -306.135278)
		(size 0.4826)
		(drill 0.254)
		(layers "F.Cu" "B.Cu")
		(net "GND")
	)
	(via
		(at 328.231246 -230.714296)
		(size 0.4064)
		(drill 0.2032)
		(layers "F.Cu" "B.Cu")
		(net "GND")
	)
	(via
		(at 344.211148 -255.014222)
		(size 0.4064)
		(drill 0.2032)
		(layers "F.Cu" "B.Cu")
		(net "GND")
	)
	(via
		(at 132.529834 -163.357052)
		(size 0.508)
		(drill 0.254)
		(layers "F.Cu" "B.Cu")
		(net "GND")
	)
	(via
		(at 275.807932 -218.585034)
		(size 0.4826)
		(drill 0.254)
		(layers "F.Cu" "B.Cu")
		(net "GND")
	)
	(via
		(at 328.53122 -272.466054)
		(size 0.4064)
		(drill 0.2032)
		(layers "F.Cu" "B.Cu")
		(net "GND")
	)
	(via
		(at 349.118682 -398.542002)
		(size 0.4064)
		(drill 0.2032)
		(layers "F.Cu" "B.Cu")
		(net "GND")
	)
	(via
		(at 101.767386 -338.000086)
		(size 0.49022)
		(drill 0.254)
		(layers "F.Cu" "B.Cu")
		(net "GND")
	)
	(via
		(at 332.931008 -253.39421)
		(size 0.4064)
		(drill 0.2032)
		(layers "F.Cu" "B.Cu")
		(net "GND")
	)
	(via
		(at 426.844714 -400.834606)
		(size 0.508)
		(drill 0.254)
		(layers "F.Cu" "B.Cu")
		(net "GND")
	)
	(via
		(at 462.160366 -81.361534)
		(size 0.508)
		(drill 0.254)
		(layers "F.Cu" "B.Cu")
		(net "GND")
	)
	(via
		(at 43.693334 -348.709488)
		(size 0.49022)
		(drill 0.254)
		(layers "F.Cu" "B.Cu")
		(net "GND")
	)
	(via
		(at 101.91115 -233.95432)
		(size 0.4064)
		(drill 0.2032)
		(layers "F.Cu" "B.Cu")
		(net "GND")
	)
	(via
		(at 363.474762 -247.724168)
		(size 0.4064)
		(drill 0.2032)
		(layers "F.Cu" "B.Cu")
		(net "GND")
	)
	(via
		(at 375.278396 -394.831062)
		(size 0.4064)
		(drill 0.2032)
		(layers "F.Cu" "B.Cu")
		(net "GND")
	)
	(via
		(at 113.184686 -251.774452)
		(size 0.4064)
		(drill 0.2032)
		(layers "F.Cu" "B.Cu")
		(net "GND")
	)
	(via
		(at 84.99094 -245.294404)
		(size 0.4064)
		(drill 0.2032)
		(layers "F.Cu" "B.Cu")
		(net "GND")
	)
	(via
		(at 179.516024 -225.385376)
		(size 0.4826)
		(drill 0.254)
		(layers "F.Cu" "B.Cu")
		(net "GND")
	)
	(via
		(at 390.285478 -182.177944)
		(size 0.49022)
		(drill 0.254)
		(layers "F.Cu" "B.Cu")
		(net "GND")
	)
	(via
		(at 382.13538 -299.27931)
		(size 0.508)
		(drill 0.254)
		(layers "F.Cu" "B.Cu")
		(net "GND")
	)
	(via
		(at 92.656152 -303.255172)
		(size 0.508)
		(drill 0.254)
		(layers "F.Cu" "B.Cu")
		(net "GND")
	)
	(via
		(at 342.801194 -223.424242)
		(size 0.4064)
		(drill 0.2032)
		(layers "F.Cu" "B.Cu")
		(net "GND")
	)
	(via
		(at 299.488606 -348.704662)
		(size 0.49022)
		(drill 0.254)
		(layers "F.Cu" "B.Cu")
		(net "GND")
	)
	(via
		(at 117.486938 -409.396184)
		(size 0.4572)
		(drill 0.254)
		(layers "F.Cu" "B.Cu")
		(net "GND")
	)
	(via
		(at 340.921086 -247.724168)
		(size 0.4064)
		(drill 0.2032)
		(layers "F.Cu" "B.Cu")
		(net "GND")
	)
	(via
		(at 452.803768 -211.784946)
		(size 0.4826)
		(drill 0.254)
		(layers "F.Cu" "B.Cu")
		(net "GND")
	)
	(via
		(at 422.9354 -39.817548)
		(size 0.508)
		(drill 0.254)
		(layers "F.Cu" "B.Cu")
		(net "GND")
	)
	(via
		(at 130.516376 -382.85293)
		(size 0.4064)
		(drill 0.2032)
		(layers "F.Cu" "B.Cu")
		(net "GND")
	)
	(via
		(at 355.491034 -224.234248)
		(size 0.4064)
		(drill 0.2032)
		(layers "F.Cu" "B.Cu")
		(net "GND")
	)
	(via
		(at 135.274812 -233.144314)
		(size 0.4064)
		(drill 0.2032)
		(layers "F.Cu" "B.Cu")
		(net "GND")
	)
	(via
		(at 187.060078 -242.385342)
		(size 0.4826)
		(drill 0.254)
		(layers "F.Cu" "B.Cu")
		(net "GND")
	)
	(via
		(at 449.93179 -45.69206)
		(size 0.508)
		(drill 0.254)
		(layers "F.Cu" "B.Cu")
		(net "GND")
	)
	(via
		(at 398.26565 -413.480504)
		(size 0.4572)
		(drill 0.254)
		(layers "F.Cu" "B.Cu")
		(net "GND")
	)
	(via
		(at 304.652426 -219.435172)
		(size 0.4826)
		(drill 0.254)
		(layers "F.Cu" "B.Cu")
		(net "GND")
	)
	(via
		(at 415.201862 -420.952168)
		(size 0.4064)
		(drill 0.2032)
		(layers "F.Cu" "B.Cu")
		(net "GND")
	)
	(via
		(at 40.494458 -428.712122)
		(size 0.508)
		(drill 0.254)
		(layers "F.Cu" "B.Cu")
		(net "GND")
	)
	(via
		(at 56.05399 -16.9799)
		(size 0.508)
		(drill 0.254)
		(layers "F.Cu" "B.Cu")
		(net "GND")
	)
	(via
		(at 330.369672 -33.969706)
		(size 0.508)
		(drill 0.254)
		(layers "F.Cu" "B.Cu")
		(net "GND")
	)
	(via
		(at 198.7042 -196.485256)
		(size 0.4826)
		(drill 0.254)
		(layers "F.Cu" "B.Cu")
		(net "GND")
	)
	(via
		(at 156.138626 -412.570168)
		(size 0.4064)
		(drill 0.2032)
		(layers "F.Cu" "B.Cu")
		(net "GND")
	)
	(via
		(at 84.246466 -184.683146)
		(size 0.49022)
		(drill 0.254)
		(layers "F.Cu" "B.Cu")
		(net "GND")
	)
	(via
		(at 113.348008 -261.323074)
		(size 0.4826)
		(drill 0.254)
		(layers "F.Cu" "B.Cu")
		(net "GND")
	)
	(via
		(at 73.24979 -428.851314)
		(size 0.4572)
		(drill 0.2032)
		(layers "F.Cu" "B.Cu")
		(net "GND")
	)
	(via
		(at 131.36245 -384.617722)
		(size 0.4064)
		(drill 0.2032)
		(layers "F.Cu" "B.Cu")
		(net "GND")
	)
	(via
		(at 447.761868 -210.51012)
		(size 0.4826)
		(drill 0.254)
		(layers "F.Cu" "B.Cu")
		(net "GND")
	)
	(via
		(at 51.884072 -272.98523)
		(size 0.4826)
		(drill 0.254)
		(layers "F.Cu" "B.Cu")
		(net "GND")
	)
	(via
		(at 137.397998 -413.204152)
		(size 0.4572)
		(drill 0.254)
		(layers "F.Cu" "B.Cu")
		(net "GND")
	)
	(via
		(at 114.83086 -32.513778)
		(size 0.508)
		(drill 0.254)
		(layers "F.Cu" "B.Cu")
		(net "GND")
	)
	(via
		(at 108.64342 -390.932924)
		(size 0.508)
		(drill 0.254)
		(layers "F.Cu" "B.Cu")
		(net "GND")
	)
	(via
		(at 194.604132 -244.085364)
		(size 0.4826)
		(drill 0.254)
		(layers "F.Cu" "B.Cu")
		(net "GND")
	)
	(via
		(at 131.98475 -238.814356)
		(size 0.4064)
		(drill 0.2032)
		(layers "F.Cu" "B.Cu")
		(net "GND")
	)
	(via
		(at 98.981514 -331.12456)
		(size 0.508)
		(drill 0.254)
		(layers "F.Cu" "B.Cu")
		(net "GND")
	)
	(via
		(at 348.911164 -222.614236)
		(size 0.4064)
		(drill 0.2032)
		(layers "F.Cu" "B.Cu")
		(net "GND")
	)
	(via
		(at 430.17186 -295.935146)
		(size 0.4826)
		(drill 0.254)
		(layers "F.Cu" "B.Cu")
		(net "GND")
	)
	(via
		(at 168.655238 -432.590194)
		(size 0.508)
		(drill 0.254)
		(layers "F.Cu" "B.Cu")
		(net "GND")
	)
	(via
		(at 178.289458 -52.799996)
		(size 0.508)
		(drill 0.254)
		(layers "F.Cu" "B.Cu")
		(net "GND")
	)
	(via
		(at 392.444732 -293.525956)
		(size 0.4064)
		(drill 0.2032)
		(layers "F.Cu" "B.Cu")
		(net "GND")
	)
	(via
		(at 31.148274 -9.424924)
		(size 0.508)
		(drill 0.254)
		(layers "F.Cu" "B.Cu")
		(net "GND")
	)
	(via
		(at 431.55616 -207.535018)
		(size 0.4826)
		(drill 0.254)
		(layers "F.Cu" "B.Cu")
		(net "GND")
	)
	(via
		(at 112.81791 -175.167798)
		(size 0.508)
		(drill 0.254)
		(layers "F.Cu" "B.Cu")
		(net "GND")
	)
	(via
		(at 331.821028 -273.27606)
		(size 0.4064)
		(drill 0.2032)
		(layers "F.Cu" "B.Cu")
		(net "GND")
	)
	(via
		(at 194.604132 -318.885316)
		(size 0.4826)
		(drill 0.254)
		(layers "F.Cu" "B.Cu")
		(net "GND")
	)
	(via
		(at 38.3286 -363.093)
		(size 0.508)
		(drill 0.254)
		(layers "F.Cu" "B.Cu")
		(net "GND")
	)
	(via
		(at 388.478522 -394.831062)
		(size 0.4064)
		(drill 0.2032)
		(layers "F.Cu" "B.Cu")
		(net "GND")
	)
	(via
		(at 413.917638 -56.347868)
		(size 0.508)
		(drill 0.254)
		(layers "F.Cu" "B.Cu")
		(net "GND")
	)
	(via
		(at 452.858378 -395.306042)
		(size 0.49022)
		(drill 0.254)
		(layers "F.Cu" "B.Cu")
		(net "GND")
	)
	(via
		(at 152.628346 -410.030168)
		(size 0.4064)
		(drill 0.2032)
		(layers "F.Cu" "B.Cu")
		(net "GND")
	)
	(via
		(at 278.950166 -342.811608)
		(size 0.508)
		(drill 0.254)
		(layers "F.Cu" "B.Cu")
		(net "GND")
	)
	(via
		(at 96.27108 -230.71455)
		(size 0.4064)
		(drill 0.2032)
		(layers "F.Cu" "B.Cu")
		(net "GND")
	)
	(via
		(at 44.340018 -265.335258)
		(size 0.4826)
		(drill 0.254)
		(layers "F.Cu" "B.Cu")
		(net "GND")
	)
	(via
		(at 363.774736 -273.27606)
		(size 0.4064)
		(drill 0.2032)
		(layers "F.Cu" "B.Cu")
		(net "GND")
	)
	(via
		(at 125.2347 -266.796266)
		(size 0.4064)
		(drill 0.2032)
		(layers "F.Cu" "B.Cu")
		(net "GND")
	)
	(via
		(at 161.546286 -388.328662)
		(size 0.4064)
		(drill 0.2032)
		(layers "F.Cu" "B.Cu")
		(net "GND")
	)
	(via
		(at 119.662956 -368.37493)
		(size 0.508)
		(drill 0.254)
		(layers "F.Cu" "B.Cu")
		(net "GND")
	)
	(via
		(at 387.444742 -250.154186)
		(size 0.4064)
		(drill 0.2032)
		(layers "F.Cu" "B.Cu")
		(net "GND")
	)
	(via
		(at 88.24976 -431.451258)
		(size 0.4572)
		(drill 0.2032)
		(layers "F.Cu" "B.Cu")
		(net "GND")
	)
	(via
		(at 132.349748 -430.147222)
		(size 0.4572)
		(drill 0.2032)
		(layers "F.Cu" "B.Cu")
		(net "GND")
	)
	(via
		(at 91.323414 -328.147172)
		(size 0.508)
		(drill 0.254)
		(layers "F.Cu" "B.Cu")
		(net "GND")
	)
	(via
		(at 198.631556 -341.188548)
		(size 0.508)
		(drill 0.254)
		(layers "F.Cu" "B.Cu")
		(net "GND")
	)
	(via
		(at 191.111886 -123.04268)
		(size 0.4572)
		(drill 0.254)
		(layers "F.Cu" "B.Cu")
		(net "GND")
	)
	(via
		(at 83.51901 -390.160002)
		(size 0.4064)
		(drill 0.2032)
		(layers "F.Cu" "B.Cu")
		(net "GND")
	)
	(via
		(at 431.989992 -349.200978)
		(size 0.49022)
		(drill 0.254)
		(layers "F.Cu" "B.Cu")
		(net "GND")
	)
	(via
		(at 54.267354 -373.96293)
		(size 0.508)
		(drill 0.254)
		(layers "F.Cu" "B.Cu")
		(net "GND")
	)
	(via
		(at 191.160146 -243.235226)
		(size 0.4826)
		(drill 0.254)
		(layers "F.Cu" "B.Cu")
		(net "GND")
	)
	(via
		(at 90.16111 -254.20447)
		(size 0.4064)
		(drill 0.2032)
		(layers "F.Cu" "B.Cu")
		(net "GND")
	)
	(via
		(at 421.09009 -392.999722)
		(size 0.4064)
		(drill 0.2032)
		(layers "F.Cu" "B.Cu")
		(net "GND")
	)
	(via
		(at 289.564318 -231.335072)
		(size 0.4826)
		(drill 0.254)
		(layers "F.Cu" "B.Cu")
		(net "GND")
	)
	(via
		(at 347.031056 -233.954066)
		(size 0.4064)
		(drill 0.2032)
		(layers "F.Cu" "B.Cu")
		(net "GND")
	)
	(via
		(at 130.87477 -271.656302)
		(size 0.4064)
		(drill 0.2032)
		(layers "F.Cu" "B.Cu")
		(net "GND")
	)
	(via
		(at 291.124386 -192.21831)
		(size 0.4826)
		(drill 0.254)
		(layers "F.Cu" "B.Cu")
		(net "GND")
	)
	(via
		(at 133.694678 -261.93623)
		(size 0.4064)
		(drill 0.2032)
		(layers "F.Cu" "B.Cu")
		(net "GND")
	)
	(via
		(at 81.246218 -388.328662)
		(size 0.4064)
		(drill 0.2032)
		(layers "F.Cu" "B.Cu")
		(net "GND")
	)
	(via
		(at 348.271084 -282.186126)
		(size 0.4064)
		(drill 0.2032)
		(layers "F.Cu" "B.Cu")
		(net "GND")
	)
	(via
		(at 79.821024 -242.864386)
		(size 0.4064)
		(drill 0.2032)
		(layers "F.Cu" "B.Cu")
		(net "GND")
	)
	(via
		(at 297.820842 -396.8369)
		(size 0.508)
		(drill 0.254)
		(layers "F.Cu" "B.Cu")
		(net "GND")
	)
	(via
		(at 132.803138 -410.664152)
		(size 0.4572)
		(drill 0.254)
		(layers "F.Cu" "B.Cu")
		(net "GND")
	)
	(via
		(at 316.673992 -199.581008)
		(size 0.508)
		(drill 0.254)
		(layers "F.Cu" "B.Cu")
		(net "GND")
	)
	(via
		(at 317.380874 -414.752536)
		(size 0.4572)
		(drill 0.254)
		(layers "F.Cu" "B.Cu")
		(net "GND")
	)
	(via
		(at 21.16836 -421.470582)
		(size 0.508)
		(drill 0.254)
		(layers "F.Cu" "B.Cu")
		(net "GND")
	)
	(via
		(at 58.84799 -18.503138)
		(size 0.508)
		(drill 0.254)
		(layers "F.Cu" "B.Cu")
		(net "GND")
	)
	(via
		(at 132.478526 -386.449062)
		(size 0.4064)
		(drill 0.2032)
		(layers "F.Cu" "B.Cu")
		(net "GND")
	)
	(via
		(at 289.589718 -424.540934)
		(size 0.508)
		(drill 0.254)
		(layers "F.Cu" "B.Cu")
		(net "GND")
	)
	(via
		(at 126.618492 -388.328662)
		(size 0.4064)
		(drill 0.2032)
		(layers "F.Cu" "B.Cu")
		(net "GND")
	)
	(via
		(at 381.145034 -420.318184)
		(size 0.4572)
		(drill 0.254)
		(layers "F.Cu" "B.Cu")
		(net "GND")
	)
	(via
		(at 94.861126 -255.824482)
		(size 0.4064)
		(drill 0.2032)
		(layers "F.Cu" "B.Cu")
		(net "GND")
	)
	(via
		(at 446.644268 -250.03506)
		(size 0.4826)
		(drill 0.254)
		(layers "F.Cu" "B.Cu")
		(net "GND")
	)
	(via
		(at 83.586066 -183.893968)
		(size 0.49022)
		(drill 0.254)
		(layers "F.Cu" "B.Cu")
		(net "GND")
	)
	(via
		(at 97.211134 -229.094538)
		(size 0.4064)
		(drill 0.2032)
		(layers "F.Cu" "B.Cu")
		(net "GND")
	)
	(via
		(at 17.608042 -266.185396)
		(size 0.4826)
		(drill 0.254)
		(layers "F.Cu" "B.Cu")
		(net "GND")
	)
	(via
		(at 379.284738 -293.525956)
		(size 0.4064)
		(drill 0.2032)
		(layers "F.Cu" "B.Cu")
		(net "GND")
	)
	(via
		(at 376.82297 -420.318184)
		(size 0.4572)
		(drill 0.254)
		(layers "F.Cu" "B.Cu")
		(net "GND")
	)
	(via
		(at 324.615048 -401.717002)
		(size 0.508)
		(drill 0.254)
		(layers "F.Cu" "B.Cu")
		(net "GND")
	)
	(via
		(at 407.044144 -402.259038)
		(size 0.4572)
		(drill 0.254)
		(layers "F.Cu" "B.Cu")
		(net "GND")
	)
	(via
		(at 375.524776 -261.12597)
		(size 0.4064)
		(drill 0.2032)
		(layers "F.Cu" "B.Cu")
		(net "GND")
	)
	(via
		(at 10.01014 -97.683828)
		(size 0.508)
		(drill 0.254)
		(layers "F.Cu" "B.Cu")
		(net "GND")
	)
	(via
		(at 295.724072 -199.035162)
		(size 0.4826)
		(drill 0.254)
		(layers "F.Cu" "B.Cu")
		(net "GND")
	)
	(via
		(at 130.87477 -286.23641)
		(size 0.4064)
		(drill 0.2032)
		(layers "F.Cu" "B.Cu")
		(net "GND")
	)
	(via
		(at 331.6224 -328.106786)
		(size 0.508)
		(drill 0.254)
		(layers "F.Cu" "B.Cu")
		(net "GND")
	)
	(via
		(at 242.57 -322.834)
		(size 0.508)
		(drill 0.254)
		(layers "F.Cu" "B.Cu")
		(net "GND")
	)
	(via
		(at 61.016642 -393.927838)
		(size 0.4572)
		(drill 0.254)
		(layers "F.Cu" "B.Cu")
		(net "GND")
	)
	(via
		(at 353.911154 -282.186126)
		(size 0.4064)
		(drill 0.2032)
		(layers "F.Cu" "B.Cu")
		(net "GND")
	)
	(via
		(at 211.189824 -12.542266)
		(size 0.508)
		(drill 0.254)
		(layers "F.Cu" "B.Cu")
		(net "GND")
	)
	(via
		(at 143.73479 -250.964446)
		(size 0.4064)
		(drill 0.2032)
		(layers "F.Cu" "B.Cu")
		(net "GND")
	)
	(via
		(at 52.999386 -4.32943)
		(size 0.508)
		(drill 0.254)
		(layers "F.Cu" "B.Cu")
		(net "GND")
	)
	(via
		(at 388.68477 -262.745982)
		(size 0.4064)
		(drill 0.2032)
		(layers "F.Cu" "B.Cu")
		(net "GND")
	)
	(via
		(at 102.211124 -278.946356)
		(size 0.4064)
		(drill 0.2032)
		(layers "F.Cu" "B.Cu")
		(net "GND")
	)
	(via
		(at 51.884072 -288.285428)
		(size 0.4826)
		(drill 0.254)
		(layers "F.Cu" "B.Cu")
		(net "GND")
	)
	(via
		(at 59.620658 -148.34362)
		(size 0.508)
		(drill 0.254)
		(layers "F.Cu" "B.Cu")
		(net "GND")
	)
	(via
		(at 119.12473 -274.08632)
		(size 0.4064)
		(drill 0.2032)
		(layers "F.Cu" "B.Cu")
		(net "GND")
	)
	(via
		(at 315.488066 -420.952168)
		(size 0.4064)
		(drill 0.2032)
		(layers "F.Cu" "B.Cu")
		(net "GND")
	)
	(via
		(at 89.690956 -232.334308)
		(size 0.4064)
		(drill 0.2032)
		(layers "F.Cu" "B.Cu")
		(net "GND")
	)
	(via
		(at 420.877238 -437.834786)
		(size 0.508)
		(drill 0.254)
		(layers "F.Cu" "B.Cu")
		(net "GND")
	)
	(via
		(at 141.384782 -222.61449)
		(size 0.4064)
		(drill 0.2032)
		(layers "F.Cu" "B.Cu")
		(net "GND")
	)
	(via
		(at 329.171046 -250.154186)
		(size 0.4064)
		(drill 0.2032)
		(layers "F.Cu" "B.Cu")
		(net "GND")
	)
	(via
		(at 171.97197 -292.535356)
		(size 0.4826)
		(drill 0.254)
		(layers "F.Cu" "B.Cu")
		(net "GND")
	)
	(via
		(at 406.128474 -168.992804)
		(size 0.49022)
		(drill 0.254)
		(layers "F.Cu" "B.Cu")
		(net "GND")
	)
	(via
		(at 80.93964 -6.347206)
		(size 0.508)
		(drill 0.254)
		(layers "F.Cu" "B.Cu")
		(net "GND")
	)
	(via
		(at 331.351128 -290.285932)
		(size 0.4064)
		(drill 0.2032)
		(layers "F.Cu" "B.Cu")
		(net "GND")
	)
	(via
		(at 124.162312 -384.617722)
		(size 0.4064)
		(drill 0.2032)
		(layers "F.Cu" "B.Cu")
		(net "GND")
	)
	(via
		(at 83.16087 -182.177944)
		(size 0.49022)
		(drill 0.254)
		(layers "F.Cu" "B.Cu")
		(net "GND")
	)
	(via
		(at 191.160146 -318.035432)
		(size 0.4826)
		(drill 0.254)
		(layers "F.Cu" "B.Cu")
		(net "GND")
	)
	(via
		(at 425.69384 -377.41733)
		(size 0.508)
		(drill 0.254)
		(layers "F.Cu" "B.Cu")
		(net "GND")
	)
	(via
		(at 198.7042 -308.685438)
		(size 0.4826)
		(drill 0.254)
		(layers "F.Cu" "B.Cu")
		(net "GND")
	)
	(via
		(at 283.351732 -211.784946)
		(size 0.4826)
		(drill 0.254)
		(layers "F.Cu" "B.Cu")
		(net "GND")
	)
	(via
		(at 101.27107 -291.906198)
		(size 0.4064)
		(drill 0.2032)
		(layers "F.Cu" "B.Cu")
		(net "GND")
	)
	(via
		(at 358.61117 -287.045908)
		(size 0.4064)
		(drill 0.2032)
		(layers "F.Cu" "B.Cu")
		(net "GND")
	)
	(via
		(at 82.174842 -370.83873)
		(size 0.508)
		(drill 0.254)
		(layers "F.Cu" "B.Cu")
		(net "GND")
	)
	(via
		(at 291.12464 -193.99631)
		(size 0.4826)
		(drill 0.254)
		(layers "F.Cu" "B.Cu")
		(net "GND")
	)
	(via
		(at 126.949454 -413.204152)
		(size 0.4572)
		(drill 0.254)
		(layers "F.Cu" "B.Cu")
		(net "GND")
	)
	(via
		(at 21.004784 -388.39013)
		(size 0.508)
		(drill 0.254)
		(layers "F.Cu" "B.Cu")
		(net "GND")
	)
	(via
		(at 295.724072 -244.08511)
		(size 0.4826)
		(drill 0.254)
		(layers "F.Cu" "B.Cu")
		(net "GND")
	)
	(via
		(at 371.93474 -244.484144)
		(size 0.4064)
		(drill 0.2032)
		(layers "F.Cu" "B.Cu")
		(net "GND")
	)
	(via
		(at 109.191044 -381.3302)
		(size 0.508)
		(drill 0.254)
		(layers "F.Cu" "B.Cu")
		(net "GND")
	)
	(via
		(at 352.505518 -173.40072)
		(size 0.508)
		(drill 0.254)
		(layers "F.Cu" "B.Cu")
		(net "GND")
	)
	(via
		(at 305.409346 -339.87867)
		(size 0.508)
		(drill 0.254)
		(layers "F.Cu" "B.Cu")
		(net "GND")
	)
	(via
		(at 386.804916 -261.12597)
		(size 0.4064)
		(drill 0.2032)
		(layers "F.Cu" "B.Cu")
		(net "GND")
	)
	(via
		(at 143.349726 -425.547282)
		(size 0.4572)
		(drill 0.2032)
		(layers "F.Cu" "B.Cu")
		(net "GND")
	)
	(via
		(at 89.514172 -57.233566)
		(size 0.508)
		(drill 0.254)
		(layers "F.Cu" "B.Cu")
		(net "GND")
	)
	(via
		(at 127.381 -109.982)
		(size 0.508)
		(drill 0.254)
		(layers "F.Cu" "B.Cu")
		(net "GND")
	)
	(via
		(at 62.554358 -344.781886)
		(size 0.49022)
		(drill 0.254)
		(layers "F.Cu" "B.Cu")
		(net "GND")
	)
	(via
		(at 467.5378 -205.791054)
		(size 0.508)
		(drill 0.254)
		(layers "F.Cu" "B.Cu")
		(net "GND")
	)
	(via
		(at 424.242992 -401.717002)
		(size 0.508)
		(drill 0.254)
		(layers "F.Cu" "B.Cu")
		(net "GND")
	)
	(via
		(at 314.761372 -31.429706)
		(size 0.508)
		(drill 0.254)
		(layers "F.Cu" "B.Cu")
		(net "GND")
	)
	(via
		(at 446.644268 -251.735082)
		(size 0.4826)
		(drill 0.254)
		(layers "F.Cu" "B.Cu")
		(net "GND")
	)
	(via
		(at 137.154666 -241.244374)
		(size 0.4064)
		(drill 0.2032)
		(layers "F.Cu" "B.Cu")
		(net "GND")
	)
	(via
		(at 162.404044 -371.49913)
		(size 0.508)
		(drill 0.254)
		(layers "F.Cu" "B.Cu")
		(net "GND")
	)
	(via
		(at 158.733998 -11.180826)
		(size 0.508)
		(drill 0.254)
		(layers "F.Cu" "B.Cu")
		(net "GND")
	)
	(via
		(at 245.59387 -290.415726)
		(size 0.508)
		(drill 0.254)
		(layers "F.Cu" "B.Cu")
		(net "GND")
	)
	(via
		(at 319.0621 -392.999722)
		(size 0.4064)
		(drill 0.2032)
		(layers "F.Cu" "B.Cu")
		(net "GND")
	)
	(via
		(at 406.606248 -394.831062)
		(size 0.4064)
		(drill 0.2032)
		(layers "F.Cu" "B.Cu")
		(net "GND")
	)
	(via
		(at 83.111086 -222.61449)
		(size 0.4064)
		(drill 0.2032)
		(layers "F.Cu" "B.Cu")
		(net "GND")
	)
	(via
		(at 315.576966 -112.58677)
		(size 0.508)
		(drill 0.254)
		(layers "F.Cu" "B.Cu")
		(net "GND")
	)
	(via
		(at 427.56582 -385.514088)
		(size 0.508)
		(drill 0.254)
		(layers "F.Cu" "B.Cu")
		(net "GND")
	)
	(via
		(at 89.99093 -283.806392)
		(size 0.4064)
		(drill 0.2032)
		(layers "F.Cu" "B.Cu")
		(net "GND")
	)
	(via
		(at 51.459384 -441.227718)
		(size 0.508)
		(drill 0.254)
		(layers "F.Cu" "B.Cu")
		(net "GND")
	)
	(via
		(at 373.75973 -413.480504)
		(size 0.4572)
		(drill 0.254)
		(layers "F.Cu" "B.Cu")
		(net "GND")
	)
	(via
		(at 406.97658 -376.75693)
		(size 0.508)
		(drill 0.254)
		(layers "F.Cu" "B.Cu")
		(net "GND")
	)
	(via
		(at 252.027182 -94.914466)
		(size 0.508)
		(drill 0.254)
		(layers "F.Cu" "B.Cu")
		(net "GND")
	)
	(via
		(at 342.801194 -249.34418)
		(size 0.4064)
		(drill 0.2032)
		(layers "F.Cu" "B.Cu")
		(net "GND")
	)
	(via
		(at 59.576716 -409.396184)
		(size 0.4572)
		(drill 0.254)
		(layers "F.Cu" "B.Cu")
		(net "GND")
	)
	(via
		(at 20.345654 -10.16508)
		(size 0.508)
		(drill 0.254)
		(layers "F.Cu" "B.Cu")
		(net "GND")
	)
	(via
		(at 132.284724 -285.426404)
		(size 0.4064)
		(drill 0.2032)
		(layers "F.Cu" "B.Cu")
		(net "GND")
	)
	(via
		(at 76.104496 -40.311324)
		(size 0.508)
		(drill 0.254)
		(layers "F.Cu" "B.Cu")
		(net "GND")
	)
	(via
		(at 331.821028 -276.516084)
		(size 0.4064)
		(drill 0.2032)
		(layers "F.Cu" "B.Cu")
		(net "GND")
	)
	(via
		(at 283.351732 -209.23504)
		(size 0.4826)
		(drill 0.254)
		(layers "F.Cu" "B.Cu")
		(net "GND")
	)
	(via
		(at 51.884072 -263.635236)
		(size 0.4826)
		(drill 0.254)
		(layers "F.Cu" "B.Cu")
		(net "GND")
	)
	(via
		(at 50.499772 -286.585406)
		(size 0.4826)
		(drill 0.254)
		(layers "F.Cu" "B.Cu")
		(net "GND")
	)
	(via
		(at 196.28358 -366.08258)
		(size 0.6604)
		(drill 0.3302)
		(layers "F.Cu" "B.Cu")
		(net "GND")
	)
	(via
		(at 343.245948 -396.710662)
		(size 0.4064)
		(drill 0.2032)
		(layers "F.Cu" "B.Cu")
		(net "GND")
	)
	(via
		(at 93.751146 -282.18638)
		(size 0.4064)
		(drill 0.2032)
		(layers "F.Cu" "B.Cu")
		(net "GND")
	)
	(via
		(at 82.390234 -384.617722)
		(size 0.4064)
		(drill 0.2032)
		(layers "F.Cu" "B.Cu")
		(net "GND")
	)
	(via
		(at 290.605972 -368.205512)
		(size 0.508)
		(drill 0.254)
		(layers "F.Cu" "B.Cu")
		(net "GND")
	)
	(via
		(at 430.572164 -436.271924)
		(size 0.508)
		(drill 0.254)
		(layers "F.Cu" "B.Cu")
		(net "GND")
	)
	(via
		(at 299.513498 -423.272966)
		(size 0.508)
		(drill 0.254)
		(layers "F.Cu" "B.Cu")
		(net "GND")
	)
	(via
		(at 314.155836 -378.07773)
		(size 0.508)
		(drill 0.254)
		(layers "F.Cu" "B.Cu")
		(net "GND")
	)
	(via
		(at 20.348194 -9.424924)
		(size 0.508)
		(drill 0.254)
		(layers "F.Cu" "B.Cu")
		(net "GND")
	)
	(via
		(at 81.832196 -28.567888)
		(size 0.6604)
		(drill 0.3302)
		(layers "F.Cu" "B.Cu")
		(net "GND")
	)
	(via
		(at 441.385452 -393.197334)
		(size 0.508)
		(drill 0.254)
		(layers "F.Cu" "B.Cu")
		(net "GND")
	)
	(via
		(at 85.614256 -405.098504)
		(size 0.4572)
		(drill 0.254)
		(layers "F.Cu" "B.Cu")
		(net "GND")
	)
	(via
		(at 202.147932 -292.535356)
		(size 0.4826)
		(drill 0.254)
		(layers "F.Cu" "B.Cu")
		(net "GND")
	)
	(via
		(at 41.62425 -212.635338)
		(size 0.4826)
		(drill 0.254)
		(layers "F.Cu" "B.Cu")
		(net "GND")
	)
	(via
		(at 322.662296 -377.41733)
		(size 0.508)
		(drill 0.254)
		(layers "F.Cu" "B.Cu")
		(net "GND")
	)
	(via
		(at 441.753752 -375.455434)
		(size 0.6604)
		(drill 0.3302)
		(layers "F.Cu" "B.Cu")
		(net "GND")
	)
	(via
		(at 121.174764 -250.964446)
		(size 0.4064)
		(drill 0.2032)
		(layers "F.Cu" "B.Cu")
		(net "GND")
	)
	(via
		(at 393.892024 -18.5039)
		(size 0.508)
		(drill 0.254)
		(layers "F.Cu" "B.Cu")
		(net "GND")
	)
	(via
		(at 134.164832 -293.52621)
		(size 0.4064)
		(drill 0.2032)
		(layers "F.Cu" "B.Cu")
		(net "GND")
	)
	(via
		(at 383.69113 -398.542002)
		(size 0.4064)
		(drill 0.2032)
		(layers "F.Cu" "B.Cu")
		(net "GND")
	)
	(via
		(at 405.884888 -6.598158)
		(size 0.508)
		(drill 0.254)
		(layers "F.Cu" "B.Cu")
		(net "GND")
	)
	(via
		(at 50.728372 -192.218564)
		(size 0.4826)
		(drill 0.254)
		(layers "F.Cu" "B.Cu")
		(net "GND")
	)
	(via
		(at 55.328058 -298.485306)
		(size 0.4826)
		(drill 0.254)
		(layers "F.Cu" "B.Cu")
		(net "GND")
	)
	(via
		(at 89.690956 -237.194344)
		(size 0.4064)
		(drill 0.2032)
		(layers "F.Cu" "B.Cu")
		(net "GND")
	)
	(via
		(at 405.34971 -430.147222)
		(size 0.4572)
		(drill 0.2032)
		(layers "F.Cu" "B.Cu")
		(net "GND")
	)
	(via
		(at 386.034788 -223.424242)
		(size 0.4064)
		(drill 0.2032)
		(layers "F.Cu" "B.Cu")
		(net "GND")
	)
	(via
		(at 269.648178 -246.635016)
		(size 0.4826)
		(drill 0.254)
		(layers "F.Cu" "B.Cu")
		(net "GND")
	)
	(via
		(at 174.687738 -302.735234)
		(size 0.4826)
		(drill 0.254)
		(layers "F.Cu" "B.Cu")
		(net "GND")
	)
	(via
		(at 187.060078 -206.685388)
		(size 0.4826)
		(drill 0.254)
		(layers "F.Cu" "B.Cu")
		(net "GND")
	)
	(via
		(at 27.548332 -9.424924)
		(size 0.508)
		(drill 0.254)
		(layers "F.Cu" "B.Cu")
		(net "GND")
	)
	(via
		(at 0.762254 -15.539212)
		(size 0.508)
		(drill 0.254)
		(layers "F.Cu" "B.Cu")
		(net "GND")
	)
	(via
		(at 75.253088 -17.558512)
		(size 0.508)
		(drill 0.254)
		(layers "F.Cu" "B.Cu")
		(net "GND")
	)
	(via
		(at 331.029564 -134.724902)
		(size 0.508)
		(drill 0.254)
		(layers "F.Cu" "B.Cu")
		(net "GND")
	)
	(via
		(at 41.637712 -0.762254)
		(size 0.508)
		(drill 0.254)
		(layers "F.Cu" "B.Cu")
		(net "GND")
	)
	(via
		(at 121.644664 -227.474526)
		(size 0.4064)
		(drill 0.2032)
		(layers "F.Cu" "B.Cu")
		(net "GND")
	)
	(via
		(at 119.12473 -283.806392)
		(size 0.4064)
		(drill 0.2032)
		(layers "F.Cu" "B.Cu")
		(net "GND")
	)
	(via
		(at 361.942634 -397.958056)
		(size 0.508)
		(drill 0.254)
		(layers "F.Cu" "B.Cu")
		(net "GND")
	)
	(via
		(at 95.1611 -292.716204)
		(size 0.4064)
		(drill 0.2032)
		(layers "F.Cu" "B.Cu")
		(net "GND")
	)
	(via
		(at 307.202586 -347.282262)
		(size 0.49022)
		(drill 0.254)
		(layers "F.Cu" "B.Cu")
		(net "GND")
	)
	(via
		(at 51.918616 -413.204152)
		(size 0.4572)
		(drill 0.254)
		(layers "F.Cu" "B.Cu")
		(net "GND")
	)
	(via
		(at 92.040964 -225.044508)
		(size 0.4064)
		(drill 0.2032)
		(layers "F.Cu" "B.Cu")
		(net "GND")
	)
	(via
		(at 125.927866 -166.342568)
		(size 0.49022)
		(drill 0.254)
		(layers "F.Cu" "B.Cu")
		(net "GND")
	)
	(via
		(at 2.76225 -121.341134)
		(size 0.508)
		(drill 0.254)
		(layers "F.Cu" "B.Cu")
		(net "GND")
	)
	(via
		(at 183.616092 -301.035212)
		(size 0.4826)
		(drill 0.254)
		(layers "F.Cu" "B.Cu")
		(net "GND")
	)
	(via
		(at 338.101178 -231.524048)
		(size 0.4064)
		(drill 0.2032)
		(layers "F.Cu" "B.Cu")
		(net "GND")
	)
	(via
		(at 391.674858 -231.524048)
		(size 0.4064)
		(drill 0.2032)
		(layers "F.Cu" "B.Cu")
		(net "GND")
	)
	(via
		(at 113.954814 -266.796266)
		(size 0.4064)
		(drill 0.2032)
		(layers "F.Cu" "B.Cu")
		(net "GND")
	)
	(via
		(at 132.284724 -288.666174)
		(size 0.4064)
		(drill 0.2032)
		(layers "F.Cu" "B.Cu")
		(net "GND")
	)
	(via
		(at 392.614912 -250.964192)
		(size 0.4064)
		(drill 0.2032)
		(layers "F.Cu" "B.Cu")
		(net "GND")
	)
	(via
		(at 336.22107 -244.484144)
		(size 0.4064)
		(drill 0.2032)
		(layers "F.Cu" "B.Cu")
		(net "GND")
	)
	(via
		(at 89.99093 -261.126224)
		(size 0.4064)
		(drill 0.2032)
		(layers "F.Cu" "B.Cu")
		(net "GND")
	)
	(via
		(at 311.862216 -392.999722)
		(size 0.4064)
		(drill 0.2032)
		(layers "F.Cu" "B.Cu")
		(net "GND")
	)
	(via
		(at 21.70811 -282.335224)
		(size 0.4826)
		(drill 0.254)
		(layers "F.Cu" "B.Cu")
		(net "GND")
	)
	(via
		(at 69.249798 -439.651394)
		(size 0.4572)
		(drill 0.2032)
		(layers "F.Cu" "B.Cu")
		(net "GND")
	)
	(via
		(at 393.084812 -230.714296)
		(size 0.4064)
		(drill 0.2032)
		(layers "F.Cu" "B.Cu")
		(net "GND")
	)
	(via
		(at 140.744702 -261.126224)
		(size 0.4064)
		(drill 0.2032)
		(layers "F.Cu" "B.Cu")
		(net "GND")
	)
	(via
		(at 268.492478 -193.99631)
		(size 0.4826)
		(drill 0.254)
		(layers "F.Cu" "B.Cu")
		(net "GND")
	)
	(via
		(at 292.280086 -255.135126)
		(size 0.4826)
		(drill 0.254)
		(layers "F.Cu" "B.Cu")
		(net "GND")
	)
	(via
		(at 403.444202 -400.212814)
		(size 0.4064)
		(drill 0.2032)
		(layers "F.Cu" "B.Cu")
		(net "GND")
	)
	(via
		(at 377.00331 -189.435486)
		(size 0.508)
		(drill 0.254)
		(layers "F.Cu" "B.Cu")
		(net "GND")
	)
	(via
		(at 385.094734 -250.964192)
		(size 0.4064)
		(drill 0.2032)
		(layers "F.Cu" "B.Cu")
		(net "GND")
	)
	(via
		(at 378.210318 -185.988198)
		(size 0.508)
		(drill 0.254)
		(layers "F.Cu" "B.Cu")
		(net "GND")
	)
	(via
		(at 394.494766 -225.044254)
		(size 0.4064)
		(drill 0.2032)
		(layers "F.Cu" "B.Cu")
		(net "GND")
	)
	(via
		(at 66.662554 -369.03533)
		(size 0.508)
		(drill 0.254)
		(layers "F.Cu" "B.Cu")
		(net "GND")
	)
	(via
		(at 169.645584 -304.010314)
		(size 0.4826)
		(drill 0.254)
		(layers "F.Cu" "B.Cu")
		(net "GND")
	)
	(via
		(at 141.214856 -268.416278)
		(size 0.4064)
		(drill 0.2032)
		(layers "F.Cu" "B.Cu")
		(net "GND")
	)
	(via
		(at 121.004838 -265.98626)
		(size 0.4064)
		(drill 0.2032)
		(layers "F.Cu" "B.Cu")
		(net "GND")
	)
	(via
		(at 131.814824 -268.416278)
		(size 0.4064)
		(drill 0.2032)
		(layers "F.Cu" "B.Cu")
		(net "GND")
	)
	(via
		(at 46.16704 -439.763154)
		(size 0.508)
		(drill 0.254)
		(layers "F.Cu" "B.Cu")
		(net "GND")
	)
	(via
		(at 454.188068 -196.485002)
		(size 0.4826)
		(drill 0.254)
		(layers "F.Cu" "B.Cu")
		(net "GND")
	)
	(via
		(at 317.559436 -383.00533)
		(size 0.508)
		(drill 0.254)
		(layers "F.Cu" "B.Cu")
		(net "GND")
	)
	(via
		(at 102.560628 -388.892542)
		(size 0.508)
		(drill 0.254)
		(layers "F.Cu" "B.Cu")
		(net "GND")
	)
	(via
		(at 389.624824 -269.22603)
		(size 0.4064)
		(drill 0.2032)
		(layers "F.Cu" "B.Cu")
		(net "GND")
	)
	(via
		(at 140.734034 -409.396184)
		(size 0.4572)
		(drill 0.254)
		(layers "F.Cu" "B.Cu")
		(net "GND")
	)
	(via
		(at 296.879772 -193.10731)
		(size 0.4826)
		(drill 0.254)
		(layers "F.Cu" "B.Cu")
		(net "GND")
	)
	(via
		(at 388.803134 -416.020504)
		(size 0.4572)
		(drill 0.254)
		(layers "F.Cu" "B.Cu")
		(net "GND")
	)
	(via
		(at 396.917926 -6.091174)
		(size 0.508)
		(drill 0.254)
		(layers "F.Cu" "B.Cu")
		(net "GND")
	)
	(via
		(at 182.204868 -14.502892)
		(size 0.508)
		(drill 0.254)
		(layers "F.Cu" "B.Cu")
		(net "GND")
	)
	(via
		(at 35.678364 -313.360308)
		(size 0.4826)
		(drill 0.254)
		(layers "F.Cu" "B.Cu")
		(net "GND")
	)
	(via
		(at 446.644268 -216.885012)
		(size 0.4826)
		(drill 0.254)
		(layers "F.Cu" "B.Cu")
		(net "GND")
	)
	(via
		(at 102.38105 -236.384338)
		(size 0.4064)
		(drill 0.2032)
		(layers "F.Cu" "B.Cu")
		(net "GND")
	)
	(via
		(at 450.088 -298.485052)
		(size 0.4826)
		(drill 0.254)
		(layers "F.Cu" "B.Cu")
		(net "GND")
	)
	(via
		(at 364.24489 -280.566114)
		(size 0.4064)
		(drill 0.2032)
		(layers "F.Cu" "B.Cu")
		(net "GND")
	)
	(via
		(at 67.507612 -407.638504)
		(size 0.4572)
		(drill 0.254)
		(layers "F.Cu" "B.Cu")
		(net "GND")
	)
	(via
		(at 95.489522 -133.325362)
		(size 0.508)
		(drill 0.254)
		(layers "F.Cu" "B.Cu")
		(net "GND")
	)
	(via
		(at 55.497222 -177.649124)
		(size 0.6604)
		(drill 0.3302)
		(layers "F.Cu" "B.Cu")
		(net "GND")
	)
	(via
		(at 58.043826 -239.835436)
		(size 0.4826)
		(drill 0.254)
		(layers "F.Cu" "B.Cu")
		(net "GND")
	)
	(via
		(at 0.762254 -71.419212)
		(size 0.508)
		(drill 0.254)
		(layers "F.Cu" "B.Cu")
		(net "GND")
	)
	(via
		(at 428.840392 -228.785166)
		(size 0.4826)
		(drill 0.254)
		(layers "F.Cu" "B.Cu")
		(net "GND")
	)
	(via
		(at 386.974842 -249.34418)
		(size 0.4064)
		(drill 0.2032)
		(layers "F.Cu" "B.Cu")
		(net "GND")
	)
	(via
		(at 207.3656 -210.510374)
		(size 0.4826)
		(drill 0.254)
		(layers "F.Cu" "B.Cu")
		(net "GND")
	)
	(via
		(at 118.824756 -237.194344)
		(size 0.4064)
		(drill 0.2032)
		(layers "F.Cu" "B.Cu")
		(net "GND")
	)
	(via
		(at 411.698948 -17.613122)
		(size 0.508)
		(drill 0.254)
		(layers "F.Cu" "B.Cu")
		(net "GND")
	)
	(via
		(at 165.812216 -203.285344)
		(size 0.4826)
		(drill 0.254)
		(layers "F.Cu" "B.Cu")
		(net "GND")
	)
	(via
		(at 69.039232 -405.098504)
		(size 0.4572)
		(drill 0.254)
		(layers "F.Cu" "B.Cu")
		(net "GND")
	)
	(via
		(at 383.21488 -228.284278)
		(size 0.4064)
		(drill 0.2032)
		(layers "F.Cu" "B.Cu")
		(net "GND")
	)
	(via
		(at 409.075382 -412.84652)
		(size 0.4064)
		(drill 0.2032)
		(layers "F.Cu" "B.Cu")
		(net "GND")
	)
	(via
		(at 102.804722 -125.590554)
		(size 0.508)
		(drill 0.254)
		(layers "F.Cu" "B.Cu")
		(net "GND")
	)
	(via
		(at 418.595302 -435.275736)
		(size 0.508)
		(drill 0.254)
		(layers "F.Cu" "B.Cu")
		(net "GND")
	)
	(via
		(at 90.16111 -236.384338)
		(size 0.4064)
		(drill 0.2032)
		(layers "F.Cu" "B.Cu")
		(net "GND")
	)
	(via
		(at 57.402222 -179.554124)
		(size 0.6604)
		(drill 0.3302)
		(layers "F.Cu" "B.Cu")
		(net "GND")
	)
	(via
		(at 284.736032 -282.33497)
		(size 0.4826)
		(drill 0.254)
		(layers "F.Cu" "B.Cu")
		(net "GND")
	)
	(via
		(at 267.07973 -67.343782)
		(size 0.508)
		(drill 0.254)
		(layers "F.Cu" "B.Cu")
		(net "GND")
	)
	(via
		(at 371.921278 -140.456158)
		(size 0.508)
		(drill 0.254)
		(layers "F.Cu" "B.Cu")
		(net "GND")
	)
	(via
		(at 88.580976 -263.556242)
		(size 0.4064)
		(drill 0.2032)
		(layers "F.Cu" "B.Cu")
		(net "GND")
	)
	(via
		(at 416.5092 -109.215428)
		(size 0.508)
		(drill 0.254)
		(layers "F.Cu" "B.Cu")
		(net "GND")
	)
	(via
		(at 75.028552 -340.00821)
		(size 0.508)
		(drill 0.254)
		(layers "F.Cu" "B.Cu")
		(net "GND")
	)
	(via
		(at 461.309466 -410.6037)
		(size 0.508)
		(drill 0.254)
		(layers "F.Cu" "B.Cu")
		(net "GND")
	)
	(via
		(at 180.900324 -221.985332)
		(size 0.4826)
		(drill 0.254)
		(layers "F.Cu" "B.Cu")
		(net "GND")
	)
	(via
		(at 146.969734 -11.458448)
		(size 0.508)
		(drill 0.254)
		(layers "F.Cu" "B.Cu")
		(net "GND")
	)
	(via
		(at 271.974564 -230.060246)
		(size 0.4826)
		(drill 0.254)
		(layers "F.Cu" "B.Cu")
		(net "GND")
	)
	(via
		(at 53.562758 -345.571064)
		(size 0.49022)
		(drill 0.254)
		(layers "F.Cu" "B.Cu")
		(net "GND")
	)
	(via
		(at 340.921086 -252.584204)
		(size 0.4064)
		(drill 0.2032)
		(layers "F.Cu" "B.Cu")
		(net "GND")
	)
	(via
		(at 392.349482 -438.499758)
		(size 0.4572)
		(drill 0.2032)
		(layers "F.Cu" "B.Cu")
		(net "GND")
	)
	(via
		(at 108.49102 -224.234502)
		(size 0.4064)
		(drill 0.2032)
		(layers "F.Cu" "B.Cu")
		(net "GND")
	)
	(via
		(at 326.720708 -333.048864)
		(size 0.49022)
		(drill 0.254)
		(layers "F.Cu" "B.Cu")
		(net "GND")
	)
	(via
		(at 125.68174 -26.916126)
		(size 0.508)
		(drill 0.254)
		(layers "F.Cu" "B.Cu")
		(net "GND")
	)
	(via
		(at 362.828332 -334.386174)
		(size 0.508)
		(drill 0.254)
		(layers "F.Cu" "B.Cu")
		(net "GND")
	)
	(via
		(at 341.691214 -272.466054)
		(size 0.4064)
		(drill 0.2032)
		(layers "F.Cu" "B.Cu")
		(net "GND")
	)
	(via
		(at 352.671126 -238.814102)
		(size 0.4064)
		(drill 0.2032)
		(layers "F.Cu" "B.Cu")
		(net "GND")
	)
	(via
		(at 198.7042 -246.63527)
		(size 0.4826)
		(drill 0.254)
		(layers "F.Cu" "B.Cu")
		(net "GND")
	)
	(via
		(at 197.3199 -237.285276)
		(size 0.4826)
		(drill 0.254)
		(layers "F.Cu" "B.Cu")
		(net "GND")
	)
	(via
		(at 282.020264 -210.085178)
		(size 0.4826)
		(drill 0.254)
		(layers "F.Cu" "B.Cu")
		(net "GND")
	)
	(via
		(at 146.776186 -53.897784)
		(size 0.508)
		(drill 0.254)
		(layers "F.Cu" "B.Cu")
		(net "GND")
	)
	(via
		(at 55.254652 -410.664152)
		(size 0.4572)
		(drill 0.254)
		(layers "F.Cu" "B.Cu")
		(net "GND")
	)
	(via
		(at 445.259968 -202.434952)
		(size 0.4826)
		(drill 0.254)
		(layers "F.Cu" "B.Cu")
		(net "GND")
	)
	(via
		(at 98.150934 -246.914416)
		(size 0.4064)
		(drill 0.2032)
		(layers "F.Cu" "B.Cu")
		(net "GND")
	)
	(via
		(at 186.130438 -349.34652)
		(size 0.508)
		(drill 0.254)
		(layers "F.Cu" "B.Cu")
		(net "GND")
	)
	(via
		(at 303.596294 -413.480504)
		(size 0.4572)
		(drill 0.254)
		(layers "F.Cu" "B.Cu")
		(net "GND")
	)
	(via
		(at 350.621092 -286.236156)
		(size 0.4064)
		(drill 0.2032)
		(layers "F.Cu" "B.Cu")
		(net "GND")
	)
	(via
		(at 181.20868 -25.92324)
		(size 0.508)
		(drill 0.254)
		(layers "F.Cu" "B.Cu")
		(net "GND")
	)
	(via
		(at 132.714746 -404.46452)
		(size 0.4064)
		(drill 0.2032)
		(layers "F.Cu" "B.Cu")
		(net "GND")
	)
	(via
		(at 18.913348 -388.53491)
		(size 0.49022)
		(drill 0.254)
		(layers "F.Cu" "B.Cu")
		(net "GND")
	)
	(via
		(at 81.701132 -244.484398)
		(size 0.4064)
		(drill 0.2032)
		(layers "F.Cu" "B.Cu")
		(net "GND")
	)
	(via
		(at 341.8967 -335.590388)
		(size 0.49022)
		(drill 0.254)
		(layers "F.Cu" "B.Cu")
		(net "GND")
	)
	(via
		(at 10.876788 -369.84305)
		(size 0.508)
		(drill 0.254)
		(layers "F.Cu" "B.Cu")
		(net "GND")
	)
	(via
		(at 312.703972 -36.09975)
		(size 0.508)
		(drill 0.254)
		(layers "F.Cu" "B.Cu")
		(net "GND")
	)
	(via
		(at 98.161094 -313.872372)
		(size 0.4064)
		(drill 0.2032)
		(layers "F.Cu" "B.Cu")
		(net "GND")
	)
	(via
		(at 36.239958 -346.322142)
		(size 0.49022)
		(drill 0.254)
		(layers "F.Cu" "B.Cu")
		(net "GND")
	)
	(via
		(at 184.732168 -113.46307)
		(size 0.4572)
		(drill 0.254)
		(layers "F.Cu" "B.Cu")
		(net "GND")
	)
	(via
		(at 149.492716 -56.204358)
		(size 0.508)
		(drill 0.254)
		(layers "F.Cu" "B.Cu")
		(net "GND")
	)
	(via
		(at 292.280086 -241.53495)
		(size 0.4826)
		(drill 0.254)
		(layers "F.Cu" "B.Cu")
		(net "GND")
	)
	(via
		(at 369.254278 -188.873638)
		(size 0.508)
		(drill 0.254)
		(layers "F.Cu" "B.Cu")
		(net "GND")
	)
	(via
		(at 54.718458 -388.328662)
		(size 0.4064)
		(drill 0.2032)
		(layers "F.Cu" "B.Cu")
		(net "GND")
	)
	(via
		(at 451.4723 -212.635084)
		(size 0.4826)
		(drill 0.254)
		(layers "F.Cu" "B.Cu")
		(net "GND")
	)
	(via
		(at 338.401152 -284.616144)
		(size 0.4064)
		(drill 0.2032)
		(layers "F.Cu" "B.Cu")
		(net "GND")
	)
	(via
		(at 93.159834 -32.42691)
		(size 0.508)
		(drill 0.254)
		(layers "F.Cu" "B.Cu")
		(net "GND")
	)
	(via
		(at 132.404866 -156.93009)
		(size 0.49022)
		(drill 0.254)
		(layers "F.Cu" "B.Cu")
		(net "GND")
	)
	(via
		(at 30.536134 -344.78595)
		(size 0.49022)
		(drill 0.254)
		(layers "F.Cu" "B.Cu")
		(net "GND")
	)
	(via
		(at 124.84227 -163.204144)
		(size 0.49022)
		(drill 0.254)
		(layers "F.Cu" "B.Cu")
		(net "GND")
	)
	(via
		(at 57.670954 -369.03533)
		(size 0.508)
		(drill 0.254)
		(layers "F.Cu" "B.Cu")
		(net "GND")
	)
	(via
		(at 380.224792 -288.66592)
		(size 0.4064)
		(drill 0.2032)
		(layers "F.Cu" "B.Cu")
		(net "GND")
	)
	(via
		(at 137.45464 -291.096192)
		(size 0.4064)
		(drill 0.2032)
		(layers "F.Cu" "B.Cu")
		(net "GND")
	)
	(via
		(at 353.911154 -277.32609)
		(size 0.4064)
		(drill 0.2032)
		(layers "F.Cu" "B.Cu")
		(net "GND")
	)
	(via
		(at 139.038076 -377.132088)
		(size 0.508)
		(drill 0.254)
		(layers "F.Cu" "B.Cu")
		(net "GND")
	)
	(via
		(at 108.33227 -176.183544)
		(size 0.49022)
		(drill 0.254)
		(layers "F.Cu" "B.Cu")
		(net "GND")
	)
	(via
		(at 372.704868 -278.946102)
		(size 0.4064)
		(drill 0.2032)
		(layers "F.Cu" "B.Cu")
		(net "GND")
	)
	(via
		(at 176.072038 -297.635422)
		(size 0.4826)
		(drill 0.254)
		(layers "F.Cu" "B.Cu")
		(net "GND")
	)
	(via
		(at 42.56532 -112.11052)
		(size 0.508)
		(drill 0.254)
		(layers "F.Cu" "B.Cu")
		(net "GND")
	)
	(via
		(at 139.409424 -111.874808)
		(size 0.508)
		(drill 0.254)
		(layers "F.Cu" "B.Cu")
		(net "GND")
	)
	(via
		(at 168.527984 -282.335224)
		(size 0.4826)
		(drill 0.254)
		(layers "F.Cu" "B.Cu")
		(net "GND")
	)
	(via
		(at 372.704868 -275.706078)
		(size 0.4064)
		(drill 0.2032)
		(layers "F.Cu" "B.Cu")
		(net "GND")
	)
	(via
		(at 176.072038 -233.885232)
		(size 0.4826)
		(drill 0.254)
		(layers "F.Cu" "B.Cu")
		(net "GND")
	)
	(via
		(at 255.927098 -203.932536)
		(size 0.508)
		(drill 0.254)
		(layers "F.Cu" "B.Cu")
		(net "GND")
	)
	(via
		(at 83.580986 -247.724422)
		(size 0.4064)
		(drill 0.2032)
		(layers "F.Cu" "B.Cu")
		(net "GND")
	)
	(via
		(at 177.189638 -201.16038)
		(size 0.4826)
		(drill 0.254)
		(layers "F.Cu" "B.Cu")
		(net "GND")
	)
	(via
		(at 409.146248 -396.710662)
		(size 0.4064)
		(drill 0.2032)
		(layers "F.Cu" "B.Cu")
		(net "GND")
	)
	(via
		(at 117.44071 -256.48031)
		(size 0.4826)
		(drill 0.254)
		(layers "F.Cu" "B.Cu")
		(net "GND")
	)
	(via
		(at 397.718788 -390.92632)
		(size 0.508)
		(drill 0.254)
		(layers "F.Cu" "B.Cu")
		(net "GND")
	)
	(via
		(at 353.441 -284.616144)
		(size 0.4064)
		(drill 0.2032)
		(layers "F.Cu" "B.Cu")
		(net "GND")
	)
	(via
		(at 384.924808 -262.745982)
		(size 0.4064)
		(drill 0.2032)
		(layers "F.Cu" "B.Cu")
		(net "GND")
	)
	(via
		(at 443.6618 -295.510204)
		(size 0.4826)
		(drill 0.254)
		(layers "F.Cu" "B.Cu")
		(net "GND")
	)
	(via
		(at 95.1611 -274.896326)
		(size 0.4064)
		(drill 0.2032)
		(layers "F.Cu" "B.Cu")
		(net "GND")
	)
	(via
		(at 362.255308 -332.931008)
		(size 0.508)
		(drill 0.254)
		(layers "F.Cu" "B.Cu")
		(net "GND")
	)
	(via
		(at 125.404626 -246.914416)
		(size 0.4064)
		(drill 0.2032)
		(layers "F.Cu" "B.Cu")
		(net "GND")
	)
	(via
		(at 369.414806 -271.656048)
		(size 0.4064)
		(drill 0.2032)
		(layers "F.Cu" "B.Cu")
		(net "GND")
	)
	(via
		(at 96.27108 -233.95432)
		(size 0.4064)
		(drill 0.2032)
		(layers "F.Cu" "B.Cu")
		(net "GND")
	)
	(via
		(at 195.988432 -221.985332)
		(size 0.4826)
		(drill 0.254)
		(layers "F.Cu" "B.Cu")
		(net "GND")
	)
	(via
		(at 212.263228 -326.509888)
		(size 0.508)
		(drill 0.254)
		(layers "F.Cu" "B.Cu")
		(net "GND")
	)
	(via
		(at 51.348894 -368.37493)
		(size 0.508)
		(drill 0.254)
		(layers "F.Cu" "B.Cu")
		(net "GND")
	)
	(via
		(at 273.092164 -252.584966)
		(size 0.4826)
		(drill 0.254)
		(layers "F.Cu" "B.Cu")
		(net "GND")
	)
	(via
		(at 351.561146 -268.416024)
		(size 0.4064)
		(drill 0.2032)
		(layers "F.Cu" "B.Cu")
		(net "GND")
	)
	(via
		(at 382.349502 -438.651396)
		(size 0.4572)
		(drill 0.2032)
		(layers "F.Cu" "B.Cu")
		(net "GND")
	)
	(via
		(at 95.944182 -393.927838)
		(size 0.4572)
		(drill 0.254)
		(layers "F.Cu" "B.Cu")
		(net "GND")
	)
	(via
		(at 194.604132 -227.085398)
		(size 0.4826)
		(drill 0.254)
		(layers "F.Cu" "B.Cu")
		(net "GND")
	)
	(via
		(at 118.354856 -228.284532)
		(size 0.4064)
		(drill 0.2032)
		(layers "F.Cu" "B.Cu")
		(net "GND")
	)
	(via
		(at 394.68298 -236.650022)
		(size 0.4064)
		(drill 0.2032)
		(layers "F.Cu" "B.Cu")
		(net "GND")
	)
	(via
		(at 203.532232 -203.285344)
		(size 0.4826)
		(drill 0.254)
		(layers "F.Cu" "B.Cu")
		(net "GND")
	)
	(via
		(at 115.818412 -388.328662)
		(size 0.4064)
		(drill 0.2032)
		(layers "F.Cu" "B.Cu")
		(net "GND")
	)
	(via
		(at 97.968054 -328.124312)
		(size 0.508)
		(drill 0.254)
		(layers "F.Cu" "B.Cu")
		(net "GND")
	)
	(via
		(at 124.294646 -286.23641)
		(size 0.4064)
		(drill 0.2032)
		(layers "F.Cu" "B.Cu")
		(net "GND")
	)
	(via
		(at 303.268126 -272.135092)
		(size 0.4826)
		(drill 0.254)
		(layers "F.Cu" "B.Cu")
		(net "GND")
	)
	(via
		(at 258.53898 -74.774044)
		(size 0.508)
		(drill 0.254)
		(layers "F.Cu" "B.Cu")
		(net "GND")
	)
	(via
		(at 90.16111 -252.584458)
		(size 0.4064)
		(drill 0.2032)
		(layers "F.Cu" "B.Cu")
		(net "GND")
	)
	(via
		(at 140.349732 -438.499758)
		(size 0.4572)
		(drill 0.2032)
		(layers "F.Cu" "B.Cu")
		(net "GND")
	)
	(via
		(at 265.54811 -269.585186)
		(size 0.4826)
		(drill 0.254)
		(layers "F.Cu" "B.Cu")
		(net "GND")
	)
	(via
		(at 103.791004 -225.854514)
		(size 0.4064)
		(drill 0.2032)
		(layers "F.Cu" "B.Cu")
		(net "GND")
	)
	(via
		(at 357.29037 -397.274542)
		(size 0.508)
		(drill 0.254)
		(layers "F.Cu" "B.Cu")
		(net "GND")
	)
	(via
		(at 419.993318 -167.672512)
		(size 0.508)
		(drill 0.254)
		(layers "F.Cu" "B.Cu")
		(net "GND")
	)
	(via
		(at 24.77262 -358.202738)
		(size 0.508)
		(drill 0.254)
		(layers "F.Cu" "B.Cu")
		(net "GND")
	)
	(via
		(at 157.806136 -386.449062)
		(size 0.4064)
		(drill 0.2032)
		(layers "F.Cu" "B.Cu")
		(net "GND")
	)
	(via
		(at 113.48466 -282.18638)
		(size 0.4064)
		(drill 0.2032)
		(layers "F.Cu" "B.Cu")
		(net "GND")
	)
	(via
		(at 72.757284 -388.77113)
		(size 0.508)
		(drill 0.254)
		(layers "F.Cu" "B.Cu")
		(net "GND")
	)
	(via
		(at 189.775846 -211.7852)
		(size 0.4826)
		(drill 0.254)
		(layers "F.Cu" "B.Cu")
		(net "GND")
	)
	(via
		(at 280.635964 -266.185142)
		(size 0.4826)
		(drill 0.254)
		(layers "F.Cu" "B.Cu")
		(net "GND")
	)
	(via
		(at 355.961188 -233.14406)
		(size 0.4064)
		(drill 0.2032)
		(layers "F.Cu" "B.Cu")
		(net "GND")
	)
	(via
		(at 88.580976 -261.93623)
		(size 0.4064)
		(drill 0.2032)
		(layers "F.Cu" "B.Cu")
		(net "GND")
	)
	(via
		(at 345.94419 -402.309838)
		(size 0.4572)
		(drill 0.254)
		(layers "F.Cu" "B.Cu")
		(net "GND")
	)
	(via
		(at 282.941522 -114.82197)
		(size 0.508)
		(drill 0.254)
		(layers "F.Cu" "B.Cu")
		(net "GND")
	)
	(via
		(at 372.22811 -419.046152)
		(size 0.4572)
		(drill 0.254)
		(layers "F.Cu" "B.Cu")
		(net "GND")
	)
	(via
		(at 52.191412 -410.664152)
		(size 0.4572)
		(drill 0.254)
		(layers "F.Cu" "B.Cu")
		(net "GND")
	)
	(via
		(at 395.888718 -179.106322)
		(size 0.49022)
		(drill 0.254)
		(layers "F.Cu" "B.Cu")
		(net "GND")
	)
	(via
		(at 394.79474 -294.335962)
		(size 0.4064)
		(drill 0.2032)
		(layers "F.Cu" "B.Cu")
		(net "GND")
	)
	(via
		(at 198.7042 -261.935214)
		(size 0.4826)
		(drill 0.254)
		(layers "F.Cu" "B.Cu")
		(net "GND")
	)
	(via
		(at 337.631024 -245.29415)
		(size 0.4064)
		(drill 0.2032)
		(layers "F.Cu" "B.Cu")
		(net "GND")
	)
	(via
		(at 280.635964 -250.884944)
		(size 0.4826)
		(drill 0.254)
		(layers "F.Cu" "B.Cu")
		(net "GND")
	)
	(via
		(at 76.1873 -380.873)
		(size 0.508)
		(drill 0.254)
		(layers "F.Cu" "B.Cu")
		(net "GND")
	)
	(via
		(at 78.41107 -250.15444)
		(size 0.4064)
		(drill 0.2032)
		(layers "F.Cu" "B.Cu")
		(net "GND")
	)
	(via
		(at 234.644692 -421.833548)
		(size 0.508)
		(drill 0.254)
		(layers "F.Cu" "B.Cu")
		(net "GND")
	)
	(via
		(at 212.799168 -21.637244)
		(size 0.508)
		(drill 0.254)
		(layers "F.Cu" "B.Cu")
		(net "GND")
	)
	(via
		(at 235.0008 -282.052522)
		(size 0.508)
		(drill 0.254)
		(layers "F.Cu" "B.Cu")
		(net "GND")
	)
	(via
		(at 93.751146 -283.806392)
		(size 0.4064)
		(drill 0.2032)
		(layers "F.Cu" "B.Cu")
		(net "GND")
	)
	(via
		(at 384.624834 -224.234248)
		(size 0.4064)
		(drill 0.2032)
		(layers "F.Cu" "B.Cu")
		(net "GND")
	)
	(via
		(at 153.146252 -388.328662)
		(size 0.4064)
		(drill 0.2032)
		(layers "F.Cu" "B.Cu")
		(net "GND")
	)
	(via
		(at 113.184686 -235.574332)
		(size 0.4064)
		(drill 0.2032)
		(layers "F.Cu" "B.Cu")
		(net "GND")
	)
	(via
		(at 416.29711 -0.762254)
		(size 0.508)
		(drill 0.254)
		(layers "F.Cu" "B.Cu")
		(net "GND")
	)
	(via
		(at 191.673734 -18.938748)
		(size 0.508)
		(drill 0.254)
		(layers "F.Cu" "B.Cu")
		(net "GND")
	)
	(via
		(at 376.634756 -226.664266)
		(size 0.4064)
		(drill 0.2032)
		(layers "F.Cu" "B.Cu")
		(net "GND")
	)
	(via
		(at 76.643738 -30.853126)
		(size 0.508)
		(drill 0.254)
		(layers "F.Cu" "B.Cu")
		(net "GND")
	)
	(via
		(at 69.767958 -333.060802)
		(size 0.49022)
		(drill 0.254)
		(layers "F.Cu" "B.Cu")
		(net "GND")
	)
	(via
		(at 391.866374 -416.020504)
		(size 0.4572)
		(drill 0.254)
		(layers "F.Cu" "B.Cu")
		(net "GND")
	)
	(via
		(at 94.5769 -427.554136)
		(size 0.508)
		(drill 0.254)
		(layers "F.Cu" "B.Cu")
		(net "GND")
	)
	(via
		(at 327.761092 -233.14406)
		(size 0.4064)
		(drill 0.2032)
		(layers "F.Cu" "B.Cu")
		(net "GND")
	)
	(via
		(at 75.650852 -154.83459)
		(size 0.508)
		(drill 0.254)
		(layers "F.Cu" "B.Cu")
		(net "GND")
	)
	(via
		(at 357.371142 -250.154186)
		(size 0.4064)
		(drill 0.2032)
		(layers "F.Cu" "B.Cu")
		(net "GND")
	)
	(via
		(at 350.321118 -231.524048)
		(size 0.4064)
		(drill 0.2032)
		(layers "F.Cu" "B.Cu")
		(net "GND")
	)
	(via
		(at 427.499272 -4.32943)
		(size 0.508)
		(drill 0.254)
		(layers "F.Cu" "B.Cu")
		(net "GND")
	)
	(via
		(at 34.080196 -203.285344)
		(size 0.4826)
		(drill 0.254)
		(layers "F.Cu" "B.Cu")
		(net "GND")
	)
	(via
		(at 174.11319 -427.293786)
		(size 0.508)
		(drill 0.254)
		(layers "F.Cu" "B.Cu")
		(net "GND")
	)
	(via
		(at 87.190072 -384.617722)
		(size 0.4064)
		(drill 0.2032)
		(layers "F.Cu" "B.Cu")
		(net "GND")
	)
	(via
		(at 42.058336 -12.37488)
		(size 0.508)
		(drill 0.254)
		(layers "F.Cu" "B.Cu")
		(net "GND")
	)
	(via
		(at 35.7632 -112.24768)
		(size 0.508)
		(drill 0.254)
		(layers "F.Cu" "B.Cu")
		(net "GND")
	)
	(via
		(at 138.864848 -277.326344)
		(size 0.4064)
		(drill 0.2032)
		(layers "F.Cu" "B.Cu")
		(net "GND")
	)
	(via
		(at 268.530578 -210.51012)
		(size 0.4826)
		(drill 0.254)
		(layers "F.Cu" "B.Cu")
		(net "GND")
	)
	(via
		(at 420.386764 -19.137122)
		(size 0.508)
		(drill 0.254)
		(layers "F.Cu" "B.Cu")
		(net "GND")
	)
	(via
		(at 194.38239 -70.198996)
		(size 0.508)
		(drill 0.254)
		(layers "F.Cu" "B.Cu")
		(net "GND")
	)
	(via
		(at 36.621974 -347.287088)
		(size 0.49022)
		(drill 0.254)
		(layers "F.Cu" "B.Cu")
		(net "GND")
	)
	(via
		(at 457.943966 -97.864422)
		(size 0.508)
		(drill 0.254)
		(layers "F.Cu" "B.Cu")
		(net "GND")
	)
	(via
		(at 382.379474 -183.893968)
		(size 0.49022)
		(drill 0.254)
		(layers "F.Cu" "B.Cu")
		(net "GND")
	)
	(via
		(at 347.97111 -251.774198)
		(size 0.4064)
		(drill 0.2032)
		(layers "F.Cu" "B.Cu")
		(net "GND")
	)
	(via
		(at 339.811106 -270.846042)
		(size 0.4064)
		(drill 0.2032)
		(layers "F.Cu" "B.Cu")
		(net "GND")
	)
	(via
		(at 52.902358 -346.322142)
		(size 0.49022)
		(drill 0.254)
		(layers "F.Cu" "B.Cu")
		(net "GND")
	)
	(via
		(at 134.349744 -427.851316)
		(size 0.4572)
		(drill 0.2032)
		(layers "F.Cu" "B.Cu")
		(net "GND")
	)
	(via
		(at 276.074632 -219.860114)
		(size 0.4826)
		(drill 0.254)
		(layers "F.Cu" "B.Cu")
		(net "GND")
	)
	(via
		(at 314.178188 -394.831062)
		(size 0.4064)
		(drill 0.2032)
		(layers "F.Cu" "B.Cu")
		(net "GND")
	)
	(via
		(at 308.120288 -427.456346)
		(size 0.508)
		(drill 0.254)
		(layers "F.Cu" "B.Cu")
		(net "GND")
	)
	(via
		(at 372.234714 -278.136096)
		(size 0.4064)
		(drill 0.2032)
		(layers "F.Cu" "B.Cu")
		(net "GND")
	)
	(via
		(at 110.848394 -187.634118)
		(size 0.508)
		(drill 0.254)
		(layers "F.Cu" "B.Cu")
		(net "GND")
	)
	(via
		(at 350.321118 -233.14406)
		(size 0.4064)
		(drill 0.2032)
		(layers "F.Cu" "B.Cu")
		(net "GND")
	)
	(via
		(at 365.654844 -266.796012)
		(size 0.4064)
		(drill 0.2032)
		(layers "F.Cu" "B.Cu")
		(net "GND")
	)
	(via
		(at 419.912038 -250.884944)
		(size 0.4826)
		(drill 0.254)
		(layers "F.Cu" "B.Cu")
		(net "GND")
	)
	(via
		(at 128.208278 -413.204152)
		(size 0.4572)
		(drill 0.254)
		(layers "F.Cu" "B.Cu")
		(net "GND")
	)
	(via
		(at 332.931008 -242.054126)
		(size 0.4064)
		(drill 0.2032)
		(layers "F.Cu" "B.Cu")
		(net "GND")
	)
	(via
		(at 269.648178 -241.53495)
		(size 0.4826)
		(drill 0.254)
		(layers "F.Cu" "B.Cu")
		(net "GND")
	)
	(via
		(at 389.762492 -377.41733)
		(size 0.508)
		(drill 0.254)
		(layers "F.Cu" "B.Cu")
		(net "GND")
	)
	(via
		(at 421.029638 -295.510204)
		(size 0.4826)
		(drill 0.254)
		(layers "F.Cu" "B.Cu")
		(net "GND")
	)
	(via
		(at 310.411876 -72.884792)
		(size 0.508)
		(drill 0.254)
		(layers "F.Cu" "B.Cu")
		(net "GND")
	)
	(via
		(at 27.84729 -386.882132)
		(size 0.49022)
		(drill 0.254)
		(layers "F.Cu" "B.Cu")
		(net "GND")
	)
	(via
		(at 82.265266 -183.14289)
		(size 0.49022)
		(drill 0.254)
		(layers "F.Cu" "B.Cu")
		(net "GND")
	)
	(via
		(at 431.55616 -235.585)
		(size 0.4826)
		(drill 0.254)
		(layers "F.Cu" "B.Cu")
		(net "GND")
	)
	(via
		(at 41.39565 -192.218564)
		(size 0.4826)
		(drill 0.254)
		(layers "F.Cu" "B.Cu")
		(net "GND")
	)
	(via
		(at 442.5442 -317.18504)
		(size 0.4826)
		(drill 0.254)
		(layers "F.Cu" "B.Cu")
		(net "GND")
	)
	(via
		(at 111.508794 -188.954918)
		(size 0.508)
		(drill 0.254)
		(layers "F.Cu" "B.Cu")
		(net "GND")
	)
	(via
		(at 388.68477 -280.566114)
		(size 0.4064)
		(drill 0.2032)
		(layers "F.Cu" "B.Cu")
		(net "GND")
	)
	(via
		(at 303.268126 -249.185176)
		(size 0.4826)
		(drill 0.254)
		(layers "F.Cu" "B.Cu")
		(net "GND")
	)
	(via
		(at 148.34616 -388.328662)
		(size 0.4064)
		(drill 0.2032)
		(layers "F.Cu" "B.Cu")
		(net "GND")
	)
	(via
		(at 330.731876 -75.708764)
		(size 0.508)
		(drill 0.254)
		(layers "F.Cu" "B.Cu")
		(net "GND")
	)
	(via
		(at 416.372294 -419.046152)
		(size 0.4572)
		(drill 0.254)
		(layers "F.Cu" "B.Cu")
		(net "GND")
	)
	(via
		(at 361.894882 -287.856168)
		(size 0.4064)
		(drill 0.2032)
		(layers "F.Cu" "B.Cu")
		(net "GND")
	)
	(via
		(at 117.961156 -370.83873)
		(size 0.508)
		(drill 0.254)
		(layers "F.Cu" "B.Cu")
		(net "GND")
	)
	(via
		(at 146.554698 -225.044508)
		(size 0.4064)
		(drill 0.2032)
		(layers "F.Cu" "B.Cu")
		(net "GND")
	)
	(via
		(at 266.93241 -294.235124)
		(size 0.4826)
		(drill 0.254)
		(layers "F.Cu" "B.Cu")
		(net "GND")
	)
	(via
		(at 338.401152 -270.036036)
		(size 0.4064)
		(drill 0.2032)
		(layers "F.Cu" "B.Cu")
		(net "GND")
	)
	(via
		(at 130.574796 -255.824482)
		(size 0.4064)
		(drill 0.2032)
		(layers "F.Cu" "B.Cu")
		(net "GND")
	)
	(via
		(at 291.164264 -418.953188)
		(size 0.508)
		(drill 0.254)
		(layers "F.Cu" "B.Cu")
		(net "GND")
	)
	(via
		(at 412.367984 -252.584966)
		(size 0.4826)
		(drill 0.254)
		(layers "F.Cu" "B.Cu")
		(net "GND")
	)
	(via
		(at 153.349706 -433.747164)
		(size 0.4572)
		(drill 0.2032)
		(layers "F.Cu" "B.Cu")
		(net "GND")
	)
	(via
		(at 420.399464 -4.963414)
		(size 0.508)
		(drill 0.254)
		(layers "F.Cu" "B.Cu")
		(net "GND")
	)
	(via
		(at 182.231792 -286.585406)
		(size 0.4826)
		(drill 0.254)
		(layers "F.Cu" "B.Cu")
		(net "GND")
	)
	(via
		(at 71.249794 -427.851316)
		(size 0.4572)
		(drill 0.2032)
		(layers "F.Cu" "B.Cu")
		(net "GND")
	)
	(via
		(at 393.222226 -191.727328)
		(size 0.508)
		(drill 0.254)
		(layers "F.Cu" "B.Cu")
		(net "GND")
	)
	(via
		(at 98.451162 -291.906198)
		(size 0.4064)
		(drill 0.2032)
		(layers "F.Cu" "B.Cu")
		(net "GND")
	)
	(via
		(at 381.192278 -136.509252)
		(size 0.508)
		(drill 0.254)
		(layers "F.Cu" "B.Cu")
		(net "GND")
	)
	(via
		(at 392.497818 -397.274542)
		(size 0.508)
		(drill 0.254)
		(layers "F.Cu" "B.Cu")
		(net "GND")
	)
	(via
		(at 25.969722 -427.294802)
		(size 0.508)
		(drill 0.254)
		(layers "F.Cu" "B.Cu")
		(net "GND")
	)
	(via
		(at 405.468074 -170.53306)
		(size 0.49022)
		(drill 0.254)
		(layers "F.Cu" "B.Cu")
		(net "GND")
	)
	(via
		(at 269.648178 -224.534984)
		(size 0.4826)
		(drill 0.254)
		(layers "F.Cu" "B.Cu")
		(net "GND")
	)
	(via
		(at 99.015296 -423.44848)
		(size 0.508)
		(drill 0.254)
		(layers "F.Cu" "B.Cu")
		(net "GND")
	)
	(via
		(at 72.188324 -407.00452)
		(size 0.4064)
		(drill 0.2032)
		(layers "F.Cu" "B.Cu")
		(net "GND")
	)
	(via
		(at 17.608042 -283.185362)
		(size 0.4826)
		(drill 0.254)
		(layers "F.Cu" "B.Cu")
		(net "GND")
	)
	(via
		(at 189.775846 -209.235294)
		(size 0.4826)
		(drill 0.254)
		(layers "F.Cu" "B.Cu")
		(net "GND")
	)
	(via
		(at 393.384786 -290.285932)
		(size 0.4064)
		(drill 0.2032)
		(layers "F.Cu" "B.Cu")
		(net "GND")
	)
	(via
		(at 41.8211 -391.2235)
		(size 0.508)
		(drill 0.254)
		(layers "F.Cu" "B.Cu")
		(net "GND")
	)
	(via
		(at 49.876964 -422.864534)
		(size 0.508)
		(drill 0.254)
		(layers "F.Cu" "B.Cu")
		(net "GND")
	)
	(via
		(at 94.861126 -231.524302)
		(size 0.4064)
		(drill 0.2032)
		(layers "F.Cu" "B.Cu")
		(net "GND")
	)
	(via
		(at 136.214866 -249.344434)
		(size 0.4064)
		(drill 0.2032)
		(layers "F.Cu" "B.Cu")
		(net "GND")
	)
	(via
		(at 199.65162 -332.805786)
		(size 0.508)
		(drill 0.254)
		(layers "F.Cu" "B.Cu")
		(net "GND")
	)
	(via
		(at 120.70461 -251.774452)
		(size 0.4064)
		(drill 0.2032)
		(layers "F.Cu" "B.Cu")
		(net "GND")
	)
	(via
		(at 365.380778 -262.18007)
		(size 0.4826)
		(drill 0.254)
		(layers "F.Cu" "B.Cu")
		(net "GND")
	)
	(via
		(at 191.160146 -263.635236)
		(size 0.4826)
		(drill 0.254)
		(layers "F.Cu" "B.Cu")
		(net "GND")
	)
	(via
		(at 349.851218 -253.39421)
		(size 0.4064)
		(drill 0.2032)
		(layers "F.Cu" "B.Cu")
		(net "GND")
	)
	(via
		(at 26.536396 -212.635338)
		(size 0.4826)
		(drill 0.254)
		(layers "F.Cu" "B.Cu")
		(net "GND")
	)
	(via
		(at 395.114272 -4.32943)
		(size 0.508)
		(drill 0.254)
		(layers "F.Cu" "B.Cu")
		(net "GND")
	)
	(via
		(at 303.575466 -344.767408)
		(size 0.508)
		(drill 0.254)
		(layers "F.Cu" "B.Cu")
		(net "GND")
	)
	(via
		(at 166.977568 -413.546798)
		(size 0.508)
		(drill 0.254)
		(layers "F.Cu" "B.Cu")
		(net "GND")
	)
	(via
		(at 248.833132 -422.15181)
		(size 0.508)
		(drill 0.254)
		(layers "F.Cu" "B.Cu")
		(net "GND")
	)
	(via
		(at 94.690946 -293.52621)
		(size 0.4064)
		(drill 0.2032)
		(layers "F.Cu" "B.Cu")
		(net "GND")
	)
	(via
		(at 17.16405 -73.025)
		(size 0.508)
		(drill 0.254)
		(layers "F.Cu" "B.Cu")
		(net "GND")
	)
	(via
		(at 454.159366 -377.29287)
		(size 0.508)
		(drill 0.254)
		(layers "F.Cu" "B.Cu")
		(net "GND")
	)
	(via
		(at 62.773814 -374.62333)
		(size 0.508)
		(drill 0.254)
		(layers "F.Cu" "B.Cu")
		(net "GND")
	)
	(via
		(at 269.648178 -248.335038)
		(size 0.4826)
		(drill 0.254)
		(layers "F.Cu" "B.Cu")
		(net "GND")
	)
	(via
		(at 401.349718 -431.29962)
		(size 0.4572)
		(drill 0.2032)
		(layers "F.Cu" "B.Cu")
		(net "GND")
	)
	(via
		(at 328.061066 -261.935976)
		(size 0.4064)
		(drill 0.2032)
		(layers "F.Cu" "B.Cu")
		(net "GND")
	)
	(via
		(at 29.107384 -441.227718)
		(size 0.508)
		(drill 0.254)
		(layers "F.Cu" "B.Cu")
		(net "GND")
	)
	(via
		(at 404.104856 -169.772838)
		(size 0.49022)
		(drill 0.254)
		(layers "F.Cu" "B.Cu")
		(net "GND")
	)
	(via
		(at 44.340018 -272.98523)
		(size 0.4826)
		(drill 0.254)
		(layers "F.Cu" "B.Cu")
		(net "GND")
	)
	(via
		(at 139.288266 -410.030168)
		(size 0.4064)
		(drill 0.2032)
		(layers "F.Cu" "B.Cu")
		(net "GND")
	)
	(via
		(at 14.884908 -401.319238)
		(size 0.508)
		(drill 0.254)
		(layers "F.Cu" "B.Cu")
		(net "GND")
	)
	(via
		(at 325.207884 -335.554066)
		(size 0.49022)
		(drill 0.254)
		(layers "F.Cu" "B.Cu")
		(net "GND")
	)
	(via
		(at 151.34971 -429.147224)
		(size 0.4572)
		(drill 0.2032)
		(layers "F.Cu" "B.Cu")
		(net "GND")
	)
	(via
		(at 90.249756 -434.899562)
		(size 0.4572)
		(drill 0.2032)
		(layers "F.Cu" "B.Cu")
		(net "GND")
	)
	(via
		(at 233.707178 -318.704468)
		(size 0.508)
		(drill 0.254)
		(layers "F.Cu" "B.Cu")
		(net "GND")
	)
	(via
		(at 378.514864 -242.864132)
		(size 0.4064)
		(drill 0.2032)
		(layers "F.Cu" "B.Cu")
		(net "GND")
	)
	(via
		(at 439.100214 -288.285174)
		(size 0.4826)
		(drill 0.254)
		(layers "F.Cu" "B.Cu")
		(net "GND")
	)
	(via
		(at 391.504678 -264.365994)
		(size 0.4064)
		(drill 0.2032)
		(layers "F.Cu" "B.Cu")
		(net "GND")
	)
	(via
		(at 282.208986 -347.282262)
		(size 0.49022)
		(drill 0.254)
		(layers "F.Cu" "B.Cu")
		(net "GND")
	)
	(via
		(at 35.411664 -227.935282)
		(size 0.4826)
		(drill 0.254)
		(layers "F.Cu" "B.Cu")
		(net "GND")
	)
	(via
		(at 339.388704 -380.54153)
		(size 0.508)
		(drill 0.254)
		(layers "F.Cu" "B.Cu")
		(net "GND")
	)
	(via
		(at 159.201866 -412.570168)
		(size 0.4064)
		(drill 0.2032)
		(layers "F.Cu" "B.Cu")
		(net "GND")
	)
	(via
		(at 31.145734 -7.215124)
		(size 0.508)
		(drill 0.254)
		(layers "F.Cu" "B.Cu")
		(net "GND")
	)
	(via
		(at 276.074632 -210.51012)
		(size 0.4826)
		(drill 0.254)
		(layers "F.Cu" "B.Cu")
		(net "GND")
	)
	(via
		(at 406.690068 -392.999722)
		(size 0.4064)
		(drill 0.2032)
		(layers "F.Cu" "B.Cu")
		(net "GND")
	)
	(via
		(at 427.456092 -283.185108)
		(size 0.4826)
		(drill 0.254)
		(layers "F.Cu" "B.Cu")
		(net "GND")
	)
	(via
		(at 134.726172 -38.905434)
		(size 0.508)
		(drill 0.254)
		(layers "F.Cu" "B.Cu")
		(net "GND")
	)
	(via
		(at 101.27107 -262.746236)
		(size 0.4064)
		(drill 0.2032)
		(layers "F.Cu" "B.Cu")
		(net "GND")
	)
	(via
		(at 332.931008 -246.914162)
		(size 0.4064)
		(drill 0.2032)
		(layers "F.Cu" "B.Cu")
		(net "GND")
	)
	(via
		(at 467.5378 -267.259054)
		(size 0.508)
		(drill 0.254)
		(layers "F.Cu" "B.Cu")
		(net "GND")
	)
	(via
		(at 91.571064 -229.094538)
		(size 0.4064)
		(drill 0.2032)
		(layers "F.Cu" "B.Cu")
		(net "GND")
	)
	(via
		(at 332.88732 -362.01096)
		(size 0.508)
		(drill 0.254)
		(layers "F.Cu" "B.Cu")
		(net "GND")
	)
	(via
		(at 133.694678 -286.23641)
		(size 0.4064)
		(drill 0.2032)
		(layers "F.Cu" "B.Cu")
		(net "GND")
	)
	(via
		(at 133.694678 -268.416278)
		(size 0.4064)
		(drill 0.2032)
		(layers "F.Cu" "B.Cu")
		(net "GND")
	)
	(via
		(at 73.361296 -405.098504)
		(size 0.4572)
		(drill 0.254)
		(layers "F.Cu" "B.Cu")
		(net "GND")
	)
	(via
		(at 447.16319 -12.37488)
		(size 0.508)
		(drill 0.254)
		(layers "F.Cu" "B.Cu")
		(net "GND")
	)
	(via
		(at 278.254206 -433.963826)
		(size 0.508)
		(drill 0.254)
		(layers "F.Cu" "B.Cu")
		(net "GND")
	)
	(via
		(at 97.906332 -386.449062)
		(size 0.4064)
		(drill 0.2032)
		(layers "F.Cu" "B.Cu")
		(net "GND")
	)
	(via
		(at 431.6095 -4.963414)
		(size 0.508)
		(drill 0.254)
		(layers "F.Cu" "B.Cu")
		(net "GND")
	)
	(via
		(at 94.488 -212.816948)
		(size 0.508)
		(drill 0.254)
		(layers "F.Cu" "B.Cu")
		(net "GND")
	)
	(via
		(at 298.43984 -295.935146)
		(size 0.4826)
		(drill 0.254)
		(layers "F.Cu" "B.Cu")
		(net "GND")
	)
	(via
		(at 374.448832 -376.75693)
		(size 0.508)
		(drill 0.254)
		(layers "F.Cu" "B.Cu")
		(net "GND")
	)
	(via
		(at 57.578498 -132.703062)
		(size 0.508)
		(drill 0.254)
		(layers "F.Cu" "B.Cu")
		(net "GND")
	)
	(via
		(at 400.16938 -376.75693)
		(size 0.508)
		(drill 0.254)
		(layers "F.Cu" "B.Cu")
		(net "GND")
	)
	(via
		(at 133.394704 -242.864386)
		(size 0.4064)
		(drill 0.2032)
		(layers "F.Cu" "B.Cu")
		(net "GND")
	)
	(via
		(at 157.581854 -411.936184)
		(size 0.4572)
		(drill 0.254)
		(layers "F.Cu" "B.Cu")
		(net "GND")
	)
	(via
		(at 202.588876 -71.687182)
		(size 0.508)
		(drill 0.254)
		(layers "F.Cu" "B.Cu")
		(net "GND")
	)
	(via
		(at 347.506798 -311.860692)
		(size 0.508)
		(drill 0.254)
		(layers "F.Cu" "B.Cu")
		(net "GND")
	)
	(via
		(at 123.554236 -370.83873)
		(size 0.508)
		(drill 0.254)
		(layers "F.Cu" "B.Cu")
		(net "GND")
	)
	(via
		(at 46.666404 -276.81047)
		(size 0.4826)
		(drill 0.254)
		(layers "F.Cu" "B.Cu")
		(net "GND")
	)
	(via
		(at 401.32889 -413.480504)
		(size 0.4572)
		(drill 0.254)
		(layers "F.Cu" "B.Cu")
		(net "GND")
	)
	(via
		(at 124.294646 -274.896326)
		(size 0.4064)
		(drill 0.2032)
		(layers "F.Cu" "B.Cu")
		(net "GND")
	)
	(via
		(at 329.941174 -286.236156)
		(size 0.4064)
		(drill 0.2032)
		(layers "F.Cu" "B.Cu")
		(net "GND")
	)
	(via
		(at 385.154678 -141.050772)
		(size 0.508)
		(drill 0.254)
		(layers "F.Cu" "B.Cu")
		(net "GND")
	)
	(via
		(at 183.366664 -359.242106)
		(size 0.508)
		(drill 0.254)
		(layers "F.Cu" "B.Cu")
		(net "GND")
	)
	(via
		(at 248.689114 -317.942468)
		(size 0.508)
		(drill 0.254)
		(layers "F.Cu" "B.Cu")
		(net "GND")
	)
	(via
		(at 133.394704 -231.524302)
		(size 0.4064)
		(drill 0.2032)
		(layers "F.Cu" "B.Cu")
		(net "GND")
	)
	(via
		(at 400.732752 -396.67815)
		(size 0.4064)
		(drill 0.2032)
		(layers "F.Cu" "B.Cu")
		(net "GND")
	)
	(via
		(at 350.79051 -256.63271)
		(size 0.4064)
		(drill 0.2032)
		(layers "F.Cu" "B.Cu")
		(net "GND")
	)
	(via
		(at 105.500932 -281.376374)
		(size 0.4064)
		(drill 0.2032)
		(layers "F.Cu" "B.Cu")
		(net "GND")
	)
	(via
		(at 358.61117 -290.285932)
		(size 0.4064)
		(drill 0.2032)
		(layers "F.Cu" "B.Cu")
		(net "GND")
	)
	(via
		(at 457.211684 -24.623522)
		(size 0.6604)
		(drill 0.3302)
		(layers "F.Cu" "B.Cu")
		(net "GND")
	)
	(via
		(at 340.24951 -438.651396)
		(size 0.4572)
		(drill 0.2032)
		(layers "F.Cu" "B.Cu")
		(net "GND")
	)
	(via
		(at 392.627104 -19.771868)
		(size 0.508)
		(drill 0.254)
		(layers "F.Cu" "B.Cu")
		(net "GND")
	)
	(via
		(at 53.462428 -384.617722)
		(size 0.4064)
		(drill 0.2032)
		(layers "F.Cu" "B.Cu")
		(net "GND")
	)
	(via
		(at 424.012106 -267.035026)
		(size 0.4826)
		(drill 0.254)
		(layers "F.Cu" "B.Cu")
		(net "GND")
	)
	(via
		(at 417.585652 -219.860114)
		(size 0.4826)
		(drill 0.254)
		(layers "F.Cu" "B.Cu")
		(net "GND")
	)
	(via
		(at 99.861116 -276.516338)
		(size 0.4064)
		(drill 0.2032)
		(layers "F.Cu" "B.Cu")
		(net "GND")
	)
	(via
		(at 257.39471 -110.090204)
		(size 0.508)
		(drill 0.254)
		(layers "F.Cu" "B.Cu")
		(net "GND")
	)
	(via
		(at 372.234714 -274.896072)
		(size 0.4064)
		(drill 0.2032)
		(layers "F.Cu" "B.Cu")
		(net "GND")
	)
	(via
		(at 131.98475 -240.434368)
		(size 0.4064)
		(drill 0.2032)
		(layers "F.Cu" "B.Cu")
		(net "GND")
	)
	(via
		(at 29.252164 -272.98523)
		(size 0.4826)
		(drill 0.254)
		(layers "F.Cu" "B.Cu")
		(net "GND")
	)
	(via
		(at 292.280086 -216.885012)
		(size 0.4826)
		(drill 0.254)
		(layers "F.Cu" "B.Cu")
		(net "GND")
	)
	(via
		(at 376.634756 -252.584204)
		(size 0.4064)
		(drill 0.2032)
		(layers "F.Cu" "B.Cu")
		(net "GND")
	)
	(via
		(at 381.634746 -282.996132)
		(size 0.4064)
		(drill 0.2032)
		(layers "F.Cu" "B.Cu")
		(net "GND")
	)
	(via
		(at 133.350254 -10.733278)
		(size 0.508)
		(drill 0.254)
		(layers "F.Cu" "B.Cu")
		(net "GND")
	)
	(via
		(at 388.618476 -396.710662)
		(size 0.4064)
		(drill 0.2032)
		(layers "F.Cu" "B.Cu")
		(net "GND")
	)
	(via
		(at 334.341216 -225.044254)
		(size 0.4064)
		(drill 0.2032)
		(layers "F.Cu" "B.Cu")
		(net "GND")
	)
	(via
		(at 32.695896 -298.485306)
		(size 0.4826)
		(drill 0.254)
		(layers "F.Cu" "B.Cu")
		(net "GND")
	)
	(via
		(at 329.958192 -383.68986)
		(size 0.508)
		(drill 0.254)
		(layers "F.Cu" "B.Cu")
		(net "GND")
	)
	(via
		(at 100.331016 -267.606272)
		(size 0.4064)
		(drill 0.2032)
		(layers "F.Cu" "B.Cu")
		(net "GND")
	)
	(via
		(at 47.784004 -252.58522)
		(size 0.4826)
		(drill 0.254)
		(layers "F.Cu" "B.Cu")
		(net "GND")
	)
	(via
		(at 347.740478 -420.318184)
		(size 0.4572)
		(drill 0.254)
		(layers "F.Cu" "B.Cu")
		(net "GND")
	)
	(via
		(at 460.522066 -53.8099)
		(size 0.508)
		(drill 0.254)
		(layers "F.Cu" "B.Cu")
		(net "GND")
	)
	(via
		(at 388.21487 -265.176)
		(size 0.4064)
		(drill 0.2032)
		(layers "F.Cu" "B.Cu")
		(net "GND")
	)
	(via
		(at 107.847892 -264.36828)
		(size 0.4064)
		(drill 0.2032)
		(layers "F.Cu" "B.Cu")
		(net "GND")
	)
	(via
		(at 328.53122 -274.086066)
		(size 0.4064)
		(drill 0.2032)
		(layers "F.Cu" "B.Cu")
		(net "GND")
	)
	(via
		(at 303.268126 -301.885096)
		(size 0.4826)
		(drill 0.254)
		(layers "F.Cu" "B.Cu")
		(net "GND")
	)
	(via
		(at 355.791008 -288.66592)
		(size 0.4064)
		(drill 0.2032)
		(layers "F.Cu" "B.Cu")
		(net "GND")
	)
	(via
		(at 56.451754 -373.96293)
		(size 0.508)
		(drill 0.254)
		(layers "F.Cu" "B.Cu")
		(net "GND")
	)
	(via
		(at 125.788928 -50.169064)
		(size 0.508)
		(drill 0.254)
		(layers "F.Cu" "B.Cu")
		(net "GND")
	)
	(via
		(at 44.340018 -204.135228)
		(size 0.4826)
		(drill 0.254)
		(layers "F.Cu" "B.Cu")
		(net "GND")
	)
	(via
		(at 328.231246 -245.29415)
		(size 0.4064)
		(drill 0.2032)
		(layers "F.Cu" "B.Cu")
		(net "GND")
	)
	(via
		(at 374.448832 -378.07773)
		(size 0.508)
		(drill 0.254)
		(layers "F.Cu" "B.Cu")
		(net "GND")
	)
	(via
		(at 111.639096 -371.49913)
		(size 0.508)
		(drill 0.254)
		(layers "F.Cu" "B.Cu")
		(net "GND")
	)
	(via
		(at 66.288666 -170.867832)
		(size 0.49022)
		(drill 0.254)
		(layers "F.Cu" "B.Cu")
		(net "GND")
	)
	(via
		(at 85.290914 -264.366248)
		(size 0.4064)
		(drill 0.2032)
		(layers "F.Cu" "B.Cu")
		(net "GND")
	)
	(via
		(at 214.469218 -385.771136)
		(size 0.508)
		(drill 0.254)
		(layers "F.Cu" "B.Cu")
		(net "GND")
	)
	(via
		(at 341.691214 -293.525956)
		(size 0.4064)
		(drill 0.2032)
		(layers "F.Cu" "B.Cu")
		(net "GND")
	)
	(via
		(at 265.54811 -281.485086)
		(size 0.4826)
		(drill 0.254)
		(layers "F.Cu" "B.Cu")
		(net "GND")
	)
	(via
		(at 351.689416 -438.992772)
		(size 0.508)
		(drill 0.254)
		(layers "F.Cu" "B.Cu")
		(net "GND")
	)
	(via
		(at 292.280086 -291.684964)
		(size 0.4826)
		(drill 0.254)
		(layers "F.Cu" "B.Cu")
		(net "GND")
	)
	(via
		(at 106.611166 -240.434368)
		(size 0.4064)
		(drill 0.2032)
		(layers "F.Cu" "B.Cu")
		(net "GND")
	)
	(via
		(at 74.807064 -412.570168)
		(size 0.4064)
		(drill 0.2032)
		(layers "F.Cu" "B.Cu")
		(net "GND")
	)
	(via
		(at 397.992854 -417.778184)
		(size 0.4572)
		(drill 0.254)
		(layers "F.Cu" "B.Cu")
		(net "GND")
	)
	(via
		(at 80.940402 -334.578706)
		(size 0.49022)
		(drill 0.254)
		(layers "F.Cu" "B.Cu")
		(net "GND")
	)
	(via
		(at 114.23904 -126.29896)
		(size 0.508)
		(drill 0.254)
		(layers "F.Cu" "B.Cu")
		(net "GND")
	)
	(via
		(at 118.5164 -391.830814)
		(size 0.4064)
		(drill 0.2032)
		(layers "F.Cu" "B.Cu")
		(net "GND")
	)
	(via
		(at 450.088 -318.885062)
		(size 0.4826)
		(drill 0.254)
		(layers "F.Cu" "B.Cu")
		(net "GND")
	)
	(via
		(at 64.444372 -406.370536)
		(size 0.4572)
		(drill 0.254)
		(layers "F.Cu" "B.Cu")
		(net "GND")
	)
	(via
		(at 68.766436 -407.638504)
		(size 0.4572)
		(drill 0.254)
		(layers "F.Cu" "B.Cu")
		(net "GND")
	)
	(via
		(at 393.892024 -19.771868)
		(size 0.508)
		(drill 0.254)
		(layers "F.Cu" "B.Cu")
		(net "GND")
	)
	(via
		(at 436.578502 -342.5063)
		(size 0.508)
		(drill 0.254)
		(layers "F.Cu" "B.Cu")
		(net "GND")
	)
	(via
		(at 331.821028 -294.335962)
		(size 0.4064)
		(drill 0.2032)
		(layers "F.Cu" "B.Cu")
		(net "GND")
	)
	(via
		(at 90.461084 -278.13635)
		(size 0.4064)
		(drill 0.2032)
		(layers "F.Cu" "B.Cu")
		(net "GND")
	)
	(via
		(at 334.249522 -426.54728)
		(size 0.4572)
		(drill 0.2032)
		(layers "F.Cu" "B.Cu")
		(net "GND")
	)
	(via
		(at 137.717276 -375.917968)
		(size 0.508)
		(drill 0.254)
		(layers "F.Cu" "B.Cu")
		(net "GND")
	)
	(via
		(at 124.464826 -237.194344)
		(size 0.4064)
		(drill 0.2032)
		(layers "F.Cu" "B.Cu")
		(net "GND")
	)
	(via
		(at 274.476464 -238.13516)
		(size 0.4826)
		(drill 0.254)
		(layers "F.Cu" "B.Cu")
		(net "GND")
	)
	(via
		(at 19.392138 -19.771868)
		(size 0.508)
		(drill 0.254)
		(layers "F.Cu" "B.Cu")
		(net "GND")
	)
	(via
		(at 182.231792 -305.285394)
		(size 0.4826)
		(drill 0.254)
		(layers "F.Cu" "B.Cu")
		(net "GND")
	)
	(via
		(at 425.96562 -7.215124)
		(size 0.508)
		(drill 0.254)
		(layers "F.Cu" "B.Cu")
		(net "GND")
	)
	(via
		(at 354.551234 -237.19409)
		(size 0.4064)
		(drill 0.2032)
		(layers "F.Cu" "B.Cu")
		(net "GND")
	)
	(via
		(at 308.191154 -398.542002)
		(size 0.4064)
		(drill 0.2032)
		(layers "F.Cu" "B.Cu")
		(net "GND")
	)
	(via
		(at 191.160146 -198.185278)
		(size 0.4826)
		(drill 0.254)
		(layers "F.Cu" "B.Cu")
		(net "GND")
	)
	(via
		(at 419.912038 -317.18504)
		(size 0.4826)
		(drill 0.254)
		(layers "F.Cu" "B.Cu")
		(net "GND")
	)
	(via
		(at 115.678458 -386.449062)
		(size 0.4064)
		(drill 0.2032)
		(layers "F.Cu" "B.Cu")
		(net "GND")
	)
	(via
		(at 297.820842 -399.6055)
		(size 0.508)
		(drill 0.254)
		(layers "F.Cu" "B.Cu")
		(net "GND")
	)
	(via
		(at 123.135136 -258.830318)
		(size 0.4826)
		(drill 0.254)
		(layers "F.Cu" "B.Cu")
		(net "GND")
	)
	(via
		(at 393.384786 -262.745982)
		(size 0.4064)
		(drill 0.2032)
		(layers "F.Cu" "B.Cu")
		(net "GND")
	)
	(via
		(at 81.687162 -373.30253)
		(size 0.508)
		(drill 0.254)
		(layers "F.Cu" "B.Cu")
		(net "GND")
	)
	(via
		(at 55.328058 -247.485408)
		(size 0.4826)
		(drill 0.254)
		(layers "F.Cu" "B.Cu")
		(net "GND")
	)
	(via
		(at 118.844822 -78.395322)
		(size 0.508)
		(drill 0.254)
		(layers "F.Cu" "B.Cu")
		(net "GND")
	)
	(via
		(at 252.096524 -46.876462)
		(size 0.508)
		(drill 0.254)
		(layers "F.Cu" "B.Cu")
		(net "GND")
	)
	(via
		(at 153.075386 -404.46452)
		(size 0.4064)
		(drill 0.2032)
		(layers "F.Cu" "B.Cu")
		(net "GND")
	)
	(via
		(at 344.681048 -226.664266)
		(size 0.4064)
		(drill 0.2032)
		(layers "F.Cu" "B.Cu")
		(net "GND")
	)
	(via
		(at 193.591942 -31.470092)
		(size 0.508)
		(drill 0.254)
		(layers "F.Cu" "B.Cu")
		(net "GND")
	)
	(via
		(at 271.295876 -420.141146)
		(size 0.508)
		(drill 0.254)
		(layers "F.Cu" "B.Cu")
		(net "GND")
	)
	(via
		(at 299.82414 -232.184956)
		(size 0.4826)
		(drill 0.254)
		(layers "F.Cu" "B.Cu")
		(net "GND")
	)
	(via
		(at 81.378044 -410.030168)
		(size 0.4064)
		(drill 0.2032)
		(layers "F.Cu" "B.Cu")
		(net "GND")
	)
	(via
		(at 325.052944 -294.070024)
		(size 0.4064)
		(drill 0.2032)
		(layers "F.Cu" "B.Cu")
		(net "GND")
	)
	(via
		(at 331.521054 -226.664266)
		(size 0.4064)
		(drill 0.2032)
		(layers "F.Cu" "B.Cu")
		(net "GND")
	)
	(via
		(at 166.287704 -171.400724)
		(size 0.508)
		(drill 0.254)
		(layers "F.Cu" "B.Cu")
		(net "GND")
	)
	(via
		(at 277.192232 -207.535018)
		(size 0.4826)
		(drill 0.254)
		(layers "F.Cu" "B.Cu")
		(net "GND")
	)
	(via
		(at 336.22107 -225.044254)
		(size 0.4064)
		(drill 0.2032)
		(layers "F.Cu" "B.Cu")
		(net "GND")
	)
	(via
		(at 125.704854 -288.666174)
		(size 0.4064)
		(drill 0.2032)
		(layers "F.Cu" "B.Cu")
		(net "GND")
	)
	(via
		(at 387.914896 -246.104156)
		(size 0.4064)
		(drill 0.2032)
		(layers "F.Cu" "B.Cu")
		(net "GND")
	)
	(via
		(at 416.5092 -109.977428)
		(size 0.508)
		(drill 0.254)
		(layers "F.Cu" "B.Cu")
		(net "GND")
	)
	(via
		(at 59.849512 -403.830536)
		(size 0.4572)
		(drill 0.254)
		(layers "F.Cu" "B.Cu")
		(net "GND")
	)
	(via
		(at 361.424728 -285.42615)
		(size 0.4064)
		(drill 0.2032)
		(layers "F.Cu" "B.Cu")
		(net "GND")
	)
	(via
		(at 460.147924 -57.515252)
		(size 0.508)
		(drill 0.254)
		(layers "F.Cu" "B.Cu")
		(net "GND")
	)
	(via
		(at 331.351128 -282.186126)
		(size 0.4064)
		(drill 0.2032)
		(layers "F.Cu" "B.Cu")
		(net "GND")
	)
	(via
		(at 319.660524 -333.055976)
		(size 0.49022)
		(drill 0.254)
		(layers "F.Cu" "B.Cu")
		(net "GND")
	)
	(via
		(at 418.624512 -5.597398)
		(size 0.508)
		(drill 0.254)
		(layers "F.Cu" "B.Cu")
		(net "GND")
	)
	(via
		(at 246.35587 -291.228526)
		(size 0.508)
		(drill 0.254)
		(layers "F.Cu" "B.Cu")
		(net "GND")
	)
	(via
		(at 144.034764 -261.93623)
		(size 0.4064)
		(drill 0.2032)
		(layers "F.Cu" "B.Cu")
		(net "GND")
	)
	(via
		(at 430.669192 -349.990156)
		(size 0.49022)
		(drill 0.254)
		(layers "F.Cu" "B.Cu")
		(net "GND")
	)
	(via
		(at 96.571054 -280.566368)
		(size 0.4064)
		(drill 0.2032)
		(layers "F.Cu" "B.Cu")
		(net "GND")
	)
	(via
		(at 394.982954 -281.110182)
		(size 0.4064)
		(drill 0.2032)
		(layers "F.Cu" "B.Cu")
		(net "GND")
	)
	(via
		(at 149.844252 -391.830814)
		(size 0.4064)
		(drill 0.2032)
		(layers "F.Cu" "B.Cu")
		(net "GND")
	)
	(via
		(at 189.775846 -218.585288)
		(size 0.4826)
		(drill 0.254)
		(layers "F.Cu" "B.Cu")
		(net "GND")
	)
	(via
		(at 65.249806 -439.651394)
		(size 0.4572)
		(drill 0.2032)
		(layers "F.Cu" "B.Cu")
		(net "GND")
	)
	(via
		(at 415.083752 -295.935146)
		(size 0.4826)
		(drill 0.254)
		(layers "F.Cu" "B.Cu")
		(net "GND")
	)
	(via
		(at 295.724072 -208.385156)
		(size 0.4826)
		(drill 0.254)
		(layers "F.Cu" "B.Cu")
		(net "GND")
	)
	(via
		(at 58.665618 -10.16508)
		(size 0.508)
		(drill 0.254)
		(layers "F.Cu" "B.Cu")
		(net "GND")
	)
	(via
		(at 142.154656 -261.93623)
		(size 0.4064)
		(drill 0.2032)
		(layers "F.Cu" "B.Cu")
		(net "GND")
	)
	(via
		(at 444.07455 -54.972458)
		(size 0.508)
		(drill 0.254)
		(layers "F.Cu" "B.Cu")
		(net "GND")
	)
	(via
		(at 442.5442 -233.035094)
		(size 0.4826)
		(drill 0.254)
		(layers "F.Cu" "B.Cu")
		(net "GND")
	)
	(via
		(at 29.252164 -301.035212)
		(size 0.4826)
		(drill 0.254)
		(layers "F.Cu" "B.Cu")
		(net "GND")
	)
	(via
		(at 419.912038 -311.23509)
		(size 0.4826)
		(drill 0.254)
		(layers "F.Cu" "B.Cu")
		(net "GND")
	)
	(via
		(at 142.794736 -249.344434)
		(size 0.4064)
		(drill 0.2032)
		(layers "F.Cu" "B.Cu")
		(net "GND")
	)
	(via
		(at 79.399384 -441.227718)
		(size 0.508)
		(drill 0.254)
		(layers "F.Cu" "B.Cu")
		(net "GND")
	)
	(via
		(at 187.077096 -14.749526)
		(size 0.508)
		(drill 0.254)
		(layers "F.Cu" "B.Cu")
		(net "GND")
	)
	(via
		(at 394.929614 -414.752536)
		(size 0.4572)
		(drill 0.254)
		(layers "F.Cu" "B.Cu")
		(net "GND")
	)
	(via
		(at 411.777434 -421.586152)
		(size 0.4572)
		(drill 0.254)
		(layers "F.Cu" "B.Cu")
		(net "GND")
	)
	(via
		(at 143.73479 -241.244374)
		(size 0.4064)
		(drill 0.2032)
		(layers "F.Cu" "B.Cu")
		(net "GND")
	)
	(via
		(at 382.676654 -417.778184)
		(size 0.4572)
		(drill 0.254)
		(layers "F.Cu" "B.Cu")
		(net "GND")
	)
	(via
		(at 415.492692 -141.062456)
		(size 0.508)
		(drill 0.254)
		(layers "F.Cu" "B.Cu")
		(net "GND")
	)
	(via
		(at 406.97658 -378.07773)
		(size 0.508)
		(drill 0.254)
		(layers "F.Cu" "B.Cu")
		(net "GND")
	)
	(via
		(at 118.354856 -239.624362)
		(size 0.4064)
		(drill 0.2032)
		(layers "F.Cu" "B.Cu")
		(net "GND")
	)
	(via
		(at 192.277746 -275.960332)
		(size 0.4826)
		(drill 0.254)
		(layers "F.Cu" "B.Cu")
		(net "GND")
	)
	(via
		(at 133.30047 -155.965144)
		(size 0.49022)
		(drill 0.254)
		(layers "F.Cu" "B.Cu")
		(net "GND")
	)
	(via
		(at 401.041616 -183.22036)
		(size 0.508)
		(drill 0.254)
		(layers "F.Cu" "B.Cu")
		(net "GND")
	)
	(via
		(at 332.195678 -28.283662)
		(size 0.508)
		(drill 0.254)
		(layers "F.Cu" "B.Cu")
		(net "GND")
	)
	(via
		(at 181.192678 -389.943848)
		(size 0.508)
		(drill 0.254)
		(layers "F.Cu" "B.Cu")
		(net "GND")
	)
	(via
		(at 108.530644 -377.49226)
		(size 0.508)
		(drill 0.254)
		(layers "F.Cu" "B.Cu")
		(net "GND")
	)
	(via
		(at 83.88096 -289.47618)
		(size 0.4064)
		(drill 0.2032)
		(layers "F.Cu" "B.Cu")
		(net "GND")
	)
	(via
		(at 102.85095 -243.674392)
		(size 0.4064)
		(drill 0.2032)
		(layers "F.Cu" "B.Cu")
		(net "GND")
	)
	(via
		(at 284.736032 -263.634982)
		(size 0.4826)
		(drill 0.254)
		(layers "F.Cu" "B.Cu")
		(net "GND")
	)
	(via
		(at 329.941174 -263.555988)
		(size 0.4064)
		(drill 0.2032)
		(layers "F.Cu" "B.Cu")
		(net "GND")
	)
	(via
		(at 452.803768 -302.73498)
		(size 0.4826)
		(drill 0.254)
		(layers "F.Cu" "B.Cu")
		(net "GND")
	)
	(via
		(at 55.328058 -216.035382)
		(size 0.4826)
		(drill 0.254)
		(layers "F.Cu" "B.Cu")
		(net "GND")
	)
	(via
		(at 84.99094 -248.534428)
		(size 0.4064)
		(drill 0.2032)
		(layers "F.Cu" "B.Cu")
		(net "GND")
	)
	(via
		(at 92.026994 -328.159872)
		(size 0.508)
		(drill 0.254)
		(layers "F.Cu" "B.Cu")
		(net "GND")
	)
	(via
		(at 403.803104 -18.503138)
		(size 0.508)
		(drill 0.254)
		(layers "F.Cu" "B.Cu")
		(net "GND")
	)
	(via
		(at 89.989914 -331.73416)
		(size 0.508)
		(drill 0.254)
		(layers "F.Cu" "B.Cu")
		(net "GND")
	)
	(via
		(at 431.55616 -251.735082)
		(size 0.4826)
		(drill 0.254)
		(layers "F.Cu" "B.Cu")
		(net "GND")
	)
	(via
		(at 344.511122 -278.946102)
		(size 0.4064)
		(drill 0.2032)
		(layers "F.Cu" "B.Cu")
		(net "GND")
	)
	(via
		(at 337.686904 -383.00533)
		(size 0.508)
		(drill 0.254)
		(layers "F.Cu" "B.Cu")
		(net "GND")
	)
	(via
		(at 179.516024 -247.485408)
		(size 0.4826)
		(drill 0.254)
		(layers "F.Cu" "B.Cu")
		(net "GND")
	)
	(via
		(at 325.207884 -336.976466)
		(size 0.49022)
		(drill 0.254)
		(layers "F.Cu" "B.Cu")
		(net "GND")
	)
	(via
		(at 90.461084 -282.996386)
		(size 0.4064)
		(drill 0.2032)
		(layers "F.Cu" "B.Cu")
		(net "GND")
	)
	(via
		(at 187.060078 -309.535322)
		(size 0.4826)
		(drill 0.254)
		(layers "F.Cu" "B.Cu")
		(net "GND")
	)
	(via
		(at 362.238036 -256.387346)
		(size 0.4826)
		(drill 0.254)
		(layers "F.Cu" "B.Cu")
		(net "GND")
	)
	(via
		(at 88.24976 -435.0512)
		(size 0.4572)
		(drill 0.2032)
		(layers "F.Cu" "B.Cu")
		(net "GND")
	)
	(via
		(at 176.072038 -215.185244)
		(size 0.4826)
		(drill 0.254)
		(layers "F.Cu" "B.Cu")
		(net "GND")
	)
	(via
		(at 197.896734 -77.76337)
		(size 0.508)
		(drill 0.254)
		(layers "F.Cu" "B.Cu")
		(net "GND")
	)
	(via
		(at 121.874788 -165.605206)
		(size 0.49022)
		(drill 0.254)
		(layers "F.Cu" "B.Cu")
		(net "GND")
	)
	(via
		(at 133.394704 -236.384338)
		(size 0.4064)
		(drill 0.2032)
		(layers "F.Cu" "B.Cu")
		(net "GND")
	)
	(via
		(at 467.5378 -295.199054)
		(size 0.508)
		(drill 0.254)
		(layers "F.Cu" "B.Cu")
		(net "GND")
	)
	(via
		(at 99.055174 -257.930396)
		(size 0.4826)
		(drill 0.254)
		(layers "F.Cu" "B.Cu")
		(net "GND")
	)
	(via
		(at 116.13896 -413.893)
		(size 0.508)
		(drill 0.254)
		(layers "F.Cu" "B.Cu")
		(net "GND")
	)
	(via
		(at 279.518364 -276.810216)
		(size 0.4826)
		(drill 0.254)
		(layers "F.Cu" "B.Cu")
		(net "GND")
	)
	(via
		(at 403.317964 -19.13636)
		(size 0.508)
		(drill 0.254)
		(layers "F.Cu" "B.Cu")
		(net "GND")
	)
	(via
		(at 399.125694 -178.321208)
		(size 0.49022)
		(drill 0.254)
		(layers "F.Cu" "B.Cu")
		(net "GND")
	)
	(via
		(at 128.659636 -374.62333)
		(size 0.508)
		(drill 0.254)
		(layers "F.Cu" "B.Cu")
		(net "GND")
	)
	(via
		(at 105.031032 -269.226284)
		(size 0.4064)
		(drill 0.2032)
		(layers "F.Cu" "B.Cu")
		(net "GND")
	)
	(via
		(at 442.5442 -206.685134)
		(size 0.4826)
		(drill 0.254)
		(layers "F.Cu" "B.Cu")
		(net "GND")
	)
	(via
		(at 194.604132 -309.535322)
		(size 0.4826)
		(drill 0.254)
		(layers "F.Cu" "B.Cu")
		(net "GND")
	)
	(via
		(at 419.912038 -301.885096)
		(size 0.4826)
		(drill 0.254)
		(layers "F.Cu" "B.Cu")
		(net "GND")
	)
	(via
		(at 443.625732 -399.233644)
		(size 0.49022)
		(drill 0.254)
		(layers "F.Cu" "B.Cu")
		(net "GND")
	)
	(via
		(at 451.099936 -65.221866)
		(size 0.508)
		(drill 0.254)
		(layers "F.Cu" "B.Cu")
		(net "GND")
	)
	(via
		(at 295.886886 -339.822536)
		(size 0.508)
		(drill 0.254)
		(layers "F.Cu" "B.Cu")
		(net "GND")
	)
	(via
		(at 97.040954 -281.376374)
		(size 0.4064)
		(drill 0.2032)
		(layers "F.Cu" "B.Cu")
		(net "GND")
	)
	(via
		(at 227.611178 -318.704468)
		(size 0.508)
		(drill 0.254)
		(layers "F.Cu" "B.Cu")
		(net "GND")
	)
	(via
		(at 348.44101 -255.824228)
		(size 0.4064)
		(drill 0.2032)
		(layers "F.Cu" "B.Cu")
		(net "GND")
	)
	(via
		(at 49.128172 -406.370536)
		(size 0.4572)
		(drill 0.254)
		(layers "F.Cu" "B.Cu")
		(net "GND")
	)
	(via
		(at 139.202414 -413.204152)
		(size 0.4572)
		(drill 0.254)
		(layers "F.Cu" "B.Cu")
		(net "GND")
	)
	(via
		(at 181.407562 -46.957742)
		(size 0.508)
		(drill 0.254)
		(layers "F.Cu" "B.Cu")
		(net "GND")
	)
	(via
		(at 43.307 -112.12068)
		(size 0.508)
		(drill 0.254)
		(layers "F.Cu" "B.Cu")
		(net "GND")
	)
	(via
		(at 107.647994 -261.323074)
		(size 0.4826)
		(drill 0.254)
		(layers "F.Cu" "B.Cu")
		(net "GND")
	)
	(via
		(at 112.267238 -42.2656)
		(size 0.508)
		(drill 0.254)
		(layers "F.Cu" "B.Cu")
		(net "GND")
	)
	(via
		(at 206.248 -318.035432)
		(size 0.4826)
		(drill 0.254)
		(layers "F.Cu" "B.Cu")
		(net "GND")
	)
	(via
		(at 35.821112 -369.49507)
		(size 0.508)
		(drill 0.254)
		(layers "F.Cu" "B.Cu")
		(net "GND")
	)
	(via
		(at 89.989914 -331.07376)
		(size 0.508)
		(drill 0.254)
		(layers "F.Cu" "B.Cu")
		(net "GND")
	)
	(via
		(at 100.317554 -333.059786)
		(size 0.508)
		(drill 0.254)
		(layers "F.Cu" "B.Cu")
		(net "GND")
	)
	(via
		(at 167.143684 -277.235412)
		(size 0.4826)
		(drill 0.254)
		(layers "F.Cu" "B.Cu")
		(net "GND")
	)
	(via
		(at 442.208666 -400.78787)
		(size 0.508)
		(drill 0.254)
		(layers "F.Cu" "B.Cu")
		(net "GND")
	)
	(via
		(at 326.442324 -336.976466)
		(size 0.49022)
		(drill 0.254)
		(layers "F.Cu" "B.Cu")
		(net "GND")
	)
	(via
		(at 138.8872 -66.7512)
		(size 0.508)
		(drill 0.254)
		(layers "F.Cu" "B.Cu")
		(net "GND")
	)
	(via
		(at 174.771304 -330.861924)
		(size 0.508)
		(drill 0.254)
		(layers "F.Cu" "B.Cu")
		(net "GND")
	)
	(via
		(at 332.584044 -377.41733)
		(size 0.508)
		(drill 0.254)
		(layers "F.Cu" "B.Cu")
		(net "GND")
	)
	(via
		(at 182.278782 -349.356172)
		(size 0.49022)
		(drill 0.254)
		(layers "F.Cu" "B.Cu")
		(net "GND")
	)
	(via
		(at 95.786702 -373.96293)
		(size 0.508)
		(drill 0.254)
		(layers "F.Cu" "B.Cu")
		(net "GND")
	)
	(via
		(at 405.34971 -437.34736)
		(size 0.4572)
		(drill 0.2032)
		(layers "F.Cu" "B.Cu")
		(net "GND")
	)
	(via
		(at 320.26225 -392.999722)
		(size 0.4064)
		(drill 0.2032)
		(layers "F.Cu" "B.Cu")
		(net "GND")
	)
	(via
		(at 304.652426 -203.28509)
		(size 0.4826)
		(drill 0.254)
		(layers "F.Cu" "B.Cu")
		(net "GND")
	)
	(via
		(at 384.624834 -248.534174)
		(size 0.4064)
		(drill 0.2032)
		(layers "F.Cu" "B.Cu")
		(net "GND")
	)
	(via
		(at 427.456092 -311.23509)
		(size 0.4826)
		(drill 0.254)
		(layers "F.Cu" "B.Cu")
		(net "GND")
	)
	(via
		(at 150.618952 -390.160002)
		(size 0.4064)
		(drill 0.2032)
		(layers "F.Cu" "B.Cu")
		(net "GND")
	)
	(via
		(at 401.3835 -378.07773)
		(size 0.508)
		(drill 0.254)
		(layers "F.Cu" "B.Cu")
		(net "GND")
	)
	(via
		(at 326.211946 -415.38652)
		(size 0.4064)
		(drill 0.2032)
		(layers "F.Cu" "B.Cu")
		(net "GND")
	)
	(via
		(at 292.02761 -345.566238)
		(size 0.49022)
		(drill 0.254)
		(layers "F.Cu" "B.Cu")
		(net "GND")
	)
	(via
		(at 99.861116 -265.176254)
		(size 0.4064)
		(drill 0.2032)
		(layers "F.Cu" "B.Cu")
		(net "GND")
	)
	(via
		(at 134.726172 -36.873434)
		(size 0.508)
		(drill 0.254)
		(layers "F.Cu" "B.Cu")
		(net "GND")
	)
	(via
		(at 386.804916 -283.806138)
		(size 0.4064)
		(drill 0.2032)
		(layers "F.Cu" "B.Cu")
		(net "GND")
	)
	(via
		(at 191.873632 -424.784774)
		(size 0.508)
		(drill 0.254)
		(layers "F.Cu" "B.Cu")
		(net "GND")
	)
	(via
		(at 137.397998 -403.830536)
		(size 0.4572)
		(drill 0.254)
		(layers "F.Cu" "B.Cu")
		(net "GND")
	)
	(via
		(at 118.448836 -369.69573)
		(size 0.508)
		(drill 0.254)
		(layers "F.Cu" "B.Cu")
		(net "GND")
	)
	(via
		(at 174.687738 -237.285276)
		(size 0.4826)
		(drill 0.254)
		(layers "F.Cu" "B.Cu")
		(net "GND")
	)
	(via
		(at 78.41107 -229.094538)
		(size 0.4064)
		(drill 0.2032)
		(layers "F.Cu" "B.Cu")
		(net "GND")
	)
	(via
		(at 25.892506 -421.066468)
		(size 0.508)
		(drill 0.254)
		(layers "F.Cu" "B.Cu")
		(net "GND")
	)
	(via
		(at 336.854546 -12.542266)
		(size 0.508)
		(drill 0.254)
		(layers "F.Cu" "B.Cu")
		(net "GND")
	)
	(via
		(at 346.86113 -294.335962)
		(size 0.4064)
		(drill 0.2032)
		(layers "F.Cu" "B.Cu")
		(net "GND")
	)
	(via
		(at 300.118272 -351.858072)
		(size 0.508)
		(drill 0.254)
		(layers "F.Cu" "B.Cu")
		(net "GND")
	)
	(via
		(at 20.55241 -193.996564)
		(size 0.4826)
		(drill 0.254)
		(layers "F.Cu" "B.Cu")
		(net "GND")
	)
	(via
		(at 453.426576 -22.091142)
		(size 0.508)
		(drill 0.254)
		(layers "F.Cu" "B.Cu")
		(net "GND")
	)
	(via
		(at 264.43051 -220.709998)
		(size 0.4826)
		(drill 0.254)
		(layers "F.Cu" "B.Cu")
		(net "GND")
	)
	(via
		(at 47.784004 -244.085364)
		(size 0.4826)
		(drill 0.254)
		(layers "F.Cu" "B.Cu")
		(net "GND")
	)
	(via
		(at 133.864858 -256.634488)
		(size 0.4064)
		(drill 0.2032)
		(layers "F.Cu" "B.Cu")
		(net "GND")
	)
	(via
		(at 133.864858 -242.05438)
		(size 0.4064)
		(drill 0.2032)
		(layers "F.Cu" "B.Cu")
		(net "GND")
	)
	(via
		(at 383.68478 -222.614236)
		(size 0.4064)
		(drill 0.2032)
		(layers "F.Cu" "B.Cu")
		(net "GND")
	)
	(via
		(at 53.265832 -7.215124)
		(size 0.508)
		(drill 0.254)
		(layers "F.Cu" "B.Cu")
		(net "GND")
	)
	(via
		(at 145.144744 -248.534428)
		(size 0.4064)
		(drill 0.2032)
		(layers "F.Cu" "B.Cu")
		(net "GND")
	)
	(via
		(at 144.905222 -143.232124)
		(size 0.6604)
		(drill 0.3302)
		(layers "F.Cu" "B.Cu")
		(net "GND")
	)
	(via
		(at 61.249814 -428.851314)
		(size 0.4572)
		(drill 0.2032)
		(layers "F.Cu" "B.Cu")
		(net "GND")
	)
	(via
		(at 299.3136 -363.982)
		(size 0.508)
		(drill 0.254)
		(layers "F.Cu" "B.Cu")
		(net "GND")
	)
	(via
		(at 76.249784 -431.451258)
		(size 0.4572)
		(drill 0.2032)
		(layers "F.Cu" "B.Cu")
		(net "GND")
	)
	(via
		(at 379.924818 -230.714296)
		(size 0.4064)
		(drill 0.2032)
		(layers "F.Cu" "B.Cu")
		(net "GND")
	)
	(via
		(at 203.899008 -115.657376)
		(size 0.508)
		(drill 0.254)
		(layers "F.Cu" "B.Cu")
		(net "GND")
	)
	(via
		(at 424.918378 -363.201712)
		(size 0.508)
		(drill 0.254)
		(layers "F.Cu" "B.Cu")
		(net "GND")
	)
	(via
		(at 186.944254 -430.659286)
		(size 0.508)
		(drill 0.254)
		(layers "F.Cu" "B.Cu")
		(net "GND")
	)
	(via
		(at 275.163026 -348.704662)
		(size 0.49022)
		(drill 0.254)
		(layers "F.Cu" "B.Cu")
		(net "GND")
	)
	(via
		(at 369.114832 -241.24412)
		(size 0.4064)
		(drill 0.2032)
		(layers "F.Cu" "B.Cu")
		(net "GND")
	)
	(via
		(at 30.44317 -362.220256)
		(size 0.508)
		(drill 0.254)
		(layers "F.Cu" "B.Cu")
		(net "GND")
	)
	(via
		(at 27.814524 -5.597398)
		(size 0.508)
		(drill 0.254)
		(layers "F.Cu" "B.Cu")
		(net "GND")
	)
	(via
		(at 106.074718 -20.084542)
		(size 0.508)
		(drill 0.254)
		(layers "F.Cu" "B.Cu")
		(net "GND")
	)
	(via
		(at 399.317718 -175.182784)
		(size 0.49022)
		(drill 0.254)
		(layers "F.Cu" "B.Cu")
		(net "GND")
	)
	(via
		(at 352.345752 -337.99526)
		(size 0.49022)
		(drill 0.254)
		(layers "F.Cu" "B.Cu")
		(net "GND")
	)
	(via
		(at 90.461084 -286.23641)
		(size 0.4064)
		(drill 0.2032)
		(layers "F.Cu" "B.Cu")
		(net "GND")
	)
	(via
		(at 426.24502 -388.917688)
		(size 0.508)
		(drill 0.254)
		(layers "F.Cu" "B.Cu")
		(net "GND")
	)
	(via
		(at 389.154924 -294.335962)
		(size 0.4064)
		(drill 0.2032)
		(layers "F.Cu" "B.Cu")
		(net "GND")
	)
	(via
		(at 412.367984 -244.08511)
		(size 0.4826)
		(drill 0.254)
		(layers "F.Cu" "B.Cu")
		(net "GND")
	)
	(via
		(at 80.291178 -245.294404)
		(size 0.4064)
		(drill 0.2032)
		(layers "F.Cu" "B.Cu")
		(net "GND")
	)
	(via
		(at 304.652426 -315.485018)
		(size 0.4826)
		(drill 0.254)
		(layers "F.Cu" "B.Cu")
		(net "GND")
	)
	(via
		(at 445.779652 -395.284452)
		(size 0.49022)
		(drill 0.254)
		(layers "F.Cu" "B.Cu")
		(net "GND")
	)
	(via
		(at 335.6102 -163.322)
		(size 0.508)
		(drill 0.254)
		(layers "F.Cu" "B.Cu")
		(net "GND")
	)
	(via
		(at 435.000146 -204.985112)
		(size 0.4826)
		(drill 0.254)
		(layers "F.Cu" "B.Cu")
		(net "GND")
	)
	(via
		(at 363.474762 -226.664266)
		(size 0.4064)
		(drill 0.2032)
		(layers "F.Cu" "B.Cu")
		(net "GND")
	)
	(via
		(at 173.35627 -315.485272)
		(size 0.4826)
		(drill 0.254)
		(layers "F.Cu" "B.Cu")
		(net "GND")
	)
	(via
		(at 64.260984 -7.20471)
		(size 0.508)
		(drill 0.254)
		(layers "F.Cu" "B.Cu")
		(net "GND")
	)
	(via
		(at 300.541436 -378.07773)
		(size 0.508)
		(drill 0.254)
		(layers "F.Cu" "B.Cu")
		(net "GND")
	)
	(via
		(at 110.371128 -225.854514)
		(size 0.4064)
		(drill 0.2032)
		(layers "F.Cu" "B.Cu")
		(net "GND")
	)
	(via
		(at 49.168304 -294.235378)
		(size 0.4826)
		(drill 0.254)
		(layers "F.Cu" "B.Cu")
		(net "GND")
	)
	(via
		(at 187.01512 -350.41332)
		(size 0.49022)
		(drill 0.254)
		(layers "F.Cu" "B.Cu")
		(net "GND")
	)
	(via
		(at 407.182574 -419.046152)
		(size 0.4572)
		(drill 0.254)
		(layers "F.Cu" "B.Cu")
		(net "GND")
	)
	(via
		(at 385.394708 -284.616144)
		(size 0.4064)
		(drill 0.2032)
		(layers "F.Cu" "B.Cu")
		(net "GND")
	)
	(via
		(at 140.274802 -265.176254)
		(size 0.4064)
		(drill 0.2032)
		(layers "F.Cu" "B.Cu")
		(net "GND")
	)
	(via
		(at 341.22106 -291.095938)
		(size 0.4064)
		(drill 0.2032)
		(layers "F.Cu" "B.Cu")
		(net "GND")
	)
	(via
		(at 373.174768 -294.335962)
		(size 0.4064)
		(drill 0.2032)
		(layers "F.Cu" "B.Cu")
		(net "GND")
	)
	(via
		(at 233.016044 -44.958)
		(size 0.508)
		(drill 0.254)
		(layers "F.Cu" "B.Cu")
		(net "GND")
	)
	(via
		(at 190.312294 -413.564832)
		(size 0.508)
		(drill 0.254)
		(layers "F.Cu" "B.Cu")
		(net "GND")
	)
	(via
		(at 82.001106 -287.856422)
		(size 0.4064)
		(drill 0.2032)
		(layers "F.Cu" "B.Cu")
		(net "GND")
	)
	(via
		(at 443.9285 -312.935112)
		(size 0.4826)
		(drill 0.254)
		(layers "F.Cu" "B.Cu")
		(net "GND")
	)
	(via
		(at 332.931008 -235.574078)
		(size 0.4064)
		(drill 0.2032)
		(layers "F.Cu" "B.Cu")
		(net "GND")
	)
	(via
		(at 361.124754 -248.534174)
		(size 0.4064)
		(drill 0.2032)
		(layers "F.Cu" "B.Cu")
		(net "GND")
	)
	(via
		(at 116.944648 -237.194344)
		(size 0.4064)
		(drill 0.2032)
		(layers "F.Cu" "B.Cu")
		(net "GND")
	)
	(via
		(at 344.511122 -280.566114)
		(size 0.4064)
		(drill 0.2032)
		(layers "F.Cu" "B.Cu")
		(net "GND")
	)
	(via
		(at 182.231792 -284.035246)
		(size 0.4826)
		(drill 0.254)
		(layers "F.Cu" "B.Cu")
		(net "GND")
	)
	(via
		(at 96.571054 -265.98626)
		(size 0.4064)
		(drill 0.2032)
		(layers "F.Cu" "B.Cu")
		(net "GND")
	)
	(via
		(at 134.386066 -158.470346)
		(size 0.49022)
		(drill 0.254)
		(layers "F.Cu" "B.Cu")
		(net "GND")
	)
	(via
		(at 145.144744 -253.394464)
		(size 0.4064)
		(drill 0.2032)
		(layers "F.Cu" "B.Cu")
		(net "GND")
	)
	(via
		(at 131.98475 -235.574332)
		(size 0.4064)
		(drill 0.2032)
		(layers "F.Cu" "B.Cu")
		(net "GND")
	)
	(via
		(at 49.168304 -238.135414)
		(size 0.4826)
		(drill 0.254)
		(layers "F.Cu" "B.Cu")
		(net "GND")
	)
	(via
		(at 265.54811 -249.185176)
		(size 0.4826)
		(drill 0.254)
		(layers "F.Cu" "B.Cu")
		(net "GND")
	)
	(via
		(at 416.31997 -6.598158)
		(size 0.508)
		(drill 0.254)
		(layers "F.Cu" "B.Cu")
		(net "GND")
	)
	(via
		(at 114.59464 -236.384338)
		(size 0.4064)
		(drill 0.2032)
		(layers "F.Cu" "B.Cu")
		(net "GND")
	)
	(via
		(at 410.64434 -400.212814)
		(size 0.4064)
		(drill 0.2032)
		(layers "F.Cu" "B.Cu")
		(net "GND")
	)
	(via
		(at 137.154666 -247.724422)
		(size 0.4064)
		(drill 0.2032)
		(layers "F.Cu" "B.Cu")
		(net "GND")
	)
	(via
		(at 471.037666 -39.233094)
		(size 0.508)
		(drill 0.254)
		(layers "F.Cu" "B.Cu")
		(net "GND")
	)
	(via
		(at 427.456092 -223.6851)
		(size 0.4826)
		(drill 0.254)
		(layers "F.Cu" "B.Cu")
		(net "GND")
	)
	(via
		(at 51.884072 -297.635422)
		(size 0.4826)
		(drill 0.254)
		(layers "F.Cu" "B.Cu")
		(net "GND")
	)
	(via
		(at 131.109466 -158.470346)
		(size 0.49022)
		(drill 0.254)
		(layers "F.Cu" "B.Cu")
		(net "GND")
	)
	(via
		(at 91.983306 -183.825896)
		(size 0.49022)
		(drill 0.254)
		(layers "F.Cu" "B.Cu")
		(net "GND")
	)
	(via
		(at 393.045696 -10.16508)
		(size 0.508)
		(drill 0.254)
		(layers "F.Cu" "B.Cu")
		(net "GND")
	)
	(via
		(at 333.757524 -333.823564)
		(size 0.49022)
		(drill 0.254)
		(layers "F.Cu" "B.Cu")
		(net "GND")
	)
	(via
		(at 67.201796 -40.438324)
		(size 0.508)
		(drill 0.254)
		(layers "F.Cu" "B.Cu")
		(net "GND")
	)
	(via
		(at 125.256036 -368.37493)
		(size 0.508)
		(drill 0.254)
		(layers "F.Cu" "B.Cu")
		(net "GND")
	)
	(via
		(at 132.916422 -391.830814)
		(size 0.4064)
		(drill 0.2032)
		(layers "F.Cu" "B.Cu")
		(net "GND")
	)
	(via
		(at 405.92375 -416.020504)
		(size 0.4572)
		(drill 0.254)
		(layers "F.Cu" "B.Cu")
		(net "GND")
	)
	(via
		(at 393.397994 -421.586152)
		(size 0.4572)
		(drill 0.254)
		(layers "F.Cu" "B.Cu")
		(net "GND")
	)
	(via
		(at 415.170874 -164.917882)
		(size 0.49022)
		(drill 0.254)
		(layers "F.Cu" "B.Cu")
		(net "GND")
	)
	(via
		(at 295.724072 -290.83508)
		(size 0.4826)
		(drill 0.254)
		(layers "F.Cu" "B.Cu")
		(net "GND")
	)
	(via
		(at 117.647466 -173.862746)
		(size 0.49022)
		(drill 0.254)
		(layers "F.Cu" "B.Cu")
		(net "GND")
	)
	(via
		(at 306.298346 -412.84652)
		(size 0.4064)
		(drill 0.2032)
		(layers "F.Cu" "B.Cu")
		(net "GND")
	)
	(via
		(at 271.974564 -239.41024)
		(size 0.4826)
		(drill 0.254)
		(layers "F.Cu" "B.Cu")
		(net "GND")
	)
	(via
		(at 332.249526 -438.651396)
		(size 0.4572)
		(drill 0.2032)
		(layers "F.Cu" "B.Cu")
		(net "GND")
	)
	(via
		(at 32.955484 -402.793454)
		(size 0.508)
		(drill 0.254)
		(layers "F.Cu" "B.Cu")
		(net "GND")
	)
	(via
		(at 424.012106 -318.035178)
		(size 0.4826)
		(drill 0.254)
		(layers "F.Cu" "B.Cu")
		(net "GND")
	)
	(via
		(at 372.43004 -425.48937)
		(size 0.508)
		(drill 0.254)
		(layers "F.Cu" "B.Cu")
		(net "GND")
	)
	(via
		(at 246.105426 -281.730958)
		(size 0.508)
		(drill 0.254)
		(layers "F.Cu" "B.Cu")
		(net "GND")
	)
	(via
		(at 2.76225 -98.989134)
		(size 0.508)
		(drill 0.254)
		(layers "F.Cu" "B.Cu")
		(net "GND")
	)
	(via
		(at 94.31909 -390.160002)
		(size 0.4064)
		(drill 0.2032)
		(layers "F.Cu" "B.Cu")
		(net "GND")
	)
	(via
		(at 221.966536 -115.159282)
		(size 0.508)
		(drill 0.254)
		(layers "F.Cu" "B.Cu")
		(net "GND")
	)
	(via
		(at 350.389952 -392.999722)
		(size 0.4064)
		(drill 0.2032)
		(layers "F.Cu" "B.Cu")
		(net "GND")
	)
	(via
		(at 373.344694 -229.094284)
		(size 0.4064)
		(drill 0.2032)
		(layers "F.Cu" "B.Cu")
		(net "GND")
	)
	(via
		(at 22.724364 -422.437052)
		(size 0.508)
		(drill 0.254)
		(layers "F.Cu" "B.Cu")
		(net "GND")
	)
	(via
		(at 307.368194 -291.684964)
		(size 0.4826)
		(drill 0.254)
		(layers "F.Cu" "B.Cu")
		(net "GND")
	)
	(via
		(at 105.500932 -282.996386)
		(size 0.4064)
		(drill 0.2032)
		(layers "F.Cu" "B.Cu")
		(net "GND")
	)
	(via
		(at 188.177678 -286.160464)
		(size 0.4826)
		(drill 0.254)
		(layers "F.Cu" "B.Cu")
		(net "GND")
	)
	(via
		(at 440.741308 -347.542866)
		(size 0.508)
		(drill 0.254)
		(layers "F.Cu" "B.Cu")
		(net "GND")
	)
	(via
		(at 218.478608 -83.413346)
		(size 0.508)
		(drill 0.254)
		(layers "F.Cu" "B.Cu")
		(net "GND")
	)
	(via
		(at 131.744466 -158.470346)
		(size 0.49022)
		(drill 0.254)
		(layers "F.Cu" "B.Cu")
		(net "GND")
	)
	(via
		(at 275.290026 -89.685876)
		(size 0.508)
		(drill 0.254)
		(layers "F.Cu" "B.Cu")
		(net "GND")
	)
	(via
		(at 68.766436 -410.664152)
		(size 0.4572)
		(drill 0.254)
		(layers "F.Cu" "B.Cu")
		(net "GND")
	)
	(via
		(at 15.339822 -108.66374)
		(size 0.508)
		(drill 0.254)
		(layers "F.Cu" "B.Cu")
		(net "GND")
	)
	(via
		(at 280.635964 -300.185074)
		(size 0.4826)
		(drill 0.254)
		(layers "F.Cu" "B.Cu")
		(net "GND")
	)
	(via
		(at 168.065704 -12.495022)
		(size 0.508)
		(drill 0.254)
		(layers "F.Cu" "B.Cu")
		(net "GND")
	)
	(via
		(at 275.807932 -295.935146)
		(size 0.4826)
		(drill 0.254)
		(layers "F.Cu" "B.Cu")
		(net "GND")
	)
	(via
		(at 66.061844 -407.00452)
		(size 0.4064)
		(drill 0.2032)
		(layers "F.Cu" "B.Cu")
		(net "GND")
	)
	(via
		(at 331.991208 -250.154186)
		(size 0.4064)
		(drill 0.2032)
		(layers "F.Cu" "B.Cu")
		(net "GND")
	)
	(via
		(at 362.834682 -287.856168)
		(size 0.4064)
		(drill 0.2032)
		(layers "F.Cu" "B.Cu")
		(net "GND")
	)
	(via
		(at 102.681024 -278.13635)
		(size 0.4064)
		(drill 0.2032)
		(layers "F.Cu" "B.Cu")
		(net "GND")
	)
	(via
		(at 29.252164 -306.985416)
		(size 0.4826)
		(drill 0.254)
		(layers "F.Cu" "B.Cu")
		(net "GND")
	)
	(via
		(at 358.141016 -270.036036)
		(size 0.4064)
		(drill 0.2032)
		(layers "F.Cu" "B.Cu")
		(net "GND")
	)
	(via
		(at 379.142498 -184.679082)
		(size 0.49022)
		(drill 0.254)
		(layers "F.Cu" "B.Cu")
		(net "GND")
	)
	(via
		(at 388.68477 -267.606018)
		(size 0.4064)
		(drill 0.2032)
		(layers "F.Cu" "B.Cu")
		(net "GND")
	)
	(via
		(at 354.34397 -402.284438)
		(size 0.4572)
		(drill 0.254)
		(layers "F.Cu" "B.Cu")
		(net "GND")
	)
	(via
		(at 327.761092 -231.524048)
		(size 0.4064)
		(drill 0.2032)
		(layers "F.Cu" "B.Cu")
		(net "GND")
	)
	(via
		(at 374.584722 -285.42615)
		(size 0.4064)
		(drill 0.2032)
		(layers "F.Cu" "B.Cu")
		(net "GND")
	)
	(via
		(at 53.562758 -344.781886)
		(size 0.49022)
		(drill 0.254)
		(layers "F.Cu" "B.Cu")
		(net "GND")
	)
	(via
		(at 343.418414 -413.480504)
		(size 0.4572)
		(drill 0.254)
		(layers "F.Cu" "B.Cu")
		(net "GND")
	)
	(via
		(at 352.201226 -223.424242)
		(size 0.4064)
		(drill 0.2032)
		(layers "F.Cu" "B.Cu")
		(net "GND")
	)
	(via
		(at 20.59051 -294.66032)
		(size 0.4826)
		(drill 0.254)
		(layers "F.Cu" "B.Cu")
		(net "GND")
	)
	(via
		(at 369.584732 -246.914162)
		(size 0.4064)
		(drill 0.2032)
		(layers "F.Cu" "B.Cu")
		(net "GND")
	)
	(via
		(at 168.527984 -306.985416)
		(size 0.4826)
		(drill 0.254)
		(layers "F.Cu" "B.Cu")
		(net "GND")
	)
	(via
		(at 80.291178 -230.71455)
		(size 0.4064)
		(drill 0.2032)
		(layers "F.Cu" "B.Cu")
		(net "GND")
	)
	(via
		(at 394.68298 -251.23013)
		(size 0.4064)
		(drill 0.2032)
		(layers "F.Cu" "B.Cu")
		(net "GND")
	)
	(via
		(at 385.651502 -420.952168)
		(size 0.4064)
		(drill 0.2032)
		(layers "F.Cu" "B.Cu")
		(net "GND")
	)
	(via
		(at 58.043826 -237.285276)
		(size 0.4826)
		(drill 0.254)
		(layers "F.Cu" "B.Cu")
		(net "GND")
	)
	(via
		(at 107.550966 -250.15444)
		(size 0.4064)
		(drill 0.2032)
		(layers "F.Cu" "B.Cu")
		(net "GND")
	)
	(via
		(at 363.87024 -390.92632)
		(size 0.508)
		(drill 0.254)
		(layers "F.Cu" "B.Cu")
		(net "GND")
	)
	(via
		(at 69.767958 -334.601058)
		(size 0.49022)
		(drill 0.254)
		(layers "F.Cu" "B.Cu")
		(net "GND")
	)
	(via
		(at 35.678364 -304.010314)
		(size 0.4826)
		(drill 0.254)
		(layers "F.Cu" "B.Cu")
		(net "GND")
	)
	(via
		(at 119.291354 -390.160002)
		(size 0.4064)
		(drill 0.2032)
		(layers "F.Cu" "B.Cu")
		(net "GND")
	)
	(via
		(at 372.704868 -267.606018)
		(size 0.4064)
		(drill 0.2032)
		(layers "F.Cu" "B.Cu")
		(net "GND")
	)
	(via
		(at 393.668758 -310.207152)
		(size 0.508)
		(drill 0.254)
		(layers "F.Cu" "B.Cu")
		(net "GND")
	)
	(via
		(at 124.294646 -287.856422)
		(size 0.4064)
		(drill 0.2032)
		(layers "F.Cu" "B.Cu")
		(net "GND")
	)
	(via
		(at 43.885358 -344.781886)
		(size 0.49022)
		(drill 0.254)
		(layers "F.Cu" "B.Cu")
		(net "GND")
	)
	(via
		(at 167.143684 -218.585288)
		(size 0.4826)
		(drill 0.254)
		(layers "F.Cu" "B.Cu")
		(net "GND")
	)
	(via
		(at 327.249536 -429.147224)
		(size 0.4572)
		(drill 0.2032)
		(layers "F.Cu" "B.Cu")
		(net "GND")
	)
	(via
		(at 137.45464 -274.896326)
		(size 0.4064)
		(drill 0.2032)
		(layers "F.Cu" "B.Cu")
		(net "GND")
	)
	(via
		(at 334.811116 -238.814102)
		(size 0.4064)
		(drill 0.2032)
		(layers "F.Cu" "B.Cu")
		(net "GND")
	)
	(via
		(at 147.042886 -273.010376)
		(size 0.4064)
		(drill 0.2032)
		(layers "F.Cu" "B.Cu")
		(net "GND")
	)
	(via
		(at 36.795964 -261.935214)
		(size 0.4826)
		(drill 0.254)
		(layers "F.Cu" "B.Cu")
		(net "GND")
	)
	(via
		(at 257.101594 -139.083796)
		(size 0.508)
		(drill 0.254)
		(layers "F.Cu" "B.Cu")
		(net "GND")
	)
	(via
		(at 180.900324 -275.53539)
		(size 0.4826)
		(drill 0.254)
		(layers "F.Cu" "B.Cu")
		(net "GND")
	)
	(via
		(at 284.736032 -246.635016)
		(size 0.4826)
		(drill 0.254)
		(layers "F.Cu" "B.Cu")
		(net "GND")
	)
	(via
		(at 371.921278 -143.504158)
		(size 0.508)
		(drill 0.254)
		(layers "F.Cu" "B.Cu")
		(net "GND")
	)
	(via
		(at 118.448836 -368.37493)
		(size 0.508)
		(drill 0.254)
		(layers "F.Cu" "B.Cu")
		(net "GND")
	)
	(via
		(at 451.4723 -296.78503)
		(size 0.4826)
		(drill 0.254)
		(layers "F.Cu" "B.Cu")
		(net "GND")
	)
	(via
		(at 113.184686 -225.854514)
		(size 0.4064)
		(drill 0.2032)
		(layers "F.Cu" "B.Cu")
		(net "GND")
	)
	(via
		(at 171.423076 -413.776668)
		(size 0.508)
		(drill 0.254)
		(layers "F.Cu" "B.Cu")
		(net "GND")
	)
	(via
		(at 288.180018 -290.83508)
		(size 0.4826)
		(drill 0.254)
		(layers "F.Cu" "B.Cu")
		(net "GND")
	)
	(via
		(at 424.012106 -265.335004)
		(size 0.4826)
		(drill 0.254)
		(layers "F.Cu" "B.Cu")
		(net "GND")
	)
	(via
		(at 441.974732 -390.504426)
		(size 0.508)
		(drill 0.254)
		(layers "F.Cu" "B.Cu")
		(net "GND")
	)
	(via
		(at 94.87789 -12.542266)
		(size 0.508)
		(drill 0.254)
		(layers "F.Cu" "B.Cu")
		(net "GND")
	)
	(via
		(at 138.7856 -30.6578)
		(size 0.508)
		(drill 0.254)
		(layers "F.Cu" "B.Cu")
		(net "GND")
	)
	(via
		(at 413.752284 -200.735184)
		(size 0.4826)
		(drill 0.254)
		(layers "F.Cu" "B.Cu")
		(net "GND")
	)
	(via
		(at 57.879234 -339.883496)
		(size 0.508)
		(drill 0.254)
		(layers "F.Cu" "B.Cu")
		(net "GND")
	)
	(via
		(at 367.064798 -280.566114)
		(size 0.4064)
		(drill 0.2032)
		(layers "F.Cu" "B.Cu")
		(net "GND")
	)
	(via
		(at 348.344236 -402.309838)
		(size 0.4572)
		(drill 0.254)
		(layers "F.Cu" "B.Cu")
		(net "GND")
	)
	(via
		(at 345.921076 -263.555988)
		(size 0.4064)
		(drill 0.2032)
		(layers "F.Cu" "B.Cu")
		(net "GND")
	)
	(via
		(at 80.591152 -267.606272)
		(size 0.4064)
		(drill 0.2032)
		(layers "F.Cu" "B.Cu")
		(net "GND")
	)
	(via
		(at 137.154666 -223.424496)
		(size 0.4064)
		(drill 0.2032)
		(layers "F.Cu" "B.Cu")
		(net "GND")
	)
	(via
		(at 352.671126 -230.714296)
		(size 0.4064)
		(drill 0.2032)
		(layers "F.Cu" "B.Cu")
		(net "GND")
	)
	(via
		(at 301.871888 -20.36191)
		(size 0.508)
		(drill 0.254)
		(layers "F.Cu" "B.Cu")
		(net "GND")
	)
	(via
		(at 169.645584 -219.860368)
		(size 0.4826)
		(drill 0.254)
		(layers "F.Cu" "B.Cu")
		(net "GND")
	)
	(via
		(at 457.778104 -51.997102)
		(size 0.508)
		(drill 0.254)
		(layers "F.Cu" "B.Cu")
		(net "GND")
	)
	(via
		(at 194.114166 -348.07652)
		(size 0.508)
		(drill 0.254)
		(layers "F.Cu" "B.Cu")
		(net "GND")
	)
	(via
		(at 25.152096 -262.785352)
		(size 0.4826)
		(drill 0.254)
		(layers "F.Cu" "B.Cu")
		(net "GND")
	)
	(via
		(at 111.800386 -249.362214)
		(size 0.4826)
		(drill 0.254)
		(layers "F.Cu" "B.Cu")
		(net "GND")
	)
	(via
		(at 117.884702 -237.194344)
		(size 0.4064)
		(drill 0.2032)
		(layers "F.Cu" "B.Cu")
		(net "GND")
	)
	(via
		(at 7.610348 -101.854)
		(size 0.508)
		(drill 0.254)
		(layers "F.Cu" "B.Cu")
		(net "GND")
	)
	(via
		(at 445.488568 -192.21831)
		(size 0.4826)
		(drill 0.254)
		(layers "F.Cu" "B.Cu")
		(net "GND")
	)
	(via
		(at 126.814834 -226.66452)
		(size 0.4064)
		(drill 0.2032)
		(layers "F.Cu" "B.Cu")
		(net "GND")
	)
	(via
		(at 260.475222 -195.254626)
		(size 0.508)
		(drill 0.254)
		(layers "F.Cu" "B.Cu")
		(net "GND")
	)
	(via
		(at 101.27107 -282.18638)
		(size 0.4064)
		(drill 0.2032)
		(layers "F.Cu" "B.Cu")
		(net "GND")
	)
	(via
		(at 390.349486 -437.49976)
		(size 0.4572)
		(drill 0.2032)
		(layers "F.Cu" "B.Cu")
		(net "GND")
	)
	(via
		(at 393.384786 -282.186126)
		(size 0.4064)
		(drill 0.2032)
		(layers "F.Cu" "B.Cu")
		(net "GND")
	)
	(via
		(at 194.604132 -255.13538)
		(size 0.4826)
		(drill 0.254)
		(layers "F.Cu" "B.Cu")
		(net "GND")
	)
	(via
		(at 204.35062 -332.805786)
		(size 0.508)
		(drill 0.254)
		(layers "F.Cu" "B.Cu")
		(net "GND")
	)
	(via
		(at 344.249502 -436.347362)
		(size 0.4572)
		(drill 0.2032)
		(layers "F.Cu" "B.Cu")
		(net "GND")
	)
	(via
		(at 136.34974 -426.54728)
		(size 0.4572)
		(drill 0.2032)
		(layers "F.Cu" "B.Cu")
		(net "GND")
	)
	(via
		(at 311.563766 -344.132408)
		(size 0.508)
		(drill 0.254)
		(layers "F.Cu" "B.Cu")
		(net "GND")
	)
	(via
		(at 27.069542 -421.69969)
		(size 0.508)
		(drill 0.254)
		(layers "F.Cu" "B.Cu")
		(net "GND")
	)
	(via
		(at 378.210318 -185.340498)
		(size 0.508)
		(drill 0.254)
		(layers "F.Cu" "B.Cu")
		(net "GND")
	)
	(via
		(at 369.584732 -229.094284)
		(size 0.4064)
		(drill 0.2032)
		(layers "F.Cu" "B.Cu")
		(net "GND")
	)
	(via
		(at 85.144356 -391.830814)
		(size 0.4064)
		(drill 0.2032)
		(layers "F.Cu" "B.Cu")
		(net "GND")
	)
	(via
		(at 235.922058 -325.894192)
		(size 0.508)
		(drill 0.254)
		(layers "F.Cu" "B.Cu")
		(net "GND")
	)
	(via
		(at 419.912038 -269.585186)
		(size 0.4826)
		(drill 0.254)
		(layers "F.Cu" "B.Cu")
		(net "GND")
	)
	(via
		(at 454.820782 -395.27353)
		(size 0.49022)
		(drill 0.254)
		(layers "F.Cu" "B.Cu")
		(net "GND")
	)
	(via
		(at 293.989506 -339.809836)
		(size 0.508)
		(drill 0.254)
		(layers "F.Cu" "B.Cu")
		(net "GND")
	)
	(via
		(at 431.55616 -241.53495)
		(size 0.4826)
		(drill 0.254)
		(layers "F.Cu" "B.Cu")
		(net "GND")
	)
	(via
		(at 320.949828 -45.859954)
		(size 0.508)
		(drill 0.254)
		(layers "F.Cu" "B.Cu")
		(net "GND")
	)
	(via
		(at 130.574796 -246.10441)
		(size 0.4064)
		(drill 0.2032)
		(layers "F.Cu" "B.Cu")
		(net "GND")
	)
	(via
		(at 413.58185 -420.318184)
		(size 0.4572)
		(drill 0.254)
		(layers "F.Cu" "B.Cu")
		(net "GND")
	)
	(via
		(at 445.488568 -193.99631)
		(size 0.4826)
		(drill 0.254)
		(layers "F.Cu" "B.Cu")
		(net "GND")
	)
	(via
		(at 381.337058 -180.755544)
		(size 0.49022)
		(drill 0.254)
		(layers "F.Cu" "B.Cu")
		(net "GND")
	)
	(via
		(at 329.249532 -437.34736)
		(size 0.4572)
		(drill 0.2032)
		(layers "F.Cu" "B.Cu")
		(net "GND")
	)
	(via
		(at 389.277352 -378.07773)
		(size 0.508)
		(drill 0.254)
		(layers "F.Cu" "B.Cu")
		(net "GND")
	)
	(via
		(at 337.930998 -283.806138)
		(size 0.4064)
		(drill 0.2032)
		(layers "F.Cu" "B.Cu")
		(net "GND")
	)
	(via
		(at 237.616238 -56.965088)
		(size 0.508)
		(drill 0.254)
		(layers "F.Cu" "B.Cu")
		(net "GND")
	)
	(via
		(at 11.537442 -50.094896)
		(size 0.508)
		(drill 0.254)
		(layers "F.Cu" "B.Cu")
		(net "GND")
	)
	(via
		(at 371.764814 -285.42615)
		(size 0.4064)
		(drill 0.2032)
		(layers "F.Cu" "B.Cu")
		(net "GND")
	)
	(via
		(at 381.634746 -281.37612)
		(size 0.4064)
		(drill 0.2032)
		(layers "F.Cu" "B.Cu")
		(net "GND")
	)
	(via
		(at 442.297566 -377.29287)
		(size 0.508)
		(drill 0.254)
		(layers "F.Cu" "B.Cu")
		(net "GND")
	)
	(via
		(at 147.82419 -99.155758)
		(size 0.508)
		(drill 0.254)
		(layers "F.Cu" "B.Cu")
		(net "GND")
	)
	(via
		(at 412.367984 -300.185074)
		(size 0.4826)
		(drill 0.254)
		(layers "F.Cu" "B.Cu")
		(net "GND")
	)
	(via
		(at 81.118964 -390.160002)
		(size 0.4064)
		(drill 0.2032)
		(layers "F.Cu" "B.Cu")
		(net "GND")
	)
	(via
		(at 332.931008 -251.774198)
		(size 0.4064)
		(drill 0.2032)
		(layers "F.Cu" "B.Cu")
		(net "GND")
	)
	(via
		(at 427.456092 -250.884944)
		(size 0.4826)
		(drill 0.254)
		(layers "F.Cu" "B.Cu")
		(net "GND")
	)
	(via
		(at 205.351126 -345.24823)
		(size 0.508)
		(drill 0.254)
		(layers "F.Cu" "B.Cu")
		(net "GND")
	)
	(via
		(at 89.944194 -382.85293)
		(size 0.4064)
		(drill 0.2032)
		(layers "F.Cu" "B.Cu")
		(net "GND")
	)
	(via
		(at 80.591152 -287.046162)
		(size 0.4064)
		(drill 0.2032)
		(layers "F.Cu" "B.Cu")
		(net "GND")
	)
	(via
		(at 141.920722 -79.736442)
		(size 0.508)
		(drill 0.254)
		(layers "F.Cu" "B.Cu")
		(net "GND")
	)
	(via
		(at 324.75297 -244.750082)
		(size 0.4064)
		(drill 0.2032)
		(layers "F.Cu" "B.Cu")
		(net "GND")
	)
	(via
		(at 149.349714 -437.34736)
		(size 0.4572)
		(drill 0.2032)
		(layers "F.Cu" "B.Cu")
		(net "GND")
	)
	(via
		(at 405.780748 -141.087602)
		(size 0.508)
		(drill 0.254)
		(layers "F.Cu" "B.Cu")
		(net "GND")
	)
	(via
		(at 366.124744 -280.566114)
		(size 0.4064)
		(drill 0.2032)
		(layers "F.Cu" "B.Cu")
		(net "GND")
	)
	(via
		(at 273.46021 -345.566238)
		(size 0.49022)
		(drill 0.254)
		(layers "F.Cu" "B.Cu")
		(net "GND")
	)
	(via
		(at 356.292658 -168.930066)
		(size 0.49022)
		(drill 0.254)
		(layers "F.Cu" "B.Cu")
		(net "GND")
	)
	(via
		(at 444.007748 -344.980006)
		(size 0.6604)
		(drill 0.3302)
		(layers "F.Cu" "B.Cu")
		(net "GND")
	)
	(via
		(at 318.150494 -18.45945)
		(size 0.508)
		(drill 0.254)
		(layers "F.Cu" "B.Cu")
		(net "GND")
	)
	(via
		(at 306.386738 -416.020504)
		(size 0.4572)
		(drill 0.254)
		(layers "F.Cu" "B.Cu")
		(net "GND")
	)
	(via
		(at 259.898134 -48.659796)
		(size 0.508)
		(drill 0.254)
		(layers "F.Cu" "B.Cu")
		(net "GND")
	)
	(via
		(at 116.331238 -42.2656)
		(size 0.508)
		(drill 0.254)
		(layers "F.Cu" "B.Cu")
		(net "GND")
	)
	(via
		(at 50.2285 -352.23196)
		(size 0.508)
		(drill 0.254)
		(layers "F.Cu" "B.Cu")
		(net "GND")
	)
	(via
		(at 366.764824 -246.914162)
		(size 0.4064)
		(drill 0.2032)
		(layers "F.Cu" "B.Cu")
		(net "GND")
	)
	(via
		(at 104.731058 -227.474526)
		(size 0.4064)
		(drill 0.2032)
		(layers "F.Cu" "B.Cu")
		(net "GND")
	)
	(via
		(at 350.621092 -276.516084)
		(size 0.4064)
		(drill 0.2032)
		(layers "F.Cu" "B.Cu")
		(net "GND")
	)
	(via
		(at 42.955718 -295.9354)
		(size 0.4826)
		(drill 0.254)
		(layers "F.Cu" "B.Cu")
		(net "GND")
	)
	(via
		(at 372.404894 -224.234248)
		(size 0.4064)
		(drill 0.2032)
		(layers "F.Cu" "B.Cu")
		(net "GND")
	)
	(via
		(at 15.58036 -97.627948)
		(size 0.508)
		(drill 0.254)
		(layers "F.Cu" "B.Cu")
		(net "GND")
	)
	(via
		(at 138.564874 -256.634488)
		(size 0.4064)
		(drill 0.2032)
		(layers "F.Cu" "B.Cu")
		(net "GND")
	)
	(via
		(at 285.87827 -346.302076)
		(size 0.49022)
		(drill 0.254)
		(layers "F.Cu" "B.Cu")
		(net "GND")
	)
	(via
		(at 291.132006 -347.282262)
		(size 0.49022)
		(drill 0.254)
		(layers "F.Cu" "B.Cu")
		(net "GND")
	)
	(via
		(at 391.204704 -235.574078)
		(size 0.4064)
		(drill 0.2032)
		(layers "F.Cu" "B.Cu")
		(net "GND")
	)
	(via
		(at 171.565824 -377.132088)
		(size 0.508)
		(drill 0.254)
		(layers "F.Cu" "B.Cu")
		(net "GND")
	)
	(via
		(at 67.249802 -432.747166)
		(size 0.4572)
		(drill 0.2032)
		(layers "F.Cu" "B.Cu")
		(net "GND")
	)
	(via
		(at 446.644268 -224.534984)
		(size 0.4826)
		(drill 0.254)
		(layers "F.Cu" "B.Cu")
		(net "GND")
	)
	(via
		(at 450.088 -301.885096)
		(size 0.4826)
		(drill 0.254)
		(layers "F.Cu" "B.Cu")
		(net "GND")
	)
	(via
		(at 85.290914 -291.906198)
		(size 0.4064)
		(drill 0.2032)
		(layers "F.Cu" "B.Cu")
		(net "GND")
	)
	(via
		(at 52.279804 -412.570168)
		(size 0.4064)
		(drill 0.2032)
		(layers "F.Cu" "B.Cu")
		(net "GND")
	)
	(via
		(at 176.732184 -106.262932)
		(size 0.4572)
		(drill 0.254)
		(layers "F.Cu" "B.Cu")
		(net "GND")
	)
	(via
		(at 338.823554 -414.752536)
		(size 0.4572)
		(drill 0.254)
		(layers "F.Cu" "B.Cu")
		(net "GND")
	)
	(via
		(at 44.340018 -222.835216)
		(size 0.4826)
		(drill 0.254)
		(layers "F.Cu" "B.Cu")
		(net "GND")
	)
	(via
		(at 165.812216 -200.735438)
		(size 0.4826)
		(drill 0.254)
		(layers "F.Cu" "B.Cu")
		(net "GND")
	)
	(via
		(at 332.593442 -393.96416)
		(size 0.508)
		(drill 0.254)
		(layers "F.Cu" "B.Cu")
		(net "GND")
	)
	(via
		(at 336.521044 -291.095938)
		(size 0.4064)
		(drill 0.2032)
		(layers "F.Cu" "B.Cu")
		(net "GND")
	)
	(via
		(at 153.895044 -373.96293)
		(size 0.508)
		(drill 0.254)
		(layers "F.Cu" "B.Cu")
		(net "GND")
	)
	(via
		(at 55.328058 -255.13538)
		(size 0.4826)
		(drill 0.254)
		(layers "F.Cu" "B.Cu")
		(net "GND")
	)
	(via
		(at 330.804266 -412.84652)
		(size 0.4064)
		(drill 0.2032)
		(layers "F.Cu" "B.Cu")
		(net "GND")
	)
	(via
		(at 445.0715 -77.1779)
		(size 0.508)
		(drill 0.254)
		(layers "F.Cu" "B.Cu")
		(net "GND")
	)
	(via
		(at 44.065952 -384.66268)
		(size 0.508)
		(drill 0.254)
		(layers "F.Cu" "B.Cu")
		(net "GND")
	)
	(via
		(at 134.35076 -393.25804)
		(size 0.508)
		(drill 0.254)
		(layers "F.Cu" "B.Cu")
		(net "GND")
	)
	(via
		(at 164.427916 -216.035382)
		(size 0.4826)
		(drill 0.254)
		(layers "F.Cu" "B.Cu")
		(net "GND")
	)
	(via
		(at 144.674844 -250.964446)
		(size 0.4064)
		(drill 0.2032)
		(layers "F.Cu" "B.Cu")
		(net "GND")
	)
	(via
		(at 78.88097 -223.424496)
		(size 0.4064)
		(drill 0.2032)
		(layers "F.Cu" "B.Cu")
		(net "GND")
	)
	(via
		(at 57.118504 -388.328662)
		(size 0.4064)
		(drill 0.2032)
		(layers "F.Cu" "B.Cu")
		(net "GND")
	)
	(via
		(at 79.56677 -189.554866)
		(size 0.508)
		(drill 0.254)
		(layers "F.Cu" "B.Cu")
		(net "GND")
	)
	(via
		(at 43.586908 -6.091174)
		(size 0.508)
		(drill 0.254)
		(layers "F.Cu" "B.Cu")
		(net "GND")
	)
	(via
		(at 418.606224 -394.831062)
		(size 0.4064)
		(drill 0.2032)
		(layers "F.Cu" "B.Cu")
		(net "GND")
	)
	(via
		(at 357.92537 -397.274542)
		(size 0.508)
		(drill 0.254)
		(layers "F.Cu" "B.Cu")
		(net "GND")
	)
	(via
		(at 274.476464 -203.28509)
		(size 0.4826)
		(drill 0.254)
		(layers "F.Cu" "B.Cu")
		(net "GND")
	)
	(via
		(at 390.281668 -77.424026)
		(size 0.508)
		(drill 0.254)
		(layers "F.Cu" "B.Cu")
		(net "GND")
	)
	(via
		(at 124.7648 -267.606272)
		(size 0.4064)
		(drill 0.2032)
		(layers "F.Cu" "B.Cu")
		(net "GND")
	)
	(via
		(at 56.712358 -303.585372)
		(size 0.4826)
		(drill 0.254)
		(layers "F.Cu" "B.Cu")
		(net "GND")
	)
	(via
		(at 307.918358 -412.212536)
		(size 0.4572)
		(drill 0.254)
		(layers "F.Cu" "B.Cu")
		(net "GND")
	)
	(via
		(at 91.44635 -189.552326)
		(size 0.508)
		(drill 0.254)
		(layers "F.Cu" "B.Cu")
		(net "GND")
	)
	(via
		(at 244.853714 -317.22568)
		(size 0.508)
		(drill 0.254)
		(layers "F.Cu" "B.Cu")
		(net "GND")
	)
	(via
		(at 125.704854 -270.846296)
		(size 0.4064)
		(drill 0.2032)
		(layers "F.Cu" "B.Cu")
		(net "GND")
	)
	(via
		(at 285.935928 -423.182288)
		(size 0.508)
		(drill 0.254)
		(layers "F.Cu" "B.Cu")
		(net "GND")
	)
	(via
		(at 183.616092 -233.885232)
		(size 0.4826)
		(drill 0.254)
		(layers "F.Cu" "B.Cu")
		(net "GND")
	)
	(via
		(at 367.16589 -393.96416)
		(size 0.508)
		(drill 0.254)
		(layers "F.Cu" "B.Cu")
		(net "GND")
	)
	(via
		(at 397.00073 -200.538588)
		(size 0.508)
		(drill 0.254)
		(layers "F.Cu" "B.Cu")
		(net "GND")
	)
	(via
		(at 366.294924 -233.14406)
		(size 0.4064)
		(drill 0.2032)
		(layers "F.Cu" "B.Cu")
		(net "GND")
	)
	(via
		(at 346.683584 -376.75693)
		(size 0.508)
		(drill 0.254)
		(layers "F.Cu" "B.Cu")
		(net "GND")
	)
	(via
		(at 239.014 -286.755078)
		(size 0.508)
		(drill 0.254)
		(layers "F.Cu" "B.Cu")
		(net "GND")
	)
	(via
		(at 370.916454 -402.284438)
		(size 0.4572)
		(drill 0.254)
		(layers "F.Cu" "B.Cu")
		(net "GND")
	)
	(via
		(at 49.644554 -373.96293)
		(size 0.508)
		(drill 0.254)
		(layers "F.Cu" "B.Cu")
		(net "GND")
	)
	(via
		(at 394.349478 -437.49976)
		(size 0.4572)
		(drill 0.2032)
		(layers "F.Cu" "B.Cu")
		(net "GND")
	)
	(via
		(at 355.961188 -228.284278)
		(size 0.4064)
		(drill 0.2032)
		(layers "F.Cu" "B.Cu")
		(net "GND")
	)
	(via
		(at 467.5378 -177.851054)
		(size 0.508)
		(drill 0.254)
		(layers "F.Cu" "B.Cu")
		(net "GND")
	)
	(via
		(at 165.812216 -221.985332)
		(size 0.4826)
		(drill 0.254)
		(layers "F.Cu" "B.Cu")
		(net "GND")
	)
	(via
		(at 460.529686 -54.52364)
		(size 0.508)
		(drill 0.254)
		(layers "F.Cu" "B.Cu")
		(net "GND")
	)
	(via
		(at 442.5442 -199.035162)
		(size 0.4826)
		(drill 0.254)
		(layers "F.Cu" "B.Cu")
		(net "GND")
	)
	(via
		(at 151.370538 -319.67805)
		(size 0.508)
		(drill 0.254)
		(layers "F.Cu" "B.Cu")
		(net "GND")
	)
	(via
		(at 151.044148 -393.877038)
		(size 0.4572)
		(drill 0.254)
		(layers "F.Cu" "B.Cu")
		(net "GND")
	)
	(via
		(at 253.823216 -325.773796)
		(size 0.762)
		(drill 0.254)
		(layers "F.Cu" "B.Cu")
		(net "GND")
	)
	(via
		(at 135.744712 -250.15444)
		(size 0.4064)
		(drill 0.2032)
		(layers "F.Cu" "B.Cu")
		(net "GND")
	)
	(via
		(at 381.334772 -246.104156)
		(size 0.4064)
		(drill 0.2032)
		(layers "F.Cu" "B.Cu")
		(net "GND")
	)
	(via
		(at 229.596442 -327.56602)
		(size 0.508)
		(drill 0.254)
		(layers "F.Cu" "B.Cu")
		(net "GND")
	)
	(via
		(at 320.949828 -40.652954)
		(size 0.508)
		(drill 0.254)
		(layers "F.Cu" "B.Cu")
		(net "GND")
	)
	(via
		(at 16.749522 -411.83687)
		(size 0.508)
		(drill 0.254)
		(layers "F.Cu" "B.Cu")
		(net "GND")
	)
	(via
		(at 89.057734 -333.043276)
		(size 0.49022)
		(drill 0.254)
		(layers "F.Cu" "B.Cu")
		(net "GND")
	)
	(via
		(at 407.024078 -168.027858)
		(size 0.49022)
		(drill 0.254)
		(layers "F.Cu" "B.Cu")
		(net "GND")
	)
	(via
		(at 116.004848 -237.194344)
		(size 0.4064)
		(drill 0.2032)
		(layers "F.Cu" "B.Cu")
		(net "GND")
	)
	(via
		(at 188.538612 -143.933418)
		(size 0.508)
		(drill 0.254)
		(layers "F.Cu" "B.Cu")
		(net "GND")
	)
	(via
		(at 442.5442 -197.33514)
		(size 0.4826)
		(drill 0.254)
		(layers "F.Cu" "B.Cu")
		(net "GND")
	)
	(via
		(at 313.134248 -22.51329)
		(size 0.508)
		(drill 0.254)
		(layers "F.Cu" "B.Cu")
		(net "GND")
	)
	(via
		(at 194.604132 -208.38541)
		(size 0.4826)
		(drill 0.254)
		(layers "F.Cu" "B.Cu")
		(net "GND")
	)
	(via
		(at 275.386546 -12.542266)
		(size 0.508)
		(drill 0.254)
		(layers "F.Cu" "B.Cu")
		(net "GND")
	)
	(via
		(at 91.871038 -295.146222)
		(size 0.4064)
		(drill 0.2032)
		(layers "F.Cu" "B.Cu")
		(net "GND")
	)
	(via
		(at 81.544414 -382.85293)
		(size 0.4064)
		(drill 0.2032)
		(layers "F.Cu" "B.Cu")
		(net "GND")
	)
	(via
		(at 103.482648 -345.081098)
		(size 0.508)
		(drill 0.254)
		(layers "F.Cu" "B.Cu")
		(net "GND")
	)
	(via
		(at 44.927774 -347.287088)
		(size 0.49022)
		(drill 0.254)
		(layers "F.Cu" "B.Cu")
		(net "GND")
	)
	(via
		(at 450.262752 -392.905234)
		(size 0.508)
		(drill 0.254)
		(layers "F.Cu" "B.Cu")
		(net "GND")
	)
	(via
		(at 2.76225 -395.153134)
		(size 0.508)
		(drill 0.254)
		(layers "F.Cu" "B.Cu")
		(net "GND")
	)
	(via
		(at 273.092164 -289.135058)
		(size 0.4826)
		(drill 0.254)
		(layers "F.Cu" "B.Cu")
		(net "GND")
	)
	(via
		(at 130.349752 -432.747166)
		(size 0.4572)
		(drill 0.2032)
		(layers "F.Cu" "B.Cu")
		(net "GND")
	)
	(via
		(at 427.456092 -255.135126)
		(size 0.4826)
		(drill 0.254)
		(layers "F.Cu" "B.Cu")
		(net "GND")
	)
	(via
		(at 22.987254 -340.093808)
		(size 0.508)
		(drill 0.254)
		(layers "F.Cu" "B.Cu")
		(net "GND")
	)
	(via
		(at 355.491034 -242.054126)
		(size 0.4064)
		(drill 0.2032)
		(layers "F.Cu" "B.Cu")
		(net "GND")
	)
	(via
		(at 396.461234 -413.480504)
		(size 0.4572)
		(drill 0.254)
		(layers "F.Cu" "B.Cu")
		(net "GND")
	)
	(via
		(at 112.257586 -254.448564)
		(size 0.4826)
		(drill 0.254)
		(layers "F.Cu" "B.Cu")
		(net "GND")
	)
	(via
		(at 124.05487 -146.957288)
		(size 0.508)
		(drill 0.254)
		(layers "F.Cu" "B.Cu")
		(net "GND")
	)
	(via
		(at 53.450236 -409.396184)
		(size 0.4572)
		(drill 0.254)
		(layers "F.Cu" "B.Cu")
		(net "GND")
	)
	(via
		(at 168.91 -337.5914)
		(size 0.6604)
		(drill 0.3302)
		(layers "F.Cu" "B.Cu")
		(net "GND")
	)
	(via
		(at 60.381134 -347.287088)
		(size 0.49022)
		(drill 0.254)
		(layers "F.Cu" "B.Cu")
		(net "GND")
	)
	(via
		(at 90.928444 -177.534062)
		(size 0.508)
		(drill 0.254)
		(layers "F.Cu" "B.Cu")
		(net "GND")
	)
	(via
		(at 228.783642 -291.224462)
		(size 0.508)
		(drill 0.254)
		(layers "F.Cu" "B.Cu")
		(net "GND")
	)
	(via
		(at 295.724072 -301.885096)
		(size 0.4826)
		(drill 0.254)
		(layers "F.Cu" "B.Cu")
		(net "GND")
	)
	(via
		(at 134.349744 -433.899564)
		(size 0.4572)
		(drill 0.2032)
		(layers "F.Cu" "B.Cu")
		(net "GND")
	)
	(via
		(at 378.04471 -229.094284)
		(size 0.4064)
		(drill 0.2032)
		(layers "F.Cu" "B.Cu")
		(net "GND")
	)
	(via
		(at 347.654626 -415.38652)
		(size 0.4064)
		(drill 0.2032)
		(layers "F.Cu" "B.Cu")
		(net "GND")
	)
	(via
		(at 118.287546 -71.839582)
		(size 0.508)
		(drill 0.254)
		(layers "F.Cu" "B.Cu")
		(net "GND")
	)
	(via
		(at 173.46295 -420.907464)
		(size 0.508)
		(drill 0.254)
		(layers "F.Cu" "B.Cu")
		(net "GND")
	)
	(via
		(at 26.536396 -303.585372)
		(size 0.4826)
		(drill 0.254)
		(layers "F.Cu" "B.Cu")
		(net "GND")
	)
	(via
		(at 58.317892 -406.370536)
		(size 0.4572)
		(drill 0.254)
		(layers "F.Cu" "B.Cu")
		(net "GND")
	)
	(via
		(at 83.88096 -274.896326)
		(size 0.4064)
		(drill 0.2032)
		(layers "F.Cu" "B.Cu")
		(net "GND")
	)
	(via
		(at 451.4723 -240.685066)
		(size 0.4826)
		(drill 0.254)
		(layers "F.Cu" "B.Cu")
		(net "GND")
	)
	(via
		(at 182.231792 -293.38524)
		(size 0.4826)
		(drill 0.254)
		(layers "F.Cu" "B.Cu")
		(net "GND")
	)
	(via
		(at 29.252164 -251.735336)
		(size 0.4826)
		(drill 0.254)
		(layers "F.Cu" "B.Cu")
		(net "GND")
	)
	(via
		(at 384.569462 -420.952168)
		(size 0.4064)
		(drill 0.2032)
		(layers "F.Cu" "B.Cu")
		(net "GND")
	)
	(via
		(at 399.349722 -429.147224)
		(size 0.4572)
		(drill 0.2032)
		(layers "F.Cu" "B.Cu")
		(net "GND")
	)
	(via
		(at 439.100214 -251.735082)
		(size 0.4826)
		(drill 0.254)
		(layers "F.Cu" "B.Cu")
		(net "GND")
	)
	(via
		(at 149.349714 -430.147222)
		(size 0.4572)
		(drill 0.2032)
		(layers "F.Cu" "B.Cu")
		(net "GND")
	)
	(via
		(at 88.446356 -388.328662)
		(size 0.4064)
		(drill 0.2032)
		(layers "F.Cu" "B.Cu")
		(net "GND")
	)
	(via
		(at 82.292698 -332.409038)
		(size 0.508)
		(drill 0.254)
		(layers "F.Cu" "B.Cu")
		(net "GND")
	)
	(via
		(at 51.884072 -248.335292)
		(size 0.4826)
		(drill 0.254)
		(layers "F.Cu" "B.Cu")
		(net "GND")
	)
	(via
		(at 417.18738 -381.68453)
		(size 0.508)
		(drill 0.254)
		(layers "F.Cu" "B.Cu")
		(net "GND")
	)
	(via
		(at 280.635964 -290.83508)
		(size 0.4826)
		(drill 0.254)
		(layers "F.Cu" "B.Cu")
		(net "GND")
	)
	(via
		(at 340.229952 -305.38293)
		(size 0.508)
		(drill 0.254)
		(layers "F.Cu" "B.Cu")
		(net "GND")
	)
	(via
		(at 105.043986 -338.000086)
		(size 0.49022)
		(drill 0.254)
		(layers "F.Cu" "B.Cu")
		(net "GND")
	)
	(via
		(at 121.474738 -273.276314)
		(size 0.4064)
		(drill 0.2032)
		(layers "F.Cu" "B.Cu")
		(net "GND")
	)
	(via
		(at 249.721624 -275.363432)
		(size 0.508)
		(drill 0.254)
		(layers "F.Cu" "B.Cu")
		(net "GND")
	)
	(via
		(at 268.263878 -295.935146)
		(size 0.4826)
		(drill 0.254)
		(layers "F.Cu" "B.Cu")
		(net "GND")
	)
	(via
		(at 402.274024 -16.979138)
		(size 0.508)
		(drill 0.254)
		(layers "F.Cu" "B.Cu")
		(net "GND")
	)
	(via
		(at 393.384786 -269.22603)
		(size 0.4064)
		(drill 0.2032)
		(layers "F.Cu" "B.Cu")
		(net "GND")
	)
	(via
		(at 165.018974 -390.160002)
		(size 0.4064)
		(drill 0.2032)
		(layers "F.Cu" "B.Cu")
		(net "GND")
	)
	(via
		(at 289.3568 -96.655382)
		(size 0.508)
		(drill 0.254)
		(layers "F.Cu" "B.Cu")
		(net "GND")
	)
	(via
		(at 266.93241 -278.085042)
		(size 0.4826)
		(drill 0.254)
		(layers "F.Cu" "B.Cu")
		(net "GND")
	)
	(via
		(at 275.807932 -302.73498)
		(size 0.4826)
		(drill 0.254)
		(layers "F.Cu" "B.Cu")
		(net "GND")
	)
	(via
		(at 141.992858 -409.396184)
		(size 0.4572)
		(drill 0.254)
		(layers "F.Cu" "B.Cu")
		(net "GND")
	)
	(via
		(at 56.754014 -344.772234)
		(size 0.508)
		(drill 0.254)
		(layers "F.Cu" "B.Cu")
		(net "GND")
	)
	(via
		(at 91.322906 -183.074818)
		(size 0.49022)
		(drill 0.254)
		(layers "F.Cu" "B.Cu")
		(net "GND")
	)
	(via
		(at 427.353476 -398.340834)
		(size 0.508)
		(drill 0.254)
		(layers "F.Cu" "B.Cu")
		(net "GND")
	)
	(via
		(at 151.946102 -388.328662)
		(size 0.4064)
		(drill 0.2032)
		(layers "F.Cu" "B.Cu")
		(net "GND")
	)
	(via
		(at 140.274802 -281.376374)
		(size 0.4064)
		(drill 0.2032)
		(layers "F.Cu" "B.Cu")
		(net "GND")
	)
	(via
		(at 265.54811 -273.835114)
		(size 0.4826)
		(drill 0.254)
		(layers "F.Cu" "B.Cu")
		(net "GND")
	)
	(via
		(at 121.678446 -386.449062)
		(size 0.4064)
		(drill 0.2032)
		(layers "F.Cu" "B.Cu")
		(net "GND")
	)
	(via
		(at 95.304102 -371.49913)
		(size 0.508)
		(drill 0.254)
		(layers "F.Cu" "B.Cu")
		(net "GND")
	)
	(via
		(at 44.340018 -248.335292)
		(size 0.4826)
		(drill 0.254)
		(layers "F.Cu" "B.Cu")
		(net "GND")
	)
	(via
		(at 121.691146 -390.160002)
		(size 0.4064)
		(drill 0.2032)
		(layers "F.Cu" "B.Cu")
		(net "GND")
	)
	(via
		(at 389.79475 -249.34418)
		(size 0.4064)
		(drill 0.2032)
		(layers "F.Cu" "B.Cu")
		(net "GND")
	)
	(via
		(at 415.083752 -284.034992)
		(size 0.4826)
		(drill 0.254)
		(layers "F.Cu" "B.Cu")
		(net "GND")
	)
	(via
		(at 82.551016 -403.830536)
		(size 0.4572)
		(drill 0.254)
		(layers "F.Cu" "B.Cu")
		(net "GND")
	)
	(via
		(at 81.701132 -234.764326)
		(size 0.4064)
		(drill 0.2032)
		(layers "F.Cu" "B.Cu")
		(net "GND")
	)
	(via
		(at 392.926316 -188.864494)
		(size 0.508)
		(drill 0.254)
		(layers "F.Cu" "B.Cu")
		(net "GND")
	)
	(via
		(at 387.914896 -254.204216)
		(size 0.4064)
		(drill 0.2032)
		(layers "F.Cu" "B.Cu")
		(net "GND")
	)
	(via
		(at 53.816504 -393.927838)
		(size 0.4572)
		(drill 0.254)
		(layers "F.Cu" "B.Cu")
		(net "GND")
	)
	(via
		(at 341.390986 -233.954066)
		(size 0.4064)
		(drill 0.2032)
		(layers "F.Cu" "B.Cu")
		(net "GND")
	)
	(via
		(at 398.070832 -172.029374)
		(size 0.508)
		(drill 0.254)
		(layers "F.Cu" "B.Cu")
		(net "GND")
	)
	(via
		(at 119.76481 -229.094538)
		(size 0.4064)
		(drill 0.2032)
		(layers "F.Cu" "B.Cu")
		(net "GND")
	)
	(via
		(at 378.04471 -230.714296)
		(size 0.4064)
		(drill 0.2032)
		(layers "F.Cu" "B.Cu")
		(net "GND")
	)
	(via
		(at 381.334772 -250.964192)
		(size 0.4064)
		(drill 0.2032)
		(layers "F.Cu" "B.Cu")
		(net "GND")
	)
	(via
		(at 191.160146 -308.685438)
		(size 0.4826)
		(drill 0.254)
		(layers "F.Cu" "B.Cu")
		(net "GND")
	)
	(via
		(at 371.46484 -229.094284)
		(size 0.4064)
		(drill 0.2032)
		(layers "F.Cu" "B.Cu")
		(net "GND")
	)
	(via
		(at 383.514854 -284.616144)
		(size 0.4064)
		(drill 0.2032)
		(layers "F.Cu" "B.Cu")
		(net "GND")
	)
	(via
		(at 146.860514 -407.638504)
		(size 0.4572)
		(drill 0.254)
		(layers "F.Cu" "B.Cu")
		(net "GND")
	)
	(via
		(at 349.689674 -163.078668)
		(size 0.49022)
		(drill 0.254)
		(layers "F.Cu" "B.Cu")
		(net "GND")
	)
	(via
		(at 347.33103 -283.806138)
		(size 0.4064)
		(drill 0.2032)
		(layers "F.Cu" "B.Cu")
		(net "GND")
	)
	(via
		(at 182.231792 -239.835436)
		(size 0.4826)
		(drill 0.254)
		(layers "F.Cu" "B.Cu")
		(net "GND")
	)
	(via
		(at 384.48107 -416.020504)
		(size 0.4572)
		(drill 0.254)
		(layers "F.Cu" "B.Cu")
		(net "GND")
	)
	(via
		(at 93.416628 -304.710592)
		(size 0.508)
		(drill 0.254)
		(layers "F.Cu" "B.Cu")
		(net "GND")
	)
	(via
		(at 467.5378 -300.787054)
		(size 0.508)
		(drill 0.254)
		(layers "F.Cu" "B.Cu")
		(net "GND")
	)
	(via
		(at 333.757524 -333.034386)
		(size 0.49022)
		(drill 0.254)
		(layers "F.Cu" "B.Cu")
		(net "GND")
	)
	(via
		(at 83.111086 -225.854514)
		(size 0.4064)
		(drill 0.2032)
		(layers "F.Cu" "B.Cu")
		(net "GND")
	)
	(via
		(at 218.959176 -73.671938)
		(size 0.508)
		(drill 0.254)
		(layers "F.Cu" "B.Cu")
		(net "GND")
	)
	(via
		(at 295.724072 -247.485154)
		(size 0.4826)
		(drill 0.254)
		(layers "F.Cu" "B.Cu")
		(net "GND")
	)
	(via
		(at 82.249772 -436.051198)
		(size 0.4572)
		(drill 0.2032)
		(layers "F.Cu" "B.Cu")
		(net "GND")
	)
	(via
		(at 116.197888 -261.323074)
		(size 0.4826)
		(drill 0.254)
		(layers "F.Cu" "B.Cu")
		(net "GND")
	)
	(via
		(at 85.528404 -410.030168)
		(size 0.4064)
		(drill 0.2032)
		(layers "F.Cu" "B.Cu")
		(net "GND")
	)
	(via
		(at 411.349698 -437.49976)
		(size 0.4572)
		(drill 0.2032)
		(layers "F.Cu" "B.Cu")
		(net "GND")
	)
	(via
		(at 49.568862 -426.662596)
		(size 0.508)
		(drill 0.254)
		(layers "F.Cu" "B.Cu")
		(net "GND")
	)
	(via
		(at 43.579034 -18.247106)
		(size 0.508)
		(drill 0.254)
		(layers "F.Cu" "B.Cu")
		(net "GND")
	)
	(via
		(at 115.534694 -236.384338)
		(size 0.4064)
		(drill 0.2032)
		(layers "F.Cu" "B.Cu")
		(net "GND")
	)
	(via
		(at 95.789242 -372.15953)
		(size 0.508)
		(drill 0.254)
		(layers "F.Cu" "B.Cu")
		(net "GND")
	)
	(via
		(at 347.506798 -310.463692)
		(size 0.508)
		(drill 0.254)
		(layers "F.Cu" "B.Cu")
		(net "GND")
	)
	(via
		(at 307.918358 -420.318184)
		(size 0.4572)
		(drill 0.254)
		(layers "F.Cu" "B.Cu")
		(net "GND")
	)
	(via
		(at 338.401152 -279.756108)
		(size 0.4064)
		(drill 0.2032)
		(layers "F.Cu" "B.Cu")
		(net "GND")
	)
	(via
		(at 70.659244 -404.46452)
		(size 0.4064)
		(drill 0.2032)
		(layers "F.Cu" "B.Cu")
		(net "GND")
	)
	(via
		(at 94.087442 -373.30253)
		(size 0.508)
		(drill 0.254)
		(layers "F.Cu" "B.Cu")
		(net "GND")
	)
	(via
		(at 348.911164 -240.434114)
		(size 0.4064)
		(drill 0.2032)
		(layers "F.Cu" "B.Cu")
		(net "GND")
	)
	(via
		(at 232.732072 -70.576186)
		(size 0.508)
		(drill 0.254)
		(layers "F.Cu" "B.Cu")
		(net "GND")
	)
	(via
		(at 51.465734 -10.16508)
		(size 0.508)
		(drill 0.254)
		(layers "F.Cu" "B.Cu")
		(net "GND")
	)
	(via
		(at 338.498942 -140.337286)
		(size 0.508)
		(drill 0.254)
		(layers "F.Cu" "B.Cu")
		(net "GND")
	)
	(via
		(at 34.919158 -344.781886)
		(size 0.49022)
		(drill 0.254)
		(layers "F.Cu" "B.Cu")
		(net "GND")
	)
	(via
		(at 150.561294 -310.054752)
		(size 0.508)
		(drill 0.254)
		(layers "F.Cu" "B.Cu")
		(net "GND")
	)
	(via
		(at 303.268126 -208.385156)
		(size 0.4826)
		(drill 0.254)
		(layers "F.Cu" "B.Cu")
		(net "GND")
	)
	(via
		(at 328.757026 -397.15313)
		(size 0.508)
		(drill 0.254)
		(layers "F.Cu" "B.Cu")
		(net "GND")
	)
	(via
		(at 65.249806 -438.499758)
		(size 0.4572)
		(drill 0.2032)
		(layers "F.Cu" "B.Cu")
		(net "GND")
	)
	(via
		(at 390.094724 -273.27606)
		(size 0.4064)
		(drill 0.2032)
		(layers "F.Cu" "B.Cu")
		(net "GND")
	)
	(via
		(at 383.514854 -294.335962)
		(size 0.4064)
		(drill 0.2032)
		(layers "F.Cu" "B.Cu")
		(net "GND")
	)
	(via
		(at 381.634746 -270.036036)
		(size 0.4064)
		(drill 0.2032)
		(layers "F.Cu" "B.Cu")
		(net "GND")
	)
	(via
		(at 233.707178 -317.942468)
		(size 0.508)
		(drill 0.254)
		(layers "F.Cu" "B.Cu")
		(net "GND")
	)
	(via
		(at 121.644664 -224.234502)
		(size 0.4064)
		(drill 0.2032)
		(layers "F.Cu" "B.Cu")
		(net "GND")
	)
	(via
		(at 12.095226 -107.10037)
		(size 0.508)
		(drill 0.254)
		(layers "F.Cu" "B.Cu")
		(net "GND")
	)
	(via
		(at 451.873366 -376.53087)
		(size 0.508)
		(drill 0.254)
		(layers "F.Cu" "B.Cu")
		(net "GND")
	)
	(via
		(at 361.894882 -268.416024)
		(size 0.4064)
		(drill 0.2032)
		(layers "F.Cu" "B.Cu")
		(net "GND")
	)
	(via
		(at 73.941686 -178.02479)
		(size 0.49022)
		(drill 0.254)
		(layers "F.Cu" "B.Cu")
		(net "GND")
	)
	(via
		(at 326.651112 -264.365994)
		(size 0.4064)
		(drill 0.2032)
		(layers "F.Cu" "B.Cu")
		(net "GND")
	)
	(via
		(at 122.800618 -53.27777)
		(size 0.508)
		(drill 0.254)
		(layers "F.Cu" "B.Cu")
		(net "GND")
	)
	(via
		(at 361.522264 -258.795012)
		(size 0.4826)
		(drill 0.254)
		(layers "F.Cu" "B.Cu")
		(net "GND")
	)
	(via
		(at 302.637952 -22.12975)
		(size 0.508)
		(drill 0.254)
		(layers "F.Cu" "B.Cu")
		(net "GND")
	)
	(via
		(at 368.955066 -425.018962)
		(size 0.508)
		(drill 0.254)
		(layers "F.Cu" "B.Cu")
		(net "GND")
	)
	(via
		(at 99.903534 -351.95002)
		(size 0.508)
		(drill 0.254)
		(layers "F.Cu" "B.Cu")
		(net "GND")
	)
	(via
		(at 346.39123 -274.086066)
		(size 0.4064)
		(drill 0.2032)
		(layers "F.Cu" "B.Cu")
		(net "GND")
	)
	(via
		(at 153.349706 -428.851314)
		(size 0.4572)
		(drill 0.2032)
		(layers "F.Cu" "B.Cu")
		(net "GND")
	)
	(via
		(at 119.76481 -222.61449)
		(size 0.4064)
		(drill 0.2032)
		(layers "F.Cu" "B.Cu")
		(net "GND")
	)
	(via
		(at 373.3165 -402.309838)
		(size 0.4572)
		(drill 0.254)
		(layers "F.Cu" "B.Cu")
		(net "GND")
	)
	(via
		(at 172.917104 -329.566524)
		(size 0.6604)
		(drill 0.3302)
		(layers "F.Cu" "B.Cu")
		(net "GND")
	)
	(via
		(at 429.288956 -18.247868)
		(size 0.508)
		(drill 0.254)
		(layers "F.Cu" "B.Cu")
		(net "GND")
	)
	(via
		(at 416.346132 -396.710662)
		(size 0.4064)
		(drill 0.2032)
		(layers "F.Cu" "B.Cu")
		(net "GND")
	)
	(via
		(at 206.248 -205.83525)
		(size 0.4826)
		(drill 0.254)
		(layers "F.Cu" "B.Cu")
		(net "GND")
	)
	(via
		(at 416.82797 -6.091174)
		(size 0.508)
		(drill 0.254)
		(layers "F.Cu" "B.Cu")
		(net "GND")
	)
	(via
		(at 314.406026 -420.952168)
		(size 0.4064)
		(drill 0.2032)
		(layers "F.Cu" "B.Cu")
		(net "GND")
	)
	(via
		(at 125.404626 -232.334308)
		(size 0.4064)
		(drill 0.2032)
		(layers "F.Cu" "B.Cu")
		(net "GND")
	)
	(via
		(at 36.795964 -232.18521)
		(size 0.4826)
		(drill 0.254)
		(layers "F.Cu" "B.Cu")
		(net "GND")
	)
	(via
		(at 88.281002 -242.864386)
		(size 0.4064)
		(drill 0.2032)
		(layers "F.Cu" "B.Cu")
		(net "GND")
	)
	(via
		(at 459.869286 -54.52364)
		(size 0.508)
		(drill 0.254)
		(layers "F.Cu" "B.Cu")
		(net "GND")
	)
	(via
		(at 100.031042 -235.574332)
		(size 0.4064)
		(drill 0.2032)
		(layers "F.Cu" "B.Cu")
		(net "GND")
	)
	(via
		(at 90.94089 -182.109872)
		(size 0.49022)
		(drill 0.254)
		(layers "F.Cu" "B.Cu")
		(net "GND")
	)
	(via
		(at 117.475 -420.497)
		(size 0.508)
		(drill 0.254)
		(layers "F.Cu" "B.Cu")
		(net "GND")
	)
	(via
		(at 149.565106 -407.00452)
		(size 0.4064)
		(drill 0.2032)
		(layers "F.Cu" "B.Cu")
		(net "GND")
	)
	(via
		(at 119.137684 -166.893748)
		(size 0.508)
		(drill 0.254)
		(layers "F.Cu" "B.Cu")
		(net "GND")
	)
	(via
		(at 289.564318 -278.085042)
		(size 0.4826)
		(drill 0.254)
		(layers "F.Cu" "B.Cu")
		(net "GND")
	)
	(via
		(at 298.40301 -345.566238)
		(size 0.49022)
		(drill 0.254)
		(layers "F.Cu" "B.Cu")
		(net "GND")
	)
	(via
		(at 97.040954 -284.616398)
		(size 0.4064)
		(drill 0.2032)
		(layers "F.Cu" "B.Cu")
		(net "GND")
	)
	(via
		(at 370.630958 -41.604184)
		(size 0.508)
		(drill 0.254)
		(layers "F.Cu" "B.Cu")
		(net "GND")
	)
	(via
		(at 371.764814 -282.186126)
		(size 0.4064)
		(drill 0.2032)
		(layers "F.Cu" "B.Cu")
		(net "GND")
	)
	(via
		(at 407.044144 -391.23493)
		(size 0.4064)
		(drill 0.2032)
		(layers "F.Cu" "B.Cu")
		(net "GND")
	)
	(via
		(at 94.861126 -249.344434)
		(size 0.4064)
		(drill 0.2032)
		(layers "F.Cu" "B.Cu")
		(net "GND")
	)
	(via
		(at 118.857522 -79.137002)
		(size 0.508)
		(drill 0.254)
		(layers "F.Cu" "B.Cu")
		(net "GND")
	)
	(via
		(at 86.701122 -276.516338)
		(size 0.4064)
		(drill 0.2032)
		(layers "F.Cu" "B.Cu")
		(net "GND")
	)
	(via
		(at 418.358066 -9.424924)
		(size 0.508)
		(drill 0.254)
		(layers "F.Cu" "B.Cu")
		(net "GND")
	)
	(via
		(at 139.974828 -241.244374)
		(size 0.4064)
		(drill 0.2032)
		(layers "F.Cu" "B.Cu")
		(net "GND")
	)
	(via
		(at 100.031042 -240.434368)
		(size 0.4064)
		(drill 0.2032)
		(layers "F.Cu" "B.Cu")
		(net "GND")
	)
	(via
		(at 83.88096 -261.93623)
		(size 0.4064)
		(drill 0.2032)
		(layers "F.Cu" "B.Cu")
		(net "GND")
	)
	(via
		(at 80.761078 -249.344434)
		(size 0.4064)
		(drill 0.2032)
		(layers "F.Cu" "B.Cu")
		(net "GND")
	)
	(via
		(at 99.190302 -369.03533)
		(size 0.508)
		(drill 0.254)
		(layers "F.Cu" "B.Cu")
		(net "GND")
	)
	(via
		(at 434.023516 -330.450952)
		(size 0.508)
		(drill 0.254)
		(layers "F.Cu" "B.Cu")
		(net "GND")
	)
	(via
		(at 347.031056 -232.334054)
		(size 0.4064)
		(drill 0.2032)
		(layers "F.Cu" "B.Cu")
		(net "GND")
	)
	(via
		(at 413.485584 -314.210192)
		(size 0.4826)
		(drill 0.254)
		(layers "F.Cu" "B.Cu")
		(net "GND")
	)
	(via
		(at 40.23995 -244.085364)
		(size 0.4826)
		(drill 0.254)
		(layers "F.Cu" "B.Cu")
		(net "GND")
	)
	(via
		(at 454.188068 -241.53495)
		(size 0.4826)
		(drill 0.254)
		(layers "F.Cu" "B.Cu")
		(net "GND")
	)
	(via
		(at 289.564318 -238.13516)
		(size 0.4826)
		(drill 0.254)
		(layers "F.Cu" "B.Cu")
		(net "GND")
	)
	(via
		(at 218.478608 -84.662518)
		(size 0.508)
		(drill 0.254)
		(layers "F.Cu" "B.Cu")
		(net "GND")
	)
	(via
		(at 73.361296 -403.830536)
		(size 0.4572)
		(drill 0.254)
		(layers "F.Cu" "B.Cu")
		(net "GND")
	)
	(via
		(at 364.884716 -222.614236)
		(size 0.4064)
		(drill 0.2032)
		(layers "F.Cu" "B.Cu")
		(net "GND")
	)
	(via
		(at 149.419056 -390.160002)
		(size 0.4064)
		(drill 0.2032)
		(layers "F.Cu" "B.Cu")
		(net "GND")
	)
	(via
		(at 102.38105 -234.764326)
		(size 0.4064)
		(drill 0.2032)
		(layers "F.Cu" "B.Cu")
		(net "GND")
	)
	(via
		(at 42.955718 -312.085228)
		(size 0.4826)
		(drill 0.254)
		(layers "F.Cu" "B.Cu")
		(net "GND")
	)
	(via
		(at 36.795964 -198.185278)
		(size 0.4826)
		(drill 0.254)
		(layers "F.Cu" "B.Cu")
		(net "GND")
	)
	(via
		(at 89.690956 -242.05438)
		(size 0.4064)
		(drill 0.2032)
		(layers "F.Cu" "B.Cu")
		(net "GND")
	)
	(via
		(at 396.397988 -385.38912)
		(size 0.508)
		(drill 0.254)
		(layers "F.Cu" "B.Cu")
		(net "GND")
	)
	(via
		(at 415.7472 -109.977428)
		(size 0.508)
		(drill 0.254)
		(layers "F.Cu" "B.Cu")
		(net "GND")
	)
	(via
		(at 364.24489 -287.046162)
		(size 0.4064)
		(drill 0.2032)
		(layers "F.Cu" "B.Cu")
		(net "GND")
	)
	(via
		(at 393.084812 -250.154186)
		(size 0.4064)
		(drill 0.2032)
		(layers "F.Cu" "B.Cu")
		(net "GND")
	)
	(via
		(at 380.224792 -272.466054)
		(size 0.4064)
		(drill 0.2032)
		(layers "F.Cu" "B.Cu")
		(net "GND")
	)
	(via
		(at 342.249506 -428.851314)
		(size 0.4572)
		(drill 0.2032)
		(layers "F.Cu" "B.Cu")
		(net "GND")
	)
	(via
		(at 387.185662 -415.38652)
		(size 0.4064)
		(drill 0.2032)
		(layers "F.Cu" "B.Cu")
		(net "GND")
	)
	(via
		(at 165.812216 -212.635338)
		(size 0.4826)
		(drill 0.254)
		(layers "F.Cu" "B.Cu")
		(net "GND")
	)
	(via
		(at 97.003362 -370.83873)
		(size 0.508)
		(drill 0.254)
		(layers "F.Cu" "B.Cu")
		(net "GND")
	)
	(via
		(at 40.23995 -298.485306)
		(size 0.4826)
		(drill 0.254)
		(layers "F.Cu" "B.Cu")
		(net "GND")
	)
	(via
		(at 361.424728 -278.946102)
		(size 0.4064)
		(drill 0.2032)
		(layers "F.Cu" "B.Cu")
		(net "GND")
	)
	(via
		(at 331.051154 -229.094284)
		(size 0.4064)
		(drill 0.2032)
		(layers "F.Cu" "B.Cu")
		(net "GND")
	)
	(via
		(at 108.961174 -238.00435)
		(size 0.4064)
		(drill 0.2032)
		(layers "F.Cu" "B.Cu")
		(net "GND")
	)
	(via
		(at 264.210546 -12.542266)
		(size 0.508)
		(drill 0.254)
		(layers "F.Cu" "B.Cu")
		(net "GND")
	)
	(via
		(at 426.90542 -387.218428)
		(size 0.508)
		(drill 0.254)
		(layers "F.Cu" "B.Cu")
		(net "GND")
	)
	(via
		(at 349.851218 -230.714296)
		(size 0.4064)
		(drill 0.2032)
		(layers "F.Cu" "B.Cu")
		(net "GND")
	)
	(via
		(at 122.81789 -12.542266)
		(size 0.508)
		(drill 0.254)
		(layers "F.Cu" "B.Cu")
		(net "GND")
	)
	(via
		(at 151.182578 -409.396184)
		(size 0.4572)
		(drill 0.254)
		(layers "F.Cu" "B.Cu")
		(net "GND")
	)
	(via
		(at 216.713054 -75.555348)
		(size 0.508)
		(drill 0.254)
		(layers "F.Cu" "B.Cu")
		(net "GND")
	)
	(via
		(at 250.534424 -275.363432)
		(size 0.508)
		(drill 0.254)
		(layers "F.Cu" "B.Cu")
		(net "GND")
	)
	(via
		(at 361.424728 -291.905944)
		(size 0.4064)
		(drill 0.2032)
		(layers "F.Cu" "B.Cu")
		(net "GND")
	)
	(via
		(at 331.165454 -412.212536)
		(size 0.4572)
		(drill 0.254)
		(layers "F.Cu" "B.Cu")
		(net "GND")
	)
	(via
		(at 397.98244 -379.88113)
		(size 0.508)
		(drill 0.254)
		(layers "F.Cu" "B.Cu")
		(net "GND")
	)
	(via
		(at 184.234582 -349.356172)
		(size 0.49022)
		(drill 0.254)
		(layers "F.Cu" "B.Cu")
		(net "GND")
	)
	(via
		(at 107.257342 -336.034634)
		(size 0.508)
		(drill 0.254)
		(layers "F.Cu" "B.Cu")
		(net "GND")
	)
	(via
		(at 331.051154 -240.434114)
		(size 0.4064)
		(drill 0.2032)
		(layers "F.Cu" "B.Cu")
		(net "GND")
	)
	(via
		(at 340.24951 -431.451258)
		(size 0.4572)
		(drill 0.2032)
		(layers "F.Cu" "B.Cu")
		(net "GND")
	)
	(via
		(at 279.96642 -351.73158)
		(size 0.508)
		(drill 0.254)
		(layers "F.Cu" "B.Cu")
		(net "GND")
	)
	(via
		(at 297.108372 -294.235124)
		(size 0.4826)
		(drill 0.254)
		(layers "F.Cu" "B.Cu")
		(net "GND")
	)
	(via
		(at 359.195878 -170.34891)
		(size 0.508)
		(drill 0.254)
		(layers "F.Cu" "B.Cu")
		(net "GND")
	)
	(via
		(at 18.231866 -39.927276)
		(size 0.508)
		(drill 0.254)
		(layers "F.Cu" "B.Cu")
		(net "GND")
	)
	(via
		(at 43.184318 -193.996564)
		(size 0.4826)
		(drill 0.254)
		(layers "F.Cu" "B.Cu")
		(net "GND")
	)
	(via
		(at 136.98474 -277.326344)
		(size 0.4064)
		(drill 0.2032)
		(layers "F.Cu" "B.Cu")
		(net "GND")
	)
	(via
		(at 102.211124 -280.566368)
		(size 0.4064)
		(drill 0.2032)
		(layers "F.Cu" "B.Cu")
		(net "GND")
	)
	(via
		(at 331.521054 -249.34418)
		(size 0.4064)
		(drill 0.2032)
		(layers "F.Cu" "B.Cu")
		(net "GND")
	)
	(via
		(at 140.274802 -279.756362)
		(size 0.4064)
		(drill 0.2032)
		(layers "F.Cu" "B.Cu")
		(net "GND")
	)
	(via
		(at 389.79475 -234.764072)
		(size 0.4064)
		(drill 0.2032)
		(layers "F.Cu" "B.Cu")
		(net "GND")
	)
	(via
		(at 187.666122 -6.042152)
		(size 0.508)
		(drill 0.254)
		(layers "F.Cu" "B.Cu")
		(net "GND")
	)
	(via
		(at 36.795964 -243.235226)
		(size 0.4826)
		(drill 0.254)
		(layers "F.Cu" "B.Cu")
		(net "GND")
	)
	(via
		(at 364.24489 -282.186126)
		(size 0.4064)
		(drill 0.2032)
		(layers "F.Cu" "B.Cu")
		(net "GND")
	)
	(via
		(at 338.101178 -250.964192)
		(size 0.4064)
		(drill 0.2032)
		(layers "F.Cu" "B.Cu")
		(net "GND")
	)
	(via
		(at 290.70681 -344.77706)
		(size 0.49022)
		(drill 0.254)
		(layers "F.Cu" "B.Cu")
		(net "GND")
	)
	(via
		(at 314.761372 -33.715706)
		(size 0.508)
		(drill 0.254)
		(layers "F.Cu" "B.Cu")
		(net "GND")
	)
	(via
		(at 403.716744 -141.087602)
		(size 0.508)
		(drill 0.254)
		(layers "F.Cu" "B.Cu")
		(net "GND")
	)
	(via
		(at 211.46135 -68.219066)
		(size 0.508)
		(drill 0.254)
		(layers "F.Cu" "B.Cu")
		(net "GND")
	)
	(via
		(at 29.618178 -6.091174)
		(size 0.508)
		(drill 0.254)
		(layers "F.Cu" "B.Cu")
		(net "GND")
	)
	(via
		(at 205.351126 -344.61323)
		(size 0.508)
		(drill 0.254)
		(layers "F.Cu" "B.Cu")
		(net "GND")
	)
	(via
		(at 421.296338 -200.735184)
		(size 0.4826)
		(drill 0.254)
		(layers "F.Cu" "B.Cu")
		(net "GND")
	)
	(via
		(at 79.746094 -153.565352)
		(size 0.508)
		(drill 0.254)
		(layers "F.Cu" "B.Cu")
		(net "GND")
	)
	(via
		(at 41.62425 -294.235378)
		(size 0.4826)
		(drill 0.254)
		(layers "F.Cu" "B.Cu")
		(net "GND")
	)
	(via
		(at 29.252164 -213.485222)
		(size 0.4826)
		(drill 0.254)
		(layers "F.Cu" "B.Cu")
		(net "GND")
	)
	(via
		(at 298.43984 -230.485188)
		(size 0.4826)
		(drill 0.254)
		(layers "F.Cu" "B.Cu")
		(net "GND")
	)
	(via
		(at 363.097318 -335.139538)
		(size 0.508)
		(drill 0.254)
		(layers "F.Cu" "B.Cu")
		(net "GND")
	)
	(via
		(at 328.53122 -282.186126)
		(size 0.4064)
		(drill 0.2032)
		(layers "F.Cu" "B.Cu")
		(net "GND")
	)
	(via
		(at 25.754584 -394.403326)
		(size 0.508)
		(drill 0.254)
		(layers "F.Cu" "B.Cu")
		(net "GND")
	)
	(via
		(at 67.234816 -403.830536)
		(size 0.4572)
		(drill 0.254)
		(layers "F.Cu" "B.Cu")
		(net "GND")
	)
	(via
		(at 31.145734 -10.16508)
		(size 0.508)
		(drill 0.254)
		(layers "F.Cu" "B.Cu")
		(net "GND")
	)
	(via
		(at 353.141026 -249.34418)
		(size 0.4064)
		(drill 0.2032)
		(layers "F.Cu" "B.Cu")
		(net "GND")
	)
	(via
		(at 372.874794 -249.34418)
		(size 0.4064)
		(drill 0.2032)
		(layers "F.Cu" "B.Cu")
		(net "GND")
	)
	(via
		(at 431.36566 -10.16508)
		(size 0.508)
		(drill 0.254)
		(layers "F.Cu" "B.Cu")
		(net "GND")
	)
	(via
		(at 65.628266 -169.327576)
		(size 0.49022)
		(drill 0.254)
		(layers "F.Cu" "B.Cu")
		(net "GND")
	)
	(via
		(at 59.231276 -357.466646)
		(size 0.508)
		(drill 0.254)
		(layers "F.Cu" "B.Cu")
		(net "GND")
	)
	(via
		(at 361.424728 -283.806138)
		(size 0.4064)
		(drill 0.2032)
		(layers "F.Cu" "B.Cu")
		(net "GND")
	)
	(via
		(at 389.07593 -420.318184)
		(size 0.4572)
		(drill 0.254)
		(layers "F.Cu" "B.Cu")
		(net "GND")
	)
	(via
		(at 442.805566 -425.438824)
		(size 0.508)
		(drill 0.254)
		(layers "F.Cu" "B.Cu")
		(net "GND")
	)
	(via
		(at 209.97291 -107.54995)
		(size 0.508)
		(drill 0.254)
		(layers "F.Cu" "B.Cu")
		(net "GND")
	)
	(via
		(at 140.744702 -280.566368)
		(size 0.4064)
		(drill 0.2032)
		(layers "F.Cu" "B.Cu")
		(net "GND")
	)
	(via
		(at 374.516396 -391.23493)
		(size 0.4064)
		(drill 0.2032)
		(layers "F.Cu" "B.Cu")
		(net "GND")
	)
	(via
		(at 145.144744 -245.294404)
		(size 0.4064)
		(drill 0.2032)
		(layers "F.Cu" "B.Cu")
		(net "GND")
	)
	(via
		(at 391.504932 -261.12597)
		(size 0.4064)
		(drill 0.2032)
		(layers "F.Cu" "B.Cu")
		(net "GND")
	)
	(via
		(at 358.141016 -279.756108)
		(size 0.4064)
		(drill 0.2032)
		(layers "F.Cu" "B.Cu")
		(net "GND")
	)
	(via
		(at 185.787538 -348.05112)
		(size 0.508)
		(drill 0.254)
		(layers "F.Cu" "B.Cu")
		(net "GND")
	)
	(via
		(at 287.062418 -286.16021)
		(size 0.4826)
		(drill 0.254)
		(layers "F.Cu" "B.Cu")
		(net "GND")
	)
	(via
		(at 349.381064 -221.80423)
		(size 0.4064)
		(drill 0.2032)
		(layers "F.Cu" "B.Cu")
		(net "GND")
	)
	(via
		(at 21.336 -361.061)
		(size 0.508)
		(drill 0.254)
		(layers "F.Cu" "B.Cu")
		(net "GND")
	)
	(via
		(at 374.284748 -243.674138)
		(size 0.4064)
		(drill 0.2032)
		(layers "F.Cu" "B.Cu")
		(net "GND")
	)
	(via
		(at 88.580976 -273.276314)
		(size 0.4064)
		(drill 0.2032)
		(layers "F.Cu" "B.Cu")
		(net "GND")
	)
	(via
		(at 406.897586 -343.350342)
		(size 0.508)
		(drill 0.254)
		(layers "F.Cu" "B.Cu")
		(net "GND")
	)
	(via
		(at 367.641632 -376.75693)
		(size 0.508)
		(drill 0.254)
		(layers "F.Cu" "B.Cu")
		(net "GND")
	)
	(via
		(at 146.282918 -107.03306)
		(size 0.508)
		(drill 0.254)
		(layers "F.Cu" "B.Cu")
		(net "GND")
	)
	(via
		(at 343.105486 -305.390042)
		(size 0.508)
		(drill 0.254)
		(layers "F.Cu" "B.Cu")
		(net "GND")
	)
	(via
		(at 132.68325 -154.542744)
		(size 0.49022)
		(drill 0.254)
		(layers "F.Cu" "B.Cu")
		(net "GND")
	)
	(via
		(at 72.115934 -328.10196)
		(size 0.508)
		(drill 0.254)
		(layers "F.Cu" "B.Cu")
		(net "GND")
	)
	(via
		(at 24.764492 -390.8425)
		(size 0.49022)
		(drill 0.254)
		(layers "F.Cu" "B.Cu")
		(net "GND")
	)
	(via
		(at 443.6618 -314.210192)
		(size 0.4826)
		(drill 0.254)
		(layers "F.Cu" "B.Cu")
		(net "GND")
	)
	(via
		(at 93.751146 -274.08632)
		(size 0.4064)
		(drill 0.2032)
		(layers "F.Cu" "B.Cu")
		(net "GND")
	)
	(via
		(at 109.191044 -375.793)
		(size 0.508)
		(drill 0.254)
		(layers "F.Cu" "B.Cu")
		(net "GND")
	)
	(via
		(at 421.296338 -287.435036)
		(size 0.4826)
		(drill 0.254)
		(layers "F.Cu" "B.Cu")
		(net "GND")
	)
	(via
		(at 421.01897 -398.542002)
		(size 0.4064)
		(drill 0.2032)
		(layers "F.Cu" "B.Cu")
		(net "GND")
	)
	(via
		(at 366.594898 -270.036036)
		(size 0.4064)
		(drill 0.2032)
		(layers "F.Cu" "B.Cu")
		(net "GND")
	)
	(via
		(at 255.927098 -208.852008)
		(size 0.508)
		(drill 0.254)
		(layers "F.Cu" "B.Cu")
		(net "GND")
	)
	(via
		(at 335.281016 -223.424242)
		(size 0.4064)
		(drill 0.2032)
		(layers "F.Cu" "B.Cu")
		(net "GND")
	)
	(via
		(at 94.087442 -374.62333)
		(size 0.508)
		(drill 0.254)
		(layers "F.Cu" "B.Cu")
		(net "GND")
	)
	(via
		(at 413.349694 -439.651394)
		(size 0.4572)
		(drill 0.2032)
		(layers "F.Cu" "B.Cu")
		(net "GND")
	)
	(via
		(at 100.971096 -256.634488)
		(size 0.4064)
		(drill 0.2032)
		(layers "F.Cu" "B.Cu")
		(net "GND")
	)
	(via
		(at 425.73194 -110.280958)
		(size 0.6604)
		(drill 0.3302)
		(layers "F.Cu" "B.Cu")
		(net "GND")
	)
	(via
		(at 347.801184 -273.27606)
		(size 0.4064)
		(drill 0.2032)
		(layers "F.Cu" "B.Cu")
		(net "GND")
	)
	(via
		(at 376.164856 -224.234248)
		(size 0.4064)
		(drill 0.2032)
		(layers "F.Cu" "B.Cu")
		(net "GND")
	)
	(via
		(at 443.6618 -211.360004)
		(size 0.4826)
		(drill 0.254)
		(layers "F.Cu" "B.Cu")
		(net "GND")
	)
	(via
		(at 76.338684 -407.00452)
		(size 0.4064)
		(drill 0.2032)
		(layers "F.Cu" "B.Cu")
		(net "GND")
	)
	(via
		(at 404.358348 -141.087602)
		(size 0.508)
		(drill 0.254)
		(layers "F.Cu" "B.Cu")
		(net "GND")
	)
	(via
		(at 118.374414 -422.887902)
		(size 0.508)
		(drill 0.254)
		(layers "F.Cu" "B.Cu")
		(net "GND")
	)
	(via
		(at 179.732432 -17.708372)
		(size 0.508)
		(drill 0.254)
		(layers "F.Cu" "B.Cu")
		(net "GND")
	)
	(via
		(at 380.224792 -283.806138)
		(size 0.4064)
		(drill 0.2032)
		(layers "F.Cu" "B.Cu")
		(net "GND")
	)
	(via
		(at 290.04641 -345.566238)
		(size 0.49022)
		(drill 0.254)
		(layers "F.Cu" "B.Cu")
		(net "GND")
	)
	(via
		(at 402.587714 -420.318184)
		(size 0.4572)
		(drill 0.254)
		(layers "F.Cu" "B.Cu")
		(net "GND")
	)
	(via
		(at 17.608042 -245.785386)
		(size 0.4826)
		(drill 0.254)
		(layers "F.Cu" "B.Cu")
		(net "GND")
	)
	(via
		(at 151.455374 -403.830536)
		(size 0.4572)
		(drill 0.254)
		(layers "F.Cu" "B.Cu")
		(net "GND")
	)
	(via
		(at 380.224792 -291.905944)
		(size 0.4064)
		(drill 0.2032)
		(layers "F.Cu" "B.Cu")
		(net "GND")
	)
	(via
		(at 39.986966 -6.091174)
		(size 0.508)
		(drill 0.254)
		(layers "F.Cu" "B.Cu")
		(net "GND")
	)
	(via
		(at 467.5378 -144.323054)
		(size 0.508)
		(drill 0.254)
		(layers "F.Cu" "B.Cu")
		(net "GND")
	)
	(via
		(at 321.975734 -420.318184)
		(size 0.4572)
		(drill 0.254)
		(layers "F.Cu" "B.Cu")
		(net "GND")
	)
	(via
		(at 431.55616 -198.185024)
		(size 0.4826)
		(drill 0.254)
		(layers "F.Cu" "B.Cu")
		(net "GND")
	)
	(via
		(at 386.804916 -275.706078)
		(size 0.4064)
		(drill 0.2032)
		(layers "F.Cu" "B.Cu")
		(net "GND")
	)
	(via
		(at 202.147932 -225.385376)
		(size 0.4826)
		(drill 0.254)
		(layers "F.Cu" "B.Cu")
		(net "GND")
	)
	(via
		(at 310.75757 -23.201884)
		(size 0.508)
		(drill 0.254)
		(layers "F.Cu" "B.Cu")
		(net "GND")
	)
	(via
		(at 142.154656 -284.616398)
		(size 0.4064)
		(drill 0.2032)
		(layers "F.Cu" "B.Cu")
		(net "GND")
	)
	(via
		(at 55.142638 -359.121202)
		(size 0.508)
		(drill 0.254)
		(layers "F.Cu" "B.Cu")
		(net "GND")
	)
	(via
		(at 352.335338 -419.046152)
		(size 0.4572)
		(drill 0.254)
		(layers "F.Cu" "B.Cu")
		(net "GND")
	)
	(via
		(at 413.309054 -419.046152)
		(size 0.4572)
		(drill 0.254)
		(layers "F.Cu" "B.Cu")
		(net "GND")
	)
	(via
		(at 346.683584 -378.07773)
		(size 0.508)
		(drill 0.254)
		(layers "F.Cu" "B.Cu")
		(net "GND")
	)
	(via
		(at 276.73681 -344.77706)
		(size 0.49022)
		(drill 0.254)
		(layers "F.Cu" "B.Cu")
		(net "GND")
	)
	(via
		(at 338.401152 -268.416024)
		(size 0.4064)
		(drill 0.2032)
		(layers "F.Cu" "B.Cu")
		(net "GND")
	)
	(via
		(at 375.9962 -177.2285)
		(size 0.508)
		(drill 0.254)
		(layers "F.Cu" "B.Cu")
		(net "GND")
	)
	(via
		(at 99.090988 -238.814356)
		(size 0.4064)
		(drill 0.2032)
		(layers "F.Cu" "B.Cu")
		(net "GND")
	)
	(via
		(at 124.7648 -278.946356)
		(size 0.4064)
		(drill 0.2032)
		(layers "F.Cu" "B.Cu")
		(net "GND")
	)
	(via
		(at 317.016384 -391.23493)
		(size 0.4064)
		(drill 0.2032)
		(layers "F.Cu" "B.Cu")
		(net "GND")
	)
	(via
		(at 336.642964 -150.500588)
		(size 0.508)
		(drill 0.254)
		(layers "F.Cu" "B.Cu")
		(net "GND")
	)
	(via
		(at 169.645584 -285.310326)
		(size 0.4826)
		(drill 0.254)
		(layers "F.Cu" "B.Cu")
		(net "GND")
	)
	(via
		(at 393.384786 -288.66592)
		(size 0.4064)
		(drill 0.2032)
		(layers "F.Cu" "B.Cu")
		(net "GND")
	)
	(via
		(at 376.82297 -413.480504)
		(size 0.4572)
		(drill 0.254)
		(layers "F.Cu" "B.Cu")
		(net "GND")
	)
	(via
		(at 99.861116 -271.656302)
		(size 0.4064)
		(drill 0.2032)
		(layers "F.Cu" "B.Cu")
		(net "GND")
	)
	(via
		(at 115.666266 -173.073568)
		(size 0.49022)
		(drill 0.254)
		(layers "F.Cu" "B.Cu")
		(net "GND")
	)
	(via
		(at 35.411664 -209.235294)
		(size 0.4826)
		(drill 0.254)
		(layers "F.Cu" "B.Cu")
		(net "GND")
	)
	(via
		(at 302.678084 -149.750018)
		(size 0.508)
		(drill 0.254)
		(layers "F.Cu" "B.Cu")
		(net "GND")
	)
	(via
		(at 135.574786 -263.556242)
		(size 0.4064)
		(drill 0.2032)
		(layers "F.Cu" "B.Cu")
		(net "GND")
	)
	(via
		(at 30.484064 -81.440274)
		(size 0.508)
		(drill 0.254)
		(layers "F.Cu" "B.Cu")
		(net "GND")
	)
	(via
		(at 441.230004 -356.574852)
		(size 0.508)
		(drill 0.254)
		(layers "F.Cu" "B.Cu")
		(net "GND")
	)
	(via
		(at 155.594304 -373.30253)
		(size 0.508)
		(drill 0.254)
		(layers "F.Cu" "B.Cu")
		(net "GND")
	)
	(via
		(at 141.058392 -383.02946)
		(size 0.508)
		(drill 0.254)
		(layers "F.Cu" "B.Cu")
		(net "GND")
	)
	(via
		(at 300.541436 -376.75693)
		(size 0.508)
		(drill 0.254)
		(layers "F.Cu" "B.Cu")
		(net "GND")
	)
	(via
		(at 421.682164 -349.175578)
		(size 0.49022)
		(drill 0.254)
		(layers "F.Cu" "B.Cu")
		(net "GND")
	)
	(via
		(at 160.218882 -390.160002)
		(size 0.4064)
		(drill 0.2032)
		(layers "F.Cu" "B.Cu")
		(net "GND")
	)
	(via
		(at 99.561142 -239.624362)
		(size 0.4064)
		(drill 0.2032)
		(layers "F.Cu" "B.Cu")
		(net "GND")
	)
	(via
		(at 110.371128 -227.474526)
		(size 0.4064)
		(drill 0.2032)
		(layers "F.Cu" "B.Cu")
		(net "GND")
	)
	(via
		(at 277.192232 -235.585)
		(size 0.4826)
		(drill 0.254)
		(layers "F.Cu" "B.Cu")
		(net "GND")
	)
	(via
		(at 72.02551 -179.560982)
		(size 0.49022)
		(drill 0.254)
		(layers "F.Cu" "B.Cu")
		(net "GND")
	)
	(via
		(at 147.444206 -391.830814)
		(size 0.4064)
		(drill 0.2032)
		(layers "F.Cu" "B.Cu")
		(net "GND")
	)
	(via
		(at 32.695896 -264.485374)
		(size 0.4826)
		(drill 0.254)
		(layers "F.Cu" "B.Cu")
		(net "GND")
	)
	(via
		(at 344.199718 -163.72332)
		(size 0.508)
		(drill 0.254)
		(layers "F.Cu" "B.Cu")
		(net "GND")
	)
	(via
		(at 266.93241 -228.785166)
		(size 0.4826)
		(drill 0.254)
		(layers "F.Cu" "B.Cu")
		(net "GND")
	)
	(via
		(at 433.349654 -162.981132)
		(size 0.508)
		(drill 0.254)
		(layers "F.Cu" "B.Cu")
		(net "GND")
	)
	(via
		(at 347.031056 -237.19409)
		(size 0.4064)
		(drill 0.2032)
		(layers "F.Cu" "B.Cu")
		(net "GND")
	)
	(via
		(at 164.103304 -372.15953)
		(size 0.508)
		(drill 0.254)
		(layers "F.Cu" "B.Cu")
		(net "GND")
	)
	(via
		(at 287.062418 -295.510204)
		(size 0.4826)
		(drill 0.254)
		(layers "F.Cu" "B.Cu")
		(net "GND")
	)
	(via
		(at 370.524786 -253.39421)
		(size 0.4064)
		(drill 0.2032)
		(layers "F.Cu" "B.Cu")
		(net "GND")
	)
	(via
		(at 93.280992 -276.516338)
		(size 0.4064)
		(drill 0.2032)
		(layers "F.Cu" "B.Cu")
		(net "GND")
	)
	(via
		(at 108.02112 -239.624362)
		(size 0.4064)
		(drill 0.2032)
		(layers "F.Cu" "B.Cu")
		(net "GND")
	)
	(via
		(at 128.994662 -278.13635)
		(size 0.4064)
		(drill 0.2032)
		(layers "F.Cu" "B.Cu")
		(net "GND")
	)
	(via
		(at 180.900324 -296.785284)
		(size 0.4826)
		(drill 0.254)
		(layers "F.Cu" "B.Cu")
		(net "GND")
	)
	(via
		(at 180.900324 -294.235378)
		(size 0.4826)
		(drill 0.254)
		(layers "F.Cu" "B.Cu")
		(net "GND")
	)
	(via
		(at 173.653196 -386.660898)
		(size 0.508)
		(drill 0.254)
		(layers "F.Cu" "B.Cu")
		(net "GND")
	)
	(via
		(at 459.325218 -56.5023)
		(size 0.508)
		(drill 0.254)
		(layers "F.Cu" "B.Cu")
		(net "GND")
	)
	(via
		(at 393.084812 -251.774198)
		(size 0.4064)
		(drill 0.2032)
		(layers "F.Cu" "B.Cu")
		(net "GND")
	)
	(via
		(at 309.449978 -417.778184)
		(size 0.4572)
		(drill 0.254)
		(layers "F.Cu" "B.Cu")
		(net "GND")
	)
	(via
		(at 297.108372 -212.635084)
		(size 0.4826)
		(drill 0.254)
		(layers "F.Cu" "B.Cu")
		(net "GND")
	)
	(via
		(at 364.24489 -283.806138)
		(size 0.4064)
		(drill 0.2032)
		(layers "F.Cu" "B.Cu")
		(net "GND")
	)
	(via
		(at 90.461084 -268.416278)
		(size 0.4064)
		(drill 0.2032)
		(layers "F.Cu" "B.Cu")
		(net "GND")
	)
	(via
		(at 388.384796 -253.39421)
		(size 0.4064)
		(drill 0.2032)
		(layers "F.Cu" "B.Cu")
		(net "GND")
	)
	(via
		(at 43.222418 -304.010314)
		(size 0.4826)
		(drill 0.254)
		(layers "F.Cu" "B.Cu")
		(net "GND")
	)
	(via
		(at 429.568102 -9.424924)
		(size 0.508)
		(drill 0.254)
		(layers "F.Cu" "B.Cu")
		(net "GND")
	)
	(via
		(at 140.744702 -288.666174)
		(size 0.4064)
		(drill 0.2032)
		(layers "F.Cu" "B.Cu")
		(net "GND")
	)
	(via
		(at 202.147932 -272.135346)
		(size 0.4826)
		(drill 0.254)
		(layers "F.Cu" "B.Cu")
		(net "GND")
	)
	(via
		(at 274.247864 -193.10731)
		(size 0.4826)
		(drill 0.254)
		(layers "F.Cu" "B.Cu")
		(net "GND")
	)
	(via
		(at 78.711044 -277.326344)
		(size 0.4064)
		(drill 0.2032)
		(layers "F.Cu" "B.Cu")
		(net "GND")
	)
	(via
		(at 185.000392 -349.98025)
		(size 0.49022)
		(drill 0.254)
		(layers "F.Cu" "B.Cu")
		(net "GND")
	)
	(via
		(at 197.3199 -293.38524)
		(size 0.4826)
		(drill 0.254)
		(layers "F.Cu" "B.Cu")
		(net "GND")
	)
	(via
		(at 14.170406 -383.342896)
		(size 0.508)
		(drill 0.254)
		(layers "F.Cu" "B.Cu")
		(net "GND")
	)
	(via
		(at 358.141016 -276.516084)
		(size 0.4064)
		(drill 0.2032)
		(layers "F.Cu" "B.Cu")
		(net "GND")
	)
	(via
		(at 102.38105 -241.244374)
		(size 0.4064)
		(drill 0.2032)
		(layers "F.Cu" "B.Cu")
		(net "GND")
	)
	(via
		(at 225.69424 -119.259858)
		(size 0.508)
		(drill 0.254)
		(layers "F.Cu" "B.Cu")
		(net "GND")
	)
	(via
		(at 366.764824 -235.574078)
		(size 0.4064)
		(drill 0.2032)
		(layers "F.Cu" "B.Cu")
		(net "GND")
	)
	(via
		(at 101.74097 -266.796266)
		(size 0.4064)
		(drill 0.2032)
		(layers "F.Cu" "B.Cu")
		(net "GND")
	)
	(via
		(at 407.290778 -331.790548)
		(size 0.508)
		(drill 0.254)
		(layers "F.Cu" "B.Cu")
		(net "GND")
	)
	(via
		(at 119.59463 -266.796266)
		(size 0.4064)
		(drill 0.2032)
		(layers "F.Cu" "B.Cu")
		(net "GND")
	)
	(via
		(at 386.504942 -255.014222)
		(size 0.4064)
		(drill 0.2032)
		(layers "F.Cu" "B.Cu")
		(net "GND")
	)
	(via
		(at 49.168304 -296.785284)
		(size 0.4826)
		(drill 0.254)
		(layers "F.Cu" "B.Cu")
		(net "GND")
	)
	(via
		(at 436.384446 -294.235124)
		(size 0.4826)
		(drill 0.254)
		(layers "F.Cu" "B.Cu")
		(net "GND")
	)
	(via
		(at 366.661954 -135.970772)
		(size 0.508)
		(drill 0.254)
		(layers "F.Cu" "B.Cu")
		(net "GND")
	)
	(via
		(at 367.064798 -272.466054)
		(size 0.4064)
		(drill 0.2032)
		(layers "F.Cu" "B.Cu")
		(net "GND")
	)
	(via
		(at 62.216538 -393.877038)
		(size 0.4572)
		(drill 0.254)
		(layers "F.Cu" "B.Cu")
		(net "GND")
	)
	(via
		(at 344.677238 -412.212536)
		(size 0.4572)
		(drill 0.254)
		(layers "F.Cu" "B.Cu")
		(net "GND")
	)
	(via
		(at 81.019396 -406.370536)
		(size 0.4572)
		(drill 0.254)
		(layers "F.Cu" "B.Cu")
		(net "GND")
	)
	(via
		(at 168.075102 -348.991174)
		(size 0.508)
		(drill 0.254)
		(layers "F.Cu" "B.Cu")
		(net "GND")
	)
	(via
		(at 328.231246 -250.154186)
		(size 0.4064)
		(drill 0.2032)
		(layers "F.Cu" "B.Cu")
		(net "GND")
	)
	(via
		(at 53.048154 -369.03533)
		(size 0.508)
		(drill 0.254)
		(layers "F.Cu" "B.Cu")
		(net "GND")
	)
	(via
		(at 445.151256 -396.884398)
		(size 0.49022)
		(drill 0.254)
		(layers "F.Cu" "B.Cu")
		(net "GND")
	)
	(via
		(at 169.1132 -388.76605)
		(size 0.508)
		(drill 0.254)
		(layers "F.Cu" "B.Cu")
		(net "GND")
	)
	(via
		(at 355.791008 -272.466054)
		(size 0.4064)
		(drill 0.2032)
		(layers "F.Cu" "B.Cu")
		(net "GND")
	)
	(via
		(at 419.912038 -234.735116)
		(size 0.4826)
		(drill 0.254)
		(layers "F.Cu" "B.Cu")
		(net "GND")
	)
	(via
		(at 295.724072 -298.485052)
		(size 0.4826)
		(drill 0.254)
		(layers "F.Cu" "B.Cu")
		(net "GND")
	)
	(via
		(at 32.695896 -252.58522)
		(size 0.4826)
		(drill 0.254)
		(layers "F.Cu" "B.Cu")
		(net "GND")
	)
	(via
		(at 119.76481 -225.854514)
		(size 0.4064)
		(drill 0.2032)
		(layers "F.Cu" "B.Cu")
		(net "GND")
	)
	(via
		(at 450.088 -252.584966)
		(size 0.4826)
		(drill 0.254)
		(layers "F.Cu" "B.Cu")
		(net "GND")
	)
	(via
		(at 307.348636 -376.75693)
		(size 0.508)
		(drill 0.254)
		(layers "F.Cu" "B.Cu")
		(net "GND")
	)
	(via
		(at 182.231792 -199.8853)
		(size 0.4826)
		(drill 0.254)
		(layers "F.Cu" "B.Cu")
		(net "GND")
	)
	(via
		(at 426.844714 -399.09369)
		(size 0.508)
		(drill 0.254)
		(layers "F.Cu" "B.Cu")
		(net "GND")
	)
	(via
		(at 138.564874 -238.814356)
		(size 0.4064)
		(drill 0.2032)
		(layers "F.Cu" "B.Cu")
		(net "GND")
	)
	(via
		(at 73.281286 -179.565046)
		(size 0.49022)
		(drill 0.254)
		(layers "F.Cu" "B.Cu")
		(net "GND")
	)
	(via
		(at 383.21488 -250.964192)
		(size 0.4064)
		(drill 0.2032)
		(layers "F.Cu" "B.Cu")
		(net "GND")
	)
	(via
		(at 375.970546 -12.542266)
		(size 0.508)
		(drill 0.254)
		(layers "F.Cu" "B.Cu")
		(net "GND")
	)
	(via
		(at 325.052944 -266.530074)
		(size 0.4064)
		(drill 0.2032)
		(layers "F.Cu" "B.Cu")
		(net "GND")
	)
	(via
		(at 321.249548 -433.747164)
		(size 0.4572)
		(drill 0.2032)
		(layers "F.Cu" "B.Cu")
		(net "GND")
	)
	(via
		(at 189.775846 -230.485442)
		(size 0.4826)
		(drill 0.254)
		(layers "F.Cu" "B.Cu")
		(net "GND")
	)
	(via
		(at 288.180018 -292.535102)
		(size 0.4826)
		(drill 0.254)
		(layers "F.Cu" "B.Cu")
		(net "GND")
	)
	(via
		(at 292.280086 -299.33519)
		(size 0.4826)
		(drill 0.254)
		(layers "F.Cu" "B.Cu")
		(net "GND")
	)
	(via
		(at 446.107566 -377.29287)
		(size 0.508)
		(drill 0.254)
		(layers "F.Cu" "B.Cu")
		(net "GND")
	)
	(via
		(at 118.354856 -247.724422)
		(size 0.4064)
		(drill 0.2032)
		(layers "F.Cu" "B.Cu")
		(net "GND")
	)
	(via
		(at 332.581504 -379.22073)
		(size 0.508)
		(drill 0.254)
		(layers "F.Cu" "B.Cu")
		(net "GND")
	)
	(via
		(at 360.042714 -350.820482)
		(size 0.508)
		(drill 0.254)
		(layers "F.Cu" "B.Cu")
		(net "GND")
	)
	(via
		(at 71.829676 -410.664152)
		(size 0.4572)
		(drill 0.254)
		(layers "F.Cu" "B.Cu")
		(net "GND")
	)
	(via
		(at 81.230978 -222.61449)
		(size 0.4064)
		(drill 0.2032)
		(layers "F.Cu" "B.Cu")
		(net "GND")
	)
	(via
		(at 388.21487 -281.37612)
		(size 0.4064)
		(drill 0.2032)
		(layers "F.Cu" "B.Cu")
		(net "GND")
	)
	(via
		(at 363.774736 -286.236156)
		(size 0.4064)
		(drill 0.2032)
		(layers "F.Cu" "B.Cu")
		(net "GND")
	)
	(via
		(at 317.249556 -434.899562)
		(size 0.4572)
		(drill 0.2032)
		(layers "F.Cu" "B.Cu")
		(net "GND")
	)
	(via
		(at 144.99844 -30.05074)
		(size 0.508)
		(drill 0.254)
		(layers "F.Cu" "B.Cu")
		(net "GND")
	)
	(via
		(at 118.824756 -251.774452)
		(size 0.4064)
		(drill 0.2032)
		(layers "F.Cu" "B.Cu")
		(net "GND")
	)
	(via
		(at 292.280086 -272.984976)
		(size 0.4826)
		(drill 0.254)
		(layers "F.Cu" "B.Cu")
		(net "GND")
	)
	(via
		(at 99.79914 -334.74152)
		(size 0.508)
		(drill 0.254)
		(layers "F.Cu" "B.Cu")
		(net "GND")
	)
	(via
		(at 315.935106 -418.412168)
		(size 0.4064)
		(drill 0.2032)
		(layers "F.Cu" "B.Cu")
		(net "GND")
	)
	(via
		(at 405.34971 -436.051198)
		(size 0.4572)
		(drill 0.2032)
		(layers "F.Cu" "B.Cu")
		(net "GND")
	)
	(via
		(at 50.659792 -403.830536)
		(size 0.4572)
		(drill 0.254)
		(layers "F.Cu" "B.Cu")
		(net "GND")
	)
	(via
		(at 29.252164 -241.535204)
		(size 0.4826)
		(drill 0.254)
		(layers "F.Cu" "B.Cu")
		(net "GND")
	)
	(via
		(at 411.349698 -426.69968)
		(size 0.4572)
		(drill 0.2032)
		(layers "F.Cu" "B.Cu")
		(net "GND")
	)
	(via
		(at 389.79475 -229.904036)
		(size 0.4064)
		(drill 0.2032)
		(layers "F.Cu" "B.Cu")
		(net "GND")
	)
	(via
		(at 122.081798 -403.830536)
		(size 0.4572)
		(drill 0.254)
		(layers "F.Cu" "B.Cu")
		(net "GND")
	)
	(via
		(at 61.778642 -386.449062)
		(size 0.4064)
		(drill 0.2032)
		(layers "F.Cu" "B.Cu")
		(net "GND")
	)
	(via
		(at 65.249806 -434.899562)
		(size 0.4572)
		(drill 0.2032)
		(layers "F.Cu" "B.Cu")
		(net "GND")
	)
	(via
		(at 65.894204 -163.78682)
		(size 0.508)
		(drill 0.254)
		(layers "F.Cu" "B.Cu")
		(net "GND")
	)
	(via
		(at 18.992342 -306.135278)
		(size 0.4826)
		(drill 0.254)
		(layers "F.Cu" "B.Cu")
		(net "GND")
	)
	(via
		(at 191.589914 -68.407788)
		(size 0.508)
		(drill 0.254)
		(layers "F.Cu" "B.Cu")
		(net "GND")
	)
	(via
		(at 446.644268 -265.335004)
		(size 0.4826)
		(drill 0.254)
		(layers "F.Cu" "B.Cu")
		(net "GND")
	)
	(via
		(at 243.981732 -422.15181)
		(size 0.508)
		(drill 0.254)
		(layers "F.Cu" "B.Cu")
		(net "GND")
	)
	(via
		(at 265.54811 -290.83508)
		(size 0.4826)
		(drill 0.254)
		(layers "F.Cu" "B.Cu")
		(net "GND")
	)
	(via
		(at 340.24951 -436.347362)
		(size 0.4572)
		(drill 0.2032)
		(layers "F.Cu" "B.Cu")
		(net "GND")
	)
	(via
		(at 318.365124 -333.055976)
		(size 0.49022)
		(drill 0.254)
		(layers "F.Cu" "B.Cu")
		(net "GND")
	)
	(via
		(at 427.456092 -249.185176)
		(size 0.4826)
		(drill 0.254)
		(layers "F.Cu" "B.Cu")
		(net "GND")
	)
	(via
		(at 171.132754 -19.835368)
		(size 0.508)
		(drill 0.254)
		(layers "F.Cu" "B.Cu")
		(net "GND")
	)
	(via
		(at 345.3257 -333.08925)
		(size 0.49022)
		(drill 0.254)
		(layers "F.Cu" "B.Cu")
		(net "GND")
	)
	(via
		(at 189.775846 -302.735234)
		(size 0.4826)
		(drill 0.254)
		(layers "F.Cu" "B.Cu")
		(net "GND")
	)
	(via
		(at 327.249536 -433.899564)
		(size 0.4572)
		(drill 0.2032)
		(layers "F.Cu" "B.Cu")
		(net "GND")
	)
	(via
		(at 45.389546 -4.32943)
		(size 0.508)
		(drill 0.254)
		(layers "F.Cu" "B.Cu")
		(net "GND")
	)
	(via
		(at 191.505586 -87.32266)
		(size 0.508)
		(drill 0.254)
		(layers "F.Cu" "B.Cu")
		(net "GND")
	)
	(via
		(at 135.104632 -269.226284)
		(size 0.4064)
		(drill 0.2032)
		(layers "F.Cu" "B.Cu")
		(net "GND")
	)
	(via
		(at 124.464826 -251.774452)
		(size 0.4064)
		(drill 0.2032)
		(layers "F.Cu" "B.Cu")
		(net "GND")
	)
	(via
		(at 337.631024 -237.19409)
		(size 0.4064)
		(drill 0.2032)
		(layers "F.Cu" "B.Cu")
		(net "GND")
	)
	(via
		(at 350.789748 -340.500462)
		(size 0.49022)
		(drill 0.254)
		(layers "F.Cu" "B.Cu")
		(net "GND")
	)
	(via
		(at 299.82414 -318.035178)
		(size 0.4826)
		(drill 0.254)
		(layers "F.Cu" "B.Cu")
		(net "GND")
	)
	(via
		(at 412.367984 -264.48512)
		(size 0.4826)
		(drill 0.254)
		(layers "F.Cu" "B.Cu")
		(net "GND")
	)
	(via
		(at 104.261158 -221.804484)
		(size 0.4064)
		(drill 0.2032)
		(layers "F.Cu" "B.Cu")
		(net "GND")
	)
	(via
		(at 17.608042 -233.035348)
		(size 0.4826)
		(drill 0.254)
		(layers "F.Cu" "B.Cu")
		(net "GND")
	)
	(via
		(at 63.43269 -38.784276)
		(size 0.508)
		(drill 0.254)
		(layers "F.Cu" "B.Cu")
		(net "GND")
	)
	(via
		(at 171.97197 -289.135312)
		(size 0.4826)
		(drill 0.254)
		(layers "F.Cu" "B.Cu")
		(net "GND")
	)
	(via
		(at 368.004852 -291.905944)
		(size 0.4064)
		(drill 0.2032)
		(layers "F.Cu" "B.Cu")
		(net "GND")
	)
	(via
		(at 331.521054 -236.384084)
		(size 0.4064)
		(drill 0.2032)
		(layers "F.Cu" "B.Cu")
		(net "GND")
	)
	(via
		(at 306.991004 -398.542002)
		(size 0.4064)
		(drill 0.2032)
		(layers "F.Cu" "B.Cu")
		(net "GND")
	)
	(via
		(at 303.268126 -264.48512)
		(size 0.4826)
		(drill 0.254)
		(layers "F.Cu" "B.Cu")
		(net "GND")
	)
	(via
		(at 312.454036 -380.54153)
		(size 0.508)
		(drill 0.254)
		(layers "F.Cu" "B.Cu")
		(net "GND")
	)
	(via
		(at 102.38105 -244.484398)
		(size 0.4064)
		(drill 0.2032)
		(layers "F.Cu" "B.Cu")
		(net "GND")
	)
	(via
		(at 156.25572 -12.495022)
		(size 0.508)
		(drill 0.254)
		(layers "F.Cu" "B.Cu")
		(net "GND")
	)
	(via
		(at 90.461084 -287.856422)
		(size 0.4064)
		(drill 0.2032)
		(layers "F.Cu" "B.Cu")
		(net "GND")
	)
	(via
		(at 97.040954 -274.896326)
		(size 0.4064)
		(drill 0.2032)
		(layers "F.Cu" "B.Cu")
		(net "GND")
	)
	(via
		(at 90.249756 -438.499758)
		(size 0.4572)
		(drill 0.2032)
		(layers "F.Cu" "B.Cu")
		(net "GND")
	)
	(via
		(at 356.014274 -170.64609)
		(size 0.49022)
		(drill 0.254)
		(layers "F.Cu" "B.Cu")
		(net "GND")
	)
	(via
		(at 392.349482 -432.451256)
		(size 0.4572)
		(drill 0.2032)
		(layers "F.Cu" "B.Cu")
		(net "GND")
	)
	(via
		(at 308.61635 -400.212814)
		(size 0.4064)
		(drill 0.2032)
		(layers "F.Cu" "B.Cu")
		(net "GND")
	)
	(via
		(at 2.76225 -138.105134)
		(size 0.508)
		(drill 0.254)
		(layers "F.Cu" "B.Cu")
		(net "GND")
	)
	(via
		(at 115.364768 -265.98626)
		(size 0.4064)
		(drill 0.2032)
		(layers "F.Cu" "B.Cu")
		(net "GND")
	)
	(via
		(at 173.868334 -38.730428)
		(size 0.508)
		(drill 0.254)
		(layers "F.Cu" "B.Cu")
		(net "GND")
	)
	(via
		(at 23.416768 -435.290214)
		(size 0.508)
		(drill 0.254)
		(layers "F.Cu" "B.Cu")
		(net "GND")
	)
	(via
		(at 98.921062 -294.336216)
		(size 0.4064)
		(drill 0.2032)
		(layers "F.Cu" "B.Cu")
		(net "GND")
	)
	(via
		(at 449.893944 -141.534896)
		(size 0.508)
		(drill 0.254)
		(layers "F.Cu" "B.Cu")
		(net "GND")
	)
	(via
		(at 365.82477 -225.85426)
		(size 0.4064)
		(drill 0.2032)
		(layers "F.Cu" "B.Cu")
		(net "GND")
	)
	(via
		(at 269.648178 -271.284954)
		(size 0.4826)
		(drill 0.254)
		(layers "F.Cu" "B.Cu")
		(net "GND")
	)
	(via
		(at 170.561 -134.493)
		(size 0.508)
		(drill 0.254)
		(layers "F.Cu" "B.Cu")
		(net "GND")
	)
	(via
		(at 455.41311 -0.762254)
		(size 0.508)
		(drill 0.254)
		(layers "F.Cu" "B.Cu")
		(net "GND")
	)
	(via
		(at 64.963294 -368.37493)
		(size 0.508)
		(drill 0.254)
		(layers "F.Cu" "B.Cu")
		(net "GND")
	)
	(via
		(at 302.150526 -276.810216)
		(size 0.4826)
		(drill 0.254)
		(layers "F.Cu" "B.Cu")
		(net "GND")
	)
	(via
		(at 342.801194 -239.624108)
		(size 0.4064)
		(drill 0.2032)
		(layers "F.Cu" "B.Cu")
		(net "GND")
	)
	(via
		(at 383.76225 -392.999722)
		(size 0.4064)
		(drill 0.2032)
		(layers "F.Cu" "B.Cu")
		(net "GND")
	)
	(via
		(at 132.284724 -291.906198)
		(size 0.4064)
		(drill 0.2032)
		(layers "F.Cu" "B.Cu")
		(net "GND")
	)
	(via
		(at 21.773388 -372.12905)
		(size 0.508)
		(drill 0.254)
		(layers "F.Cu" "B.Cu")
		(net "GND")
	)
	(via
		(at 349.272098 -417.778184)
		(size 0.4572)
		(drill 0.254)
		(layers "F.Cu" "B.Cu")
		(net "GND")
	)
	(via
		(at 411.662118 -166.351712)
		(size 0.508)
		(drill 0.254)
		(layers "F.Cu" "B.Cu")
		(net "GND")
	)
	(via
		(at 298.839636 -379.22073)
		(size 0.508)
		(drill 0.254)
		(layers "F.Cu" "B.Cu")
		(net "GND")
	)
	(via
		(at 27.037792 -430.894744)
		(size 0.508)
		(drill 0.254)
		(layers "F.Cu" "B.Cu")
		(net "GND")
	)
	(via
		(at 157.349698 -431.29962)
		(size 0.4572)
		(drill 0.2032)
		(layers "F.Cu" "B.Cu")
		(net "GND")
	)
	(via
		(at 105.031032 -282.18638)
		(size 0.4064)
		(drill 0.2032)
		(layers "F.Cu" "B.Cu")
		(net "GND")
	)
	(via
		(at 471.037666 -55.997094)
		(size 0.508)
		(drill 0.254)
		(layers "F.Cu" "B.Cu")
		(net "GND")
	)
	(via
		(at 421.296338 -294.235124)
		(size 0.4826)
		(drill 0.254)
		(layers "F.Cu" "B.Cu")
		(net "GND")
	)
	(via
		(at 346.091002 -243.674138)
		(size 0.4064)
		(drill 0.2032)
		(layers "F.Cu" "B.Cu")
		(net "GND")
	)
	(via
		(at 17.608042 -250.885198)
		(size 0.4826)
		(drill 0.254)
		(layers "F.Cu" "B.Cu")
		(net "GND")
	)
	(via
		(at 314.262262 -392.999722)
		(size 0.4064)
		(drill 0.2032)
		(layers "F.Cu" "B.Cu")
		(net "GND")
	)
	(via
		(at 301.169578 -119.479568)
		(size 0.508)
		(drill 0.254)
		(layers "F.Cu" "B.Cu")
		(net "GND")
	)
	(via
		(at 352.9711 -278.946102)
		(size 0.4064)
		(drill 0.2032)
		(layers "F.Cu" "B.Cu")
		(net "GND")
	)
	(via
		(at 87.418672 -403.830536)
		(size 0.4572)
		(drill 0.254)
		(layers "F.Cu" "B.Cu")
		(net "GND")
	)
	(via
		(at 117.647466 -173.073568)
		(size 0.49022)
		(drill 0.254)
		(layers "F.Cu" "B.Cu")
		(net "GND")
	)
	(via
		(at 2.76225 -378.389134)
		(size 0.508)
		(drill 0.254)
		(layers "F.Cu" "B.Cu")
		(net "GND")
	)
	(via
		(at 111.332264 -257.74523)
		(size 0.4826)
		(drill 0.254)
		(layers "F.Cu" "B.Cu")
		(net "GND")
	)
	(via
		(at 42.328084 -6.091174)
		(size 0.508)
		(drill 0.254)
		(layers "F.Cu" "B.Cu")
		(net "GND")
	)
	(via
		(at 51.884072 -226.23526)
		(size 0.4826)
		(drill 0.254)
		(layers "F.Cu" "B.Cu")
		(net "GND")
	)
	(via
		(at 91.144344 -391.830814)
		(size 0.4064)
		(drill 0.2032)
		(layers "F.Cu" "B.Cu")
		(net "GND")
	)
	(via
		(at 14.848078 -17.61236)
		(size 0.508)
		(drill 0.254)
		(layers "F.Cu" "B.Cu")
		(net "GND")
	)
	(via
		(at 152.601422 -49.06899)
		(size 0.508)
		(drill 0.254)
		(layers "F.Cu" "B.Cu")
		(net "GND")
	)
	(via
		(at 60.573158 -345.571064)
		(size 0.49022)
		(drill 0.254)
		(layers "F.Cu" "B.Cu")
		(net "GND")
	)
	(via
		(at 292.280086 -224.534984)
		(size 0.4826)
		(drill 0.254)
		(layers "F.Cu" "B.Cu")
		(net "GND")
	)
	(via
		(at 359.740454 -245.55196)
		(size 0.4826)
		(drill 0.254)
		(layers "F.Cu" "B.Cu")
		(net "GND")
	)
	(via
		(at 339.26018 -328.142346)
		(size 0.508)
		(drill 0.254)
		(layers "F.Cu" "B.Cu")
		(net "GND")
	)
	(via
		(at 435.000146 -318.885062)
		(size 0.4826)
		(drill 0.254)
		(layers "F.Cu" "B.Cu")
		(net "GND")
	)
	(via
		(at 388.803134 -417.778184)
		(size 0.4572)
		(drill 0.254)
		(layers "F.Cu" "B.Cu")
		(net "GND")
	)
	(via
		(at 372.878604 -394.831062)
		(size 0.4064)
		(drill 0.2032)
		(layers "F.Cu" "B.Cu")
		(net "GND")
	)
	(via
		(at 59.428126 -243.235226)
		(size 0.4826)
		(drill 0.254)
		(layers "F.Cu" "B.Cu")
		(net "GND")
	)
	(via
		(at 105.500932 -271.656302)
		(size 0.4064)
		(drill 0.2032)
		(layers "F.Cu" "B.Cu")
		(net "GND")
	)
	(via
		(at 87.057484 -412.570168)
		(size 0.4064)
		(drill 0.2032)
		(layers "F.Cu" "B.Cu")
		(net "GND")
	)
	(via
		(at 28.53817 -362.220256)
		(size 0.508)
		(drill 0.254)
		(layers "F.Cu" "B.Cu")
		(net "GND")
	)
	(via
		(at 105.031032 -288.666174)
		(size 0.4064)
		(drill 0.2032)
		(layers "F.Cu" "B.Cu")
		(net "GND")
	)
	(via
		(at 335.078324 -333.034386)
		(size 0.49022)
		(drill 0.254)
		(layers "F.Cu" "B.Cu")
		(net "GND")
	)
	(via
		(at 90.16111 -234.764326)
		(size 0.4064)
		(drill 0.2032)
		(layers "F.Cu" "B.Cu")
		(net "GND")
	)
	(via
		(at 96.571054 -267.606272)
		(size 0.4064)
		(drill 0.2032)
		(layers "F.Cu" "B.Cu")
		(net "GND")
	)
	(via
		(at 47.784004 -264.485374)
		(size 0.4826)
		(drill 0.254)
		(layers "F.Cu" "B.Cu")
		(net "GND")
	)
	(via
		(at 117.759734 -403.830536)
		(size 0.4572)
		(drill 0.254)
		(layers "F.Cu" "B.Cu")
		(net "GND")
	)
	(via
		(at 56.881014 -339.869272)
		(size 0.508)
		(drill 0.254)
		(layers "F.Cu" "B.Cu")
		(net "GND")
	)
	(via
		(at 384.659632 -381.68453)
		(size 0.508)
		(drill 0.254)
		(layers "F.Cu" "B.Cu")
		(net "GND")
	)
	(via
		(at 139.202414 -403.830536)
		(size 0.4572)
		(drill 0.254)
		(layers "F.Cu" "B.Cu")
		(net "GND")
	)
	(via
		(at 282.020264 -315.485018)
		(size 0.4826)
		(drill 0.254)
		(layers "F.Cu" "B.Cu")
		(net "GND")
	)
	(via
		(at 128.694688 -247.724422)
		(size 0.4064)
		(drill 0.2032)
		(layers "F.Cu" "B.Cu")
		(net "GND")
	)
	(via
		(at 330.892658 -417.778184)
		(size 0.4572)
		(drill 0.254)
		(layers "F.Cu" "B.Cu")
		(net "GND")
	)
	(via
		(at 194.604132 -307.8353)
		(size 0.4826)
		(drill 0.254)
		(layers "F.Cu" "B.Cu")
		(net "GND")
	)
	(via
		(at 419.144958 -343.272618)
		(size 0.508)
		(drill 0.254)
		(layers "F.Cu" "B.Cu")
		(net "GND")
	)
	(via
		(at 172.108876 -9.19607)
		(size 0.508)
		(drill 0.254)
		(layers "F.Cu" "B.Cu")
		(net "GND")
	)
	(via
		(at 211.94522 -110.397036)
		(size 0.508)
		(drill 0.254)
		(layers "F.Cu" "B.Cu")
		(net "GND")
	)
	(via
		(at 123.824746 -262.746236)
		(size 0.4064)
		(drill 0.2032)
		(layers "F.Cu" "B.Cu")
		(net "GND")
	)
	(via
		(at 355.961188 -239.624108)
		(size 0.4064)
		(drill 0.2032)
		(layers "F.Cu" "B.Cu")
		(net "GND")
	)
	(via
		(at 273.092164 -234.735116)
		(size 0.4826)
		(drill 0.254)
		(layers "F.Cu" "B.Cu")
		(net "GND")
	)
	(via
		(at 35.411664 -230.485442)
		(size 0.4826)
		(drill 0.254)
		(layers "F.Cu" "B.Cu")
		(net "GND")
	)
	(via
		(at 131.88696 -24.121618)
		(size 0.508)
		(drill 0.254)
		(layers "F.Cu" "B.Cu")
		(net "GND")
	)
	(via
		(at 78.711044 -290.286186)
		(size 0.4064)
		(drill 0.2032)
		(layers "F.Cu" "B.Cu")
		(net "GND")
	)
	(via
		(at 42.535094 -19.13636)
		(size 0.508)
		(drill 0.254)
		(layers "F.Cu" "B.Cu")
		(net "GND")
	)
	(via
		(at 150.974044 -371.49913)
		(size 0.508)
		(drill 0.254)
		(layers "F.Cu" "B.Cu")
		(net "GND")
	)
	(via
		(at 36.795964 -196.485256)
		(size 0.4826)
		(drill 0.254)
		(layers "F.Cu" "B.Cu")
		(net "GND")
	)
	(via
		(at 67.249802 -425.547282)
		(size 0.4572)
		(drill 0.2032)
		(layers "F.Cu" "B.Cu")
		(net "GND")
	)
	(via
		(at 90.16111 -239.624362)
		(size 0.4064)
		(drill 0.2032)
		(layers "F.Cu" "B.Cu")
		(net "GND")
	)
	(via
		(at 107.530646 -410.935678)
		(size 0.508)
		(drill 0.254)
		(layers "F.Cu" "B.Cu")
		(net "GND")
	)
	(via
		(at 336.974942 -138.406886)
		(size 0.508)
		(drill 0.254)
		(layers "F.Cu" "B.Cu")
		(net "GND")
	)
	(via
		(at 370.040408 -425.02328)
		(size 0.508)
		(drill 0.254)
		(layers "F.Cu" "B.Cu")
		(net "GND")
	)
	(via
		(at 99.861116 -268.416278)
		(size 0.4064)
		(drill 0.2032)
		(layers "F.Cu" "B.Cu")
		(net "GND")
	)
	(via
		(at 308.562756 -378.07773)
		(size 0.508)
		(drill 0.254)
		(layers "F.Cu" "B.Cu")
		(net "GND")
	)
	(via
		(at 301.67961 -344.77706)
		(size 0.49022)
		(drill 0.254)
		(layers "F.Cu" "B.Cu")
		(net "GND")
	)
	(via
		(at 349.851218 -235.574078)
		(size 0.4064)
		(drill 0.2032)
		(layers "F.Cu" "B.Cu")
		(net "GND")
	)
	(via
		(at 94.567502 -417.006786)
		(size 0.508)
		(drill 0.254)
		(layers "F.Cu" "B.Cu")
		(net "GND")
	)
	(via
		(at 335.93532 -362.01096)
		(size 0.508)
		(drill 0.254)
		(layers "F.Cu" "B.Cu")
		(net "GND")
	)
	(via
		(at 466.140292 -406.781508)
		(size 0.508)
		(drill 0.254)
		(layers "F.Cu" "B.Cu")
		(net "GND")
	)
	(via
		(at 350.151192 -278.946102)
		(size 0.4064)
		(drill 0.2032)
		(layers "F.Cu" "B.Cu")
		(net "GND")
	)
	(via
		(at 331.821028 -265.176)
		(size 0.4064)
		(drill 0.2032)
		(layers "F.Cu" "B.Cu")
		(net "GND")
	)
	(via
		(at 379.924818 -255.014222)
		(size 0.4064)
		(drill 0.2032)
		(layers "F.Cu" "B.Cu")
		(net "GND")
	)
	(via
		(at 139.288266 -407.00452)
		(size 0.4064)
		(drill 0.2032)
		(layers "F.Cu" "B.Cu")
		(net "GND")
	)
	(via
		(at 88.580976 -282.996386)
		(size 0.4064)
		(drill 0.2032)
		(layers "F.Cu" "B.Cu")
		(net "GND")
	)
	(via
		(at 168.527984 -215.185244)
		(size 0.4826)
		(drill 0.254)
		(layers "F.Cu" "B.Cu")
		(net "GND")
	)
	(via
		(at 130.104642 -250.15444)
		(size 0.4064)
		(drill 0.2032)
		(layers "F.Cu" "B.Cu")
		(net "GND")
	)
	(via
		(at 90.63101 -250.15444)
		(size 0.4064)
		(drill 0.2032)
		(layers "F.Cu" "B.Cu")
		(net "GND")
	)
	(via
		(at 374.584722 -291.905944)
		(size 0.4064)
		(drill 0.2032)
		(layers "F.Cu" "B.Cu")
		(net "GND")
	)
	(via
		(at 299.82414 -253.435104)
		(size 0.4826)
		(drill 0.254)
		(layers "F.Cu" "B.Cu")
		(net "GND")
	)
	(via
		(at 338.26958 -333.024734)
		(size 0.508)
		(drill 0.254)
		(layers "F.Cu" "B.Cu")
		(net "GND")
	)
	(via
		(at 119.12473 -267.606272)
		(size 0.4064)
		(drill 0.2032)
		(layers "F.Cu" "B.Cu")
		(net "GND")
	)
	(via
		(at 29.079444 -4.32943)
		(size 0.508)
		(drill 0.254)
		(layers "F.Cu" "B.Cu")
		(net "GND")
	)
	(via
		(at 287.47466 -405.887936)
		(size 0.508)
		(drill 0.254)
		(layers "F.Cu" "B.Cu")
		(net "GND")
	)
	(via
		(at 54.578504 -386.449062)
		(size 0.4064)
		(drill 0.2032)
		(layers "F.Cu" "B.Cu")
		(net "GND")
	)
	(via
		(at 126.34468 -250.15444)
		(size 0.4064)
		(drill 0.2032)
		(layers "F.Cu" "B.Cu")
		(net "GND")
	)
	(via
		(at 380.516638 -402.309838)
		(size 0.4572)
		(drill 0.254)
		(layers "F.Cu" "B.Cu")
		(net "GND")
	)
	(via
		(at 319.025524 -333.055976)
		(size 0.49022)
		(drill 0.254)
		(layers "F.Cu" "B.Cu")
		(net "GND")
	)
	(via
		(at 135.93318 -27.61742)
		(size 0.508)
		(drill 0.254)
		(layers "F.Cu" "B.Cu")
		(net "GND")
	)
	(via
		(at 336.249518 -435.0512)
		(size 0.4572)
		(drill 0.2032)
		(layers "F.Cu" "B.Cu")
		(net "GND")
	)
	(via
		(at 443.6618 -239.41024)
		(size 0.4826)
		(drill 0.254)
		(layers "F.Cu" "B.Cu")
		(net "GND")
	)
	(via
		(at 84.99094 -238.814356)
		(size 0.4064)
		(drill 0.2032)
		(layers "F.Cu" "B.Cu")
		(net "GND")
	)
	(via
		(at 122.584718 -250.15444)
		(size 0.4064)
		(drill 0.2032)
		(layers "F.Cu" "B.Cu")
		(net "GND")
	)
	(via
		(at 303.268126 -298.485052)
		(size 0.4826)
		(drill 0.254)
		(layers "F.Cu" "B.Cu")
		(net "GND")
	)
	(via
		(at 146.554698 -226.66452)
		(size 0.4064)
		(drill 0.2032)
		(layers "F.Cu" "B.Cu")
		(net "GND")
	)
	(via
		(at 70.570852 -406.370536)
		(size 0.4572)
		(drill 0.254)
		(layers "F.Cu" "B.Cu")
		(net "GND")
	)
	(via
		(at 450.088 -233.035094)
		(size 0.4826)
		(drill 0.254)
		(layers "F.Cu" "B.Cu")
		(net "GND")
	)
	(via
		(at 147.146264 -388.328662)
		(size 0.4064)
		(drill 0.2032)
		(layers "F.Cu" "B.Cu")
		(net "GND")
	)
	(via
		(at 84.709 -146.939)
		(size 0.508)
		(drill 0.254)
		(layers "F.Cu" "B.Cu")
		(net "GND")
	)
	(via
		(at 282.90139 -406.771348)
		(size 0.508)
		(drill 0.254)
		(layers "F.Cu" "B.Cu")
		(net "GND")
	)
	(via
		(at 78.41107 -238.814356)
		(size 0.4064)
		(drill 0.2032)
		(layers "F.Cu" "B.Cu")
		(net "GND")
	)
	(via
		(at 298.43984 -284.034992)
		(size 0.4826)
		(drill 0.254)
		(layers "F.Cu" "B.Cu")
		(net "GND")
	)
	(via
		(at 70.570852 -407.638504)
		(size 0.4572)
		(drill 0.254)
		(layers "F.Cu" "B.Cu")
		(net "GND")
	)
	(via
		(at 427.456092 -252.584966)
		(size 0.4826)
		(drill 0.254)
		(layers "F.Cu" "B.Cu")
		(net "GND")
	)
	(via
		(at 171.97197 -298.485306)
		(size 0.4826)
		(drill 0.254)
		(layers "F.Cu" "B.Cu")
		(net "GND")
	)
	(via
		(at 90.16111 -226.66452)
		(size 0.4064)
		(drill 0.2032)
		(layers "F.Cu" "B.Cu")
		(net "GND")
	)
	(via
		(at 70.43293 -180.870098)
		(size 0.508)
		(drill 0.254)
		(layers "F.Cu" "B.Cu")
		(net "GND")
	)
	(via
		(at 178.267106 -11.458448)
		(size 0.508)
		(drill 0.254)
		(layers "F.Cu" "B.Cu")
		(net "GND")
	)
	(via
		(at 329.6412 -255.824228)
		(size 0.4064)
		(drill 0.2032)
		(layers "F.Cu" "B.Cu")
		(net "GND")
	)
	(via
		(at 182.115206 -390.461246)
		(size 0.508)
		(drill 0.254)
		(layers "F.Cu" "B.Cu")
		(net "GND")
	)
	(via
		(at 421.296338 -231.335072)
		(size 0.4826)
		(drill 0.254)
		(layers "F.Cu" "B.Cu")
		(net "GND")
	)
	(via
		(at 95.1611 -281.376374)
		(size 0.4064)
		(drill 0.2032)
		(layers "F.Cu" "B.Cu")
		(net "GND")
	)
	(via
		(at 79.806546 -355.739446)
		(size 0.508)
		(drill 0.254)
		(layers "F.Cu" "B.Cu")
		(net "GND")
	)
	(via
		(at 118.65483 -276.516338)
		(size 0.4064)
		(drill 0.2032)
		(layers "F.Cu" "B.Cu")
		(net "GND")
	)
	(via
		(at 25.634188 -387.704076)
		(size 0.49022)
		(drill 0.254)
		(layers "F.Cu" "B.Cu")
		(net "GND")
	)
	(via
		(at 345.621102 -225.044254)
		(size 0.4064)
		(drill 0.2032)
		(layers "F.Cu" "B.Cu")
		(net "GND")
	)
	(via
		(at 75.922886 -178.775868)
		(size 0.49022)
		(drill 0.254)
		(layers "F.Cu" "B.Cu")
		(net "GND")
	)
	(via
		(at 372.97233 -123.845828)
		(size 0.508)
		(drill 0.254)
		(layers "F.Cu" "B.Cu")
		(net "GND")
	)
	(via
		(at 88.24976 -432.747166)
		(size 0.4572)
		(drill 0.2032)
		(layers "F.Cu" "B.Cu")
		(net "GND")
	)
	(via
		(at 467.5378 -328.727054)
		(size 0.508)
		(drill 0.254)
		(layers "F.Cu" "B.Cu")
		(net "GND")
	)
	(via
		(at 138.564874 -243.674392)
		(size 0.4064)
		(drill 0.2032)
		(layers "F.Cu" "B.Cu")
		(net "GND")
	)
	(via
		(at 120.064784 -277.326344)
		(size 0.4064)
		(drill 0.2032)
		(layers "F.Cu" "B.Cu")
		(net "GND")
	)
	(via
		(at 70.993 -59.45505)
		(size 0.508)
		(drill 0.254)
		(layers "F.Cu" "B.Cu")
		(net "GND")
	)
	(via
		(at 331.351128 -262.745982)
		(size 0.4064)
		(drill 0.2032)
		(layers "F.Cu" "B.Cu")
		(net "GND")
	)
	(via
		(at 333.230982 -270.846042)
		(size 0.4064)
		(drill 0.2032)
		(layers "F.Cu" "B.Cu")
		(net "GND")
	)
	(via
		(at 73.24979 -434.899816)
		(size 0.4572)
		(drill 0.2032)
		(layers "F.Cu" "B.Cu")
		(net "GND")
	)
	(via
		(at 22.186138 -16.979138)
		(size 0.508)
		(drill 0.254)
		(layers "F.Cu" "B.Cu")
		(net "GND")
	)
	(via
		(at 326.032622 -397.274542)
		(size 0.508)
		(drill 0.254)
		(layers "F.Cu" "B.Cu")
		(net "GND")
	)
	(via
		(at 372.404894 -253.39421)
		(size 0.4064)
		(drill 0.2032)
		(layers "F.Cu" "B.Cu")
		(net "GND")
	)
	(via
		(at 157.581854 -405.098504)
		(size 0.4572)
		(drill 0.254)
		(layers "F.Cu" "B.Cu")
		(net "GND")
	)
	(via
		(at 28.619958 -346.322142)
		(size 0.49022)
		(drill 0.254)
		(layers "F.Cu" "B.Cu")
		(net "GND")
	)
	(via
		(at 83.41106 -288.666174)
		(size 0.4064)
		(drill 0.2032)
		(layers "F.Cu" "B.Cu")
		(net "GND")
	)
	(via
		(at 338.012532 -134.276846)
		(size 0.508)
		(drill 0.254)
		(layers "F.Cu" "B.Cu")
		(net "GND")
	)
	(via
		(at 310.895746 -418.412168)
		(size 0.4064)
		(drill 0.2032)
		(layers "F.Cu" "B.Cu")
		(net "GND")
	)
	(via
		(at 98.451162 -288.666174)
		(size 0.4064)
		(drill 0.2032)
		(layers "F.Cu" "B.Cu")
		(net "GND")
	)
	(via
		(at 367.534698 -268.416024)
		(size 0.4064)
		(drill 0.2032)
		(layers "F.Cu" "B.Cu")
		(net "GND")
	)
	(via
		(at 21.889974 -368.767614)
		(size 0.6604)
		(drill 0.3302)
		(layers "F.Cu" "B.Cu")
		(net "GND")
	)
	(via
		(at 431.55616 -246.635016)
		(size 0.4826)
		(drill 0.254)
		(layers "F.Cu" "B.Cu")
		(net "GND")
	)
	(via
		(at 0.762254 -54.655212)
		(size 0.508)
		(drill 0.254)
		(layers "F.Cu" "B.Cu")
		(net "GND")
	)
	(via
		(at 450.088 -311.23509)
		(size 0.4826)
		(drill 0.254)
		(layers "F.Cu" "B.Cu")
		(net "GND")
	)
	(via
		(at 242.796314 -317.22568)
		(size 0.508)
		(drill 0.254)
		(layers "F.Cu" "B.Cu")
		(net "GND")
	)
	(via
		(at 452.197978 -396.09522)
		(size 0.49022)
		(drill 0.254)
		(layers "F.Cu" "B.Cu")
		(net "GND")
	)
	(via
		(at 95.944182 -391.830814)
		(size 0.4064)
		(drill 0.2032)
		(layers "F.Cu" "B.Cu")
		(net "GND")
	)
	(via
		(at 93.450918 -243.674392)
		(size 0.4064)
		(drill 0.2032)
		(layers "F.Cu" "B.Cu")
		(net "GND")
	)
	(via
		(at 180.396134 -342.769952)
		(size 0.508)
		(drill 0.254)
		(layers "F.Cu" "B.Cu")
		(net "GND")
	)
	(via
		(at 149.51202 -318.78905)
		(size 0.508)
		(drill 0.254)
		(layers "F.Cu" "B.Cu")
		(net "GND")
	)
	(via
		(at 50.499772 -274.685252)
		(size 0.4826)
		(drill 0.254)
		(layers "F.Cu" "B.Cu")
		(net "GND")
	)
	(via
		(at 97.040954 -286.23641)
		(size 0.4064)
		(drill 0.2032)
		(layers "F.Cu" "B.Cu")
		(net "GND")
	)
	(via
		(at 284.736032 -289.985196)
		(size 0.4826)
		(drill 0.254)
		(layers "F.Cu" "B.Cu")
		(net "GND")
	)
	(via
		(at 105.500932 -287.856422)
		(size 0.4064)
		(drill 0.2032)
		(layers "F.Cu" "B.Cu")
		(net "GND")
	)
	(via
		(at 388.21487 -291.095938)
		(size 0.4064)
		(drill 0.2032)
		(layers "F.Cu" "B.Cu")
		(net "GND")
	)
	(via
		(at 204.8637 -274.685252)
		(size 0.4826)
		(drill 0.254)
		(layers "F.Cu" "B.Cu")
		(net "GND")
	)
	(via
		(at 84.52104 -249.344434)
		(size 0.4064)
		(drill 0.2032)
		(layers "F.Cu" "B.Cu")
		(net "GND")
	)
	(via
		(at 372.874794 -250.964192)
		(size 0.4064)
		(drill 0.2032)
		(layers "F.Cu" "B.Cu")
		(net "GND")
	)
	(via
		(at 77.888338 -336.981292)
		(size 0.49022)
		(drill 0.254)
		(layers "F.Cu" "B.Cu")
		(net "GND")
	)
	(via
		(at 280.635964 -292.535102)
		(size 0.4826)
		(drill 0.254)
		(layers "F.Cu" "B.Cu")
		(net "GND")
	)
	(via
		(at 216.97315 -71.126858)
		(size 0.508)
		(drill 0.254)
		(layers "F.Cu" "B.Cu")
		(net "GND")
	)
	(via
		(at 84.79028 -384.617722)
		(size 0.4064)
		(drill 0.2032)
		(layers "F.Cu" "B.Cu")
		(net "GND")
	)
	(via
		(at 187.911994 -114.262916)
		(size 0.4572)
		(drill 0.254)
		(layers "F.Cu" "B.Cu")
		(net "GND")
	)
	(via
		(at 412.367984 -301.885096)
		(size 0.4826)
		(drill 0.254)
		(layers "F.Cu" "B.Cu")
		(net "GND")
	)
	(via
		(at 120.70461 -246.914416)
		(size 0.4064)
		(drill 0.2032)
		(layers "F.Cu" "B.Cu")
		(net "GND")
	)
	(via
		(at 340.24951 -437.49976)
		(size 0.4572)
		(drill 0.2032)
		(layers "F.Cu" "B.Cu")
		(net "GND")
	)
	(via
		(at 443.6618 -286.16021)
		(size 0.4826)
		(drill 0.254)
		(layers "F.Cu" "B.Cu")
		(net "GND")
	)
	(via
		(at 13.626592 -419.884352)
		(size 0.508)
		(drill 0.254)
		(layers "F.Cu" "B.Cu")
		(net "GND")
	)
	(via
		(at 146.742912 -230.170228)
		(size 0.4064)
		(drill 0.2032)
		(layers "F.Cu" "B.Cu")
		(net "GND")
	)
	(via
		(at 17.675606 -424.149012)
		(size 0.508)
		(drill 0.254)
		(layers "F.Cu" "B.Cu")
		(net "GND")
	)
	(via
		(at 69.107558 -333.060802)
		(size 0.49022)
		(drill 0.254)
		(layers "F.Cu" "B.Cu")
		(net "GND")
	)
	(via
		(at 435.000146 -244.08511)
		(size 0.4826)
		(drill 0.254)
		(layers "F.Cu" "B.Cu")
		(net "GND")
	)
	(via
		(at 47.784004 -242.385342)
		(size 0.4826)
		(drill 0.254)
		(layers "F.Cu" "B.Cu")
		(net "GND")
	)
	(via
		(at 163.77793 -347.003878)
		(size 0.508)
		(drill 0.254)
		(layers "F.Cu" "B.Cu")
		(net "GND")
	)
	(via
		(at 424.012106 -204.134974)
		(size 0.4826)
		(drill 0.254)
		(layers "F.Cu" "B.Cu")
		(net "GND")
	)
	(via
		(at 89.99093 -267.606272)
		(size 0.4064)
		(drill 0.2032)
		(layers "F.Cu" "B.Cu")
		(net "GND")
	)
	(via
		(at 364.884716 -240.434114)
		(size 0.4064)
		(drill 0.2032)
		(layers "F.Cu" "B.Cu")
		(net "GND")
	)
	(via
		(at 439.100214 -226.235006)
		(size 0.4826)
		(drill 0.254)
		(layers "F.Cu" "B.Cu")
		(net "GND")
	)
	(via
		(at 384.924808 -287.045908)
		(size 0.4064)
		(drill 0.2032)
		(layers "F.Cu" "B.Cu")
		(net "GND")
	)
	(via
		(at 137.209022 -388.892542)
		(size 0.508)
		(drill 0.254)
		(layers "F.Cu" "B.Cu")
		(net "GND")
	)
	(via
		(at 266.93241 -287.435036)
		(size 0.4826)
		(drill 0.254)
		(layers "F.Cu" "B.Cu")
		(net "GND")
	)
	(via
		(at 394.68298 -247.990106)
		(size 0.4064)
		(drill 0.2032)
		(layers "F.Cu" "B.Cu")
		(net "GND")
	)
	(via
		(at 375.524776 -269.22603)
		(size 0.4064)
		(drill 0.2032)
		(layers "F.Cu" "B.Cu")
		(net "GND")
	)
	(via
		(at 346.249498 -426.54728)
		(size 0.4572)
		(drill 0.2032)
		(layers "F.Cu" "B.Cu")
		(net "GND")
	)
	(via
		(at 30.493208 -434.9623)
		(size 0.508)
		(drill 0.254)
		(layers "F.Cu" "B.Cu")
		(net "GND")
	)
	(via
		(at 203.532232 -238.135414)
		(size 0.4826)
		(drill 0.254)
		(layers "F.Cu" "B.Cu")
		(net "GND")
	)
	(via
		(at 229.503224 -155.971748)
		(size 0.508)
		(drill 0.254)
		(layers "F.Cu" "B.Cu")
		(net "GND")
	)
	(via
		(at 326.570594 -414.752536)
		(size 0.4572)
		(drill 0.254)
		(layers "F.Cu" "B.Cu")
		(net "GND")
	)
	(via
		(at 35.411664 -277.235412)
		(size 0.4826)
		(drill 0.254)
		(layers "F.Cu" "B.Cu")
		(net "GND")
	)
	(via
		(at 382.1049 -280.566114)
		(size 0.4064)
		(drill 0.2032)
		(layers "F.Cu" "B.Cu")
		(net "GND")
	)
	(via
		(at 358.311196 -237.19409)
		(size 0.4064)
		(drill 0.2032)
		(layers "F.Cu" "B.Cu")
		(net "GND")
	)
	(via
		(at 172.380656 -22.37232)
		(size 0.508)
		(drill 0.254)
		(layers "F.Cu" "B.Cu")
		(net "GND")
	)
	(via
		(at 336.642964 -149.738588)
		(size 0.508)
		(drill 0.254)
		(layers "F.Cu" "B.Cu")
		(net "GND")
	)
	(via
		(at 105.918 -427.609)
		(size 0.508)
		(drill 0.254)
		(layers "F.Cu" "B.Cu")
		(net "GND")
	)
	(via
		(at 114.35588 -332.951836)
		(size 0.508)
		(drill 0.254)
		(layers "F.Cu" "B.Cu")
		(net "GND")
	)
	(via
		(at 135.574786 -281.376374)
		(size 0.4064)
		(drill 0.2032)
		(layers "F.Cu" "B.Cu")
		(net "GND")
	)
	(via
		(at 93.272356 -409.396184)
		(size 0.4572)
		(drill 0.254)
		(layers "F.Cu" "B.Cu")
		(net "GND")
	)
	(via
		(at 369.414806 -276.516084)
		(size 0.4064)
		(drill 0.2032)
		(layers "F.Cu" "B.Cu")
		(net "GND")
	)
	(via
		(at 53.450236 -406.370536)
		(size 0.4572)
		(drill 0.254)
		(layers "F.Cu" "B.Cu")
		(net "GND")
	)
	(via
		(at 266.919964 -421.525192)
		(size 0.508)
		(drill 0.254)
		(layers "F.Cu" "B.Cu")
		(net "GND")
	)
	(via
		(at 374.516396 -400.212814)
		(size 0.4064)
		(drill 0.2032)
		(layers "F.Cu" "B.Cu")
		(net "GND")
	)
	(via
		(at 458.390752 -391.762234)
		(size 0.508)
		(drill 0.254)
		(layers "F.Cu" "B.Cu")
		(net "GND")
	)
	(via
		(at 436.855108 -346.940886)
		(size 0.508)
		(drill 0.254)
		(layers "F.Cu" "B.Cu")
		(net "GND")
	)
	(via
		(at 56.513476 -409.396184)
		(size 0.4572)
		(drill 0.254)
		(layers "F.Cu" "B.Cu")
		(net "GND")
	)
	(via
		(at 183.616092 -205.83525)
		(size 0.4826)
		(drill 0.254)
		(layers "F.Cu" "B.Cu")
		(net "GND")
	)
	(via
		(at 306.745386 -415.38652)
		(size 0.4064)
		(drill 0.2032)
		(layers "F.Cu" "B.Cu")
		(net "GND")
	)
	(via
		(at 352.031046 -274.086066)
		(size 0.4064)
		(drill 0.2032)
		(layers "F.Cu" "B.Cu")
		(net "GND")
	)
	(via
		(at 48.939704 -193.107564)
		(size 0.4826)
		(drill 0.254)
		(layers "F.Cu" "B.Cu")
		(net "GND")
	)
	(via
		(at 166.373048 -390.160002)
		(size 0.4064)
		(drill 0.2032)
		(layers "F.Cu" "B.Cu")
		(net "GND")
	)
	(via
		(at 143.349726 -426.69968)
		(size 0.4572)
		(drill 0.2032)
		(layers "F.Cu" "B.Cu")
		(net "GND")
	)
	(via
		(at 115.534694 -226.66452)
		(size 0.4064)
		(drill 0.2032)
		(layers "F.Cu" "B.Cu")
		(net "GND")
	)
	(via
		(at 53.361844 -404.46452)
		(size 0.4064)
		(drill 0.2032)
		(layers "F.Cu" "B.Cu")
		(net "GND")
	)
	(via
		(at 60.573158 -344.781886)
		(size 0.49022)
		(drill 0.254)
		(layers "F.Cu" "B.Cu")
		(net "GND")
	)
	(via
		(at 369.46459 -184.692798)
		(size 0.508)
		(drill 0.254)
		(layers "F.Cu" "B.Cu")
		(net "GND")
	)
	(via
		(at 137.166096 -369.03533)
		(size 0.508)
		(drill 0.254)
		(layers "F.Cu" "B.Cu")
		(net "GND")
	)
	(via
		(at 44.340018 -255.13538)
		(size 0.4826)
		(drill 0.254)
		(layers "F.Cu" "B.Cu")
		(net "GND")
	)
	(via
		(at 31.578296 -286.160464)
		(size 0.4826)
		(drill 0.254)
		(layers "F.Cu" "B.Cu")
		(net "GND")
	)
	(via
		(at 138.666474 -368.641376)
		(size 0.508)
		(drill 0.254)
		(layers "F.Cu" "B.Cu")
		(net "GND")
	)
	(via
		(at 374.754902 -246.104156)
		(size 0.4064)
		(drill 0.2032)
		(layers "F.Cu" "B.Cu")
		(net "GND")
	)
	(via
		(at 82.249772 -426.54728)
		(size 0.4572)
		(drill 0.2032)
		(layers "F.Cu" "B.Cu")
		(net "GND")
	)
	(via
		(at 356.674674 -171.435268)
		(size 0.49022)
		(drill 0.254)
		(layers "F.Cu" "B.Cu")
		(net "GND")
	)
	(via
		(at 384.208274 -413.480504)
		(size 0.4572)
		(drill 0.254)
		(layers "F.Cu" "B.Cu")
		(net "GND")
	)
	(via
		(at 50.90287 -158.08579)
		(size 0.508)
		(drill 0.254)
		(layers "F.Cu" "B.Cu")
		(net "GND")
	)
	(via
		(at 94.446344 -388.328662)
		(size 0.4064)
		(drill 0.2032)
		(layers "F.Cu" "B.Cu")
		(net "GND")
	)
	(via
		(at 106.141266 -180.111146)
		(size 0.49022)
		(drill 0.254)
		(layers "F.Cu" "B.Cu")
		(net "GND")
	)
	(via
		(at 323.148706 -418.412168)
		(size 0.4064)
		(drill 0.2032)
		(layers "F.Cu" "B.Cu")
		(net "GND")
	)
	(via
		(at 188.444378 -303.585372)
		(size 0.4826)
		(drill 0.254)
		(layers "F.Cu" "B.Cu")
		(net "GND")
	)
	(via
		(at 110.632494 -335.691988)
		(size 0.508)
		(drill 0.254)
		(layers "F.Cu" "B.Cu")
		(net "GND")
	)
	(via
		(at 284.736032 -232.184956)
		(size 0.4826)
		(drill 0.254)
		(layers "F.Cu" "B.Cu")
		(net "GND")
	)
	(via
		(at 153.444194 -393.927838)
		(size 0.4572)
		(drill 0.254)
		(layers "F.Cu" "B.Cu")
		(net "GND")
	)
	(via
		(at 47.784004 -247.485408)
		(size 0.4826)
		(drill 0.254)
		(layers "F.Cu" "B.Cu")
		(net "GND")
	)
	(via
		(at 436.384446 -221.985078)
		(size 0.4826)
		(drill 0.254)
		(layers "F.Cu" "B.Cu")
		(net "GND")
	)
	(via
		(at 120.550178 -410.664152)
		(size 0.4572)
		(drill 0.254)
		(layers "F.Cu" "B.Cu")
		(net "GND")
	)
	(via
		(at 305.488594 -22.263354)
		(size 0.508)
		(drill 0.254)
		(layers "F.Cu" "B.Cu")
		(net "GND")
	)
	(via
		(at 304.774346 -339.86851)
		(size 0.508)
		(drill 0.254)
		(layers "F.Cu" "B.Cu")
		(net "GND")
	)
	(via
		(at 162.69208 -415.412682)
		(size 0.508)
		(drill 0.254)
		(layers "F.Cu" "B.Cu")
		(net "GND")
	)
	(via
		(at 180.735224 -146.070574)
		(size 0.508)
		(drill 0.254)
		(layers "F.Cu" "B.Cu")
		(net "GND")
	)
	(via
		(at 124.01804 -106.42092)
		(size 0.508)
		(drill 0.254)
		(layers "F.Cu" "B.Cu")
		(net "GND")
	)
	(via
		(at 366.594898 -284.616144)
		(size 0.4064)
		(drill 0.2032)
		(layers "F.Cu" "B.Cu")
		(net "GND")
	)
	(via
		(at 131.544314 -407.638504)
		(size 0.4572)
		(drill 0.254)
		(layers "F.Cu" "B.Cu")
		(net "GND")
	)
	(via
		(at 273.092164 -264.48512)
		(size 0.4826)
		(drill 0.254)
		(layers "F.Cu" "B.Cu")
		(net "GND")
	)
	(via
		(at 334.341216 -233.14406)
		(size 0.4064)
		(drill 0.2032)
		(layers "F.Cu" "B.Cu")
		(net "GND")
	)
	(via
		(at 105.329228 -179.348384)
		(size 0.49022)
		(drill 0.254)
		(layers "F.Cu" "B.Cu")
		(net "GND")
	)
	(via
		(at 393.854686 -294.335962)
		(size 0.4064)
		(drill 0.2032)
		(layers "F.Cu" "B.Cu")
		(net "GND")
	)
	(via
		(at 97.003362 -372.15953)
		(size 0.508)
		(drill 0.254)
		(layers "F.Cu" "B.Cu")
		(net "GND")
	)
	(via
		(at 91.571064 -251.774452)
		(size 0.4064)
		(drill 0.2032)
		(layers "F.Cu" "B.Cu")
		(net "GND")
	)
	(via
		(at 341.691214 -287.045908)
		(size 0.4064)
		(drill 0.2032)
		(layers "F.Cu" "B.Cu")
		(net "GND")
	)
	(via
		(at 13.864336 -7.70509)
		(size 0.508)
		(drill 0.254)
		(layers "F.Cu" "B.Cu")
		(net "GND")
	)
	(via
		(at 393.384786 -267.606018)
		(size 0.4064)
		(drill 0.2032)
		(layers "F.Cu" "B.Cu")
		(net "GND")
	)
	(via
		(at 16.972788 -369.84305)
		(size 0.508)
		(drill 0.254)
		(layers "F.Cu" "B.Cu")
		(net "GND")
	)
	(via
		(at 89.99093 -288.666174)
		(size 0.4064)
		(drill 0.2032)
		(layers "F.Cu" "B.Cu")
		(net "GND")
	)
	(via
		(at 378.04471 -240.434114)
		(size 0.4064)
		(drill 0.2032)
		(layers "F.Cu" "B.Cu")
		(net "GND")
	)
	(via
		(at 69.249798 -428.851314)
		(size 0.4572)
		(drill 0.2032)
		(layers "F.Cu" "B.Cu")
		(net "GND")
	)
	(via
		(at 428.611792 -194.88531)
		(size 0.4826)
		(drill 0.254)
		(layers "F.Cu" "B.Cu")
		(net "GND")
	)
	(via
		(at 12.54887 -384.76809)
		(size 0.508)
		(drill 0.254)
		(layers "F.Cu" "B.Cu")
		(net "GND")
	)
	(via
		(at 137.924794 -269.226284)
		(size 0.4064)
		(drill 0.2032)
		(layers "F.Cu" "B.Cu")
		(net "GND")
	)
	(via
		(at 69.249798 -434.899562)
		(size 0.4572)
		(drill 0.2032)
		(layers "F.Cu" "B.Cu")
		(net "GND")
	)
	(via
		(at 67.507612 -409.396184)
		(size 0.4572)
		(drill 0.254)
		(layers "F.Cu" "B.Cu")
		(net "GND")
	)
	(via
		(at 130.349752 -426.69968)
		(size 0.4572)
		(drill 0.2032)
		(layers "F.Cu" "B.Cu")
		(net "GND")
	)
	(via
		(at 102.38105 -228.284532)
		(size 0.4064)
		(drill 0.2032)
		(layers "F.Cu" "B.Cu")
		(net "GND")
	)
	(via
		(at 202.147932 -266.185396)
		(size 0.4826)
		(drill 0.254)
		(layers "F.Cu" "B.Cu")
		(net "GND")
	)
	(via
		(at 45.886878 -19.137122)
		(size 0.508)
		(drill 0.254)
		(layers "F.Cu" "B.Cu")
		(net "GND")
	)
	(via
		(at 117.759734 -411.936184)
		(size 0.4572)
		(drill 0.254)
		(layers "F.Cu" "B.Cu")
		(net "GND")
	)
	(via
		(at 448.665346 -63.845694)
		(size 0.508)
		(drill 0.254)
		(layers "F.Cu" "B.Cu")
		(net "GND")
	)
	(via
		(at 334.811116 -240.434114)
		(size 0.4064)
		(drill 0.2032)
		(layers "F.Cu" "B.Cu")
		(net "GND")
	)
	(via
		(at 143.438626 -407.00452)
		(size 0.4064)
		(drill 0.2032)
		(layers "F.Cu" "B.Cu")
		(net "GND")
	)
	(via
		(at 426.90542 -389.402828)
		(size 0.508)
		(drill 0.254)
		(layers "F.Cu" "B.Cu")
		(net "GND")
	)
	(via
		(at 421.296338 -278.085042)
		(size 0.4826)
		(drill 0.254)
		(layers "F.Cu" "B.Cu")
		(net "GND")
	)
	(via
		(at 89.690956 -255.014476)
		(size 0.4064)
		(drill 0.2032)
		(layers "F.Cu" "B.Cu")
		(net "GND")
	)
	(via
		(at 265.54811 -236.435138)
		(size 0.4826)
		(drill 0.254)
		(layers "F.Cu" "B.Cu")
		(net "GND")
	)
	(via
		(at 142.154656 -274.896326)
		(size 0.4064)
		(drill 0.2032)
		(layers "F.Cu" "B.Cu")
		(net "GND")
	)
	(via
		(at 18.818098 -6.091174)
		(size 0.508)
		(drill 0.254)
		(layers "F.Cu" "B.Cu")
		(net "GND")
	)
	(via
		(at 89.590118 -384.617722)
		(size 0.4064)
		(drill 0.2032)
		(layers "F.Cu" "B.Cu")
		(net "GND")
	)
	(via
		(at 237.688882 -161.048954)
		(size 0.508)
		(drill 0.254)
		(layers "F.Cu" "B.Cu")
		(net "GND")
	)
	(via
		(at 387.271514 -420.318184)
		(size 0.4572)
		(drill 0.254)
		(layers "F.Cu" "B.Cu")
		(net "GND")
	)
	(via
		(at 337.631024 -251.774198)
		(size 0.4064)
		(drill 0.2032)
		(layers "F.Cu" "B.Cu")
		(net "GND")
	)
	(via
		(at 58.406284 -404.46452)
		(size 0.4064)
		(drill 0.2032)
		(layers "F.Cu" "B.Cu")
		(net "GND")
	)
	(via
		(at 128.694688 -249.344434)
		(size 0.4064)
		(drill 0.2032)
		(layers "F.Cu" "B.Cu")
		(net "GND")
	)
	(via
		(at 417.844224 -400.212814)
		(size 0.4064)
		(drill 0.2032)
		(layers "F.Cu" "B.Cu")
		(net "GND")
	)
	(via
		(at 33.813496 -194.885564)
		(size 0.4826)
		(drill 0.254)
		(layers "F.Cu" "B.Cu")
		(net "GND")
	)
	(via
		(at 440.110118 -332.112112)
		(size 0.508)
		(drill 0.254)
		(layers "F.Cu" "B.Cu")
		(net "GND")
	)
	(via
		(at 36.239958 -344.781886)
		(size 0.49022)
		(drill 0.254)
		(layers "F.Cu" "B.Cu")
		(net "GND")
	)
	(via
		(at 292.280086 -280.634948)
		(size 0.4826)
		(drill 0.254)
		(layers "F.Cu" "B.Cu")
		(net "GND")
	)
	(via
		(at 129.74701 -17.668748)
		(size 0.508)
		(drill 0.254)
		(layers "F.Cu" "B.Cu")
		(net "GND")
	)
	(via
		(at 366.124744 -291.905944)
		(size 0.4064)
		(drill 0.2032)
		(layers "F.Cu" "B.Cu")
		(net "GND")
	)
	(via
		(at 388.384796 -256.634234)
		(size 0.4064)
		(drill 0.2032)
		(layers "F.Cu" "B.Cu")
		(net "GND")
	)
	(via
		(at 439.100214 -289.985196)
		(size 0.4826)
		(drill 0.254)
		(layers "F.Cu" "B.Cu")
		(net "GND")
	)
	(via
		(at 53.723032 -403.830536)
		(size 0.4572)
		(drill 0.254)
		(layers "F.Cu" "B.Cu")
		(net "GND")
	)
	(via
		(at 336.521044 -286.236156)
		(size 0.4064)
		(drill 0.2032)
		(layers "F.Cu" "B.Cu")
		(net "GND")
	)
	(via
		(at 248.689114 -317.22568)
		(size 0.508)
		(drill 0.254)
		(layers "F.Cu" "B.Cu")
		(net "GND")
	)
	(via
		(at 290.895786 -211.784946)
		(size 0.4826)
		(drill 0.254)
		(layers "F.Cu" "B.Cu")
		(net "GND")
	)
	(via
		(at 25.152096 -283.185362)
		(size 0.4826)
		(drill 0.254)
		(layers "F.Cu" "B.Cu")
		(net "GND")
	)
	(via
		(at 81.292192 -403.830536)
		(size 0.4572)
		(drill 0.254)
		(layers "F.Cu" "B.Cu")
		(net "GND")
	)
	(via
		(at 183.423814 -357.101648)
		(size 0.508)
		(drill 0.254)
		(layers "F.Cu" "B.Cu")
		(net "GND")
	)
	(via
		(at 324.941184 -226.664266)
		(size 0.4064)
		(drill 0.2032)
		(layers "F.Cu" "B.Cu")
		(net "GND")
	)
	(via
		(at 124.768356 -370.83873)
		(size 0.508)
		(drill 0.254)
		(layers "F.Cu" "B.Cu")
		(net "GND")
	)
	(via
		(at 49.161954 -371.49913)
		(size 0.508)
		(drill 0.254)
		(layers "F.Cu" "B.Cu")
		(net "GND")
	)
	(via
		(at 15.55115 -398.851882)
		(size 0.508)
		(drill 0.254)
		(layers "F.Cu" "B.Cu")
		(net "GND")
	)
	(via
		(at 417.59378 -17.61236)
		(size 0.508)
		(drill 0.254)
		(layers "F.Cu" "B.Cu")
		(net "GND")
	)
	(via
		(at 299.82414 -244.934994)
		(size 0.4826)
		(drill 0.254)
		(layers "F.Cu" "B.Cu")
		(net "GND")
	)
	(via
		(at 449.47459 -54.63286)
		(size 0.508)
		(drill 0.254)
		(layers "F.Cu" "B.Cu")
		(net "GND")
	)
	(via
		(at 14.279372 -389.918956)
		(size 0.6604)
		(drill 0.3302)
		(layers "F.Cu" "B.Cu")
		(net "GND")
	)
	(via
		(at 422.9354 -42.357548)
		(size 0.508)
		(drill 0.254)
		(layers "F.Cu" "B.Cu")
		(net "GND")
	)
	(via
		(at 363.329474 -397.15313)
		(size 0.508)
		(drill 0.254)
		(layers "F.Cu" "B.Cu")
		(net "GND")
	)
	(via
		(at 34.080196 -240.68532)
		(size 0.4826)
		(drill 0.254)
		(layers "F.Cu" "B.Cu")
		(net "GND")
	)
	(via
		(at 325.052944 -287.59023)
		(size 0.4064)
		(drill 0.2032)
		(layers "F.Cu" "B.Cu")
		(net "GND")
	)
	(via
		(at 450.088 -264.48512)
		(size 0.4826)
		(drill 0.254)
		(layers "F.Cu" "B.Cu")
		(net "GND")
	)
	(via
		(at 140.734034 -410.664152)
		(size 0.4572)
		(drill 0.254)
		(layers "F.Cu" "B.Cu")
		(net "GND")
	)
	(via
		(at 384.624834 -253.39421)
		(size 0.4064)
		(drill 0.2032)
		(layers "F.Cu" "B.Cu")
		(net "GND")
	)
	(via
		(at 93.867478 -183.54421)
		(size 0.49022)
		(drill 0.254)
		(layers "F.Cu" "B.Cu")
		(net "GND")
	)
	(via
		(at 420.59098 -376.75693)
		(size 0.508)
		(drill 0.254)
		(layers "F.Cu" "B.Cu")
		(net "GND")
	)
	(via
		(at 166.074344 -343.122758)
		(size 0.508)
		(drill 0.254)
		(layers "F.Cu" "B.Cu")
		(net "GND")
	)
	(via
		(at 374.754902 -254.204216)
		(size 0.4064)
		(drill 0.2032)
		(layers "F.Cu" "B.Cu")
		(net "GND")
	)
	(via
		(at 51.884072 -244.935248)
		(size 0.4826)
		(drill 0.254)
		(layers "F.Cu" "B.Cu")
		(net "GND")
	)
	(via
		(at 435.000146 -279.785064)
		(size 0.4826)
		(drill 0.254)
		(layers "F.Cu" "B.Cu")
		(net "GND")
	)
	(via
		(at 99.273106 -390.160002)
		(size 0.4064)
		(drill 0.2032)
		(layers "F.Cu" "B.Cu")
		(net "GND")
	)
	(via
		(at 371.46484 -243.674138)
		(size 0.4064)
		(drill 0.2032)
		(layers "F.Cu" "B.Cu")
		(net "GND")
	)
	(via
		(at 206.248 -291.685218)
		(size 0.4826)
		(drill 0.254)
		(layers "F.Cu" "B.Cu")
		(net "GND")
	)
	(via
		(at 42.545 -435.067456)
		(size 0.508)
		(drill 0.254)
		(layers "F.Cu" "B.Cu")
		(net "GND")
	)
	(via
		(at 104.24541 -180.120798)
		(size 0.508)
		(drill 0.254)
		(layers "F.Cu" "B.Cu")
		(net "GND")
	)
	(via
		(at 149.349714 -431.29962)
		(size 0.4572)
		(drill 0.2032)
		(layers "F.Cu" "B.Cu")
		(net "GND")
	)
	(via
		(at 77.112876 -284.35046)
		(size 0.4064)
		(drill 0.2032)
		(layers "F.Cu" "B.Cu")
		(net "GND")
	)
	(via
		(at 253.822962 -326.566022)
		(size 0.508)
		(drill 0.254)
		(layers "F.Cu" "B.Cu")
		(net "GND")
	)
	(via
		(at 336.22107 -242.864132)
		(size 0.4064)
		(drill 0.2032)
		(layers "F.Cu" "B.Cu")
		(net "GND")
	)
	(via
		(at 307.4162 -402.259038)
		(size 0.4572)
		(drill 0.254)
		(layers "F.Cu" "B.Cu")
		(net "GND")
	)
	(via
		(at 446.644268 -248.335038)
		(size 0.4826)
		(drill 0.254)
		(layers "F.Cu" "B.Cu")
		(net "GND")
	)
	(via
		(at 419.597586 -175.2092)
		(size 0.508)
		(drill 0.254)
		(layers "F.Cu" "B.Cu")
		(net "GND")
	)
	(via
		(at 365.18469 -282.186126)
		(size 0.4064)
		(drill 0.2032)
		(layers "F.Cu" "B.Cu")
		(net "GND")
	)
	(via
		(at 189.775846 -305.285394)
		(size 0.4826)
		(drill 0.254)
		(layers "F.Cu" "B.Cu")
		(net "GND")
	)
	(via
		(at 146.554698 -223.424496)
		(size 0.4064)
		(drill 0.2032)
		(layers "F.Cu" "B.Cu")
		(net "GND")
	)
	(via
		(at 149.650958 -413.204152)
		(size 0.4572)
		(drill 0.254)
		(layers "F.Cu" "B.Cu")
		(net "GND")
	)
	(via
		(at 243.270532 -420.67099)
		(size 0.508)
		(drill 0.254)
		(layers "F.Cu" "B.Cu")
		(net "GND")
	)
	(via
		(at 369.14709 -186.648598)
		(size 0.508)
		(drill 0.254)
		(layers "F.Cu" "B.Cu")
		(net "GND")
	)
	(via
		(at 300.065694 -393.96416)
		(size 0.508)
		(drill 0.254)
		(layers "F.Cu" "B.Cu")
		(net "GND")
	)
	(via
		(at 15.953232 -106.34345)
		(size 0.508)
		(drill 0.254)
		(layers "F.Cu" "B.Cu")
		(net "GND")
	)
	(via
		(at 350.791018 -246.914162)
		(size 0.4064)
		(drill 0.2032)
		(layers "F.Cu" "B.Cu")
		(net "GND")
	)
	(via
		(at 458.244194 -45.233082)
		(size 0.508)
		(drill 0.254)
		(layers "F.Cu" "B.Cu")
		(net "GND")
	)
	(via
		(at 182.231792 -277.235412)
		(size 0.4826)
		(drill 0.254)
		(layers "F.Cu" "B.Cu")
		(net "GND")
	)
	(via
		(at 246.306086 -288.803842)
		(size 0.508)
		(drill 0.254)
		(layers "F.Cu" "B.Cu")
		(net "GND")
	)
	(via
		(at 362.378498 -179.706524)
		(size 0.49022)
		(drill 0.254)
		(layers "F.Cu" "B.Cu")
		(net "GND")
	)
	(via
		(at 0.762254 -60.243212)
		(size 0.508)
		(drill 0.254)
		(layers "F.Cu" "B.Cu")
		(net "GND")
	)
	(via
		(at 121.762266 -384.617722)
		(size 0.4064)
		(drill 0.2032)
		(layers "F.Cu" "B.Cu")
		(net "GND")
	)
	(via
		(at 123.824746 -277.326344)
		(size 0.4064)
		(drill 0.2032)
		(layers "F.Cu" "B.Cu")
		(net "GND")
	)
	(via
		(at 71.249794 -426.69968)
		(size 0.4572)
		(drill 0.2032)
		(layers "F.Cu" "B.Cu")
		(net "GND")
	)
	(via
		(at 393.365736 -395.466062)
		(size 0.508)
		(drill 0.254)
		(layers "F.Cu" "B.Cu")
		(net "GND")
	)
	(via
		(at 70.066154 -369.03533)
		(size 0.508)
		(drill 0.254)
		(layers "F.Cu" "B.Cu")
		(net "GND")
	)
	(via
		(at 234.41152 -290.415726)
		(size 0.508)
		(drill 0.254)
		(layers "F.Cu" "B.Cu")
		(net "GND")
	)
	(via
		(at 122.354594 -406.370536)
		(size 0.4572)
		(drill 0.254)
		(layers "F.Cu" "B.Cu")
		(net "GND")
	)
	(via
		(at 378.35459 -417.778184)
		(size 0.4572)
		(drill 0.254)
		(layers "F.Cu" "B.Cu")
		(net "GND")
	)
	(via
		(at 295.724072 -273.835114)
		(size 0.4826)
		(drill 0.254)
		(layers "F.Cu" "B.Cu")
		(net "GND")
	)
	(via
		(at 139.202414 -411.936184)
		(size 0.4572)
		(drill 0.254)
		(layers "F.Cu" "B.Cu")
		(net "GND")
	)
	(via
		(at 339.811106 -291.905944)
		(size 0.4064)
		(drill 0.2032)
		(layers "F.Cu" "B.Cu")
		(net "GND")
	)
	(via
		(at 117.884702 -246.914416)
		(size 0.4064)
		(drill 0.2032)
		(layers "F.Cu" "B.Cu")
		(net "GND")
	)
	(via
		(at 88.74633 -184.61101)
		(size 0.49022)
		(drill 0.254)
		(layers "F.Cu" "B.Cu")
		(net "GND")
	)
	(via
		(at 109.261148 -276.516338)
		(size 0.4064)
		(drill 0.2032)
		(layers "F.Cu" "B.Cu")
		(net "GND")
	)
	(via
		(at 357.995474 -171.435268)
		(size 0.49022)
		(drill 0.254)
		(layers "F.Cu" "B.Cu")
		(net "GND")
	)
	(via
		(at 247.65 -332.105)
		(size 0.508)
		(drill 0.254)
		(layers "F.Cu" "B.Cu")
		(net "GND")
	)
	(via
		(at 30.461712 -0.762254)
		(size 0.508)
		(drill 0.254)
		(layers "F.Cu" "B.Cu")
		(net "GND")
	)
	(via
		(at 321.249548 -431.29962)
		(size 0.4572)
		(drill 0.2032)
		(layers "F.Cu" "B.Cu")
		(net "GND")
	)
	(via
		(at 63.24981 -433.899564)
		(size 0.4572)
		(drill 0.2032)
		(layers "F.Cu" "B.Cu")
		(net "GND")
	)
	(via
		(at 413.78378 -376.75693)
		(size 0.508)
		(drill 0.254)
		(layers "F.Cu" "B.Cu")
		(net "GND")
	)
	(via
		(at 188.444378 -278.085296)
		(size 0.4826)
		(drill 0.254)
		(layers "F.Cu" "B.Cu")
		(net "GND")
	)
	(via
		(at 416.468052 -301.034958)
		(size 0.4826)
		(drill 0.254)
		(layers "F.Cu" "B.Cu")
		(net "GND")
	)
	(via
		(at 93.280992 -266.796266)
		(size 0.4064)
		(drill 0.2032)
		(layers "F.Cu" "B.Cu")
		(net "GND")
	)
	(via
		(at 93.751146 -293.52621)
		(size 0.4064)
		(drill 0.2032)
		(layers "F.Cu" "B.Cu")
		(net "GND")
	)
	(via
		(at 383.21488 -223.424242)
		(size 0.4064)
		(drill 0.2032)
		(layers "F.Cu" "B.Cu")
		(net "GND")
	)
	(via
		(at 392.13917 -413.480504)
		(size 0.4572)
		(drill 0.254)
		(layers "F.Cu" "B.Cu")
		(net "GND")
	)
	(via
		(at 133.065266 -156.93009)
		(size 0.49022)
		(drill 0.254)
		(layers "F.Cu" "B.Cu")
		(net "GND")
	)
	(via
		(at 442.5442 -269.585186)
		(size 0.4826)
		(drill 0.254)
		(layers "F.Cu" "B.Cu")
		(net "GND")
	)
	(via
		(at 273.092164 -249.185176)
		(size 0.4826)
		(drill 0.254)
		(layers "F.Cu" "B.Cu")
		(net "GND")
	)
	(via
		(at 183.225694 -331.532484)
		(size 0.508)
		(drill 0.254)
		(layers "F.Cu" "B.Cu")
		(net "GND")
	)
	(via
		(at 242.188492 -294.277796)
		(size 0.508)
		(drill 0.254)
		(layers "F.Cu" "B.Cu")
		(net "GND")
	)
	(via
		(at 339.391244 -377.41733)
		(size 0.508)
		(drill 0.254)
		(layers "F.Cu" "B.Cu")
		(net "GND")
	)
	(via
		(at 347.740478 -412.212536)
		(size 0.4572)
		(drill 0.254)
		(layers "F.Cu" "B.Cu")
		(net "GND")
	)
	(via
		(at 315.24956 -429.147224)
		(size 0.4572)
		(drill 0.2032)
		(layers "F.Cu" "B.Cu")
		(net "GND")
	)
	(via
		(at 91.322906 -184.615074)
		(size 0.49022)
		(drill 0.254)
		(layers "F.Cu" "B.Cu")
		(net "GND")
	)
	(via
		(at 359.272332 -259.845048)
		(size 0.4826)
		(drill 0.254)
		(layers "F.Cu" "B.Cu")
		(net "GND")
	)
	(via
		(at 102.211124 -277.326344)
		(size 0.4064)
		(drill 0.2032)
		(layers "F.Cu" "B.Cu")
		(net "GND")
	)
	(via
		(at 366.294924 -238.004096)
		(size 0.4064)
		(drill 0.2032)
		(layers "F.Cu" "B.Cu")
		(net "GND")
	)
	(via
		(at 366.767872 -253.392178)
		(size 0.4064)
		(drill 0.2032)
		(layers "F.Cu" "B.Cu")
		(net "GND")
	)
	(via
		(at 86.401148 -242.864386)
		(size 0.4064)
		(drill 0.2032)
		(layers "F.Cu" "B.Cu")
		(net "GND")
	)
	(via
		(at 321.249548 -426.54728)
		(size 0.4572)
		(drill 0.2032)
		(layers "F.Cu" "B.Cu")
		(net "GND")
	)
	(via
		(at 460.255366 -376.53087)
		(size 0.508)
		(drill 0.254)
		(layers "F.Cu" "B.Cu")
		(net "GND")
	)
	(via
		(at 164.427916 -249.18543)
		(size 0.4826)
		(drill 0.254)
		(layers "F.Cu" "B.Cu")
		(net "GND")
	)
	(via
		(at 353.141026 -228.284278)
		(size 0.4064)
		(drill 0.2032)
		(layers "F.Cu" "B.Cu")
		(net "GND")
	)
	(via
		(at 423.672 -438.634886)
		(size 0.508)
		(drill 0.254)
		(layers "F.Cu" "B.Cu")
		(net "GND")
	)
	(via
		(at 106.309922 -125.570996)
		(size 0.508)
		(drill 0.254)
		(layers "F.Cu" "B.Cu")
		(net "GND")
	)
	(via
		(at 330.892658 -414.752536)
		(size 0.4572)
		(drill 0.254)
		(layers "F.Cu" "B.Cu")
		(net "GND")
	)
	(via
		(at 168.33596 -95.31096)
		(size 0.508)
		(drill 0.254)
		(layers "F.Cu" "B.Cu")
		(net "GND")
	)
	(via
		(at 417.546282 -396.710662)
		(size 0.4064)
		(drill 0.2032)
		(layers "F.Cu" "B.Cu")
		(net "GND")
	)
	(via
		(at 124.768356 -372.15953)
		(size 0.508)
		(drill 0.254)
		(layers "F.Cu" "B.Cu")
		(net "GND")
	)
	(via
		(at 127.114808 -273.276314)
		(size 0.4064)
		(drill 0.2032)
		(layers "F.Cu" "B.Cu")
		(net "GND")
	)
	(via
		(at 44.340018 -310.385206)
		(size 0.4826)
		(drill 0.254)
		(layers "F.Cu" "B.Cu")
		(net "GND")
	)
	(via
		(at 255.927098 -194.93992)
		(size 0.508)
		(drill 0.254)
		(layers "F.Cu" "B.Cu")
		(net "GND")
	)
	(via
		(at 40.299894 -19.13636)
		(size 0.508)
		(drill 0.254)
		(layers "F.Cu" "B.Cu")
		(net "GND")
	)
	(via
		(at 410.245814 -416.020504)
		(size 0.4572)
		(drill 0.254)
		(layers "F.Cu" "B.Cu")
		(net "GND")
	)
	(via
		(at 352.671126 -245.29415)
		(size 0.4064)
		(drill 0.2032)
		(layers "F.Cu" "B.Cu")
		(net "GND")
	)
	(via
		(at 32.695896 -281.48534)
		(size 0.4826)
		(drill 0.254)
		(layers "F.Cu" "B.Cu")
		(net "GND")
	)
	(via
		(at 391.862818 -397.274542)
		(size 0.508)
		(drill 0.254)
		(layers "F.Cu" "B.Cu")
		(net "GND")
	)
	(via
		(at 104.090978 -267.606272)
		(size 0.4064)
		(drill 0.2032)
		(layers "F.Cu" "B.Cu")
		(net "GND")
	)
	(via
		(at 149.349714 -426.54728)
		(size 0.4572)
		(drill 0.2032)
		(layers "F.Cu" "B.Cu")
		(net "GND")
	)
	(via
		(at 131.632706 -412.570168)
		(size 0.4064)
		(drill 0.2032)
		(layers "F.Cu" "B.Cu")
		(net "GND")
	)
	(via
		(at 270.175736 -340.437216)
		(size 0.6604)
		(drill 0.3302)
		(layers "F.Cu" "B.Cu")
		(net "GND")
	)
	(via
		(at 150.95982 -314.47105)
		(size 0.508)
		(drill 0.254)
		(layers "F.Cu" "B.Cu")
		(net "GND")
	)
	(via
		(at 29.05887 -384.26009)
		(size 0.508)
		(drill 0.254)
		(layers "F.Cu" "B.Cu")
		(net "GND")
	)
	(via
		(at 396.461234 -420.318184)
		(size 0.4572)
		(drill 0.254)
		(layers "F.Cu" "B.Cu")
		(net "GND")
	)
	(via
		(at 91.571064 -222.61449)
		(size 0.4064)
		(drill 0.2032)
		(layers "F.Cu" "B.Cu")
		(net "GND")
	)
	(via
		(at 25.152096 -269.58544)
		(size 0.4826)
		(drill 0.254)
		(layers "F.Cu" "B.Cu")
		(net "GND")
	)
	(via
		(at 385.873752 -381.68453)
		(size 0.508)
		(drill 0.254)
		(layers "F.Cu" "B.Cu")
		(net "GND")
	)
	(via
		(at 282.020264 -219.435172)
		(size 0.4826)
		(drill 0.254)
		(layers "F.Cu" "B.Cu")
		(net "GND")
	)
	(via
		(at 343.105994 -394.831062)
		(size 0.4064)
		(drill 0.2032)
		(layers "F.Cu" "B.Cu")
		(net "GND")
	)
	(via
		(at 149.274784 -370.83873)
		(size 0.508)
		(drill 0.254)
		(layers "F.Cu" "B.Cu")
		(net "GND")
	)
	(via
		(at 36.50488 -112.25784)
		(size 0.508)
		(drill 0.254)
		(layers "F.Cu" "B.Cu")
		(net "GND")
	)
	(via
		(at 2.76225 -372.801134)
		(size 0.508)
		(drill 0.254)
		(layers "F.Cu" "B.Cu")
		(net "GND")
	)
	(via
		(at 390.334754 -420.318184)
		(size 0.4572)
		(drill 0.254)
		(layers "F.Cu" "B.Cu")
		(net "GND")
	)
	(via
		(at 384.349498 -426.54728)
		(size 0.4572)
		(drill 0.2032)
		(layers "F.Cu" "B.Cu")
		(net "GND")
	)
	(via
		(at 412.185104 -18.247868)
		(size 0.508)
		(drill 0.254)
		(layers "F.Cu" "B.Cu")
		(net "GND")
	)
	(via
		(at 146.742912 -244.750336)
		(size 0.4064)
		(drill 0.2032)
		(layers "F.Cu" "B.Cu")
		(net "GND")
	)
	(via
		(at 233.707178 -317.22568)
		(size 0.508)
		(drill 0.254)
		(layers "F.Cu" "B.Cu")
		(net "GND")
	)
	(via
		(at 129.739898 -406.370536)
		(size 0.4572)
		(drill 0.254)
		(layers "F.Cu" "B.Cu")
		(net "GND")
	)
	(via
		(at 111.610394 -186.315858)
		(size 0.508)
		(drill 0.254)
		(layers "F.Cu" "B.Cu")
		(net "GND")
	)
	(via
		(at 323.249544 -425.547282)
		(size 0.4572)
		(drill 0.2032)
		(layers "F.Cu" "B.Cu")
		(net "GND")
	)
	(via
		(at 257.379724 -134.351268)
		(size 0.508)
		(drill 0.254)
		(layers "F.Cu" "B.Cu")
		(net "GND")
	)
	(via
		(at 405.650954 -420.318184)
		(size 0.4572)
		(drill 0.254)
		(layers "F.Cu" "B.Cu")
		(net "GND")
	)
	(via
		(at 369.114832 -246.104156)
		(size 0.4064)
		(drill 0.2032)
		(layers "F.Cu" "B.Cu")
		(net "GND")
	)
	(via
		(at 17.49298 -386.879338)
		(size 0.49022)
		(drill 0.254)
		(layers "F.Cu" "B.Cu")
		(net "GND")
	)
	(via
		(at 102.38105 -246.10441)
		(size 0.4064)
		(drill 0.2032)
		(layers "F.Cu" "B.Cu")
		(net "GND")
	)
	(via
		(at 215.139778 -385.783836)
		(size 0.508)
		(drill 0.254)
		(layers "F.Cu" "B.Cu")
		(net "GND")
	)
	(via
		(at 383.68478 -224.234248)
		(size 0.4064)
		(drill 0.2032)
		(layers "F.Cu" "B.Cu")
		(net "GND")
	)
	(via
		(at 84.99094 -225.854514)
		(size 0.4064)
		(drill 0.2032)
		(layers "F.Cu" "B.Cu")
		(net "GND")
	)
	(via
		(at 436.384446 -210.085178)
		(size 0.4826)
		(drill 0.254)
		(layers "F.Cu" "B.Cu")
		(net "GND")
	)
	(via
		(at 80.249776 -436.347362)
		(size 0.4572)
		(drill 0.2032)
		(layers "F.Cu" "B.Cu")
		(net "GND")
	)
	(via
		(at 124.464826 -255.014476)
		(size 0.4064)
		(drill 0.2032)
		(layers "F.Cu" "B.Cu")
		(net "GND")
	)
	(via
		(at 451.4723 -228.785166)
		(size 0.4826)
		(drill 0.254)
		(layers "F.Cu" "B.Cu")
		(net "GND")
	)
	(via
		(at 422.342564 -349.175578)
		(size 0.49022)
		(drill 0.254)
		(layers "F.Cu" "B.Cu")
		(net "GND")
	)
	(via
		(at 346.249498 -434.899562)
		(size 0.4572)
		(drill 0.2032)
		(layers "F.Cu" "B.Cu")
		(net "GND")
	)
	(via
		(at 382.578102 -295.983406)
		(size 0.4064)
		(drill 0.2032)
		(layers "F.Cu" "B.Cu")
		(net "GND")
	)
	(via
		(at 233.651044 -44.323)
		(size 0.508)
		(drill 0.254)
		(layers "F.Cu" "B.Cu")
		(net "GND")
	)
	(via
		(at 128.349756 -431.29962)
		(size 0.4572)
		(drill 0.2032)
		(layers "F.Cu" "B.Cu")
		(net "GND")
	)
	(via
		(at 420.222426 -59.197748)
		(size 0.508)
		(drill 0.254)
		(layers "F.Cu" "B.Cu")
		(net "GND")
	)
	(via
		(at 413.752284 -231.335072)
		(size 0.4826)
		(drill 0.254)
		(layers "F.Cu" "B.Cu")
		(net "GND")
	)
	(via
		(at 25.152096 -318.885316)
		(size 0.4826)
		(drill 0.254)
		(layers "F.Cu" "B.Cu")
		(net "GND")
	)
	(via
		(at 79.746094 -154.200352)
		(size 0.508)
		(drill 0.254)
		(layers "F.Cu" "B.Cu")
		(net "GND")
	)
	(via
		(at 380.768352 -380.54153)
		(size 0.508)
		(drill 0.254)
		(layers "F.Cu" "B.Cu")
		(net "GND")
	)
	(via
		(at 389.833104 -18.247106)
		(size 0.508)
		(drill 0.254)
		(layers "F.Cu" "B.Cu")
		(net "GND")
	)
	(via
		(at 256.921 -339.09)
		(size 0.508)
		(drill 0.254)
		(layers "F.Cu" "B.Cu")
		(net "GND")
	)
	(via
		(at 99.861116 -266.796266)
		(size 0.4064)
		(drill 0.2032)
		(layers "F.Cu" "B.Cu")
		(net "GND")
	)
	(via
		(at 194.604132 -252.58522)
		(size 0.4826)
		(drill 0.254)
		(layers "F.Cu" "B.Cu")
		(net "GND")
	)
	(via
		(at 395.20241 -413.480504)
		(size 0.4572)
		(drill 0.254)
		(layers "F.Cu" "B.Cu")
		(net "GND")
	)
	(via
		(at 51.884072 -243.235226)
		(size 0.4826)
		(drill 0.254)
		(layers "F.Cu" "B.Cu")
		(net "GND")
	)
	(via
		(at 371.045232 -383.00533)
		(size 0.508)
		(drill 0.254)
		(layers "F.Cu" "B.Cu")
		(net "GND")
	)
	(via
		(at 32.695896 -236.435392)
		(size 0.4826)
		(drill 0.254)
		(layers "F.Cu" "B.Cu")
		(net "GND")
	)
	(via
		(at 449.106036 -20.457922)
		(size 0.508)
		(drill 0.254)
		(layers "F.Cu" "B.Cu")
		(net "GND")
	)
	(via
		(at 134.164832 -269.226284)
		(size 0.4064)
		(drill 0.2032)
		(layers "F.Cu" "B.Cu")
		(net "GND")
	)
	(via
		(at 179.21478 -33.97504)
		(size 0.508)
		(drill 0.254)
		(layers "F.Cu" "B.Cu")
		(net "GND")
	)
	(via
		(at 369.414806 -278.136096)
		(size 0.4064)
		(drill 0.2032)
		(layers "F.Cu" "B.Cu")
		(net "GND")
	)
	(via
		(at 235.0008 -283.170122)
		(size 0.508)
		(drill 0.254)
		(layers "F.Cu" "B.Cu")
		(net "GND")
	)
	(via
		(at 79.821024 -236.384338)
		(size 0.4064)
		(drill 0.2032)
		(layers "F.Cu" "B.Cu")
		(net "GND")
	)
	(via
		(at 118.5164 -393.877038)
		(size 0.4572)
		(drill 0.254)
		(layers "F.Cu" "B.Cu")
		(net "GND")
	)
	(via
		(at 453.569578 -396.884398)
		(size 0.49022)
		(drill 0.254)
		(layers "F.Cu" "B.Cu")
		(net "GND")
	)
	(via
		(at 445.100456 -396.09522)
		(size 0.49022)
		(drill 0.254)
		(layers "F.Cu" "B.Cu")
		(net "GND")
	)
	(via
		(at 123.994672 -247.724422)
		(size 0.4064)
		(drill 0.2032)
		(layers "F.Cu" "B.Cu")
		(net "GND")
	)
	(via
		(at 303.268126 -262.785098)
		(size 0.4826)
		(drill 0.254)
		(layers "F.Cu" "B.Cu")
		(net "GND")
	)
	(via
		(at 127.584708 -280.566368)
		(size 0.4064)
		(drill 0.2032)
		(layers "F.Cu" "B.Cu")
		(net "GND")
	)
	(via
		(at 105.942892 -389.576056)
		(size 0.508)
		(drill 0.254)
		(layers "F.Cu" "B.Cu")
		(net "GND")
	)
	(via
		(at 365.380778 -255.530096)
		(size 0.4826)
		(drill 0.254)
		(layers "F.Cu" "B.Cu")
		(net "GND")
	)
	(via
		(at 275.807932 -239.835182)
		(size 0.4826)
		(drill 0.254)
		(layers "F.Cu" "B.Cu")
		(net "GND")
	)
	(via
		(at 41.8719 -352.23196)
		(size 0.508)
		(drill 0.254)
		(layers "F.Cu" "B.Cu")
		(net "GND")
	)
	(via
		(at 173.35627 -228.78542)
		(size 0.4826)
		(drill 0.254)
		(layers "F.Cu" "B.Cu")
		(net "GND")
	)
	(via
		(at 36.795964 -272.98523)
		(size 0.4826)
		(drill 0.254)
		(layers "F.Cu" "B.Cu")
		(net "GND")
	)
	(via
		(at 451.2056 -286.16021)
		(size 0.4826)
		(drill 0.254)
		(layers "F.Cu" "B.Cu")
		(net "GND")
	)
	(via
		(at 347.801184 -276.516084)
		(size 0.4064)
		(drill 0.2032)
		(layers "F.Cu" "B.Cu")
		(net "GND")
	)
	(via
		(at 344.981022 -276.516084)
		(size 0.4064)
		(drill 0.2032)
		(layers "F.Cu" "B.Cu")
		(net "GND")
	)
	(via
		(at 394.68298 -230.169974)
		(size 0.4064)
		(drill 0.2032)
		(layers "F.Cu" "B.Cu")
		(net "GND")
	)
	(via
		(at 120.916446 -382.85293)
		(size 0.4064)
		(drill 0.2032)
		(layers "F.Cu" "B.Cu")
		(net "GND")
	)
	(via
		(at 346.536518 -167.987472)
		(size 0.508)
		(drill 0.254)
		(layers "F.Cu" "B.Cu")
		(net "GND")
	)
	(via
		(at 341.691214 -267.606018)
		(size 0.4064)
		(drill 0.2032)
		(layers "F.Cu" "B.Cu")
		(net "GND")
	)
	(via
		(at 140.375386 -407.00452)
		(size 0.4064)
		(drill 0.2032)
		(layers "F.Cu" "B.Cu")
		(net "GND")
	)
	(via
		(at 264.43051 -211.360004)
		(size 0.4826)
		(drill 0.254)
		(layers "F.Cu" "B.Cu")
		(net "GND")
	)
	(via
		(at 336.249518 -426.69968)
		(size 0.4572)
		(drill 0.2032)
		(layers "F.Cu" "B.Cu")
		(net "GND")
	)
	(via
		(at 428.840392 -294.235124)
		(size 0.4826)
		(drill 0.254)
		(layers "F.Cu" "B.Cu")
		(net "GND")
	)
	(via
		(at 127.114808 -265.176254)
		(size 0.4064)
		(drill 0.2032)
		(layers "F.Cu" "B.Cu")
		(net "GND")
	)
	(via
		(at 349.221298 -159.151066)
		(size 0.49022)
		(drill 0.254)
		(layers "F.Cu" "B.Cu")
		(net "GND")
	)
	(via
		(at 430.17186 -314.635134)
		(size 0.4826)
		(drill 0.254)
		(layers "F.Cu" "B.Cu")
		(net "GND")
	)
	(via
		(at 191.160146 -291.685218)
		(size 0.4826)
		(drill 0.254)
		(layers "F.Cu" "B.Cu")
		(net "GND")
	)
	(via
		(at 379.316488 -402.284438)
		(size 0.4572)
		(drill 0.254)
		(layers "F.Cu" "B.Cu")
		(net "GND")
	)
	(via
		(at 96.27108 -238.814356)
		(size 0.4064)
		(drill 0.2032)
		(layers "F.Cu" "B.Cu")
		(net "GND")
	)
	(via
		(at 435.000146 -208.385156)
		(size 0.4826)
		(drill 0.254)
		(layers "F.Cu" "B.Cu")
		(net "GND")
	)
	(via
		(at 12.671806 -134.911846)
		(size 0.508)
		(drill 0.254)
		(layers "F.Cu" "B.Cu")
		(net "GND")
	)
	(via
		(at 412.367984 -307.835046)
		(size 0.4826)
		(drill 0.254)
		(layers "F.Cu" "B.Cu")
		(net "GND")
	)
	(via
		(at 370.994686 -249.34418)
		(size 0.4064)
		(drill 0.2032)
		(layers "F.Cu" "B.Cu")
		(net "GND")
	)
	(via
		(at 322.75018 -328.072496)
		(size 0.508)
		(drill 0.254)
		(layers "F.Cu" "B.Cu")
		(net "GND")
	)
	(via
		(at 346.39123 -285.42615)
		(size 0.4064)
		(drill 0.2032)
		(layers "F.Cu" "B.Cu")
		(net "GND")
	)
	(via
		(at 102.548436 -28.022804)
		(size 0.508)
		(drill 0.254)
		(layers "F.Cu" "B.Cu")
		(net "GND")
	)
	(via
		(at 335.848706 -412.84652)
		(size 0.4064)
		(drill 0.2032)
		(layers "F.Cu" "B.Cu")
		(net "GND")
	)
	(via
		(at 369.568476 -391.290048)
		(size 0.4064)
		(drill 0.2032)
		(layers "F.Cu" "B.Cu")
		(net "GND")
	)
	(via
		(at 450.116194 -54.63286)
		(size 0.508)
		(drill 0.254)
		(layers "F.Cu" "B.Cu")
		(net "GND")
	)
	(via
		(at 371.955314 -421.586152)
		(size 0.4572)
		(drill 0.254)
		(layers "F.Cu" "B.Cu")
		(net "GND")
	)
	(via
		(at 358.311196 -240.434114)
		(size 0.4064)
		(drill 0.2032)
		(layers "F.Cu" "B.Cu")
		(net "GND")
	)
	(via
		(at 415.083752 -218.585034)
		(size 0.4826)
		(drill 0.254)
		(layers "F.Cu" "B.Cu")
		(net "GND")
	)
	(via
		(at 381.058674 -184.683146)
		(size 0.49022)
		(drill 0.254)
		(layers "F.Cu" "B.Cu")
		(net "GND")
	)
	(via
		(at 90.249756 -428.851314)
		(size 0.4572)
		(drill 0.2032)
		(layers "F.Cu" "B.Cu")
		(net "GND")
	)
	(via
		(at 122.584718 -253.394464)
		(size 0.4064)
		(drill 0.2032)
		(layers "F.Cu" "B.Cu")
		(net "GND")
	)
	(via
		(at 153.349706 -436.051198)
		(size 0.4572)
		(drill 0.2032)
		(layers "F.Cu" "B.Cu")
		(net "GND")
	)
	(via
		(at 440.217814 -275.960078)
		(size 0.4826)
		(drill 0.254)
		(layers "F.Cu" "B.Cu")
		(net "GND")
	)
	(via
		(at 96.571054 -287.046162)
		(size 0.4064)
		(drill 0.2032)
		(layers "F.Cu" "B.Cu")
		(net "GND")
	)
	(via
		(at 346.25788 -332.440534)
		(size 0.508)
		(drill 0.254)
		(layers "F.Cu" "B.Cu")
		(net "GND")
	)
	(via
		(at 422.627806 -293.384986)
		(size 0.4826)
		(drill 0.254)
		(layers "F.Cu" "B.Cu")
		(net "GND")
	)
	(via
		(at 129.55651 -159.775398)
		(size 0.508)
		(drill 0.254)
		(layers "F.Cu" "B.Cu")
		(net "GND")
	)
	(via
		(at 154.604466 -407.00452)
		(size 0.4064)
		(drill 0.2032)
		(layers "F.Cu" "B.Cu")
		(net "GND")
	)
	(via
		(at 139.974828 -242.864386)
		(size 0.4064)
		(drill 0.2032)
		(layers "F.Cu" "B.Cu")
		(net "GND")
	)
	(via
		(at 381.278384 -394.831062)
		(size 0.4064)
		(drill 0.2032)
		(layers "F.Cu" "B.Cu")
		(net "GND")
	)
	(via
		(at 378.081794 -420.318184)
		(size 0.4572)
		(drill 0.254)
		(layers "F.Cu" "B.Cu")
		(net "GND")
	)
	(via
		(at 288.180018 -311.23509)
		(size 0.4826)
		(drill 0.254)
		(layers "F.Cu" "B.Cu")
		(net "GND")
	)
	(via
		(at 379.613414 -417.778184)
		(size 0.4572)
		(drill 0.254)
		(layers "F.Cu" "B.Cu")
		(net "GND")
	)
	(via
		(at 385.316476 -391.23493)
		(size 0.4064)
		(drill 0.2032)
		(layers "F.Cu" "B.Cu")
		(net "GND")
	)
	(via
		(at 84.074 -68.64604)
		(size 0.508)
		(drill 0.254)
		(layers "F.Cu" "B.Cu")
		(net "GND")
	)
	(via
		(at 135.274812 -250.964446)
		(size 0.4064)
		(drill 0.2032)
		(layers "F.Cu" "B.Cu")
		(net "GND")
	)
	(via
		(at 176.072038 -261.935214)
		(size 0.4826)
		(drill 0.254)
		(layers "F.Cu" "B.Cu")
		(net "GND")
	)
	(via
		(at 73.275444 -407.00452)
		(size 0.4064)
		(drill 0.2032)
		(layers "F.Cu" "B.Cu")
		(net "GND")
	)
	(via
		(at 379.924818 -232.334054)
		(size 0.4064)
		(drill 0.2032)
		(layers "F.Cu" "B.Cu")
		(net "GND")
	)
	(via
		(at 381.634746 -289.475926)
		(size 0.4064)
		(drill 0.2032)
		(layers "F.Cu" "B.Cu")
		(net "GND")
	)
	(via
		(at 339.811106 -295.145968)
		(size 0.4064)
		(drill 0.2032)
		(layers "F.Cu" "B.Cu")
		(net "GND")
	)
	(via
		(at 414.486852 -6.091174)
		(size 0.508)
		(drill 0.254)
		(layers "F.Cu" "B.Cu")
		(net "GND")
	)
	(via
		(at 410.20619 -394.831062)
		(size 0.4064)
		(drill 0.2032)
		(layers "F.Cu" "B.Cu")
		(net "GND")
	)
	(via
		(at 78.711044 -274.08632)
		(size 0.4064)
		(drill 0.2032)
		(layers "F.Cu" "B.Cu")
		(net "GND")
	)
	(via
		(at 55.328058 -206.685388)
		(size 0.4826)
		(drill 0.254)
		(layers "F.Cu" "B.Cu")
		(net "GND")
	)
	(via
		(at 104.090978 -274.08632)
		(size 0.4064)
		(drill 0.2032)
		(layers "F.Cu" "B.Cu")
		(net "GND")
	)
	(via
		(at 186.312048 -116.642642)
		(size 0.4572)
		(drill 0.254)
		(layers "F.Cu" "B.Cu")
		(net "GND")
	)
	(via
		(at 148.477986 -407.00452)
		(size 0.4064)
		(drill 0.2032)
		(layers "F.Cu" "B.Cu")
		(net "GND")
	)
	(via
		(at 303.268126 -252.584966)
		(size 0.4826)
		(drill 0.254)
		(layers "F.Cu" "B.Cu")
		(net "GND")
	)
	(via
		(at 130.39344 -42.97426)
		(size 0.508)
		(drill 0.254)
		(layers "F.Cu" "B.Cu")
		(net "GND")
	)
	(via
		(at 325.24954 -437.34736)
		(size 0.4572)
		(drill 0.2032)
		(layers "F.Cu" "B.Cu")
		(net "GND")
	)
	(via
		(at 138.349736 -427.851316)
		(size 0.4572)
		(drill 0.2032)
		(layers "F.Cu" "B.Cu")
		(net "GND")
	)
	(via
		(at 108.321094 -281.376374)
		(size 0.4064)
		(drill 0.2032)
		(layers "F.Cu" "B.Cu")
		(net "GND")
	)
	(via
		(at 298.70654 -275.960078)
		(size 0.4826)
		(drill 0.254)
		(layers "F.Cu" "B.Cu")
		(net "GND")
	)
	(via
		(at 335.75117 -250.154186)
		(size 0.4064)
		(drill 0.2032)
		(layers "F.Cu" "B.Cu")
		(net "GND")
	)
	(via
		(at 47.945294 -374.62333)
		(size 0.508)
		(drill 0.254)
		(layers "F.Cu" "B.Cu")
		(net "GND")
	)
	(via
		(at 74.071226 -390.932924)
		(size 0.508)
		(drill 0.254)
		(layers "F.Cu" "B.Cu")
		(net "GND")
	)
	(via
		(at 424.975528 -429.448214)
		(size 0.508)
		(drill 0.254)
		(layers "F.Cu" "B.Cu")
		(net "GND")
	)
	(via
		(at 52.667154 -348.709488)
		(size 0.49022)
		(drill 0.254)
		(layers "F.Cu" "B.Cu")
		(net "GND")
	)
	(via
		(at 59.428126 -224.535238)
		(size 0.4826)
		(drill 0.254)
		(layers "F.Cu" "B.Cu")
		(net "GND")
	)
	(via
		(at 25.199594 -339.793834)
		(size 0.508)
		(drill 0.254)
		(layers "F.Cu" "B.Cu")
		(net "GND")
	)
	(via
		(at 317.108078 -412.212536)
		(size 0.4572)
		(drill 0.254)
		(layers "F.Cu" "B.Cu")
		(net "GND")
	)
	(via
		(at 37.332412 -365.76)
		(size 0.508)
		(drill 0.254)
		(layers "F.Cu" "B.Cu")
		(net "GND")
	)
	(via
		(at 266.70381 -194.88531)
		(size 0.4826)
		(drill 0.254)
		(layers "F.Cu" "B.Cu")
		(net "GND")
	)
	(via
		(at 164.427916 -309.535322)
		(size 0.4826)
		(drill 0.254)
		(layers "F.Cu" "B.Cu")
		(net "GND")
	)
	(via
		(at 55.328058 -289.135312)
		(size 0.4826)
		(drill 0.254)
		(layers "F.Cu" "B.Cu")
		(net "GND")
	)
	(via
		(at 166.290244 -369.03533)
		(size 0.508)
		(drill 0.254)
		(layers "F.Cu" "B.Cu")
		(net "GND")
	)
	(via
		(at 435.000146 -252.584966)
		(size 0.4826)
		(drill 0.254)
		(layers "F.Cu" "B.Cu")
		(net "GND")
	)
	(via
		(at 342.801194 -228.284278)
		(size 0.4064)
		(drill 0.2032)
		(layers "F.Cu" "B.Cu")
		(net "GND")
	)
	(via
		(at 346.79001 -392.999722)
		(size 0.4064)
		(drill 0.2032)
		(layers "F.Cu" "B.Cu")
		(net "GND")
	)
	(via
		(at 186.758834 -345.797632)
		(size 0.6604)
		(drill 0.3302)
		(layers "F.Cu" "B.Cu")
		(net "GND")
	)
	(via
		(at 96.033082 -300.977046)
		(size 0.508)
		(drill 0.254)
		(layers "F.Cu" "B.Cu")
		(net "GND")
	)
	(via
		(at 403.05609 -323.067172)
		(size 0.508)
		(drill 0.254)
		(layers "F.Cu" "B.Cu")
		(net "GND")
	)
	(via
		(at 2.76225 -171.633134)
		(size 0.508)
		(drill 0.254)
		(layers "F.Cu" "B.Cu")
		(net "GND")
	)
	(via
		(at 61.605922 -175.54321)
		(size 0.508)
		(drill 0.254)
		(layers "F.Cu" "B.Cu")
		(net "GND")
	)
	(via
		(at 363.004862 -251.774198)
		(size 0.4064)
		(drill 0.2032)
		(layers "F.Cu" "B.Cu")
		(net "GND")
	)
	(via
		(at 467.5378 -216.967054)
		(size 0.508)
		(drill 0.254)
		(layers "F.Cu" "B.Cu")
		(net "GND")
	)
	(via
		(at 388.384796 -229.094284)
		(size 0.4064)
		(drill 0.2032)
		(layers "F.Cu" "B.Cu")
		(net "GND")
	)
	(via
		(at 442.5442 -281.485086)
		(size 0.4826)
		(drill 0.254)
		(layers "F.Cu" "B.Cu")
		(net "GND")
	)
	(via
		(at 157.349698 -432.451256)
		(size 0.4572)
		(drill 0.2032)
		(layers "F.Cu" "B.Cu")
		(net "GND")
	)
	(via
		(at 157.631384 -441.227718)
		(size 0.508)
		(drill 0.254)
		(layers "F.Cu" "B.Cu")
		(net "GND")
	)
	(via
		(at 26.638758 -344.781886)
		(size 0.49022)
		(drill 0.254)
		(layers "F.Cu" "B.Cu")
		(net "GND")
	)
	(via
		(at 240.376964 -169.877994)
		(size 0.508)
		(drill 0.254)
		(layers "F.Cu" "B.Cu")
		(net "GND")
	)
	(via
		(at 139.974828 -254.20447)
		(size 0.4064)
		(drill 0.2032)
		(layers "F.Cu" "B.Cu")
		(net "GND")
	)
	(via
		(at 450.088 -255.135126)
		(size 0.4826)
		(drill 0.254)
		(layers "F.Cu" "B.Cu")
		(net "GND")
	)
	(via
		(at 332.593442 -393.04468)
		(size 0.508)
		(drill 0.254)
		(layers "F.Cu" "B.Cu")
		(net "GND")
	)
	(via
		(at 350.172528 -340.500462)
		(size 0.49022)
		(drill 0.254)
		(layers "F.Cu" "B.Cu")
		(net "GND")
	)
	(via
		(at 110.371128 -235.574332)
		(size 0.4064)
		(drill 0.2032)
		(layers "F.Cu" "B.Cu")
		(net "GND")
	)
	(via
		(at 164.427916 -317.185294)
		(size 0.4826)
		(drill 0.254)
		(layers "F.Cu" "B.Cu")
		(net "GND")
	)
	(via
		(at 135.274812 -244.484398)
		(size 0.4064)
		(drill 0.2032)
		(layers "F.Cu" "B.Cu")
		(net "GND")
	)
	(via
		(at 441.091066 -403.21992)
		(size 0.508)
		(drill 0.254)
		(layers "F.Cu" "B.Cu")
		(net "GND")
	)
	(via
		(at 369.14709 -185.988198)
		(size 0.508)
		(drill 0.254)
		(layers "F.Cu" "B.Cu")
		(net "GND")
	)
	(via
		(at 436.855108 -347.601286)
		(size 0.508)
		(drill 0.254)
		(layers "F.Cu" "B.Cu")
		(net "GND")
	)
	(via
		(at 170.245024 -375.917968)
		(size 0.508)
		(drill 0.254)
		(layers "F.Cu" "B.Cu")
		(net "GND")
	)
	(via
		(at 183.616092 -244.935248)
		(size 0.4826)
		(drill 0.254)
		(layers "F.Cu" "B.Cu")
		(net "GND")
	)
	(via
		(at 62.92215 -339.887814)
		(size 0.508)
		(drill 0.254)
		(layers "F.Cu" "B.Cu")
		(net "GND")
	)
	(via
		(at 105.031032 -285.426404)
		(size 0.4064)
		(drill 0.2032)
		(layers "F.Cu" "B.Cu")
		(net "GND")
	)
	(via
		(at 216.716102 -385.733036)
		(size 0.508)
		(drill 0.254)
		(layers "F.Cu" "B.Cu")
		(net "GND")
	)
	(via
		(at 360.785918 -181.01564)
		(size 0.508)
		(drill 0.254)
		(layers "F.Cu" "B.Cu")
		(net "GND")
	)
	(via
		(at 188.444378 -296.785284)
		(size 0.4826)
		(drill 0.254)
		(layers "F.Cu" "B.Cu")
		(net "GND")
	)
	(via
		(at 99.861116 -291.096192)
		(size 0.4064)
		(drill 0.2032)
		(layers "F.Cu" "B.Cu")
		(net "GND")
	)
	(via
		(at 83.111086 -235.574332)
		(size 0.4064)
		(drill 0.2032)
		(layers "F.Cu" "B.Cu")
		(net "GND")
	)
	(via
		(at 295.724072 -227.085144)
		(size 0.4826)
		(drill 0.254)
		(layers "F.Cu" "B.Cu")
		(net "GND")
	)
	(via
		(at 324.75297 -230.169974)
		(size 0.4064)
		(drill 0.2032)
		(layers "F.Cu" "B.Cu")
		(net "GND")
	)
	(via
		(at 338.401152 -266.796012)
		(size 0.4064)
		(drill 0.2032)
		(layers "F.Cu" "B.Cu")
		(net "GND")
	)
	(via
		(at 404.212298 -170.528996)
		(size 0.49022)
		(drill 0.254)
		(layers "F.Cu" "B.Cu")
		(net "GND")
	)
	(via
		(at 452.704454 -399.233644)
		(size 0.49022)
		(drill 0.254)
		(layers "F.Cu" "B.Cu")
		(net "GND")
	)
	(via
		(at 81.106264 -386.449062)
		(size 0.4064)
		(drill 0.2032)
		(layers "F.Cu" "B.Cu")
		(net "GND")
	)
	(via
		(at 130.012694 -413.204152)
		(size 0.4572)
		(drill 0.254)
		(layers "F.Cu" "B.Cu")
		(net "GND")
	)
	(via
		(at 80.120998 -284.616398)
		(size 0.4064)
		(drill 0.2032)
		(layers "F.Cu" "B.Cu")
		(net "GND")
	)
	(via
		(at 336.521044 -294.335962)
		(size 0.4064)
		(drill 0.2032)
		(layers "F.Cu" "B.Cu")
		(net "GND")
	)
	(via
		(at 374.754902 -244.484144)
		(size 0.4064)
		(drill 0.2032)
		(layers "F.Cu" "B.Cu")
		(net "GND")
	)
	(via
		(at 123.613418 -407.638504)
		(size 0.4572)
		(drill 0.254)
		(layers "F.Cu" "B.Cu")
		(net "GND")
	)
	(via
		(at 94.84995 -189.526926)
		(size 0.508)
		(drill 0.254)
		(layers "F.Cu" "B.Cu")
		(net "GND")
	)
	(via
		(at 349.211138 -277.32609)
		(size 0.4064)
		(drill 0.2032)
		(layers "F.Cu" "B.Cu")
		(net "GND")
	)
	(via
		(at 104.58831 -180.755798)
		(size 0.508)
		(drill 0.254)
		(layers "F.Cu" "B.Cu")
		(net "GND")
	)
	(via
		(at 344.981022 -281.37612)
		(size 0.4064)
		(drill 0.2032)
		(layers "F.Cu" "B.Cu")
		(net "GND")
	)
	(via
		(at 317.559436 -381.68453)
		(size 0.508)
		(drill 0.254)
		(layers "F.Cu" "B.Cu")
		(net "GND")
	)
	(via
		(at 176.072038 -207.535272)
		(size 0.4826)
		(drill 0.254)
		(layers "F.Cu" "B.Cu")
		(net "GND")
	)
	(via
		(at 467.5378 -172.263054)
		(size 0.508)
		(drill 0.254)
		(layers "F.Cu" "B.Cu")
		(net "GND")
	)
	(via
		(at 71.411338 -132.537962)
		(size 0.508)
		(drill 0.254)
		(layers "F.Cu" "B.Cu")
		(net "GND")
	)
	(via
		(at 209.239358 -142.490952)
		(size 0.508)
		(drill 0.254)
		(layers "F.Cu" "B.Cu")
		(net "GND")
	)
	(via
		(at 321.816222 -400.212814)
		(size 0.4064)
		(drill 0.2032)
		(layers "F.Cu" "B.Cu")
		(net "GND")
	)
	(via
		(at 378.35459 -419.046152)
		(size 0.4572)
		(drill 0.254)
		(layers "F.Cu" "B.Cu")
		(net "GND")
	)
	(via
		(at 298.43984 -202.434952)
		(size 0.4826)
		(drill 0.254)
		(layers "F.Cu" "B.Cu")
		(net "GND")
	)
	(via
		(at 438.222644 -7.164832)
		(size 0.508)
		(drill 0.254)
		(layers "F.Cu" "B.Cu")
		(net "GND")
	)
	(via
		(at 121.09831 -167.776398)
		(size 0.508)
		(drill 0.254)
		(layers "F.Cu" "B.Cu")
		(net "GND")
	)
	(via
		(at 79.821024 -231.524302)
		(size 0.4064)
		(drill 0.2032)
		(layers "F.Cu" "B.Cu")
		(net "GND")
	)
	(via
		(at 18.992342 -231.335326)
		(size 0.4826)
		(drill 0.254)
		(layers "F.Cu" "B.Cu")
		(net "GND")
	)
	(via
		(at 38.3286 -364.109)
		(size 0.508)
		(drill 0.254)
		(layers "F.Cu" "B.Cu")
		(net "GND")
	)
	(via
		(at 376.461782 -420.952168)
		(size 0.4064)
		(drill 0.2032)
		(layers "F.Cu" "B.Cu")
		(net "GND")
	)
	(via
		(at 431.55616 -250.03506)
		(size 0.4826)
		(drill 0.254)
		(layers "F.Cu" "B.Cu")
		(net "GND")
	)
	(via
		(at 334.811116 -255.014222)
		(size 0.4064)
		(drill 0.2032)
		(layers "F.Cu" "B.Cu")
		(net "GND")
	)
	(via
		(at 50.684938 -432.96967)
		(size 0.508)
		(drill 0.254)
		(layers "F.Cu" "B.Cu")
		(net "GND")
	)
	(via
		(at 50.499772 -230.485442)
		(size 0.4826)
		(drill 0.254)
		(layers "F.Cu" "B.Cu")
		(net "GND")
	)
	(via
		(at 386.162296 -392.999722)
		(size 0.4064)
		(drill 0.2032)
		(layers "F.Cu" "B.Cu")
		(net "GND")
	)
	(via
		(at 51.918616 -411.936184)
		(size 0.4572)
		(drill 0.254)
		(layers "F.Cu" "B.Cu")
		(net "GND")
	)
	(via
		(at 390.094724 -287.856168)
		(size 0.4064)
		(drill 0.2032)
		(layers "F.Cu" "B.Cu")
		(net "GND")
	)
	(via
		(at 327.249536 -431.451258)
		(size 0.4572)
		(drill 0.2032)
		(layers "F.Cu" "B.Cu")
		(net "GND")
	)
	(via
		(at 44.340018 -282.335224)
		(size 0.4826)
		(drill 0.254)
		(layers "F.Cu" "B.Cu")
		(net "GND")
	)
	(via
		(at 356.909878 -167.507666)
		(size 0.49022)
		(drill 0.254)
		(layers "F.Cu" "B.Cu")
		(net "GND")
	)
	(via
		(at 453.518778 -396.09522)
		(size 0.49022)
		(drill 0.254)
		(layers "F.Cu" "B.Cu")
		(net "GND")
	)
	(via
		(at 51.884072 -310.385206)
		(size 0.4826)
		(drill 0.254)
		(layers "F.Cu" "B.Cu")
		(net "GND")
	)
	(via
		(at 329.965304 -134.625842)
		(size 0.508)
		(drill 0.254)
		(layers "F.Cu" "B.Cu")
		(net "GND")
	)
	(via
		(at 269.648178 -244.934994)
		(size 0.4826)
		(drill 0.254)
		(layers "F.Cu" "B.Cu")
		(net "GND")
	)
	(via
		(at 20.921218 -16.979138)
		(size 0.508)
		(drill 0.254)
		(layers "F.Cu" "B.Cu")
		(net "GND")
	)
	(via
		(at 45.206158 -344.781886)
		(size 0.49022)
		(drill 0.254)
		(layers "F.Cu" "B.Cu")
		(net "GND")
	)
	(via
		(at 121.944638 -282.18638)
		(size 0.4064)
		(drill 0.2032)
		(layers "F.Cu" "B.Cu")
		(net "GND")
	)
	(via
		(at 305.016408 -400.212814)
		(size 0.4064)
		(drill 0.2032)
		(layers "F.Cu" "B.Cu")
		(net "GND")
	)
	(via
		(at 325.397622 -397.274542)
		(size 0.508)
		(drill 0.254)
		(layers "F.Cu" "B.Cu")
		(net "GND")
	)
	(via
		(at 168.06799 -347.289882)
		(size 0.508)
		(drill 0.254)
		(layers "F.Cu" "B.Cu")
		(net "GND")
	)
	(via
		(at 284.736032 -308.685184)
		(size 0.4826)
		(drill 0.254)
		(layers "F.Cu" "B.Cu")
		(net "GND")
	)
	(via
		(at 103.088186 -338.789264)
		(size 0.49022)
		(drill 0.254)
		(layers "F.Cu" "B.Cu")
		(net "GND")
	)
	(via
		(at 129.018538 -388.328662)
		(size 0.4064)
		(drill 0.2032)
		(layers "F.Cu" "B.Cu")
		(net "GND")
	)
	(via
		(at 112.19815 -178.422046)
		(size 0.508)
		(drill 0.254)
		(layers "F.Cu" "B.Cu")
		(net "GND")
	)
	(via
		(at 58.043826 -302.735234)
		(size 0.4826)
		(drill 0.254)
		(layers "F.Cu" "B.Cu")
		(net "GND")
	)
	(via
		(at 22.6441 -39.241476)
		(size 0.508)
		(drill 0.254)
		(layers "F.Cu" "B.Cu")
		(net "GND")
	)
	(via
		(at 276.074632 -229.210108)
		(size 0.4826)
		(drill 0.254)
		(layers "F.Cu" "B.Cu")
		(net "GND")
	)
	(via
		(at 350.151192 -272.466054)
		(size 0.4064)
		(drill 0.2032)
		(layers "F.Cu" "B.Cu")
		(net "GND")
	)
	(via
		(at 400.24812 -9.424924)
		(size 0.508)
		(drill 0.254)
		(layers "F.Cu" "B.Cu")
		(net "GND")
	)
	(via
		(at 120.70461 -250.15444)
		(size 0.4064)
		(drill 0.2032)
		(layers "F.Cu" "B.Cu")
		(net "GND")
	)
	(via
		(at 189.94501 -350.17075)
		(size 0.49022)
		(drill 0.254)
		(layers "F.Cu" "B.Cu")
		(net "GND")
	)
	(via
		(at 288.180018 -267.885164)
		(size 0.4826)
		(drill 0.254)
		(layers "F.Cu" "B.Cu")
		(net "GND")
	)
	(via
		(at 44.340018 -241.535204)
		(size 0.4826)
		(drill 0.254)
		(layers "F.Cu" "B.Cu")
		(net "GND")
	)
	(via
		(at 442.303154 -441.227718)
		(size 0.508)
		(drill 0.254)
		(layers "F.Cu" "B.Cu")
		(net "GND")
	)
	(via
		(at 467.5378 -200.203054)
		(size 0.508)
		(drill 0.254)
		(layers "F.Cu" "B.Cu")
		(net "GND")
	)
	(via
		(at 50.386996 -410.664152)
		(size 0.4572)
		(drill 0.254)
		(layers "F.Cu" "B.Cu")
		(net "GND")
	)
	(via
		(at 407.182574 -416.020504)
		(size 0.4572)
		(drill 0.254)
		(layers "F.Cu" "B.Cu")
		(net "GND")
	)
	(via
		(at 292.280086 -268.735048)
		(size 0.4826)
		(drill 0.254)
		(layers "F.Cu" "B.Cu")
		(net "GND")
	)
	(via
		(at 78.41107 -237.194344)
		(size 0.4064)
		(drill 0.2032)
		(layers "F.Cu" "B.Cu")
		(net "GND")
	)
	(via
		(at 302.46828 -391.290048)
		(size 0.4064)
		(drill 0.2032)
		(layers "F.Cu" "B.Cu")
		(net "GND")
	)
	(via
		(at 10.876788 -370.60505)
		(size 0.508)
		(drill 0.254)
		(layers "F.Cu" "B.Cu")
		(net "GND")
	)
	(via
		(at 204.8637 -202.435206)
		(size 0.4826)
		(drill 0.254)
		(layers "F.Cu" "B.Cu")
		(net "GND")
	)
	(via
		(at 412.486856 -164.19576)
		(size 0.49022)
		(drill 0.254)
		(layers "F.Cu" "B.Cu")
		(net "GND")
	)
	(via
		(at 138.377676 -375.432828)
		(size 0.508)
		(drill 0.254)
		(layers "F.Cu" "B.Cu")
		(net "GND")
	)
	(via
		(at 169.102024 -382.237488)
		(size 0.508)
		(drill 0.254)
		(layers "F.Cu" "B.Cu")
		(net "GND")
	)
	(via
		(at 212.51418 -328.00417)
		(size 0.508)
		(drill 0.254)
		(layers "F.Cu" "B.Cu")
		(net "GND")
	)
	(via
		(at 383.514854 -271.656048)
		(size 0.4064)
		(drill 0.2032)
		(layers "F.Cu" "B.Cu")
		(net "GND")
	)
	(via
		(at 376.550174 -414.752536)
		(size 0.4572)
		(drill 0.254)
		(layers "F.Cu" "B.Cu")
		(net "GND")
	)
	(via
		(at 376.634756 -238.004096)
		(size 0.4064)
		(drill 0.2032)
		(layers "F.Cu" "B.Cu")
		(net "GND")
	)
	(via
		(at 378.878592 -394.831062)
		(size 0.4064)
		(drill 0.2032)
		(layers "F.Cu" "B.Cu")
		(net "GND")
	)
	(via
		(at 183.616092 -318.035432)
		(size 0.4826)
		(drill 0.254)
		(layers "F.Cu" "B.Cu")
		(net "GND")
	)
	(via
		(at 348.529656 -361.64774)
		(size 0.508)
		(drill 0.254)
		(layers "F.Cu" "B.Cu")
		(net "GND")
	)
	(via
		(at 376.634756 -246.104156)
		(size 0.4064)
		(drill 0.2032)
		(layers "F.Cu" "B.Cu")
		(net "GND")
	)
	(via
		(at 137.154666 -228.284532)
		(size 0.4064)
		(drill 0.2032)
		(layers "F.Cu" "B.Cu")
		(net "GND")
	)
	(via
		(at 15.793974 -368.767614)
		(size 0.6604)
		(drill 0.3302)
		(layers "F.Cu" "B.Cu")
		(net "GND")
	)
	(via
		(at 83.41106 -293.52621)
		(size 0.4064)
		(drill 0.2032)
		(layers "F.Cu" "B.Cu")
		(net "GND")
	)
	(via
		(at 48.397414 -344.772234)
		(size 0.508)
		(drill 0.254)
		(layers "F.Cu" "B.Cu")
		(net "GND")
	)
	(via
		(at 341.144098 -391.23493)
		(size 0.4064)
		(drill 0.2032)
		(layers "F.Cu" "B.Cu")
		(net "GND")
	)
	(via
		(at 370.562378 -392.999722)
		(size 0.4064)
		(drill 0.2032)
		(layers "F.Cu" "B.Cu")
		(net "GND")
	)
	(via
		(at 312.513218 -417.778184)
		(size 0.4572)
		(drill 0.254)
		(layers "F.Cu" "B.Cu")
		(net "GND")
	)
	(via
		(at 56.712358 -238.135414)
		(size 0.4826)
		(drill 0.254)
		(layers "F.Cu" "B.Cu")
		(net "GND")
	)
	(via
		(at 78.180946 -355.160326)
		(size 0.508)
		(drill 0.254)
		(layers "F.Cu" "B.Cu")
		(net "GND")
	)
	(via
		(at 352.197924 -255.822196)
		(size 0.4064)
		(drill 0.2032)
		(layers "F.Cu" "B.Cu")
		(net "GND")
	)
	(via
		(at 269.648178 -267.035026)
		(size 0.4826)
		(drill 0.254)
		(layers "F.Cu" "B.Cu")
		(net "GND")
	)
	(via
		(at 167.143684 -209.235294)
		(size 0.4826)
		(drill 0.254)
		(layers "F.Cu" "B.Cu")
		(net "GND")
	)
	(via
		(at 192.277746 -201.16038)
		(size 0.4826)
		(drill 0.254)
		(layers "F.Cu" "B.Cu")
		(net "GND")
	)
	(via
		(at 72.45604 -59.436)
		(size 0.508)
		(drill 0.254)
		(layers "F.Cu" "B.Cu")
		(net "GND")
	)
	(via
		(at 71.249794 -430.299622)
		(size 0.4572)
		(drill 0.2032)
		(layers "F.Cu" "B.Cu")
		(net "GND")
	)
	(via
		(at 341.886794 -414.752536)
		(size 0.4572)
		(drill 0.254)
		(layers "F.Cu" "B.Cu")
		(net "GND")
	)
	(via
		(at 272.593816 -97.387918)
		(size 0.508)
		(drill 0.254)
		(layers "F.Cu" "B.Cu")
		(net "GND")
	)
	(via
		(at 336.521044 -295.955974)
		(size 0.4064)
		(drill 0.2032)
		(layers "F.Cu" "B.Cu")
		(net "GND")
	)
	(via
		(at 384.399028 -177.2285)
		(size 0.508)
		(drill 0.254)
		(layers "F.Cu" "B.Cu")
		(net "GND")
	)
	(via
		(at 25.152096 -199.035416)
		(size 0.4826)
		(drill 0.254)
		(layers "F.Cu" "B.Cu")
		(net "GND")
	)
	(via
		(at 198.12 -344.805)
		(size 0.508)
		(drill 0.254)
		(layers "F.Cu" "B.Cu")
		(net "GND")
	)
	(via
		(at 143.264636 -245.294404)
		(size 0.4064)
		(drill 0.2032)
		(layers "F.Cu" "B.Cu")
		(net "GND")
	)
	(via
		(at 344.681048 -241.24412)
		(size 0.4064)
		(drill 0.2032)
		(layers "F.Cu" "B.Cu")
		(net "GND")
	)
	(via
		(at 28.619958 -344.781886)
		(size 0.49022)
		(drill 0.254)
		(layers "F.Cu" "B.Cu")
		(net "GND")
	)
	(via
		(at 393.084812 -253.39421)
		(size 0.4064)
		(drill 0.2032)
		(layers "F.Cu" "B.Cu")
		(net "GND")
	)
	(via
		(at 47.784004 -317.185294)
		(size 0.4826)
		(drill 0.254)
		(layers "F.Cu" "B.Cu")
		(net "GND")
	)
	(via
		(at 428.588678 -365.828072)
		(size 0.508)
		(drill 0.254)
		(layers "F.Cu" "B.Cu")
		(net "GND")
	)
	(via
		(at 292.280086 -271.284954)
		(size 0.4826)
		(drill 0.254)
		(layers "F.Cu" "B.Cu")
		(net "GND")
	)
	(via
		(at 339.811106 -280.566114)
		(size 0.4064)
		(drill 0.2032)
		(layers "F.Cu" "B.Cu")
		(net "GND")
	)
	(via
		(at 401.32889 -420.318184)
		(size 0.4572)
		(drill 0.254)
		(layers "F.Cu" "B.Cu")
		(net "GND")
	)
	(via
		(at 340.921086 -236.384084)
		(size 0.4064)
		(drill 0.2032)
		(layers "F.Cu" "B.Cu")
		(net "GND")
	)
	(via
		(at 362.534708 -244.484144)
		(size 0.4064)
		(drill 0.2032)
		(layers "F.Cu" "B.Cu")
		(net "GND")
	)
	(via
		(at 416.64509 -412.212536)
		(size 0.4572)
		(drill 0.254)
		(layers "F.Cu" "B.Cu")
		(net "GND")
	)
	(via
		(at 331.201522 -363.405166)
		(size 0.508)
		(drill 0.254)
		(layers "F.Cu" "B.Cu")
		(net "GND")
	)
	(via
		(at 328.188066 -418.412168)
		(size 0.4064)
		(drill 0.2032)
		(layers "F.Cu" "B.Cu")
		(net "GND")
	)
	(via
		(at 182.231792 -211.7852)
		(size 0.4826)
		(drill 0.254)
		(layers "F.Cu" "B.Cu")
		(net "GND")
	)
	(via
		(at 125.278388 -386.449062)
		(size 0.4064)
		(drill 0.2032)
		(layers "F.Cu" "B.Cu")
		(net "GND")
	)
	(via
		(at 42.058336 -9.424924)
		(size 0.508)
		(drill 0.254)
		(layers "F.Cu" "B.Cu")
		(net "GND")
	)
	(via
		(at 85.906356 -386.449062)
		(size 0.4064)
		(drill 0.2032)
		(layers "F.Cu" "B.Cu")
		(net "GND")
	)
	(via
		(at 212.55736 -97.028762)
		(size 0.508)
		(drill 0.254)
		(layers "F.Cu" "B.Cu")
		(net "GND")
	)
	(via
		(at 344.249502 -425.547282)
		(size 0.4572)
		(drill 0.2032)
		(layers "F.Cu" "B.Cu")
		(net "GND")
	)
	(via
		(at 197.3199 -199.8853)
		(size 0.4826)
		(drill 0.254)
		(layers "F.Cu" "B.Cu")
		(net "GND")
	)
	(via
		(at 373.963692 -377.41733)
		(size 0.508)
		(drill 0.254)
		(layers "F.Cu" "B.Cu")
		(net "GND")
	)
	(via
		(at 139.974828 -233.144314)
		(size 0.4064)
		(drill 0.2032)
		(layers "F.Cu" "B.Cu")
		(net "GND")
	)
	(via
		(at 179.516024 -317.185294)
		(size 0.4826)
		(drill 0.254)
		(layers "F.Cu" "B.Cu")
		(net "GND")
	)
	(via
		(at 141.058392 -377.49226)
		(size 0.508)
		(drill 0.254)
		(layers "F.Cu" "B.Cu")
		(net "GND")
	)
	(via
		(at 206.248 -215.185244)
		(size 0.4826)
		(drill 0.254)
		(layers "F.Cu" "B.Cu")
		(net "GND")
	)
	(via
		(at 218.789758 -86.296754)
		(size 0.508)
		(drill 0.254)
		(layers "F.Cu" "B.Cu")
		(net "GND")
	)
	(via
		(at 427.353476 -400.08175)
		(size 0.508)
		(drill 0.254)
		(layers "F.Cu" "B.Cu")
		(net "GND")
	)
	(via
		(at 125.2347 -263.556242)
		(size 0.4064)
		(drill 0.2032)
		(layers "F.Cu" "B.Cu")
		(net "GND")
	)
	(via
		(at 62.991238 -390.160002)
		(size 0.4064)
		(drill 0.2032)
		(layers "F.Cu" "B.Cu")
		(net "GND")
	)
	(via
		(at 299.82414 -288.285174)
		(size 0.4826)
		(drill 0.254)
		(layers "F.Cu" "B.Cu")
		(net "GND")
	)
	(via
		(at 117.759734 -405.098504)
		(size 0.4572)
		(drill 0.254)
		(layers "F.Cu" "B.Cu")
		(net "GND")
	)
	(via
		(at 43.87596 -111.31804)
		(size 0.508)
		(drill 0.254)
		(layers "F.Cu" "B.Cu")
		(net "GND")
	)
	(via
		(at 93.280992 -271.656302)
		(size 0.4064)
		(drill 0.2032)
		(layers "F.Cu" "B.Cu")
		(net "GND")
	)
	(via
		(at 295.724072 -264.48512)
		(size 0.4826)
		(drill 0.254)
		(layers "F.Cu" "B.Cu")
		(net "GND")
	)
	(via
		(at 427.975268 -59.436)
		(size 0.508)
		(drill 0.254)
		(layers "F.Cu" "B.Cu")
		(net "GND")
	)
	(via
		(at 41.430702 -377.49226)
		(size 0.508)
		(drill 0.254)
		(layers "F.Cu" "B.Cu")
		(net "GND")
	)
	(via
		(at 369.114832 -250.964192)
		(size 0.4064)
		(drill 0.2032)
		(layers "F.Cu" "B.Cu")
		(net "GND")
	)
	(via
		(at 28.341574 -348.709488)
		(size 0.49022)
		(drill 0.254)
		(layers "F.Cu" "B.Cu")
		(net "GND")
	)
	(via
		(at 119.60733 -32.51708)
		(size 0.508)
		(drill 0.254)
		(layers "F.Cu" "B.Cu")
		(net "GND")
	)
	(via
		(at 191.160146 -250.035314)
		(size 0.4826)
		(drill 0.254)
		(layers "F.Cu" "B.Cu")
		(net "GND")
	)
	(via
		(at 117.486938 -406.370536)
		(size 0.4572)
		(drill 0.254)
		(layers "F.Cu" "B.Cu")
		(net "GND")
	)
	(via
		(at 381.634746 -273.27606)
		(size 0.4064)
		(drill 0.2032)
		(layers "F.Cu" "B.Cu")
		(net "GND")
	)
	(via
		(at 237.616238 -53.364892)
		(size 0.508)
		(drill 0.254)
		(layers "F.Cu" "B.Cu")
		(net "GND")
	)
	(via
		(at 90.19794 -355.171248)
		(size 0.508)
		(drill 0.254)
		(layers "F.Cu" "B.Cu")
		(net "GND")
	)
	(via
		(at 77.330046 -154.83078)
		(size 0.508)
		(drill 0.254)
		(layers "F.Cu" "B.Cu")
		(net "GND")
	)
	(via
		(at 407.641298 -168.027858)
		(size 0.49022)
		(drill 0.254)
		(layers "F.Cu" "B.Cu")
		(net "GND")
	)
	(via
		(at 120.064784 -291.906198)
		(size 0.4064)
		(drill 0.2032)
		(layers "F.Cu" "B.Cu")
		(net "GND")
	)
	(via
		(at 121.09831 -169.097198)
		(size 0.508)
		(drill 0.254)
		(layers "F.Cu" "B.Cu")
		(net "GND")
	)
	(via
		(at 370.382546 -12.542266)
		(size 0.508)
		(drill 0.254)
		(layers "F.Cu" "B.Cu")
		(net "GND")
	)
	(via
		(at 347.897704 -376.75693)
		(size 0.508)
		(drill 0.254)
		(layers "F.Cu" "B.Cu")
		(net "GND")
	)
	(via
		(at 361.594908 -238.004096)
		(size 0.4064)
		(drill 0.2032)
		(layers "F.Cu" "B.Cu")
		(net "GND")
	)
	(via
		(at 54.210458 -314.210446)
		(size 0.4826)
		(drill 0.254)
		(layers "F.Cu" "B.Cu")
		(net "GND")
	)
	(via
		(at 367.685066 -425.018962)
		(size 0.508)
		(drill 0.254)
		(layers "F.Cu" "B.Cu")
		(net "GND")
	)
	(via
		(at 35.411664 -221.135194)
		(size 0.4826)
		(drill 0.254)
		(layers "F.Cu" "B.Cu")
		(net "GND")
	)
	(via
		(at 341.691214 -264.365994)
		(size 0.4064)
		(drill 0.2032)
		(layers "F.Cu" "B.Cu")
		(net "GND")
	)
	(via
		(at 56.599582 -5.597398)
		(size 0.508)
		(drill 0.254)
		(layers "F.Cu" "B.Cu")
		(net "GND")
	)
	(via
		(at 336.131154 -441.227718)
		(size 0.508)
		(drill 0.254)
		(layers "F.Cu" "B.Cu")
		(net "GND")
	)
	(via
		(at 331.926946 -334.12176)
		(size 0.508)
		(drill 0.254)
		(layers "F.Cu" "B.Cu")
		(net "GND")
	)
	(via
		(at 67.015106 -175.780446)
		(size 0.508)
		(drill 0.254)
		(layers "F.Cu" "B.Cu")
		(net "GND")
	)
	(via
		(at 141.718792 -381.3302)
		(size 0.508)
		(drill 0.254)
		(layers "F.Cu" "B.Cu")
		(net "GND")
	)
	(via
		(at 341.613998 -412.212536)
		(size 0.4572)
		(drill 0.254)
		(layers "F.Cu" "B.Cu")
		(net "GND")
	)
	(via
		(at 369.884706 -272.466054)
		(size 0.4064)
		(drill 0.2032)
		(layers "F.Cu" "B.Cu")
		(net "GND")
	)
	(via
		(at 424.012106 -244.934994)
		(size 0.4826)
		(drill 0.254)
		(layers "F.Cu" "B.Cu")
		(net "GND")
	)
	(via
		(at 246.301514 -318.704468)
		(size 0.508)
		(drill 0.254)
		(layers "F.Cu" "B.Cu")
		(net "GND")
	)
	(via
		(at 148.666962 -80.81518)
		(size 0.6604)
		(drill 0.3302)
		(layers "F.Cu" "B.Cu")
		(net "GND")
	)
	(via
		(at 372.704868 -264.365994)
		(size 0.4064)
		(drill 0.2032)
		(layers "F.Cu" "B.Cu")
		(net "GND")
	)
	(via
		(at 409.349702 -431.29962)
		(size 0.4572)
		(drill 0.2032)
		(layers "F.Cu" "B.Cu")
		(net "GND")
	)
	(via
		(at 80.591152 -264.366248)
		(size 0.4064)
		(drill 0.2032)
		(layers "F.Cu" "B.Cu")
		(net "GND")
	)
	(via
		(at 346.091002 -235.574078)
		(size 0.4064)
		(drill 0.2032)
		(layers "F.Cu" "B.Cu")
		(net "GND")
	)
	(via
		(at 269.648178 -213.484968)
		(size 0.4826)
		(drill 0.254)
		(layers "F.Cu" "B.Cu")
		(net "GND")
	)
	(via
		(at 23.628096 -386.914898)
		(size 0.49022)
		(drill 0.254)
		(layers "F.Cu" "B.Cu")
		(net "GND")
	)
	(via
		(at 58.310526 -238.560356)
		(size 0.4826)
		(drill 0.254)
		(layers "F.Cu" "B.Cu")
		(net "GND")
	)
	(via
		(at 151.694642 -81.8388)
		(size 0.508)
		(drill 0.254)
		(layers "F.Cu" "B.Cu")
		(net "GND")
	)
	(via
		(at 303.268126 -289.135058)
		(size 0.4826)
		(drill 0.254)
		(layers "F.Cu" "B.Cu")
		(net "GND")
	)
	(via
		(at 50.499772 -239.835436)
		(size 0.4826)
		(drill 0.254)
		(layers "F.Cu" "B.Cu")
		(net "GND")
	)
	(via
		(at 307.4162 -400.212814)
		(size 0.4064)
		(drill 0.2032)
		(layers "F.Cu" "B.Cu")
		(net "GND")
	)
	(via
		(at 120.904 -426.72)
		(size 0.508)
		(drill 0.254)
		(layers "F.Cu" "B.Cu")
		(net "GND")
	)
	(via
		(at 8.814816 -384.86969)
		(size 0.508)
		(drill 0.254)
		(layers "F.Cu" "B.Cu")
		(net "GND")
	)
	(via
		(at 2.76225 -283.393134)
		(size 0.508)
		(drill 0.254)
		(layers "F.Cu" "B.Cu")
		(net "GND")
	)
	(via
		(at 136.225026 -410.030168)
		(size 0.4064)
		(drill 0.2032)
		(layers "F.Cu" "B.Cu")
		(net "GND")
	)
	(via
		(at 454.188068 -282.33497)
		(size 0.4826)
		(drill 0.254)
		(layers "F.Cu" "B.Cu")
		(net "GND")
	)
	(via
		(at 287.062418 -230.060246)
		(size 0.4826)
		(drill 0.254)
		(layers "F.Cu" "B.Cu")
		(net "GND")
	)
	(via
		(at 390.094724 -271.656048)
		(size 0.4064)
		(drill 0.2032)
		(layers "F.Cu" "B.Cu")
		(net "GND")
	)
	(via
		(at 47.784004 -290.835334)
		(size 0.4826)
		(drill 0.254)
		(layers "F.Cu" "B.Cu")
		(net "GND")
	)
	(via
		(at 181.619398 -153.232612)
		(size 0.508)
		(drill 0.254)
		(layers "F.Cu" "B.Cu")
		(net "GND")
	)
	(via
		(at 392.587226 -191.727328)
		(size 0.508)
		(drill 0.254)
		(layers "F.Cu" "B.Cu")
		(net "GND")
	)
	(via
		(at 447.419476 -422.134538)
		(size 0.508)
		(drill 0.254)
		(layers "F.Cu" "B.Cu")
		(net "GND")
	)
	(via
		(at 88.580976 -268.416278)
		(size 0.4064)
		(drill 0.2032)
		(layers "F.Cu" "B.Cu")
		(net "GND")
	)
	(via
		(at 119.294656 -249.344434)
		(size 0.4064)
		(drill 0.2032)
		(layers "F.Cu" "B.Cu")
		(net "GND")
	)
	(via
		(at 283.72181 -346.317316)
		(size 0.49022)
		(drill 0.254)
		(layers "F.Cu" "B.Cu")
		(net "GND")
	)
	(via
		(at 53.450236 -407.638504)
		(size 0.4572)
		(drill 0.254)
		(layers "F.Cu" "B.Cu")
		(net "GND")
	)
	(via
		(at 234.696 -332.74)
		(size 0.508)
		(drill 0.254)
		(layers "F.Cu" "B.Cu")
		(net "GND")
	)
	(via
		(at 78.711044 -285.426404)
		(size 0.4064)
		(drill 0.2032)
		(layers "F.Cu" "B.Cu")
		(net "GND")
	)
	(via
		(at 4.81584 -405.937974)
		(size 0.508)
		(drill 0.254)
		(layers "F.Cu" "B.Cu")
		(net "GND")
	)
	(via
		(at 99.561142 -229.90429)
		(size 0.4064)
		(drill 0.2032)
		(layers "F.Cu" "B.Cu")
		(net "GND")
	)
	(via
		(at 298.70654 -210.51012)
		(size 0.4826)
		(drill 0.254)
		(layers "F.Cu" "B.Cu")
		(net "GND")
	)
	(via
		(at 320.444114 -419.046152)
		(size 0.4572)
		(drill 0.254)
		(layers "F.Cu" "B.Cu")
		(net "GND")
	)
	(via
		(at 283.443426 -347.282262)
		(size 0.49022)
		(drill 0.254)
		(layers "F.Cu" "B.Cu")
		(net "GND")
	)
	(via
		(at 383.514854 -263.555988)
		(size 0.4064)
		(drill 0.2032)
		(layers "F.Cu" "B.Cu")
		(net "GND")
	)
	(via
		(at 431.094388 -351.70618)
		(size 0.49022)
		(drill 0.254)
		(layers "F.Cu" "B.Cu")
		(net "GND")
	)
	(via
		(at 174.687738 -221.135194)
		(size 0.4826)
		(drill 0.254)
		(layers "F.Cu" "B.Cu")
		(net "GND")
	)
	(via
		(at 420.87292 -18.5039)
		(size 0.508)
		(drill 0.254)
		(layers "F.Cu" "B.Cu")
		(net "GND")
	)
	(via
		(at 341.22106 -274.896072)
		(size 0.4064)
		(drill 0.2032)
		(layers "F.Cu" "B.Cu")
		(net "GND")
	)
	(via
		(at 26.536396 -200.735438)
		(size 0.4826)
		(drill 0.254)
		(layers "F.Cu" "B.Cu")
		(net "GND")
	)
	(via
		(at 99.054666 -184.632346)
		(size 0.49022)
		(drill 0.254)
		(layers "F.Cu" "B.Cu")
		(net "GND")
	)
	(via
		(at 300.38421 -345.566238)
		(size 0.49022)
		(drill 0.254)
		(layers "F.Cu" "B.Cu")
		(net "GND")
	)
	(via
		(at 110.76686 -31.497778)
		(size 0.508)
		(drill 0.254)
		(layers "F.Cu" "B.Cu")
		(net "GND")
	)
	(via
		(at 338.101178 -221.80423)
		(size 0.4064)
		(drill 0.2032)
		(layers "F.Cu" "B.Cu")
		(net "GND")
	)
	(via
		(at 41.78935 -5.597398)
		(size 0.508)
		(drill 0.254)
		(layers "F.Cu" "B.Cu")
		(net "GND")
	)
	(via
		(at 189.504828 -382.760474)
		(size 0.508)
		(drill 0.254)
		(layers "F.Cu" "B.Cu")
		(net "GND")
	)
	(via
		(at 305.983894 -230.485188)
		(size 0.4826)
		(drill 0.254)
		(layers "F.Cu" "B.Cu")
		(net "GND")
	)
	(via
		(at 366.764824 -237.19409)
		(size 0.4064)
		(drill 0.2032)
		(layers "F.Cu" "B.Cu")
		(net "GND")
	)
	(via
		(at 155.694126 -113.60404)
		(size 0.508)
		(drill 0.254)
		(layers "F.Cu" "B.Cu")
		(net "GND")
	)
	(via
		(at 123.972066 -407.00452)
		(size 0.4064)
		(drill 0.2032)
		(layers "F.Cu" "B.Cu")
		(net "GND")
	)
	(via
		(at 102.38105 -242.864386)
		(size 0.4064)
		(drill 0.2032)
		(layers "F.Cu" "B.Cu")
		(net "GND")
	)
	(via
		(at 180.633624 -286.160464)
		(size 0.4826)
		(drill 0.254)
		(layers "F.Cu" "B.Cu")
		(net "GND")
	)
	(via
		(at 128.481074 -410.664152)
		(size 0.4572)
		(drill 0.254)
		(layers "F.Cu" "B.Cu")
		(net "GND")
	)
	(via
		(at 432.974496 -110.1471)
		(size 0.508)
		(drill 0.254)
		(layers "F.Cu" "B.Cu")
		(net "GND")
	)
	(via
		(at 206.248 -196.485256)
		(size 0.4826)
		(drill 0.254)
		(layers "F.Cu" "B.Cu")
		(net "GND")
	)
	(via
		(at 179.496974 -413.349694)
		(size 0.508)
		(drill 0.254)
		(layers "F.Cu" "B.Cu")
		(net "GND")
	)
	(via
		(at 44.340018 -205.83525)
		(size 0.4826)
		(drill 0.254)
		(layers "F.Cu" "B.Cu")
		(net "GND")
	)
	(via
		(at 391.204704 -238.814102)
		(size 0.4064)
		(drill 0.2032)
		(layers "F.Cu" "B.Cu")
		(net "GND")
	)
	(via
		(at 364.24489 -274.086066)
		(size 0.4064)
		(drill 0.2032)
		(layers "F.Cu" "B.Cu")
		(net "GND")
	)
	(via
		(at 358.61117 -288.66592)
		(size 0.4064)
		(drill 0.2032)
		(layers "F.Cu" "B.Cu")
		(net "GND")
	)
	(via
		(at 358.593644 -377.41733)
		(size 0.508)
		(drill 0.254)
		(layers "F.Cu" "B.Cu")
		(net "GND")
	)
	(via
		(at 336.521044 -265.176)
		(size 0.4064)
		(drill 0.2032)
		(layers "F.Cu" "B.Cu")
		(net "GND")
	)
	(via
		(at 356.261162 -270.036036)
		(size 0.4064)
		(drill 0.2032)
		(layers "F.Cu" "B.Cu")
		(net "GND")
	)
	(via
		(at 11.324082 -426.113702)
		(size 0.508)
		(drill 0.254)
		(layers "F.Cu" "B.Cu")
		(net "GND")
	)
	(via
		(at 126.562358 -384.617722)
		(size 0.4064)
		(drill 0.2032)
		(layers "F.Cu" "B.Cu")
		(net "GND")
	)
	(via
		(at 298.43984 -312.084974)
		(size 0.4826)
		(drill 0.254)
		(layers "F.Cu" "B.Cu")
		(net "GND")
	)
	(via
		(at 348.911164 -256.634234)
		(size 0.4064)
		(drill 0.2032)
		(layers "F.Cu" "B.Cu")
		(net "GND")
	)
	(via
		(at 388.21487 -284.616144)
		(size 0.4064)
		(drill 0.2032)
		(layers "F.Cu" "B.Cu")
		(net "GND")
	)
	(via
		(at 140.744702 -291.906198)
		(size 0.4064)
		(drill 0.2032)
		(layers "F.Cu" "B.Cu")
		(net "GND")
	)
	(via
		(at 418.4015 -383.00533)
		(size 0.508)
		(drill 0.254)
		(layers "F.Cu" "B.Cu")
		(net "GND")
	)
	(via
		(at 115.955318 -403.830536)
		(size 0.4572)
		(drill 0.254)
		(layers "F.Cu" "B.Cu")
		(net "GND")
	)
	(via
		(at 250.270772 -420.65067)
		(size 0.508)
		(drill 0.254)
		(layers "F.Cu" "B.Cu")
		(net "GND")
	)
	(via
		(at 96.335596 -409.396184)
		(size 0.4572)
		(drill 0.254)
		(layers "F.Cu" "B.Cu")
		(net "GND")
	)
	(via
		(at 338.401152 -265.176)
		(size 0.4064)
		(drill 0.2032)
		(layers "F.Cu" "B.Cu")
		(net "GND")
	)
	(via
		(at 97.6884 -56.3372)
		(size 0.508)
		(drill 0.254)
		(layers "F.Cu" "B.Cu")
		(net "GND")
	)
	(via
		(at 143.681704 -370.83873)
		(size 0.508)
		(drill 0.254)
		(layers "F.Cu" "B.Cu")
		(net "GND")
	)
	(via
		(at 140.4874 -57.8358)
		(size 0.508)
		(drill 0.254)
		(layers "F.Cu" "B.Cu")
		(net "GND")
	)
	(via
		(at 27.414474 -40.326818)
		(size 0.508)
		(drill 0.254)
		(layers "F.Cu" "B.Cu")
		(net "GND")
	)
	(via
		(at 105.671112 -229.094538)
		(size 0.4064)
		(drill 0.2032)
		(layers "F.Cu" "B.Cu")
		(net "GND")
	)
	(via
		(at 210.711288 -75.313794)
		(size 0.508)
		(drill 0.254)
		(layers "F.Cu" "B.Cu")
		(net "GND")
	)
	(via
		(at 118.162324 -384.617722)
		(size 0.4064)
		(drill 0.2032)
		(layers "F.Cu" "B.Cu")
		(net "GND")
	)
	(via
		(at 90.002106 -184.615074)
		(size 0.49022)
		(drill 0.254)
		(layers "F.Cu" "B.Cu")
		(net "GND")
	)
	(via
		(at 12.700508 -114.072924)
		(size 0.508)
		(drill 0.254)
		(layers "F.Cu" "B.Cu")
		(net "GND")
	)
	(via
		(at 143.56461 -267.606272)
		(size 0.4064)
		(drill 0.2032)
		(layers "F.Cu" "B.Cu")
		(net "GND")
	)
	(via
		(at 416.5092 -108.453428)
		(size 0.508)
		(drill 0.254)
		(layers "F.Cu" "B.Cu")
		(net "GND")
	)
	(via
		(at 365.18469 -267.606018)
		(size 0.4064)
		(drill 0.2032)
		(layers "F.Cu" "B.Cu")
		(net "GND")
	)
	(via
		(at 233.016044 -43.688)
		(size 0.508)
		(drill 0.254)
		(layers "F.Cu" "B.Cu")
		(net "GND")
	)
	(via
		(at 25.152096 -252.58522)
		(size 0.4826)
		(drill 0.254)
		(layers "F.Cu" "B.Cu")
		(net "GND")
	)
	(via
		(at 421.92194 -98.850958)
		(size 0.6604)
		(drill 0.3302)
		(layers "F.Cu" "B.Cu")
		(net "GND")
	)
	(via
		(at 407.180288 -4.32943)
		(size 0.508)
		(drill 0.254)
		(layers "F.Cu" "B.Cu")
		(net "GND")
	)
	(via
		(at 123.994672 -228.284532)
		(size 0.4064)
		(drill 0.2032)
		(layers "F.Cu" "B.Cu")
		(net "GND")
	)
	(via
		(at 281.74061 -345.566238)
		(size 0.49022)
		(drill 0.254)
		(layers "F.Cu" "B.Cu")
		(net "GND")
	)
	(via
		(at 326.351138 -224.234248)
		(size 0.4064)
		(drill 0.2032)
		(layers "F.Cu" "B.Cu")
		(net "GND")
	)
	(via
		(at 93.450918 -255.014476)
		(size 0.4064)
		(drill 0.2032)
		(layers "F.Cu" "B.Cu")
		(net "GND")
	)
	(via
		(at 145.056098 -409.396184)
		(size 0.4572)
		(drill 0.254)
		(layers "F.Cu" "B.Cu")
		(net "GND")
	)
	(via
		(at 417.903914 -420.318184)
		(size 0.4572)
		(drill 0.254)
		(layers "F.Cu" "B.Cu")
		(net "GND")
	)
	(via
		(at 343.101168 -289.475926)
		(size 0.4064)
		(drill 0.2032)
		(layers "F.Cu" "B.Cu")
		(net "GND")
	)
	(via
		(at 167.83685 -19.89582)
		(size 0.508)
		(drill 0.254)
		(layers "F.Cu" "B.Cu")
		(net "GND")
	)
	(via
		(at 27.867864 -295.9354)
		(size 0.4826)
		(drill 0.254)
		(layers "F.Cu" "B.Cu")
		(net "GND")
	)
	(via
		(at 316.8523 -336.983578)
		(size 0.49022)
		(drill 0.254)
		(layers "F.Cu" "B.Cu")
		(net "GND")
	)
	(via
		(at 130.358896 -373.96293)
		(size 0.508)
		(drill 0.254)
		(layers "F.Cu" "B.Cu")
		(net "GND")
	)
	(via
		(at 367.641632 -378.07773)
		(size 0.508)
		(drill 0.254)
		(layers "F.Cu" "B.Cu")
		(net "GND")
	)
	(via
		(at 328.701146 -249.34418)
		(size 0.4064)
		(drill 0.2032)
		(layers "F.Cu" "B.Cu")
		(net "GND")
	)
	(via
		(at 273.928586 -347.282262)
		(size 0.49022)
		(drill 0.254)
		(layers "F.Cu" "B.Cu")
		(net "GND")
	)
	(via
		(at 338.58708 -331.729334)
		(size 0.508)
		(drill 0.254)
		(layers "F.Cu" "B.Cu")
		(net "GND")
	)
	(via
		(at 436.384446 -315.485018)
		(size 0.4826)
		(drill 0.254)
		(layers "F.Cu" "B.Cu")
		(net "GND")
	)
	(via
		(at 246.105426 -283.508958)
		(size 0.508)
		(drill 0.254)
		(layers "F.Cu" "B.Cu")
		(net "GND")
	)
	(via
		(at 180.633624 -314.210446)
		(size 0.4826)
		(drill 0.254)
		(layers "F.Cu" "B.Cu")
		(net "GND")
	)
	(via
		(at 52.194206 -36.26866)
		(size 0.508)
		(drill 0.254)
		(layers "F.Cu" "B.Cu")
		(net "GND")
	)
	(via
		(at 437.715914 -237.285022)
		(size 0.4826)
		(drill 0.254)
		(layers "F.Cu" "B.Cu")
		(net "GND")
	)
	(via
		(at 230.26878 -168.63822)
		(size 0.508)
		(drill 0.254)
		(layers "F.Cu" "B.Cu")
		(net "GND")
	)
	(via
		(at 78.711044 -288.666174)
		(size 0.4064)
		(drill 0.2032)
		(layers "F.Cu" "B.Cu")
		(net "GND")
	)
	(via
		(at 355.588062 -256.387346)
		(size 0.4826)
		(drill 0.254)
		(layers "F.Cu" "B.Cu")
		(net "GND")
	)
	(via
		(at 355.321108 -268.416024)
		(size 0.4064)
		(drill 0.2032)
		(layers "F.Cu" "B.Cu")
		(net "GND")
	)
	(via
		(at 48.714914 -343.476834)
		(size 0.508)
		(drill 0.254)
		(layers "F.Cu" "B.Cu")
		(net "GND")
	)
	(via
		(at 384.7846 -63.967106)
		(size 0.508)
		(drill 0.254)
		(layers "F.Cu" "B.Cu")
		(net "GND")
	)
	(via
		(at 128.89611 -159.114998)
		(size 0.508)
		(drill 0.254)
		(layers "F.Cu" "B.Cu")
		(net "GND")
	)
	(via
		(at 102.211124 -288.666174)
		(size 0.4064)
		(drill 0.2032)
		(layers "F.Cu" "B.Cu")
		(net "GND")
	)
	(via
		(at 188.177678 -202.010264)
		(size 0.4826)
		(drill 0.254)
		(layers "F.Cu" "B.Cu")
		(net "GND")
	)
	(via
		(at 97.902522 -151.708866)
		(size 0.508)
		(drill 0.254)
		(layers "F.Cu" "B.Cu")
		(net "GND")
	)
	(via
		(at 353.911154 -293.525956)
		(size 0.4064)
		(drill 0.2032)
		(layers "F.Cu" "B.Cu")
		(net "GND")
	)
	(via
		(at 56.712358 -210.085432)
		(size 0.4826)
		(drill 0.254)
		(layers "F.Cu" "B.Cu")
		(net "GND")
	)
	(via
		(at 406.746202 -396.710662)
		(size 0.4064)
		(drill 0.2032)
		(layers "F.Cu" "B.Cu")
		(net "GND")
	)
	(via
		(at 27.774138 -18.247106)
		(size 0.508)
		(drill 0.254)
		(layers "F.Cu" "B.Cu")
		(net "GND")
	)
	(via
		(at 344.211148 -253.39421)
		(size 0.4064)
		(drill 0.2032)
		(layers "F.Cu" "B.Cu")
		(net "GND")
	)
	(via
		(at 148.290026 -384.617722)
		(size 0.4064)
		(drill 0.2032)
		(layers "F.Cu" "B.Cu")
		(net "GND")
	)
	(via
		(at 134.164832 -278.946356)
		(size 0.4064)
		(drill 0.2032)
		(layers "F.Cu" "B.Cu")
		(net "GND")
	)
	(via
		(at 28.818078 -19.13636)
		(size 0.508)
		(drill 0.254)
		(layers "F.Cu" "B.Cu")
		(net "GND")
	)
	(via
		(at 124.294646 -276.516338)
		(size 0.4064)
		(drill 0.2032)
		(layers "F.Cu" "B.Cu")
		(net "GND")
	)
	(via
		(at 97.211134 -237.194344)
		(size 0.4064)
		(drill 0.2032)
		(layers "F.Cu" "B.Cu")
		(net "GND")
	)
	(via
		(at 130.349752 -435.0512)
		(size 0.4572)
		(drill 0.2032)
		(layers "F.Cu" "B.Cu")
		(net "GND")
	)
	(via
		(at 27.867864 -227.935282)
		(size 0.4826)
		(drill 0.254)
		(layers "F.Cu" "B.Cu")
		(net "GND")
	)
	(via
		(at 303.268126 -244.08511)
		(size 0.4826)
		(drill 0.254)
		(layers "F.Cu" "B.Cu")
		(net "GND")
	)
	(via
		(at 365.82477 -240.434114)
		(size 0.4064)
		(drill 0.2032)
		(layers "F.Cu" "B.Cu")
		(net "GND")
	)
	(via
		(at 26.292302 -386.866892)
		(size 0.49022)
		(drill 0.254)
		(layers "F.Cu" "B.Cu")
		(net "GND")
	)
	(via
		(at 378.814838 -276.516084)
		(size 0.4064)
		(drill 0.2032)
		(layers "F.Cu" "B.Cu")
		(net "GND")
	)
	(via
		(at 17.812258 -428.589948)
		(size 0.508)
		(drill 0.254)
		(layers "F.Cu" "B.Cu")
		(net "GND")
	)
	(via
		(at 5.42163 -98.49104)
		(size 0.508)
		(drill 0.254)
		(layers "F.Cu" "B.Cu")
		(net "GND")
	)
	(via
		(at 351.506028 -394.831062)
		(size 0.4064)
		(drill 0.2032)
		(layers "F.Cu" "B.Cu")
		(net "GND")
	)
	(via
		(at 443.9285 -294.235124)
		(size 0.4826)
		(drill 0.254)
		(layers "F.Cu" "B.Cu")
		(net "GND")
	)
	(via
		(at 164.244274 -393.927838)
		(size 0.4572)
		(drill 0.254)
		(layers "F.Cu" "B.Cu")
		(net "GND")
	)
	(via
		(at 255.927098 -214.441024)
		(size 0.508)
		(drill 0.254)
		(layers "F.Cu" "B.Cu")
		(net "GND")
	)
	(via
		(at 273.092164 -311.23509)
		(size 0.4826)
		(drill 0.254)
		(layers "F.Cu" "B.Cu")
		(net "GND")
	)
	(via
		(at 431.93208 -436.086758)
		(size 0.508)
		(drill 0.254)
		(layers "F.Cu" "B.Cu")
		(net "GND")
	)
	(via
		(at 350.151192 -283.806138)
		(size 0.4064)
		(drill 0.2032)
		(layers "F.Cu" "B.Cu")
		(net "GND")
	)
	(via
		(at 40.23995 -249.18543)
		(size 0.4826)
		(drill 0.254)
		(layers "F.Cu" "B.Cu")
		(net "GND")
	)
	(via
		(at 126.644654 -288.666174)
		(size 0.4064)
		(drill 0.2032)
		(layers "F.Cu" "B.Cu")
		(net "GND")
	)
	(via
		(at 329.569064 -332.404212)
		(size 0.508)
		(drill 0.254)
		(layers "F.Cu" "B.Cu")
		(net "GND")
	)
	(via
		(at 393.084812 -232.334054)
		(size 0.4064)
		(drill 0.2032)
		(layers "F.Cu" "B.Cu")
		(net "GND")
	)
	(via
		(at 202.147932 -247.485408)
		(size 0.4826)
		(drill 0.254)
		(layers "F.Cu" "B.Cu")
		(net "GND")
	)
	(via
		(at 33.5661 -352.23196)
		(size 0.508)
		(drill 0.254)
		(layers "F.Cu" "B.Cu")
		(net "GND")
	)
	(via
		(at 371.764814 -270.846042)
		(size 0.4064)
		(drill 0.2032)
		(layers "F.Cu" "B.Cu")
		(net "GND")
	)
	(via
		(at 376.478546 -394.831062)
		(size 0.4064)
		(drill 0.2032)
		(layers "F.Cu" "B.Cu")
		(net "GND")
	)
	(via
		(at 299.06341 -345.566238)
		(size 0.49022)
		(drill 0.254)
		(layers "F.Cu" "B.Cu")
		(net "GND")
	)
	(via
		(at 211.992464 -23.958296)
		(size 0.508)
		(drill 0.254)
		(layers "F.Cu" "B.Cu")
		(net "GND")
	)
	(via
		(at 419.912038 -289.135058)
		(size 0.4826)
		(drill 0.254)
		(layers "F.Cu" "B.Cu")
		(net "GND")
	)
	(via
		(at 115.534694 -250.964446)
		(size 0.4064)
		(drill 0.2032)
		(layers "F.Cu" "B.Cu")
		(net "GND")
	)
	(via
		(at 154.518614 -405.098504)
		(size 0.4572)
		(drill 0.254)
		(layers "F.Cu" "B.Cu")
		(net "GND")
	)
	(via
		(at 421.029638 -211.360004)
		(size 0.4826)
		(drill 0.254)
		(layers "F.Cu" "B.Cu")
		(net "GND")
	)
	(via
		(at 96.27108 -248.534428)
		(size 0.4064)
		(drill 0.2032)
		(layers "F.Cu" "B.Cu")
		(net "GND")
	)
	(via
		(at 151.944832 -98.355658)
		(size 0.508)
		(drill 0.254)
		(layers "F.Cu" "B.Cu")
		(net "GND")
	)
	(via
		(at 134.334758 -413.204152)
		(size 0.4572)
		(drill 0.254)
		(layers "F.Cu" "B.Cu")
		(net "GND")
	)
	(via
		(at 403.280118 -172.498512)
		(size 0.508)
		(drill 0.254)
		(layers "F.Cu" "B.Cu")
		(net "GND")
	)
	(via
		(at 413.752284 -303.585118)
		(size 0.4826)
		(drill 0.254)
		(layers "F.Cu" "B.Cu")
		(net "GND")
	)
	(via
		(at 255.846072 -421.46093)
		(size 0.508)
		(drill 0.254)
		(layers "F.Cu" "B.Cu")
		(net "GND")
	)
	(via
		(at 374.16867 -182.177944)
		(size 0.49022)
		(drill 0.254)
		(layers "F.Cu" "B.Cu")
		(net "GND")
	)
	(via
		(at 44.340018 -278.935434)
		(size 0.4826)
		(drill 0.254)
		(layers "F.Cu" "B.Cu")
		(net "GND")
	)
	(via
		(at 84.249768 -431.451258)
		(size 0.4572)
		(drill 0.2032)
		(layers "F.Cu" "B.Cu")
		(net "GND")
	)
	(via
		(at 456.620626 -47.39894)
		(size 0.508)
		(drill 0.254)
		(layers "F.Cu" "B.Cu")
		(net "GND")
	)
	(via
		(at 442.5442 -252.584966)
		(size 0.4826)
		(drill 0.254)
		(layers "F.Cu" "B.Cu")
		(net "GND")
	)
	(via
		(at 40.23995 -307.8353)
		(size 0.4826)
		(drill 0.254)
		(layers "F.Cu" "B.Cu")
		(net "GND")
	)
	(via
		(at 329.941174 -268.416024)
		(size 0.4064)
		(drill 0.2032)
		(layers "F.Cu" "B.Cu")
		(net "GND")
	)
	(via
		(at 2.76225 -93.401134)
		(size 0.508)
		(drill 0.254)
		(layers "F.Cu" "B.Cu")
		(net "GND")
	)
	(via
		(at 109.363256 -14.312392)
		(size 0.508)
		(drill 0.254)
		(layers "F.Cu" "B.Cu")
		(net "GND")
	)
	(via
		(at 409.006294 -394.831062)
		(size 0.4064)
		(drill 0.2032)
		(layers "F.Cu" "B.Cu")
		(net "GND")
	)
	(via
		(at 21.70811 -318.035432)
		(size 0.4826)
		(drill 0.254)
		(layers "F.Cu" "B.Cu")
		(net "GND")
	)
	(via
		(at 319.249552 -437.49976)
		(size 0.4572)
		(drill 0.2032)
		(layers "F.Cu" "B.Cu")
		(net "GND")
	)
	(via
		(at 416.70224 -382.34493)
		(size 0.508)
		(drill 0.254)
		(layers "F.Cu" "B.Cu")
		(net "GND")
	)
	(via
		(at 9.352788 -369.84305)
		(size 0.508)
		(drill 0.254)
		(layers "F.Cu" "B.Cu")
		(net "GND")
	)
	(via
		(at 34.080196 -221.985332)
		(size 0.4826)
		(drill 0.254)
		(layers "F.Cu" "B.Cu")
		(net "GND")
	)
	(via
		(at 76.249784 -430.299622)
		(size 0.4572)
		(drill 0.2032)
		(layers "F.Cu" "B.Cu")
		(net "GND")
	)
	(via
		(at 43.224958 -345.571064)
		(size 0.49022)
		(drill 0.254)
		(layers "F.Cu" "B.Cu")
		(net "GND")
	)
	(via
		(at 265.54811 -252.584966)
		(size 0.4826)
		(drill 0.254)
		(layers "F.Cu" "B.Cu")
		(net "GND")
	)
	(via
		(at 405.139144 -141.087602)
		(size 0.508)
		(drill 0.254)
		(layers "F.Cu" "B.Cu")
		(net "GND")
	)
	(via
		(at 353.61118 -229.094284)
		(size 0.4064)
		(drill 0.2032)
		(layers "F.Cu" "B.Cu")
		(net "GND")
	)
	(via
		(at 368.004852 -270.846042)
		(size 0.4064)
		(drill 0.2032)
		(layers "F.Cu" "B.Cu")
		(net "GND")
	)
	(via
		(at 344.74404 -400.212814)
		(size 0.4064)
		(drill 0.2032)
		(layers "F.Cu" "B.Cu")
		(net "GND")
	)
	(via
		(at 187.111894 -117.442742)
		(size 0.4572)
		(drill 0.254)
		(layers "F.Cu" "B.Cu")
		(net "GND")
	)
	(via
		(at 361.424728 -282.186126)
		(size 0.4064)
		(drill 0.2032)
		(layers "F.Cu" "B.Cu")
		(net "GND")
	)
	(via
		(at 416.468052 -243.234972)
		(size 0.4826)
		(drill 0.254)
		(layers "F.Cu" "B.Cu")
		(net "GND")
	)
	(via
		(at 277.37562 -435.823614)
		(size 0.508)
		(drill 0.254)
		(layers "F.Cu" "B.Cu")
		(net "GND")
	)
	(via
		(at 199.202294 -376.440446)
		(size 0.508)
		(drill 0.254)
		(layers "F.Cu" "B.Cu")
		(net "GND")
	)
	(via
		(at 180.900324 -315.485272)
		(size 0.4826)
		(drill 0.254)
		(layers "F.Cu" "B.Cu")
		(net "GND")
	)
	(via
		(at 328.53122 -278.946102)
		(size 0.4064)
		(drill 0.2032)
		(layers "F.Cu" "B.Cu")
		(net "GND")
	)
	(via
		(at 315.816488 -402.309838)
		(size 0.4572)
		(drill 0.254)
		(layers "F.Cu" "B.Cu")
		(net "GND")
	)
	(via
		(at 95.1611 -276.516338)
		(size 0.4064)
		(drill 0.2032)
		(layers "F.Cu" "B.Cu")
		(net "GND")
	)
	(via
		(at 361.594908 -233.14406)
		(size 0.4064)
		(drill 0.2032)
		(layers "F.Cu" "B.Cu")
		(net "GND")
	)
	(via
		(at 378.344938 -261.12597)
		(size 0.4064)
		(drill 0.2032)
		(layers "F.Cu" "B.Cu")
		(net "GND")
	)
	(via
		(at 47.784004 -318.885316)
		(size 0.4826)
		(drill 0.254)
		(layers "F.Cu" "B.Cu")
		(net "GND")
	)
	(via
		(at 112.85855 -178.422046)
		(size 0.508)
		(drill 0.254)
		(layers "F.Cu" "B.Cu")
		(net "GND")
	)
	(via
		(at 325.678546 -12.542266)
		(size 0.508)
		(drill 0.254)
		(layers "F.Cu" "B.Cu")
		(net "GND")
	)
	(via
		(at 85.887052 -407.638504)
		(size 0.4572)
		(drill 0.254)
		(layers "F.Cu" "B.Cu")
		(net "GND")
	)
	(via
		(at 108.597954 -261.323074)
		(size 0.4826)
		(drill 0.254)
		(layers "F.Cu" "B.Cu")
		(net "GND")
	)
	(via
		(at 378.814838 -261.935976)
		(size 0.4064)
		(drill 0.2032)
		(layers "F.Cu" "B.Cu")
		(net "GND")
	)
	(via
		(at 109.900974 -244.484398)
		(size 0.4064)
		(drill 0.2032)
		(layers "F.Cu" "B.Cu")
		(net "GND")
	)
	(via
		(at 387.575552 -379.22073)
		(size 0.508)
		(drill 0.254)
		(layers "F.Cu" "B.Cu")
		(net "GND")
	)
	(via
		(at 377.867418 -184.692798)
		(size 0.508)
		(drill 0.254)
		(layers "F.Cu" "B.Cu")
		(net "GND")
	)
	(via
		(at 245.745 -340.421214)
		(size 0.508)
		(drill 0.254)
		(layers "F.Cu" "B.Cu")
		(net "GND")
	)
	(via
		(at 358.141016 -287.856168)
		(size 0.4064)
		(drill 0.2032)
		(layers "F.Cu" "B.Cu")
		(net "GND")
	)
	(via
		(at 56.868314 -9.424924)
		(size 0.508)
		(drill 0.254)
		(layers "F.Cu" "B.Cu")
		(net "GND")
	)
	(via
		(at 299.82414 -215.18499)
		(size 0.4826)
		(drill 0.254)
		(layers "F.Cu" "B.Cu")
		(net "GND")
	)
	(via
		(at 210.90636 -57.948322)
		(size 0.508)
		(drill 0.254)
		(layers "F.Cu" "B.Cu")
		(net "GND")
	)
	(via
		(at 124.607066 -166.342568)
		(size 0.49022)
		(drill 0.254)
		(layers "F.Cu" "B.Cu")
		(net "GND")
	)
	(via
		(at 90.249756 -431.29962)
		(size 0.4572)
		(drill 0.2032)
		(layers "F.Cu" "B.Cu")
		(net "GND")
	)
	(via
		(at 338.401152 -292.71595)
		(size 0.4064)
		(drill 0.2032)
		(layers "F.Cu" "B.Cu")
		(net "GND")
	)
	(via
		(at 347.801184 -261.935976)
		(size 0.4064)
		(drill 0.2032)
		(layers "F.Cu" "B.Cu")
		(net "GND")
	)
	(via
		(at 135.274812 -225.044508)
		(size 0.4064)
		(drill 0.2032)
		(layers "F.Cu" "B.Cu")
		(net "GND")
	)
	(via
		(at 168.527984 -207.535272)
		(size 0.4826)
		(drill 0.254)
		(layers "F.Cu" "B.Cu")
		(net "GND")
	)
	(via
		(at 307.39461 -344.77706)
		(size 0.49022)
		(drill 0.254)
		(layers "F.Cu" "B.Cu")
		(net "GND")
	)
	(via
		(at 7.262368 -422.138094)
		(size 0.508)
		(drill 0.254)
		(layers "F.Cu" "B.Cu")
		(net "GND")
	)
	(via
		(at 40.23995 -247.485408)
		(size 0.4826)
		(drill 0.254)
		(layers "F.Cu" "B.Cu")
		(net "GND")
	)
	(via
		(at 344.677238 -413.480504)
		(size 0.4572)
		(drill 0.254)
		(layers "F.Cu" "B.Cu")
		(net "GND")
	)
	(via
		(at 352.718878 -398.542002)
		(size 0.4064)
		(drill 0.2032)
		(layers "F.Cu" "B.Cu")
		(net "GND")
	)
	(via
		(at 380.394718 -249.34418)
		(size 0.4064)
		(drill 0.2032)
		(layers "F.Cu" "B.Cu")
		(net "GND")
	)
	(via
		(at 292.280086 -297.635168)
		(size 0.4826)
		(drill 0.254)
		(layers "F.Cu" "B.Cu")
		(net "GND")
	)
	(via
		(at 92.981018 -238.00435)
		(size 0.4064)
		(drill 0.2032)
		(layers "F.Cu" "B.Cu")
		(net "GND")
	)
	(via
		(at 431.55616 -196.485002)
		(size 0.4826)
		(drill 0.254)
		(layers "F.Cu" "B.Cu")
		(net "GND")
	)
	(via
		(at 19.400012 -357.281988)
		(size 0.508)
		(drill 0.254)
		(layers "F.Cu" "B.Cu")
		(net "GND")
	)
	(via
		(at 143.349726 -433.899564)
		(size 0.4572)
		(drill 0.2032)
		(layers "F.Cu" "B.Cu")
		(net "GND")
	)
	(via
		(at 428.840392 -315.485018)
		(size 0.4826)
		(drill 0.254)
		(layers "F.Cu" "B.Cu")
		(net "GND")
	)
	(via
		(at 78.24978 -437.34736)
		(size 0.4572)
		(drill 0.2032)
		(layers "F.Cu" "B.Cu")
		(net "GND")
	)
	(via
		(at 383.21488 -226.664266)
		(size 0.4064)
		(drill 0.2032)
		(layers "F.Cu" "B.Cu")
		(net "GND")
	)
	(via
		(at 87.171022 -267.606272)
		(size 0.4064)
		(drill 0.2032)
		(layers "F.Cu" "B.Cu")
		(net "GND")
	)
	(via
		(at 402.214842 -402.734018)
		(size 0.508)
		(drill 0.254)
		(layers "F.Cu" "B.Cu")
		(net "GND")
	)
	(via
		(at 51.884072 -246.63527)
		(size 0.4826)
		(drill 0.254)
		(layers "F.Cu" "B.Cu")
		(net "GND")
	)
	(via
		(at 143.56461 -262.746236)
		(size 0.4064)
		(drill 0.2032)
		(layers "F.Cu" "B.Cu")
		(net "GND")
	)
	(via
		(at 388.21487 -289.475926)
		(size 0.4064)
		(drill 0.2032)
		(layers "F.Cu" "B.Cu")
		(net "GND")
	)
	(via
		(at 140.744702 -275.706332)
		(size 0.4064)
		(drill 0.2032)
		(layers "F.Cu" "B.Cu")
		(net "GND")
	)
	(via
		(at 143.56461 -295.146222)
		(size 0.4064)
		(drill 0.2032)
		(layers "F.Cu" "B.Cu")
		(net "GND")
	)
	(via
		(at 306.73421 -344.77706)
		(size 0.49022)
		(drill 0.254)
		(layers "F.Cu" "B.Cu")
		(net "GND")
	)
	(via
		(at 55.778654 -386.449062)
		(size 0.4064)
		(drill 0.2032)
		(layers "F.Cu" "B.Cu")
		(net "GND")
	)
	(via
		(at 355.961188 -229.904036)
		(size 0.4064)
		(drill 0.2032)
		(layers "F.Cu" "B.Cu")
		(net "GND")
	)
	(via
		(at 400.48942 -4.963414)
		(size 0.508)
		(drill 0.254)
		(layers "F.Cu" "B.Cu")
		(net "GND")
	)
	(via
		(at 288.180018 -227.085144)
		(size 0.4826)
		(drill 0.254)
		(layers "F.Cu" "B.Cu")
		(net "GND")
	)
	(via
		(at 380.303278 -144.266158)
		(size 0.508)
		(drill 0.254)
		(layers "F.Cu" "B.Cu")
		(net "GND")
	)
	(via
		(at 125.788928 -48.137064)
		(size 0.508)
		(drill 0.254)
		(layers "F.Cu" "B.Cu")
		(net "GND")
	)
	(via
		(at 81.293462 -21.794724)
		(size 0.508)
		(drill 0.254)
		(layers "F.Cu" "B.Cu")
		(net "GND")
	)
	(via
		(at 155.688538 -318.02705)
		(size 0.508)
		(drill 0.254)
		(layers "F.Cu" "B.Cu")
		(net "GND")
	)
	(via
		(at 265.54811 -307.835046)
		(size 0.4826)
		(drill 0.254)
		(layers "F.Cu" "B.Cu")
		(net "GND")
	)
	(via
		(at 59.428126 -288.285428)
		(size 0.4826)
		(drill 0.254)
		(layers "F.Cu" "B.Cu")
		(net "GND")
	)
	(via
		(at 406.97404 -379.88113)
		(size 0.508)
		(drill 0.254)
		(layers "F.Cu" "B.Cu")
		(net "GND")
	)
	(via
		(at 104.9274 -410.9466)
		(size 0.508)
		(drill 0.254)
		(layers "F.Cu" "B.Cu")
		(net "GND")
	)
	(via
		(at 429.80483 -6.598158)
		(size 0.508)
		(drill 0.254)
		(layers "F.Cu" "B.Cu")
		(net "GND")
	)
	(via
		(at 147.572984 -374.62333)
		(size 0.508)
		(drill 0.254)
		(layers "F.Cu" "B.Cu")
		(net "GND")
	)
	(via
		(at 451.151752 -392.905234)
		(size 0.508)
		(drill 0.254)
		(layers "F.Cu" "B.Cu")
		(net "GND")
	)
	(via
		(at 122.584718 -251.774452)
		(size 0.4064)
		(drill 0.2032)
		(layers "F.Cu" "B.Cu")
		(net "GND")
	)
	(via
		(at 32.580072 -398.460976)
		(size 0.508)
		(drill 0.254)
		(layers "F.Cu" "B.Cu")
		(net "GND")
	)
	(via
		(at 372.704868 -290.285932)
		(size 0.4064)
		(drill 0.2032)
		(layers "F.Cu" "B.Cu")
		(net "GND")
	)
	(via
		(at 335.11109 -267.606018)
		(size 0.4064)
		(drill 0.2032)
		(layers "F.Cu" "B.Cu")
		(net "GND")
	)
	(via
		(at 276.896322 -417.48075)
		(size 0.508)
		(drill 0.254)
		(layers "F.Cu" "B.Cu")
		(net "GND")
	)
	(via
		(at 141.476222 -156.567124)
		(size 0.508)
		(drill 0.254)
		(layers "F.Cu" "B.Cu")
		(net "GND")
	)
	(via
		(at 240.858548 -370.033804)
		(size 0.508)
		(drill 0.254)
		(layers "F.Cu" "B.Cu")
		(net "GND")
	)
	(via
		(at 394.68298 -235.03001)
		(size 0.4064)
		(drill 0.2032)
		(layers "F.Cu" "B.Cu")
		(net "GND")
	)
	(via
		(at 370.69649 -413.480504)
		(size 0.4572)
		(drill 0.254)
		(layers "F.Cu" "B.Cu")
		(net "GND")
	)
	(via
		(at 351.301304 -383.00533)
		(size 0.508)
		(drill 0.254)
		(layers "F.Cu" "B.Cu")
		(net "GND")
	)
	(via
		(at 165.090094 -384.617722)
		(size 0.4064)
		(drill 0.2032)
		(layers "F.Cu" "B.Cu")
		(net "GND")
	)
	(via
		(at 82.374486 -356.056946)
		(size 0.508)
		(drill 0.254)
		(layers "F.Cu" "B.Cu")
		(net "GND")
	)
	(via
		(at 347.654626 -418.412168)
		(size 0.4064)
		(drill 0.2032)
		(layers "F.Cu" "B.Cu")
		(net "GND")
	)
	(via
		(at 13.410184 -387.723126)
		(size 0.508)
		(drill 0.254)
		(layers "F.Cu" "B.Cu")
		(net "GND")
	)
	(via
		(at 202.147932 -234.73537)
		(size 0.4826)
		(drill 0.254)
		(layers "F.Cu" "B.Cu")
		(net "GND")
	)
	(via
		(at 275.44141 -345.566238)
		(size 0.49022)
		(drill 0.254)
		(layers "F.Cu" "B.Cu")
		(net "GND")
	)
	(via
		(at 186.876436 -28.444952)
		(size 0.508)
		(drill 0.254)
		(layers "F.Cu" "B.Cu")
		(net "GND")
	)
	(via
		(at 408.98699 -416.020504)
		(size 0.4572)
		(drill 0.254)
		(layers "F.Cu" "B.Cu")
		(net "GND")
	)
	(via
		(at 297.108372 -228.785166)
		(size 0.4826)
		(drill 0.254)
		(layers "F.Cu" "B.Cu")
		(net "GND")
	)
	(via
		(at 55.328058 -245.785386)
		(size 0.4826)
		(drill 0.254)
		(layers "F.Cu" "B.Cu")
		(net "GND")
	)
	(via
		(at 166.11727 -393.445746)
		(size 0.508)
		(drill 0.254)
		(layers "F.Cu" "B.Cu")
		(net "GND")
	)
	(via
		(at 443.9285 -296.78503)
		(size 0.4826)
		(drill 0.254)
		(layers "F.Cu" "B.Cu")
		(net "GND")
	)
	(via
		(at 352.671126 -248.534174)
		(size 0.4064)
		(drill 0.2032)
		(layers "F.Cu" "B.Cu")
		(net "GND")
	)
	(via
		(at 83.41106 -291.906198)
		(size 0.4064)
		(drill 0.2032)
		(layers "F.Cu" "B.Cu")
		(net "GND")
	)
	(via
		(at 123.824746 -285.426404)
		(size 0.4064)
		(drill 0.2032)
		(layers "F.Cu" "B.Cu")
		(net "GND")
	)
	(via
		(at 32.695896 -206.685388)
		(size 0.4826)
		(drill 0.254)
		(layers "F.Cu" "B.Cu")
		(net "GND")
	)
	(via
		(at 352.031046 -270.846042)
		(size 0.4064)
		(drill 0.2032)
		(layers "F.Cu" "B.Cu")
		(net "GND")
	)
	(via
		(at 381.334772 -244.484144)
		(size 0.4064)
		(drill 0.2032)
		(layers "F.Cu" "B.Cu")
		(net "GND")
	)
	(via
		(at 100.946204 -28.65501)
		(size 0.508)
		(drill 0.254)
		(layers "F.Cu" "B.Cu")
		(net "GND")
	)
	(via
		(at 20.32381 -218.585288)
		(size 0.4826)
		(drill 0.254)
		(layers "F.Cu" "B.Cu")
		(net "GND")
	)
	(via
		(at 203.532232 -240.68532)
		(size 0.4826)
		(drill 0.254)
		(layers "F.Cu" "B.Cu")
		(net "GND")
	)
	(via
		(at 459.550516 -409.89885)
		(size 0.508)
		(drill 0.254)
		(layers "F.Cu" "B.Cu")
		(net "GND")
	)
	(via
		(at 194.604132 -216.035382)
		(size 0.4826)
		(drill 0.254)
		(layers "F.Cu" "B.Cu")
		(net "GND")
	)
	(via
		(at 295.724072 -318.885062)
		(size 0.4826)
		(drill 0.254)
		(layers "F.Cu" "B.Cu")
		(net "GND")
	)
	(via
		(at 83.88096 -284.616398)
		(size 0.4064)
		(drill 0.2032)
		(layers "F.Cu" "B.Cu")
		(net "GND")
	)
	(via
		(at 405.34971 -426.54728)
		(size 0.4572)
		(drill 0.2032)
		(layers "F.Cu" "B.Cu")
		(net "GND")
	)
	(via
		(at 349.211138 -261.12597)
		(size 0.4064)
		(drill 0.2032)
		(layers "F.Cu" "B.Cu")
		(net "GND")
	)
	(via
		(at 413.752284 -210.085178)
		(size 0.4826)
		(drill 0.254)
		(layers "F.Cu" "B.Cu")
		(net "GND")
	)
	(via
		(at 104.140508 -349.273622)
		(size 0.508)
		(drill 0.254)
		(layers "F.Cu" "B.Cu")
		(net "GND")
	)
	(via
		(at 382.349502 -435.0512)
		(size 0.4572)
		(drill 0.2032)
		(layers "F.Cu" "B.Cu")
		(net "GND")
	)
	(via
		(at 303.378362 -394.831062)
		(size 0.4064)
		(drill 0.2032)
		(layers "F.Cu" "B.Cu")
		(net "GND")
	)
	(via
		(at 81.183734 -328.10196)
		(size 0.508)
		(drill 0.254)
		(layers "F.Cu" "B.Cu")
		(net "GND")
	)
	(via
		(at 84.249768 -437.49976)
		(size 0.4572)
		(drill 0.2032)
		(layers "F.Cu" "B.Cu")
		(net "GND")
	)
	(via
		(at 338.744052 -391.23493)
		(size 0.4064)
		(drill 0.2032)
		(layers "F.Cu" "B.Cu")
		(net "GND")
	)
	(via
		(at 80.291178 -238.814356)
		(size 0.4064)
		(drill 0.2032)
		(layers "F.Cu" "B.Cu")
		(net "GND")
	)
	(via
		(at 395.421104 -16.979138)
		(size 0.508)
		(drill 0.254)
		(layers "F.Cu" "B.Cu")
		(net "GND")
	)
	(via
		(at 445.010032 -6.387084)
		(size 0.508)
		(drill 0.254)
		(layers "F.Cu" "B.Cu")
		(net "GND")
	)
	(via
		(at 426.089064 -152.388824)
		(size 0.508)
		(drill 0.254)
		(layers "F.Cu" "B.Cu")
		(net "GND")
	)
	(via
		(at 165.545516 -276.81047)
		(size 0.4826)
		(drill 0.254)
		(layers "F.Cu" "B.Cu")
		(net "GND")
	)
	(via
		(at 321.21348 -332.411324)
		(size 0.508)
		(drill 0.254)
		(layers "F.Cu" "B.Cu")
		(net "GND")
	)
	(via
		(at 334.228694 -413.480504)
		(size 0.4572)
		(drill 0.254)
		(layers "F.Cu" "B.Cu")
		(net "GND")
	)
	(via
		(at 396.686024 -18.247106)
		(size 0.508)
		(drill 0.254)
		(layers "F.Cu" "B.Cu")
		(net "GND")
	)
	(via
		(at 379.066552 -383.00533)
		(size 0.508)
		(drill 0.254)
		(layers "F.Cu" "B.Cu")
		(net "GND")
	)
	(via
		(at 443.6618 -304.860198)
		(size 0.4826)
		(drill 0.254)
		(layers "F.Cu" "B.Cu")
		(net "GND")
	)
	(via
		(at 78.19771 -154.83078)
		(size 0.508)
		(drill 0.254)
		(layers "F.Cu" "B.Cu")
		(net "GND")
	)
	(via
		(at 194.604132 -233.035348)
		(size 0.4826)
		(drill 0.254)
		(layers "F.Cu" "B.Cu")
		(net "GND")
	)
	(via
		(at 160.283906 -412.570168)
		(size 0.4064)
		(drill 0.2032)
		(layers "F.Cu" "B.Cu")
		(net "GND")
	)
	(via
		(at 148.119338 -407.638504)
		(size 0.4572)
		(drill 0.254)
		(layers "F.Cu" "B.Cu")
		(net "GND")
	)
	(via
		(at 355.961188 -247.724168)
		(size 0.4064)
		(drill 0.2032)
		(layers "F.Cu" "B.Cu")
		(net "GND")
	)
	(via
		(at 378.344938 -272.466054)
		(size 0.4064)
		(drill 0.2032)
		(layers "F.Cu" "B.Cu")
		(net "GND")
	)
	(via
		(at 295.724072 -225.385122)
		(size 0.4826)
		(drill 0.254)
		(layers "F.Cu" "B.Cu")
		(net "GND")
	)
	(via
		(at 303.268126 -250.884944)
		(size 0.4826)
		(drill 0.254)
		(layers "F.Cu" "B.Cu")
		(net "GND")
	)
	(via
		(at 319.040256 -25.6794)
		(size 0.508)
		(drill 0.254)
		(layers "F.Cu" "B.Cu")
		(net "GND")
	)
	(via
		(at 344.74404 -391.23493)
		(size 0.4064)
		(drill 0.2032)
		(layers "F.Cu" "B.Cu")
		(net "GND")
	)
	(via
		(at 100.971096 -232.334308)
		(size 0.4064)
		(drill 0.2032)
		(layers "F.Cu" "B.Cu")
		(net "GND")
	)
	(via
		(at 102.681024 -281.376374)
		(size 0.4064)
		(drill 0.2032)
		(layers "F.Cu" "B.Cu")
		(net "GND")
	)
	(via
		(at 280.635964 -197.33514)
		(size 0.4826)
		(drill 0.254)
		(layers "F.Cu" "B.Cu")
		(net "GND")
	)
	(via
		(at 280.387552 -352.227134)
		(size 0.508)
		(drill 0.254)
		(layers "F.Cu" "B.Cu")
		(net "GND")
	)
	(via
		(at 353.165918 -172.07992)
		(size 0.508)
		(drill 0.254)
		(layers "F.Cu" "B.Cu")
		(net "GND")
	)
	(via
		(at 343.101168 -274.896072)
		(size 0.4064)
		(drill 0.2032)
		(layers "F.Cu" "B.Cu")
		(net "GND")
	)
	(via
		(at 82.001106 -286.23641)
		(size 0.4064)
		(drill 0.2032)
		(layers "F.Cu" "B.Cu")
		(net "GND")
	)
	(via
		(at 129.164842 -250.15444)
		(size 0.4064)
		(drill 0.2032)
		(layers "F.Cu" "B.Cu")
		(net "GND")
	)
	(via
		(at 397.718788 -385.38912)
		(size 0.508)
		(drill 0.254)
		(layers "F.Cu" "B.Cu")
		(net "GND")
	)
	(via
		(at 379.924818 -233.954066)
		(size 0.4064)
		(drill 0.2032)
		(layers "F.Cu" "B.Cu")
		(net "GND")
	)
	(via
		(at 341.691214 -288.66592)
		(size 0.4064)
		(drill 0.2032)
		(layers "F.Cu" "B.Cu")
		(net "GND")
	)
	(via
		(at 326.651112 -267.606018)
		(size 0.4064)
		(drill 0.2032)
		(layers "F.Cu" "B.Cu")
		(net "GND")
	)
	(via
		(at 415.083752 -209.23504)
		(size 0.4826)
		(drill 0.254)
		(layers "F.Cu" "B.Cu")
		(net "GND")
	)
	(via
		(at 414.510474 -165.70706)
		(size 0.49022)
		(drill 0.254)
		(layers "F.Cu" "B.Cu")
		(net "GND")
	)
	(via
		(at 315.576458 -414.752536)
		(size 0.4572)
		(drill 0.254)
		(layers "F.Cu" "B.Cu")
		(net "GND")
	)
	(via
		(at 196.398134 -75.250548)
		(size 0.508)
		(drill 0.254)
		(layers "F.Cu" "B.Cu")
		(net "GND")
	)
	(via
		(at 301.161704 -431.101246)
		(size 0.508)
		(drill 0.254)
		(layers "F.Cu" "B.Cu")
		(net "GND")
	)
	(via
		(at 159.113474 -410.664152)
		(size 0.4572)
		(drill 0.254)
		(layers "F.Cu" "B.Cu")
		(net "GND")
	)
	(via
		(at 55.065676 -10.16508)
		(size 0.508)
		(drill 0.254)
		(layers "F.Cu" "B.Cu")
		(net "GND")
	)
	(via
		(at 436.433214 -165.63467)
		(size 0.508)
		(drill 0.254)
		(layers "F.Cu" "B.Cu")
		(net "GND")
	)
	(via
		(at 345.90482 -328.119486)
		(size 0.508)
		(drill 0.254)
		(layers "F.Cu" "B.Cu")
		(net "GND")
	)
	(via
		(at 177.664618 -346.33154)
		(size 0.508)
		(drill 0.254)
		(layers "F.Cu" "B.Cu")
		(net "GND")
	)
	(via
		(at 331.744066 -340.48446)
		(size 0.508)
		(drill 0.254)
		(layers "F.Cu" "B.Cu")
		(net "GND")
	)
	(via
		(at 411.196536 -135.480552)
		(size 0.508)
		(drill 0.254)
		(layers "F.Cu" "B.Cu")
		(net "GND")
	)
	(via
		(at 460.420466 -410.6037)
		(size 0.508)
		(drill 0.254)
		(layers "F.Cu" "B.Cu")
		(net "GND")
	)
	(via
		(at 348.271084 -277.32609)
		(size 0.4064)
		(drill 0.2032)
		(layers "F.Cu" "B.Cu")
		(net "GND")
	)
	(via
		(at 118.65483 -286.23641)
		(size 0.4064)
		(drill 0.2032)
		(layers "F.Cu" "B.Cu")
		(net "GND")
	)
	(via
		(at 88.982042 -372.15953)
		(size 0.508)
		(drill 0.254)
		(layers "F.Cu" "B.Cu")
		(net "GND")
	)
	(via
		(at 173.08957 -211.360258)
		(size 0.4826)
		(drill 0.254)
		(layers "F.Cu" "B.Cu")
		(net "GND")
	)
	(via
		(at 78.711044 -291.906198)
		(size 0.4064)
		(drill 0.2032)
		(layers "F.Cu" "B.Cu")
		(net "GND")
	)
	(via
		(at 159.444182 -391.830814)
		(size 0.4064)
		(drill 0.2032)
		(layers "F.Cu" "B.Cu")
		(net "GND")
	)
	(via
		(at 304.931572 -25.62225)
		(size 0.508)
		(drill 0.254)
		(layers "F.Cu" "B.Cu")
		(net "GND")
	)
	(via
		(at 324.75297 -254.470154)
		(size 0.4064)
		(drill 0.2032)
		(layers "F.Cu" "B.Cu")
		(net "GND")
	)
	(via
		(at 386.504942 -224.234248)
		(size 0.4064)
		(drill 0.2032)
		(layers "F.Cu" "B.Cu")
		(net "GND")
	)
	(via
		(at 149.9362 -48.42764)
		(size 0.508)
		(drill 0.254)
		(layers "F.Cu" "B.Cu")
		(net "GND")
	)
	(via
		(at 268.263878 -277.235158)
		(size 0.4826)
		(drill 0.254)
		(layers "F.Cu" "B.Cu")
		(net "GND")
	)
	(via
		(at 442.894974 -413.1945)
		(size 0.508)
		(drill 0.254)
		(layers "F.Cu" "B.Cu")
		(net "GND")
	)
	(via
		(at 151.806148 -386.449062)
		(size 0.4064)
		(drill 0.2032)
		(layers "F.Cu" "B.Cu")
		(net "GND")
	)
	(via
		(at 291.038026 -342.456516)
		(size 0.6604)
		(drill 0.3302)
		(layers "F.Cu" "B.Cu")
		(net "GND")
	)
	(via
		(at 130.40487 -264.366248)
		(size 0.4064)
		(drill 0.2032)
		(layers "F.Cu" "B.Cu")
		(net "GND")
	)
	(via
		(at 325.24954 -434.899562)
		(size 0.4572)
		(drill 0.2032)
		(layers "F.Cu" "B.Cu")
		(net "GND")
	)
	(via
		(at 340.214966 -334.15478)
		(size 0.508)
		(drill 0.254)
		(layers "F.Cu" "B.Cu")
		(net "GND")
	)
	(via
		(at 93.54439 -393.927838)
		(size 0.4572)
		(drill 0.254)
		(layers "F.Cu" "B.Cu")
		(net "GND")
	)
	(via
		(at 40.23995 -272.135346)
		(size 0.4826)
		(drill 0.254)
		(layers "F.Cu" "B.Cu")
		(net "GND")
	)
	(via
		(at 394.982954 -268.150086)
		(size 0.4064)
		(drill 0.2032)
		(layers "F.Cu" "B.Cu")
		(net "GND")
	)
	(via
		(at 341.613998 -420.318184)
		(size 0.4572)
		(drill 0.254)
		(layers "F.Cu" "B.Cu")
		(net "GND")
	)
	(via
		(at 91.654884 -407.00452)
		(size 0.4064)
		(drill 0.2032)
		(layers "F.Cu" "B.Cu")
		(net "GND")
	)
	(via
		(at 130.574796 -233.144314)
		(size 0.4064)
		(drill 0.2032)
		(layers "F.Cu" "B.Cu")
		(net "GND")
	)
	(via
		(at 44.927774 -348.709488)
		(size 0.49022)
		(drill 0.254)
		(layers "F.Cu" "B.Cu")
		(net "GND")
	)
	(via
		(at 316.662054 -392.999722)
		(size 0.4064)
		(drill 0.2032)
		(layers "F.Cu" "B.Cu")
		(net "GND")
	)
	(via
		(at 419.912038 -208.385156)
		(size 0.4826)
		(drill 0.254)
		(layers "F.Cu" "B.Cu")
		(net "GND")
	)
	(via
		(at 89.944194 -391.830814)
		(size 0.4064)
		(drill 0.2032)
		(layers "F.Cu" "B.Cu")
		(net "GND")
	)
	(via
		(at 82.001106 -274.896326)
		(size 0.4064)
		(drill 0.2032)
		(layers "F.Cu" "B.Cu")
		(net "GND")
	)
	(via
		(at 346.198444 -377.41733)
		(size 0.508)
		(drill 0.254)
		(layers "F.Cu" "B.Cu")
		(net "GND")
	)
	(via
		(at 268.530578 -313.360054)
		(size 0.4826)
		(drill 0.254)
		(layers "F.Cu" "B.Cu")
		(net "GND")
	)
	(via
		(at 233.299 -217.65895)
		(size 0.508)
		(drill 0.254)
		(layers "F.Cu" "B.Cu")
		(net "GND")
	)
	(via
		(at 412.367984 -298.485052)
		(size 0.4826)
		(drill 0.254)
		(layers "F.Cu" "B.Cu")
		(net "GND")
	)
	(via
		(at 451.4723 -294.235124)
		(size 0.4826)
		(drill 0.254)
		(layers "F.Cu" "B.Cu")
		(net "GND")
	)
	(via
		(at 35.678364 -275.960332)
		(size 0.4826)
		(drill 0.254)
		(layers "F.Cu" "B.Cu")
		(net "GND")
	)
	(via
		(at 303.268126 -255.135126)
		(size 0.4826)
		(drill 0.254)
		(layers "F.Cu" "B.Cu")
		(net "GND")
	)
	(via
		(at 165.583616 -192.218564)
		(size 0.4826)
		(drill 0.254)
		(layers "F.Cu" "B.Cu")
		(net "GND")
	)
	(via
		(at 59.378596 -386.449062)
		(size 0.4064)
		(drill 0.2032)
		(layers "F.Cu" "B.Cu")
		(net "GND")
	)
	(via
		(at 320.949828 -47.002954)
		(size 0.508)
		(drill 0.254)
		(layers "F.Cu" "B.Cu")
		(net "GND")
	)
	(via
		(at 141.854682 -234.764326)
		(size 0.4064)
		(drill 0.2032)
		(layers "F.Cu" "B.Cu")
		(net "GND")
	)
	(via
		(at 198.631556 -339.613748)
		(size 0.508)
		(drill 0.254)
		(layers "F.Cu" "B.Cu")
		(net "GND")
	)
	(via
		(at 412.367984 -233.035094)
		(size 0.4826)
		(drill 0.254)
		(layers "F.Cu" "B.Cu")
		(net "GND")
	)
	(via
		(at 250.534424 -279.503632)
		(size 0.508)
		(drill 0.254)
		(layers "F.Cu" "B.Cu")
		(net "GND")
	)
	(via
		(at 138.564874 -250.15444)
		(size 0.4064)
		(drill 0.2032)
		(layers "F.Cu" "B.Cu")
		(net "GND")
	)
	(via
		(at 283.351732 -312.084974)
		(size 0.4826)
		(drill 0.254)
		(layers "F.Cu" "B.Cu")
		(net "GND")
	)
	(via
		(at 295.724072 -216.035128)
		(size 0.4826)
		(drill 0.254)
		(layers "F.Cu" "B.Cu")
		(net "GND")
	)
	(via
		(at 392.587226 -190.995808)
		(size 0.508)
		(drill 0.254)
		(layers "F.Cu" "B.Cu")
		(net "GND")
	)
	(via
		(at 242.57 -324.866)
		(size 0.508)
		(drill 0.254)
		(layers "F.Cu" "B.Cu")
		(net "GND")
	)
	(via
		(at 177.532284 -111.063024)
		(size 0.4572)
		(drill 0.254)
		(layers "F.Cu" "B.Cu")
		(net "GND")
	)
	(via
		(at 76.249784 -426.69968)
		(size 0.4572)
		(drill 0.2032)
		(layers "F.Cu" "B.Cu")
		(net "GND")
	)
	(via
		(at 329.941174 -292.71595)
		(size 0.4064)
		(drill 0.2032)
		(layers "F.Cu" "B.Cu")
		(net "GND")
	)
	(via
		(at 74.422 -54.991)
		(size 0.508)
		(drill 0.254)
		(layers "F.Cu" "B.Cu")
		(net "GND")
	)
	(via
		(at 391.371074 -183.893968)
		(size 0.49022)
		(drill 0.254)
		(layers "F.Cu" "B.Cu")
		(net "GND")
	)
	(via
		(at 50.659792 -405.098504)
		(size 0.4572)
		(drill 0.254)
		(layers "F.Cu" "B.Cu")
		(net "GND")
	)
	(via
		(at 132.349748 -437.34736)
		(size 0.4572)
		(drill 0.2032)
		(layers "F.Cu" "B.Cu")
		(net "GND")
	)
	(via
		(at 21.70811 -226.23526)
		(size 0.4826)
		(drill 0.254)
		(layers "F.Cu" "B.Cu")
		(net "GND")
	)
	(via
		(at 222.152718 -278.779478)
		(size 0.508)
		(drill 0.254)
		(layers "F.Cu" "B.Cu")
		(net "GND")
	)
	(via
		(at 383.818384 -396.710662)
		(size 0.4064)
		(drill 0.2032)
		(layers "F.Cu" "B.Cu")
		(net "GND")
	)
	(via
		(at 345.151202 -232.334054)
		(size 0.4064)
		(drill 0.2032)
		(layers "F.Cu" "B.Cu")
		(net "GND")
	)
	(via
		(at 387.914896 -252.584204)
		(size 0.4064)
		(drill 0.2032)
		(layers "F.Cu" "B.Cu")
		(net "GND")
	)
	(via
		(at 317.044324 -333.055976)
		(size 0.49022)
		(drill 0.254)
		(layers "F.Cu" "B.Cu")
		(net "GND")
	)
	(via
		(at 388.21487 -282.996132)
		(size 0.4064)
		(drill 0.2032)
		(layers "F.Cu" "B.Cu")
		(net "GND")
	)
	(via
		(at 411.691582 -415.38652)
		(size 0.4064)
		(drill 0.2032)
		(layers "F.Cu" "B.Cu")
		(net "GND")
	)
	(via
		(at 101.91115 -238.814356)
		(size 0.4064)
		(drill 0.2032)
		(layers "F.Cu" "B.Cu")
		(net "GND")
	)
	(via
		(at 140.744702 -287.046162)
		(size 0.4064)
		(drill 0.2032)
		(layers "F.Cu" "B.Cu")
		(net "GND")
	)
	(via
		(at 283.351732 -293.384986)
		(size 0.4826)
		(drill 0.254)
		(layers "F.Cu" "B.Cu")
		(net "GND")
	)
	(via
		(at 84.99094 -240.434368)
		(size 0.4064)
		(drill 0.2032)
		(layers "F.Cu" "B.Cu")
		(net "GND")
	)
	(via
		(at 55.719218 -345.555824)
		(size 0.49022)
		(drill 0.254)
		(layers "F.Cu" "B.Cu")
		(net "GND")
	)
	(via
		(at 407.349706 -438.651396)
		(size 0.4572)
		(drill 0.2032)
		(layers "F.Cu" "B.Cu")
		(net "GND")
	)
	(via
		(at 259.889498 -37.23132)
		(size 0.508)
		(drill 0.254)
		(layers "F.Cu" "B.Cu")
		(net "GND")
	)
	(via
		(at 364.884716 -235.574078)
		(size 0.4064)
		(drill 0.2032)
		(layers "F.Cu" "B.Cu")
		(net "GND")
	)
	(via
		(at 312.871866 -418.412168)
		(size 0.4064)
		(drill 0.2032)
		(layers "F.Cu" "B.Cu")
		(net "GND")
	)
	(via
		(at 417.861242 -158.617412)
		(size 0.508)
		(drill 0.254)
		(layers "F.Cu" "B.Cu")
		(net "GND")
	)
	(via
		(at 61.016642 -382.85293)
		(size 0.4064)
		(drill 0.2032)
		(layers "F.Cu" "B.Cu")
		(net "GND")
	)
	(via
		(at 336.521044 -287.856168)
		(size 0.4064)
		(drill 0.2032)
		(layers "F.Cu" "B.Cu")
		(net "GND")
	)
	(via
		(at 317.158878 -421.535352)
		(size 0.4572)
		(drill 0.254)
		(layers "F.Cu" "B.Cu")
		(net "GND")
	)
	(via
		(at 183.366664 -363.623606)
		(size 0.508)
		(drill 0.254)
		(layers "F.Cu" "B.Cu")
		(net "GND")
	)
	(via
		(at 43.222418 -229.210362)
		(size 0.4826)
		(drill 0.254)
		(layers "F.Cu" "B.Cu")
		(net "GND")
	)
	(via
		(at 336.521044 -281.37612)
		(size 0.4064)
		(drill 0.2032)
		(layers "F.Cu" "B.Cu")
		(net "GND")
	)
	(via
		(at 342.51392 -335.590388)
		(size 0.49022)
		(drill 0.254)
		(layers "F.Cu" "B.Cu")
		(net "GND")
	)
	(via
		(at 35.977068 -124.824236)
		(size 0.508)
		(drill 0.254)
		(layers "F.Cu" "B.Cu")
		(net "GND")
	)
	(via
		(at 329.569064 -331.743812)
		(size 0.508)
		(drill 0.254)
		(layers "F.Cu" "B.Cu")
		(net "GND")
	)
	(via
		(at 36.795964 -280.635202)
		(size 0.4826)
		(drill 0.254)
		(layers "F.Cu" "B.Cu")
		(net "GND")
	)
	(via
		(at 353.441 -274.896072)
		(size 0.4064)
		(drill 0.2032)
		(layers "F.Cu" "B.Cu")
		(net "GND")
	)
	(via
		(at 94.812358 -333.87919)
		(size 0.49022)
		(drill 0.254)
		(layers "F.Cu" "B.Cu")
		(net "GND")
	)
	(via
		(at 223.978978 -317.22568)
		(size 0.508)
		(drill 0.254)
		(layers "F.Cu" "B.Cu")
		(net "GND")
	)
	(via
		(at 417.12896 -101.499162)
		(size 0.508)
		(drill 0.254)
		(layers "F.Cu" "B.Cu")
		(net "GND")
	)
	(via
		(at 350.321118 -234.764072)
		(size 0.4064)
		(drill 0.2032)
		(layers "F.Cu" "B.Cu")
		(net "GND")
	)
	(via
		(at 73.361296 -413.204152)
		(size 0.4572)
		(drill 0.254)
		(layers "F.Cu" "B.Cu")
		(net "GND")
	)
	(via
		(at 78.24978 -426.54728)
		(size 0.4572)
		(drill 0.2032)
		(layers "F.Cu" "B.Cu")
		(net "GND")
	)
	(via
		(at 183.930036 -35.887152)
		(size 0.508)
		(drill 0.254)
		(layers "F.Cu" "B.Cu")
		(net "GND")
	)
	(via
		(at 204.8637 -239.835436)
		(size 0.4826)
		(drill 0.254)
		(layers "F.Cu" "B.Cu")
		(net "GND")
	)
	(via
		(at 432.55819 -431.883312)
		(size 0.508)
		(drill 0.254)
		(layers "F.Cu" "B.Cu")
		(net "GND")
	)
	(via
		(at 379.758194 -295.983406)
		(size 0.4064)
		(drill 0.2032)
		(layers "F.Cu" "B.Cu")
		(net "GND")
	)
	(via
		(at 446.644268 -241.53495)
		(size 0.4826)
		(drill 0.254)
		(layers "F.Cu" "B.Cu")
		(net "GND")
	)
	(via
		(at 154.290014 -384.617722)
		(size 0.4064)
		(drill 0.2032)
		(layers "F.Cu" "B.Cu")
		(net "GND")
	)
	(via
		(at 350.744028 -400.212814)
		(size 0.4064)
		(drill 0.2032)
		(layers "F.Cu" "B.Cu")
		(net "GND")
	)
	(via
		(at 202.268582 -111.593376)
		(size 0.508)
		(drill 0.254)
		(layers "F.Cu" "B.Cu")
		(net "GND")
	)
	(via
		(at 303.232566 -343.472008)
		(size 0.508)
		(drill 0.254)
		(layers "F.Cu" "B.Cu")
		(net "GND")
	)
	(via
		(at 424.012106 -268.735048)
		(size 0.4826)
		(drill 0.254)
		(layers "F.Cu" "B.Cu")
		(net "GND")
	)
	(via
		(at 121.852436 -374.62333)
		(size 0.508)
		(drill 0.254)
		(layers "F.Cu" "B.Cu")
		(net "GND")
	)
	(via
		(at 350.795082 -257.930142)
		(size 0.4826)
		(drill 0.254)
		(layers "F.Cu" "B.Cu")
		(net "GND")
	)
	(via
		(at 287.062418 -211.360004)
		(size 0.4826)
		(drill 0.254)
		(layers "F.Cu" "B.Cu")
		(net "GND")
	)
	(via
		(at 73.634092 -410.664152)
		(size 0.4572)
		(drill 0.254)
		(layers "F.Cu" "B.Cu")
		(net "GND")
	)
	(via
		(at 446.543938 -17.433798)
		(size 0.508)
		(drill 0.254)
		(layers "F.Cu" "B.Cu")
		(net "GND")
	)
	(via
		(at 413.752284 -275.535136)
		(size 0.4826)
		(drill 0.254)
		(layers "F.Cu" "B.Cu")
		(net "GND")
	)
	(via
		(at 126.814834 -249.344434)
		(size 0.4064)
		(drill 0.2032)
		(layers "F.Cu" "B.Cu")
		(net "GND")
	)
	(via
		(at 177.1142 -369.35156)
		(size 0.508)
		(drill 0.254)
		(layers "F.Cu" "B.Cu")
		(net "GND")
	)
	(via
		(at 345.151202 -224.234248)
		(size 0.4064)
		(drill 0.2032)
		(layers "F.Cu" "B.Cu")
		(net "GND")
	)
	(via
		(at 348.911164 -229.094284)
		(size 0.4064)
		(drill 0.2032)
		(layers "F.Cu" "B.Cu")
		(net "GND")
	)
	(via
		(at 379.316488 -400.212814)
		(size 0.4064)
		(drill 0.2032)
		(layers "F.Cu" "B.Cu")
		(net "GND")
	)
	(via
		(at 443.9285 -278.085042)
		(size 0.4826)
		(drill 0.254)
		(layers "F.Cu" "B.Cu")
		(net "GND")
	)
	(via
		(at 39.748714 -344.137234)
		(size 0.508)
		(drill 0.254)
		(layers "F.Cu" "B.Cu")
		(net "GND")
	)
	(via
		(at 123.886214 -413.204152)
		(size 0.4572)
		(drill 0.254)
		(layers "F.Cu" "B.Cu")
		(net "GND")
	)
	(via
		(at 331.322934 -339.988906)
		(size 0.508)
		(drill 0.254)
		(layers "F.Cu" "B.Cu")
		(net "GND")
	)
	(via
		(at 352.376232 -359.065322)
		(size 0.508)
		(drill 0.254)
		(layers "F.Cu" "B.Cu")
		(net "GND")
	)
	(via
		(at 429.103282 -439.213498)
		(size 0.508)
		(drill 0.254)
		(layers "F.Cu" "B.Cu")
		(net "GND")
	)
	(via
		(at 98.464878 -138.906504)
		(size 0.508)
		(drill 0.254)
		(layers "F.Cu" "B.Cu")
		(net "GND")
	)
	(via
		(at 135.578088 -295.98366)
		(size 0.4064)
		(drill 0.2032)
		(layers "F.Cu" "B.Cu")
		(net "GND")
	)
	(via
		(at 205.990444 -345.867736)
		(size 0.508)
		(drill 0.254)
		(layers "F.Cu" "B.Cu")
		(net "GND")
	)
	(via
		(at 353.618546 -12.542266)
		(size 0.508)
		(drill 0.254)
		(layers "F.Cu" "B.Cu")
		(net "GND")
	)
	(via
		(at 335.11109 -291.905944)
		(size 0.4064)
		(drill 0.2032)
		(layers "F.Cu" "B.Cu")
		(net "GND")
	)
	(via
		(at 423.38498 -353.10318)
		(size 0.49022)
		(drill 0.254)
		(layers "F.Cu" "B.Cu")
		(net "GND")
	)
	(via
		(at 65.249806 -436.051198)
		(size 0.4572)
		(drill 0.2032)
		(layers "F.Cu" "B.Cu")
		(net "GND")
	)
	(via
		(at 171.97197 -208.38541)
		(size 0.4826)
		(drill 0.254)
		(layers "F.Cu" "B.Cu")
		(net "GND")
	)
	(via
		(at 50.766472 -229.210362)
		(size 0.4826)
		(drill 0.254)
		(layers "F.Cu" "B.Cu")
		(net "GND")
	)
	(via
		(at 359.144824 -388.917688)
		(size 0.508)
		(drill 0.254)
		(layers "F.Cu" "B.Cu")
		(net "GND")
	)
	(via
		(at 124.607066 -167.131746)
		(size 0.49022)
		(drill 0.254)
		(layers "F.Cu" "B.Cu")
		(net "GND")
	)
	(via
		(at 372.704868 -277.32609)
		(size 0.4064)
		(drill 0.2032)
		(layers "F.Cu" "B.Cu")
		(net "GND")
	)
	(via
		(at 412.958026 -9.424924)
		(size 0.508)
		(drill 0.254)
		(layers "F.Cu" "B.Cu")
		(net "GND")
	)
	(via
		(at 140.274802 -287.856422)
		(size 0.4064)
		(drill 0.2032)
		(layers "F.Cu" "B.Cu")
		(net "GND")
	)
	(via
		(at 351.164906 -420.952168)
		(size 0.4064)
		(drill 0.2032)
		(layers "F.Cu" "B.Cu")
		(net "GND")
	)
	(via
		(at 189.775846 -202.435206)
		(size 0.4826)
		(drill 0.254)
		(layers "F.Cu" "B.Cu")
		(net "GND")
	)
	(via
		(at 448.063366 -378.81687)
		(size 0.508)
		(drill 0.254)
		(layers "F.Cu" "B.Cu")
		(net "GND")
	)
	(via
		(at 80.249776 -429.147224)
		(size 0.4572)
		(drill 0.2032)
		(layers "F.Cu" "B.Cu")
		(net "GND")
	)
	(via
		(at 350.321118 -226.664266)
		(size 0.4064)
		(drill 0.2032)
		(layers "F.Cu" "B.Cu")
		(net "GND")
	)
	(via
		(at 47.391066 -390.160002)
		(size 0.4064)
		(drill 0.2032)
		(layers "F.Cu" "B.Cu")
		(net "GND")
	)
	(via
		(at 303.268126 -300.185074)
		(size 0.4826)
		(drill 0.254)
		(layers "F.Cu" "B.Cu")
		(net "GND")
	)
	(via
		(at 198.12 -345.567)
		(size 0.508)
		(drill 0.254)
		(layers "F.Cu" "B.Cu")
		(net "GND")
	)
	(via
		(at 55.328058 -317.185294)
		(size 0.4826)
		(drill 0.254)
		(layers "F.Cu" "B.Cu")
		(net "GND")
	)
	(via
		(at 269.648178 -289.985196)
		(size 0.4826)
		(drill 0.254)
		(layers "F.Cu" "B.Cu")
		(net "GND")
	)
	(via
		(at 69.107558 -333.84998)
		(size 0.49022)
		(drill 0.254)
		(layers "F.Cu" "B.Cu")
		(net "GND")
	)
	(via
		(at 124.103384 -441.227718)
		(size 0.508)
		(drill 0.254)
		(layers "F.Cu" "B.Cu")
		(net "GND")
	)
	(via
		(at 55.497222 -173.839124)
		(size 0.6604)
		(drill 0.3302)
		(layers "F.Cu" "B.Cu")
		(net "GND")
	)
	(via
		(at 461.81137 -37.92855)
		(size 0.508)
		(drill 0.254)
		(layers "F.Cu" "B.Cu")
		(net "GND")
	)
	(via
		(at 425.00423 -425.06265)
		(size 0.508)
		(drill 0.254)
		(layers "F.Cu" "B.Cu")
		(net "GND")
	)
	(via
		(at 94.744286 -393.877038)
		(size 0.4572)
		(drill 0.254)
		(layers "F.Cu" "B.Cu")
		(net "GND")
	)
	(via
		(at 112.257586 -252.416564)
		(size 0.4826)
		(drill 0.254)
		(layers "F.Cu" "B.Cu")
		(net "GND")
	)
	(via
		(at 374.584722 -265.986006)
		(size 0.4064)
		(drill 0.2032)
		(layers "F.Cu" "B.Cu")
		(net "GND")
	)
	(via
		(at 324.75297 -231.789986)
		(size 0.4064)
		(drill 0.2032)
		(layers "F.Cu" "B.Cu")
		(net "GND")
	)
	(via
		(at 182.043578 -353.283774)
		(size 0.49022)
		(drill 0.254)
		(layers "F.Cu" "B.Cu")
		(net "GND")
	)
	(via
		(at 446.644268 -301.034958)
		(size 0.4826)
		(drill 0.254)
		(layers "F.Cu" "B.Cu")
		(net "GND")
	)
	(via
		(at 47.225712 -0.762254)
		(size 0.508)
		(drill 0.254)
		(layers "F.Cu" "B.Cu")
		(net "GND")
	)
	(via
		(at 168.527984 -267.03528)
		(size 0.4826)
		(drill 0.254)
		(layers "F.Cu" "B.Cu")
		(net "GND")
	)
	(via
		(at 427.456092 -317.18504)
		(size 0.4826)
		(drill 0.254)
		(layers "F.Cu" "B.Cu")
		(net "GND")
	)
	(via
		(at 356.674674 -169.895012)
		(size 0.49022)
		(drill 0.254)
		(layers "F.Cu" "B.Cu")
		(net "GND")
	)
	(via
		(at 342.249506 -439.651394)
		(size 0.4572)
		(drill 0.2032)
		(layers "F.Cu" "B.Cu")
		(net "GND")
	)
	(via
		(at 386.820918 -30.457648)
		(size 0.508)
		(drill 0.254)
		(layers "F.Cu" "B.Cu")
		(net "GND")
	)
	(via
		(at 158.244286 -391.830814)
		(size 0.4064)
		(drill 0.2032)
		(layers "F.Cu" "B.Cu")
		(net "GND")
	)
	(via
		(at 345.921076 -265.176)
		(size 0.4064)
		(drill 0.2032)
		(layers "F.Cu" "B.Cu")
		(net "GND")
	)
	(via
		(at 391.504678 -269.22603)
		(size 0.4064)
		(drill 0.2032)
		(layers "F.Cu" "B.Cu")
		(net "GND")
	)
	(via
		(at 378.344938 -291.905944)
		(size 0.4064)
		(drill 0.2032)
		(layers "F.Cu" "B.Cu")
		(net "GND")
	)
	(via
		(at 319.249552 -432.747166)
		(size 0.4572)
		(drill 0.2032)
		(layers "F.Cu" "B.Cu")
		(net "GND")
	)
	(via
		(at 361.124754 -237.19409)
		(size 0.4064)
		(drill 0.2032)
		(layers "F.Cu" "B.Cu")
		(net "GND")
	)
	(via
		(at 290.895786 -239.835182)
		(size 0.4826)
		(drill 0.254)
		(layers "F.Cu" "B.Cu")
		(net "GND")
	)
	(via
		(at 299.82414 -255.135126)
		(size 0.4826)
		(drill 0.254)
		(layers "F.Cu" "B.Cu")
		(net "GND")
	)
	(via
		(at 164.427916 -245.785386)
		(size 0.4826)
		(drill 0.254)
		(layers "F.Cu" "B.Cu")
		(net "GND")
	)
	(via
		(at 199.39 -143.129)
		(size 0.508)
		(drill 0.254)
		(layers "F.Cu" "B.Cu")
		(net "GND")
	)
	(via
		(at 225.820478 -267.495782)
		(size 0.508)
		(drill 0.254)
		(layers "F.Cu" "B.Cu")
		(net "GND")
	)
	(via
		(at 332.424278 -421.586152)
		(size 0.4572)
		(drill 0.254)
		(layers "F.Cu" "B.Cu")
		(net "GND")
	)
	(via
		(at 82.001106 -263.556242)
		(size 0.4064)
		(drill 0.2032)
		(layers "F.Cu" "B.Cu")
		(net "GND")
	)
	(via
		(at 374.516396 -402.259038)
		(size 0.4572)
		(drill 0.254)
		(layers "F.Cu" "B.Cu")
		(net "GND")
	)
	(via
		(at 97.144332 -393.927838)
		(size 0.4572)
		(drill 0.254)
		(layers "F.Cu" "B.Cu")
		(net "GND")
	)
	(via
		(at 342.801194 -244.484144)
		(size 0.4064)
		(drill 0.2032)
		(layers "F.Cu" "B.Cu")
		(net "GND")
	)
	(via
		(at 389.154924 -295.955974)
		(size 0.4064)
		(drill 0.2032)
		(layers "F.Cu" "B.Cu")
		(net "GND")
	)
	(via
		(at 355.791008 -275.706078)
		(size 0.4064)
		(drill 0.2032)
		(layers "F.Cu" "B.Cu")
		(net "GND")
	)
	(via
		(at 324.955154 -441.227718)
		(size 0.508)
		(drill 0.254)
		(layers "F.Cu" "B.Cu")
		(net "GND")
	)
	(via
		(at 433.285392 -349.200978)
		(size 0.49022)
		(drill 0.254)
		(layers "F.Cu" "B.Cu")
		(net "GND")
	)
	(via
		(at 352.031046 -277.32609)
		(size 0.4064)
		(drill 0.2032)
		(layers "F.Cu" "B.Cu")
		(net "GND")
	)
	(via
		(at 198.7042 -233.885232)
		(size 0.4826)
		(drill 0.254)
		(layers "F.Cu" "B.Cu")
		(net "GND")
	)
	(via
		(at 103.791004 -232.334308)
		(size 0.4064)
		(drill 0.2032)
		(layers "F.Cu" "B.Cu")
		(net "GND")
	)
	(via
		(at 179.516024 -266.185396)
		(size 0.4826)
		(drill 0.254)
		(layers "F.Cu" "B.Cu")
		(net "GND")
	)
	(via
		(at 121.944638 -280.566368)
		(size 0.4064)
		(drill 0.2032)
		(layers "F.Cu" "B.Cu")
		(net "GND")
	)
	(via
		(at 352.45548 -437.240172)
		(size 0.508)
		(drill 0.254)
		(layers "F.Cu" "B.Cu")
		(net "GND")
	)
	(via
		(at 207.3656 -219.860368)
		(size 0.4826)
		(drill 0.254)
		(layers "F.Cu" "B.Cu")
		(net "GND")
	)
	(via
		(at 167.143684 -239.835436)
		(size 0.4826)
		(drill 0.254)
		(layers "F.Cu" "B.Cu")
		(net "GND")
	)
	(via
		(at 23.607014 -341.927688)
		(size 0.508)
		(drill 0.254)
		(layers "F.Cu" "B.Cu")
		(net "GND")
	)
	(via
		(at 327.829418 -417.778184)
		(size 0.4572)
		(drill 0.254)
		(layers "F.Cu" "B.Cu")
		(net "GND")
	)
	(via
		(at 327.591166 -269.22603)
		(size 0.4064)
		(drill 0.2032)
		(layers "F.Cu" "B.Cu")
		(net "GND")
	)
	(via
		(at 163.465002 -353.715574)
		(size 0.508)
		(drill 0.254)
		(layers "F.Cu" "B.Cu")
		(net "GND")
	)
	(via
		(at 354.851208 -295.145968)
		(size 0.4064)
		(drill 0.2032)
		(layers "F.Cu" "B.Cu")
		(net "GND")
	)
	(via
		(at 440.741308 -346.247466)
		(size 0.508)
		(drill 0.254)
		(layers "F.Cu" "B.Cu")
		(net "GND")
	)
	(via
		(at 119.37365 -438.101232)
		(size 0.508)
		(drill 0.254)
		(layers "F.Cu" "B.Cu")
		(net "GND")
	)
	(via
		(at 372.404894 -256.634234)
		(size 0.4064)
		(drill 0.2032)
		(layers "F.Cu" "B.Cu")
		(net "GND")
	)
	(via
		(at 381.634746 -274.896072)
		(size 0.4064)
		(drill 0.2032)
		(layers "F.Cu" "B.Cu")
		(net "GND")
	)
	(via
		(at 124.464826 -243.674392)
		(size 0.4064)
		(drill 0.2032)
		(layers "F.Cu" "B.Cu")
		(net "GND")
	)
	(via
		(at 65.81648 -391.830814)
		(size 0.4064)
		(drill 0.2032)
		(layers "F.Cu" "B.Cu")
		(net "GND")
	)
	(via
		(at 145.349722 -436.051198)
		(size 0.4572)
		(drill 0.2032)
		(layers "F.Cu" "B.Cu")
		(net "GND")
	)
	(via
		(at 57.668414 -370.83873)
		(size 0.508)
		(drill 0.254)
		(layers "F.Cu" "B.Cu")
		(net "GND")
	)
	(via
		(at 77.867764 -404.46452)
		(size 0.4064)
		(drill 0.2032)
		(layers "F.Cu" "B.Cu")
		(net "GND")
	)
	(via
		(at 114.618516 -388.328662)
		(size 0.4064)
		(drill 0.2032)
		(layers "F.Cu" "B.Cu")
		(net "GND")
	)
	(via
		(at 326.351138 -233.954066)
		(size 0.4064)
		(drill 0.2032)
		(layers "F.Cu" "B.Cu")
		(net "GND")
	)
	(via
		(at 240.205514 -319.466468)
		(size 0.508)
		(drill 0.254)
		(layers "F.Cu" "B.Cu")
		(net "GND")
	)
	(via
		(at 155.349702 -431.451258)
		(size 0.4572)
		(drill 0.2032)
		(layers "F.Cu" "B.Cu")
		(net "GND")
	)
	(via
		(at 382.1049 -264.365994)
		(size 0.4064)
		(drill 0.2032)
		(layers "F.Cu" "B.Cu")
		(net "GND")
	)
	(via
		(at 354.851208 -285.42615)
		(size 0.4064)
		(drill 0.2032)
		(layers "F.Cu" "B.Cu")
		(net "GND")
	)
	(via
		(at 453.99706 -41.105836)
		(size 0.508)
		(drill 0.254)
		(layers "F.Cu" "B.Cu")
		(net "GND")
	)
	(via
		(at 436.117746 -230.060246)
		(size 0.4826)
		(drill 0.254)
		(layers "F.Cu" "B.Cu")
		(net "GND")
	)
	(via
		(at 391.974832 -289.475926)
		(size 0.4064)
		(drill 0.2032)
		(layers "F.Cu" "B.Cu")
		(net "GND")
	)
	(via
		(at 460.163672 -55.6006)
		(size 0.508)
		(drill 0.254)
		(layers "F.Cu" "B.Cu")
		(net "GND")
	)
	(via
		(at 77.112876 -268.15034)
		(size 0.4064)
		(drill 0.2032)
		(layers "F.Cu" "B.Cu")
		(net "GND")
	)
	(via
		(at 72.123046 -38.736524)
		(size 0.508)
		(drill 0.254)
		(layers "F.Cu" "B.Cu")
		(net "GND")
	)
	(via
		(at 52.318412 -388.328662)
		(size 0.4064)
		(drill 0.2032)
		(layers "F.Cu" "B.Cu")
		(net "GND")
	)
	(via
		(at 147.00631 -386.449062)
		(size 0.4064)
		(drill 0.2032)
		(layers "F.Cu" "B.Cu")
		(net "GND")
	)
	(via
		(at 380.224792 -270.846042)
		(size 0.4064)
		(drill 0.2032)
		(layers "F.Cu" "B.Cu")
		(net "GND")
	)
	(via
		(at 412.367984 -267.885164)
		(size 0.4826)
		(drill 0.254)
		(layers "F.Cu" "B.Cu")
		(net "GND")
	)
	(via
		(at 55.478934 -344.78595)
		(size 0.49022)
		(drill 0.254)
		(layers "F.Cu" "B.Cu")
		(net "GND")
	)
	(via
		(at 386.804916 -272.466054)
		(size 0.4064)
		(drill 0.2032)
		(layers "F.Cu" "B.Cu")
		(net "GND")
	)
	(via
		(at 174.830232 -414.435544)
		(size 0.508)
		(drill 0.254)
		(layers "F.Cu" "B.Cu")
		(net "GND")
	)
	(via
		(at 77.001116 -225.044508)
		(size 0.4064)
		(drill 0.2032)
		(layers "F.Cu" "B.Cu")
		(net "GND")
	)
	(via
		(at 233.658664 -230.864664)
		(size 0.4826)
		(drill 0.254)
		(layers "F.Cu" "B.Cu")
		(net "GND")
	)
	(via
		(at 363.774736 -291.095938)
		(size 0.4064)
		(drill 0.2032)
		(layers "F.Cu" "B.Cu")
		(net "GND")
	)
	(via
		(at 107.550966 -242.05438)
		(size 0.4064)
		(drill 0.2032)
		(layers "F.Cu" "B.Cu")
		(net "GND")
	)
	(via
		(at 50.216562 -382.85293)
		(size 0.4064)
		(drill 0.2032)
		(layers "F.Cu" "B.Cu")
		(net "GND")
	)
	(via
		(at 190.60541 -350.921828)
		(size 0.49022)
		(drill 0.254)
		(layers "F.Cu" "B.Cu")
		(net "GND")
	)
	(via
		(at 25.748234 -9.424924)
		(size 0.508)
		(drill 0.254)
		(layers "F.Cu" "B.Cu")
		(net "GND")
	)
	(via
		(at 436.384446 -306.135024)
		(size 0.4826)
		(drill 0.254)
		(layers "F.Cu" "B.Cu")
		(net "GND")
	)
	(via
		(at 79.351124 -250.15444)
		(size 0.4064)
		(drill 0.2032)
		(layers "F.Cu" "B.Cu")
		(net "GND")
	)
	(via
		(at 41.430702 -375.30786)
		(size 0.508)
		(drill 0.254)
		(layers "F.Cu" "B.Cu")
		(net "GND")
	)
	(via
		(at 174.644558 -361.963716)
		(size 0.508)
		(drill 0.254)
		(layers "F.Cu" "B.Cu")
		(net "GND")
	)
	(via
		(at 154.065986 -202.213464)
		(size 0.508)
		(drill 0.254)
		(layers "F.Cu" "B.Cu")
		(net "GND")
	)
	(via
		(at 405.068024 -19.771106)
		(size 0.508)
		(drill 0.254)
		(layers "F.Cu" "B.Cu")
		(net "GND")
	)
	(via
		(at 360.35996 -412.217108)
		(size 0.508)
		(drill 0.254)
		(layers "F.Cu" "B.Cu")
		(net "GND")
	)
	(via
		(at 380.224792 -277.32609)
		(size 0.4064)
		(drill 0.2032)
		(layers "F.Cu" "B.Cu")
		(net "GND")
	)
	(via
		(at 105.971086 -291.906198)
		(size 0.4064)
		(drill 0.2032)
		(layers "F.Cu" "B.Cu")
		(net "GND")
	)
	(via
		(at 278.503126 -417.440872)
		(size 0.508)
		(drill 0.254)
		(layers "F.Cu" "B.Cu")
		(net "GND")
	)
	(via
		(at 55.304944 -6.598158)
		(size 0.508)
		(drill 0.254)
		(layers "F.Cu" "B.Cu")
		(net "GND")
	)
	(via
		(at 278.504142 -124.305314)
		(size 0.508)
		(drill 0.254)
		(layers "F.Cu" "B.Cu")
		(net "GND")
	)
	(via
		(at 203.532232 -294.235378)
		(size 0.4826)
		(drill 0.254)
		(layers "F.Cu" "B.Cu")
		(net "GND")
	)
	(via
		(at 255.927098 -206.083408)
		(size 0.508)
		(drill 0.254)
		(layers "F.Cu" "B.Cu")
		(net "GND")
	)
	(via
		(at 177.189638 -294.66032)
		(size 0.4826)
		(drill 0.254)
		(layers "F.Cu" "B.Cu")
		(net "GND")
	)
	(via
		(at 334.228694 -412.212536)
		(size 0.4572)
		(drill 0.254)
		(layers "F.Cu" "B.Cu")
		(net "GND")
	)
	(via
		(at 352.031046 -288.66592)
		(size 0.4064)
		(drill 0.2032)
		(layers "F.Cu" "B.Cu")
		(net "GND")
	)
	(via
		(at 59.249818 -430.299622)
		(size 0.4572)
		(drill 0.2032)
		(layers "F.Cu" "B.Cu")
		(net "GND")
	)
	(via
		(at 204.8637 -286.585406)
		(size 0.4826)
		(drill 0.254)
		(layers "F.Cu" "B.Cu")
		(net "GND")
	)
	(via
		(at 321.391026 -398.542002)
		(size 0.4064)
		(drill 0.2032)
		(layers "F.Cu" "B.Cu")
		(net "GND")
	)
	(via
		(at 412.367984 -249.185176)
		(size 0.4826)
		(drill 0.254)
		(layers "F.Cu" "B.Cu")
		(net "GND")
	)
	(via
		(at 450.057774 -31.988506)
		(size 0.508)
		(drill 0.254)
		(layers "F.Cu" "B.Cu")
		(net "GND")
	)
	(via
		(at 337.930998 -262.745982)
		(size 0.4064)
		(drill 0.2032)
		(layers "F.Cu" "B.Cu")
		(net "GND")
	)
	(via
		(at 233.618532 -342.64346)
		(size 0.508)
		(drill 0.254)
		(layers "F.Cu" "B.Cu")
		(net "GND")
	)
	(via
		(at 357.201216 -287.856168)
		(size 0.4064)
		(drill 0.2032)
		(layers "F.Cu" "B.Cu")
		(net "GND")
	)
	(via
		(at 54.662324 -384.617722)
		(size 0.4064)
		(drill 0.2032)
		(layers "F.Cu" "B.Cu")
		(net "GND")
	)
	(via
		(at 364.884716 -225.85426)
		(size 0.4064)
		(drill 0.2032)
		(layers "F.Cu" "B.Cu")
		(net "GND")
	)
	(via
		(at 319.249552 -431.451258)
		(size 0.4572)
		(drill 0.2032)
		(layers "F.Cu" "B.Cu")
		(net "GND")
	)
	(via
		(at 110.371128 -233.95432)
		(size 0.4064)
		(drill 0.2032)
		(layers "F.Cu" "B.Cu")
		(net "GND")
	)
	(via
		(at 198.7042 -204.135228)
		(size 0.4826)
		(drill 0.254)
		(layers "F.Cu" "B.Cu")
		(net "GND")
	)
	(via
		(at 426.24502 -384.299968)
		(size 0.508)
		(drill 0.254)
		(layers "F.Cu" "B.Cu")
		(net "GND")
	)
	(via
		(at 137.874502 -81.069942)
		(size 0.508)
		(drill 0.254)
		(layers "F.Cu" "B.Cu")
		(net "GND")
	)
	(via
		(at 338.571078 -250.154186)
		(size 0.4064)
		(drill 0.2032)
		(layers "F.Cu" "B.Cu")
		(net "GND")
	)
	(via
		(at 430.477168 -351.70618)
		(size 0.49022)
		(drill 0.254)
		(layers "F.Cu" "B.Cu")
		(net "GND")
	)
	(via
		(at 401.414742 -418.412168)
		(size 0.4064)
		(drill 0.2032)
		(layers "F.Cu" "B.Cu")
		(net "GND")
	)
	(via
		(at 78.24978 -439.651394)
		(size 0.4572)
		(drill 0.2032)
		(layers "F.Cu" "B.Cu")
		(net "GND")
	)
	(via
		(at 36.900358 -346.322142)
		(size 0.49022)
		(drill 0.254)
		(layers "F.Cu" "B.Cu")
		(net "GND")
	)
	(via
		(at 390.334754 -412.212536)
		(size 0.4572)
		(drill 0.254)
		(layers "F.Cu" "B.Cu")
		(net "GND")
	)
	(via
		(at 355.487986 -253.392178)
		(size 0.4064)
		(drill 0.2032)
		(layers "F.Cu" "B.Cu")
		(net "GND")
	)
	(via
		(at 361.124754 -232.334054)
		(size 0.4064)
		(drill 0.2032)
		(layers "F.Cu" "B.Cu")
		(net "GND")
	)
	(via
		(at 455.985626 -47.22114)
		(size 0.508)
		(drill 0.254)
		(layers "F.Cu" "B.Cu")
		(net "GND")
	)
	(via
		(at 102.85095 -232.334308)
		(size 0.4064)
		(drill 0.2032)
		(layers "F.Cu" "B.Cu")
		(net "GND")
	)
	(via
		(at 194.604132 -223.685354)
		(size 0.4826)
		(drill 0.254)
		(layers "F.Cu" "B.Cu")
		(net "GND")
	)
	(via
		(at 379.88621 -421.586152)
		(size 0.4572)
		(drill 0.254)
		(layers "F.Cu" "B.Cu")
		(net "GND")
	)
	(via
		(at 398.26565 -421.586152)
		(size 0.4572)
		(drill 0.254)
		(layers "F.Cu" "B.Cu")
		(net "GND")
	)
	(via
		(at 439.100214 -291.684964)
		(size 0.4826)
		(drill 0.254)
		(layers "F.Cu" "B.Cu")
		(net "GND")
	)
	(via
		(at 145.144744 -242.05438)
		(size 0.4064)
		(drill 0.2032)
		(layers "F.Cu" "B.Cu")
		(net "GND")
	)
	(via
		(at 18.230088 -107.123484)
		(size 0.508)
		(drill 0.254)
		(layers "F.Cu" "B.Cu")
		(net "GND")
	)
	(via
		(at 394.494766 -228.284278)
		(size 0.4064)
		(drill 0.2032)
		(layers "F.Cu" "B.Cu")
		(net "GND")
	)
	(via
		(at 445.259968 -295.935146)
		(size 0.4826)
		(drill 0.254)
		(layers "F.Cu" "B.Cu")
		(net "GND")
	)
	(via
		(at 113.582196 -259.845302)
		(size 0.4826)
		(drill 0.254)
		(layers "F.Cu" "B.Cu")
		(net "GND")
	)
	(via
		(at 123.525026 -404.46452)
		(size 0.4064)
		(drill 0.2032)
		(layers "F.Cu" "B.Cu")
		(net "GND")
	)
	(via
		(at 320.097658 -104.426512)
		(size 0.508)
		(drill 0.254)
		(layers "F.Cu" "B.Cu")
		(net "GND")
	)
	(via
		(at 71.09333 -180.870098)
		(size 0.508)
		(drill 0.254)
		(layers "F.Cu" "B.Cu")
		(net "GND")
	)
	(via
		(at 66.773044 -37.437314)
		(size 0.508)
		(drill 0.254)
		(layers "F.Cu" "B.Cu")
		(net "GND")
	)
	(via
		(at 425.129706 -275.960078)
		(size 0.4826)
		(drill 0.254)
		(layers "F.Cu" "B.Cu")
		(net "GND")
	)
	(via
		(at 357.80726 -336.499962)
		(size 0.508)
		(drill 0.254)
		(layers "F.Cu" "B.Cu")
		(net "GND")
	)
	(via
		(at 386.804916 -270.846042)
		(size 0.4064)
		(drill 0.2032)
		(layers "F.Cu" "B.Cu")
		(net "GND")
	)
	(via
		(at 369.584732 -227.474272)
		(size 0.4064)
		(drill 0.2032)
		(layers "F.Cu" "B.Cu")
		(net "GND")
	)
	(via
		(at 331.051154 -251.774198)
		(size 0.4064)
		(drill 0.2032)
		(layers "F.Cu" "B.Cu")
		(net "GND")
	)
	(via
		(at 364.137956 -256.387346)
		(size 0.4826)
		(drill 0.254)
		(layers "F.Cu" "B.Cu")
		(net "GND")
	)
	(via
		(at 371.764814 -274.086066)
		(size 0.4064)
		(drill 0.2032)
		(layers "F.Cu" "B.Cu")
		(net "GND")
	)
	(via
		(at 93.450918 -253.394464)
		(size 0.4064)
		(drill 0.2032)
		(layers "F.Cu" "B.Cu")
		(net "GND")
	)
	(via
		(at 428.573692 -314.210192)
		(size 0.4826)
		(drill 0.254)
		(layers "F.Cu" "B.Cu")
		(net "GND")
	)
	(via
		(at 47.784004 -216.035382)
		(size 0.4826)
		(drill 0.254)
		(layers "F.Cu" "B.Cu")
		(net "GND")
	)
	(via
		(at 406.49144 -377.41733)
		(size 0.508)
		(drill 0.254)
		(layers "F.Cu" "B.Cu")
		(net "GND")
	)
	(via
		(at 400.517868 -6.091174)
		(size 0.508)
		(drill 0.254)
		(layers "F.Cu" "B.Cu")
		(net "GND")
	)
	(via
		(at 113.48466 -288.666174)
		(size 0.4064)
		(drill 0.2032)
		(layers "F.Cu" "B.Cu")
		(net "GND")
	)
	(via
		(at 47.784004 -199.035416)
		(size 0.4826)
		(drill 0.254)
		(layers "F.Cu" "B.Cu")
		(net "GND")
	)
	(via
		(at 158.244286 -393.927838)
		(size 0.4572)
		(drill 0.254)
		(layers "F.Cu" "B.Cu")
		(net "GND")
	)
	(via
		(at 107.436666 -179.321968)
		(size 0.49022)
		(drill 0.254)
		(layers "F.Cu" "B.Cu")
		(net "GND")
	)
	(via
		(at 396.73403 -416.020504)
		(size 0.4572)
		(drill 0.254)
		(layers "F.Cu" "B.Cu")
		(net "GND")
	)
	(via
		(at 30.568138 -19.771106)
		(size 0.508)
		(drill 0.254)
		(layers "F.Cu" "B.Cu")
		(net "GND")
	)
	(via
		(at 442.5442 -244.08511)
		(size 0.4826)
		(drill 0.254)
		(layers "F.Cu" "B.Cu")
		(net "GND")
	)
	(via
		(at 331.051154 -238.814102)
		(size 0.4064)
		(drill 0.2032)
		(layers "F.Cu" "B.Cu")
		(net "GND")
	)
	(via
		(at 320.475356 -379.22073)
		(size 0.508)
		(drill 0.254)
		(layers "F.Cu" "B.Cu")
		(net "GND")
	)
	(via
		(at 457.628752 -391.762234)
		(size 0.49022)
		(drill 0.254)
		(layers "F.Cu" "B.Cu")
		(net "GND")
	)
	(via
		(at 310.895746 -415.38652)
		(size 0.4064)
		(drill 0.2032)
		(layers "F.Cu" "B.Cu")
		(net "GND")
	)
	(via
		(at 106.91114 -274.08632)
		(size 0.4064)
		(drill 0.2032)
		(layers "F.Cu" "B.Cu")
		(net "GND")
	)
	(via
		(at 152.318212 -44.585636)
		(size 0.508)
		(drill 0.254)
		(layers "F.Cu" "B.Cu")
		(net "GND")
	)
	(via
		(at 361.424728 -290.285932)
		(size 0.4064)
		(drill 0.2032)
		(layers "F.Cu" "B.Cu")
		(net "GND")
	)
	(via
		(at 125.417834 -407.638504)
		(size 0.4572)
		(drill 0.254)
		(layers "F.Cu" "B.Cu")
		(net "GND")
	)
	(via
		(at 59.428126 -196.485256)
		(size 0.4826)
		(drill 0.254)
		(layers "F.Cu" "B.Cu")
		(net "GND")
	)
	(via
		(at 44.340018 -297.635422)
		(size 0.4826)
		(drill 0.254)
		(layers "F.Cu" "B.Cu")
		(net "GND")
	)
	(via
		(at 269.648178 -299.33519)
		(size 0.4826)
		(drill 0.254)
		(layers "F.Cu" "B.Cu")
		(net "GND")
	)
	(via
		(at 329.6412 -226.664266)
		(size 0.4064)
		(drill 0.2032)
		(layers "F.Cu" "B.Cu")
		(net "GND")
	)
	(via
		(at 58.088022 -357.85679)
		(size 0.508)
		(drill 0.254)
		(layers "F.Cu" "B.Cu")
		(net "GND")
	)
	(via
		(at 305.983894 -277.235158)
		(size 0.4826)
		(drill 0.254)
		(layers "F.Cu" "B.Cu")
		(net "GND")
	)
	(via
		(at 450.088 -267.885164)
		(size 0.4826)
		(drill 0.254)
		(layers "F.Cu" "B.Cu")
		(net "GND")
	)
	(via
		(at 371.93474 -247.724168)
		(size 0.4064)
		(drill 0.2032)
		(layers "F.Cu" "B.Cu")
		(net "GND")
	)
	(via
		(at 424.012106 -282.33497)
		(size 0.4826)
		(drill 0.254)
		(layers "F.Cu" "B.Cu")
		(net "GND")
	)
	(via
		(at 131.271518 -405.098504)
		(size 0.4572)
		(drill 0.254)
		(layers "F.Cu" "B.Cu")
		(net "GND")
	)
	(via
		(at 452.803768 -286.585152)
		(size 0.4826)
		(drill 0.254)
		(layers "F.Cu" "B.Cu")
		(net "GND")
	)
	(via
		(at 363.774736 -281.37612)
		(size 0.4064)
		(drill 0.2032)
		(layers "F.Cu" "B.Cu")
		(net "GND")
	)
	(via
		(at 74.064622 -389.103108)
		(size 0.508)
		(drill 0.254)
		(layers "F.Cu" "B.Cu")
		(net "GND")
	)
	(via
		(at 384.924808 -274.086066)
		(size 0.4064)
		(drill 0.2032)
		(layers "F.Cu" "B.Cu")
		(net "GND")
	)
	(via
		(at 56.21655 -393.902438)
		(size 0.4572)
		(drill 0.254)
		(layers "F.Cu" "B.Cu")
		(net "GND")
	)
	(via
		(at 392.702796 -193.131694)
		(size 0.508)
		(drill 0.254)
		(layers "F.Cu" "B.Cu")
		(net "GND")
	)
	(via
		(at 148.206206 -386.449062)
		(size 0.4064)
		(drill 0.2032)
		(layers "F.Cu" "B.Cu")
		(net "GND")
	)
	(via
		(at 381.506222 -420.952168)
		(size 0.4064)
		(drill 0.2032)
		(layers "F.Cu" "B.Cu")
		(net "GND")
	)
	(via
		(at 194.312032 -123.84278)
		(size 0.4572)
		(drill 0.254)
		(layers "F.Cu" "B.Cu")
		(net "GND")
	)
	(via
		(at 265.54811 -197.33514)
		(size 0.4826)
		(drill 0.254)
		(layers "F.Cu" "B.Cu")
		(net "GND")
	)
	(via
		(at 291.162486 -219.860114)
		(size 0.4826)
		(drill 0.254)
		(layers "F.Cu" "B.Cu")
		(net "GND")
	)
	(via
		(at 96.74098 -246.10441)
		(size 0.4064)
		(drill 0.2032)
		(layers "F.Cu" "B.Cu")
		(net "GND")
	)
	(via
		(at 373.976646 -184.683146)
		(size 0.49022)
		(drill 0.254)
		(layers "F.Cu" "B.Cu")
		(net "GND")
	)
	(via
		(at 317.249556 -439.651394)
		(size 0.4572)
		(drill 0.2032)
		(layers "F.Cu" "B.Cu")
		(net "GND")
	)
	(via
		(at 391.674858 -233.14406)
		(size 0.4064)
		(drill 0.2032)
		(layers "F.Cu" "B.Cu")
		(net "GND")
	)
	(via
		(at 83.88096 -271.656302)
		(size 0.4064)
		(drill 0.2032)
		(layers "F.Cu" "B.Cu")
		(net "GND")
	)
	(via
		(at 239.014 -282.081478)
		(size 0.508)
		(drill 0.254)
		(layers "F.Cu" "B.Cu")
		(net "GND")
	)
	(via
		(at 379.924818 -235.574078)
		(size 0.4064)
		(drill 0.2032)
		(layers "F.Cu" "B.Cu")
		(net "GND")
	)
	(via
		(at 110.671102 -287.046162)
		(size 0.4064)
		(drill 0.2032)
		(layers "F.Cu" "B.Cu")
		(net "GND")
	)
	(via
		(at 242.57 -323.85)
		(size 0.508)
		(drill 0.254)
		(layers "F.Cu" "B.Cu")
		(net "GND")
	)
	(via
		(at 191.111886 -107.063032)
		(size 0.4572)
		(drill 0.254)
		(layers "F.Cu" "B.Cu")
		(net "GND")
	)
	(via
		(at 214.686134 -54.999128)
		(size 0.508)
		(drill 0.254)
		(layers "F.Cu" "B.Cu")
		(net "GND")
	)
	(via
		(at 18.231866 -40.943276)
		(size 0.508)
		(drill 0.254)
		(layers "F.Cu" "B.Cu")
		(net "GND")
	)
	(via
		(at 64.532764 -404.46452)
		(size 0.4064)
		(drill 0.2032)
		(layers "F.Cu" "B.Cu")
		(net "GND")
	)
	(via
		(at 15.68577 -390.8425)
		(size 0.49022)
		(drill 0.254)
		(layers "F.Cu" "B.Cu")
		(net "GND")
	)
	(via
		(at 56.712358 -278.085296)
		(size 0.4826)
		(drill 0.254)
		(layers "F.Cu" "B.Cu")
		(net "GND")
	)
	(via
		(at 418.809678 -356.469696)
		(size 0.508)
		(drill 0.254)
		(layers "F.Cu" "B.Cu")
		(net "GND")
	)
	(via
		(at 428.573692 -220.709998)
		(size 0.4826)
		(drill 0.254)
		(layers "F.Cu" "B.Cu")
		(net "GND")
	)
	(via
		(at 386.504942 -227.474272)
		(size 0.4064)
		(drill 0.2032)
		(layers "F.Cu" "B.Cu")
		(net "GND")
	)
	(via
		(at 394.982954 -264.910062)
		(size 0.4064)
		(drill 0.2032)
		(layers "F.Cu" "B.Cu")
		(net "GND")
	)
	(via
		(at 317.249556 -430.147222)
		(size 0.4572)
		(drill 0.2032)
		(layers "F.Cu" "B.Cu")
		(net "GND")
	)
	(via
		(at 139.504674 -250.15444)
		(size 0.4064)
		(drill 0.2032)
		(layers "F.Cu" "B.Cu")
		(net "GND")
	)
	(via
		(at 153.006298 -386.449062)
		(size 0.4064)
		(drill 0.2032)
		(layers "F.Cu" "B.Cu")
		(net "GND")
	)
	(via
		(at 360.465624 -385.514088)
		(size 0.508)
		(drill 0.254)
		(layers "F.Cu" "B.Cu")
		(net "GND")
	)
	(via
		(at 329.361038 -412.212536)
		(size 0.4572)
		(drill 0.254)
		(layers "F.Cu" "B.Cu")
		(net "GND")
	)
	(via
		(at 363.774736 -289.475926)
		(size 0.4064)
		(drill 0.2032)
		(layers "F.Cu" "B.Cu")
		(net "GND")
	)
	(via
		(at 425.10202 -389.405368)
		(size 0.508)
		(drill 0.254)
		(layers "F.Cu" "B.Cu")
		(net "GND")
	)
	(via
		(at 383.514854 -281.37612)
		(size 0.4064)
		(drill 0.2032)
		(layers "F.Cu" "B.Cu")
		(net "GND")
	)
	(via
		(at 89.690956 -245.294404)
		(size 0.4064)
		(drill 0.2032)
		(layers "F.Cu" "B.Cu")
		(net "GND")
	)
	(via
		(at 188.177678 -276.81047)
		(size 0.4826)
		(drill 0.254)
		(layers "F.Cu" "B.Cu")
		(net "GND")
	)
	(via
		(at 381.804926 -243.674138)
		(size 0.4064)
		(drill 0.2032)
		(layers "F.Cu" "B.Cu")
		(net "GND")
	)
	(via
		(at 24.214582 -5.597398)
		(size 0.508)
		(drill 0.254)
		(layers "F.Cu" "B.Cu")
		(net "GND")
	)
	(via
		(at 95.800926 -223.424496)
		(size 0.4064)
		(drill 0.2032)
		(layers "F.Cu" "B.Cu")
		(net "GND")
	)
	(via
		(at 127.284734 -245.294404)
		(size 0.4064)
		(drill 0.2032)
		(layers "F.Cu" "B.Cu")
		(net "GND")
	)
	(via
		(at 20.32 -432.4223)
		(size 0.508)
		(drill 0.254)
		(layers "F.Cu" "B.Cu")
		(net "GND")
	)
	(via
		(at 90.209116 -410.664152)
		(size 0.4572)
		(drill 0.254)
		(layers "F.Cu" "B.Cu")
		(net "GND")
	)
	(via
		(at 35.07486 -112.2426)
		(size 0.508)
		(drill 0.254)
		(layers "F.Cu" "B.Cu")
		(net "GND")
	)
	(via
		(at 140.744702 -265.98626)
		(size 0.4064)
		(drill 0.2032)
		(layers "F.Cu" "B.Cu")
		(net "GND")
	)
	(via
		(at 105.500932 -284.616398)
		(size 0.4064)
		(drill 0.2032)
		(layers "F.Cu" "B.Cu")
		(net "GND")
	)
	(via
		(at 105.031032 -270.846296)
		(size 0.4064)
		(drill 0.2032)
		(layers "F.Cu" "B.Cu")
		(net "GND")
	)
	(via
		(at 436.384446 -312.935112)
		(size 0.4826)
		(drill 0.254)
		(layers "F.Cu" "B.Cu")
		(net "GND")
	)
	(via
		(at 137.154666 -246.10441)
		(size 0.4064)
		(drill 0.2032)
		(layers "F.Cu" "B.Cu")
		(net "GND")
	)
	(via
		(at 141.854682 -233.144314)
		(size 0.4064)
		(drill 0.2032)
		(layers "F.Cu" "B.Cu")
		(net "GND")
	)
	(via
		(at 137.36574 -387.084062)
		(size 0.508)
		(drill 0.254)
		(layers "F.Cu" "B.Cu")
		(net "GND")
	)
	(via
		(at 436.117746 -211.360004)
		(size 0.4826)
		(drill 0.254)
		(layers "F.Cu" "B.Cu")
		(net "GND")
	)
	(via
		(at 437.715914 -293.384986)
		(size 0.4826)
		(drill 0.254)
		(layers "F.Cu" "B.Cu")
		(net "GND")
	)
	(via
		(at 422.29024 -377.41733)
		(size 0.508)
		(drill 0.254)
		(layers "F.Cu" "B.Cu")
		(net "GND")
	)
	(via
		(at 101.74097 -294.336216)
		(size 0.4064)
		(drill 0.2032)
		(layers "F.Cu" "B.Cu")
		(net "GND")
	)
	(via
		(at 144.99844 -32.38754)
		(size 0.508)
		(drill 0.254)
		(layers "F.Cu" "B.Cu")
		(net "GND")
	)
	(via
		(at 340.75116 -293.525956)
		(size 0.4064)
		(drill 0.2032)
		(layers "F.Cu" "B.Cu")
		(net "GND")
	)
	(via
		(at 369.884706 -285.42615)
		(size 0.4064)
		(drill 0.2032)
		(layers "F.Cu" "B.Cu")
		(net "GND")
	)
	(via
		(at 41.87698 -112.10544)
		(size 0.508)
		(drill 0.254)
		(layers "F.Cu" "B.Cu")
		(net "GND")
	)
	(via
		(at 339.040978 -249.34418)
		(size 0.4064)
		(drill 0.2032)
		(layers "F.Cu" "B.Cu")
		(net "GND")
	)
	(via
		(at 451.46468 -4.954524)
		(size 0.508)
		(drill 0.254)
		(layers "F.Cu" "B.Cu")
		(net "GND")
	)
	(via
		(at 343.3445 -18.497804)
		(size 0.508)
		(drill 0.254)
		(layers "F.Cu" "B.Cu")
		(net "GND")
	)
	(via
		(at 382.94945 -421.586152)
		(size 0.4572)
		(drill 0.254)
		(layers "F.Cu" "B.Cu")
		(net "GND")
	)
	(via
		(at 304.652426 -312.935112)
		(size 0.4826)
		(drill 0.254)
		(layers "F.Cu" "B.Cu")
		(net "GND")
	)
	(via
		(at 35.411664 -237.285276)
		(size 0.4826)
		(drill 0.254)
		(layers "F.Cu" "B.Cu")
		(net "GND")
	)
	(via
		(at 161.903918 -405.098504)
		(size 0.4572)
		(drill 0.254)
		(layers "F.Cu" "B.Cu")
		(net "GND")
	)
	(via
		(at 119.127778 -264.36828)
		(size 0.4064)
		(drill 0.2032)
		(layers "F.Cu" "B.Cu")
		(net "GND")
	)
	(via
		(at 319.367154 -441.227718)
		(size 0.508)
		(drill 0.254)
		(layers "F.Cu" "B.Cu")
		(net "GND")
	)
	(via
		(at 349.381064 -255.824228)
		(size 0.4064)
		(drill 0.2032)
		(layers "F.Cu" "B.Cu")
		(net "GND")
	)
	(via
		(at 384.349498 -439.651394)
		(size 0.4572)
		(drill 0.2032)
		(layers "F.Cu" "B.Cu")
		(net "GND")
	)
	(via
		(at 56.712358 -306.135278)
		(size 0.4826)
		(drill 0.254)
		(layers "F.Cu" "B.Cu")
		(net "GND")
	)
	(via
		(at 276.098 -121.285)
		(size 0.508)
		(drill 0.254)
		(layers "F.Cu" "B.Cu")
		(net "GND")
	)
	(via
		(at 346.39123 -291.905944)
		(size 0.4064)
		(drill 0.2032)
		(layers "F.Cu" "B.Cu")
		(net "GND")
	)
	(via
		(at 111.608616 -410.247084)
		(size 0.508)
		(drill 0.254)
		(layers "F.Cu" "B.Cu")
		(net "GND")
	)
	(via
		(at 89.690956 -256.634488)
		(size 0.4064)
		(drill 0.2032)
		(layers "F.Cu" "B.Cu")
		(net "GND")
	)
	(via
		(at 233.867452 -335.626202)
		(size 0.508)
		(drill 0.254)
		(layers "F.Cu" "B.Cu")
		(net "GND")
	)
	(via
		(at 434.004212 -349.926656)
		(size 0.49022)
		(drill 0.254)
		(layers "F.Cu" "B.Cu")
		(net "GND")
	)
	(via
		(at 65.703196 -410.664152)
		(size 0.4572)
		(drill 0.254)
		(layers "F.Cu" "B.Cu")
		(net "GND")
	)
	(via
		(at 167.143684 -293.38524)
		(size 0.4826)
		(drill 0.254)
		(layers "F.Cu" "B.Cu")
		(net "GND")
	)
	(via
		(at 44.054014 -372.15953)
		(size 0.508)
		(drill 0.254)
		(layers "F.Cu" "B.Cu")
		(net "GND")
	)
	(via
		(at 203.532232 -228.78542)
		(size 0.4826)
		(drill 0.254)
		(layers "F.Cu" "B.Cu")
		(net "GND")
	)
	(via
		(at 428.840392 -231.335072)
		(size 0.4826)
		(drill 0.254)
		(layers "F.Cu" "B.Cu")
		(net "GND")
	)
	(via
		(at 346.249498 -439.651394)
		(size 0.4572)
		(drill 0.2032)
		(layers "F.Cu" "B.Cu")
		(net "GND")
	)
	(via
		(at 424.451018 -356.976172)
		(size 0.508)
		(drill 0.254)
		(layers "F.Cu" "B.Cu")
		(net "GND")
	)
	(via
		(at 191.160146 -246.63527)
		(size 0.4826)
		(drill 0.254)
		(layers "F.Cu" "B.Cu")
		(net "GND")
	)
	(via
		(at 49.791366 -390.160002)
		(size 0.4064)
		(drill 0.2032)
		(layers "F.Cu" "B.Cu")
		(net "GND")
	)
	(via
		(at 36.795964 -213.485222)
		(size 0.4826)
		(drill 0.254)
		(layers "F.Cu" "B.Cu")
		(net "GND")
	)
	(via
		(at 435.000146 -267.885164)
		(size 0.4826)
		(drill 0.254)
		(layers "F.Cu" "B.Cu")
		(net "GND")
	)
	(via
		(at 341.390986 -245.29415)
		(size 0.4064)
		(drill 0.2032)
		(layers "F.Cu" "B.Cu")
		(net "GND")
	)
	(via
		(at 54.78907 -16.9799)
		(size 0.508)
		(drill 0.254)
		(layers "F.Cu" "B.Cu")
		(net "GND")
	)
	(via
		(at 115.834668 -266.796266)
		(size 0.4064)
		(drill 0.2032)
		(layers "F.Cu" "B.Cu")
		(net "GND")
	)
	(via
		(at 344.981784 -380.54153)
		(size 0.508)
		(drill 0.254)
		(layers "F.Cu" "B.Cu")
		(net "GND")
	)
	(via
		(at 25.152096 -204.985366)
		(size 0.4826)
		(drill 0.254)
		(layers "F.Cu" "B.Cu")
		(net "GND")
	)
	(via
		(at 359.737914 -177.198274)
		(size 0.508)
		(drill 0.254)
		(layers "F.Cu" "B.Cu")
		(net "GND")
	)
	(via
		(at 78.41107 -235.574332)
		(size 0.4064)
		(drill 0.2032)
		(layers "F.Cu" "B.Cu")
		(net "GND")
	)
	(via
		(at 197.3199 -305.285394)
		(size 0.4826)
		(drill 0.254)
		(layers "F.Cu" "B.Cu")
		(net "GND")
	)
	(via
		(at 169.645584 -275.960332)
		(size 0.4826)
		(drill 0.254)
		(layers "F.Cu" "B.Cu")
		(net "GND")
	)
	(via
		(at 41.62425 -275.53539)
		(size 0.4826)
		(drill 0.254)
		(layers "F.Cu" "B.Cu")
		(net "GND")
	)
	(via
		(at 40.23995 -208.38541)
		(size 0.4826)
		(drill 0.254)
		(layers "F.Cu" "B.Cu")
		(net "GND")
	)
	(via
		(at 290.895786 -286.585152)
		(size 0.4826)
		(drill 0.254)
		(layers "F.Cu" "B.Cu")
		(net "GND")
	)
	(via
		(at 121.174764 -254.20447)
		(size 0.4064)
		(drill 0.2032)
		(layers "F.Cu" "B.Cu")
		(net "GND")
	)
	(via
		(at 187.060078 -208.38541)
		(size 0.4826)
		(drill 0.254)
		(layers "F.Cu" "B.Cu")
		(net "GND")
	)
	(via
		(at 46.666404 -304.860452)
		(size 0.4826)
		(drill 0.254)
		(layers "F.Cu" "B.Cu")
		(net "GND")
	)
	(via
		(at 298.43984 -199.885046)
		(size 0.4826)
		(drill 0.254)
		(layers "F.Cu" "B.Cu")
		(net "GND")
	)
	(via
		(at 21.773388 -371.36705)
		(size 0.508)
		(drill 0.254)
		(layers "F.Cu" "B.Cu")
		(net "GND")
	)
	(via
		(at 14.875256 -398.833086)
		(size 0.508)
		(drill 0.254)
		(layers "F.Cu" "B.Cu")
		(net "GND")
	)
	(via
		(at 299.82414 -297.635168)
		(size 0.4826)
		(drill 0.254)
		(layers "F.Cu" "B.Cu")
		(net "GND")
	)
	(via
		(at 116.998496 -62.002162)
		(size 0.508)
		(drill 0.254)
		(layers "F.Cu" "B.Cu")
		(net "GND")
	)
	(via
		(at 265.54811 -247.485154)
		(size 0.4826)
		(drill 0.254)
		(layers "F.Cu" "B.Cu")
		(net "GND")
	)
	(via
		(at 249.54357 -69.962522)
		(size 0.508)
		(drill 0.254)
		(layers "F.Cu" "B.Cu")
		(net "GND")
	)
	(via
		(at 188.90996 -420.961058)
		(size 0.508)
		(drill 0.254)
		(layers "F.Cu" "B.Cu")
		(net "GND")
	)
	(via
		(at 415.7472 -110.739428)
		(size 0.508)
		(drill 0.254)
		(layers "F.Cu" "B.Cu")
		(net "GND")
	)
	(via
		(at 20.59051 -219.860368)
		(size 0.4826)
		(drill 0.254)
		(layers "F.Cu" "B.Cu")
		(net "GND")
	)
	(via
		(at 108.961174 -229.90429)
		(size 0.4064)
		(drill 0.2032)
		(layers "F.Cu" "B.Cu")
		(net "GND")
	)
	(via
		(at 363.87024 -389.7122)
		(size 0.508)
		(drill 0.254)
		(layers "F.Cu" "B.Cu")
		(net "GND")
	)
	(via
		(at 144.974818 -268.416278)
		(size 0.4064)
		(drill 0.2032)
		(layers "F.Cu" "B.Cu")
		(net "GND")
	)
	(via
		(at 332.931008 -238.814102)
		(size 0.4064)
		(drill 0.2032)
		(layers "F.Cu" "B.Cu")
		(net "GND")
	)
	(via
		(at 398.214596 -4.963414)
		(size 0.508)
		(drill 0.254)
		(layers "F.Cu" "B.Cu")
		(net "GND")
	)
	(via
		(at 98.451162 -293.52621)
		(size 0.4064)
		(drill 0.2032)
		(layers "F.Cu" "B.Cu")
		(net "GND")
	)
	(via
		(at 418.355526 -10.16508)
		(size 0.508)
		(drill 0.254)
		(layers "F.Cu" "B.Cu")
		(net "GND")
	)
	(via
		(at 83.580986 -226.66452)
		(size 0.4064)
		(drill 0.2032)
		(layers "F.Cu" "B.Cu")
		(net "GND")
	)
	(via
		(at 378.04471 -255.014222)
		(size 0.4064)
		(drill 0.2032)
		(layers "F.Cu" "B.Cu")
		(net "GND")
	)
	(via
		(at 273.092164 -245.785132)
		(size 0.4826)
		(drill 0.254)
		(layers "F.Cu" "B.Cu")
		(net "GND")
	)
	(via
		(at 239.55629 -248.190766)
		(size 0.4826)
		(drill 0.254)
		(layers "F.Cu" "B.Cu")
		(net "GND")
	)
	(via
		(at 91.871038 -274.08632)
		(size 0.4064)
		(drill 0.2032)
		(layers "F.Cu" "B.Cu")
		(net "GND")
	)
	(via
		(at 81.632298 -332.409038)
		(size 0.508)
		(drill 0.254)
		(layers "F.Cu" "B.Cu")
		(net "GND")
	)
	(via
		(at 40.61714 -425.909994)
		(size 0.508)
		(drill 0.254)
		(layers "F.Cu" "B.Cu")
		(net "GND")
	)
	(via
		(at 337.461098 -268.416024)
		(size 0.4064)
		(drill 0.2032)
		(layers "F.Cu" "B.Cu")
		(net "GND")
	)
	(via
		(at 133.694678 -263.556242)
		(size 0.4064)
		(drill 0.2032)
		(layers "F.Cu" "B.Cu")
		(net "GND")
	)
	(via
		(at 192.277746 -285.310326)
		(size 0.4826)
		(drill 0.254)
		(layers "F.Cu" "B.Cu")
		(net "GND")
	)
	(via
		(at 20.55241 -192.218564)
		(size 0.4826)
		(drill 0.254)
		(layers "F.Cu" "B.Cu")
		(net "GND")
	)
	(via
		(at 70.570852 -409.396184)
		(size 0.4572)
		(drill 0.254)
		(layers "F.Cu" "B.Cu")
		(net "GND")
	)
	(via
		(at 180.836316 -329.576684)
		(size 0.508)
		(drill 0.254)
		(layers "F.Cu" "B.Cu")
		(net "GND")
	)
	(via
		(at 373.316246 -184.683146)
		(size 0.49022)
		(drill 0.254)
		(layers "F.Cu" "B.Cu")
		(net "GND")
	)
	(via
		(at 334.249522 -437.34736)
		(size 0.4572)
		(drill 0.2032)
		(layers "F.Cu" "B.Cu")
		(net "GND")
	)
	(via
		(at 332.338426 -418.412168)
		(size 0.4064)
		(drill 0.2032)
		(layers "F.Cu" "B.Cu")
		(net "GND")
	)
	(via
		(at 73.722484 -404.46452)
		(size 0.4064)
		(drill 0.2032)
		(layers "F.Cu" "B.Cu")
		(net "GND")
	)
	(via
		(at 105.971086 -288.666174)
		(size 0.4064)
		(drill 0.2032)
		(layers "F.Cu" "B.Cu")
		(net "GND")
	)
	(via
		(at 295.724072 -272.135092)
		(size 0.4826)
		(drill 0.254)
		(layers "F.Cu" "B.Cu")
		(net "GND")
	)
	(via
		(at 137.374122 -6.042152)
		(size 0.508)
		(drill 0.254)
		(layers "F.Cu" "B.Cu")
		(net "GND")
	)
	(via
		(at 99.090988 -230.71455)
		(size 0.4064)
		(drill 0.2032)
		(layers "F.Cu" "B.Cu")
		(net "GND")
	)
	(via
		(at 138.394694 -268.416278)
		(size 0.4064)
		(drill 0.2032)
		(layers "F.Cu" "B.Cu")
		(net "GND")
	)
	(via
		(at 83.41106 -285.426404)
		(size 0.4064)
		(drill 0.2032)
		(layers "F.Cu" "B.Cu")
		(net "GND")
	)
	(via
		(at 105.905046 -339.525102)
		(size 0.49022)
		(drill 0.254)
		(layers "F.Cu" "B.Cu")
		(net "GND")
	)
	(via
		(at 456.249278 -396.55877)
		(size 0.49022)
		(drill 0.254)
		(layers "F.Cu" "B.Cu")
		(net "GND")
	)
	(via
		(at 176.072038 -224.535238)
		(size 0.4826)
		(drill 0.254)
		(layers "F.Cu" "B.Cu")
		(net "GND")
	)
	(via
		(at 139.038076 -375.917968)
		(size 0.508)
		(drill 0.254)
		(layers "F.Cu" "B.Cu")
		(net "GND")
	)
	(via
		(at 457.105766 -50.51298)
		(size 0.508)
		(drill 0.254)
		(layers "F.Cu" "B.Cu")
		(net "GND")
	)
	(via
		(at 341.090504 -376.75693)
		(size 0.508)
		(drill 0.254)
		(layers "F.Cu" "B.Cu")
		(net "GND")
	)
	(via
		(at 63.24981 -427.851316)
		(size 0.4572)
		(drill 0.2032)
		(layers "F.Cu" "B.Cu")
		(net "GND")
	)
	(via
		(at 73.276714 -331.75575)
		(size 0.508)
		(drill 0.254)
		(layers "F.Cu" "B.Cu")
		(net "GND")
	)
	(via
		(at 106.405172 -260.280404)
		(size 0.4826)
		(drill 0.254)
		(layers "F.Cu" "B.Cu")
		(net "GND")
	)
	(via
		(at 375.29135 -414.752536)
		(size 0.4572)
		(drill 0.254)
		(layers "F.Cu" "B.Cu")
		(net "GND")
	)
	(via
		(at 78.41107 -240.434368)
		(size 0.4064)
		(drill 0.2032)
		(layers "F.Cu" "B.Cu")
		(net "GND")
	)
	(via
		(at 347.801184 -291.095938)
		(size 0.4064)
		(drill 0.2032)
		(layers "F.Cu" "B.Cu")
		(net "GND")
	)
	(via
		(at 379.924818 -227.474272)
		(size 0.4064)
		(drill 0.2032)
		(layers "F.Cu" "B.Cu")
		(net "GND")
	)
	(via
		(at 363.944916 -240.434114)
		(size 0.4064)
		(drill 0.2032)
		(layers "F.Cu" "B.Cu")
		(net "GND")
	)
	(via
		(at 350.321118 -246.104156)
		(size 0.4064)
		(drill 0.2032)
		(layers "F.Cu" "B.Cu")
		(net "GND")
	)
	(via
		(at 137.670794 -406.370536)
		(size 0.4572)
		(drill 0.254)
		(layers "F.Cu" "B.Cu")
		(net "GND")
	)
	(via
		(at 113.434114 -182.076598)
		(size 0.508)
		(drill 0.254)
		(layers "F.Cu" "B.Cu")
		(net "GND")
	)
	(via
		(at 302.150526 -304.860198)
		(size 0.4826)
		(drill 0.254)
		(layers "F.Cu" "B.Cu")
		(net "GND")
	)
	(via
		(at 123.994672 -244.484398)
		(size 0.4064)
		(drill 0.2032)
		(layers "F.Cu" "B.Cu")
		(net "GND")
	)
	(via
		(at 59.428126 -297.635422)
		(size 0.4826)
		(drill 0.254)
		(layers "F.Cu" "B.Cu")
		(net "GND")
	)
	(via
		(at 115.045236 -374.62333)
		(size 0.508)
		(drill 0.254)
		(layers "F.Cu" "B.Cu")
		(net "GND")
	)
	(via
		(at 40.23995 -309.535322)
		(size 0.4826)
		(drill 0.254)
		(layers "F.Cu" "B.Cu")
		(net "GND")
	)
	(via
		(at 57.09793 -19.13636)
		(size 0.508)
		(drill 0.254)
		(layers "F.Cu" "B.Cu")
		(net "GND")
	)
	(via
		(at 108.09097 -23.371556)
		(size 0.508)
		(drill 0.254)
		(layers "F.Cu" "B.Cu")
		(net "GND")
	)
	(via
		(at 94.39021 -384.617722)
		(size 0.4064)
		(drill 0.2032)
		(layers "F.Cu" "B.Cu")
		(net "GND")
	)
	(via
		(at 370.054886 -221.80423)
		(size 0.4064)
		(drill 0.2032)
		(layers "F.Cu" "B.Cu")
		(net "GND")
	)
	(via
		(at 288.180018 -236.435138)
		(size 0.4826)
		(drill 0.254)
		(layers "F.Cu" "B.Cu")
		(net "GND")
	)
	(via
		(at 2.76225 -193.985134)
		(size 0.508)
		(drill 0.254)
		(layers "F.Cu" "B.Cu")
		(net "GND")
	)
	(via
		(at 187.144914 -10.117328)
		(size 0.508)
		(drill 0.254)
		(layers "F.Cu" "B.Cu")
		(net "GND")
	)
	(via
		(at 92.013532 -406.34666)
		(size 0.4572)
		(drill 0.254)
		(layers "F.Cu" "B.Cu")
		(net "GND")
	)
	(via
		(at 195.988432 -238.135414)
		(size 0.4826)
		(drill 0.254)
		(layers "F.Cu" "B.Cu")
		(net "GND")
	)
	(via
		(at 117.44071 -255.53035)
		(size 0.4826)
		(drill 0.254)
		(layers "F.Cu" "B.Cu")
		(net "GND")
	)
	(via
		(at 202.147932 -281.48534)
		(size 0.4826)
		(drill 0.254)
		(layers "F.Cu" "B.Cu")
		(net "GND")
	)
	(via
		(at 274.607782 -117.225064)
		(size 0.508)
		(drill 0.254)
		(layers "F.Cu" "B.Cu")
		(net "GND")
	)
	(via
		(at 363.944916 -245.29415)
		(size 0.4064)
		(drill 0.2032)
		(layers "F.Cu" "B.Cu")
		(net "GND")
	)
	(via
		(at 419.889432 -4.32943)
		(size 0.508)
		(drill 0.254)
		(layers "F.Cu" "B.Cu")
		(net "GND")
	)
	(via
		(at 168.527984 -316.33541)
		(size 0.4826)
		(drill 0.254)
		(layers "F.Cu" "B.Cu")
		(net "GND")
	)
	(via
		(at 202.147932 -236.435392)
		(size 0.4826)
		(drill 0.254)
		(layers "F.Cu" "B.Cu")
		(net "GND")
	)
	(via
		(at 90.461084 -295.956228)
		(size 0.4064)
		(drill 0.2032)
		(layers "F.Cu" "B.Cu")
		(net "GND")
	)
	(via
		(at 452.619364 -31.369254)
		(size 0.508)
		(drill 0.254)
		(layers "F.Cu" "B.Cu")
		(net "GND")
	)
	(via
		(at 303.596294 -420.318184)
		(size 0.4572)
		(drill 0.254)
		(layers "F.Cu" "B.Cu")
		(net "GND")
	)
	(via
		(at 198.7042 -250.035314)
		(size 0.4826)
		(drill 0.254)
		(layers "F.Cu" "B.Cu")
		(net "GND")
	)
	(via
		(at 193.002916 -330.135484)
		(size 0.508)
		(drill 0.254)
		(layers "F.Cu" "B.Cu")
		(net "GND")
	)
	(via
		(at 373.644922 -262.745982)
		(size 0.4064)
		(drill 0.2032)
		(layers "F.Cu" "B.Cu")
		(net "GND")
	)
	(via
		(at 419.34384 -16.979138)
		(size 0.508)
		(drill 0.254)
		(layers "F.Cu" "B.Cu")
		(net "GND")
	)
	(via
		(at 395.20241 -412.212536)
		(size 0.4572)
		(drill 0.254)
		(layers "F.Cu" "B.Cu")
		(net "GND")
	)
	(via
		(at 308.262274 -392.999722)
		(size 0.4064)
		(drill 0.2032)
		(layers "F.Cu" "B.Cu")
		(net "GND")
	)
	(via
		(at 55.328058 -300.185328)
		(size 0.4826)
		(drill 0.254)
		(layers "F.Cu" "B.Cu")
		(net "GND")
	)
	(via
		(at 337.631024 -242.054126)
		(size 0.4064)
		(drill 0.2032)
		(layers "F.Cu" "B.Cu")
		(net "GND")
	)
	(via
		(at 366.764824 -232.334054)
		(size 0.4064)
		(drill 0.2032)
		(layers "F.Cu" "B.Cu")
		(net "GND")
	)
	(via
		(at 358.311196 -229.094284)
		(size 0.4064)
		(drill 0.2032)
		(layers "F.Cu" "B.Cu")
		(net "GND")
	)
	(via
		(at 367.290858 -396.679674)
		(size 0.508)
		(drill 0.254)
		(layers "F.Cu" "B.Cu")
		(net "GND")
	)
	(via
		(at 437.715914 -312.084974)
		(size 0.4826)
		(drill 0.254)
		(layers "F.Cu" "B.Cu")
		(net "GND")
	)
	(via
		(at 76.581762 -370.83873)
		(size 0.508)
		(drill 0.254)
		(layers "F.Cu" "B.Cu")
		(net "GND")
	)
	(via
		(at 361.424728 -280.566114)
		(size 0.4064)
		(drill 0.2032)
		(layers "F.Cu" "B.Cu")
		(net "GND")
	)
	(via
		(at 339.485732 -161.981134)
		(size 0.49022)
		(drill 0.254)
		(layers "F.Cu" "B.Cu")
		(net "GND")
	)
	(via
		(at 15.333218 -16.979138)
		(size 0.508)
		(drill 0.254)
		(layers "F.Cu" "B.Cu")
		(net "GND")
	)
	(via
		(at 392.13917 -420.318184)
		(size 0.4572)
		(drill 0.254)
		(layers "F.Cu" "B.Cu")
		(net "GND")
	)
	(via
		(at 102.681024 -291.096192)
		(size 0.4064)
		(drill 0.2032)
		(layers "F.Cu" "B.Cu")
		(net "GND")
	)
	(via
		(at 131.98475 -224.234502)
		(size 0.4064)
		(drill 0.2032)
		(layers "F.Cu" "B.Cu")
		(net "GND")
	)
	(via
		(at 177.927 -138.648948)
		(size 0.508)
		(drill 0.254)
		(layers "F.Cu" "B.Cu")
		(net "GND")
	)
	(via
		(at 412.367984 -225.385122)
		(size 0.4826)
		(drill 0.254)
		(layers "F.Cu" "B.Cu")
		(net "GND")
	)
	(via
		(at 347.801184 -274.896072)
		(size 0.4064)
		(drill 0.2032)
		(layers "F.Cu" "B.Cu")
		(net "GND")
	)
	(via
		(at 142.154656 -270.03629)
		(size 0.4064)
		(drill 0.2032)
		(layers "F.Cu" "B.Cu")
		(net "GND")
	)
	(via
		(at 98.981514 -332.44536)
		(size 0.508)
		(drill 0.254)
		(layers "F.Cu" "B.Cu")
		(net "GND")
	)
	(via
		(at 355.961188 -238.004096)
		(size 0.4064)
		(drill 0.2032)
		(layers "F.Cu" "B.Cu")
		(net "GND")
	)
	(via
		(at 203.532232 -231.335326)
		(size 0.4826)
		(drill 0.254)
		(layers "F.Cu" "B.Cu")
		(net "GND")
	)
	(via
		(at 98.150934 -224.234502)
		(size 0.4064)
		(drill 0.2032)
		(layers "F.Cu" "B.Cu")
		(net "GND")
	)
	(via
		(at 305.646836 -379.22073)
		(size 0.508)
		(drill 0.254)
		(layers "F.Cu" "B.Cu")
		(net "GND")
	)
	(via
		(at 140.274802 -268.416278)
		(size 0.4064)
		(drill 0.2032)
		(layers "F.Cu" "B.Cu")
		(net "GND")
	)
	(via
		(at 416.468052 -205.834996)
		(size 0.4826)
		(drill 0.254)
		(layers "F.Cu" "B.Cu")
		(net "GND")
	)
	(via
		(at 114.59464 -241.244374)
		(size 0.4064)
		(drill 0.2032)
		(layers "F.Cu" "B.Cu")
		(net "GND")
	)
	(via
		(at 132.694172 -34.841434)
		(size 0.508)
		(drill 0.254)
		(layers "F.Cu" "B.Cu")
		(net "GND")
	)
	(via
		(at 122.884692 -282.18638)
		(size 0.4064)
		(drill 0.2032)
		(layers "F.Cu" "B.Cu")
		(net "GND")
	)
	(via
		(at 83.88096 -263.556242)
		(size 0.4064)
		(drill 0.2032)
		(layers "F.Cu" "B.Cu")
		(net "GND")
	)
	(via
		(at 74.61885 -381.3302)
		(size 0.508)
		(drill 0.254)
		(layers "F.Cu" "B.Cu")
		(net "GND")
	)
	(via
		(at 344.041222 -294.335962)
		(size 0.4064)
		(drill 0.2032)
		(layers "F.Cu" "B.Cu")
		(net "GND")
	)
	(via
		(at 180.900324 -200.735438)
		(size 0.4826)
		(drill 0.254)
		(layers "F.Cu" "B.Cu")
		(net "GND")
	)
	(via
		(at 98.643694 -328.603102)
		(size 0.508)
		(drill 0.254)
		(layers "F.Cu" "B.Cu")
		(net "GND")
	)
	(via
		(at 105.500932 -273.276314)
		(size 0.4064)
		(drill 0.2032)
		(layers "F.Cu" "B.Cu")
		(net "GND")
	)
	(via
		(at 155.349702 -430.299622)
		(size 0.4572)
		(drill 0.2032)
		(layers "F.Cu" "B.Cu")
		(net "GND")
	)
	(via
		(at 155.84424 -391.830814)
		(size 0.4064)
		(drill 0.2032)
		(layers "F.Cu" "B.Cu")
		(net "GND")
	)
	(via
		(at 134.726172 -35.857434)
		(size 0.508)
		(drill 0.254)
		(layers "F.Cu" "B.Cu")
		(net "GND")
	)
	(via
		(at 58.665618 -7.215124)
		(size 0.508)
		(drill 0.254)
		(layers "F.Cu" "B.Cu")
		(net "GND")
	)
	(via
		(at 102.002082 -382.237488)
		(size 0.508)
		(drill 0.254)
		(layers "F.Cu" "B.Cu")
		(net "GND")
	)
	(via
		(at 83.580986 -254.20447)
		(size 0.4064)
		(drill 0.2032)
		(layers "F.Cu" "B.Cu")
		(net "GND")
	)
	(via
		(at 113.56848 -382.908048)
		(size 0.4064)
		(drill 0.2032)
		(layers "F.Cu" "B.Cu")
		(net "GND")
	)
	(via
		(at 233.016044 -42.418)
		(size 0.508)
		(drill 0.254)
		(layers "F.Cu" "B.Cu")
		(net "GND")
	)
	(via
		(at 393.084812 -229.094284)
		(size 0.4064)
		(drill 0.2032)
		(layers "F.Cu" "B.Cu")
		(net "GND")
	)
	(via
		(at 325.580756 -378.07773)
		(size 0.508)
		(drill 0.254)
		(layers "F.Cu" "B.Cu")
		(net "GND")
	)
	(via
		(at 83.111086 -248.534428)
		(size 0.4064)
		(drill 0.2032)
		(layers "F.Cu" "B.Cu")
		(net "GND")
	)
	(via
		(at 69.249798 -433.747164)
		(size 0.4572)
		(drill 0.2032)
		(layers "F.Cu" "B.Cu")
		(net "GND")
	)
	(via
		(at 12.92352 -358.791002)
		(size 0.508)
		(drill 0.254)
		(layers "F.Cu" "B.Cu")
		(net "GND")
	)
	(via
		(at 346.39123 -267.606018)
		(size 0.4064)
		(drill 0.2032)
		(layers "F.Cu" "B.Cu")
		(net "GND")
	)
	(via
		(at 202.147932 -262.785352)
		(size 0.4826)
		(drill 0.254)
		(layers "F.Cu" "B.Cu")
		(net "GND")
	)
	(via
		(at 407.349706 -431.451258)
		(size 0.4572)
		(drill 0.2032)
		(layers "F.Cu" "B.Cu")
		(net "GND")
	)
	(via
		(at 391.974832 -270.036036)
		(size 0.4064)
		(drill 0.2032)
		(layers "F.Cu" "B.Cu")
		(net "GND")
	)
	(via
		(at 79.821024 -247.724422)
		(size 0.4064)
		(drill 0.2032)
		(layers "F.Cu" "B.Cu")
		(net "GND")
	)
	(via
		(at 358.311196 -242.054126)
		(size 0.4064)
		(drill 0.2032)
		(layers "F.Cu" "B.Cu")
		(net "GND")
	)
	(via
		(at 402.759164 -17.61236)
		(size 0.508)
		(drill 0.254)
		(layers "F.Cu" "B.Cu")
		(net "GND")
	)
	(via
		(at 61.249814 -437.34736)
		(size 0.4572)
		(drill 0.2032)
		(layers "F.Cu" "B.Cu")
		(net "GND")
	)
	(via
		(at 157.044136 -382.85293)
		(size 0.4064)
		(drill 0.2032)
		(layers "F.Cu" "B.Cu")
		(net "GND")
	)
	(via
		(at 351.091246 -285.42615)
		(size 0.4064)
		(drill 0.2032)
		(layers "F.Cu" "B.Cu")
		(net "GND")
	)
	(via
		(at 148.844 -205.450948)
		(size 0.508)
		(drill 0.254)
		(layers "F.Cu" "B.Cu")
		(net "GND")
	)
	(via
		(at 409.741116 -174.812452)
		(size 0.508)
		(drill 0.254)
		(layers "F.Cu" "B.Cu")
		(net "GND")
	)
	(via
		(at 134.981696 -369.03533)
		(size 0.508)
		(drill 0.254)
		(layers "F.Cu" "B.Cu")
		(net "GND")
	)
	(via
		(at 45.755814 -369.69573)
		(size 0.508)
		(drill 0.254)
		(layers "F.Cu" "B.Cu")
		(net "GND")
	)
	(via
		(at 104.090978 -285.426404)
		(size 0.4064)
		(drill 0.2032)
		(layers "F.Cu" "B.Cu")
		(net "GND")
	)
	(via
		(at 351.091246 -288.66592)
		(size 0.4064)
		(drill 0.2032)
		(layers "F.Cu" "B.Cu")
		(net "GND")
	)
	(via
		(at 414.840674 -420.318184)
		(size 0.4572)
		(drill 0.254)
		(layers "F.Cu" "B.Cu")
		(net "GND")
	)
	(via
		(at 51.884072 -251.735336)
		(size 0.4826)
		(drill 0.254)
		(layers "F.Cu" "B.Cu")
		(net "GND")
	)
	(via
		(at 87.504524 -407.00452)
		(size 0.4064)
		(drill 0.2032)
		(layers "F.Cu" "B.Cu")
		(net "GND")
	)
	(via
		(at 317.469266 -412.84652)
		(size 0.4064)
		(drill 0.2032)
		(layers "F.Cu" "B.Cu")
		(net "GND")
	)
	(via
		(at 43.222418 -294.66032)
		(size 0.4826)
		(drill 0.254)
		(layers "F.Cu" "B.Cu")
		(net "GND")
	)
	(via
		(at 375.224802 -230.714296)
		(size 0.4064)
		(drill 0.2032)
		(layers "F.Cu" "B.Cu")
		(net "GND")
	)
	(via
		(at 64.318642 -388.328662)
		(size 0.4064)
		(drill 0.2032)
		(layers "F.Cu" "B.Cu")
		(net "GND")
	)
	(via
		(at 23.230078 -19.13636)
		(size 0.508)
		(drill 0.254)
		(layers "F.Cu" "B.Cu")
		(net "GND")
	)
	(via
		(at 166.26586 -12.495022)
		(size 0.508)
		(drill 0.254)
		(layers "F.Cu" "B.Cu")
		(net "GND")
	)
	(via
		(at 190.60541 -349.381572)
		(size 0.49022)
		(drill 0.254)
		(layers "F.Cu" "B.Cu")
		(net "GND")
	)
	(via
		(at 148.392134 -405.098504)
		(size 0.4572)
		(drill 0.254)
		(layers "F.Cu" "B.Cu")
		(net "GND")
	)
	(via
		(at 143.56461 -274.08632)
		(size 0.4064)
		(drill 0.2032)
		(layers "F.Cu" "B.Cu")
		(net "GND")
	)
	(via
		(at 336.22107 -247.724168)
		(size 0.4064)
		(drill 0.2032)
		(layers "F.Cu" "B.Cu")
		(net "GND")
	)
	(via
		(at 364.955074 -178.92141)
		(size 0.49022)
		(drill 0.254)
		(layers "F.Cu" "B.Cu")
		(net "GND")
	)
	(via
		(at 369.14963 -259.729986)
		(size 0.4826)
		(drill 0.254)
		(layers "F.Cu" "B.Cu")
		(net "GND")
	)
	(via
		(at 79.487776 -403.830536)
		(size 0.4572)
		(drill 0.254)
		(layers "F.Cu" "B.Cu")
		(net "GND")
	)
	(via
		(at 110.200948 -281.376374)
		(size 0.4064)
		(drill 0.2032)
		(layers "F.Cu" "B.Cu")
		(net "GND")
	)
	(via
		(at 80.249776 -431.451258)
		(size 0.4572)
		(drill 0.2032)
		(layers "F.Cu" "B.Cu")
		(net "GND")
	)
	(via
		(at 115.834668 -279.756362)
		(size 0.4064)
		(drill 0.2032)
		(layers "F.Cu" "B.Cu")
		(net "GND")
	)
	(via
		(at 16.490442 -314.210446)
		(size 0.4826)
		(drill 0.254)
		(layers "F.Cu" "B.Cu")
		(net "GND")
	)
	(via
		(at 464.751928 -93.309186)
		(size 0.508)
		(drill 0.254)
		(layers "F.Cu" "B.Cu")
		(net "GND")
	)
	(via
		(at 398.465294 -177.57013)
		(size 0.49022)
		(drill 0.254)
		(layers "F.Cu" "B.Cu")
		(net "GND")
	)
	(via
		(at 277.59787 -346.302076)
		(size 0.49022)
		(drill 0.254)
		(layers "F.Cu" "B.Cu")
		(net "GND")
	)
	(via
		(at 149.535642 -107.683046)
		(size 0.508)
		(drill 0.254)
		(layers "F.Cu" "B.Cu")
		(net "GND")
	)
	(via
		(at 445.259968 -237.285022)
		(size 0.4826)
		(drill 0.254)
		(layers "F.Cu" "B.Cu")
		(net "GND")
	)
	(via
		(at 421.444166 -402.284438)
		(size 0.4572)
		(drill 0.254)
		(layers "F.Cu" "B.Cu")
		(net "GND")
	)
	(via
		(at 88.580976 -295.956228)
		(size 0.4064)
		(drill 0.2032)
		(layers "F.Cu" "B.Cu")
		(net "GND")
	)
	(via
		(at 180.900324 -219.435426)
		(size 0.4826)
		(drill 0.254)
		(layers "F.Cu" "B.Cu")
		(net "GND")
	)
	(via
		(at 203.303632 -194.885564)
		(size 0.4826)
		(drill 0.254)
		(layers "F.Cu" "B.Cu")
		(net "GND")
	)
	(via
		(at 358.437942 -261.32282)
		(size 0.4826)
		(drill 0.254)
		(layers "F.Cu" "B.Cu")
		(net "GND")
	)
	(via
		(at 255.145032 -421.46093)
		(size 0.508)
		(drill 0.254)
		(layers "F.Cu" "B.Cu")
		(net "GND")
	)
	(via
		(at 152.043384 -441.227718)
		(size 0.508)
		(drill 0.254)
		(layers "F.Cu" "B.Cu")
		(net "GND")
	)
	(via
		(at 173.978316 -26.661872)
		(size 0.508)
		(drill 0.254)
		(layers "F.Cu" "B.Cu")
		(net "GND")
	)
	(via
		(at 105.329228 -178.597306)
		(size 0.49022)
		(drill 0.254)
		(layers "F.Cu" "B.Cu")
		(net "GND")
	)
	(via
		(at 197.61962 -332.805786)
		(size 0.508)
		(drill 0.254)
		(layers "F.Cu" "B.Cu")
		(net "GND")
	)
	(via
		(at 133.053074 -24.24303)
		(size 0.508)
		(drill 0.254)
		(layers "F.Cu" "B.Cu")
		(net "GND")
	)
	(via
		(at 425.96816 -9.424924)
		(size 0.508)
		(drill 0.254)
		(layers "F.Cu" "B.Cu")
		(net "GND")
	)
	(via
		(at 59.428126 -299.335444)
		(size 0.4826)
		(drill 0.254)
		(layers "F.Cu" "B.Cu")
		(net "GND")
	)
	(via
		(at 117.17909 -169.935144)
		(size 0.49022)
		(drill 0.254)
		(layers "F.Cu" "B.Cu")
		(net "GND")
	)
	(via
		(at 457.99883 -50.469038)
		(size 0.508)
		(drill 0.254)
		(layers "F.Cu" "B.Cu")
		(net "GND")
	)
	(via
		(at 188.215778 -193.107564)
		(size 0.4826)
		(drill 0.254)
		(layers "F.Cu" "B.Cu")
		(net "GND")
	)
	(via
		(at 145.144744 -256.634488)
		(size 0.4064)
		(drill 0.2032)
		(layers "F.Cu" "B.Cu")
		(net "GND")
	)
	(via
		(at 133.864858 -229.094538)
		(size 0.4064)
		(drill 0.2032)
		(layers "F.Cu" "B.Cu")
		(net "GND")
	)
	(via
		(at 442.5442 -262.785098)
		(size 0.4826)
		(drill 0.254)
		(layers "F.Cu" "B.Cu")
		(net "GND")
	)
	(via
		(at 12.5095 -100.668328)
		(size 0.508)
		(drill 0.254)
		(layers "F.Cu" "B.Cu")
		(net "GND")
	)
	(via
		(at 53.620162 -434.082952)
		(size 0.508)
		(drill 0.254)
		(layers "F.Cu" "B.Cu")
		(net "GND")
	)
	(via
		(at 126.34976 -436.347362)
		(size 0.4572)
		(drill 0.2032)
		(layers "F.Cu" "B.Cu")
		(net "GND")
	)
	(via
		(at 109.900974 -238.00435)
		(size 0.4064)
		(drill 0.2032)
		(layers "F.Cu" "B.Cu")
		(net "GND")
	)
	(via
		(at 421.296338 -296.78503)
		(size 0.4826)
		(drill 0.254)
		(layers "F.Cu" "B.Cu")
		(net "GND")
	)
	(via
		(at 157.349698 -428.851314)
		(size 0.4572)
		(drill 0.2032)
		(layers "F.Cu" "B.Cu")
		(net "GND")
	)
	(via
		(at 131.716526 -391.830814)
		(size 0.4064)
		(drill 0.2032)
		(layers "F.Cu" "B.Cu")
		(net "GND")
	)
	(via
		(at 406.618948 -398.542002)
		(size 0.4064)
		(drill 0.2032)
		(layers "F.Cu" "B.Cu")
		(net "GND")
	)
	(via
		(at 19.75866 -132.107432)
		(size 0.508)
		(drill 0.254)
		(layers "F.Cu" "B.Cu")
		(net "GND")
	)
	(via
		(at 78.505558 -336.981292)
		(size 0.49022)
		(drill 0.254)
		(layers "F.Cu" "B.Cu")
		(net "GND")
	)
	(via
		(at 446.955164 -14.657832)
		(size 0.508)
		(drill 0.254)
		(layers "F.Cu" "B.Cu")
		(net "GND")
	)
	(via
		(at 70.298056 -411.936184)
		(size 0.4572)
		(drill 0.254)
		(layers "F.Cu" "B.Cu")
		(net "GND")
	)
	(via
		(at 329.958192 -389.25246)
		(size 0.508)
		(drill 0.254)
		(layers "F.Cu" "B.Cu")
		(net "GND")
	)
	(via
		(at 51.884072 -204.135228)
		(size 0.4826)
		(drill 0.254)
		(layers "F.Cu" "B.Cu")
		(net "GND")
	)
	(via
		(at 48.122078 -19.137122)
		(size 0.508)
		(drill 0.254)
		(layers "F.Cu" "B.Cu")
		(net "GND")
	)
	(via
		(at 183.932322 -123.04268)
		(size 0.4572)
		(drill 0.254)
		(layers "F.Cu" "B.Cu")
		(net "GND")
	)
	(via
		(at 277.805388 -108.70184)
		(size 0.508)
		(drill 0.254)
		(layers "F.Cu" "B.Cu")
		(net "GND")
	)
	(via
		(at 185.496708 -421.1447)
		(size 0.508)
		(drill 0.254)
		(layers "F.Cu" "B.Cu")
		(net "GND")
	)
	(via
		(at 164.427916 -244.085364)
		(size 0.4826)
		(drill 0.254)
		(layers "F.Cu" "B.Cu")
		(net "GND")
	)
	(via
		(at 88.580976 -292.716204)
		(size 0.4064)
		(drill 0.2032)
		(layers "F.Cu" "B.Cu")
		(net "GND")
	)
	(via
		(at 388.364222 -1.04521)
		(size 0.508)
		(drill 0.254)
		(layers "F.Cu" "B.Cu")
		(net "GND")
	)
	(via
		(at 119.12473 -265.98626)
		(size 0.4064)
		(drill 0.2032)
		(layers "F.Cu" "B.Cu")
		(net "GND")
	)
	(via
		(at 107.38104 -266.796266)
		(size 0.4064)
		(drill 0.2032)
		(layers "F.Cu" "B.Cu")
		(net "GND")
	)
	(via
		(at 108.961174 -236.384338)
		(size 0.4064)
		(drill 0.2032)
		(layers "F.Cu" "B.Cu")
		(net "GND")
	)
	(via
		(at 347.801184 -263.555988)
		(size 0.4064)
		(drill 0.2032)
		(layers "F.Cu" "B.Cu")
		(net "GND")
	)
	(via
		(at 257.10388 -61.884052)
		(size 0.508)
		(drill 0.254)
		(layers "F.Cu" "B.Cu")
		(net "GND")
	)
	(via
		(at 40.23995 -217.735404)
		(size 0.4826)
		(drill 0.254)
		(layers "F.Cu" "B.Cu")
		(net "GND")
	)
	(via
		(at 452.803768 -312.084974)
		(size 0.4826)
		(drill 0.254)
		(layers "F.Cu" "B.Cu")
		(net "GND")
	)
	(via
		(at 129.693924 -79.787496)
		(size 0.508)
		(drill 0.254)
		(layers "F.Cu" "B.Cu")
		(net "GND")
	)
	(via
		(at 202.147932 -255.13538)
		(size 0.4826)
		(drill 0.254)
		(layers "F.Cu" "B.Cu")
		(net "GND")
	)
	(via
		(at 108.961174 -233.144314)
		(size 0.4064)
		(drill 0.2032)
		(layers "F.Cu" "B.Cu")
		(net "GND")
	)
	(via
		(at 115.271042 -335.644744)
		(size 0.508)
		(drill 0.254)
		(layers "F.Cu" "B.Cu")
		(net "GND")
	)
	(via
		(at 128.349756 -427.699678)
		(size 0.4572)
		(drill 0.2032)
		(layers "F.Cu" "B.Cu")
		(net "GND")
	)
	(via
		(at 412.367984 -242.385088)
		(size 0.4826)
		(drill 0.254)
		(layers "F.Cu" "B.Cu")
		(net "GND")
	)
	(via
		(at 21.70811 -233.885232)
		(size 0.4826)
		(drill 0.254)
		(layers "F.Cu" "B.Cu")
		(net "GND")
	)
	(via
		(at 59.576716 -407.638504)
		(size 0.4572)
		(drill 0.254)
		(layers "F.Cu" "B.Cu")
		(net "GND")
	)
	(via
		(at 107.550966 -230.714296)
		(size 0.4064)
		(drill 0.2032)
		(layers "F.Cu" "B.Cu")
		(net "GND")
	)
	(via
		(at 353.441 -287.856168)
		(size 0.4064)
		(drill 0.2032)
		(layers "F.Cu" "B.Cu")
		(net "GND")
	)
	(via
		(at 86.245954 -335.544414)
		(size 0.49022)
		(drill 0.254)
		(layers "F.Cu" "B.Cu")
		(net "GND")
	)
	(via
		(at 396.461234 -421.586152)
		(size 0.4572)
		(drill 0.254)
		(layers "F.Cu" "B.Cu")
		(net "GND")
	)
	(via
		(at 133.864858 -250.15444)
		(size 0.4064)
		(drill 0.2032)
		(layers "F.Cu" "B.Cu")
		(net "GND")
	)
	(via
		(at 329.249532 -428.851314)
		(size 0.4572)
		(drill 0.2032)
		(layers "F.Cu" "B.Cu")
		(net "GND")
	)
	(via
		(at 431.55616 -213.484968)
		(size 0.4826)
		(drill 0.254)
		(layers "F.Cu" "B.Cu")
		(net "GND")
	)
	(via
		(at 301.231808 -113.843308)
		(size 0.508)
		(drill 0.254)
		(layers "F.Cu" "B.Cu")
		(net "GND")
	)
	(via
		(at 37.89934 -111.41456)
		(size 0.508)
		(drill 0.254)
		(layers "F.Cu" "B.Cu")
		(net "GND")
	)
	(via
		(at 108.961174 -250.964446)
		(size 0.4064)
		(drill 0.2032)
		(layers "F.Cu" "B.Cu")
		(net "GND")
	)
	(via
		(at 256.049272 -50.390298)
		(size 0.508)
		(drill 0.254)
		(layers "F.Cu" "B.Cu")
		(net "GND")
	)
	(via
		(at 97.511108 -270.846296)
		(size 0.4064)
		(drill 0.2032)
		(layers "F.Cu" "B.Cu")
		(net "GND")
	)
	(via
		(at 369.114832 -239.624108)
		(size 0.4064)
		(drill 0.2032)
		(layers "F.Cu" "B.Cu")
		(net "GND")
	)
	(via
		(at 188.122052 -139.6746)
		(size 0.508)
		(drill 0.254)
		(layers "F.Cu" "B.Cu")
		(net "GND")
	)
	(via
		(at 206.248 -233.885232)
		(size 0.4826)
		(drill 0.254)
		(layers "F.Cu" "B.Cu")
		(net "GND")
	)
	(via
		(at 99.95027 -182.127144)
		(size 0.49022)
		(drill 0.254)
		(layers "F.Cu" "B.Cu")
		(net "GND")
	)
	(via
		(at 77.112876 -263.290304)
		(size 0.4064)
		(drill 0.2032)
		(layers "F.Cu" "B.Cu")
		(net "GND")
	)
	(via
		(at 324.766178 -416.020504)
		(size 0.4572)
		(drill 0.254)
		(layers "F.Cu" "B.Cu")
		(net "GND")
	)
	(via
		(at 366.124744 -274.086066)
		(size 0.4064)
		(drill 0.2032)
		(layers "F.Cu" "B.Cu")
		(net "GND")
	)
	(via
		(at 363.474762 -246.104156)
		(size 0.4064)
		(drill 0.2032)
		(layers "F.Cu" "B.Cu")
		(net "GND")
	)
	(via
		(at 25.016968 -386.914898)
		(size 0.49022)
		(drill 0.254)
		(layers "F.Cu" "B.Cu")
		(net "GND")
	)
	(via
		(at 171.675298 -11.496548)
		(size 0.508)
		(drill 0.254)
		(layers "F.Cu" "B.Cu")
		(net "GND")
	)
	(via
		(at 372.937278 -176.85131)
		(size 0.508)
		(drill 0.254)
		(layers "F.Cu" "B.Cu")
		(net "GND")
	)
	(via
		(at 336.249518 -427.851316)
		(size 0.4572)
		(drill 0.2032)
		(layers "F.Cu" "B.Cu")
		(net "GND")
	)
	(via
		(at 49.862486 -384.617722)
		(size 0.4064)
		(drill 0.2032)
		(layers "F.Cu" "B.Cu")
		(net "GND")
	)
	(via
		(at 458.390752 -395.191234)
		(size 0.508)
		(drill 0.254)
		(layers "F.Cu" "B.Cu")
		(net "GND")
	)
	(via
		(at 29.69387 -385.14909)
		(size 0.508)
		(drill 0.254)
		(layers "F.Cu" "B.Cu")
		(net "GND")
	)
	(via
		(at 11.590782 -404.490174)
		(size 0.508)
		(drill 0.254)
		(layers "F.Cu" "B.Cu")
		(net "GND")
	)
	(via
		(at 164.427916 -223.685354)
		(size 0.4826)
		(drill 0.254)
		(layers "F.Cu" "B.Cu")
		(net "GND")
	)
	(via
		(at 305.791108 -398.542002)
		(size 0.4064)
		(drill 0.2032)
		(layers "F.Cu" "B.Cu")
		(net "GND")
	)
	(via
		(at 314.318142 -396.710662)
		(size 0.4064)
		(drill 0.2032)
		(layers "F.Cu" "B.Cu")
		(net "GND")
	)
	(via
		(at 123.01855 -388.328662)
		(size 0.4064)
		(drill 0.2032)
		(layers "F.Cu" "B.Cu")
		(net "GND")
	)
	(via
		(at 145.349722 -430.147222)
		(size 0.4572)
		(drill 0.2032)
		(layers "F.Cu" "B.Cu")
		(net "GND")
	)
	(via
		(at 348.895162 -258.830064)
		(size 0.4826)
		(drill 0.254)
		(layers "F.Cu" "B.Cu")
		(net "GND")
	)
	(via
		(at 372.921784 -177.602134)
		(size 0.508)
		(drill 0.254)
		(layers "F.Cu" "B.Cu")
		(net "GND")
	)
	(via
		(at 80.291178 -243.674392)
		(size 0.4064)
		(drill 0.2032)
		(layers "F.Cu" "B.Cu")
		(net "GND")
	)
	(via
		(at 451.4723 -219.435172)
		(size 0.4826)
		(drill 0.254)
		(layers "F.Cu" "B.Cu")
		(net "GND")
	)
	(via
		(at 442.740288 -363.781594)
		(size 0.508)
		(drill 0.254)
		(layers "F.Cu" "B.Cu")
		(net "GND")
	)
	(via
		(at 303.268126 -236.435138)
		(size 0.4826)
		(drill 0.254)
		(layers "F.Cu" "B.Cu")
		(net "GND")
	)
	(via
		(at 128.481074 -406.370536)
		(size 0.4572)
		(drill 0.254)
		(layers "F.Cu" "B.Cu")
		(net "GND")
	)
	(via
		(at 116.197888 -256.3876)
		(size 0.4826)
		(drill 0.254)
		(layers "F.Cu" "B.Cu")
		(net "GND")
	)
	(via
		(at 94.861126 -247.724422)
		(size 0.4064)
		(drill 0.2032)
		(layers "F.Cu" "B.Cu")
		(net "GND")
	)
	(via
		(at 22.572472 -383.86639)
		(size 0.508)
		(drill 0.254)
		(layers "F.Cu" "B.Cu")
		(net "GND")
	)
	(via
		(at 345.151202 -240.434114)
		(size 0.4064)
		(drill 0.2032)
		(layers "F.Cu" "B.Cu")
		(net "GND")
	)
	(via
		(at 197.3199 -302.735234)
		(size 0.4826)
		(drill 0.254)
		(layers "F.Cu" "B.Cu")
		(net "GND")
	)
	(via
		(at 103.151178 -293.52621)
		(size 0.4064)
		(drill 0.2032)
		(layers "F.Cu" "B.Cu")
		(net "GND")
	)
	(via
		(at 87.171022 -282.18638)
		(size 0.4064)
		(drill 0.2032)
		(layers "F.Cu" "B.Cu")
		(net "GND")
	)
	(via
		(at 32.992568 -400.183096)
		(size 0.508)
		(drill 0.254)
		(layers "F.Cu" "B.Cu")
		(net "GND")
	)
	(via
		(at 413.309054 -414.752536)
		(size 0.4572)
		(drill 0.254)
		(layers "F.Cu" "B.Cu")
		(net "GND")
	)
	(via
		(at 228.27488 -36.882324)
		(size 0.508)
		(drill 0.254)
		(layers "F.Cu" "B.Cu")
		(net "GND")
	)
	(via
		(at 153.349706 -432.451256)
		(size 0.4572)
		(drill 0.2032)
		(layers "F.Cu" "B.Cu")
		(net "GND")
	)
	(via
		(at 174.88916 -369.60556)
		(size 0.508)
		(drill 0.254)
		(layers "F.Cu" "B.Cu")
		(net "GND")
	)
	(via
		(at 366.594898 -271.656048)
		(size 0.4064)
		(drill 0.2032)
		(layers "F.Cu" "B.Cu")
		(net "GND")
	)
	(via
		(at 335.692242 -394.25753)
		(size 0.4064)
		(drill 0.2032)
		(layers "F.Cu" "B.Cu")
		(net "GND")
	)
	(via
		(at 257.429 -336.677)
		(size 0.508)
		(drill 0.254)
		(layers "F.Cu" "B.Cu")
		(net "GND")
	)
	(via
		(at 85.761068 -268.416278)
		(size 0.4064)
		(drill 0.2032)
		(layers "F.Cu" "B.Cu")
		(net "GND")
	)
	(via
		(at 202.147932 -242.385342)
		(size 0.4826)
		(drill 0.254)
		(layers "F.Cu" "B.Cu")
		(net "GND")
	)
	(via
		(at 292.280086 -207.535018)
		(size 0.4826)
		(drill 0.254)
		(layers "F.Cu" "B.Cu")
		(net "GND")
	)
	(via
		(at 436.852822 -408.84856)
		(size 0.508)
		(drill 0.254)
		(layers "F.Cu" "B.Cu")
		(net "GND")
	)
	(via
		(at 419.912038 -267.885164)
		(size 0.4826)
		(drill 0.254)
		(layers "F.Cu" "B.Cu")
		(net "GND")
	)
	(via
		(at 390.094724 -292.71595)
		(size 0.4064)
		(drill 0.2032)
		(layers "F.Cu" "B.Cu")
		(net "GND")
	)
	(via
		(at 303.268126 -309.535068)
		(size 0.4826)
		(drill 0.254)
		(layers "F.Cu" "B.Cu")
		(net "GND")
	)
	(via
		(at 445.259968 -221.13494)
		(size 0.4826)
		(drill 0.254)
		(layers "F.Cu" "B.Cu")
		(net "GND")
	)
	(via
		(at 162.22853 -347.003878)
		(size 0.508)
		(drill 0.254)
		(layers "F.Cu" "B.Cu")
		(net "GND")
	)
	(via
		(at 168.580562 -8.273796)
		(size 0.508)
		(drill 0.254)
		(layers "F.Cu" "B.Cu")
		(net "GND")
	)
	(via
		(at 27.276806 -6.091174)
		(size 0.508)
		(drill 0.254)
		(layers "F.Cu" "B.Cu")
		(net "GND")
	)
	(via
		(at 101.91115 -227.474526)
		(size 0.4064)
		(drill 0.2032)
		(layers "F.Cu" "B.Cu")
		(net "GND")
	)
	(via
		(at 183.616092 -216.885266)
		(size 0.4826)
		(drill 0.254)
		(layers "F.Cu" "B.Cu")
		(net "GND")
	)
	(via
		(at 120.064784 -282.18638)
		(size 0.4064)
		(drill 0.2032)
		(layers "F.Cu" "B.Cu")
		(net "GND")
	)
	(via
		(at 368.644932 -225.85426)
		(size 0.4064)
		(drill 0.2032)
		(layers "F.Cu" "B.Cu")
		(net "GND")
	)
	(via
		(at 383.21488 -254.204216)
		(size 0.4064)
		(drill 0.2032)
		(layers "F.Cu" "B.Cu")
		(net "GND")
	)
	(via
		(at 121.004838 -293.52621)
		(size 0.4064)
		(drill 0.2032)
		(layers "F.Cu" "B.Cu")
		(net "GND")
	)
	(via
		(at 464.537552 -375.455434)
		(size 0.6604)
		(drill 0.3302)
		(layers "F.Cu" "B.Cu")
		(net "GND")
	)
	(via
		(at 29.252164 -216.885266)
		(size 0.4826)
		(drill 0.254)
		(layers "F.Cu" "B.Cu")
		(net "GND")
	)
	(via
		(at 314.616338 -400.212814)
		(size 0.4064)
		(drill 0.2032)
		(layers "F.Cu" "B.Cu")
		(net "GND")
	)
	(via
		(at 36.795964 -278.935434)
		(size 0.4826)
		(drill 0.254)
		(layers "F.Cu" "B.Cu")
		(net "GND")
	)
	(via
		(at 374.584722 -293.525956)
		(size 0.4064)
		(drill 0.2032)
		(layers "F.Cu" "B.Cu")
		(net "GND")
	)
	(via
		(at 17.608042 -298.485306)
		(size 0.4826)
		(drill 0.254)
		(layers "F.Cu" "B.Cu")
		(net "GND")
	)
	(via
		(at 392.13917 -421.586152)
		(size 0.4572)
		(drill 0.254)
		(layers "F.Cu" "B.Cu")
		(net "GND")
	)
	(via
		(at 348.013274 -416.020504)
		(size 0.4572)
		(drill 0.254)
		(layers "F.Cu" "B.Cu")
		(net "GND")
	)
	(via
		(at 162.592766 -171.42206)
		(size 0.508)
		(drill 0.254)
		(layers "F.Cu" "B.Cu")
		(net "GND")
	)
	(via
		(at 384.174492 -382.34493)
		(size 0.508)
		(drill 0.254)
		(layers "F.Cu" "B.Cu")
		(net "GND")
	)
	(via
		(at 369.254278 -189.508638)
		(size 0.508)
		(drill 0.254)
		(layers "F.Cu" "B.Cu")
		(net "GND")
	)
	(via
		(at 307.202586 -348.704662)
		(size 0.49022)
		(drill 0.254)
		(layers "F.Cu" "B.Cu")
		(net "GND")
	)
	(via
		(at 280.635964 -279.785064)
		(size 0.4826)
		(drill 0.254)
		(layers "F.Cu" "B.Cu")
		(net "GND")
	)
	(via
		(at 99.390962 -278.946356)
		(size 0.4064)
		(drill 0.2032)
		(layers "F.Cu" "B.Cu")
		(net "GND")
	)
	(via
		(at 310.7182 -396.710662)
		(size 0.4064)
		(drill 0.2032)
		(layers "F.Cu" "B.Cu")
		(net "GND")
	)
	(via
		(at 171.97197 -199.035416)
		(size 0.4826)
		(drill 0.254)
		(layers "F.Cu" "B.Cu")
		(net "GND")
	)
	(via
		(at 106.91114 -270.846296)
		(size 0.4064)
		(drill 0.2032)
		(layers "F.Cu" "B.Cu")
		(net "GND")
	)
	(via
		(at 170.902122 -6.042152)
		(size 0.508)
		(drill 0.254)
		(layers "F.Cu" "B.Cu")
		(net "GND")
	)
	(via
		(at 261.75335 -99.405948)
		(size 0.508)
		(drill 0.254)
		(layers "F.Cu" "B.Cu")
		(net "GND")
	)
	(via
		(at 357.841042 -233.14406)
		(size 0.4064)
		(drill 0.2032)
		(layers "F.Cu" "B.Cu")
		(net "GND")
	)
	(via
		(at 131.27863 -386.449062)
		(size 0.4064)
		(drill 0.2032)
		(layers "F.Cu" "B.Cu")
		(net "GND")
	)
	(via
		(at 273.092164 -227.085144)
		(size 0.4826)
		(drill 0.254)
		(layers "F.Cu" "B.Cu")
		(net "GND")
	)
	(via
		(at 98.321114 -331.12456)
		(size 0.508)
		(drill 0.254)
		(layers "F.Cu" "B.Cu")
		(net "GND")
	)
	(via
		(at 385.881118 -186.648598)
		(size 0.508)
		(drill 0.254)
		(layers "F.Cu" "B.Cu")
		(net "GND")
	)
	(via
		(at 143.349726 -427.851316)
		(size 0.4572)
		(drill 0.2032)
		(layers "F.Cu" "B.Cu")
		(net "GND")
	)
	(via
		(at 80.822546 -355.739446)
		(size 0.508)
		(drill 0.254)
		(layers "F.Cu" "B.Cu")
		(net "GND")
	)
	(via
		(at 90.461084 -271.656302)
		(size 0.4064)
		(drill 0.2032)
		(layers "F.Cu" "B.Cu")
		(net "GND")
	)
	(via
		(at 467.5378 -82.855054)
		(size 0.508)
		(drill 0.254)
		(layers "F.Cu" "B.Cu")
		(net "GND")
	)
	(via
		(at 283.06141 -346.317316)
		(size 0.49022)
		(drill 0.254)
		(layers "F.Cu" "B.Cu")
		(net "GND")
	)
	(via
		(at 339.99932 -362.01096)
		(size 0.508)
		(drill 0.254)
		(layers "F.Cu" "B.Cu")
		(net "GND")
	)
	(via
		(at 121.174764 -247.724422)
		(size 0.4064)
		(drill 0.2032)
		(layers "F.Cu" "B.Cu")
		(net "GND")
	)
	(via
		(at 21.70811 -265.335258)
		(size 0.4826)
		(drill 0.254)
		(layers "F.Cu" "B.Cu")
		(net "GND")
	)
	(via
		(at 83.88096 -292.716204)
		(size 0.4064)
		(drill 0.2032)
		(layers "F.Cu" "B.Cu")
		(net "GND")
	)
	(via
		(at 206.248 -289.98545)
		(size 0.4826)
		(drill 0.254)
		(layers "F.Cu" "B.Cu")
		(net "GND")
	)
	(via
		(at 122.884692 -285.426404)
		(size 0.4064)
		(drill 0.2032)
		(layers "F.Cu" "B.Cu")
		(net "GND")
	)
	(via
		(at 36.795964 -250.035314)
		(size 0.4826)
		(drill 0.254)
		(layers "F.Cu" "B.Cu")
		(net "GND")
	)
	(via
		(at 454.033636 -65.219326)
		(size 0.508)
		(drill 0.254)
		(layers "F.Cu" "B.Cu")
		(net "GND")
	)
	(via
		(at 90.209116 -409.396184)
		(size 0.4572)
		(drill 0.254)
		(layers "F.Cu" "B.Cu")
		(net "GND")
	)
	(via
		(at 92.981018 -241.244374)
		(size 0.4064)
		(drill 0.2032)
		(layers "F.Cu" "B.Cu")
		(net "GND")
	)
	(via
		(at 405.553164 -19.13636)
		(size 0.508)
		(drill 0.254)
		(layers "F.Cu" "B.Cu")
		(net "GND")
	)
	(via
		(at 78.41107 -224.234502)
		(size 0.4064)
		(drill 0.2032)
		(layers "F.Cu" "B.Cu")
		(net "GND")
	)
	(via
		(at 61.381132 -407.638504)
		(size 0.4572)
		(drill 0.254)
		(layers "F.Cu" "B.Cu")
		(net "GND")
	)
	(via
		(at 323.249544 -429.147224)
		(size 0.4572)
		(drill 0.2032)
		(layers "F.Cu" "B.Cu")
		(net "GND")
	)
	(via
		(at 78.783942 -334.593946)
		(size 0.49022)
		(drill 0.254)
		(layers "F.Cu" "B.Cu")
		(net "GND")
	)
	(via
		(at 407.541222 -418.412168)
		(size 0.4064)
		(drill 0.2032)
		(layers "F.Cu" "B.Cu")
		(net "GND")
	)
	(via
		(at 392.349482 -433.747164)
		(size 0.4572)
		(drill 0.2032)
		(layers "F.Cu" "B.Cu")
		(net "GND")
	)
	(via
		(at 193.32702 -350.756728)
		(size 0.49022)
		(drill 0.254)
		(layers "F.Cu" "B.Cu")
		(net "GND")
	)
	(via
		(at 403.57933 -4.32943)
		(size 0.508)
		(drill 0.254)
		(layers "F.Cu" "B.Cu")
		(net "GND")
	)
	(via
		(at 90.120724 -404.46452)
		(size 0.4064)
		(drill 0.2032)
		(layers "F.Cu" "B.Cu")
		(net "GND")
	)
	(via
		(at 430.17186 -293.384986)
		(size 0.4826)
		(drill 0.254)
		(layers "F.Cu" "B.Cu")
		(net "GND")
	)
	(via
		(at 141.992858 -410.664152)
		(size 0.4572)
		(drill 0.254)
		(layers "F.Cu" "B.Cu")
		(net "GND")
	)
	(via
		(at 328.061066 -286.236156)
		(size 0.4064)
		(drill 0.2032)
		(layers "F.Cu" "B.Cu")
		(net "GND")
	)
	(via
		(at 123.994672 -236.384338)
		(size 0.4064)
		(drill 0.2032)
		(layers "F.Cu" "B.Cu")
		(net "GND")
	)
	(via
		(at 449.246752 -393.667234)
		(size 0.508)
		(drill 0.254)
		(layers "F.Cu" "B.Cu")
		(net "GND")
	)
	(via
		(at 353.441 -286.236156)
		(size 0.4064)
		(drill 0.2032)
		(layers "F.Cu" "B.Cu")
		(net "GND")
	)
	(via
		(at 460.39278 -40.45585)
		(size 0.508)
		(drill 0.254)
		(layers "F.Cu" "B.Cu")
		(net "GND")
	)
	(via
		(at 329.361038 -421.586152)
		(size 0.4572)
		(drill 0.254)
		(layers "F.Cu" "B.Cu")
		(net "GND")
	)
	(via
		(at 169.645584 -229.210362)
		(size 0.4826)
		(drill 0.254)
		(layers "F.Cu" "B.Cu")
		(net "GND")
	)
	(via
		(at 344.517218 -163.08832)
		(size 0.508)
		(drill 0.254)
		(layers "F.Cu" "B.Cu")
		(net "GND")
	)
	(via
		(at 110.606078 -179.04841)
		(size 0.49022)
		(drill 0.254)
		(layers "F.Cu" "B.Cu")
		(net "GND")
	)
	(via
		(at 389.161782 -418.412168)
		(size 0.4064)
		(drill 0.2032)
		(layers "F.Cu" "B.Cu")
		(net "GND")
	)
	(via
		(at 113.65484 -229.90429)
		(size 0.4064)
		(drill 0.2032)
		(layers "F.Cu" "B.Cu")
		(net "GND")
	)
	(via
		(at 17.608042 -217.735404)
		(size 0.4826)
		(drill 0.254)
		(layers "F.Cu" "B.Cu")
		(net "GND")
	)
	(via
		(at 421.296338 -210.085178)
		(size 0.4826)
		(drill 0.254)
		(layers "F.Cu" "B.Cu")
		(net "GND")
	)
	(via
		(at 179.516024 -272.135346)
		(size 0.4826)
		(drill 0.254)
		(layers "F.Cu" "B.Cu")
		(net "GND")
	)
	(via
		(at 387.278626 -394.831062)
		(size 0.4064)
		(drill 0.2032)
		(layers "F.Cu" "B.Cu")
		(net "GND")
	)
	(via
		(at 123.524772 -229.094538)
		(size 0.4064)
		(drill 0.2032)
		(layers "F.Cu" "B.Cu")
		(net "GND")
	)
	(via
		(at 347.918786 -398.542002)
		(size 0.4064)
		(drill 0.2032)
		(layers "F.Cu" "B.Cu")
		(net "GND")
	)
	(via
		(at 350.621092 -270.036036)
		(size 0.4064)
		(drill 0.2032)
		(layers "F.Cu" "B.Cu")
		(net "GND")
	)
	(via
		(at 113.75009 -173.858682)
		(size 0.49022)
		(drill 0.254)
		(layers "F.Cu" "B.Cu")
		(net "GND")
	)
	(via
		(at 427.17212 -347.210126)
		(size 0.508)
		(drill 0.254)
		(layers "F.Cu" "B.Cu")
		(net "GND")
	)
	(via
		(at 268.530578 -201.160126)
		(size 0.4826)
		(drill 0.254)
		(layers "F.Cu" "B.Cu")
		(net "GND")
	)
	(via
		(at 57.959244 -407.00452)
		(size 0.4064)
		(drill 0.2032)
		(layers "F.Cu" "B.Cu")
		(net "GND")
	)
	(via
		(at 76.5937 -383.7432)
		(size 0.508)
		(drill 0.254)
		(layers "F.Cu" "B.Cu")
		(net "GND")
	)
	(via
		(at 449.987924 -61.960252)
		(size 0.6604)
		(drill 0.3302)
		(layers "F.Cu" "B.Cu")
		(net "GND")
	)
	(via
		(at 75.520042 -421.582088)
		(size 0.508)
		(drill 0.254)
		(layers "F.Cu" "B.Cu")
		(net "GND")
	)
	(via
		(at 288.180018 -216.035128)
		(size 0.4826)
		(drill 0.254)
		(layers "F.Cu" "B.Cu")
		(net "GND")
	)
	(via
		(at 353.61118 -240.434114)
		(size 0.4064)
		(drill 0.2032)
		(layers "F.Cu" "B.Cu")
		(net "GND")
	)
	(via
		(at 314.616338 -391.23493)
		(size 0.4064)
		(drill 0.2032)
		(layers "F.Cu" "B.Cu")
		(net "GND")
	)
	(via
		(at 171.319444 -418.551868)
		(size 0.508)
		(drill 0.254)
		(layers "F.Cu" "B.Cu")
		(net "GND")
	)
	(via
		(at 25.745694 -10.16508)
		(size 0.508)
		(drill 0.254)
		(layers "F.Cu" "B.Cu")
		(net "GND")
	)
	(via
		(at 59.488324 -404.46452)
		(size 0.4064)
		(drill 0.2032)
		(layers "F.Cu" "B.Cu")
		(net "GND")
	)
	(via
		(at 331.821028 -291.095938)
		(size 0.4064)
		(drill 0.2032)
		(layers "F.Cu" "B.Cu")
		(net "GND")
	)
	(via
		(at 86.701122 -291.096192)
		(size 0.4064)
		(drill 0.2032)
		(layers "F.Cu" "B.Cu")
		(net "GND")
	)
	(via
		(at 105.671112 -225.854514)
		(size 0.4064)
		(drill 0.2032)
		(layers "F.Cu" "B.Cu")
		(net "GND")
	)
	(via
		(at 65.596262 -33.981644)
		(size 0.508)
		(drill 0.254)
		(layers "F.Cu" "B.Cu")
		(net "GND")
	)
	(via
		(at 255.927098 -212.307424)
		(size 0.508)
		(drill 0.254)
		(layers "F.Cu" "B.Cu")
		(net "GND")
	)
	(via
		(at 222.152718 -279.643078)
		(size 0.508)
		(drill 0.254)
		(layers "F.Cu" "B.Cu")
		(net "GND")
	)
	(via
		(at 373.3165 -400.212814)
		(size 0.4064)
		(drill 0.2032)
		(layers "F.Cu" "B.Cu")
		(net "GND")
	)
	(via
		(at 453.426576 -22.853142)
		(size 0.508)
		(drill 0.254)
		(layers "F.Cu" "B.Cu")
		(net "GND")
	)
	(via
		(at 341.691214 -274.086066)
		(size 0.4064)
		(drill 0.2032)
		(layers "F.Cu" "B.Cu")
		(net "GND")
	)
	(via
		(at 393.084812 -246.914162)
		(size 0.4064)
		(drill 0.2032)
		(layers "F.Cu" "B.Cu")
		(net "GND")
	)
	(via
		(at 409.44419 -400.212814)
		(size 0.4064)
		(drill 0.2032)
		(layers "F.Cu" "B.Cu")
		(net "GND")
	)
	(via
		(at 347.974412 -155.997656)
		(size 0.508)
		(drill 0.254)
		(layers "F.Cu" "B.Cu")
		(net "GND")
	)
	(via
		(at 138.864848 -282.18638)
		(size 0.4064)
		(drill 0.2032)
		(layers "F.Cu" "B.Cu")
		(net "GND")
	)
	(via
		(at 162.401504 -374.62333)
		(size 0.508)
		(drill 0.254)
		(layers "F.Cu" "B.Cu")
		(net "GND")
	)
	(via
		(at 87.145876 -406.370536)
		(size 0.4572)
		(drill 0.254)
		(layers "F.Cu" "B.Cu")
		(net "GND")
	)
	(via
		(at 24.034496 -276.81047)
		(size 0.4826)
		(drill 0.254)
		(layers "F.Cu" "B.Cu")
		(net "GND")
	)
	(via
		(at 156.630116 -351.247456)
		(size 0.508)
		(drill 0.254)
		(layers "F.Cu" "B.Cu")
		(net "GND")
	)
	(via
		(at 213.69274 -385.726432)
		(size 0.508)
		(drill 0.254)
		(layers "F.Cu" "B.Cu")
		(net "GND")
	)
	(via
		(at 456.382374 -11.858244)
		(size 0.508)
		(drill 0.254)
		(layers "F.Cu" "B.Cu")
		(net "GND")
	)
	(via
		(at 412.367984 -217.73515)
		(size 0.4826)
		(drill 0.254)
		(layers "F.Cu" "B.Cu")
		(net "GND")
	)
	(via
		(at 289.012884 -369.185698)
		(size 0.508)
		(drill 0.254)
		(layers "F.Cu" "B.Cu")
		(net "GND")
	)
	(via
		(at 434.023516 -331.771752)
		(size 0.508)
		(drill 0.254)
		(layers "F.Cu" "B.Cu")
		(net "GND")
	)
	(via
		(at 457.628752 -394.429234)
		(size 0.508)
		(drill 0.254)
		(layers "F.Cu" "B.Cu")
		(net "GND")
	)
	(via
		(at 370.054886 -223.424242)
		(size 0.4064)
		(drill 0.2032)
		(layers "F.Cu" "B.Cu")
		(net "GND")
	)
	(via
		(at 141.854682 -238.00435)
		(size 0.4064)
		(drill 0.2032)
		(layers "F.Cu" "B.Cu")
		(net "GND")
	)
	(via
		(at 332.593442 -392.1252)
		(size 0.508)
		(drill 0.254)
		(layers "F.Cu" "B.Cu")
		(net "GND")
	)
	(via
		(at 130.104642 -253.394464)
		(size 0.4064)
		(drill 0.2032)
		(layers "F.Cu" "B.Cu")
		(net "GND")
	)
	(via
		(at 59.249818 -433.899564)
		(size 0.4572)
		(drill 0.2032)
		(layers "F.Cu" "B.Cu")
		(net "GND")
	)
	(via
		(at 99.861116 -284.616398)
		(size 0.4064)
		(drill 0.2032)
		(layers "F.Cu" "B.Cu")
		(net "GND")
	)
	(via
		(at 160.645094 -413.204152)
		(size 0.4572)
		(drill 0.254)
		(layers "F.Cu" "B.Cu")
		(net "GND")
	)
	(via
		(at 89.18194 -355.171248)
		(size 0.508)
		(drill 0.254)
		(layers "F.Cu" "B.Cu")
		(net "GND")
	)
	(via
		(at 32.34817 -366.030256)
		(size 0.508)
		(drill 0.254)
		(layers "F.Cu" "B.Cu")
		(net "GND")
	)
	(via
		(at 381.334772 -247.724168)
		(size 0.4064)
		(drill 0.2032)
		(layers "F.Cu" "B.Cu")
		(net "GND")
	)
	(via
		(at 375.054876 -271.656048)
		(size 0.4064)
		(drill 0.2032)
		(layers "F.Cu" "B.Cu")
		(net "GND")
	)
	(via
		(at 107.550966 -233.95432)
		(size 0.4064)
		(drill 0.2032)
		(layers "F.Cu" "B.Cu")
		(net "GND")
	)
	(via
		(at 296.770044 -385.38912)
		(size 0.508)
		(drill 0.254)
		(layers "F.Cu" "B.Cu")
		(net "GND")
	)
	(via
		(at 259.38988 -61.884052)
		(size 0.508)
		(drill 0.254)
		(layers "F.Cu" "B.Cu")
		(net "GND")
	)
	(via
		(at 110.671102 -285.426404)
		(size 0.4064)
		(drill 0.2032)
		(layers "F.Cu" "B.Cu")
		(net "GND")
	)
	(via
		(at 65.402714 -343.476834)
		(size 0.508)
		(drill 0.254)
		(layers "F.Cu" "B.Cu")
		(net "GND")
	)
	(via
		(at 427.915832 -331.12329)
		(size 0.508)
		(drill 0.254)
		(layers "F.Cu" "B.Cu")
		(net "GND")
	)
	(via
		(at 77.471016 -224.234502)
		(size 0.4064)
		(drill 0.2032)
		(layers "F.Cu" "B.Cu")
		(net "GND")
	)
	(via
		(at 55.328058 -290.835334)
		(size 0.4826)
		(drill 0.254)
		(layers "F.Cu" "B.Cu")
		(net "GND")
	)
	(via
		(at 118.824756 -242.05438)
		(size 0.4064)
		(drill 0.2032)
		(layers "F.Cu" "B.Cu")
		(net "GND")
	)
	(via
		(at 138.929618 -406.370536)
		(size 0.4572)
		(drill 0.254)
		(layers "F.Cu" "B.Cu")
		(net "GND")
	)
	(via
		(at 318.639698 -416.020504)
		(size 0.4572)
		(drill 0.254)
		(layers "F.Cu" "B.Cu")
		(net "GND")
	)
	(via
		(at 391.974832 -279.756108)
		(size 0.4064)
		(drill 0.2032)
		(layers "F.Cu" "B.Cu")
		(net "GND")
	)
	(via
		(at 412.958026 -12.37488)
		(size 0.508)
		(drill 0.254)
		(layers "F.Cu" "B.Cu")
		(net "GND")
	)
	(via
		(at 387.444742 -224.234248)
		(size 0.4064)
		(drill 0.2032)
		(layers "F.Cu" "B.Cu")
		(net "GND")
	)
	(via
		(at 65.518538 -388.328662)
		(size 0.4064)
		(drill 0.2032)
		(layers "F.Cu" "B.Cu")
		(net "GND")
	)
	(via
		(at 353.144074 -400.212814)
		(size 0.4064)
		(drill 0.2032)
		(layers "F.Cu" "B.Cu")
		(net "GND")
	)
	(via
		(at 138.349736 -438.651396)
		(size 0.4572)
		(drill 0.2032)
		(layers "F.Cu" "B.Cu")
		(net "GND")
	)
	(via
		(at 365.35487 -249.34418)
		(size 0.4064)
		(drill 0.2032)
		(layers "F.Cu" "B.Cu")
		(net "GND")
	)
	(via
		(at 408.628342 -415.38652)
		(size 0.4064)
		(drill 0.2032)
		(layers "F.Cu" "B.Cu")
		(net "GND")
	)
	(via
		(at 55.328058 -249.18543)
		(size 0.4826)
		(drill 0.254)
		(layers "F.Cu" "B.Cu")
		(net "GND")
	)
	(via
		(at 27.867864 -314.635388)
		(size 0.4826)
		(drill 0.254)
		(layers "F.Cu" "B.Cu")
		(net "GND")
	)
	(via
		(at 96.571054 -269.226284)
		(size 0.4064)
		(drill 0.2032)
		(layers "F.Cu" "B.Cu")
		(net "GND")
	)
	(via
		(at 381.059182 -418.412168)
		(size 0.4064)
		(drill 0.2032)
		(layers "F.Cu" "B.Cu")
		(net "GND")
	)
	(via
		(at 388.384796 -222.614236)
		(size 0.4064)
		(drill 0.2032)
		(layers "F.Cu" "B.Cu")
		(net "GND")
	)
	(via
		(at 358.56926 -336.499962)
		(size 0.508)
		(drill 0.254)
		(layers "F.Cu" "B.Cu")
		(net "GND")
	)
	(via
		(at 134.638034 -295.98366)
		(size 0.4064)
		(drill 0.2032)
		(layers "F.Cu" "B.Cu")
		(net "GND")
	)
	(via
		(at 16.490442 -220.710252)
		(size 0.4826)
		(drill 0.254)
		(layers "F.Cu" "B.Cu")
		(net "GND")
	)
	(via
		(at 44.539154 -371.49913)
		(size 0.508)
		(drill 0.254)
		(layers "F.Cu" "B.Cu")
		(net "GND")
	)
	(via
		(at 131.044696 -222.61449)
		(size 0.4064)
		(drill 0.2032)
		(layers "F.Cu" "B.Cu")
		(net "GND")
	)
	(via
		(at 366.124744 -288.66592)
		(size 0.4064)
		(drill 0.2032)
		(layers "F.Cu" "B.Cu")
		(net "GND")
	)
	(via
		(at 88.580976 -274.896326)
		(size 0.4064)
		(drill 0.2032)
		(layers "F.Cu" "B.Cu")
		(net "GND")
	)
	(via
		(at 133.694678 -281.376374)
		(size 0.4064)
		(drill 0.2032)
		(layers "F.Cu" "B.Cu")
		(net "GND")
	)
	(via
		(at 349.851218 -232.334054)
		(size 0.4064)
		(drill 0.2032)
		(layers "F.Cu" "B.Cu")
		(net "GND")
	)
	(via
		(at 182.332122 -113.46307)
		(size 0.4572)
		(drill 0.254)
		(layers "F.Cu" "B.Cu")
		(net "GND")
	)
	(via
		(at 189.775846 -237.285276)
		(size 0.4826)
		(drill 0.254)
		(layers "F.Cu" "B.Cu")
		(net "GND")
	)
	(via
		(at 118.65483 -274.896326)
		(size 0.4064)
		(drill 0.2032)
		(layers "F.Cu" "B.Cu")
		(net "GND")
	)
	(via
		(at 383.514854 -287.856168)
		(size 0.4064)
		(drill 0.2032)
		(layers "F.Cu" "B.Cu")
		(net "GND")
	)
	(via
		(at 110.371128 -230.71455)
		(size 0.4064)
		(drill 0.2032)
		(layers "F.Cu" "B.Cu")
		(net "GND")
	)
	(via
		(at 50.766472 -304.010314)
		(size 0.4826)
		(drill 0.254)
		(layers "F.Cu" "B.Cu")
		(net "GND")
	)
	(via
		(at 330.064364 -396.850108)
		(size 0.508)
		(drill 0.254)
		(layers "F.Cu" "B.Cu")
		(net "GND")
	)
	(via
		(at 123.886214 -403.830536)
		(size 0.4572)
		(drill 0.254)
		(layers "F.Cu" "B.Cu")
		(net "GND")
	)
	(via
		(at 165.812216 -210.085432)
		(size 0.4826)
		(drill 0.254)
		(layers "F.Cu" "B.Cu")
		(net "GND")
	)
	(via
		(at 58.1914 -390.160002)
		(size 0.4064)
		(drill 0.2032)
		(layers "F.Cu" "B.Cu")
		(net "GND")
	)
	(via
		(at 204.8637 -312.085228)
		(size 0.4826)
		(drill 0.254)
		(layers "F.Cu" "B.Cu")
		(net "GND")
	)
	(via
		(at 112.927384 -441.227718)
		(size 0.508)
		(drill 0.254)
		(layers "F.Cu" "B.Cu")
		(net "GND")
	)
	(via
		(at 454.188068 -271.284954)
		(size 0.4826)
		(drill 0.254)
		(layers "F.Cu" "B.Cu")
		(net "GND")
	)
	(via
		(at 365.18469 -277.32609)
		(size 0.4064)
		(drill 0.2032)
		(layers "F.Cu" "B.Cu")
		(net "GND")
	)
	(via
		(at 48.11014 -98.59772)
		(size 0.508)
		(drill 0.254)
		(layers "F.Cu" "B.Cu")
		(net "GND")
	)
	(via
		(at 427.97095 -30.165548)
		(size 0.508)
		(drill 0.254)
		(layers "F.Cu" "B.Cu")
		(net "GND")
	)
	(via
		(at 292.280086 -198.185024)
		(size 0.4826)
		(drill 0.254)
		(layers "F.Cu" "B.Cu")
		(net "GND")
	)
	(via
		(at 109.547914 -256.3876)
		(size 0.4826)
		(drill 0.254)
		(layers "F.Cu" "B.Cu")
		(net "GND")
	)
	(via
		(at 423.38498 -351.68078)
		(size 0.49022)
		(drill 0.254)
		(layers "F.Cu" "B.Cu")
		(net "GND")
	)
	(via
		(at 458.390752 -396.080234)
		(size 0.508)
		(drill 0.254)
		(layers "F.Cu" "B.Cu")
		(net "GND")
	)
	(via
		(at 329.171046 -222.614236)
		(size 0.4064)
		(drill 0.2032)
		(layers "F.Cu" "B.Cu")
		(net "GND")
	)
	(via
		(at 381.804926 -225.85426)
		(size 0.4064)
		(drill 0.2032)
		(layers "F.Cu" "B.Cu")
		(net "GND")
	)
	(via
		(at 100.331016 -291.906198)
		(size 0.4064)
		(drill 0.2032)
		(layers "F.Cu" "B.Cu")
		(net "GND")
	)
	(via
		(at 116.944648 -251.774452)
		(size 0.4064)
		(drill 0.2032)
		(layers "F.Cu" "B.Cu")
		(net "GND")
	)
	(via
		(at 363.944916 -229.094284)
		(size 0.4064)
		(drill 0.2032)
		(layers "F.Cu" "B.Cu")
		(net "GND")
	)
	(via
		(at 83.111086 -227.474526)
		(size 0.4064)
		(drill 0.2032)
		(layers "F.Cu" "B.Cu")
		(net "GND")
	)
	(via
		(at 341.528146 -415.38652)
		(size 0.4064)
		(drill 0.2032)
		(layers "F.Cu" "B.Cu")
		(net "GND")
	)
	(via
		(at 345.943936 -400.212814)
		(size 0.4064)
		(drill 0.2032)
		(layers "F.Cu" "B.Cu")
		(net "GND")
	)
	(via
		(at 27.107134 -348.709488)
		(size 0.49022)
		(drill 0.254)
		(layers "F.Cu" "B.Cu")
		(net "GND")
	)
	(via
		(at 331.051154 -235.574078)
		(size 0.4064)
		(drill 0.2032)
		(layers "F.Cu" "B.Cu")
		(net "GND")
	)
	(via
		(at 54.210458 -220.710252)
		(size 0.4826)
		(drill 0.254)
		(layers "F.Cu" "B.Cu")
		(net "GND")
	)
	(via
		(at 429.834548 -4.32943)
		(size 0.508)
		(drill 0.254)
		(layers "F.Cu" "B.Cu")
		(net "GND")
	)
	(via
		(at 348.299786 -24.892)
		(size 0.508)
		(drill 0.254)
		(layers "F.Cu" "B.Cu")
		(net "GND")
	)
	(via
		(at 83.580986 -238.00435)
		(size 0.4064)
		(drill 0.2032)
		(layers "F.Cu" "B.Cu")
		(net "GND")
	)
	(via
		(at 157.349698 -434.899562)
		(size 0.4572)
		(drill 0.2032)
		(layers "F.Cu" "B.Cu")
		(net "GND")
	)
	(via
		(at 386.504942 -253.39421)
		(size 0.4064)
		(drill 0.2032)
		(layers "F.Cu" "B.Cu")
		(net "GND")
	)
	(via
		(at 326.351138 -237.19409)
		(size 0.4064)
		(drill 0.2032)
		(layers "F.Cu" "B.Cu")
		(net "GND")
	)
	(via
		(at 195.721732 -239.410494)
		(size 0.4826)
		(drill 0.254)
		(layers "F.Cu" "B.Cu")
		(net "GND")
	)
	(via
		(at 382.349502 -431.451258)
		(size 0.4572)
		(drill 0.2032)
		(layers "F.Cu" "B.Cu")
		(net "GND")
	)
	(via
		(at 289.564318 -210.085178)
		(size 0.4826)
		(drill 0.254)
		(layers "F.Cu" "B.Cu")
		(net "GND")
	)
	(via
		(at 149.565106 -410.030168)
		(size 0.4064)
		(drill 0.2032)
		(layers "F.Cu" "B.Cu")
		(net "GND")
	)
	(via
		(at 131.98475 -227.474526)
		(size 0.4064)
		(drill 0.2032)
		(layers "F.Cu" "B.Cu")
		(net "GND")
	)
	(via
		(at 403.848062 -9.424924)
		(size 0.508)
		(drill 0.254)
		(layers "F.Cu" "B.Cu")
		(net "GND")
	)
	(via
		(at 47.784004 -217.735404)
		(size 0.4826)
		(drill 0.254)
		(layers "F.Cu" "B.Cu")
		(net "GND")
	)
	(via
		(at 329.633834 -416.020504)
		(size 0.4572)
		(drill 0.254)
		(layers "F.Cu" "B.Cu")
		(net "GND")
	)
	(via
		(at 76.697332 -406.370536)
		(size 0.4572)
		(drill 0.254)
		(layers "F.Cu" "B.Cu")
		(net "GND")
	)
	(via
		(at 341.487252 -161.981134)
		(size 0.49022)
		(drill 0.254)
		(layers "F.Cu" "B.Cu")
		(net "GND")
	)
	(via
		(at 83.50631 -386.449062)
		(size 0.4064)
		(drill 0.2032)
		(layers "F.Cu" "B.Cu")
		(net "GND")
	)
	(via
		(at 188.177678 -211.360258)
		(size 0.4826)
		(drill 0.254)
		(layers "F.Cu" "B.Cu")
		(net "GND")
	)
	(via
		(at 116.228114 -407.638504)
		(size 0.4572)
		(drill 0.254)
		(layers "F.Cu" "B.Cu")
		(net "GND")
	)
	(via
		(at 117.244622 -270.846296)
		(size 0.4064)
		(drill 0.2032)
		(layers "F.Cu" "B.Cu")
		(net "GND")
	)
	(via
		(at 58.045096 -413.204152)
		(size 0.4572)
		(drill 0.254)
		(layers "F.Cu" "B.Cu")
		(net "GND")
	)
	(via
		(at 426.51172 -347.210126)
		(size 0.508)
		(drill 0.254)
		(layers "F.Cu" "B.Cu")
		(net "GND")
	)
	(via
		(at 446.592452 -395.284452)
		(size 0.49022)
		(drill 0.254)
		(layers "F.Cu" "B.Cu")
		(net "GND")
	)
	(via
		(at 341.390986 -230.714042)
		(size 0.4064)
		(drill 0.2032)
		(layers "F.Cu" "B.Cu")
		(net "GND")
	)
	(via
		(at 73.276714 -332.41615)
		(size 0.508)
		(drill 0.254)
		(layers "F.Cu" "B.Cu")
		(net "GND")
	)
	(via
		(at 370.82476 -282.186126)
		(size 0.4064)
		(drill 0.2032)
		(layers "F.Cu" "B.Cu")
		(net "GND")
	)
	(via
		(at 82.174842 -372.15953)
		(size 0.508)
		(drill 0.254)
		(layers "F.Cu" "B.Cu")
		(net "GND")
	)
	(via
		(at 339.811106 -278.946102)
		(size 0.4064)
		(drill 0.2032)
		(layers "F.Cu" "B.Cu")
		(net "GND")
	)
	(via
		(at 120.75541 -167.141398)
		(size 0.508)
		(drill 0.254)
		(layers "F.Cu" "B.Cu")
		(net "GND")
	)
	(via
		(at 71.897748 -178.799744)
		(size 0.49022)
		(drill 0.254)
		(layers "F.Cu" "B.Cu")
		(net "GND")
	)
	(via
		(at 394.349478 -436.347362)
		(size 0.4572)
		(drill 0.2032)
		(layers "F.Cu" "B.Cu")
		(net "GND")
	)
	(via
		(at 309.481474 -35.94862)
		(size 0.508)
		(drill 0.254)
		(layers "F.Cu" "B.Cu")
		(net "GND")
	)
	(via
		(at 145.444718 -278.946356)
		(size 0.4064)
		(drill 0.2032)
		(layers "F.Cu" "B.Cu")
		(net "GND")
	)
	(via
		(at 385.876292 -379.88113)
		(size 0.508)
		(drill 0.254)
		(layers "F.Cu" "B.Cu")
		(net "GND")
	)
	(via
		(at 93.751146 -288.666174)
		(size 0.4064)
		(drill 0.2032)
		(layers "F.Cu" "B.Cu")
		(net "GND")
	)
	(via
		(at 208.965546 -14.404848)
		(size 0.508)
		(drill 0.254)
		(layers "F.Cu" "B.Cu")
		(net "GND")
	)
	(via
		(at 47.784004 -279.785318)
		(size 0.4826)
		(drill 0.254)
		(layers "F.Cu" "B.Cu")
		(net "GND")
	)
	(via
		(at 302.240696 -377.41733)
		(size 0.508)
		(drill 0.254)
		(layers "F.Cu" "B.Cu")
		(net "GND")
	)
	(via
		(at 326.651112 -270.846042)
		(size 0.4064)
		(drill 0.2032)
		(layers "F.Cu" "B.Cu")
		(net "GND")
	)
	(via
		(at 53.391308 -390.160002)
		(size 0.4064)
		(drill 0.2032)
		(layers "F.Cu" "B.Cu")
		(net "GND")
	)
	(via
		(at 311.968896 -379.88113)
		(size 0.508)
		(drill 0.254)
		(layers "F.Cu" "B.Cu")
		(net "GND")
	)
	(via
		(at 206.248 -271.285208)
		(size 0.4826)
		(drill 0.254)
		(layers "F.Cu" "B.Cu")
		(net "GND")
	)
	(via
		(at 202.147932 -290.835334)
		(size 0.4826)
		(drill 0.254)
		(layers "F.Cu" "B.Cu")
		(net "GND")
	)
	(via
		(at 401.349718 -436.051198)
		(size 0.4572)
		(drill 0.2032)
		(layers "F.Cu" "B.Cu")
		(net "GND")
	)
	(via
		(at 401.349718 -430.147222)
		(size 0.4572)
		(drill 0.2032)
		(layers "F.Cu" "B.Cu")
		(net "GND")
	)
	(via
		(at 99.903788 -399.630138)
		(size 0.508)
		(drill 0.254)
		(layers "F.Cu" "B.Cu")
		(net "GND")
	)
	(via
		(at 69.532754 -335.566004)
		(size 0.49022)
		(drill 0.254)
		(layers "F.Cu" "B.Cu")
		(net "GND")
	)
	(via
		(at 321.55638 -333.046324)
		(size 0.508)
		(drill 0.254)
		(layers "F.Cu" "B.Cu")
		(net "GND")
	)
	(via
		(at 126.34976 -427.851316)
		(size 0.4572)
		(drill 0.2032)
		(layers "F.Cu" "B.Cu")
		(net "GND")
	)
	(via
		(at 186.932316 -329.576684)
		(size 0.508)
		(drill 0.254)
		(layers "F.Cu" "B.Cu")
		(net "GND")
	)
	(via
		(at 337.687158 -310.428132)
		(size 0.508)
		(drill 0.254)
		(layers "F.Cu" "B.Cu")
		(net "GND")
	)
	(via
		(at 170.844718 -390.71169)
		(size 0.508)
		(drill 0.254)
		(layers "F.Cu" "B.Cu")
		(net "GND")
	)
	(via
		(at 150.488904 -372.15953)
		(size 0.508)
		(drill 0.254)
		(layers "F.Cu" "B.Cu")
		(net "GND")
	)
	(via
		(at 99.561142 -244.484398)
		(size 0.4064)
		(drill 0.2032)
		(layers "F.Cu" "B.Cu")
		(net "GND")
	)
	(via
		(at 276.036532 -192.21831)
		(size 0.4826)
		(drill 0.254)
		(layers "F.Cu" "B.Cu")
		(net "GND")
	)
	(via
		(at 48.939704 -194.885564)
		(size 0.4826)
		(drill 0.254)
		(layers "F.Cu" "B.Cu")
		(net "GND")
	)
	(via
		(at 352.027998 -261.128002)
		(size 0.4064)
		(drill 0.2032)
		(layers "F.Cu" "B.Cu")
		(net "GND")
	)
	(via
		(at 413.752284 -296.78503)
		(size 0.4826)
		(drill 0.254)
		(layers "F.Cu" "B.Cu")
		(net "GND")
	)
	(via
		(at 133.394704 -223.424496)
		(size 0.4064)
		(drill 0.2032)
		(layers "F.Cu" "B.Cu")
		(net "GND")
	)
	(via
		(at 195.721732 -220.710252)
		(size 0.4826)
		(drill 0.254)
		(layers "F.Cu" "B.Cu")
		(net "GND")
	)
	(via
		(at 228.092 -285.331408)
		(size 0.508)
		(drill 0.254)
		(layers "F.Cu" "B.Cu")
		(net "GND")
	)
	(via
		(at 95.1611 -286.23641)
		(size 0.4064)
		(drill 0.2032)
		(layers "F.Cu" "B.Cu")
		(net "GND")
	)
	(via
		(at 425.539154 -441.227718)
		(size 0.508)
		(drill 0.254)
		(layers "F.Cu" "B.Cu")
		(net "GND")
	)
	(via
		(at 130.104642 -224.234502)
		(size 0.4064)
		(drill 0.2032)
		(layers "F.Cu" "B.Cu")
		(net "GND")
	)
	(via
		(at 67.507612 -406.34666)
		(size 0.4572)
		(drill 0.254)
		(layers "F.Cu" "B.Cu")
		(net "GND")
	)
	(via
		(at 336.22107 -229.904036)
		(size 0.4064)
		(drill 0.2032)
		(layers "F.Cu" "B.Cu")
		(net "GND")
	)
	(via
		(at 407.862024 -18.247868)
		(size 0.508)
		(drill 0.254)
		(layers "F.Cu" "B.Cu")
		(net "GND")
	)
	(via
		(at 292.280086 -222.834962)
		(size 0.4826)
		(drill 0.254)
		(layers "F.Cu" "B.Cu")
		(net "GND")
	)
	(via
		(at 25.152096 -307.8353)
		(size 0.4826)
		(drill 0.254)
		(layers "F.Cu" "B.Cu")
		(net "GND")
	)
	(via
		(at 9.106408 -171.57954)
		(size 0.508)
		(drill 0.254)
		(layers "F.Cu" "B.Cu")
		(net "GND")
	)
	(via
		(at 65.378584 -386.449062)
		(size 0.4064)
		(drill 0.2032)
		(layers "F.Cu" "B.Cu")
		(net "GND")
	)
	(via
		(at 194.312032 -106.262932)
		(size 0.4572)
		(drill 0.254)
		(layers "F.Cu" "B.Cu")
		(net "GND")
	)
	(via
		(at 54.210458 -239.410494)
		(size 0.4826)
		(drill 0.254)
		(layers "F.Cu" "B.Cu")
		(net "GND")
	)
	(via
		(at 60.848494 -339.883496)
		(size 0.508)
		(drill 0.254)
		(layers "F.Cu" "B.Cu")
		(net "GND")
	)
	(via
		(at 367.645442 -172.62094)
		(size 0.508)
		(drill 0.254)
		(layers "F.Cu" "B.Cu")
		(net "GND")
	)
	(via
		(at 419.912038 -252.584966)
		(size 0.4826)
		(drill 0.254)
		(layers "F.Cu" "B.Cu")
		(net "GND")
	)
	(via
		(at 44.94022 -351.862898)
		(size 0.508)
		(drill 0.254)
		(layers "F.Cu" "B.Cu")
		(net "GND")
	)
	(via
		(at 149.923754 -409.396184)
		(size 0.4572)
		(drill 0.254)
		(layers "F.Cu" "B.Cu")
		(net "GND")
	)
	(via
		(at 140.444728 -222.61449)
		(size 0.4064)
		(drill 0.2032)
		(layers "F.Cu" "B.Cu")
		(net "GND")
	)
	(via
		(at 118.65483 -270.03629)
		(size 0.4064)
		(drill 0.2032)
		(layers "F.Cu" "B.Cu")
		(net "GND")
	)
	(via
		(at 148.218906 -390.160002)
		(size 0.4064)
		(drill 0.2032)
		(layers "F.Cu" "B.Cu")
		(net "GND")
	)
	(via
		(at 124.934726 -255.824482)
		(size 0.4064)
		(drill 0.2032)
		(layers "F.Cu" "B.Cu")
		(net "GND")
	)
	(via
		(at 424.012106 -198.185024)
		(size 0.4826)
		(drill 0.254)
		(layers "F.Cu" "B.Cu")
		(net "GND")
	)
	(via
		(at 161.490152 -384.617722)
		(size 0.4064)
		(drill 0.2032)
		(layers "F.Cu" "B.Cu")
		(net "GND")
	)
	(via
		(at 364.122208 -259.845048)
		(size 0.4826)
		(drill 0.254)
		(layers "F.Cu" "B.Cu")
		(net "GND")
	)
	(via
		(at 344.681048 -239.624108)
		(size 0.4064)
		(drill 0.2032)
		(layers "F.Cu" "B.Cu")
		(net "GND")
	)
	(via
		(at 108.832142 -257.74523)
		(size 0.4826)
		(drill 0.254)
		(layers "F.Cu" "B.Cu")
		(net "GND")
	)
	(via
		(at 133.075934 -403.830536)
		(size 0.4572)
		(drill 0.254)
		(layers "F.Cu" "B.Cu")
		(net "GND")
	)
	(via
		(at 421.067738 -194.88531)
		(size 0.4826)
		(drill 0.254)
		(layers "F.Cu" "B.Cu")
		(net "GND")
	)
	(via
		(at 16.784574 -386.914898)
		(size 0.49022)
		(drill 0.254)
		(layers "F.Cu" "B.Cu")
		(net "GND")
	)
	(via
		(at 173.495208 -342.785192)
		(size 0.508)
		(drill 0.254)
		(layers "F.Cu" "B.Cu")
		(net "GND")
	)
	(via
		(at 18.310098 -6.598158)
		(size 0.508)
		(drill 0.254)
		(layers "F.Cu" "B.Cu")
		(net "GND")
	)
	(via
		(at 406.788874 -170.53306)
		(size 0.49022)
		(drill 0.254)
		(layers "F.Cu" "B.Cu")
		(net "GND")
	)
	(via
		(at 424.565064 -154.8003)
		(size 0.508)
		(drill 0.254)
		(layers "F.Cu" "B.Cu")
		(net "GND")
	)
	(via
		(at 283.351732 -302.73498)
		(size 0.4826)
		(drill 0.254)
		(layers "F.Cu" "B.Cu")
		(net "GND")
	)
	(via
		(at 444.021464 -9.412732)
		(size 0.508)
		(drill 0.254)
		(layers "F.Cu" "B.Cu")
		(net "GND")
	)
	(via
		(at 125.0442 -31.594806)
		(size 0.508)
		(drill 0.254)
		(layers "F.Cu" "B.Cu")
		(net "GND")
	)
	(via
		(at 233.64952 -289.552126)
		(size 0.508)
		(drill 0.254)
		(layers "F.Cu" "B.Cu")
		(net "GND")
	)
	(via
		(at 80.291178 -225.854514)
		(size 0.4064)
		(drill 0.2032)
		(layers "F.Cu" "B.Cu")
		(net "GND")
	)
	(via
		(at 338.02828 -131.63931)
		(size 0.508)
		(drill 0.254)
		(layers "F.Cu" "B.Cu")
		(net "GND")
	)
	(via
		(at 303.268126 -242.385088)
		(size 0.4826)
		(drill 0.254)
		(layers "F.Cu" "B.Cu")
		(net "GND")
	)
	(via
		(at 294.606472 -286.16021)
		(size 0.4826)
		(drill 0.254)
		(layers "F.Cu" "B.Cu")
		(net "GND")
	)
	(via
		(at 121.474738 -266.796266)
		(size 0.4064)
		(drill 0.2032)
		(layers "F.Cu" "B.Cu")
		(net "GND")
	)
	(via
		(at 39.12235 -314.210446)
		(size 0.4826)
		(drill 0.254)
		(layers "F.Cu" "B.Cu")
		(net "GND")
	)
	(via
		(at 345.151202 -256.634234)
		(size 0.4064)
		(drill 0.2032)
		(layers "F.Cu" "B.Cu")
		(net "GND")
	)
	(via
		(at 123.525026 -412.570168)
		(size 0.4064)
		(drill 0.2032)
		(layers "F.Cu" "B.Cu")
		(net "GND")
	)
	(via
		(at 344.591386 -415.38652)
		(size 0.4064)
		(drill 0.2032)
		(layers "F.Cu" "B.Cu")
		(net "GND")
	)
	(via
		(at 203.532232 -296.785284)
		(size 0.4826)
		(drill 0.254)
		(layers "F.Cu" "B.Cu")
		(net "GND")
	)
	(via
		(at 313.416188 -400.212814)
		(size 0.4064)
		(drill 0.2032)
		(layers "F.Cu" "B.Cu")
		(net "GND")
	)
	(via
		(at 356.674674 -170.64609)
		(size 0.49022)
		(drill 0.254)
		(layers "F.Cu" "B.Cu")
		(net "GND")
	)
	(via
		(at 16.704818 -410.31287)
		(size 0.508)
		(drill 0.254)
		(layers "F.Cu" "B.Cu")
		(net "GND")
	)
	(via
		(at 366.294924 -226.664266)
		(size 0.4064)
		(drill 0.2032)
		(layers "F.Cu" "B.Cu")
		(net "GND")
	)
	(via
		(at 416.730942 -415.362644)
		(size 0.4064)
		(drill 0.2032)
		(layers "F.Cu" "B.Cu")
		(net "GND")
	)
	(via
		(at 268.263878 -221.13494)
		(size 0.4826)
		(drill 0.254)
		(layers "F.Cu" "B.Cu")
		(net "GND")
	)
	(via
		(at 80.940402 -333.827628)
		(size 0.49022)
		(drill 0.254)
		(layers "F.Cu" "B.Cu")
		(net "GND")
	)
	(via
		(at 135.574786 -291.096192)
		(size 0.4064)
		(drill 0.2032)
		(layers "F.Cu" "B.Cu")
		(net "GND")
	)
	(via
		(at 97.681034 -250.964446)
		(size 0.4064)
		(drill 0.2032)
		(layers "F.Cu" "B.Cu")
		(net "GND")
	)
	(via
		(at 105.200958 -233.144314)
		(size 0.4064)
		(drill 0.2032)
		(layers "F.Cu" "B.Cu")
		(net "GND")
	)
	(via
		(at 50.991262 -390.160002)
		(size 0.4064)
		(drill 0.2032)
		(layers "F.Cu" "B.Cu")
		(net "GND")
	)
	(via
		(at 361.424728 -287.045908)
		(size 0.4064)
		(drill 0.2032)
		(layers "F.Cu" "B.Cu")
		(net "GND")
	)
	(via
		(at 332.931008 -229.094284)
		(size 0.4064)
		(drill 0.2032)
		(layers "F.Cu" "B.Cu")
		(net "GND")
	)
	(via
		(at 335.11109 -262.745982)
		(size 0.4064)
		(drill 0.2032)
		(layers "F.Cu" "B.Cu")
		(net "GND")
	)
	(via
		(at 212.230716 -325.456296)
		(size 0.508)
		(drill 0.254)
		(layers "F.Cu" "B.Cu")
		(net "GND")
	)
	(via
		(at 235.960666 -324.793102)
		(size 0.508)
		(drill 0.254)
		(layers "F.Cu" "B.Cu")
		(net "GND")
	)
	(via
		(at 70.298056 -405.098504)
		(size 0.4572)
		(drill 0.254)
		(layers "F.Cu" "B.Cu")
		(net "GND")
	)
	(via
		(at 153.349706 -431.29962)
		(size 0.4572)
		(drill 0.2032)
		(layers "F.Cu" "B.Cu")
		(net "GND")
	)
	(via
		(at 157.349698 -438.499758)
		(size 0.4572)
		(drill 0.2032)
		(layers "F.Cu" "B.Cu")
		(net "GND")
	)
	(via
		(at 113.283238 -43.358054)
		(size 0.508)
		(drill 0.254)
		(layers "F.Cu" "B.Cu")
		(net "GND")
	)
	(via
		(at 206.248 -243.235226)
		(size 0.4826)
		(drill 0.254)
		(layers "F.Cu" "B.Cu")
		(net "GND")
	)
	(via
		(at 388.931658 -311.822592)
		(size 0.508)
		(drill 0.254)
		(layers "F.Cu" "B.Cu")
		(net "GND")
	)
	(via
		(at 364.366302 -27.1653)
		(size 0.508)
		(drill 0.254)
		(layers "F.Cu" "B.Cu")
		(net "GND")
	)
	(via
		(at 410.51861 -420.318184)
		(size 0.4572)
		(drill 0.254)
		(layers "F.Cu" "B.Cu")
		(net "GND")
	)
	(via
		(at 115.534694 -246.10441)
		(size 0.4064)
		(drill 0.2032)
		(layers "F.Cu" "B.Cu")
		(net "GND")
	)
	(via
		(at 112.15751 -175.167798)
		(size 0.508)
		(drill 0.254)
		(layers "F.Cu" "B.Cu")
		(net "GND")
	)
	(via
		(at 429.568102 -12.37488)
		(size 0.508)
		(drill 0.254)
		(layers "F.Cu" "B.Cu")
		(net "GND")
	)
	(via
		(at 112.58169 -173.897798)
		(size 0.508)
		(drill 0.254)
		(layers "F.Cu" "B.Cu")
		(net "GND")
	)
	(via
		(at 435.000146 -225.385122)
		(size 0.4826)
		(drill 0.254)
		(layers "F.Cu" "B.Cu")
		(net "GND")
	)
	(via
		(at 96.571054 -262.746236)
		(size 0.4064)
		(drill 0.2032)
		(layers "F.Cu" "B.Cu")
		(net "GND")
	)
	(via
		(at 151.313642 -73.589134)
		(size 0.508)
		(drill 0.254)
		(layers "F.Cu" "B.Cu")
		(net "GND")
	)
	(via
		(at 160.283906 -404.46452)
		(size 0.4064)
		(drill 0.2032)
		(layers "F.Cu" "B.Cu")
		(net "GND")
	)
	(via
		(at 76.338684 -410.030168)
		(size 0.4064)
		(drill 0.2032)
		(layers "F.Cu" "B.Cu")
		(net "GND")
	)
	(via
		(at 366.124744 -293.525956)
		(size 0.4064)
		(drill 0.2032)
		(layers "F.Cu" "B.Cu")
		(net "GND")
	)
	(via
		(at 124.078492 -386.449062)
		(size 0.4064)
		(drill 0.2032)
		(layers "F.Cu" "B.Cu")
		(net "GND")
	)
	(via
		(at 106.405172 -257.43027)
		(size 0.4826)
		(drill 0.254)
		(layers "F.Cu" "B.Cu")
		(net "GND")
	)
	(via
		(at 60.381134 -348.709488)
		(size 0.49022)
		(drill 0.254)
		(layers "F.Cu" "B.Cu")
		(net "GND")
	)
	(via
		(at 132.284724 -293.52621)
		(size 0.4064)
		(drill 0.2032)
		(layers "F.Cu" "B.Cu")
		(net "GND")
	)
	(via
		(at 140.246862 -81.057242)
		(size 0.508)
		(drill 0.254)
		(layers "F.Cu" "B.Cu")
		(net "GND")
	)
	(via
		(at 283.06141 -344.77706)
		(size 0.49022)
		(drill 0.254)
		(layers "F.Cu" "B.Cu")
		(net "GND")
	)
	(via
		(at 326.065896 -377.41733)
		(size 0.508)
		(drill 0.254)
		(layers "F.Cu" "B.Cu")
		(net "GND")
	)
	(via
		(at 26.536396 -278.085296)
		(size 0.4826)
		(drill 0.254)
		(layers "F.Cu" "B.Cu")
		(net "GND")
	)
	(via
		(at 416.468052 -250.03506)
		(size 0.4826)
		(drill 0.254)
		(layers "F.Cu" "B.Cu")
		(net "GND")
	)
	(via
		(at 33.189672 -4.963414)
		(size 0.508)
		(drill 0.254)
		(layers "F.Cu" "B.Cu")
		(net "GND")
	)
	(via
		(at 84.79282 -354.024946)
		(size 0.508)
		(drill 0.254)
		(layers "F.Cu" "B.Cu")
		(net "GND")
	)
	(via
		(at 312.371486 -339.87867)
		(size 0.508)
		(drill 0.254)
		(layers "F.Cu" "B.Cu")
		(net "GND")
	)
	(via
		(at 80.473042 -374.62333)
		(size 0.508)
		(drill 0.254)
		(layers "F.Cu" "B.Cu")
		(net "GND")
	)
	(via
		(at 327.277476 -389.402828)
		(size 0.508)
		(drill 0.254)
		(layers "F.Cu" "B.Cu")
		(net "GND")
	)
	(via
		(at 439.100214 -318.035178)
		(size 0.4826)
		(drill 0.254)
		(layers "F.Cu" "B.Cu")
		(net "GND")
	)
	(via
		(at 40.785034 -18.503138)
		(size 0.508)
		(drill 0.254)
		(layers "F.Cu" "B.Cu")
		(net "GND")
	)
	(via
		(at 188.444378 -219.435426)
		(size 0.4826)
		(drill 0.254)
		(layers "F.Cu" "B.Cu")
		(net "GND")
	)
	(via
		(at 467.5378 -211.379054)
		(size 0.508)
		(drill 0.254)
		(layers "F.Cu" "B.Cu")
		(net "GND")
	)
	(via
		(at 113.594896 -391.77595)
		(size 0.4064)
		(drill 0.2032)
		(layers "F.Cu" "B.Cu")
		(net "GND")
	)
	(via
		(at 81.701132 -255.824482)
		(size 0.4064)
		(drill 0.2032)
		(layers "F.Cu" "B.Cu")
		(net "GND")
	)
	(via
		(at 191.160146 -215.185244)
		(size 0.4826)
		(drill 0.254)
		(layers "F.Cu" "B.Cu")
		(net "GND")
	)
	(via
		(at 27.545792 -10.16508)
		(size 0.508)
		(drill 0.254)
		(layers "F.Cu" "B.Cu")
		(net "GND")
	)
	(via
		(at 229.601014 -221.996)
		(size 0.508)
		(drill 0.254)
		(layers "F.Cu" "B.Cu")
		(net "GND")
	)
	(via
		(at 99.090988 -256.634488)
		(size 0.4064)
		(drill 0.2032)
		(layers "F.Cu" "B.Cu")
		(net "GND")
	)
	(via
		(at 183.132222 -114.262916)
		(size 0.4572)
		(drill 0.254)
		(layers "F.Cu" "B.Cu")
		(net "GND")
	)
	(via
		(at 157.349698 -426.54728)
		(size 0.4572)
		(drill 0.2032)
		(layers "F.Cu" "B.Cu")
		(net "GND")
	)
	(via
		(at 42.049954 -19.771106)
		(size 0.508)
		(drill 0.254)
		(layers "F.Cu" "B.Cu")
		(net "GND")
	)
	(via
		(at 377.404884 -293.525956)
		(size 0.4064)
		(drill 0.2032)
		(layers "F.Cu" "B.Cu")
		(net "GND")
	)
	(via
		(at 299.82414 -198.185024)
		(size 0.4826)
		(drill 0.254)
		(layers "F.Cu" "B.Cu")
		(net "GND")
	)
	(via
		(at 342.801194 -252.584204)
		(size 0.4064)
		(drill 0.2032)
		(layers "F.Cu" "B.Cu")
		(net "GND")
	)
	(via
		(at 392.92911 -189.514226)
		(size 0.508)
		(drill 0.254)
		(layers "F.Cu" "B.Cu")
		(net "GND")
	)
	(via
		(at 451.2056 -220.709998)
		(size 0.4826)
		(drill 0.254)
		(layers "F.Cu" "B.Cu")
		(net "GND")
	)
	(via
		(at 467.5378 -250.495054)
		(size 0.508)
		(drill 0.254)
		(layers "F.Cu" "B.Cu")
		(net "GND")
	)
	(via
		(at 203.532232 -219.435426)
		(size 0.4826)
		(drill 0.254)
		(layers "F.Cu" "B.Cu")
		(net "GND")
	)
	(via
		(at 393.397994 -413.480504)
		(size 0.4572)
		(drill 0.254)
		(layers "F.Cu" "B.Cu")
		(net "GND")
	)
	(via
		(at 122.878596 -386.449062)
		(size 0.4064)
		(drill 0.2032)
		(layers "F.Cu" "B.Cu")
		(net "GND")
	)
	(via
		(at 331.351128 -269.22603)
		(size 0.4064)
		(drill 0.2032)
		(layers "F.Cu" "B.Cu")
		(net "GND")
	)
	(via
		(at 304.652426 -303.585118)
		(size 0.4826)
		(drill 0.254)
		(layers "F.Cu" "B.Cu")
		(net "GND")
	)
	(via
		(at 395.038072 -385.514088)
		(size 0.508)
		(drill 0.254)
		(layers "F.Cu" "B.Cu")
		(net "GND")
	)
	(via
		(at 416.468052 -215.18499)
		(size 0.4826)
		(drill 0.254)
		(layers "F.Cu" "B.Cu")
		(net "GND")
	)
	(via
		(at 443.9285 -219.435172)
		(size 0.4826)
		(drill 0.254)
		(layers "F.Cu" "B.Cu")
		(net "GND")
	)
	(via
		(at 317.249556 -438.499758)
		(size 0.4572)
		(drill 0.2032)
		(layers "F.Cu" "B.Cu")
		(net "GND")
	)
	(via
		(at 374.284748 -246.914162)
		(size 0.4064)
		(drill 0.2032)
		(layers "F.Cu" "B.Cu")
		(net "GND")
	)
	(via
		(at 450.088 -300.185074)
		(size 0.4826)
		(drill 0.254)
		(layers "F.Cu" "B.Cu")
		(net "GND")
	)
	(via
		(at 321.816222 -391.23493)
		(size 0.4064)
		(drill 0.2032)
		(layers "F.Cu" "B.Cu")
		(net "GND")
	)
	(via
		(at 341.22106 -265.176)
		(size 0.4064)
		(drill 0.2032)
		(layers "F.Cu" "B.Cu")
		(net "GND")
	)
	(via
		(at 44.340018 -280.635202)
		(size 0.4826)
		(drill 0.254)
		(layers "F.Cu" "B.Cu")
		(net "GND")
	)
	(via
		(at 99.054666 -183.843168)
		(size 0.49022)
		(drill 0.254)
		(layers "F.Cu" "B.Cu")
		(net "GND")
	)
	(via
		(at 21.336 -359.918)
		(size 0.508)
		(drill 0.254)
		(layers "F.Cu" "B.Cu")
		(net "GND")
	)
	(via
		(at 187.911994 -112.66297)
		(size 0.4572)
		(drill 0.254)
		(layers "F.Cu" "B.Cu")
		(net "GND")
	)
	(via
		(at 164.427916 -264.485374)
		(size 0.4826)
		(drill 0.254)
		(layers "F.Cu" "B.Cu")
		(net "GND")
	)
	(via
		(at 42.955718 -199.8853)
		(size 0.4826)
		(drill 0.254)
		(layers "F.Cu" "B.Cu")
		(net "GND")
	)
	(via
		(at 168.527984 -255.13538)
		(size 0.4826)
		(drill 0.254)
		(layers "F.Cu" "B.Cu")
		(net "GND")
	)
	(via
		(at 83.8073 -340.489286)
		(size 0.508)
		(drill 0.254)
		(layers "F.Cu" "B.Cu")
		(net "GND")
	)
	(via
		(at 375.224802 -248.534174)
		(size 0.4064)
		(drill 0.2032)
		(layers "F.Cu" "B.Cu")
		(net "GND")
	)
	(via
		(at 349.851218 -242.054126)
		(size 0.4064)
		(drill 0.2032)
		(layers "F.Cu" "B.Cu")
		(net "GND")
	)
	(via
		(at 122.884692 -264.366248)
		(size 0.4064)
		(drill 0.2032)
		(layers "F.Cu" "B.Cu")
		(net "GND")
	)
	(via
		(at 440.217814 -313.360054)
		(size 0.4826)
		(drill 0.254)
		(layers "F.Cu" "B.Cu")
		(net "GND")
	)
	(via
		(at 361.894882 -279.756108)
		(size 0.4064)
		(drill 0.2032)
		(layers "F.Cu" "B.Cu")
		(net "GND")
	)
	(via
		(at 124.516642 -393.927838)
		(size 0.4572)
		(drill 0.254)
		(layers "F.Cu" "B.Cu")
		(net "GND")
	)
	(via
		(at 80.473042 -373.30253)
		(size 0.508)
		(drill 0.254)
		(layers "F.Cu" "B.Cu")
		(net "GND")
	)
	(via
		(at 96.571054 -283.806392)
		(size 0.4064)
		(drill 0.2032)
		(layers "F.Cu" "B.Cu")
		(net "GND")
	)
	(via
		(at 349.211138 -282.186126)
		(size 0.4064)
		(drill 0.2032)
		(layers "F.Cu" "B.Cu")
		(net "GND")
	)
	(via
		(at 90.16111 -250.964446)
		(size 0.4064)
		(drill 0.2032)
		(layers "F.Cu" "B.Cu")
		(net "GND")
	)
	(via
		(at 263.645396 -439.90768)
		(size 0.508)
		(drill 0.254)
		(layers "F.Cu" "B.Cu")
		(net "GND")
	)
	(via
		(at 350.744028 -391.23493)
		(size 0.4064)
		(drill 0.2032)
		(layers "F.Cu" "B.Cu")
		(net "GND")
	)
	(via
		(at 91.871038 -285.426404)
		(size 0.4064)
		(drill 0.2032)
		(layers "F.Cu" "B.Cu")
		(net "GND")
	)
	(via
		(at 145.444718 -269.226284)
		(size 0.4064)
		(drill 0.2032)
		(layers "F.Cu" "B.Cu")
		(net "GND")
	)
	(via
		(at 41.62425 -210.085432)
		(size 0.4826)
		(drill 0.254)
		(layers "F.Cu" "B.Cu")
		(net "GND")
	)
	(via
		(at 82.001106 -284.616398)
		(size 0.4064)
		(drill 0.2032)
		(layers "F.Cu" "B.Cu")
		(net "GND")
	)
	(via
		(at 385.394708 -274.896072)
		(size 0.4064)
		(drill 0.2032)
		(layers "F.Cu" "B.Cu")
		(net "GND")
	)
	(via
		(at 336.9945 -333.03845)
		(size 0.49022)
		(drill 0.254)
		(layers "F.Cu" "B.Cu")
		(net "GND")
	)
	(via
		(at 338.911946 -420.952168)
		(size 0.4064)
		(drill 0.2032)
		(layers "F.Cu" "B.Cu")
		(net "GND")
	)
	(via
		(at 283.580332 -192.21831)
		(size 0.4826)
		(drill 0.254)
		(layers "F.Cu" "B.Cu")
		(net "GND")
	)
	(via
		(at 99.561142 -254.20447)
		(size 0.4064)
		(drill 0.2032)
		(layers "F.Cu" "B.Cu")
		(net "GND")
	)
	(via
		(at 95.194374 -337.017614)
		(size 0.49022)
		(drill 0.254)
		(layers "F.Cu" "B.Cu")
		(net "GND")
	)
	(via
		(at 421.92194 -102.660958)
		(size 0.6604)
		(drill 0.3302)
		(layers "F.Cu" "B.Cu")
		(net "GND")
	)
	(via
		(at 364.636812 -397.485108)
		(size 0.508)
		(drill 0.254)
		(layers "F.Cu" "B.Cu")
		(net "GND")
	)
	(via
		(at 376.634756 -239.624108)
		(size 0.4064)
		(drill 0.2032)
		(layers "F.Cu" "B.Cu")
		(net "GND")
	)
	(via
		(at 286.913066 -344.767408)
		(size 0.508)
		(drill 0.254)
		(layers "F.Cu" "B.Cu")
		(net "GND")
	)
	(via
		(at 395.362176 -187.466986)
		(size 0.508)
		(drill 0.254)
		(layers "F.Cu" "B.Cu")
		(net "GND")
	)
	(via
		(at 122.081798 -405.098504)
		(size 0.4572)
		(drill 0.254)
		(layers "F.Cu" "B.Cu")
		(net "GND")
	)
	(via
		(at 206.248 -232.18521)
		(size 0.4826)
		(drill 0.254)
		(layers "F.Cu" "B.Cu")
		(net "GND")
	)
	(via
		(at 436.852822 -406.33396)
		(size 0.508)
		(drill 0.254)
		(layers "F.Cu" "B.Cu")
		(net "GND")
	)
	(via
		(at 49.168304 -203.285344)
		(size 0.4826)
		(drill 0.254)
		(layers "F.Cu" "B.Cu")
		(net "GND")
	)
	(via
		(at 336.521044 -289.475926)
		(size 0.4064)
		(drill 0.2032)
		(layers "F.Cu" "B.Cu")
		(net "GND")
	)
	(via
		(at 126.34976 -429.147224)
		(size 0.4572)
		(drill 0.2032)
		(layers "F.Cu" "B.Cu")
		(net "GND")
	)
	(via
		(at 177.189638 -285.310326)
		(size 0.4826)
		(drill 0.254)
		(layers "F.Cu" "B.Cu")
		(net "GND")
	)
	(via
		(at 135.574786 -271.656302)
		(size 0.4064)
		(drill 0.2032)
		(layers "F.Cu" "B.Cu")
		(net "GND")
	)
	(via
		(at 132.284724 -264.366248)
		(size 0.4064)
		(drill 0.2032)
		(layers "F.Cu" "B.Cu")
		(net "GND")
	)
	(via
		(at 381.804926 -240.434114)
		(size 0.4064)
		(drill 0.2032)
		(layers "F.Cu" "B.Cu")
		(net "GND")
	)
	(via
		(at 176.072038 -204.135228)
		(size 0.4826)
		(drill 0.254)
		(layers "F.Cu" "B.Cu")
		(net "GND")
	)
	(via
		(at 40.23995 -318.885316)
		(size 0.4826)
		(drill 0.254)
		(layers "F.Cu" "B.Cu")
		(net "GND")
	)
	(via
		(at 455.305668 -229.210108)
		(size 0.4826)
		(drill 0.254)
		(layers "F.Cu" "B.Cu")
		(net "GND")
	)
	(via
		(at 313.958986 -418.412168)
		(size 0.4064)
		(drill 0.2032)
		(layers "F.Cu" "B.Cu")
		(net "GND")
	)
	(via
		(at 422.2115 -394.831062)
		(size 0.4064)
		(drill 0.2032)
		(layers "F.Cu" "B.Cu")
		(net "GND")
	)
	(via
		(at 429.288956 -16.9799)
		(size 0.508)
		(drill 0.254)
		(layers "F.Cu" "B.Cu")
		(net "GND")
	)
	(via
		(at 164.427916 -227.085398)
		(size 0.4826)
		(drill 0.254)
		(layers "F.Cu" "B.Cu")
		(net "GND")
	)
	(via
		(at 433.347876 -18.503138)
		(size 0.508)
		(drill 0.254)
		(layers "F.Cu" "B.Cu")
		(net "GND")
	)
	(via
		(at 183.616092 -265.335258)
		(size 0.4826)
		(drill 0.254)
		(layers "F.Cu" "B.Cu")
		(net "GND")
	)
	(via
		(at 25.465278 -19.13636)
		(size 0.508)
		(drill 0.254)
		(layers "F.Cu" "B.Cu")
		(net "GND")
	)
	(via
		(at 411.5943 -383.00533)
		(size 0.508)
		(drill 0.254)
		(layers "F.Cu" "B.Cu")
		(net "GND")
	)
	(via
		(at 164.427916 -247.485408)
		(size 0.4826)
		(drill 0.254)
		(layers "F.Cu" "B.Cu")
		(net "GND")
	)
	(via
		(at 417.818062 -418.412168)
		(size 0.4064)
		(drill 0.2032)
		(layers "F.Cu" "B.Cu")
		(net "GND")
	)
	(via
		(at 157.296104 -372.15953)
		(size 0.508)
		(drill 0.254)
		(layers "F.Cu" "B.Cu")
		(net "GND")
	)
	(via
		(at 284.736032 -233.884978)
		(size 0.4826)
		(drill 0.254)
		(layers "F.Cu" "B.Cu")
		(net "GND")
	)
	(via
		(at 191.85509 -75.079606)
		(size 0.508)
		(drill 0.254)
		(layers "F.Cu" "B.Cu")
		(net "GND")
	)
	(via
		(at 179.346606 -417.426394)
		(size 0.508)
		(drill 0.254)
		(layers "F.Cu" "B.Cu")
		(net "GND")
	)
	(via
		(at 323.249544 -438.651396)
		(size 0.4572)
		(drill 0.2032)
		(layers "F.Cu" "B.Cu")
		(net "GND")
	)
	(via
		(at 143.349726 -431.451258)
		(size 0.4572)
		(drill 0.2032)
		(layers "F.Cu" "B.Cu")
		(net "GND")
	)
	(via
		(at 141.306042 -80.079342)
		(size 0.508)
		(drill 0.254)
		(layers "F.Cu" "B.Cu")
		(net "GND")
	)
	(via
		(at 121.209562 -257.930396)
		(size 0.4826)
		(drill 0.254)
		(layers "F.Cu" "B.Cu")
		(net "GND")
	)
	(via
		(at 298.43984 -277.235158)
		(size 0.4826)
		(drill 0.254)
		(layers "F.Cu" "B.Cu")
		(net "GND")
	)
	(via
		(at 75.520042 -419.397688)
		(size 0.508)
		(drill 0.254)
		(layers "F.Cu" "B.Cu")
		(net "GND")
	)
	(via
		(at 389.79475 -244.484144)
		(size 0.4064)
		(drill 0.2032)
		(layers "F.Cu" "B.Cu")
		(net "GND")
	)
	(via
		(at 265.54811 -242.385088)
		(size 0.4826)
		(drill 0.254)
		(layers "F.Cu" "B.Cu")
		(net "GND")
	)
	(via
		(at 348.271084 -265.986006)
		(size 0.4064)
		(drill 0.2032)
		(layers "F.Cu" "B.Cu")
		(net "GND")
	)
	(via
		(at 320.17843 -394.831062)
		(size 0.4064)
		(drill 0.2032)
		(layers "F.Cu" "B.Cu")
		(net "GND")
	)
	(via
		(at 394.349478 -426.69968)
		(size 0.4572)
		(drill 0.2032)
		(layers "F.Cu" "B.Cu")
		(net "GND")
	)
	(via
		(at 35.579558 -345.571064)
		(size 0.49022)
		(drill 0.254)
		(layers "F.Cu" "B.Cu")
		(net "GND")
	)
	(via
		(at 65.249806 -430.147222)
		(size 0.4572)
		(drill 0.2032)
		(layers "F.Cu" "B.Cu")
		(net "GND")
	)
	(via
		(at 132.75818 -295.98366)
		(size 0.4064)
		(drill 0.2032)
		(layers "F.Cu" "B.Cu")
		(net "GND")
	)
	(via
		(at 134.349744 -437.49976)
		(size 0.4572)
		(drill 0.2032)
		(layers "F.Cu" "B.Cu")
		(net "GND")
	)
	(via
		(at 346.91828 -331.780134)
		(size 0.508)
		(drill 0.254)
		(layers "F.Cu" "B.Cu")
		(net "GND")
	)
	(via
		(at 29.05887 -383.37109)
		(size 0.49022)
		(drill 0.254)
		(layers "F.Cu" "B.Cu")
		(net "GND")
	)
	(via
		(at 391.974832 -265.176)
		(size 0.4064)
		(drill 0.2032)
		(layers "F.Cu" "B.Cu")
		(net "GND")
	)
	(via
		(at 383.514854 -292.71595)
		(size 0.4064)
		(drill 0.2032)
		(layers "F.Cu" "B.Cu")
		(net "GND")
	)
	(via
		(at 61.233558 -345.571064)
		(size 0.49022)
		(drill 0.254)
		(layers "F.Cu" "B.Cu")
		(net "GND")
	)
	(via
		(at 352.031046 -265.986006)
		(size 0.4064)
		(drill 0.2032)
		(layers "F.Cu" "B.Cu")
		(net "GND")
	)
	(via
		(at 371.93474 -246.104156)
		(size 0.4064)
		(drill 0.2032)
		(layers "F.Cu" "B.Cu")
		(net "GND")
	)
	(via
		(at 333.90332 -362.01096)
		(size 0.508)
		(drill 0.254)
		(layers "F.Cu" "B.Cu")
		(net "GND")
	)
	(via
		(at 422.856406 -192.21831)
		(size 0.4826)
		(drill 0.254)
		(layers "F.Cu" "B.Cu")
		(net "GND")
	)
	(via
		(at 385.094734 -255.824228)
		(size 0.4064)
		(drill 0.2032)
		(layers "F.Cu" "B.Cu")
		(net "GND")
	)
	(via
		(at 18.54835 -9.424924)
		(size 0.508)
		(drill 0.254)
		(layers "F.Cu" "B.Cu")
		(net "GND")
	)
	(via
		(at 304.468276 -14.48181)
		(size 0.508)
		(drill 0.254)
		(layers "F.Cu" "B.Cu")
		(net "GND")
	)
	(via
		(at 274.476464 -303.585118)
		(size 0.4826)
		(drill 0.254)
		(layers "F.Cu" "B.Cu")
		(net "GND")
	)
	(via
		(at 326.26554 -395.466062)
		(size 0.508)
		(drill 0.254)
		(layers "F.Cu" "B.Cu")
		(net "GND")
	)
	(via
		(at 182.939182 -349.356172)
		(size 0.49022)
		(drill 0.254)
		(layers "F.Cu" "B.Cu")
		(net "GND")
	)
	(via
		(at 117.475 -440.309)
		(size 0.508)
		(drill 0.254)
		(layers "F.Cu" "B.Cu")
		(net "GND")
	)
	(via
		(at 47.664624 -19.771868)
		(size 0.508)
		(drill 0.254)
		(layers "F.Cu" "B.Cu")
		(net "GND")
	)
	(via
		(at 64.532764 -412.570168)
		(size 0.4064)
		(drill 0.2032)
		(layers "F.Cu" "B.Cu")
		(net "GND")
	)
	(via
		(at 349.544894 -412.212536)
		(size 0.4572)
		(drill 0.254)
		(layers "F.Cu" "B.Cu")
		(net "GND")
	)
	(via
		(at 25.152096 -214.33536)
		(size 0.4826)
		(drill 0.254)
		(layers "F.Cu" "B.Cu")
		(net "GND")
	)
	(via
		(at 369.884706 -274.086066)
		(size 0.4064)
		(drill 0.2032)
		(layers "F.Cu" "B.Cu")
		(net "GND")
	)
	(via
		(at 49.668176 -12.37488)
		(size 0.508)
		(drill 0.254)
		(layers "F.Cu" "B.Cu")
		(net "GND")
	)
	(via
		(at 121.174764 -252.584458)
		(size 0.4064)
		(drill 0.2032)
		(layers "F.Cu" "B.Cu")
		(net "GND")
	)
	(via
		(at 95.165164 -412.570168)
		(size 0.4064)
		(drill 0.2032)
		(layers "F.Cu" "B.Cu")
		(net "GND")
	)
	(via
		(at 116.314474 -54.026562)
		(size 0.508)
		(drill 0.254)
		(layers "F.Cu" "B.Cu")
		(net "GND")
	)
	(via
		(at 421.296338 -303.585118)
		(size 0.4826)
		(drill 0.254)
		(layers "F.Cu" "B.Cu")
		(net "GND")
	)
	(via
		(at 88.817704 -70.283832)
		(size 0.508)
		(drill 0.254)
		(layers "F.Cu" "B.Cu")
		(net "GND")
	)
	(via
		(at 27.724354 -348.709488)
		(size 0.49022)
		(drill 0.254)
		(layers "F.Cu" "B.Cu")
		(net "GND")
	)
	(via
		(at 266.93241 -219.435172)
		(size 0.4826)
		(drill 0.254)
		(layers "F.Cu" "B.Cu")
		(net "GND")
	)
	(via
		(at 17.608042 -290.835334)
		(size 0.4826)
		(drill 0.254)
		(layers "F.Cu" "B.Cu")
		(net "GND")
	)
	(via
		(at 275.807932 -277.235158)
		(size 0.4826)
		(drill 0.254)
		(layers "F.Cu" "B.Cu")
		(net "GND")
	)
	(via
		(at 377.678442 -394.831062)
		(size 0.4064)
		(drill 0.2032)
		(layers "F.Cu" "B.Cu")
		(net "GND")
	)
	(via
		(at 384.924808 -272.466054)
		(size 0.4064)
		(drill 0.2032)
		(layers "F.Cu" "B.Cu")
		(net "GND")
	)
	(via
		(at 83.580986 -231.524302)
		(size 0.4064)
		(drill 0.2032)
		(layers "F.Cu" "B.Cu")
		(net "GND")
	)
	(via
		(at 413.349694 -433.747164)
		(size 0.4572)
		(drill 0.2032)
		(layers "F.Cu" "B.Cu")
		(net "GND")
	)
	(via
		(at 275.807932 -274.684998)
		(size 0.4826)
		(drill 0.254)
		(layers "F.Cu" "B.Cu")
		(net "GND")
	)
	(via
		(at 299.72381 -345.566238)
		(size 0.49022)
		(drill 0.254)
		(layers "F.Cu" "B.Cu")
		(net "GND")
	)
	(via
		(at 32.695896 -300.185328)
		(size 0.4826)
		(drill 0.254)
		(layers "F.Cu" "B.Cu")
		(net "GND")
	)
	(via
		(at 230.222298 -207.891634)
		(size 0.508)
		(drill 0.254)
		(layers "F.Cu" "B.Cu")
		(net "GND")
	)
	(via
		(at 277.192232 -297.635168)
		(size 0.4826)
		(drill 0.254)
		(layers "F.Cu" "B.Cu")
		(net "GND")
	)
	(via
		(at 47.596552 -413.204152)
		(size 0.4572)
		(drill 0.254)
		(layers "F.Cu" "B.Cu")
		(net "GND")
	)
	(via
		(at 117.244622 -288.666174)
		(size 0.4064)
		(drill 0.2032)
		(layers "F.Cu" "B.Cu")
		(net "GND")
	)
	(via
		(at 419.796722 -418.412168)
		(size 0.4064)
		(drill 0.2032)
		(layers "F.Cu" "B.Cu")
		(net "GND")
	)
	(via
		(at 421.029638 -276.810216)
		(size 0.4826)
		(drill 0.254)
		(layers "F.Cu" "B.Cu")
		(net "GND")
	)
	(via
		(at 82.001106 -273.276314)
		(size 0.4064)
		(drill 0.2032)
		(layers "F.Cu" "B.Cu")
		(net "GND")
	)
	(via
		(at 80.120998 -291.096192)
		(size 0.4064)
		(drill 0.2032)
		(layers "F.Cu" "B.Cu")
		(net "GND")
	)
	(via
		(at 86.701122 -265.176254)
		(size 0.4064)
		(drill 0.2032)
		(layers "F.Cu" "B.Cu")
		(net "GND")
	)
	(via
		(at 390.349486 -433.899564)
		(size 0.4572)
		(drill 0.2032)
		(layers "F.Cu" "B.Cu")
		(net "GND")
	)
	(via
		(at 40.23995 -252.58522)
		(size 0.4826)
		(drill 0.254)
		(layers "F.Cu" "B.Cu")
		(net "GND")
	)
	(via
		(at 51.832764 -410.030168)
		(size 0.4064)
		(drill 0.2032)
		(layers "F.Cu" "B.Cu")
		(net "GND")
	)
	(via
		(at 93.751146 -264.366248)
		(size 0.4064)
		(drill 0.2032)
		(layers "F.Cu" "B.Cu")
		(net "GND")
	)
	(via
		(at 202.147932 -298.485306)
		(size 0.4826)
		(drill 0.254)
		(layers "F.Cu" "B.Cu")
		(net "GND")
	)
	(via
		(at 271.974564 -276.810216)
		(size 0.4826)
		(drill 0.254)
		(layers "F.Cu" "B.Cu")
		(net "GND")
	)
	(via
		(at 32.695896 -244.085364)
		(size 0.4826)
		(drill 0.254)
		(layers "F.Cu" "B.Cu")
		(net "GND")
	)
	(via
		(at 92.22994 -355.171248)
		(size 0.508)
		(drill 0.254)
		(layers "F.Cu" "B.Cu")
		(net "GND")
	)
	(via
		(at 203.265532 -314.210446)
		(size 0.4826)
		(drill 0.254)
		(layers "F.Cu" "B.Cu")
		(net "GND")
	)
	(via
		(at 419.912038 -233.035094)
		(size 0.4826)
		(drill 0.254)
		(layers "F.Cu" "B.Cu")
		(net "GND")
	)
	(via
		(at 159.018986 -390.160002)
		(size 0.4064)
		(drill 0.2032)
		(layers "F.Cu" "B.Cu")
		(net "GND")
	)
	(via
		(at 145.144744 -255.014476)
		(size 0.4064)
		(drill 0.2032)
		(layers "F.Cu" "B.Cu")
		(net "GND")
	)
	(via
		(at 55.328058 -244.085364)
		(size 0.4826)
		(drill 0.254)
		(layers "F.Cu" "B.Cu")
		(net "GND")
	)
	(via
		(at 184.908444 -26.791158)
		(size 0.508)
		(drill 0.254)
		(layers "F.Cu" "B.Cu")
		(net "GND")
	)
	(via
		(at 339.646006 -396.710662)
		(size 0.4064)
		(drill 0.2032)
		(layers "F.Cu" "B.Cu")
		(net "GND")
	)
	(via
		(at 340.790022 -392.999722)
		(size 0.4064)
		(drill 0.2032)
		(layers "F.Cu" "B.Cu")
		(net "GND")
	)
	(via
		(at 373.55145 -180.755544)
		(size 0.49022)
		(drill 0.254)
		(layers "F.Cu" "B.Cu")
		(net "GND")
	)
	(via
		(at 422.627806 -274.684998)
		(size 0.4826)
		(drill 0.254)
		(layers "F.Cu" "B.Cu")
		(net "GND")
	)
	(via
		(at 138.377676 -378.836428)
		(size 0.508)
		(drill 0.254)
		(layers "F.Cu" "B.Cu")
		(net "GND")
	)
	(via
		(at 51.832764 -407.00452)
		(size 0.4064)
		(drill 0.2032)
		(layers "F.Cu" "B.Cu")
		(net "GND")
	)
	(via
		(at 81.604866 -184.683146)
		(size 0.49022)
		(drill 0.254)
		(layers "F.Cu" "B.Cu")
		(net "GND")
	)
	(via
		(at 416.468052 -289.985196)
		(size 0.4826)
		(drill 0.254)
		(layers "F.Cu" "B.Cu")
		(net "GND")
	)
	(via
		(at 371.46484 -246.914162)
		(size 0.4064)
		(drill 0.2032)
		(layers "F.Cu" "B.Cu")
		(net "GND")
	)
	(via
		(at 128.694688 -250.964446)
		(size 0.4064)
		(drill 0.2032)
		(layers "F.Cu" "B.Cu")
		(net "GND")
	)
	(via
		(at 393.717272 -387.703568)
		(size 0.508)
		(drill 0.254)
		(layers "F.Cu" "B.Cu")
		(net "GND")
	)
	(via
		(at 329.941174 -291.095938)
		(size 0.4064)
		(drill 0.2032)
		(layers "F.Cu" "B.Cu")
		(net "GND")
	)
	(via
		(at 122.414792 -261.93623)
		(size 0.4064)
		(drill 0.2032)
		(layers "F.Cu" "B.Cu")
		(net "GND")
	)
	(via
		(at 83.70189 -12.542266)
		(size 0.508)
		(drill 0.254)
		(layers "F.Cu" "B.Cu")
		(net "GND")
	)
	(via
		(at 273.664172 -107.168188)
		(size 0.508)
		(drill 0.254)
		(layers "F.Cu" "B.Cu")
		(net "GND")
	)
	(via
		(at 360.690668 -419.027864)
		(size 0.508)
		(drill 0.254)
		(layers "F.Cu" "B.Cu")
		(net "GND")
	)
	(via
		(at 419.912038 -279.785064)
		(size 0.4826)
		(drill 0.254)
		(layers "F.Cu" "B.Cu")
		(net "GND")
	)
	(via
		(at 183.616092 -316.33541)
		(size 0.4826)
		(drill 0.254)
		(layers "F.Cu" "B.Cu")
		(net "GND")
	)
	(via
		(at 357.201216 -279.756108)
		(size 0.4064)
		(drill 0.2032)
		(layers "F.Cu" "B.Cu")
		(net "GND")
	)
	(via
		(at 456.931522 -52.004976)
		(size 0.508)
		(drill 0.254)
		(layers "F.Cu" "B.Cu")
		(net "GND")
	)
	(via
		(at 117.845586 -410.030168)
		(size 0.4064)
		(drill 0.2032)
		(layers "F.Cu" "B.Cu")
		(net "GND")
	)
	(via
		(at 9.065006 -76.544678)
		(size 0.508)
		(drill 0.254)
		(layers "F.Cu" "B.Cu")
		(net "GND")
	)
	(via
		(at 44.216574 -339.814662)
		(size 0.508)
		(drill 0.254)
		(layers "F.Cu" "B.Cu")
		(net "GND")
	)
	(via
		(at 421.92194 -106.470958)
		(size 0.6604)
		(drill 0.3302)
		(layers "F.Cu" "B.Cu")
		(net "GND")
	)
	(via
		(at 133.694678 -276.516338)
		(size 0.4064)
		(drill 0.2032)
		(layers "F.Cu" "B.Cu")
		(net "GND")
	)
	(via
		(at 260.475222 -192.740026)
		(size 0.508)
		(drill 0.254)
		(layers "F.Cu" "B.Cu")
		(net "GND")
	)
	(via
		(at 443.733174 -410.6037)
		(size 0.508)
		(drill 0.254)
		(layers "F.Cu" "B.Cu")
		(net "GND")
	)
	(via
		(at 373.976646 -183.893968)
		(size 0.49022)
		(drill 0.254)
		(layers "F.Cu" "B.Cu")
		(net "GND")
	)
	(via
		(at 326.651112 -283.806138)
		(size 0.4064)
		(drill 0.2032)
		(layers "F.Cu" "B.Cu")
		(net "GND")
	)
	(via
		(at 71.19747 -154.55519)
		(size 0.508)
		(drill 0.254)
		(layers "F.Cu" "B.Cu")
		(net "GND")
	)
	(via
		(at 165.545516 -220.710252)
		(size 0.4826)
		(drill 0.254)
		(layers "F.Cu" "B.Cu")
		(net "GND")
	)
	(via
		(at 61.469524 -412.570168)
		(size 0.4064)
		(drill 0.2032)
		(layers "F.Cu" "B.Cu")
		(net "GND")
	)
	(via
		(at 138.564874 -227.474526)
		(size 0.4064)
		(drill 0.2032)
		(layers "F.Cu" "B.Cu")
		(net "GND")
	)
	(via
		(at 67.249802 -426.69968)
		(size 0.4572)
		(drill 0.2032)
		(layers "F.Cu" "B.Cu")
		(net "GND")
	)
	(via
		(at 288.180018 -244.08511)
		(size 0.4826)
		(drill 0.254)
		(layers "F.Cu" "B.Cu")
		(net "GND")
	)
	(via
		(at 123.994672 -229.90429)
		(size 0.4064)
		(drill 0.2032)
		(layers "F.Cu" "B.Cu")
		(net "GND")
	)
	(via
		(at 90.249756 -430.147222)
		(size 0.4572)
		(drill 0.2032)
		(layers "F.Cu" "B.Cu")
		(net "GND")
	)
	(via
		(at 127.762254 -384.617722)
		(size 0.4064)
		(drill 0.2032)
		(layers "F.Cu" "B.Cu")
		(net "GND")
	)
	(via
		(at 203.265532 -295.510458)
		(size 0.4826)
		(drill 0.254)
		(layers "F.Cu" "B.Cu")
		(net "GND")
	)
	(via
		(at 112.15751 -175.828198)
		(size 0.508)
		(drill 0.254)
		(layers "F.Cu" "B.Cu")
		(net "GND")
	)
	(via
		(at 425.327064 -152.388824)
		(size 0.508)
		(drill 0.254)
		(layers "F.Cu" "B.Cu")
		(net "GND")
	)
	(via
		(at 173.35627 -203.285344)
		(size 0.4826)
		(drill 0.254)
		(layers "F.Cu" "B.Cu")
		(net "GND")
	)
	(via
		(at 63.24981 -430.299622)
		(size 0.4572)
		(drill 0.2032)
		(layers "F.Cu" "B.Cu")
		(net "GND")
	)
	(via
		(at 443.9285 -228.785166)
		(size 0.4826)
		(drill 0.254)
		(layers "F.Cu" "B.Cu")
		(net "GND")
	)
	(via
		(at 378.04471 -243.674138)
		(size 0.4064)
		(drill 0.2032)
		(layers "F.Cu" "B.Cu")
		(net "GND")
	)
	(via
		(at 91.871038 -262.746236)
		(size 0.4064)
		(drill 0.2032)
		(layers "F.Cu" "B.Cu")
		(net "GND")
	)
	(via
		(at 365.82477 -237.19409)
		(size 0.4064)
		(drill 0.2032)
		(layers "F.Cu" "B.Cu")
		(net "GND")
	)
	(via
		(at 445.259968 -305.28514)
		(size 0.4826)
		(drill 0.254)
		(layers "F.Cu" "B.Cu")
		(net "GND")
	)
	(via
		(at 334.314546 -418.412168)
		(size 0.4064)
		(drill 0.2032)
		(layers "F.Cu" "B.Cu")
		(net "GND")
	)
	(via
		(at 375.054876 -273.27606)
		(size 0.4064)
		(drill 0.2032)
		(layers "F.Cu" "B.Cu")
		(net "GND")
	)
	(via
		(at 427.922182 -431.533808)
		(size 0.508)
		(drill 0.254)
		(layers "F.Cu" "B.Cu")
		(net "GND")
	)
	(via
		(at 38.728142 -6.091174)
		(size 0.508)
		(drill 0.254)
		(layers "F.Cu" "B.Cu")
		(net "GND")
	)
	(via
		(at 244.636036 -224.265744)
		(size 0.508)
		(drill 0.254)
		(layers "F.Cu" "B.Cu")
		(net "GND")
	)
	(via
		(at 398.46758 -379.22073)
		(size 0.508)
		(drill 0.254)
		(layers "F.Cu" "B.Cu")
		(net "GND")
	)
	(via
		(at 109.431074 -250.15444)
		(size 0.4064)
		(drill 0.2032)
		(layers "F.Cu" "B.Cu")
		(net "GND")
	)
	(via
		(at 79.821024 -255.824482)
		(size 0.4064)
		(drill 0.2032)
		(layers "F.Cu" "B.Cu")
		(net "GND")
	)
	(via
		(at 350.321118 -239.624108)
		(size 0.4064)
		(drill 0.2032)
		(layers "F.Cu" "B.Cu")
		(net "GND")
	)
	(via
		(at 385.394708 -279.756108)
		(size 0.4064)
		(drill 0.2032)
		(layers "F.Cu" "B.Cu")
		(net "GND")
	)
	(via
		(at 126.814834 -239.624362)
		(size 0.4064)
		(drill 0.2032)
		(layers "F.Cu" "B.Cu")
		(net "GND")
	)
	(via
		(at 140.444728 -237.194344)
		(size 0.4064)
		(drill 0.2032)
		(layers "F.Cu" "B.Cu")
		(net "GND")
	)
	(via
		(at 113.954814 -287.856422)
		(size 0.4064)
		(drill 0.2032)
		(layers "F.Cu" "B.Cu")
		(net "GND")
	)
	(via
		(at 416.468052 -207.535018)
		(size 0.4826)
		(drill 0.254)
		(layers "F.Cu" "B.Cu")
		(net "GND")
	)
	(via
		(at 425.497498 -330.53909)
		(size 0.508)
		(drill 0.254)
		(layers "F.Cu" "B.Cu")
		(net "GND")
	)
	(via
		(at 347.031056 -240.434114)
		(size 0.4064)
		(drill 0.2032)
		(layers "F.Cu" "B.Cu")
		(net "GND")
	)
	(via
		(at 359.144824 -384.299968)
		(size 0.508)
		(drill 0.254)
		(layers "F.Cu" "B.Cu")
		(net "GND")
	)
	(via
		(at 149.650958 -411.936184)
		(size 0.4572)
		(drill 0.254)
		(layers "F.Cu" "B.Cu")
		(net "GND")
	)
	(via
		(at 139.83716 -387.83514)
		(size 0.508)
		(drill 0.254)
		(layers "F.Cu" "B.Cu")
		(net "GND")
	)
	(via
		(at 235.0008 -286.726122)
		(size 0.508)
		(drill 0.254)
		(layers "F.Cu" "B.Cu")
		(net "GND")
	)
	(via
		(at 407.182574 -414.752536)
		(size 0.4572)
		(drill 0.254)
		(layers "F.Cu" "B.Cu")
		(net "GND")
	)
	(via
		(at 353.911154 -274.086066)
		(size 0.4064)
		(drill 0.2032)
		(layers "F.Cu" "B.Cu")
		(net "GND")
	)
	(via
		(at 78.711044 -293.52621)
		(size 0.4064)
		(drill 0.2032)
		(layers "F.Cu" "B.Cu")
		(net "GND")
	)
	(via
		(at 28.341574 -347.287088)
		(size 0.49022)
		(drill 0.254)
		(layers "F.Cu" "B.Cu")
		(net "GND")
	)
	(via
		(at 322.583556 -394.831062)
		(size 0.4064)
		(drill 0.2032)
		(layers "F.Cu" "B.Cu")
		(net "GND")
	)
	(via
		(at 68.366894 -369.69573)
		(size 0.508)
		(drill 0.254)
		(layers "F.Cu" "B.Cu")
		(net "GND")
	)
	(via
		(at 245.364 -330.2)
		(size 0.508)
		(drill 0.254)
		(layers "F.Cu" "B.Cu")
		(net "GND")
	)
	(via
		(at 16.972788 -372.12905)
		(size 0.508)
		(drill 0.254)
		(layers "F.Cu" "B.Cu")
		(net "GND")
	)
	(via
		(at 438.610756 -26.153872)
		(size 0.508)
		(drill 0.254)
		(layers "F.Cu" "B.Cu")
		(net "GND")
	)
	(via
		(at 380.770892 -377.41733)
		(size 0.508)
		(drill 0.254)
		(layers "F.Cu" "B.Cu")
		(net "GND")
	)
	(via
		(at 135.599678 -157.38221)
		(size 0.49022)
		(drill 0.254)
		(layers "F.Cu" "B.Cu")
		(net "GND")
	)
	(via
		(at 347.144086 -400.212814)
		(size 0.4064)
		(drill 0.2032)
		(layers "F.Cu" "B.Cu")
		(net "GND")
	)
	(via
		(at 449.373752 -392.905234)
		(size 0.508)
		(drill 0.254)
		(layers "F.Cu" "B.Cu")
		(net "GND")
	)
	(via
		(at 346.249498 -438.499758)
		(size 0.4572)
		(drill 0.2032)
		(layers "F.Cu" "B.Cu")
		(net "GND")
	)
	(via
		(at 140.734034 -407.638504)
		(size 0.4572)
		(drill 0.254)
		(layers "F.Cu" "B.Cu")
		(net "GND")
	)
	(via
		(at 36.795964 -271.285208)
		(size 0.4826)
		(drill 0.254)
		(layers "F.Cu" "B.Cu")
		(net "GND")
	)
	(via
		(at 297.108372 -221.985078)
		(size 0.4826)
		(drill 0.254)
		(layers "F.Cu" "B.Cu")
		(net "GND")
	)
	(via
		(at 97.919032 -390.160002)
		(size 0.4064)
		(drill 0.2032)
		(layers "F.Cu" "B.Cu")
		(net "GND")
	)
	(via
		(at 61.531754 -41.27881)
		(size 0.508)
		(drill 0.254)
		(layers "F.Cu" "B.Cu")
		(net "GND")
	)
	(via
		(at 427.759876 -18.503138)
		(size 0.508)
		(drill 0.254)
		(layers "F.Cu" "B.Cu")
		(net "GND")
	)
	(via
		(at 107.436666 -178.57089)
		(size 0.49022)
		(drill 0.254)
		(layers "F.Cu" "B.Cu")
		(net "GND")
	)
	(via
		(at 439.100214 -299.33519)
		(size 0.4826)
		(drill 0.254)
		(layers "F.Cu" "B.Cu")
		(net "GND")
	)
	(via
		(at 349.681038 -268.416024)
		(size 0.4064)
		(drill 0.2032)
		(layers "F.Cu" "B.Cu")
		(net "GND")
	)
	(via
		(at 328.53122 -267.606018)
		(size 0.4064)
		(drill 0.2032)
		(layers "F.Cu" "B.Cu")
		(net "GND")
	)
	(via
		(at 331.351128 -293.525956)
		(size 0.4064)
		(drill 0.2032)
		(layers "F.Cu" "B.Cu")
		(net "GND")
	)
	(via
		(at 182.673244 -356.437184)
		(size 0.508)
		(drill 0.254)
		(layers "F.Cu" "B.Cu")
		(net "GND")
	)
	(via
		(at 110.371128 -243.674392)
		(size 0.4064)
		(drill 0.2032)
		(layers "F.Cu" "B.Cu")
		(net "GND")
	)
	(via
		(at 80.591152 -288.666174)
		(size 0.4064)
		(drill 0.2032)
		(layers "F.Cu" "B.Cu")
		(net "GND")
	)
	(via
		(at 329.275186 -418.412168)
		(size 0.4064)
		(drill 0.2032)
		(layers "F.Cu" "B.Cu")
		(net "GND")
	)
	(via
		(at 183.616092 -198.185278)
		(size 0.4826)
		(drill 0.254)
		(layers "F.Cu" "B.Cu")
		(net "GND")
	)
	(via
		(at 39.434262 -17.613122)
		(size 0.508)
		(drill 0.254)
		(layers "F.Cu" "B.Cu")
		(net "GND")
	)
	(via
		(at 412.367984 -214.335106)
		(size 0.4826)
		(drill 0.254)
		(layers "F.Cu" "B.Cu")
		(net "GND")
	)
	(via
		(at 339.811106 -272.466054)
		(size 0.4064)
		(drill 0.2032)
		(layers "F.Cu" "B.Cu")
		(net "GND")
	)
	(via
		(at 109.431074 -224.234502)
		(size 0.4064)
		(drill 0.2032)
		(layers "F.Cu" "B.Cu")
		(net "GND")
	)
	(via
		(at 93.11894 -390.160002)
		(size 0.4064)
		(drill 0.2032)
		(layers "F.Cu" "B.Cu")
		(net "GND")
	)
	(via
		(at 86.344252 -393.927838)
		(size 0.4572)
		(drill 0.254)
		(layers "F.Cu" "B.Cu")
		(net "GND")
	)
	(via
		(at 460.255366 -377.29287)
		(size 0.508)
		(drill 0.254)
		(layers "F.Cu" "B.Cu")
		(net "GND")
	)
	(via
		(at 32.605218 -53.909214)
		(size 0.508)
		(drill 0.254)
		(layers "F.Cu" "B.Cu")
		(net "GND")
	)
	(via
		(at 145.444718 -280.566368)
		(size 0.4064)
		(drill 0.2032)
		(layers "F.Cu" "B.Cu")
		(net "GND")
	)
	(via
		(at 74.369168 -386.476494)
		(size 0.508)
		(drill 0.254)
		(layers "F.Cu" "B.Cu")
		(net "GND")
	)
	(via
		(at 111.577882 -408.610816)
		(size 0.508)
		(drill 0.254)
		(layers "F.Cu" "B.Cu")
		(net "GND")
	)
	(via
		(at 82.249772 -434.899562)
		(size 0.4572)
		(drill 0.2032)
		(layers "F.Cu" "B.Cu")
		(net "GND")
	)
	(via
		(at 323.234558 -420.318184)
		(size 0.4572)
		(drill 0.254)
		(layers "F.Cu" "B.Cu")
		(net "GND")
	)
	(via
		(at 93.272356 -410.664152)
		(size 0.4572)
		(drill 0.254)
		(layers "F.Cu" "B.Cu")
		(net "GND")
	)
	(via
		(at 304.652426 -287.435036)
		(size 0.4826)
		(drill 0.254)
		(layers "F.Cu" "B.Cu")
		(net "GND")
	)
	(via
		(at 130.349752 -437.49976)
		(size 0.4572)
		(drill 0.2032)
		(layers "F.Cu" "B.Cu")
		(net "GND")
	)
	(via
		(at 346.249498 -437.34736)
		(size 0.4572)
		(drill 0.2032)
		(layers "F.Cu" "B.Cu")
		(net "GND")
	)
	(via
		(at 102.87 -427.609)
		(size 0.508)
		(drill 0.254)
		(layers "F.Cu" "B.Cu")
		(net "GND")
	)
	(via
		(at 452.803768 -227.935028)
		(size 0.4826)
		(drill 0.254)
		(layers "F.Cu" "B.Cu")
		(net "GND")
	)
	(via
		(at 88.436958 -333.039212)
		(size 0.49022)
		(drill 0.254)
		(layers "F.Cu" "B.Cu")
		(net "GND")
	)
	(via
		(at 84.99094 -256.634488)
		(size 0.4064)
		(drill 0.2032)
		(layers "F.Cu" "B.Cu")
		(net "GND")
	)
	(via
		(at 116.304822 -287.046416)
		(size 0.4064)
		(drill 0.2032)
		(layers "F.Cu" "B.Cu")
		(net "GND")
	)
	(via
		(at 135.274812 -231.524302)
		(size 0.4064)
		(drill 0.2032)
		(layers "F.Cu" "B.Cu")
		(net "GND")
	)
	(via
		(at 229.60203 -326.49668)
		(size 0.508)
		(drill 0.254)
		(layers "F.Cu" "B.Cu")
		(net "GND")
	)
	(via
		(at 54.210458 -211.360258)
		(size 0.4826)
		(drill 0.254)
		(layers "F.Cu" "B.Cu")
		(net "GND")
	)
	(via
		(at 69.249798 -432.451256)
		(size 0.4572)
		(drill 0.2032)
		(layers "F.Cu" "B.Cu")
		(net "GND")
	)
	(via
		(at 34.080196 -231.335326)
		(size 0.4826)
		(drill 0.254)
		(layers "F.Cu" "B.Cu")
		(net "GND")
	)
	(via
		(at 95.472758 -334.630268)
		(size 0.49022)
		(drill 0.254)
		(layers "F.Cu" "B.Cu")
		(net "GND")
	)
	(via
		(at 317.074296 -382.34493)
		(size 0.508)
		(drill 0.254)
		(layers "F.Cu" "B.Cu")
		(net "GND")
	)
	(via
		(at 83.386168 -339.993732)
		(size 0.508)
		(drill 0.254)
		(layers "F.Cu" "B.Cu")
		(net "GND")
	)
	(via
		(at 283.618432 -275.960078)
		(size 0.4826)
		(drill 0.254)
		(layers "F.Cu" "B.Cu")
		(net "GND")
	)
	(via
		(at 422.15054 -353.10318)
		(size 0.49022)
		(drill 0.254)
		(layers "F.Cu" "B.Cu")
		(net "GND")
	)
	(via
		(at 371.075204 -257.930142)
		(size 0.4826)
		(drill 0.254)
		(layers "F.Cu" "B.Cu")
		(net "GND")
	)
	(via
		(at 282.020264 -221.985078)
		(size 0.4826)
		(drill 0.254)
		(layers "F.Cu" "B.Cu")
		(net "GND")
	)
	(via
		(at 339.811106 -285.42615)
		(size 0.4064)
		(drill 0.2032)
		(layers "F.Cu" "B.Cu")
		(net "GND")
	)
	(via
		(at 140.349732 -437.34736)
		(size 0.4572)
		(drill 0.2032)
		(layers "F.Cu" "B.Cu")
		(net "GND")
	)
	(via
		(at 360.197654 -253.43231)
		(size 0.4826)
		(drill 0.254)
		(layers "F.Cu" "B.Cu")
		(net "GND")
	)
	(via
		(at 22.148292 -12.37488)
		(size 0.508)
		(drill 0.254)
		(layers "F.Cu" "B.Cu")
		(net "GND")
	)
	(via
		(at 352.895154 -441.227718)
		(size 0.508)
		(drill 0.254)
		(layers "F.Cu" "B.Cu")
		(net "GND")
	)
	(via
		(at 160.702244 -373.96293)
		(size 0.508)
		(drill 0.254)
		(layers "F.Cu" "B.Cu")
		(net "GND")
	)
	(via
		(at 413.58185 -413.480504)
		(size 0.4572)
		(drill 0.254)
		(layers "F.Cu" "B.Cu")
		(net "GND")
	)
	(via
		(at 88.24976 -427.851316)
		(size 0.4572)
		(drill 0.2032)
		(layers "F.Cu" "B.Cu")
		(net "GND")
	)
	(via
		(at 443.783974 -413.1945)
		(size 0.508)
		(drill 0.254)
		(layers "F.Cu" "B.Cu")
		(net "GND")
	)
	(via
		(at 143.264636 -229.094538)
		(size 0.4064)
		(drill 0.2032)
		(layers "F.Cu" "B.Cu")
		(net "GND")
	)
	(via
		(at 411.662118 -167.012112)
		(size 0.508)
		(drill 0.254)
		(layers "F.Cu" "B.Cu")
		(net "GND")
	)
	(via
		(at 198.7042 -243.235226)
		(size 0.4826)
		(drill 0.254)
		(layers "F.Cu" "B.Cu")
		(net "GND")
	)
	(via
		(at 136.684766 -248.534428)
		(size 0.4064)
		(drill 0.2032)
		(layers "F.Cu" "B.Cu")
		(net "GND")
	)
	(via
		(at 417.585652 -201.160126)
		(size 0.4826)
		(drill 0.254)
		(layers "F.Cu" "B.Cu")
		(net "GND")
	)
	(via
		(at 121.209562 -258.830318)
		(size 0.4826)
		(drill 0.254)
		(layers "F.Cu" "B.Cu")
		(net "GND")
	)
	(via
		(at 176.072038 -213.485222)
		(size 0.4826)
		(drill 0.254)
		(layers "F.Cu" "B.Cu")
		(net "GND")
	)
	(via
		(at 134.164832 -283.806392)
		(size 0.4064)
		(drill 0.2032)
		(layers "F.Cu" "B.Cu")
		(net "GND")
	)
	(via
		(at 33.847278 -17.613122)
		(size 0.508)
		(drill 0.254)
		(layers "F.Cu" "B.Cu")
		(net "GND")
	)
	(via
		(at 378.814838 -294.335962)
		(size 0.4064)
		(drill 0.2032)
		(layers "F.Cu" "B.Cu")
		(net "GND")
	)
	(via
		(at 35.387534 -348.709488)
		(size 0.49022)
		(drill 0.254)
		(layers "F.Cu" "B.Cu")
		(net "GND")
	)
	(via
		(at 362.455206 -353.34956)
		(size 0.6604)
		(drill 0.3302)
		(layers "F.Cu" "B.Cu")
		(net "GND")
	)
	(via
		(at 280.635964 -301.885096)
		(size 0.4826)
		(drill 0.254)
		(layers "F.Cu" "B.Cu")
		(net "GND")
	)
	(via
		(at 206.248 -297.635422)
		(size 0.4826)
		(drill 0.254)
		(layers "F.Cu" "B.Cu")
		(net "GND")
	)
	(via
		(at 372.404894 -246.914162)
		(size 0.4064)
		(drill 0.2032)
		(layers "F.Cu" "B.Cu")
		(net "GND")
	)
	(via
		(at 96.571054 -275.706332)
		(size 0.4064)
		(drill 0.2032)
		(layers "F.Cu" "B.Cu")
		(net "GND")
	)
	(via
		(at 271.974564 -286.16021)
		(size 0.4826)
		(drill 0.254)
		(layers "F.Cu" "B.Cu")
		(net "GND")
	)
	(via
		(at 117.963696 -369.03533)
		(size 0.508)
		(drill 0.254)
		(layers "F.Cu" "B.Cu")
		(net "GND")
	)
	(via
		(at 173.35627 -287.43529)
		(size 0.4826)
		(drill 0.254)
		(layers "F.Cu" "B.Cu")
		(net "GND")
	)
	(via
		(at 377.10491 -250.154186)
		(size 0.4064)
		(drill 0.2032)
		(layers "F.Cu" "B.Cu")
		(net "GND")
	)
	(via
		(at 309.722774 -420.318184)
		(size 0.4572)
		(drill 0.254)
		(layers "F.Cu" "B.Cu")
		(net "GND")
	)
	(via
		(at 372.874794 -252.584204)
		(size 0.4064)
		(drill 0.2032)
		(layers "F.Cu" "B.Cu")
		(net "GND")
	)
	(via
		(at 179.516024 -300.185328)
		(size 0.4826)
		(drill 0.254)
		(layers "F.Cu" "B.Cu")
		(net "GND")
	)
	(via
		(at 91.571064 -255.014476)
		(size 0.4064)
		(drill 0.2032)
		(layers "F.Cu" "B.Cu")
		(net "GND")
	)
	(via
		(at 343.101168 -265.176)
		(size 0.4064)
		(drill 0.2032)
		(layers "F.Cu" "B.Cu")
		(net "GND")
	)
	(via
		(at 233.707178 -316.46368)
		(size 0.508)
		(drill 0.254)
		(layers "F.Cu" "B.Cu")
		(net "GND")
	)
	(via
		(at 135.777986 -412.570168)
		(size 0.4064)
		(drill 0.2032)
		(layers "F.Cu" "B.Cu")
		(net "GND")
	)
	(via
		(at 336.344006 -402.284438)
		(size 0.4572)
		(drill 0.254)
		(layers "F.Cu" "B.Cu")
		(net "GND")
	)
	(via
		(at 420.467282 -363.611414)
		(size 0.508)
		(drill 0.254)
		(layers "F.Cu" "B.Cu")
		(net "GND")
	)
	(via
		(at 328.231246 -224.234248)
		(size 0.4064)
		(drill 0.2032)
		(layers "F.Cu" "B.Cu")
		(net "GND")
	)
	(via
		(at 103.151178 -285.426404)
		(size 0.4064)
		(drill 0.2032)
		(layers "F.Cu" "B.Cu")
		(net "GND")
	)
	(via
		(at 351.076514 -414.752536)
		(size 0.4572)
		(drill 0.254)
		(layers "F.Cu" "B.Cu")
		(net "GND")
	)
	(via
		(at 388.34949 -434.899562)
		(size 0.4572)
		(drill 0.2032)
		(layers "F.Cu" "B.Cu")
		(net "GND")
	)
	(via
		(at 413.752284 -203.28509)
		(size 0.4826)
		(drill 0.254)
		(layers "F.Cu" "B.Cu")
		(net "GND")
	)
	(via
		(at 191.26581 -350.921828)
		(size 0.49022)
		(drill 0.254)
		(layers "F.Cu" "B.Cu")
		(net "GND")
	)
	(via
		(at 318.639698 -417.778184)
		(size 0.4572)
		(drill 0.254)
		(layers "F.Cu" "B.Cu")
		(net "GND")
	)
	(via
		(at 87.811102 -250.15444)
		(size 0.4064)
		(drill 0.2032)
		(layers "F.Cu" "B.Cu")
		(net "GND")
	)
	(via
		(at 325.052944 -284.350206)
		(size 0.4064)
		(drill 0.2032)
		(layers "F.Cu" "B.Cu")
		(net "GND")
	)
	(via
		(at 74.816462 -39.070026)
		(size 0.508)
		(drill 0.254)
		(layers "F.Cu" "B.Cu")
		(net "GND")
	)
	(via
		(at 415.492692 -140.249656)
		(size 0.508)
		(drill 0.254)
		(layers "F.Cu" "B.Cu")
		(net "GND")
	)
	(via
		(at 320.0527 -328.097134)
		(size 0.508)
		(drill 0.254)
		(layers "F.Cu" "B.Cu")
		(net "GND")
	)
	(via
		(at 290.895786 -199.885046)
		(size 0.4826)
		(drill 0.254)
		(layers "F.Cu" "B.Cu")
		(net "GND")
	)
	(via
		(at 419.332918 -167.672512)
		(size 0.508)
		(drill 0.254)
		(layers "F.Cu" "B.Cu")
		(net "GND")
	)
	(via
		(at 32.695896 -255.13538)
		(size 0.4826)
		(drill 0.254)
		(layers "F.Cu" "B.Cu")
		(net "GND")
	)
	(via
		(at 116.774722 -294.336216)
		(size 0.4064)
		(drill 0.2032)
		(layers "F.Cu" "B.Cu")
		(net "GND")
	)
	(via
		(at 188.444378 -221.985332)
		(size 0.4826)
		(drill 0.254)
		(layers "F.Cu" "B.Cu")
		(net "GND")
	)
	(via
		(at 364.884716 -246.914162)
		(size 0.4064)
		(drill 0.2032)
		(layers "F.Cu" "B.Cu")
		(net "GND")
	)
	(via
		(at 384.122422 -415.38652)
		(size 0.4064)
		(drill 0.2032)
		(layers "F.Cu" "B.Cu")
		(net "GND")
	)
	(via
		(at 133.694678 -274.896326)
		(size 0.4064)
		(drill 0.2032)
		(layers "F.Cu" "B.Cu")
		(net "GND")
	)
	(via
		(at 396.461234 -412.212536)
		(size 0.4572)
		(drill 0.254)
		(layers "F.Cu" "B.Cu")
		(net "GND")
	)
	(via
		(at 233.016044 -43.053)
		(size 0.508)
		(drill 0.254)
		(layers "F.Cu" "B.Cu")
		(net "GND")
	)
	(via
		(at 284.736032 -316.335156)
		(size 0.4826)
		(drill 0.254)
		(layers "F.Cu" "B.Cu")
		(net "GND")
	)
	(via
		(at 289.564318 -315.485018)
		(size 0.4826)
		(drill 0.254)
		(layers "F.Cu" "B.Cu")
		(net "GND")
	)
	(via
		(at 16.2941 -110.482888)
		(size 0.508)
		(drill 0.254)
		(layers "F.Cu" "B.Cu")
		(net "GND")
	)
	(via
		(at 437.886602 -421.37711)
		(size 0.508)
		(drill 0.254)
		(layers "F.Cu" "B.Cu")
		(net "GND")
	)
	(via
		(at 207.3656 -238.560356)
		(size 0.4826)
		(drill 0.254)
		(layers "F.Cu" "B.Cu")
		(net "GND")
	)
	(via
		(at 71.249794 -432.747166)
		(size 0.4572)
		(drill 0.2032)
		(layers "F.Cu" "B.Cu")
		(net "GND")
	)
	(via
		(at 36.795964 -222.835216)
		(size 0.4826)
		(drill 0.254)
		(layers "F.Cu" "B.Cu")
		(net "GND")
	)
	(via
		(at 242.57 -321.818)
		(size 0.508)
		(drill 0.254)
		(layers "F.Cu" "B.Cu")
		(net "GND")
	)
	(via
		(at 97.990152 -384.617722)
		(size 0.4064)
		(drill 0.2032)
		(layers "F.Cu" "B.Cu")
		(net "GND")
	)
	(via
		(at 434.838348 -347.895926)
		(size 0.508)
		(drill 0.254)
		(layers "F.Cu" "B.Cu")
		(net "GND")
	)
	(via
		(at 349.681038 -261.935976)
		(size 0.4064)
		(drill 0.2032)
		(layers "F.Cu" "B.Cu")
		(net "GND")
	)
	(via
		(at 194.457066 -349.37192)
		(size 0.508)
		(drill 0.254)
		(layers "F.Cu" "B.Cu")
		(net "GND")
	)
	(via
		(at 334.64119 -294.335962)
		(size 0.4064)
		(drill 0.2032)
		(layers "F.Cu" "B.Cu")
		(net "GND")
	)
	(via
		(at 439.100214 -233.884978)
		(size 0.4826)
		(drill 0.254)
		(layers "F.Cu" "B.Cu")
		(net "GND")
	)
	(via
		(at 451.2056 -314.210192)
		(size 0.4826)
		(drill 0.254)
		(layers "F.Cu" "B.Cu")
		(net "GND")
	)
	(via
		(at 51.884072 -213.485222)
		(size 0.4826)
		(drill 0.254)
		(layers "F.Cu" "B.Cu")
		(net "GND")
	)
	(via
		(at 18.992342 -275.53539)
		(size 0.4826)
		(drill 0.254)
		(layers "F.Cu" "B.Cu")
		(net "GND")
	)
	(via
		(at 136.684766 -225.854514)
		(size 0.4064)
		(drill 0.2032)
		(layers "F.Cu" "B.Cu")
		(net "GND")
	)
	(via
		(at 104.08793 -261.128256)
		(size 0.4064)
		(drill 0.2032)
		(layers "F.Cu" "B.Cu")
		(net "GND")
	)
	(via
		(at 382.91643 -400.212814)
		(size 0.4064)
		(drill 0.2032)
		(layers "F.Cu" "B.Cu")
		(net "GND")
	)
	(via
		(at 108.832142 -259.845302)
		(size 0.4826)
		(drill 0.254)
		(layers "F.Cu" "B.Cu")
		(net "GND")
	)
	(via
		(at 382.5748 -294.335962)
		(size 0.4064)
		(drill 0.2032)
		(layers "F.Cu" "B.Cu")
		(net "GND")
	)
	(via
		(at 330.618592 -390.92632)
		(size 0.508)
		(drill 0.254)
		(layers "F.Cu" "B.Cu")
		(net "GND")
	)
	(via
		(at 49.665636 -7.215124)
		(size 0.508)
		(drill 0.254)
		(layers "F.Cu" "B.Cu")
		(net "GND")
	)
	(via
		(at 93.246194 -388.328662)
		(size 0.4064)
		(drill 0.2032)
		(layers "F.Cu" "B.Cu")
		(net "GND")
	)
	(via
		(at 118.354856 -231.524302)
		(size 0.4064)
		(drill 0.2032)
		(layers "F.Cu" "B.Cu")
		(net "GND")
	)
	(via
		(at 369.895628 -146.552158)
		(size 0.508)
		(drill 0.254)
		(layers "F.Cu" "B.Cu")
		(net "GND")
	)
	(via
		(at 298.090844 -384.175)
		(size 0.508)
		(drill 0.254)
		(layers "F.Cu" "B.Cu")
		(net "GND")
	)
	(via
		(at 456.160886 -53.118512)
		(size 0.508)
		(drill 0.254)
		(layers "F.Cu" "B.Cu")
		(net "GND")
	)
	(via
		(at 375.716546 -391.23493)
		(size 0.4064)
		(drill 0.2032)
		(layers "F.Cu" "B.Cu")
		(net "GND")
	)
	(via
		(at 337.377786 -418.412168)
		(size 0.4064)
		(drill 0.2032)
		(layers "F.Cu" "B.Cu")
		(net "GND")
	)
	(via
		(at 442.5442 -247.485154)
		(size 0.4826)
		(drill 0.254)
		(layers "F.Cu" "B.Cu")
		(net "GND")
	)
	(via
		(at 275.807932 -312.084974)
		(size 0.4826)
		(drill 0.254)
		(layers "F.Cu" "B.Cu")
		(net "GND")
	)
	(via
		(at 21.70811 -207.535272)
		(size 0.4826)
		(drill 0.254)
		(layers "F.Cu" "B.Cu")
		(net "GND")
	)
	(via
		(at 255.956562 -192.789048)
		(size 0.508)
		(drill 0.254)
		(layers "F.Cu" "B.Cu")
		(net "GND")
	)
	(via
		(at 161.903918 -411.936184)
		(size 0.4572)
		(drill 0.254)
		(layers "F.Cu" "B.Cu")
		(net "GND")
	)
	(via
		(at 273.928586 -348.704662)
		(size 0.49022)
		(drill 0.254)
		(layers "F.Cu" "B.Cu")
		(net "GND")
	)
	(via
		(at 443.9285 -275.535136)
		(size 0.4826)
		(drill 0.254)
		(layers "F.Cu" "B.Cu")
		(net "GND")
	)
	(via
		(at 241.293396 -439.90768)
		(size 0.508)
		(drill 0.254)
		(layers "F.Cu" "B.Cu")
		(net "GND")
	)
	(via
		(at 355.961188 -244.484144)
		(size 0.4064)
		(drill 0.2032)
		(layers "F.Cu" "B.Cu")
		(net "GND")
	)
	(via
		(at 435.000146 -233.035094)
		(size 0.4826)
		(drill 0.254)
		(layers "F.Cu" "B.Cu")
		(net "GND")
	)
	(via
		(at 282.020264 -200.735184)
		(size 0.4826)
		(drill 0.254)
		(layers "F.Cu" "B.Cu")
		(net "GND")
	)
	(via
		(at 413.752284 -238.13516)
		(size 0.4826)
		(drill 0.254)
		(layers "F.Cu" "B.Cu")
		(net "GND")
	)
	(via
		(at 68.958714 -328.10196)
		(size 0.508)
		(drill 0.254)
		(layers "F.Cu" "B.Cu")
		(net "GND")
	)
	(via
		(at 138.864848 -269.226284)
		(size 0.4064)
		(drill 0.2032)
		(layers "F.Cu" "B.Cu")
		(net "GND")
	)
	(via
		(at 378.814838 -266.796012)
		(size 0.4064)
		(drill 0.2032)
		(layers "F.Cu" "B.Cu")
		(net "GND")
	)
	(via
		(at 64.444372 -407.638504)
		(size 0.4572)
		(drill 0.254)
		(layers "F.Cu" "B.Cu")
		(net "GND")
	)
	(via
		(at 376.634756 -242.864132)
		(size 0.4064)
		(drill 0.2032)
		(layers "F.Cu" "B.Cu")
		(net "GND")
	)
	(via
		(at 122.414792 -294.336216)
		(size 0.4064)
		(drill 0.2032)
		(layers "F.Cu" "B.Cu")
		(net "GND")
	)
	(via
		(at 73.24979 -433.747418)
		(size 0.4572)
		(drill 0.2032)
		(layers "F.Cu" "B.Cu")
		(net "GND")
	)
	(via
		(at 273.092164 -242.385088)
		(size 0.4826)
		(drill 0.254)
		(layers "F.Cu" "B.Cu")
		(net "GND")
	)
	(via
		(at 307.368194 -268.735048)
		(size 0.4826)
		(drill 0.254)
		(layers "F.Cu" "B.Cu")
		(net "GND")
	)
	(via
		(at 89.99093 -264.366248)
		(size 0.4064)
		(drill 0.2032)
		(layers "F.Cu" "B.Cu")
		(net "GND")
	)
	(via
		(at 357.201216 -294.335962)
		(size 0.4064)
		(drill 0.2032)
		(layers "F.Cu" "B.Cu")
		(net "GND")
	)
	(via
		(at 119.82196 -335.80578)
		(size 0.6604)
		(drill 0.3302)
		(layers "F.Cu" "B.Cu")
		(net "GND")
	)
	(via
		(at 115.834668 -287.856422)
		(size 0.4064)
		(drill 0.2032)
		(layers "F.Cu" "B.Cu")
		(net "GND")
	)
	(via
		(at 332.249526 -433.899564)
		(size 0.4572)
		(drill 0.2032)
		(layers "F.Cu" "B.Cu")
		(net "GND")
	)
	(via
		(at 57.018174 -336.275172)
		(size 0.508)
		(drill 0.254)
		(layers "F.Cu" "B.Cu")
		(net "GND")
	)
	(via
		(at 52.241958 -344.781886)
		(size 0.49022)
		(drill 0.254)
		(layers "F.Cu" "B.Cu")
		(net "GND")
	)
	(via
		(at 333.230982 -280.566114)
		(size 0.4064)
		(drill 0.2032)
		(layers "F.Cu" "B.Cu")
		(net "GND")
	)
	(via
		(at 357.995474 -170.64609)
		(size 0.49022)
		(drill 0.254)
		(layers "F.Cu" "B.Cu")
		(net "GND")
	)
	(via
		(at 337.631024 -238.814102)
		(size 0.4064)
		(drill 0.2032)
		(layers "F.Cu" "B.Cu")
		(net "GND")
	)
	(via
		(at 343.101168 -263.555988)
		(size 0.4064)
		(drill 0.2032)
		(layers "F.Cu" "B.Cu")
		(net "GND")
	)
	(via
		(at 399.349722 -425.547282)
		(size 0.4572)
		(drill 0.2032)
		(layers "F.Cu" "B.Cu")
		(net "GND")
	)
	(via
		(at 165.812216 -296.785284)
		(size 0.4826)
		(drill 0.254)
		(layers "F.Cu" "B.Cu")
		(net "GND")
	)
	(via
		(at 18.992342 -284.885384)
		(size 0.4826)
		(drill 0.254)
		(layers "F.Cu" "B.Cu")
		(net "GND")
	)
	(via
		(at 427.456092 -217.73515)
		(size 0.4826)
		(drill 0.254)
		(layers "F.Cu" "B.Cu")
		(net "GND")
	)
	(via
		(at 107.85094 -278.946356)
		(size 0.4064)
		(drill 0.2032)
		(layers "F.Cu" "B.Cu")
		(net "GND")
	)
	(via
		(at 292.216332 -364.019084)
		(size 0.508)
		(drill 0.254)
		(layers "F.Cu" "B.Cu")
		(net "GND")
	)
	(via
		(at 338.174584 -379.22073)
		(size 0.508)
		(drill 0.254)
		(layers "F.Cu" "B.Cu")
		(net "GND")
	)
	(via
		(at 332.761082 -294.335962)
		(size 0.4064)
		(drill 0.2032)
		(layers "F.Cu" "B.Cu")
		(net "GND")
	)
	(via
		(at 111.437928 -392.932158)
		(size 0.508)
		(drill 0.254)
		(layers "F.Cu" "B.Cu")
		(net "GND")
	)
	(via
		(at 345.451176 -270.846042)
		(size 0.4064)
		(drill 0.2032)
		(layers "F.Cu" "B.Cu")
		(net "GND")
	)
	(via
		(at 354.851208 -291.905944)
		(size 0.4064)
		(drill 0.2032)
		(layers "F.Cu" "B.Cu")
		(net "GND")
	)
	(via
		(at 151.694642 -75.70089)
		(size 0.508)
		(drill 0.254)
		(layers "F.Cu" "B.Cu")
		(net "GND")
	)
	(via
		(at 366.594898 -282.996132)
		(size 0.4064)
		(drill 0.2032)
		(layers "F.Cu" "B.Cu")
		(net "GND")
	)
	(via
		(at 29.303218 -19.771106)
		(size 0.508)
		(drill 0.254)
		(layers "F.Cu" "B.Cu")
		(net "GND")
	)
	(via
		(at 430.17186 -221.13494)
		(size 0.4826)
		(drill 0.254)
		(layers "F.Cu" "B.Cu")
		(net "GND")
	)
	(via
		(at 439.100214 -255.135126)
		(size 0.4826)
		(drill 0.254)
		(layers "F.Cu" "B.Cu")
		(net "GND")
	)
	(via
		(at 87.171022 -293.52621)
		(size 0.4064)
		(drill 0.2032)
		(layers "F.Cu" "B.Cu")
		(net "GND")
	)
	(via
		(at 32.357568 -400.183096)
		(size 0.508)
		(drill 0.254)
		(layers "F.Cu" "B.Cu")
		(net "GND")
	)
	(via
		(at 383.21488 -238.004096)
		(size 0.4064)
		(drill 0.2032)
		(layers "F.Cu" "B.Cu")
		(net "GND")
	)
	(via
		(at 97.211134 -225.854514)
		(size 0.4064)
		(drill 0.2032)
		(layers "F.Cu" "B.Cu")
		(net "GND")
	)
	(via
		(at 357.371142 -225.85426)
		(size 0.4064)
		(drill 0.2032)
		(layers "F.Cu" "B.Cu")
		(net "GND")
	)
	(via
		(at 48.855376 -403.830536)
		(size 0.4572)
		(drill 0.254)
		(layers "F.Cu" "B.Cu")
		(net "GND")
	)
	(via
		(at 421.067738 -192.21831)
		(size 0.4826)
		(drill 0.254)
		(layers "F.Cu" "B.Cu")
		(net "GND")
	)
	(via
		(at 424.168062 -12.37488)
		(size 0.508)
		(drill 0.254)
		(layers "F.Cu" "B.Cu")
		(net "GND")
	)
	(via
		(at 138.564874 -235.574332)
		(size 0.4064)
		(drill 0.2032)
		(layers "F.Cu" "B.Cu")
		(net "GND")
	)
	(via
		(at 51.884072 -224.535238)
		(size 0.4826)
		(drill 0.254)
		(layers "F.Cu" "B.Cu")
		(net "GND")
	)
	(via
		(at 21.336 -358.775)
		(size 0.508)
		(drill 0.254)
		(layers "F.Cu" "B.Cu")
		(net "GND")
	)
	(via
		(at 65.249806 -437.34736)
		(size 0.4572)
		(drill 0.2032)
		(layers "F.Cu" "B.Cu")
		(net "GND")
	)
	(via
		(at 405.27478 -379.22073)
		(size 0.508)
		(drill 0.254)
		(layers "F.Cu" "B.Cu")
		(net "GND")
	)
	(via
		(at 173.35627 -294.235378)
		(size 0.4826)
		(drill 0.254)
		(layers "F.Cu" "B.Cu")
		(net "GND")
	)
	(via
		(at 164.15639 -75.481434)
		(size 0.508)
		(drill 0.254)
		(layers "F.Cu" "B.Cu")
		(net "GND")
	)
	(via
		(at 435.000146 -266.185142)
		(size 0.4826)
		(drill 0.254)
		(layers "F.Cu" "B.Cu")
		(net "GND")
	)
	(via
		(at 149.650958 -405.098504)
		(size 0.4572)
		(drill 0.254)
		(layers "F.Cu" "B.Cu")
		(net "GND")
	)
	(via
		(at 378.344938 -269.22603)
		(size 0.4064)
		(drill 0.2032)
		(layers "F.Cu" "B.Cu")
		(net "GND")
	)
	(via
		(at 284.556962 -427.24197)
		(size 0.508)
		(drill 0.254)
		(layers "F.Cu" "B.Cu")
		(net "GND")
	)
	(via
		(at 356.431088 -224.234248)
		(size 0.4064)
		(drill 0.2032)
		(layers "F.Cu" "B.Cu")
		(net "GND")
	)
	(via
		(at 306.250594 -275.960078)
		(size 0.4826)
		(drill 0.254)
		(layers "F.Cu" "B.Cu")
		(net "GND")
	)
	(via
		(at 139.190222 -156.567124)
		(size 0.508)
		(drill 0.254)
		(layers "F.Cu" "B.Cu")
		(net "GND")
	)
	(via
		(at 334.249522 -432.451256)
		(size 0.4572)
		(drill 0.2032)
		(layers "F.Cu" "B.Cu")
		(net "GND")
	)
	(via
		(at 442.297566 -378.81687)
		(size 0.508)
		(drill 0.254)
		(layers "F.Cu" "B.Cu")
		(net "GND")
	)
	(via
		(at 195.988432 -231.335326)
		(size 0.4826)
		(drill 0.254)
		(layers "F.Cu" "B.Cu")
		(net "GND")
	)
	(via
		(at 450.088 -244.08511)
		(size 0.4826)
		(drill 0.254)
		(layers "F.Cu" "B.Cu")
		(net "GND")
	)
	(via
		(at 347.708474 -163.078668)
		(size 0.49022)
		(drill 0.254)
		(layers "F.Cu" "B.Cu")
		(net "GND")
	)
	(via
		(at 277.192232 -261.93496)
		(size 0.4826)
		(drill 0.254)
		(layers "F.Cu" "B.Cu")
		(net "GND")
	)
	(via
		(at 103.748586 -339.540342)
		(size 0.49022)
		(drill 0.254)
		(layers "F.Cu" "B.Cu")
		(net "GND")
	)
	(via
		(at 412.367984 -266.185142)
		(size 0.4826)
		(drill 0.254)
		(layers "F.Cu" "B.Cu")
		(net "GND")
	)
	(via
		(at 24.134572 -390.8425)
		(size 0.49022)
		(drill 0.254)
		(layers "F.Cu" "B.Cu")
		(net "GND")
	)
	(via
		(at 375.054876 -287.856168)
		(size 0.4064)
		(drill 0.2032)
		(layers "F.Cu" "B.Cu")
		(net "GND")
	)
	(via
		(at 338.249514 -432.451256)
		(size 0.4572)
		(drill 0.2032)
		(layers "F.Cu" "B.Cu")
		(net "GND")
	)
	(via
		(at 315.576458 -419.046152)
		(size 0.4572)
		(drill 0.254)
		(layers "F.Cu" "B.Cu")
		(net "GND")
	)
	(via
		(at 91.571064 -250.15444)
		(size 0.4064)
		(drill 0.2032)
		(layers "F.Cu" "B.Cu")
		(net "GND")
	)
	(via
		(at 93.450918 -238.814356)
		(size 0.4064)
		(drill 0.2032)
		(layers "F.Cu" "B.Cu")
		(net "GND")
	)
	(via
		(at 408.98699 -417.778184)
		(size 0.4572)
		(drill 0.254)
		(layers "F.Cu" "B.Cu")
		(net "GND")
	)
	(via
		(at 50.991516 -151.174196)
		(size 0.508)
		(drill 0.254)
		(layers "F.Cu" "B.Cu")
		(net "GND")
	)
	(via
		(at 242.593114 -319.466468)
		(size 0.508)
		(drill 0.254)
		(layers "F.Cu" "B.Cu")
		(net "GND")
	)
	(via
		(at 343.101168 -261.935976)
		(size 0.4064)
		(drill 0.2032)
		(layers "F.Cu" "B.Cu")
		(net "GND")
	)
	(via
		(at 51.7652 -418.295328)
		(size 0.508)
		(drill 0.254)
		(layers "F.Cu" "B.Cu")
		(net "GND")
	)
	(via
		(at 168.10863 -436.20436)
		(size 0.508)
		(drill 0.254)
		(layers "F.Cu" "B.Cu")
		(net "GND")
	)
	(via
		(at 379.035056 -183.922924)
		(size 0.49022)
		(drill 0.254)
		(layers "F.Cu" "B.Cu")
		(net "GND")
	)
	(via
		(at 88.677496 -405.098504)
		(size 0.4572)
		(drill 0.254)
		(layers "F.Cu" "B.Cu")
		(net "GND")
	)
	(via
		(at 21.69287 -383.209292)
		(size 0.508)
		(drill 0.254)
		(layers "F.Cu" "B.Cu")
		(net "GND")
	)
	(via
		(at 285.839154 -441.227718)
		(size 0.508)
		(drill 0.254)
		(layers "F.Cu" "B.Cu")
		(net "GND")
	)
	(via
		(at 38.950138 -18.247868)
		(size 0.508)
		(drill 0.254)
		(layers "F.Cu" "B.Cu")
		(net "GND")
	)
	(via
		(at 44.340018 -250.035314)
		(size 0.4826)
		(drill 0.254)
		(layers "F.Cu" "B.Cu")
		(net "GND")
	)
	(via
		(at 105.200958 -226.66452)
		(size 0.4064)
		(drill 0.2032)
		(layers "F.Cu" "B.Cu")
		(net "GND")
	)
	(via
		(at 222.758 -340.421214)
		(size 0.508)
		(drill 0.254)
		(layers "F.Cu" "B.Cu")
		(net "GND")
	)
	(via
		(at 171.565824 -380.535688)
		(size 0.508)
		(drill 0.254)
		(layers "F.Cu" "B.Cu")
		(net "GND")
	)
	(via
		(at 314.502546 -12.542266)
		(size 0.508)
		(drill 0.254)
		(layers "F.Cu" "B.Cu")
		(net "GND")
	)
	(via
		(at 169.645584 -210.510374)
		(size 0.4826)
		(drill 0.254)
		(layers "F.Cu" "B.Cu")
		(net "GND")
	)
	(via
		(at 456.188826 -51.31562)
		(size 0.508)
		(drill 0.254)
		(layers "F.Cu" "B.Cu")
		(net "GND")
	)
	(via
		(at 388.34949 -426.54728)
		(size 0.4572)
		(drill 0.2032)
		(layers "F.Cu" "B.Cu")
		(net "GND")
	)
	(via
		(at 340.24951 -426.69968)
		(size 0.4572)
		(drill 0.2032)
		(layers "F.Cu" "B.Cu")
		(net "GND")
	)
	(via
		(at 393.166092 -377.41733)
		(size 0.508)
		(drill 0.254)
		(layers "F.Cu" "B.Cu")
		(net "GND")
	)
	(via
		(at 362.537756 -333.624428)
		(size 0.508)
		(drill 0.254)
		(layers "F.Cu" "B.Cu")
		(net "GND")
	)
	(via
		(at 372.516146 -426.567854)
		(size 0.508)
		(drill 0.254)
		(layers "F.Cu" "B.Cu")
		(net "GND")
	)
	(via
		(at 288.180018 -242.385088)
		(size 0.4826)
		(drill 0.254)
		(layers "F.Cu" "B.Cu")
		(net "GND")
	)
	(via
		(at 40.23995 -197.335394)
		(size 0.4826)
		(drill 0.254)
		(layers "F.Cu" "B.Cu")
		(net "GND")
	)
	(via
		(at 371.995446 -184.683146)
		(size 0.49022)
		(drill 0.254)
		(layers "F.Cu" "B.Cu")
		(net "GND")
	)
	(via
		(at 413.752284 -284.88513)
		(size 0.4826)
		(drill 0.254)
		(layers "F.Cu" "B.Cu")
		(net "GND")
	)
	(via
		(at 429.565562 -10.16508)
		(size 0.508)
		(drill 0.254)
		(layers "F.Cu" "B.Cu")
		(net "GND")
	)
	(via
		(at 376.93473 -289.475926)
		(size 0.4064)
		(drill 0.2032)
		(layers "F.Cu" "B.Cu")
		(net "GND")
	)
	(via
		(at 16.704818 -408.78887)
		(size 0.508)
		(drill 0.254)
		(layers "F.Cu" "B.Cu")
		(net "GND")
	)
	(via
		(at 361.446318 -180.35524)
		(size 0.508)
		(drill 0.254)
		(layers "F.Cu" "B.Cu")
		(net "GND")
	)
	(via
		(at 396.903702 -397.463264)
		(size 0.508)
		(drill 0.254)
		(layers "F.Cu" "B.Cu")
		(net "GND")
	)
	(via
		(at 96.696784 -410.030168)
		(size 0.4064)
		(drill 0.2032)
		(layers "F.Cu" "B.Cu")
		(net "GND")
	)
	(via
		(at 315.24956 -436.347362)
		(size 0.4572)
		(drill 0.2032)
		(layers "F.Cu" "B.Cu")
		(net "GND")
	)
	(via
		(at 331.821028 -281.37612)
		(size 0.4064)
		(drill 0.2032)
		(layers "F.Cu" "B.Cu")
		(net "GND")
	)
	(via
		(at 428.840392 -238.13516)
		(size 0.4826)
		(drill 0.254)
		(layers "F.Cu" "B.Cu")
		(net "GND")
	)
	(via
		(at 28.53817 -364.125256)
		(size 0.508)
		(drill 0.254)
		(layers "F.Cu" "B.Cu")
		(net "GND")
	)
	(via
		(at 423.04208 -436.086758)
		(size 0.508)
		(drill 0.254)
		(layers "F.Cu" "B.Cu")
		(net "GND")
	)
	(via
		(at 351.731072 -232.334054)
		(size 0.4064)
		(drill 0.2032)
		(layers "F.Cu" "B.Cu")
		(net "GND")
	)
	(via
		(at 336.344006 -400.212814)
		(size 0.4064)
		(drill 0.2032)
		(layers "F.Cu" "B.Cu")
		(net "GND")
	)
	(via
		(at 265.54811 -300.185074)
		(size 0.4826)
		(drill 0.254)
		(layers "F.Cu" "B.Cu")
		(net "GND")
	)
	(via
		(at 187.060078 -197.335394)
		(size 0.4826)
		(drill 0.254)
		(layers "F.Cu" "B.Cu")
		(net "GND")
	)
	(via
		(at 100.031042 -224.234502)
		(size 0.4064)
		(drill 0.2032)
		(layers "F.Cu" "B.Cu")
		(net "GND")
	)
	(via
		(at 354.704904 -378.07773)
		(size 0.508)
		(drill 0.254)
		(layers "F.Cu" "B.Cu")
		(net "GND")
	)
	(via
		(at 194.604132 -247.485408)
		(size 0.4826)
		(drill 0.254)
		(layers "F.Cu" "B.Cu")
		(net "GND")
	)
	(via
		(at 387.575552 -380.54153)
		(size 0.508)
		(drill 0.254)
		(layers "F.Cu" "B.Cu")
		(net "GND")
	)
	(via
		(at 44.340018 -261.935214)
		(size 0.4826)
		(drill 0.254)
		(layers "F.Cu" "B.Cu")
		(net "GND")
	)
	(via
		(at 385.651502 -412.84652)
		(size 0.4064)
		(drill 0.2032)
		(layers "F.Cu" "B.Cu")
		(net "GND")
	)
	(via
		(at 338.401152 -287.856168)
		(size 0.4064)
		(drill 0.2032)
		(layers "F.Cu" "B.Cu")
		(net "GND")
	)
	(via
		(at 184.733692 -275.960332)
		(size 0.4826)
		(drill 0.254)
		(layers "F.Cu" "B.Cu")
		(net "GND")
	)
	(via
		(at 324.543928 -63.904876)
		(size 0.508)
		(drill 0.254)
		(layers "F.Cu" "B.Cu")
		(net "GND")
	)
	(via
		(at 18.992342 -240.68532)
		(size 0.4826)
		(drill 0.254)
		(layers "F.Cu" "B.Cu")
		(net "GND")
	)
	(via
		(at 130.40487 -287.046416)
		(size 0.4064)
		(drill 0.2032)
		(layers "F.Cu" "B.Cu")
		(net "GND")
	)
	(via
		(at 222.965518 -278.779478)
		(size 0.508)
		(drill 0.254)
		(layers "F.Cu" "B.Cu")
		(net "GND")
	)
	(via
		(at 361.424728 -269.22603)
		(size 0.4064)
		(drill 0.2032)
		(layers "F.Cu" "B.Cu")
		(net "GND")
	)
	(via
		(at 334.64119 -274.896072)
		(size 0.4064)
		(drill 0.2032)
		(layers "F.Cu" "B.Cu")
		(net "GND")
	)
	(via
		(at 11.476228 -108.15574)
		(size 0.508)
		(drill 0.254)
		(layers "F.Cu" "B.Cu")
		(net "GND")
	)
	(via
		(at 61.249814 -433.747164)
		(size 0.4572)
		(drill 0.2032)
		(layers "F.Cu" "B.Cu")
		(net "GND")
	)
	(via
		(at 69.249798 -430.147222)
		(size 0.4572)
		(drill 0.2032)
		(layers "F.Cu" "B.Cu")
		(net "GND")
	)
	(via
		(at 298.950888 -22.044152)
		(size 0.508)
		(drill 0.254)
		(layers "F.Cu" "B.Cu")
		(net "GND")
	)
	(via
		(at 168.527984 -198.185278)
		(size 0.4826)
		(drill 0.254)
		(layers "F.Cu" "B.Cu")
		(net "GND")
	)
	(via
		(at 129.31648 -382.85293)
		(size 0.4064)
		(drill 0.2032)
		(layers "F.Cu" "B.Cu")
		(net "GND")
	)
	(via
		(at 129.31648 -391.830814)
		(size 0.4064)
		(drill 0.2032)
		(layers "F.Cu" "B.Cu")
		(net "GND")
	)
	(via
		(at 327.761092 -247.724168)
		(size 0.4064)
		(drill 0.2032)
		(layers "F.Cu" "B.Cu")
		(net "GND")
	)
	(via
		(at 328.231246 -233.954066)
		(size 0.4064)
		(drill 0.2032)
		(layers "F.Cu" "B.Cu")
		(net "GND")
	)
	(via
		(at 288.180018 -283.185108)
		(size 0.4826)
		(drill 0.254)
		(layers "F.Cu" "B.Cu")
		(net "GND")
	)
	(via
		(at 146.860514 -406.370536)
		(size 0.4572)
		(drill 0.254)
		(layers "F.Cu" "B.Cu")
		(net "GND")
	)
	(via
		(at 123.994672 -239.624362)
		(size 0.4064)
		(drill 0.2032)
		(layers "F.Cu" "B.Cu")
		(net "GND")
	)
	(via
		(at 378.514864 -252.584204)
		(size 0.4064)
		(drill 0.2032)
		(layers "F.Cu" "B.Cu")
		(net "GND")
	)
	(via
		(at 12.090908 -412.093156)
		(size 0.508)
		(drill 0.254)
		(layers "F.Cu" "B.Cu")
		(net "GND")
	)
	(via
		(at 182.231792 -302.735234)
		(size 0.4826)
		(drill 0.254)
		(layers "F.Cu" "B.Cu")
		(net "GND")
	)
	(via
		(at 27.724354 -347.287088)
		(size 0.49022)
		(drill 0.254)
		(layers "F.Cu" "B.Cu")
		(net "GND")
	)
	(via
		(at 292.280086 -318.035178)
		(size 0.4826)
		(drill 0.254)
		(layers "F.Cu" "B.Cu")
		(net "GND")
	)
	(via
		(at 147.042886 -285.970472)
		(size 0.4064)
		(drill 0.2032)
		(layers "F.Cu" "B.Cu")
		(net "GND")
	)
	(via
		(at 461.859376 -391.000742)
		(size 0.508)
		(drill 0.254)
		(layers "F.Cu" "B.Cu")
		(net "GND")
	)
	(via
		(at 396.889478 -4.963414)
		(size 0.508)
		(drill 0.254)
		(layers "F.Cu" "B.Cu")
		(net "GND")
	)
	(via
		(at 403.349714 -425.547282)
		(size 0.4572)
		(drill 0.2032)
		(layers "F.Cu" "B.Cu")
		(net "GND")
	)
	(via
		(at 164.143944 -343.122758)
		(size 0.508)
		(drill 0.254)
		(layers "F.Cu" "B.Cu")
		(net "GND")
	)
	(via
		(at 52.51704 -37.78504)
		(size 0.508)
		(drill 0.254)
		(layers "F.Cu" "B.Cu")
		(net "GND")
	)
	(via
		(at 369.884706 -262.745982)
		(size 0.4064)
		(drill 0.2032)
		(layers "F.Cu" "B.Cu")
		(net "GND")
	)
	(via
		(at 334.249522 -433.747164)
		(size 0.4572)
		(drill 0.2032)
		(layers "F.Cu" "B.Cu")
		(net "GND")
	)
	(via
		(at 62.216538 -391.830814)
		(size 0.4064)
		(drill 0.2032)
		(layers "F.Cu" "B.Cu")
		(net "GND")
	)
	(via
		(at 102.852982 -340.505288)
		(size 0.49022)
		(drill 0.254)
		(layers "F.Cu" "B.Cu")
		(net "GND")
	)
	(via
		(at 70.617334 -377.132088)
		(size 0.508)
		(drill 0.254)
		(layers "F.Cu" "B.Cu")
		(net "GND")
	)
	(via
		(at 138.377676 -381.020828)
		(size 0.508)
		(drill 0.254)
		(layers "F.Cu" "B.Cu")
		(net "GND")
	)
	(via
		(at 76.812902 -235.030264)
		(size 0.4064)
		(drill 0.2032)
		(layers "F.Cu" "B.Cu")
		(net "GND")
	)
	(via
		(at 39.12235 -220.710252)
		(size 0.4826)
		(drill 0.254)
		(layers "F.Cu" "B.Cu")
		(net "GND")
	)
	(via
		(at 135.574786 -282.996386)
		(size 0.4064)
		(drill 0.2032)
		(layers "F.Cu" "B.Cu")
		(net "GND")
	)
	(via
		(at 307.368194 -246.635016)
		(size 0.4826)
		(drill 0.254)
		(layers "F.Cu" "B.Cu")
		(net "GND")
	)
	(via
		(at 222.537782 -18.68932)
		(size 0.508)
		(drill 0.254)
		(layers "F.Cu" "B.Cu")
		(net "GND")
	)
	(via
		(at 82.001106 -278.13635)
		(size 0.4064)
		(drill 0.2032)
		(layers "F.Cu" "B.Cu")
		(net "GND")
	)
	(via
		(at 179.639722 -31.482284)
		(size 0.508)
		(drill 0.254)
		(layers "F.Cu" "B.Cu")
		(net "GND")
	)
	(via
		(at 432.67376 -294.660066)
		(size 0.4826)
		(drill 0.254)
		(layers "F.Cu" "B.Cu")
		(net "GND")
	)
	(via
		(at 243.280692 -422.15181)
		(size 0.508)
		(drill 0.254)
		(layers "F.Cu" "B.Cu")
		(net "GND")
	)
	(via
		(at 78.241144 -294.336216)
		(size 0.4064)
		(drill 0.2032)
		(layers "F.Cu" "B.Cu")
		(net "GND")
	)
	(via
		(at 250.280932 -422.13149)
		(size 0.508)
		(drill 0.254)
		(layers "F.Cu" "B.Cu")
		(net "GND")
	)
	(via
		(at 156.22905 -112.522)
		(size 0.508)
		(drill 0.254)
		(layers "F.Cu" "B.Cu")
		(net "GND")
	)
	(via
		(at 375.99493 -268.416024)
		(size 0.4064)
		(drill 0.2032)
		(layers "F.Cu" "B.Cu")
		(net "GND")
	)
	(via
		(at 364.809278 -171.77131)
		(size 0.508)
		(drill 0.254)
		(layers "F.Cu" "B.Cu")
		(net "GND")
	)
	(via
		(at 168.527984 -297.635422)
		(size 0.4826)
		(drill 0.254)
		(layers "F.Cu" "B.Cu")
		(net "GND")
	)
	(via
		(at 265.54811 -289.135058)
		(size 0.4826)
		(drill 0.254)
		(layers "F.Cu" "B.Cu")
		(net "GND")
	)
	(via
		(at 110.671102 -283.806392)
		(size 0.4064)
		(drill 0.2032)
		(layers "F.Cu" "B.Cu")
		(net "GND")
	)
	(via
		(at 298.40301 -344.77706)
		(size 0.49022)
		(drill 0.254)
		(layers "F.Cu" "B.Cu")
		(net "GND")
	)
	(via
		(at 335.75117 -224.234248)
		(size 0.4064)
		(drill 0.2032)
		(layers "F.Cu" "B.Cu")
		(net "GND")
	)
	(via
		(at 131.632706 -404.46452)
		(size 0.4064)
		(drill 0.2032)
		(layers "F.Cu" "B.Cu")
		(net "GND")
	)
	(via
		(at 136.34974 -428.851314)
		(size 0.4572)
		(drill 0.2032)
		(layers "F.Cu" "B.Cu")
		(net "GND")
	)
	(via
		(at 133.277356 -369.69573)
		(size 0.508)
		(drill 0.254)
		(layers "F.Cu" "B.Cu")
		(net "GND")
	)
	(via
		(at 340.705948 -394.831062)
		(size 0.4064)
		(drill 0.2032)
		(layers "F.Cu" "B.Cu")
		(net "GND")
	)
	(via
		(at 110.200948 -287.856422)
		(size 0.4064)
		(drill 0.2032)
		(layers "F.Cu" "B.Cu")
		(net "GND")
	)
	(via
		(at 222.515176 -366.856518)
		(size 0.508)
		(drill 0.254)
		(layers "F.Cu" "B.Cu")
		(net "GND")
	)
	(via
		(at 387.914896 -238.004096)
		(size 0.4064)
		(drill 0.2032)
		(layers "F.Cu" "B.Cu")
		(net "GND")
	)
	(via
		(at 379.525022 -420.952168)
		(size 0.4064)
		(drill 0.2032)
		(layers "F.Cu" "B.Cu")
		(net "GND")
	)
	(via
		(at 450.313044 -9.50722)
		(size 0.508)
		(drill 0.254)
		(layers "F.Cu" "B.Cu")
		(net "GND")
	)
	(via
		(at 83.41106 -262.746236)
		(size 0.4064)
		(drill 0.2032)
		(layers "F.Cu" "B.Cu")
		(net "GND")
	)
	(via
		(at 405.34971 -439.651394)
		(size 0.4572)
		(drill 0.2032)
		(layers "F.Cu" "B.Cu")
		(net "GND")
	)
	(via
		(at 349.544894 -413.480504)
		(size 0.4572)
		(drill 0.254)
		(layers "F.Cu" "B.Cu")
		(net "GND")
	)
	(via
		(at 22.58187 -383.209292)
		(size 0.508)
		(drill 0.254)
		(layers "F.Cu" "B.Cu")
		(net "GND")
	)
	(via
		(at 29.252164 -222.835216)
		(size 0.4826)
		(drill 0.254)
		(layers "F.Cu" "B.Cu")
		(net "GND")
	)
	(via
		(at 414.244282 -400.212814)
		(size 0.4064)
		(drill 0.2032)
		(layers "F.Cu" "B.Cu")
		(net "GND")
	)
	(via
		(at 445.224154 -45.676058)
		(size 0.508)
		(drill 0.254)
		(layers "F.Cu" "B.Cu")
		(net "GND")
	)
	(via
		(at 436.384446 -203.28509)
		(size 0.4826)
		(drill 0.254)
		(layers "F.Cu" "B.Cu")
		(net "GND")
	)
	(via
		(at 300.056296 -377.41733)
		(size 0.508)
		(drill 0.254)
		(layers "F.Cu" "B.Cu")
		(net "GND")
	)
	(via
		(at 117.244622 -291.906198)
		(size 0.4064)
		(drill 0.2032)
		(layers "F.Cu" "B.Cu")
		(net "GND")
	)
	(via
		(at 86.481158 -334.579468)
		(size 0.49022)
		(drill 0.254)
		(layers "F.Cu" "B.Cu")
		(net "GND")
	)
	(via
		(at 268.530578 -275.960078)
		(size 0.4826)
		(drill 0.254)
		(layers "F.Cu" "B.Cu")
		(net "GND")
	)
	(via
		(at 97.005902 -369.03533)
		(size 0.508)
		(drill 0.254)
		(layers "F.Cu" "B.Cu")
		(net "GND")
	)
	(via
		(at 318.639698 -414.752536)
		(size 0.4572)
		(drill 0.254)
		(layers "F.Cu" "B.Cu")
		(net "GND")
	)
	(via
		(at 324.75297 -243.13007)
		(size 0.4064)
		(drill 0.2032)
		(layers "F.Cu" "B.Cu")
		(net "GND")
	)
	(via
		(at 343.101168 -273.27606)
		(size 0.4064)
		(drill 0.2032)
		(layers "F.Cu" "B.Cu")
		(net "GND")
	)
	(via
		(at 117.868954 -57.098946)
		(size 0.508)
		(drill 0.254)
		(layers "F.Cu" "B.Cu")
		(net "GND")
	)
	(via
		(at 347.50121 -252.584204)
		(size 0.4064)
		(drill 0.2032)
		(layers "F.Cu" "B.Cu")
		(net "GND")
	)
	(via
		(at 27.650694 -387.70814)
		(size 0.49022)
		(drill 0.254)
		(layers "F.Cu" "B.Cu")
		(net "GND")
	)
	(via
		(at 355.021134 -221.80423)
		(size 0.4064)
		(drill 0.2032)
		(layers "F.Cu" "B.Cu")
		(net "GND")
	)
	(via
		(at 306.118006 -335.658968)
		(size 0.508)
		(drill 0.254)
		(layers "F.Cu" "B.Cu")
		(net "GND")
	)
	(via
		(at 444.255652 -399.233644)
		(size 0.49022)
		(drill 0.254)
		(layers "F.Cu" "B.Cu")
		(net "GND")
	)
	(via
		(at 324.75297 -238.270034)
		(size 0.4064)
		(drill 0.2032)
		(layers "F.Cu" "B.Cu")
		(net "GND")
	)
	(via
		(at 467.51621 -12.542266)
		(size 0.508)
		(drill 0.254)
		(layers "F.Cu" "B.Cu")
		(net "GND")
	)
	(via
		(at 134.349744 -426.69968)
		(size 0.4572)
		(drill 0.2032)
		(layers "F.Cu" "B.Cu")
		(net "GND")
	)
	(via
		(at 233.707178 -319.466468)
		(size 0.508)
		(drill 0.254)
		(layers "F.Cu" "B.Cu")
		(net "GND")
	)
	(via
		(at 99.390962 -277.326344)
		(size 0.4064)
		(drill 0.2032)
		(layers "F.Cu" "B.Cu")
		(net "GND")
	)
	(via
		(at 88.580976 -270.03629)
		(size 0.4064)
		(drill 0.2032)
		(layers "F.Cu" "B.Cu")
		(net "GND")
	)
	(via
		(at 84.99094 -227.474526)
		(size 0.4064)
		(drill 0.2032)
		(layers "F.Cu" "B.Cu")
		(net "GND")
	)
	(via
		(at 442.5442 -300.185074)
		(size 0.4826)
		(drill 0.254)
		(layers "F.Cu" "B.Cu")
		(net "GND")
	)
	(via
		(at 165.805104 -369.69573)
		(size 0.508)
		(drill 0.254)
		(layers "F.Cu" "B.Cu")
		(net "GND")
	)
	(via
		(at 393.67079 -419.046152)
		(size 0.4572)
		(drill 0.254)
		(layers "F.Cu" "B.Cu")
		(net "GND")
	)
	(via
		(at 437.325516 -330.069952)
		(size 0.508)
		(drill 0.254)
		(layers "F.Cu" "B.Cu")
		(net "GND")
	)
	(via
		(at 361.124754 -243.674138)
		(size 0.4064)
		(drill 0.2032)
		(layers "F.Cu" "B.Cu")
		(net "GND")
	)
	(via
		(at 391.674858 -255.824228)
		(size 0.4064)
		(drill 0.2032)
		(layers "F.Cu" "B.Cu")
		(net "GND")
	)
	(via
		(at 276.61362 -429.572166)
		(size 0.508)
		(drill 0.254)
		(layers "F.Cu" "B.Cu")
		(net "GND")
	)
	(via
		(at 90.461084 -276.516338)
		(size 0.4064)
		(drill 0.2032)
		(layers "F.Cu" "B.Cu")
		(net "GND")
	)
	(via
		(at 12.733782 -404.490174)
		(size 0.508)
		(drill 0.254)
		(layers "F.Cu" "B.Cu")
		(net "GND")
	)
	(via
		(at 446.107566 -376.53087)
		(size 0.508)
		(drill 0.254)
		(layers "F.Cu" "B.Cu")
		(net "GND")
	)
	(via
		(at 336.22107 -238.004096)
		(size 0.4064)
		(drill 0.2032)
		(layers "F.Cu" "B.Cu")
		(net "GND")
	)
	(via
		(at 55.254652 -407.638504)
		(size 0.4572)
		(drill 0.254)
		(layers "F.Cu" "B.Cu")
		(net "GND")
	)
	(via
		(at 437.715914 -277.235158)
		(size 0.4826)
		(drill 0.254)
		(layers "F.Cu" "B.Cu")
		(net "GND")
	)
	(via
		(at 373.344694 -243.674138)
		(size 0.4064)
		(drill 0.2032)
		(layers "F.Cu" "B.Cu")
		(net "GND")
	)
	(via
		(at 314.191142 -398.542002)
		(size 0.4064)
		(drill 0.2032)
		(layers "F.Cu" "B.Cu")
		(net "GND")
	)
	(via
		(at 378.398278 -140.456158)
		(size 0.508)
		(drill 0.254)
		(layers "F.Cu" "B.Cu")
		(net "GND")
	)
	(via
		(at 350.087184 -381.68453)
		(size 0.508)
		(drill 0.254)
		(layers "F.Cu" "B.Cu")
		(net "GND")
	)
	(via
		(at 26.536396 -203.285344)
		(size 0.4826)
		(drill 0.254)
		(layers "F.Cu" "B.Cu")
		(net "GND")
	)
	(via
		(at 337.930998 -295.145968)
		(size 0.4064)
		(drill 0.2032)
		(layers "F.Cu" "B.Cu")
		(net "GND")
	)
	(via
		(at 343.101168 -278.136096)
		(size 0.4064)
		(drill 0.2032)
		(layers "F.Cu" "B.Cu")
		(net "GND")
	)
	(via
		(at 123.824746 -270.846296)
		(size 0.4064)
		(drill 0.2032)
		(layers "F.Cu" "B.Cu")
		(net "GND")
	)
	(via
		(at 280.635964 -281.485086)
		(size 0.4826)
		(drill 0.254)
		(layers "F.Cu" "B.Cu")
		(net "GND")
	)
	(via
		(at 14.549374 -387.704076)
		(size 0.49022)
		(drill 0.254)
		(layers "F.Cu" "B.Cu")
		(net "GND")
	)
	(via
		(at 74.534522 -19.958304)
		(size 0.508)
		(drill 0.254)
		(layers "F.Cu" "B.Cu")
		(net "GND")
	)
	(via
		(at 373.644922 -274.086066)
		(size 0.4064)
		(drill 0.2032)
		(layers "F.Cu" "B.Cu")
		(net "GND")
	)
	(via
		(at 76.812902 -256.09042)
		(size 0.4064)
		(drill 0.2032)
		(layers "F.Cu" "B.Cu")
		(net "GND")
	)
	(via
		(at 133.694678 -266.796266)
		(size 0.4064)
		(drill 0.2032)
		(layers "F.Cu" "B.Cu")
		(net "GND")
	)
	(via
		(at 378.344938 -278.946102)
		(size 0.4064)
		(drill 0.2032)
		(layers "F.Cu" "B.Cu")
		(net "GND")
	)
	(via
		(at 266.93241 -231.335072)
		(size 0.4826)
		(drill 0.254)
		(layers "F.Cu" "B.Cu")
		(net "GND")
	)
	(via
		(at 77.112876 -279.490424)
		(size 0.4064)
		(drill 0.2032)
		(layers "F.Cu" "B.Cu")
		(net "GND")
	)
	(via
		(at 321.975734 -412.212536)
		(size 0.4572)
		(drill 0.254)
		(layers "F.Cu" "B.Cu")
		(net "GND")
	)
	(via
		(at 372.234714 -291.095938)
		(size 0.4064)
		(drill 0.2032)
		(layers "F.Cu" "B.Cu")
		(net "GND")
	)
	(via
		(at 454.188068 -204.134974)
		(size 0.4826)
		(drill 0.254)
		(layers "F.Cu" "B.Cu")
		(net "GND")
	)
	(via
		(at 69.149468 -132.861304)
		(size 0.508)
		(drill 0.254)
		(layers "F.Cu" "B.Cu")
		(net "GND")
	)
	(via
		(at 14.686788 -369.84305)
		(size 0.508)
		(drill 0.254)
		(layers "F.Cu" "B.Cu")
		(net "GND")
	)
	(via
		(at 33.768538 -345.799918)
		(size 0.49022)
		(drill 0.254)
		(layers "F.Cu" "B.Cu")
		(net "GND")
	)
	(via
		(at 69.179694 -30.541722)
		(size 0.508)
		(drill 0.254)
		(layers "F.Cu" "B.Cu")
		(net "GND")
	)
	(via
		(at 239.282224 -370.7511)
		(size 0.508)
		(drill 0.254)
		(layers "F.Cu" "B.Cu")
		(net "GND")
	)
	(via
		(at 145.144744 -225.854514)
		(size 0.4064)
		(drill 0.2032)
		(layers "F.Cu" "B.Cu")
		(net "GND")
	)
	(via
		(at 318.08674 -335.561178)
		(size 0.49022)
		(drill 0.254)
		(layers "F.Cu" "B.Cu")
		(net "GND")
	)
	(via
		(at 416.468052 -306.985162)
		(size 0.4826)
		(drill 0.254)
		(layers "F.Cu" "B.Cu")
		(net "GND")
	)
	(via
		(at 380.303278 -142.361158)
		(size 0.508)
		(drill 0.254)
		(layers "F.Cu" "B.Cu")
		(net "GND")
	)
	(via
		(at 148.119338 -410.664152)
		(size 0.4572)
		(drill 0.254)
		(layers "F.Cu" "B.Cu")
		(net "GND")
	)
	(via
		(at 382.349502 -430.299622)
		(size 0.4572)
		(drill 0.2032)
		(layers "F.Cu" "B.Cu")
		(net "GND")
	)
	(via
		(at 198.7042 -301.035212)
		(size 0.4826)
		(drill 0.254)
		(layers "F.Cu" "B.Cu")
		(net "GND")
	)
	(via
		(at 59.912758 -345.571064)
		(size 0.49022)
		(drill 0.254)
		(layers "F.Cu" "B.Cu")
		(net "GND")
	)
	(via
		(at 171.06392 -422.317672)
		(size 0.508)
		(drill 0.254)
		(layers "F.Cu" "B.Cu")
		(net "GND")
	)
	(via
		(at 54.591204 -390.160002)
		(size 0.4064)
		(drill 0.2032)
		(layers "F.Cu" "B.Cu")
		(net "GND")
	)
	(via
		(at 103.805482 -375.432828)
		(size 0.508)
		(drill 0.254)
		(layers "F.Cu" "B.Cu")
		(net "GND")
	)
	(via
		(at 340.921086 -231.524048)
		(size 0.4064)
		(drill 0.2032)
		(layers "F.Cu" "B.Cu")
		(net "GND")
	)
	(via
		(at 329.47102 -293.525956)
		(size 0.4064)
		(drill 0.2032)
		(layers "F.Cu" "B.Cu")
		(net "GND")
	)
	(via
		(at 59.428126 -267.03528)
		(size 0.4826)
		(drill 0.254)
		(layers "F.Cu" "B.Cu")
		(net "GND")
	)
	(via
		(at 78.711044 -262.746236)
		(size 0.4064)
		(drill 0.2032)
		(layers "F.Cu" "B.Cu")
		(net "GND")
	)
	(via
		(at 370.524786 -243.674138)
		(size 0.4064)
		(drill 0.2032)
		(layers "F.Cu" "B.Cu")
		(net "GND")
	)
	(via
		(at 36.795964 -205.83525)
		(size 0.4826)
		(drill 0.254)
		(layers "F.Cu" "B.Cu")
		(net "GND")
	)
	(via
		(at 140.444728 -250.15444)
		(size 0.4064)
		(drill 0.2032)
		(layers "F.Cu" "B.Cu")
		(net "GND")
	)
	(via
		(at 336.521044 -282.996132)
		(size 0.4064)
		(drill 0.2032)
		(layers "F.Cu" "B.Cu")
		(net "GND")
	)
	(via
		(at 429.767238 -433.986686)
		(size 0.508)
		(drill 0.254)
		(layers "F.Cu" "B.Cu")
		(net "GND")
	)
	(via
		(at 131.51485 -225.044508)
		(size 0.4064)
		(drill 0.2032)
		(layers "F.Cu" "B.Cu")
		(net "GND")
	)
	(via
		(at 122.116596 -382.85293)
		(size 0.4064)
		(drill 0.2032)
		(layers "F.Cu" "B.Cu")
		(net "GND")
	)
	(via
		(at 111.508794 -187.634118)
		(size 0.508)
		(drill 0.254)
		(layers "F.Cu" "B.Cu")
		(net "GND")
	)
	(via
		(at 105.031032 -287.046162)
		(size 0.4064)
		(drill 0.2032)
		(layers "F.Cu" "B.Cu")
		(net "GND")
	)
	(via
		(at 333.230982 -290.285932)
		(size 0.4064)
		(drill 0.2032)
		(layers "F.Cu" "B.Cu")
		(net "GND")
	)
	(via
		(at 51.884072 -301.035212)
		(size 0.4826)
		(drill 0.254)
		(layers "F.Cu" "B.Cu")
		(net "GND")
	)
	(via
		(at 202.147932 -223.685354)
		(size 0.4826)
		(drill 0.254)
		(layers "F.Cu" "B.Cu")
		(net "GND")
	)
	(via
		(at 58.043826 -274.685252)
		(size 0.4826)
		(drill 0.254)
		(layers "F.Cu" "B.Cu")
		(net "GND")
	)
	(via
		(at 274.791678 -68.543424)
		(size 0.508)
		(drill 0.254)
		(layers "F.Cu" "B.Cu")
		(net "GND")
	)
	(via
		(at 467.5378 -239.319054)
		(size 0.508)
		(drill 0.254)
		(layers "F.Cu" "B.Cu")
		(net "GND")
	)
	(via
		(at 125.059186 -410.030168)
		(size 0.4064)
		(drill 0.2032)
		(layers "F.Cu" "B.Cu")
		(net "GND")
	)
	(via
		(at 83.111086 -251.774452)
		(size 0.4064)
		(drill 0.2032)
		(layers "F.Cu" "B.Cu")
		(net "GND")
	)
	(via
		(at 137.45464 -265.176254)
		(size 0.4064)
		(drill 0.2032)
		(layers "F.Cu" "B.Cu")
		(net "GND")
	)
	(via
		(at 152.714198 -403.830536)
		(size 0.4572)
		(drill 0.254)
		(layers "F.Cu" "B.Cu")
		(net "GND")
	)
	(via
		(at 353.141026 -247.724168)
		(size 0.4064)
		(drill 0.2032)
		(layers "F.Cu" "B.Cu")
		(net "GND")
	)
	(via
		(at 143.243554 -40.803576)
		(size 0.508)
		(drill 0.254)
		(layers "F.Cu" "B.Cu")
		(net "GND")
	)
	(via
		(at 15.180818 -411.83687)
		(size 0.508)
		(drill 0.254)
		(layers "F.Cu" "B.Cu")
		(net "GND")
	)
	(via
		(at 159.090106 -384.617722)
		(size 0.4064)
		(drill 0.2032)
		(layers "F.Cu" "B.Cu")
		(net "GND")
	)
	(via
		(at 27.959558 -346.322142)
		(size 0.49022)
		(drill 0.254)
		(layers "F.Cu" "B.Cu")
		(net "GND")
	)
	(via
		(at 59.249818 -431.451258)
		(size 0.4572)
		(drill 0.2032)
		(layers "F.Cu" "B.Cu")
		(net "GND")
	)
	(via
		(at 90.650314 -331.73416)
		(size 0.508)
		(drill 0.254)
		(layers "F.Cu" "B.Cu")
		(net "GND")
	)
	(via
		(at 352.9711 -290.285932)
		(size 0.4064)
		(drill 0.2032)
		(layers "F.Cu" "B.Cu")
		(net "GND")
	)
	(via
		(at 145.144744 -240.434368)
		(size 0.4064)
		(drill 0.2032)
		(layers "F.Cu" "B.Cu")
		(net "GND")
	)
	(via
		(at 71.625968 -341.04707)
		(size 0.508)
		(drill 0.254)
		(layers "F.Cu" "B.Cu")
		(net "GND")
	)
	(via
		(at 233.651044 -45.593)
		(size 0.508)
		(drill 0.254)
		(layers "F.Cu" "B.Cu")
		(net "GND")
	)
	(via
		(at 104.731058 -229.094538)
		(size 0.4064)
		(drill 0.2032)
		(layers "F.Cu" "B.Cu")
		(net "GND")
	)
	(via
		(at 437.421782 -438.23636)
		(size 0.508)
		(drill 0.254)
		(layers "F.Cu" "B.Cu")
		(net "GND")
	)
	(via
		(at 198.631556 -340.375748)
		(size 0.508)
		(drill 0.254)
		(layers "F.Cu" "B.Cu")
		(net "GND")
	)
	(via
		(at 21.70811 -268.735302)
		(size 0.4826)
		(drill 0.254)
		(layers "F.Cu" "B.Cu")
		(net "GND")
	)
	(via
		(at 393.045696 -7.215124)
		(size 0.508)
		(drill 0.254)
		(layers "F.Cu" "B.Cu")
		(net "GND")
	)
	(via
		(at 390.094724 -289.475926)
		(size 0.4064)
		(drill 0.2032)
		(layers "F.Cu" "B.Cu")
		(net "GND")
	)
	(via
		(at 451.4723 -287.435036)
		(size 0.4826)
		(drill 0.254)
		(layers "F.Cu" "B.Cu")
		(net "GND")
	)
	(via
		(at 136.34974 -430.147222)
		(size 0.4572)
		(drill 0.2032)
		(layers "F.Cu" "B.Cu")
		(net "GND")
	)
	(via
		(at 340.24951 -425.547282)
		(size 0.4572)
		(drill 0.2032)
		(layers "F.Cu" "B.Cu")
		(net "GND")
	)
	(via
		(at 334.314546 -415.38652)
		(size 0.4064)
		(drill 0.2032)
		(layers "F.Cu" "B.Cu")
		(net "GND")
	)
	(via
		(at 416.5092 -111.501428)
		(size 0.508)
		(drill 0.254)
		(layers "F.Cu" "B.Cu")
		(net "GND")
	)
	(via
		(at 191.160146 -282.335224)
		(size 0.4826)
		(drill 0.254)
		(layers "F.Cu" "B.Cu")
		(net "GND")
	)
	(via
		(at 102.38105 -247.724422)
		(size 0.4064)
		(drill 0.2032)
		(layers "F.Cu" "B.Cu")
		(net "GND")
	)
	(via
		(at 84.821014 -294.336216)
		(size 0.4064)
		(drill 0.2032)
		(layers "F.Cu" "B.Cu")
		(net "GND")
	)
	(via
		(at 51.468274 -9.424924)
		(size 0.508)
		(drill 0.254)
		(layers "F.Cu" "B.Cu")
		(net "GND")
	)
	(via
		(at 375.054876 -282.996132)
		(size 0.4064)
		(drill 0.2032)
		(layers "F.Cu" "B.Cu")
		(net "GND")
	)
	(via
		(at 116.891308 -390.160002)
		(size 0.4064)
		(drill 0.2032)
		(layers "F.Cu" "B.Cu")
		(net "GND")
	)
	(via
		(at 133.394704 -247.724422)
		(size 0.4064)
		(drill 0.2032)
		(layers "F.Cu" "B.Cu")
		(net "GND")
	)
	(via
		(at 358.108504 -378.07773)
		(size 0.508)
		(drill 0.254)
		(layers "F.Cu" "B.Cu")
		(net "GND")
	)
	(via
		(at 421.296338 -306.135024)
		(size 0.4826)
		(drill 0.254)
		(layers "F.Cu" "B.Cu")
		(net "GND")
	)
	(via
		(at 160.645094 -411.936184)
		(size 0.4572)
		(drill 0.254)
		(layers "F.Cu" "B.Cu")
		(net "GND")
	)
	(via
		(at 88.494362 -373.30253)
		(size 0.508)
		(drill 0.254)
		(layers "F.Cu" "B.Cu")
		(net "GND")
	)
	(via
		(at 165.812216 -294.235378)
		(size 0.4826)
		(drill 0.254)
		(layers "F.Cu" "B.Cu")
		(net "GND")
	)
	(via
		(at 391.504678 -262.745982)
		(size 0.4064)
		(drill 0.2032)
		(layers "F.Cu" "B.Cu")
		(net "GND")
	)
	(via
		(at 115.534694 -249.344434)
		(size 0.4064)
		(drill 0.2032)
		(layers "F.Cu" "B.Cu")
		(net "GND")
	)
	(via
		(at 416.558222 -9.424924)
		(size 0.508)
		(drill 0.254)
		(layers "F.Cu" "B.Cu")
		(net "GND")
	)
	(via
		(at 388.463536 -51.11623)
		(size 0.508)
		(drill 0.254)
		(layers "F.Cu" "B.Cu")
		(net "GND")
	)
	(via
		(at 74.83729 -175.637444)
		(size 0.49022)
		(drill 0.254)
		(layers "F.Cu" "B.Cu")
		(net "GND")
	)
	(via
		(at 399.524474 -412.212536)
		(size 0.4572)
		(drill 0.254)
		(layers "F.Cu" "B.Cu")
		(net "GND")
	)
	(via
		(at 382.1049 -293.525956)
		(size 0.4064)
		(drill 0.2032)
		(layers "F.Cu" "B.Cu")
		(net "GND")
	)
	(via
		(at 384.924808 -282.186126)
		(size 0.4064)
		(drill 0.2032)
		(layers "F.Cu" "B.Cu")
		(net "GND")
	)
	(via
		(at 386.361432 -379.22073)
		(size 0.508)
		(drill 0.254)
		(layers "F.Cu" "B.Cu")
		(net "GND")
	)
	(via
		(at 365.18469 -288.66592)
		(size 0.4064)
		(drill 0.2032)
		(layers "F.Cu" "B.Cu")
		(net "GND")
	)
	(via
		(at 32.680402 -5.597398)
		(size 0.508)
		(drill 0.254)
		(layers "F.Cu" "B.Cu")
		(net "GND")
	)
	(via
		(at 137.417302 -56.500014)
		(size 0.508)
		(drill 0.254)
		(layers "F.Cu" "B.Cu")
		(net "GND")
	)
	(via
		(at 386.541518 -185.988198)
		(size 0.508)
		(drill 0.254)
		(layers "F.Cu" "B.Cu")
		(net "GND")
	)
	(via
		(at 128.994662 -263.556242)
		(size 0.4064)
		(drill 0.2032)
		(layers "F.Cu" "B.Cu")
		(net "GND")
	)
	(via
		(at 48.71847 -388.328662)
		(size 0.4064)
		(drill 0.2032)
		(layers "F.Cu" "B.Cu")
		(net "GND")
	)
	(via
		(at 428.8028 -17.613122)
		(size 0.508)
		(drill 0.254)
		(layers "F.Cu" "B.Cu")
		(net "GND")
	)
	(via
		(at 141.058392 -375.30786)
		(size 0.508)
		(drill 0.254)
		(layers "F.Cu" "B.Cu")
		(net "GND")
	)
	(via
		(at 58.153554 -371.49913)
		(size 0.508)
		(drill 0.254)
		(layers "F.Cu" "B.Cu")
		(net "GND")
	)
	(via
		(at 403.57933 -5.597398)
		(size 0.508)
		(drill 0.254)
		(layers "F.Cu" "B.Cu")
		(net "GND")
	)
	(via
		(at 407.182574 -417.778184)
		(size 0.4572)
		(drill 0.254)
		(layers "F.Cu" "B.Cu")
		(net "GND")
	)
	(via
		(at 169.208704 -369.69573)
		(size 0.508)
		(drill 0.254)
		(layers "F.Cu" "B.Cu")
		(net "GND")
	)
	(via
		(at 96.74098 -226.66452)
		(size 0.4064)
		(drill 0.2032)
		(layers "F.Cu" "B.Cu")
		(net "GND")
	)
	(via
		(at 88.950292 -407.638504)
		(size 0.4572)
		(drill 0.254)
		(layers "F.Cu" "B.Cu")
		(net "GND")
	)
	(via
		(at 283.351732 -221.13494)
		(size 0.4826)
		(drill 0.254)
		(layers "F.Cu" "B.Cu")
		(net "GND")
	)
	(via
		(at 78.711044 -269.226284)
		(size 0.4064)
		(drill 0.2032)
		(layers "F.Cu" "B.Cu")
		(net "GND")
	)
	(via
		(at 243.994432 -421.48125)
		(size 0.508)
		(drill 0.254)
		(layers "F.Cu" "B.Cu")
		(net "GND")
	)
	(via
		(at 42.955718 -277.235412)
		(size 0.4826)
		(drill 0.254)
		(layers "F.Cu" "B.Cu")
		(net "GND")
	)
	(via
		(at 134.695946 -404.46452)
		(size 0.4064)
		(drill 0.2032)
		(layers "F.Cu" "B.Cu")
		(net "GND")
	)
	(via
		(at 145.383504 -368.37493)
		(size 0.508)
		(drill 0.254)
		(layers "F.Cu" "B.Cu")
		(net "GND")
	)
	(via
		(at 292.451536 -395.231366)
		(size 0.508)
		(drill 0.254)
		(layers "F.Cu" "B.Cu")
		(net "GND")
	)
	(via
		(at 107.85094 -293.52621)
		(size 0.4064)
		(drill 0.2032)
		(layers "F.Cu" "B.Cu")
		(net "GND")
	)
	(via
		(at 143.885666 -412.570168)
		(size 0.4064)
		(drill 0.2032)
		(layers "F.Cu" "B.Cu")
		(net "GND")
	)
	(via
		(at 429.571404 -396.119604)
		(size 0.508)
		(drill 0.254)
		(layers "F.Cu" "B.Cu")
		(net "GND")
	)
	(via
		(at 411.349698 -425.547282)
		(size 0.4572)
		(drill 0.2032)
		(layers "F.Cu" "B.Cu")
		(net "GND")
	)
	(via
		(at 327.829418 -416.020504)
		(size 0.4572)
		(drill 0.254)
		(layers "F.Cu" "B.Cu")
		(net "GND")
	)
	(via
		(at 336.249518 -425.547282)
		(size 0.4572)
		(drill 0.2032)
		(layers "F.Cu" "B.Cu")
		(net "GND")
	)
	(via
		(at 380.224792 -287.045908)
		(size 0.4064)
		(drill 0.2032)
		(layers "F.Cu" "B.Cu")
		(net "GND")
	)
	(via
		(at 128.349756 -434.899562)
		(size 0.4572)
		(drill 0.2032)
		(layers "F.Cu" "B.Cu")
		(net "GND")
	)
	(via
		(at 102.855014 -258.830318)
		(size 0.4826)
		(drill 0.254)
		(layers "F.Cu" "B.Cu")
		(net "GND")
	)
	(via
		(at 7.262368 -410.962094)
		(size 0.508)
		(drill 0.254)
		(layers "F.Cu" "B.Cu")
		(net "GND")
	)
	(via
		(at 170.245024 -380.535688)
		(size 0.508)
		(drill 0.254)
		(layers "F.Cu" "B.Cu")
		(net "GND")
	)
	(via
		(at 277.192232 -243.234972)
		(size 0.4826)
		(drill 0.254)
		(layers "F.Cu" "B.Cu")
		(net "GND")
	)
	(via
		(at 118.354856 -241.244374)
		(size 0.4064)
		(drill 0.2032)
		(layers "F.Cu" "B.Cu")
		(net "GND")
	)
	(via
		(at 50.499772 -211.7852)
		(size 0.4826)
		(drill 0.254)
		(layers "F.Cu" "B.Cu")
		(net "GND")
	)
	(via
		(at 158.840678 -411.936184)
		(size 0.4572)
		(drill 0.254)
		(layers "F.Cu" "B.Cu")
		(net "GND")
	)
	(via
		(at 374.16232 -392.999722)
		(size 0.4064)
		(drill 0.2032)
		(layers "F.Cu" "B.Cu")
		(net "GND")
	)
	(via
		(at 361.420156 -406.822402)
		(size 0.508)
		(drill 0.254)
		(layers "F.Cu" "B.Cu")
		(net "GND")
	)
	(via
		(at 123.824746 -274.08632)
		(size 0.4064)
		(drill 0.2032)
		(layers "F.Cu" "B.Cu")
		(net "GND")
	)
	(via
		(at 333.069184 -378.07773)
		(size 0.508)
		(drill 0.254)
		(layers "F.Cu" "B.Cu")
		(net "GND")
	)
	(via
		(at 196.71919 -72.867266)
		(size 0.508)
		(drill 0.254)
		(layers "F.Cu" "B.Cu")
		(net "GND")
	)
	(via
		(at 134.349744 -430.299622)
		(size 0.4572)
		(drill 0.2032)
		(layers "F.Cu" "B.Cu")
		(net "GND")
	)
	(via
		(at 399.349722 -437.49976)
		(size 0.4572)
		(drill 0.2032)
		(layers "F.Cu" "B.Cu")
		(net "GND")
	)
	(via
		(at 418.599366 -436.564786)
		(size 0.508)
		(drill 0.254)
		(layers "F.Cu" "B.Cu")
		(net "GND")
	)
	(via
		(at 98.50247 -409.143708)
		(size 0.508)
		(drill 0.254)
		(layers "F.Cu" "B.Cu")
		(net "GND")
	)
	(via
		(at 114.008408 -71.962772)
		(size 0.508)
		(drill 0.254)
		(layers "F.Cu" "B.Cu")
		(net "GND")
	)
	(via
		(at 297.430444 -391.41146)
		(size 0.508)
		(drill 0.254)
		(layers "F.Cu" "B.Cu")
		(net "GND")
	)
	(via
		(at 414.788858 -163.201858)
		(size 0.49022)
		(drill 0.254)
		(layers "F.Cu" "B.Cu")
		(net "GND")
	)
	(via
		(at 421.898318 -170.212512)
		(size 0.6604)
		(drill 0.3302)
		(layers "F.Cu" "B.Cu")
		(net "GND")
	)
	(via
		(at 338.401152 -281.37612)
		(size 0.4064)
		(drill 0.2032)
		(layers "F.Cu" "B.Cu")
		(net "GND")
	)
	(via
		(at 355.791008 -278.946102)
		(size 0.4064)
		(drill 0.2032)
		(layers "F.Cu" "B.Cu")
		(net "GND")
	)
	(via
		(at 174.45355 -418.44722)
		(size 0.508)
		(drill 0.254)
		(layers "F.Cu" "B.Cu")
		(net "GND")
	)
	(via
		(at 455.306684 -18.908522)
		(size 0.6604)
		(drill 0.3302)
		(layers "F.Cu" "B.Cu")
		(net "GND")
	)
	(via
		(at 426.499782 -342.52408)
		(size 0.508)
		(drill 0.254)
		(layers "F.Cu" "B.Cu")
		(net "GND")
	)
	(via
		(at 100.971096 -243.674392)
		(size 0.4064)
		(drill 0.2032)
		(layers "F.Cu" "B.Cu")
		(net "GND")
	)
	(via
		(at 161.187384 -374.62333)
		(size 0.508)
		(drill 0.254)
		(layers "F.Cu" "B.Cu")
		(net "GND")
	)
	(via
		(at 184.733692 -294.66032)
		(size 0.4826)
		(drill 0.254)
		(layers "F.Cu" "B.Cu")
		(net "GND")
	)
	(via
		(at 202.099672 -75.895454)
		(size 0.508)
		(drill 0.254)
		(layers "F.Cu" "B.Cu")
		(net "GND")
	)
	(via
		(at 371.691154 -398.542002)
		(size 0.4064)
		(drill 0.2032)
		(layers "F.Cu" "B.Cu")
		(net "GND")
	)
	(via
		(at 100.031042 -229.094538)
		(size 0.4064)
		(drill 0.2032)
		(layers "F.Cu" "B.Cu")
		(net "GND")
	)
	(via
		(at 63.24981 -437.49976)
		(size 0.4572)
		(drill 0.2032)
		(layers "F.Cu" "B.Cu")
		(net "GND")
	)
	(via
		(at 62.77991 -172.833284)
		(size 0.508)
		(drill 0.254)
		(layers "F.Cu" "B.Cu")
		(net "GND")
	)
	(via
		(at 146.501866 -407.00452)
		(size 0.4064)
		(drill 0.2032)
		(layers "F.Cu" "B.Cu")
		(net "GND")
	)
	(via
		(at 327.291192 -250.154186)
		(size 0.4064)
		(drill 0.2032)
		(layers "F.Cu" "B.Cu")
		(net "GND")
	)
	(via
		(at 358.311196 -245.29415)
		(size 0.4064)
		(drill 0.2032)
		(layers "F.Cu" "B.Cu")
		(net "GND")
	)
	(via
		(at 302.494696 -400.15795)
		(size 0.4064)
		(drill 0.2032)
		(layers "F.Cu" "B.Cu")
		(net "GND")
	)
	(via
		(at 52.999386 -5.597398)
		(size 0.508)
		(drill 0.254)
		(layers "F.Cu" "B.Cu")
		(net "GND")
	)
	(via
		(at 388.34949 -428.851314)
		(size 0.4572)
		(drill 0.2032)
		(layers "F.Cu" "B.Cu")
		(net "GND")
	)
	(via
		(at 64.742314 -343.476834)
		(size 0.508)
		(drill 0.254)
		(layers "F.Cu" "B.Cu")
		(net "GND")
	)
	(via
		(at 320.171318 -412.212536)
		(size 0.4572)
		(drill 0.254)
		(layers "F.Cu" "B.Cu")
		(net "GND")
	)
	(via
		(at 329.633834 -414.752536)
		(size 0.4572)
		(drill 0.254)
		(layers "F.Cu" "B.Cu")
		(net "GND")
	)
	(via
		(at 325.24954 -438.499758)
		(size 0.4572)
		(drill 0.2032)
		(layers "F.Cu" "B.Cu")
		(net "GND")
	)
	(via
		(at 130.104642 -238.814356)
		(size 0.4064)
		(drill 0.2032)
		(layers "F.Cu" "B.Cu")
		(net "GND")
	)
	(via
		(at 180.900324 -231.335326)
		(size 0.4826)
		(drill 0.254)
		(layers "F.Cu" "B.Cu")
		(net "GND")
	)
	(via
		(at 280.635964 -309.535068)
		(size 0.4826)
		(drill 0.254)
		(layers "F.Cu" "B.Cu")
		(net "GND")
	)
	(via
		(at 370.82476 -291.905944)
		(size 0.4064)
		(drill 0.2032)
		(layers "F.Cu" "B.Cu")
		(net "GND")
	)
	(via
		(at 172.90034 -386.152136)
		(size 0.508)
		(drill 0.254)
		(layers "F.Cu" "B.Cu")
		(net "GND")
	)
	(via
		(at 425.10202 -390.619488)
		(size 0.508)
		(drill 0.254)
		(layers "F.Cu" "B.Cu")
		(net "GND")
	)
	(via
		(at 378.514864 -241.24412)
		(size 0.4064)
		(drill 0.2032)
		(layers "F.Cu" "B.Cu")
		(net "GND")
	)
	(via
		(at 446.644268 -308.685184)
		(size 0.4826)
		(drill 0.254)
		(layers "F.Cu" "B.Cu")
		(net "GND")
	)
	(via
		(at 353.911154 -280.566114)
		(size 0.4064)
		(drill 0.2032)
		(layers "F.Cu" "B.Cu")
		(net "GND")
	)
	(via
		(at 198.7042 -213.485222)
		(size 0.4826)
		(drill 0.254)
		(layers "F.Cu" "B.Cu")
		(net "GND")
	)
	(via
		(at 396.822422 -420.952168)
		(size 0.4064)
		(drill 0.2032)
		(layers "F.Cu" "B.Cu")
		(net "GND")
	)
	(via
		(at 307.368194 -272.984976)
		(size 0.4826)
		(drill 0.254)
		(layers "F.Cu" "B.Cu")
		(net "GND")
	)
	(via
		(at 151.455374 -405.098504)
		(size 0.4572)
		(drill 0.254)
		(layers "F.Cu" "B.Cu")
		(net "GND")
	)
	(via
		(at 396.379192 -5.597398)
		(size 0.508)
		(drill 0.254)
		(layers "F.Cu" "B.Cu")
		(net "GND")
	)
	(via
		(at 152.628346 -407.00452)
		(size 0.4064)
		(drill 0.2032)
		(layers "F.Cu" "B.Cu")
		(net "GND")
	)
	(via
		(at 70.659244 -412.570168)
		(size 0.4064)
		(drill 0.2032)
		(layers "F.Cu" "B.Cu")
		(net "GND")
	)
	(via
		(at 394.841222 -420.952168)
		(size 0.4064)
		(drill 0.2032)
		(layers "F.Cu" "B.Cu")
		(net "GND")
	)
	(via
		(at 81.54416 -393.902438)
		(size 0.4572)
		(drill 0.254)
		(layers "F.Cu" "B.Cu")
		(net "GND")
	)
	(via
		(at 168.527984 -241.535204)
		(size 0.4826)
		(drill 0.254)
		(layers "F.Cu" "B.Cu")
		(net "GND")
	)
	(via
		(at 96.27108 -251.774452)
		(size 0.4064)
		(drill 0.2032)
		(layers "F.Cu" "B.Cu")
		(net "GND")
	)
	(via
		(at 177.160682 -331.522324)
		(size 0.508)
		(drill 0.254)
		(layers "F.Cu" "B.Cu")
		(net "GND")
	)
	(via
		(at 264.43051 -276.810216)
		(size 0.4826)
		(drill 0.254)
		(layers "F.Cu" "B.Cu")
		(net "GND")
	)
	(via
		(at 20.59051 -201.16038)
		(size 0.4826)
		(drill 0.254)
		(layers "F.Cu" "B.Cu")
		(net "GND")
	)
	(via
		(at 358.61117 -278.946102)
		(size 0.4064)
		(drill 0.2032)
		(layers "F.Cu" "B.Cu")
		(net "GND")
	)
	(via
		(at 26.536396 -284.885384)
		(size 0.4826)
		(drill 0.254)
		(layers "F.Cu" "B.Cu")
		(net "GND")
	)
	(via
		(at 386.504942 -235.574078)
		(size 0.4064)
		(drill 0.2032)
		(layers "F.Cu" "B.Cu")
		(net "GND")
	)
	(via
		(at 383.514854 -274.896072)
		(size 0.4064)
		(drill 0.2032)
		(layers "F.Cu" "B.Cu")
		(net "GND")
	)
	(via
		(at 363.301026 -412.370016)
		(size 0.508)
		(drill 0.254)
		(layers "F.Cu" "B.Cu")
		(net "GND")
	)
	(via
		(at 361.594908 -249.34418)
		(size 0.4064)
		(drill 0.2032)
		(layers "F.Cu" "B.Cu")
		(net "GND")
	)
	(via
		(at 333.5655 -336.961988)
		(size 0.49022)
		(drill 0.254)
		(layers "F.Cu" "B.Cu")
		(net "GND")
	)
	(via
		(at 53.723032 -413.204152)
		(size 0.4572)
		(drill 0.254)
		(layers "F.Cu" "B.Cu")
		(net "GND")
	)
	(via
		(at 142.800832 -98.355658)
		(size 0.508)
		(drill 0.254)
		(layers "F.Cu" "B.Cu")
		(net "GND")
	)
	(via
		(at 105.908348 -415.067242)
		(size 0.508)
		(drill 0.254)
		(layers "F.Cu" "B.Cu")
		(net "GND")
	)
	(via
		(at 330.623164 -141.074902)
		(size 0.508)
		(drill 0.254)
		(layers "F.Cu" "B.Cu")
		(net "GND")
	)
	(via
		(at 410.51861 -412.212536)
		(size 0.4572)
		(drill 0.254)
		(layers "F.Cu" "B.Cu")
		(net "GND")
	)
	(via
		(at 126.644654 -264.366248)
		(size 0.4064)
		(drill 0.2032)
		(layers "F.Cu" "B.Cu")
		(net "GND")
	)
	(via
		(at 324.75297 -256.090166)
		(size 0.4064)
		(drill 0.2032)
		(layers "F.Cu" "B.Cu")
		(net "GND")
	)
	(via
		(at 418.88918 -379.22073)
		(size 0.508)
		(drill 0.254)
		(layers "F.Cu" "B.Cu")
		(net "GND")
	)
	(via
		(at 79.185516 -32.377888)
		(size 0.508)
		(drill 0.254)
		(layers "F.Cu" "B.Cu")
		(net "GND")
	)
	(via
		(at 25.152096 -264.485374)
		(size 0.4826)
		(drill 0.254)
		(layers "F.Cu" "B.Cu")
		(net "GND")
	)
	(via
		(at 27.867864 -274.685252)
		(size 0.4826)
		(drill 0.254)
		(layers "F.Cu" "B.Cu")
		(net "GND")
	)
	(via
		(at 311.254394 -417.778184)
		(size 0.4572)
		(drill 0.254)
		(layers "F.Cu" "B.Cu")
		(net "GND")
	)
	(via
		(at 419.912038 -266.185142)
		(size 0.4826)
		(drill 0.254)
		(layers "F.Cu" "B.Cu")
		(net "GND")
	)
	(via
		(at 124.84227 -164.626544)
		(size 0.49022)
		(drill 0.254)
		(layers "F.Cu" "B.Cu")
		(net "GND")
	)
	(via
		(at 107.550966 -237.194344)
		(size 0.4064)
		(drill 0.2032)
		(layers "F.Cu" "B.Cu")
		(net "GND")
	)
	(via
		(at 373.344694 -225.85426)
		(size 0.4064)
		(drill 0.2032)
		(layers "F.Cu" "B.Cu")
		(net "GND")
	)
	(via
		(at 331.521054 -247.724168)
		(size 0.4064)
		(drill 0.2032)
		(layers "F.Cu" "B.Cu")
		(net "GND")
	)
	(via
		(at 87.171022 -287.046162)
		(size 0.4064)
		(drill 0.2032)
		(layers "F.Cu" "B.Cu")
		(net "GND")
	)
	(via
		(at 91.401138 -294.336216)
		(size 0.4064)
		(drill 0.2032)
		(layers "F.Cu" "B.Cu")
		(net "GND")
	)
	(via
		(at 157.309058 -406.370536)
		(size 0.4572)
		(drill 0.254)
		(layers "F.Cu" "B.Cu")
		(net "GND")
	)
	(via
		(at 189.35065 -330.135484)
		(size 0.508)
		(drill 0.254)
		(layers "F.Cu" "B.Cu")
		(net "GND")
	)
	(via
		(at 164.427916 -273.835368)
		(size 0.4826)
		(drill 0.254)
		(layers "F.Cu" "B.Cu")
		(net "GND")
	)
	(via
		(at 135.279384 -441.227718)
		(size 0.508)
		(drill 0.254)
		(layers "F.Cu" "B.Cu")
		(net "GND")
	)
	(via
		(at 91.571064 -227.474526)
		(size 0.4064)
		(drill 0.2032)
		(layers "F.Cu" "B.Cu")
		(net "GND")
	)
	(via
		(at 54.796944 -6.091174)
		(size 0.508)
		(drill 0.254)
		(layers "F.Cu" "B.Cu")
		(net "GND")
	)
	(via
		(at 328.231246 -235.574078)
		(size 0.4064)
		(drill 0.2032)
		(layers "F.Cu" "B.Cu")
		(net "GND")
	)
	(via
		(at 124.90196 -340.88578)
		(size 0.6604)
		(drill 0.3302)
		(layers "F.Cu" "B.Cu")
		(net "GND")
	)
	(via
		(at 121.174764 -228.284532)
		(size 0.4064)
		(drill 0.2032)
		(layers "F.Cu" "B.Cu")
		(net "GND")
	)
	(via
		(at 356.261162 -273.27606)
		(size 0.4064)
		(drill 0.2032)
		(layers "F.Cu" "B.Cu")
		(net "GND")
	)
	(via
		(at 55.328058 -266.185396)
		(size 0.4826)
		(drill 0.254)
		(layers "F.Cu" "B.Cu")
		(net "GND")
	)
	(via
		(at 195.458334 -329.488546)
		(size 0.508)
		(drill 0.254)
		(layers "F.Cu" "B.Cu")
		(net "GND")
	)
	(via
		(at 284.38221 -344.77706)
		(size 0.49022)
		(drill 0.254)
		(layers "F.Cu" "B.Cu")
		(net "GND")
	)
	(via
		(at 376.93473 -261.935976)
		(size 0.4064)
		(drill 0.2032)
		(layers "F.Cu" "B.Cu")
		(net "GND")
	)
	(via
		(at 303.189386 -336.953606)
		(size 0.508)
		(drill 0.254)
		(layers "F.Cu" "B.Cu")
		(net "GND")
	)
	(via
		(at 299.82414 -271.284954)
		(size 0.4826)
		(drill 0.254)
		(layers "F.Cu" "B.Cu")
		(net "GND")
	)
	(via
		(at 137.851642 -10.048748)
		(size 0.508)
		(drill 0.254)
		(layers "F.Cu" "B.Cu")
		(net "GND")
	)
	(via
		(at 338.401152 -278.136096)
		(size 0.4064)
		(drill 0.2032)
		(layers "F.Cu" "B.Cu")
		(net "GND")
	)
	(via
		(at 184.732168 -112.66297)
		(size 0.4572)
		(drill 0.254)
		(layers "F.Cu" "B.Cu")
		(net "GND")
	)
	(via
		(at 432.562 -434.786786)
		(size 0.508)
		(drill 0.254)
		(layers "F.Cu" "B.Cu")
		(net "GND")
	)
	(via
		(at 40.23995 -225.385376)
		(size 0.4826)
		(drill 0.254)
		(layers "F.Cu" "B.Cu")
		(net "GND")
	)
	(via
		(at 292.280086 -301.034958)
		(size 0.4826)
		(drill 0.254)
		(layers "F.Cu" "B.Cu")
		(net "GND")
	)
	(via
		(at 89.99093 -280.566368)
		(size 0.4064)
		(drill 0.2032)
		(layers "F.Cu" "B.Cu")
		(net "GND")
	)
	(via
		(at 45.578776 -434.03774)
		(size 0.508)
		(drill 0.254)
		(layers "F.Cu" "B.Cu")
		(net "GND")
	)
	(via
		(at 295.724072 -214.335106)
		(size 0.4826)
		(drill 0.254)
		(layers "F.Cu" "B.Cu")
		(net "GND")
	)
	(via
		(at 138.349736 -437.49976)
		(size 0.4572)
		(drill 0.2032)
		(layers "F.Cu" "B.Cu")
		(net "GND")
	)
	(via
		(at 336.051144 -295.145968)
		(size 0.4064)
		(drill 0.2032)
		(layers "F.Cu" "B.Cu")
		(net "GND")
	)
	(via
		(at 182.231792 -295.9354)
		(size 0.4826)
		(drill 0.254)
		(layers "F.Cu" "B.Cu")
		(net "GND")
	)
	(via
		(at 326.651112 -288.66592)
		(size 0.4064)
		(drill 0.2032)
		(layers "F.Cu" "B.Cu")
		(net "GND")
	)
	(via
		(at 133.694678 -278.13635)
		(size 0.4064)
		(drill 0.2032)
		(layers "F.Cu" "B.Cu")
		(net "GND")
	)
	(via
		(at 376.493278 -140.456158)
		(size 0.508)
		(drill 0.254)
		(layers "F.Cu" "B.Cu")
		(net "GND")
	)
	(via
		(at 426.82922 -383.844292)
		(size 0.508)
		(drill 0.254)
		(layers "F.Cu" "B.Cu")
		(net "GND")
	)
	(via
		(at 134.607554 -407.638504)
		(size 0.4572)
		(drill 0.254)
		(layers "F.Cu" "B.Cu")
		(net "GND")
	)
	(via
		(at 103.621078 -266.796266)
		(size 0.4064)
		(drill 0.2032)
		(layers "F.Cu" "B.Cu")
		(net "GND")
	)
	(via
		(at 237.616238 -55.16499)
		(size 0.508)
		(drill 0.254)
		(layers "F.Cu" "B.Cu")
		(net "GND")
	)
	(via
		(at 354.551234 -222.614236)
		(size 0.4064)
		(drill 0.2032)
		(layers "F.Cu" "B.Cu")
		(net "GND")
	)
	(via
		(at 141.854682 -226.66452)
		(size 0.4064)
		(drill 0.2032)
		(layers "F.Cu" "B.Cu")
		(net "GND")
	)
	(via
		(at 328.061066 -281.37612)
		(size 0.4064)
		(drill 0.2032)
		(layers "F.Cu" "B.Cu")
		(net "GND")
	)
	(via
		(at 16.490442 -202.010264)
		(size 0.4826)
		(drill 0.254)
		(layers "F.Cu" "B.Cu")
		(net "GND")
	)
	(via
		(at 142.265654 -405.098504)
		(size 0.4572)
		(drill 0.254)
		(layers "F.Cu" "B.Cu")
		(net "GND")
	)
	(via
		(at 38.509194 -422.638982)
		(size 0.508)
		(drill 0.254)
		(layers "F.Cu" "B.Cu")
		(net "GND")
	)
	(via
		(at 118.9609 -417.919154)
		(size 0.508)
		(drill 0.254)
		(layers "F.Cu" "B.Cu")
		(net "GND")
	)
	(via
		(at 282.40101 -345.566238)
		(size 0.49022)
		(drill 0.254)
		(layers "F.Cu" "B.Cu")
		(net "GND")
	)
	(via
		(at 427.456092 -206.685134)
		(size 0.4826)
		(drill 0.254)
		(layers "F.Cu" "B.Cu")
		(net "GND")
	)
	(via
		(at 151.944832 -95.612458)
		(size 0.508)
		(drill 0.254)
		(layers "F.Cu" "B.Cu")
		(net "GND")
	)
	(via
		(at 349.851218 -240.434114)
		(size 0.4064)
		(drill 0.2032)
		(layers "F.Cu" "B.Cu")
		(net "GND")
	)
	(via
		(at 283.06141 -345.566238)
		(size 0.49022)
		(drill 0.254)
		(layers "F.Cu" "B.Cu")
		(net "GND")
	)
	(via
		(at 288.853372 -345.86164)
		(size 0.49022)
		(drill 0.254)
		(layers "F.Cu" "B.Cu")
		(net "GND")
	)
	(via
		(at 311.016396 -391.23493)
		(size 0.4064)
		(drill 0.2032)
		(layers "F.Cu" "B.Cu")
		(net "GND")
	)
	(via
		(at 280.635964 -272.135092)
		(size 0.4826)
		(drill 0.254)
		(layers "F.Cu" "B.Cu")
		(net "GND")
	)
	(via
		(at 368.944906 -291.905944)
		(size 0.4064)
		(drill 0.2032)
		(layers "F.Cu" "B.Cu")
		(net "GND")
	)
	(via
		(at 440.09564 -94.663768)
		(size 0.508)
		(drill 0.254)
		(layers "F.Cu" "B.Cu")
		(net "GND")
	)
	(via
		(at 348.271084 -267.606018)
		(size 0.4064)
		(drill 0.2032)
		(layers "F.Cu" "B.Cu")
		(net "GND")
	)
	(via
		(at 130.574796 -236.384338)
		(size 0.4064)
		(drill 0.2032)
		(layers "F.Cu" "B.Cu")
		(net "GND")
	)
	(via
		(at 346.091002 -237.19409)
		(size 0.4064)
		(drill 0.2032)
		(layers "F.Cu" "B.Cu")
		(net "GND")
	)
	(via
		(at 399.786094 -179.110386)
		(size 0.49022)
		(drill 0.254)
		(layers "F.Cu" "B.Cu")
		(net "GND")
	)
	(via
		(at 332.249526 -430.299622)
		(size 0.4572)
		(drill 0.2032)
		(layers "F.Cu" "B.Cu")
		(net "GND")
	)
	(via
		(at 399.79727 -414.752536)
		(size 0.4572)
		(drill 0.254)
		(layers "F.Cu" "B.Cu")
		(net "GND")
	)
	(via
		(at 103.151178 -282.18638)
		(size 0.4064)
		(drill 0.2032)
		(layers "F.Cu" "B.Cu")
		(net "GND")
	)
	(via
		(at 300.08703 -150.588472)
		(size 0.508)
		(drill 0.254)
		(layers "F.Cu" "B.Cu")
		(net "GND")
	)
	(via
		(at 80.291178 -255.014476)
		(size 0.4064)
		(drill 0.2032)
		(layers "F.Cu" "B.Cu")
		(net "GND")
	)
	(via
		(at 12.827 -79.0194)
		(size 0.508)
		(drill 0.254)
		(layers "F.Cu" "B.Cu")
		(net "GND")
	)
	(via
		(at 353.141026 -244.484144)
		(size 0.4064)
		(drill 0.2032)
		(layers "F.Cu" "B.Cu")
		(net "GND")
	)
	(via
		(at 412.955486 -10.16508)
		(size 0.508)
		(drill 0.254)
		(layers "F.Cu" "B.Cu")
		(net "GND")
	)
	(via
		(at 102.855014 -257.930396)
		(size 0.4826)
		(drill 0.254)
		(layers "F.Cu" "B.Cu")
		(net "GND")
	)
	(via
		(at 275.163026 -347.282262)
		(size 0.49022)
		(drill 0.254)
		(layers "F.Cu" "B.Cu")
		(net "GND")
	)
	(via
		(at 431.55616 -216.885012)
		(size 0.4826)
		(drill 0.254)
		(layers "F.Cu" "B.Cu")
		(net "GND")
	)
	(via
		(at 295.724072 -217.73515)
		(size 0.4826)
		(drill 0.254)
		(layers "F.Cu" "B.Cu")
		(net "GND")
	)
	(via
		(at 292.280086 -267.035026)
		(size 0.4826)
		(drill 0.254)
		(layers "F.Cu" "B.Cu")
		(net "GND")
	)
	(via
		(at 38.4556 -7.215124)
		(size 0.508)
		(drill 0.254)
		(layers "F.Cu" "B.Cu")
		(net "GND")
	)
	(via
		(at 218.651836 -70.311518)
		(size 0.508)
		(drill 0.254)
		(layers "F.Cu" "B.Cu")
		(net "GND")
	)
	(via
		(at 114.562382 -384.617722)
		(size 0.4064)
		(drill 0.2032)
		(layers "F.Cu" "B.Cu")
		(net "GND")
	)
	(via
		(at 25.152096 -208.38541)
		(size 0.4826)
		(drill 0.254)
		(layers "F.Cu" "B.Cu")
		(net "GND")
	)
	(via
		(at 442.5442 -266.185142)
		(size 0.4826)
		(drill 0.254)
		(layers "F.Cu" "B.Cu")
		(net "GND")
	)
	(via
		(at 206.248 -280.635202)
		(size 0.4826)
		(drill 0.254)
		(layers "F.Cu" "B.Cu")
		(net "GND")
	)
	(via
		(at 116.304822 -282.18638)
		(size 0.4064)
		(drill 0.2032)
		(layers "F.Cu" "B.Cu")
		(net "GND")
	)
	(via
		(at 98.734372 -352.396044)
		(size 0.508)
		(drill 0.254)
		(layers "F.Cu" "B.Cu")
		(net "GND")
	)
	(via
		(at 84.99094 -237.194344)
		(size 0.4064)
		(drill 0.2032)
		(layers "F.Cu" "B.Cu")
		(net "GND")
	)
	(via
		(at 309.449978 -419.046152)
		(size 0.4572)
		(drill 0.254)
		(layers "F.Cu" "B.Cu")
		(net "GND")
	)
	(via
		(at 439.100214 -248.335038)
		(size 0.4826)
		(drill 0.254)
		(layers "F.Cu" "B.Cu")
		(net "GND")
	)
	(via
		(at 307.368194 -213.484968)
		(size 0.4826)
		(drill 0.254)
		(layers "F.Cu" "B.Cu")
		(net "GND")
	)
	(via
		(at 21.70811 -224.535238)
		(size 0.4826)
		(drill 0.254)
		(layers "F.Cu" "B.Cu")
		(net "GND")
	)
	(via
		(at 47.784004 -267.885418)
		(size 0.4826)
		(drill 0.254)
		(layers "F.Cu" "B.Cu")
		(net "GND")
	)
	(via
		(at 126.644654 -267.606272)
		(size 0.4064)
		(drill 0.2032)
		(layers "F.Cu" "B.Cu")
		(net "GND")
	)
	(via
		(at 126.644654 -293.52621)
		(size 0.4064)
		(drill 0.2032)
		(layers "F.Cu" "B.Cu")
		(net "GND")
	)
	(via
		(at 413.215074 -165.70706)
		(size 0.49022)
		(drill 0.254)
		(layers "F.Cu" "B.Cu")
		(net "GND")
	)
	(via
		(at 427.915832 -330.46289)
		(size 0.508)
		(drill 0.254)
		(layers "F.Cu" "B.Cu")
		(net "GND")
	)
	(via
		(at 337.987132 -136.842246)
		(size 0.508)
		(drill 0.254)
		(layers "F.Cu" "B.Cu")
		(net "GND")
	)
	(via
		(at 292.280086 -246.635016)
		(size 0.4826)
		(drill 0.254)
		(layers "F.Cu" "B.Cu")
		(net "GND")
	)
	(via
		(at 284.736032 -306.985162)
		(size 0.4826)
		(drill 0.254)
		(layers "F.Cu" "B.Cu")
		(net "GND")
	)
	(via
		(at 326.651112 -274.086066)
		(size 0.4064)
		(drill 0.2032)
		(layers "F.Cu" "B.Cu")
		(net "GND")
	)
	(via
		(at 372.234714 -281.37612)
		(size 0.4064)
		(drill 0.2032)
		(layers "F.Cu" "B.Cu")
		(net "GND")
	)
	(via
		(at 448.795394 -45.69206)
		(size 0.508)
		(drill 0.254)
		(layers "F.Cu" "B.Cu")
		(net "GND")
	)
	(via
		(at 355.003608 -337.985608)
		(size 0.508)
		(drill 0.254)
		(layers "F.Cu" "B.Cu")
		(net "GND")
	)
	(via
		(at 198.7042 -244.935248)
		(size 0.4826)
		(drill 0.254)
		(layers "F.Cu" "B.Cu")
		(net "GND")
	)
	(via
		(at 41.508934 -362.628434)
		(size 0.508)
		(drill 0.254)
		(layers "F.Cu" "B.Cu")
		(net "GND")
	)
	(via
		(at 198.7042 -255.13538)
		(size 0.4826)
		(drill 0.254)
		(layers "F.Cu" "B.Cu")
		(net "GND")
	)
	(via
		(at 378.04471 -235.574078)
		(size 0.4064)
		(drill 0.2032)
		(layers "F.Cu" "B.Cu")
		(net "GND")
	)
	(via
		(at 338.401152 -289.475926)
		(size 0.4064)
		(drill 0.2032)
		(layers "F.Cu" "B.Cu")
		(net "GND")
	)
	(via
		(at 327.121012 -268.416024)
		(size 0.4064)
		(drill 0.2032)
		(layers "F.Cu" "B.Cu")
		(net "GND")
	)
	(via
		(at 135.274812 -247.724422)
		(size 0.4064)
		(drill 0.2032)
		(layers "F.Cu" "B.Cu")
		(net "GND")
	)
	(via
		(at 176.072038 -308.685438)
		(size 0.4826)
		(drill 0.254)
		(layers "F.Cu" "B.Cu")
		(net "GND")
	)
	(via
		(at 62.919864 -19.26971)
		(size 0.508)
		(drill 0.254)
		(layers "F.Cu" "B.Cu")
		(net "GND")
	)
	(via
		(at 105.671112 -237.194344)
		(size 0.4064)
		(drill 0.2032)
		(layers "F.Cu" "B.Cu")
		(net "GND")
	)
	(via
		(at 418.745416 -170.629072)
		(size 0.508)
		(drill 0.254)
		(layers "F.Cu" "B.Cu")
		(net "GND")
	)
	(via
		(at 50.499772 -221.135194)
		(size 0.4826)
		(drill 0.254)
		(layers "F.Cu" "B.Cu")
		(net "GND")
	)
	(via
		(at 108.321094 -284.616398)
		(size 0.4064)
		(drill 0.2032)
		(layers "F.Cu" "B.Cu")
		(net "GND")
	)
	(via
		(at 90.461084 -263.556242)
		(size 0.4064)
		(drill 0.2032)
		(layers "F.Cu" "B.Cu")
		(net "GND")
	)
	(via
		(at 308.191154 -419.046152)
		(size 0.4572)
		(drill 0.254)
		(layers "F.Cu" "B.Cu")
		(net "GND")
	)
	(via
		(at 73.941686 -178.775868)
		(size 0.49022)
		(drill 0.254)
		(layers "F.Cu" "B.Cu")
		(net "GND")
	)
	(via
		(at 366.594898 -278.136096)
		(size 0.4064)
		(drill 0.2032)
		(layers "F.Cu" "B.Cu")
		(net "GND")
	)
	(via
		(at 65.249806 -431.29962)
		(size 0.4572)
		(drill 0.2032)
		(layers "F.Cu" "B.Cu")
		(net "GND")
	)
	(via
		(at 32.601662 -418.239448)
		(size 0.508)
		(drill 0.254)
		(layers "F.Cu" "B.Cu")
		(net "GND")
	)
	(via
		(at 365.454692 -379.88113)
		(size 0.508)
		(drill 0.254)
		(layers "F.Cu" "B.Cu")
		(net "GND")
	)
	(via
		(at 437.59374 -364.57382)
		(size 0.508)
		(drill 0.254)
		(layers "F.Cu" "B.Cu")
		(net "GND")
	)
	(via
		(at 432.67376 -210.51012)
		(size 0.4826)
		(drill 0.254)
		(layers "F.Cu" "B.Cu")
		(net "GND")
	)
	(via
		(at 51.884072 -198.185278)
		(size 0.4826)
		(drill 0.254)
		(layers "F.Cu" "B.Cu")
		(net "GND")
	)
	(via
		(at 471.037666 -28.057094)
		(size 0.508)
		(drill 0.254)
		(layers "F.Cu" "B.Cu")
		(net "GND")
	)
	(via
		(at 195.988432 -312.935366)
		(size 0.4826)
		(drill 0.254)
		(layers "F.Cu" "B.Cu")
		(net "GND")
	)
	(via
		(at 268.530578 -219.860114)
		(size 0.4826)
		(drill 0.254)
		(layers "F.Cu" "B.Cu")
		(net "GND")
	)
	(via
		(at 72.122284 -388.77113)
		(size 0.508)
		(drill 0.254)
		(layers "F.Cu" "B.Cu")
		(net "GND")
	)
	(via
		(at 381.334772 -223.424242)
		(size 0.4064)
		(drill 0.2032)
		(layers "F.Cu" "B.Cu")
		(net "GND")
	)
	(via
		(at 306.659534 -421.586152)
		(size 0.4572)
		(drill 0.254)
		(layers "F.Cu" "B.Cu")
		(net "GND")
	)
	(via
		(at 430.665382 -342.49868)
		(size 0.508)
		(drill 0.254)
		(layers "F.Cu" "B.Cu")
		(net "GND")
	)
	(via
		(at 456.249278 -395.92377)
		(size 0.49022)
		(drill 0.254)
		(layers "F.Cu" "B.Cu")
		(net "GND")
	)
	(via
		(at 222.537782 -29.86532)
		(size 0.508)
		(drill 0.254)
		(layers "F.Cu" "B.Cu")
		(net "GND")
	)
	(via
		(at 402.587714 -412.212536)
		(size 0.4572)
		(drill 0.254)
		(layers "F.Cu" "B.Cu")
		(net "GND")
	)
	(via
		(at 69.249798 -426.54728)
		(size 0.4572)
		(drill 0.2032)
		(layers "F.Cu" "B.Cu")
		(net "GND")
	)
	(via
		(at 349.211138 -288.66592)
		(size 0.4064)
		(drill 0.2032)
		(layers "F.Cu" "B.Cu")
		(net "GND")
	)
	(via
		(at 191.26581 -350.17075)
		(size 0.49022)
		(drill 0.254)
		(layers "F.Cu" "B.Cu")
		(net "GND")
	)
	(via
		(at 79.821024 -238.00435)
		(size 0.4064)
		(drill 0.2032)
		(layers "F.Cu" "B.Cu")
		(net "GND")
	)
	(via
		(at 124.294646 -291.096192)
		(size 0.4064)
		(drill 0.2032)
		(layers "F.Cu" "B.Cu")
		(net "GND")
	)
	(via
		(at 385.094734 -231.524048)
		(size 0.4064)
		(drill 0.2032)
		(layers "F.Cu" "B.Cu")
		(net "GND")
	)
	(via
		(at 410.70911 -0.762254)
		(size 0.508)
		(drill 0.254)
		(layers "F.Cu" "B.Cu")
		(net "GND")
	)
	(via
		(at 407.862024 -16.9799)
		(size 0.508)
		(drill 0.254)
		(layers "F.Cu" "B.Cu")
		(net "GND")
	)
	(via
		(at 93.751146 -287.046162)
		(size 0.4064)
		(drill 0.2032)
		(layers "F.Cu" "B.Cu")
		(net "GND")
	)
	(via
		(at 130.098546 -410.030168)
		(size 0.4064)
		(drill 0.2032)
		(layers "F.Cu" "B.Cu")
		(net "GND")
	)
	(via
		(at 440.217814 -229.210108)
		(size 0.4826)
		(drill 0.254)
		(layers "F.Cu" "B.Cu")
		(net "GND")
	)
	(via
		(at 78.04277 -416.8521)
		(size 0.508)
		(drill 0.254)
		(layers "F.Cu" "B.Cu")
		(net "GND")
	)
	(via
		(at 373.961152 -380.54153)
		(size 0.508)
		(drill 0.254)
		(layers "F.Cu" "B.Cu")
		(net "GND")
	)
	(via
		(at 334.18272 -336.961988)
		(size 0.49022)
		(drill 0.254)
		(layers "F.Cu" "B.Cu")
		(net "GND")
	)
	(via
		(at 74.602086 -178.775868)
		(size 0.49022)
		(drill 0.254)
		(layers "F.Cu" "B.Cu")
		(net "GND")
	)
	(via
		(at 252.274324 -45.225462)
		(size 0.508)
		(drill 0.254)
		(layers "F.Cu" "B.Cu")
		(net "GND")
	)
	(via
		(at 60.106052 -150.763224)
		(size 0.508)
		(drill 0.254)
		(layers "F.Cu" "B.Cu")
		(net "GND")
	)
	(via
		(at 92.981018 -233.144314)
		(size 0.4064)
		(drill 0.2032)
		(layers "F.Cu" "B.Cu")
		(net "GND")
	)
	(via
		(at 67.596004 -412.570168)
		(size 0.4064)
		(drill 0.2032)
		(layers "F.Cu" "B.Cu")
		(net "GND")
	)
	(via
		(at 49.778666 -386.449062)
		(size 0.4064)
		(drill 0.2032)
		(layers "F.Cu" "B.Cu")
		(net "GND")
	)
	(via
		(at 27.976576 -405.849074)
		(size 0.508)
		(drill 0.254)
		(layers "F.Cu" "B.Cu")
		(net "GND")
	)
	(via
		(at 303.268126 -217.73515)
		(size 0.4826)
		(drill 0.254)
		(layers "F.Cu" "B.Cu")
		(net "GND")
	)
	(via
		(at 370.916454 -391.23493)
		(size 0.4064)
		(drill 0.2032)
		(layers "F.Cu" "B.Cu")
		(net "GND")
	)
	(via
		(at 383.514854 -270.036036)
		(size 0.4064)
		(drill 0.2032)
		(layers "F.Cu" "B.Cu")
		(net "GND")
	)
	(via
		(at 369.14709 -185.327798)
		(size 0.508)
		(drill 0.254)
		(layers "F.Cu" "B.Cu")
		(net "GND")
	)
	(via
		(at 83.111086 -253.394464)
		(size 0.4064)
		(drill 0.2032)
		(layers "F.Cu" "B.Cu")
		(net "GND")
	)
	(via
		(at 385.094734 -241.24412)
		(size 0.4064)
		(drill 0.2032)
		(layers "F.Cu" "B.Cu")
		(net "GND")
	)
	(via
		(at 168.527984 -224.535238)
		(size 0.4826)
		(drill 0.254)
		(layers "F.Cu" "B.Cu")
		(net "GND")
	)
	(via
		(at 451.46468 -6.224524)
		(size 0.508)
		(drill 0.254)
		(layers "F.Cu" "B.Cu")
		(net "GND")
	)
	(via
		(at 197.869556 -340.375748)
		(size 0.508)
		(drill 0.254)
		(layers "F.Cu" "B.Cu")
		(net "GND")
	)
	(via
		(at 454.188068 -244.934994)
		(size 0.4826)
		(drill 0.254)
		(layers "F.Cu" "B.Cu")
		(net "GND")
	)
	(via
		(at 92.643706 -183.825896)
		(size 0.49022)
		(drill 0.254)
		(layers "F.Cu" "B.Cu")
		(net "GND")
	)
	(via
		(at 347.97111 -243.674138)
		(size 0.4064)
		(drill 0.2032)
		(layers "F.Cu" "B.Cu")
		(net "GND")
	)
	(via
		(at 107.425744 -59.129422)
		(size 0.508)
		(drill 0.254)
		(layers "F.Cu" "B.Cu")
		(net "GND")
	)
	(via
		(at 29.553662 -418.239448)
		(size 0.508)
		(drill 0.254)
		(layers "F.Cu" "B.Cu")
		(net "GND")
	)
	(via
		(at 331.521054 -228.284278)
		(size 0.4064)
		(drill 0.2032)
		(layers "F.Cu" "B.Cu")
		(net "GND")
	)
	(via
		(at 173.12767 -192.218564)
		(size 0.4826)
		(drill 0.254)
		(layers "F.Cu" "B.Cu")
		(net "GND")
	)
	(via
		(at 221.49308 -104.9782)
		(size 0.508)
		(drill 0.254)
		(layers "F.Cu" "B.Cu")
		(net "GND")
	)
	(via
		(at 255.927098 -198.34352)
		(size 0.508)
		(drill 0.254)
		(layers "F.Cu" "B.Cu")
		(net "GND")
	)
	(via
		(at 91.740736 -405.098504)
		(size 0.4572)
		(drill 0.254)
		(layers "F.Cu" "B.Cu")
		(net "GND")
	)
	(via
		(at 143.73479 -252.584458)
		(size 0.4064)
		(drill 0.2032)
		(layers "F.Cu" "B.Cu")
		(net "GND")
	)
	(via
		(at 325.825104 -335.554066)
		(size 0.49022)
		(drill 0.254)
		(layers "F.Cu" "B.Cu")
		(net "GND")
	)
	(via
		(at 423.66692 -16.979138)
		(size 0.508)
		(drill 0.254)
		(layers "F.Cu" "B.Cu")
		(net "GND")
	)
	(via
		(at 392.225022 -418.412168)
		(size 0.4064)
		(drill 0.2032)
		(layers "F.Cu" "B.Cu")
		(net "GND")
	)
	(via
		(at 129.873756 -373.30253)
		(size 0.508)
		(drill 0.254)
		(layers "F.Cu" "B.Cu")
		(net "GND")
	)
	(via
		(at 86.230968 -269.226284)
		(size 0.4064)
		(drill 0.2032)
		(layers "F.Cu" "B.Cu")
		(net "GND")
	)
	(via
		(at 174.687738 -286.585406)
		(size 0.4826)
		(drill 0.254)
		(layers "F.Cu" "B.Cu")
		(net "GND")
	)
	(via
		(at 175.639984 -146.070574)
		(size 0.508)
		(drill 0.254)
		(layers "F.Cu" "B.Cu")
		(net "GND")
	)
	(via
		(at 329.941174 -279.756108)
		(size 0.4064)
		(drill 0.2032)
		(layers "F.Cu" "B.Cu")
		(net "GND")
	)
	(via
		(at 166.070534 -22.942804)
		(size 0.508)
		(drill 0.254)
		(layers "F.Cu" "B.Cu")
		(net "GND")
	)
	(via
		(at 56.454294 -372.15953)
		(size 0.508)
		(drill 0.254)
		(layers "F.Cu" "B.Cu")
		(net "GND")
	)
	(via
		(at 337.631024 -250.154186)
		(size 0.4064)
		(drill 0.2032)
		(layers "F.Cu" "B.Cu")
		(net "GND")
	)
	(via
		(at 446.644268 -289.985196)
		(size 0.4826)
		(drill 0.254)
		(layers "F.Cu" "B.Cu")
		(net "GND")
	)
	(via
		(at 111.447834 -261.323074)
		(size 0.4826)
		(drill 0.254)
		(layers "F.Cu" "B.Cu")
		(net "GND")
	)
	(via
		(at 82.001106 -265.176254)
		(size 0.4064)
		(drill 0.2032)
		(layers "F.Cu" "B.Cu")
		(net "GND")
	)
	(via
		(at 416.468052 -288.285174)
		(size 0.4826)
		(drill 0.254)
		(layers "F.Cu" "B.Cu")
		(net "GND")
	)
	(via
		(at 163.890198 -384.617722)
		(size 0.4064)
		(drill 0.2032)
		(layers "F.Cu" "B.Cu")
		(net "GND")
	)
	(via
		(at 317.791084 -398.542002)
		(size 0.4064)
		(drill 0.2032)
		(layers "F.Cu" "B.Cu")
		(net "GND")
	)
	(via
		(at 424.012106 -306.985162)
		(size 0.4826)
		(drill 0.254)
		(layers "F.Cu" "B.Cu")
		(net "GND")
	)
	(via
		(at 440.217814 -285.310072)
		(size 0.4826)
		(drill 0.254)
		(layers "F.Cu" "B.Cu")
		(net "GND")
	)
	(via
		(at 285.87827 -345.550998)
		(size 0.49022)
		(drill 0.254)
		(layers "F.Cu" "B.Cu")
		(net "GND")
	)
	(via
		(at 59.370214 -369.69573)
		(size 0.508)
		(drill 0.254)
		(layers "F.Cu" "B.Cu")
		(net "GND")
	)
	(via
		(at 131.06908 -26.12898)
		(size 0.508)
		(drill 0.254)
		(layers "F.Cu" "B.Cu")
		(net "GND")
	)
	(via
		(at 55.328058 -267.885418)
		(size 0.4826)
		(drill 0.254)
		(layers "F.Cu" "B.Cu")
		(net "GND")
	)
	(via
		(at 344.511122 -275.706078)
		(size 0.4064)
		(drill 0.2032)
		(layers "F.Cu" "B.Cu")
		(net "GND")
	)
	(via
		(at 346.091002 -232.334054)
		(size 0.4064)
		(drill 0.2032)
		(layers "F.Cu" "B.Cu")
		(net "GND")
	)
	(via
		(at 332.785466 -412.84652)
		(size 0.4064)
		(drill 0.2032)
		(layers "F.Cu" "B.Cu")
		(net "GND")
	)
	(via
		(at 108.597954 -256.3876)
		(size 0.4826)
		(drill 0.254)
		(layers "F.Cu" "B.Cu")
		(net "GND")
	)
	(via
		(at 426.204888 -6.598158)
		(size 0.508)
		(drill 0.254)
		(layers "F.Cu" "B.Cu")
		(net "GND")
	)
	(via
		(at 318.099186 -340.136988)
		(size 0.508)
		(drill 0.254)
		(layers "F.Cu" "B.Cu")
		(net "GND")
	)
	(via
		(at 120.822974 -411.936184)
		(size 0.4572)
		(drill 0.254)
		(layers "F.Cu" "B.Cu")
		(net "GND")
	)
	(via
		(at 382.1049 -267.606018)
		(size 0.4064)
		(drill 0.2032)
		(layers "F.Cu" "B.Cu")
		(net "GND")
	)
	(via
		(at 146.742912 -252.850396)
		(size 0.4064)
		(drill 0.2032)
		(layers "F.Cu" "B.Cu")
		(net "GND")
	)
	(via
		(at 416.468052 -291.684964)
		(size 0.4826)
		(drill 0.254)
		(layers "F.Cu" "B.Cu")
		(net "GND")
	)
	(via
		(at 204.8637 -221.135194)
		(size 0.4826)
		(drill 0.254)
		(layers "F.Cu" "B.Cu")
		(net "GND")
	)
	(via
		(at 18.127218 -19.771868)
		(size 0.508)
		(drill 0.254)
		(layers "F.Cu" "B.Cu")
		(net "GND")
	)
	(via
		(at 396.349474 -430.147222)
		(size 0.4572)
		(drill 0.2032)
		(layers "F.Cu" "B.Cu")
		(net "GND")
	)
	(via
		(at 355.321108 -336.690208)
		(size 0.508)
		(drill 0.254)
		(layers "F.Cu" "B.Cu")
		(net "GND")
	)
	(via
		(at 450.573394 -45.69206)
		(size 0.508)
		(drill 0.254)
		(layers "F.Cu" "B.Cu")
		(net "GND")
	)
	(via
		(at 46.501558 -344.781886)
		(size 0.49022)
		(drill 0.254)
		(layers "F.Cu" "B.Cu")
		(net "GND")
	)
	(via
		(at 240.205514 -317.942468)
		(size 0.508)
		(drill 0.254)
		(layers "F.Cu" "B.Cu")
		(net "GND")
	)
	(via
		(at 287.062418 -314.210192)
		(size 0.4826)
		(drill 0.254)
		(layers "F.Cu" "B.Cu")
		(net "GND")
	)
	(via
		(at 107.537504 -24.552656)
		(size 0.508)
		(drill 0.254)
		(layers "F.Cu" "B.Cu")
		(net "GND")
	)
	(via
		(at 113.954814 -276.516338)
		(size 0.4064)
		(drill 0.2032)
		(layers "F.Cu" "B.Cu")
		(net "GND")
	)
	(via
		(at 395.421104 -18.247106)
		(size 0.508)
		(drill 0.254)
		(layers "F.Cu" "B.Cu")
		(net "GND")
	)
	(via
		(at 190.76162 -423.820082)
		(size 0.508)
		(drill 0.254)
		(layers "F.Cu" "B.Cu")
		(net "GND")
	)
	(via
		(at 109.731048 -291.906198)
		(size 0.4064)
		(drill 0.2032)
		(layers "F.Cu" "B.Cu")
		(net "GND")
	)
	(via
		(at 88.281002 -225.044508)
		(size 0.4064)
		(drill 0.2032)
		(layers "F.Cu" "B.Cu")
		(net "GND")
	)
	(via
		(at 116.304822 -290.286186)
		(size 0.4064)
		(drill 0.2032)
		(layers "F.Cu" "B.Cu")
		(net "GND")
	)
	(via
		(at 376.93473 -284.616144)
		(size 0.4064)
		(drill 0.2032)
		(layers "F.Cu" "B.Cu")
		(net "GND")
	)
	(via
		(at 283.618432 -219.860114)
		(size 0.4826)
		(drill 0.254)
		(layers "F.Cu" "B.Cu")
		(net "GND")
	)
	(via
		(at 181.426358 -351.861374)
		(size 0.49022)
		(drill 0.254)
		(layers "F.Cu" "B.Cu")
		(net "GND")
	)
	(via
		(at 330.731876 -72.884792)
		(size 0.508)
		(drill 0.254)
		(layers "F.Cu" "B.Cu")
		(net "GND")
	)
	(via
		(at 380.536958 -207.521302)
		(size 0.508)
		(drill 0.254)
		(layers "F.Cu" "B.Cu")
		(net "GND")
	)
	(via
		(at 96.977708 -183.080406)
		(size 0.49022)
		(drill 0.254)
		(layers "F.Cu" "B.Cu")
		(net "GND")
	)
	(via
		(at 347.97111 -229.094284)
		(size 0.4064)
		(drill 0.2032)
		(layers "F.Cu" "B.Cu")
		(net "GND")
	)
	(via
		(at 450.088 -206.685134)
		(size 0.4826)
		(drill 0.254)
		(layers "F.Cu" "B.Cu")
		(net "GND")
	)
	(via
		(at 353.441 -273.27606)
		(size 0.4064)
		(drill 0.2032)
		(layers "F.Cu" "B.Cu")
		(net "GND")
	)
	(via
		(at 391.204704 -253.39421)
		(size 0.4064)
		(drill 0.2032)
		(layers "F.Cu" "B.Cu")
		(net "GND")
	)
	(via
		(at 324.366636 -376.75693)
		(size 0.508)
		(drill 0.254)
		(layers "F.Cu" "B.Cu")
		(net "GND")
	)
	(via
		(at 45.655738 -10.16508)
		(size 0.508)
		(drill 0.254)
		(layers "F.Cu" "B.Cu")
		(net "GND")
	)
	(via
		(at 386.098542 -415.38652)
		(size 0.4064)
		(drill 0.2032)
		(layers "F.Cu" "B.Cu")
		(net "GND")
	)
	(via
		(at 337.736942 -141.912086)
		(size 0.508)
		(drill 0.254)
		(layers "F.Cu" "B.Cu")
		(net "GND")
	)
	(via
		(at 367.064798 -269.22603)
		(size 0.4064)
		(drill 0.2032)
		(layers "F.Cu" "B.Cu")
		(net "GND")
	)
	(via
		(at 364.643416 -398.679924)
		(size 0.508)
		(drill 0.254)
		(layers "F.Cu" "B.Cu")
		(net "GND")
	)
	(via
		(at 97.040954 -278.13635)
		(size 0.4064)
		(drill 0.2032)
		(layers "F.Cu" "B.Cu")
		(net "GND")
	)
	(via
		(at 119.728234 -58.868056)
		(size 0.508)
		(drill 0.254)
		(layers "F.Cu" "B.Cu")
		(net "GND")
	)
	(via
		(at 362.364782 -291.905944)
		(size 0.4064)
		(drill 0.2032)
		(layers "F.Cu" "B.Cu")
		(net "GND")
	)
	(via
		(at 13.909548 -113.028222)
		(size 0.508)
		(drill 0.254)
		(layers "F.Cu" "B.Cu")
		(net "GND")
	)
	(via
		(at 385.094734 -252.584204)
		(size 0.4064)
		(drill 0.2032)
		(layers "F.Cu" "B.Cu")
		(net "GND")
	)
	(via
		(at 354.551234 -229.094284)
		(size 0.4064)
		(drill 0.2032)
		(layers "F.Cu" "B.Cu")
		(net "GND")
	)
	(via
		(at 303.849786 -335.673446)
		(size 0.508)
		(drill 0.254)
		(layers "F.Cu" "B.Cu")
		(net "GND")
	)
	(via
		(at 31.578296 -295.510458)
		(size 0.4826)
		(drill 0.254)
		(layers "F.Cu" "B.Cu")
		(net "GND")
	)
	(via
		(at 73.941686 -179.565046)
		(size 0.49022)
		(drill 0.254)
		(layers "F.Cu" "B.Cu")
		(net "GND")
	)
	(via
		(at 20.32381 -302.735234)
		(size 0.4826)
		(drill 0.254)
		(layers "F.Cu" "B.Cu")
		(net "GND")
	)
	(via
		(at 76.249784 -429.147224)
		(size 0.4572)
		(drill 0.2032)
		(layers "F.Cu" "B.Cu")
		(net "GND")
	)
	(via
		(at 25.152096 -267.885418)
		(size 0.4826)
		(drill 0.254)
		(layers "F.Cu" "B.Cu")
		(net "GND")
	)
	(via
		(at 338.249514 -431.29962)
		(size 0.4572)
		(drill 0.2032)
		(layers "F.Cu" "B.Cu")
		(net "GND")
	)
	(via
		(at 380.516384 -391.23493)
		(size 0.4064)
		(drill 0.2032)
		(layers "F.Cu" "B.Cu")
		(net "GND")
	)
	(via
		(at 452.803768 -277.235158)
		(size 0.4826)
		(drill 0.254)
		(layers "F.Cu" "B.Cu")
		(net "GND")
	)
	(via
		(at 188.444378 -294.235378)
		(size 0.4826)
		(drill 0.254)
		(layers "F.Cu" "B.Cu")
		(net "GND")
	)
	(via
		(at 229.87 -230.886)
		(size 0.508)
		(drill 0.254)
		(layers "F.Cu" "B.Cu")
		(net "GND")
	)
	(via
		(at 116.004848 -240.434368)
		(size 0.4064)
		(drill 0.2032)
		(layers "F.Cu" "B.Cu")
		(net "GND")
	)
	(via
		(at 123.994672 -226.66452)
		(size 0.4064)
		(drill 0.2032)
		(layers "F.Cu" "B.Cu")
		(net "GND")
	)
	(via
		(at 58.463434 -335.636616)
		(size 0.508)
		(drill 0.254)
		(layers "F.Cu" "B.Cu")
		(net "GND")
	)
	(via
		(at 89.298018 -334.564228)
		(size 0.49022)
		(drill 0.254)
		(layers "F.Cu" "B.Cu")
		(net "GND")
	)
	(via
		(at 344.511122 -267.606018)
		(size 0.4064)
		(drill 0.2032)
		(layers "F.Cu" "B.Cu")
		(net "GND")
	)
	(via
		(at 222.33763 -13.10513)
		(size 0.508)
		(drill 0.254)
		(layers "F.Cu" "B.Cu")
		(net "GND")
	)
	(via
		(at 139.974828 -226.66452)
		(size 0.4064)
		(drill 0.2032)
		(layers "F.Cu" "B.Cu")
		(net "GND")
	)
	(via
		(at 425.129706 -313.360054)
		(size 0.4826)
		(drill 0.254)
		(layers "F.Cu" "B.Cu")
		(net "GND")
	)
	(via
		(at 378.35459 -414.752536)
		(size 0.4572)
		(drill 0.254)
		(layers "F.Cu" "B.Cu")
		(net "GND")
	)
	(via
		(at 372.22811 -414.752536)
		(size 0.4572)
		(drill 0.254)
		(layers "F.Cu" "B.Cu")
		(net "GND")
	)
	(via
		(at 104.318054 -25.183592)
		(size 0.508)
		(drill 0.254)
		(layers "F.Cu" "B.Cu")
		(net "GND")
	)
	(via
		(at 246.35587 -292.041326)
		(size 0.508)
		(drill 0.254)
		(layers "F.Cu" "B.Cu")
		(net "GND")
	)
	(via
		(at 386.349494 -430.299622)
		(size 0.4572)
		(drill 0.2032)
		(layers "F.Cu" "B.Cu")
		(net "GND")
	)
	(via
		(at 131.98475 -253.394464)
		(size 0.4064)
		(drill 0.2032)
		(layers "F.Cu" "B.Cu")
		(net "GND")
	)
	(via
		(at 186.038236 -429.42764)
		(size 0.508)
		(drill 0.254)
		(layers "F.Cu" "B.Cu")
		(net "GND")
	)
	(via
		(at 437.707786 -166.024814)
		(size 0.508)
		(drill 0.254)
		(layers "F.Cu" "B.Cu")
		(net "GND")
	)
	(via
		(at 76.111862 -23.496524)
		(size 0.508)
		(drill 0.254)
		(layers "F.Cu" "B.Cu")
		(net "GND")
	)
	(via
		(at 117.414802 -249.344434)
		(size 0.4064)
		(drill 0.2032)
		(layers "F.Cu" "B.Cu")
		(net "GND")
	)
	(via
		(at 100.031042 -251.774452)
		(size 0.4064)
		(drill 0.2032)
		(layers "F.Cu" "B.Cu")
		(net "GND")
	)
	(via
		(at 290.895786 -277.235158)
		(size 0.4826)
		(drill 0.254)
		(layers "F.Cu" "B.Cu")
		(net "GND")
	)
	(via
		(at 353.908106 -264.368026)
		(size 0.4064)
		(drill 0.2032)
		(layers "F.Cu" "B.Cu")
		(net "GND")
	)
	(via
		(at 20.32381 -295.9354)
		(size 0.4826)
		(drill 0.254)
		(layers "F.Cu" "B.Cu")
		(net "GND")
	)
	(via
		(at 396.379192 -4.32943)
		(size 0.508)
		(drill 0.254)
		(layers "F.Cu" "B.Cu")
		(net "GND")
	)
	(via
		(at 317.469266 -420.952168)
		(size 0.4064)
		(drill 0.2032)
		(layers "F.Cu" "B.Cu")
		(net "GND")
	)
	(via
		(at 378.514864 -250.964192)
		(size 0.4064)
		(drill 0.2032)
		(layers "F.Cu" "B.Cu")
		(net "GND")
	)
	(via
		(at 121.474738 -271.656302)
		(size 0.4064)
		(drill 0.2032)
		(layers "F.Cu" "B.Cu")
		(net "GND")
	)
	(via
		(at 118.363238 -42.2656)
		(size 0.508)
		(drill 0.254)
		(layers "F.Cu" "B.Cu")
		(net "GND")
	)
	(via
		(at 346.091002 -246.914162)
		(size 0.4064)
		(drill 0.2032)
		(layers "F.Cu" "B.Cu")
		(net "GND")
	)
	(via
		(at 232.88752 -289.298126)
		(size 0.508)
		(drill 0.254)
		(layers "F.Cu" "B.Cu")
		(net "GND")
	)
	(via
		(at 356.261162 -271.656048)
		(size 0.4064)
		(drill 0.2032)
		(layers "F.Cu" "B.Cu")
		(net "GND")
	)
	(via
		(at 325.052944 -277.870158)
		(size 0.4064)
		(drill 0.2032)
		(layers "F.Cu" "B.Cu")
		(net "GND")
	)
	(via
		(at 404.7871 -381.68453)
		(size 0.508)
		(drill 0.254)
		(layers "F.Cu" "B.Cu")
		(net "GND")
	)
	(via
		(at 81.292192 -405.098504)
		(size 0.4572)
		(drill 0.254)
		(layers "F.Cu" "B.Cu")
		(net "GND")
	)
	(via
		(at 165.146228 -388.328662)
		(size 0.4064)
		(drill 0.2032)
		(layers "F.Cu" "B.Cu")
		(net "GND")
	)
	(via
		(at 61.249814 -427.699678)
		(size 0.4572)
		(drill 0.2032)
		(layers "F.Cu" "B.Cu")
		(net "GND")
	)
	(via
		(at 336.22107 -252.584204)
		(size 0.4064)
		(drill 0.2032)
		(layers "F.Cu" "B.Cu")
		(net "GND")
	)
	(via
		(at 184.733692 -201.16038)
		(size 0.4826)
		(drill 0.254)
		(layers "F.Cu" "B.Cu")
		(net "GND")
	)
	(via
		(at 20.32381 -227.935282)
		(size 0.4826)
		(drill 0.254)
		(layers "F.Cu" "B.Cu")
		(net "GND")
	)
	(via
		(at 266.93241 -296.78503)
		(size 0.4826)
		(drill 0.254)
		(layers "F.Cu" "B.Cu")
		(net "GND")
	)
	(via
		(at 336.930746 -412.84652)
		(size 0.4064)
		(drill 0.2032)
		(layers "F.Cu" "B.Cu")
		(net "GND")
	)
	(via
		(at 361.838494 -331.613764)
		(size 0.508)
		(drill 0.254)
		(layers "F.Cu" "B.Cu")
		(net "GND")
	)
	(via
		(at 381.804926 -230.714042)
		(size 0.4064)
		(drill 0.2032)
		(layers "F.Cu" "B.Cu")
		(net "GND")
	)
	(via
		(at 403.848062 -12.37488)
		(size 0.508)
		(drill 0.254)
		(layers "F.Cu" "B.Cu")
		(net "GND")
	)
	(via
		(at 119.822722 -77.450442)
		(size 0.508)
		(drill 0.254)
		(layers "F.Cu" "B.Cu")
		(net "GND")
	)
	(via
		(at 347.50121 -234.764072)
		(size 0.4064)
		(drill 0.2032)
		(layers "F.Cu" "B.Cu")
		(net "GND")
	)
	(via
		(at 350.151192 -293.525956)
		(size 0.4064)
		(drill 0.2032)
		(layers "F.Cu" "B.Cu")
		(net "GND")
	)
	(via
		(at 115.834668 -289.47618)
		(size 0.4064)
		(drill 0.2032)
		(layers "F.Cu" "B.Cu")
		(net "GND")
	)
	(via
		(at 333.5655 -335.539588)
		(size 0.49022)
		(drill 0.254)
		(layers "F.Cu" "B.Cu")
		(net "GND")
	)
	(via
		(at 160.644332 -382.85293)
		(size 0.4064)
		(drill 0.2032)
		(layers "F.Cu" "B.Cu")
		(net "GND")
	)
	(via
		(at 431.55616 -308.685184)
		(size 0.4826)
		(drill 0.254)
		(layers "F.Cu" "B.Cu")
		(net "GND")
	)
	(via
		(at 467.5378 -334.315054)
		(size 0.508)
		(drill 0.254)
		(layers "F.Cu" "B.Cu")
		(net "GND")
	)
	(via
		(at 417.03498 -19.13636)
		(size 0.508)
		(drill 0.254)
		(layers "F.Cu" "B.Cu")
		(net "GND")
	)
	(via
		(at 339.15604 -62.634876)
		(size 0.508)
		(drill 0.254)
		(layers "F.Cu" "B.Cu")
		(net "GND")
	)
	(via
		(at 310.267096 -382.34493)
		(size 0.508)
		(drill 0.254)
		(layers "F.Cu" "B.Cu")
		(net "GND")
	)
	(via
		(at 46.373034 -19.771868)
		(size 0.508)
		(drill 0.254)
		(layers "F.Cu" "B.Cu")
		(net "GND")
	)
	(via
		(at 64.268096 -154.323288)
		(size 0.6604)
		(drill 0.3302)
		(layers "F.Cu" "B.Cu")
		(net "GND")
	)
	(via
		(at 380.224792 -269.22603)
		(size 0.4064)
		(drill 0.2032)
		(layers "F.Cu" "B.Cu")
		(net "GND")
	)
	(via
		(at 350.151192 -267.606018)
		(size 0.4064)
		(drill 0.2032)
		(layers "F.Cu" "B.Cu")
		(net "GND")
	)
	(via
		(at 141.854682 -241.244374)
		(size 0.4064)
		(drill 0.2032)
		(layers "F.Cu" "B.Cu")
		(net "GND")
	)
	(via
		(at 329.941174 -284.616144)
		(size 0.4064)
		(drill 0.2032)
		(layers "F.Cu" "B.Cu")
		(net "GND")
	)
	(via
		(at 467.5378 -183.439054)
		(size 0.508)
		(drill 0.254)
		(layers "F.Cu" "B.Cu")
		(net "GND")
	)
	(via
		(at 114.935 -415.939986)
		(size 0.508)
		(drill 0.254)
		(layers "F.Cu" "B.Cu")
		(net "GND")
	)
	(via
		(at 414.524698 -4.963414)
		(size 0.508)
		(drill 0.254)
		(layers "F.Cu" "B.Cu")
		(net "GND")
	)
	(via
		(at 31.578296 -314.210446)
		(size 0.4826)
		(drill 0.254)
		(layers "F.Cu" "B.Cu")
		(net "GND")
	)
	(via
		(at 57.047384 -441.227718)
		(size 0.508)
		(drill 0.254)
		(layers "F.Cu" "B.Cu")
		(net "GND")
	)
	(via
		(at 430.17186 -286.585152)
		(size 0.4826)
		(drill 0.254)
		(layers "F.Cu" "B.Cu")
		(net "GND")
	)
	(via
		(at 87.418672 -405.098504)
		(size 0.4572)
		(drill 0.254)
		(layers "F.Cu" "B.Cu")
		(net "GND")
	)
	(via
		(at 350.151192 -270.846042)
		(size 0.4064)
		(drill 0.2032)
		(layers "F.Cu" "B.Cu")
		(net "GND")
	)
	(via
		(at 355.106732 -411.399482)
		(size 0.508)
		(drill 0.254)
		(layers "F.Cu" "B.Cu")
		(net "GND")
	)
	(via
		(at 280.635964 -318.885062)
		(size 0.4826)
		(drill 0.254)
		(layers "F.Cu" "B.Cu")
		(net "GND")
	)
	(via
		(at 124.294646 -271.656302)
		(size 0.4064)
		(drill 0.2032)
		(layers "F.Cu" "B.Cu")
		(net "GND")
	)
	(via
		(at 87.145876 -407.638504)
		(size 0.4572)
		(drill 0.254)
		(layers "F.Cu" "B.Cu")
		(net "GND")
	)
	(via
		(at 431.55616 -288.285174)
		(size 0.4826)
		(drill 0.254)
		(layers "F.Cu" "B.Cu")
		(net "GND")
	)
	(via
		(at 332.249526 -431.451258)
		(size 0.4572)
		(drill 0.2032)
		(layers "F.Cu" "B.Cu")
		(net "GND")
	)
	(via
		(at 105.200958 -246.10441)
		(size 0.4064)
		(drill 0.2032)
		(layers "F.Cu" "B.Cu")
		(net "GND")
	)
	(via
		(at 198.7042 -268.735302)
		(size 0.4826)
		(drill 0.254)
		(layers "F.Cu" "B.Cu")
		(net "GND")
	)
	(via
		(at 332.461108 -249.34418)
		(size 0.4064)
		(drill 0.2032)
		(layers "F.Cu" "B.Cu")
		(net "GND")
	)
	(via
		(at 316.507876 -71.265542)
		(size 0.508)
		(drill 0.254)
		(layers "F.Cu" "B.Cu")
		(net "GND")
	)
	(via
		(at 20.32381 -209.235294)
		(size 0.4826)
		(drill 0.254)
		(layers "F.Cu" "B.Cu")
		(net "GND")
	)
	(via
		(at 340.355174 -420.318184)
		(size 0.4572)
		(drill 0.254)
		(layers "F.Cu" "B.Cu")
		(net "GND")
	)
	(via
		(at 63.189358 -344.781886)
		(size 0.49022)
		(drill 0.254)
		(layers "F.Cu" "B.Cu")
		(net "GND")
	)
	(via
		(at 382.588262 -412.84652)
		(size 0.4064)
		(drill 0.2032)
		(layers "F.Cu" "B.Cu")
		(net "GND")
	)
	(via
		(at 130.574796 -231.524302)
		(size 0.4064)
		(drill 0.2032)
		(layers "F.Cu" "B.Cu")
		(net "GND")
	)
	(via
		(at 335.022444 -400.15795)
		(size 0.4064)
		(drill 0.2032)
		(layers "F.Cu" "B.Cu")
		(net "GND")
	)
	(via
		(at 121.644664 -243.674392)
		(size 0.4064)
		(drill 0.2032)
		(layers "F.Cu" "B.Cu")
		(net "GND")
	)
	(via
		(at 50.766472 -238.560356)
		(size 0.4826)
		(drill 0.254)
		(layers "F.Cu" "B.Cu")
		(net "GND")
	)
	(via
		(at 328.53122 -291.905944)
		(size 0.4064)
		(drill 0.2032)
		(layers "F.Cu" "B.Cu")
		(net "GND")
	)
	(via
		(at 108.33227 -177.605944)
		(size 0.49022)
		(drill 0.254)
		(layers "F.Cu" "B.Cu")
		(net "GND")
	)
	(via
		(at 107.550966 -246.914416)
		(size 0.4064)
		(drill 0.2032)
		(layers "F.Cu" "B.Cu")
		(net "GND")
	)
	(via
		(at 62.11951 -171.512484)
		(size 0.508)
		(drill 0.254)
		(layers "F.Cu" "B.Cu")
		(net "GND")
	)
	(via
		(at 65.975992 -411.936184)
		(size 0.4572)
		(drill 0.254)
		(layers "F.Cu" "B.Cu")
		(net "GND")
	)
	(via
		(at 368.004852 -277.32609)
		(size 0.4064)
		(drill 0.2032)
		(layers "F.Cu" "B.Cu")
		(net "GND")
	)
	(via
		(at 183.616092 -278.935434)
		(size 0.4826)
		(drill 0.254)
		(layers "F.Cu" "B.Cu")
		(net "GND")
	)
	(via
		(at 341.22106 -271.656048)
		(size 0.4064)
		(drill 0.2032)
		(layers "F.Cu" "B.Cu")
		(net "GND")
	)
	(via
		(at 121.474738 -276.516338)
		(size 0.4064)
		(drill 0.2032)
		(layers "F.Cu" "B.Cu")
		(net "GND")
	)
	(via
		(at 184.733692 -229.210362)
		(size 0.4826)
		(drill 0.254)
		(layers "F.Cu" "B.Cu")
		(net "GND")
	)
	(via
		(at 80.291178 -229.094538)
		(size 0.4064)
		(drill 0.2032)
		(layers "F.Cu" "B.Cu")
		(net "GND")
	)
	(via
		(at 72.06107 -154.55519)
		(size 0.508)
		(drill 0.254)
		(layers "F.Cu" "B.Cu")
		(net "GND")
	)
	(via
		(at 284.736032 -318.035178)
		(size 0.4826)
		(drill 0.254)
		(layers "F.Cu" "B.Cu")
		(net "GND")
	)
	(via
		(at 69.241162 -175.99914)
		(size 0.508)
		(drill 0.254)
		(layers "F.Cu" "B.Cu")
		(net "GND")
	)
	(via
		(at 295.724072 -242.385088)
		(size 0.4826)
		(drill 0.254)
		(layers "F.Cu" "B.Cu")
		(net "GND")
	)
	(via
		(at 141.854682 -228.284532)
		(size 0.4064)
		(drill 0.2032)
		(layers "F.Cu" "B.Cu")
		(net "GND")
	)
	(via
		(at 109.261148 -284.616398)
		(size 0.4064)
		(drill 0.2032)
		(layers "F.Cu" "B.Cu")
		(net "GND")
	)
	(via
		(at 298.66844 -192.21831)
		(size 0.4826)
		(drill 0.254)
		(layers "F.Cu" "B.Cu")
		(net "GND")
	)
	(via
		(at 159.14624 -388.328662)
		(size 0.4064)
		(drill 0.2032)
		(layers "F.Cu" "B.Cu")
		(net "GND")
	)
	(via
		(at 44.340018 -306.985416)
		(size 0.4826)
		(drill 0.254)
		(layers "F.Cu" "B.Cu")
		(net "GND")
	)
	(via
		(at 8.590788 -370.60505)
		(size 0.508)
		(drill 0.254)
		(layers "F.Cu" "B.Cu")
		(net "GND")
	)
	(via
		(at 363.474762 -231.524048)
		(size 0.4064)
		(drill 0.2032)
		(layers "F.Cu" "B.Cu")
		(net "GND")
	)
	(via
		(at 153.444194 -382.85293)
		(size 0.4064)
		(drill 0.2032)
		(layers "F.Cu" "B.Cu")
		(net "GND")
	)
	(via
		(at 393.384786 -270.846042)
		(size 0.4064)
		(drill 0.2032)
		(layers "F.Cu" "B.Cu")
		(net "GND")
	)
	(via
		(at 384.48107 -417.778184)
		(size 0.4572)
		(drill 0.254)
		(layers "F.Cu" "B.Cu")
		(net "GND")
	)
	(via
		(at 369.895628 -145.536158)
		(size 0.508)
		(drill 0.254)
		(layers "F.Cu" "B.Cu")
		(net "GND")
	)
	(via
		(at 391.504678 -267.606018)
		(size 0.4064)
		(drill 0.2032)
		(layers "F.Cu" "B.Cu")
		(net "GND")
	)
	(via
		(at 93.751146 -267.606272)
		(size 0.4064)
		(drill 0.2032)
		(layers "F.Cu" "B.Cu")
		(net "GND")
	)
	(via
		(at 338.401152 -282.996132)
		(size 0.4064)
		(drill 0.2032)
		(layers "F.Cu" "B.Cu")
		(net "GND")
	)
	(via
		(at 76.643738 -32.377126)
		(size 0.508)
		(drill 0.254)
		(layers "F.Cu" "B.Cu")
		(net "GND")
	)
	(via
		(at 90.481912 -405.098504)
		(size 0.4572)
		(drill 0.254)
		(layers "F.Cu" "B.Cu")
		(net "GND")
	)
	(via
		(at 115.869466 -407.00452)
		(size 0.4064)
		(drill 0.2032)
		(layers "F.Cu" "B.Cu")
		(net "GND")
	)
	(via
		(at 80.120998 -279.756362)
		(size 0.4064)
		(drill 0.2032)
		(layers "F.Cu" "B.Cu")
		(net "GND")
	)
	(via
		(at 132.670804 -151.389334)
		(size 0.508)
		(drill 0.254)
		(layers "F.Cu" "B.Cu")
		(net "GND")
	)
	(via
		(at 381.719074 -183.14289)
		(size 0.49022)
		(drill 0.254)
		(layers "F.Cu" "B.Cu")
		(net "GND")
	)
	(via
		(at 145.444718 -290.286186)
		(size 0.4064)
		(drill 0.2032)
		(layers "F.Cu" "B.Cu")
		(net "GND")
	)
	(via
		(at 372.704868 -283.806138)
		(size 0.4064)
		(drill 0.2032)
		(layers "F.Cu" "B.Cu")
		(net "GND")
	)
	(via
		(at 140.444728 -251.774452)
		(size 0.4064)
		(drill 0.2032)
		(layers "F.Cu" "B.Cu")
		(net "GND")
	)
	(via
		(at 235.219748 -238.436658)
		(size 0.4826)
		(drill 0.254)
		(layers "F.Cu" "B.Cu")
		(net "GND")
	)
	(via
		(at 192.573402 -387.660642)
		(size 0.508)
		(drill 0.254)
		(layers "F.Cu" "B.Cu")
		(net "GND")
	)
	(via
		(at 305.16576 -169.707052)
		(size 0.508)
		(drill 0.254)
		(layers "F.Cu" "B.Cu")
		(net "GND")
	)
	(via
		(at 32.695896 -227.085398)
		(size 0.4826)
		(drill 0.254)
		(layers "F.Cu" "B.Cu")
		(net "GND")
	)
	(via
		(at 287.062418 -276.810216)
		(size 0.4826)
		(drill 0.254)
		(layers "F.Cu" "B.Cu")
		(net "GND")
	)
	(via
		(at 105.031032 -277.326344)
		(size 0.4064)
		(drill 0.2032)
		(layers "F.Cu" "B.Cu")
		(net "GND")
	)
	(via
		(at 130.87477 -276.516338)
		(size 0.4064)
		(drill 0.2032)
		(layers "F.Cu" "B.Cu")
		(net "GND")
	)
	(via
		(at 368.855752 -376.75693)
		(size 0.508)
		(drill 0.254)
		(layers "F.Cu" "B.Cu")
		(net "GND")
	)
	(via
		(at 334.64119 -270.036036)
		(size 0.4064)
		(drill 0.2032)
		(layers "F.Cu" "B.Cu")
		(net "GND")
	)
	(via
		(at 105.52049 -180.107082)
		(size 0.49022)
		(drill 0.254)
		(layers "F.Cu" "B.Cu")
		(net "GND")
	)
	(via
		(at 93.19006 -384.617722)
		(size 0.4064)
		(drill 0.2032)
		(layers "F.Cu" "B.Cu")
		(net "GND")
	)
	(via
		(at 455.07783 -49.122838)
		(size 0.508)
		(drill 0.254)
		(layers "F.Cu" "B.Cu")
		(net "GND")
	)
	(via
		(at 106.611166 -232.334308)
		(size 0.4064)
		(drill 0.2032)
		(layers "F.Cu" "B.Cu")
		(net "GND")
	)
	(via
		(at 79.821024 -252.584458)
		(size 0.4064)
		(drill 0.2032)
		(layers "F.Cu" "B.Cu")
		(net "GND")
	)
	(via
		(at 451.873366 -378.05487)
		(size 0.508)
		(drill 0.254)
		(layers "F.Cu" "B.Cu")
		(net "GND")
	)
	(via
		(at 381.558546 -12.542266)
		(size 0.508)
		(drill 0.254)
		(layers "F.Cu" "B.Cu")
		(net "GND")
	)
	(via
		(at 104.090978 -277.326344)
		(size 0.4064)
		(drill 0.2032)
		(layers "F.Cu" "B.Cu")
		(net "GND")
	)
	(via
		(at 330.804266 -420.952168)
		(size 0.4064)
		(drill 0.2032)
		(layers "F.Cu" "B.Cu")
		(net "GND")
	)
	(via
		(at 145.349722 -439.651394)
		(size 0.4572)
		(drill 0.2032)
		(layers "F.Cu" "B.Cu")
		(net "GND")
	)
	(via
		(at 142.467584 -370.83873)
		(size 0.508)
		(drill 0.254)
		(layers "F.Cu" "B.Cu")
		(net "GND")
	)
	(via
		(at 78.983078 -309.658004)
		(size 0.4064)
		(drill 0.2032)
		(layers "F.Cu" "B.Cu")
		(net "GND")
	)
	(via
		(at 187.060078 -289.135312)
		(size 0.4826)
		(drill 0.254)
		(layers "F.Cu" "B.Cu")
		(net "GND")
	)
	(via
		(at 40.770302 -381.3302)
		(size 0.508)
		(drill 0.254)
		(layers "F.Cu" "B.Cu")
		(net "GND")
	)
	(via
		(at 124.091192 -390.160002)
		(size 0.4064)
		(drill 0.2032)
		(layers "F.Cu" "B.Cu")
		(net "GND")
	)
	(via
		(at 201.041 -142.24)
		(size 0.508)
		(drill 0.254)
		(layers "F.Cu" "B.Cu")
		(net "GND")
	)
	(via
		(at 329.249532 -427.699678)
		(size 0.4572)
		(drill 0.2032)
		(layers "F.Cu" "B.Cu")
		(net "GND")
	)
	(via
		(at 395.857222 -397.15313)
		(size 0.508)
		(drill 0.254)
		(layers "F.Cu" "B.Cu")
		(net "GND")
	)
	(via
		(at 320.475356 -380.54153)
		(size 0.508)
		(drill 0.254)
		(layers "F.Cu" "B.Cu")
		(net "GND")
	)
	(via
		(at 56.712358 -212.635338)
		(size 0.4826)
		(drill 0.254)
		(layers "F.Cu" "B.Cu")
		(net "GND")
	)
	(via
		(at 290.895786 -221.13494)
		(size 0.4826)
		(drill 0.254)
		(layers "F.Cu" "B.Cu")
		(net "GND")
	)
	(via
		(at 138.349736 -436.347362)
		(size 0.4572)
		(drill 0.2032)
		(layers "F.Cu" "B.Cu")
		(net "GND")
	)
	(via
		(at 83.580986 -225.044508)
		(size 0.4064)
		(drill 0.2032)
		(layers "F.Cu" "B.Cu")
		(net "GND")
	)
	(via
		(at 292.280086 -253.435104)
		(size 0.4826)
		(drill 0.254)
		(layers "F.Cu" "B.Cu")
		(net "GND")
	)
	(via
		(at 142.154656 -266.796266)
		(size 0.4064)
		(drill 0.2032)
		(layers "F.Cu" "B.Cu")
		(net "GND")
	)
	(via
		(at 340.24951 -435.0512)
		(size 0.4572)
		(drill 0.2032)
		(layers "F.Cu" "B.Cu")
		(net "GND")
	)
	(via
		(at 389.389874 -183.893968)
		(size 0.49022)
		(drill 0.254)
		(layers "F.Cu" "B.Cu")
		(net "GND")
	)
	(via
		(at 373.316246 -183.14289)
		(size 0.49022)
		(drill 0.254)
		(layers "F.Cu" "B.Cu")
		(net "GND")
	)
	(via
		(at 80.046322 -388.328662)
		(size 0.4064)
		(drill 0.2032)
		(layers "F.Cu" "B.Cu")
		(net "GND")
	)
	(via
		(at 133.864858 -235.574332)
		(size 0.4064)
		(drill 0.2032)
		(layers "F.Cu" "B.Cu")
		(net "GND")
	)
	(via
		(at 82.001106 -276.516338)
		(size 0.4064)
		(drill 0.2032)
		(layers "F.Cu" "B.Cu")
		(net "GND")
	)
	(via
		(at 98.621088 -225.044508)
		(size 0.4064)
		(drill 0.2032)
		(layers "F.Cu" "B.Cu")
		(net "GND")
	)
	(via
		(at 59.428126 -241.535204)
		(size 0.4826)
		(drill 0.254)
		(layers "F.Cu" "B.Cu")
		(net "GND")
	)
	(via
		(at 348.271084 -288.66592)
		(size 0.4064)
		(drill 0.2032)
		(layers "F.Cu" "B.Cu")
		(net "GND")
	)
	(via
		(at 347.031056 -242.054126)
		(size 0.4064)
		(drill 0.2032)
		(layers "F.Cu" "B.Cu")
		(net "GND")
	)
	(via
		(at 393.94511 -0.762254)
		(size 0.508)
		(drill 0.254)
		(layers "F.Cu" "B.Cu")
		(net "GND")
	)
	(via
		(at 77.632814 -387.04774)
		(size 0.4064)
		(drill 0.2032)
		(layers "F.Cu" "B.Cu")
		(net "GND")
	)
	(via
		(at 265.54811 -216.035128)
		(size 0.4826)
		(drill 0.254)
		(layers "F.Cu" "B.Cu")
		(net "GND")
	)
	(via
		(at 174.687738 -202.435206)
		(size 0.4826)
		(drill 0.254)
		(layers "F.Cu" "B.Cu")
		(net "GND")
	)
	(via
		(at 295.724072 -262.785098)
		(size 0.4826)
		(drill 0.254)
		(layers "F.Cu" "B.Cu")
		(net "GND")
	)
	(via
		(at 253.753874 -134.257796)
		(size 0.508)
		(drill 0.254)
		(layers "F.Cu" "B.Cu")
		(net "GND")
	)
	(via
		(at 246.0752 -287.692084)
		(size 0.508)
		(drill 0.254)
		(layers "F.Cu" "B.Cu")
		(net "GND")
	)
	(via
		(at 123.613418 -409.396184)
		(size 0.4572)
		(drill 0.254)
		(layers "F.Cu" "B.Cu")
		(net "GND")
	)
	(via
		(at 312.216292 -400.212814)
		(size 0.4064)
		(drill 0.2032)
		(layers "F.Cu" "B.Cu")
		(net "GND")
	)
	(via
		(at 355.491034 -240.434114)
		(size 0.4064)
		(drill 0.2032)
		(layers "F.Cu" "B.Cu")
		(net "GND")
	)
	(via
		(at 204.8637 -199.8853)
		(size 0.4826)
		(drill 0.254)
		(layers "F.Cu" "B.Cu")
		(net "GND")
	)
	(via
		(at 338.101178 -228.284278)
		(size 0.4064)
		(drill 0.2032)
		(layers "F.Cu" "B.Cu")
		(net "GND")
	)
	(via
		(at 138.864848 -291.906198)
		(size 0.4064)
		(drill 0.2032)
		(layers "F.Cu" "B.Cu")
		(net "GND")
	)
	(via
		(at 414.510474 -164.166804)
		(size 0.49022)
		(drill 0.254)
		(layers "F.Cu" "B.Cu")
		(net "GND")
	)
	(via
		(at 123.5964 -51.0032)
		(size 0.508)
		(drill 0.254)
		(layers "F.Cu" "B.Cu")
		(net "GND")
	)
	(via
		(at 235.928408 -323.746114)
		(size 0.508)
		(drill 0.254)
		(layers "F.Cu" "B.Cu")
		(net "GND")
	)
	(via
		(at 25.892506 -422.332912)
		(size 0.508)
		(drill 0.254)
		(layers "F.Cu" "B.Cu")
		(net "GND")
	)
	(via
		(at 305.644296 -382.34493)
		(size 0.508)
		(drill 0.254)
		(layers "F.Cu" "B.Cu")
		(net "GND")
	)
	(via
		(at 188.444378 -306.135278)
		(size 0.4826)
		(drill 0.254)
		(layers "F.Cu" "B.Cu")
		(net "GND")
	)
	(via
		(at 202.036934 -338.139278)
		(size 0.508)
		(drill 0.254)
		(layers "F.Cu" "B.Cu")
		(net "GND")
	)
	(via
		(at 355.491034 -250.154186)
		(size 0.4064)
		(drill 0.2032)
		(layers "F.Cu" "B.Cu")
		(net "GND")
	)
	(via
		(at 166.602156 -423.860976)
		(size 0.508)
		(drill 0.254)
		(layers "F.Cu" "B.Cu")
		(net "GND")
	)
	(via
		(at 223.068134 -48.78197)
		(size 0.508)
		(drill 0.254)
		(layers "F.Cu" "B.Cu")
		(net "GND")
	)
	(via
		(at 363.774736 -279.756108)
		(size 0.4064)
		(drill 0.2032)
		(layers "F.Cu" "B.Cu")
		(net "GND")
	)
	(via
		(at 102.850442 -256.632964)
		(size 0.4064)
		(drill 0.2032)
		(layers "F.Cu" "B.Cu")
		(net "GND")
	)
	(via
		(at 451.4723 -275.535136)
		(size 0.4826)
		(drill 0.254)
		(layers "F.Cu" "B.Cu")
		(net "GND")
	)
	(via
		(at 308.191154 -414.752536)
		(size 0.4572)
		(drill 0.254)
		(layers "F.Cu" "B.Cu")
		(net "GND")
	)
	(via
		(at 347.031056 -235.574078)
		(size 0.4064)
		(drill 0.2032)
		(layers "F.Cu" "B.Cu")
		(net "GND")
	)
	(via
		(at 140.385546 -74.125582)
		(size 0.508)
		(drill 0.254)
		(layers "F.Cu" "B.Cu")
		(net "GND")
	)
	(via
		(at 388.21487 -273.27606)
		(size 0.4064)
		(drill 0.2032)
		(layers "F.Cu" "B.Cu")
		(net "GND")
	)
	(via
		(at 123.286266 -167.131746)
		(size 0.49022)
		(drill 0.254)
		(layers "F.Cu" "B.Cu")
		(net "GND")
	)
	(via
		(at 297.108372 -231.335072)
		(size 0.4826)
		(drill 0.254)
		(layers "F.Cu" "B.Cu")
		(net "GND")
	)
	(via
		(at 132.284724 -270.846296)
		(size 0.4064)
		(drill 0.2032)
		(layers "F.Cu" "B.Cu")
		(net "GND")
	)
	(via
		(at 328.231246 -238.814102)
		(size 0.4064)
		(drill 0.2032)
		(layers "F.Cu" "B.Cu")
		(net "GND")
	)
	(via
		(at 50.991516 -153.231596)
		(size 0.508)
		(drill 0.254)
		(layers "F.Cu" "B.Cu")
		(net "GND")
	)
	(via
		(at 325.038974 -412.212536)
		(size 0.4572)
		(drill 0.254)
		(layers "F.Cu" "B.Cu")
		(net "GND")
	)
	(via
		(at 430.669192 -349.200978)
		(size 0.49022)
		(drill 0.254)
		(layers "F.Cu" "B.Cu")
		(net "GND")
	)
	(via
		(at 177.532284 -119.042688)
		(size 0.4572)
		(drill 0.254)
		(layers "F.Cu" "B.Cu")
		(net "GND")
	)
	(via
		(at 385.316476 -400.212814)
		(size 0.4064)
		(drill 0.2032)
		(layers "F.Cu" "B.Cu")
		(net "GND")
	)
	(via
		(at 99.47529 -40.917114)
		(size 0.508)
		(drill 0.254)
		(layers "F.Cu" "B.Cu")
		(net "GND")
	)
	(via
		(at 58.84799 -19.771106)
		(size 0.508)
		(drill 0.254)
		(layers "F.Cu" "B.Cu")
		(net "GND")
	)
	(via
		(at 100.971096 -229.094538)
		(size 0.4064)
		(drill 0.2032)
		(layers "F.Cu" "B.Cu")
		(net "GND")
	)
	(via
		(at 152.714198 -411.936184)
		(size 0.4572)
		(drill 0.254)
		(layers "F.Cu" "B.Cu")
		(net "GND")
	)
	(via
		(at 123.554236 -372.15953)
		(size 0.508)
		(drill 0.254)
		(layers "F.Cu" "B.Cu")
		(net "GND")
	)
	(via
		(at 338.401152 -295.955974)
		(size 0.4064)
		(drill 0.2032)
		(layers "F.Cu" "B.Cu")
		(net "GND")
	)
	(via
		(at 378.442982 -412.84652)
		(size 0.4064)
		(drill 0.2032)
		(layers "F.Cu" "B.Cu")
		(net "GND")
	)
	(via
		(at 50.917094 -17.61236)
		(size 0.508)
		(drill 0.254)
		(layers "F.Cu" "B.Cu")
		(net "GND")
	)
	(via
		(at 436.384446 -238.13516)
		(size 0.4826)
		(drill 0.254)
		(layers "F.Cu" "B.Cu")
		(net "GND")
	)
	(via
		(at 116.747036 -372.15953)
		(size 0.508)
		(drill 0.254)
		(layers "F.Cu" "B.Cu")
		(net "GND")
	)
	(via
		(at 294.606472 -295.510204)
		(size 0.4826)
		(drill 0.254)
		(layers "F.Cu" "B.Cu")
		(net "GND")
	)
	(via
		(at 126.34468 -225.854514)
		(size 0.4064)
		(drill 0.2032)
		(layers "F.Cu" "B.Cu")
		(net "GND")
	)
	(via
		(at 399.6817 -379.22073)
		(size 0.508)
		(drill 0.254)
		(layers "F.Cu" "B.Cu")
		(net "GND")
	)
	(via
		(at 91.571064 -233.95432)
		(size 0.4064)
		(drill 0.2032)
		(layers "F.Cu" "B.Cu")
		(net "GND")
	)
	(via
		(at 61.233558 -344.781886)
		(size 0.49022)
		(drill 0.254)
		(layers "F.Cu" "B.Cu")
		(net "GND")
	)
	(via
		(at 180.633624 -239.410494)
		(size 0.4826)
		(drill 0.254)
		(layers "F.Cu" "B.Cu")
		(net "GND")
	)
	(via
		(at 385.864862 -295.145968)
		(size 0.4064)
		(drill 0.2032)
		(layers "F.Cu" "B.Cu")
		(net "GND")
	)
	(via
		(at 203.265532 -286.160464)
		(size 0.4826)
		(drill 0.254)
		(layers "F.Cu" "B.Cu")
		(net "GND")
	)
	(via
		(at 38.016688 -169.037)
		(size 0.508)
		(drill 0.254)
		(layers "F.Cu" "B.Cu")
		(net "GND")
	)
	(via
		(at 382.1049 -285.42615)
		(size 0.4064)
		(drill 0.2032)
		(layers "F.Cu" "B.Cu")
		(net "GND")
	)
	(via
		(at 99.090988 -232.334308)
		(size 0.4064)
		(drill 0.2032)
		(layers "F.Cu" "B.Cu")
		(net "GND")
	)
	(via
		(at 135.866378 -407.638504)
		(size 0.4572)
		(drill 0.254)
		(layers "F.Cu" "B.Cu")
		(net "GND")
	)
	(via
		(at 242.593114 -317.942468)
		(size 0.508)
		(drill 0.254)
		(layers "F.Cu" "B.Cu")
		(net "GND")
	)
	(via
		(at 373.644922 -291.905944)
		(size 0.4064)
		(drill 0.2032)
		(layers "F.Cu" "B.Cu")
		(net "GND")
	)
	(via
		(at 160.70453 -350.077278)
		(size 0.508)
		(drill 0.254)
		(layers "F.Cu" "B.Cu")
		(net "GND")
	)
	(via
		(at 337.24596 -396.710662)
		(size 0.4064)
		(drill 0.2032)
		(layers "F.Cu" "B.Cu")
		(net "GND")
	)
	(via
		(at 134.634732 -268.416278)
		(size 0.4064)
		(drill 0.2032)
		(layers "F.Cu" "B.Cu")
		(net "GND")
	)
	(via
		(at 176.072038 -250.035314)
		(size 0.4826)
		(drill 0.254)
		(layers "F.Cu" "B.Cu")
		(net "GND")
	)
	(via
		(at 325.052944 -281.110182)
		(size 0.4064)
		(drill 0.2032)
		(layers "F.Cu" "B.Cu")
		(net "GND")
	)
	(via
		(at 451.4723 -238.13516)
		(size 0.4826)
		(drill 0.254)
		(layers "F.Cu" "B.Cu")
		(net "GND")
	)
	(via
		(at 43.224958 -344.781886)
		(size 0.49022)
		(drill 0.254)
		(layers "F.Cu" "B.Cu")
		(net "GND")
	)
	(via
		(at 412.367984 -279.785064)
		(size 0.4826)
		(drill 0.254)
		(layers "F.Cu" "B.Cu")
		(net "GND")
	)
	(via
		(at 235.0008 -283.830522)
		(size 0.508)
		(drill 0.254)
		(layers "F.Cu" "B.Cu")
		(net "GND")
	)
	(via
		(at 382.1049 -282.186126)
		(size 0.4064)
		(drill 0.2032)
		(layers "F.Cu" "B.Cu")
		(net "GND")
	)
	(via
		(at 223.829118 -275.502878)
		(size 0.508)
		(drill 0.254)
		(layers "F.Cu" "B.Cu")
		(net "GND")
	)
	(via
		(at 108.02112 -244.484398)
		(size 0.4064)
		(drill 0.2032)
		(layers "F.Cu" "B.Cu")
		(net "GND")
	)
	(via
		(at 129.82956 -27.896566)
		(size 0.508)
		(drill 0.254)
		(layers "F.Cu" "B.Cu")
		(net "GND")
	)
	(via
		(at 118.354856 -233.144314)
		(size 0.4064)
		(drill 0.2032)
		(layers "F.Cu" "B.Cu")
		(net "GND")
	)
	(via
		(at 443.6618 -230.060246)
		(size 0.4826)
		(drill 0.254)
		(layers "F.Cu" "B.Cu")
		(net "GND")
	)
	(via
		(at 275.807932 -199.885046)
		(size 0.4826)
		(drill 0.254)
		(layers "F.Cu" "B.Cu")
		(net "GND")
	)
	(via
		(at 156.081984 -372.15953)
		(size 0.508)
		(drill 0.254)
		(layers "F.Cu" "B.Cu")
		(net "GND")
	)
	(via
		(at 391.674858 -252.584204)
		(size 0.4064)
		(drill 0.2032)
		(layers "F.Cu" "B.Cu")
		(net "GND")
	)
	(via
		(at 27.867864 -239.835436)
		(size 0.4826)
		(drill 0.254)
		(layers "F.Cu" "B.Cu")
		(net "GND")
	)
	(via
		(at 32.695896 -217.735404)
		(size 0.4826)
		(drill 0.254)
		(layers "F.Cu" "B.Cu")
		(net "GND")
	)
	(via
		(at 435.000146 -262.785098)
		(size 0.4826)
		(drill 0.254)
		(layers "F.Cu" "B.Cu")
		(net "GND")
	)
	(via
		(at 327.13803 -398.719802)
		(size 0.508)
		(drill 0.254)
		(layers "F.Cu" "B.Cu")
		(net "GND")
	)
	(via
		(at 113.65484 -250.964446)
		(size 0.4064)
		(drill 0.2032)
		(layers "F.Cu" "B.Cu")
		(net "GND")
	)
	(via
		(at 189.35065 -331.456284)
		(size 0.508)
		(drill 0.254)
		(layers "F.Cu" "B.Cu")
		(net "GND")
	)
	(via
		(at 54.858158 -344.781886)
		(size 0.49022)
		(drill 0.254)
		(layers "F.Cu" "B.Cu")
		(net "GND")
	)
	(via
		(at 126.34468 -253.394464)
		(size 0.4064)
		(drill 0.2032)
		(layers "F.Cu" "B.Cu")
		(net "GND")
	)
	(via
		(at 154.380184 -374.62333)
		(size 0.508)
		(drill 0.254)
		(layers "F.Cu" "B.Cu")
		(net "GND")
	)
	(via
		(at 114.894614 -276.516338)
		(size 0.4064)
		(drill 0.2032)
		(layers "F.Cu" "B.Cu")
		(net "GND")
	)
	(via
		(at 372.234714 -270.036036)
		(size 0.4064)
		(drill 0.2032)
		(layers "F.Cu" "B.Cu")
		(net "GND")
	)
	(via
		(at 17.067784 -394.428726)
		(size 0.508)
		(drill 0.254)
		(layers "F.Cu" "B.Cu")
		(net "GND")
	)
	(via
		(at 98.621088 -223.424496)
		(size 0.4064)
		(drill 0.2032)
		(layers "F.Cu" "B.Cu")
		(net "GND")
	)
	(via
		(at 32.695896 -225.385376)
		(size 0.4826)
		(drill 0.254)
		(layers "F.Cu" "B.Cu")
		(net "GND")
	)
	(via
		(at 128.955292 -73.41489)
		(size 0.508)
		(drill 0.254)
		(layers "F.Cu" "B.Cu")
		(net "GND")
	)
	(via
		(at 58.406284 -412.570168)
		(size 0.4064)
		(drill 0.2032)
		(layers "F.Cu" "B.Cu")
		(net "GND")
	)
	(via
		(at 369.414806 -286.236156)
		(size 0.4064)
		(drill 0.2032)
		(layers "F.Cu" "B.Cu")
		(net "GND")
	)
	(via
		(at 338.125308 -307.717952)
		(size 0.508)
		(drill 0.254)
		(layers "F.Cu" "B.Cu")
		(net "GND")
	)
	(via
		(at 391.204704 -240.434114)
		(size 0.4064)
		(drill 0.2032)
		(layers "F.Cu" "B.Cu")
		(net "GND")
	)
	(via
		(at 291.749226 -347.282262)
		(size 0.49022)
		(drill 0.254)
		(layers "F.Cu" "B.Cu")
		(net "GND")
	)
	(via
		(at 394.457174 -56.089804)
		(size 0.508)
		(drill 0.254)
		(layers "F.Cu" "B.Cu")
		(net "GND")
	)
	(via
		(at 369.584732 -235.574078)
		(size 0.4064)
		(drill 0.2032)
		(layers "F.Cu" "B.Cu")
		(net "GND")
	)
	(via
		(at 303.268126 -283.185108)
		(size 0.4826)
		(drill 0.254)
		(layers "F.Cu" "B.Cu")
		(net "GND")
	)
	(via
		(at 80.753712 -0.762254)
		(size 0.508)
		(drill 0.254)
		(layers "F.Cu" "B.Cu")
		(net "GND")
	)
	(via
		(at 108.02112 -226.66452)
		(size 0.4064)
		(drill 0.2032)
		(layers "F.Cu" "B.Cu")
		(net "GND")
	)
	(via
		(at 328.53122 -288.66592)
		(size 0.4064)
		(drill 0.2032)
		(layers "F.Cu" "B.Cu")
		(net "GND")
	)
	(via
		(at 88.281002 -241.244374)
		(size 0.4064)
		(drill 0.2032)
		(layers "F.Cu" "B.Cu")
		(net "GND")
	)
	(via
		(at 320.532506 -420.952168)
		(size 0.4064)
		(drill 0.2032)
		(layers "F.Cu" "B.Cu")
		(net "GND")
	)
	(via
		(at 181.618382 -349.356172)
		(size 0.49022)
		(drill 0.254)
		(layers "F.Cu" "B.Cu")
		(net "GND")
	)
	(via
		(at 140.274802 -292.716204)
		(size 0.4064)
		(drill 0.2032)
		(layers "F.Cu" "B.Cu")
		(net "GND")
	)
	(via
		(at 87.418672 -411.936184)
		(size 0.4572)
		(drill 0.254)
		(layers "F.Cu" "B.Cu")
		(net "GND")
	)
	(via
		(at 446.644268 -222.834962)
		(size 0.4826)
		(drill 0.254)
		(layers "F.Cu" "B.Cu")
		(net "GND")
	)
	(via
		(at 138.564874 -229.094538)
		(size 0.4064)
		(drill 0.2032)
		(layers "F.Cu" "B.Cu")
		(net "GND")
	)
	(via
		(at 344.981022 -289.475926)
		(size 0.4064)
		(drill 0.2032)
		(layers "F.Cu" "B.Cu")
		(net "GND")
	)
	(via
		(at 400.178016 -344.450162)
		(size 0.508)
		(drill 0.254)
		(layers "F.Cu" "B.Cu")
		(net "GND")
	)
	(via
		(at 356.014274 -169.895012)
		(size 0.49022)
		(drill 0.254)
		(layers "F.Cu" "B.Cu")
		(net "GND")
	)
	(via
		(at 95.1611 -273.276314)
		(size 0.4064)
		(drill 0.2032)
		(layers "F.Cu" "B.Cu")
		(net "GND")
	)
	(via
		(at 407.349706 -435.0512)
		(size 0.4572)
		(drill 0.2032)
		(layers "F.Cu" "B.Cu")
		(net "GND")
	)
	(via
		(at 423.04208 -439.934858)
		(size 0.508)
		(drill 0.254)
		(layers "F.Cu" "B.Cu")
		(net "GND")
	)
	(via
		(at 460.248762 -407.38425)
		(size 0.508)
		(drill 0.254)
		(layers "F.Cu" "B.Cu")
		(net "GND")
	)
	(via
		(at 133.394704 -228.284532)
		(size 0.4064)
		(drill 0.2032)
		(layers "F.Cu" "B.Cu")
		(net "GND")
	)
	(via
		(at 122.354594 -407.638504)
		(size 0.4572)
		(drill 0.254)
		(layers "F.Cu" "B.Cu")
		(net "GND")
	)
	(via
		(at 401.86864 -377.41733)
		(size 0.508)
		(drill 0.254)
		(layers "F.Cu" "B.Cu")
		(net "GND")
	)
	(via
		(at 127.114808 -271.656302)
		(size 0.4064)
		(drill 0.2032)
		(layers "F.Cu" "B.Cu")
		(net "GND")
	)
	(via
		(at 124.90196 -330.72578)
		(size 0.6604)
		(drill 0.3302)
		(layers "F.Cu" "B.Cu")
		(net "GND")
	)
	(via
		(at 103.791004 -235.574332)
		(size 0.4064)
		(drill 0.2032)
		(layers "F.Cu" "B.Cu")
		(net "GND")
	)
	(via
		(at 143.349726 -435.0512)
		(size 0.4572)
		(drill 0.2032)
		(layers "F.Cu" "B.Cu")
		(net "GND")
	)
	(via
		(at 91.571064 -232.334308)
		(size 0.4064)
		(drill 0.2032)
		(layers "F.Cu" "B.Cu")
		(net "GND")
	)
	(via
		(at 413.485584 -295.510204)
		(size 0.4826)
		(drill 0.254)
		(layers "F.Cu" "B.Cu")
		(net "GND")
	)
	(via
		(at 199.8218 -313.360308)
		(size 0.4826)
		(drill 0.254)
		(layers "F.Cu" "B.Cu")
		(net "GND")
	)
	(via
		(at 350.744028 -402.259038)
		(size 0.4572)
		(drill 0.254)
		(layers "F.Cu" "B.Cu")
		(net "GND")
	)
	(via
		(at 86.871048 -224.234502)
		(size 0.4064)
		(drill 0.2032)
		(layers "F.Cu" "B.Cu")
		(net "GND")
	)
	(via
		(at 372.404894 -243.674138)
		(size 0.4064)
		(drill 0.2032)
		(layers "F.Cu" "B.Cu")
		(net "GND")
	)
	(via
		(at 57.668414 -372.15953)
		(size 0.508)
		(drill 0.254)
		(layers "F.Cu" "B.Cu")
		(net "GND")
	)
	(via
		(at 86.871048 -238.814356)
		(size 0.4064)
		(drill 0.2032)
		(layers "F.Cu" "B.Cu")
		(net "GND")
	)
	(via
		(at 324.640194 -38.10762)
		(size 0.508)
		(drill 0.254)
		(layers "F.Cu" "B.Cu")
		(net "GND")
	)
	(via
		(at 127.035306 -410.030168)
		(size 0.4064)
		(drill 0.2032)
		(layers "F.Cu" "B.Cu")
		(net "GND")
	)
	(via
		(at 168.527984 -308.685438)
		(size 0.4826)
		(drill 0.254)
		(layers "F.Cu" "B.Cu")
		(net "GND")
	)
	(via
		(at 105.671112 -224.234502)
		(size 0.4064)
		(drill 0.2032)
		(layers "F.Cu" "B.Cu")
		(net "GND")
	)
	(via
		(at 154.644344 -393.877038)
		(size 0.4572)
		(drill 0.254)
		(layers "F.Cu" "B.Cu")
		(net "GND")
	)
	(via
		(at 255.927098 -203.297536)
		(size 0.508)
		(drill 0.254)
		(layers "F.Cu" "B.Cu")
		(net "GND")
	)
	(via
		(at 21.70811 -308.685438)
		(size 0.4826)
		(drill 0.254)
		(layers "F.Cu" "B.Cu")
		(net "GND")
	)
	(via
		(at 394.179298 -154.162252)
		(size 0.508)
		(drill 0.254)
		(layers "F.Cu" "B.Cu")
		(net "GND")
	)
	(via
		(at 412.367984 -247.485154)
		(size 0.4826)
		(drill 0.254)
		(layers "F.Cu" "B.Cu")
		(net "GND")
	)
	(via
		(at 116.304822 -283.806392)
		(size 0.4064)
		(drill 0.2032)
		(layers "F.Cu" "B.Cu")
		(net "GND")
	)
	(via
		(at 435.000146 -300.185074)
		(size 0.4826)
		(drill 0.254)
		(layers "F.Cu" "B.Cu")
		(net "GND")
	)
	(via
		(at 268.263878 -202.434952)
		(size 0.4826)
		(drill 0.254)
		(layers "F.Cu" "B.Cu")
		(net "GND")
	)
	(via
		(at 251.263658 -98.884994)
		(size 0.508)
		(drill 0.254)
		(layers "F.Cu" "B.Cu")
		(net "GND")
	)
	(via
		(at 447.67119 -54.98846)
		(size 0.508)
		(drill 0.254)
		(layers "F.Cu" "B.Cu")
		(net "GND")
	)
	(via
		(at 437.349138 -332.053692)
		(size 0.508)
		(drill 0.254)
		(layers "F.Cu" "B.Cu")
		(net "GND")
	)
	(via
		(at 356.280212 -164.354256)
		(size 0.508)
		(drill 0.254)
		(layers "F.Cu" "B.Cu")
		(net "GND")
	)
	(via
		(at 278.289766 -342.811608)
		(size 0.508)
		(drill 0.254)
		(layers "F.Cu" "B.Cu")
		(net "GND")
	)
	(via
		(at 462.09204 -75.04684)
		(size 0.6604)
		(drill 0.3302)
		(layers "F.Cu" "B.Cu")
		(net "GND")
	)
	(via
		(at 277.192232 -318.035178)
		(size 0.4826)
		(drill 0.254)
		(layers "F.Cu" "B.Cu")
		(net "GND")
	)
	(via
		(at 46.666404 -230.0605)
		(size 0.4826)
		(drill 0.254)
		(layers "F.Cu" "B.Cu")
		(net "GND")
	)
	(via
		(at 22.535388 -371.36705)
		(size 0.508)
		(drill 0.254)
		(layers "F.Cu" "B.Cu")
		(net "GND")
	)
	(via
		(at 393.384786 -274.086066)
		(size 0.4064)
		(drill 0.2032)
		(layers "F.Cu" "B.Cu")
		(net "GND")
	)
	(via
		(at 93.751146 -269.226284)
		(size 0.4064)
		(drill 0.2032)
		(layers "F.Cu" "B.Cu")
		(net "GND")
	)
	(via
		(at 15.588996 -424.162474)
		(size 0.508)
		(drill 0.254)
		(layers "F.Cu" "B.Cu")
		(net "GND")
	)
	(via
		(at 99.390962 -288.666174)
		(size 0.4064)
		(drill 0.2032)
		(layers "F.Cu" "B.Cu")
		(net "GND")
	)
	(via
		(at 119.018558 -403.830536)
		(size 0.4572)
		(drill 0.254)
		(layers "F.Cu" "B.Cu")
		(net "GND")
	)
	(via
		(at 77.001116 -223.424496)
		(size 0.4064)
		(drill 0.2032)
		(layers "F.Cu" "B.Cu")
		(net "GND")
	)
	(via
		(at 445.259968 -293.384986)
		(size 0.4826)
		(drill 0.254)
		(layers "F.Cu" "B.Cu")
		(net "GND")
	)
	(via
		(at 127.754634 -223.424496)
		(size 0.4064)
		(drill 0.2032)
		(layers "F.Cu" "B.Cu")
		(net "GND")
	)
	(via
		(at 144.967706 -404.46452)
		(size 0.4064)
		(drill 0.2032)
		(layers "F.Cu" "B.Cu")
		(net "GND")
	)
	(via
		(at 360.85526 -336.499962)
		(size 0.508)
		(drill 0.254)
		(layers "F.Cu" "B.Cu")
		(net "GND")
	)
	(via
		(at 431.36566 -7.215124)
		(size 0.508)
		(drill 0.254)
		(layers "F.Cu" "B.Cu")
		(net "GND")
	)
	(via
		(at 241.91595 -222.65005)
		(size 0.508)
		(drill 0.254)
		(layers "F.Cu" "B.Cu")
		(net "GND")
	)
	(via
		(at 202.502008 -119.721376)
		(size 0.508)
		(drill 0.254)
		(layers "F.Cu" "B.Cu")
		(net "GND")
	)
	(via
		(at 341.691214 -282.186126)
		(size 0.4064)
		(drill 0.2032)
		(layers "F.Cu" "B.Cu")
		(net "GND")
	)
	(via
		(at 249.28703 -47.088806)
		(size 0.508)
		(drill 0.254)
		(layers "F.Cu" "B.Cu")
		(net "GND")
	)
	(via
		(at 348.368874 -163.078668)
		(size 0.49022)
		(drill 0.254)
		(layers "F.Cu" "B.Cu")
		(net "GND")
	)
	(via
		(at 377.995942 -415.38652)
		(size 0.4064)
		(drill 0.2032)
		(layers "F.Cu" "B.Cu")
		(net "GND")
	)
	(via
		(at 446.644268 -271.284954)
		(size 0.4826)
		(drill 0.254)
		(layers "F.Cu" "B.Cu")
		(net "GND")
	)
	(via
		(at 117.486938 -407.638504)
		(size 0.4572)
		(drill 0.254)
		(layers "F.Cu" "B.Cu")
		(net "GND")
	)
	(via
		(at 422.627806 -211.784946)
		(size 0.4826)
		(drill 0.254)
		(layers "F.Cu" "B.Cu")
		(net "GND")
	)
	(via
		(at 260.99008 -140.391896)
		(size 0.508)
		(drill 0.254)
		(layers "F.Cu" "B.Cu")
		(net "GND")
	)
	(via
		(at 348.911164 -237.19409)
		(size 0.4064)
		(drill 0.2032)
		(layers "F.Cu" "B.Cu")
		(net "GND")
	)
	(via
		(at 152.986994 -409.396184)
		(size 0.4572)
		(drill 0.254)
		(layers "F.Cu" "B.Cu")
		(net "GND")
	)
	(via
		(at 35.640264 -193.996564)
		(size 0.4826)
		(drill 0.254)
		(layers "F.Cu" "B.Cu")
		(net "GND")
	)
	(via
		(at 443.9285 -203.28509)
		(size 0.4826)
		(drill 0.254)
		(layers "F.Cu" "B.Cu")
		(net "GND")
	)
	(via
		(at 137.670794 -407.638504)
		(size 0.4572)
		(drill 0.254)
		(layers "F.Cu" "B.Cu")
		(net "GND")
	)
	(via
		(at 440.217814 -238.560102)
		(size 0.4826)
		(drill 0.254)
		(layers "F.Cu" "B.Cu")
		(net "GND")
	)
	(via
		(at 202.147932 -227.085398)
		(size 0.4826)
		(drill 0.254)
		(layers "F.Cu" "B.Cu")
		(net "GND")
	)
	(via
		(at 124.464826 -256.634488)
		(size 0.4064)
		(drill 0.2032)
		(layers "F.Cu" "B.Cu")
		(net "GND")
	)
	(via
		(at 35.678364 -294.66032)
		(size 0.4826)
		(drill 0.254)
		(layers "F.Cu" "B.Cu")
		(net "GND")
	)
	(via
		(at 397.992854 -414.752536)
		(size 0.4572)
		(drill 0.254)
		(layers "F.Cu" "B.Cu")
		(net "GND")
	)
	(via
		(at 59.849512 -405.098504)
		(size 0.4572)
		(drill 0.254)
		(layers "F.Cu" "B.Cu")
		(net "GND")
	)
	(via
		(at 182.231792 -227.935282)
		(size 0.4826)
		(drill 0.254)
		(layers "F.Cu" "B.Cu")
		(net "GND")
	)
	(via
		(at 83.59013 -384.617722)
		(size 0.4064)
		(drill 0.2032)
		(layers "F.Cu" "B.Cu")
		(net "GND")
	)
	(via
		(at 181.407562 -49.878742)
		(size 0.508)
		(drill 0.254)
		(layers "F.Cu" "B.Cu")
		(net "GND")
	)
	(via
		(at 21.075396 -394.220954)
		(size 0.508)
		(drill 0.254)
		(layers "F.Cu" "B.Cu")
		(net "GND")
	)
	(via
		(at 170.905424 -375.432828)
		(size 0.508)
		(drill 0.254)
		(layers "F.Cu" "B.Cu")
		(net "GND")
	)
	(via
		(at 369.414806 -274.896072)
		(size 0.4064)
		(drill 0.2032)
		(layers "F.Cu" "B.Cu")
		(net "GND")
	)
	(via
		(at 243.946934 -40.055546)
		(size 0.508)
		(drill 0.254)
		(layers "F.Cu" "B.Cu")
		(net "GND")
	)
	(via
		(at 416.468052 -244.934994)
		(size 0.4826)
		(drill 0.254)
		(layers "F.Cu" "B.Cu")
		(net "GND")
	)
	(via
		(at 324.75297 -241.510058)
		(size 0.4064)
		(drill 0.2032)
		(layers "F.Cu" "B.Cu")
		(net "GND")
	)
	(via
		(at 349.851218 -233.954066)
		(size 0.4064)
		(drill 0.2032)
		(layers "F.Cu" "B.Cu")
		(net "GND")
	)
	(via
		(at 343.409524 -334.625442)
		(size 0.49022)
		(drill 0.254)
		(layers "F.Cu" "B.Cu")
		(net "GND")
	)
	(via
		(at 365.82477 -232.334054)
		(size 0.4064)
		(drill 0.2032)
		(layers "F.Cu" "B.Cu")
		(net "GND")
	)
	(via
		(at 171.97197 -233.035348)
		(size 0.4826)
		(drill 0.254)
		(layers "F.Cu" "B.Cu")
		(net "GND")
	)
	(via
		(at 190.52286 -18.49628)
		(size 0.508)
		(drill 0.254)
		(layers "F.Cu" "B.Cu")
		(net "GND")
	)
	(via
		(at 32.695896 -242.385342)
		(size 0.4826)
		(drill 0.254)
		(layers "F.Cu" "B.Cu")
		(net "GND")
	)
	(via
		(at 110.371128 -245.294404)
		(size 0.4064)
		(drill 0.2032)
		(layers "F.Cu" "B.Cu")
		(net "GND")
	)
	(via
		(at 412.367984 -289.135058)
		(size 0.4826)
		(drill 0.254)
		(layers "F.Cu" "B.Cu")
		(net "GND")
	)
	(via
		(at 359.805224 -385.999228)
		(size 0.508)
		(drill 0.254)
		(layers "F.Cu" "B.Cu")
		(net "GND")
	)
	(via
		(at 392.809984 -6.598158)
		(size 0.508)
		(drill 0.254)
		(layers "F.Cu" "B.Cu")
		(net "GND")
	)
	(via
		(at 282.020264 -287.435036)
		(size 0.4826)
		(drill 0.254)
		(layers "F.Cu" "B.Cu")
		(net "GND")
	)
	(via
		(at 141.992858 -407.638504)
		(size 0.4572)
		(drill 0.254)
		(layers "F.Cu" "B.Cu")
		(net "GND")
	)
	(via
		(at 81.701132 -228.284532)
		(size 0.4064)
		(drill 0.2032)
		(layers "F.Cu" "B.Cu")
		(net "GND")
	)
	(via
		(at 90.87104 -355.968046)
		(size 0.508)
		(drill 0.254)
		(layers "F.Cu" "B.Cu")
		(net "GND")
	)
	(via
		(at 163.435538 -406.370536)
		(size 0.4572)
		(drill 0.254)
		(layers "F.Cu" "B.Cu")
		(net "GND")
	)
	(via
		(at 108.521754 -328.103738)
		(size 0.508)
		(drill 0.254)
		(layers "F.Cu" "B.Cu")
		(net "GND")
	)
	(via
		(at 420.24427 -402.309838)
		(size 0.4572)
		(drill 0.254)
		(layers "F.Cu" "B.Cu")
		(net "GND")
	)
	(via
		(at 138.864848 -265.98626)
		(size 0.4064)
		(drill 0.2032)
		(layers "F.Cu" "B.Cu")
		(net "GND")
	)
	(via
		(at 331.521054 -238.004096)
		(size 0.4064)
		(drill 0.2032)
		(layers "F.Cu" "B.Cu")
		(net "GND")
	)
	(via
		(at 126.916434 -382.85293)
		(size 0.4064)
		(drill 0.2032)
		(layers "F.Cu" "B.Cu")
		(net "GND")
	)
	(via
		(at 388.094474 -184.683146)
		(size 0.49022)
		(drill 0.254)
		(layers "F.Cu" "B.Cu")
		(net "GND")
	)
	(via
		(at 83.41106 -280.566368)
		(size 0.4064)
		(drill 0.2032)
		(layers "F.Cu" "B.Cu")
		(net "GND")
	)
	(via
		(at 353.441 -271.656048)
		(size 0.4064)
		(drill 0.2032)
		(layers "F.Cu" "B.Cu")
		(net "GND")
	)
	(via
		(at 26.307796 -194.885564)
		(size 0.4826)
		(drill 0.254)
		(layers "F.Cu" "B.Cu")
		(net "GND")
	)
	(via
		(at 117.714776 -266.796266)
		(size 0.4064)
		(drill 0.2032)
		(layers "F.Cu" "B.Cu")
		(net "GND")
	)
	(via
		(at 31.585662 -418.239448)
		(size 0.508)
		(drill 0.254)
		(layers "F.Cu" "B.Cu")
		(net "GND")
	)
	(via
		(at 351.024952 -337.99526)
		(size 0.49022)
		(drill 0.254)
		(layers "F.Cu" "B.Cu")
		(net "GND")
	)
	(via
		(at 467.5378 -105.207054)
		(size 0.508)
		(drill 0.254)
		(layers "F.Cu" "B.Cu")
		(net "GND")
	)
	(via
		(at 57.071514 -343.476834)
		(size 0.508)
		(drill 0.254)
		(layers "F.Cu" "B.Cu")
		(net "GND")
	)
	(via
		(at 373.644922 -270.846042)
		(size 0.4064)
		(drill 0.2032)
		(layers "F.Cu" "B.Cu")
		(net "GND")
	)
	(via
		(at 86.245954 -336.966814)
		(size 0.49022)
		(drill 0.254)
		(layers "F.Cu" "B.Cu")
		(net "GND")
	)
	(via
		(at 21.623782 -410.564584)
		(size 0.508)
		(drill 0.254)
		(layers "F.Cu" "B.Cu")
		(net "GND")
	)
	(via
		(at 114.478562 -386.449062)
		(size 0.4064)
		(drill 0.2032)
		(layers "F.Cu" "B.Cu")
		(net "GND")
	)
	(via
		(at 2.76225 -288.981134)
		(size 0.508)
		(drill 0.254)
		(layers "F.Cu" "B.Cu")
		(net "GND")
	)
	(via
		(at 6.799834 -101.297994)
		(size 0.508)
		(drill 0.254)
		(layers "F.Cu" "B.Cu")
		(net "GND")
	)
	(via
		(at 416.289236 -4.32943)
		(size 0.508)
		(drill 0.254)
		(layers "F.Cu" "B.Cu")
		(net "GND")
	)
	(via
		(at 91.571064 -225.854514)
		(size 0.4064)
		(drill 0.2032)
		(layers "F.Cu" "B.Cu")
		(net "GND")
	)
	(via
		(at 130.104642 -233.95432)
		(size 0.4064)
		(drill 0.2032)
		(layers "F.Cu" "B.Cu")
		(net "GND")
	)
	(via
		(at 284.736032 -267.035026)
		(size 0.4826)
		(drill 0.254)
		(layers "F.Cu" "B.Cu")
		(net "GND")
	)
	(via
		(at 121.644664 -233.95432)
		(size 0.4064)
		(drill 0.2032)
		(layers "F.Cu" "B.Cu")
		(net "GND")
	)
	(via
		(at 99.561142 -250.964446)
		(size 0.4064)
		(drill 0.2032)
		(layers "F.Cu" "B.Cu")
		(net "GND")
	)
	(via
		(at 209.423 -130.683)
		(size 0.508)
		(drill 0.254)
		(layers "F.Cu" "B.Cu")
		(net "GND")
	)
	(via
		(at 194.604132 -225.385376)
		(size 0.4826)
		(drill 0.254)
		(layers "F.Cu" "B.Cu")
		(net "GND")
	)
	(via
		(at 380.224792 -278.946102)
		(size 0.4064)
		(drill 0.2032)
		(layers "F.Cu" "B.Cu")
		(net "GND")
	)
	(via
		(at 85.614256 -411.936184)
		(size 0.4572)
		(drill 0.254)
		(layers "F.Cu" "B.Cu")
		(net "GND")
	)
	(via
		(at 375.054876 -270.036036)
		(size 0.4064)
		(drill 0.2032)
		(layers "F.Cu" "B.Cu")
		(net "GND")
	)
	(via
		(at 51.884072 -261.935214)
		(size 0.4826)
		(drill 0.254)
		(layers "F.Cu" "B.Cu")
		(net "GND")
	)
	(via
		(at 71.249794 -433.899564)
		(size 0.4572)
		(drill 0.2032)
		(layers "F.Cu" "B.Cu")
		(net "GND")
	)
	(via
		(at 27.548332 -12.37488)
		(size 0.508)
		(drill 0.254)
		(layers "F.Cu" "B.Cu")
		(net "GND")
	)
	(via
		(at 347.97111 -224.234248)
		(size 0.4064)
		(drill 0.2032)
		(layers "F.Cu" "B.Cu")
		(net "GND")
	)
	(via
		(at 44.843954 -18.247106)
		(size 0.508)
		(drill 0.254)
		(layers "F.Cu" "B.Cu")
		(net "GND")
	)
	(via
		(at 47.784004 -214.33536)
		(size 0.4826)
		(drill 0.254)
		(layers "F.Cu" "B.Cu")
		(net "GND")
	)
	(via
		(at 303.892966 -344.132408)
		(size 0.508)
		(drill 0.254)
		(layers "F.Cu" "B.Cu")
		(net "GND")
	)
	(via
		(at 345.621102 -250.964192)
		(size 0.4064)
		(drill 0.2032)
		(layers "F.Cu" "B.Cu")
		(net "GND")
	)
	(via
		(at 115.260882 -55.282084)
		(size 0.508)
		(drill 0.254)
		(layers "F.Cu" "B.Cu")
		(net "GND")
	)
	(via
		(at 397.058388 -385.87426)
		(size 0.508)
		(drill 0.254)
		(layers "F.Cu" "B.Cu")
		(net "GND")
	)
	(via
		(at 51.465734 -7.215124)
		(size 0.508)
		(drill 0.254)
		(layers "F.Cu" "B.Cu")
		(net "GND")
	)
	(via
		(at 206.248 -222.835216)
		(size 0.4826)
		(drill 0.254)
		(layers "F.Cu" "B.Cu")
		(net "GND")
	)
	(via
		(at 471.037666 -16.881094)
		(size 0.508)
		(drill 0.254)
		(layers "F.Cu" "B.Cu")
		(net "GND")
	)
	(via
		(at 384.48107 -414.752536)
		(size 0.4572)
		(drill 0.254)
		(layers "F.Cu" "B.Cu")
		(net "GND")
	)
	(via
		(at 440.217814 -294.660066)
		(size 0.4826)
		(drill 0.254)
		(layers "F.Cu" "B.Cu")
		(net "GND")
	)
	(via
		(at 352.671126 -233.954066)
		(size 0.4064)
		(drill 0.2032)
		(layers "F.Cu" "B.Cu")
		(net "GND")
	)
	(via
		(at 394.68298 -246.370094)
		(size 0.4064)
		(drill 0.2032)
		(layers "F.Cu" "B.Cu")
		(net "GND")
	)
	(via
		(at 171.97197 -264.485374)
		(size 0.4826)
		(drill 0.254)
		(layers "F.Cu" "B.Cu")
		(net "GND")
	)
	(via
		(at 44.065952 -385.58216)
		(size 0.508)
		(drill 0.254)
		(layers "F.Cu" "B.Cu")
		(net "GND")
	)
	(via
		(at 179.93233 -109.463078)
		(size 0.4572)
		(drill 0.254)
		(layers "F.Cu" "B.Cu")
		(net "GND")
	)
	(via
		(at 363.304836 -291.905944)
		(size 0.4064)
		(drill 0.2032)
		(layers "F.Cu" "B.Cu")
		(net "GND")
	)
	(via
		(at 390.349486 -425.547282)
		(size 0.4572)
		(drill 0.2032)
		(layers "F.Cu" "B.Cu")
		(net "GND")
	)
	(via
		(at 356.431088 -225.85426)
		(size 0.4064)
		(drill 0.2032)
		(layers "F.Cu" "B.Cu")
		(net "GND")
	)
	(via
		(at 328.016108 -333.048864)
		(size 0.49022)
		(drill 0.254)
		(layers "F.Cu" "B.Cu")
		(net "GND")
	)
	(via
		(at 85.024976 -143.785844)
		(size 0.508)
		(drill 0.254)
		(layers "F.Cu" "B.Cu")
		(net "GND")
	)
	(via
		(at 144.417542 -81.786222)
		(size 0.508)
		(drill 0.254)
		(layers "F.Cu" "B.Cu")
		(net "GND")
	)
	(via
		(at 102.548436 -30.219904)
		(size 0.508)
		(drill 0.254)
		(layers "F.Cu" "B.Cu")
		(net "GND")
	)
	(via
		(at 348.368874 -161.538412)
		(size 0.49022)
		(drill 0.254)
		(layers "F.Cu" "B.Cu")
		(net "GND")
	)
	(via
		(at 327.277476 -387.218428)
		(size 0.508)
		(drill 0.254)
		(layers "F.Cu" "B.Cu")
		(net "GND")
	)
	(via
		(at 128.694688 -254.20447)
		(size 0.4064)
		(drill 0.2032)
		(layers "F.Cu" "B.Cu")
		(net "GND")
	)
	(via
		(at 73.619614 -333.05115)
		(size 0.508)
		(drill 0.254)
		(layers "F.Cu" "B.Cu")
		(net "GND")
	)
	(via
		(at 138.349736 -430.299622)
		(size 0.4572)
		(drill 0.2032)
		(layers "F.Cu" "B.Cu")
		(net "GND")
	)
	(via
		(at 431.55616 -271.284954)
		(size 0.4826)
		(drill 0.254)
		(layers "F.Cu" "B.Cu")
		(net "GND")
	)
	(via
		(at 286.82442 -423.208196)
		(size 0.508)
		(drill 0.254)
		(layers "F.Cu" "B.Cu")
		(net "GND")
	)
	(via
		(at 108.530644 -383.02946)
		(size 0.508)
		(drill 0.254)
		(layers "F.Cu" "B.Cu")
		(net "GND")
	)
	(via
		(at 59.33313 -19.13636)
		(size 0.508)
		(drill 0.254)
		(layers "F.Cu" "B.Cu")
		(net "GND")
	)
	(via
		(at 387.347714 -421.586152)
		(size 0.4572)
		(drill 0.254)
		(layers "F.Cu" "B.Cu")
		(net "GND")
	)
	(via
		(at 87.141558 -334.579468)
		(size 0.49022)
		(drill 0.254)
		(layers "F.Cu" "B.Cu")
		(net "GND")
	)
	(via
		(at 369.80749 -186.648598)
		(size 0.508)
		(drill 0.254)
		(layers "F.Cu" "B.Cu")
		(net "GND")
	)
	(via
		(at 346.39123 -270.846042)
		(size 0.4064)
		(drill 0.2032)
		(layers "F.Cu" "B.Cu")
		(net "GND")
	)
	(via
		(at 415.11347 -416.020504)
		(size 0.4572)
		(drill 0.254)
		(layers "F.Cu" "B.Cu")
		(net "GND")
	)
	(via
		(at 173.468284 -17.775428)
		(size 0.508)
		(drill 0.254)
		(layers "F.Cu" "B.Cu")
		(net "GND")
	)
	(via
		(at 10.522458 -423.821098)
		(size 0.508)
		(drill 0.254)
		(layers "F.Cu" "B.Cu")
		(net "GND")
	)
	(via
		(at 138.929618 -409.396184)
		(size 0.4572)
		(drill 0.254)
		(layers "F.Cu" "B.Cu")
		(net "GND")
	)
	(via
		(at 365.807498 -177.205386)
		(size 0.49022)
		(drill 0.254)
		(layers "F.Cu" "B.Cu")
		(net "GND")
	)
	(via
		(at 213.995 -331.724)
		(size 0.508)
		(drill 0.254)
		(layers "F.Cu" "B.Cu")
		(net "GND")
	)
	(via
		(at 52.262532 -384.617722)
		(size 0.4064)
		(drill 0.2032)
		(layers "F.Cu" "B.Cu")
		(net "GND")
	)
	(via
		(at 164.427916 -307.8353)
		(size 0.4826)
		(drill 0.254)
		(layers "F.Cu" "B.Cu")
		(net "GND")
	)
	(via
		(at 179.516024 -233.035348)
		(size 0.4826)
		(drill 0.254)
		(layers "F.Cu" "B.Cu")
		(net "GND")
	)
	(via
		(at 22.389592 -4.963414)
		(size 0.508)
		(drill 0.254)
		(layers "F.Cu" "B.Cu")
		(net "GND")
	)
	(via
		(at 82.54365 -180.755544)
		(size 0.49022)
		(drill 0.254)
		(layers "F.Cu" "B.Cu")
		(net "GND")
	)
	(via
		(at 150.606252 -386.449062)
		(size 0.4064)
		(drill 0.2032)
		(layers "F.Cu" "B.Cu")
		(net "GND")
	)
	(via
		(at 373.018558 -396.710662)
		(size 0.4064)
		(drill 0.2032)
		(layers "F.Cu" "B.Cu")
		(net "GND")
	)
	(via
		(at 415.492692 -138.573256)
		(size 0.508)
		(drill 0.254)
		(layers "F.Cu" "B.Cu")
		(net "GND")
	)
	(via
		(at 255.799082 -92.319094)
		(size 0.508)
		(drill 0.254)
		(layers "F.Cu" "B.Cu")
		(net "GND")
	)
	(via
		(at 205.092554 -193.99631)
		(size 0.4826)
		(drill 0.254)
		(layers "F.Cu" "B.Cu")
		(net "GND")
	)
	(via
		(at 102.395782 -143.61541)
		(size 0.508)
		(drill 0.254)
		(layers "F.Cu" "B.Cu")
		(net "GND")
	)
	(via
		(at 195.988432 -203.285344)
		(size 0.4826)
		(drill 0.254)
		(layers "F.Cu" "B.Cu")
		(net "GND")
	)
	(via
		(at 121.174764 -242.864386)
		(size 0.4064)
		(drill 0.2032)
		(layers "F.Cu" "B.Cu")
		(net "GND")
	)
	(via
		(at 395.288262 -418.412168)
		(size 0.4064)
		(drill 0.2032)
		(layers "F.Cu" "B.Cu")
		(net "GND")
	)
	(via
		(at 42.955718 -218.585288)
		(size 0.4826)
		(drill 0.254)
		(layers "F.Cu" "B.Cu")
		(net "GND")
	)
	(via
		(at 448.318636 -20.432522)
		(size 0.508)
		(drill 0.254)
		(layers "F.Cu" "B.Cu")
		(net "GND")
	)
	(via
		(at 364.884716 -237.19409)
		(size 0.4064)
		(drill 0.2032)
		(layers "F.Cu" "B.Cu")
		(net "GND")
	)
	(via
		(at 90.16111 -228.284532)
		(size 0.4064)
		(drill 0.2032)
		(layers "F.Cu" "B.Cu")
		(net "GND")
	)
	(via
		(at 423.803064 -154.8003)
		(size 0.508)
		(drill 0.254)
		(layers "F.Cu" "B.Cu")
		(net "GND")
	)
	(via
		(at 373.3165 -391.23493)
		(size 0.4064)
		(drill 0.2032)
		(layers "F.Cu" "B.Cu")
		(net "GND")
	)
	(via
		(at 343.145618 -419.046152)
		(size 0.4572)
		(drill 0.254)
		(layers "F.Cu" "B.Cu")
		(net "GND")
	)
	(via
		(at 367.234724 -223.424242)
		(size 0.4064)
		(drill 0.2032)
		(layers "F.Cu" "B.Cu")
		(net "GND")
	)
	(via
		(at 347.97111 -235.574078)
		(size 0.4064)
		(drill 0.2032)
		(layers "F.Cu" "B.Cu")
		(net "GND")
	)
	(via
		(at 354.08108 -221.80423)
		(size 0.4064)
		(drill 0.2032)
		(layers "F.Cu" "B.Cu")
		(net "GND")
	)
	(via
		(at 256.232406 -124.115068)
		(size 0.508)
		(drill 0.254)
		(layers "F.Cu" "B.Cu")
		(net "GND")
	)
	(via
		(at 121.944638 -285.426404)
		(size 0.4064)
		(drill 0.2032)
		(layers "F.Cu" "B.Cu")
		(net "GND")
	)
	(via
		(at 18.992342 -238.135414)
		(size 0.4826)
		(drill 0.254)
		(layers "F.Cu" "B.Cu")
		(net "GND")
	)
	(via
		(at 54.752494 -373.30253)
		(size 0.508)
		(drill 0.254)
		(layers "F.Cu" "B.Cu")
		(net "GND")
	)
	(via
		(at 274.476464 -284.88513)
		(size 0.4826)
		(drill 0.254)
		(layers "F.Cu" "B.Cu")
		(net "GND")
	)
	(via
		(at 121.644664 -237.194344)
		(size 0.4064)
		(drill 0.2032)
		(layers "F.Cu" "B.Cu")
		(net "GND")
	)
	(via
		(at 142.265654 -411.936184)
		(size 0.4572)
		(drill 0.254)
		(layers "F.Cu" "B.Cu")
		(net "GND")
	)
	(via
		(at 392.349482 -439.651394)
		(size 0.4572)
		(drill 0.2032)
		(layers "F.Cu" "B.Cu")
		(net "GND")
	)
	(via
		(at 121.174764 -246.10441)
		(size 0.4064)
		(drill 0.2032)
		(layers "F.Cu" "B.Cu")
		(net "GND")
	)
	(via
		(at 79.180944 -268.416278)
		(size 0.4064)
		(drill 0.2032)
		(layers "F.Cu" "B.Cu")
		(net "GND")
	)
	(via
		(at 325.24954 -432.451256)
		(size 0.4572)
		(drill 0.2032)
		(layers "F.Cu" "B.Cu")
		(net "GND")
	)
	(via
		(at 141.854682 -254.20447)
		(size 0.4064)
		(drill 0.2032)
		(layers "F.Cu" "B.Cu")
		(net "GND")
	)
	(via
		(at 336.521044 -273.27606)
		(size 0.4064)
		(drill 0.2032)
		(layers "F.Cu" "B.Cu")
		(net "GND")
	)
	(via
		(at 269.648178 -243.234972)
		(size 0.4826)
		(drill 0.254)
		(layers "F.Cu" "B.Cu")
		(net "GND")
	)
	(via
		(at 315.849254 -413.480504)
		(size 0.4572)
		(drill 0.254)
		(layers "F.Cu" "B.Cu")
		(net "GND")
	)
	(via
		(at 76.812902 -254.470408)
		(size 0.4064)
		(drill 0.2032)
		(layers "F.Cu" "B.Cu")
		(net "GND")
	)
	(via
		(at 439.100214 -235.585)
		(size 0.4826)
		(drill 0.254)
		(layers "F.Cu" "B.Cu")
		(net "GND")
	)
	(via
		(at 15.68577 -389.4201)
		(size 0.49022)
		(drill 0.254)
		(layers "F.Cu" "B.Cu")
		(net "GND")
	)
	(via
		(at 147.349718 -435.0512)
		(size 0.4572)
		(drill 0.2032)
		(layers "F.Cu" "B.Cu")
		(net "GND")
	)
	(via
		(at 344.211148 -227.474272)
		(size 0.4064)
		(drill 0.2032)
		(layers "F.Cu" "B.Cu")
		(net "GND")
	)
	(via
		(at 97.13849 -184.628282)
		(size 0.49022)
		(drill 0.254)
		(layers "F.Cu" "B.Cu")
		(net "GND")
	)
	(via
		(at 181.407562 -43.909742)
		(size 0.508)
		(drill 0.254)
		(layers "F.Cu" "B.Cu")
		(net "GND")
	)
	(via
		(at 437.715914 -211.784946)
		(size 0.4826)
		(drill 0.254)
		(layers "F.Cu" "B.Cu")
		(net "GND")
	)
	(via
		(at 194.774566 -347.41612)
		(size 0.508)
		(drill 0.254)
		(layers "F.Cu" "B.Cu")
		(net "GND")
	)
	(via
		(at 82.925666 -183.14289)
		(size 0.49022)
		(drill 0.254)
		(layers "F.Cu" "B.Cu")
		(net "GND")
	)
	(via
		(at 98.120962 -315.150754)
		(size 0.4064)
		(drill 0.2032)
		(layers "F.Cu" "B.Cu")
		(net "GND")
	)
	(via
		(at 119.76481 -246.914416)
		(size 0.4064)
		(drill 0.2032)
		(layers "F.Cu" "B.Cu")
		(net "GND")
	)
	(via
		(at 445.363092 -12.37488)
		(size 0.508)
		(drill 0.254)
		(layers "F.Cu" "B.Cu")
		(net "GND")
	)
	(via
		(at 317.016384 -402.309838)
		(size 0.4572)
		(drill 0.254)
		(layers "F.Cu" "B.Cu")
		(net "GND")
	)
	(via
		(at 168.527984 -263.635236)
		(size 0.4826)
		(drill 0.254)
		(layers "F.Cu" "B.Cu")
		(net "GND")
	)
	(via
		(at 92.981018 -225.044508)
		(size 0.4064)
		(drill 0.2032)
		(layers "F.Cu" "B.Cu")
		(net "GND")
	)
	(via
		(at 394.935964 -17.61236)
		(size 0.508)
		(drill 0.254)
		(layers "F.Cu" "B.Cu")
		(net "GND")
	)
	(via
		(at 419.912038 -206.685134)
		(size 0.4826)
		(drill 0.254)
		(layers "F.Cu" "B.Cu")
		(net "GND")
	)
	(via
		(at 194.774566 -348.07652)
		(size 0.508)
		(drill 0.254)
		(layers "F.Cu" "B.Cu")
		(net "GND")
	)
	(via
		(at 55.328058 -269.58544)
		(size 0.4826)
		(drill 0.254)
		(layers "F.Cu" "B.Cu")
		(net "GND")
	)
	(via
		(at 49.807368 -351.736406)
		(size 0.508)
		(drill 0.254)
		(layers "F.Cu" "B.Cu")
		(net "GND")
	)
	(via
		(at 448.063366 -376.53087)
		(size 0.508)
		(drill 0.254)
		(layers "F.Cu" "B.Cu")
		(net "GND")
	)
	(via
		(at 29.252164 -278.935434)
		(size 0.4826)
		(drill 0.254)
		(layers "F.Cu" "B.Cu")
		(net "GND")
	)
	(via
		(at 83.876642 -369.69573)
		(size 0.508)
		(drill 0.254)
		(layers "F.Cu" "B.Cu")
		(net "GND")
	)
	(via
		(at 318.81445 -34.938462)
		(size 0.508)
		(drill 0.254)
		(layers "F.Cu" "B.Cu")
		(net "GND")
	)
	(via
		(at 339.511132 -227.474272)
		(size 0.4064)
		(drill 0.2032)
		(layers "F.Cu" "B.Cu")
		(net "GND")
	)
	(via
		(at 98.716338 -310.757062)
		(size 0.4064)
		(drill 0.2032)
		(layers "F.Cu" "B.Cu")
		(net "GND")
	)
	(via
		(at 29.252164 -308.685438)
		(size 0.4826)
		(drill 0.254)
		(layers "F.Cu" "B.Cu")
		(net "GND")
	)
	(via
		(at 127.754634 -225.044508)
		(size 0.4064)
		(drill 0.2032)
		(layers "F.Cu" "B.Cu")
		(net "GND")
	)
	(via
		(at 116.004848 -246.914416)
		(size 0.4064)
		(drill 0.2032)
		(layers "F.Cu" "B.Cu")
		(net "GND")
	)
	(via
		(at 23.804118 -40.399462)
		(size 0.508)
		(drill 0.254)
		(layers "F.Cu" "B.Cu")
		(net "GND")
	)
	(via
		(at 96.84639 -388.328662)
		(size 0.4064)
		(drill 0.2032)
		(layers "F.Cu" "B.Cu")
		(net "GND")
	)
	(via
		(at 441.351924 -391.110978)
		(size 0.508)
		(drill 0.254)
		(layers "F.Cu" "B.Cu")
		(net "GND")
	)
	(via
		(at 426.57268 -427.633638)
		(size 0.508)
		(drill 0.254)
		(layers "F.Cu" "B.Cu")
		(net "GND")
	)
	(via
		(at 28.821126 -428.183802)
		(size 0.508)
		(drill 0.254)
		(layers "F.Cu" "B.Cu")
		(net "GND")
	)
	(via
		(at 164.45103 -353.72167)
		(size 0.508)
		(drill 0.254)
		(layers "F.Cu" "B.Cu")
		(net "GND")
	)
	(via
		(at 364.888018 -253.392178)
		(size 0.4064)
		(drill 0.2032)
		(layers "F.Cu" "B.Cu")
		(net "GND")
	)
	(via
		(at 445.125094 -64.093598)
		(size 0.508)
		(drill 0.254)
		(layers "F.Cu" "B.Cu")
		(net "GND")
	)
	(via
		(at 303.268126 -281.485086)
		(size 0.4826)
		(drill 0.254)
		(layers "F.Cu" "B.Cu")
		(net "GND")
	)
	(via
		(at 58.045096 -411.936184)
		(size 0.4572)
		(drill 0.254)
		(layers "F.Cu" "B.Cu")
		(net "GND")
	)
	(via
		(at 231.319578 -317.942468)
		(size 0.508)
		(drill 0.254)
		(layers "F.Cu" "B.Cu")
		(net "GND")
	)
	(via
		(at 376.93473 -270.036036)
		(size 0.4064)
		(drill 0.2032)
		(layers "F.Cu" "B.Cu")
		(net "GND")
	)
	(via
		(at 42.839894 -372.15953)
		(size 0.508)
		(drill 0.254)
		(layers "F.Cu" "B.Cu")
		(net "GND")
	)
	(via
		(at 355.491034 -248.534174)
		(size 0.4064)
		(drill 0.2032)
		(layers "F.Cu" "B.Cu")
		(net "GND")
	)
	(via
		(at 164.244274 -382.85293)
		(size 0.4064)
		(drill 0.2032)
		(layers "F.Cu" "B.Cu")
		(net "GND")
	)
	(via
		(at 187.060078 -225.385376)
		(size 0.4826)
		(drill 0.254)
		(layers "F.Cu" "B.Cu")
		(net "GND")
	)
	(via
		(at 158.244286 -382.85293)
		(size 0.4064)
		(drill 0.2032)
		(layers "F.Cu" "B.Cu")
		(net "GND")
	)
	(via
		(at 161.006028 -149.221952)
		(size 0.508)
		(drill 0.254)
		(layers "F.Cu" "B.Cu")
		(net "GND")
	)
	(via
		(at 88.281002 -250.964446)
		(size 0.4064)
		(drill 0.2032)
		(layers "F.Cu" "B.Cu")
		(net "GND")
	)
	(via
		(at 467.5378 -121.971054)
		(size 0.508)
		(drill 0.254)
		(layers "F.Cu" "B.Cu")
		(net "GND")
	)
	(via
		(at 136.139174 -411.936184)
		(size 0.4572)
		(drill 0.254)
		(layers "F.Cu" "B.Cu")
		(net "GND")
	)
	(via
		(at 130.305048 -157.659324)
		(size 0.49022)
		(drill 0.254)
		(layers "F.Cu" "B.Cu")
		(net "GND")
	)
	(via
		(at 251.347224 -276.227032)
		(size 0.508)
		(drill 0.254)
		(layers "F.Cu" "B.Cu")
		(net "GND")
	)
	(via
		(at 349.630746 -418.412168)
		(size 0.4064)
		(drill 0.2032)
		(layers "F.Cu" "B.Cu")
		(net "GND")
	)
	(via
		(at 432.928776 -103.38943)
		(size 0.508)
		(drill 0.254)
		(layers "F.Cu" "B.Cu")
		(net "GND")
	)
	(via
		(at 369.884706 -278.946102)
		(size 0.4064)
		(drill 0.2032)
		(layers "F.Cu" "B.Cu")
		(net "GND")
	)
	(via
		(at 297.108372 -278.085042)
		(size 0.4826)
		(drill 0.254)
		(layers "F.Cu" "B.Cu")
		(net "GND")
	)
	(via
		(at 186.312048 -117.442742)
		(size 0.4572)
		(drill 0.254)
		(layers "F.Cu" "B.Cu")
		(net "GND")
	)
	(via
		(at 51.015392 -420.536624)
		(size 0.508)
		(drill 0.254)
		(layers "F.Cu" "B.Cu")
		(net "GND")
	)
	(via
		(at 167.527986 -353.320858)
		(size 0.508)
		(drill 0.254)
		(layers "F.Cu" "B.Cu")
		(net "GND")
	)
	(via
		(at 29.252164 -291.685218)
		(size 0.4826)
		(drill 0.254)
		(layers "F.Cu" "B.Cu")
		(net "GND")
	)
	(via
		(at 413.667702 -415.38652)
		(size 0.4064)
		(drill 0.2032)
		(layers "F.Cu" "B.Cu")
		(net "GND")
	)
	(via
		(at 56.712358 -231.335326)
		(size 0.4826)
		(drill 0.254)
		(layers "F.Cu" "B.Cu")
		(net "GND")
	)
	(via
		(at 96.27108 -227.474526)
		(size 0.4064)
		(drill 0.2032)
		(layers "F.Cu" "B.Cu")
		(net "GND")
	)
	(via
		(at 419.435534 -416.020504)
		(size 0.4572)
		(drill 0.254)
		(layers "F.Cu" "B.Cu")
		(net "GND")
	)
	(via
		(at 181.17312 -161.771838)
		(size 0.508)
		(drill 0.254)
		(layers "F.Cu" "B.Cu")
		(net "GND")
	)
	(via
		(at 404.39213 -420.318184)
		(size 0.4572)
		(drill 0.254)
		(layers "F.Cu" "B.Cu")
		(net "GND")
	)
	(via
		(at 280.635964 -236.435138)
		(size 0.4826)
		(drill 0.254)
		(layers "F.Cu" "B.Cu")
		(net "GND")
	)
	(via
		(at 128.116584 -393.927838)
		(size 0.4572)
		(drill 0.254)
		(layers "F.Cu" "B.Cu")
		(net "GND")
	)
	(via
		(at 77.112876 -290.830254)
		(size 0.4064)
		(drill 0.2032)
		(layers "F.Cu" "B.Cu")
		(net "GND")
	)
	(via
		(at 42.955718 -221.135194)
		(size 0.4826)
		(drill 0.254)
		(layers "F.Cu" "B.Cu")
		(net "GND")
	)
	(via
		(at 116.116608 -382.85293)
		(size 0.4064)
		(drill 0.2032)
		(layers "F.Cu" "B.Cu")
		(net "GND")
	)
	(via
		(at 136.684766 -235.574332)
		(size 0.4064)
		(drill 0.2032)
		(layers "F.Cu" "B.Cu")
		(net "GND")
	)
	(via
		(at 421.919654 -424.594274)
		(size 0.508)
		(drill 0.254)
		(layers "F.Cu" "B.Cu")
		(net "GND")
	)
	(via
		(at 415.11347 -417.778184)
		(size 0.4572)
		(drill 0.254)
		(layers "F.Cu" "B.Cu")
		(net "GND")
	)
	(via
		(at 413.309054 -417.778184)
		(size 0.4572)
		(drill 0.254)
		(layers "F.Cu" "B.Cu")
		(net "GND")
	)
	(via
		(at 331.521054 -252.584204)
		(size 0.4064)
		(drill 0.2032)
		(layers "F.Cu" "B.Cu")
		(net "GND")
	)
	(via
		(at 353.490784 -378.07773)
		(size 0.508)
		(drill 0.254)
		(layers "F.Cu" "B.Cu")
		(net "GND")
	)
	(via
		(at 405.64562 -7.215124)
		(size 0.508)
		(drill 0.254)
		(layers "F.Cu" "B.Cu")
		(net "GND")
	)
	(via
		(at 405.92375 -419.046152)
		(size 0.4572)
		(drill 0.254)
		(layers "F.Cu" "B.Cu")
		(net "GND")
	)
	(via
		(at 130.40487 -288.666174)
		(size 0.4064)
		(drill 0.2032)
		(layers "F.Cu" "B.Cu")
		(net "GND")
	)
	(via
		(at 197.869556 -342.001348)
		(size 0.508)
		(drill 0.254)
		(layers "F.Cu" "B.Cu")
		(net "GND")
	)
	(via
		(at 68.915534 -336.988404)
		(size 0.49022)
		(drill 0.254)
		(layers "F.Cu" "B.Cu")
		(net "GND")
	)
	(via
		(at 51.060096 -145.153888)
		(size 0.6604)
		(drill 0.3302)
		(layers "F.Cu" "B.Cu")
		(net "GND")
	)
	(via
		(at 315.595 -365.01705)
		(size 0.508)
		(drill 0.254)
		(layers "F.Cu" "B.Cu")
		(net "GND")
	)
	(via
		(at 386.21843 -396.710662)
		(size 0.4064)
		(drill 0.2032)
		(layers "F.Cu" "B.Cu")
		(net "GND")
	)
	(via
		(at 115.064794 -225.854514)
		(size 0.4064)
		(drill 0.2032)
		(layers "F.Cu" "B.Cu")
		(net "GND")
	)
	(via
		(at 383.039874 -184.683146)
		(size 0.49022)
		(drill 0.254)
		(layers "F.Cu" "B.Cu")
		(net "GND")
	)
	(via
		(at 81.701132 -252.584458)
		(size 0.4064)
		(drill 0.2032)
		(layers "F.Cu" "B.Cu")
		(net "GND")
	)
	(via
		(at 29.303218 -18.503138)
		(size 0.508)
		(drill 0.254)
		(layers "F.Cu" "B.Cu")
		(net "GND")
	)
	(via
		(at 164.715698 -11.202924)
		(size 0.508)
		(drill 0.254)
		(layers "F.Cu" "B.Cu")
		(net "GND")
	)
	(via
		(at 352.789998 -392.999722)
		(size 0.4064)
		(drill 0.2032)
		(layers "F.Cu" "B.Cu")
		(net "GND")
	)
	(via
		(at 105.500932 -268.416278)
		(size 0.4064)
		(drill 0.2032)
		(layers "F.Cu" "B.Cu")
		(net "GND")
	)
	(via
		(at 77.905864 -10.15619)
		(size 0.508)
		(drill 0.254)
		(layers "F.Cu" "B.Cu")
		(net "GND")
	)
	(via
		(at 198.7042 -297.635422)
		(size 0.4826)
		(drill 0.254)
		(layers "F.Cu" "B.Cu")
		(net "GND")
	)
	(via
		(at 332.249526 -425.547282)
		(size 0.4572)
		(drill 0.2032)
		(layers "F.Cu" "B.Cu")
		(net "GND")
	)
	(via
		(at 398.26565 -412.212536)
		(size 0.4572)
		(drill 0.254)
		(layers "F.Cu" "B.Cu")
		(net "GND")
	)
	(via
		(at 163.044124 -382.85293)
		(size 0.4064)
		(drill 0.2032)
		(layers "F.Cu" "B.Cu")
		(net "GND")
	)
	(via
		(at 86.701122 -284.616398)
		(size 0.4064)
		(drill 0.2032)
		(layers "F.Cu" "B.Cu")
		(net "GND")
	)
	(via
		(at 102.211124 -282.18638)
		(size 0.4064)
		(drill 0.2032)
		(layers "F.Cu" "B.Cu")
		(net "GND")
	)
	(via
		(at 84.355432 -403.830536)
		(size 0.4572)
		(drill 0.254)
		(layers "F.Cu" "B.Cu")
		(net "GND")
	)
	(via
		(at 143.365474 -11.463528)
		(size 0.508)
		(drill 0.254)
		(layers "F.Cu" "B.Cu")
		(net "GND")
	)
	(via
		(at 436.155846 -192.21831)
		(size 0.4826)
		(drill 0.254)
		(layers "F.Cu" "B.Cu")
		(net "GND")
	)
	(via
		(at 216.60612 -74.055986)
		(size 0.508)
		(drill 0.254)
		(layers "F.Cu" "B.Cu")
		(net "GND")
	)
	(via
		(at 168.527984 -253.435358)
		(size 0.4826)
		(drill 0.254)
		(layers "F.Cu" "B.Cu")
		(net "GND")
	)
	(via
		(at 14.01826 -91.658948)
		(size 0.508)
		(drill 0.254)
		(layers "F.Cu" "B.Cu")
		(net "GND")
	)
	(via
		(at 97.388934 -333.094076)
		(size 0.49022)
		(drill 0.254)
		(layers "F.Cu" "B.Cu")
		(net "GND")
	)
	(via
		(at 107.553506 -409.551378)
		(size 0.508)
		(drill 0.254)
		(layers "F.Cu" "B.Cu")
		(net "GND")
	)
	(via
		(at 308.191154 -417.778184)
		(size 0.4572)
		(drill 0.254)
		(layers "F.Cu" "B.Cu")
		(net "GND")
	)
	(via
		(at 383.035302 -418.412168)
		(size 0.4064)
		(drill 0.2032)
		(layers "F.Cu" "B.Cu")
		(net "GND")
	)
	(via
		(at 98.451162 -262.746236)
		(size 0.4064)
		(drill 0.2032)
		(layers "F.Cu" "B.Cu")
		(net "GND")
	)
	(via
		(at 113.184686 -222.61449)
		(size 0.4064)
		(drill 0.2032)
		(layers "F.Cu" "B.Cu")
		(net "GND")
	)
	(via
		(at 133.075934 -405.098504)
		(size 0.4572)
		(drill 0.254)
		(layers "F.Cu" "B.Cu")
		(net "GND")
	)
	(via
		(at 337.631024 -224.234248)
		(size 0.4064)
		(drill 0.2032)
		(layers "F.Cu" "B.Cu")
		(net "GND")
	)
	(via
		(at 20.32381 -202.435206)
		(size 0.4826)
		(drill 0.254)
		(layers "F.Cu" "B.Cu")
		(net "GND")
	)
	(via
		(at 392.700002 -192.481962)
		(size 0.508)
		(drill 0.254)
		(layers "F.Cu" "B.Cu")
		(net "GND")
	)
	(via
		(at 409.349702 -427.699678)
		(size 0.4572)
		(drill 0.2032)
		(layers "F.Cu" "B.Cu")
		(net "GND")
	)
	(via
		(at 381.41783 -417.778184)
		(size 0.4572)
		(drill 0.254)
		(layers "F.Cu" "B.Cu")
		(net "GND")
	)
	(via
		(at 106.405172 -259.330444)
		(size 0.4826)
		(drill 0.254)
		(layers "F.Cu" "B.Cu")
		(net "GND")
	)
	(via
		(at 114.894614 -284.616398)
		(size 0.4064)
		(drill 0.2032)
		(layers "F.Cu" "B.Cu")
		(net "GND")
	)
	(via
		(at 96.523048 -61.87821)
		(size 0.508)
		(drill 0.254)
		(layers "F.Cu" "B.Cu")
		(net "GND")
	)
	(via
		(at 174.687738 -274.685252)
		(size 0.4826)
		(drill 0.254)
		(layers "F.Cu" "B.Cu")
		(net "GND")
	)
	(via
		(at 413.667702 -418.412168)
		(size 0.4064)
		(drill 0.2032)
		(layers "F.Cu" "B.Cu")
		(net "GND")
	)
	(via
		(at 320.085466 -415.38652)
		(size 0.4064)
		(drill 0.2032)
		(layers "F.Cu" "B.Cu")
		(net "GND")
	)
	(via
		(at 411.001718 -167.012112)
		(size 0.508)
		(drill 0.254)
		(layers "F.Cu" "B.Cu")
		(net "GND")
	)
	(via
		(at 334.417924 -334.574642)
		(size 0.49022)
		(drill 0.254)
		(layers "F.Cu" "B.Cu")
		(net "GND")
	)
	(via
		(at 441.86856 -439.047382)
		(size 0.508)
		(drill 0.254)
		(layers "F.Cu" "B.Cu")
		(net "GND")
	)
	(via
		(at 303.268126 -273.835114)
		(size 0.4826)
		(drill 0.254)
		(layers "F.Cu" "B.Cu")
		(net "GND")
	)
	(via
		(at 329.361038 -420.318184)
		(size 0.4572)
		(drill 0.254)
		(layers "F.Cu" "B.Cu")
		(net "GND")
	)
	(via
		(at 446.644268 -288.285174)
		(size 0.4826)
		(drill 0.254)
		(layers "F.Cu" "B.Cu")
		(net "GND")
	)
	(via
		(at 307.368194 -235.585)
		(size 0.4826)
		(drill 0.254)
		(layers "F.Cu" "B.Cu")
		(net "GND")
	)
	(via
		(at 298.43984 -209.23504)
		(size 0.4826)
		(drill 0.254)
		(layers "F.Cu" "B.Cu")
		(net "GND")
	)
	(via
		(at 371.93474 -228.284278)
		(size 0.4064)
		(drill 0.2032)
		(layers "F.Cu" "B.Cu")
		(net "GND")
	)
	(via
		(at 392.67384 -143.551148)
		(size 0.508)
		(drill 0.254)
		(layers "F.Cu" "B.Cu")
		(net "GND")
	)
	(via
		(at 416.468052 -196.485002)
		(size 0.4826)
		(drill 0.254)
		(layers "F.Cu" "B.Cu")
		(net "GND")
	)
	(via
		(at 330.892658 -416.020504)
		(size 0.4572)
		(drill 0.254)
		(layers "F.Cu" "B.Cu")
		(net "GND")
	)
	(via
		(at 227.611178 -317.942468)
		(size 0.508)
		(drill 0.254)
		(layers "F.Cu" "B.Cu")
		(net "GND")
	)
	(via
		(at 328.877168 -334.57388)
		(size 0.49022)
		(drill 0.254)
		(layers "F.Cu" "B.Cu")
		(net "GND")
	)
	(via
		(at 32.695896 -234.73537)
		(size 0.4826)
		(drill 0.254)
		(layers "F.Cu" "B.Cu")
		(net "GND")
	)
	(via
		(at 416.468052 -268.735048)
		(size 0.4826)
		(drill 0.254)
		(layers "F.Cu" "B.Cu")
		(net "GND")
	)
	(via
		(at 384.924808 -261.12597)
		(size 0.4064)
		(drill 0.2032)
		(layers "F.Cu" "B.Cu")
		(net "GND")
	)
	(via
		(at 43.093894 -17.61236)
		(size 0.508)
		(drill 0.254)
		(layers "F.Cu" "B.Cu")
		(net "GND")
	)
	(via
		(at 47.784004 -289.135312)
		(size 0.4826)
		(drill 0.254)
		(layers "F.Cu" "B.Cu")
		(net "GND")
	)
	(via
		(at 27.545792 -7.215124)
		(size 0.508)
		(drill 0.254)
		(layers "F.Cu" "B.Cu")
		(net "GND")
	)
	(via
		(at 318.365124 -333.845154)
		(size 0.49022)
		(drill 0.254)
		(layers "F.Cu" "B.Cu")
		(net "GND")
	)
	(via
		(at 388.34949 -430.147222)
		(size 0.4572)
		(drill 0.2032)
		(layers "F.Cu" "B.Cu")
		(net "GND")
	)
	(via
		(at 278.335486 -339.807296)
		(size 0.508)
		(drill 0.254)
		(layers "F.Cu" "B.Cu")
		(net "GND")
	)
	(via
		(at 394.349478 -425.547282)
		(size 0.4572)
		(drill 0.2032)
		(layers "F.Cu" "B.Cu")
		(net "GND")
	)
	(via
		(at 118.723664 -438.101232)
		(size 0.508)
		(drill 0.254)
		(layers "F.Cu" "B.Cu")
		(net "GND")
	)
	(via
		(at 239.014 -281.421078)
		(size 0.508)
		(drill 0.254)
		(layers "F.Cu" "B.Cu")
		(net "GND")
	)
	(via
		(at 371.075204 -258.830064)
		(size 0.4826)
		(drill 0.254)
		(layers "F.Cu" "B.Cu")
		(net "GND")
	)
	(via
		(at 375.99493 -294.335962)
		(size 0.4064)
		(drill 0.2032)
		(layers "F.Cu" "B.Cu")
		(net "GND")
	)
	(via
		(at 361.594908 -244.484144)
		(size 0.4064)
		(drill 0.2032)
		(layers "F.Cu" "B.Cu")
		(net "GND")
	)
	(via
		(at 338.012532 -136.004046)
		(size 0.508)
		(drill 0.254)
		(layers "F.Cu" "B.Cu")
		(net "GND")
	)
	(via
		(at 381.334772 -241.24412)
		(size 0.4064)
		(drill 0.2032)
		(layers "F.Cu" "B.Cu")
		(net "GND")
	)
	(via
		(at 81.378044 -407.00452)
		(size 0.4064)
		(drill 0.2032)
		(layers "F.Cu" "B.Cu")
		(net "GND")
	)
	(via
		(at 341.390986 -235.574078)
		(size 0.4064)
		(drill 0.2032)
		(layers "F.Cu" "B.Cu")
		(net "GND")
	)
	(via
		(at 18.87855 -386.918962)
		(size 0.49022)
		(drill 0.254)
		(layers "F.Cu" "B.Cu")
		(net "GND")
	)
	(via
		(at 325.052944 -274.630134)
		(size 0.4064)
		(drill 0.2032)
		(layers "F.Cu" "B.Cu")
		(net "GND")
	)
	(via
		(at 197.3199 -227.935282)
		(size 0.4826)
		(drill 0.254)
		(layers "F.Cu" "B.Cu")
		(net "GND")
	)
	(via
		(at 355.961188 -246.104156)
		(size 0.4064)
		(drill 0.2032)
		(layers "F.Cu" "B.Cu")
		(net "GND")
	)
	(via
		(at 353.003104 -379.22073)
		(size 0.508)
		(drill 0.254)
		(layers "F.Cu" "B.Cu")
		(net "GND")
	)
	(via
		(at 113.48466 -274.08632)
		(size 0.4064)
		(drill 0.2032)
		(layers "F.Cu" "B.Cu")
		(net "GND")
	)
	(via
		(at 40.770302 -382.54432)
		(size 0.508)
		(drill 0.254)
		(layers "F.Cu" "B.Cu")
		(net "GND")
	)
	(via
		(at 299.06341 -344.77706)
		(size 0.49022)
		(drill 0.254)
		(layers "F.Cu" "B.Cu")
		(net "GND")
	)
	(via
		(at 25.152096 -266.185396)
		(size 0.4826)
		(drill 0.254)
		(layers "F.Cu" "B.Cu")
		(net "GND")
	)
	(via
		(at 316.590934 -398.542002)
		(size 0.4064)
		(drill 0.2032)
		(layers "F.Cu" "B.Cu")
		(net "GND")
	)
	(via
		(at 355.491034 -246.914162)
		(size 0.4064)
		(drill 0.2032)
		(layers "F.Cu" "B.Cu")
		(net "GND")
	)
	(via
		(at 126.814834 -255.824482)
		(size 0.4064)
		(drill 0.2032)
		(layers "F.Cu" "B.Cu")
		(net "GND")
	)
	(via
		(at 182.043578 -351.861374)
		(size 0.49022)
		(drill 0.254)
		(layers "F.Cu" "B.Cu")
		(net "GND")
	)
	(via
		(at 399.6817 -380.54153)
		(size 0.508)
		(drill 0.254)
		(layers "F.Cu" "B.Cu")
		(net "GND")
	)
	(via
		(at 136.574276 -382.237488)
		(size 0.508)
		(drill 0.254)
		(layers "F.Cu" "B.Cu")
		(net "GND")
	)
	(via
		(at 338.44611 -396.710662)
		(size 0.4064)
		(drill 0.2032)
		(layers "F.Cu" "B.Cu")
		(net "GND")
	)
	(via
		(at 274.821396 -439.90768)
		(size 0.508)
		(drill 0.254)
		(layers "F.Cu" "B.Cu")
		(net "GND")
	)
	(via
		(at 21.70811 -310.385206)
		(size 0.4826)
		(drill 0.254)
		(layers "F.Cu" "B.Cu")
		(net "GND")
	)
	(via
		(at 36.795964 -216.885266)
		(size 0.4826)
		(drill 0.254)
		(layers "F.Cu" "B.Cu")
		(net "GND")
	)
	(via
		(at 116.944648 -246.914416)
		(size 0.4064)
		(drill 0.2032)
		(layers "F.Cu" "B.Cu")
		(net "GND")
	)
	(via
		(at 386.504942 -246.914162)
		(size 0.4064)
		(drill 0.2032)
		(layers "F.Cu" "B.Cu")
		(net "GND")
	)
	(via
		(at 461.097376 -391.000742)
		(size 0.508)
		(drill 0.254)
		(layers "F.Cu" "B.Cu")
		(net "GND")
	)
	(via
		(at 88.982042 -370.83873)
		(size 0.508)
		(drill 0.254)
		(layers "F.Cu" "B.Cu")
		(net "GND")
	)
	(via
		(at 14.686788 -370.60505)
		(size 0.508)
		(drill 0.254)
		(layers "F.Cu" "B.Cu")
		(net "GND")
	)
	(via
		(at 68.766436 -406.34666)
		(size 0.4572)
		(drill 0.254)
		(layers "F.Cu" "B.Cu")
		(net "GND")
	)
	(via
		(at 383.21488 -255.824228)
		(size 0.4064)
		(drill 0.2032)
		(layers "F.Cu" "B.Cu")
		(net "GND")
	)
	(via
		(at 134.307834 -163.357052)
		(size 0.508)
		(drill 0.254)
		(layers "F.Cu" "B.Cu")
		(net "GND")
	)
	(via
		(at 130.574796 -228.284532)
		(size 0.4064)
		(drill 0.2032)
		(layers "F.Cu" "B.Cu")
		(net "GND")
	)
	(via
		(at 138.66749 -19.689064)
		(size 0.508)
		(drill 0.254)
		(layers "F.Cu" "B.Cu")
		(net "GND")
	)
	(via
		(at 147.042886 -263.290304)
		(size 0.4064)
		(drill 0.2032)
		(layers "F.Cu" "B.Cu")
		(net "GND")
	)
	(via
		(at 187.060078 -214.33536)
		(size 0.4826)
		(drill 0.254)
		(layers "F.Cu" "B.Cu")
		(net "GND")
	)
	(via
		(at 411.001718 -166.351712)
		(size 0.508)
		(drill 0.254)
		(layers "F.Cu" "B.Cu")
		(net "GND")
	)
	(via
		(at 47.784004 -309.535322)
		(size 0.4826)
		(drill 0.254)
		(layers "F.Cu" "B.Cu")
		(net "GND")
	)
	(via
		(at 313.062112 -392.999722)
		(size 0.4064)
		(drill 0.2032)
		(layers "F.Cu" "B.Cu")
		(net "GND")
	)
	(via
		(at 322.177156 -378.07773)
		(size 0.508)
		(drill 0.254)
		(layers "F.Cu" "B.Cu")
		(net "GND")
	)
	(via
		(at 399.349722 -427.851316)
		(size 0.4572)
		(drill 0.2032)
		(layers "F.Cu" "B.Cu")
		(net "GND")
	)
	(via
		(at 189.775846 -277.235412)
		(size 0.4826)
		(drill 0.254)
		(layers "F.Cu" "B.Cu")
		(net "GND")
	)
	(via
		(at 50.863754 -369.03533)
		(size 0.508)
		(drill 0.254)
		(layers "F.Cu" "B.Cu")
		(net "GND")
	)
	(via
		(at 338.101178 -249.34418)
		(size 0.4064)
		(drill 0.2032)
		(layers "F.Cu" "B.Cu")
		(net "GND")
	)
	(via
		(at 413.220662 -420.952168)
		(size 0.4064)
		(drill 0.2032)
		(layers "F.Cu" "B.Cu")
		(net "GND")
	)
	(via
		(at 116.944648 -229.094538)
		(size 0.4064)
		(drill 0.2032)
		(layers "F.Cu" "B.Cu")
		(net "GND")
	)
	(via
		(at 425.708318 -170.212512)
		(size 0.6604)
		(drill 0.3302)
		(layers "F.Cu" "B.Cu")
		(net "GND")
	)
	(via
		(at 389.79475 -231.524048)
		(size 0.4064)
		(drill 0.2032)
		(layers "F.Cu" "B.Cu")
		(net "GND")
	)
	(via
		(at 194.604132 -300.185328)
		(size 0.4826)
		(drill 0.254)
		(layers "F.Cu" "B.Cu")
		(net "GND")
	)
	(via
		(at 77.112876 -271.390364)
		(size 0.4064)
		(drill 0.2032)
		(layers "F.Cu" "B.Cu")
		(net "GND")
	)
	(via
		(at 20.348194 -12.37488)
		(size 0.508)
		(drill 0.254)
		(layers "F.Cu" "B.Cu")
		(net "GND")
	)
	(via
		(at 141.854682 -246.10441)
		(size 0.4064)
		(drill 0.2032)
		(layers "F.Cu" "B.Cu")
		(net "GND")
	)
	(via
		(at 140.274802 -286.23641)
		(size 0.4064)
		(drill 0.2032)
		(layers "F.Cu" "B.Cu")
		(net "GND")
	)
	(via
		(at 116.944648 -250.15444)
		(size 0.4064)
		(drill 0.2032)
		(layers "F.Cu" "B.Cu")
		(net "GND")
	)
	(via
		(at 312.513218 -416.020504)
		(size 0.4572)
		(drill 0.254)
		(layers "F.Cu" "B.Cu")
		(net "GND")
	)
	(via
		(at 347.33103 -282.186126)
		(size 0.4064)
		(drill 0.2032)
		(layers "F.Cu" "B.Cu")
		(net "GND")
	)
	(via
		(at 68.915534 -335.566004)
		(size 0.49022)
		(drill 0.254)
		(layers "F.Cu" "B.Cu")
		(net "GND")
	)
	(via
		(at 14.406626 -134.90448)
		(size 0.508)
		(drill 0.254)
		(layers "F.Cu" "B.Cu")
		(net "GND")
	)
	(via
		(at 363.474762 -242.864132)
		(size 0.4064)
		(drill 0.2032)
		(layers "F.Cu" "B.Cu")
		(net "GND")
	)
	(via
		(at 313.670696 -377.41733)
		(size 0.508)
		(drill 0.254)
		(layers "F.Cu" "B.Cu")
		(net "GND")
	)
	(via
		(at 235.678726 -334.623918)
		(size 0.508)
		(drill 0.254)
		(layers "F.Cu" "B.Cu")
		(net "GND")
	)
	(via
		(at 155.17749 -104.138984)
		(size 0.508)
		(drill 0.254)
		(layers "F.Cu" "B.Cu")
		(net "GND")
	)
	(via
		(at 128.349756 -437.34736)
		(size 0.4572)
		(drill 0.2032)
		(layers "F.Cu" "B.Cu")
		(net "GND")
	)
	(via
		(at 373.398542 -420.952168)
		(size 0.4064)
		(drill 0.2032)
		(layers "F.Cu" "B.Cu")
		(net "GND")
	)
	(via
		(at 175.528732 -33.377632)
		(size 0.508)
		(drill 0.254)
		(layers "F.Cu" "B.Cu")
		(net "GND")
	)
	(via
		(at 392.349482 -430.147222)
		(size 0.4572)
		(drill 0.2032)
		(layers "F.Cu" "B.Cu")
		(net "GND")
	)
	(via
		(at 338.571078 -224.234248)
		(size 0.4064)
		(drill 0.2032)
		(layers "F.Cu" "B.Cu")
		(net "GND")
	)
	(via
		(at 329.249532 -433.747164)
		(size 0.4572)
		(drill 0.2032)
		(layers "F.Cu" "B.Cu")
		(net "GND")
	)
	(via
		(at 61.615574 -348.709488)
		(size 0.49022)
		(drill 0.254)
		(layers "F.Cu" "B.Cu")
		(net "GND")
	)
	(via
		(at 141.992858 -406.370536)
		(size 0.4572)
		(drill 0.254)
		(layers "F.Cu" "B.Cu")
		(net "GND")
	)
	(via
		(at 138.09472 -223.424496)
		(size 0.4064)
		(drill 0.2032)
		(layers "F.Cu" "B.Cu")
		(net "GND")
	)
	(via
		(at 435.000146 -247.485154)
		(size 0.4826)
		(drill 0.254)
		(layers "F.Cu" "B.Cu")
		(net "GND")
	)
	(via
		(at 144.905222 -148.312124)
		(size 0.6604)
		(drill 0.3302)
		(layers "F.Cu" "B.Cu")
		(net "GND")
	)
	(via
		(at 394.68298 -249.610118)
		(size 0.4064)
		(drill 0.2032)
		(layers "F.Cu" "B.Cu")
		(net "GND")
	)
	(via
		(at 403.349714 -429.147224)
		(size 0.4572)
		(drill 0.2032)
		(layers "F.Cu" "B.Cu")
		(net "GND")
	)
	(via
		(at 100.971096 -246.914416)
		(size 0.4064)
		(drill 0.2032)
		(layers "F.Cu" "B.Cu")
		(net "GND")
	)
	(via
		(at 302.150526 -295.510204)
		(size 0.4826)
		(drill 0.254)
		(layers "F.Cu" "B.Cu")
		(net "GND")
	)
	(via
		(at 321.249548 -437.34736)
		(size 0.4572)
		(drill 0.2032)
		(layers "F.Cu" "B.Cu")
		(net "GND")
	)
	(via
		(at 100.946204 -29.51861)
		(size 0.508)
		(drill 0.254)
		(layers "F.Cu" "B.Cu")
		(net "GND")
	)
	(via
		(at 418.17671 -414.752536)
		(size 0.4572)
		(drill 0.254)
		(layers "F.Cu" "B.Cu")
		(net "GND")
	)
	(via
		(at 51.884072 -280.635202)
		(size 0.4826)
		(drill 0.254)
		(layers "F.Cu" "B.Cu")
		(net "GND")
	)
	(via
		(at 90.481912 -411.936184)
		(size 0.4572)
		(drill 0.254)
		(layers "F.Cu" "B.Cu")
		(net "GND")
	)
	(via
		(at 169.859706 -11.496548)
		(size 0.508)
		(drill 0.254)
		(layers "F.Cu" "B.Cu")
		(net "GND")
	)
	(via
		(at 163.178744 -343.122758)
		(size 0.508)
		(drill 0.254)
		(layers "F.Cu" "B.Cu")
		(net "GND")
	)
	(via
		(at 450.088 -236.435138)
		(size 0.4826)
		(drill 0.254)
		(layers "F.Cu" "B.Cu")
		(net "GND")
	)
	(via
		(at 277.192232 -253.435104)
		(size 0.4826)
		(drill 0.254)
		(layers "F.Cu" "B.Cu")
		(net "GND")
	)
	(via
		(at 344.511122 -272.466054)
		(size 0.4064)
		(drill 0.2032)
		(layers "F.Cu" "B.Cu")
		(net "GND")
	)
	(via
		(at 274.545806 -348.704662)
		(size 0.49022)
		(drill 0.254)
		(layers "F.Cu" "B.Cu")
		(net "GND")
	)
	(via
		(at 86.401148 -223.410272)
		(size 0.4064)
		(drill 0.2032)
		(layers "F.Cu" "B.Cu")
		(net "GND")
	)
	(via
		(at 409.349702 -433.747164)
		(size 0.4572)
		(drill 0.2032)
		(layers "F.Cu" "B.Cu")
		(net "GND")
	)
	(via
		(at 27.867864 -293.38524)
		(size 0.4826)
		(drill 0.254)
		(layers "F.Cu" "B.Cu")
		(net "GND")
	)
	(via
		(at 363.474762 -229.904036)
		(size 0.4064)
		(drill 0.2032)
		(layers "F.Cu" "B.Cu")
		(net "GND")
	)
	(via
		(at 180.836316 -330.211684)
		(size 0.508)
		(drill 0.254)
		(layers "F.Cu" "B.Cu")
		(net "GND")
	)
	(via
		(at 53.268372 -12.37488)
		(size 0.508)
		(drill 0.254)
		(layers "F.Cu" "B.Cu")
		(net "GND")
	)
	(via
		(at 427.631098 -364.08995)
		(size 0.508)
		(drill 0.254)
		(layers "F.Cu" "B.Cu")
		(net "GND")
	)
	(via
		(at 334.8482 -162.56)
		(size 0.508)
		(drill 0.254)
		(layers "F.Cu" "B.Cu")
		(net "GND")
	)
	(via
		(at 416.468052 -213.484968)
		(size 0.4826)
		(drill 0.254)
		(layers "F.Cu" "B.Cu")
		(net "GND")
	)
	(via
		(at 90.461084 -281.376374)
		(size 0.4064)
		(drill 0.2032)
		(layers "F.Cu" "B.Cu")
		(net "GND")
	)
	(via
		(at 105.490772 -262.180324)
		(size 0.4826)
		(drill 0.254)
		(layers "F.Cu" "B.Cu")
		(net "GND")
	)
	(via
		(at 290.377626 -339.809836)
		(size 0.508)
		(drill 0.254)
		(layers "F.Cu" "B.Cu")
		(net "GND")
	)
	(via
		(at 84.249768 -426.69968)
		(size 0.4572)
		(drill 0.2032)
		(layers "F.Cu" "B.Cu")
		(net "GND")
	)
	(via
		(at 107.538266 -408.34945)
		(size 0.508)
		(drill 0.254)
		(layers "F.Cu" "B.Cu")
		(net "GND")
	)
	(via
		(at 125.704854 -282.18638)
		(size 0.4064)
		(drill 0.2032)
		(layers "F.Cu" "B.Cu")
		(net "GND")
	)
	(via
		(at 333.230982 -262.745982)
		(size 0.4064)
		(drill 0.2032)
		(layers "F.Cu" "B.Cu")
		(net "GND")
	)
	(via
		(at 137.45464 -279.756362)
		(size 0.4064)
		(drill 0.2032)
		(layers "F.Cu" "B.Cu")
		(net "GND")
	)
	(via
		(at 206.248 -250.035314)
		(size 0.4826)
		(drill 0.254)
		(layers "F.Cu" "B.Cu")
		(net "GND")
	)
	(via
		(at 313.118246 -396.710662)
		(size 0.4064)
		(drill 0.2032)
		(layers "F.Cu" "B.Cu")
		(net "GND")
	)
	(via
		(at 60.998354 -347.287088)
		(size 0.49022)
		(drill 0.254)
		(layers "F.Cu" "B.Cu")
		(net "GND")
	)
	(via
		(at 134.745222 -159.742124)
		(size 0.6604)
		(drill 0.3302)
		(layers "F.Cu" "B.Cu")
		(net "GND")
	)
	(via
		(at 125.404626 -240.434368)
		(size 0.4064)
		(drill 0.2032)
		(layers "F.Cu" "B.Cu")
		(net "GND")
	)
	(via
		(at 115.534694 -241.244374)
		(size 0.4064)
		(drill 0.2032)
		(layers "F.Cu" "B.Cu")
		(net "GND")
	)
	(via
		(at 90.16111 -233.144314)
		(size 0.4064)
		(drill 0.2032)
		(layers "F.Cu" "B.Cu")
		(net "GND")
	)
	(via
		(at 269.648178 -250.03506)
		(size 0.4826)
		(drill 0.254)
		(layers "F.Cu" "B.Cu")
		(net "GND")
	)
	(via
		(at 59.428126 -222.835216)
		(size 0.4826)
		(drill 0.254)
		(layers "F.Cu" "B.Cu")
		(net "GND")
	)
	(via
		(at 391.866374 -417.778184)
		(size 0.4572)
		(drill 0.254)
		(layers "F.Cu" "B.Cu")
		(net "GND")
	)
	(via
		(at 124.90196 -335.80578)
		(size 0.6604)
		(drill 0.3302)
		(layers "F.Cu" "B.Cu")
		(net "GND")
	)
	(via
		(at 369.114832 -231.524048)
		(size 0.4064)
		(drill 0.2032)
		(layers "F.Cu" "B.Cu")
		(net "GND")
	)
	(via
		(at 327.761092 -236.384084)
		(size 0.4064)
		(drill 0.2032)
		(layers "F.Cu" "B.Cu")
		(net "GND")
	)
	(via
		(at 280.635964 -214.335106)
		(size 0.4826)
		(drill 0.254)
		(layers "F.Cu" "B.Cu")
		(net "GND")
	)
	(via
		(at 296.770044 -384.175)
		(size 0.508)
		(drill 0.254)
		(layers "F.Cu" "B.Cu")
		(net "GND")
	)
	(via
		(at 25.152096 -223.685354)
		(size 0.4826)
		(drill 0.254)
		(layers "F.Cu" "B.Cu")
		(net "GND")
	)
	(via
		(at 86.80704 -355.968046)
		(size 0.508)
		(drill 0.254)
		(layers "F.Cu" "B.Cu")
		(net "GND")
	)
	(via
		(at 390.050274 -183.14289)
		(size 0.49022)
		(drill 0.254)
		(layers "F.Cu" "B.Cu")
		(net "GND")
	)
	(via
		(at 306.622958 -169.70121)
		(size 0.508)
		(drill 0.254)
		(layers "F.Cu" "B.Cu")
		(net "GND")
	)
	(via
		(at 349.689674 -162.28949)
		(size 0.49022)
		(drill 0.254)
		(layers "F.Cu" "B.Cu")
		(net "GND")
	)
	(via
		(at 306.216304 -402.309838)
		(size 0.4572)
		(drill 0.254)
		(layers "F.Cu" "B.Cu")
		(net "GND")
	)
	(via
		(at 18.992342 -221.985332)
		(size 0.4826)
		(drill 0.254)
		(layers "F.Cu" "B.Cu")
		(net "GND")
	)
	(via
		(at 319.562734 -341.042244)
		(size 0.508)
		(drill 0.254)
		(layers "F.Cu" "B.Cu")
		(net "GND")
	)
	(via
		(at 201.36358 -362.27258)
		(size 0.6604)
		(drill 0.3302)
		(layers "F.Cu" "B.Cu")
		(net "GND")
	)
	(via
		(at 412.367984 -292.535102)
		(size 0.4826)
		(drill 0.254)
		(layers "F.Cu" "B.Cu")
		(net "GND")
	)
	(via
		(at 160.372298 -407.638504)
		(size 0.4572)
		(drill 0.254)
		(layers "F.Cu" "B.Cu")
		(net "GND")
	)
	(via
		(at 171.97197 -197.335394)
		(size 0.4826)
		(drill 0.254)
		(layers "F.Cu" "B.Cu")
		(net "GND")
	)
	(via
		(at 42.21988 -111.36884)
		(size 0.508)
		(drill 0.254)
		(layers "F.Cu" "B.Cu")
		(net "GND")
	)
	(via
		(at 105.500932 -278.13635)
		(size 0.4064)
		(drill 0.2032)
		(layers "F.Cu" "B.Cu")
		(net "GND")
	)
	(via
		(at 308.744112 -43.78833)
		(size 0.508)
		(drill 0.254)
		(layers "F.Cu" "B.Cu")
		(net "GND")
	)
	(via
		(at 86.97595 -189.552326)
		(size 0.508)
		(drill 0.254)
		(layers "F.Cu" "B.Cu")
		(net "GND")
	)
	(via
		(at 295.724072 -266.185142)
		(size 0.4826)
		(drill 0.254)
		(layers "F.Cu" "B.Cu")
		(net "GND")
	)
	(via
		(at 107.550966 -227.474526)
		(size 0.4064)
		(drill 0.2032)
		(layers "F.Cu" "B.Cu")
		(net "GND")
	)
	(via
		(at 386.804916 -291.905944)
		(size 0.4064)
		(drill 0.2032)
		(layers "F.Cu" "B.Cu")
		(net "GND")
	)
	(via
		(at 49.016666 -391.830814)
		(size 0.4064)
		(drill 0.2032)
		(layers "F.Cu" "B.Cu")
		(net "GND")
	)
	(via
		(at 375.224802 -237.19409)
		(size 0.4064)
		(drill 0.2032)
		(layers "F.Cu" "B.Cu")
		(net "GND")
	)
	(via
		(at 184.732168 -117.442742)
		(size 0.4572)
		(drill 0.254)
		(layers "F.Cu" "B.Cu")
		(net "GND")
	)
	(via
		(at 375.524776 -278.946102)
		(size 0.4064)
		(drill 0.2032)
		(layers "F.Cu" "B.Cu")
		(net "GND")
	)
	(via
		(at 359.272332 -258.795012)
		(size 0.4826)
		(drill 0.254)
		(layers "F.Cu" "B.Cu")
		(net "GND")
	)
	(via
		(at 39.12235 -202.010264)
		(size 0.4826)
		(drill 0.254)
		(layers "F.Cu" "B.Cu")
		(net "GND")
	)
	(via
		(at 351.406968 -340.500462)
		(size 0.49022)
		(drill 0.254)
		(layers "F.Cu" "B.Cu")
		(net "GND")
	)
	(via
		(at 300.571916 -19.73199)
		(size 0.508)
		(drill 0.254)
		(layers "F.Cu" "B.Cu")
		(net "GND")
	)
	(via
		(at 237.920022 -371.431312)
		(size 0.508)
		(drill 0.254)
		(layers "F.Cu" "B.Cu")
		(net "GND")
	)
	(via
		(at 37.560758 -344.781886)
		(size 0.49022)
		(drill 0.254)
		(layers "F.Cu" "B.Cu")
		(net "GND")
	)
	(via
		(at 198.7042 -253.435358)
		(size 0.4826)
		(drill 0.254)
		(layers "F.Cu" "B.Cu")
		(net "GND")
	)
	(via
		(at 112.918494 -335.691988)
		(size 0.508)
		(drill 0.254)
		(layers "F.Cu" "B.Cu")
		(net "GND")
	)
	(via
		(at 32.34817 -364.125256)
		(size 0.508)
		(drill 0.254)
		(layers "F.Cu" "B.Cu")
		(net "GND")
	)
	(via
		(at 57.018174 -336.910172)
		(size 0.508)
		(drill 0.254)
		(layers "F.Cu" "B.Cu")
		(net "GND")
	)
	(via
		(at 228.092 -282.533344)
		(size 0.508)
		(drill 0.254)
		(layers "F.Cu" "B.Cu")
		(net "GND")
	)
	(via
		(at 131.98475 -230.71455)
		(size 0.4064)
		(drill 0.2032)
		(layers "F.Cu" "B.Cu")
		(net "GND")
	)
	(via
		(at 388.384796 -245.29415)
		(size 0.4064)
		(drill 0.2032)
		(layers "F.Cu" "B.Cu")
		(net "GND")
	)
	(via
		(at 131.98475 -246.914416)
		(size 0.4064)
		(drill 0.2032)
		(layers "F.Cu" "B.Cu")
		(net "GND")
	)
	(via
		(at 451.739 -46.68266)
		(size 0.508)
		(drill 0.254)
		(layers "F.Cu" "B.Cu")
		(net "GND")
	)
	(via
		(at 333.955898 -414.752536)
		(size 0.4572)
		(drill 0.254)
		(layers "F.Cu" "B.Cu")
		(net "GND")
	)
	(via
		(at 354.34524 -255.530096)
		(size 0.4826)
		(drill 0.254)
		(layers "F.Cu" "B.Cu")
		(net "GND")
	)
	(via
		(at 139.974828 -229.90429)
		(size 0.4064)
		(drill 0.2032)
		(layers "F.Cu" "B.Cu")
		(net "GND")
	)
	(via
		(at 395.092174 -55.454804)
		(size 0.508)
		(drill 0.254)
		(layers "F.Cu" "B.Cu")
		(net "GND")
	)
	(via
		(at 321.249548 -438.499758)
		(size 0.4572)
		(drill 0.2032)
		(layers "F.Cu" "B.Cu")
		(net "GND")
	)
	(via
		(at 107.870244 -381.3302)
		(size 0.508)
		(drill 0.254)
		(layers "F.Cu" "B.Cu")
		(net "GND")
	)
	(via
		(at 270.312134 -422.332404)
		(size 0.508)
		(drill 0.254)
		(layers "F.Cu" "B.Cu")
		(net "GND")
	)
	(via
		(at 381.634746 -261.935976)
		(size 0.4064)
		(drill 0.2032)
		(layers "F.Cu" "B.Cu")
		(net "GND")
	)
	(via
		(at 368.944906 -277.32609)
		(size 0.4064)
		(drill 0.2032)
		(layers "F.Cu" "B.Cu")
		(net "GND")
	)
	(via
		(at 292.280086 -288.285174)
		(size 0.4826)
		(drill 0.254)
		(layers "F.Cu" "B.Cu")
		(net "GND")
	)
	(via
		(at 137.992358 -22.512528)
		(size 0.508)
		(drill 0.254)
		(layers "F.Cu" "B.Cu")
		(net "GND")
	)
	(via
		(at 91.906344 -386.449062)
		(size 0.4064)
		(drill 0.2032)
		(layers "F.Cu" "B.Cu")
		(net "GND")
	)
	(via
		(at 416.023298 -163.201858)
		(size 0.49022)
		(drill 0.254)
		(layers "F.Cu" "B.Cu")
		(net "GND")
	)
	(via
		(at 113.48466 -272.466308)
		(size 0.4064)
		(drill 0.2032)
		(layers "F.Cu" "B.Cu")
		(net "GND")
	)
	(via
		(at 291.544502 -125.049026)
		(size 0.508)
		(drill 0.254)
		(layers "F.Cu" "B.Cu")
		(net "GND")
	)
	(via
		(at 58.043826 -312.085228)
		(size 0.4826)
		(drill 0.254)
		(layers "F.Cu" "B.Cu")
		(net "GND")
	)
	(via
		(at 193.002916 -331.456284)
		(size 0.508)
		(drill 0.254)
		(layers "F.Cu" "B.Cu")
		(net "GND")
	)
	(via
		(at 273.092164 -283.185108)
		(size 0.4826)
		(drill 0.254)
		(layers "F.Cu" "B.Cu")
		(net "GND")
	)
	(via
		(at 277.192232 -216.885012)
		(size 0.4826)
		(drill 0.254)
		(layers "F.Cu" "B.Cu")
		(net "GND")
	)
	(via
		(at 135.866378 -410.664152)
		(size 0.4572)
		(drill 0.254)
		(layers "F.Cu" "B.Cu")
		(net "GND")
	)
	(via
		(at 407.044144 -400.212814)
		(size 0.4064)
		(drill 0.2032)
		(layers "F.Cu" "B.Cu")
		(net "GND")
	)
	(via
		(at 148.24202 -318.78905)
		(size 0.508)
		(drill 0.254)
		(layers "F.Cu" "B.Cu")
		(net "GND")
	)
	(via
		(at 370.524786 -235.574078)
		(size 0.4064)
		(drill 0.2032)
		(layers "F.Cu" "B.Cu")
		(net "GND")
	)
	(via
		(at 20.32381 -239.835436)
		(size 0.4826)
		(drill 0.254)
		(layers "F.Cu" "B.Cu")
		(net "GND")
	)
	(via
		(at 292.280086 -310.384952)
		(size 0.4826)
		(drill 0.254)
		(layers "F.Cu" "B.Cu")
		(net "GND")
	)
	(via
		(at 75.652122 -334.071722)
		(size 0.49022)
		(drill 0.254)
		(layers "F.Cu" "B.Cu")
		(net "GND")
	)
	(via
		(at 104.731058 -246.914416)
		(size 0.4064)
		(drill 0.2032)
		(layers "F.Cu" "B.Cu")
		(net "GND")
	)
	(via
		(at 192.277746 -229.210362)
		(size 0.4826)
		(drill 0.254)
		(layers "F.Cu" "B.Cu")
		(net "GND")
	)
	(via
		(at 128.524762 -269.226284)
		(size 0.4064)
		(drill 0.2032)
		(layers "F.Cu" "B.Cu")
		(net "GND")
	)
	(via
		(at 297.108372 -210.085178)
		(size 0.4826)
		(drill 0.254)
		(layers "F.Cu" "B.Cu")
		(net "GND")
	)
	(via
		(at 121.644664 -232.334308)
		(size 0.4064)
		(drill 0.2032)
		(layers "F.Cu" "B.Cu")
		(net "GND")
	)
	(via
		(at 183.616092 -224.535238)
		(size 0.4826)
		(drill 0.254)
		(layers "F.Cu" "B.Cu")
		(net "GND")
	)
	(via
		(at 155.553156 -57.668414)
		(size 0.508)
		(drill 0.254)
		(layers "F.Cu" "B.Cu")
		(net "GND")
	)
	(via
		(at 140.397992 -377.00712)
		(size 0.508)
		(drill 0.254)
		(layers "F.Cu" "B.Cu")
		(net "GND")
	)
	(via
		(at 344.681048 -246.104156)
		(size 0.4064)
		(drill 0.2032)
		(layers "F.Cu" "B.Cu")
		(net "GND")
	)
	(via
		(at 292.280086 -204.134974)
		(size 0.4826)
		(drill 0.254)
		(layers "F.Cu" "B.Cu")
		(net "GND")
	)
	(via
		(at 401.056094 -414.752536)
		(size 0.4572)
		(drill 0.254)
		(layers "F.Cu" "B.Cu")
		(net "GND")
	)
	(via
		(at 277.192232 -271.284954)
		(size 0.4826)
		(drill 0.254)
		(layers "F.Cu" "B.Cu")
		(net "GND")
	)
	(via
		(at 26.536396 -275.53539)
		(size 0.4826)
		(drill 0.254)
		(layers "F.Cu" "B.Cu")
		(net "GND")
	)
	(via
		(at 87.757 -145.90141)
		(size 0.508)
		(drill 0.254)
		(layers "F.Cu" "B.Cu")
		(net "GND")
	)
	(via
		(at 197.869556 -341.188548)
		(size 0.508)
		(drill 0.254)
		(layers "F.Cu" "B.Cu")
		(net "GND")
	)
	(via
		(at 388.85495 -225.044254)
		(size 0.4064)
		(drill 0.2032)
		(layers "F.Cu" "B.Cu")
		(net "GND")
	)
	(via
		(at 187.5917 -430.07661)
		(size 0.508)
		(drill 0.254)
		(layers "F.Cu" "B.Cu")
		(net "GND")
	)
	(via
		(at 144.034764 -270.03629)
		(size 0.4064)
		(drill 0.2032)
		(layers "F.Cu" "B.Cu")
		(net "GND")
	)
	(via
		(at 29.252164 -271.285208)
		(size 0.4826)
		(drill 0.254)
		(layers "F.Cu" "B.Cu")
		(net "GND")
	)
	(via
		(at 383.0447 -269.22603)
		(size 0.4064)
		(drill 0.2032)
		(layers "F.Cu" "B.Cu")
		(net "GND")
	)
	(via
		(at 40.23995 -245.785386)
		(size 0.4826)
		(drill 0.254)
		(layers "F.Cu" "B.Cu")
		(net "GND")
	)
	(via
		(at 446.644268 -243.234972)
		(size 0.4826)
		(drill 0.254)
		(layers "F.Cu" "B.Cu")
		(net "GND")
	)
	(via
		(at 428.840392 -306.135024)
		(size 0.4826)
		(drill 0.254)
		(layers "F.Cu" "B.Cu")
		(net "GND")
	)
	(via
		(at 196.359526 -349.377)
		(size 0.508)
		(drill 0.254)
		(layers "F.Cu" "B.Cu")
		(net "GND")
	)
	(via
		(at 142.154656 -263.556242)
		(size 0.4064)
		(drill 0.2032)
		(layers "F.Cu" "B.Cu")
		(net "GND")
	)
	(via
		(at 46.666404 -211.360258)
		(size 0.4826)
		(drill 0.254)
		(layers "F.Cu" "B.Cu")
		(net "GND")
	)
	(via
		(at 63.24981 -429.147224)
		(size 0.4572)
		(drill 0.2032)
		(layers "F.Cu" "B.Cu")
		(net "GND")
	)
	(via
		(at 415.018982 -398.542002)
		(size 0.4064)
		(drill 0.2032)
		(layers "F.Cu" "B.Cu")
		(net "GND")
	)
	(via
		(at 431.989992 -349.990156)
		(size 0.49022)
		(drill 0.254)
		(layers "F.Cu" "B.Cu")
		(net "GND")
	)
	(via
		(at 123.994672 -241.244374)
		(size 0.4064)
		(drill 0.2032)
		(layers "F.Cu" "B.Cu")
		(net "GND")
	)
	(via
		(at 184.733692 -238.560356)
		(size 0.4826)
		(drill 0.254)
		(layers "F.Cu" "B.Cu")
		(net "GND")
	)
	(via
		(at 91.871038 -272.466308)
		(size 0.4064)
		(drill 0.2032)
		(layers "F.Cu" "B.Cu")
		(net "GND")
	)
	(via
		(at 366.275874 -179.710588)
		(size 0.49022)
		(drill 0.254)
		(layers "F.Cu" "B.Cu")
		(net "GND")
	)
	(via
		(at 99.561142 -233.144314)
		(size 0.4064)
		(drill 0.2032)
		(layers "F.Cu" "B.Cu")
		(net "GND")
	)
	(via
		(at 41.778174 -339.804502)
		(size 0.508)
		(drill 0.254)
		(layers "F.Cu" "B.Cu")
		(net "GND")
	)
	(via
		(at 105.200958 -239.624362)
		(size 0.4064)
		(drill 0.2032)
		(layers "F.Cu" "B.Cu")
		(net "GND")
	)
	(via
		(at 171.336208 -342.769952)
		(size 0.508)
		(drill 0.254)
		(layers "F.Cu" "B.Cu")
		(net "GND")
	)
	(via
		(at 335.487518 -413.480504)
		(size 0.4572)
		(drill 0.254)
		(layers "F.Cu" "B.Cu")
		(net "GND")
	)
	(via
		(at 393.384786 -285.42615)
		(size 0.4064)
		(drill 0.2032)
		(layers "F.Cu" "B.Cu")
		(net "GND")
	)
	(via
		(at 21.70811 -301.035212)
		(size 0.4826)
		(drill 0.254)
		(layers "F.Cu" "B.Cu")
		(net "GND")
	)
	(via
		(at 431.568098 -330.46289)
		(size 0.508)
		(drill 0.254)
		(layers "F.Cu" "B.Cu")
		(net "GND")
	)
	(via
		(at 309.813452 -439.676794)
		(size 0.508)
		(drill 0.254)
		(layers "F.Cu" "B.Cu")
		(net "GND")
	)
	(via
		(at 341.886794 -419.046152)
		(size 0.4572)
		(drill 0.254)
		(layers "F.Cu" "B.Cu")
		(net "GND")
	)
	(via
		(at 156.61894 -390.160002)
		(size 0.4064)
		(drill 0.2032)
		(layers "F.Cu" "B.Cu")
		(net "GND")
	)
	(via
		(at 440.000644 -7.164832)
		(size 0.508)
		(drill 0.254)
		(layers "F.Cu" "B.Cu")
		(net "GND")
	)
	(via
		(at 339.943948 -400.212814)
		(size 0.4064)
		(drill 0.2032)
		(layers "F.Cu" "B.Cu")
		(net "GND")
	)
	(via
		(at 344.955876 -72.884792)
		(size 0.508)
		(drill 0.254)
		(layers "F.Cu" "B.Cu")
		(net "GND")
	)
	(via
		(at 234.41152 -292.041326)
		(size 0.508)
		(drill 0.254)
		(layers "F.Cu" "B.Cu")
		(net "GND")
	)
	(via
		(at 87.81415 -185.259726)
		(size 0.508)
		(drill 0.254)
		(layers "F.Cu" "B.Cu")
		(net "GND")
	)
	(via
		(at 378.344938 -282.186126)
		(size 0.4064)
		(drill 0.2032)
		(layers "F.Cu" "B.Cu")
		(net "GND")
	)
	(via
		(at 140.461238 -403.830536)
		(size 0.4572)
		(drill 0.254)
		(layers "F.Cu" "B.Cu")
		(net "GND")
	)
	(via
		(at 272.728182 -352.602292)
		(size 0.508)
		(drill 0.254)
		(layers "F.Cu" "B.Cu")
		(net "GND")
	)
	(via
		(at 191.160146 -299.335444)
		(size 0.4826)
		(drill 0.254)
		(layers "F.Cu" "B.Cu")
		(net "GND")
	)
	(via
		(at 329.249532 -436.051198)
		(size 0.4572)
		(drill 0.2032)
		(layers "F.Cu" "B.Cu")
		(net "GND")
	)
	(via
		(at 143.264636 -248.534428)
		(size 0.4064)
		(drill 0.2032)
		(layers "F.Cu" "B.Cu")
		(net "GND")
	)
	(via
		(at 259.562346 -15.64386)
		(size 0.508)
		(drill 0.254)
		(layers "F.Cu" "B.Cu")
		(net "GND")
	)
	(via
		(at 136.684766 -233.95432)
		(size 0.4064)
		(drill 0.2032)
		(layers "F.Cu" "B.Cu")
		(net "GND")
	)
	(via
		(at 95.64624 -388.328662)
		(size 0.4064)
		(drill 0.2032)
		(layers "F.Cu" "B.Cu")
		(net "GND")
	)
	(via
		(at 346.84589 -396.710662)
		(size 0.4064)
		(drill 0.2032)
		(layers "F.Cu" "B.Cu")
		(net "GND")
	)
	(via
		(at 341.390986 -248.534174)
		(size 0.4064)
		(drill 0.2032)
		(layers "F.Cu" "B.Cu")
		(net "GND")
	)
	(via
		(at 86.481158 -333.039212)
		(size 0.49022)
		(drill 0.254)
		(layers "F.Cu" "B.Cu")
		(net "GND")
	)
	(via
		(at 382.491234 -398.542002)
		(size 0.4064)
		(drill 0.2032)
		(layers "F.Cu" "B.Cu")
		(net "GND")
	)
	(via
		(at 105.500932 -289.47618)
		(size 0.4064)
		(drill 0.2032)
		(layers "F.Cu" "B.Cu")
		(net "GND")
	)
	(via
		(at 355.791008 -270.846042)
		(size 0.4064)
		(drill 0.2032)
		(layers "F.Cu" "B.Cu")
		(net "GND")
	)
	(via
		(at 127.114808 -291.096192)
		(size 0.4064)
		(drill 0.2032)
		(layers "F.Cu" "B.Cu")
		(net "GND")
	)
	(via
		(at 405.844248 -400.212814)
		(size 0.4064)
		(drill 0.2032)
		(layers "F.Cu" "B.Cu")
		(net "GND")
	)
	(via
		(at 29.252164 -198.185278)
		(size 0.4826)
		(drill 0.254)
		(layers "F.Cu" "B.Cu")
		(net "GND")
	)
	(via
		(at 58.045096 -403.830536)
		(size 0.4572)
		(drill 0.254)
		(layers "F.Cu" "B.Cu")
		(net "GND")
	)
	(via
		(at 321.702938 -416.020504)
		(size 0.4572)
		(drill 0.254)
		(layers "F.Cu" "B.Cu")
		(net "GND")
	)
	(via
		(at 125.253496 -371.49913)
		(size 0.508)
		(drill 0.254)
		(layers "F.Cu" "B.Cu")
		(net "GND")
	)
	(via
		(at 51.062382 -384.617722)
		(size 0.4064)
		(drill 0.2032)
		(layers "F.Cu" "B.Cu")
		(net "GND")
	)
	(via
		(at 125.704854 -291.906198)
		(size 0.4064)
		(drill 0.2032)
		(layers "F.Cu" "B.Cu")
		(net "GND")
	)
	(via
		(at 376.461782 -412.84652)
		(size 0.4064)
		(drill 0.2032)
		(layers "F.Cu" "B.Cu")
		(net "GND")
	)
	(via
		(at 344.511122 -265.986006)
		(size 0.4064)
		(drill 0.2032)
		(layers "F.Cu" "B.Cu")
		(net "GND")
	)
	(via
		(at 109.939836 -372.15953)
		(size 0.508)
		(drill 0.254)
		(layers "F.Cu" "B.Cu")
		(net "GND")
	)
	(via
		(at 104.561132 -294.336216)
		(size 0.4064)
		(drill 0.2032)
		(layers "F.Cu" "B.Cu")
		(net "GND")
	)
	(via
		(at 56.786272 -413.204152)
		(size 0.4572)
		(drill 0.254)
		(layers "F.Cu" "B.Cu")
		(net "GND")
	)
	(via
		(at 457.211684 -20.813522)
		(size 0.6604)
		(drill 0.3302)
		(layers "F.Cu" "B.Cu")
		(net "GND")
	)
	(via
		(at 289.564318 -240.685066)
		(size 0.4826)
		(drill 0.254)
		(layers "F.Cu" "B.Cu")
		(net "GND")
	)
	(via
		(at 133.864858 -230.714296)
		(size 0.4064)
		(drill 0.2032)
		(layers "F.Cu" "B.Cu")
		(net "GND")
	)
	(via
		(at 42.091102 -377.00712)
		(size 0.508)
		(drill 0.254)
		(layers "F.Cu" "B.Cu")
		(net "GND")
	)
	(via
		(at 299.82414 -205.834996)
		(size 0.4826)
		(drill 0.254)
		(layers "F.Cu" "B.Cu")
		(net "GND")
	)
	(via
		(at 366.11306 -41.641776)
		(size 0.508)
		(drill 0.254)
		(layers "F.Cu" "B.Cu")
		(net "GND")
	)
	(via
		(at 41.62425 -315.485272)
		(size 0.4826)
		(drill 0.254)
		(layers "F.Cu" "B.Cu")
		(net "GND")
	)
	(via
		(at 163.796726 -410.030168)
		(size 0.4064)
		(drill 0.2032)
		(layers "F.Cu" "B.Cu")
		(net "GND")
	)
	(via
		(at 352.671126 -235.574078)
		(size 0.4064)
		(drill 0.2032)
		(layers "F.Cu" "B.Cu")
		(net "GND")
	)
	(via
		(at 396.349474 -438.499758)
		(size 0.4572)
		(drill 0.2032)
		(layers "F.Cu" "B.Cu")
		(net "GND")
	)
	(via
		(at 290.895786 -274.684998)
		(size 0.4826)
		(drill 0.254)
		(layers "F.Cu" "B.Cu")
		(net "GND")
	)
	(via
		(at 374.284748 -253.39421)
		(size 0.4064)
		(drill 0.2032)
		(layers "F.Cu" "B.Cu")
		(net "GND")
	)
	(via
		(at 91.983306 -184.615074)
		(size 0.49022)
		(drill 0.254)
		(layers "F.Cu" "B.Cu")
		(net "GND")
	)
	(via
		(at 423.66692 -18.247106)
		(size 0.508)
		(drill 0.254)
		(layers "F.Cu" "B.Cu")
		(net "GND")
	)
	(via
		(at 47.784004 -266.185396)
		(size 0.4826)
		(drill 0.254)
		(layers "F.Cu" "B.Cu")
		(net "GND")
	)
	(via
		(at 146.742912 -231.79024)
		(size 0.4064)
		(drill 0.2032)
		(layers "F.Cu" "B.Cu")
		(net "GND")
	)
	(via
		(at 143.264636 -235.574332)
		(size 0.4064)
		(drill 0.2032)
		(layers "F.Cu" "B.Cu")
		(net "GND")
	)
	(via
		(at 167.143684 -286.585406)
		(size 0.4826)
		(drill 0.254)
		(layers "F.Cu" "B.Cu")
		(net "GND")
	)
	(via
		(at 334.64119 -261.935976)
		(size 0.4064)
		(drill 0.2032)
		(layers "F.Cu" "B.Cu")
		(net "GND")
	)
	(via
		(at 93.921072 -249.344434)
		(size 0.4064)
		(drill 0.2032)
		(layers "F.Cu" "B.Cu")
		(net "GND")
	)
	(via
		(at 393.759182 -420.952168)
		(size 0.4064)
		(drill 0.2032)
		(layers "F.Cu" "B.Cu")
		(net "GND")
	)
	(via
		(at 412.05023 -417.778184)
		(size 0.4572)
		(drill 0.254)
		(layers "F.Cu" "B.Cu")
		(net "GND")
	)
	(via
		(at 358.61117 -291.905944)
		(size 0.4064)
		(drill 0.2032)
		(layers "F.Cu" "B.Cu")
		(net "GND")
	)
	(via
		(at 20.614386 -5.597398)
		(size 0.508)
		(drill 0.254)
		(layers "F.Cu" "B.Cu")
		(net "GND")
	)
	(via
		(at 274.476464 -200.735184)
		(size 0.4826)
		(drill 0.254)
		(layers "F.Cu" "B.Cu")
		(net "GND")
	)
	(via
		(at 350.151192 -277.32609)
		(size 0.4064)
		(drill 0.2032)
		(layers "F.Cu" "B.Cu")
		(net "GND")
	)
	(via
		(at 326.489314 -36.208462)
		(size 0.508)
		(drill 0.254)
		(layers "F.Cu" "B.Cu")
		(net "GND")
	)
	(via
		(at 55.328058 -281.48534)
		(size 0.4826)
		(drill 0.254)
		(layers "F.Cu" "B.Cu")
		(net "GND")
	)
	(via
		(at 123.835414 -57.537858)
		(size 0.508)
		(drill 0.254)
		(layers "F.Cu" "B.Cu")
		(net "GND")
	)
	(via
		(at 269.648178 -280.634948)
		(size 0.4826)
		(drill 0.254)
		(layers "F.Cu" "B.Cu")
		(net "GND")
	)
	(via
		(at 99.33305 -180.704744)
		(size 0.49022)
		(drill 0.254)
		(layers "F.Cu" "B.Cu")
		(net "GND")
	)
	(via
		(at 121.474738 -263.556242)
		(size 0.4064)
		(drill 0.2032)
		(layers "F.Cu" "B.Cu")
		(net "GND")
	)
	(via
		(at 280.635964 -227.085144)
		(size 0.4826)
		(drill 0.254)
		(layers "F.Cu" "B.Cu")
		(net "GND")
	)
	(via
		(at 108.94949 -176.183544)
		(size 0.49022)
		(drill 0.254)
		(layers "F.Cu" "B.Cu")
		(net "GND")
	)
	(via
		(at 2.76225 -305.745134)
		(size 0.508)
		(drill 0.254)
		(layers "F.Cu" "B.Cu")
		(net "GND")
	)
	(via
		(at 138.864848 -275.706332)
		(size 0.4064)
		(drill 0.2032)
		(layers "F.Cu" "B.Cu")
		(net "GND")
	)
	(via
		(at 93.450918 -235.574332)
		(size 0.4064)
		(drill 0.2032)
		(layers "F.Cu" "B.Cu")
		(net "GND")
	)
	(via
		(at 282.020264 -312.935112)
		(size 0.4826)
		(drill 0.254)
		(layers "F.Cu" "B.Cu")
		(net "GND")
	)
	(via
		(at 25.63241 -426.609256)
		(size 0.508)
		(drill 0.254)
		(layers "F.Cu" "B.Cu")
		(net "GND")
	)
	(via
		(at 437.715914 -239.835182)
		(size 0.4826)
		(drill 0.254)
		(layers "F.Cu" "B.Cu")
		(net "GND")
	)
	(via
		(at 51.884072 -207.535272)
		(size 0.4826)
		(drill 0.254)
		(layers "F.Cu" "B.Cu")
		(net "GND")
	)
	(via
		(at 146.742912 -256.09042)
		(size 0.4064)
		(drill 0.2032)
		(layers "F.Cu" "B.Cu")
		(net "GND")
	)
	(via
		(at 413.349694 -438.499758)
		(size 0.4572)
		(drill 0.2032)
		(layers "F.Cu" "B.Cu")
		(net "GND")
	)
	(via
		(at 177.292762 -427.911768)
		(size 0.508)
		(drill 0.254)
		(layers "F.Cu" "B.Cu")
		(net "GND")
	)
	(via
		(at 12.094972 -104.803702)
		(size 0.508)
		(drill 0.254)
		(layers "F.Cu" "B.Cu")
		(net "GND")
	)
	(via
		(at 293.32301 -344.77706)
		(size 0.49022)
		(drill 0.254)
		(layers "F.Cu" "B.Cu")
		(net "GND")
	)
	(via
		(at 95.789242 -370.83873)
		(size 0.508)
		(drill 0.254)
		(layers "F.Cu" "B.Cu")
		(net "GND")
	)
	(via
		(at 375.054876 -289.475926)
		(size 0.4064)
		(drill 0.2032)
		(layers "F.Cu" "B.Cu")
		(net "GND")
	)
	(via
		(at 90.198702 -369.03533)
		(size 0.508)
		(drill 0.254)
		(layers "F.Cu" "B.Cu")
		(net "GND")
	)
	(via
		(at 289.564318 -306.135024)
		(size 0.4826)
		(drill 0.254)
		(layers "F.Cu" "B.Cu")
		(net "GND")
	)
	(via
		(at 34.080196 -200.735438)
		(size 0.4826)
		(drill 0.254)
		(layers "F.Cu" "B.Cu")
		(net "GND")
	)
	(via
		(at 141.501114 -29.053028)
		(size 0.508)
		(drill 0.254)
		(layers "F.Cu" "B.Cu")
		(net "GND")
	)
	(via
		(at 182.231792 -230.485442)
		(size 0.4826)
		(drill 0.254)
		(layers "F.Cu" "B.Cu")
		(net "GND")
	)
	(via
		(at 138.864848 -285.426404)
		(size 0.4064)
		(drill 0.2032)
		(layers "F.Cu" "B.Cu")
		(net "GND")
	)
	(via
		(at 347.986858 -159.151066)
		(size 0.49022)
		(drill 0.254)
		(layers "F.Cu" "B.Cu")
		(net "GND")
	)
	(via
		(at 231.319578 -319.466468)
		(size 0.508)
		(drill 0.254)
		(layers "F.Cu" "B.Cu")
		(net "GND")
	)
	(via
		(at 106.939842 -337.990434)
		(size 0.508)
		(drill 0.254)
		(layers "F.Cu" "B.Cu")
		(net "GND")
	)
	(via
		(at 143.56461 -288.666174)
		(size 0.4064)
		(drill 0.2032)
		(layers "F.Cu" "B.Cu")
		(net "GND")
	)
	(via
		(at 93.430344 -307.214524)
		(size 0.508)
		(drill 0.254)
		(layers "F.Cu" "B.Cu")
		(net "GND")
	)
	(via
		(at 455.305668 -219.860114)
		(size 0.4826)
		(drill 0.254)
		(layers "F.Cu" "B.Cu")
		(net "GND")
	)
	(via
		(at 100.031042 -225.854514)
		(size 0.4064)
		(drill 0.2032)
		(layers "F.Cu" "B.Cu")
		(net "GND")
	)
	(via
		(at 140.444728 -253.394464)
		(size 0.4064)
		(drill 0.2032)
		(layers "F.Cu" "B.Cu")
		(net "GND")
	)
	(via
		(at 29.252164 -233.885232)
		(size 0.4826)
		(drill 0.254)
		(layers "F.Cu" "B.Cu")
		(net "GND")
	)
	(via
		(at 283.351732 -295.935146)
		(size 0.4826)
		(drill 0.254)
		(layers "F.Cu" "B.Cu")
		(net "GND")
	)
	(via
		(at 266.365736 -340.437216)
		(size 0.6604)
		(drill 0.3302)
		(layers "F.Cu" "B.Cu")
		(net "GND")
	)
	(via
		(at 154.218894 -390.160002)
		(size 0.4064)
		(drill 0.2032)
		(layers "F.Cu" "B.Cu")
		(net "GND")
	)
	(via
		(at 171.97197 -309.535322)
		(size 0.4826)
		(drill 0.254)
		(layers "F.Cu" "B.Cu")
		(net "GND")
	)
	(via
		(at 420.1033 -380.54153)
		(size 0.508)
		(drill 0.254)
		(layers "F.Cu" "B.Cu")
		(net "GND")
	)
	(via
		(at 173.08957 -276.81047)
		(size 0.4826)
		(drill 0.254)
		(layers "F.Cu" "B.Cu")
		(net "GND")
	)
	(via
		(at 273.092164 -233.035094)
		(size 0.4826)
		(drill 0.254)
		(layers "F.Cu" "B.Cu")
		(net "GND")
	)
	(via
		(at 306.250594 -294.660066)
		(size 0.4826)
		(drill 0.254)
		(layers "F.Cu" "B.Cu")
		(net "GND")
	)
	(via
		(at 20.59051 -229.210362)
		(size 0.4826)
		(drill 0.254)
		(layers "F.Cu" "B.Cu")
		(net "GND")
	)
	(via
		(at 359.365042 -164.34562)
		(size 0.508)
		(drill 0.254)
		(layers "F.Cu" "B.Cu")
		(net "GND")
	)
	(via
		(at 171.97197 -283.185362)
		(size 0.4826)
		(drill 0.254)
		(layers "F.Cu" "B.Cu")
		(net "GND")
	)
	(via
		(at 434.630576 -108.19003)
		(size 0.508)
		(drill 0.254)
		(layers "F.Cu" "B.Cu")
		(net "GND")
	)
	(via
		(at 328.231246 -225.85426)
		(size 0.4064)
		(drill 0.2032)
		(layers "F.Cu" "B.Cu")
		(net "GND")
	)
	(via
		(at 77.112876 -285.970472)
		(size 0.4064)
		(drill 0.2032)
		(layers "F.Cu" "B.Cu")
		(net "GND")
	)
	(via
		(at 144.732756 -388.29615)
		(size 0.4064)
		(drill 0.2032)
		(layers "F.Cu" "B.Cu")
		(net "GND")
	)
	(via
		(at 38.78707 -173.537372)
		(size 0.508)
		(drill 0.254)
		(layers "F.Cu" "B.Cu")
		(net "GND")
	)
	(via
		(at 215.8365 -101.92512)
		(size 0.508)
		(drill 0.254)
		(layers "F.Cu" "B.Cu")
		(net "GND")
	)
	(via
		(at 339.811106 -269.22603)
		(size 0.4064)
		(drill 0.2032)
		(layers "F.Cu" "B.Cu")
		(net "GND")
	)
	(via
		(at 347.33103 -277.32609)
		(size 0.4064)
		(drill 0.2032)
		(layers "F.Cu" "B.Cu")
		(net "GND")
	)
	(via
		(at 131.544314 -409.396184)
		(size 0.4572)
		(drill 0.254)
		(layers "F.Cu" "B.Cu")
		(net "GND")
	)
	(via
		(at 63.24981 -431.451258)
		(size 0.4572)
		(drill 0.2032)
		(layers "F.Cu" "B.Cu")
		(net "GND")
	)
	(via
		(at 94.812358 -334.630268)
		(size 0.49022)
		(drill 0.254)
		(layers "F.Cu" "B.Cu")
		(net "GND")
	)
	(via
		(at 288.180018 -214.335106)
		(size 0.4826)
		(drill 0.254)
		(layers "F.Cu" "B.Cu")
		(net "GND")
	)
	(via
		(at 107.38104 -268.416278)
		(size 0.4064)
		(drill 0.2032)
		(layers "F.Cu" "B.Cu")
		(net "GND")
	)
	(via
		(at 250.293632 -421.46093)
		(size 0.508)
		(drill 0.254)
		(layers "F.Cu" "B.Cu")
		(net "GND")
	)
	(via
		(at 61.918596 -388.328662)
		(size 0.4064)
		(drill 0.2032)
		(layers "F.Cu" "B.Cu")
		(net "GND")
	)
	(via
		(at 442.5442 -279.785064)
		(size 0.4826)
		(drill 0.254)
		(layers "F.Cu" "B.Cu")
		(net "GND")
	)
	(via
		(at 86.871048 -235.574332)
		(size 0.4064)
		(drill 0.2032)
		(layers "F.Cu" "B.Cu")
		(net "GND")
	)
	(via
		(at 333.069184 -376.75693)
		(size 0.508)
		(drill 0.254)
		(layers "F.Cu" "B.Cu")
		(net "GND")
	)
	(via
		(at 375.29135 -419.046152)
		(size 0.4572)
		(drill 0.254)
		(layers "F.Cu" "B.Cu")
		(net "GND")
	)
	(via
		(at 90.356182 -69.864986)
		(size 0.508)
		(drill 0.254)
		(layers "F.Cu" "B.Cu")
		(net "GND")
	)
	(via
		(at 372.321328 -135.97382)
		(size 0.508)
		(drill 0.254)
		(layers "F.Cu" "B.Cu")
		(net "GND")
	)
	(via
		(at 309.051452 -437.098694)
		(size 0.508)
		(drill 0.254)
		(layers "F.Cu" "B.Cu")
		(net "GND")
	)
	(via
		(at 24.980138 -19.771106)
		(size 0.508)
		(drill 0.254)
		(layers "F.Cu" "B.Cu")
		(net "GND")
	)
	(via
		(at 115.064794 -251.774452)
		(size 0.4064)
		(drill 0.2032)
		(layers "F.Cu" "B.Cu")
		(net "GND")
	)
	(via
		(at 341.22106 -270.036036)
		(size 0.4064)
		(drill 0.2032)
		(layers "F.Cu" "B.Cu")
		(net "GND")
	)
	(via
		(at 385.394708 -276.516084)
		(size 0.4064)
		(drill 0.2032)
		(layers "F.Cu" "B.Cu")
		(net "GND")
	)
	(via
		(at 326.821038 -223.424242)
		(size 0.4064)
		(drill 0.2032)
		(layers "F.Cu" "B.Cu")
		(net "GND")
	)
	(via
		(at 207.630014 -131.557014)
		(size 0.508)
		(drill 0.254)
		(layers "F.Cu" "B.Cu")
		(net "GND")
	)
	(via
		(at 24.873712 -0.762254)
		(size 0.508)
		(drill 0.254)
		(layers "F.Cu" "B.Cu")
		(net "GND")
	)
	(via
		(at 54.83479 -4.963414)
		(size 0.508)
		(drill 0.254)
		(layers "F.Cu" "B.Cu")
		(net "GND")
	)
	(via
		(at 391.504678 -287.045908)
		(size 0.4064)
		(drill 0.2032)
		(layers "F.Cu" "B.Cu")
		(net "GND")
	)
	(via
		(at 123.354846 -268.416278)
		(size 0.4064)
		(drill 0.2032)
		(layers "F.Cu" "B.Cu")
		(net "GND")
	)
	(via
		(at 146.742912 -236.650276)
		(size 0.4064)
		(drill 0.2032)
		(layers "F.Cu" "B.Cu")
		(net "GND")
	)
	(via
		(at 372.704868 -269.22603)
		(size 0.4064)
		(drill 0.2032)
		(layers "F.Cu" "B.Cu")
		(net "GND")
	)
	(via
		(at 168.527984 -204.135228)
		(size 0.4826)
		(drill 0.254)
		(layers "F.Cu" "B.Cu")
		(net "GND")
	)
	(via
		(at 55.328058 -283.185362)
		(size 0.4826)
		(drill 0.254)
		(layers "F.Cu" "B.Cu")
		(net "GND")
	)
	(via
		(at 100.331016 -274.08632)
		(size 0.4064)
		(drill 0.2032)
		(layers "F.Cu" "B.Cu")
		(net "GND")
	)
	(via
		(at 376.411236 -177.71618)
		(size 0.508)
		(drill 0.254)
		(layers "F.Cu" "B.Cu")
		(net "GND")
	)
	(via
		(at 202.147932 -249.18543)
		(size 0.4826)
		(drill 0.254)
		(layers "F.Cu" "B.Cu")
		(net "GND")
	)
	(via
		(at 298.43984 -218.585034)
		(size 0.4826)
		(drill 0.254)
		(layers "F.Cu" "B.Cu")
		(net "GND")
	)
	(via
		(at 11.537442 -52.634896)
		(size 0.508)
		(drill 0.254)
		(layers "F.Cu" "B.Cu")
		(net "GND")
	)
	(via
		(at 450.088 -283.185108)
		(size 0.4826)
		(drill 0.254)
		(layers "F.Cu" "B.Cu")
		(net "GND")
	)
	(via
		(at 437.715914 -209.23504)
		(size 0.4826)
		(drill 0.254)
		(layers "F.Cu" "B.Cu")
		(net "GND")
	)
	(via
		(at 202.147932 -216.035382)
		(size 0.4826)
		(drill 0.254)
		(layers "F.Cu" "B.Cu")
		(net "GND")
	)
	(via
		(at 141.854682 -231.524302)
		(size 0.4064)
		(drill 0.2032)
		(layers "F.Cu" "B.Cu")
		(net "GND")
	)
	(via
		(at 407.689558 -4.963414)
		(size 0.508)
		(drill 0.254)
		(layers "F.Cu" "B.Cu")
		(net "GND")
	)
	(via
		(at 76.812902 -239.8903)
		(size 0.4064)
		(drill 0.2032)
		(layers "F.Cu" "B.Cu")
		(net "GND")
	)
	(via
		(at 337.890358 -217.776552)
		(size 0.508)
		(drill 0.254)
		(layers "F.Cu" "B.Cu")
		(net "GND")
	)
	(via
		(at 306.9336 -150.274274)
		(size 0.508)
		(drill 0.254)
		(layers "F.Cu" "B.Cu")
		(net "GND")
	)
	(via
		(at 211.840318 -338.730336)
		(size 0.508)
		(drill 0.254)
		(layers "F.Cu" "B.Cu")
		(net "GND")
	)
	(via
		(at 448.01536 -9.59866)
		(size 0.508)
		(drill 0.254)
		(layers "F.Cu" "B.Cu")
		(net "GND")
	)
	(via
		(at 206.248 -310.385206)
		(size 0.4826)
		(drill 0.254)
		(layers "F.Cu" "B.Cu")
		(net "GND")
	)
	(via
		(at 187.060078 -227.085398)
		(size 0.4826)
		(drill 0.254)
		(layers "F.Cu" "B.Cu")
		(net "GND")
	)
	(via
		(at 155.349702 -425.547282)
		(size 0.4572)
		(drill 0.2032)
		(layers "F.Cu" "B.Cu")
		(net "GND")
	)
	(via
		(at 91.871038 -275.706332)
		(size 0.4064)
		(drill 0.2032)
		(layers "F.Cu" "B.Cu")
		(net "GND")
	)
	(via
		(at 381.804926 -238.814102)
		(size 0.4064)
		(drill 0.2032)
		(layers "F.Cu" "B.Cu")
		(net "GND")
	)
	(via
		(at 339.811106 -287.045908)
		(size 0.4064)
		(drill 0.2032)
		(layers "F.Cu" "B.Cu")
		(net "GND")
	)
	(via
		(at 336.521044 -268.416024)
		(size 0.4064)
		(drill 0.2032)
		(layers "F.Cu" "B.Cu")
		(net "GND")
	)
	(via
		(at 99.090988 -243.674392)
		(size 0.4064)
		(drill 0.2032)
		(layers "F.Cu" "B.Cu")
		(net "GND")
	)
	(via
		(at 64.616584 -393.927838)
		(size 0.4572)
		(drill 0.254)
		(layers "F.Cu" "B.Cu")
		(net "GND")
	)
	(via
		(at 416.254692 -139.436856)
		(size 0.508)
		(drill 0.254)
		(layers "F.Cu" "B.Cu")
		(net "GND")
	)
	(via
		(at 171.97197 -255.13538)
		(size 0.4826)
		(drill 0.254)
		(layers "F.Cu" "B.Cu")
		(net "GND")
	)
	(via
		(at 28.192984 -404.372572)
		(size 0.508)
		(drill 0.254)
		(layers "F.Cu" "B.Cu")
		(net "GND")
	)
	(via
		(at 407.349706 -433.899564)
		(size 0.4572)
		(drill 0.2032)
		(layers "F.Cu" "B.Cu")
		(net "GND")
	)
	(via
		(at 122.442986 -412.570168)
		(size 0.4064)
		(drill 0.2032)
		(layers "F.Cu" "B.Cu")
		(net "GND")
	)
	(via
		(at 170.844718 -392.452606)
		(size 0.508)
		(drill 0.254)
		(layers "F.Cu" "B.Cu")
		(net "GND")
	)
	(via
		(at 141.720062 -80.681322)
		(size 0.508)
		(drill 0.254)
		(layers "F.Cu" "B.Cu")
		(net "GND")
	)
	(via
		(at 40.23995 -204.985366)
		(size 0.4826)
		(drill 0.254)
		(layers "F.Cu" "B.Cu")
		(net "GND")
	)
	(via
		(at 329.249532 -434.899562)
		(size 0.4572)
		(drill 0.2032)
		(layers "F.Cu" "B.Cu")
		(net "GND")
	)
	(via
		(at 14.820646 -358.833674)
		(size 0.508)
		(drill 0.254)
		(layers "F.Cu" "B.Cu")
		(net "GND")
	)
	(via
		(at 352.671126 -224.234248)
		(size 0.4064)
		(drill 0.2032)
		(layers "F.Cu" "B.Cu")
		(net "GND")
	)
	(via
		(at 93.280992 -291.096192)
		(size 0.4064)
		(drill 0.2032)
		(layers "F.Cu" "B.Cu")
		(net "GND")
	)
	(via
		(at 298.565316 -423.683684)
		(size 0.508)
		(drill 0.254)
		(layers "F.Cu" "B.Cu")
		(net "GND")
	)
	(via
		(at 261.041896 -101.022404)
		(size 0.508)
		(drill 0.254)
		(layers "F.Cu" "B.Cu")
		(net "GND")
	)
	(via
		(at 388.384796 -225.85426)
		(size 0.4064)
		(drill 0.2032)
		(layers "F.Cu" "B.Cu")
		(net "GND")
	)
	(via
		(at 170.16857 -125.848872)
		(size 0.508)
		(drill 0.254)
		(layers "F.Cu" "B.Cu")
		(net "GND")
	)
	(via
		(at 455.305668 -210.51012)
		(size 0.4826)
		(drill 0.254)
		(layers "F.Cu" "B.Cu")
		(net "GND")
	)
	(via
		(at 85.290914 -290.286186)
		(size 0.4064)
		(drill 0.2032)
		(layers "F.Cu" "B.Cu")
		(net "GND")
	)
	(via
		(at 369.114832 -234.764072)
		(size 0.4064)
		(drill 0.2032)
		(layers "F.Cu" "B.Cu")
		(net "GND")
	)
	(via
		(at 451.25259 -54.63286)
		(size 0.508)
		(drill 0.254)
		(layers "F.Cu" "B.Cu")
		(net "GND")
	)
	(via
		(at 374.932702 -415.38652)
		(size 0.4064)
		(drill 0.2032)
		(layers "F.Cu" "B.Cu")
		(net "GND")
	)
	(via
		(at 351.091246 -293.525956)
		(size 0.4064)
		(drill 0.2032)
		(layers "F.Cu" "B.Cu")
		(net "GND")
	)
	(via
		(at 458.52969 -51.9811)
		(size 0.508)
		(drill 0.254)
		(layers "F.Cu" "B.Cu")
		(net "GND")
	)
	(via
		(at 112.855756 -369.69573)
		(size 0.508)
		(drill 0.254)
		(layers "F.Cu" "B.Cu")
		(net "GND")
	)
	(via
		(at 168.527984 -226.23526)
		(size 0.4826)
		(drill 0.254)
		(layers "F.Cu" "B.Cu")
		(net "GND")
	)
	(via
		(at 209.832448 -322.464684)
		(size 0.508)
		(drill 0.254)
		(layers "F.Cu" "B.Cu")
		(net "GND")
	)
	(via
		(at 384.624834 -255.014222)
		(size 0.4064)
		(drill 0.2032)
		(layers "F.Cu" "B.Cu")
		(net "GND")
	)
	(via
		(at 10.876788 -371.36705)
		(size 0.508)
		(drill 0.254)
		(layers "F.Cu" "B.Cu")
		(net "GND")
	)
	(via
		(at 337.92668 -332.389734)
		(size 0.508)
		(drill 0.254)
		(layers "F.Cu" "B.Cu")
		(net "GND")
	)
	(via
		(at 133.91769 -155.965144)
		(size 0.49022)
		(drill 0.254)
		(layers "F.Cu" "B.Cu")
		(net "GND")
	)
	(via
		(at 313.416188 -391.23493)
		(size 0.4064)
		(drill 0.2032)
		(layers "F.Cu" "B.Cu")
		(net "GND")
	)
	(via
		(at 132.063236 -368.37493)
		(size 0.508)
		(drill 0.254)
		(layers "F.Cu" "B.Cu")
		(net "GND")
	)
	(via
		(at 117.714776 -268.416278)
		(size 0.4064)
		(drill 0.2032)
		(layers "F.Cu" "B.Cu")
		(net "GND")
	)
	(via
		(at 338.101178 -255.824228)
		(size 0.4064)
		(drill 0.2032)
		(layers "F.Cu" "B.Cu")
		(net "GND")
	)
	(via
		(at 349.029274 -163.078668)
		(size 0.49022)
		(drill 0.254)
		(layers "F.Cu" "B.Cu")
		(net "GND")
	)
	(via
		(at 121.004838 -285.426404)
		(size 0.4064)
		(drill 0.2032)
		(layers "F.Cu" "B.Cu")
		(net "GND")
	)
	(via
		(at 401.349718 -432.451256)
		(size 0.4572)
		(drill 0.2032)
		(layers "F.Cu" "B.Cu")
		(net "GND")
	)
	(via
		(at 424.012106 -222.834962)
		(size 0.4826)
		(drill 0.254)
		(layers "F.Cu" "B.Cu")
		(net "GND")
	)
	(via
		(at 405.64562 -10.16508)
		(size 0.508)
		(drill 0.254)
		(layers "F.Cu" "B.Cu")
		(net "GND")
	)
	(via
		(at 93.631004 -406.980644)
		(size 0.4064)
		(drill 0.2032)
		(layers "F.Cu" "B.Cu")
		(net "GND")
	)
	(via
		(at 40.23995 -216.035382)
		(size 0.4826)
		(drill 0.254)
		(layers "F.Cu" "B.Cu")
		(net "GND")
	)
	(via
		(at 96.271842 -57.187846)
		(size 0.508)
		(drill 0.254)
		(layers "F.Cu" "B.Cu")
		(net "GND")
	)
	(via
		(at 372.891304 -398.542002)
		(size 0.4064)
		(drill 0.2032)
		(layers "F.Cu" "B.Cu")
		(net "GND")
	)
	(via
		(at 157.81909 -390.160002)
		(size 0.4064)
		(drill 0.2032)
		(layers "F.Cu" "B.Cu")
		(net "GND")
	)
	(via
		(at 131.98475 -233.95432)
		(size 0.4064)
		(drill 0.2032)
		(layers "F.Cu" "B.Cu")
		(net "GND")
	)
	(via
		(at 396.73403 -414.752536)
		(size 0.4572)
		(drill 0.254)
		(layers "F.Cu" "B.Cu")
		(net "GND")
	)
	(via
		(at 180.281834 -420.351458)
		(size 0.508)
		(drill 0.254)
		(layers "F.Cu" "B.Cu")
		(net "GND")
	)
	(via
		(at 58.310526 -294.66032)
		(size 0.4826)
		(drill 0.254)
		(layers "F.Cu" "B.Cu")
		(net "GND")
	)
	(via
		(at 456.396852 -395.25575)
		(size 0.49022)
		(drill 0.254)
		(layers "F.Cu" "B.Cu")
		(net "GND")
	)
	(via
		(at 216.716102 -386.399532)
		(size 0.508)
		(drill 0.254)
		(layers "F.Cu" "B.Cu")
		(net "GND")
	)
	(via
		(at 183.616092 -297.635422)
		(size 0.4826)
		(drill 0.254)
		(layers "F.Cu" "B.Cu")
		(net "GND")
	)
	(via
		(at 413.523684 -192.21831)
		(size 0.4826)
		(drill 0.254)
		(layers "F.Cu" "B.Cu")
		(net "GND")
	)
	(via
		(at 76.812902 -247.99036)
		(size 0.4064)
		(drill 0.2032)
		(layers "F.Cu" "B.Cu")
		(net "GND")
	)
	(via
		(at 63.261494 -370.83873)
		(size 0.508)
		(drill 0.254)
		(layers "F.Cu" "B.Cu")
		(net "GND")
	)
	(via
		(at 27.814524 -4.32943)
		(size 0.508)
		(drill 0.254)
		(layers "F.Cu" "B.Cu")
		(net "GND")
	)
	(via
		(at 361.124754 -238.814102)
		(size 0.4064)
		(drill 0.2032)
		(layers "F.Cu" "B.Cu")
		(net "GND")
	)
	(via
		(at 59.428126 -226.23526)
		(size 0.4826)
		(drill 0.254)
		(layers "F.Cu" "B.Cu")
		(net "GND")
	)
	(via
		(at 349.681038 -263.555988)
		(size 0.4064)
		(drill 0.2032)
		(layers "F.Cu" "B.Cu")
		(net "GND")
	)
	(via
		(at 228.092 -281.872944)
		(size 0.508)
		(drill 0.254)
		(layers "F.Cu" "B.Cu")
		(net "GND")
	)
	(via
		(at 98.150934 -251.774452)
		(size 0.4064)
		(drill 0.2032)
		(layers "F.Cu" "B.Cu")
		(net "GND")
	)
	(via
		(at 382.571498 -182.177944)
		(size 0.49022)
		(drill 0.254)
		(layers "F.Cu" "B.Cu")
		(net "GND")
	)
	(via
		(at 141.732762 -81.423002)
		(size 0.508)
		(drill 0.254)
		(layers "F.Cu" "B.Cu")
		(net "GND")
	)
	(via
		(at 375.524776 -290.285932)
		(size 0.4064)
		(drill 0.2032)
		(layers "F.Cu" "B.Cu")
		(net "GND")
	)
	(via
		(at 250.534424 -276.227032)
		(size 0.508)
		(drill 0.254)
		(layers "F.Cu" "B.Cu")
		(net "GND")
	)
	(via
		(at 28.096464 -192.218564)
		(size 0.4826)
		(drill 0.254)
		(layers "F.Cu" "B.Cu")
		(net "GND")
	)
	(via
		(at 390.349486 -426.69968)
		(size 0.4572)
		(drill 0.2032)
		(layers "F.Cu" "B.Cu")
		(net "GND")
	)
	(via
		(at 366.294924 -246.104156)
		(size 0.4064)
		(drill 0.2032)
		(layers "F.Cu" "B.Cu")
		(net "GND")
	)
	(via
		(at 421.296338 -238.13516)
		(size 0.4826)
		(drill 0.254)
		(layers "F.Cu" "B.Cu")
		(net "GND")
	)
	(via
		(at 229.203504 -151.042878)
		(size 0.508)
		(drill 0.254)
		(layers "F.Cu" "B.Cu")
		(net "GND")
	)
	(via
		(at 298.43984 -239.835182)
		(size 0.4826)
		(drill 0.254)
		(layers "F.Cu" "B.Cu")
		(net "GND")
	)
	(via
		(at 143.409162 -50.235612)
		(size 0.508)
		(drill 0.254)
		(layers "F.Cu" "B.Cu")
		(net "GND")
	)
	(via
		(at 443.9285 -238.13516)
		(size 0.4826)
		(drill 0.254)
		(layers "F.Cu" "B.Cu")
		(net "GND")
	)
	(via
		(at 83.586066 -184.683146)
		(size 0.49022)
		(drill 0.254)
		(layers "F.Cu" "B.Cu")
		(net "GND")
	)
	(via
		(at 217.602054 -77.434948)
		(size 0.508)
		(drill 0.254)
		(layers "F.Cu" "B.Cu")
		(net "GND")
	)
	(via
		(at 141.854682 -229.90429)
		(size 0.4064)
		(drill 0.2032)
		(layers "F.Cu" "B.Cu")
		(net "GND")
	)
	(via
		(at 143.56461 -283.806392)
		(size 0.4064)
		(drill 0.2032)
		(layers "F.Cu" "B.Cu")
		(net "GND")
	)
	(via
		(at 197.869556 -342.864948)
		(size 0.508)
		(drill 0.254)
		(layers "F.Cu" "B.Cu")
		(net "GND")
	)
	(via
		(at 194.604132 -269.58544)
		(size 0.4826)
		(drill 0.254)
		(layers "F.Cu" "B.Cu")
		(net "GND")
	)
	(via
		(at 322.7451 -398.542002)
		(size 0.4064)
		(drill 0.2032)
		(layers "F.Cu" "B.Cu")
		(net "GND")
	)
	(via
		(at 142.962122 -6.042152)
		(size 0.508)
		(drill 0.254)
		(layers "F.Cu" "B.Cu")
		(net "GND")
	)
	(via
		(at 87.246206 -388.328662)
		(size 0.4064)
		(drill 0.2032)
		(layers "F.Cu" "B.Cu")
		(net "GND")
	)
	(via
		(at 41.62425 -200.735438)
		(size 0.4826)
		(drill 0.254)
		(layers "F.Cu" "B.Cu")
		(net "GND")
	)
	(via
		(at 336.472784 -383.00533)
		(size 0.508)
		(drill 0.254)
		(layers "F.Cu" "B.Cu")
		(net "GND")
	)
	(via
		(at 275.44141 -346.317316)
		(size 0.49022)
		(drill 0.254)
		(layers "F.Cu" "B.Cu")
		(net "GND")
	)
	(via
		(at 427.485302 -435.275736)
		(size 0.508)
		(drill 0.254)
		(layers "F.Cu" "B.Cu")
		(net "GND")
	)
	(via
		(at 161.818066 -407.00452)
		(size 0.4064)
		(drill 0.2032)
		(layers "F.Cu" "B.Cu")
		(net "GND")
	)
	(via
		(at 194.604132 -199.035416)
		(size 0.4826)
		(drill 0.254)
		(layers "F.Cu" "B.Cu")
		(net "GND")
	)
	(via
		(at 133.694678 -291.096192)
		(size 0.4064)
		(drill 0.2032)
		(layers "F.Cu" "B.Cu")
		(net "GND")
	)
	(via
		(at 59.428126 -291.685218)
		(size 0.4826)
		(drill 0.254)
		(layers "F.Cu" "B.Cu")
		(net "GND")
	)
	(via
		(at 372.404894 -235.574078)
		(size 0.4064)
		(drill 0.2032)
		(layers "F.Cu" "B.Cu")
		(net "GND")
	)
	(via
		(at 178.289458 -48.299878)
		(size 0.508)
		(drill 0.254)
		(layers "F.Cu" "B.Cu")
		(net "GND")
	)
	(via
		(at 53.74513 -19.13636)
		(size 0.508)
		(drill 0.254)
		(layers "F.Cu" "B.Cu")
		(net "GND")
	)
	(via
		(at 328.53122 -283.806138)
		(size 0.4064)
		(drill 0.2032)
		(layers "F.Cu" "B.Cu")
		(net "GND")
	)
	(via
		(at 305.983894 -239.835182)
		(size 0.4826)
		(drill 0.254)
		(layers "F.Cu" "B.Cu")
		(net "GND")
	)
	(via
		(at 197.5866 -192.218564)
		(size 0.4826)
		(drill 0.254)
		(layers "F.Cu" "B.Cu")
		(net "GND")
	)
	(via
		(at 34.080196 -278.085296)
		(size 0.4826)
		(drill 0.254)
		(layers "F.Cu" "B.Cu")
		(net "GND")
	)
	(via
		(at 269.706598 -132.004562)
		(size 0.508)
		(drill 0.254)
		(layers "F.Cu" "B.Cu")
		(net "GND")
	)
	(via
		(at 54.78907 -18.247868)
		(size 0.508)
		(drill 0.254)
		(layers "F.Cu" "B.Cu")
		(net "GND")
	)
	(via
		(at 119.294656 -250.964446)
		(size 0.4064)
		(drill 0.2032)
		(layers "F.Cu" "B.Cu")
		(net "GND")
	)
	(via
		(at 179.516024 -199.035416)
		(size 0.4826)
		(drill 0.254)
		(layers "F.Cu" "B.Cu")
		(net "GND")
	)
	(via
		(at 83.111086 -233.95432)
		(size 0.4064)
		(drill 0.2032)
		(layers "F.Cu" "B.Cu")
		(net "GND")
	)
	(via
		(at 305.983894 -274.684998)
		(size 0.4826)
		(drill 0.254)
		(layers "F.Cu" "B.Cu")
		(net "GND")
	)
	(via
		(at 352.9711 -283.806138)
		(size 0.4064)
		(drill 0.2032)
		(layers "F.Cu" "B.Cu")
		(net "GND")
	)
	(via
		(at 265.54811 -233.035094)
		(size 0.4826)
		(drill 0.254)
		(layers "F.Cu" "B.Cu")
		(net "GND")
	)
	(via
		(at 113.434114 -182.736998)
		(size 0.508)
		(drill 0.254)
		(layers "F.Cu" "B.Cu")
		(net "GND")
	)
	(via
		(at 451.4723 -200.735184)
		(size 0.4826)
		(drill 0.254)
		(layers "F.Cu" "B.Cu")
		(net "GND")
	)
	(via
		(at 124.464826 -235.574332)
		(size 0.4064)
		(drill 0.2032)
		(layers "F.Cu" "B.Cu")
		(net "GND")
	)
	(via
		(at 303.518316 -396.710662)
		(size 0.4064)
		(drill 0.2032)
		(layers "F.Cu" "B.Cu")
		(net "GND")
	)
	(via
		(at 410.64434 -402.259038)
		(size 0.4572)
		(drill 0.254)
		(layers "F.Cu" "B.Cu")
		(net "GND")
	)
	(via
		(at 329.275186 -415.38652)
		(size 0.4064)
		(drill 0.2032)
		(layers "F.Cu" "B.Cu")
		(net "GND")
	)
	(via
		(at 355.491034 -245.29415)
		(size 0.4064)
		(drill 0.2032)
		(layers "F.Cu" "B.Cu")
		(net "GND")
	)
	(via
		(at 399.438622 -418.412168)
		(size 0.4064)
		(drill 0.2032)
		(layers "F.Cu" "B.Cu")
		(net "GND")
	)
	(via
		(at 156.96819 -101.238812)
		(size 0.508)
		(drill 0.254)
		(layers "F.Cu" "B.Cu")
		(net "GND")
	)
	(via
		(at 78.24978 -430.147222)
		(size 0.4572)
		(drill 0.2032)
		(layers "F.Cu" "B.Cu")
		(net "GND")
	)
	(via
		(at 191.160146 -289.98545)
		(size 0.4826)
		(drill 0.254)
		(layers "F.Cu" "B.Cu")
		(net "GND")
	)
	(via
		(at 49.128172 -409.396184)
		(size 0.4572)
		(drill 0.254)
		(layers "F.Cu" "B.Cu")
		(net "GND")
	)
	(via
		(at 361.446318 -181.67604)
		(size 0.508)
		(drill 0.254)
		(layers "F.Cu" "B.Cu")
		(net "GND")
	)
	(via
		(at 97.662746 -208.244948)
		(size 0.508)
		(drill 0.254)
		(layers "F.Cu" "B.Cu")
		(net "GND")
	)
	(via
		(at 239.790478 -224.253044)
		(size 0.508)
		(drill 0.254)
		(layers "F.Cu" "B.Cu")
		(net "GND")
	)
	(via
		(at 365.190278 -175.782986)
		(size 0.49022)
		(drill 0.254)
		(layers "F.Cu" "B.Cu")
		(net "GND")
	)
	(via
		(at 105.971086 -274.08632)
		(size 0.4064)
		(drill 0.2032)
		(layers "F.Cu" "B.Cu")
		(net "GND")
	)
	(via
		(at 387.632702 -420.952168)
		(size 0.4064)
		(drill 0.2032)
		(layers "F.Cu" "B.Cu")
		(net "GND")
	)
	(via
		(at 25.90673 -352.614738)
		(size 0.508)
		(drill 0.254)
		(layers "F.Cu" "B.Cu")
		(net "GND")
	)
	(via
		(at 100.375466 -184.632346)
		(size 0.49022)
		(drill 0.254)
		(layers "F.Cu" "B.Cu")
		(net "GND")
	)
	(via
		(at 407.024078 -166.605458)
		(size 0.49022)
		(drill 0.254)
		(layers "F.Cu" "B.Cu")
		(net "GND")
	)
	(via
		(at 108.321094 -276.516338)
		(size 0.4064)
		(drill 0.2032)
		(layers "F.Cu" "B.Cu")
		(net "GND")
	)
	(via
		(at 119.76481 -235.574332)
		(size 0.4064)
		(drill 0.2032)
		(layers "F.Cu" "B.Cu")
		(net "GND")
	)
	(via
		(at 150.85568 -12.495022)
		(size 0.508)
		(drill 0.254)
		(layers "F.Cu" "B.Cu")
		(net "GND")
	)
	(via
		(at 49.168304 -221.985332)
		(size 0.4826)
		(drill 0.254)
		(layers "F.Cu" "B.Cu")
		(net "GND")
	)
	(via
		(at 63.24981 -426.69968)
		(size 0.4572)
		(drill 0.2032)
		(layers "F.Cu" "B.Cu")
		(net "GND")
	)
	(via
		(at 35.411664 -218.585288)
		(size 0.4826)
		(drill 0.254)
		(layers "F.Cu" "B.Cu")
		(net "GND")
	)
	(via
		(at 350.318832 -398.542002)
		(size 0.4064)
		(drill 0.2032)
		(layers "F.Cu" "B.Cu")
		(net "GND")
	)
	(via
		(at 305.381152 -352.227134)
		(size 0.508)
		(drill 0.254)
		(layers "F.Cu" "B.Cu")
		(net "GND")
	)
	(via
		(at 39.748714 -343.476834)
		(size 0.508)
		(drill 0.254)
		(layers "F.Cu" "B.Cu")
		(net "GND")
	)
	(via
		(at 306.860956 -380.54153)
		(size 0.508)
		(drill 0.254)
		(layers "F.Cu" "B.Cu")
		(net "GND")
	)
	(via
		(at 347.50121 -244.484144)
		(size 0.4064)
		(drill 0.2032)
		(layers "F.Cu" "B.Cu")
		(net "GND")
	)
	(via
		(at 379.284738 -269.22603)
		(size 0.4064)
		(drill 0.2032)
		(layers "F.Cu" "B.Cu")
		(net "GND")
	)
	(via
		(at 191.160146 -268.735302)
		(size 0.4826)
		(drill 0.254)
		(layers "F.Cu" "B.Cu")
		(net "GND")
	)
	(via
		(at 87.340948 -223.424496)
		(size 0.4064)
		(drill 0.2032)
		(layers "F.Cu" "B.Cu")
		(net "GND")
	)
	(via
		(at 324.783958 -205.482952)
		(size 0.508)
		(drill 0.254)
		(layers "F.Cu" "B.Cu")
		(net "GND")
	)
	(via
		(at 187.060078 -247.485408)
		(size 0.4826)
		(drill 0.254)
		(layers "F.Cu" "B.Cu")
		(net "GND")
	)
	(via
		(at 180.900324 -312.935366)
		(size 0.4826)
		(drill 0.254)
		(layers "F.Cu" "B.Cu")
		(net "GND")
	)
	(via
		(at 42.955718 -293.38524)
		(size 0.4826)
		(drill 0.254)
		(layers "F.Cu" "B.Cu")
		(net "GND")
	)
	(via
		(at 390.094724 -266.796012)
		(size 0.4064)
		(drill 0.2032)
		(layers "F.Cu" "B.Cu")
		(net "GND")
	)
	(via
		(at 138.349736 -429.147224)
		(size 0.4572)
		(drill 0.2032)
		(layers "F.Cu" "B.Cu")
		(net "GND")
	)
	(via
		(at 168.527984 -310.385206)
		(size 0.4826)
		(drill 0.254)
		(layers "F.Cu" "B.Cu")
		(net "GND")
	)
	(via
		(at 373.75973 -412.212536)
		(size 0.4572)
		(drill 0.254)
		(layers "F.Cu" "B.Cu")
		(net "GND")
	)
	(via
		(at 295.724072 -289.135058)
		(size 0.4826)
		(drill 0.254)
		(layers "F.Cu" "B.Cu")
		(net "GND")
	)
	(via
		(at 140.397992 -375.793)
		(size 0.508)
		(drill 0.254)
		(layers "F.Cu" "B.Cu")
		(net "GND")
	)
	(via
		(at 288.587942 -399.704052)
		(size 0.508)
		(drill 0.254)
		(layers "F.Cu" "B.Cu")
		(net "GND")
	)
	(via
		(at 99.861116 -274.896326)
		(size 0.4064)
		(drill 0.2032)
		(layers "F.Cu" "B.Cu")
		(net "GND")
	)
	(via
		(at 48.714914 -342.816434)
		(size 0.508)
		(drill 0.254)
		(layers "F.Cu" "B.Cu")
		(net "GND")
	)
	(via
		(at 305.216306 -412.84652)
		(size 0.4064)
		(drill 0.2032)
		(layers "F.Cu" "B.Cu")
		(net "GND")
	)
	(via
		(at 288.180018 -217.73515)
		(size 0.4826)
		(drill 0.254)
		(layers "F.Cu" "B.Cu")
		(net "GND")
	)
	(via
		(at 121.944638 -290.286186)
		(size 0.4064)
		(drill 0.2032)
		(layers "F.Cu" "B.Cu")
		(net "GND")
	)
	(via
		(at 199.8218 -304.010314)
		(size 0.4826)
		(drill 0.254)
		(layers "F.Cu" "B.Cu")
		(net "GND")
	)
	(via
		(at 100.971096 -225.854514)
		(size 0.4064)
		(drill 0.2032)
		(layers "F.Cu" "B.Cu")
		(net "GND")
	)
	(via
		(at 204.8637 -209.235294)
		(size 0.4826)
		(drill 0.254)
		(layers "F.Cu" "B.Cu")
		(net "GND")
	)
	(via
		(at 191.159384 -441.227718)
		(size 0.508)
		(drill 0.254)
		(layers "F.Cu" "B.Cu")
		(net "GND")
	)
	(via
		(at 78.123542 -333.05369)
		(size 0.49022)
		(drill 0.254)
		(layers "F.Cu" "B.Cu")
		(net "GND")
	)
	(via
		(at 151.656034 -203.014072)
		(size 0.508)
		(drill 0.254)
		(layers "F.Cu" "B.Cu")
		(net "GND")
	)
	(via
		(at 405.406352 -394.831062)
		(size 0.4064)
		(drill 0.2032)
		(layers "F.Cu" "B.Cu")
		(net "GND")
	)
	(via
		(at 382.676654 -416.020504)
		(size 0.4572)
		(drill 0.254)
		(layers "F.Cu" "B.Cu")
		(net "GND")
	)
	(via
		(at 311.91835 -396.710662)
		(size 0.4064)
		(drill 0.2032)
		(layers "F.Cu" "B.Cu")
		(net "GND")
	)
	(via
		(at 56.868314 -12.37488)
		(size 0.508)
		(drill 0.254)
		(layers "F.Cu" "B.Cu")
		(net "GND")
	)
	(via
		(at 21.879306 -4.32943)
		(size 0.508)
		(drill 0.254)
		(layers "F.Cu" "B.Cu")
		(net "GND")
	)
	(via
		(at 5.412486 -100.510848)
		(size 0.508)
		(drill 0.254)
		(layers "F.Cu" "B.Cu")
		(net "GND")
	)
	(via
		(at 403.444202 -402.284438)
		(size 0.4572)
		(drill 0.254)
		(layers "F.Cu" "B.Cu")
		(net "GND")
	)
	(via
		(at 399.317718 -176.605184)
		(size 0.49022)
		(drill 0.254)
		(layers "F.Cu" "B.Cu")
		(net "GND")
	)
	(via
		(at 146.742912 -247.99036)
		(size 0.4064)
		(drill 0.2032)
		(layers "F.Cu" "B.Cu")
		(net "GND")
	)
	(via
		(at 188.177678 -295.510458)
		(size 0.4826)
		(drill 0.254)
		(layers "F.Cu" "B.Cu")
		(net "GND")
	)
	(via
		(at 41.62425 -221.985332)
		(size 0.4826)
		(drill 0.254)
		(layers "F.Cu" "B.Cu")
		(net "GND")
	)
	(via
		(at 198.7042 -216.885266)
		(size 0.4826)
		(drill 0.254)
		(layers "F.Cu" "B.Cu")
		(net "GND")
	)
	(via
		(at 363.304836 -265.986006)
		(size 0.4064)
		(drill 0.2032)
		(layers "F.Cu" "B.Cu")
		(net "GND")
	)
	(via
		(at 140.274802 -289.47618)
		(size 0.4064)
		(drill 0.2032)
		(layers "F.Cu" "B.Cu")
		(net "GND")
	)
	(via
		(at 381.634746 -263.555988)
		(size 0.4064)
		(drill 0.2032)
		(layers "F.Cu" "B.Cu")
		(net "GND")
	)
	(via
		(at 83.111086 -242.05438)
		(size 0.4064)
		(drill 0.2032)
		(layers "F.Cu" "B.Cu")
		(net "GND")
	)
	(via
		(at 146.214846 -394.352018)
		(size 0.508)
		(drill 0.254)
		(layers "F.Cu" "B.Cu")
		(net "GND")
	)
	(via
		(at 174.884334 -38.730428)
		(size 0.508)
		(drill 0.254)
		(layers "F.Cu" "B.Cu")
		(net "GND")
	)
	(via
		(at 138.987784 -49.595024)
		(size 0.508)
		(drill 0.254)
		(layers "F.Cu" "B.Cu")
		(net "GND")
	)
	(via
		(at 303.596294 -421.586152)
		(size 0.4572)
		(drill 0.254)
		(layers "F.Cu" "B.Cu")
		(net "GND")
	)
	(via
		(at 124.464826 -229.094538)
		(size 0.4064)
		(drill 0.2032)
		(layers "F.Cu" "B.Cu")
		(net "GND")
	)
	(via
		(at 346.567506 -418.412168)
		(size 0.4064)
		(drill 0.2032)
		(layers "F.Cu" "B.Cu")
		(net "GND")
	)
	(via
		(at 374.754902 -229.904036)
		(size 0.4064)
		(drill 0.2032)
		(layers "F.Cu" "B.Cu")
		(net "GND")
	)
	(via
		(at 381.145034 -421.586152)
		(size 0.4572)
		(drill 0.254)
		(layers "F.Cu" "B.Cu")
		(net "GND")
	)
	(via
		(at 392.444732 -269.22603)
		(size 0.4064)
		(drill 0.2032)
		(layers "F.Cu" "B.Cu")
		(net "GND")
	)
	(via
		(at 388.68477 -269.22603)
		(size 0.4064)
		(drill 0.2032)
		(layers "F.Cu" "B.Cu")
		(net "GND")
	)
	(via
		(at 79.41691 -186.648598)
		(size 0.508)
		(drill 0.254)
		(layers "F.Cu" "B.Cu")
		(net "GND")
	)
	(via
		(at 450.088 -250.884944)
		(size 0.4826)
		(drill 0.254)
		(layers "F.Cu" "B.Cu")
		(net "GND")
	)
	(via
		(at 61.108336 -411.936184)
		(size 0.4572)
		(drill 0.254)
		(layers "F.Cu" "B.Cu")
		(net "GND")
	)
	(via
		(at 268.263878 -237.285022)
		(size 0.4826)
		(drill 0.254)
		(layers "F.Cu" "B.Cu")
		(net "GND")
	)
	(via
		(at 357.371142 -251.774198)
		(size 0.4064)
		(drill 0.2032)
		(layers "F.Cu" "B.Cu")
		(net "GND")
	)
	(via
		(at 211.854034 -340.984078)
		(size 0.508)
		(drill 0.254)
		(layers "F.Cu" "B.Cu")
		(net "GND")
	)
	(via
		(at 422.627806 -230.485188)
		(size 0.4826)
		(drill 0.254)
		(layers "F.Cu" "B.Cu")
		(net "GND")
	)
	(via
		(at 86.249764 -427.699678)
		(size 0.4572)
		(drill 0.2032)
		(layers "F.Cu" "B.Cu")
		(net "GND")
	)
	(via
		(at 431.711608 -351.70618)
		(size 0.49022)
		(drill 0.254)
		(layers "F.Cu" "B.Cu")
		(net "GND")
	)
	(via
		(at 64.171576 -411.936184)
		(size 0.4572)
		(drill 0.254)
		(layers "F.Cu" "B.Cu")
		(net "GND")
	)
	(via
		(at 353.61118 -251.774198)
		(size 0.4064)
		(drill 0.2032)
		(layers "F.Cu" "B.Cu")
		(net "GND")
	)
	(via
		(at 413.220662 -412.84652)
		(size 0.4064)
		(drill 0.2032)
		(layers "F.Cu" "B.Cu")
		(net "GND")
	)
	(via
		(at 71.249794 -438.651396)
		(size 0.4572)
		(drill 0.2032)
		(layers "F.Cu" "B.Cu")
		(net "GND")
	)
	(via
		(at 390.695942 -420.952168)
		(size 0.4064)
		(drill 0.2032)
		(layers "F.Cu" "B.Cu")
		(net "GND")
	)
	(via
		(at 277.192232 -310.384952)
		(size 0.4826)
		(drill 0.254)
		(layers "F.Cu" "B.Cu")
		(net "GND")
	)
	(via
		(at 187.060078 -217.735404)
		(size 0.4826)
		(drill 0.254)
		(layers "F.Cu" "B.Cu")
		(net "GND")
	)
	(via
		(at 78.41107 -248.534428)
		(size 0.4064)
		(drill 0.2032)
		(layers "F.Cu" "B.Cu")
		(net "GND")
	)
	(via
		(at 15.094458 -417.68014)
		(size 0.508)
		(drill 0.254)
		(layers "F.Cu" "B.Cu")
		(net "GND")
	)
	(via
		(at 184.732168 -120.642634)
		(size 0.4572)
		(drill 0.254)
		(layers "F.Cu" "B.Cu")
		(net "GND")
	)
	(via
		(at 407.45537 -412.212536)
		(size 0.4572)
		(drill 0.254)
		(layers "F.Cu" "B.Cu")
		(net "GND")
	)
	(via
		(at 268.99997 -125.104398)
		(size 0.508)
		(drill 0.254)
		(layers "F.Cu" "B.Cu")
		(net "GND")
	)
	(via
		(at 275.807932 -237.285022)
		(size 0.4826)
		(drill 0.254)
		(layers "F.Cu" "B.Cu")
		(net "GND")
	)
	(via
		(at 97.040954 -291.096192)
		(size 0.4064)
		(drill 0.2032)
		(layers "F.Cu" "B.Cu")
		(net "GND")
	)
	(via
		(at 351.943924 -400.212814)
		(size 0.4064)
		(drill 0.2032)
		(layers "F.Cu" "B.Cu")
		(net "GND")
	)
	(via
		(at 86.344252 -382.85293)
		(size 0.4064)
		(drill 0.2032)
		(layers "F.Cu" "B.Cu")
		(net "GND")
	)
	(via
		(at 129.934716 -295.956228)
		(size 0.4064)
		(drill 0.2032)
		(layers "F.Cu" "B.Cu")
		(net "GND")
	)
	(via
		(at 70.617334 -379.321568)
		(size 0.508)
		(drill 0.254)
		(layers "F.Cu" "B.Cu")
		(net "GND")
	)
	(via
		(at 76.249784 -436.347362)
		(size 0.4572)
		(drill 0.2032)
		(layers "F.Cu" "B.Cu")
		(net "GND")
	)
	(via
		(at 338.101178 -247.724168)
		(size 0.4064)
		(drill 0.2032)
		(layers "F.Cu" "B.Cu")
		(net "GND")
	)
	(via
		(at 110.671102 -275.706332)
		(size 0.4064)
		(drill 0.2032)
		(layers "F.Cu" "B.Cu")
		(net "GND")
	)
	(via
		(at 59.428126 -198.185278)
		(size 0.4826)
		(drill 0.254)
		(layers "F.Cu" "B.Cu")
		(net "GND")
	)
	(via
		(at 303.268126 -267.885164)
		(size 0.4826)
		(drill 0.254)
		(layers "F.Cu" "B.Cu")
		(net "GND")
	)
	(via
		(at 165.32733 -418.62121)
		(size 0.508)
		(drill 0.254)
		(layers "F.Cu" "B.Cu")
		(net "GND")
	)
	(via
		(at 65.249806 -433.747164)
		(size 0.4572)
		(drill 0.2032)
		(layers "F.Cu" "B.Cu")
		(net "GND")
	)
	(via
		(at 34.695384 -441.227718)
		(size 0.508)
		(drill 0.254)
		(layers "F.Cu" "B.Cu")
		(net "GND")
	)
	(via
		(at 20.80387 -384.51409)
		(size 0.508)
		(drill 0.254)
		(layers "F.Cu" "B.Cu")
		(net "GND")
	)
	(via
		(at 269.423134 -333.744316)
		(size 0.508)
		(drill 0.254)
		(layers "F.Cu" "B.Cu")
		(net "GND")
	)
	(via
		(at 303.268126 -245.785132)
		(size 0.4826)
		(drill 0.254)
		(layers "F.Cu" "B.Cu")
		(net "GND")
	)
	(via
		(at 188.215778 -194.885564)
		(size 0.4826)
		(drill 0.254)
		(layers "F.Cu" "B.Cu")
		(net "GND")
	)
	(via
		(at 93.450918 -245.294404)
		(size 0.4064)
		(drill 0.2032)
		(layers "F.Cu" "B.Cu")
		(net "GND")
	)
	(via
		(at 365.564928 -151.457914)
		(size 0.508)
		(drill 0.254)
		(layers "F.Cu" "B.Cu")
		(net "GND")
	)
	(via
		(at 347.33103 -269.22603)
		(size 0.4064)
		(drill 0.2032)
		(layers "F.Cu" "B.Cu")
		(net "GND")
	)
	(via
		(at 402.86051 -419.046152)
		(size 0.4572)
		(drill 0.254)
		(layers "F.Cu" "B.Cu")
		(net "GND")
	)
	(via
		(at 160.645094 -403.830536)
		(size 0.4572)
		(drill 0.254)
		(layers "F.Cu" "B.Cu")
		(net "GND")
	)
	(via
		(at 419.912038 -199.035162)
		(size 0.4826)
		(drill 0.254)
		(layers "F.Cu" "B.Cu")
		(net "GND")
	)
	(via
		(at 136.98474 -291.906198)
		(size 0.4064)
		(drill 0.2032)
		(layers "F.Cu" "B.Cu")
		(net "GND")
	)
	(via
		(at 116.304822 -288.666174)
		(size 0.4064)
		(drill 0.2032)
		(layers "F.Cu" "B.Cu")
		(net "GND")
	)
	(via
		(at 346.481654 -421.586152)
		(size 0.4572)
		(drill 0.254)
		(layers "F.Cu" "B.Cu")
		(net "GND")
	)
	(via
		(at 140.822426 -412.570168)
		(size 0.4064)
		(drill 0.2032)
		(layers "F.Cu" "B.Cu")
		(net "GND")
	)
	(via
		(at 189.775846 -227.935282)
		(size 0.4826)
		(drill 0.254)
		(layers "F.Cu" "B.Cu")
		(net "GND")
	)
	(via
		(at 235.84789 -232.017316)
		(size 0.4826)
		(drill 0.254)
		(layers "F.Cu" "B.Cu")
		(net "GND")
	)
	(via
		(at 417.585652 -210.51012)
		(size 0.4826)
		(drill 0.254)
		(layers "F.Cu" "B.Cu")
		(net "GND")
	)
	(via
		(at 408.1907 -378.07773)
		(size 0.508)
		(drill 0.254)
		(layers "F.Cu" "B.Cu")
		(net "GND")
	)
	(via
		(at 147.82419 -96.412558)
		(size 0.508)
		(drill 0.254)
		(layers "F.Cu" "B.Cu")
		(net "GND")
	)
	(via
		(at 117.961156 -372.15953)
		(size 0.508)
		(drill 0.254)
		(layers "F.Cu" "B.Cu")
		(net "GND")
	)
	(via
		(at 361.594908 -241.24412)
		(size 0.4064)
		(drill 0.2032)
		(layers "F.Cu" "B.Cu")
		(net "GND")
	)
	(via
		(at 319.416176 -400.212814)
		(size 0.4064)
		(drill 0.2032)
		(layers "F.Cu" "B.Cu")
		(net "GND")
	)
	(via
		(at 467.5378 -395.783054)
		(size 0.508)
		(drill 0.254)
		(layers "F.Cu" "B.Cu")
		(net "GND")
	)
	(via
		(at 408.905964 -19.13636)
		(size 0.508)
		(drill 0.254)
		(layers "F.Cu" "B.Cu")
		(net "GND")
	)
	(via
		(at 125.2347 -265.176254)
		(size 0.4064)
		(drill 0.2032)
		(layers "F.Cu" "B.Cu")
		(net "GND")
	)
	(via
		(at 168.527984 -246.63527)
		(size 0.4826)
		(drill 0.254)
		(layers "F.Cu" "B.Cu")
		(net "GND")
	)
	(via
		(at 319.416176 -402.309838)
		(size 0.4572)
		(drill 0.254)
		(layers "F.Cu" "B.Cu")
		(net "GND")
	)
	(via
		(at 24.811482 -437.509158)
		(size 0.508)
		(drill 0.254)
		(layers "F.Cu" "B.Cu")
		(net "GND")
	)
	(via
		(at 417.585652 -304.01006)
		(size 0.4826)
		(drill 0.254)
		(layers "F.Cu" "B.Cu")
		(net "GND")
	)
	(via
		(at 107.550966 -240.434368)
		(size 0.4064)
		(drill 0.2032)
		(layers "F.Cu" "B.Cu")
		(net "GND")
	)
	(via
		(at 110.371128 -222.61449)
		(size 0.4064)
		(drill 0.2032)
		(layers "F.Cu" "B.Cu")
		(net "GND")
	)
	(via
		(at 87.15375 -186.580526)
		(size 0.508)
		(drill 0.254)
		(layers "F.Cu" "B.Cu")
		(net "GND")
	)
	(via
		(at 386.078476 -394.831062)
		(size 0.4064)
		(drill 0.2032)
		(layers "F.Cu" "B.Cu")
		(net "GND")
	)
	(via
		(at 72.102472 -403.830536)
		(size 0.4572)
		(drill 0.254)
		(layers "F.Cu" "B.Cu")
		(net "GND")
	)
	(via
		(at 64.171576 -413.204152)
		(size 0.4572)
		(drill 0.254)
		(layers "F.Cu" "B.Cu")
		(net "GND")
	)
	(via
		(at 353.911154 -265.986006)
		(size 0.4064)
		(drill 0.2032)
		(layers "F.Cu" "B.Cu")
		(net "GND")
	)
	(via
		(at 292.280086 -248.335038)
		(size 0.4826)
		(drill 0.254)
		(layers "F.Cu" "B.Cu")
		(net "GND")
	)
	(via
		(at 143.56461 -287.046162)
		(size 0.4064)
		(drill 0.2032)
		(layers "F.Cu" "B.Cu")
		(net "GND")
	)
	(via
		(at 374.584722 -280.566114)
		(size 0.4064)
		(drill 0.2032)
		(layers "F.Cu" "B.Cu")
		(net "GND")
	)
	(via
		(at 181.218586 -391.392918)
		(size 0.508)
		(drill 0.254)
		(layers "F.Cu" "B.Cu")
		(net "GND")
	)
	(via
		(at 18.992342 -200.735438)
		(size 0.4826)
		(drill 0.254)
		(layers "F.Cu" "B.Cu")
		(net "GND")
	)
	(via
		(at 176.072038 -222.835216)
		(size 0.4826)
		(drill 0.254)
		(layers "F.Cu" "B.Cu")
		(net "GND")
	)
	(via
		(at 157.812486 -122.769884)
		(size 0.508)
		(drill 0.254)
		(layers "F.Cu" "B.Cu")
		(net "GND")
	)
	(via
		(at 157.581854 -403.830536)
		(size 0.4572)
		(drill 0.254)
		(layers "F.Cu" "B.Cu")
		(net "GND")
	)
	(via
		(at 393.084812 -248.534174)
		(size 0.4064)
		(drill 0.2032)
		(layers "F.Cu" "B.Cu")
		(net "GND")
	)
	(via
		(at 431.295556 -107.70997)
		(size 0.508)
		(drill 0.254)
		(layers "F.Cu" "B.Cu")
		(net "GND")
	)
	(via
		(at 173.295056 -56.925464)
		(size 0.508)
		(drill 0.254)
		(layers "F.Cu" "B.Cu")
		(net "GND")
	)
	(via
		(at 82.249772 -431.29962)
		(size 0.4572)
		(drill 0.2032)
		(layers "F.Cu" "B.Cu")
		(net "GND")
	)
	(via
		(at 284.736032 -297.635168)
		(size 0.4826)
		(drill 0.254)
		(layers "F.Cu" "B.Cu")
		(net "GND")
	)
	(via
		(at 174.687738 -295.9354)
		(size 0.4826)
		(drill 0.254)
		(layers "F.Cu" "B.Cu")
		(net "GND")
	)
	(via
		(at 368.644678 -243.674138)
		(size 0.4064)
		(drill 0.2032)
		(layers "F.Cu" "B.Cu")
		(net "GND")
	)
	(via
		(at 393.317984 -6.091174)
		(size 0.508)
		(drill 0.254)
		(layers "F.Cu" "B.Cu")
		(net "GND")
	)
	(via
		(at 104.090978 -295.146222)
		(size 0.4064)
		(drill 0.2032)
		(layers "F.Cu" "B.Cu")
		(net "GND")
	)
	(via
		(at 204.8637 -277.235412)
		(size 0.4826)
		(drill 0.254)
		(layers "F.Cu" "B.Cu")
		(net "GND")
	)
	(via
		(at 288.300922 -394.556234)
		(size 0.508)
		(drill 0.254)
		(layers "F.Cu" "B.Cu")
		(net "GND")
	)
	(via
		(at 191.160146 -310.385206)
		(size 0.4826)
		(drill 0.254)
		(layers "F.Cu" "B.Cu")
		(net "GND")
	)
	(via
		(at 203.71562 -332.805786)
		(size 0.508)
		(drill 0.254)
		(layers "F.Cu" "B.Cu")
		(net "GND")
	)
	(via
		(at 381.634746 -292.71595)
		(size 0.4064)
		(drill 0.2032)
		(layers "F.Cu" "B.Cu")
		(net "GND")
	)
	(via
		(at 132.349748 -428.851314)
		(size 0.4572)
		(drill 0.2032)
		(layers "F.Cu" "B.Cu")
		(net "GND")
	)
	(via
		(at 81.832196 -32.377888)
		(size 0.6604)
		(drill 0.3302)
		(layers "F.Cu" "B.Cu")
		(net "GND")
	)
	(via
		(at 269.648178 -251.735082)
		(size 0.4826)
		(drill 0.254)
		(layers "F.Cu" "B.Cu")
		(net "GND")
	)
	(via
		(at 439.100214 -308.685184)
		(size 0.4826)
		(drill 0.254)
		(layers "F.Cu" "B.Cu")
		(net "GND")
	)
	(via
		(at 331.351128 -295.145968)
		(size 0.4064)
		(drill 0.2032)
		(layers "F.Cu" "B.Cu")
		(net "GND")
	)
	(via
		(at 89.038684 -412.570168)
		(size 0.4064)
		(drill 0.2032)
		(layers "F.Cu" "B.Cu")
		(net "GND")
	)
	(via
		(at 79.821024 -226.66452)
		(size 0.4064)
		(drill 0.2032)
		(layers "F.Cu" "B.Cu")
		(net "GND")
	)
	(via
		(at 63.416434 -393.927838)
		(size 0.4572)
		(drill 0.254)
		(layers "F.Cu" "B.Cu")
		(net "GND")
	)
	(via
		(at 177.160682 -330.861924)
		(size 0.508)
		(drill 0.254)
		(layers "F.Cu" "B.Cu")
		(net "GND")
	)
	(via
		(at 94.390972 -250.15444)
		(size 0.4064)
		(drill 0.2032)
		(layers "F.Cu" "B.Cu")
		(net "GND")
	)
	(via
		(at 104.731058 -245.294404)
		(size 0.4064)
		(drill 0.2032)
		(layers "F.Cu" "B.Cu")
		(net "GND")
	)
	(via
		(at 182.078122 -6.042152)
		(size 0.508)
		(drill 0.254)
		(layers "F.Cu" "B.Cu")
		(net "GND")
	)
	(via
		(at 269.648178 -288.285174)
		(size 0.4826)
		(drill 0.254)
		(layers "F.Cu" "B.Cu")
		(net "GND")
	)
	(via
		(at 370.524786 -225.85426)
		(size 0.4064)
		(drill 0.2032)
		(layers "F.Cu" "B.Cu")
		(net "GND")
	)
	(via
		(at 407.448258 -12.37488)
		(size 0.508)
		(drill 0.254)
		(layers "F.Cu" "B.Cu")
		(net "GND")
	)
	(via
		(at 380.864872 -224.234248)
		(size 0.4064)
		(drill 0.2032)
		(layers "F.Cu" "B.Cu")
		(net "GND")
	)
	(via
		(at 127.584708 -278.946356)
		(size 0.4064)
		(drill 0.2032)
		(layers "F.Cu" "B.Cu")
		(net "GND")
	)
	(via
		(at 336.249518 -432.747166)
		(size 0.4572)
		(drill 0.2032)
		(layers "F.Cu" "B.Cu")
		(net "GND")
	)
	(via
		(at 13.830046 -416.997388)
		(size 0.508)
		(drill 0.254)
		(layers "F.Cu" "B.Cu")
		(net "GND")
	)
	(via
		(at 106.246422 -408.30373)
		(size 0.508)
		(drill 0.254)
		(layers "F.Cu" "B.Cu")
		(net "GND")
	)
	(via
		(at 109.549946 -51.85283)
		(size 0.508)
		(drill 0.254)
		(layers "F.Cu" "B.Cu")
		(net "GND")
	)
	(via
		(at 346.249498 -432.451256)
		(size 0.4572)
		(drill 0.2032)
		(layers "F.Cu" "B.Cu")
		(net "GND")
	)
	(via
		(at 269.648178 -263.634982)
		(size 0.4826)
		(drill 0.254)
		(layers "F.Cu" "B.Cu")
		(net "GND")
	)
	(via
		(at 409.44419 -402.309838)
		(size 0.4572)
		(drill 0.254)
		(layers "F.Cu" "B.Cu")
		(net "GND")
	)
	(via
		(at 389.79475 -233.14406)
		(size 0.4064)
		(drill 0.2032)
		(layers "F.Cu" "B.Cu")
		(net "GND")
	)
	(via
		(at 121.644664 -246.914416)
		(size 0.4064)
		(drill 0.2032)
		(layers "F.Cu" "B.Cu")
		(net "GND")
	)
	(via
		(at 128.994662 -271.656302)
		(size 0.4064)
		(drill 0.2032)
		(layers "F.Cu" "B.Cu")
		(net "GND")
	)
	(via
		(at 179.516024 -204.985366)
		(size 0.4826)
		(drill 0.254)
		(layers "F.Cu" "B.Cu")
		(net "GND")
	)
	(via
		(at 173.35627 -238.135414)
		(size 0.4826)
		(drill 0.254)
		(layers "F.Cu" "B.Cu")
		(net "GND")
	)
	(via
		(at 49.168304 -275.53539)
		(size 0.4826)
		(drill 0.254)
		(layers "F.Cu" "B.Cu")
		(net "GND")
	)
	(via
		(at 83.88096 -287.856422)
		(size 0.4064)
		(drill 0.2032)
		(layers "F.Cu" "B.Cu")
		(net "GND")
	)
	(via
		(at 344.979244 -382.34493)
		(size 0.508)
		(drill 0.254)
		(layers "F.Cu" "B.Cu")
		(net "GND")
	)
	(via
		(at 421.296338 -219.435172)
		(size 0.4826)
		(drill 0.254)
		(layers "F.Cu" "B.Cu")
		(net "GND")
	)
	(via
		(at 422.627806 -237.285022)
		(size 0.4826)
		(drill 0.254)
		(layers "F.Cu" "B.Cu")
		(net "GND")
	)
	(via
		(at 401.056094 -416.020504)
		(size 0.4572)
		(drill 0.254)
		(layers "F.Cu" "B.Cu")
		(net "GND")
	)
	(via
		(at 236.714792 -226.414838)
		(size 0.4826)
		(drill 0.254)
		(layers "F.Cu" "B.Cu")
		(net "GND")
	)
	(via
		(at 375.224802 -242.054126)
		(size 0.4064)
		(drill 0.2032)
		(layers "F.Cu" "B.Cu")
		(net "GND")
	)
	(via
		(at 290.895786 -209.23504)
		(size 0.4826)
		(drill 0.254)
		(layers "F.Cu" "B.Cu")
		(net "GND")
	)
	(via
		(at 168.527984 -222.835216)
		(size 0.4826)
		(drill 0.254)
		(layers "F.Cu" "B.Cu")
		(net "GND")
	)
	(via
		(at 268.263878 -284.034992)
		(size 0.4826)
		(drill 0.254)
		(layers "F.Cu" "B.Cu")
		(net "GND")
	)
	(via
		(at 110.848394 -188.954918)
		(size 0.508)
		(drill 0.254)
		(layers "F.Cu" "B.Cu")
		(net "GND")
	)
	(via
		(at 250.534424 -278.640032)
		(size 0.508)
		(drill 0.254)
		(layers "F.Cu" "B.Cu")
		(net "GND")
	)
	(via
		(at 414.415732 -149.482302)
		(size 0.508)
		(drill 0.254)
		(layers "F.Cu" "B.Cu")
		(net "GND")
	)
	(via
		(at 124.934726 -249.344434)
		(size 0.4064)
		(drill 0.2032)
		(layers "F.Cu" "B.Cu")
		(net "GND")
	)
	(via
		(at 228.092 -287.06064)
		(size 0.508)
		(drill 0.254)
		(layers "F.Cu" "B.Cu")
		(net "GND")
	)
	(via
		(at 59.428126 -248.335292)
		(size 0.4826)
		(drill 0.254)
		(layers "F.Cu" "B.Cu")
		(net "GND")
	)
	(via
		(at 222.152718 -275.502878)
		(size 0.508)
		(drill 0.254)
		(layers "F.Cu" "B.Cu")
		(net "GND")
	)
	(via
		(at 256.779776 -325.056754)
		(size 0.508)
		(drill 0.254)
		(layers "F.Cu" "B.Cu")
		(net "GND")
	)
	(via
		(at 84.355432 -411.936184)
		(size 0.4572)
		(drill 0.254)
		(layers "F.Cu" "B.Cu")
		(net "GND")
	)
	(via
		(at 412.367984 -318.885062)
		(size 0.4826)
		(drill 0.254)
		(layers "F.Cu" "B.Cu")
		(net "GND")
	)
	(via
		(at 442.50991 -391.06348)
		(size 0.508)
		(drill 0.254)
		(layers "F.Cu" "B.Cu")
		(net "GND")
	)
	(via
		(at 284.736032 -288.285174)
		(size 0.4826)
		(drill 0.254)
		(layers "F.Cu" "B.Cu")
		(net "GND")
	)
	(via
		(at 344.211148 -237.19409)
		(size 0.4064)
		(drill 0.2032)
		(layers "F.Cu" "B.Cu")
		(net "GND")
	)
	(via
		(at 358.311196 -225.85426)
		(size 0.4064)
		(drill 0.2032)
		(layers "F.Cu" "B.Cu")
		(net "GND")
	)
	(via
		(at 284.575504 -416.987736)
		(size 0.4572)
		(drill 0.254)
		(layers "F.Cu" "B.Cu")
		(net "GND")
	)
	(via
		(at 56.388 -40.64)
		(size 0.508)
		(drill 0.254)
		(layers "F.Cu" "B.Cu")
		(net "GND")
	)
	(via
		(at 416.468052 -318.035178)
		(size 0.4826)
		(drill 0.254)
		(layers "F.Cu" "B.Cu")
		(net "GND")
	)
	(via
		(at 402.619718 -171.177712)
		(size 0.508)
		(drill 0.254)
		(layers "F.Cu" "B.Cu")
		(net "GND")
	)
	(via
		(at 138.864848 -293.52621)
		(size 0.4064)
		(drill 0.2032)
		(layers "F.Cu" "B.Cu")
		(net "GND")
	)
	(via
		(at 305.983894 -305.28514)
		(size 0.4826)
		(drill 0.254)
		(layers "F.Cu" "B.Cu")
		(net "GND")
	)
	(via
		(at 178.33213 -107.063032)
		(size 0.4572)
		(drill 0.254)
		(layers "F.Cu" "B.Cu")
		(net "GND")
	)
	(via
		(at 110.671102 -293.52621)
		(size 0.4064)
		(drill 0.2032)
		(layers "F.Cu" "B.Cu")
		(net "GND")
	)
	(via
		(at 358.311196 -232.334054)
		(size 0.4064)
		(drill 0.2032)
		(layers "F.Cu" "B.Cu")
		(net "GND")
	)
	(via
		(at 60.998354 -348.709488)
		(size 0.49022)
		(drill 0.254)
		(layers "F.Cu" "B.Cu")
		(net "GND")
	)
	(via
		(at 425.393358 -357.554276)
		(size 0.508)
		(drill 0.254)
		(layers "F.Cu" "B.Cu")
		(net "GND")
	)
	(via
		(at 336.521044 -263.555988)
		(size 0.4064)
		(drill 0.2032)
		(layers "F.Cu" "B.Cu")
		(net "GND")
	)
	(via
		(at 153.178256 -11.308842)
		(size 0.508)
		(drill 0.254)
		(layers "F.Cu" "B.Cu")
		(net "GND")
	)
	(via
		(at 374.446292 -379.88113)
		(size 0.508)
		(drill 0.254)
		(layers "F.Cu" "B.Cu")
		(net "GND")
	)
	(via
		(at 133.394704 -239.624362)
		(size 0.4064)
		(drill 0.2032)
		(layers "F.Cu" "B.Cu")
		(net "GND")
	)
	(via
		(at 404.477982 -418.412168)
		(size 0.4064)
		(drill 0.2032)
		(layers "F.Cu" "B.Cu")
		(net "GND")
	)
	(via
		(at 101.91115 -230.714296)
		(size 0.4064)
		(drill 0.2032)
		(layers "F.Cu" "B.Cu")
		(net "GND")
	)
	(via
		(at 102.108762 -369.69573)
		(size 0.508)
		(drill 0.254)
		(layers "F.Cu" "B.Cu")
		(net "GND")
	)
	(via
		(at 289.3568 -97.967292)
		(size 0.508)
		(drill 0.254)
		(layers "F.Cu" "B.Cu")
		(net "GND")
	)
	(via
		(at 149.13356 -65.43802)
		(size 0.508)
		(drill 0.254)
		(layers "F.Cu" "B.Cu")
		(net "GND")
	)
	(via
		(at 50.861214 -372.15953)
		(size 0.508)
		(drill 0.254)
		(layers "F.Cu" "B.Cu")
		(net "GND")
	)
	(via
		(at 77.112876 -277.870412)
		(size 0.4064)
		(drill 0.2032)
		(layers "F.Cu" "B.Cu")
		(net "GND")
	)
	(via
		(at 144.391888 -37.903404)
		(size 0.508)
		(drill 0.254)
		(layers "F.Cu" "B.Cu")
		(net "GND")
	)
	(via
		(at 153.349706 -437.34736)
		(size 0.4572)
		(drill 0.2032)
		(layers "F.Cu" "B.Cu")
		(net "GND")
	)
	(via
		(at 134.164832 -288.666174)
		(size 0.4064)
		(drill 0.2032)
		(layers "F.Cu" "B.Cu")
		(net "GND")
	)
	(via
		(at 354.551234 -240.434114)
		(size 0.4064)
		(drill 0.2032)
		(layers "F.Cu" "B.Cu")
		(net "GND")
	)
	(via
		(at 365.19104 -390.92632)
		(size 0.508)
		(drill 0.254)
		(layers "F.Cu" "B.Cu")
		(net "GND")
	)
	(via
		(at 306.250594 -238.560102)
		(size 0.4826)
		(drill 0.254)
		(layers "F.Cu" "B.Cu")
		(net "GND")
	)
	(via
		(at 283.973016 -402.566632)
		(size 0.508)
		(drill 0.254)
		(layers "F.Cu" "B.Cu")
		(net "GND")
	)
	(via
		(at 334.585564 -150.500588)
		(size 0.508)
		(drill 0.254)
		(layers "F.Cu" "B.Cu")
		(net "GND")
	)
	(via
		(at 305.159156 -381.68453)
		(size 0.508)
		(drill 0.254)
		(layers "F.Cu" "B.Cu")
		(net "GND")
	)
	(via
		(at 83.580986 -252.584458)
		(size 0.4064)
		(drill 0.2032)
		(layers "F.Cu" "B.Cu")
		(net "GND")
	)
	(via
		(at 29.252164 -250.035314)
		(size 0.4826)
		(drill 0.254)
		(layers "F.Cu" "B.Cu")
		(net "GND")
	)
	(via
		(at 76.643738 -31.615126)
		(size 0.508)
		(drill 0.254)
		(layers "F.Cu" "B.Cu")
		(net "GND")
	)
	(via
		(at 133.864858 -225.854514)
		(size 0.4064)
		(drill 0.2032)
		(layers "F.Cu" "B.Cu")
		(net "GND")
	)
	(via
		(at 61.615574 -347.287088)
		(size 0.49022)
		(drill 0.254)
		(layers "F.Cu" "B.Cu")
		(net "GND")
	)
	(via
		(at 412.05023 -419.046152)
		(size 0.4572)
		(drill 0.254)
		(layers "F.Cu" "B.Cu")
		(net "GND")
	)
	(via
		(at 39.748714 -342.816434)
		(size 0.508)
		(drill 0.254)
		(layers "F.Cu" "B.Cu")
		(net "GND")
	)
	(via
		(at 287.062418 -304.860198)
		(size 0.4826)
		(drill 0.254)
		(layers "F.Cu" "B.Cu")
		(net "GND")
	)
	(via
		(at 128.694688 -252.584458)
		(size 0.4064)
		(drill 0.2032)
		(layers "F.Cu" "B.Cu")
		(net "GND")
	)
	(via
		(at 347.97111 -250.154186)
		(size 0.4064)
		(drill 0.2032)
		(layers "F.Cu" "B.Cu")
		(net "GND")
	)
	(via
		(at 121.474738 -265.176254)
		(size 0.4064)
		(drill 0.2032)
		(layers "F.Cu" "B.Cu")
		(net "GND")
	)
	(via
		(at 297.108372 -200.735184)
		(size 0.4826)
		(drill 0.254)
		(layers "F.Cu" "B.Cu")
		(net "GND")
	)
	(via
		(at 416.206178 -394.831062)
		(size 0.4064)
		(drill 0.2032)
		(layers "F.Cu" "B.Cu")
		(net "GND")
	)
	(via
		(at 415.083752 -211.784946)
		(size 0.4826)
		(drill 0.254)
		(layers "F.Cu" "B.Cu")
		(net "GND")
	)
	(via
		(at 268.263878 -209.23504)
		(size 0.4826)
		(drill 0.254)
		(layers "F.Cu" "B.Cu")
		(net "GND")
	)
	(via
		(at 365.331248 -38.650164)
		(size 0.508)
		(drill 0.254)
		(layers "F.Cu" "B.Cu")
		(net "GND")
	)
	(via
		(at 401.657058 -318.225932)
		(size 0.508)
		(drill 0.254)
		(layers "F.Cu" "B.Cu")
		(net "GND")
	)
	(via
		(at 128.349756 -436.051198)
		(size 0.4572)
		(drill 0.2032)
		(layers "F.Cu" "B.Cu")
		(net "GND")
	)
	(via
		(at 93.769434 -142.84452)
		(size 0.508)
		(drill 0.254)
		(layers "F.Cu" "B.Cu")
		(net "GND")
	)
	(via
		(at 150.523448 -204.720444)
		(size 0.508)
		(drill 0.254)
		(layers "F.Cu" "B.Cu")
		(net "GND")
	)
	(via
		(at 365.615474 -179.710588)
		(size 0.49022)
		(drill 0.254)
		(layers "F.Cu" "B.Cu")
		(net "GND")
	)
	(via
		(at 148.477986 -410.030168)
		(size 0.4064)
		(drill 0.2032)
		(layers "F.Cu" "B.Cu")
		(net "GND")
	)
	(via
		(at 122.891296 -390.160002)
		(size 0.4064)
		(drill 0.2032)
		(layers "F.Cu" "B.Cu")
		(net "GND")
	)
	(via
		(at 320.171318 -421.586152)
		(size 0.4572)
		(drill 0.254)
		(layers "F.Cu" "B.Cu")
		(net "GND")
	)
	(via
		(at 382.955292 -377.41733)
		(size 0.508)
		(drill 0.254)
		(layers "F.Cu" "B.Cu")
		(net "GND")
	)
	(via
		(at 164.427916 -252.58522)
		(size 0.4826)
		(drill 0.254)
		(layers "F.Cu" "B.Cu")
		(net "GND")
	)
	(via
		(at 431.55616 -265.335004)
		(size 0.4826)
		(drill 0.254)
		(layers "F.Cu" "B.Cu")
		(net "GND")
	)
	(via
		(at 96.273112 -59.069986)
		(size 0.508)
		(drill 0.254)
		(layers "F.Cu" "B.Cu")
		(net "GND")
	)
	(via
		(at 399.349722 -430.299622)
		(size 0.4572)
		(drill 0.2032)
		(layers "F.Cu" "B.Cu")
		(net "GND")
	)
	(via
		(at 202.147932 -197.335394)
		(size 0.4826)
		(drill 0.254)
		(layers "F.Cu" "B.Cu")
		(net "GND")
	)
	(via
		(at 401.349718 -427.699678)
		(size 0.4572)
		(drill 0.2032)
		(layers "F.Cu" "B.Cu")
		(net "GND")
	)
	(via
		(at 436.155846 -193.10731)
		(size 0.4826)
		(drill 0.254)
		(layers "F.Cu" "B.Cu")
		(net "GND")
	)
	(via
		(at 104.090978 -282.18638)
		(size 0.4064)
		(drill 0.2032)
		(layers "F.Cu" "B.Cu")
		(net "GND")
	)
	(via
		(at 109.431074 -251.774452)
		(size 0.4064)
		(drill 0.2032)
		(layers "F.Cu" "B.Cu")
		(net "GND")
	)
	(via
		(at 428.573692 -230.060246)
		(size 0.4826)
		(drill 0.254)
		(layers "F.Cu" "B.Cu")
		(net "GND")
	)
	(via
		(at 268.355318 -130.247898)
		(size 0.508)
		(drill 0.254)
		(layers "F.Cu" "B.Cu")
		(net "GND")
	)
	(via
		(at 350.803718 -420.318184)
		(size 0.4572)
		(drill 0.254)
		(layers "F.Cu" "B.Cu")
		(net "GND")
	)
	(via
		(at 391.974832 -276.516084)
		(size 0.4064)
		(drill 0.2032)
		(layers "F.Cu" "B.Cu")
		(net "GND")
	)
	(via
		(at 427.456092 -267.885164)
		(size 0.4826)
		(drill 0.254)
		(layers "F.Cu" "B.Cu")
		(net "GND")
	)
	(via
		(at 54.210458 -304.860452)
		(size 0.4826)
		(drill 0.254)
		(layers "F.Cu" "B.Cu")
		(net "GND")
	)
	(via
		(at 378.344938 -274.086066)
		(size 0.4064)
		(drill 0.2032)
		(layers "F.Cu" "B.Cu")
		(net "GND")
	)
	(via
		(at 314.317634 -417.778184)
		(size 0.4572)
		(drill 0.254)
		(layers "F.Cu" "B.Cu")
		(net "GND")
	)
	(via
		(at 397.058388 -389.25246)
		(size 0.508)
		(drill 0.254)
		(layers "F.Cu" "B.Cu")
		(net "GND")
	)
	(via
		(at 349.851218 -245.29415)
		(size 0.4064)
		(drill 0.2032)
		(layers "F.Cu" "B.Cu")
		(net "GND")
	)
	(via
		(at 109.900974 -233.144314)
		(size 0.4064)
		(drill 0.2032)
		(layers "F.Cu" "B.Cu")
		(net "GND")
	)
	(via
		(at 185.161174 -10.127488)
		(size 0.508)
		(drill 0.254)
		(layers "F.Cu" "B.Cu")
		(net "GND")
	)
	(via
		(at 433.168044 -12.37488)
		(size 0.508)
		(drill 0.254)
		(layers "F.Cu" "B.Cu")
		(net "GND")
	)
	(via
		(at 37.319712 -428.012098)
		(size 0.508)
		(drill 0.254)
		(layers "F.Cu" "B.Cu")
		(net "GND")
	)
	(via
		(at 352.9711 -285.42615)
		(size 0.4064)
		(drill 0.2032)
		(layers "F.Cu" "B.Cu")
		(net "GND")
	)
	(via
		(at 454.188068 -301.034958)
		(size 0.4826)
		(drill 0.254)
		(layers "F.Cu" "B.Cu")
		(net "GND")
	)
	(via
		(at 325.038974 -420.318184)
		(size 0.4572)
		(drill 0.254)
		(layers "F.Cu" "B.Cu")
		(net "GND")
	)
	(via
		(at 361.522264 -259.845048)
		(size 0.4826)
		(drill 0.254)
		(layers "F.Cu" "B.Cu")
		(net "GND")
	)
	(via
		(at 372.404894 -255.014222)
		(size 0.4064)
		(drill 0.2032)
		(layers "F.Cu" "B.Cu")
		(net "GND")
	)
	(via
		(at 206.248 -198.185278)
		(size 0.4826)
		(drill 0.254)
		(layers "F.Cu" "B.Cu")
		(net "GND")
	)
	(via
		(at 416.468052 -224.534984)
		(size 0.4826)
		(drill 0.254)
		(layers "F.Cu" "B.Cu")
		(net "GND")
	)
	(via
		(at 358.61117 -295.145968)
		(size 0.4064)
		(drill 0.2032)
		(layers "F.Cu" "B.Cu")
		(net "GND")
	)
	(via
		(at 385.094734 -247.724168)
		(size 0.4064)
		(drill 0.2032)
		(layers "F.Cu" "B.Cu")
		(net "GND")
	)
	(via
		(at 76.697332 -409.396184)
		(size 0.4572)
		(drill 0.254)
		(layers "F.Cu" "B.Cu")
		(net "GND")
	)
	(via
		(at 138.748262 -17.654778)
		(size 0.508)
		(drill 0.254)
		(layers "F.Cu" "B.Cu")
		(net "GND")
	)
	(via
		(at 128.694688 -233.144314)
		(size 0.4064)
		(drill 0.2032)
		(layers "F.Cu" "B.Cu")
		(net "GND")
	)
	(via
		(at 138.864848 -262.746236)
		(size 0.4064)
		(drill 0.2032)
		(layers "F.Cu" "B.Cu")
		(net "GND")
	)
	(via
		(at 118.827804 -253.392432)
		(size 0.4064)
		(drill 0.2032)
		(layers "F.Cu" "B.Cu")
		(net "GND")
	)
	(via
		(at 265.54811 -208.385156)
		(size 0.4826)
		(drill 0.254)
		(layers "F.Cu" "B.Cu")
		(net "GND")
	)
	(via
		(at 95.86341 -184.641998)
		(size 0.508)
		(drill 0.254)
		(layers "F.Cu" "B.Cu")
		(net "GND")
	)
	(via
		(at 392.680952 -378.07773)
		(size 0.508)
		(drill 0.254)
		(layers "F.Cu" "B.Cu")
		(net "GND")
	)
	(via
		(at 97.211134 -224.234502)
		(size 0.4064)
		(drill 0.2032)
		(layers "F.Cu" "B.Cu")
		(net "GND")
	)
	(via
		(at 91.871038 -283.806392)
		(size 0.4064)
		(drill 0.2032)
		(layers "F.Cu" "B.Cu")
		(net "GND")
	)
	(via
		(at 47.784004 -204.985366)
		(size 0.4826)
		(drill 0.254)
		(layers "F.Cu" "B.Cu")
		(net "GND")
	)
	(via
		(at 113.579148 -173.066964)
		(size 0.49022)
		(drill 0.254)
		(layers "F.Cu" "B.Cu")
		(net "GND")
	)
	(via
		(at 460.439516 -409.89885)
		(size 0.508)
		(drill 0.254)
		(layers "F.Cu" "B.Cu")
		(net "GND")
	)
	(via
		(at 24.034496 -230.0605)
		(size 0.4826)
		(drill 0.254)
		(layers "F.Cu" "B.Cu")
		(net "GND")
	)
	(via
		(at 128.590294 -219.795852)
		(size 0.508)
		(drill 0.254)
		(layers "F.Cu" "B.Cu")
		(net "GND")
	)
	(via
		(at 371.46484 -224.234248)
		(size 0.4064)
		(drill 0.2032)
		(layers "F.Cu" "B.Cu")
		(net "GND")
	)
	(via
		(at 162.606228 -386.449062)
		(size 0.4064)
		(drill 0.2032)
		(layers "F.Cu" "B.Cu")
		(net "GND")
	)
	(via
		(at 98.451162 -274.08632)
		(size 0.4064)
		(drill 0.2032)
		(layers "F.Cu" "B.Cu")
		(net "GND")
	)
	(via
		(at 442.5442 -227.085144)
		(size 0.4826)
		(drill 0.254)
		(layers "F.Cu" "B.Cu")
		(net "GND")
	)
	(via
		(at 21.70811 -198.185278)
		(size 0.4826)
		(drill 0.254)
		(layers "F.Cu" "B.Cu")
		(net "GND")
	)
	(via
		(at 89.690956 -225.854514)
		(size 0.4064)
		(drill 0.2032)
		(layers "F.Cu" "B.Cu")
		(net "GND")
	)
	(via
		(at 29.252164 -224.535238)
		(size 0.4826)
		(drill 0.254)
		(layers "F.Cu" "B.Cu")
		(net "GND")
	)
	(via
		(at 243.000022 -370.79047)
		(size 0.508)
		(drill 0.254)
		(layers "F.Cu" "B.Cu")
		(net "GND")
	)
	(via
		(at 308.562756 -376.75693)
		(size 0.508)
		(drill 0.254)
		(layers "F.Cu" "B.Cu")
		(net "GND")
	)
	(via
		(at 364.24489 -285.42615)
		(size 0.4064)
		(drill 0.2032)
		(layers "F.Cu" "B.Cu")
		(net "GND")
	)
	(via
		(at 115.834668 -270.03629)
		(size 0.4064)
		(drill 0.2032)
		(layers "F.Cu" "B.Cu")
		(net "GND")
	)
	(via
		(at 385.094734 -228.284278)
		(size 0.4064)
		(drill 0.2032)
		(layers "F.Cu" "B.Cu")
		(net "GND")
	)
	(via
		(at 277.192232 -272.984976)
		(size 0.4826)
		(drill 0.254)
		(layers "F.Cu" "B.Cu")
		(net "GND")
	)
	(via
		(at 78.41107 -251.774452)
		(size 0.4064)
		(drill 0.2032)
		(layers "F.Cu" "B.Cu")
		(net "GND")
	)
	(via
		(at 381.804926 -250.154186)
		(size 0.4064)
		(drill 0.2032)
		(layers "F.Cu" "B.Cu")
		(net "GND")
	)
	(via
		(at 374.284748 -250.154186)
		(size 0.4064)
		(drill 0.2032)
		(layers "F.Cu" "B.Cu")
		(net "GND")
	)
	(via
		(at 292.280086 -251.735082)
		(size 0.4826)
		(drill 0.254)
		(layers "F.Cu" "B.Cu")
		(net "GND")
	)
	(via
		(at 328.231246 -248.534174)
		(size 0.4064)
		(drill 0.2032)
		(layers "F.Cu" "B.Cu")
		(net "GND")
	)
	(via
		(at 384.624834 -245.29415)
		(size 0.4064)
		(drill 0.2032)
		(layers "F.Cu" "B.Cu")
		(net "GND")
	)
	(via
		(at 109.261148 -294.336216)
		(size 0.4064)
		(drill 0.2032)
		(layers "F.Cu" "B.Cu")
		(net "GND")
	)
	(via
		(at 402.551646 -201.550524)
		(size 0.508)
		(drill 0.254)
		(layers "F.Cu" "B.Cu")
		(net "GND")
	)
	(via
		(at 59.428126 -271.285208)
		(size 0.4826)
		(drill 0.254)
		(layers "F.Cu" "B.Cu")
		(net "GND")
	)
	(via
		(at 292.280086 -316.335156)
		(size 0.4826)
		(drill 0.254)
		(layers "F.Cu" "B.Cu")
		(net "GND")
	)
	(via
		(at 269.413736 -343.083896)
		(size 0.49022)
		(drill 0.254)
		(layers "F.Cu" "B.Cu")
		(net "GND")
	)
	(via
		(at 105.200958 -236.384338)
		(size 0.4064)
		(drill 0.2032)
		(layers "F.Cu" "B.Cu")
		(net "GND")
	)
	(via
		(at 168.91 -342.6714)
		(size 0.6604)
		(drill 0.3302)
		(layers "F.Cu" "B.Cu")
		(net "GND")
	)
	(via
		(at 170.861736 -386.76326)
		(size 0.508)
		(drill 0.254)
		(layers "F.Cu" "B.Cu")
		(net "GND")
	)
	(via
		(at 354.851208 -274.086066)
		(size 0.4064)
		(drill 0.2032)
		(layers "F.Cu" "B.Cu")
		(net "GND")
	)
	(via
		(at 340.355174 -421.586152)
		(size 0.4572)
		(drill 0.254)
		(layers "F.Cu" "B.Cu")
		(net "GND")
	)
	(via
		(at 78.46695 -66.05905)
		(size 0.508)
		(drill 0.254)
		(layers "F.Cu" "B.Cu")
		(net "GND")
	)
	(via
		(at 80.241648 -183.143906)
		(size 0.49022)
		(drill 0.254)
		(layers "F.Cu" "B.Cu")
		(net "GND")
	)
	(via
		(at 422.16451 -18.5039)
		(size 0.508)
		(drill 0.254)
		(layers "F.Cu" "B.Cu")
		(net "GND")
	)
	(via
		(at 363.474762 -239.624108)
		(size 0.4064)
		(drill 0.2032)
		(layers "F.Cu" "B.Cu")
		(net "GND")
	)
	(via
		(at 85.290914 -272.466308)
		(size 0.4064)
		(drill 0.2032)
		(layers "F.Cu" "B.Cu")
		(net "GND")
	)
	(via
		(at 98.705162 -369.69573)
		(size 0.508)
		(drill 0.254)
		(layers "F.Cu" "B.Cu")
		(net "GND")
	)
	(via
		(at 265.54811 -267.885164)
		(size 0.4826)
		(drill 0.254)
		(layers "F.Cu" "B.Cu")
		(net "GND")
	)
	(via
		(at 147.349718 -431.451258)
		(size 0.4572)
		(drill 0.2032)
		(layers "F.Cu" "B.Cu")
		(net "GND")
	)
	(via
		(at 350.803718 -421.586152)
		(size 0.4572)
		(drill 0.254)
		(layers "F.Cu" "B.Cu")
		(net "GND")
	)
	(via
		(at 323.38645 -340.498938)
		(size 0.508)
		(drill 0.254)
		(layers "F.Cu" "B.Cu")
		(net "GND")
	)
	(via
		(at 78.24978 -436.051198)
		(size 0.4572)
		(drill 0.2032)
		(layers "F.Cu" "B.Cu")
		(net "GND")
	)
	(via
		(at 274.247864 -192.21831)
		(size 0.4826)
		(drill 0.254)
		(layers "F.Cu" "B.Cu")
		(net "GND")
	)
	(via
		(at 353.841812 -339.520276)
		(size 0.49022)
		(drill 0.254)
		(layers "F.Cu" "B.Cu")
		(net "GND")
	)
	(via
		(at 83.944206 -382.85293)
		(size 0.4064)
		(drill 0.2032)
		(layers "F.Cu" "B.Cu")
		(net "GND")
	)
	(via
		(at 432.082956 -19.771106)
		(size 0.508)
		(drill 0.254)
		(layers "F.Cu" "B.Cu")
		(net "GND")
	)
	(via
		(at 379.284738 -295.145968)
		(size 0.4064)
		(drill 0.2032)
		(layers "F.Cu" "B.Cu")
		(net "GND")
	)
	(via
		(at 51.884072 -282.335224)
		(size 0.4826)
		(drill 0.254)
		(layers "F.Cu" "B.Cu")
		(net "GND")
	)
	(via
		(at 17.608042 -204.985366)
		(size 0.4826)
		(drill 0.254)
		(layers "F.Cu" "B.Cu")
		(net "GND")
	)
	(via
		(at 128.994662 -273.276314)
		(size 0.4064)
		(drill 0.2032)
		(layers "F.Cu" "B.Cu")
		(net "GND")
	)
	(via
		(at 191.160146 -253.435358)
		(size 0.4826)
		(drill 0.254)
		(layers "F.Cu" "B.Cu")
		(net "GND")
	)
	(via
		(at 408.775154 -441.227718)
		(size 0.508)
		(drill 0.254)
		(layers "F.Cu" "B.Cu")
		(net "GND")
	)
	(via
		(at 124.7648 -270.846296)
		(size 0.4064)
		(drill 0.2032)
		(layers "F.Cu" "B.Cu")
		(net "GND")
	)
	(via
		(at 394.296138 -179.755038)
		(size 0.508)
		(drill 0.254)
		(layers "F.Cu" "B.Cu")
		(net "GND")
	)
	(via
		(at 307.4162 -391.23493)
		(size 0.4064)
		(drill 0.2032)
		(layers "F.Cu" "B.Cu")
		(net "GND")
	)
	(via
		(at 442.49848 -433.89931)
		(size 0.508)
		(drill 0.254)
		(layers "F.Cu" "B.Cu")
		(net "GND")
	)
	(via
		(at 323.507354 -416.020504)
		(size 0.4572)
		(drill 0.254)
		(layers "F.Cu" "B.Cu")
		(net "GND")
	)
	(via
		(at 86.249764 -428.851314)
		(size 0.4572)
		(drill 0.2032)
		(layers "F.Cu" "B.Cu")
		(net "GND")
	)
	(via
		(at 15.98422 -79.467964)
		(size 0.508)
		(drill 0.254)
		(layers "F.Cu" "B.Cu")
		(net "GND")
	)
	(via
		(at 280.635964 -247.485154)
		(size 0.4826)
		(drill 0.254)
		(layers "F.Cu" "B.Cu")
		(net "GND")
	)
	(via
		(at 325.052944 -276.250146)
		(size 0.4064)
		(drill 0.2032)
		(layers "F.Cu" "B.Cu")
		(net "GND")
	)
	(via
		(at 65.90665 -166.94023)
		(size 0.49022)
		(drill 0.254)
		(layers "F.Cu" "B.Cu")
		(net "GND")
	)
	(via
		(at 338.550758 -412.212536)
		(size 0.4572)
		(drill 0.254)
		(layers "F.Cu" "B.Cu")
		(net "GND")
	)
	(via
		(at 346.249498 -430.147222)
		(size 0.4572)
		(drill 0.2032)
		(layers "F.Cu" "B.Cu")
		(net "GND")
	)
	(via
		(at 342.801194 -225.044254)
		(size 0.4064)
		(drill 0.2032)
		(layers "F.Cu" "B.Cu")
		(net "GND")
	)
	(via
		(at 324.941184 -228.284278)
		(size 0.4064)
		(drill 0.2032)
		(layers "F.Cu" "B.Cu")
		(net "GND")
	)
	(via
		(at 122.884692 -291.906198)
		(size 0.4064)
		(drill 0.2032)
		(layers "F.Cu" "B.Cu")
		(net "GND")
	)
	(via
		(at 192.277746 -313.360308)
		(size 0.4826)
		(drill 0.254)
		(layers "F.Cu" "B.Cu")
		(net "GND")
	)
	(via
		(at 173.08957 -314.210446)
		(size 0.4826)
		(drill 0.254)
		(layers "F.Cu" "B.Cu")
		(net "GND")
	)
	(via
		(at 54.210458 -230.0605)
		(size 0.4826)
		(drill 0.254)
		(layers "F.Cu" "B.Cu")
		(net "GND")
	)
	(via
		(at 98.344228 -391.830814)
		(size 0.4064)
		(drill 0.2032)
		(layers "F.Cu" "B.Cu")
		(net "GND")
	)
	(via
		(at 27.867864 -302.735234)
		(size 0.4826)
		(drill 0.254)
		(layers "F.Cu" "B.Cu")
		(net "GND")
	)
	(via
		(at 279.518364 -295.510204)
		(size 0.4826)
		(drill 0.254)
		(layers "F.Cu" "B.Cu")
		(net "GND")
	)
	(via
		(at 394.982954 -279.49017)
		(size 0.4064)
		(drill 0.2032)
		(layers "F.Cu" "B.Cu")
		(net "GND")
	)
	(via
		(at 454.188068 -268.735048)
		(size 0.4826)
		(drill 0.254)
		(layers "F.Cu" "B.Cu")
		(net "GND")
	)
	(via
		(at 107.702604 -173.030134)
		(size 0.508)
		(drill 0.254)
		(layers "F.Cu" "B.Cu")
		(net "GND")
	)
	(via
		(at 127.284734 -248.534428)
		(size 0.4064)
		(drill 0.2032)
		(layers "F.Cu" "B.Cu")
		(net "GND")
	)
	(via
		(at 37.685218 -18.247868)
		(size 0.508)
		(drill 0.254)
		(layers "F.Cu" "B.Cu")
		(net "GND")
	)
	(via
		(at 111.800386 -245.552214)
		(size 0.4826)
		(drill 0.254)
		(layers "F.Cu" "B.Cu")
		(net "GND")
	)
	(via
		(at 2.76225 -328.097134)
		(size 0.508)
		(drill 0.254)
		(layers "F.Cu" "B.Cu")
		(net "GND")
	)
	(via
		(at 170.905424 -381.020828)
		(size 0.508)
		(drill 0.254)
		(layers "F.Cu" "B.Cu")
		(net "GND")
	)
	(via
		(at 373.961152 -379.22073)
		(size 0.508)
		(drill 0.254)
		(layers "F.Cu" "B.Cu")
		(net "GND")
	)
	(via
		(at 358.311196 -235.574078)
		(size 0.4064)
		(drill 0.2032)
		(layers "F.Cu" "B.Cu")
		(net "GND")
	)
	(via
		(at 427.456092 -208.385156)
		(size 0.4826)
		(drill 0.254)
		(layers "F.Cu" "B.Cu")
		(net "GND")
	)
	(via
		(at 49.804574 -416.394646)
		(size 0.508)
		(drill 0.254)
		(layers "F.Cu" "B.Cu")
		(net "GND")
	)
	(via
		(at 195.759832 -193.107564)
		(size 0.4826)
		(drill 0.254)
		(layers "F.Cu" "B.Cu")
		(net "GND")
	)
	(via
		(at 183.132222 -116.642642)
		(size 0.4572)
		(drill 0.254)
		(layers "F.Cu" "B.Cu")
		(net "GND")
	)
	(via
		(at 46.240954 -369.03533)
		(size 0.508)
		(drill 0.254)
		(layers "F.Cu" "B.Cu")
		(net "GND")
	)
	(via
		(at 195.988432 -200.735438)
		(size 0.4826)
		(drill 0.254)
		(layers "F.Cu" "B.Cu")
		(net "GND")
	)
	(via
		(at 68.678044 -412.570168)
		(size 0.4064)
		(drill 0.2032)
		(layers "F.Cu" "B.Cu")
		(net "GND")
	)
	(via
		(at 461.92821 -12.542266)
		(size 0.508)
		(drill 0.254)
		(layers "F.Cu" "B.Cu")
		(net "GND")
	)
	(via
		(at 290.338002 -401.404836)
		(size 0.508)
		(drill 0.254)
		(layers "F.Cu" "B.Cu")
		(net "GND")
	)
	(via
		(at 59.428126 -265.335258)
		(size 0.4826)
		(drill 0.254)
		(layers "F.Cu" "B.Cu")
		(net "GND")
	)
	(via
		(at 157.349698 -439.651394)
		(size 0.4572)
		(drill 0.2032)
		(layers "F.Cu" "B.Cu")
		(net "GND")
	)
	(via
		(at 61.022484 -410.030168)
		(size 0.4064)
		(drill 0.2032)
		(layers "F.Cu" "B.Cu")
		(net "GND")
	)
	(via
		(at 391.504678 -274.086066)
		(size 0.4064)
		(drill 0.2032)
		(layers "F.Cu" "B.Cu")
		(net "GND")
	)
	(via
		(at 389.79475 -226.664266)
		(size 0.4064)
		(drill 0.2032)
		(layers "F.Cu" "B.Cu")
		(net "GND")
	)
	(via
		(at 119.634762 -79.137002)
		(size 0.508)
		(drill 0.254)
		(layers "F.Cu" "B.Cu")
		(net "GND")
	)
	(via
		(at 352.9711 -269.22603)
		(size 0.4064)
		(drill 0.2032)
		(layers "F.Cu" "B.Cu")
		(net "GND")
	)
	(via
		(at 69.125084 -410.030168)
		(size 0.4064)
		(drill 0.2032)
		(layers "F.Cu" "B.Cu")
		(net "GND")
	)
	(via
		(at 404.676356 -134.931404)
		(size 0.508)
		(drill 0.254)
		(layers "F.Cu" "B.Cu")
		(net "GND")
	)
	(via
		(at 405.414734 -4.963414)
		(size 0.508)
		(drill 0.254)
		(layers "F.Cu" "B.Cu")
		(net "GND")
	)
	(via
		(at 312.786014 -413.480504)
		(size 0.4572)
		(drill 0.254)
		(layers "F.Cu" "B.Cu")
		(net "GND")
	)
	(via
		(at 445.853566 -423.914824)
		(size 0.508)
		(drill 0.254)
		(layers "F.Cu" "B.Cu")
		(net "GND")
	)
	(via
		(at 388.803134 -419.046152)
		(size 0.4572)
		(drill 0.254)
		(layers "F.Cu" "B.Cu")
		(net "GND")
	)
	(via
		(at 338.306156 -394.831062)
		(size 0.4064)
		(drill 0.2032)
		(layers "F.Cu" "B.Cu")
		(net "GND")
	)
	(via
		(at 147.349718 -426.69968)
		(size 0.4572)
		(drill 0.2032)
		(layers "F.Cu" "B.Cu")
		(net "GND")
	)
	(via
		(at 443.9285 -287.435036)
		(size 0.4826)
		(drill 0.254)
		(layers "F.Cu" "B.Cu")
		(net "GND")
	)
	(via
		(at 140.274802 -284.616398)
		(size 0.4064)
		(drill 0.2032)
		(layers "F.Cu" "B.Cu")
		(net "GND")
	)
	(via
		(at 419.380416 -170.629072)
		(size 0.508)
		(drill 0.254)
		(layers "F.Cu" "B.Cu")
		(net "GND")
	)
	(via
		(at 189.35065 -330.795884)
		(size 0.508)
		(drill 0.254)
		(layers "F.Cu" "B.Cu")
		(net "GND")
	)
	(via
		(at 99.390962 -293.52621)
		(size 0.4064)
		(drill 0.2032)
		(layers "F.Cu" "B.Cu")
		(net "GND")
	)
	(via
		(at 367.064798 -267.606018)
		(size 0.4064)
		(drill 0.2032)
		(layers "F.Cu" "B.Cu")
		(net "GND")
	)
	(via
		(at 326.651112 -278.946102)
		(size 0.4064)
		(drill 0.2032)
		(layers "F.Cu" "B.Cu")
		(net "GND")
	)
	(via
		(at 386.504942 -250.154186)
		(size 0.4064)
		(drill 0.2032)
		(layers "F.Cu" "B.Cu")
		(net "GND")
	)
	(via
		(at 356.014274 -171.435268)
		(size 0.49022)
		(drill 0.254)
		(layers "F.Cu" "B.Cu")
		(net "GND")
	)
	(via
		(at 457.298806 -49.129696)
		(size 0.508)
		(drill 0.254)
		(layers "F.Cu" "B.Cu")
		(net "GND")
	)
	(via
		(at 80.249776 -438.651396)
		(size 0.4572)
		(drill 0.2032)
		(layers "F.Cu" "B.Cu")
		(net "GND")
	)
	(via
		(at 61.249814 -436.051198)
		(size 0.4572)
		(drill 0.2032)
		(layers "F.Cu" "B.Cu")
		(net "GND")
	)
	(via
		(at 24.432514 -339.781134)
		(size 0.508)
		(drill 0.254)
		(layers "F.Cu" "B.Cu")
		(net "GND")
	)
	(via
		(at 49.168304 -278.085296)
		(size 0.4826)
		(drill 0.254)
		(layers "F.Cu" "B.Cu")
		(net "GND")
	)
	(via
		(at 251.347224 -278.640032)
		(size 0.508)
		(drill 0.254)
		(layers "F.Cu" "B.Cu")
		(net "GND")
	)
	(via
		(at 269.648178 -222.834962)
		(size 0.4826)
		(drill 0.254)
		(layers "F.Cu" "B.Cu")
		(net "GND")
	)
	(via
		(at 315.24956 -433.899564)
		(size 0.4572)
		(drill 0.2032)
		(layers "F.Cu" "B.Cu")
		(net "GND")
	)
	(via
		(at 390.334754 -413.480504)
		(size 0.4572)
		(drill 0.254)
		(layers "F.Cu" "B.Cu")
		(net "GND")
	)
	(via
		(at 165.812216 -238.135414)
		(size 0.4826)
		(drill 0.254)
		(layers "F.Cu" "B.Cu")
		(net "GND")
	)
	(via
		(at 453.797924 -61.960252)
		(size 0.6604)
		(drill 0.3302)
		(layers "F.Cu" "B.Cu")
		(net "GND")
	)
	(via
		(at 294.875966 -342.811608)
		(size 0.508)
		(drill 0.254)
		(layers "F.Cu" "B.Cu")
		(net "GND")
	)
	(via
		(at 133.394704 -252.584458)
		(size 0.4064)
		(drill 0.2032)
		(layers "F.Cu" "B.Cu")
		(net "GND")
	)
	(via
		(at 424.012106 -216.885012)
		(size 0.4826)
		(drill 0.254)
		(layers "F.Cu" "B.Cu")
		(net "GND")
	)
	(via
		(at 428.234602 -356.155498)
		(size 0.508)
		(drill 0.254)
		(layers "F.Cu" "B.Cu")
		(net "GND")
	)
	(via
		(at 368.644678 -251.774198)
		(size 0.4064)
		(drill 0.2032)
		(layers "F.Cu" "B.Cu")
		(net "GND")
	)
	(via
		(at 438.743344 -13.849096)
		(size 0.508)
		(drill 0.254)
		(layers "F.Cu" "B.Cu")
		(net "GND")
	)
	(via
		(at 88.24976 -437.49976)
		(size 0.4572)
		(drill 0.2032)
		(layers "F.Cu" "B.Cu")
		(net "GND")
	)
	(via
		(at 83.646264 -388.328662)
		(size 0.4064)
		(drill 0.2032)
		(layers "F.Cu" "B.Cu")
		(net "GND")
	)
	(via
		(at 184.733692 -304.010314)
		(size 0.4826)
		(drill 0.254)
		(layers "F.Cu" "B.Cu")
		(net "GND")
	)
	(via
		(at 445.259968 -230.485188)
		(size 0.4826)
		(drill 0.254)
		(layers "F.Cu" "B.Cu")
		(net "GND")
	)
	(via
		(at 403.349714 -437.49976)
		(size 0.4572)
		(drill 0.2032)
		(layers "F.Cu" "B.Cu")
		(net "GND")
	)
	(via
		(at 305.983894 -286.585152)
		(size 0.4826)
		(drill 0.254)
		(layers "F.Cu" "B.Cu")
		(net "GND")
	)
	(via
		(at 350.151192 -288.66592)
		(size 0.4064)
		(drill 0.2032)
		(layers "F.Cu" "B.Cu")
		(net "GND")
	)
	(via
		(at 206.248 -207.535272)
		(size 0.4826)
		(drill 0.254)
		(layers "F.Cu" "B.Cu")
		(net "GND")
	)
	(via
		(at 12.5476 -97.635568)
		(size 0.508)
		(drill 0.254)
		(layers "F.Cu" "B.Cu")
		(net "GND")
	)
	(via
		(at 151.094186 -404.46452)
		(size 0.4064)
		(drill 0.2032)
		(layers "F.Cu" "B.Cu")
		(net "GND")
	)
	(via
		(at 111.800386 -247.457214)
		(size 0.4826)
		(drill 0.254)
		(layers "F.Cu" "B.Cu")
		(net "GND")
	)
	(via
		(at 394.68298 -239.890046)
		(size 0.4064)
		(drill 0.2032)
		(layers "F.Cu" "B.Cu")
		(net "GND")
	)
	(via
		(at 338.249514 -439.651394)
		(size 0.4572)
		(drill 0.2032)
		(layers "F.Cu" "B.Cu")
		(net "GND")
	)
	(via
		(at 226.478592 -289.012122)
		(size 0.508)
		(drill 0.254)
		(layers "F.Cu" "B.Cu")
		(net "GND")
	)
	(via
		(at 19.744182 -133.798056)
		(size 0.508)
		(drill 0.254)
		(layers "F.Cu" "B.Cu")
		(net "GND")
	)
	(via
		(at 122.884692 -274.08632)
		(size 0.4064)
		(drill 0.2032)
		(layers "F.Cu" "B.Cu")
		(net "GND")
	)
	(via
		(at 250.971812 -420.65067)
		(size 0.508)
		(drill 0.254)
		(layers "F.Cu" "B.Cu")
		(net "GND")
	)
	(via
		(at 41.117774 -339.804502)
		(size 0.508)
		(drill 0.254)
		(layers "F.Cu" "B.Cu")
		(net "GND")
	)
	(via
		(at 344.494104 -381.68453)
		(size 0.508)
		(drill 0.254)
		(layers "F.Cu" "B.Cu")
		(net "GND")
	)
	(via
		(at 69.239384 -6.90499)
		(size 0.508)
		(drill 0.254)
		(layers "F.Cu" "B.Cu")
		(net "GND")
	)
	(via
		(at 452.619364 -32.004254)
		(size 0.508)
		(drill 0.254)
		(layers "F.Cu" "B.Cu")
		(net "GND")
	)
	(via
		(at 419.435534 -414.752536)
		(size 0.4572)
		(drill 0.254)
		(layers "F.Cu" "B.Cu")
		(net "GND")
	)
	(via
		(at 17.608042 -292.535356)
		(size 0.4826)
		(drill 0.254)
		(layers "F.Cu" "B.Cu")
		(net "GND")
	)
	(via
		(at 425.129706 -201.160126)
		(size 0.4826)
		(drill 0.254)
		(layers "F.Cu" "B.Cu")
		(net "GND")
	)
	(via
		(at 277.59787 -345.550998)
		(size 0.49022)
		(drill 0.254)
		(layers "F.Cu" "B.Cu")
		(net "GND")
	)
	(via
		(at 334.811116 -230.714296)
		(size 0.4064)
		(drill 0.2032)
		(layers "F.Cu" "B.Cu")
		(net "GND")
	)
	(via
		(at 387.914896 -226.664266)
		(size 0.4064)
		(drill 0.2032)
		(layers "F.Cu" "B.Cu")
		(net "GND")
	)
	(via
		(at 343.101168 -294.335962)
		(size 0.4064)
		(drill 0.2032)
		(layers "F.Cu" "B.Cu")
		(net "GND")
	)
	(via
		(at 83.111086 -229.094538)
		(size 0.4064)
		(drill 0.2032)
		(layers "F.Cu" "B.Cu")
		(net "GND")
	)
	(via
		(at 202.147932 -245.785386)
		(size 0.4826)
		(drill 0.254)
		(layers "F.Cu" "B.Cu")
		(net "GND")
	)
	(via
		(at 388.491222 -398.542002)
		(size 0.4064)
		(drill 0.2032)
		(layers "F.Cu" "B.Cu")
		(net "GND")
	)
	(via
		(at 173.35627 -240.68532)
		(size 0.4826)
		(drill 0.254)
		(layers "F.Cu" "B.Cu")
		(net "GND")
	)
	(via
		(at 19.285712 -0.762254)
		(size 0.508)
		(drill 0.254)
		(layers "F.Cu" "B.Cu")
		(net "GND")
	)
	(via
		(at 22.528784 -387.799326)
		(size 0.508)
		(drill 0.254)
		(layers "F.Cu" "B.Cu")
		(net "GND")
	)
	(via
		(at 317.380874 -416.020504)
		(size 0.4572)
		(drill 0.254)
		(layers "F.Cu" "B.Cu")
		(net "GND")
	)
	(via
		(at 337.106006 -394.831062)
		(size 0.4064)
		(drill 0.2032)
		(layers "F.Cu" "B.Cu")
		(net "GND")
	)
	(via
		(at 52.902358 -344.781886)
		(size 0.49022)
		(drill 0.254)
		(layers "F.Cu" "B.Cu")
		(net "GND")
	)
	(via
		(at 284.736032 -216.885012)
		(size 0.4826)
		(drill 0.254)
		(layers "F.Cu" "B.Cu")
		(net "GND")
	)
	(via
		(at 388.68477 -282.186126)
		(size 0.4064)
		(drill 0.2032)
		(layers "F.Cu" "B.Cu")
		(net "GND")
	)
	(via
		(at 284.736032 -243.234972)
		(size 0.4826)
		(drill 0.254)
		(layers "F.Cu" "B.Cu")
		(net "GND")
	)
	(via
		(at 337.631024 -255.014222)
		(size 0.4064)
		(drill 0.2032)
		(layers "F.Cu" "B.Cu")
		(net "GND")
	)
	(via
		(at 152.53208 -102.038912)
		(size 0.508)
		(drill 0.254)
		(layers "F.Cu" "B.Cu")
		(net "GND")
	)
	(via
		(at 125.704854 -262.746236)
		(size 0.4064)
		(drill 0.2032)
		(layers "F.Cu" "B.Cu")
		(net "GND")
	)
	(via
		(at 330.070968 -398.679924)
		(size 0.508)
		(drill 0.254)
		(layers "F.Cu" "B.Cu")
		(net "GND")
	)
	(via
		(at 238.252 -330.581)
		(size 0.508)
		(drill 0.254)
		(layers "F.Cu" "B.Cu")
		(net "GND")
	)
	(via
		(at 87.171022 -264.366248)
		(size 0.4064)
		(drill 0.2032)
		(layers "F.Cu" "B.Cu")
		(net "GND")
	)
	(via
		(at 197.3199 -274.685252)
		(size 0.4826)
		(drill 0.254)
		(layers "F.Cu" "B.Cu")
		(net "GND")
	)
	(via
		(at 56.357774 -336.910172)
		(size 0.508)
		(drill 0.254)
		(layers "F.Cu" "B.Cu")
		(net "GND")
	)
	(via
		(at 80.591152 -269.226284)
		(size 0.4064)
		(drill 0.2032)
		(layers "F.Cu" "B.Cu")
		(net "GND")
	)
	(via
		(at 356.261162 -281.37612)
		(size 0.4064)
		(drill 0.2032)
		(layers "F.Cu" "B.Cu")
		(net "GND")
	)
	(via
		(at 342.343994 -400.212814)
		(size 0.4064)
		(drill 0.2032)
		(layers "F.Cu" "B.Cu")
		(net "GND")
	)
	(via
		(at 381.716534 -402.309838)
		(size 0.4572)
		(drill 0.254)
		(layers "F.Cu" "B.Cu")
		(net "GND")
	)
	(via
		(at 252.778006 -66.88836)
		(size 0.508)
		(drill 0.254)
		(layers "F.Cu" "B.Cu")
		(net "GND")
	)
	(via
		(at 34.891218 -18.503138)
		(size 0.508)
		(drill 0.254)
		(layers "F.Cu" "B.Cu")
		(net "GND")
	)
	(via
		(at 36.795964 -244.935248)
		(size 0.4826)
		(drill 0.254)
		(layers "F.Cu" "B.Cu")
		(net "GND")
	)
	(via
		(at 396.349474 -439.651394)
		(size 0.4572)
		(drill 0.2032)
		(layers "F.Cu" "B.Cu")
		(net "GND")
	)
	(via
		(at 86.338156 -41.95318)
		(size 0.508)
		(drill 0.254)
		(layers "F.Cu" "B.Cu")
		(net "GND")
	)
	(via
		(at 32.695896 -309.535322)
		(size 0.4826)
		(drill 0.254)
		(layers "F.Cu" "B.Cu")
		(net "GND")
	)
	(via
		(at 383.039874 -183.893968)
		(size 0.49022)
		(drill 0.254)
		(layers "F.Cu" "B.Cu")
		(net "GND")
	)
	(via
		(at 276.074632 -294.660066)
		(size 0.4826)
		(drill 0.254)
		(layers "F.Cu" "B.Cu")
		(net "GND")
	)
	(via
		(at 366.124744 -277.32609)
		(size 0.4064)
		(drill 0.2032)
		(layers "F.Cu" "B.Cu")
		(net "GND")
	)
	(via
		(at 85.79104 -355.968046)
		(size 0.508)
		(drill 0.254)
		(layers "F.Cu" "B.Cu")
		(net "GND")
	)
	(via
		(at 68.797678 -169.80281)
		(size 0.508)
		(drill 0.254)
		(layers "F.Cu" "B.Cu")
		(net "GND")
	)
	(via
		(at 246.682768 -55.775606)
		(size 0.508)
		(drill 0.254)
		(layers "F.Cu" "B.Cu")
		(net "GND")
	)
	(via
		(at 165.583616 -193.107564)
		(size 0.4826)
		(drill 0.254)
		(layers "F.Cu" "B.Cu")
		(net "GND")
	)
	(via
		(at 143.73479 -236.384338)
		(size 0.4064)
		(drill 0.2032)
		(layers "F.Cu" "B.Cu")
		(net "GND")
	)
	(via
		(at 258.905756 -327.446386)
		(size 0.508)
		(drill 0.254)
		(layers "F.Cu" "B.Cu")
		(net "GND")
	)
	(via
		(at 147.349718 -425.547282)
		(size 0.4572)
		(drill 0.2032)
		(layers "F.Cu" "B.Cu")
		(net "GND")
	)
	(via
		(at 232.30205 -142.246858)
		(size 0.508)
		(drill 0.254)
		(layers "F.Cu" "B.Cu")
		(net "GND")
	)
	(via
		(at 65.402714 -344.137234)
		(size 0.508)
		(drill 0.254)
		(layers "F.Cu" "B.Cu")
		(net "GND")
	)
	(via
		(at 273.46021 -344.77706)
		(size 0.49022)
		(drill 0.254)
		(layers "F.Cu" "B.Cu")
		(net "GND")
	)
	(via
		(at 384.624834 -238.814102)
		(size 0.4064)
		(drill 0.2032)
		(layers "F.Cu" "B.Cu")
		(net "GND")
	)
	(via
		(at 173.08957 -202.010264)
		(size 0.4826)
		(drill 0.254)
		(layers "F.Cu" "B.Cu")
		(net "GND")
	)
	(via
		(at 103.805482 -377.617228)
		(size 0.508)
		(drill 0.254)
		(layers "F.Cu" "B.Cu")
		(net "GND")
	)
	(via
		(at 83.944206 -391.830814)
		(size 0.4064)
		(drill 0.2032)
		(layers "F.Cu" "B.Cu")
		(net "GND")
	)
	(via
		(at 390.902698 -182.177944)
		(size 0.49022)
		(drill 0.254)
		(layers "F.Cu" "B.Cu")
		(net "GND")
	)
	(via
		(at 132.916422 -382.85293)
		(size 0.4064)
		(drill 0.2032)
		(layers "F.Cu" "B.Cu")
		(net "GND")
	)
	(via
		(at 71.249794 -425.547282)
		(size 0.4572)
		(drill 0.2032)
		(layers "F.Cu" "B.Cu")
		(net "GND")
	)
	(via
		(at 336.521044 -278.136096)
		(size 0.4064)
		(drill 0.2032)
		(layers "F.Cu" "B.Cu")
		(net "GND")
	)
	(via
		(at 339.993986 -412.84652)
		(size 0.4064)
		(drill 0.2032)
		(layers "F.Cu" "B.Cu")
		(net "GND")
	)
	(via
		(at 42.955718 -202.435206)
		(size 0.4826)
		(drill 0.254)
		(layers "F.Cu" "B.Cu")
		(net "GND")
	)
	(via
		(at 16.490442 -276.81047)
		(size 0.4826)
		(drill 0.254)
		(layers "F.Cu" "B.Cu")
		(net "GND")
	)
	(via
		(at 80.34909 -184.679082)
		(size 0.49022)
		(drill 0.254)
		(layers "F.Cu" "B.Cu")
		(net "GND")
	)
	(via
		(at 454.188068 -310.384952)
		(size 0.4826)
		(drill 0.254)
		(layers "F.Cu" "B.Cu")
		(net "GND")
	)
	(via
		(at 96.565974 -60.115196)
		(size 0.508)
		(drill 0.254)
		(layers "F.Cu" "B.Cu")
		(net "GND")
	)
	(via
		(at 255.823212 -420.65067)
		(size 0.508)
		(drill 0.254)
		(layers "F.Cu" "B.Cu")
		(net "GND")
	)
	(via
		(at 109.191044 -382.54432)
		(size 0.508)
		(drill 0.254)
		(layers "F.Cu" "B.Cu")
		(net "GND")
	)
	(via
		(at 274.476464 -210.085178)
		(size 0.4826)
		(drill 0.254)
		(layers "F.Cu" "B.Cu")
		(net "GND")
	)
	(via
		(at 87.544402 -393.877038)
		(size 0.4572)
		(drill 0.254)
		(layers "F.Cu" "B.Cu")
		(net "GND")
	)
	(via
		(at 342.631014 -293.525956)
		(size 0.4064)
		(drill 0.2032)
		(layers "F.Cu" "B.Cu")
		(net "GND")
	)
	(via
		(at 106.611166 -235.574332)
		(size 0.4064)
		(drill 0.2032)
		(layers "F.Cu" "B.Cu")
		(net "GND")
	)
	(via
		(at 0.762254 -77.007212)
		(size 0.508)
		(drill 0.254)
		(layers "F.Cu" "B.Cu")
		(net "GND")
	)
	(via
		(at 274.247864 -194.88531)
		(size 0.4826)
		(drill 0.254)
		(layers "F.Cu" "B.Cu")
		(net "GND")
	)
	(via
		(at 146.742912 -251.230384)
		(size 0.4064)
		(drill 0.2032)
		(layers "F.Cu" "B.Cu")
		(net "GND")
	)
	(via
		(at 11.973052 -384.320288)
		(size 0.508)
		(drill 0.254)
		(layers "F.Cu" "B.Cu")
		(net "GND")
	)
	(via
		(at 126.949454 -403.830536)
		(size 0.4572)
		(drill 0.254)
		(layers "F.Cu" "B.Cu")
		(net "GND")
	)
	(via
		(at 419.912038 -273.835114)
		(size 0.4826)
		(drill 0.254)
		(layers "F.Cu" "B.Cu")
		(net "GND")
	)
	(via
		(at 304.769266 -415.38652)
		(size 0.4064)
		(drill 0.2032)
		(layers "F.Cu" "B.Cu")
		(net "GND")
	)
	(via
		(at 431.55616 -244.934994)
		(size 0.4826)
		(drill 0.254)
		(layers "F.Cu" "B.Cu")
		(net "GND")
	)
	(via
		(at 359.754678 -417.582858)
		(size 0.508)
		(drill 0.254)
		(layers "F.Cu" "B.Cu")
		(net "GND")
	)
	(via
		(at 83.557364 -139.19962)
		(size 0.508)
		(drill 0.254)
		(layers "F.Cu" "B.Cu")
		(net "GND")
	)
	(via
		(at 125.404626 -222.61449)
		(size 0.4064)
		(drill 0.2032)
		(layers "F.Cu" "B.Cu")
		(net "GND")
	)
	(via
		(at 91.871038 -287.046162)
		(size 0.4064)
		(drill 0.2032)
		(layers "F.Cu" "B.Cu")
		(net "GND")
	)
	(via
		(at 2.76225 -300.157134)
		(size 0.508)
		(drill 0.254)
		(layers "F.Cu" "B.Cu")
		(net "GND")
	)
	(via
		(at 378.116592 -391.23493)
		(size 0.4064)
		(drill 0.2032)
		(layers "F.Cu" "B.Cu")
		(net "GND")
	)
	(via
		(at 409.349702 -438.499758)
		(size 0.4572)
		(drill 0.2032)
		(layers "F.Cu" "B.Cu")
		(net "GND")
	)
	(via
		(at 30.914848 -4.963414)
		(size 0.508)
		(drill 0.254)
		(layers "F.Cu" "B.Cu")
		(net "GND")
	)
	(via
		(at 127.287782 -221.517972)
		(size 0.4064)
		(drill 0.2032)
		(layers "F.Cu" "B.Cu")
		(net "GND")
	)
	(via
		(at 157.667706 -410.030168)
		(size 0.4064)
		(drill 0.2032)
		(layers "F.Cu" "B.Cu")
		(net "GND")
	)
	(via
		(at 217.524838 -87.545926)
		(size 0.508)
		(drill 0.254)
		(layers "F.Cu" "B.Cu")
		(net "GND")
	)
	(via
		(at 457.654406 -390.332468)
		(size 0.508)
		(drill 0.254)
		(layers "F.Cu" "B.Cu")
		(net "GND")
	)
	(via
		(at 122.584718 -232.334308)
		(size 0.4064)
		(drill 0.2032)
		(layers "F.Cu" "B.Cu")
		(net "GND")
	)
	(via
		(at 310.87187 -345.550998)
		(size 0.49022)
		(drill 0.254)
		(layers "F.Cu" "B.Cu")
		(net "GND")
	)
	(via
		(at 101.27107 -288.666174)
		(size 0.4064)
		(drill 0.2032)
		(layers "F.Cu" "B.Cu")
		(net "GND")
	)
	(via
		(at 140.444728 -246.914416)
		(size 0.4064)
		(drill 0.2032)
		(layers "F.Cu" "B.Cu")
		(net "GND")
	)
	(via
		(at 113.48466 -293.52621)
		(size 0.4064)
		(drill 0.2032)
		(layers "F.Cu" "B.Cu")
		(net "GND")
	)
	(via
		(at 140.744702 -285.426404)
		(size 0.4064)
		(drill 0.2032)
		(layers "F.Cu" "B.Cu")
		(net "GND")
	)
	(via
		(at 77.112876 -287.590484)
		(size 0.4064)
		(drill 0.2032)
		(layers "F.Cu" "B.Cu")
		(net "GND")
	)
	(via
		(at 86.401148 -255.824482)
		(size 0.4064)
		(drill 0.2032)
		(layers "F.Cu" "B.Cu")
		(net "GND")
	)
	(via
		(at 164.427916 -292.535356)
		(size 0.4826)
		(drill 0.254)
		(layers "F.Cu" "B.Cu")
		(net "GND")
	)
	(via
		(at 280.251154 -441.227718)
		(size 0.508)
		(drill 0.254)
		(layers "F.Cu" "B.Cu")
		(net "GND")
	)
	(via
		(at 406.012142 -412.84652)
		(size 0.4064)
		(drill 0.2032)
		(layers "F.Cu" "B.Cu")
		(net "GND")
	)
	(via
		(at 352.980752 -337.99526)
		(size 0.49022)
		(drill 0.254)
		(layers "F.Cu" "B.Cu")
		(net "GND")
	)
	(via
		(at 351.731072 -246.914162)
		(size 0.4064)
		(drill 0.2032)
		(layers "F.Cu" "B.Cu")
		(net "GND")
	)
	(via
		(at 420.467282 -360.538014)
		(size 0.508)
		(drill 0.254)
		(layers "F.Cu" "B.Cu")
		(net "GND")
	)
	(via
		(at 403.57298 -381.68453)
		(size 0.508)
		(drill 0.254)
		(layers "F.Cu" "B.Cu")
		(net "GND")
	)
	(via
		(at 194.604132 -298.485306)
		(size 0.4826)
		(drill 0.254)
		(layers "F.Cu" "B.Cu")
		(net "GND")
	)
	(via
		(at 448.219576 -31.235142)
		(size 0.508)
		(drill 0.254)
		(layers "F.Cu" "B.Cu")
		(net "GND")
	)
	(via
		(at 131.209288 -219.793058)
		(size 0.508)
		(drill 0.254)
		(layers "F.Cu" "B.Cu")
		(net "GND")
	)
	(via
		(at 410.38018 -383.00533)
		(size 0.508)
		(drill 0.254)
		(layers "F.Cu" "B.Cu")
		(net "GND")
	)
	(via
		(at 189.775846 -199.8853)
		(size 0.4826)
		(drill 0.254)
		(layers "F.Cu" "B.Cu")
		(net "GND")
	)
	(via
		(at 334.417924 -333.823564)
		(size 0.49022)
		(drill 0.254)
		(layers "F.Cu" "B.Cu")
		(net "GND")
	)
	(via
		(at 409.018994 -398.542002)
		(size 0.4064)
		(drill 0.2032)
		(layers "F.Cu" "B.Cu")
		(net "GND")
	)
	(via
		(at 407.449274 -169.743882)
		(size 0.49022)
		(drill 0.254)
		(layers "F.Cu" "B.Cu")
		(net "GND")
	)
	(via
		(at 424.012106 -278.93518)
		(size 0.4826)
		(drill 0.254)
		(layers "F.Cu" "B.Cu")
		(net "GND")
	)
	(via
		(at 47.164752 -385.87553)
		(size 0.4064)
		(drill 0.2032)
		(layers "F.Cu" "B.Cu")
		(net "GND")
	)
	(via
		(at 347.031056 -246.914162)
		(size 0.4064)
		(drill 0.2032)
		(layers "F.Cu" "B.Cu")
		(net "GND")
	)
	(via
		(at 211.008722 -127.18796)
		(size 0.508)
		(drill 0.254)
		(layers "F.Cu" "B.Cu")
		(net "GND")
	)
	(via
		(at 97.681034 -221.804484)
		(size 0.4064)
		(drill 0.2032)
		(layers "F.Cu" "B.Cu")
		(net "GND")
	)
	(via
		(at 92.340938 -295.956228)
		(size 0.4064)
		(drill 0.2032)
		(layers "F.Cu" "B.Cu")
		(net "GND")
	)
	(via
		(at 234.007406 -422.449498)
		(size 0.508)
		(drill 0.254)
		(layers "F.Cu" "B.Cu")
		(net "GND")
	)
	(via
		(at 125.704854 -285.426404)
		(size 0.4064)
		(drill 0.2032)
		(layers "F.Cu" "B.Cu")
		(net "GND")
	)
	(via
		(at 305.430936 -356.226618)
		(size 0.508)
		(drill 0.254)
		(layers "F.Cu" "B.Cu")
		(net "GND")
	)
	(via
		(at 83.41106 -270.846296)
		(size 0.4064)
		(drill 0.2032)
		(layers "F.Cu" "B.Cu")
		(net "GND")
	)
	(via
		(at 442.5442 -216.035128)
		(size 0.4826)
		(drill 0.254)
		(layers "F.Cu" "B.Cu")
		(net "GND")
	)
	(via
		(at 141.854682 -255.824482)
		(size 0.4064)
		(drill 0.2032)
		(layers "F.Cu" "B.Cu")
		(net "GND")
	)
	(via
		(at 145.383504 -369.69573)
		(size 0.508)
		(drill 0.254)
		(layers "F.Cu" "B.Cu")
		(net "GND")
	)
	(via
		(at 49.168304 -315.485272)
		(size 0.4826)
		(drill 0.254)
		(layers "F.Cu" "B.Cu")
		(net "GND")
	)
	(via
		(at 424.758358 -357.554276)
		(size 0.508)
		(drill 0.254)
		(layers "F.Cu" "B.Cu")
		(net "GND")
	)
	(via
		(at 382.379474 -184.683146)
		(size 0.49022)
		(drill 0.254)
		(layers "F.Cu" "B.Cu")
		(net "GND")
	)
	(via
		(at 305.009296 -404.748492)
		(size 0.508)
		(drill 0.254)
		(layers "F.Cu" "B.Cu")
		(net "GND")
	)
	(via
		(at 308.19217 -360.696256)
		(size 0.508)
		(drill 0.254)
		(layers "F.Cu" "B.Cu")
		(net "GND")
	)
	(via
		(at 445.259968 -199.885046)
		(size 0.4826)
		(drill 0.254)
		(layers "F.Cu" "B.Cu")
		(net "GND")
	)
	(via
		(at 116.261896 -371.49913)
		(size 0.508)
		(drill 0.254)
		(layers "F.Cu" "B.Cu")
		(net "GND")
	)
	(via
		(at 420.467282 -362.087414)
		(size 0.508)
		(drill 0.254)
		(layers "F.Cu" "B.Cu")
		(net "GND")
	)
	(via
		(at 319.249552 -426.69968)
		(size 0.4572)
		(drill 0.2032)
		(layers "F.Cu" "B.Cu")
		(net "GND")
	)
	(via
		(at 142.800832 -101.894132)
		(size 0.508)
		(drill 0.254)
		(layers "F.Cu" "B.Cu")
		(net "GND")
	)
	(via
		(at 381.418338 -396.710662)
		(size 0.4064)
		(drill 0.2032)
		(layers "F.Cu" "B.Cu")
		(net "GND")
	)
	(via
		(at 143.14805 -113.89995)
		(size 0.508)
		(drill 0.254)
		(layers "F.Cu" "B.Cu")
		(net "GND")
	)
	(via
		(at 112.09528 -78.78318)
		(size 0.508)
		(drill 0.254)
		(layers "F.Cu" "B.Cu")
		(net "GND")
	)
	(via
		(at 353.141026 -226.664266)
		(size 0.4064)
		(drill 0.2032)
		(layers "F.Cu" "B.Cu")
		(net "GND")
	)
	(via
		(at 375.054876 -266.796012)
		(size 0.4064)
		(drill 0.2032)
		(layers "F.Cu" "B.Cu")
		(net "GND")
	)
	(via
		(at 86.249764 -434.899562)
		(size 0.4572)
		(drill 0.2032)
		(layers "F.Cu" "B.Cu")
		(net "GND")
	)
	(via
		(at 431.55616 -318.035178)
		(size 0.4826)
		(drill 0.254)
		(layers "F.Cu" "B.Cu")
		(net "GND")
	)
	(via
		(at 111.633 -122.936)
		(size 0.508)
		(drill 0.254)
		(layers "F.Cu" "B.Cu")
		(net "GND")
	)
	(via
		(at 362.834682 -276.516084)
		(size 0.4064)
		(drill 0.2032)
		(layers "F.Cu" "B.Cu")
		(net "GND")
	)
	(via
		(at 324.75297 -235.03001)
		(size 0.4064)
		(drill 0.2032)
		(layers "F.Cu" "B.Cu")
		(net "GND")
	)
	(via
		(at 121.209562 -259.73024)
		(size 0.4826)
		(drill 0.254)
		(layers "F.Cu" "B.Cu")
		(net "GND")
	)
	(via
		(at 187.911994 -115.842796)
		(size 0.4572)
		(drill 0.254)
		(layers "F.Cu" "B.Cu")
		(net "GND")
	)
	(via
		(at 179.516024 -252.58522)
		(size 0.4826)
		(drill 0.254)
		(layers "F.Cu" "B.Cu")
		(net "GND")
	)
	(via
		(at 218.96705 -101.228398)
		(size 0.508)
		(drill 0.254)
		(layers "F.Cu" "B.Cu")
		(net "GND")
	)
	(via
		(at 381.634746 -284.616144)
		(size 0.4064)
		(drill 0.2032)
		(layers "F.Cu" "B.Cu")
		(net "GND")
	)
	(via
		(at 128.054862 -268.416278)
		(size 0.4064)
		(drill 0.2032)
		(layers "F.Cu" "B.Cu")
		(net "GND")
	)
	(via
		(at 92.17533 -182.109872)
		(size 0.49022)
		(drill 0.254)
		(layers "F.Cu" "B.Cu")
		(net "GND")
	)
	(via
		(at 26.017982 -6.091174)
		(size 0.508)
		(drill 0.254)
		(layers "F.Cu" "B.Cu")
		(net "GND")
	)
	(via
		(at 341.390986 -250.154186)
		(size 0.4064)
		(drill 0.2032)
		(layers "F.Cu" "B.Cu")
		(net "GND")
	)
	(via
		(at 252.469396 -439.90768)
		(size 0.508)
		(drill 0.254)
		(layers "F.Cu" "B.Cu")
		(net "GND")
	)
	(via
		(at 135.274812 -234.764326)
		(size 0.4064)
		(drill 0.2032)
		(layers "F.Cu" "B.Cu")
		(net "GND")
	)
	(via
		(at 167.143684 -221.135194)
		(size 0.4826)
		(drill 0.254)
		(layers "F.Cu" "B.Cu")
		(net "GND")
	)
	(via
		(at 25.989534 -4.963414)
		(size 0.508)
		(drill 0.254)
		(layers "F.Cu" "B.Cu")
		(net "GND")
	)
	(via
		(at 153.090118 -384.617722)
		(size 0.4064)
		(drill 0.2032)
		(layers "F.Cu" "B.Cu")
		(net "GND")
	)
	(via
		(at 152.714198 -405.098504)
		(size 0.4572)
		(drill 0.254)
		(layers "F.Cu" "B.Cu")
		(net "GND")
	)
	(via
		(at 105.200958 -242.864386)
		(size 0.4064)
		(drill 0.2032)
		(layers "F.Cu" "B.Cu")
		(net "GND")
	)
	(via
		(at 18.992342 -203.285344)
		(size 0.4826)
		(drill 0.254)
		(layers "F.Cu" "B.Cu")
		(net "GND")
	)
	(via
		(at 79.185516 -31.615888)
		(size 0.508)
		(drill 0.254)
		(layers "F.Cu" "B.Cu")
		(net "GND")
	)
	(via
		(at 115.762278 -384.617722)
		(size 0.4064)
		(drill 0.2032)
		(layers "F.Cu" "B.Cu")
		(net "GND")
	)
	(via
		(at 363.299248 -335.892648)
		(size 0.508)
		(drill 0.254)
		(layers "F.Cu" "B.Cu")
		(net "GND")
	)
	(via
		(at 154.399234 -91.252548)
		(size 0.508)
		(drill 0.254)
		(layers "F.Cu" "B.Cu")
		(net "GND")
	)
	(via
		(at 401.32889 -421.586152)
		(size 0.4572)
		(drill 0.254)
		(layers "F.Cu" "B.Cu")
		(net "GND")
	)
	(via
		(at 119.12473 -278.946356)
		(size 0.4064)
		(drill 0.2032)
		(layers "F.Cu" "B.Cu")
		(net "GND")
	)
	(via
		(at 344.591386 -418.412168)
		(size 0.4064)
		(drill 0.2032)
		(layers "F.Cu" "B.Cu")
		(net "GND")
	)
	(via
		(at 109.417866 -179.321968)
		(size 0.49022)
		(drill 0.254)
		(layers "F.Cu" "B.Cu")
		(net "GND")
	)
	(via
		(at 398.316704 -144.379442)
		(size 0.49022)
		(drill 0.254)
		(layers "F.Cu" "B.Cu")
		(net "GND")
	)
	(via
		(at 435.000146 -214.335106)
		(size 0.4826)
		(drill 0.254)
		(layers "F.Cu" "B.Cu")
		(net "GND")
	)
	(via
		(at 387.127496 -12.08278)
		(size 0.508)
		(drill 0.254)
		(layers "F.Cu" "B.Cu")
		(net "GND")
	)
	(via
		(at 307.368194 -265.335004)
		(size 0.4826)
		(drill 0.254)
		(layers "F.Cu" "B.Cu")
		(net "GND")
	)
	(via
		(at 94.803976 -411.936184)
		(size 0.4572)
		(drill 0.254)
		(layers "F.Cu" "B.Cu")
		(net "GND")
	)
	(via
		(at 358.311196 -248.534174)
		(size 0.4064)
		(drill 0.2032)
		(layers "F.Cu" "B.Cu")
		(net "GND")
	)
	(via
		(at 335.760314 -417.778184)
		(size 0.4572)
		(drill 0.254)
		(layers "F.Cu" "B.Cu")
		(net "GND")
	)
	(via
		(at 139.038076 -380.535688)
		(size 0.508)
		(drill 0.254)
		(layers "F.Cu" "B.Cu")
		(net "GND")
	)
	(via
		(at 58.043826 -218.585288)
		(size 0.4826)
		(drill 0.254)
		(layers "F.Cu" "B.Cu")
		(net "GND")
	)
	(via
		(at 31.053278 -19.13636)
		(size 0.508)
		(drill 0.254)
		(layers "F.Cu" "B.Cu")
		(net "GND")
	)
	(via
		(at 436.117746 -239.41024)
		(size 0.4826)
		(drill 0.254)
		(layers "F.Cu" "B.Cu")
		(net "GND")
	)
	(via
		(at 150.976584 -369.69573)
		(size 0.508)
		(drill 0.254)
		(layers "F.Cu" "B.Cu")
		(net "GND")
	)
	(via
		(at 168.527984 -289.98545)
		(size 0.4826)
		(drill 0.254)
		(layers "F.Cu" "B.Cu")
		(net "GND")
	)
	(via
		(at 139.974828 -236.384338)
		(size 0.4064)
		(drill 0.2032)
		(layers "F.Cu" "B.Cu")
		(net "GND")
	)
	(via
		(at 67.148964 -407.00452)
		(size 0.4064)
		(drill 0.2032)
		(layers "F.Cu" "B.Cu")
		(net "GND")
	)
	(via
		(at 83.580986 -234.764326)
		(size 0.4064)
		(drill 0.2032)
		(layers "F.Cu" "B.Cu")
		(net "GND")
	)
	(via
		(at 351.076514 -416.020504)
		(size 0.4572)
		(drill 0.254)
		(layers "F.Cu" "B.Cu")
		(net "GND")
	)
	(via
		(at 360.785918 -181.67604)
		(size 0.508)
		(drill 0.254)
		(layers "F.Cu" "B.Cu")
		(net "GND")
	)
	(via
		(at 337.291934 -420.318184)
		(size 0.4572)
		(drill 0.254)
		(layers "F.Cu" "B.Cu")
		(net "GND")
	)
	(via
		(at 362.271056 -178.199288)
		(size 0.49022)
		(drill 0.254)
		(layers "F.Cu" "B.Cu")
		(net "GND")
	)
	(via
		(at 23.519384 -441.227718)
		(size 0.508)
		(drill 0.254)
		(layers "F.Cu" "B.Cu")
		(net "GND")
	)
	(via
		(at 105.500932 -286.23641)
		(size 0.4064)
		(drill 0.2032)
		(layers "F.Cu" "B.Cu")
		(net "GND")
	)
	(via
		(at 453.334374 -397.811244)
		(size 0.49022)
		(drill 0.254)
		(layers "F.Cu" "B.Cu")
		(net "GND")
	)
	(via
		(at 402.501862 -418.412168)
		(size 0.4064)
		(drill 0.2032)
		(layers "F.Cu" "B.Cu")
		(net "GND")
	)
	(via
		(at 89.514172 -56.471566)
		(size 0.508)
		(drill 0.254)
		(layers "F.Cu" "B.Cu")
		(net "GND")
	)
	(via
		(at 346.91828 -332.440534)
		(size 0.508)
		(drill 0.254)
		(layers "F.Cu" "B.Cu")
		(net "GND")
	)
	(via
		(at 40.409114 -342.816434)
		(size 0.508)
		(drill 0.254)
		(layers "F.Cu" "B.Cu")
		(net "GND")
	)
	(via
		(at 143.681704 -372.15953)
		(size 0.508)
		(drill 0.254)
		(layers "F.Cu" "B.Cu")
		(net "GND")
	)
	(via
		(at 187.54598 -426.188886)
		(size 0.508)
		(drill 0.254)
		(layers "F.Cu" "B.Cu")
		(net "GND")
	)
	(via
		(at 78.24978 -431.29962)
		(size 0.4572)
		(drill 0.2032)
		(layers "F.Cu" "B.Cu")
		(net "GND")
	)
	(via
		(at 145.444718 -285.426404)
		(size 0.4064)
		(drill 0.2032)
		(layers "F.Cu" "B.Cu")
		(net "GND")
	)
	(via
		(at 383.67843 -394.831062)
		(size 0.4064)
		(drill 0.2032)
		(layers "F.Cu" "B.Cu")
		(net "GND")
	)
	(via
		(at 389.79475 -241.24412)
		(size 0.4064)
		(drill 0.2032)
		(layers "F.Cu" "B.Cu")
		(net "GND")
	)
	(via
		(at 157.309058 -410.664152)
		(size 0.4572)
		(drill 0.254)
		(layers "F.Cu" "B.Cu")
		(net "GND")
	)
	(via
		(at 139.6492 -37.338)
		(size 0.508)
		(drill 0.254)
		(layers "F.Cu" "B.Cu")
		(net "GND")
	)
	(via
		(at 161.818066 -410.030168)
		(size 0.4064)
		(drill 0.2032)
		(layers "F.Cu" "B.Cu")
		(net "GND")
	)
	(via
		(at 360.465624 -384.299968)
		(size 0.508)
		(drill 0.254)
		(layers "F.Cu" "B.Cu")
		(net "GND")
	)
	(via
		(at 93.395038 -309.022496)
		(size 0.4064)
		(drill 0.2032)
		(layers "F.Cu" "B.Cu")
		(net "GND")
	)
	(via
		(at 59.428126 -251.735336)
		(size 0.4826)
		(drill 0.254)
		(layers "F.Cu" "B.Cu")
		(net "GND")
	)
	(via
		(at 359.805224 -389.402828)
		(size 0.508)
		(drill 0.254)
		(layers "F.Cu" "B.Cu")
		(net "GND")
	)
	(via
		(at 41.39565 -194.885564)
		(size 0.4826)
		(drill 0.254)
		(layers "F.Cu" "B.Cu")
		(net "GND")
	)
	(via
		(at 328.061066 -265.176)
		(size 0.4064)
		(drill 0.2032)
		(layers "F.Cu" "B.Cu")
		(net "GND")
	)
	(via
		(at 351.731072 -243.674138)
		(size 0.4064)
		(drill 0.2032)
		(layers "F.Cu" "B.Cu")
		(net "GND")
	)
	(via
		(at 22.145752 -7.215124)
		(size 0.508)
		(drill 0.254)
		(layers "F.Cu" "B.Cu")
		(net "GND")
	)
	(via
		(at 17.608042 -223.685354)
		(size 0.4826)
		(drill 0.254)
		(layers "F.Cu" "B.Cu")
		(net "GND")
	)
	(via
		(at 326.351138 -242.054126)
		(size 0.4064)
		(drill 0.2032)
		(layers "F.Cu" "B.Cu")
		(net "GND")
	)
	(via
		(at 467.5378 -261.671054)
		(size 0.508)
		(drill 0.254)
		(layers "F.Cu" "B.Cu")
		(net "GND")
	)
	(via
		(at 328.061066 -270.036036)
		(size 0.4064)
		(drill 0.2032)
		(layers "F.Cu" "B.Cu")
		(net "GND")
	)
	(via
		(at 71.249794 -429.147224)
		(size 0.4572)
		(drill 0.2032)
		(layers "F.Cu" "B.Cu")
		(net "GND")
	)
	(via
		(at 236.696758 -233.214672)
		(size 0.4826)
		(drill 0.254)
		(layers "F.Cu" "B.Cu")
		(net "GND")
	)
	(via
		(at 16.124174 -386.914898)
		(size 0.49022)
		(drill 0.254)
		(layers "F.Cu" "B.Cu")
		(net "GND")
	)
	(via
		(at 82.823812 -407.638504)
		(size 0.4572)
		(drill 0.254)
		(layers "F.Cu" "B.Cu")
		(net "GND")
	)
	(via
		(at 88.24976 -425.547282)
		(size 0.4572)
		(drill 0.2032)
		(layers "F.Cu" "B.Cu")
		(net "GND")
	)
	(via
		(at 78.228952 -403.830536)
		(size 0.4572)
		(drill 0.254)
		(layers "F.Cu" "B.Cu")
		(net "GND")
	)
	(via
		(at 98.321114 -332.44536)
		(size 0.508)
		(drill 0.254)
		(layers "F.Cu" "B.Cu")
		(net "GND")
	)
	(via
		(at 370.69649 -412.212536)
		(size 0.4572)
		(drill 0.254)
		(layers "F.Cu" "B.Cu")
		(net "GND")
	)
	(via
		(at 35.526726 -174.391828)
		(size 0.508)
		(drill 0.254)
		(layers "F.Cu" "B.Cu")
		(net "GND")
	)
	(via
		(at 58.043826 -209.235294)
		(size 0.4826)
		(drill 0.254)
		(layers "F.Cu" "B.Cu")
		(net "GND")
	)
	(via
		(at 43.891708 -173.237144)
		(size 0.508)
		(drill 0.254)
		(layers "F.Cu" "B.Cu")
		(net "GND")
	)
	(via
		(at 264.43051 -230.060246)
		(size 0.4826)
		(drill 0.254)
		(layers "F.Cu" "B.Cu")
		(net "GND")
	)
	(via
		(at 173.35627 -312.935366)
		(size 0.4826)
		(drill 0.254)
		(layers "F.Cu" "B.Cu")
		(net "GND")
	)
	(via
		(at 369.114832 -255.824228)
		(size 0.4064)
		(drill 0.2032)
		(layers "F.Cu" "B.Cu")
		(net "GND")
	)
	(via
		(at 110.77956 -380.82728)
		(size 0.508)
		(drill 0.254)
		(layers "F.Cu" "B.Cu")
		(net "GND")
	)
	(via
		(at 37.333428 -133.857238)
		(size 0.508)
		(drill 0.254)
		(layers "F.Cu" "B.Cu")
		(net "GND")
	)
	(via
		(at 416.468052 -241.53495)
		(size 0.4826)
		(drill 0.254)
		(layers "F.Cu" "B.Cu")
		(net "GND")
	)
	(via
		(at 89.99093 -295.146222)
		(size 0.4064)
		(drill 0.2032)
		(layers "F.Cu" "B.Cu")
		(net "GND")
	)
	(via
		(at 204.8637 -314.635388)
		(size 0.4826)
		(drill 0.254)
		(layers "F.Cu" "B.Cu")
		(net "GND")
	)
	(via
		(at 102.211124 -283.806392)
		(size 0.4064)
		(drill 0.2032)
		(layers "F.Cu" "B.Cu")
		(net "GND")
	)
	(via
		(at 439.100214 -265.335004)
		(size 0.4826)
		(drill 0.254)
		(layers "F.Cu" "B.Cu")
		(net "GND")
	)
	(via
		(at 162.618928 -390.160002)
		(size 0.4064)
		(drill 0.2032)
		(layers "F.Cu" "B.Cu")
		(net "GND")
	)
	(via
		(at 18.54835 -12.37488)
		(size 0.508)
		(drill 0.254)
		(layers "F.Cu" "B.Cu")
		(net "GND")
	)
	(via
		(at 455.305668 -238.560102)
		(size 0.4826)
		(drill 0.254)
		(layers "F.Cu" "B.Cu")
		(net "GND")
	)
	(via
		(at 179.516024 -283.185362)
		(size 0.4826)
		(drill 0.254)
		(layers "F.Cu" "B.Cu")
		(net "GND")
	)
	(via
		(at 120.064784 -270.846296)
		(size 0.4064)
		(drill 0.2032)
		(layers "F.Cu" "B.Cu")
		(net "GND")
	)
	(via
		(at 49.168304 -303.585372)
		(size 0.4826)
		(drill 0.254)
		(layers "F.Cu" "B.Cu")
		(net "GND")
	)
	(via
		(at 369.80749 -185.988198)
		(size 0.508)
		(drill 0.254)
		(layers "F.Cu" "B.Cu")
		(net "GND")
	)
	(via
		(at 134.164832 -290.286186)
		(size 0.4064)
		(drill 0.2032)
		(layers "F.Cu" "B.Cu")
		(net "GND")
	)
	(via
		(at 83.580986 -229.90429)
		(size 0.4064)
		(drill 0.2032)
		(layers "F.Cu" "B.Cu")
		(net "GND")
	)
	(via
		(at 83.874102 -371.49913)
		(size 0.508)
		(drill 0.254)
		(layers "F.Cu" "B.Cu")
		(net "GND")
	)
	(via
		(at 74.207624 -172.484034)
		(size 0.508)
		(drill 0.254)
		(layers "F.Cu" "B.Cu")
		(net "GND")
	)
	(via
		(at 383.21488 -225.044254)
		(size 0.4064)
		(drill 0.2032)
		(layers "F.Cu" "B.Cu")
		(net "GND")
	)
	(via
		(at 344.981022 -284.616144)
		(size 0.4064)
		(drill 0.2032)
		(layers "F.Cu" "B.Cu")
		(net "GND")
	)
	(via
		(at 292.280086 -215.18499)
		(size 0.4826)
		(drill 0.254)
		(layers "F.Cu" "B.Cu")
		(net "GND")
	)
	(via
		(at 364.137956 -261.32282)
		(size 0.4826)
		(drill 0.254)
		(layers "F.Cu" "B.Cu")
		(net "GND")
	)
	(via
		(at 165.812216 -278.085296)
		(size 0.4826)
		(drill 0.254)
		(layers "F.Cu" "B.Cu")
		(net "GND")
	)
	(via
		(at 138.864848 -270.846296)
		(size 0.4064)
		(drill 0.2032)
		(layers "F.Cu" "B.Cu")
		(net "GND")
	)
	(via
		(at 97.663 -205.958948)
		(size 0.508)
		(drill 0.254)
		(layers "F.Cu" "B.Cu")
		(net "GND")
	)
	(via
		(at 327.249536 -432.747166)
		(size 0.4572)
		(drill 0.2032)
		(layers "F.Cu" "B.Cu")
		(net "GND")
	)
	(via
		(at 355.961188 -226.664266)
		(size 0.4064)
		(drill 0.2032)
		(layers "F.Cu" "B.Cu")
		(net "GND")
	)
	(via
		(at 408.244294 -400.212814)
		(size 0.4064)
		(drill 0.2032)
		(layers "F.Cu" "B.Cu")
		(net "GND")
	)
	(via
		(at 165.812216 -287.43529)
		(size 0.4826)
		(drill 0.254)
		(layers "F.Cu" "B.Cu")
		(net "GND")
	)
	(via
		(at 128.481074 -409.396184)
		(size 0.4572)
		(drill 0.254)
		(layers "F.Cu" "B.Cu")
		(net "GND")
	)
	(via
		(at 300.7614 -358.14)
		(size 0.508)
		(drill 0.254)
		(layers "F.Cu" "B.Cu")
		(net "GND")
	)
	(via
		(at 284.736032 -261.93496)
		(size 0.4826)
		(drill 0.254)
		(layers "F.Cu" "B.Cu")
		(net "GND")
	)
	(via
		(at 332.931008 -225.85426)
		(size 0.4064)
		(drill 0.2032)
		(layers "F.Cu" "B.Cu")
		(net "GND")
	)
	(via
		(at 36.795964 -267.03528)
		(size 0.4826)
		(drill 0.254)
		(layers "F.Cu" "B.Cu")
		(net "GND")
	)
	(via
		(at 55.966614 -373.30253)
		(size 0.508)
		(drill 0.254)
		(layers "F.Cu" "B.Cu")
		(net "GND")
	)
	(via
		(at 382.349502 -429.147224)
		(size 0.4572)
		(drill 0.2032)
		(layers "F.Cu" "B.Cu")
		(net "GND")
	)
	(via
		(at 88.24976 -426.69968)
		(size 0.4572)
		(drill 0.2032)
		(layers "F.Cu" "B.Cu")
		(net "GND")
	)
	(via
		(at 212.385402 -70.95617)
		(size 0.508)
		(drill 0.254)
		(layers "F.Cu" "B.Cu")
		(net "GND")
	)
	(via
		(at 44.340018 -213.485222)
		(size 0.4826)
		(drill 0.254)
		(layers "F.Cu" "B.Cu")
		(net "GND")
	)
	(via
		(at 57.021222 -171.934124)
		(size 0.508)
		(drill 0.254)
		(layers "F.Cu" "B.Cu")
		(net "GND")
	)
	(via
		(at 265.54811 -283.185108)
		(size 0.4826)
		(drill 0.254)
		(layers "F.Cu" "B.Cu")
		(net "GND")
	)
	(via
		(at 307.346096 -379.88113)
		(size 0.508)
		(drill 0.254)
		(layers "F.Cu" "B.Cu")
		(net "GND")
	)
	(via
		(at 122.49277 -34.473388)
		(size 0.508)
		(drill 0.254)
		(layers "F.Cu" "B.Cu")
		(net "GND")
	)
	(via
		(at 62.051184 -15.18031)
		(size 0.508)
		(drill 0.254)
		(layers "F.Cu" "B.Cu")
		(net "GND")
	)
	(via
		(at 454.502266 -403.473412)
		(size 0.508)
		(drill 0.254)
		(layers "F.Cu" "B.Cu")
		(net "GND")
	)
	(via
		(at 427.456092 -236.435138)
		(size 0.4826)
		(drill 0.254)
		(layers "F.Cu" "B.Cu")
		(net "GND")
	)
	(via
		(at 90.120724 -412.570168)
		(size 0.4064)
		(drill 0.2032)
		(layers "F.Cu" "B.Cu")
		(net "GND")
	)
	(via
		(at 131.185666 -410.030168)
		(size 0.4064)
		(drill 0.2032)
		(layers "F.Cu" "B.Cu")
		(net "GND")
	)
	(via
		(at 167.487092 -131.13004)
		(size 0.508)
		(drill 0.254)
		(layers "F.Cu" "B.Cu")
		(net "GND")
	)
	(via
		(at 79.41691 -185.988198)
		(size 0.508)
		(drill 0.254)
		(layers "F.Cu" "B.Cu")
		(net "GND")
	)
	(via
		(at 31.578296 -220.710252)
		(size 0.4826)
		(drill 0.254)
		(layers "F.Cu" "B.Cu")
		(net "GND")
	)
	(via
		(at 59.428126 -213.485222)
		(size 0.4826)
		(drill 0.254)
		(layers "F.Cu" "B.Cu")
		(net "GND")
	)
	(via
		(at 83.88096 -291.096192)
		(size 0.4064)
		(drill 0.2032)
		(layers "F.Cu" "B.Cu")
		(net "GND")
	)
	(via
		(at 354.34397 -400.212814)
		(size 0.4064)
		(drill 0.2032)
		(layers "F.Cu" "B.Cu")
		(net "GND")
	)
	(via
		(at 328.53122 -264.365994)
		(size 0.4064)
		(drill 0.2032)
		(layers "F.Cu" "B.Cu")
		(net "GND")
	)
	(via
		(at 109.900974 -247.724422)
		(size 0.4064)
		(drill 0.2032)
		(layers "F.Cu" "B.Cu")
		(net "GND")
	)
	(via
		(at 290.895786 -295.935146)
		(size 0.4826)
		(drill 0.254)
		(layers "F.Cu" "B.Cu")
		(net "GND")
	)
	(via
		(at 41.820084 -6.598158)
		(size 0.508)
		(drill 0.254)
		(layers "F.Cu" "B.Cu")
		(net "GND")
	)
	(via
		(at 131.716526 -393.927838)
		(size 0.4572)
		(drill 0.254)
		(layers "F.Cu" "B.Cu")
		(net "GND")
	)
	(via
		(at 74.299064 -355.125528)
		(size 0.508)
		(drill 0.254)
		(layers "F.Cu" "B.Cu")
		(net "GND")
	)
	(via
		(at 194.604132 -214.33536)
		(size 0.4826)
		(drill 0.254)
		(layers "F.Cu" "B.Cu")
		(net "GND")
	)
	(via
		(at 69.581014 -369.69573)
		(size 0.508)
		(drill 0.254)
		(layers "F.Cu" "B.Cu")
		(net "GND")
	)
	(via
		(at 335.401666 -418.412168)
		(size 0.4064)
		(drill 0.2032)
		(layers "F.Cu" "B.Cu")
		(net "GND")
	)
	(via
		(at 185.81497 -21.25599)
		(size 0.508)
		(drill 0.254)
		(layers "F.Cu" "B.Cu")
		(net "GND")
	)
	(via
		(at 306.73421 -345.566238)
		(size 0.49022)
		(drill 0.254)
		(layers "F.Cu" "B.Cu")
		(net "GND")
	)
	(via
		(at 271.974564 -314.210192)
		(size 0.4826)
		(drill 0.254)
		(layers "F.Cu" "B.Cu")
		(net "GND")
	)
	(via
		(at 76.812902 -251.230384)
		(size 0.4064)
		(drill 0.2032)
		(layers "F.Cu" "B.Cu")
		(net "GND")
	)
	(via
		(at 302.150526 -230.060246)
		(size 0.4826)
		(drill 0.254)
		(layers "F.Cu" "B.Cu")
		(net "GND")
	)
	(via
		(at 58.178446 -386.449062)
		(size 0.4064)
		(drill 0.2032)
		(layers "F.Cu" "B.Cu")
		(net "GND")
	)
	(via
		(at 145.444718 -264.366248)
		(size 0.4064)
		(drill 0.2032)
		(layers "F.Cu" "B.Cu")
		(net "GND")
	)
	(via
		(at 114.696494 -413.204152)
		(size 0.4572)
		(drill 0.254)
		(layers "F.Cu" "B.Cu")
		(net "GND")
	)
	(via
		(at 95.631 -295.146222)
		(size 0.4064)
		(drill 0.2032)
		(layers "F.Cu" "B.Cu")
		(net "GND")
	)
	(via
		(at 386.01269 -421.586152)
		(size 0.4572)
		(drill 0.254)
		(layers "F.Cu" "B.Cu")
		(net "GND")
	)
	(via
		(at 16.23441 -395.288516)
		(size 0.508)
		(drill 0.254)
		(layers "F.Cu" "B.Cu")
		(net "GND")
	)
	(via
		(at 374.114822 -292.71595)
		(size 0.4064)
		(drill 0.2032)
		(layers "F.Cu" "B.Cu")
		(net "GND")
	)
	(via
		(at 183.616092 -299.335444)
		(size 0.4826)
		(drill 0.254)
		(layers "F.Cu" "B.Cu")
		(net "GND")
	)
	(via
		(at 421.296338 -284.88513)
		(size 0.4826)
		(drill 0.254)
		(layers "F.Cu" "B.Cu")
		(net "GND")
	)
	(via
		(at 122.081798 -411.936184)
		(size 0.4572)
		(drill 0.254)
		(layers "F.Cu" "B.Cu")
		(net "GND")
	)
	(via
		(at 47.784004 -223.685354)
		(size 0.4826)
		(drill 0.254)
		(layers "F.Cu" "B.Cu")
		(net "GND")
	)
	(via
		(at 307.832506 -418.412168)
		(size 0.4064)
		(drill 0.2032)
		(layers "F.Cu" "B.Cu")
		(net "GND")
	)
	(via
		(at 117.526562 -61.554868)
		(size 0.508)
		(drill 0.254)
		(layers "F.Cu" "B.Cu")
		(net "GND")
	)
	(via
		(at 373.174768 -268.416024)
		(size 0.4064)
		(drill 0.2032)
		(layers "F.Cu" "B.Cu")
		(net "GND")
	)
	(via
		(at 358.61117 -282.186126)
		(size 0.4064)
		(drill 0.2032)
		(layers "F.Cu" "B.Cu")
		(net "GND")
	)
	(via
		(at 15.959582 -104.037638)
		(size 0.508)
		(drill 0.254)
		(layers "F.Cu" "B.Cu")
		(net "GND")
	)
	(via
		(at 328.231246 -243.674138)
		(size 0.4064)
		(drill 0.2032)
		(layers "F.Cu" "B.Cu")
		(net "GND")
	)
	(via
		(at 153.349706 -430.147222)
		(size 0.4572)
		(drill 0.2032)
		(layers "F.Cu" "B.Cu")
		(net "GND")
	)
	(via
		(at 339.341206 -294.335962)
		(size 0.4064)
		(drill 0.2032)
		(layers "F.Cu" "B.Cu")
		(net "GND")
	)
	(via
		(at 393.384786 -261.12597)
		(size 0.4064)
		(drill 0.2032)
		(layers "F.Cu" "B.Cu")
		(net "GND")
	)
	(via
		(at 79.821024 -233.144314)
		(size 0.4064)
		(drill 0.2032)
		(layers "F.Cu" "B.Cu")
		(net "GND")
	)
	(via
		(at 195.721732 -211.360258)
		(size 0.4826)
		(drill 0.254)
		(layers "F.Cu" "B.Cu")
		(net "GND")
	)
	(via
		(at 123.354846 -265.176254)
		(size 0.4064)
		(drill 0.2032)
		(layers "F.Cu" "B.Cu")
		(net "GND")
	)
	(via
		(at 47.784004 -234.73537)
		(size 0.4826)
		(drill 0.254)
		(layers "F.Cu" "B.Cu")
		(net "GND")
	)
	(via
		(at 385.739894 -414.752536)
		(size 0.4572)
		(drill 0.254)
		(layers "F.Cu" "B.Cu")
		(net "GND")
	)
	(via
		(at 91.10091 -249.344434)
		(size 0.4064)
		(drill 0.2032)
		(layers "F.Cu" "B.Cu")
		(net "GND")
	)
	(via
		(at 188.681614 -10.117328)
		(size 0.508)
		(drill 0.254)
		(layers "F.Cu" "B.Cu")
		(net "GND")
	)
	(via
		(at 292.280086 -243.234972)
		(size 0.4826)
		(drill 0.254)
		(layers "F.Cu" "B.Cu")
		(net "GND")
	)
	(via
		(at 142.154656 -281.376374)
		(size 0.4064)
		(drill 0.2032)
		(layers "F.Cu" "B.Cu")
		(net "GND")
	)
	(via
		(at 36.900358 -345.571064)
		(size 0.49022)
		(drill 0.254)
		(layers "F.Cu" "B.Cu")
		(net "GND")
	)
	(via
		(at 298.871386 -348.704662)
		(size 0.49022)
		(drill 0.254)
		(layers "F.Cu" "B.Cu")
		(net "GND")
	)
	(via
		(at 350.151192 -275.706078)
		(size 0.4064)
		(drill 0.2032)
		(layers "F.Cu" "B.Cu")
		(net "GND")
	)
	(via
		(at 76.5937 -384.66268)
		(size 0.508)
		(drill 0.254)
		(layers "F.Cu" "B.Cu")
		(net "GND")
	)
	(via
		(at 20.32381 -199.8853)
		(size 0.4826)
		(drill 0.254)
		(layers "F.Cu" "B.Cu")
		(net "GND")
	)
	(via
		(at 355.961188 -231.524048)
		(size 0.4064)
		(drill 0.2032)
		(layers "F.Cu" "B.Cu")
		(net "GND")
	)
	(via
		(at 369.80749 -185.327798)
		(size 0.508)
		(drill 0.254)
		(layers "F.Cu" "B.Cu")
		(net "GND")
	)
	(via
		(at 349.381064 -223.424242)
		(size 0.4064)
		(drill 0.2032)
		(layers "F.Cu" "B.Cu")
		(net "GND")
	)
	(via
		(at 388.68477 -283.806138)
		(size 0.4064)
		(drill 0.2032)
		(layers "F.Cu" "B.Cu")
		(net "GND")
	)
	(via
		(at 378.04471 -248.534174)
		(size 0.4064)
		(drill 0.2032)
		(layers "F.Cu" "B.Cu")
		(net "GND")
	)
	(via
		(at 57.06237 -384.617722)
		(size 0.4064)
		(drill 0.2032)
		(layers "F.Cu" "B.Cu")
		(net "GND")
	)
	(via
		(at 369.414806 -268.416024)
		(size 0.4064)
		(drill 0.2032)
		(layers "F.Cu" "B.Cu")
		(net "GND")
	)
	(via
		(at 100.30841 -403.864572)
		(size 0.508)
		(drill 0.254)
		(layers "F.Cu" "B.Cu")
		(net "GND")
	)
	(via
		(at 26.687526 -428.183802)
		(size 0.508)
		(drill 0.254)
		(layers "F.Cu" "B.Cu")
		(net "GND")
	)
	(via
		(at 268.263878 -314.635134)
		(size 0.4826)
		(drill 0.254)
		(layers "F.Cu" "B.Cu")
		(net "GND")
	)
	(via
		(at 454.324466 -402.79447)
		(size 0.508)
		(drill 0.254)
		(layers "F.Cu" "B.Cu")
		(net "GND")
	)
	(via
		(at 77.112876 -261.670292)
		(size 0.4064)
		(drill 0.2032)
		(layers "F.Cu" "B.Cu")
		(net "GND")
	)
	(via
		(at 93.280992 -284.616398)
		(size 0.4064)
		(drill 0.2032)
		(layers "F.Cu" "B.Cu")
		(net "GND")
	)
	(via
		(at 9.246108 -134.28345)
		(size 0.508)
		(drill 0.254)
		(layers "F.Cu" "B.Cu")
		(net "GND")
	)
	(via
		(at 382.1049 -277.32609)
		(size 0.4064)
		(drill 0.2032)
		(layers "F.Cu" "B.Cu")
		(net "GND")
	)
	(via
		(at 427.411896 -436.296054)
		(size 0.508)
		(drill 0.254)
		(layers "F.Cu" "B.Cu")
		(net "GND")
	)
	(via
		(at 191.160146 -216.885266)
		(size 0.4826)
		(drill 0.254)
		(layers "F.Cu" "B.Cu")
		(net "GND")
	)
	(via
		(at 381.334772 -226.664266)
		(size 0.4064)
		(drill 0.2032)
		(layers "F.Cu" "B.Cu")
		(net "GND")
	)
	(via
		(at 412.08198 -380.54153)
		(size 0.508)
		(drill 0.254)
		(layers "F.Cu" "B.Cu")
		(net "GND")
	)
	(via
		(at 59.249818 -429.147224)
		(size 0.4572)
		(drill 0.2032)
		(layers "F.Cu" "B.Cu")
		(net "GND")
	)
	(via
		(at 437.715914 -230.485188)
		(size 0.4826)
		(drill 0.254)
		(layers "F.Cu" "B.Cu")
		(net "GND")
	)
	(via
		(at 126.676658 -406.370536)
		(size 0.4572)
		(drill 0.254)
		(layers "F.Cu" "B.Cu")
		(net "GND")
	)
	(via
		(at 425.678854 -350.659954)
		(size 0.49022)
		(drill 0.254)
		(layers "F.Cu" "B.Cu")
		(net "GND")
	)
	(via
		(at 298.839636 -380.54153)
		(size 0.508)
		(drill 0.254)
		(layers "F.Cu" "B.Cu")
		(net "GND")
	)
	(via
		(at 115.534694 -244.484398)
		(size 0.4064)
		(drill 0.2032)
		(layers "F.Cu" "B.Cu")
		(net "GND")
	)
	(via
		(at 415.7472 -108.453428)
		(size 0.508)
		(drill 0.254)
		(layers "F.Cu" "B.Cu")
		(net "GND")
	)
	(via
		(at 361.446318 -181.01564)
		(size 0.508)
		(drill 0.254)
		(layers "F.Cu" "B.Cu")
		(net "GND")
	)
	(via
		(at 317.249556 -428.851314)
		(size 0.4572)
		(drill 0.2032)
		(layers "F.Cu" "B.Cu")
		(net "GND")
	)
	(via
		(at 422.55694 -100.260658)
		(size 0.508)
		(drill 0.254)
		(layers "F.Cu" "B.Cu")
		(net "GND")
	)
	(via
		(at 15.05585 -390.8425)
		(size 0.49022)
		(drill 0.254)
		(layers "F.Cu" "B.Cu")
		(net "GND")
	)
	(via
		(at 339.15604 -61.364876)
		(size 0.508)
		(drill 0.254)
		(layers "F.Cu" "B.Cu")
		(net "GND")
	)
	(via
		(at 129.215642 -71.303134)
		(size 0.508)
		(drill 0.254)
		(layers "F.Cu" "B.Cu")
		(net "GND")
	)
	(via
		(at 407.180288 -5.597398)
		(size 0.508)
		(drill 0.254)
		(layers "F.Cu" "B.Cu")
		(net "GND")
	)
	(via
		(at 121.004838 -267.606272)
		(size 0.4064)
		(drill 0.2032)
		(layers "F.Cu" "B.Cu")
		(net "GND")
	)
	(via
		(at 70.37197 -183.552846)
		(size 0.508)
		(drill 0.254)
		(layers "F.Cu" "B.Cu")
		(net "GND")
	)
	(via
		(at 36.795964 -251.735336)
		(size 0.4826)
		(drill 0.254)
		(layers "F.Cu" "B.Cu")
		(net "GND")
	)
	(via
		(at 46.494954 -391.77595)
		(size 0.4064)
		(drill 0.2032)
		(layers "F.Cu" "B.Cu")
		(net "GND")
	)
	(via
		(at 183.616092 -241.535204)
		(size 0.4826)
		(drill 0.254)
		(layers "F.Cu" "B.Cu")
		(net "GND")
	)
	(via
		(at 349.544894 -420.318184)
		(size 0.4572)
		(drill 0.254)
		(layers "F.Cu" "B.Cu")
		(net "GND")
	)
	(via
		(at 325.038974 -421.586152)
		(size 0.4572)
		(drill 0.254)
		(layers "F.Cu" "B.Cu")
		(net "GND")
	)
	(via
		(at 67.07759 -340.15045)
		(size 0.508)
		(drill 0.254)
		(layers "F.Cu" "B.Cu")
		(net "GND")
	)
	(via
		(at 307.118258 -396.710662)
		(size 0.4064)
		(drill 0.2032)
		(layers "F.Cu" "B.Cu")
		(net "GND")
	)
	(via
		(at 280.635964 -199.035162)
		(size 0.4826)
		(drill 0.254)
		(layers "F.Cu" "B.Cu")
		(net "GND")
	)
	(via
		(at 167.509444 -369.03533)
		(size 0.508)
		(drill 0.254)
		(layers "F.Cu" "B.Cu")
		(net "GND")
	)
	(via
		(at 211.266024 -228.934772)
		(size 0.4826)
		(drill 0.254)
		(layers "F.Cu" "B.Cu")
		(net "GND")
	)
	(via
		(at 78.228952 -405.098504)
		(size 0.4572)
		(drill 0.254)
		(layers "F.Cu" "B.Cu")
		(net "GND")
	)
	(via
		(at 399.79727 -419.046152)
		(size 0.4572)
		(drill 0.254)
		(layers "F.Cu" "B.Cu")
		(net "GND")
	)
	(via
		(at 35.411664 -302.735234)
		(size 0.4826)
		(drill 0.254)
		(layers "F.Cu" "B.Cu")
		(net "GND")
	)
	(via
		(at 2.76225 -188.397134)
		(size 0.508)
		(drill 0.254)
		(layers "F.Cu" "B.Cu")
		(net "GND")
	)
	(via
		(at 341.918798 -398.542002)
		(size 0.4064)
		(drill 0.2032)
		(layers "F.Cu" "B.Cu")
		(net "GND")
	)
	(via
		(at 404.206202 -394.831062)
		(size 0.4064)
		(drill 0.2032)
		(layers "F.Cu" "B.Cu")
		(net "GND")
	)
	(via
		(at 328.877168 -333.822802)
		(size 0.49022)
		(drill 0.254)
		(layers "F.Cu" "B.Cu")
		(net "GND")
	)
	(via
		(at 171.478448 -375.818908)
		(size 0.508)
		(drill 0.254)
		(layers "F.Cu" "B.Cu")
		(net "GND")
	)
	(via
		(at 355.961188 -241.24412)
		(size 0.4064)
		(drill 0.2032)
		(layers "F.Cu" "B.Cu")
		(net "GND")
	)
	(via
		(at 446.107566 -378.05487)
		(size 0.508)
		(drill 0.254)
		(layers "F.Cu" "B.Cu")
		(net "GND")
	)
	(via
		(at 194.604132 -217.735404)
		(size 0.4826)
		(drill 0.254)
		(layers "F.Cu" "B.Cu")
		(net "GND")
	)
	(via
		(at 53.816504 -382.85293)
		(size 0.4064)
		(drill 0.2032)
		(layers "F.Cu" "B.Cu")
		(net "GND")
	)
	(via
		(at 353.585272 -423.648378)
		(size 0.508)
		(drill 0.254)
		(layers "F.Cu" "B.Cu")
		(net "GND")
	)
	(via
		(at 370.82476 -270.846042)
		(size 0.4064)
		(drill 0.2032)
		(layers "F.Cu" "B.Cu")
		(net "GND")
	)
	(via
		(at 428.245016 -19.13636)
		(size 0.508)
		(drill 0.254)
		(layers "F.Cu" "B.Cu")
		(net "GND")
	)
	(via
		(at 245.999 -330.2)
		(size 0.508)
		(drill 0.254)
		(layers "F.Cu" "B.Cu")
		(net "GND")
	)
	(via
		(at 91.571064 -246.914416)
		(size 0.4064)
		(drill 0.2032)
		(layers "F.Cu" "B.Cu")
		(net "GND")
	)
	(via
		(at 416.468052 -255.135126)
		(size 0.4826)
		(drill 0.254)
		(layers "F.Cu" "B.Cu")
		(net "GND")
	)
	(via
		(at 377.691142 -398.542002)
		(size 0.4064)
		(drill 0.2032)
		(layers "F.Cu" "B.Cu")
		(net "GND")
	)
	(via
		(at 372.704868 -288.66592)
		(size 0.4064)
		(drill 0.2032)
		(layers "F.Cu" "B.Cu")
		(net "GND")
	)
	(via
		(at 36.156138 -19.771106)
		(size 0.508)
		(drill 0.254)
		(layers "F.Cu" "B.Cu")
		(net "GND")
	)
	(via
		(at 333.955898 -417.778184)
		(size 0.4572)
		(drill 0.254)
		(layers "F.Cu" "B.Cu")
		(net "GND")
	)
	(via
		(at 295.724072 -233.035094)
		(size 0.4826)
		(drill 0.254)
		(layers "F.Cu" "B.Cu")
		(net "GND")
	)
	(via
		(at 383.514854 -278.136096)
		(size 0.4064)
		(drill 0.2032)
		(layers "F.Cu" "B.Cu")
		(net "GND")
	)
	(via
		(at 252.299724 -44.438062)
		(size 0.508)
		(drill 0.254)
		(layers "F.Cu" "B.Cu")
		(net "GND")
	)
	(via
		(at 353.141026 -233.14406)
		(size 0.4064)
		(drill 0.2032)
		(layers "F.Cu" "B.Cu")
		(net "GND")
	)
	(via
		(at 305.983894 -221.13494)
		(size 0.4826)
		(drill 0.254)
		(layers "F.Cu" "B.Cu")
		(net "GND")
	)
	(via
		(at 328.061066 -276.516084)
		(size 0.4064)
		(drill 0.2032)
		(layers "F.Cu" "B.Cu")
		(net "GND")
	)
	(via
		(at 118.34495 -124.44095)
		(size 0.508)
		(drill 0.254)
		(layers "F.Cu" "B.Cu")
		(net "GND")
	)
	(via
		(at 101.91115 -237.194344)
		(size 0.4064)
		(drill 0.2032)
		(layers "F.Cu" "B.Cu")
		(net "GND")
	)
	(via
		(at 41.62425 -231.335326)
		(size 0.4826)
		(drill 0.254)
		(layers "F.Cu" "B.Cu")
		(net "GND")
	)
	(via
		(at 96.27108 -253.394464)
		(size 0.4064)
		(drill 0.2032)
		(layers "F.Cu" "B.Cu")
		(net "GND")
	)
	(via
		(at 82.319114 -390.160002)
		(size 0.4064)
		(drill 0.2032)
		(layers "F.Cu" "B.Cu")
		(net "GND")
	)
	(via
		(at 111.165894 -383.7432)
		(size 0.508)
		(drill 0.254)
		(layers "F.Cu" "B.Cu")
		(net "GND")
	)
	(via
		(at 338.016342 -135.071104)
		(size 0.508)
		(drill 0.254)
		(layers "F.Cu" "B.Cu")
		(net "GND")
	)
	(via
		(at 334.64119 -281.37612)
		(size 0.4064)
		(drill 0.2032)
		(layers "F.Cu" "B.Cu")
		(net "GND")
	)
	(via
		(at 113.48466 -287.046162)
		(size 0.4064)
		(drill 0.2032)
		(layers "F.Cu" "B.Cu")
		(net "GND")
	)
	(via
		(at 253.361952 -94.052898)
		(size 0.508)
		(drill 0.254)
		(layers "F.Cu" "B.Cu")
		(net "GND")
	)
	(via
		(at 155.777438 -405.098504)
		(size 0.4572)
		(drill 0.254)
		(layers "F.Cu" "B.Cu")
		(net "GND")
	)
	(via
		(at 310.09717 -358.791256)
		(size 0.508)
		(drill 0.254)
		(layers "F.Cu" "B.Cu")
		(net "GND")
	)
	(via
		(at 112.808512 -407.4668)
		(size 0.508)
		(drill 0.254)
		(layers "F.Cu" "B.Cu")
		(net "GND")
	)
	(via
		(at 96.335596 -406.370536)
		(size 0.4572)
		(drill 0.254)
		(layers "F.Cu" "B.Cu")
		(net "GND")
	)
	(via
		(at 444.391034 -64.850518)
		(size 0.508)
		(drill 0.254)
		(layers "F.Cu" "B.Cu")
		(net "GND")
	)
	(via
		(at 416.372294 -416.020504)
		(size 0.4572)
		(drill 0.254)
		(layers "F.Cu" "B.Cu")
		(net "GND")
	)
	(via
		(at 431.55616 -291.684964)
		(size 0.4826)
		(drill 0.254)
		(layers "F.Cu" "B.Cu")
		(net "GND")
	)
	(via
		(at 34.556192 -423.380154)
		(size 0.508)
		(drill 0.254)
		(layers "F.Cu" "B.Cu")
		(net "GND")
	)
	(via
		(at 370.335302 -412.84652)
		(size 0.4064)
		(drill 0.2032)
		(layers "F.Cu" "B.Cu")
		(net "GND")
	)
	(via
		(at 301.73295 -359.918)
		(size 0.508)
		(drill 0.254)
		(layers "F.Cu" "B.Cu")
		(net "GND")
	)
	(via
		(at 326.351138 -248.534174)
		(size 0.4064)
		(drill 0.2032)
		(layers "F.Cu" "B.Cu")
		(net "GND")
	)
	(via
		(at 143.264636 -243.674392)
		(size 0.4064)
		(drill 0.2032)
		(layers "F.Cu" "B.Cu")
		(net "GND")
	)
	(via
		(at 393.384786 -287.045908)
		(size 0.4064)
		(drill 0.2032)
		(layers "F.Cu" "B.Cu")
		(net "GND")
	)
	(via
		(at 315.849254 -421.586152)
		(size 0.4572)
		(drill 0.254)
		(layers "F.Cu" "B.Cu")
		(net "GND")
	)
	(via
		(at 109.900974 -223.424496)
		(size 0.4064)
		(drill 0.2032)
		(layers "F.Cu" "B.Cu")
		(net "GND")
	)
	(via
		(at 134.349744 -432.747166)
		(size 0.4572)
		(drill 0.2032)
		(layers "F.Cu" "B.Cu")
		(net "GND")
	)
	(via
		(at 81.632298 -331.748638)
		(size 0.508)
		(drill 0.254)
		(layers "F.Cu" "B.Cu")
		(net "GND")
	)
	(via
		(at 313.26963 -76.239878)
		(size 0.508)
		(drill 0.254)
		(layers "F.Cu" "B.Cu")
		(net "GND")
	)
	(via
		(at 384.349498 -430.147222)
		(size 0.4572)
		(drill 0.2032)
		(layers "F.Cu" "B.Cu")
		(net "GND")
	)
	(via
		(at 165.44417 -382.85293)
		(size 0.4064)
		(drill 0.2032)
		(layers "F.Cu" "B.Cu")
		(net "GND")
	)
	(via
		(at 47.596552 -411.936184)
		(size 0.4572)
		(drill 0.254)
		(layers "F.Cu" "B.Cu")
		(net "GND")
	)
	(via
		(at 47.417228 -341.525352)
		(size 0.6604)
		(drill 0.3302)
		(layers "F.Cu" "B.Cu")
		(net "GND")
	)
	(via
		(at 230.926894 -51.565048)
		(size 0.508)
		(drill 0.254)
		(layers "F.Cu" "B.Cu")
		(net "GND")
	)
	(via
		(at 113.65484 -241.244374)
		(size 0.4064)
		(drill 0.2032)
		(layers "F.Cu" "B.Cu")
		(net "GND")
	)
	(via
		(at 136.684766 -240.434368)
		(size 0.4064)
		(drill 0.2032)
		(layers "F.Cu" "B.Cu")
		(net "GND")
	)
	(via
		(at 344.950034 -416.020504)
		(size 0.4572)
		(drill 0.254)
		(layers "F.Cu" "B.Cu")
		(net "GND")
	)
	(via
		(at 350.087184 -383.00533)
		(size 0.508)
		(drill 0.254)
		(layers "F.Cu" "B.Cu")
		(net "GND")
	)
	(via
		(at 358.61117 -274.086066)
		(size 0.4064)
		(drill 0.2032)
		(layers "F.Cu" "B.Cu")
		(net "GND")
	)
	(via
		(at 388.68477 -275.706078)
		(size 0.4064)
		(drill 0.2032)
		(layers "F.Cu" "B.Cu")
		(net "GND")
	)
	(via
		(at 264.184638 -134.495032)
		(size 0.508)
		(drill 0.254)
		(layers "F.Cu" "B.Cu")
		(net "GND")
	)
	(via
		(at 431.568098 -331.12329)
		(size 0.508)
		(drill 0.254)
		(layers "F.Cu" "B.Cu")
		(net "GND")
	)
	(via
		(at 390.264904 -250.154186)
		(size 0.4064)
		(drill 0.2032)
		(layers "F.Cu" "B.Cu")
		(net "GND")
	)
	(via
		(at 121.474738 -289.47618)
		(size 0.4064)
		(drill 0.2032)
		(layers "F.Cu" "B.Cu")
		(net "GND")
	)
	(via
		(at 419.819074 -398.542002)
		(size 0.4064)
		(drill 0.2032)
		(layers "F.Cu" "B.Cu")
		(net "GND")
	)
	(via
		(at 92.013532 -409.396184)
		(size 0.4572)
		(drill 0.254)
		(layers "F.Cu" "B.Cu")
		(net "GND")
	)
	(via
		(at 401.004278 -178.04511)
		(size 0.49022)
		(drill 0.254)
		(layers "F.Cu" "B.Cu")
		(net "GND")
	)
	(via
		(at 416.644328 -402.309838)
		(size 0.4572)
		(drill 0.254)
		(layers "F.Cu" "B.Cu")
		(net "GND")
	)
	(via
		(at 265.54811 -279.785064)
		(size 0.4826)
		(drill 0.254)
		(layers "F.Cu" "B.Cu")
		(net "GND")
	)
	(via
		(at 369.114832 -233.14406)
		(size 0.4064)
		(drill 0.2032)
		(layers "F.Cu" "B.Cu")
		(net "GND")
	)
	(via
		(at 139.825222 -148.312124)
		(size 0.6604)
		(drill 0.3302)
		(layers "F.Cu" "B.Cu")
		(net "GND")
	)
	(via
		(at 391.674858 -247.724168)
		(size 0.4064)
		(drill 0.2032)
		(layers "F.Cu" "B.Cu")
		(net "GND")
	)
	(via
		(at 83.88096 -281.376374)
		(size 0.4064)
		(drill 0.2032)
		(layers "F.Cu" "B.Cu")
		(net "GND")
	)
	(via
		(at 92.383102 -369.03533)
		(size 0.508)
		(drill 0.254)
		(layers "F.Cu" "B.Cu")
		(net "GND")
	)
	(via
		(at 54.896004 -407.00452)
		(size 0.4064)
		(drill 0.2032)
		(layers "F.Cu" "B.Cu")
		(net "GND")
	)
	(via
		(at 76.718668 -388.297674)
		(size 0.508)
		(drill 0.254)
		(layers "F.Cu" "B.Cu")
		(net "GND")
	)
	(via
		(at 102.681024 -270.03629)
		(size 0.4064)
		(drill 0.2032)
		(layers "F.Cu" "B.Cu")
		(net "GND")
	)
	(via
		(at 113.989104 -411.420564)
		(size 0.508)
		(drill 0.254)
		(layers "F.Cu" "B.Cu")
		(net "GND")
	)
	(via
		(at 346.39123 -293.525956)
		(size 0.4064)
		(drill 0.2032)
		(layers "F.Cu" "B.Cu")
		(net "GND")
	)
	(via
		(at 16.490442 -295.510458)
		(size 0.4826)
		(drill 0.254)
		(layers "F.Cu" "B.Cu")
		(net "GND")
	)
	(via
		(at 285.637986 -344.781124)
		(size 0.49022)
		(drill 0.254)
		(layers "F.Cu" "B.Cu")
		(net "GND")
	)
	(via
		(at 348.271084 -274.086066)
		(size 0.4064)
		(drill 0.2032)
		(layers "F.Cu" "B.Cu")
		(net "GND")
	)
	(via
		(at 40.954706 -414.322514)
		(size 0.4572)
		(drill 0.254)
		(layers "F.Cu" "B.Cu")
		(net "GND")
	)
	(via
		(at 67.249802 -427.851316)
		(size 0.4572)
		(drill 0.2032)
		(layers "F.Cu" "B.Cu")
		(net "GND")
	)
	(via
		(at 75.251564 -407.00452)
		(size 0.4064)
		(drill 0.2032)
		(layers "F.Cu" "B.Cu")
		(net "GND")
	)
	(via
		(at 394.84808 -9.424924)
		(size 0.508)
		(drill 0.254)
		(layers "F.Cu" "B.Cu")
		(net "GND")
	)
	(via
		(at 378.814838 -291.095938)
		(size 0.4064)
		(drill 0.2032)
		(layers "F.Cu" "B.Cu")
		(net "GND")
	)
	(via
		(at 144.034764 -281.376374)
		(size 0.4064)
		(drill 0.2032)
		(layers "F.Cu" "B.Cu")
		(net "GND")
	)
	(via
		(at 59.347862 -41.166796)
		(size 0.508)
		(drill 0.254)
		(layers "F.Cu" "B.Cu")
		(net "GND")
	)
	(via
		(at 375.224802 -227.474272)
		(size 0.4064)
		(drill 0.2032)
		(layers "F.Cu" "B.Cu")
		(net "GND")
	)
	(via
		(at 189.28461 -350.17075)
		(size 0.49022)
		(drill 0.254)
		(layers "F.Cu" "B.Cu")
		(net "GND")
	)
	(via
		(at 168.527984 -301.035212)
		(size 0.4826)
		(drill 0.254)
		(layers "F.Cu" "B.Cu")
		(net "GND")
	)
	(via
		(at 84.99094 -246.914416)
		(size 0.4064)
		(drill 0.2032)
		(layers "F.Cu" "B.Cu")
		(net "GND")
	)
	(via
		(at 331.051154 -248.534174)
		(size 0.4064)
		(drill 0.2032)
		(layers "F.Cu" "B.Cu")
		(net "GND")
	)
	(via
		(at 170.625262 -101.075744)
		(size 0.508)
		(drill 0.254)
		(layers "F.Cu" "B.Cu")
		(net "GND")
	)
	(via
		(at 358.311196 -246.914162)
		(size 0.4064)
		(drill 0.2032)
		(layers "F.Cu" "B.Cu")
		(net "GND")
	)
	(via
		(at 187.060078 -298.485306)
		(size 0.4826)
		(drill 0.254)
		(layers "F.Cu" "B.Cu")
		(net "GND")
	)
	(via
		(at 300.99 -356.997)
		(size 0.508)
		(drill 0.254)
		(layers "F.Cu" "B.Cu")
		(net "GND")
	)
	(via
		(at 439.378344 -14.484096)
		(size 0.508)
		(drill 0.254)
		(layers "F.Cu" "B.Cu")
		(net "GND")
	)
	(via
		(at 56.712358 -294.235378)
		(size 0.4826)
		(drill 0.254)
		(layers "F.Cu" "B.Cu")
		(net "GND")
	)
	(via
		(at 163.946332 -388.328662)
		(size 0.4064)
		(drill 0.2032)
		(layers "F.Cu" "B.Cu")
		(net "GND")
	)
	(via
		(at 128.694688 -229.90429)
		(size 0.4064)
		(drill 0.2032)
		(layers "F.Cu" "B.Cu")
		(net "GND")
	)
	(via
		(at 304.855118 -412.212536)
		(size 0.4572)
		(drill 0.254)
		(layers "F.Cu" "B.Cu")
		(net "GND")
	)
	(via
		(at 341.613998 -413.480504)
		(size 0.4572)
		(drill 0.254)
		(layers "F.Cu" "B.Cu")
		(net "GND")
	)
	(via
		(at 426.234352 -4.32943)
		(size 0.508)
		(drill 0.254)
		(layers "F.Cu" "B.Cu")
		(net "GND")
	)
	(via
		(at 96.101154 -268.416278)
		(size 0.4064)
		(drill 0.2032)
		(layers "F.Cu" "B.Cu")
		(net "GND")
	)
	(via
		(at 418.595302 -439.123836)
		(size 0.508)
		(drill 0.254)
		(layers "F.Cu" "B.Cu")
		(net "GND")
	)
	(via
		(at 156.597858 -353.245928)
		(size 0.508)
		(drill 0.254)
		(layers "F.Cu" "B.Cu")
		(net "GND")
	)
	(via
		(at 332.71841 -396.679674)
		(size 0.508)
		(drill 0.254)
		(layers "F.Cu" "B.Cu")
		(net "GND")
	)
	(via
		(at 59.370214 -368.37493)
		(size 0.508)
		(drill 0.254)
		(layers "F.Cu" "B.Cu")
		(net "GND")
	)
	(via
		(at 17.608042 -206.685388)
		(size 0.4826)
		(drill 0.254)
		(layers "F.Cu" "B.Cu")
		(net "GND")
	)
	(via
		(at 91.571064 -248.534428)
		(size 0.4064)
		(drill 0.2032)
		(layers "F.Cu" "B.Cu")
		(net "GND")
	)
	(via
		(at 95.506286 -386.449062)
		(size 0.4064)
		(drill 0.2032)
		(layers "F.Cu" "B.Cu")
		(net "GND")
	)
	(via
		(at 146.455384 -441.227718)
		(size 0.508)
		(drill 0.254)
		(layers "F.Cu" "B.Cu")
		(net "GND")
	)
	(via
		(at 162.176714 -410.664152)
		(size 0.4572)
		(drill 0.254)
		(layers "F.Cu" "B.Cu")
		(net "GND")
	)
	(via
		(at 98.40976 -133.389116)
		(size 0.508)
		(drill 0.254)
		(layers "F.Cu" "B.Cu")
		(net "GND")
	)
	(via
		(at 396.905734 -398.719294)
		(size 0.508)
		(drill 0.254)
		(layers "F.Cu" "B.Cu")
		(net "GND")
	)
	(via
		(at 297.108372 -312.935112)
		(size 0.4826)
		(drill 0.254)
		(layers "F.Cu" "B.Cu")
		(net "GND")
	)
	(via
		(at 15.209774 -386.914898)
		(size 0.49022)
		(drill 0.254)
		(layers "F.Cu" "B.Cu")
		(net "GND")
	)
	(via
		(at 176.6316 -428.215298)
		(size 0.508)
		(drill 0.254)
		(layers "F.Cu" "B.Cu")
		(net "GND")
	)
	(via
		(at 108.321094 -279.756362)
		(size 0.4064)
		(drill 0.2032)
		(layers "F.Cu" "B.Cu")
		(net "GND")
	)
	(via
		(at 306.118006 -336.293968)
		(size 0.508)
		(drill 0.254)
		(layers "F.Cu" "B.Cu")
		(net "GND")
	)
	(via
		(at 77.069442 -369.69573)
		(size 0.508)
		(drill 0.254)
		(layers "F.Cu" "B.Cu")
		(net "GND")
	)
	(via
		(at 349.681038 -265.176)
		(size 0.4064)
		(drill 0.2032)
		(layers "F.Cu" "B.Cu")
		(net "GND")
	)
	(via
		(at 125.145038 -413.204152)
		(size 0.4572)
		(drill 0.254)
		(layers "F.Cu" "B.Cu")
		(net "GND")
	)
	(via
		(at 157.298644 -369.03533)
		(size 0.508)
		(drill 0.254)
		(layers "F.Cu" "B.Cu")
		(net "GND")
	)
	(via
		(at 131.98475 -243.674392)
		(size 0.4064)
		(drill 0.2032)
		(layers "F.Cu" "B.Cu")
		(net "GND")
	)
	(via
		(at 394.982954 -276.250146)
		(size 0.4064)
		(drill 0.2032)
		(layers "F.Cu" "B.Cu")
		(net "GND")
	)
	(via
		(at 189.775846 -221.135194)
		(size 0.4826)
		(drill 0.254)
		(layers "F.Cu" "B.Cu")
		(net "GND")
	)
	(via
		(at 105.031032 -290.286186)
		(size 0.4064)
		(drill 0.2032)
		(layers "F.Cu" "B.Cu")
		(net "GND")
	)
	(via
		(at 170.18 -116.292376)
		(size 0.508)
		(drill 0.254)
		(layers "F.Cu" "B.Cu")
		(net "GND")
	)
	(via
		(at 183.132222 -112.66297)
		(size 0.4572)
		(drill 0.254)
		(layers "F.Cu" "B.Cu")
		(net "GND")
	)
	(via
		(at 418.594794 -6.598158)
		(size 0.508)
		(drill 0.254)
		(layers "F.Cu" "B.Cu")
		(net "GND")
	)
	(via
		(at 102.023164 -426.19295)
		(size 0.508)
		(drill 0.254)
		(layers "F.Cu" "B.Cu")
		(net "GND")
	)
	(via
		(at 107.189778 -404.45182)
		(size 0.508)
		(drill 0.254)
		(layers "F.Cu" "B.Cu")
		(net "GND")
	)
	(via
		(at 58.043826 -293.38524)
		(size 0.4826)
		(drill 0.254)
		(layers "F.Cu" "B.Cu")
		(net "GND")
	)
	(via
		(at 132.349748 -432.451256)
		(size 0.4572)
		(drill 0.2032)
		(layers "F.Cu" "B.Cu")
		(net "GND")
	)
	(via
		(at 303.268126 -290.83508)
		(size 0.4826)
		(drill 0.254)
		(layers "F.Cu" "B.Cu")
		(net "GND")
	)
	(via
		(at 55.328058 -307.8353)
		(size 0.4826)
		(drill 0.254)
		(layers "F.Cu" "B.Cu")
		(net "GND")
	)
	(via
		(at 413.58185 -421.586152)
		(size 0.4572)
		(drill 0.254)
		(layers "F.Cu" "B.Cu")
		(net "GND")
	)
	(via
		(at 351.076514 -417.778184)
		(size 0.4572)
		(drill 0.254)
		(layers "F.Cu" "B.Cu")
		(net "GND")
	)
	(via
		(at 32.128714 -342.816434)
		(size 0.508)
		(drill 0.254)
		(layers "F.Cu" "B.Cu")
		(net "GND")
	)
	(via
		(at 62.11951 -172.833284)
		(size 0.508)
		(drill 0.254)
		(layers "F.Cu" "B.Cu")
		(net "GND")
	)
	(via
		(at 339.511132 -255.014222)
		(size 0.4064)
		(drill 0.2032)
		(layers "F.Cu" "B.Cu")
		(net "GND")
	)
	(via
		(at 371.93474 -233.14406)
		(size 0.4064)
		(drill 0.2032)
		(layers "F.Cu" "B.Cu")
		(net "GND")
	)
	(via
		(at 65.149984 -7.20471)
		(size 0.508)
		(drill 0.254)
		(layers "F.Cu" "B.Cu")
		(net "GND")
	)
	(via
		(at 107.574334 -333.240126)
		(size 0.508)
		(drill 0.254)
		(layers "F.Cu" "B.Cu")
		(net "GND")
	)
	(via
		(at 459.531466 -410.6037)
		(size 0.508)
		(drill 0.254)
		(layers "F.Cu" "B.Cu")
		(net "GND")
	)
	(via
		(at 102.096062 -350.645476)
		(size 0.508)
		(drill 0.254)
		(layers "F.Cu" "B.Cu")
		(net "GND")
	)
	(via
		(at 393.084812 -224.234248)
		(size 0.4064)
		(drill 0.2032)
		(layers "F.Cu" "B.Cu")
		(net "GND")
	)
	(via
		(at 452.980552 -375.455434)
		(size 0.6604)
		(drill 0.3302)
		(layers "F.Cu" "B.Cu")
		(net "GND")
	)
	(via
		(at 16.490442 -211.360258)
		(size 0.4826)
		(drill 0.254)
		(layers "F.Cu" "B.Cu")
		(net "GND")
	)
	(via
		(at 136.684766 -253.394464)
		(size 0.4064)
		(drill 0.2032)
		(layers "F.Cu" "B.Cu")
		(net "GND")
	)
	(via
		(at 338.401152 -274.896072)
		(size 0.4064)
		(drill 0.2032)
		(layers "F.Cu" "B.Cu")
		(net "GND")
	)
	(via
		(at 187.060078 -301.88535)
		(size 0.4826)
		(drill 0.254)
		(layers "F.Cu" "B.Cu")
		(net "GND")
	)
	(via
		(at 294.606472 -230.060246)
		(size 0.4826)
		(drill 0.254)
		(layers "F.Cu" "B.Cu")
		(net "GND")
	)
	(via
		(at 171.370498 -386.010404)
		(size 0.508)
		(drill 0.254)
		(layers "F.Cu" "B.Cu")
		(net "GND")
	)
	(via
		(at 295.724072 -307.835046)
		(size 0.4826)
		(drill 0.254)
		(layers "F.Cu" "B.Cu")
		(net "GND")
	)
	(via
		(at 427.768258 -9.424924)
		(size 0.508)
		(drill 0.254)
		(layers "F.Cu" "B.Cu")
		(net "GND")
	)
	(via
		(at 386.349494 -426.69968)
		(size 0.4572)
		(drill 0.2032)
		(layers "F.Cu" "B.Cu")
		(net "GND")
	)
	(via
		(at 273.092164 -279.785064)
		(size 0.4826)
		(drill 0.254)
		(layers "F.Cu" "B.Cu")
		(net "GND")
	)
	(via
		(at 444.255652 -397.811244)
		(size 0.49022)
		(drill 0.254)
		(layers "F.Cu" "B.Cu")
		(net "GND")
	)
	(via
		(at 294.18407 -345.550998)
		(size 0.49022)
		(drill 0.254)
		(layers "F.Cu" "B.Cu")
		(net "GND")
	)
	(via
		(at 337.930998 -282.186126)
		(size 0.4064)
		(drill 0.2032)
		(layers "F.Cu" "B.Cu")
		(net "GND")
	)
	(via
		(at 182.231792 -221.135194)
		(size 0.4826)
		(drill 0.254)
		(layers "F.Cu" "B.Cu")
		(net "GND")
	)
	(via
		(at 419.74135 -36.007548)
		(size 0.508)
		(drill 0.254)
		(layers "F.Cu" "B.Cu")
		(net "GND")
	)
	(via
		(at 304.803048 -47.037498)
		(size 0.508)
		(drill 0.254)
		(layers "F.Cu" "B.Cu")
		(net "GND")
	)
	(via
		(at 326.821038 -221.80423)
		(size 0.4064)
		(drill 0.2032)
		(layers "F.Cu" "B.Cu")
		(net "GND")
	)
	(via
		(at 454.179178 -396.09522)
		(size 0.49022)
		(drill 0.254)
		(layers "F.Cu" "B.Cu")
		(net "GND")
	)
	(via
		(at 183.535574 -12.492228)
		(size 0.508)
		(drill 0.254)
		(layers "F.Cu" "B.Cu")
		(net "GND")
	)
	(via
		(at 58.616596 -393.927838)
		(size 0.4572)
		(drill 0.254)
		(layers "F.Cu" "B.Cu")
		(net "GND")
	)
	(via
		(at 306.250594 -304.01006)
		(size 0.4826)
		(drill 0.254)
		(layers "F.Cu" "B.Cu")
		(net "GND")
	)
	(via
		(at 335.11109 -288.66592)
		(size 0.4064)
		(drill 0.2032)
		(layers "F.Cu" "B.Cu")
		(net "GND")
	)
	(via
		(at 58.043826 -295.9354)
		(size 0.4826)
		(drill 0.254)
		(layers "F.Cu" "B.Cu")
		(net "GND")
	)
	(via
		(at 119.12473 -272.466308)
		(size 0.4064)
		(drill 0.2032)
		(layers "F.Cu" "B.Cu")
		(net "GND")
	)
	(via
		(at 368.944906 -270.846042)
		(size 0.4064)
		(drill 0.2032)
		(layers "F.Cu" "B.Cu")
		(net "GND")
	)
	(via
		(at 378.250958 -204.085952)
		(size 0.508)
		(drill 0.254)
		(layers "F.Cu" "B.Cu")
		(net "GND")
	)
	(via
		(at 357.841042 -229.904036)
		(size 0.4064)
		(drill 0.2032)
		(layers "F.Cu" "B.Cu")
		(net "GND")
	)
	(via
		(at 69.039232 -403.830536)
		(size 0.4572)
		(drill 0.254)
		(layers "F.Cu" "B.Cu")
		(net "GND")
	)
	(via
		(at 371.93474 -231.524048)
		(size 0.4064)
		(drill 0.2032)
		(layers "F.Cu" "B.Cu")
		(net "GND")
	)
	(via
		(at 88.24976 -429.147224)
		(size 0.4572)
		(drill 0.2032)
		(layers "F.Cu" "B.Cu")
		(net "GND")
	)
	(via
		(at 28.134564 -201.16038)
		(size 0.4826)
		(drill 0.254)
		(layers "F.Cu" "B.Cu")
		(net "GND")
	)
	(via
		(at 375.018554 -421.586152)
		(size 0.4572)
		(drill 0.254)
		(layers "F.Cu" "B.Cu")
		(net "GND")
	)
	(via
		(at 369.114832 -226.664266)
		(size 0.4064)
		(drill 0.2032)
		(layers "F.Cu" "B.Cu")
		(net "GND")
	)
	(via
		(at 386.358892 -382.34493)
		(size 0.508)
		(drill 0.254)
		(layers "F.Cu" "B.Cu")
		(net "GND")
	)
	(via
		(at 137.154412 -255.824736)
		(size 0.4064)
		(drill 0.2032)
		(layers "F.Cu" "B.Cu")
		(net "GND")
	)
	(via
		(at 273.092164 -247.485154)
		(size 0.4826)
		(drill 0.254)
		(layers "F.Cu" "B.Cu")
		(net "GND")
	)
	(via
		(at 105.031032 -293.52621)
		(size 0.4064)
		(drill 0.2032)
		(layers "F.Cu" "B.Cu")
		(net "GND")
	)
	(via
		(at 345.51874 -398.542002)
		(size 0.4064)
		(drill 0.2032)
		(layers "F.Cu" "B.Cu")
		(net "GND")
	)
	(via
		(at 378.514864 -226.664266)
		(size 0.4064)
		(drill 0.2032)
		(layers "F.Cu" "B.Cu")
		(net "GND")
	)
	(via
		(at 338.401152 -291.095938)
		(size 0.4064)
		(drill 0.2032)
		(layers "F.Cu" "B.Cu")
		(net "GND")
	)
	(via
		(at 387.291326 -398.542002)
		(size 0.4064)
		(drill 0.2032)
		(layers "F.Cu" "B.Cu")
		(net "GND")
	)
	(via
		(at 365.939832 -380.54153)
		(size 0.508)
		(drill 0.254)
		(layers "F.Cu" "B.Cu")
		(net "GND")
	)
	(via
		(at 319.261236 -380.54153)
		(size 0.508)
		(drill 0.254)
		(layers "F.Cu" "B.Cu")
		(net "GND")
	)
	(via
		(at 82.249772 -437.34736)
		(size 0.4572)
		(drill 0.2032)
		(layers "F.Cu" "B.Cu")
		(net "GND")
	)
	(via
		(at 85.290914 -283.806392)
		(size 0.4064)
		(drill 0.2032)
		(layers "F.Cu" "B.Cu")
		(net "GND")
	)
	(via
		(at 78.711044 -275.706332)
		(size 0.4064)
		(drill 0.2032)
		(layers "F.Cu" "B.Cu")
		(net "GND")
	)
	(via
		(at 101.27107 -285.426404)
		(size 0.4064)
		(drill 0.2032)
		(layers "F.Cu" "B.Cu")
		(net "GND")
	)
	(via
		(at 20.32381 -305.285394)
		(size 0.4826)
		(drill 0.254)
		(layers "F.Cu" "B.Cu")
		(net "GND")
	)
	(via
		(at 371.045232 -381.68453)
		(size 0.508)
		(drill 0.254)
		(layers "F.Cu" "B.Cu")
		(net "GND")
	)
	(via
		(at 304.855118 -421.586152)
		(size 0.4572)
		(drill 0.254)
		(layers "F.Cu" "B.Cu")
		(net "GND")
	)
	(via
		(at 119.12473 -280.566368)
		(size 0.4064)
		(drill 0.2032)
		(layers "F.Cu" "B.Cu")
		(net "GND")
	)
	(via
		(at 154.518614 -403.830536)
		(size 0.4572)
		(drill 0.254)
		(layers "F.Cu" "B.Cu")
		(net "GND")
	)
	(via
		(at 397.718788 -389.7122)
		(size 0.508)
		(drill 0.254)
		(layers "F.Cu" "B.Cu")
		(net "GND")
	)
	(via
		(at 425.129706 -304.01006)
		(size 0.4826)
		(drill 0.254)
		(layers "F.Cu" "B.Cu")
		(net "GND")
	)
	(via
		(at 58.310526 -313.360308)
		(size 0.4826)
		(drill 0.254)
		(layers "F.Cu" "B.Cu")
		(net "GND")
	)
	(via
		(at 29.252164 -265.335258)
		(size 0.4826)
		(drill 0.254)
		(layers "F.Cu" "B.Cu")
		(net "GND")
	)
	(via
		(at 350.621092 -271.656048)
		(size 0.4064)
		(drill 0.2032)
		(layers "F.Cu" "B.Cu")
		(net "GND")
	)
	(via
		(at 229.61092 -322.17868)
		(size 0.508)
		(drill 0.254)
		(layers "F.Cu" "B.Cu")
		(net "GND")
	)
	(via
		(at 412.367984 -273.835114)
		(size 0.4826)
		(drill 0.254)
		(layers "F.Cu" "B.Cu")
		(net "GND")
	)
	(via
		(at 307.368194 -196.485002)
		(size 0.4826)
		(drill 0.254)
		(layers "F.Cu" "B.Cu")
		(net "GND")
	)
	(via
		(at 369.884706 -280.566114)
		(size 0.4064)
		(drill 0.2032)
		(layers "F.Cu" "B.Cu")
		(net "GND")
	)
	(via
		(at 372.874794 -255.824228)
		(size 0.4064)
		(drill 0.2032)
		(layers "F.Cu" "B.Cu")
		(net "GND")
	)
	(via
		(at 115.067842 -253.392432)
		(size 0.4064)
		(drill 0.2032)
		(layers "F.Cu" "B.Cu")
		(net "GND")
	)
	(via
		(at 350.621092 -273.27606)
		(size 0.4064)
		(drill 0.2032)
		(layers "F.Cu" "B.Cu")
		(net "GND")
	)
	(via
		(at 311.427876 -77.524864)
		(size 0.508)
		(drill 0.254)
		(layers "F.Cu" "B.Cu")
		(net "GND")
	)
	(via
		(at 415.083752 -221.13494)
		(size 0.4826)
		(drill 0.254)
		(layers "F.Cu" "B.Cu")
		(net "GND")
	)
	(via
		(at 294.606472 -314.210192)
		(size 0.4826)
		(drill 0.254)
		(layers "F.Cu" "B.Cu")
		(net "GND")
	)
	(via
		(at 436.384446 -240.685066)
		(size 0.4826)
		(drill 0.254)
		(layers "F.Cu" "B.Cu")
		(net "GND")
	)
	(via
		(at 115.834668 -274.896326)
		(size 0.4064)
		(drill 0.2032)
		(layers "F.Cu" "B.Cu")
		(net "GND")
	)
	(via
		(at 56.712358 -284.885384)
		(size 0.4826)
		(drill 0.254)
		(layers "F.Cu" "B.Cu")
		(net "GND")
	)
	(via
		(at 199.8218 -201.16038)
		(size 0.4826)
		(drill 0.254)
		(layers "F.Cu" "B.Cu")
		(net "GND")
	)
	(via
		(at 182.231792 -312.085228)
		(size 0.4826)
		(drill 0.254)
		(layers "F.Cu" "B.Cu")
		(net "GND")
	)
	(via
		(at 445.259968 -284.034992)
		(size 0.4826)
		(drill 0.254)
		(layers "F.Cu" "B.Cu")
		(net "GND")
	)
	(via
		(at 443.9285 -200.735184)
		(size 0.4826)
		(drill 0.254)
		(layers "F.Cu" "B.Cu")
		(net "GND")
	)
	(via
		(at 381.41783 -414.752536)
		(size 0.4572)
		(drill 0.254)
		(layers "F.Cu" "B.Cu")
		(net "GND")
	)
	(via
		(at 52.616608 -391.830814)
		(size 0.4064)
		(drill 0.2032)
		(layers "F.Cu" "B.Cu")
		(net "GND")
	)
	(via
		(at 291.36721 -344.77706)
		(size 0.49022)
		(drill 0.254)
		(layers "F.Cu" "B.Cu")
		(net "GND")
	)
	(via
		(at 92.34424 -391.830814)
		(size 0.4064)
		(drill 0.2032)
		(layers "F.Cu" "B.Cu")
		(net "GND")
	)
	(via
		(at 277.192232 -308.685184)
		(size 0.4826)
		(drill 0.254)
		(layers "F.Cu" "B.Cu")
		(net "GND")
	)
	(via
		(at 387.366256 -183.922924)
		(size 0.49022)
		(drill 0.254)
		(layers "F.Cu" "B.Cu")
		(net "GND")
	)
	(via
		(at 426.51172 -348.530926)
		(size 0.508)
		(drill 0.254)
		(layers "F.Cu" "B.Cu")
		(net "GND")
	)
	(via
		(at 113.65484 -223.424496)
		(size 0.4064)
		(drill 0.2032)
		(layers "F.Cu" "B.Cu")
		(net "GND")
	)
	(via
		(at 155.349702 -429.147224)
		(size 0.4572)
		(drill 0.2032)
		(layers "F.Cu" "B.Cu")
		(net "GND")
	)
	(via
		(at 178.179984 -147.461224)
		(size 0.508)
		(drill 0.254)
		(layers "F.Cu" "B.Cu")
		(net "GND")
	)
	(via
		(at 361.894882 -284.616144)
		(size 0.4064)
		(drill 0.2032)
		(layers "F.Cu" "B.Cu")
		(net "GND")
	)
	(via
		(at 117.247924 -264.36828)
		(size 0.4064)
		(drill 0.2032)
		(layers "F.Cu" "B.Cu")
		(net "GND")
	)
	(via
		(at 98.705162 -368.37493)
		(size 0.508)
		(drill 0.254)
		(layers "F.Cu" "B.Cu")
		(net "GND")
	)
	(via
		(at 240.205514 -318.704468)
		(size 0.508)
		(drill 0.254)
		(layers "F.Cu" "B.Cu")
		(net "GND")
	)
	(via
		(at 138.114786 -390.368028)
		(size 0.508)
		(drill 0.254)
		(layers "F.Cu" "B.Cu")
		(net "GND")
	)
	(via
		(at 389.07593 -413.480504)
		(size 0.4572)
		(drill 0.254)
		(layers "F.Cu" "B.Cu")
		(net "GND")
	)
	(via
		(at 451.098666 -396.19047)
		(size 0.508)
		(drill 0.254)
		(layers "F.Cu" "B.Cu")
		(net "GND")
	)
	(via
		(at 210.608418 -73.168002)
		(size 0.508)
		(drill 0.254)
		(layers "F.Cu" "B.Cu")
		(net "GND")
	)
	(via
		(at 68.985384 -10.20191)
		(size 0.508)
		(drill 0.254)
		(layers "F.Cu" "B.Cu")
		(net "GND")
	)
	(via
		(at 169.865802 -12.495022)
		(size 0.508)
		(drill 0.254)
		(layers "F.Cu" "B.Cu")
		(net "GND")
	)
	(via
		(at 121.474738 -284.616398)
		(size 0.4064)
		(drill 0.2032)
		(layers "F.Cu" "B.Cu")
		(net "GND")
	)
	(via
		(at 60.662312 -384.617722)
		(size 0.4064)
		(drill 0.2032)
		(layers "F.Cu" "B.Cu")
		(net "GND")
	)
	(via
		(at 421.444166 -400.212814)
		(size 0.4064)
		(drill 0.2032)
		(layers "F.Cu" "B.Cu")
		(net "GND")
	)
	(via
		(at 145.444718 -283.806392)
		(size 0.4064)
		(drill 0.2032)
		(layers "F.Cu" "B.Cu")
		(net "GND")
	)
	(via
		(at 132.349748 -426.54728)
		(size 0.4572)
		(drill 0.2032)
		(layers "F.Cu" "B.Cu")
		(net "GND")
	)
	(via
		(at 303.268126 -197.33514)
		(size 0.4826)
		(drill 0.254)
		(layers "F.Cu" "B.Cu")
		(net "GND")
	)
	(via
		(at 320.949828 -41.668954)
		(size 0.508)
		(drill 0.254)
		(layers "F.Cu" "B.Cu")
		(net "GND")
	)
	(via
		(at 331.051154 -256.634234)
		(size 0.4064)
		(drill 0.2032)
		(layers "F.Cu" "B.Cu")
		(net "GND")
	)
	(via
		(at 269.648178 -207.535018)
		(size 0.4826)
		(drill 0.254)
		(layers "F.Cu" "B.Cu")
		(net "GND")
	)
	(via
		(at 428.655734 -356.651052)
		(size 0.508)
		(drill 0.254)
		(layers "F.Cu" "B.Cu")
		(net "GND")
	)
	(via
		(at 348.911164 -235.574078)
		(size 0.4064)
		(drill 0.2032)
		(layers "F.Cu" "B.Cu")
		(net "GND")
	)
	(via
		(at 414.840674 -412.212536)
		(size 0.4572)
		(drill 0.254)
		(layers "F.Cu" "B.Cu")
		(net "GND")
	)
	(via
		(at 435.000146 -234.735116)
		(size 0.4826)
		(drill 0.254)
		(layers "F.Cu" "B.Cu")
		(net "GND")
	)
	(via
		(at 144.169384 -369.69573)
		(size 0.508)
		(drill 0.254)
		(layers "F.Cu" "B.Cu")
		(net "GND")
	)
	(via
		(at 122.584718 -246.914416)
		(size 0.4064)
		(drill 0.2032)
		(layers "F.Cu" "B.Cu")
		(net "GND")
	)
	(via
		(at 402.501862 -415.38652)
		(size 0.4064)
		(drill 0.2032)
		(layers "F.Cu" "B.Cu")
		(net "GND")
	)
	(via
		(at 182.67553 -45.17771)
		(size 0.508)
		(drill 0.254)
		(layers "F.Cu" "B.Cu")
		(net "GND")
	)
	(via
		(at 412.720028 -6.598158)
		(size 0.508)
		(drill 0.254)
		(layers "F.Cu" "B.Cu")
		(net "GND")
	)
	(via
		(at 381.256032 -378.07773)
		(size 0.508)
		(drill 0.254)
		(layers "F.Cu" "B.Cu")
		(net "GND")
	)
	(via
		(at 61.249814 -426.54728)
		(size 0.4572)
		(drill 0.2032)
		(layers "F.Cu" "B.Cu")
		(net "GND")
	)
	(via
		(at 418.4015 -381.68453)
		(size 0.508)
		(drill 0.254)
		(layers "F.Cu" "B.Cu")
		(net "GND")
	)
	(via
		(at 26.307796 -193.107564)
		(size 0.4826)
		(drill 0.254)
		(layers "F.Cu" "B.Cu")
		(net "GND")
	)
	(via
		(at 119.12473 -287.046162)
		(size 0.4064)
		(drill 0.2032)
		(layers "F.Cu" "B.Cu")
		(net "GND")
	)
	(via
		(at 344.981022 -270.036036)
		(size 0.4064)
		(drill 0.2032)
		(layers "F.Cu" "B.Cu")
		(net "GND")
	)
	(via
		(at 331.821028 -284.616144)
		(size 0.4064)
		(drill 0.2032)
		(layers "F.Cu" "B.Cu")
		(net "GND")
	)
	(via
		(at 17.36471 -112.693958)
		(size 0.508)
		(drill 0.254)
		(layers "F.Cu" "B.Cu")
		(net "GND")
	)
	(via
		(at 339.811106 -290.285932)
		(size 0.4064)
		(drill 0.2032)
		(layers "F.Cu" "B.Cu")
		(net "GND")
	)
	(via
		(at 55.328058 -236.435392)
		(size 0.4826)
		(drill 0.254)
		(layers "F.Cu" "B.Cu")
		(net "GND")
	)
	(via
		(at 111.290862 -388.297674)
		(size 0.508)
		(drill 0.254)
		(layers "F.Cu" "B.Cu")
		(net "GND")
	)
	(via
		(at 93.183964 -412.570168)
		(size 0.4064)
		(drill 0.2032)
		(layers "F.Cu" "B.Cu")
		(net "GND")
	)
	(via
		(at 409.349702 -430.147222)
		(size 0.4572)
		(drill 0.2032)
		(layers "F.Cu" "B.Cu")
		(net "GND")
	)
	(via
		(at 445.227456 -435.961282)
		(size 0.508)
		(drill 0.254)
		(layers "F.Cu" "B.Cu")
		(net "GND")
	)
	(via
		(at 375.76125 -428.239936)
		(size 0.508)
		(drill 0.254)
		(layers "F.Cu" "B.Cu")
		(net "GND")
	)
	(via
		(at 75.922886 -179.565046)
		(size 0.49022)
		(drill 0.254)
		(layers "F.Cu" "B.Cu")
		(net "GND")
	)
	(via
		(at 412.367984 -227.085144)
		(size 0.4826)
		(drill 0.254)
		(layers "F.Cu" "B.Cu")
		(net "GND")
	)
	(via
		(at 366.594898 -274.896072)
		(size 0.4064)
		(drill 0.2032)
		(layers "F.Cu" "B.Cu")
		(net "GND")
	)
	(via
		(at 32.695896 -290.835334)
		(size 0.4826)
		(drill 0.254)
		(layers "F.Cu" "B.Cu")
		(net "GND")
	)
	(via
		(at 85.290914 -265.98626)
		(size 0.4064)
		(drill 0.2032)
		(layers "F.Cu" "B.Cu")
		(net "GND")
	)
	(via
		(at 27.650694 -388.32536)
		(size 0.49022)
		(drill 0.254)
		(layers "F.Cu" "B.Cu")
		(net "GND")
	)
	(via
		(at 243.971572 -420.67099)
		(size 0.508)
		(drill 0.254)
		(layers "F.Cu" "B.Cu")
		(net "GND")
	)
	(via
		(at 364.230666 -420.53637)
		(size 0.508)
		(drill 0.254)
		(layers "F.Cu" "B.Cu")
		(net "GND")
	)
	(via
		(at 361.894882 -281.37612)
		(size 0.4064)
		(drill 0.2032)
		(layers "F.Cu" "B.Cu")
		(net "GND")
	)
	(via
		(at 446.644268 -310.384952)
		(size 0.4826)
		(drill 0.254)
		(layers "F.Cu" "B.Cu")
		(net "GND")
	)
	(via
		(at 135.574786 -265.176254)
		(size 0.4064)
		(drill 0.2032)
		(layers "F.Cu" "B.Cu")
		(net "GND")
	)
	(via
		(at 76.581762 -372.15953)
		(size 0.508)
		(drill 0.254)
		(layers "F.Cu" "B.Cu")
		(net "GND")
	)
	(via
		(at 321.975734 -413.480504)
		(size 0.4572)
		(drill 0.254)
		(layers "F.Cu" "B.Cu")
		(net "GND")
	)
	(via
		(at 21.70811 -299.335444)
		(size 0.4826)
		(drill 0.254)
		(layers "F.Cu" "B.Cu")
		(net "GND")
	)
	(via
		(at 41.84142 -386.476494)
		(size 0.508)
		(drill 0.254)
		(layers "F.Cu" "B.Cu")
		(net "GND")
	)
	(via
		(at 405.490172 -392.999722)
		(size 0.4064)
		(drill 0.2032)
		(layers "F.Cu" "B.Cu")
		(net "GND")
	)
	(via
		(at 250.994672 -421.46093)
		(size 0.508)
		(drill 0.254)
		(layers "F.Cu" "B.Cu")
		(net "GND")
	)
	(via
		(at 278.950166 -344.132408)
		(size 0.508)
		(drill 0.254)
		(layers "F.Cu" "B.Cu")
		(net "GND")
	)
	(via
		(at 352.9711 -275.706078)
		(size 0.4064)
		(drill 0.2032)
		(layers "F.Cu" "B.Cu")
		(net "GND")
	)
	(via
		(at 165.656006 -361.004104)
		(size 0.508)
		(drill 0.254)
		(layers "F.Cu" "B.Cu")
		(net "GND")
	)
	(via
		(at 41.62425 -240.68532)
		(size 0.4826)
		(drill 0.254)
		(layers "F.Cu" "B.Cu")
		(net "GND")
	)
	(via
		(at 265.54811 -227.085144)
		(size 0.4826)
		(drill 0.254)
		(layers "F.Cu" "B.Cu")
		(net "GND")
	)
	(via
		(at 89.989914 -332.39456)
		(size 0.508)
		(drill 0.254)
		(layers "F.Cu" "B.Cu")
		(net "GND")
	)
	(via
		(at 132.68325 -155.965144)
		(size 0.49022)
		(drill 0.254)
		(layers "F.Cu" "B.Cu")
		(net "GND")
	)
	(via
		(at 204.973936 -67.475862)
		(size 0.508)
		(drill 0.254)
		(layers "F.Cu" "B.Cu")
		(net "GND")
	)
	(via
		(at 290.354258 -418.863272)
		(size 0.508)
		(drill 0.254)
		(layers "F.Cu" "B.Cu")
		(net "GND")
	)
	(via
		(at 374.284748 -232.334054)
		(size 0.4064)
		(drill 0.2032)
		(layers "F.Cu" "B.Cu")
		(net "GND")
	)
	(via
		(at 58.668158 -9.424924)
		(size 0.508)
		(drill 0.254)
		(layers "F.Cu" "B.Cu")
		(net "GND")
	)
	(via
		(at 86.249764 -437.34736)
		(size 0.4572)
		(drill 0.2032)
		(layers "F.Cu" "B.Cu")
		(net "GND")
	)
	(via
		(at 250.981972 -422.13149)
		(size 0.508)
		(drill 0.254)
		(layers "F.Cu" "B.Cu")
		(net "GND")
	)
	(via
		(at 195.988432 -287.43529)
		(size 0.4826)
		(drill 0.254)
		(layers "F.Cu" "B.Cu")
		(net "GND")
	)
	(via
		(at 217.386662 -386.412232)
		(size 0.508)
		(drill 0.254)
		(layers "F.Cu" "B.Cu")
		(net "GND")
	)
	(via
		(at 305.983894 -199.885046)
		(size 0.4826)
		(drill 0.254)
		(layers "F.Cu" "B.Cu")
		(net "GND")
	)
	(via
		(at 85.761068 -294.336216)
		(size 0.4064)
		(drill 0.2032)
		(layers "F.Cu" "B.Cu")
		(net "GND")
	)
	(via
		(at 376.916442 -391.23493)
		(size 0.4064)
		(drill 0.2032)
		(layers "F.Cu" "B.Cu")
		(net "GND")
	)
	(via
		(at 273.092164 -199.035162)
		(size 0.4826)
		(drill 0.254)
		(layers "F.Cu" "B.Cu")
		(net "GND")
	)
	(via
		(at 410.51861 -413.480504)
		(size 0.4572)
		(drill 0.254)
		(layers "F.Cu" "B.Cu")
		(net "GND")
	)
	(via
		(at 415.831274 -164.917882)
		(size 0.49022)
		(drill 0.254)
		(layers "F.Cu" "B.Cu")
		(net "GND")
	)
	(via
		(at 255.833372 -422.13149)
		(size 0.508)
		(drill 0.254)
		(layers "F.Cu" "B.Cu")
		(net "GND")
	)
	(via
		(at 65.462404 -384.617722)
		(size 0.4064)
		(drill 0.2032)
		(layers "F.Cu" "B.Cu")
		(net "GND")
	)
	(via
		(at 284.736032 -196.485002)
		(size 0.4826)
		(drill 0.254)
		(layers "F.Cu" "B.Cu")
		(net "GND")
	)
	(via
		(at 347.50121 -228.284278)
		(size 0.4064)
		(drill 0.2032)
		(layers "F.Cu" "B.Cu")
		(net "GND")
	)
	(via
		(at 334.64119 -279.756108)
		(size 0.4064)
		(drill 0.2032)
		(layers "F.Cu" "B.Cu")
		(net "GND")
	)
	(via
		(at 108.49102 -225.854514)
		(size 0.4064)
		(drill 0.2032)
		(layers "F.Cu" "B.Cu")
		(net "GND")
	)
	(via
		(at 160.372298 -406.34666)
		(size 0.4572)
		(drill 0.254)
		(layers "F.Cu" "B.Cu")
		(net "GND")
	)
	(via
		(at 337.019138 -417.778184)
		(size 0.4572)
		(drill 0.254)
		(layers "F.Cu" "B.Cu")
		(net "GND")
	)
	(via
		(at 324.762622 -397.274542)
		(size 0.508)
		(drill 0.254)
		(layers "F.Cu" "B.Cu")
		(net "GND")
	)
	(via
		(at 327.761092 -238.004096)
		(size 0.4064)
		(drill 0.2032)
		(layers "F.Cu" "B.Cu")
		(net "GND")
	)
	(via
		(at 325.052944 -273.010122)
		(size 0.4064)
		(drill 0.2032)
		(layers "F.Cu" "B.Cu")
		(net "GND")
	)
	(via
		(at 91.871038 -282.18638)
		(size 0.4064)
		(drill 0.2032)
		(layers "F.Cu" "B.Cu")
		(net "GND")
	)
	(via
		(at 334.64119 -266.796012)
		(size 0.4064)
		(drill 0.2032)
		(layers "F.Cu" "B.Cu")
		(net "GND")
	)
	(via
		(at 113.954814 -273.276314)
		(size 0.4064)
		(drill 0.2032)
		(layers "F.Cu" "B.Cu")
		(net "GND")
	)
	(via
		(at 101.74097 -268.416278)
		(size 0.4064)
		(drill 0.2032)
		(layers "F.Cu" "B.Cu")
		(net "GND")
	)
	(via
		(at 145.144744 -246.914416)
		(size 0.4064)
		(drill 0.2032)
		(layers "F.Cu" "B.Cu")
		(net "GND")
	)
	(via
		(at 435.000146 -283.185108)
		(size 0.4826)
		(drill 0.254)
		(layers "F.Cu" "B.Cu")
		(net "GND")
	)
	(via
		(at 303.816258 -400.212814)
		(size 0.4064)
		(drill 0.2032)
		(layers "F.Cu" "B.Cu")
		(net "GND")
	)
	(via
		(at 179.516024 -208.38541)
		(size 0.4826)
		(drill 0.254)
		(layers "F.Cu" "B.Cu")
		(net "GND")
	)
	(via
		(at 99.080828 -393.491212)
		(size 0.508)
		(drill 0.254)
		(layers "F.Cu" "B.Cu")
		(net "GND")
	)
	(via
		(at 435.000146 -311.23509)
		(size 0.4826)
		(drill 0.254)
		(layers "F.Cu" "B.Cu")
		(net "GND")
	)
	(via
		(at 193.598546 -32.177736)
		(size 0.508)
		(drill 0.254)
		(layers "F.Cu" "B.Cu")
		(net "GND")
	)
	(via
		(at 290.895786 -202.434952)
		(size 0.4826)
		(drill 0.254)
		(layers "F.Cu" "B.Cu")
		(net "GND")
	)
	(via
		(at 355.491034 -237.19409)
		(size 0.4064)
		(drill 0.2032)
		(layers "F.Cu" "B.Cu")
		(net "GND")
	)
	(via
		(at 335.195418 -22.247098)
		(size 0.508)
		(drill 0.254)
		(layers "F.Cu" "B.Cu")
		(net "GND")
	)
	(via
		(at 89.99093 -282.18638)
		(size 0.4064)
		(drill 0.2032)
		(layers "F.Cu" "B.Cu")
		(net "GND")
	)
	(via
		(at 9.106408 -170.94454)
		(size 0.508)
		(drill 0.254)
		(layers "F.Cu" "B.Cu")
		(net "GND")
	)
	(via
		(at 423.397426 -356.25659)
		(size 0.508)
		(drill 0.254)
		(layers "F.Cu" "B.Cu")
		(net "GND")
	)
	(via
		(at 151.34971 -427.851316)
		(size 0.4572)
		(drill 0.2032)
		(layers "F.Cu" "B.Cu")
		(net "GND")
	)
	(via
		(at 148.76399 -45.24375)
		(size 0.508)
		(drill 0.254)
		(layers "F.Cu" "B.Cu")
		(net "GND")
	)
	(via
		(at 126.34468 -240.434368)
		(size 0.4064)
		(drill 0.2032)
		(layers "F.Cu" "B.Cu")
		(net "GND")
	)
	(via
		(at 343.544144 -391.23493)
		(size 0.4064)
		(drill 0.2032)
		(layers "F.Cu" "B.Cu")
		(net "GND")
	)
	(via
		(at 378.04471 -245.29415)
		(size 0.4064)
		(drill 0.2032)
		(layers "F.Cu" "B.Cu")
		(net "GND")
	)
	(via
		(at 431.094388 -353.12858)
		(size 0.49022)
		(drill 0.254)
		(layers "F.Cu" "B.Cu")
		(net "GND")
	)
	(via
		(at 17.608042 -269.58544)
		(size 0.4826)
		(drill 0.254)
		(layers "F.Cu" "B.Cu")
		(net "GND")
	)
	(via
		(at 161.903918 -403.830536)
		(size 0.4572)
		(drill 0.254)
		(layers "F.Cu" "B.Cu")
		(net "GND")
	)
	(via
		(at 155.349702 -432.747166)
		(size 0.4572)
		(drill 0.2032)
		(layers "F.Cu" "B.Cu")
		(net "GND")
	)
	(via
		(at 127.584708 -293.52621)
		(size 0.4064)
		(drill 0.2032)
		(layers "F.Cu" "B.Cu")
		(net "GND")
	)
	(via
		(at 62.978538 -386.449062)
		(size 0.4064)
		(drill 0.2032)
		(layers "F.Cu" "B.Cu")
		(net "GND")
	)
	(via
		(at 142.794736 -223.424496)
		(size 0.4064)
		(drill 0.2032)
		(layers "F.Cu" "B.Cu")
		(net "GND")
	)
	(via
		(at 373.75973 -421.586152)
		(size 0.4572)
		(drill 0.254)
		(layers "F.Cu" "B.Cu")
		(net "GND")
	)
	(via
		(at 360.465624 -388.917688)
		(size 0.508)
		(drill 0.254)
		(layers "F.Cu" "B.Cu")
		(net "GND")
	)
	(via
		(at 296.770044 -389.7122)
		(size 0.508)
		(drill 0.254)
		(layers "F.Cu" "B.Cu")
		(net "GND")
	)
	(via
		(at 283.928312 -374.165114)
		(size 0.4572)
		(drill 0.254)
		(layers "F.Cu" "B.Cu")
		(net "GND")
	)
	(via
		(at 337.631024 -248.534174)
		(size 0.4064)
		(drill 0.2032)
		(layers "F.Cu" "B.Cu")
		(net "GND")
	)
	(via
		(at 361.128056 -253.392178)
		(size 0.4064)
		(drill 0.2032)
		(layers "F.Cu" "B.Cu")
		(net "GND")
	)
	(via
		(at 87.81415 -185.920126)
		(size 0.508)
		(drill 0.254)
		(layers "F.Cu" "B.Cu")
		(net "GND")
	)
	(via
		(at 90.94089 -180.687472)
		(size 0.49022)
		(drill 0.254)
		(layers "F.Cu" "B.Cu")
		(net "GND")
	)
	(via
		(at 309.518304 -396.710662)
		(size 0.4064)
		(drill 0.2032)
		(layers "F.Cu" "B.Cu")
		(net "GND")
	)
	(via
		(at 331.991208 -224.234248)
		(size 0.4064)
		(drill 0.2032)
		(layers "F.Cu" "B.Cu")
		(net "GND")
	)
	(via
		(at 88.281002 -244.484398)
		(size 0.4064)
		(drill 0.2032)
		(layers "F.Cu" "B.Cu")
		(net "GND")
	)
	(via
		(at 94.861126 -234.764326)
		(size 0.4064)
		(drill 0.2032)
		(layers "F.Cu" "B.Cu")
		(net "GND")
	)
	(via
		(at 143.409162 -50.877216)
		(size 0.508)
		(drill 0.254)
		(layers "F.Cu" "B.Cu")
		(net "GND")
	)
	(via
		(at 416.254692 -140.249656)
		(size 0.508)
		(drill 0.254)
		(layers "F.Cu" "B.Cu")
		(net "GND")
	)
	(via
		(at 328.061066 -284.616144)
		(size 0.4064)
		(drill 0.2032)
		(layers "F.Cu" "B.Cu")
		(net "GND")
	)
	(via
		(at 99.561142 -226.66452)
		(size 0.4064)
		(drill 0.2032)
		(layers "F.Cu" "B.Cu")
		(net "GND")
	)
	(via
		(at 51.197002 -6.091174)
		(size 0.508)
		(drill 0.254)
		(layers "F.Cu" "B.Cu")
		(net "GND")
	)
	(via
		(at 25.152096 -247.485408)
		(size 0.4826)
		(drill 0.254)
		(layers "F.Cu" "B.Cu")
		(net "GND")
	)
	(via
		(at 266.93241 -284.88513)
		(size 0.4826)
		(drill 0.254)
		(layers "F.Cu" "B.Cu")
		(net "GND")
	)
	(via
		(at 123.524772 -243.674392)
		(size 0.4064)
		(drill 0.2032)
		(layers "F.Cu" "B.Cu")
		(net "GND")
	)
	(via
		(at 303.276 -362.839)
		(size 0.508)
		(drill 0.254)
		(layers "F.Cu" "B.Cu")
		(net "GND")
	)
	(via
		(at 77.520546 -355.160326)
		(size 0.508)
		(drill 0.254)
		(layers "F.Cu" "B.Cu")
		(net "GND")
	)
	(via
		(at 130.098546 -407.00452)
		(size 0.4064)
		(drill 0.2032)
		(layers "F.Cu" "B.Cu")
		(net "GND")
	)
	(via
		(at 422.342564 -349.964756)
		(size 0.49022)
		(drill 0.254)
		(layers "F.Cu" "B.Cu")
		(net "GND")
	)
	(via
		(at 304.652426 -306.135024)
		(size 0.4826)
		(drill 0.254)
		(layers "F.Cu" "B.Cu")
		(net "GND")
	)
	(via
		(at 138.349736 -435.0512)
		(size 0.4572)
		(drill 0.2032)
		(layers "F.Cu" "B.Cu")
		(net "GND")
	)
	(via
		(at 165.314122 -6.042152)
		(size 0.508)
		(drill 0.254)
		(layers "F.Cu" "B.Cu")
		(net "GND")
	)
	(via
		(at 376.93473 -286.236156)
		(size 0.4064)
		(drill 0.2032)
		(layers "F.Cu" "B.Cu")
		(net "GND")
	)
	(via
		(at 84.987384 -441.227718)
		(size 0.508)
		(drill 0.254)
		(layers "F.Cu" "B.Cu")
		(net "GND")
	)
	(via
		(at 361.424728 -272.466054)
		(size 0.4064)
		(drill 0.2032)
		(layers "F.Cu" "B.Cu")
		(net "GND")
	)
	(via
		(at 386.349494 -429.147224)
		(size 0.4572)
		(drill 0.2032)
		(layers "F.Cu" "B.Cu")
		(net "GND")
	)
	(via
		(at 143.264636 -230.71455)
		(size 0.4064)
		(drill 0.2032)
		(layers "F.Cu" "B.Cu")
		(net "GND")
	)
	(via
		(at 343.057226 -412.84652)
		(size 0.4064)
		(drill 0.2032)
		(layers "F.Cu" "B.Cu")
		(net "GND")
	)
	(via
		(at 233.64952 -292.041326)
		(size 0.508)
		(drill 0.254)
		(layers "F.Cu" "B.Cu")
		(net "GND")
	)
	(via
		(at 310.752236 -381.68453)
		(size 0.508)
		(drill 0.254)
		(layers "F.Cu" "B.Cu")
		(net "GND")
	)
	(via
		(at 362.705142 -15.343886)
		(size 0.508)
		(drill 0.254)
		(layers "F.Cu" "B.Cu")
		(net "GND")
	)
	(via
		(at 394.68298 -254.470154)
		(size 0.4064)
		(drill 0.2032)
		(layers "F.Cu" "B.Cu")
		(net "GND")
	)
	(via
		(at 40.23995 -262.785352)
		(size 0.4826)
		(drill 0.254)
		(layers "F.Cu" "B.Cu")
		(net "GND")
	)
	(via
		(at 369.414806 -281.37612)
		(size 0.4064)
		(drill 0.2032)
		(layers "F.Cu" "B.Cu")
		(net "GND")
	)
	(via
		(at 110.671102 -278.946356)
		(size 0.4064)
		(drill 0.2032)
		(layers "F.Cu" "B.Cu")
		(net "GND")
	)
	(via
		(at 94.577154 -335.595214)
		(size 0.49022)
		(drill 0.254)
		(layers "F.Cu" "B.Cu")
		(net "GND")
	)
	(via
		(at 268.530578 -294.660066)
		(size 0.4826)
		(drill 0.254)
		(layers "F.Cu" "B.Cu")
		(net "GND")
	)
	(via
		(at 206.248 -251.735336)
		(size 0.4826)
		(drill 0.254)
		(layers "F.Cu" "B.Cu")
		(net "GND")
	)
	(via
		(at 49.725834 -339.827362)
		(size 0.508)
		(drill 0.254)
		(layers "F.Cu" "B.Cu")
		(net "GND")
	)
	(via
		(at 419.912038 -292.535102)
		(size 0.4826)
		(drill 0.254)
		(layers "F.Cu" "B.Cu")
		(net "GND")
	)
	(via
		(at 114.325908 -22.100794)
		(size 0.508)
		(drill 0.254)
		(layers "F.Cu" "B.Cu")
		(net "GND")
	)
	(via
		(at 329.941174 -289.475926)
		(size 0.4064)
		(drill 0.2032)
		(layers "F.Cu" "B.Cu")
		(net "GND")
	)
	(via
		(at 337.930998 -291.905944)
		(size 0.4064)
		(drill 0.2032)
		(layers "F.Cu" "B.Cu")
		(net "GND")
	)
	(via
		(at 126.470156 -368.37493)
		(size 0.508)
		(drill 0.254)
		(layers "F.Cu" "B.Cu")
		(net "GND")
	)
	(via
		(at 416.555682 -7.215124)
		(size 0.508)
		(drill 0.254)
		(layers "F.Cu" "B.Cu")
		(net "GND")
	)
	(via
		(at 334.171036 -269.22603)
		(size 0.4064)
		(drill 0.2032)
		(layers "F.Cu" "B.Cu")
		(net "GND")
	)
	(via
		(at 26.536396 -240.68532)
		(size 0.4826)
		(drill 0.254)
		(layers "F.Cu" "B.Cu")
		(net "GND")
	)
	(via
		(at 353.441 -268.416024)
		(size 0.4064)
		(drill 0.2032)
		(layers "F.Cu" "B.Cu")
		(net "GND")
	)
	(via
		(at 92.811092 -293.52621)
		(size 0.4064)
		(drill 0.2032)
		(layers "F.Cu" "B.Cu")
		(net "GND")
	)
	(via
		(at 14.820646 -356.446074)
		(size 0.508)
		(drill 0.254)
		(layers "F.Cu" "B.Cu")
		(net "GND")
	)
	(via
		(at 189.66307 -80.174338)
		(size 0.508)
		(drill 0.254)
		(layers "F.Cu" "B.Cu")
		(net "GND")
	)
	(via
		(at 424.012106 -308.685184)
		(size 0.4826)
		(drill 0.254)
		(layers "F.Cu" "B.Cu")
		(net "GND")
	)
	(via
		(at 12.54887 -384.044444)
		(size 0.508)
		(drill 0.254)
		(layers "F.Cu" "B.Cu")
		(net "GND")
	)
	(via
		(at 120.908826 -410.030168)
		(size 0.4064)
		(drill 0.2032)
		(layers "F.Cu" "B.Cu")
		(net "GND")
	)
	(via
		(at 225.223578 -319.466468)
		(size 0.508)
		(drill 0.254)
		(layers "F.Cu" "B.Cu")
		(net "GND")
	)
	(via
		(at 174.815246 -103.029512)
		(size 0.508)
		(drill 0.254)
		(layers "F.Cu" "B.Cu")
		(net "GND")
	)
	(via
		(at 257.302 -331.851)
		(size 0.508)
		(drill 0.254)
		(layers "F.Cu" "B.Cu")
		(net "GND")
	)
	(via
		(at 88.80475 -189.552326)
		(size 0.508)
		(drill 0.254)
		(layers "F.Cu" "B.Cu")
		(net "GND")
	)
	(via
		(at 90.249756 -426.54728)
		(size 0.4572)
		(drill 0.2032)
		(layers "F.Cu" "B.Cu")
		(net "GND")
	)
	(via
		(at 376.634756 -229.904036)
		(size 0.4064)
		(drill 0.2032)
		(layers "F.Cu" "B.Cu")
		(net "GND")
	)
	(via
		(at 395.038072 -384.299968)
		(size 0.508)
		(drill 0.254)
		(layers "F.Cu" "B.Cu")
		(net "GND")
	)
	(via
		(at 146.742912 -233.410252)
		(size 0.4064)
		(drill 0.2032)
		(layers "F.Cu" "B.Cu")
		(net "GND")
	)
	(via
		(at 29.252164 -232.18521)
		(size 0.4826)
		(drill 0.254)
		(layers "F.Cu" "B.Cu")
		(net "GND")
	)
	(via
		(at 32.987996 -399.478246)
		(size 0.508)
		(drill 0.254)
		(layers "F.Cu" "B.Cu")
		(net "GND")
	)
	(via
		(at 189.775846 -314.635388)
		(size 0.4826)
		(drill 0.254)
		(layers "F.Cu" "B.Cu")
		(net "GND")
	)
	(via
		(at 356.261162 -282.996132)
		(size 0.4064)
		(drill 0.2032)
		(layers "F.Cu" "B.Cu")
		(net "GND")
	)
	(via
		(at 127.068326 -57.168034)
		(size 0.508)
		(drill 0.254)
		(layers "F.Cu" "B.Cu")
		(net "GND")
	)
	(via
		(at 382.562354 -392.999722)
		(size 0.4064)
		(drill 0.2032)
		(layers "F.Cu" "B.Cu")
		(net "GND")
	)
	(via
		(at 362.060998 -332.278736)
		(size 0.508)
		(drill 0.254)
		(layers "F.Cu" "B.Cu")
		(net "GND")
	)
	(via
		(at 93.272356 -407.638504)
		(size 0.4572)
		(drill 0.254)
		(layers "F.Cu" "B.Cu")
		(net "GND")
	)
	(via
		(at 147.349718 -438.651396)
		(size 0.4572)
		(drill 0.2032)
		(layers "F.Cu" "B.Cu")
		(net "GND")
	)
	(via
		(at 47.122334 -344.78595)
		(size 0.49022)
		(drill 0.254)
		(layers "F.Cu" "B.Cu")
		(net "GND")
	)
	(via
		(at 454.188068 -222.834962)
		(size 0.4826)
		(drill 0.254)
		(layers "F.Cu" "B.Cu")
		(net "GND")
	)
	(via
		(at 17.608042 -208.38541)
		(size 0.4826)
		(drill 0.254)
		(layers "F.Cu" "B.Cu")
		(net "GND")
	)
	(via
		(at 55.334662 -4.32943)
		(size 0.508)
		(drill 0.254)
		(layers "F.Cu" "B.Cu")
		(net "GND")
	)
	(via
		(at 385.739894 -417.778184)
		(size 0.4572)
		(drill 0.254)
		(layers "F.Cu" "B.Cu")
		(net "GND")
	)
	(via
		(at 44.310554 -348.709488)
		(size 0.49022)
		(drill 0.254)
		(layers "F.Cu" "B.Cu")
		(net "GND")
	)
	(via
		(at 140.444728 -232.334308)
		(size 0.4064)
		(drill 0.2032)
		(layers "F.Cu" "B.Cu")
		(net "GND")
	)
	(via
		(at 110.848394 -188.294518)
		(size 0.508)
		(drill 0.254)
		(layers "F.Cu" "B.Cu")
		(net "GND")
	)
	(via
		(at 188.215778 -192.218564)
		(size 0.4826)
		(drill 0.254)
		(layers "F.Cu" "B.Cu")
		(net "GND")
	)
	(via
		(at 413.485584 -220.709998)
		(size 0.4826)
		(drill 0.254)
		(layers "F.Cu" "B.Cu")
		(net "GND")
	)
	(via
		(at 133.762496 -369.03533)
		(size 0.508)
		(drill 0.254)
		(layers "F.Cu" "B.Cu")
		(net "GND")
	)
	(via
		(at 346.39123 -264.365994)
		(size 0.4064)
		(drill 0.2032)
		(layers "F.Cu" "B.Cu")
		(net "GND")
	)
	(via
		(at 176.072038 -198.185278)
		(size 0.4826)
		(drill 0.254)
		(layers "F.Cu" "B.Cu")
		(net "GND")
	)
	(via
		(at 53.592222 -175.744124)
		(size 0.6604)
		(drill 0.3302)
		(layers "F.Cu" "B.Cu")
		(net "GND")
	)
	(via
		(at 246.105426 -285.947358)
		(size 0.508)
		(drill 0.254)
		(layers "F.Cu" "B.Cu")
		(net "GND")
	)
	(via
		(at 299.82414 -261.93496)
		(size 0.4826)
		(drill 0.254)
		(layers "F.Cu" "B.Cu")
		(net "GND")
	)
	(via
		(at 363.004862 -250.154186)
		(size 0.4064)
		(drill 0.2032)
		(layers "F.Cu" "B.Cu")
		(net "GND")
	)
	(via
		(at 174.037498 -346.329)
		(size 0.508)
		(drill 0.254)
		(layers "F.Cu" "B.Cu")
		(net "GND")
	)
	(via
		(at 231.156764 -243.924328)
		(size 0.4826)
		(drill 0.254)
		(layers "F.Cu" "B.Cu")
		(net "GND")
	)
	(via
		(at 145.414746 -410.030168)
		(size 0.4064)
		(drill 0.2032)
		(layers "F.Cu" "B.Cu")
		(net "GND")
	)
	(via
		(at 383.21488 -252.584204)
		(size 0.4064)
		(drill 0.2032)
		(layers "F.Cu" "B.Cu")
		(net "GND")
	)
	(via
		(at 131.544314 -410.664152)
		(size 0.4572)
		(drill 0.254)
		(layers "F.Cu" "B.Cu")
		(net "GND")
	)
	(via
		(at 273.092164 -197.33514)
		(size 0.4826)
		(drill 0.254)
		(layers "F.Cu" "B.Cu")
		(net "GND")
	)
	(via
		(at 323.148706 -415.38652)
		(size 0.4064)
		(drill 0.2032)
		(layers "F.Cu" "B.Cu")
		(net "GND")
	)
	(via
		(at 309.722774 -421.586152)
		(size 0.4572)
		(drill 0.254)
		(layers "F.Cu" "B.Cu")
		(net "GND")
	)
	(via
		(at 375.054876 -284.616144)
		(size 0.4064)
		(drill 0.2032)
		(layers "F.Cu" "B.Cu")
		(net "GND")
	)
	(via
		(at 428.038006 -6.091174)
		(size 0.508)
		(drill 0.254)
		(layers "F.Cu" "B.Cu")
		(net "GND")
	)
	(via
		(at 295.724072 -236.435138)
		(size 0.4826)
		(drill 0.254)
		(layers "F.Cu" "B.Cu")
		(net "GND")
	)
	(via
		(at 429.334676 -4.963414)
		(size 0.508)
		(drill 0.254)
		(layers "F.Cu" "B.Cu")
		(net "GND")
	)
	(via
		(at 372.404894 -230.714042)
		(size 0.4064)
		(drill 0.2032)
		(layers "F.Cu" "B.Cu")
		(net "GND")
	)
	(via
		(at 363.474762 -241.24412)
		(size 0.4064)
		(drill 0.2032)
		(layers "F.Cu" "B.Cu")
		(net "GND")
	)
	(via
		(at 132.754878 -294.336216)
		(size 0.4064)
		(drill 0.2032)
		(layers "F.Cu" "B.Cu")
		(net "GND")
	)
	(via
		(at 157.220666 -412.570168)
		(size 0.4064)
		(drill 0.2032)
		(layers "F.Cu" "B.Cu")
		(net "GND")
	)
	(via
		(at 184.908444 -25.902666)
		(size 0.508)
		(drill 0.254)
		(layers "F.Cu" "B.Cu")
		(net "GND")
	)
	(via
		(at 192.419478 -427.848776)
		(size 0.508)
		(drill 0.254)
		(layers "F.Cu" "B.Cu")
		(net "GND")
	)
	(via
		(at 151.053292 -81.8388)
		(size 0.508)
		(drill 0.254)
		(layers "F.Cu" "B.Cu")
		(net "GND")
	)
	(via
		(at 80.120998 -261.93623)
		(size 0.4064)
		(drill 0.2032)
		(layers "F.Cu" "B.Cu")
		(net "GND")
	)
	(via
		(at 90.461084 -270.03629)
		(size 0.4064)
		(drill 0.2032)
		(layers "F.Cu" "B.Cu")
		(net "GND")
	)
	(via
		(at 130.87477 -261.93623)
		(size 0.4064)
		(drill 0.2032)
		(layers "F.Cu" "B.Cu")
		(net "GND")
	)
	(via
		(at 116.18214 -259.845302)
		(size 0.4826)
		(drill 0.254)
		(layers "F.Cu" "B.Cu")
		(net "GND")
	)
	(via
		(at 417.585652 -294.660066)
		(size 0.4826)
		(drill 0.254)
		(layers "F.Cu" "B.Cu")
		(net "GND")
	)
	(via
		(at 132.349748 -438.499758)
		(size 0.4572)
		(drill 0.2032)
		(layers "F.Cu" "B.Cu")
		(net "GND")
	)
	(via
		(at 182.939182 -350.14535)
		(size 0.49022)
		(drill 0.254)
		(layers "F.Cu" "B.Cu")
		(net "GND")
	)
	(via
		(at 51.884072 -215.185244)
		(size 0.4826)
		(drill 0.254)
		(layers "F.Cu" "B.Cu")
		(net "GND")
	)
	(via
		(at 115.005866 -173.862746)
		(size 0.49022)
		(drill 0.254)
		(layers "F.Cu" "B.Cu")
		(net "GND")
	)
	(via
		(at 99.390962 -269.226284)
		(size 0.4064)
		(drill 0.2032)
		(layers "F.Cu" "B.Cu")
		(net "GND")
	)
	(via
		(at 123.354846 -263.556242)
		(size 0.4064)
		(drill 0.2032)
		(layers "F.Cu" "B.Cu")
		(net "GND")
	)
	(via
		(at 104.731058 -240.434368)
		(size 0.4064)
		(drill 0.2032)
		(layers "F.Cu" "B.Cu")
		(net "GND")
	)
	(via
		(at 180.836316 -330.872084)
		(size 0.508)
		(drill 0.254)
		(layers "F.Cu" "B.Cu")
		(net "GND")
	)
	(via
		(at 367.704878 -222.614236)
		(size 0.4064)
		(drill 0.2032)
		(layers "F.Cu" "B.Cu")
		(net "GND")
	)
	(via
		(at 17.608042 -236.435392)
		(size 0.4826)
		(drill 0.254)
		(layers "F.Cu" "B.Cu")
		(net "GND")
	)
	(via
		(at 54.896004 -410.030168)
		(size 0.4064)
		(drill 0.2032)
		(layers "F.Cu" "B.Cu")
		(net "GND")
	)
	(via
		(at 126.814834 -242.864386)
		(size 0.4064)
		(drill 0.2032)
		(layers "F.Cu" "B.Cu")
		(net "GND")
	)
	(via
		(at 346.58046 -328.598276)
		(size 0.508)
		(drill 0.254)
		(layers "F.Cu" "B.Cu")
		(net "GND")
	)
	(via
		(at 400.732752 -395.42974)
		(size 0.4064)
		(drill 0.2032)
		(layers "F.Cu" "B.Cu")
		(net "GND")
	)
	(via
		(at 308.437026 -348.704662)
		(size 0.49022)
		(drill 0.254)
		(layers "F.Cu" "B.Cu")
		(net "GND")
	)
	(via
		(at 355.491034 -235.574078)
		(size 0.4064)
		(drill 0.2032)
		(layers "F.Cu" "B.Cu")
		(net "GND")
	)
	(via
		(at 84.71916 -390.160002)
		(size 0.4064)
		(drill 0.2032)
		(layers "F.Cu" "B.Cu")
		(net "GND")
	)
	(via
		(at 17.608042 -214.33536)
		(size 0.4826)
		(drill 0.254)
		(layers "F.Cu" "B.Cu")
		(net "GND")
	)
	(via
		(at 74.299064 -355.760528)
		(size 0.508)
		(drill 0.254)
		(layers "F.Cu" "B.Cu")
		(net "GND")
	)
	(via
		(at 118.078504 -386.449062)
		(size 0.4064)
		(drill 0.2032)
		(layers "F.Cu" "B.Cu")
		(net "GND")
	)
	(via
		(at 138.564874 -237.194344)
		(size 0.4064)
		(drill 0.2032)
		(layers "F.Cu" "B.Cu")
		(net "GND")
	)
	(via
		(at 91.871038 -264.366248)
		(size 0.4064)
		(drill 0.2032)
		(layers "F.Cu" "B.Cu")
		(net "GND")
	)
	(via
		(at 407.45537 -420.318184)
		(size 0.4572)
		(drill 0.254)
		(layers "F.Cu" "B.Cu")
		(net "GND")
	)
	(via
		(at 326.651112 -280.566114)
		(size 0.4064)
		(drill 0.2032)
		(layers "F.Cu" "B.Cu")
		(net "GND")
	)
	(via
		(at 173.571408 -388.753604)
		(size 0.508)
		(drill 0.254)
		(layers "F.Cu" "B.Cu")
		(net "GND")
	)
	(via
		(at 139.038076 -379.321568)
		(size 0.508)
		(drill 0.254)
		(layers "F.Cu" "B.Cu")
		(net "GND")
	)
	(via
		(at 304.652426 -275.535136)
		(size 0.4826)
		(drill 0.254)
		(layers "F.Cu" "B.Cu")
		(net "GND")
	)
	(via
		(at 360.465624 -387.703568)
		(size 0.508)
		(drill 0.254)
		(layers "F.Cu" "B.Cu")
		(net "GND")
	)
	(via
		(at 135.574786 -274.896326)
		(size 0.4064)
		(drill 0.2032)
		(layers "F.Cu" "B.Cu")
		(net "GND")
	)
	(via
		(at 173.08957 -304.860452)
		(size 0.4826)
		(drill 0.254)
		(layers "F.Cu" "B.Cu")
		(net "GND")
	)
	(via
		(at 194.604132 -204.985366)
		(size 0.4826)
		(drill 0.254)
		(layers "F.Cu" "B.Cu")
		(net "GND")
	)
	(via
		(at 346.120466 -412.84652)
		(size 0.4064)
		(drill 0.2032)
		(layers "F.Cu" "B.Cu")
		(net "GND")
	)
	(via
		(at 331.521054 -241.24412)
		(size 0.4064)
		(drill 0.2032)
		(layers "F.Cu" "B.Cu")
		(net "GND")
	)
	(via
		(at 331.351128 -270.846042)
		(size 0.4064)
		(drill 0.2032)
		(layers "F.Cu" "B.Cu")
		(net "GND")
	)
	(via
		(at 76.424536 -405.098504)
		(size 0.4572)
		(drill 0.254)
		(layers "F.Cu" "B.Cu")
		(net "GND")
	)
	(via
		(at 61.249814 -432.451256)
		(size 0.4572)
		(drill 0.2032)
		(layers "F.Cu" "B.Cu")
		(net "GND")
	)
	(via
		(at 431.55616 -289.985196)
		(size 0.4826)
		(drill 0.254)
		(layers "F.Cu" "B.Cu")
		(net "GND")
	)
	(via
		(at 204.8637 -284.035246)
		(size 0.4826)
		(drill 0.254)
		(layers "F.Cu" "B.Cu")
		(net "GND")
	)
	(via
		(at 53.361844 -412.570168)
		(size 0.4064)
		(drill 0.2032)
		(layers "F.Cu" "B.Cu")
		(net "GND")
	)
	(via
		(at 98.38055 -413.311848)
		(size 0.508)
		(drill 0.254)
		(layers "F.Cu" "B.Cu")
		(net "GND")
	)
	(via
		(at 104.731058 -235.574332)
		(size 0.4064)
		(drill 0.2032)
		(layers "F.Cu" "B.Cu")
		(net "GND")
	)
	(via
		(at 47.784004 -301.88535)
		(size 0.4826)
		(drill 0.254)
		(layers "F.Cu" "B.Cu")
		(net "GND")
	)
	(via
		(at 423.544492 -167.391334)
		(size 0.49022)
		(drill 0.254)
		(layers "F.Cu" "B.Cu")
		(net "GND")
	)
	(via
		(at 227.814378 -316.46368)
		(size 0.508)
		(drill 0.254)
		(layers "F.Cu" "B.Cu")
		(net "GND")
	)
	(via
		(at 331.521054 -233.14406)
		(size 0.4064)
		(drill 0.2032)
		(layers "F.Cu" "B.Cu")
		(net "GND")
	)
	(via
		(at 391.674858 -238.004096)
		(size 0.4064)
		(drill 0.2032)
		(layers "F.Cu" "B.Cu")
		(net "GND")
	)
	(via
		(at 364.71479 -292.71595)
		(size 0.4064)
		(drill 0.2032)
		(layers "F.Cu" "B.Cu")
		(net "GND")
	)
	(via
		(at 19.508724 -404.68931)
		(size 0.508)
		(drill 0.254)
		(layers "F.Cu" "B.Cu")
		(net "GND")
	)
	(via
		(at 105.942892 -388.941056)
		(size 0.508)
		(drill 0.254)
		(layers "F.Cu" "B.Cu")
		(net "GND")
	)
	(via
		(at 145.444718 -267.606272)
		(size 0.4064)
		(drill 0.2032)
		(layers "F.Cu" "B.Cu")
		(net "GND")
	)
	(via
		(at 217.095578 -58.389012)
		(size 0.508)
		(drill 0.254)
		(layers "F.Cu" "B.Cu")
		(net "GND")
	)
	(via
		(at 346.39123 -261.12597)
		(size 0.4064)
		(drill 0.2032)
		(layers "F.Cu" "B.Cu")
		(net "GND")
	)
	(via
		(at 135.14832 -17.654778)
		(size 0.508)
		(drill 0.254)
		(layers "F.Cu" "B.Cu")
		(net "GND")
	)
	(via
		(at 272.021046 -339.789008)
		(size 0.508)
		(drill 0.254)
		(layers "F.Cu" "B.Cu")
		(net "GND")
	)
	(via
		(at 331.821028 -295.955974)
		(size 0.4064)
		(drill 0.2032)
		(layers "F.Cu" "B.Cu")
		(net "GND")
	)
	(via
		(at 375.524776 -287.045908)
		(size 0.4064)
		(drill 0.2032)
		(layers "F.Cu" "B.Cu")
		(net "GND")
	)
	(via
		(at 173.35627 -275.53539)
		(size 0.4826)
		(drill 0.254)
		(layers "F.Cu" "B.Cu")
		(net "GND")
	)
	(via
		(at 203.532232 -287.43529)
		(size 0.4826)
		(drill 0.254)
		(layers "F.Cu" "B.Cu")
		(net "GND")
	)
	(via
		(at 337.930998 -275.706078)
		(size 0.4064)
		(drill 0.2032)
		(layers "F.Cu" "B.Cu")
		(net "GND")
	)
	(via
		(at 67.296538 -334.078834)
		(size 0.49022)
		(drill 0.254)
		(layers "F.Cu" "B.Cu")
		(net "GND")
	)
	(via
		(at 57.959244 -410.030168)
		(size 0.4064)
		(drill 0.2032)
		(layers "F.Cu" "B.Cu")
		(net "GND")
	)
	(via
		(at 377.57481 -249.34418)
		(size 0.4064)
		(drill 0.2032)
		(layers "F.Cu" "B.Cu")
		(net "GND")
	)
	(via
		(at 385.094734 -246.104156)
		(size 0.4064)
		(drill 0.2032)
		(layers "F.Cu" "B.Cu")
		(net "GND")
	)
	(via
		(at 369.3033 -427.0883)
		(size 0.508)
		(drill 0.254)
		(layers "F.Cu" "B.Cu")
		(net "GND")
	)
	(via
		(at 51.884072 -306.985416)
		(size 0.4826)
		(drill 0.254)
		(layers "F.Cu" "B.Cu")
		(net "GND")
	)
	(via
		(at 271.482058 -98.992436)
		(size 0.508)
		(drill 0.254)
		(layers "F.Cu" "B.Cu")
		(net "GND")
	)
	(via
		(at 284.5308 -418.235638)
		(size 0.4572)
		(drill 0.254)
		(layers "F.Cu" "B.Cu")
		(net "GND")
	)
	(via
		(at 93.959934 -337.017614)
		(size 0.49022)
		(drill 0.254)
		(layers "F.Cu" "B.Cu")
		(net "GND")
	)
	(via
		(at 315.935106 -415.38652)
		(size 0.4064)
		(drill 0.2032)
		(layers "F.Cu" "B.Cu")
		(net "GND")
	)
	(via
		(at 50.499772 -302.735234)
		(size 0.4826)
		(drill 0.254)
		(layers "F.Cu" "B.Cu")
		(net "GND")
	)
	(via
		(at 430.17186 -209.23504)
		(size 0.4826)
		(drill 0.254)
		(layers "F.Cu" "B.Cu")
		(net "GND")
	)
	(via
		(at 131.34467 -295.146222)
		(size 0.4064)
		(drill 0.2032)
		(layers "F.Cu" "B.Cu")
		(net "GND")
	)
	(via
		(at 110.013496 -56.452262)
		(size 0.508)
		(drill 0.254)
		(layers "F.Cu" "B.Cu")
		(net "GND")
	)
	(via
		(at 56.872124 -410.030168)
		(size 0.4064)
		(drill 0.2032)
		(layers "F.Cu" "B.Cu")
		(net "GND")
	)
	(via
		(at 351.164906 -412.84652)
		(size 0.4064)
		(drill 0.2032)
		(layers "F.Cu" "B.Cu")
		(net "GND")
	)
	(via
		(at 171.191428 -416.379406)
		(size 0.508)
		(drill 0.254)
		(layers "F.Cu" "B.Cu")
		(net "GND")
	)
	(via
		(at 141.387068 -388.464806)
		(size 0.508)
		(drill 0.254)
		(layers "F.Cu" "B.Cu")
		(net "GND")
	)
	(via
		(at 73.95845 -380.87046)
		(size 0.508)
		(drill 0.254)
		(layers "F.Cu" "B.Cu")
		(net "GND")
	)
	(via
		(at 361.424728 -270.846042)
		(size 0.4064)
		(drill 0.2032)
		(layers "F.Cu" "B.Cu")
		(net "GND")
	)
	(via
		(at 180.225954 -357.270812)
		(size 0.508)
		(drill 0.254)
		(layers "F.Cu" "B.Cu")
		(net "GND")
	)
	(via
		(at 306.386738 -417.778184)
		(size 0.4572)
		(drill 0.254)
		(layers "F.Cu" "B.Cu")
		(net "GND")
	)
	(via
		(at 347.50121 -229.904036)
		(size 0.4064)
		(drill 0.2032)
		(layers "F.Cu" "B.Cu")
		(net "GND")
	)
	(via
		(at 113.348008 -256.3876)
		(size 0.4826)
		(drill 0.254)
		(layers "F.Cu" "B.Cu")
		(net "GND")
	)
	(via
		(at 43.85818 -9.424924)
		(size 0.508)
		(drill 0.254)
		(layers "F.Cu" "B.Cu")
		(net "GND")
	)
	(via
		(at 26.536396 -231.335326)
		(size 0.4826)
		(drill 0.254)
		(layers "F.Cu" "B.Cu")
		(net "GND")
	)
	(via
		(at 374.754902 -233.14406)
		(size 0.4064)
		(drill 0.2032)
		(layers "F.Cu" "B.Cu")
		(net "GND")
	)
	(via
		(at 189.775846 -239.835436)
		(size 0.4826)
		(drill 0.254)
		(layers "F.Cu" "B.Cu")
		(net "GND")
	)
	(via
		(at 328.102214 -413.480504)
		(size 0.4572)
		(drill 0.254)
		(layers "F.Cu" "B.Cu")
		(net "GND")
	)
	(via
		(at 50.431954 -18.247106)
		(size 0.508)
		(drill 0.254)
		(layers "F.Cu" "B.Cu")
		(net "GND")
	)
	(via
		(at 106.05389 -12.542266)
		(size 0.508)
		(drill 0.254)
		(layers "F.Cu" "B.Cu")
		(net "GND")
	)
	(via
		(at 422.627806 -302.73498)
		(size 0.4826)
		(drill 0.254)
		(layers "F.Cu" "B.Cu")
		(net "GND")
	)
	(via
		(at 129.052574 -79.787496)
		(size 0.508)
		(drill 0.254)
		(layers "F.Cu" "B.Cu")
		(net "GND")
	)
	(via
		(at 224.011998 -317.971678)
		(size 0.508)
		(drill 0.254)
		(layers "F.Cu" "B.Cu")
		(net "GND")
	)
	(via
		(at 157.296104 -370.83873)
		(size 0.508)
		(drill 0.254)
		(layers "F.Cu" "B.Cu")
		(net "GND")
	)
	(via
		(at 112.773714 -182.736998)
		(size 0.508)
		(drill 0.254)
		(layers "F.Cu" "B.Cu")
		(net "GND")
	)
	(via
		(at 139.469622 -81.057242)
		(size 0.508)
		(drill 0.254)
		(layers "F.Cu" "B.Cu")
		(net "GND")
	)
	(via
		(at 51.884072 -250.035314)
		(size 0.4826)
		(drill 0.254)
		(layers "F.Cu" "B.Cu")
		(net "GND")
	)
	(via
		(at 143.81861 -388.297674)
		(size 0.508)
		(drill 0.254)
		(layers "F.Cu" "B.Cu")
		(net "GND")
	)
	(via
		(at 65.975992 -405.098504)
		(size 0.4572)
		(drill 0.254)
		(layers "F.Cu" "B.Cu")
		(net "GND")
	)
	(via
		(at 65.249806 -426.54728)
		(size 0.4572)
		(drill 0.2032)
		(layers "F.Cu" "B.Cu")
		(net "GND")
	)
	(via
		(at 382.618488 -396.710662)
		(size 0.4064)
		(drill 0.2032)
		(layers "F.Cu" "B.Cu")
		(net "GND")
	)
	(via
		(at 140.274802 -274.896326)
		(size 0.4064)
		(drill 0.2032)
		(layers "F.Cu" "B.Cu")
		(net "GND")
	)
	(via
		(at 315.816234 -400.212814)
		(size 0.4064)
		(drill 0.2032)
		(layers "F.Cu" "B.Cu")
		(net "GND")
	)
	(via
		(at 288.599626 -339.799676)
		(size 0.508)
		(drill 0.254)
		(layers "F.Cu" "B.Cu")
		(net "GND")
	)
	(via
		(at 29.252164 -268.735302)
		(size 0.4826)
		(drill 0.254)
		(layers "F.Cu" "B.Cu")
		(net "GND")
	)
	(via
		(at 182.753 -91.658948)
		(size 0.508)
		(drill 0.254)
		(layers "F.Cu" "B.Cu")
		(net "GND")
	)
	(via
		(at 50.766472 -285.310326)
		(size 0.4826)
		(drill 0.254)
		(layers "F.Cu" "B.Cu")
		(net "GND")
	)
	(via
		(at 277.192232 -204.134974)
		(size 0.4826)
		(drill 0.254)
		(layers "F.Cu" "B.Cu")
		(net "GND")
	)
	(via
		(at 386.504942 -251.774198)
		(size 0.4064)
		(drill 0.2032)
		(layers "F.Cu" "B.Cu")
		(net "GND")
	)
	(via
		(at 47.784004 -249.18543)
		(size 0.4826)
		(drill 0.254)
		(layers "F.Cu" "B.Cu")
		(net "GND")
	)
	(via
		(at 44.094908 -6.598158)
		(size 0.508)
		(drill 0.254)
		(layers "F.Cu" "B.Cu")
		(net "GND")
	)
	(via
		(at 115.247928 -256.3876)
		(size 0.4826)
		(drill 0.254)
		(layers "F.Cu" "B.Cu")
		(net "GND")
	)
	(via
		(at 370.26469 -394.25753)
		(size 0.4064)
		(drill 0.2032)
		(layers "F.Cu" "B.Cu")
		(net "GND")
	)
	(via
		(at 100.285296 -423.44848)
		(size 0.508)
		(drill 0.254)
		(layers "F.Cu" "B.Cu")
		(net "GND")
	)
	(via
		(at 337.291934 -412.212536)
		(size 0.4572)
		(drill 0.254)
		(layers "F.Cu" "B.Cu")
		(net "GND")
	)
	(via
		(at 334.8482 -164.084)
		(size 0.508)
		(drill 0.254)
		(layers "F.Cu" "B.Cu")
		(net "GND")
	)
	(via
		(at 384.814064 -177.71618)
		(size 0.508)
		(drill 0.254)
		(layers "F.Cu" "B.Cu")
		(net "GND")
	)
	(via
		(at 88.319102 -390.160002)
		(size 0.4064)
		(drill 0.2032)
		(layers "F.Cu" "B.Cu")
		(net "GND")
	)
	(via
		(at 246.915686 -288.327846)
		(size 0.508)
		(drill 0.254)
		(layers "F.Cu" "B.Cu")
		(net "GND")
	)
	(via
		(at 21.70811 -232.18521)
		(size 0.4826)
		(drill 0.254)
		(layers "F.Cu" "B.Cu")
		(net "GND")
	)
	(via
		(at 407.541222 -415.38652)
		(size 0.4064)
		(drill 0.2032)
		(layers "F.Cu" "B.Cu")
		(net "GND")
	)
	(via
		(at 353.441 -278.136096)
		(size 0.4064)
		(drill 0.2032)
		(layers "F.Cu" "B.Cu")
		(net "GND")
	)
	(via
		(at 421.54094 -100.260658)
		(size 0.508)
		(drill 0.254)
		(layers "F.Cu" "B.Cu")
		(net "GND")
	)
	(via
		(at 97.60458 -353.02825)
		(size 0.508)
		(drill 0.254)
		(layers "F.Cu" "B.Cu")
		(net "GND")
	)
	(via
		(at 408.05989 -140.537438)
		(size 0.508)
		(drill 0.254)
		(layers "F.Cu" "B.Cu")
		(net "GND")
	)
	(via
		(at 381.334772 -229.904036)
		(size 0.4064)
		(drill 0.2032)
		(layers "F.Cu" "B.Cu")
		(net "GND")
	)
	(via
		(at 130.574796 -250.964446)
		(size 0.4064)
		(drill 0.2032)
		(layers "F.Cu" "B.Cu")
		(net "GND")
	)
	(via
		(at 395.36497 -188.116718)
		(size 0.508)
		(drill 0.254)
		(layers "F.Cu" "B.Cu")
		(net "GND")
	)
	(via
		(at 167.143684 -202.435206)
		(size 0.4826)
		(drill 0.254)
		(layers "F.Cu" "B.Cu")
		(net "GND")
	)
	(via
		(at 167.556942 -437.432196)
		(size 0.508)
		(drill 0.254)
		(layers "F.Cu" "B.Cu")
		(net "GND")
	)
	(via
		(at 353.441 -279.756108)
		(size 0.4064)
		(drill 0.2032)
		(layers "F.Cu" "B.Cu")
		(net "GND")
	)
	(via
		(at 222.965518 -276.366478)
		(size 0.508)
		(drill 0.254)
		(layers "F.Cu" "B.Cu")
		(net "GND")
	)
	(via
		(at 86.701122 -266.796266)
		(size 0.4064)
		(drill 0.2032)
		(layers "F.Cu" "B.Cu")
		(net "GND")
	)
	(via
		(at 175.652938 -98.255836)
		(size 0.508)
		(drill 0.254)
		(layers "F.Cu" "B.Cu")
		(net "GND")
	)
	(via
		(at 426.494956 -19.771106)
		(size 0.508)
		(drill 0.254)
		(layers "F.Cu" "B.Cu")
		(net "GND")
	)
	(via
		(at 295.724072 -197.33514)
		(size 0.4826)
		(drill 0.254)
		(layers "F.Cu" "B.Cu")
		(net "GND")
	)
	(via
		(at 29.252164 -215.185244)
		(size 0.4826)
		(drill 0.254)
		(layers "F.Cu" "B.Cu")
		(net "GND")
	)
	(via
		(at 394.982954 -292.450012)
		(size 0.4064)
		(drill 0.2032)
		(layers "F.Cu" "B.Cu")
		(net "GND")
	)
	(via
		(at 115.834668 -278.13635)
		(size 0.4064)
		(drill 0.2032)
		(layers "F.Cu" "B.Cu")
		(net "GND")
	)
	(via
		(at 279.518364 -304.860198)
		(size 0.4826)
		(drill 0.254)
		(layers "F.Cu" "B.Cu")
		(net "GND")
	)
	(via
		(at 323.507354 -419.046152)
		(size 0.4572)
		(drill 0.254)
		(layers "F.Cu" "B.Cu")
		(net "GND")
	)
	(via
		(at 29.252164 -282.335224)
		(size 0.4826)
		(drill 0.254)
		(layers "F.Cu" "B.Cu")
		(net "GND")
	)
	(via
		(at 118.824756 -248.534428)
		(size 0.4064)
		(drill 0.2032)
		(layers "F.Cu" "B.Cu")
		(net "GND")
	)
	(via
		(at 265.54811 -264.48512)
		(size 0.4826)
		(drill 0.254)
		(layers "F.Cu" "B.Cu")
		(net "GND")
	)
	(via
		(at 366.764824 -224.234248)
		(size 0.4064)
		(drill 0.2032)
		(layers "F.Cu" "B.Cu")
		(net "GND")
	)
	(via
		(at 350.321118 -242.864132)
		(size 0.4064)
		(drill 0.2032)
		(layers "F.Cu" "B.Cu")
		(net "GND")
	)
	(via
		(at 21.623782 -411.707584)
		(size 0.508)
		(drill 0.254)
		(layers "F.Cu" "B.Cu")
		(net "GND")
	)
	(via
		(at 292.280086 -226.235006)
		(size 0.4826)
		(drill 0.254)
		(layers "F.Cu" "B.Cu")
		(net "GND")
	)
	(via
		(at 151.273002 -60.738512)
		(size 0.508)
		(drill 0.254)
		(layers "F.Cu" "B.Cu")
		(net "GND")
	)
	(via
		(at 21.70811 -222.835216)
		(size 0.4826)
		(drill 0.254)
		(layers "F.Cu" "B.Cu")
		(net "GND")
	)
	(via
		(at 371.294914 -263.555988)
		(size 0.4064)
		(drill 0.2032)
		(layers "F.Cu" "B.Cu")
		(net "GND")
	)
	(via
		(at 425.41698 -17.61236)
		(size 0.508)
		(drill 0.254)
		(layers "F.Cu" "B.Cu")
		(net "GND")
	)
	(via
		(at 103.321104 -249.344434)
		(size 0.4064)
		(drill 0.2032)
		(layers "F.Cu" "B.Cu")
		(net "GND")
	)
	(via
		(at 100.331016 -288.666174)
		(size 0.4064)
		(drill 0.2032)
		(layers "F.Cu" "B.Cu")
		(net "GND")
	)
	(via
		(at 104.82961 -68.62191)
		(size 0.508)
		(drill 0.254)
		(layers "F.Cu" "B.Cu")
		(net "GND")
	)
	(via
		(at 457.23175 -51.271678)
		(size 0.508)
		(drill 0.254)
		(layers "F.Cu" "B.Cu")
		(net "GND")
	)
	(via
		(at 412.690056 -392.999722)
		(size 0.4064)
		(drill 0.2032)
		(layers "F.Cu" "B.Cu")
		(net "GND")
	)
	(via
		(at 121.944638 -274.08632)
		(size 0.4064)
		(drill 0.2032)
		(layers "F.Cu" "B.Cu")
		(net "GND")
	)
	(via
		(at 333.871062 -222.614236)
		(size 0.4064)
		(drill 0.2032)
		(layers "F.Cu" "B.Cu")
		(net "GND")
	)
	(via
		(at 184.682892 -342.665558)
		(size 0.508)
		(drill 0.254)
		(layers "F.Cu" "B.Cu")
		(net "GND")
	)
	(via
		(at 303.990756 -438.470294)
		(size 0.508)
		(drill 0.254)
		(layers "F.Cu" "B.Cu")
		(net "GND")
	)
	(via
		(at 38.81501 -433.197)
		(size 0.508)
		(drill 0.254)
		(layers "F.Cu" "B.Cu")
		(net "GND")
	)
	(via
		(at 171.97197 -234.73537)
		(size 0.4826)
		(drill 0.254)
		(layers "F.Cu" "B.Cu")
		(net "GND")
	)
	(via
		(at 372.404894 -238.814102)
		(size 0.4064)
		(drill 0.2032)
		(layers "F.Cu" "B.Cu")
		(net "GND")
	)
	(via
		(at 20.32381 -293.38524)
		(size 0.4826)
		(drill 0.254)
		(layers "F.Cu" "B.Cu")
		(net "GND")
	)
	(via
		(at 111.581946 -55.891684)
		(size 0.508)
		(drill 0.254)
		(layers "F.Cu" "B.Cu")
		(net "GND")
	)
	(via
		(at 460.255366 -378.05487)
		(size 0.508)
		(drill 0.254)
		(layers "F.Cu" "B.Cu")
		(net "GND")
	)
	(via
		(at 69.039232 -413.204152)
		(size 0.4572)
		(drill 0.254)
		(layers "F.Cu" "B.Cu")
		(net "GND")
	)
	(via
		(at 387.271514 -413.480504)
		(size 0.4572)
		(drill 0.254)
		(layers "F.Cu" "B.Cu")
		(net "GND")
	)
	(via
		(at 302.190658 -45.005498)
		(size 0.508)
		(drill 0.254)
		(layers "F.Cu" "B.Cu")
		(net "GND")
	)
	(via
		(at 156.079444 -373.96293)
		(size 0.508)
		(drill 0.254)
		(layers "F.Cu" "B.Cu")
		(net "GND")
	)
	(via
		(at 202.147932 -199.035416)
		(size 0.4826)
		(drill 0.254)
		(layers "F.Cu" "B.Cu")
		(net "GND")
	)
	(via
		(at 4.392168 -73.694798)
		(size 0.508)
		(drill 0.254)
		(layers "F.Cu" "B.Cu")
		(net "GND")
	)
	(via
		(at 351.805494 -437.240172)
		(size 0.508)
		(drill 0.254)
		(layers "F.Cu" "B.Cu")
		(net "GND")
	)
	(via
		(at 80.120998 -271.656302)
		(size 0.4064)
		(drill 0.2032)
		(layers "F.Cu" "B.Cu")
		(net "GND")
	)
	(via
		(at 311.254394 -419.046152)
		(size 0.4572)
		(drill 0.254)
		(layers "F.Cu" "B.Cu")
		(net "GND")
	)
	(via
		(at 198.7042 -318.035432)
		(size 0.4826)
		(drill 0.254)
		(layers "F.Cu" "B.Cu")
		(net "GND")
	)
	(via
		(at 291.749226 -348.704662)
		(size 0.49022)
		(drill 0.254)
		(layers "F.Cu" "B.Cu")
		(net "GND")
	)
	(via
		(at 329.941174 -276.516084)
		(size 0.4064)
		(drill 0.2032)
		(layers "F.Cu" "B.Cu")
		(net "GND")
	)
	(via
		(at 154.157426 -412.570168)
		(size 0.4064)
		(drill 0.2032)
		(layers "F.Cu" "B.Cu")
		(net "GND")
	)
	(via
		(at 119.12473 -275.706332)
		(size 0.4064)
		(drill 0.2032)
		(layers "F.Cu" "B.Cu")
		(net "GND")
	)
	(via
		(at 442.5442 -217.73515)
		(size 0.4826)
		(drill 0.254)
		(layers "F.Cu" "B.Cu")
		(net "GND")
	)
	(via
		(at 18.992342 -315.485272)
		(size 0.4826)
		(drill 0.254)
		(layers "F.Cu" "B.Cu")
		(net "GND")
	)
	(via
		(at 295.724072 -234.735116)
		(size 0.4826)
		(drill 0.254)
		(layers "F.Cu" "B.Cu")
		(net "GND")
	)
	(via
		(at 288.693352 -352.227134)
		(size 0.508)
		(drill 0.254)
		(layers "F.Cu" "B.Cu")
		(net "GND")
	)
	(via
		(at 351.788984 -379.22073)
		(size 0.508)
		(drill 0.254)
		(layers "F.Cu" "B.Cu")
		(net "GND")
	)
	(via
		(at 149.844252 -382.85293)
		(size 0.4064)
		(drill 0.2032)
		(layers "F.Cu" "B.Cu")
		(net "GND")
	)
	(via
		(at 217.524838 -86.296754)
		(size 0.508)
		(drill 0.254)
		(layers "F.Cu" "B.Cu")
		(net "GND")
	)
	(via
		(at 125.040136 -258.830318)
		(size 0.4826)
		(drill 0.254)
		(layers "F.Cu" "B.Cu")
		(net "GND")
	)
	(via
		(at 193.4972 -343.415874)
		(size 0.508)
		(drill 0.254)
		(layers "F.Cu" "B.Cu")
		(net "GND")
	)
	(via
		(at 368.644678 -240.434114)
		(size 0.4064)
		(drill 0.2032)
		(layers "F.Cu" "B.Cu")
		(net "GND")
	)
	(via
		(at 437.715914 -202.434952)
		(size 0.4826)
		(drill 0.254)
		(layers "F.Cu" "B.Cu")
		(net "GND")
	)
	(via
		(at 290.895786 -227.935028)
		(size 0.4826)
		(drill 0.254)
		(layers "F.Cu" "B.Cu")
		(net "GND")
	)
	(via
		(at 424.012106 -213.484968)
		(size 0.4826)
		(drill 0.254)
		(layers "F.Cu" "B.Cu")
		(net "GND")
	)
	(via
		(at 439.378344 -13.849096)
		(size 0.508)
		(drill 0.254)
		(layers "F.Cu" "B.Cu")
		(net "GND")
	)
	(via
		(at 14.549374 -386.914898)
		(size 0.49022)
		(drill 0.254)
		(layers "F.Cu" "B.Cu")
		(net "GND")
	)
	(via
		(at 376.916442 -402.309838)
		(size 0.4572)
		(drill 0.254)
		(layers "F.Cu" "B.Cu")
		(net "GND")
	)
	(via
		(at 134.349744 -436.347362)
		(size 0.4572)
		(drill 0.2032)
		(layers "F.Cu" "B.Cu")
		(net "GND")
	)
	(via
		(at 187.060078 -223.685354)
		(size 0.4826)
		(drill 0.254)
		(layers "F.Cu" "B.Cu")
		(net "GND")
	)
	(via
		(at 291.162486 -294.660066)
		(size 0.4826)
		(drill 0.254)
		(layers "F.Cu" "B.Cu")
		(net "GND")
	)
	(via
		(at 337.019138 -414.752536)
		(size 0.4572)
		(drill 0.254)
		(layers "F.Cu" "B.Cu")
		(net "GND")
	)
	(via
		(at 390.349486 -432.747166)
		(size 0.4572)
		(drill 0.2032)
		(layers "F.Cu" "B.Cu")
		(net "GND")
	)
	(via
		(at 171.97197 -216.035382)
		(size 0.4826)
		(drill 0.254)
		(layers "F.Cu" "B.Cu")
		(net "GND")
	)
	(via
		(at 346.71889 -398.542002)
		(size 0.4064)
		(drill 0.2032)
		(layers "F.Cu" "B.Cu")
		(net "GND")
	)
	(via
		(at 120.064784 -285.426404)
		(size 0.4064)
		(drill 0.2032)
		(layers "F.Cu" "B.Cu")
		(net "GND")
	)
	(via
		(at 156.050234 -410.664152)
		(size 0.4572)
		(drill 0.254)
		(layers "F.Cu" "B.Cu")
		(net "GND")
	)
	(via
		(at 96.74098 -229.90429)
		(size 0.4064)
		(drill 0.2032)
		(layers "F.Cu" "B.Cu")
		(net "GND")
	)
	(via
		(at 138.564874 -222.61449)
		(size 0.4064)
		(drill 0.2032)
		(layers "F.Cu" "B.Cu")
		(net "GND")
	)
	(via
		(at 107.550966 -245.294404)
		(size 0.4064)
		(drill 0.2032)
		(layers "F.Cu" "B.Cu")
		(net "GND")
	)
	(via
		(at 65.975992 -413.204152)
		(size 0.4572)
		(drill 0.254)
		(layers "F.Cu" "B.Cu")
		(net "GND")
	)
	(via
		(at 359.313226 -62.0903)
		(size 0.508)
		(drill 0.254)
		(layers "F.Cu" "B.Cu")
		(net "GND")
	)
	(via
		(at 110.76686 -29.465778)
		(size 0.508)
		(drill 0.254)
		(layers "F.Cu" "B.Cu")
		(net "GND")
	)
	(via
		(at 97.211134 -243.674392)
		(size 0.4064)
		(drill 0.2032)
		(layers "F.Cu" "B.Cu")
		(net "GND")
	)
	(via
		(at 377.549918 -185.988198)
		(size 0.508)
		(drill 0.254)
		(layers "F.Cu" "B.Cu")
		(net "GND")
	)
	(via
		(at 413.485584 -202.01001)
		(size 0.4826)
		(drill 0.254)
		(layers "F.Cu" "B.Cu")
		(net "GND")
	)
	(via
		(at 385.394708 -289.475926)
		(size 0.4064)
		(drill 0.2032)
		(layers "F.Cu" "B.Cu")
		(net "GND")
	)
	(via
		(at 426.90542 -385.999228)
		(size 0.508)
		(drill 0.254)
		(layers "F.Cu" "B.Cu")
		(net "GND")
	)
	(via
		(at 211.502244 -84.081112)
		(size 0.508)
		(drill 0.254)
		(layers "F.Cu" "B.Cu")
		(net "GND")
	)
	(via
		(at 86.871048 -256.634488)
		(size 0.4064)
		(drill 0.2032)
		(layers "F.Cu" "B.Cu")
		(net "GND")
	)
	(via
		(at 332.931008 -237.19409)
		(size 0.4064)
		(drill 0.2032)
		(layers "F.Cu" "B.Cu")
		(net "GND")
	)
	(via
		(at 443.9285 -315.485018)
		(size 0.4826)
		(drill 0.254)
		(layers "F.Cu" "B.Cu")
		(net "GND")
	)
	(via
		(at 65.249806 -427.699678)
		(size 0.4572)
		(drill 0.2032)
		(layers "F.Cu" "B.Cu")
		(net "GND")
	)
	(via
		(at 142.351506 -407.00452)
		(size 0.4064)
		(drill 0.2032)
		(layers "F.Cu" "B.Cu")
		(net "GND")
	)
	(via
		(at 20.67687 -386.03809)
		(size 0.508)
		(drill 0.254)
		(layers "F.Cu" "B.Cu")
		(net "GND")
	)
	(via
		(at 129.31648 -393.877038)
		(size 0.4572)
		(drill 0.254)
		(layers "F.Cu" "B.Cu")
		(net "GND")
	)
	(via
		(at 424.93184 -16.979138)
		(size 0.508)
		(drill 0.254)
		(layers "F.Cu" "B.Cu")
		(net "GND")
	)
	(via
		(at 117.244622 -285.426404)
		(size 0.4064)
		(drill 0.2032)
		(layers "F.Cu" "B.Cu")
		(net "GND")
	)
	(via
		(at 104.08793 -264.36828)
		(size 0.4064)
		(drill 0.2032)
		(layers "F.Cu" "B.Cu")
		(net "GND")
	)
	(via
		(at 52.563014 -368.37493)
		(size 0.508)
		(drill 0.254)
		(layers "F.Cu" "B.Cu")
		(net "GND")
	)
	(via
		(at 235.947712 -326.947022)
		(size 0.508)
		(drill 0.254)
		(layers "F.Cu" "B.Cu")
		(net "GND")
	)
	(via
		(at 290.895786 -293.384986)
		(size 0.4826)
		(drill 0.254)
		(layers "F.Cu" "B.Cu")
		(net "GND")
	)
	(via
		(at 143.06042 -108.333032)
		(size 0.508)
		(drill 0.254)
		(layers "F.Cu" "B.Cu")
		(net "GND")
	)
	(via
		(at 143.56461 -293.52621)
		(size 0.4064)
		(drill 0.2032)
		(layers "F.Cu" "B.Cu")
		(net "GND")
	)
	(via
		(at 2.76225 -367.213134)
		(size 0.508)
		(drill 0.254)
		(layers "F.Cu" "B.Cu")
		(net "GND")
	)
	(via
		(at 55.328058 -242.385342)
		(size 0.4826)
		(drill 0.254)
		(layers "F.Cu" "B.Cu")
		(net "GND")
	)
	(via
		(at 251.06884 -90.10015)
		(size 0.508)
		(drill 0.254)
		(layers "F.Cu" "B.Cu")
		(net "GND")
	)
	(via
		(at 253.60884 -90.10015)
		(size 0.508)
		(drill 0.254)
		(layers "F.Cu" "B.Cu")
		(net "GND")
	)
	(via
		(at 194.604132 -272.135346)
		(size 0.4826)
		(drill 0.254)
		(layers "F.Cu" "B.Cu")
		(net "GND")
	)
	(via
		(at 386.504942 -229.094284)
		(size 0.4064)
		(drill 0.2032)
		(layers "F.Cu" "B.Cu")
		(net "GND")
	)
	(via
		(at 350.306132 -394.831062)
		(size 0.4064)
		(drill 0.2032)
		(layers "F.Cu" "B.Cu")
		(net "GND")
	)
	(via
		(at 55.719218 -346.306902)
		(size 0.49022)
		(drill 0.254)
		(layers "F.Cu" "B.Cu")
		(net "GND")
	)
	(via
		(at 299.82414 -316.335156)
		(size 0.4826)
		(drill 0.254)
		(layers "F.Cu" "B.Cu")
		(net "GND")
	)
	(via
		(at 410.245814 -419.046152)
		(size 0.4572)
		(drill 0.254)
		(layers "F.Cu" "B.Cu")
		(net "GND")
	)
	(via
		(at 371.294914 -292.71595)
		(size 0.4064)
		(drill 0.2032)
		(layers "F.Cu" "B.Cu")
		(net "GND")
	)
	(via
		(at 245.044722 -45.698918)
		(size 0.508)
		(drill 0.254)
		(layers "F.Cu" "B.Cu")
		(net "GND")
	)
	(via
		(at 44.340018 -207.535272)
		(size 0.4826)
		(drill 0.254)
		(layers "F.Cu" "B.Cu")
		(net "GND")
	)
	(via
		(at 335.6102 -164.846)
		(size 0.508)
		(drill 0.254)
		(layers "F.Cu" "B.Cu")
		(net "GND")
	)
	(via
		(at 380.162308 -392.999722)
		(size 0.4064)
		(drill 0.2032)
		(layers "F.Cu" "B.Cu")
		(net "GND")
	)
	(via
		(at 394.349478 -427.851316)
		(size 0.4572)
		(drill 0.2032)
		(layers "F.Cu" "B.Cu")
		(net "GND")
	)
	(via
		(at 147.042886 -281.110436)
		(size 0.4064)
		(drill 0.2032)
		(layers "F.Cu" "B.Cu")
		(net "GND")
	)
	(via
		(at 401.349718 -426.54728)
		(size 0.4572)
		(drill 0.2032)
		(layers "F.Cu" "B.Cu")
		(net "GND")
	)
	(via
		(at 63.416434 -382.85293)
		(size 0.4064)
		(drill 0.2032)
		(layers "F.Cu" "B.Cu")
		(net "GND")
	)
	(via
		(at 376.491246 -398.542002)
		(size 0.4064)
		(drill 0.2032)
		(layers "F.Cu" "B.Cu")
		(net "GND")
	)
	(via
		(at 67.716654 -148.990812)
		(size 0.508)
		(drill 0.254)
		(layers "F.Cu" "B.Cu")
		(net "GND")
	)
	(via
		(at 376.634756 -250.964192)
		(size 0.4064)
		(drill 0.2032)
		(layers "F.Cu" "B.Cu")
		(net "GND")
	)
	(via
		(at 127.114808 -274.896326)
		(size 0.4064)
		(drill 0.2032)
		(layers "F.Cu" "B.Cu")
		(net "GND")
	)
	(via
		(at 90.662506 -183.074818)
		(size 0.49022)
		(drill 0.254)
		(layers "F.Cu" "B.Cu")
		(net "GND")
	)
	(via
		(at 71.938134 -377.132088)
		(size 0.508)
		(drill 0.254)
		(layers "F.Cu" "B.Cu")
		(net "GND")
	)
	(via
		(at 83.580986 -233.144314)
		(size 0.4064)
		(drill 0.2032)
		(layers "F.Cu" "B.Cu")
		(net "GND")
	)
	(via
		(at 96.27108 -250.15444)
		(size 0.4064)
		(drill 0.2032)
		(layers "F.Cu" "B.Cu")
		(net "GND")
	)
	(via
		(at 396.93342 -171.49572)
		(size 0.508)
		(drill 0.254)
		(layers "F.Cu" "B.Cu")
		(net "GND")
	)
	(via
		(at 164.427916 -281.48534)
		(size 0.4826)
		(drill 0.254)
		(layers "F.Cu" "B.Cu")
		(net "GND")
	)
	(via
		(at 400.967702 -420.952168)
		(size 0.4064)
		(drill 0.2032)
		(layers "F.Cu" "B.Cu")
		(net "GND")
	)
	(via
		(at 344.496644 -379.88113)
		(size 0.508)
		(drill 0.254)
		(layers "F.Cu" "B.Cu")
		(net "GND")
	)
	(via
		(at 194.604132 -283.185362)
		(size 0.4826)
		(drill 0.254)
		(layers "F.Cu" "B.Cu")
		(net "GND")
	)
	(via
		(at 103.470202 -340.505288)
		(size 0.49022)
		(drill 0.254)
		(layers "F.Cu" "B.Cu")
		(net "GND")
	)
	(via
		(at 392.13917 -412.212536)
		(size 0.4572)
		(drill 0.254)
		(layers "F.Cu" "B.Cu")
		(net "GND")
	)
	(via
		(at 416.468052 -198.185024)
		(size 0.4826)
		(drill 0.254)
		(layers "F.Cu" "B.Cu")
		(net "GND")
	)
	(via
		(at 86.871048 -225.854514)
		(size 0.4064)
		(drill 0.2032)
		(layers "F.Cu" "B.Cu")
		(net "GND")
	)
	(via
		(at 147.042886 -289.210242)
		(size 0.4064)
		(drill 0.2032)
		(layers "F.Cu" "B.Cu")
		(net "GND")
	)
	(via
		(at 158.39567 -55.696358)
		(size 0.508)
		(drill 0.254)
		(layers "F.Cu" "B.Cu")
		(net "GND")
	)
	(via
		(at 299.066966 -22.747224)
		(size 0.508)
		(drill 0.254)
		(layers "F.Cu" "B.Cu")
		(net "GND")
	)
	(via
		(at 91.571064 -238.814356)
		(size 0.4064)
		(drill 0.2032)
		(layers "F.Cu" "B.Cu")
		(net "GND")
	)
	(via
		(at 50.659792 -411.936184)
		(size 0.4572)
		(drill 0.254)
		(layers "F.Cu" "B.Cu")
		(net "GND")
	)
	(via
		(at 273.092164 -273.835114)
		(size 0.4826)
		(drill 0.254)
		(layers "F.Cu" "B.Cu")
		(net "GND")
	)
	(via
		(at 133.69798 -295.98366)
		(size 0.4064)
		(drill 0.2032)
		(layers "F.Cu" "B.Cu")
		(net "GND")
	)
	(via
		(at 145.444718 -261.126224)
		(size 0.4064)
		(drill 0.2032)
		(layers "F.Cu" "B.Cu")
		(net "GND")
	)
	(via
		(at 21.70811 -196.485256)
		(size 0.4826)
		(drill 0.254)
		(layers "F.Cu" "B.Cu")
		(net "GND")
	)
	(via
		(at 325.052944 -269.770098)
		(size 0.4064)
		(drill 0.2032)
		(layers "F.Cu" "B.Cu")
		(net "GND")
	)
	(via
		(at 435.000146 -197.33514)
		(size 0.4826)
		(drill 0.254)
		(layers "F.Cu" "B.Cu")
		(net "GND")
	)
	(via
		(at 134.164832 -267.606272)
		(size 0.4064)
		(drill 0.2032)
		(layers "F.Cu" "B.Cu")
		(net "GND")
	)
	(via
		(at 356.901242 -236.384084)
		(size 0.4064)
		(drill 0.2032)
		(layers "F.Cu" "B.Cu")
		(net "GND")
	)
	(via
		(at 113.65484 -249.344434)
		(size 0.4064)
		(drill 0.2032)
		(layers "F.Cu" "B.Cu")
		(net "GND")
	)
	(via
		(at 238.634778 -371.474238)
		(size 0.508)
		(drill 0.254)
		(layers "F.Cu" "B.Cu")
		(net "GND")
	)
	(via
		(at 431.55616 -205.834996)
		(size 0.4826)
		(drill 0.254)
		(layers "F.Cu" "B.Cu")
		(net "GND")
	)
	(via
		(at 296.846498 -18.847308)
		(size 0.508)
		(drill 0.254)
		(layers "F.Cu" "B.Cu")
		(net "GND")
	)
	(via
		(at 427.779688 -390.68629)
		(size 0.508)
		(drill 0.254)
		(layers "F.Cu" "B.Cu")
		(net "GND")
	)
	(via
		(at 78.24978 -433.747164)
		(size 0.4572)
		(drill 0.2032)
		(layers "F.Cu" "B.Cu")
		(net "GND")
	)
	(via
		(at 412.367984 -204.985112)
		(size 0.4826)
		(drill 0.254)
		(layers "F.Cu" "B.Cu")
		(net "GND")
	)
	(via
		(at 341.575644 -377.41733)
		(size 0.508)
		(drill 0.254)
		(layers "F.Cu" "B.Cu")
		(net "GND")
	)
	(via
		(at 402.948902 -420.952168)
		(size 0.4064)
		(drill 0.2032)
		(layers "F.Cu" "B.Cu")
		(net "GND")
	)
	(via
		(at 355.491034 -229.094284)
		(size 0.4064)
		(drill 0.2032)
		(layers "F.Cu" "B.Cu")
		(net "GND")
	)
	(via
		(at 125.2347 -294.336216)
		(size 0.4064)
		(drill 0.2032)
		(layers "F.Cu" "B.Cu")
		(net "GND")
	)
	(via
		(at 365.380778 -261.23011)
		(size 0.4826)
		(drill 0.254)
		(layers "F.Cu" "B.Cu")
		(net "GND")
	)
	(via
		(at 347.97111 -240.434114)
		(size 0.4064)
		(drill 0.2032)
		(layers "F.Cu" "B.Cu")
		(net "GND")
	)
	(via
		(at 137.397998 -411.936184)
		(size 0.4572)
		(drill 0.254)
		(layers "F.Cu" "B.Cu")
		(net "GND")
	)
	(via
		(at 245.08841 -288.905696)
		(size 0.508)
		(drill 0.254)
		(layers "F.Cu" "B.Cu")
		(net "GND")
	)
	(via
		(at 44.340018 -235.585254)
		(size 0.4826)
		(drill 0.254)
		(layers "F.Cu" "B.Cu")
		(net "GND")
	)
	(via
		(at 79.760572 -407.638504)
		(size 0.4572)
		(drill 0.254)
		(layers "F.Cu" "B.Cu")
		(net "GND")
	)
	(via
		(at 77.292454 -172.475398)
		(size 0.508)
		(drill 0.254)
		(layers "F.Cu" "B.Cu")
		(net "GND")
	)
	(via
		(at 86.401148 -226.66452)
		(size 0.4064)
		(drill 0.2032)
		(layers "F.Cu" "B.Cu")
		(net "GND")
	)
	(via
		(at 119.82196 -345.96578)
		(size 0.6604)
		(drill 0.3302)
		(layers "F.Cu" "B.Cu")
		(net "GND")
	)
	(via
		(at 342.801194 -229.904036)
		(size 0.4064)
		(drill 0.2032)
		(layers "F.Cu" "B.Cu")
		(net "GND")
	)
	(via
		(at 90.650314 -331.07376)
		(size 0.508)
		(drill 0.254)
		(layers "F.Cu" "B.Cu")
		(net "GND")
	)
	(via
		(at 164.588444 -371.49913)
		(size 0.508)
		(drill 0.254)
		(layers "F.Cu" "B.Cu")
		(net "GND")
	)
	(via
		(at 359.747058 -346.018866)
		(size 0.6604)
		(drill 0.3302)
		(layers "F.Cu" "B.Cu")
		(net "GND")
	)
	(via
		(at 371.93474 -241.24412)
		(size 0.4064)
		(drill 0.2032)
		(layers "F.Cu" "B.Cu")
		(net "GND")
	)
	(via
		(at 124.464826 -242.05438)
		(size 0.4064)
		(drill 0.2032)
		(layers "F.Cu" "B.Cu")
		(net "GND")
	)
	(via
		(at 21.70811 -280.635202)
		(size 0.4826)
		(drill 0.254)
		(layers "F.Cu" "B.Cu")
		(net "GND")
	)
	(via
		(at 147.042886 -261.670292)
		(size 0.4064)
		(drill 0.2032)
		(layers "F.Cu" "B.Cu")
		(net "GND")
	)
	(via
		(at 372.404894 -240.434114)
		(size 0.4064)
		(drill 0.2032)
		(layers "F.Cu" "B.Cu")
		(net "GND")
	)
	(via
		(at 71.277734 -378.836428)
		(size 0.508)
		(drill 0.254)
		(layers "F.Cu" "B.Cu")
		(net "GND")
	)
	(via
		(at 443.9285 -240.685066)
		(size 0.4826)
		(drill 0.254)
		(layers "F.Cu" "B.Cu")
		(net "GND")
	)
	(via
		(at 349.681038 -294.335962)
		(size 0.4064)
		(drill 0.2032)
		(layers "F.Cu" "B.Cu")
		(net "GND")
	)
	(via
		(at 87.171022 -295.146222)
		(size 0.4064)
		(drill 0.2032)
		(layers "F.Cu" "B.Cu")
		(net "GND")
	)
	(via
		(at 281.791664 -194.88531)
		(size 0.4826)
		(drill 0.254)
		(layers "F.Cu" "B.Cu")
		(net "GND")
	)
	(via
		(at 118.354856 -244.484398)
		(size 0.4064)
		(drill 0.2032)
		(layers "F.Cu" "B.Cu")
		(net "GND")
	)
	(via
		(at 380.224792 -261.12597)
		(size 0.4064)
		(drill 0.2032)
		(layers "F.Cu" "B.Cu")
		(net "GND")
	)
	(via
		(at 425.2087 -376.75693)
		(size 0.508)
		(drill 0.254)
		(layers "F.Cu" "B.Cu")
		(net "GND")
	)
	(via
		(at 118.65483 -281.376374)
		(size 0.4064)
		(drill 0.2032)
		(layers "F.Cu" "B.Cu")
		(net "GND")
	)
	(via
		(at 85.160358 -333.82839)
		(size 0.49022)
		(drill 0.254)
		(layers "F.Cu" "B.Cu")
		(net "GND")
	)
	(via
		(at 443.9285 -231.335072)
		(size 0.4826)
		(drill 0.254)
		(layers "F.Cu" "B.Cu")
		(net "GND")
	)
	(via
		(at 36.156138 -18.503138)
		(size 0.508)
		(drill 0.254)
		(layers "F.Cu" "B.Cu")
		(net "GND")
	)
	(via
		(at 130.40487 -278.946356)
		(size 0.4064)
		(drill 0.2032)
		(layers "F.Cu" "B.Cu")
		(net "GND")
	)
	(via
		(at 351.091246 -270.846042)
		(size 0.4064)
		(drill 0.2032)
		(layers "F.Cu" "B.Cu")
		(net "GND")
	)
	(via
		(at 417.393882 -363.611414)
		(size 0.508)
		(drill 0.254)
		(layers "F.Cu" "B.Cu")
		(net "GND")
	)
	(via
		(at 259.247894 -37.23132)
		(size 0.508)
		(drill 0.254)
		(layers "F.Cu" "B.Cu")
		(net "GND")
	)
	(via
		(at 27.105102 -386.866892)
		(size 0.49022)
		(drill 0.254)
		(layers "F.Cu" "B.Cu")
		(net "GND")
	)
	(via
		(at 73.24979 -432.45151)
		(size 0.4572)
		(drill 0.2032)
		(layers "F.Cu" "B.Cu")
		(net "GND")
	)
	(via
		(at 44.056554 -369.03533)
		(size 0.508)
		(drill 0.254)
		(layers "F.Cu" "B.Cu")
		(net "GND")
	)
	(via
		(at 11.537442 -53.904896)
		(size 0.508)
		(drill 0.254)
		(layers "F.Cu" "B.Cu")
		(net "GND")
	)
	(via
		(at 459.861666 -53.8099)
		(size 0.508)
		(drill 0.254)
		(layers "F.Cu" "B.Cu")
		(net "GND")
	)
	(via
		(at 89.903554 -328.13752)
		(size 0.508)
		(drill 0.254)
		(layers "F.Cu" "B.Cu")
		(net "GND")
	)
	(via
		(at 289.335718 -193.10731)
		(size 0.4826)
		(drill 0.254)
		(layers "F.Cu" "B.Cu")
		(net "GND")
	)
	(via
		(at 128.694688 -238.00435)
		(size 0.4064)
		(drill 0.2032)
		(layers "F.Cu" "B.Cu")
		(net "GND")
	)
	(via
		(at 171.97197 -307.8353)
		(size 0.4826)
		(drill 0.254)
		(layers "F.Cu" "B.Cu")
		(net "GND")
	)
	(via
		(at 120.822974 -403.830536)
		(size 0.4572)
		(drill 0.254)
		(layers "F.Cu" "B.Cu")
		(net "GND")
	)
	(via
		(at 76.249784 -432.747166)
		(size 0.4572)
		(drill 0.2032)
		(layers "F.Cu" "B.Cu")
		(net "GND")
	)
	(via
		(at 83.41106 -272.466308)
		(size 0.4064)
		(drill 0.2032)
		(layers "F.Cu" "B.Cu")
		(net "GND")
	)
	(via
		(at 331.521054 -250.964192)
		(size 0.4064)
		(drill 0.2032)
		(layers "F.Cu" "B.Cu")
		(net "GND")
	)
	(via
		(at 332.931008 -243.674138)
		(size 0.4064)
		(drill 0.2032)
		(layers "F.Cu" "B.Cu")
		(net "GND")
	)
	(via
		(at 96.3168 -75.888088)
		(size 0.508)
		(drill 0.254)
		(layers "F.Cu" "B.Cu")
		(net "GND")
	)
	(via
		(at 164.427916 -301.88535)
		(size 0.4826)
		(drill 0.254)
		(layers "F.Cu" "B.Cu")
		(net "GND")
	)
	(via
		(at 459.10881 -14.341094)
		(size 0.508)
		(drill 0.254)
		(layers "F.Cu" "B.Cu")
		(net "GND")
	)
	(via
		(at 344.511122 -269.22603)
		(size 0.4064)
		(drill 0.2032)
		(layers "F.Cu" "B.Cu")
		(net "GND")
	)
	(via
		(at 136.684766 -224.234502)
		(size 0.4064)
		(drill 0.2032)
		(layers "F.Cu" "B.Cu")
		(net "GND")
	)
	(via
		(at 369.584732 -248.534174)
		(size 0.4064)
		(drill 0.2032)
		(layers "F.Cu" "B.Cu")
		(net "GND")
	)
	(via
		(at 55.016654 -382.85293)
		(size 0.4064)
		(drill 0.2032)
		(layers "F.Cu" "B.Cu")
		(net "GND")
	)
	(via
		(at 340.441026 -415.38652)
		(size 0.4064)
		(drill 0.2032)
		(layers "F.Cu" "B.Cu")
		(net "GND")
	)
	(via
		(at 73.95845 -375.30786)
		(size 0.508)
		(drill 0.254)
		(layers "F.Cu" "B.Cu")
		(net "GND")
	)
	(via
		(at 364.071154 -441.227718)
		(size 0.508)
		(drill 0.254)
		(layers "F.Cu" "B.Cu")
		(net "GND")
	)
	(via
		(at 399.885662 -412.84652)
		(size 0.4064)
		(drill 0.2032)
		(layers "F.Cu" "B.Cu")
		(net "GND")
	)
	(via
		(at 83.580986 -249.344434)
		(size 0.4064)
		(drill 0.2032)
		(layers "F.Cu" "B.Cu")
		(net "GND")
	)
	(via
		(at 366.049814 -13.639546)
		(size 0.508)
		(drill 0.254)
		(layers "F.Cu" "B.Cu")
		(net "GND")
	)
	(via
		(at 381.719074 -184.683146)
		(size 0.49022)
		(drill 0.254)
		(layers "F.Cu" "B.Cu")
		(net "GND")
	)
	(via
		(at 205.130654 -332.026514)
		(size 0.508)
		(drill 0.254)
		(layers "F.Cu" "B.Cu")
		(net "GND")
	)
	(via
		(at 342.249506 -433.747164)
		(size 0.4572)
		(drill 0.2032)
		(layers "F.Cu" "B.Cu")
		(net "GND")
	)
	(via
		(at 192.199768 -70.851268)
		(size 0.508)
		(drill 0.254)
		(layers "F.Cu" "B.Cu")
		(net "GND")
	)
	(via
		(at 134.386066 -157.681168)
		(size 0.49022)
		(drill 0.254)
		(layers "F.Cu" "B.Cu")
		(net "GND")
	)
	(via
		(at 386.423154 -441.227718)
		(size 0.508)
		(drill 0.254)
		(layers "F.Cu" "B.Cu")
		(net "GND")
	)
	(via
		(at 106.776266 -180.111146)
		(size 0.49022)
		(drill 0.254)
		(layers "F.Cu" "B.Cu")
		(net "GND")
	)
	(via
		(at 76.812902 -252.850396)
		(size 0.4064)
		(drill 0.2032)
		(layers "F.Cu" "B.Cu")
		(net "GND")
	)
	(via
		(at 77.956156 -406.370536)
		(size 0.4572)
		(drill 0.254)
		(layers "F.Cu" "B.Cu")
		(net "GND")
	)
	(via
		(at 116.304822 -269.226284)
		(size 0.4064)
		(drill 0.2032)
		(layers "F.Cu" "B.Cu")
		(net "GND")
	)
	(via
		(at 390.734804 -223.424242)
		(size 0.4064)
		(drill 0.2032)
		(layers "F.Cu" "B.Cu")
		(net "GND")
	)
	(via
		(at 326.351138 -229.094284)
		(size 0.4064)
		(drill 0.2032)
		(layers "F.Cu" "B.Cu")
		(net "GND")
	)
	(via
		(at 192.277746 -219.860368)
		(size 0.4826)
		(drill 0.254)
		(layers "F.Cu" "B.Cu")
		(net "GND")
	)
	(via
		(at 346.995242 -257.930142)
		(size 0.4826)
		(drill 0.254)
		(layers "F.Cu" "B.Cu")
		(net "GND")
	)
	(via
		(at 352.031046 -282.186126)
		(size 0.4064)
		(drill 0.2032)
		(layers "F.Cu" "B.Cu")
		(net "GND")
	)
	(via
		(at 197.3199 -209.235294)
		(size 0.4826)
		(drill 0.254)
		(layers "F.Cu" "B.Cu")
		(net "GND")
	)
	(via
		(at 371.46484 -240.434114)
		(size 0.4064)
		(drill 0.2032)
		(layers "F.Cu" "B.Cu")
		(net "GND")
	)
	(via
		(at 174.687738 -230.485442)
		(size 0.4826)
		(drill 0.254)
		(layers "F.Cu" "B.Cu")
		(net "GND")
	)
	(via
		(at 308.71541 -344.77706)
		(size 0.49022)
		(drill 0.254)
		(layers "F.Cu" "B.Cu")
		(net "GND")
	)
	(via
		(at 15.180818 -408.78887)
		(size 0.508)
		(drill 0.254)
		(layers "F.Cu" "B.Cu")
		(net "GND")
	)
	(via
		(at 165.545516 -314.210446)
		(size 0.4826)
		(drill 0.254)
		(layers "F.Cu" "B.Cu")
		(net "GND")
	)
	(via
		(at 198.7042 -282.335224)
		(size 0.4826)
		(drill 0.254)
		(layers "F.Cu" "B.Cu")
		(net "GND")
	)
	(via
		(at 372.962424 -392.999722)
		(size 0.4064)
		(drill 0.2032)
		(layers "F.Cu" "B.Cu")
		(net "GND")
	)
	(via
		(at 101.74097 -263.556242)
		(size 0.4064)
		(drill 0.2032)
		(layers "F.Cu" "B.Cu")
		(net "GND")
	)
	(via
		(at 386.334762 -268.416024)
		(size 0.4064)
		(drill 0.2032)
		(layers "F.Cu" "B.Cu")
		(net "GND")
	)
	(via
		(at 53.29682 -351.862898)
		(size 0.508)
		(drill 0.254)
		(layers "F.Cu" "B.Cu")
		(net "GND")
	)
	(via
		(at 334.811116 -243.674138)
		(size 0.4064)
		(drill 0.2032)
		(layers "F.Cu" "B.Cu")
		(net "GND")
	)
	(via
		(at 445.282066 -408.0637)
		(size 0.508)
		(drill 0.254)
		(layers "F.Cu" "B.Cu")
		(net "GND")
	)
	(via
		(at 128.878584 -386.449062)
		(size 0.4064)
		(drill 0.2032)
		(layers "F.Cu" "B.Cu")
		(net "GND")
	)
	(via
		(at 85.290914 -295.146222)
		(size 0.4064)
		(drill 0.2032)
		(layers "F.Cu" "B.Cu")
		(net "GND")
	)
	(via
		(at 187.060078 -269.58544)
		(size 0.4826)
		(drill 0.254)
		(layers "F.Cu" "B.Cu")
		(net "GND")
	)
	(via
		(at 356.901242 -229.904036)
		(size 0.4064)
		(drill 0.2032)
		(layers "F.Cu" "B.Cu")
		(net "GND")
	)
	(via
		(at 173.35627 -200.735438)
		(size 0.4826)
		(drill 0.254)
		(layers "F.Cu" "B.Cu")
		(net "GND")
	)
	(via
		(at 402.619718 -171.838112)
		(size 0.508)
		(drill 0.254)
		(layers "F.Cu" "B.Cu")
		(net "GND")
	)
	(via
		(at 133.694678 -273.276314)
		(size 0.4064)
		(drill 0.2032)
		(layers "F.Cu" "B.Cu")
		(net "GND")
	)
	(via
		(at 233.783886 -233.241596)
		(size 0.4826)
		(drill 0.254)
		(layers "F.Cu" "B.Cu")
		(net "GND")
	)
	(via
		(at 53.816504 -391.830814)
		(size 0.4064)
		(drill 0.2032)
		(layers "F.Cu" "B.Cu")
		(net "GND")
	)
	(via
		(at 284.736032 -235.585)
		(size 0.4826)
		(drill 0.254)
		(layers "F.Cu" "B.Cu")
		(net "GND")
	)
	(via
		(at 274.476464 -296.78503)
		(size 0.4826)
		(drill 0.254)
		(layers "F.Cu" "B.Cu")
		(net "GND")
	)
	(via
		(at 61.559694 -373.30253)
		(size 0.508)
		(drill 0.254)
		(layers "F.Cu" "B.Cu")
		(net "GND")
	)
	(via
		(at 332.30566 -389.47852)
		(size 0.508)
		(drill 0.254)
		(layers "F.Cu" "B.Cu")
		(net "GND")
	)
	(via
		(at 271.308322 -97.456752)
		(size 0.508)
		(drill 0.254)
		(layers "F.Cu" "B.Cu")
		(net "GND")
	)
	(via
		(at 17.608042 -300.185328)
		(size 0.4826)
		(drill 0.254)
		(layers "F.Cu" "B.Cu")
		(net "GND")
	)
	(via
		(at 402.937218 -170.542712)
		(size 0.508)
		(drill 0.254)
		(layers "F.Cu" "B.Cu")
		(net "GND")
	)
	(via
		(at 425.129706 -285.310072)
		(size 0.4826)
		(drill 0.254)
		(layers "F.Cu" "B.Cu")
		(net "GND")
	)
	(via
		(at 399.965164 -19.13636)
		(size 0.508)
		(drill 0.254)
		(layers "F.Cu" "B.Cu")
		(net "GND")
	)
	(via
		(at 116.944648 -240.434368)
		(size 0.4064)
		(drill 0.2032)
		(layers "F.Cu" "B.Cu")
		(net "GND")
	)
	(via
		(at 93.751146 -291.906198)
		(size 0.4064)
		(drill 0.2032)
		(layers "F.Cu" "B.Cu")
		(net "GND")
	)
	(via
		(at 56.712358 -228.78542)
		(size 0.4826)
		(drill 0.254)
		(layers "F.Cu" "B.Cu")
		(net "GND")
	)
	(via
		(at 376.93473 -292.71595)
		(size 0.4064)
		(drill 0.2032)
		(layers "F.Cu" "B.Cu")
		(net "GND")
	)
	(via
		(at 449.82511 -0.762254)
		(size 0.508)
		(drill 0.254)
		(layers "F.Cu" "B.Cu")
		(net "GND")
	)
	(via
		(at 124.464826 -227.474526)
		(size 0.4064)
		(drill 0.2032)
		(layers "F.Cu" "B.Cu")
		(net "GND")
	)
	(via
		(at 381.804926 -232.334054)
		(size 0.4064)
		(drill 0.2032)
		(layers "F.Cu" "B.Cu")
		(net "GND")
	)
	(via
		(at 278.632666 -344.767408)
		(size 0.508)
		(drill 0.254)
		(layers "F.Cu" "B.Cu")
		(net "GND")
	)
	(via
		(at 329.958192 -391.41146)
		(size 0.508)
		(drill 0.254)
		(layers "F.Cu" "B.Cu")
		(net "GND")
	)
	(via
		(at 78.768702 -369.03533)
		(size 0.508)
		(drill 0.254)
		(layers "F.Cu" "B.Cu")
		(net "GND")
	)
	(via
		(at 103.791004 -240.434368)
		(size 0.4064)
		(drill 0.2032)
		(layers "F.Cu" "B.Cu")
		(net "GND")
	)
	(via
		(at 78.228952 -413.204152)
		(size 0.4572)
		(drill 0.254)
		(layers "F.Cu" "B.Cu")
		(net "GND")
	)
	(via
		(at 111.78286 -33.529778)
		(size 0.508)
		(drill 0.254)
		(layers "F.Cu" "B.Cu")
		(net "GND")
	)
	(via
		(at 279.518364 -239.41024)
		(size 0.4826)
		(drill 0.254)
		(layers "F.Cu" "B.Cu")
		(net "GND")
	)
	(via
		(at 193.181986 -349.385636)
		(size 0.49022)
		(drill 0.254)
		(layers "F.Cu" "B.Cu")
		(net "GND")
	)
	(via
		(at 20.193 -436.9943)
		(size 0.508)
		(drill 0.254)
		(layers "F.Cu" "B.Cu")
		(net "GND")
	)
	(via
		(at 166.249858 -436.430166)
		(size 0.508)
		(drill 0.254)
		(layers "F.Cu" "B.Cu")
		(net "GND")
	)
	(via
		(at 99.861116 -278.13635)
		(size 0.4064)
		(drill 0.2032)
		(layers "F.Cu" "B.Cu")
		(net "GND")
	)
	(via
		(at 23.628096 -387.704076)
		(size 0.49022)
		(drill 0.254)
		(layers "F.Cu" "B.Cu")
		(net "GND")
	)
	(via
		(at 160.346136 -388.328662)
		(size 0.4064)
		(drill 0.2032)
		(layers "F.Cu" "B.Cu")
		(net "GND")
	)
	(via
		(at 77.956156 -409.396184)
		(size 0.4572)
		(drill 0.254)
		(layers "F.Cu" "B.Cu")
		(net "GND")
	)
	(via
		(at 269.648178 -272.984976)
		(size 0.4826)
		(drill 0.254)
		(layers "F.Cu" "B.Cu")
		(net "GND")
	)
	(via
		(at 418.88664 -382.34493)
		(size 0.508)
		(drill 0.254)
		(layers "F.Cu" "B.Cu")
		(net "GND")
	)
	(via
		(at 416.54984 -19.771106)
		(size 0.508)
		(drill 0.254)
		(layers "F.Cu" "B.Cu")
		(net "GND")
	)
	(via
		(at 450.088 -307.835046)
		(size 0.4826)
		(drill 0.254)
		(layers "F.Cu" "B.Cu")
		(net "GND")
	)
	(via
		(at 371.818408 -396.710662)
		(size 0.4064)
		(drill 0.2032)
		(layers "F.Cu" "B.Cu")
		(net "GND")
	)
	(via
		(at 456.048872 -107.018836)
		(size 0.508)
		(drill 0.254)
		(layers "F.Cu" "B.Cu")
		(net "GND")
	)
	(via
		(at 153.349706 -426.54728)
		(size 0.4572)
		(drill 0.2032)
		(layers "F.Cu" "B.Cu")
		(net "GND")
	)
	(via
		(at 372.259352 -381.68453)
		(size 0.508)
		(drill 0.254)
		(layers "F.Cu" "B.Cu")
		(net "GND")
	)
	(via
		(at 128.694688 -255.824482)
		(size 0.4064)
		(drill 0.2032)
		(layers "F.Cu" "B.Cu")
		(net "GND")
	)
	(via
		(at 87.168228 -150.19909)
		(size 0.508)
		(drill 0.254)
		(layers "F.Cu" "B.Cu")
		(net "GND")
	)
	(via
		(at 118.824756 -229.094538)
		(size 0.4064)
		(drill 0.2032)
		(layers "F.Cu" "B.Cu")
		(net "GND")
	)
	(via
		(at 57.416446 -382.85293)
		(size 0.4064)
		(drill 0.2032)
		(layers "F.Cu" "B.Cu")
		(net "GND")
	)
	(via
		(at 374.584722 -288.66592)
		(size 0.4064)
		(drill 0.2032)
		(layers "F.Cu" "B.Cu")
		(net "GND")
	)
	(via
		(at 90.461084 -291.096192)
		(size 0.4064)
		(drill 0.2032)
		(layers "F.Cu" "B.Cu")
		(net "GND")
	)
	(via
		(at 119.71655 -391.830814)
		(size 0.4064)
		(drill 0.2032)
		(layers "F.Cu" "B.Cu")
		(net "GND")
	)
	(via
		(at 47.816516 -393.902438)
		(size 0.4572)
		(drill 0.254)
		(layers "F.Cu" "B.Cu")
		(net "GND")
	)
	(via
		(at 74.804524 -404.46452)
		(size 0.4064)
		(drill 0.2032)
		(layers "F.Cu" "B.Cu")
		(net "GND")
	)
	(via
		(at 317.016384 -400.212814)
		(size 0.4064)
		(drill 0.2032)
		(layers "F.Cu" "B.Cu")
		(net "GND")
	)
	(via
		(at 327.591166 -293.525956)
		(size 0.4064)
		(drill 0.2032)
		(layers "F.Cu" "B.Cu")
		(net "GND")
	)
	(via
		(at 344.06332 -362.01096)
		(size 0.508)
		(drill 0.254)
		(layers "F.Cu" "B.Cu")
		(net "GND")
	)
	(via
		(at 119.76481 -243.674392)
		(size 0.4064)
		(drill 0.2032)
		(layers "F.Cu" "B.Cu")
		(net "GND")
	)
	(via
		(at 46.82236 -436.372)
		(size 0.508)
		(drill 0.254)
		(layers "F.Cu" "B.Cu")
		(net "GND")
	)
	(via
		(at 298.090844 -385.38912)
		(size 0.508)
		(drill 0.254)
		(layers "F.Cu" "B.Cu")
		(net "GND")
	)
	(via
		(at 416.468052 -271.284954)
		(size 0.4826)
		(drill 0.254)
		(layers "F.Cu" "B.Cu")
		(net "GND")
	)
	(via
		(at 65.402714 -342.816434)
		(size 0.508)
		(drill 0.254)
		(layers "F.Cu" "B.Cu")
		(net "GND")
	)
	(via
		(at 347.031056 -243.674138)
		(size 0.4064)
		(drill 0.2032)
		(layers "F.Cu" "B.Cu")
		(net "GND")
	)
	(via
		(at 384.349498 -434.899562)
		(size 0.4572)
		(drill 0.2032)
		(layers "F.Cu" "B.Cu")
		(net "GND")
	)
	(via
		(at 188.444378 -228.78542)
		(size 0.4826)
		(drill 0.254)
		(layers "F.Cu" "B.Cu")
		(net "GND")
	)
	(via
		(at 15.920974 -388.493254)
		(size 0.49022)
		(drill 0.254)
		(layers "F.Cu" "B.Cu")
		(net "GND")
	)
	(via
		(at 205.601824 -12.542266)
		(size 0.508)
		(drill 0.254)
		(layers "F.Cu" "B.Cu")
		(net "GND")
	)
	(via
		(at 272.9992 -99.380548)
		(size 0.508)
		(drill 0.254)
		(layers "F.Cu" "B.Cu")
		(net "GND")
	)
	(via
		(at 446.644268 -280.634948)
		(size 0.4826)
		(drill 0.254)
		(layers "F.Cu" "B.Cu")
		(net "GND")
	)
	(via
		(at 194.604132 -301.88535)
		(size 0.4826)
		(drill 0.254)
		(layers "F.Cu" "B.Cu")
		(net "GND")
	)
	(via
		(at 124.464826 -246.914416)
		(size 0.4064)
		(drill 0.2032)
		(layers "F.Cu" "B.Cu")
		(net "GND")
	)
	(via
		(at 100.955094 -257.930396)
		(size 0.4826)
		(drill 0.254)
		(layers "F.Cu" "B.Cu")
		(net "GND")
	)
	(via
		(at 77.112876 -264.910316)
		(size 0.4064)
		(drill 0.2032)
		(layers "F.Cu" "B.Cu")
		(net "GND")
	)
	(via
		(at 303.268126 -204.985112)
		(size 0.4826)
		(drill 0.254)
		(layers "F.Cu" "B.Cu")
		(net "GND")
	)
	(via
		(at 64.332866 -170.867832)
		(size 0.49022)
		(drill 0.254)
		(layers "F.Cu" "B.Cu")
		(net "GND")
	)
	(via
		(at 241.529108 -370.713)
		(size 0.508)
		(drill 0.254)
		(layers "F.Cu" "B.Cu")
		(net "GND")
	)
	(via
		(at 283.351732 -305.28514)
		(size 0.4826)
		(drill 0.254)
		(layers "F.Cu" "B.Cu")
		(net "GND")
	)
	(via
		(at 413.752284 -240.685066)
		(size 0.4826)
		(drill 0.254)
		(layers "F.Cu" "B.Cu")
		(net "GND")
	)
	(via
		(at 102.427786 -338.789264)
		(size 0.49022)
		(drill 0.254)
		(layers "F.Cu" "B.Cu")
		(net "GND")
	)
	(via
		(at 280.635964 -255.135126)
		(size 0.4826)
		(drill 0.254)
		(layers "F.Cu" "B.Cu")
		(net "GND")
	)
	(via
		(at 369.414806 -287.856168)
		(size 0.4064)
		(drill 0.2032)
		(layers "F.Cu" "B.Cu")
		(net "GND")
	)
	(via
		(at 64.629792 -175.7807)
		(size 0.508)
		(drill 0.254)
		(layers "F.Cu" "B.Cu")
		(net "GND")
	)
	(via
		(at 351.091246 -291.905944)
		(size 0.4064)
		(drill 0.2032)
		(layers "F.Cu" "B.Cu")
		(net "GND")
	)
	(via
		(at 319.249552 -427.851316)
		(size 0.4572)
		(drill 0.2032)
		(layers "F.Cu" "B.Cu")
		(net "GND")
	)
	(via
		(at 419.806374 -394.831062)
		(size 0.4064)
		(drill 0.2032)
		(layers "F.Cu" "B.Cu")
		(net "GND")
	)
	(via
		(at 394.982954 -289.209988)
		(size 0.4064)
		(drill 0.2032)
		(layers "F.Cu" "B.Cu")
		(net "GND")
	)
	(via
		(at 116.944648 -235.574332)
		(size 0.4064)
		(drill 0.2032)
		(layers "F.Cu" "B.Cu")
		(net "GND")
	)
	(via
		(at 171.117514 -50.970688)
		(size 0.508)
		(drill 0.254)
		(layers "F.Cu" "B.Cu")
		(net "GND")
	)
	(via
		(at 349.544132 -400.212814)
		(size 0.4064)
		(drill 0.2032)
		(layers "F.Cu" "B.Cu")
		(net "GND")
	)
	(via
		(at 376.634756 -254.204216)
		(size 0.4064)
		(drill 0.2032)
		(layers "F.Cu" "B.Cu")
		(net "GND")
	)
	(via
		(at 390.094724 -278.136096)
		(size 0.4064)
		(drill 0.2032)
		(layers "F.Cu" "B.Cu")
		(net "GND")
	)
	(via
		(at 198.435468 -124.351796)
		(size 0.508)
		(drill 0.254)
		(layers "F.Cu" "B.Cu")
		(net "GND")
	)
	(via
		(at 206.248 -301.035212)
		(size 0.4826)
		(drill 0.254)
		(layers "F.Cu" "B.Cu")
		(net "GND")
	)
	(via
		(at 393.384786 -291.905944)
		(size 0.4064)
		(drill 0.2032)
		(layers "F.Cu" "B.Cu")
		(net "GND")
	)
	(via
		(at 102.211124 -269.226284)
		(size 0.4064)
		(drill 0.2032)
		(layers "F.Cu" "B.Cu")
		(net "GND")
	)
	(via
		(at 339.811106 -262.745982)
		(size 0.4064)
		(drill 0.2032)
		(layers "F.Cu" "B.Cu")
		(net "GND")
	)
	(via
		(at 18.650458 -417.68014)
		(size 0.508)
		(drill 0.254)
		(layers "F.Cu" "B.Cu")
		(net "GND")
	)
	(via
		(at 29.252164 -253.435358)
		(size 0.4826)
		(drill 0.254)
		(layers "F.Cu" "B.Cu")
		(net "GND")
	)
	(via
		(at 104.731058 -232.334308)
		(size 0.4064)
		(drill 0.2032)
		(layers "F.Cu" "B.Cu")
		(net "GND")
	)
	(via
		(at 404.477982 -415.38652)
		(size 0.4064)
		(drill 0.2032)
		(layers "F.Cu" "B.Cu")
		(net "GND")
	)
	(via
		(at 401.009104 -16.979138)
		(size 0.508)
		(drill 0.254)
		(layers "F.Cu" "B.Cu")
		(net "GND")
	)
	(via
		(at 390.094724 -276.516084)
		(size 0.4064)
		(drill 0.2032)
		(layers "F.Cu" "B.Cu")
		(net "GND")
	)
	(via
		(at 329.297792 -389.7122)
		(size 0.508)
		(drill 0.254)
		(layers "F.Cu" "B.Cu")
		(net "GND")
	)
	(via
		(at 359.740454 -249.36196)
		(size 0.4826)
		(drill 0.254)
		(layers "F.Cu" "B.Cu")
		(net "GND")
	)
	(via
		(at 207.3656 -229.210362)
		(size 0.4826)
		(drill 0.254)
		(layers "F.Cu" "B.Cu")
		(net "GND")
	)
	(via
		(at 91.55811 -180.687472)
		(size 0.49022)
		(drill 0.254)
		(layers "F.Cu" "B.Cu")
		(net "GND")
	)
	(via
		(at 180.633624 -304.860452)
		(size 0.4826)
		(drill 0.254)
		(layers "F.Cu" "B.Cu")
		(net "GND")
	)
	(via
		(at 115.534694 -238.00435)
		(size 0.4064)
		(drill 0.2032)
		(layers "F.Cu" "B.Cu")
		(net "GND")
	)
	(via
		(at 127.114808 -281.376374)
		(size 0.4064)
		(drill 0.2032)
		(layers "F.Cu" "B.Cu")
		(net "GND")
	)
	(via
		(at 32.695896 -199.035416)
		(size 0.4826)
		(drill 0.254)
		(layers "F.Cu" "B.Cu")
		(net "GND")
	)
	(via
		(at 145.349722 -437.34736)
		(size 0.4572)
		(drill 0.2032)
		(layers "F.Cu" "B.Cu")
		(net "GND")
	)
	(via
		(at 115.045744 -334.96885)
		(size 0.508)
		(drill 0.254)
		(layers "F.Cu" "B.Cu")
		(net "GND")
	)
	(via
		(at 128.994662 -284.616398)
		(size 0.4064)
		(drill 0.2032)
		(layers "F.Cu" "B.Cu")
		(net "GND")
	)
	(via
		(at 84.082636 -409.396184)
		(size 0.4572)
		(drill 0.254)
		(layers "F.Cu" "B.Cu")
		(net "GND")
	)
	(via
		(at 137.312146 -410.030168)
		(size 0.4064)
		(drill 0.2032)
		(layers "F.Cu" "B.Cu")
		(net "GND")
	)
	(via
		(at 329.561698 -150.014178)
		(size 0.508)
		(drill 0.254)
		(layers "F.Cu" "B.Cu")
		(net "GND")
	)
	(via
		(at 143.73479 -226.66452)
		(size 0.4064)
		(drill 0.2032)
		(layers "F.Cu" "B.Cu")
		(net "GND")
	)
	(via
		(at 59.172094 -335.636616)
		(size 0.508)
		(drill 0.254)
		(layers "F.Cu" "B.Cu")
		(net "GND")
	)
	(via
		(at 306.250594 -285.310072)
		(size 0.4826)
		(drill 0.254)
		(layers "F.Cu" "B.Cu")
		(net "GND")
	)
	(via
		(at 323.234558 -413.480504)
		(size 0.4572)
		(drill 0.254)
		(layers "F.Cu" "B.Cu")
		(net "GND")
	)
	(via
		(at 36.900358 -344.781886)
		(size 0.49022)
		(drill 0.254)
		(layers "F.Cu" "B.Cu")
		(net "GND")
	)
	(via
		(at 372.404894 -227.474272)
		(size 0.4064)
		(drill 0.2032)
		(layers "F.Cu" "B.Cu")
		(net "GND")
	)
	(via
		(at 128.208278 -405.098504)
		(size 0.4572)
		(drill 0.254)
		(layers "F.Cu" "B.Cu")
		(net "GND")
	)
	(via
		(at 410.64434 -391.23493)
		(size 0.4064)
		(drill 0.2032)
		(layers "F.Cu" "B.Cu")
		(net "GND")
	)
	(via
		(at 385.69773 -189.514226)
		(size 0.508)
		(drill 0.254)
		(layers "F.Cu" "B.Cu")
		(net "GND")
	)
	(via
		(at 419.912038 -214.335106)
		(size 0.4826)
		(drill 0.254)
		(layers "F.Cu" "B.Cu")
		(net "GND")
	)
	(via
		(at 140.397992 -381.3302)
		(size 0.508)
		(drill 0.254)
		(layers "F.Cu" "B.Cu")
		(net "GND")
	)
	(via
		(at 100.331016 -270.846296)
		(size 0.4064)
		(drill 0.2032)
		(layers "F.Cu" "B.Cu")
		(net "GND")
	)
	(via
		(at 391.897108 -138.084814)
		(size 0.508)
		(drill 0.254)
		(layers "F.Cu" "B.Cu")
		(net "GND")
	)
	(via
		(at 299.82414 -226.235006)
		(size 0.4826)
		(drill 0.254)
		(layers "F.Cu" "B.Cu")
		(net "GND")
	)
	(via
		(at 407.349706 -432.747166)
		(size 0.4572)
		(drill 0.2032)
		(layers "F.Cu" "B.Cu")
		(net "GND")
	)
	(via
		(at 376.93473 -281.37612)
		(size 0.4064)
		(drill 0.2032)
		(layers "F.Cu" "B.Cu")
		(net "GND")
	)
	(via
		(at 176.072038 -280.635202)
		(size 0.4826)
		(drill 0.254)
		(layers "F.Cu" "B.Cu")
		(net "GND")
	)
	(via
		(at 207.345788 -72.229726)
		(size 0.508)
		(drill 0.254)
		(layers "F.Cu" "B.Cu")
		(net "GND")
	)
	(via
		(at 74.34707 -147.38985)
		(size 0.508)
		(drill 0.254)
		(layers "F.Cu" "B.Cu")
		(net "GND")
	)
	(via
		(at 79.487776 -413.204152)
		(size 0.4572)
		(drill 0.254)
		(layers "F.Cu" "B.Cu")
		(net "GND")
	)
	(via
		(at 71.09333 -180.209698)
		(size 0.508)
		(drill 0.254)
		(layers "F.Cu" "B.Cu")
		(net "GND")
	)
	(via
		(at 122.584718 -225.854514)
		(size 0.4064)
		(drill 0.2032)
		(layers "F.Cu" "B.Cu")
		(net "GND")
	)
	(via
		(at 332.785466 -420.952168)
		(size 0.4064)
		(drill 0.2032)
		(layers "F.Cu" "B.Cu")
		(net "GND")
	)
	(via
		(at 308.437026 -347.282262)
		(size 0.49022)
		(drill 0.254)
		(layers "F.Cu" "B.Cu")
		(net "GND")
	)
	(via
		(at 61.862462 -384.617722)
		(size 0.4064)
		(drill 0.2032)
		(layers "F.Cu" "B.Cu")
		(net "GND")
	)
	(via
		(at 307.819806 -347.282262)
		(size 0.49022)
		(drill 0.254)
		(layers "F.Cu" "B.Cu")
		(net "GND")
	)
	(via
		(at 407.349706 -436.347362)
		(size 0.4572)
		(drill 0.2032)
		(layers "F.Cu" "B.Cu")
		(net "GND")
	)
	(via
		(at 135.574786 -292.716204)
		(size 0.4064)
		(drill 0.2032)
		(layers "F.Cu" "B.Cu")
		(net "GND")
	)
	(via
		(at 259.063744 -53.457602)
		(size 0.508)
		(drill 0.254)
		(layers "F.Cu" "B.Cu")
		(net "GND")
	)
	(via
		(at 361.288076 -256.387346)
		(size 0.4826)
		(drill 0.254)
		(layers "F.Cu" "B.Cu")
		(net "GND")
	)
	(via
		(at 405.376888 -6.091174)
		(size 0.508)
		(drill 0.254)
		(layers "F.Cu" "B.Cu")
		(net "GND")
	)
	(via
		(at 101.512878 -138.91641)
		(size 0.762)
		(drill 0.254)
		(layers "F.Cu" "B.Cu")
		(net "GND")
	)
	(via
		(at 143.693642 -385.58216)
		(size 0.508)
		(drill 0.254)
		(layers "F.Cu" "B.Cu")
		(net "GND")
	)
	(via
		(at 336.22107 -236.384084)
		(size 0.4064)
		(drill 0.2032)
		(layers "F.Cu" "B.Cu")
		(net "GND")
	)
	(via
		(at 233.651044 -43.053)
		(size 0.508)
		(drill 0.254)
		(layers "F.Cu" "B.Cu")
		(net "GND")
	)
	(via
		(at 174.687738 -284.035246)
		(size 0.4826)
		(drill 0.254)
		(layers "F.Cu" "B.Cu")
		(net "GND")
	)
	(via
		(at 351.731072 -229.094284)
		(size 0.4064)
		(drill 0.2032)
		(layers "F.Cu" "B.Cu")
		(net "GND")
	)
	(via
		(at 51.71567 -158.08579)
		(size 0.508)
		(drill 0.254)
		(layers "F.Cu" "B.Cu")
		(net "GND")
	)
	(via
		(at 189.899798 -135.857996)
		(size 0.508)
		(drill 0.254)
		(layers "F.Cu" "B.Cu")
		(net "GND")
	)
	(via
		(at 435.7497 -26.142442)
		(size 0.508)
		(drill 0.254)
		(layers "F.Cu" "B.Cu")
		(net "GND")
	)
	(via
		(at 268.207236 -97.913952)
		(size 0.508)
		(drill 0.254)
		(layers "F.Cu" "B.Cu")
		(net "GND")
	)
	(via
		(at 411.41904 -398.542002)
		(size 0.4064)
		(drill 0.2032)
		(layers "F.Cu" "B.Cu")
		(net "GND")
	)
	(via
		(at 108.097066 -178.57089)
		(size 0.49022)
		(drill 0.254)
		(layers "F.Cu" "B.Cu")
		(net "GND")
	)
	(via
		(at 29.252164 -288.285428)
		(size 0.4826)
		(drill 0.254)
		(layers "F.Cu" "B.Cu")
		(net "GND")
	)
	(via
		(at 273.092164 -262.785098)
		(size 0.4826)
		(drill 0.254)
		(layers "F.Cu" "B.Cu")
		(net "GND")
	)
	(via
		(at 415.170874 -165.70706)
		(size 0.49022)
		(drill 0.254)
		(layers "F.Cu" "B.Cu")
		(net "GND")
	)
	(via
		(at 386.349494 -438.651396)
		(size 0.4572)
		(drill 0.2032)
		(layers "F.Cu" "B.Cu")
		(net "GND")
	)
	(via
		(at 62.912752 -411.936184)
		(size 0.4572)
		(drill 0.254)
		(layers "F.Cu" "B.Cu")
		(net "GND")
	)
	(via
		(at 415.11347 -414.72866)
		(size 0.4572)
		(drill 0.254)
		(layers "F.Cu" "B.Cu")
		(net "GND")
	)
	(via
		(at 142.154656 -294.336216)
		(size 0.4064)
		(drill 0.2032)
		(layers "F.Cu" "B.Cu")
		(net "GND")
	)
	(via
		(at 106.596942 -336.034634)
		(size 0.508)
		(drill 0.254)
		(layers "F.Cu" "B.Cu")
		(net "GND")
	)
	(via
		(at 467.5378 -99.619054)
		(size 0.508)
		(drill 0.254)
		(layers "F.Cu" "B.Cu")
		(net "GND")
	)
	(via
		(at 94.718124 -410.030168)
		(size 0.4064)
		(drill 0.2032)
		(layers "F.Cu" "B.Cu")
		(net "GND")
	)
	(via
		(at 206.248 -272.98523)
		(size 0.4826)
		(drill 0.254)
		(layers "F.Cu" "B.Cu")
		(net "GND")
	)
	(via
		(at 344.681048 -244.484144)
		(size 0.4064)
		(drill 0.2032)
		(layers "F.Cu" "B.Cu")
		(net "GND")
	)
	(via
		(at 86.401148 -246.10441)
		(size 0.4064)
		(drill 0.2032)
		(layers "F.Cu" "B.Cu")
		(net "GND")
	)
	(via
		(at 356.261162 -276.516084)
		(size 0.4064)
		(drill 0.2032)
		(layers "F.Cu" "B.Cu")
		(net "GND")
	)
	(via
		(at 370.524786 -250.154186)
		(size 0.4064)
		(drill 0.2032)
		(layers "F.Cu" "B.Cu")
		(net "GND")
	)
	(via
		(at 384.349498 -438.499758)
		(size 0.4572)
		(drill 0.2032)
		(layers "F.Cu" "B.Cu")
		(net "GND")
	)
	(via
		(at 297.108372 -296.78503)
		(size 0.4826)
		(drill 0.254)
		(layers "F.Cu" "B.Cu")
		(net "GND")
	)
	(via
		(at 339.582252 -167.950134)
		(size 0.6604)
		(drill 0.3302)
		(layers "F.Cu" "B.Cu")
		(net "GND")
	)
	(via
		(at 402.917914 -77.913484)
		(size 0.508)
		(drill 0.254)
		(layers "F.Cu" "B.Cu")
		(net "GND")
	)
	(via
		(at 396.409926 -6.598158)
		(size 0.508)
		(drill 0.254)
		(layers "F.Cu" "B.Cu")
		(net "GND")
	)
	(via
		(at 85.820758 -333.039212)
		(size 0.49022)
		(drill 0.254)
		(layers "F.Cu" "B.Cu")
		(net "GND")
	)
	(via
		(at 403.349714 -432.747166)
		(size 0.4572)
		(drill 0.2032)
		(layers "F.Cu" "B.Cu")
		(net "GND")
	)
	(via
		(at 378.514864 -247.724168)
		(size 0.4064)
		(drill 0.2032)
		(layers "F.Cu" "B.Cu")
		(net "GND")
	)
	(via
		(at 114.297968 -261.323074)
		(size 0.4826)
		(drill 0.254)
		(layers "F.Cu" "B.Cu")
		(net "GND")
	)
	(via
		(at 419.332918 -167.012112)
		(size 0.508)
		(drill 0.254)
		(layers "F.Cu" "B.Cu")
		(net "GND")
	)
	(via
		(at 347.33103 -278.946102)
		(size 0.4064)
		(drill 0.2032)
		(layers "F.Cu" "B.Cu")
		(net "GND")
	)
	(via
		(at 336.22107 -234.764072)
		(size 0.4064)
		(drill 0.2032)
		(layers "F.Cu" "B.Cu")
		(net "GND")
	)
	(via
		(at 339.811106 -282.186126)
		(size 0.4064)
		(drill 0.2032)
		(layers "F.Cu" "B.Cu")
		(net "GND")
	)
	(via
		(at 428.840392 -278.085042)
		(size 0.4826)
		(drill 0.254)
		(layers "F.Cu" "B.Cu")
		(net "GND")
	)
	(via
		(at 121.174764 -236.384338)
		(size 0.4064)
		(drill 0.2032)
		(layers "F.Cu" "B.Cu")
		(net "GND")
	)
	(via
		(at 447.761868 -285.310072)
		(size 0.4826)
		(drill 0.254)
		(layers "F.Cu" "B.Cu")
		(net "GND")
	)
	(via
		(at 102.681024 -284.616398)
		(size 0.4064)
		(drill 0.2032)
		(layers "F.Cu" "B.Cu")
		(net "GND")
	)
	(via
		(at 384.48107 -419.046152)
		(size 0.4572)
		(drill 0.254)
		(layers "F.Cu" "B.Cu")
		(net "GND")
	)
	(via
		(at 113.184686 -243.674392)
		(size 0.4064)
		(drill 0.2032)
		(layers "F.Cu" "B.Cu")
		(net "GND")
	)
	(via
		(at 116.259356 -373.30253)
		(size 0.508)
		(drill 0.254)
		(layers "F.Cu" "B.Cu")
		(net "GND")
	)
	(via
		(at 373.486934 -414.752536)
		(size 0.4572)
		(drill 0.254)
		(layers "F.Cu" "B.Cu")
		(net "GND")
	)
	(via
		(at 222.965518 -275.502878)
		(size 0.508)
		(drill 0.254)
		(layers "F.Cu" "B.Cu")
		(net "GND")
	)
	(via
		(at 290.514786 -348.704662)
		(size 0.49022)
		(drill 0.254)
		(layers "F.Cu" "B.Cu")
		(net "GND")
	)
	(via
		(at 94.861126 -239.624362)
		(size 0.4064)
		(drill 0.2032)
		(layers "F.Cu" "B.Cu")
		(net "GND")
	)
	(via
		(at 435.000146 -298.485052)
		(size 0.4826)
		(drill 0.254)
		(layers "F.Cu" "B.Cu")
		(net "GND")
	)
	(via
		(at 198.7042 -316.33541)
		(size 0.4826)
		(drill 0.254)
		(layers "F.Cu" "B.Cu")
		(net "GND")
	)
	(via
		(at 403.349714 -431.451258)
		(size 0.4572)
		(drill 0.2032)
		(layers "F.Cu" "B.Cu")
		(net "GND")
	)
	(via
		(at 306.820316 -426.826426)
		(size 0.508)
		(drill 0.254)
		(layers "F.Cu" "B.Cu")
		(net "GND")
	)
	(via
		(at 457.628752 -393.540234)
		(size 0.508)
		(drill 0.254)
		(layers "F.Cu" "B.Cu")
		(net "GND")
	)
	(via
		(at 448.625976 -23.792942)
		(size 0.508)
		(drill 0.254)
		(layers "F.Cu" "B.Cu")
		(net "GND")
	)
	(via
		(at 88.744298 -393.902438)
		(size 0.4572)
		(drill 0.254)
		(layers "F.Cu" "B.Cu")
		(net "GND")
	)
	(via
		(at 309.449978 -414.752536)
		(size 0.4572)
		(drill 0.254)
		(layers "F.Cu" "B.Cu")
		(net "GND")
	)
	(via
		(at 163.868354 -17.654778)
		(size 0.508)
		(drill 0.254)
		(layers "F.Cu" "B.Cu")
		(net "GND")
	)
	(via
		(at 31.468314 -343.476834)
		(size 0.508)
		(drill 0.254)
		(layers "F.Cu" "B.Cu")
		(net "GND")
	)
	(via
		(at 425.73194 -102.660958)
		(size 0.6604)
		(drill 0.3302)
		(layers "F.Cu" "B.Cu")
		(net "GND")
	)
	(via
		(at 180.900324 -212.635338)
		(size 0.4826)
		(drill 0.254)
		(layers "F.Cu" "B.Cu")
		(net "GND")
	)
	(via
		(at 419.912038 -197.33514)
		(size 0.4826)
		(drill 0.254)
		(layers "F.Cu" "B.Cu")
		(net "GND")
	)
	(via
		(at 154.245818 -406.370536)
		(size 0.4572)
		(drill 0.254)
		(layers "F.Cu" "B.Cu")
		(net "GND")
	)
	(via
		(at 457.969366 -376.53087)
		(size 0.508)
		(drill 0.254)
		(layers "F.Cu" "B.Cu")
		(net "GND")
	)
	(via
		(at 379.069092 -379.88113)
		(size 0.508)
		(drill 0.254)
		(layers "F.Cu" "B.Cu")
		(net "GND")
	)
	(via
		(at 345.07932 -362.01096)
		(size 0.508)
		(drill 0.254)
		(layers "F.Cu" "B.Cu")
		(net "GND")
	)
	(via
		(at 426.24502 -385.514088)
		(size 0.508)
		(drill 0.254)
		(layers "F.Cu" "B.Cu")
		(net "GND")
	)
	(via
		(at 116.747036 -370.83873)
		(size 0.508)
		(drill 0.254)
		(layers "F.Cu" "B.Cu")
		(net "GND")
	)
	(via
		(at 196.458078 -63.447168)
		(size 0.508)
		(drill 0.254)
		(layers "F.Cu" "B.Cu")
		(net "GND")
	)
	(via
		(at 276.074632 -275.960078)
		(size 0.4826)
		(drill 0.254)
		(layers "F.Cu" "B.Cu")
		(net "GND")
	)
	(via
		(at 332.931008 -256.634234)
		(size 0.4064)
		(drill 0.2032)
		(layers "F.Cu" "B.Cu")
		(net "GND")
	)
	(via
		(at 421.92194 -110.280958)
		(size 0.508)
		(drill 0.254)
		(layers "F.Cu" "B.Cu")
		(net "GND")
	)
	(via
		(at 121.174764 -226.66452)
		(size 0.4064)
		(drill 0.2032)
		(layers "F.Cu" "B.Cu")
		(net "GND")
	)
	(via
		(at 53.25999 -18.503138)
		(size 0.508)
		(drill 0.254)
		(layers "F.Cu" "B.Cu")
		(net "GND")
	)
	(via
		(at 363.474762 -250.964192)
		(size 0.4064)
		(drill 0.2032)
		(layers "F.Cu" "B.Cu")
		(net "GND")
	)
	(via
		(at 151.303228 -11.389868)
		(size 0.508)
		(drill 0.254)
		(layers "F.Cu" "B.Cu")
		(net "GND")
	)
	(via
		(at 179.516024 -227.085398)
		(size 0.4826)
		(drill 0.254)
		(layers "F.Cu" "B.Cu")
		(net "GND")
	)
	(via
		(at 276.074632 -304.01006)
		(size 0.4826)
		(drill 0.254)
		(layers "F.Cu" "B.Cu")
		(net "GND")
	)
	(via
		(at 69.249798 -436.051198)
		(size 0.4572)
		(drill 0.2032)
		(layers "F.Cu" "B.Cu")
		(net "GND")
	)
	(via
		(at 347.50121 -231.524048)
		(size 0.4064)
		(drill 0.2032)
		(layers "F.Cu" "B.Cu")
		(net "GND")
	)
	(via
		(at 13.656818 -408.78887)
		(size 0.508)
		(drill 0.254)
		(layers "F.Cu" "B.Cu")
		(net "GND")
	)
	(via
		(at 440.217814 -304.01006)
		(size 0.4826)
		(drill 0.254)
		(layers "F.Cu" "B.Cu")
		(net "GND")
	)
	(via
		(at 91.571064 -243.674392)
		(size 0.4064)
		(drill 0.2032)
		(layers "F.Cu" "B.Cu")
		(net "GND")
	)
	(via
		(at 237.616238 -51.565048)
		(size 0.508)
		(drill 0.254)
		(layers "F.Cu" "B.Cu")
		(net "GND")
	)
	(via
		(at 110.671102 -272.466308)
		(size 0.4064)
		(drill 0.2032)
		(layers "F.Cu" "B.Cu")
		(net "GND")
	)
	(via
		(at 129.876296 -371.49913)
		(size 0.508)
		(drill 0.254)
		(layers "F.Cu" "B.Cu")
		(net "GND")
	)
	(via
		(at 32.097218 -18.247868)
		(size 0.508)
		(drill 0.254)
		(layers "F.Cu" "B.Cu")
		(net "GND")
	)
	(via
		(at 419.430454 -350.20631)
		(size 0.49022)
		(drill 0.254)
		(layers "F.Cu" "B.Cu")
		(net "GND")
	)
	(via
		(at 398.083278 -175.182784)
		(size 0.49022)
		(drill 0.254)
		(layers "F.Cu" "B.Cu")
		(net "GND")
	)
	(via
		(at 368.944906 -288.66592)
		(size 0.4064)
		(drill 0.2032)
		(layers "F.Cu" "B.Cu")
		(net "GND")
	)
	(via
		(at 363.33811 -345.70924)
		(size 0.508)
		(drill 0.254)
		(layers "F.Cu" "B.Cu")
		(net "GND")
	)
	(via
		(at 467.5378 -384.607054)
		(size 0.508)
		(drill 0.254)
		(layers "F.Cu" "B.Cu")
		(net "GND")
	)
	(via
		(at 363.774736 -284.616144)
		(size 0.4064)
		(drill 0.2032)
		(layers "F.Cu" "B.Cu")
		(net "GND")
	)
	(via
		(at 443.119256 -396.09522)
		(size 0.49022)
		(drill 0.254)
		(layers "F.Cu" "B.Cu")
		(net "GND")
	)
	(via
		(at 339.511132 -251.774198)
		(size 0.4064)
		(drill 0.2032)
		(layers "F.Cu" "B.Cu")
		(net "GND")
	)
	(via
		(at 112.397794 -256.3876)
		(size 0.4826)
		(drill 0.254)
		(layers "F.Cu" "B.Cu")
		(net "GND")
	)
	(via
		(at 321.462146 -392.999722)
		(size 0.4064)
		(drill 0.2032)
		(layers "F.Cu" "B.Cu")
		(net "GND")
	)
	(via
		(at 396.648178 -9.424924)
		(size 0.508)
		(drill 0.254)
		(layers "F.Cu" "B.Cu")
		(net "GND")
	)
	(via
		(at 151.541226 -410.030168)
		(size 0.4064)
		(drill 0.2032)
		(layers "F.Cu" "B.Cu")
		(net "GND")
	)
	(via
		(at 241.647218 -232.066592)
		(size 0.4826)
		(drill 0.254)
		(layers "F.Cu" "B.Cu")
		(net "GND")
	)
	(via
		(at 55.328058 -214.33536)
		(size 0.4826)
		(drill 0.254)
		(layers "F.Cu" "B.Cu")
		(net "GND")
	)
	(via
		(at 79.651098 -269.226284)
		(size 0.4064)
		(drill 0.2032)
		(layers "F.Cu" "B.Cu")
		(net "GND")
	)
	(via
		(at 144.527016 -58.057034)
		(size 0.508)
		(drill 0.254)
		(layers "F.Cu" "B.Cu")
		(net "GND")
	)
	(via
		(at 62.998604 -407.00452)
		(size 0.4064)
		(drill 0.2032)
		(layers "F.Cu" "B.Cu")
		(net "GND")
	)
	(via
		(at 85.144356 -382.85293)
		(size 0.4064)
		(drill 0.2032)
		(layers "F.Cu" "B.Cu")
		(net "GND")
	)
	(via
		(at 357.527098 -168.930066)
		(size 0.49022)
		(drill 0.254)
		(layers "F.Cu" "B.Cu")
		(net "GND")
	)
	(via
		(at 78.41107 -225.854514)
		(size 0.4064)
		(drill 0.2032)
		(layers "F.Cu" "B.Cu")
		(net "GND")
	)
	(via
		(at 195.988432 -315.485272)
		(size 0.4826)
		(drill 0.254)
		(layers "F.Cu" "B.Cu")
		(net "GND")
	)
	(via
		(at 353.488244 -379.88113)
		(size 0.508)
		(drill 0.254)
		(layers "F.Cu" "B.Cu")
		(net "GND")
	)
	(via
		(at 378.04471 -225.85426)
		(size 0.4064)
		(drill 0.2032)
		(layers "F.Cu" "B.Cu")
		(net "GND")
	)
	(via
		(at 173.35627 -221.985332)
		(size 0.4826)
		(drill 0.254)
		(layers "F.Cu" "B.Cu")
		(net "GND")
	)
	(via
		(at 361.288076 -261.32282)
		(size 0.4826)
		(drill 0.254)
		(layers "F.Cu" "B.Cu")
		(net "GND")
	)
	(via
		(at 246.022876 -327.201022)
		(size 0.508)
		(drill 0.254)
		(layers "F.Cu" "B.Cu")
		(net "GND")
	)
	(via
		(at 189.28461 -349.381572)
		(size 0.49022)
		(drill 0.254)
		(layers "F.Cu" "B.Cu")
		(net "GND")
	)
	(via
		(at 25.152096 -309.535322)
		(size 0.4826)
		(drill 0.254)
		(layers "F.Cu" "B.Cu")
		(net "GND")
	)
	(via
		(at 129.596642 -73.41489)
		(size 0.508)
		(drill 0.254)
		(layers "F.Cu" "B.Cu")
		(net "GND")
	)
	(via
		(at 94.861126 -226.66452)
		(size 0.4064)
		(drill 0.2032)
		(layers "F.Cu" "B.Cu")
		(net "GND")
	)
	(via
		(at 230.244142 -294.277796)
		(size 0.508)
		(drill 0.254)
		(layers "F.Cu" "B.Cu")
		(net "GND")
	)
	(via
		(at 69.619114 -328.10196)
		(size 0.508)
		(drill 0.254)
		(layers "F.Cu" "B.Cu")
		(net "GND")
	)
	(via
		(at 390.094724 -291.095938)
		(size 0.4064)
		(drill 0.2032)
		(layers "F.Cu" "B.Cu")
		(net "GND")
	)
	(via
		(at 403.610064 -6.598158)
		(size 0.508)
		(drill 0.254)
		(layers "F.Cu" "B.Cu")
		(net "GND")
	)
	(via
		(at 118.861078 -172.80001)
		(size 0.49022)
		(drill 0.254)
		(layers "F.Cu" "B.Cu")
		(net "GND")
	)
	(via
		(at 326.351138 -251.774198)
		(size 0.4064)
		(drill 0.2032)
		(layers "F.Cu" "B.Cu")
		(net "GND")
	)
	(via
		(at 265.494516 -132.352796)
		(size 0.508)
		(drill 0.254)
		(layers "F.Cu" "B.Cu")
		(net "GND")
	)
	(via
		(at 179.162964 -427.752256)
		(size 0.508)
		(drill 0.254)
		(layers "F.Cu" "B.Cu")
		(net "GND")
	)
	(via
		(at 347.97111 -255.014222)
		(size 0.4064)
		(drill 0.2032)
		(layers "F.Cu" "B.Cu")
		(net "GND")
	)
	(via
		(at 162.265106 -404.46452)
		(size 0.4064)
		(drill 0.2032)
		(layers "F.Cu" "B.Cu")
		(net "GND")
	)
	(via
		(at 371.360446 -184.683146)
		(size 0.49022)
		(drill 0.254)
		(layers "F.Cu" "B.Cu")
		(net "GND")
	)
	(via
		(at 282.020264 -284.88513)
		(size 0.4826)
		(drill 0.254)
		(layers "F.Cu" "B.Cu")
		(net "GND")
	)
	(via
		(at 17.608042 -272.135346)
		(size 0.4826)
		(drill 0.254)
		(layers "F.Cu" "B.Cu")
		(net "GND")
	)
	(via
		(at 255.927098 -197.70852)
		(size 0.508)
		(drill 0.254)
		(layers "F.Cu" "B.Cu")
		(net "GND")
	)
	(via
		(at 457.969366 -378.81687)
		(size 0.508)
		(drill 0.254)
		(layers "F.Cu" "B.Cu")
		(net "GND")
	)
	(via
		(at 113.184686 -238.814356)
		(size 0.4064)
		(drill 0.2032)
		(layers "F.Cu" "B.Cu")
		(net "GND")
	)
	(via
		(at 167.143684 -302.735234)
		(size 0.4826)
		(drill 0.254)
		(layers "F.Cu" "B.Cu")
		(net "GND")
	)
	(via
		(at 195.988432 -210.085432)
		(size 0.4826)
		(drill 0.254)
		(layers "F.Cu" "B.Cu")
		(net "GND")
	)
	(via
		(at 215.55964 -165.386258)
		(size 0.508)
		(drill 0.254)
		(layers "F.Cu" "B.Cu")
		(net "GND")
	)
	(via
		(at 381.334772 -238.004096)
		(size 0.4064)
		(drill 0.2032)
		(layers "F.Cu" "B.Cu")
		(net "GND")
	)
	(via
		(at 435.000146 -242.385088)
		(size 0.4826)
		(drill 0.254)
		(layers "F.Cu" "B.Cu")
		(net "GND")
	)
	(via
		(at 410.604462 -415.38652)
		(size 0.4064)
		(drill 0.2032)
		(layers "F.Cu" "B.Cu")
		(net "GND")
	)
	(via
		(at 180.957982 -349.356172)
		(size 0.49022)
		(drill 0.254)
		(layers "F.Cu" "B.Cu")
		(net "GND")
	)
	(via
		(at 369.687094 -402.734018)
		(size 0.508)
		(drill 0.254)
		(layers "F.Cu" "B.Cu")
		(net "GND")
	)
	(via
		(at 163.746942 -108.157264)
		(size 0.508)
		(drill 0.254)
		(layers "F.Cu" "B.Cu")
		(net "GND")
	)
	(via
		(at 347.906086 -394.831062)
		(size 0.4064)
		(drill 0.2032)
		(layers "F.Cu" "B.Cu")
		(net "GND")
	)
	(via
		(at 104.635808 -33.718754)
		(size 0.508)
		(drill 0.254)
		(layers "F.Cu" "B.Cu")
		(net "GND")
	)
	(via
		(at 385.094734 -226.664266)
		(size 0.4064)
		(drill 0.2032)
		(layers "F.Cu" "B.Cu")
		(net "GND")
	)
	(via
		(at 349.851218 -227.474272)
		(size 0.4064)
		(drill 0.2032)
		(layers "F.Cu" "B.Cu")
		(net "GND")
	)
	(via
		(at 339.981032 -225.044254)
		(size 0.4064)
		(drill 0.2032)
		(layers "F.Cu" "B.Cu")
		(net "GND")
	)
	(via
		(at 117.44071 -261.230364)
		(size 0.4826)
		(drill 0.254)
		(layers "F.Cu" "B.Cu")
		(net "GND")
	)
	(via
		(at 320.19113 -398.542002)
		(size 0.4064)
		(drill 0.2032)
		(layers "F.Cu" "B.Cu")
		(net "GND")
	)
	(via
		(at 222.87992 -317.206376)
		(size 0.508)
		(drill 0.254)
		(layers "F.Cu" "B.Cu")
		(net "GND")
	)
	(via
		(at 120.064784 -288.666174)
		(size 0.4064)
		(drill 0.2032)
		(layers "F.Cu" "B.Cu")
		(net "GND")
	)
	(via
		(at 338.101178 -254.204216)
		(size 0.4064)
		(drill 0.2032)
		(layers "F.Cu" "B.Cu")
		(net "GND")
	)
	(via
		(at 27.867864 -218.585288)
		(size 0.4826)
		(drill 0.254)
		(layers "F.Cu" "B.Cu")
		(net "GND")
	)
	(via
		(at 25.152096 -317.185294)
		(size 0.4826)
		(drill 0.254)
		(layers "F.Cu" "B.Cu")
		(net "GND")
	)
	(via
		(at 361.424728 -265.986006)
		(size 0.4064)
		(drill 0.2032)
		(layers "F.Cu" "B.Cu")
		(net "GND")
	)
	(via
		(at 339.511132 -248.534174)
		(size 0.4064)
		(drill 0.2032)
		(layers "F.Cu" "B.Cu")
		(net "GND")
	)
	(via
		(at 131.185666 -407.00452)
		(size 0.4064)
		(drill 0.2032)
		(layers "F.Cu" "B.Cu")
		(net "GND")
	)
	(via
		(at 21.70811 -253.435358)
		(size 0.4826)
		(drill 0.254)
		(layers "F.Cu" "B.Cu")
		(net "GND")
	)
	(via
		(at 369.114832 -236.384084)
		(size 0.4064)
		(drill 0.2032)
		(layers "F.Cu" "B.Cu")
		(net "GND")
	)
	(via
		(at 139.034774 -249.344434)
		(size 0.4064)
		(drill 0.2032)
		(layers "F.Cu" "B.Cu")
		(net "GND")
	)
	(via
		(at 180.900324 -306.135278)
		(size 0.4826)
		(drill 0.254)
		(layers "F.Cu" "B.Cu")
		(net "GND")
	)
	(via
		(at 106.91114 -291.906198)
		(size 0.4064)
		(drill 0.2032)
		(layers "F.Cu" "B.Cu")
		(net "GND")
	)
	(via
		(at 60.110624 -152.805892)
		(size 0.508)
		(drill 0.254)
		(layers "F.Cu" "B.Cu")
		(net "GND")
	)
	(via
		(at 135.274812 -241.244374)
		(size 0.4064)
		(drill 0.2032)
		(layers "F.Cu" "B.Cu")
		(net "GND")
	)
	(via
		(at 349.681038 -295.955974)
		(size 0.4064)
		(drill 0.2032)
		(layers "F.Cu" "B.Cu")
		(net "GND")
	)
	(via
		(at 99.861116 -263.556242)
		(size 0.4064)
		(drill 0.2032)
		(layers "F.Cu" "B.Cu")
		(net "GND")
	)
	(via
		(at 283.310076 -411.557724)
		(size 0.508)
		(drill 0.254)
		(layers "F.Cu" "B.Cu")
		(net "GND")
	)
	(via
		(at 394.349478 -431.451258)
		(size 0.4572)
		(drill 0.2032)
		(layers "F.Cu" "B.Cu")
		(net "GND")
	)
	(via
		(at 59.855354 -369.03533)
		(size 0.508)
		(drill 0.254)
		(layers "F.Cu" "B.Cu")
		(net "GND")
	)
	(via
		(at 327.249536 -425.547282)
		(size 0.4572)
		(drill 0.2032)
		(layers "F.Cu" "B.Cu")
		(net "GND")
	)
	(via
		(at 344.677238 -421.586152)
		(size 0.4572)
		(drill 0.254)
		(layers "F.Cu" "B.Cu")
		(net "GND")
	)
	(via
		(at 341.8967 -337.012788)
		(size 0.49022)
		(drill 0.254)
		(layers "F.Cu" "B.Cu")
		(net "GND")
	)
	(via
		(at 84.709 -147.955)
		(size 0.508)
		(drill 0.254)
		(layers "F.Cu" "B.Cu")
		(net "GND")
	)
	(via
		(at 20.32381 -237.285276)
		(size 0.4826)
		(drill 0.254)
		(layers "F.Cu" "B.Cu")
		(net "GND")
	)
	(via
		(at 384.924808 -269.22603)
		(size 0.4064)
		(drill 0.2032)
		(layers "F.Cu" "B.Cu")
		(net "GND")
	)
	(via
		(at 91.740736 -411.936184)
		(size 0.4572)
		(drill 0.254)
		(layers "F.Cu" "B.Cu")
		(net "GND")
	)
	(via
		(at 114.575082 -333.590138)
		(size 0.508)
		(drill 0.254)
		(layers "F.Cu" "B.Cu")
		(net "GND")
	)
	(via
		(at 339.388704 -379.22073)
		(size 0.508)
		(drill 0.254)
		(layers "F.Cu" "B.Cu")
		(net "GND")
	)
	(via
		(at 231.521 -236.474)
		(size 0.508)
		(drill 0.254)
		(layers "F.Cu" "B.Cu")
		(net "GND")
	)
	(via
		(at 451.132702 -391.457688)
		(size 0.508)
		(drill 0.254)
		(layers "F.Cu" "B.Cu")
		(net "GND")
	)
	(via
		(at 36.795964 -255.13538)
		(size 0.4826)
		(drill 0.254)
		(layers "F.Cu" "B.Cu")
		(net "GND")
	)
	(via
		(at 411.844236 -402.284438)
		(size 0.4572)
		(drill 0.254)
		(layers "F.Cu" "B.Cu")
		(net "GND")
	)
	(via
		(at 204.8637 -237.285276)
		(size 0.4826)
		(drill 0.254)
		(layers "F.Cu" "B.Cu")
		(net "GND")
	)
	(via
		(at 50.499772 -209.235294)
		(size 0.4826)
		(drill 0.254)
		(layers "F.Cu" "B.Cu")
		(net "GND")
	)
	(via
		(at 102.211124 -287.046162)
		(size 0.4064)
		(drill 0.2032)
		(layers "F.Cu" "B.Cu")
		(net "GND")
	)
	(via
		(at 403.349714 -430.299622)
		(size 0.4572)
		(drill 0.2032)
		(layers "F.Cu" "B.Cu")
		(net "GND")
	)
	(via
		(at 46.666404 -286.160464)
		(size 0.4826)
		(drill 0.254)
		(layers "F.Cu" "B.Cu")
		(net "GND")
	)
	(via
		(at 165.545516 -239.410494)
		(size 0.4826)
		(drill 0.254)
		(layers "F.Cu" "B.Cu")
		(net "GND")
	)
	(via
		(at 113.48466 -285.426404)
		(size 0.4064)
		(drill 0.2032)
		(layers "F.Cu" "B.Cu")
		(net "GND")
	)
	(via
		(at 451.151752 -392.143234)
		(size 0.508)
		(drill 0.254)
		(layers "F.Cu" "B.Cu")
		(net "GND")
	)
	(via
		(at 137.759186 -404.46452)
		(size 0.4064)
		(drill 0.2032)
		(layers "F.Cu" "B.Cu")
		(net "GND")
	)
	(via
		(at 206.248 -246.63527)
		(size 0.4826)
		(drill 0.254)
		(layers "F.Cu" "B.Cu")
		(net "GND")
	)
	(via
		(at 98.150934 -222.61449)
		(size 0.4064)
		(drill 0.2032)
		(layers "F.Cu" "B.Cu")
		(net "GND")
	)
	(via
		(at 387.54431 -419.046152)
		(size 0.4572)
		(drill 0.254)
		(layers "F.Cu" "B.Cu")
		(net "GND")
	)
	(via
		(at 13.656818 -411.83687)
		(size 0.508)
		(drill 0.254)
		(layers "F.Cu" "B.Cu")
		(net "GND")
	)
	(via
		(at 343.101168 -276.516084)
		(size 0.4064)
		(drill 0.2032)
		(layers "F.Cu" "B.Cu")
		(net "GND")
	)
	(via
		(at 164.427916 -197.335394)
		(size 0.4826)
		(drill 0.254)
		(layers "F.Cu" "B.Cu")
		(net "GND")
	)
	(via
		(at 58.043826 -199.8853)
		(size 0.4826)
		(drill 0.254)
		(layers "F.Cu" "B.Cu")
		(net "GND")
	)
	(via
		(at 405.419052 -398.542002)
		(size 0.4064)
		(drill 0.2032)
		(layers "F.Cu" "B.Cu")
		(net "GND")
	)
	(via
		(at 336.472784 -381.68453)
		(size 0.508)
		(drill 0.254)
		(layers "F.Cu" "B.Cu")
		(net "GND")
	)
	(via
		(at 107.550966 -238.814356)
		(size 0.4064)
		(drill 0.2032)
		(layers "F.Cu" "B.Cu")
		(net "GND")
	)
	(via
		(at 409.349702 -437.34736)
		(size 0.4572)
		(drill 0.2032)
		(layers "F.Cu" "B.Cu")
		(net "GND")
	)
	(via
		(at 89.991184 -287.04667)
		(size 0.4064)
		(drill 0.2032)
		(layers "F.Cu" "B.Cu")
		(net "GND")
	)
	(via
		(at 337.631024 -256.634234)
		(size 0.4064)
		(drill 0.2032)
		(layers "F.Cu" "B.Cu")
		(net "GND")
	)
	(via
		(at 82.823812 -406.370536)
		(size 0.4572)
		(drill 0.254)
		(layers "F.Cu" "B.Cu")
		(net "GND")
	)
	(via
		(at 355.021134 -250.964192)
		(size 0.4064)
		(drill 0.2032)
		(layers "F.Cu" "B.Cu")
		(net "GND")
	)
	(via
		(at 467.5378 -339.903054)
		(size 0.508)
		(drill 0.254)
		(layers "F.Cu" "B.Cu")
		(net "GND")
	)
	(via
		(at 277.192232 -241.53495)
		(size 0.4826)
		(drill 0.254)
		(layers "F.Cu" "B.Cu")
		(net "GND")
	)
	(via
		(at 451.2056 -239.41024)
		(size 0.4826)
		(drill 0.254)
		(layers "F.Cu" "B.Cu")
		(net "GND")
	)
	(via
		(at 467.5378 -127.559054)
		(size 0.508)
		(drill 0.254)
		(layers "F.Cu" "B.Cu")
		(net "GND")
	)
	(via
		(at 121.174764 -241.244374)
		(size 0.4064)
		(drill 0.2032)
		(layers "F.Cu" "B.Cu")
		(net "GND")
	)
	(via
		(at 59.576716 -410.664152)
		(size 0.4572)
		(drill 0.254)
		(layers "F.Cu" "B.Cu")
		(net "GND")
	)
	(via
		(at 266.93241 -221.985078)
		(size 0.4826)
		(drill 0.254)
		(layers "F.Cu" "B.Cu")
		(net "GND")
	)
	(via
		(at 227.814378 -317.22568)
		(size 0.508)
		(drill 0.254)
		(layers "F.Cu" "B.Cu")
		(net "GND")
	)
	(via
		(at 182.460392 -193.996564)
		(size 0.4826)
		(drill 0.254)
		(layers "F.Cu" "B.Cu")
		(net "GND")
	)
	(via
		(at 119.76481 -232.334308)
		(size 0.4064)
		(drill 0.2032)
		(layers "F.Cu" "B.Cu")
		(net "GND")
	)
	(via
		(at 82.249772 -433.747164)
		(size 0.4572)
		(drill 0.2032)
		(layers "F.Cu" "B.Cu")
		(net "GND")
	)
	(via
		(at 370.82476 -264.365994)
		(size 0.4064)
		(drill 0.2032)
		(layers "F.Cu" "B.Cu")
		(net "GND")
	)
	(via
		(at 344.692478 -167.977312)
		(size 0.508)
		(drill 0.254)
		(layers "F.Cu" "B.Cu")
		(net "GND")
	)
	(via
		(at 90.461084 -279.756362)
		(size 0.4064)
		(drill 0.2032)
		(layers "F.Cu" "B.Cu")
		(net "GND")
	)
	(via
		(at 51.734466 -4.32943)
		(size 0.508)
		(drill 0.254)
		(layers "F.Cu" "B.Cu")
		(net "GND")
	)
	(via
		(at 99.090988 -227.474526)
		(size 0.4064)
		(drill 0.2032)
		(layers "F.Cu" "B.Cu")
		(net "GND")
	)
	(via
		(at 113.48466 -269.226284)
		(size 0.4064)
		(drill 0.2032)
		(layers "F.Cu" "B.Cu")
		(net "GND")
	)
	(via
		(at 343.189814 -392.999722)
		(size 0.4064)
		(drill 0.2032)
		(layers "F.Cu" "B.Cu")
		(net "GND")
	)
	(via
		(at 382.1049 -291.905944)
		(size 0.4064)
		(drill 0.2032)
		(layers "F.Cu" "B.Cu")
		(net "GND")
	)
	(via
		(at 287.230566 -343.472008)
		(size 0.508)
		(drill 0.254)
		(layers "F.Cu" "B.Cu")
		(net "GND")
	)
	(via
		(at 284.736032 -244.934994)
		(size 0.4826)
		(drill 0.254)
		(layers "F.Cu" "B.Cu")
		(net "GND")
	)
	(via
		(at 369.584732 -238.814102)
		(size 0.4064)
		(drill 0.2032)
		(layers "F.Cu" "B.Cu")
		(net "GND")
	)
	(via
		(at 130.349752 -433.899564)
		(size 0.4572)
		(drill 0.2032)
		(layers "F.Cu" "B.Cu")
		(net "GND")
	)
	(via
		(at 121.644664 -229.094538)
		(size 0.4064)
		(drill 0.2032)
		(layers "F.Cu" "B.Cu")
		(net "GND")
	)
	(via
		(at 166.548308 -353.341178)
		(size 0.508)
		(drill 0.254)
		(layers "F.Cu" "B.Cu")
		(net "GND")
	)
	(via
		(at 25.152096 -279.785318)
		(size 0.4826)
		(drill 0.254)
		(layers "F.Cu" "B.Cu")
		(net "GND")
	)
	(via
		(at 125.704854 -277.326344)
		(size 0.4064)
		(drill 0.2032)
		(layers "F.Cu" "B.Cu")
		(net "GND")
	)
	(via
		(at 130.87477 -294.336216)
		(size 0.4064)
		(drill 0.2032)
		(layers "F.Cu" "B.Cu")
		(net "GND")
	)
	(via
		(at 381.362458 -392.999722)
		(size 0.4064)
		(drill 0.2032)
		(layers "F.Cu" "B.Cu")
		(net "GND")
	)
	(via
		(at 331.351128 -291.905944)
		(size 0.4064)
		(drill 0.2032)
		(layers "F.Cu" "B.Cu")
		(net "GND")
	)
	(via
		(at 419.912038 -255.135126)
		(size 0.4826)
		(drill 0.254)
		(layers "F.Cu" "B.Cu")
		(net "GND")
	)
	(via
		(at 315.391038 -398.542002)
		(size 0.4064)
		(drill 0.2032)
		(layers "F.Cu" "B.Cu")
		(net "GND")
	)
	(via
		(at 388.21487 -263.555988)
		(size 0.4064)
		(drill 0.2032)
		(layers "F.Cu" "B.Cu")
		(net "GND")
	)
	(via
		(at 21.69287 -384.51409)
		(size 0.508)
		(drill 0.254)
		(layers "F.Cu" "B.Cu")
		(net "GND")
	)
	(via
		(at 131.29133 -390.160002)
		(size 0.4064)
		(drill 0.2032)
		(layers "F.Cu" "B.Cu")
		(net "GND")
	)
	(via
		(at 99.090988 -242.05438)
		(size 0.4064)
		(drill 0.2032)
		(layers "F.Cu" "B.Cu")
		(net "GND")
	)
	(via
		(at 130.40487 -277.326344)
		(size 0.4064)
		(drill 0.2032)
		(layers "F.Cu" "B.Cu")
		(net "GND")
	)
	(via
		(at 167.994584 -369.69573)
		(size 0.508)
		(drill 0.254)
		(layers "F.Cu" "B.Cu")
		(net "GND")
	)
	(via
		(at 98.344736 -119.50573)
		(size 0.508)
		(drill 0.254)
		(layers "F.Cu" "B.Cu")
		(net "GND")
	)
	(via
		(at 303.232566 -342.811608)
		(size 0.508)
		(drill 0.254)
		(layers "F.Cu" "B.Cu")
		(net "GND")
	)
	(via
		(at 431.568098 -329.80249)
		(size 0.508)
		(drill 0.254)
		(layers "F.Cu" "B.Cu")
		(net "GND")
	)
	(via
		(at 109.13999 -22.518878)
		(size 0.508)
		(drill 0.254)
		(layers "F.Cu" "B.Cu")
		(net "GND")
	)
	(via
		(at 431.55616 -297.635168)
		(size 0.4826)
		(drill 0.254)
		(layers "F.Cu" "B.Cu")
		(net "GND")
	)
	(via
		(at 391.715244 -401.717002)
		(size 0.508)
		(drill 0.254)
		(layers "F.Cu" "B.Cu")
		(net "GND")
	)
	(via
		(at 421.790876 -331.85989)
		(size 0.508)
		(drill 0.254)
		(layers "F.Cu" "B.Cu")
		(net "GND")
	)
	(via
		(at 341.886794 -417.778184)
		(size 0.4572)
		(drill 0.254)
		(layers "F.Cu" "B.Cu")
		(net "GND")
	)
	(via
		(at 392.144758 -250.154186)
		(size 0.4064)
		(drill 0.2032)
		(layers "F.Cu" "B.Cu")
		(net "GND")
	)
	(via
		(at 282.020264 -306.135024)
		(size 0.4826)
		(drill 0.254)
		(layers "F.Cu" "B.Cu")
		(net "GND")
	)
	(via
		(at 324.543928 -60.094876)
		(size 0.508)
		(drill 0.254)
		(layers "F.Cu" "B.Cu")
		(net "GND")
	)
	(via
		(at 408.714194 -420.318184)
		(size 0.4572)
		(drill 0.254)
		(layers "F.Cu" "B.Cu")
		(net "GND")
	)
	(via
		(at 105.971086 -267.606272)
		(size 0.4064)
		(drill 0.2032)
		(layers "F.Cu" "B.Cu")
		(net "GND")
	)
	(via
		(at 251.977398 -123.283726)
		(size 0.508)
		(drill 0.254)
		(layers "F.Cu" "B.Cu")
		(net "GND")
	)
	(via
		(at 52.616608 -382.85293)
		(size 0.4064)
		(drill 0.2032)
		(layers "F.Cu" "B.Cu")
		(net "GND")
	)
	(via
		(at 229.53726 -329.698858)
		(size 0.508)
		(drill 0.254)
		(layers "F.Cu" "B.Cu")
		(net "GND")
	)
	(via
		(at 132.61848 -388.328662)
		(size 0.4064)
		(drill 0.2032)
		(layers "F.Cu" "B.Cu")
		(net "GND")
	)
	(via
		(at 383.21488 -247.724168)
		(size 0.4064)
		(drill 0.2032)
		(layers "F.Cu" "B.Cu")
		(net "GND")
	)
	(via
		(at 314.317634 -419.046152)
		(size 0.4572)
		(drill 0.254)
		(layers "F.Cu" "B.Cu")
		(net "GND")
	)
	(via
		(at 305.929538 -433.614322)
		(size 0.508)
		(drill 0.254)
		(layers "F.Cu" "B.Cu")
		(net "GND")
	)
	(via
		(at 355.491034 -232.334054)
		(size 0.4064)
		(drill 0.2032)
		(layers "F.Cu" "B.Cu")
		(net "GND")
	)
	(via
		(at 21.70811 -278.935434)
		(size 0.4826)
		(drill 0.254)
		(layers "F.Cu" "B.Cu")
		(net "GND")
	)
	(via
		(at 401.776692 -6.091174)
		(size 0.508)
		(drill 0.254)
		(layers "F.Cu" "B.Cu")
		(net "GND")
	)
	(via
		(at 121.944638 -262.746236)
		(size 0.4064)
		(drill 0.2032)
		(layers "F.Cu" "B.Cu")
		(net "GND")
	)
	(via
		(at 419.04412 -391.23493)
		(size 0.4064)
		(drill 0.2032)
		(layers "F.Cu" "B.Cu")
		(net "GND")
	)
	(via
		(at 277.192232 -250.03506)
		(size 0.4826)
		(drill 0.254)
		(layers "F.Cu" "B.Cu")
		(net "GND")
	)
	(via
		(at 394.982954 -277.870158)
		(size 0.4064)
		(drill 0.2032)
		(layers "F.Cu" "B.Cu")
		(net "GND")
	)
	(via
		(at 110.77702 -173.553374)
		(size 0.508)
		(drill 0.254)
		(layers "F.Cu" "B.Cu")
		(net "GND")
	)
	(via
		(at 387.54431 -417.778184)
		(size 0.4572)
		(drill 0.254)
		(layers "F.Cu" "B.Cu")
		(net "GND")
	)
	(via
		(at 124.934726 -250.964446)
		(size 0.4064)
		(drill 0.2032)
		(layers "F.Cu" "B.Cu")
		(net "GND")
	)
	(via
		(at 86.863174 -336.966814)
		(size 0.49022)
		(drill 0.254)
		(layers "F.Cu" "B.Cu")
		(net "GND")
	)
	(via
		(at 137.717276 -379.321568)
		(size 0.508)
		(drill 0.254)
		(layers "F.Cu" "B.Cu")
		(net "GND")
	)
	(via
		(at 329.941174 -266.796012)
		(size 0.4064)
		(drill 0.2032)
		(layers "F.Cu" "B.Cu")
		(net "GND")
	)
	(via
		(at 116.326666 -173.862746)
		(size 0.49022)
		(drill 0.254)
		(layers "F.Cu" "B.Cu")
		(net "GND")
	)
	(via
		(at 82.001106 -292.716204)
		(size 0.4064)
		(drill 0.2032)
		(layers "F.Cu" "B.Cu")
		(net "GND")
	)
	(via
		(at 126.34976 -430.299622)
		(size 0.4572)
		(drill 0.2032)
		(layers "F.Cu" "B.Cu")
		(net "GND")
	)
	(via
		(at 80.591152 -262.746236)
		(size 0.4064)
		(drill 0.2032)
		(layers "F.Cu" "B.Cu")
		(net "GND")
	)
	(via
		(at 123.994672 -233.144314)
		(size 0.4064)
		(drill 0.2032)
		(layers "F.Cu" "B.Cu")
		(net "GND")
	)
	(via
		(at 384.924808 -277.32609)
		(size 0.4064)
		(drill 0.2032)
		(layers "F.Cu" "B.Cu")
		(net "GND")
	)
	(via
		(at 331.051154 -253.39421)
		(size 0.4064)
		(drill 0.2032)
		(layers "F.Cu" "B.Cu")
		(net "GND")
	)
	(via
		(at 336.521044 -266.796012)
		(size 0.4064)
		(drill 0.2032)
		(layers "F.Cu" "B.Cu")
		(net "GND")
	)
	(via
		(at 421.790876 -330.53909)
		(size 0.508)
		(drill 0.254)
		(layers "F.Cu" "B.Cu")
		(net "GND")
	)
	(via
		(at 323.249544 -432.747166)
		(size 0.4572)
		(drill 0.2032)
		(layers "F.Cu" "B.Cu")
		(net "GND")
	)
	(via
		(at 344.249502 -438.651396)
		(size 0.4572)
		(drill 0.2032)
		(layers "F.Cu" "B.Cu")
		(net "GND")
	)
	(via
		(at 442.633608 -170.559476)
		(size 0.508)
		(drill 0.254)
		(layers "F.Cu" "B.Cu")
		(net "GND")
	)
	(via
		(at 329.941174 -265.176)
		(size 0.4064)
		(drill 0.2032)
		(layers "F.Cu" "B.Cu")
		(net "GND")
	)
	(via
		(at 369.584732 -224.234248)
		(size 0.4064)
		(drill 0.2032)
		(layers "F.Cu" "B.Cu")
		(net "GND")
	)
	(via
		(at 280.635964 -225.385122)
		(size 0.4826)
		(drill 0.254)
		(layers "F.Cu" "B.Cu")
		(net "GND")
	)
	(via
		(at 108.530644 -380.87046)
		(size 0.508)
		(drill 0.254)
		(layers "F.Cu" "B.Cu")
		(net "GND")
	)
	(via
		(at 392.225022 -415.38652)
		(size 0.4064)
		(drill 0.2032)
		(layers "F.Cu" "B.Cu")
		(net "GND")
	)
	(via
		(at 309.808626 -415.38652)
		(size 0.4064)
		(drill 0.2032)
		(layers "F.Cu" "B.Cu")
		(net "GND")
	)
	(via
		(at 191.074294 -15.184628)
		(size 0.508)
		(drill 0.254)
		(layers "F.Cu" "B.Cu")
		(net "GND")
	)
	(via
		(at 130.751834 -163.357052)
		(size 0.508)
		(drill 0.254)
		(layers "F.Cu" "B.Cu")
		(net "GND")
	)
	(via
		(at 364.122208 -257.744976)
		(size 0.4826)
		(drill 0.254)
		(layers "F.Cu" "B.Cu")
		(net "GND")
	)
	(via
		(at 118.65483 -282.996386)
		(size 0.4064)
		(drill 0.2032)
		(layers "F.Cu" "B.Cu")
		(net "GND")
	)
	(via
		(at 337.736942 -140.337286)
		(size 0.508)
		(drill 0.254)
		(layers "F.Cu" "B.Cu")
		(net "GND")
	)
	(via
		(at 388.68477 -264.365994)
		(size 0.4064)
		(drill 0.2032)
		(layers "F.Cu" "B.Cu")
		(net "GND")
	)
	(via
		(at 134.164832 -262.746236)
		(size 0.4064)
		(drill 0.2032)
		(layers "F.Cu" "B.Cu")
		(net "GND")
	)
	(via
		(at 425.950634 -423.819828)
		(size 0.508)
		(drill 0.254)
		(layers "F.Cu" "B.Cu")
		(net "GND")
	)
	(via
		(at 464.065366 -378.81687)
		(size 0.508)
		(drill 0.254)
		(layers "F.Cu" "B.Cu")
		(net "GND")
	)
	(via
		(at 369.884706 -270.846042)
		(size 0.4064)
		(drill 0.2032)
		(layers "F.Cu" "B.Cu")
		(net "GND")
	)
	(via
		(at 91.571064 -237.194344)
		(size 0.4064)
		(drill 0.2032)
		(layers "F.Cu" "B.Cu")
		(net "GND")
	)
	(via
		(at 362.534708 -241.24412)
		(size 0.4064)
		(drill 0.2032)
		(layers "F.Cu" "B.Cu")
		(net "GND")
	)
	(via
		(at 75.251564 -410.030168)
		(size 0.4064)
		(drill 0.2032)
		(layers "F.Cu" "B.Cu")
		(net "GND")
	)
	(via
		(at 117.414802 -250.964446)
		(size 0.4064)
		(drill 0.2032)
		(layers "F.Cu" "B.Cu")
		(net "GND")
	)
	(via
		(at 142.154656 -273.276314)
		(size 0.4064)
		(drill 0.2032)
		(layers "F.Cu" "B.Cu")
		(net "GND")
	)
	(via
		(at 187.060078 -204.985366)
		(size 0.4826)
		(drill 0.254)
		(layers "F.Cu" "B.Cu")
		(net "GND")
	)
	(via
		(at 67.249802 -431.451258)
		(size 0.4572)
		(drill 0.2032)
		(layers "F.Cu" "B.Cu")
		(net "GND")
	)
	(via
		(at 277.192232 -280.634948)
		(size 0.4826)
		(drill 0.254)
		(layers "F.Cu" "B.Cu")
		(net "GND")
	)
	(via
		(at 301.755556 -378.07773)
		(size 0.508)
		(drill 0.254)
		(layers "F.Cu" "B.Cu")
		(net "GND")
	)
	(via
		(at 424.93184 -18.247106)
		(size 0.508)
		(drill 0.254)
		(layers "F.Cu" "B.Cu")
		(net "GND")
	)
	(via
		(at 304.652426 -296.78503)
		(size 0.4826)
		(drill 0.254)
		(layers "F.Cu" "B.Cu")
		(net "GND")
	)
	(via
		(at 90.332814 -333.02956)
		(size 0.508)
		(drill 0.254)
		(layers "F.Cu" "B.Cu")
		(net "GND")
	)
	(via
		(at 290.895786 -305.28514)
		(size 0.4826)
		(drill 0.254)
		(layers "F.Cu" "B.Cu")
		(net "GND")
	)
	(via
		(at 55.328058 -292.535356)
		(size 0.4826)
		(drill 0.254)
		(layers "F.Cu" "B.Cu")
		(net "GND")
	)
	(via
		(at 20.584922 -6.598158)
		(size 0.508)
		(drill 0.254)
		(layers "F.Cu" "B.Cu")
		(net "GND")
	)
	(via
		(at 431.55616 -215.18499)
		(size 0.4826)
		(drill 0.254)
		(layers "F.Cu" "B.Cu")
		(net "GND")
	)
	(via
		(at 373.790464 -424.204892)
		(size 0.508)
		(drill 0.254)
		(layers "F.Cu" "B.Cu")
		(net "GND")
	)
	(via
		(at 130.87477 -274.896326)
		(size 0.4064)
		(drill 0.2032)
		(layers "F.Cu" "B.Cu")
		(net "GND")
	)
	(via
		(at 7.79272 -111.288068)
		(size 0.508)
		(drill 0.254)
		(layers "F.Cu" "B.Cu")
		(net "GND")
	)
	(via
		(at 394.0175 -183.85536)
		(size 0.508)
		(drill 0.254)
		(layers "F.Cu" "B.Cu")
		(net "GND")
	)
	(via
		(at 87.171022 -283.806392)
		(size 0.4064)
		(drill 0.2032)
		(layers "F.Cu" "B.Cu")
		(net "GND")
	)
	(via
		(at 50.499772 -199.8853)
		(size 0.4826)
		(drill 0.254)
		(layers "F.Cu" "B.Cu")
		(net "GND")
	)
	(via
		(at 132.694172 -38.905434)
		(size 0.508)
		(drill 0.254)
		(layers "F.Cu" "B.Cu")
		(net "GND")
	)
	(via
		(at 78.41107 -255.014476)
		(size 0.4064)
		(drill 0.2032)
		(layers "F.Cu" "B.Cu")
		(net "GND")
	)
	(via
		(at 315.24956 -437.49976)
		(size 0.4572)
		(drill 0.2032)
		(layers "F.Cu" "B.Cu")
		(net "GND")
	)
	(via
		(at 311.254394 -416.020504)
		(size 0.4572)
		(drill 0.254)
		(layers "F.Cu" "B.Cu")
		(net "GND")
	)
	(via
		(at 387.41858 -396.710662)
		(size 0.4064)
		(drill 0.2032)
		(layers "F.Cu" "B.Cu")
		(net "GND")
	)
	(via
		(at 323.507354 -414.72866)
		(size 0.4572)
		(drill 0.254)
		(layers "F.Cu" "B.Cu")
		(net "GND")
	)
	(via
		(at 329.6412 -239.624108)
		(size 0.4064)
		(drill 0.2032)
		(layers "F.Cu" "B.Cu")
		(net "GND")
	)
	(via
		(at 101.91115 -229.094538)
		(size 0.4064)
		(drill 0.2032)
		(layers "F.Cu" "B.Cu")
		(net "GND")
	)
	(via
		(at 110.371128 -242.05438)
		(size 0.4064)
		(drill 0.2032)
		(layers "F.Cu" "B.Cu")
		(net "GND")
	)
	(via
		(at 431.270156 -108.49737)
		(size 0.508)
		(drill 0.254)
		(layers "F.Cu" "B.Cu")
		(net "GND")
	)
	(via
		(at 342.249506 -426.54728)
		(size 0.4572)
		(drill 0.2032)
		(layers "F.Cu" "B.Cu")
		(net "GND")
	)
	(via
		(at 274.476464 -221.985078)
		(size 0.4826)
		(drill 0.254)
		(layers "F.Cu" "B.Cu")
		(net "GND")
	)
	(via
		(at 274.476464 -231.335072)
		(size 0.4826)
		(drill 0.254)
		(layers "F.Cu" "B.Cu")
		(net "GND")
	)
	(via
		(at 56.425084 -404.46452)
		(size 0.4064)
		(drill 0.2032)
		(layers "F.Cu" "B.Cu")
		(net "GND")
	)
	(via
		(at 195.83146 -342.669114)
		(size 0.508)
		(drill 0.254)
		(layers "F.Cu" "B.Cu")
		(net "GND")
	)
	(via
		(at 94.812358 -333.090012)
		(size 0.49022)
		(drill 0.254)
		(layers "F.Cu" "B.Cu")
		(net "GND")
	)
	(via
		(at 366.415066 -425.018962)
		(size 0.508)
		(drill 0.254)
		(layers "F.Cu" "B.Cu")
		(net "GND")
	)
	(via
		(at 118.65483 -284.616398)
		(size 0.4064)
		(drill 0.2032)
		(layers "F.Cu" "B.Cu")
		(net "GND")
	)
	(via
		(at 138.564874 -233.95432)
		(size 0.4064)
		(drill 0.2032)
		(layers "F.Cu" "B.Cu")
		(net "GND")
	)
	(via
		(at 349.544132 -391.23493)
		(size 0.4064)
		(drill 0.2032)
		(layers "F.Cu" "B.Cu")
		(net "GND")
	)
	(via
		(at 389.79475 -255.824228)
		(size 0.4064)
		(drill 0.2032)
		(layers "F.Cu" "B.Cu")
		(net "GND")
	)
	(via
		(at 390.094724 -279.756108)
		(size 0.4064)
		(drill 0.2032)
		(layers "F.Cu" "B.Cu")
		(net "GND")
	)
	(via
		(at 324.941184 -223.424242)
		(size 0.4064)
		(drill 0.2032)
		(layers "F.Cu" "B.Cu")
		(net "GND")
	)
	(via
		(at 64.444372 -409.396184)
		(size 0.4572)
		(drill 0.254)
		(layers "F.Cu" "B.Cu")
		(net "GND")
	)
	(via
		(at 373.486934 -419.046152)
		(size 0.4572)
		(drill 0.254)
		(layers "F.Cu" "B.Cu")
		(net "GND")
	)
	(via
		(at 340.082378 -419.046152)
		(size 0.4572)
		(drill 0.254)
		(layers "F.Cu" "B.Cu")
		(net "GND")
	)
	(via
		(at 248.822972 -420.67099)
		(size 0.508)
		(drill 0.254)
		(layers "F.Cu" "B.Cu")
		(net "GND")
	)
	(via
		(at 56.712358 -296.785284)
		(size 0.4826)
		(drill 0.254)
		(layers "F.Cu" "B.Cu")
		(net "GND")
	)
	(via
		(at 88.950292 -406.370536)
		(size 0.4572)
		(drill 0.254)
		(layers "F.Cu" "B.Cu")
		(net "GND")
	)
	(via
		(at 47.46244 -384.617722)
		(size 0.4064)
		(drill 0.2032)
		(layers "F.Cu" "B.Cu")
		(net "GND")
	)
	(via
		(at 42.955718 -211.7852)
		(size 0.4826)
		(drill 0.254)
		(layers "F.Cu" "B.Cu")
		(net "GND")
	)
	(via
		(at 364.636812 -396.850108)
		(size 0.508)
		(drill 0.254)
		(layers "F.Cu" "B.Cu")
		(net "GND")
	)
	(via
		(at 145.444718 -277.326344)
		(size 0.4064)
		(drill 0.2032)
		(layers "F.Cu" "B.Cu")
		(net "GND")
	)
	(via
		(at 97.759266 -184.632346)
		(size 0.49022)
		(drill 0.254)
		(layers "F.Cu" "B.Cu")
		(net "GND")
	)
	(via
		(at 151.34971 -432.747166)
		(size 0.4572)
		(drill 0.2032)
		(layers "F.Cu" "B.Cu")
		(net "GND")
	)
	(via
		(at 452.803768 -230.485188)
		(size 0.4826)
		(drill 0.254)
		(layers "F.Cu" "B.Cu")
		(net "GND")
	)
	(via
		(at 354.551234 -243.674138)
		(size 0.4064)
		(drill 0.2032)
		(layers "F.Cu" "B.Cu")
		(net "GND")
	)
	(via
		(at 432.082956 -18.503138)
		(size 0.508)
		(drill 0.254)
		(layers "F.Cu" "B.Cu")
		(net "GND")
	)
	(via
		(at 123.972066 -410.030168)
		(size 0.4064)
		(drill 0.2032)
		(layers "F.Cu" "B.Cu")
		(net "GND")
	)
	(via
		(at 309.37835 -394.831062)
		(size 0.4064)
		(drill 0.2032)
		(layers "F.Cu" "B.Cu")
		(net "GND")
	)
	(via
		(at 399.979388 -4.32943)
		(size 0.508)
		(drill 0.254)
		(layers "F.Cu" "B.Cu")
		(net "GND")
	)
	(via
		(at 50.861214 -370.83873)
		(size 0.508)
		(drill 0.254)
		(layers "F.Cu" "B.Cu")
		(net "GND")
	)
	(via
		(at 80.120998 -281.376374)
		(size 0.4064)
		(drill 0.2032)
		(layers "F.Cu" "B.Cu")
		(net "GND")
	)
	(via
		(at 80.931004 -412.570168)
		(size 0.4064)
		(drill 0.2032)
		(layers "F.Cu" "B.Cu")
		(net "GND")
	)
	(via
		(at 413.78124 -379.88113)
		(size 0.508)
		(drill 0.254)
		(layers "F.Cu" "B.Cu")
		(net "GND")
	)
	(via
		(at 344.681048 -242.864132)
		(size 0.4064)
		(drill 0.2032)
		(layers "F.Cu" "B.Cu")
		(net "GND")
	)
	(via
		(at 89.99093 -293.52621)
		(size 0.4064)
		(drill 0.2032)
		(layers "F.Cu" "B.Cu")
		(net "GND")
	)
	(via
		(at 110.671102 -290.286186)
		(size 0.4064)
		(drill 0.2032)
		(layers "F.Cu" "B.Cu")
		(net "GND")
	)
	(via
		(at 413.044132 -391.23493)
		(size 0.4064)
		(drill 0.2032)
		(layers "F.Cu" "B.Cu")
		(net "GND")
	)
	(via
		(at 128.89611 -160.435798)
		(size 0.508)
		(drill 0.254)
		(layers "F.Cu" "B.Cu")
		(net "GND")
	)
	(via
		(at 394.349478 -432.747166)
		(size 0.4572)
		(drill 0.2032)
		(layers "F.Cu" "B.Cu")
		(net "GND")
	)
	(via
		(at 134.334758 -403.830536)
		(size 0.4572)
		(drill 0.254)
		(layers "F.Cu" "B.Cu")
		(net "GND")
	)
	(via
		(at 131.34467 -293.52621)
		(size 0.4064)
		(drill 0.2032)
		(layers "F.Cu" "B.Cu")
		(net "GND")
	)
	(via
		(at 187.060078 -292.535356)
		(size 0.4826)
		(drill 0.254)
		(layers "F.Cu" "B.Cu")
		(net "GND")
	)
	(via
		(at 99.4664 -30.779212)
		(size 0.508)
		(drill 0.254)
		(layers "F.Cu" "B.Cu")
		(net "GND")
	)
	(via
		(at 67.715384 -441.227718)
		(size 0.508)
		(drill 0.254)
		(layers "F.Cu" "B.Cu")
		(net "GND")
	)
	(via
		(at 427.765718 -7.215124)
		(size 0.508)
		(drill 0.254)
		(layers "F.Cu" "B.Cu")
		(net "GND")
	)
	(via
		(at 416.54984 -18.503138)
		(size 0.508)
		(drill 0.254)
		(layers "F.Cu" "B.Cu")
		(net "GND")
	)
	(via
		(at 442.5442 -311.23509)
		(size 0.4826)
		(drill 0.254)
		(layers "F.Cu" "B.Cu")
		(net "GND")
	)
	(via
		(at 194.604132 -292.535356)
		(size 0.4826)
		(drill 0.254)
		(layers "F.Cu" "B.Cu")
		(net "GND")
	)
	(via
		(at 118.824756 -246.914416)
		(size 0.4064)
		(drill 0.2032)
		(layers "F.Cu" "B.Cu")
		(net "GND")
	)
	(via
		(at 344.981784 -379.22073)
		(size 0.508)
		(drill 0.254)
		(layers "F.Cu" "B.Cu")
		(net "GND")
	)
	(via
		(at 460.147924 -56.518302)
		(size 0.508)
		(drill 0.254)
		(layers "F.Cu" "B.Cu")
		(net "GND")
	)
	(via
		(at 367.16589 -393.04468)
		(size 0.508)
		(drill 0.254)
		(layers "F.Cu" "B.Cu")
		(net "GND")
	)
	(via
		(at 435.000146 -309.535068)
		(size 0.4826)
		(drill 0.254)
		(layers "F.Cu" "B.Cu")
		(net "GND")
	)
	(via
		(at 388.34949 -433.747164)
		(size 0.4572)
		(drill 0.2032)
		(layers "F.Cu" "B.Cu")
		(net "GND")
	)
	(via
		(at 467.5378 -323.139054)
		(size 0.508)
		(drill 0.254)
		(layers "F.Cu" "B.Cu")
		(net "GND")
	)
	(via
		(at 269.648178 -301.034958)
		(size 0.4826)
		(drill 0.254)
		(layers "F.Cu" "B.Cu")
		(net "GND")
	)
	(via
		(at 369.884706 -288.66592)
		(size 0.4064)
		(drill 0.2032)
		(layers "F.Cu" "B.Cu")
		(net "GND")
	)
	(via
		(at 83.111086 -240.434368)
		(size 0.4064)
		(drill 0.2032)
		(layers "F.Cu" "B.Cu")
		(net "GND")
	)
	(via
		(at 450.088 -279.785064)
		(size 0.4826)
		(drill 0.254)
		(layers "F.Cu" "B.Cu")
		(net "GND")
	)
	(via
		(at 284.736032 -213.484968)
		(size 0.4826)
		(drill 0.254)
		(layers "F.Cu" "B.Cu")
		(net "GND")
	)
	(via
		(at 119.12473 -290.286186)
		(size 0.4064)
		(drill 0.2032)
		(layers "F.Cu" "B.Cu")
		(net "GND")
	)
	(via
		(at 47.518574 -388.328662)
		(size 0.4064)
		(drill 0.2032)
		(layers "F.Cu" "B.Cu")
		(net "GND")
	)
	(via
		(at 163.943284 -149.1742)
		(size 0.508)
		(drill 0.254)
		(layers "F.Cu" "B.Cu")
		(net "GND")
	)
	(via
		(at 16.60652 -108.66374)
		(size 0.508)
		(drill 0.254)
		(layers "F.Cu" "B.Cu")
		(net "GND")
	)
	(via
		(at 295.724072 -300.185074)
		(size 0.4826)
		(drill 0.254)
		(layers "F.Cu" "B.Cu")
		(net "GND")
	)
	(via
		(at 333.230982 -287.046162)
		(size 0.4064)
		(drill 0.2032)
		(layers "F.Cu" "B.Cu")
		(net "GND")
	)
	(via
		(at 209.727546 -35.321748)
		(size 0.508)
		(drill 0.254)
		(layers "F.Cu" "B.Cu")
		(net "GND")
	)
	(via
		(at 101.555296 -423.44848)
		(size 0.508)
		(drill 0.254)
		(layers "F.Cu" "B.Cu")
		(net "GND")
	)
	(via
		(at 14.892782 -416.912552)
		(size 0.508)
		(drill 0.254)
		(layers "F.Cu" "B.Cu")
		(net "GND")
	)
	(via
		(at 440.58205 -396.765272)
		(size 0.508)
		(drill 0.254)
		(layers "F.Cu" "B.Cu")
		(net "GND")
	)
	(via
		(at 366.764824 -233.954066)
		(size 0.4064)
		(drill 0.2032)
		(layers "F.Cu" "B.Cu")
		(net "GND")
	)
	(via
		(at 181.407562 -45.17771)
		(size 0.508)
		(drill 0.254)
		(layers "F.Cu" "B.Cu")
		(net "GND")
	)
	(via
		(at 125.506226 -404.46452)
		(size 0.4064)
		(drill 0.2032)
		(layers "F.Cu" "B.Cu")
		(net "GND")
	)
	(via
		(at 412.486856 -164.946838)
		(size 0.49022)
		(drill 0.254)
		(layers "F.Cu" "B.Cu")
		(net "GND")
	)
	(via
		(at 385.394708 -286.236156)
		(size 0.4064)
		(drill 0.2032)
		(layers "F.Cu" "B.Cu")
		(net "GND")
	)
	(via
		(at 93.7514 -146.6596)
		(size 0.508)
		(drill 0.254)
		(layers "F.Cu" "B.Cu")
		(net "GND")
	)
	(via
		(at 42.955718 -305.285394)
		(size 0.4826)
		(drill 0.254)
		(layers "F.Cu" "B.Cu")
		(net "GND")
	)
	(via
		(at 20.59051 -304.010314)
		(size 0.4826)
		(drill 0.254)
		(layers "F.Cu" "B.Cu")
		(net "GND")
	)
	(via
		(at 467.5378 -356.667054)
		(size 0.508)
		(drill 0.254)
		(layers "F.Cu" "B.Cu")
		(net "GND")
	)
	(via
		(at 94.861126 -242.864386)
		(size 0.4064)
		(drill 0.2032)
		(layers "F.Cu" "B.Cu")
		(net "GND")
	)
	(via
		(at 109.547914 -261.323074)
		(size 0.4826)
		(drill 0.254)
		(layers "F.Cu" "B.Cu")
		(net "GND")
	)
	(via
		(at 399.297144 -331.745082)
		(size 0.508)
		(drill 0.254)
		(layers "F.Cu" "B.Cu")
		(net "GND")
	)
	(via
		(at 400.009868 -6.598158)
		(size 0.508)
		(drill 0.254)
		(layers "F.Cu" "B.Cu")
		(net "GND")
	)
	(via
		(at 424.012106 -215.18499)
		(size 0.4826)
		(drill 0.254)
		(layers "F.Cu" "B.Cu")
		(net "GND")
	)
	(via
		(at 165.44417 -393.902438)
		(size 0.4572)
		(drill 0.254)
		(layers "F.Cu" "B.Cu")
		(net "GND")
	)
	(via
		(at 362.853986 -346.785184)
		(size 0.508)
		(drill 0.254)
		(layers "F.Cu" "B.Cu")
		(net "GND")
	)
	(via
		(at 230.38689 -149.903688)
		(size 0.508)
		(drill 0.254)
		(layers "F.Cu" "B.Cu")
		(net "GND")
	)
	(via
		(at 458.60335 -37.265864)
		(size 0.508)
		(drill 0.254)
		(layers "F.Cu" "B.Cu")
		(net "GND")
	)
	(via
		(at 296.770044 -390.92632)
		(size 0.508)
		(drill 0.254)
		(layers "F.Cu" "B.Cu")
		(net "GND")
	)
	(via
		(at 195.721732 -304.860452)
		(size 0.4826)
		(drill 0.254)
		(layers "F.Cu" "B.Cu")
		(net "GND")
	)
	(via
		(at 206.248 -255.13538)
		(size 0.4826)
		(drill 0.254)
		(layers "F.Cu" "B.Cu")
		(net "GND")
	)
	(via
		(at 314.044838 -421.586152)
		(size 0.4572)
		(drill 0.254)
		(layers "F.Cu" "B.Cu")
		(net "GND")
	)
	(via
		(at 119.59463 -268.416278)
		(size 0.4064)
		(drill 0.2032)
		(layers "F.Cu" "B.Cu")
		(net "GND")
	)
	(via
		(at 346.091002 -250.154186)
		(size 0.4064)
		(drill 0.2032)
		(layers "F.Cu" "B.Cu")
		(net "GND")
	)
	(via
		(at 49.167034 -18.247106)
		(size 0.508)
		(drill 0.254)
		(layers "F.Cu" "B.Cu")
		(net "GND")
	)
	(via
		(at 404.104856 -169.02176)
		(size 0.49022)
		(drill 0.254)
		(layers "F.Cu" "B.Cu")
		(net "GND")
	)
	(via
		(at 292.02761 -346.317316)
		(size 0.49022)
		(drill 0.254)
		(layers "F.Cu" "B.Cu")
		(net "GND")
	)
	(via
		(at 404.833074 -170.53306)
		(size 0.49022)
		(drill 0.254)
		(layers "F.Cu" "B.Cu")
		(net "GND")
	)
	(via
		(at 238.611664 -370.071904)
		(size 0.508)
		(drill 0.254)
		(layers "F.Cu" "B.Cu")
		(net "GND")
	)
	(via
		(at 336.22107 -239.624108)
		(size 0.4064)
		(drill 0.2032)
		(layers "F.Cu" "B.Cu")
		(net "GND")
	)
	(via
		(at 394.956538 -180.415438)
		(size 0.508)
		(drill 0.254)
		(layers "F.Cu" "B.Cu")
		(net "GND")
	)
	(via
		(at 353.911154 -267.606018)
		(size 0.4064)
		(drill 0.2032)
		(layers "F.Cu" "B.Cu")
		(net "GND")
	)
	(via
		(at 312.786014 -421.586152)
		(size 0.4572)
		(drill 0.254)
		(layers "F.Cu" "B.Cu")
		(net "GND")
	)
	(via
		(at 82.001106 -270.03629)
		(size 0.4064)
		(drill 0.2032)
		(layers "F.Cu" "B.Cu")
		(net "GND")
	)
	(via
		(at 337.631024 -232.334054)
		(size 0.4064)
		(drill 0.2032)
		(layers "F.Cu" "B.Cu")
		(net "GND")
	)
	(via
		(at 71.09333 -181.530498)
		(size 0.508)
		(drill 0.254)
		(layers "F.Cu" "B.Cu")
		(net "GND")
	)
	(via
		(at 348.895162 -259.729986)
		(size 0.4826)
		(drill 0.254)
		(layers "F.Cu" "B.Cu")
		(net "GND")
	)
	(via
		(at 449.354702 -391.457688)
		(size 0.508)
		(drill 0.254)
		(layers "F.Cu" "B.Cu")
		(net "GND")
	)
	(via
		(at 239.465866 -70.543674)
		(size 0.508)
		(drill 0.254)
		(layers "F.Cu" "B.Cu")
		(net "GND")
	)
	(via
		(at 389.653018 -401.873212)
		(size 0.508)
		(drill 0.254)
		(layers "F.Cu" "B.Cu")
		(net "GND")
	)
	(via
		(at 277.61692 -430.791366)
		(size 0.508)
		(drill 0.254)
		(layers "F.Cu" "B.Cu")
		(net "GND")
	)
	(via
		(at 139.974828 -234.764326)
		(size 0.4064)
		(drill 0.2032)
		(layers "F.Cu" "B.Cu")
		(net "GND")
	)
	(via
		(at 345.151202 -235.574078)
		(size 0.4064)
		(drill 0.2032)
		(layers "F.Cu" "B.Cu")
		(net "GND")
	)
	(via
		(at 44.340018 -216.885266)
		(size 0.4826)
		(drill 0.254)
		(layers "F.Cu" "B.Cu")
		(net "GND")
	)
	(via
		(at 467.5378 -94.031054)
		(size 0.508)
		(drill 0.254)
		(layers "F.Cu" "B.Cu")
		(net "GND")
	)
	(via
		(at 344.950034 -419.046152)
		(size 0.4572)
		(drill 0.254)
		(layers "F.Cu" "B.Cu")
		(net "GND")
	)
	(via
		(at 79.114904 -394.352018)
		(size 0.508)
		(drill 0.254)
		(layers "F.Cu" "B.Cu")
		(net "GND")
	)
	(via
		(at 401.270978 -170.502072)
		(size 0.508)
		(drill 0.254)
		(layers "F.Cu" "B.Cu")
		(net "GND")
	)
	(via
		(at 97.211134 -235.574332)
		(size 0.4064)
		(drill 0.2032)
		(layers "F.Cu" "B.Cu")
		(net "GND")
	)
	(via
		(at 100.885498 -351.371916)
		(size 0.508)
		(drill 0.254)
		(layers "F.Cu" "B.Cu")
		(net "GND")
	)
	(via
		(at 294.606472 -211.360004)
		(size 0.4826)
		(drill 0.254)
		(layers "F.Cu" "B.Cu")
		(net "GND")
	)
	(via
		(at 386.974842 -221.80423)
		(size 0.4064)
		(drill 0.2032)
		(layers "F.Cu" "B.Cu")
		(net "GND")
	)
	(via
		(at 176.072038 -299.335444)
		(size 0.4826)
		(drill 0.254)
		(layers "F.Cu" "B.Cu")
		(net "GND")
	)
	(via
		(at 373.134636 -423.619676)
		(size 0.508)
		(drill 0.254)
		(layers "F.Cu" "B.Cu")
		(net "GND")
	)
	(via
		(at 73.24979 -438.499758)
		(size 0.4572)
		(drill 0.2032)
		(layers "F.Cu" "B.Cu")
		(net "GND")
	)
	(via
		(at 115.341146 -418.99205)
		(size 0.508)
		(drill 0.254)
		(layers "F.Cu" "B.Cu")
		(net "GND")
	)
	(via
		(at 165.56736 -398.209008)
		(size 0.508)
		(drill 0.254)
		(layers "F.Cu" "B.Cu")
		(net "GND")
	)
	(via
		(at 137.154666 -231.524302)
		(size 0.4064)
		(drill 0.2032)
		(layers "F.Cu" "B.Cu")
		(net "GND")
	)
	(via
		(at 55.328058 -250.885198)
		(size 0.4826)
		(drill 0.254)
		(layers "F.Cu" "B.Cu")
		(net "GND")
	)
	(via
		(at 383.514854 -265.176)
		(size 0.4064)
		(drill 0.2032)
		(layers "F.Cu" "B.Cu")
		(net "GND")
	)
	(via
		(at 247.825006 -39.8653)
		(size 0.508)
		(drill 0.254)
		(layers "F.Cu" "B.Cu")
		(net "GND")
	)
	(via
		(at 376.550174 -416.020504)
		(size 0.4572)
		(drill 0.254)
		(layers "F.Cu" "B.Cu")
		(net "GND")
	)
	(via
		(at 128.694688 -239.624362)
		(size 0.4064)
		(drill 0.2032)
		(layers "F.Cu" "B.Cu")
		(net "GND")
	)
	(via
		(at 58.043826 -230.485442)
		(size 0.4826)
		(drill 0.254)
		(layers "F.Cu" "B.Cu")
		(net "GND")
	)
	(via
		(at 44.065952 -383.7432)
		(size 0.508)
		(drill 0.254)
		(layers "F.Cu" "B.Cu")
		(net "GND")
	)
	(via
		(at 135.14578 -12.495022)
		(size 0.508)
		(drill 0.254)
		(layers "F.Cu" "B.Cu")
		(net "GND")
	)
	(via
		(at 350.717866 -415.38652)
		(size 0.4064)
		(drill 0.2032)
		(layers "F.Cu" "B.Cu")
		(net "GND")
	)
	(via
		(at 114.830606 -334.282796)
		(size 0.508)
		(drill 0.254)
		(layers "F.Cu" "B.Cu")
		(net "GND")
	)
	(via
		(at 307.368194 -301.034958)
		(size 0.4826)
		(drill 0.254)
		(layers "F.Cu" "B.Cu")
		(net "GND")
	)
	(via
		(at 17.608042 -262.785352)
		(size 0.4826)
		(drill 0.254)
		(layers "F.Cu" "B.Cu")
		(net "GND")
	)
	(via
		(at 393.132818 -397.274542)
		(size 0.508)
		(drill 0.254)
		(layers "F.Cu" "B.Cu")
		(net "GND")
	)
	(via
		(at 193.42354 -416.162236)
		(size 0.508)
		(drill 0.254)
		(layers "F.Cu" "B.Cu")
		(net "GND")
	)
	(via
		(at 142.154656 -287.856422)
		(size 0.4064)
		(drill 0.2032)
		(layers "F.Cu" "B.Cu")
		(net "GND")
	)
	(via
		(at 344.681048 -228.284278)
		(size 0.4064)
		(drill 0.2032)
		(layers "F.Cu" "B.Cu")
		(net "GND")
	)
	(via
		(at 413.271208 -361.877864)
		(size 0.508)
		(drill 0.254)
		(layers "F.Cu" "B.Cu")
		(net "GND")
	)
	(via
		(at 329.6412 -249.34418)
		(size 0.4064)
		(drill 0.2032)
		(layers "F.Cu" "B.Cu")
		(net "GND")
	)
	(via
		(at 384.569462 -412.84652)
		(size 0.4064)
		(drill 0.2032)
		(layers "F.Cu" "B.Cu")
		(net "GND")
	)
	(via
		(at 405.34971 -428.851314)
		(size 0.4572)
		(drill 0.2032)
		(layers "F.Cu" "B.Cu")
		(net "GND")
	)
	(via
		(at 148.550122 -6.042152)
		(size 0.508)
		(drill 0.254)
		(layers "F.Cu" "B.Cu")
		(net "GND")
	)
	(via
		(at 80.761078 -223.424496)
		(size 0.4064)
		(drill 0.2032)
		(layers "F.Cu" "B.Cu")
		(net "GND")
	)
	(via
		(at 93.280992 -265.176254)
		(size 0.4064)
		(drill 0.2032)
		(layers "F.Cu" "B.Cu")
		(net "GND")
	)
	(via
		(at 127.297434 -160.042098)
		(size 0.508)
		(drill 0.254)
		(layers "F.Cu" "B.Cu")
		(net "GND")
	)
	(via
		(at 113.184686 -237.194344)
		(size 0.4064)
		(drill 0.2032)
		(layers "F.Cu" "B.Cu")
		(net "GND")
	)
	(via
		(at 381.716534 -391.23493)
		(size 0.4064)
		(drill 0.2032)
		(layers "F.Cu" "B.Cu")
		(net "GND")
	)
	(via
		(at 336.249518 -438.651396)
		(size 0.4572)
		(drill 0.2032)
		(layers "F.Cu" "B.Cu")
		(net "GND")
	)
	(via
		(at 202.147932 -208.38541)
		(size 0.4826)
		(drill 0.254)
		(layers "F.Cu" "B.Cu")
		(net "GND")
	)
	(via
		(at 71.277734 -375.432828)
		(size 0.508)
		(drill 0.254)
		(layers "F.Cu" "B.Cu")
		(net "GND")
	)
	(via
		(at 105.66781 -253.392432)
		(size 0.4064)
		(drill 0.2032)
		(layers "F.Cu" "B.Cu")
		(net "GND")
	)
	(via
		(at 26.536396 -219.435426)
		(size 0.4826)
		(drill 0.254)
		(layers "F.Cu" "B.Cu")
		(net "GND")
	)
	(via
		(at 339.518752 -398.542002)
		(size 0.4064)
		(drill 0.2032)
		(layers "F.Cu" "B.Cu")
		(net "GND")
	)
	(via
		(at 330.93406 -328.106786)
		(size 0.508)
		(drill 0.254)
		(layers "F.Cu" "B.Cu")
		(net "GND")
	)
	(via
		(at 94.861126 -252.584458)
		(size 0.4064)
		(drill 0.2032)
		(layers "F.Cu" "B.Cu")
		(net "GND")
	)
	(via
		(at 29.252164 -204.135228)
		(size 0.4826)
		(drill 0.254)
		(layers "F.Cu" "B.Cu")
		(net "GND")
	)
	(via
		(at 86.020656 -177.71364)
		(size 0.508)
		(drill 0.254)
		(layers "F.Cu" "B.Cu")
		(net "GND")
	)
	(via
		(at 299.82414 -278.93518)
		(size 0.4826)
		(drill 0.254)
		(layers "F.Cu" "B.Cu")
		(net "GND")
	)
	(via
		(at 76.802742 -333.842868)
		(size 0.49022)
		(drill 0.254)
		(layers "F.Cu" "B.Cu")
		(net "GND")
	)
	(via
		(at 195.924424 -42.549572)
		(size 0.508)
		(drill 0.254)
		(layers "F.Cu" "B.Cu")
		(net "GND")
	)
	(via
		(at 152.714198 -413.204152)
		(size 0.4572)
		(drill 0.254)
		(layers "F.Cu" "B.Cu")
		(net "GND")
	)
	(via
		(at 394.613638 -179.120038)
		(size 0.508)
		(drill 0.254)
		(layers "F.Cu" "B.Cu")
		(net "GND")
	)
	(via
		(at 68.766436 -409.396184)
		(size 0.4572)
		(drill 0.254)
		(layers "F.Cu" "B.Cu")
		(net "GND")
	)
	(via
		(at 270.650208 -68.946014)
		(size 0.508)
		(drill 0.254)
		(layers "F.Cu" "B.Cu")
		(net "GND")
	)
	(via
		(at 335.11109 -293.525956)
		(size 0.4064)
		(drill 0.2032)
		(layers "F.Cu" "B.Cu")
		(net "GND")
	)
	(via
		(at 350.791018 -243.674138)
		(size 0.4064)
		(drill 0.2032)
		(layers "F.Cu" "B.Cu")
		(net "GND")
	)
	(via
		(at 348.911164 -246.914162)
		(size 0.4064)
		(drill 0.2032)
		(layers "F.Cu" "B.Cu")
		(net "GND")
	)
	(via
		(at 125.145038 -411.936184)
		(size 0.4572)
		(drill 0.254)
		(layers "F.Cu" "B.Cu")
		(net "GND")
	)
	(via
		(at 361.894882 -266.796012)
		(size 0.4064)
		(drill 0.2032)
		(layers "F.Cu" "B.Cu")
		(net "GND")
	)
	(via
		(at 344.511122 -264.365994)
		(size 0.4064)
		(drill 0.2032)
		(layers "F.Cu" "B.Cu")
		(net "GND")
	)
	(via
		(at 350.446086 -396.710662)
		(size 0.4064)
		(drill 0.2032)
		(layers "F.Cu" "B.Cu")
		(net "GND")
	)
	(via
		(at 348.04604 -396.710662)
		(size 0.4064)
		(drill 0.2032)
		(layers "F.Cu" "B.Cu")
		(net "GND")
	)
	(via
		(at 148.789644 -371.49913)
		(size 0.508)
		(drill 0.254)
		(layers "F.Cu" "B.Cu")
		(net "GND")
	)
	(via
		(at 298.090844 -390.92632)
		(size 0.508)
		(drill 0.254)
		(layers "F.Cu" "B.Cu")
		(net "GND")
	)
	(via
		(at 396.349474 -432.451256)
		(size 0.4572)
		(drill 0.2032)
		(layers "F.Cu" "B.Cu")
		(net "GND")
	)
	(via
		(at 363.774736 -287.856168)
		(size 0.4064)
		(drill 0.2032)
		(layers "F.Cu" "B.Cu")
		(net "GND")
	)
	(via
		(at 273.092164 -307.835046)
		(size 0.4826)
		(drill 0.254)
		(layers "F.Cu" "B.Cu")
		(net "GND")
	)
	(via
		(at 444.391034 -64.088518)
		(size 0.508)
		(drill 0.254)
		(layers "F.Cu" "B.Cu")
		(net "GND")
	)
	(via
		(at 49.128172 -407.638504)
		(size 0.4572)
		(drill 0.254)
		(layers "F.Cu" "B.Cu")
		(net "GND")
	)
	(via
		(at 13.221208 -427.742858)
		(size 0.508)
		(drill 0.254)
		(layers "F.Cu" "B.Cu")
		(net "GND")
	)
	(via
		(at 203.265532 -211.360258)
		(size 0.4826)
		(drill 0.254)
		(layers "F.Cu" "B.Cu")
		(net "GND")
	)
	(via
		(at 357.841042 -247.724168)
		(size 0.4064)
		(drill 0.2032)
		(layers "F.Cu" "B.Cu")
		(net "GND")
	)
	(via
		(at 246.881396 -439.90768)
		(size 0.508)
		(drill 0.254)
		(layers "F.Cu" "B.Cu")
		(net "GND")
	)
	(via
		(at 372.404894 -248.534174)
		(size 0.4064)
		(drill 0.2032)
		(layers "F.Cu" "B.Cu")
		(net "GND")
	)
	(via
		(at 303.276 -360.172)
		(size 0.508)
		(drill 0.254)
		(layers "F.Cu" "B.Cu")
		(net "GND")
	)
	(via
		(at 440.217814 -210.51012)
		(size 0.4826)
		(drill 0.254)
		(layers "F.Cu" "B.Cu")
		(net "GND")
	)
	(via
		(at 337.92668 -331.729334)
		(size 0.508)
		(drill 0.254)
		(layers "F.Cu" "B.Cu")
		(net "GND")
	)
	(via
		(at 49.668176 -9.424924)
		(size 0.508)
		(drill 0.254)
		(layers "F.Cu" "B.Cu")
		(net "GND")
	)
	(via
		(at 302.150526 -286.16021)
		(size 0.4826)
		(drill 0.254)
		(layers "F.Cu" "B.Cu")
		(net "GND")
	)
	(via
		(at 352.031046 -285.42615)
		(size 0.4064)
		(drill 0.2032)
		(layers "F.Cu" "B.Cu")
		(net "GND")
	)
	(via
		(at 128.994662 -274.896326)
		(size 0.4064)
		(drill 0.2032)
		(layers "F.Cu" "B.Cu")
		(net "GND")
	)
	(via
		(at 376.634756 -228.284278)
		(size 0.4064)
		(drill 0.2032)
		(layers "F.Cu" "B.Cu")
		(net "GND")
	)
	(via
		(at 151.34971 -426.69968)
		(size 0.4572)
		(drill 0.2032)
		(layers "F.Cu" "B.Cu")
		(net "GND")
	)
	(via
		(at 33.81248 -369.506754)
		(size 0.508)
		(drill 0.254)
		(layers "F.Cu" "B.Cu")
		(net "GND")
	)
	(via
		(at 215.139778 -386.450332)
		(size 0.508)
		(drill 0.254)
		(layers "F.Cu" "B.Cu")
		(net "GND")
	)
	(via
		(at 376.634756 -255.824228)
		(size 0.4064)
		(drill 0.2032)
		(layers "F.Cu" "B.Cu")
		(net "GND")
	)
	(via
		(at 329.633834 -417.778184)
		(size 0.4572)
		(drill 0.254)
		(layers "F.Cu" "B.Cu")
		(net "GND")
	)
	(via
		(at 143.264636 -233.95432)
		(size 0.4064)
		(drill 0.2032)
		(layers "F.Cu" "B.Cu")
		(net "GND")
	)
	(via
		(at 332.581504 -380.54153)
		(size 0.508)
		(drill 0.254)
		(layers "F.Cu" "B.Cu")
		(net "GND")
	)
	(via
		(at 34.080196 -296.785284)
		(size 0.4826)
		(drill 0.254)
		(layers "F.Cu" "B.Cu")
		(net "GND")
	)
	(via
		(at 365.380778 -260.28015)
		(size 0.4826)
		(drill 0.254)
		(layers "F.Cu" "B.Cu")
		(net "GND")
	)
	(via
		(at 344.511122 -283.806138)
		(size 0.4064)
		(drill 0.2032)
		(layers "F.Cu" "B.Cu")
		(net "GND")
	)
	(via
		(at 176.81067 -92.493846)
		(size 0.508)
		(drill 0.254)
		(layers "F.Cu" "B.Cu")
		(net "GND")
	)
	(via
		(at 275.807932 -314.635134)
		(size 0.4826)
		(drill 0.254)
		(layers "F.Cu" "B.Cu")
		(net "GND")
	)
	(via
		(at 356.538022 -256.387346)
		(size 0.4826)
		(drill 0.254)
		(layers "F.Cu" "B.Cu")
		(net "GND")
	)
	(via
		(at 419.979856 -423.777664)
		(size 0.508)
		(drill 0.254)
		(layers "F.Cu" "B.Cu")
		(net "GND")
	)
	(via
		(at 182.332122 -116.642642)
		(size 0.4572)
		(drill 0.254)
		(layers "F.Cu" "B.Cu")
		(net "GND")
	)
	(via
		(at 85.628734 -335.544414)
		(size 0.49022)
		(drill 0.254)
		(layers "F.Cu" "B.Cu")
		(net "GND")
	)
	(via
		(at 353.61118 -243.674138)
		(size 0.4064)
		(drill 0.2032)
		(layers "F.Cu" "B.Cu")
		(net "GND")
	)
	(via
		(at 321.975734 -421.586152)
		(size 0.4572)
		(drill 0.254)
		(layers "F.Cu" "B.Cu")
		(net "GND")
	)
	(via
		(at 104.731058 -233.95432)
		(size 0.4064)
		(drill 0.2032)
		(layers "F.Cu" "B.Cu")
		(net "GND")
	)
	(via
		(at 182.939182 -350.896428)
		(size 0.49022)
		(drill 0.254)
		(layers "F.Cu" "B.Cu")
		(net "GND")
	)
	(via
		(at 365.190278 -177.205386)
		(size 0.49022)
		(drill 0.254)
		(layers "F.Cu" "B.Cu")
		(net "GND")
	)
	(via
		(at 122.884692 -270.846296)
		(size 0.4064)
		(drill 0.2032)
		(layers "F.Cu" "B.Cu")
		(net "GND")
	)
	(via
		(at 296.62882 -351.73158)
		(size 0.508)
		(drill 0.254)
		(layers "F.Cu" "B.Cu")
		(net "GND")
	)
	(via
		(at 372.261892 -379.88113)
		(size 0.508)
		(drill 0.254)
		(layers "F.Cu" "B.Cu")
		(net "GND")
	)
	(via
		(at 334.79994 -335.539588)
		(size 0.49022)
		(drill 0.254)
		(layers "F.Cu" "B.Cu")
		(net "GND")
	)
	(via
		(at 332.779624 -74.184764)
		(size 0.508)
		(drill 0.254)
		(layers "F.Cu" "B.Cu")
		(net "GND")
	)
	(via
		(at 381.506222 -412.84652)
		(size 0.4064)
		(drill 0.2032)
		(layers "F.Cu" "B.Cu")
		(net "GND")
	)
	(via
		(at 366.764824 -243.674138)
		(size 0.4064)
		(drill 0.2032)
		(layers "F.Cu" "B.Cu")
		(net "GND")
	)
	(via
		(at 140.461238 -413.204152)
		(size 0.4572)
		(drill 0.254)
		(layers "F.Cu" "B.Cu")
		(net "GND")
	)
	(via
		(at 77.271118 -335.558892)
		(size 0.49022)
		(drill 0.254)
		(layers "F.Cu" "B.Cu")
		(net "GND")
	)
	(via
		(at 29.110178 -6.598158)
		(size 0.508)
		(drill 0.254)
		(layers "F.Cu" "B.Cu")
		(net "GND")
	)
	(via
		(at 86.344252 -391.830814)
		(size 0.4064)
		(drill 0.2032)
		(layers "F.Cu" "B.Cu")
		(net "GND")
	)
	(via
		(at 301.04461 -344.77706)
		(size 0.49022)
		(drill 0.254)
		(layers "F.Cu" "B.Cu")
		(net "GND")
	)
	(via
		(at 343.101168 -292.71595)
		(size 0.4064)
		(drill 0.2032)
		(layers "F.Cu" "B.Cu")
		(net "GND")
	)
	(via
		(at 356.77221 -259.845048)
		(size 0.4826)
		(drill 0.254)
		(layers "F.Cu" "B.Cu")
		(net "GND")
	)
	(via
		(at 107.85094 -280.566368)
		(size 0.4064)
		(drill 0.2032)
		(layers "F.Cu" "B.Cu")
		(net "GND")
	)
	(via
		(at 57.783222 -171.934124)
		(size 0.508)
		(drill 0.254)
		(layers "F.Cu" "B.Cu")
		(net "GND")
	)
	(via
		(at 302.603154 -441.227718)
		(size 0.508)
		(drill 0.254)
		(layers "F.Cu" "B.Cu")
		(net "GND")
	)
	(via
		(at 88.979502 -373.96293)
		(size 0.508)
		(drill 0.254)
		(layers "F.Cu" "B.Cu")
		(net "GND")
	)
	(via
		(at 100.616766 -339.018118)
		(size 0.49022)
		(drill 0.254)
		(layers "F.Cu" "B.Cu")
		(net "GND")
	)
	(via
		(at 345.451176 -274.086066)
		(size 0.4064)
		(drill 0.2032)
		(layers "F.Cu" "B.Cu")
		(net "GND")
	)
	(via
		(at 77.128878 -178.51501)
		(size 0.49022)
		(drill 0.254)
		(layers "F.Cu" "B.Cu")
		(net "GND")
	)
	(via
		(at 182.231792 -202.435206)
		(size 0.4826)
		(drill 0.254)
		(layers "F.Cu" "B.Cu")
		(net "GND")
	)
	(via
		(at 84.79282 -355.320346)
		(size 0.508)
		(drill 0.254)
		(layers "F.Cu" "B.Cu")
		(net "GND")
	)
	(via
		(at 96.74098 -247.724422)
		(size 0.4064)
		(drill 0.2032)
		(layers "F.Cu" "B.Cu")
		(net "GND")
	)
	(via
		(at 344.681048 -247.724168)
		(size 0.4064)
		(drill 0.2032)
		(layers "F.Cu" "B.Cu")
		(net "GND")
	)
	(via
		(at 55.966614 -374.62333)
		(size 0.508)
		(drill 0.254)
		(layers "F.Cu" "B.Cu")
		(net "GND")
	)
	(via
		(at 81.230978 -250.15444)
		(size 0.4064)
		(drill 0.2032)
		(layers "F.Cu" "B.Cu")
		(net "GND")
	)
	(via
		(at 128.694688 -241.244374)
		(size 0.4064)
		(drill 0.2032)
		(layers "F.Cu" "B.Cu")
		(net "GND")
	)
	(via
		(at 118.515384 -441.227718)
		(size 0.508)
		(drill 0.254)
		(layers "F.Cu" "B.Cu")
		(net "GND")
	)
	(via
		(at 48.328834 -424.625262)
		(size 0.508)
		(drill 0.254)
		(layers "F.Cu" "B.Cu")
		(net "GND")
	)
	(via
		(at 382.676654 -419.046152)
		(size 0.4572)
		(drill 0.254)
		(layers "F.Cu" "B.Cu")
		(net "GND")
	)
	(via
		(at 366.661954 -136.986772)
		(size 0.508)
		(drill 0.254)
		(layers "F.Cu" "B.Cu")
		(net "GND")
	)
	(via
		(at 143.56461 -269.226284)
		(size 0.4064)
		(drill 0.2032)
		(layers "F.Cu" "B.Cu")
		(net "GND")
	)
	(via
		(at 89.99093 -269.226284)
		(size 0.4064)
		(drill 0.2032)
		(layers "F.Cu" "B.Cu")
		(net "GND")
	)
	(via
		(at 78.41107 -243.674392)
		(size 0.4064)
		(drill 0.2032)
		(layers "F.Cu" "B.Cu")
		(net "GND")
	)
	(via
		(at 331.521054 -234.764072)
		(size 0.4064)
		(drill 0.2032)
		(layers "F.Cu" "B.Cu")
		(net "GND")
	)
	(via
		(at 338.174584 -380.54153)
		(size 0.508)
		(drill 0.254)
		(layers "F.Cu" "B.Cu")
		(net "GND")
	)
	(via
		(at 111.394494 -335.691988)
		(size 0.508)
		(drill 0.254)
		(layers "F.Cu" "B.Cu")
		(net "GND")
	)
	(via
		(at 146.761454 -118.364)
		(size 0.508)
		(drill 0.254)
		(layers "F.Cu" "B.Cu")
		(net "GND")
	)
	(via
		(at 324.677786 -412.84652)
		(size 0.4064)
		(drill 0.2032)
		(layers "F.Cu" "B.Cu")
		(net "GND")
	)
	(via
		(at 83.388962 -372.15953)
		(size 0.508)
		(drill 0.254)
		(layers "F.Cu" "B.Cu")
		(net "GND")
	)
	(via
		(at 29.915358 -344.781886)
		(size 0.49022)
		(drill 0.254)
		(layers "F.Cu" "B.Cu")
		(net "GND")
	)
	(via
		(at 316.578234 -394.831062)
		(size 0.4064)
		(drill 0.2032)
		(layers "F.Cu" "B.Cu")
		(net "GND")
	)
	(via
		(at 75.449684 -340.503764)
		(size 0.508)
		(drill 0.254)
		(layers "F.Cu" "B.Cu")
		(net "GND")
	)
	(via
		(at 96.571054 -264.366248)
		(size 0.4064)
		(drill 0.2032)
		(layers "F.Cu" "B.Cu")
		(net "GND")
	)
	(via
		(at 415.779966 -136.82726)
		(size 0.508)
		(drill 0.254)
		(layers "F.Cu" "B.Cu")
		(net "GND")
	)
	(via
		(at 327.249536 -436.347362)
		(size 0.4572)
		(drill 0.2032)
		(layers "F.Cu" "B.Cu")
		(net "GND")
	)
	(via
		(at 367.067846 -264.368026)
		(size 0.4064)
		(drill 0.2032)
		(layers "F.Cu" "B.Cu")
		(net "GND")
	)
	(via
		(at 107.85094 -274.08632)
		(size 0.4064)
		(drill 0.2032)
		(layers "F.Cu" "B.Cu")
		(net "GND")
	)
	(via
		(at 454.188068 -251.735082)
		(size 0.4826)
		(drill 0.254)
		(layers "F.Cu" "B.Cu")
		(net "GND")
	)
	(via
		(at 202.147932 -244.085364)
		(size 0.4826)
		(drill 0.254)
		(layers "F.Cu" "B.Cu")
		(net "GND")
	)
	(via
		(at 56.05399 -18.247868)
		(size 0.508)
		(drill 0.254)
		(layers "F.Cu" "B.Cu")
		(net "GND")
	)
	(via
		(at 95.301562 -374.62333)
		(size 0.508)
		(drill 0.254)
		(layers "F.Cu" "B.Cu")
		(net "GND")
	)
	(via
		(at 159.501332 -420.144956)
		(size 0.508)
		(drill 0.254)
		(layers "F.Cu" "B.Cu")
		(net "GND")
	)
	(via
		(at 426.494956 -18.503138)
		(size 0.508)
		(drill 0.254)
		(layers "F.Cu" "B.Cu")
		(net "GND")
	)
	(via
		(at 312.424826 -420.952168)
		(size 0.4064)
		(drill 0.2032)
		(layers "F.Cu" "B.Cu")
		(net "GND")
	)
	(via
		(at 416.468052 -253.435104)
		(size 0.4826)
		(drill 0.254)
		(layers "F.Cu" "B.Cu")
		(net "GND")
	)
	(via
		(at 164.105844 -369.03533)
		(size 0.508)
		(drill 0.254)
		(layers "F.Cu" "B.Cu")
		(net "GND")
	)
	(via
		(at 118.65483 -291.096192)
		(size 0.4064)
		(drill 0.2032)
		(layers "F.Cu" "B.Cu")
		(net "GND")
	)
	(via
		(at 113.48466 -280.566368)
		(size 0.4064)
		(drill 0.2032)
		(layers "F.Cu" "B.Cu")
		(net "GND")
	)
	(via
		(at 202.147932 -264.485374)
		(size 0.4826)
		(drill 0.254)
		(layers "F.Cu" "B.Cu")
		(net "GND")
	)
	(via
		(at 449.71208 -93.509592)
		(size 0.508)
		(drill 0.254)
		(layers "F.Cu" "B.Cu")
		(net "GND")
	)
	(via
		(at 42.839894 -370.83873)
		(size 0.508)
		(drill 0.254)
		(layers "F.Cu" "B.Cu")
		(net "GND")
	)
	(via
		(at 29.252164 -299.335444)
		(size 0.4826)
		(drill 0.254)
		(layers "F.Cu" "B.Cu")
		(net "GND")
	)
	(via
		(at 394.982954 -261.670038)
		(size 0.4064)
		(drill 0.2032)
		(layers "F.Cu" "B.Cu")
		(net "GND")
	)
	(via
		(at 85.290914 -288.666174)
		(size 0.4064)
		(drill 0.2032)
		(layers "F.Cu" "B.Cu")
		(net "GND")
	)
	(via
		(at 389.389874 -183.14289)
		(size 0.49022)
		(drill 0.254)
		(layers "F.Cu" "B.Cu")
		(net "GND")
	)
	(via
		(at 16.25346 -396.792958)
		(size 0.508)
		(drill 0.254)
		(layers "F.Cu" "B.Cu")
		(net "GND")
	)
	(via
		(at 288.180018 -204.985112)
		(size 0.4826)
		(drill 0.254)
		(layers "F.Cu" "B.Cu")
		(net "GND")
	)
	(via
		(at 211.149692 -26.468324)
		(size 0.508)
		(drill 0.254)
		(layers "F.Cu" "B.Cu")
		(net "GND")
	)
	(via
		(at 388.68477 -288.66592)
		(size 0.4064)
		(drill 0.2032)
		(layers "F.Cu" "B.Cu")
		(net "GND")
	)
	(via
		(at 192.560194 -43.849544)
		(size 0.508)
		(drill 0.254)
		(layers "F.Cu" "B.Cu")
		(net "GND")
	)
	(via
		(at 153.349706 -438.499758)
		(size 0.4572)
		(drill 0.2032)
		(layers "F.Cu" "B.Cu")
		(net "GND")
	)
	(via
		(at 380.835154 -441.227718)
		(size 0.508)
		(drill 0.254)
		(layers "F.Cu" "B.Cu")
		(net "GND")
	)
	(via
		(at 394.68298 -241.510058)
		(size 0.4064)
		(drill 0.2032)
		(layers "F.Cu" "B.Cu")
		(net "GND")
	)
	(via
		(at 101.27107 -270.846296)
		(size 0.4064)
		(drill 0.2032)
		(layers "F.Cu" "B.Cu")
		(net "GND")
	)
	(via
		(at 284.736032 -310.384952)
		(size 0.4826)
		(drill 0.254)
		(layers "F.Cu" "B.Cu")
		(net "GND")
	)
	(via
		(at 417.585652 -285.310072)
		(size 0.4826)
		(drill 0.254)
		(layers "F.Cu" "B.Cu")
		(net "GND")
	)
	(via
		(at 85.60562 -177.2285)
		(size 0.508)
		(drill 0.254)
		(layers "F.Cu" "B.Cu")
		(net "GND")
	)
	(via
		(at 363.944916 -242.054126)
		(size 0.4064)
		(drill 0.2032)
		(layers "F.Cu" "B.Cu")
		(net "GND")
	)
	(via
		(at 337.631024 -240.434114)
		(size 0.4064)
		(drill 0.2032)
		(layers "F.Cu" "B.Cu")
		(net "GND")
	)
	(via
		(at 308.71541 -346.317316)
		(size 0.49022)
		(drill 0.254)
		(layers "F.Cu" "B.Cu")
		(net "GND")
	)
	(via
		(at 9.106408 -173.71314)
		(size 0.508)
		(drill 0.254)
		(layers "F.Cu" "B.Cu")
		(net "GND")
	)
	(via
		(at 91.740736 -413.204152)
		(size 0.4572)
		(drill 0.254)
		(layers "F.Cu" "B.Cu")
		(net "GND")
	)
	(via
		(at 375.379742 -412.84652)
		(size 0.4064)
		(drill 0.2032)
		(layers "F.Cu" "B.Cu")
		(net "GND")
	)
	(via
		(at 80.249776 -435.0512)
		(size 0.4572)
		(drill 0.2032)
		(layers "F.Cu" "B.Cu")
		(net "GND")
	)
	(via
		(at 150.690072 -384.617722)
		(size 0.4064)
		(drill 0.2032)
		(layers "F.Cu" "B.Cu")
		(net "GND")
	)
	(via
		(at 31.312612 -421.281098)
		(size 0.508)
		(drill 0.254)
		(layers "F.Cu" "B.Cu")
		(net "GND")
	)
	(via
		(at 90.567764 -407.00452)
		(size 0.4064)
		(drill 0.2032)
		(layers "F.Cu" "B.Cu")
		(net "GND")
	)
	(via
		(at 325.66991 -103.882698)
		(size 0.508)
		(drill 0.254)
		(layers "F.Cu" "B.Cu")
		(net "GND")
	)
	(via
		(at 133.065266 -157.681168)
		(size 0.49022)
		(drill 0.254)
		(layers "F.Cu" "B.Cu")
		(net "GND")
	)
	(via
		(at 182.67553 -51.14671)
		(size 0.508)
		(drill 0.254)
		(layers "F.Cu" "B.Cu")
		(net "GND")
	)
	(via
		(at 183.616092 -306.985416)
		(size 0.4826)
		(drill 0.254)
		(layers "F.Cu" "B.Cu")
		(net "GND")
	)
	(via
		(at 165.865302 -112.5728)
		(size 0.508)
		(drill 0.254)
		(layers "F.Cu" "B.Cu")
		(net "GND")
	)
	(via
		(at 85.528404 -407.00452)
		(size 0.4064)
		(drill 0.2032)
		(layers "F.Cu" "B.Cu")
		(net "GND")
	)
	(via
		(at 81.701132 -246.10441)
		(size 0.4064)
		(drill 0.2032)
		(layers "F.Cu" "B.Cu")
		(net "GND")
	)
	(via
		(at 430.665382 -343.23528)
		(size 0.508)
		(drill 0.254)
		(layers "F.Cu" "B.Cu")
		(net "GND")
	)
	(via
		(at 346.091002 -253.39421)
		(size 0.4064)
		(drill 0.2032)
		(layers "F.Cu" "B.Cu")
		(net "GND")
	)
	(via
		(at 191.160146 -222.835216)
		(size 0.4826)
		(drill 0.254)
		(layers "F.Cu" "B.Cu")
		(net "GND")
	)
	(via
		(at 100.331016 -261.126224)
		(size 0.4064)
		(drill 0.2032)
		(layers "F.Cu" "B.Cu")
		(net "GND")
	)
	(via
		(at 119.82196 -330.72578)
		(size 0.6604)
		(drill 0.3302)
		(layers "F.Cu" "B.Cu")
		(net "GND")
	)
	(via
		(at 145.056098 -406.370536)
		(size 0.4572)
		(drill 0.254)
		(layers "F.Cu" "B.Cu")
		(net "GND")
	)
	(via
		(at 273.092164 -225.385122)
		(size 0.4826)
		(drill 0.254)
		(layers "F.Cu" "B.Cu")
		(net "GND")
	)
	(via
		(at 432.650392 -349.200978)
		(size 0.49022)
		(drill 0.254)
		(layers "F.Cu" "B.Cu")
		(net "GND")
	)
	(segment
		(start 180.0352 -106.31043)
		(end 180.65115 -106.31043)
		(width 0.254)
		(layer "B.Cu")
		(net "GND")
	)
	(segment
		(start 228.88575 -324.349872)
		(end 229.602538 -324.349872)
		(width 0.381)
		(layer "B.Cu")
		(net "GND")
	)
	(segment
		(start 51.72964 -423.825162)
		(end 51.08448 -423.825162)
		(width 0.381)
		(layer "B.Cu")
		(net "GND")
	)
	(segment
		(start 384.240278 -137.135108)
		(end 384.240278 -136.519158)
		(width 0.381)
		(layer "B.Cu")
		(net "GND")
	)
	(segment
		(start 371.769894 -246.269002)
		(end 371.93474 -246.104156)
		(width 0.4572)
		(layer "B.Cu")
		(net "GND")
	)
	(segment
		(start 198.305928 -75.242674)
		(end 200.146158 -75.242674)
		(width 0.3556)
		(layer "B.Cu")
		(net "GND")
	)
	(segment
		(start 180.166518 -415.216594)
		(end 179.571904 -415.216594)
		(width 0.4572)
		(layer "B.Cu")
		(net "GND")
	)
	(segment
		(start 151.275034 -202.377802)
		(end 152.265634 -202.377802)
		(width 0.4572)
		(layer "B.Cu")
		(net "GND")
	)
	(segment
		(start 89.809828 -142.85341)
		(end 89.809828 -141.83741)
		(width 0.381)
		(layer "B.Cu")
		(net "GND")
	)
	(segment
		(start 235.485432 -51.209448)
		(end 235.8009 -51.209448)
		(width 0.3556)
		(layer "B.Cu")
		(net "GND")
	)
	(segment
		(start 238.708692 -422.449498)
		(end 238.708692 -421.833548)
		(width 0.381)
		(layer "B.Cu")
		(net "GND")
	)
	(segment
		(start 256.1717 -332.867)
		(end 256.7051 -332.867)
		(width 0.254)
		(layer "B.Cu")
		(net "GND")
	)
	(segment
		(start 299.532294 -392.66876)
		(end 299.689774 -392.66876)
		(width 0.254)
		(layer "B.Cu")
		(net "GND")
	)
	(segment
		(start 170.307 -98.535998)
		(end 169.881042 -98.535998)
		(width 0.4572)
		(layer "B.Cu")
		(net "GND")
	)
	(segment
		(start 324.711568 -396.150592)
		(end 324.916038 -396.355062)
		(width 0.3048)
		(layer "B.Cu")
		(net "GND")
	)
	(segment
		(start 384.513328 -142.234158)
		(end 385.129278 -142.234158)
		(width 0.381)
		(layer "B.Cu")
		(net "GND")
	)
	(segment
		(start 391.811764 -396.150592)
		(end 390.78408 -396.150592)
		(width 0.3048)
		(layer "B.Cu")
		(net "GND")
	)
	(segment
		(start 47.668942 -424.625262)
		(end 48.328834 -424.625262)
		(width 0.381)
		(layer "B.Cu")
		(net "GND")
	)
	(segment
		(start 214.6173 -331.724)
		(end 213.995 -331.724)
		(width 0.381)
		(layer "B.Cu")
		(net "GND")
	)
	(segment
		(start 16.637762 -112.693958)
		(end 17.36471 -112.693958)
		(width 0.3556)
		(layer "B.Cu")
		(net "GND")
	)
	(segment
		(start 142.64132 -316.465458)
		(end 142.64132 -315.65596)
		(width 0.4572)
		(layer "B.Cu")
		(net "GND")
	)
	(segment
		(start 155.364434 -199.634602)
		(end 154.348434 -199.634602)
		(width 0.4064)
		(layer "B.Cu")
		(net "GND")
	)
	(segment
		(start 400.964146 -354.839778)
		(end 402.186394 -354.839778)
		(width 0.4572)
		(layer "B.Cu")
		(net "GND")
	)
	(segment
		(start 301.73295 -359.283)
		(end 301.73295 -359.918)
		(width 0.4572)
		(layer "B.Cu")
		(net "GND")
	)
	(segment
		(start 382.491234 -399.024602)
		(end 382.491234 -398.542002)
		(width 0.254)
		(layer "B.Cu")
		(net "GND")
	)
	(segment
		(start 232.857802 -251.442728)
		(end 233.495088 -251.442728)
		(width 0.4572)
		(layer "B.Cu")
		(net "GND")
	)
	(segment
		(start 337.687158 -309.614062)
		(end 337.687158 -310.428132)
		(width 0.381)
		(layer "B.Cu")
		(net "GND")
	)
	(segment
		(start 240.740692 -422.449498)
		(end 240.740692 -421.833548)
		(width 0.381)
		(layer "B.Cu")
		(net "GND")
	)
	(segment
		(start 137.089388 -382.237488)
		(end 136.574276 -382.237488)
		(width 0.254)
		(layer "B.Cu")
		(net "GND")
	)
	(segment
		(start 164.462968 -121.701814)
		(end 165.168072 -121.701814)
		(width 0.4572)
		(layer "B.Cu")
		(net "GND")
	)
	(segment
		(start 49.568862 -425.925234)
		(end 49.568862 -426.662596)
		(width 0.4572)
		(layer "B.Cu")
		(net "GND")
	)
	(segment
		(start 155.567634 -199.837802)
		(end 155.364434 -199.634602)
		(width 0.4064)
		(layer "B.Cu")
		(net "GND")
	)
	(segment
		(start 97.902522 -151.099012)
		(end 97.902522 -151.708866)
		(width 0.381)
		(layer "B.Cu")
		(net "GND")
	)
	(segment
		(start 380.629922 -148.70176)
		(end 380.629922 -149.311614)
		(width 0.381)
		(layer "B.Cu")
		(net "GND")
	)
	(segment
		(start 169.5577 -98.85934)
		(end 169.5577 -100.008182)
		(width 0.4572)
		(layer "B.Cu")
		(net "GND")
	)
	(segment
		(start 235.20527 -325.894192)
		(end 235.922058 -325.894192)
		(width 0.381)
		(layer "B.Cu")
		(net "GND")
	)
	(segment
		(start 407.099008 -326.894952)
		(end 407.546048 -327.341992)
		(width 0.381)
		(layer "B.Cu")
		(net "GND")
	)
	(segment
		(start 237.829598 -237.230666)
		(end 236.987334 -237.230666)
		(width 0.254)
		(layer "B.Cu")
		(net "GND")
	)
	(segment
		(start 372.537228 -140.456158)
		(end 371.921278 -140.456158)
		(width 0.4572)
		(layer "B.Cu")
		(net "GND")
	)
	(segment
		(start 243.31295 -324.866)
		(end 242.57 -324.866)
		(width 0.4572)
		(layer "B.Cu")
		(net "GND")
	)
	(segment
		(start 428.5869 -41.087548)
		(end 427.97095 -41.087548)
		(width 0.4064)
		(layer "B.Cu")
		(net "GND")
	)
	(segment
		(start 407.117804 -330.97216)
		(end 407.290778 -331.145134)
		(width 0.4064)
		(layer "B.Cu")
		(net "GND")
	)
	(segment
		(start 179.571904 -415.216594)
		(end 179.281582 -414.926272)
		(width 0.4572)
		(layer "B.Cu")
		(net "GND")
	)
	(segment
		(start 228.873558 -325.425562)
		(end 229.590346 -325.425562)
		(width 0.381)
		(layer "B.Cu")
		(net "GND")
	)
	(segment
		(start 109.869986 -414.08604)
		(end 109.869986 -413.385)
		(width 0.4572)
		(layer "B.Cu")
		(net "GND")
	)
	(segment
		(start 347.638624 -74.184764)
		(end 347.003624 -74.184764)
		(width 0.4572)
		(layer "B.Cu")
		(net "GND")
	)
	(segment
		(start 143.160242 -383.7432)
		(end 143.693642 -383.7432)
		(width 0.254)
		(layer "B.Cu")
		(net "GND")
	)
	(segment
		(start 188.48705 -143.256)
		(end 188.48705 -143.881856)
		(width 0.4572)
		(layer "B.Cu")
		(net "GND")
	)
	(segment
		(start 110.632494 -383.7432)
		(end 111.165894 -383.7432)
		(width 0.254)
		(layer "B.Cu")
		(net "GND")
	)
	(segment
		(start 91.893644 -301.716948)
		(end 92.396056 -301.716948)
		(width 0.4572)
		(layer "B.Cu")
		(net "GND")
	)
	(segment
		(start 379.613922 -148.70176)
		(end 380.629922 -148.70176)
		(width 0.381)
		(layer "B.Cu")
		(net "GND")
	)
	(segment
		(start 147.261834 -204.079602)
		(end 148.227034 -204.079602)
		(width 0.4572)
		(layer "B.Cu")
		(net "GND")
	)
	(segment
		(start 243.31295 -321.818)
		(end 242.57 -321.818)
		(width 0.4572)
		(layer "B.Cu")
		(net "GND")
	)
	(segment
		(start 180.166518 -413.349694)
		(end 179.496974 -413.349694)
		(width 0.4572)
		(layer "B.Cu")
		(net "GND")
	)
	(segment
		(start 164.465 -426.6819)
		(end 164.465 -427.4439)
		(width 0.254)
		(layer "B.Cu")
		(net "GND")
	)
	(segment
		(start 102.847648 -382.8796)
		(end 102.847648 -383.257806)
		(width 0.254)
		(layer "B.Cu")
		(net "GND")
	)
	(segment
		(start 150.300436 -314.47105)
		(end 150.95982 -314.47105)
		(width 0.4572)
		(layer "B.Cu")
		(net "GND")
	)
	(segment
		(start 182.42661 -113.46307)
		(end 182.332122 -113.46307)
		(width 0.254)
		(layer "B.Cu")
		(net "GND")
	)
	(segment
		(start 182.586122 -112.263174)
		(end 182.332122 -112.009174)
		(width 0.254)
		(layer "B.Cu")
		(net "GND")
	)
	(segment
		(start 137.928604 -64.436752)
		(end 137.928604 -65.792604)
		(width 0.4572)
		(layer "B.Cu")
		(net "GND")
	)
	(segment
		(start 159.018986 -390.642602)
		(end 159.018986 -390.160002)
		(width 0.254)
		(layer "B.Cu")
		(net "GND")
	)
	(segment
		(start 259.565394 -52.160932)
		(end 259.063744 -52.662582)
		(width 0.4572)
		(layer "B.Cu")
		(net "GND")
	)
	(segment
		(start 89.193878 -142.85341)
		(end 89.809828 -142.85341)
		(width 0.381)
		(layer "B.Cu")
		(net "GND")
	)
	(segment
		(start 429.103282 -438.592722)
		(end 429.103282 -439.213498)
		(width 0.4572)
		(layer "B.Cu")
		(net "GND")
	)
	(segment
		(start 327.450704 -72.884792)
		(end 326.667876 -72.884792)
		(width 0.4572)
		(layer "B.Cu")
		(net "GND")
	)
	(segment
		(start 165.199568 -417.962588)
		(end 165.199568 -418.493448)
		(width 0.4572)
		(layer "B.Cu")
		(net "GND")
	)
	(segment
		(start 76.0603 -383.7432)
		(end 76.5937 -383.7432)
		(width 0.254)
		(layer "B.Cu")
		(net "GND")
	)
	(segment
		(start 198.276972 -75.27163)
		(end 198.305928 -75.242674)
		(width 0.3556)
		(layer "B.Cu")
		(net "GND")
	)
	(segment
		(start 92.458794 -301.779686)
		(end 92.572078 -301.779686)
		(width 0.4572)
		(layer "B.Cu")
		(net "GND")
	)
	(segment
		(start 449.518278 -8.75665)
		(end 449.562474 -8.75665)
		(width 0.4572)
		(layer "B.Cu")
		(net "GND")
	)
	(segment
		(start 241.173 -223.62795)
		(end 241.173 -222.65005)
		(width 0.381)
		(layer "B.Cu")
		(net "GND")
	)
	(segment
		(start 186.312048 -113.357406)
		(end 186.312048 -113.46307)
		(width 0.254)
		(layer "B.Cu")
		(net "GND")
	)
	(segment
		(start 16.189452 -110.587536)
		(end 15.433294 -110.587536)
		(width 0.3556)
		(layer "B.Cu")
		(net "GND")
	)
	(segment
		(start 348.101158 -271.478502)
		(end 347.97873 -271.478502)
		(width 0.4572)
		(layer "B.Cu")
		(net "GND")
	)
	(segment
		(start 170.424348 -422.957244)
		(end 170.424348 -423.5323)
		(width 0.4572)
		(layer "B.Cu")
		(net "GND")
	)
	(segment
		(start 95.29318 -301.716948)
		(end 96.033082 -300.977046)
		(width 0.4572)
		(layer "B.Cu")
		(net "GND")
	)
	(segment
		(start 9.666732 -412.291784)
		(end 8.949182 -412.291784)
		(width 0.508)
		(layer "B.Cu")
		(net "GND")
	)
	(segment
		(start 159.664908 -415.073592)
		(end 159.934656 -414.803844)
		(width 0.381)
		(layer "B.Cu")
		(net "GND")
	)
	(segment
		(start 248.2723 -332.105)
		(end 247.65 -332.105)
		(width 0.254)
		(layer "B.Cu")
		(net "GND")
	)
	(segment
		(start 341.674704 -72.884792)
		(end 340.891876 -72.884792)
		(width 0.4572)
		(layer "B.Cu")
		(net "GND")
	)
	(segment
		(start 101.444044 -387.973062)
		(end 101.239574 -387.768592)
		(width 0.3048)
		(layer "B.Cu")
		(net "GND")
	)
	(segment
		(start 155.567634 -200.438512)
		(end 155.567634 -199.837802)
		(width 0.4064)
		(layer "B.Cu")
		(net "GND")
	)
	(segment
		(start 107.329986 -416.37204)
		(end 107.329986 -416.02152)
		(width 0.4572)
		(layer "B.Cu")
		(net "GND")
	)
	(segment
		(start 366.63249 -393.96416)
		(end 367.16589 -393.96416)
		(width 0.254)
		(layer "B.Cu")
		(net "GND")
	)
	(segment
		(start 123.766834 -246.269002)
		(end 123.83008 -246.269002)
		(width 0.254)
		(layer "B.Cu")
		(net "GND")
	)
	(segment
		(start 190.792862 -70.459346)
		(end 190.792862 -71.54545)
		(width 0.4572)
		(layer "B.Cu")
		(net "GND")
	)
	(segment
		(start 13.61567 -416.235896)
		(end 13.038582 -416.812984)
		(width 0.381)
		(layer "B.Cu")
		(net "GND")
	)
	(segment
		(start 288.642806 -427.359572)
		(end 288.642806 -427.770798)
		(width 0.4572)
		(layer "B.Cu")
		(net "GND")
	)
	(segment
		(start 413.975804 -361.827064)
		(end 413.322008 -361.827064)
		(width 0.381)
		(layer "B.Cu")
		(net "GND")
	)
	(segment
		(start 449.843652 -422.01211)
		(end 450.561202 -422.01211)
		(width 0.508)
		(layer "B.Cu")
		(net "GND")
	)
	(segment
		(start 405.809196 -355.345746)
		(end 406.181306 -355.717856)
		(width 0.4572)
		(layer "B.Cu")
		(net "GND")
	)
	(segment
		(start 180.281834 -420.97706)
		(end 180.281834 -420.351458)
		(width 0.4572)
		(layer "B.Cu")
		(net "GND")
	)
	(segment
		(start 299.735494 -394.29436)
		(end 300.065694 -393.96416)
		(width 0.254)
		(layer "B.Cu")
		(net "GND")
	)
	(segment
		(start 229.87 -231.75595)
		(end 229.87 -230.886)
		(width 0.381)
		(layer "B.Cu")
		(net "GND")
	)
	(segment
		(start 115.530884 -246.376952)
		(end 115.530884 -246.10822)
		(width 0.254)
		(layer "B.Cu")
		(net "GND")
	)
	(segment
		(start 399.518124 -344.450162)
		(end 400.178016 -344.450162)
		(width 0.4572)
		(layer "B.Cu")
		(net "GND")
	)
	(segment
		(start 56.473852 -194.885564)
		(end 56.483758 -194.885564)
		(width 0.381)
		(layer "B.Cu")
		(net "GND")
	)
	(segment
		(start 238.379 -331.47)
		(end 238.252 -331.343)
		(width 0.381)
		(layer "B.Cu")
		(net "GND")
	)
	(segment
		(start 108.712 -417.42995)
		(end 108.712 -416.687)
		(width 0.4572)
		(layer "B.Cu")
		(net "GND")
	)
	(segment
		(start 78.159864 -10.86866)
		(end 77.905864 -10.61466)
		(width 0.3556)
		(layer "B.Cu")
		(net "GND")
	)
	(segment
		(start 66.800984 -196.95414)
		(end 65.65138 -196.95414)
		(width 0.4572)
		(layer "B.Cu")
		(net "GND")
	)
	(segment
		(start 332.060042 -393.04468)
		(end 332.593442 -393.04468)
		(width 0.254)
		(layer "B.Cu")
		(net "GND")
	)
	(segment
		(start 164.578538 -433.75453)
		(end 164.979604 -434.155596)
		(width 0.4572)
		(layer "B.Cu")
		(net "GND")
	)
	(segment
		(start 299.532294 -394.29436)
		(end 299.735494 -394.29436)
		(width 0.254)
		(layer "B.Cu")
		(net "GND")
	)
	(segment
		(start 218.066112 -67.260978)
		(end 218.066112 -66.645028)
		(width 0.4572)
		(layer "B.Cu")
		(net "GND")
	)
	(segment
		(start 418.5158 -425.253912)
		(end 418.822886 -425.560998)
		(width 0.254)
		(layer "B.Cu")
		(net "GND")
	)
	(segment
		(start 404.381208 -329.003152)
		(end 405.012906 -329.003152)
		(width 0.381)
		(layer "B.Cu")
		(net "GND")
	)
	(segment
		(start 405.700738 -343.350342)
		(end 406.897586 -343.350342)
		(width 0.4572)
		(layer "B.Cu")
		(net "GND")
	)
	(segment
		(start 307.485034 -428.0916)
		(end 308.120288 -427.456346)
		(width 0.254)
		(layer "B.Cu")
		(net "GND")
	)
	(segment
		(start 460.005938 -44.416726)
		(end 459.21295 -44.416726)
		(width 0.4572)
		(layer "B.Cu")
		(net "GND")
	)
	(segment
		(start 374.135396 -422.618916)
		(end 373.134636 -423.619676)
		(width 0.4572)
		(layer "B.Cu")
		(net "GND")
	)
	(segment
		(start 182.332122 -112.009174)
		(end 182.332122 -111.86287)
		(width 0.254)
		(layer "B.Cu")
		(net "GND")
	)
	(segment
		(start 450.482716 -10.194036)
		(end 450.482716 -9.676892)
		(width 0.4572)
		(layer "B.Cu")
		(net "GND")
	)
	(segment
		(start 413.322008 -361.827064)
		(end 413.271208 -361.877864)
		(width 0.381)
		(layer "B.Cu")
		(net "GND")
	)
	(segment
		(start 415.018982 -399.024602)
		(end 415.018982 -398.542002)
		(width 0.254)
		(layer "B.Cu")
		(net "GND")
	)
	(segment
		(start 225.966528 -289.524186)
		(end 226.478592 -289.012122)
		(width 0.381)
		(layer "B.Cu")
		(net "GND")
	)
	(segment
		(start 425.050458 -391.686288)
		(end 425.050458 -390.67105)
		(width 0.254)
		(layer "B.Cu")
		(net "GND")
	)
	(segment
		(start 187.490354 -428.965106)
		(end 186.944254 -429.511206)
		(width 0.4572)
		(layer "B.Cu")
		(net "GND")
	)
	(segment
		(start 182.442358 -116.642642)
		(end 182.332122 -116.642642)
		(width 0.254)
		(layer "B.Cu")
		(net "GND")
	)
	(segment
		(start 398.657572 -204.232002)
		(end 398.657572 -204.897736)
		(width 0.4572)
		(layer "B.Cu")
		(net "GND")
	)
	(segment
		(start 170.791378 -118.324376)
		(end 170.18 -118.324376)
		(width 0.4572)
		(layer "B.Cu")
		(net "GND")
	)
	(segment
		(start 101.785928 -143.61541)
		(end 101.785928 -142.59941)
		(width 0.381)
		(layer "B.Cu")
		(net "GND")
	)
	(segment
		(start 70.3199 -382.8796)
		(end 70.3199 -383.257806)
		(width 0.254)
		(layer "B.Cu")
		(net "GND")
	)
	(segment
		(start 311.194704 -72.884792)
		(end 310.411876 -72.884792)
		(width 0.4572)
		(layer "B.Cu")
		(net "GND")
	)
	(segment
		(start 108.570014 -416.545014)
		(end 108.712 -416.687)
		(width 0.4572)
		(layer "B.Cu")
		(net "GND")
	)
	(segment
		(start 339.510624 -74.184764)
		(end 338.875624 -74.184764)
		(width 0.4572)
		(layer "B.Cu")
		(net "GND")
	)
	(segment
		(start 76.0603 -384.66268)
		(end 76.5937 -384.66268)
		(width 0.254)
		(layer "B.Cu")
		(net "GND")
	)
	(segment
		(start 182.732426 -117.77472)
		(end 182.732426 -117.842792)
		(width 0.254)
		(layer "B.Cu")
		(net "GND")
	)
	(segment
		(start 179.793646 -32.287972)
		(end 179.793646 -31.636208)
		(width 0.4572)
		(layer "B.Cu")
		(net "GND")
	)
	(segment
		(start 162.083242 -414.803844)
		(end 162.69208 -415.412682)
		(width 0.381)
		(layer "B.Cu")
		(net "GND")
	)
	(segment
		(start 235.224066 -322.683632)
		(end 235.940854 -322.683632)
		(width 0.381)
		(layer "B.Cu")
		(net "GND")
	)
	(segment
		(start 444.617602 -417.283138)
		(end 444.617602 -418.18306)
		(width 0.4572)
		(layer "B.Cu")
		(net "GND")
	)
	(segment
		(start 238.8743 -332.613)
		(end 238.252 -332.613)
		(width 0.381)
		(layer "B.Cu")
		(net "GND")
	)
	(segment
		(start 333.210408 -389.97763)
		(end 332.80477 -389.97763)
		(width 0.4572)
		(layer "B.Cu")
		(net "GND")
	)
	(segment
		(start 115.364768 -415.510218)
		(end 114.935 -415.939986)
		(width 0.4572)
		(layer "B.Cu")
		(net "GND")
	)
	(segment
		(start 209.841084 -73.168002)
		(end 210.608418 -73.168002)
		(width 0.4572)
		(layer "B.Cu")
		(net "GND")
	)
	(segment
		(start 171.06392 -422.317672)
		(end 170.424348 -422.957244)
		(width 0.4572)
		(layer "B.Cu")
		(net "GND")
	)
	(segment
		(start 51.766978 -430.24298)
		(end 51.766978 -430.876964)
		(width 0.381)
		(layer "B.Cu")
		(net "GND")
	)
	(segment
		(start 91.893644 -303.255172)
		(end 92.656152 -303.255172)
		(width 0.4572)
		(layer "B.Cu")
		(net "GND")
	)
	(segment
		(start 160.103312 -418.344858)
		(end 160.103312 -418.7952)
		(width 0.3302)
		(layer "B.Cu")
		(net "GND")
	)
	(segment
		(start 434.07076 -9.189974)
		(end 433.835302 -9.425432)
		(width 0.4572)
		(layer "B.Cu")
		(net "GND")
	)
	(segment
		(start 179.281582 -414.283144)
		(end 179.281582 -414.926272)
		(width 0.4572)
		(layer "B.Cu")
		(net "GND")
	)
	(segment
		(start 339.846158 -309.614062)
		(end 339.846158 -310.134762)
		(width 0.381)
		(layer "B.Cu")
		(net "GND")
	)
	(segment
		(start 162.173158 -115.65255)
		(end 161.926016 -115.405408)
		(width 0.4572)
		(layer "B.Cu")
		(net "GND")
	)
	(segment
		(start 376.472958 -208.130902)
		(end 375.456958 -208.130902)
		(width 0.381)
		(layer "B.Cu")
		(net "GND")
	)
	(segment
		(start 77.905864 -10.61466)
		(end 77.905864 -10.15619)
		(width 0.3556)
		(layer "B.Cu")
		(net "GND")
	)
	(segment
		(start 184.58688 -144.663668)
		(end 184.58688 -146.02714)
		(width 0.381)
		(layer "B.Cu")
		(net "GND")
	)
	(segment
		(start 99.725734 -246.269002)
		(end 99.561142 -246.10441)
		(width 0.3556)
		(layer "B.Cu")
		(net "GND")
	)
	(segment
		(start 213.216236 -329.201272)
		(end 213.029546 -329.014582)
		(width 0.381)
		(layer "B.Cu")
		(net "GND")
	)
	(segment
		(start 378.250958 -204.701902)
		(end 378.250958 -204.085952)
		(width 0.381)
		(layer "B.Cu")
		(net "GND")
	)
	(segment
		(start 184.332372 -117.042946)
		(end 184.4294 -117.042946)
		(width 0.254)
		(layer "B.Cu")
		(net "GND")
	)
	(segment
		(start 89.809828 -145.90141)
		(end 89.809828 -144.88541)
		(width 0.381)
		(layer "B.Cu")
		(net "GND")
	)
	(segment
		(start 401.554696 -340.772242)
		(end 400.789902 -340.772242)
		(width 0.4572)
		(layer "B.Cu")
		(net "GND")
	)
	(segment
		(start 169.5577 -100.008182)
		(end 170.625262 -101.075744)
		(width 0.4572)
		(layer "B.Cu")
		(net "GND")
	)
	(segment
		(start 151.275034 -202.633072)
		(end 151.656034 -203.014072)
		(width 0.4572)
		(layer "B.Cu")
		(net "GND")
	)
	(segment
		(start 315.391038 -399.024602)
		(end 315.391038 -398.542002)
		(width 0.254)
		(layer "B.Cu")
		(net "GND")
	)
	(segment
		(start 21.632418 -413.99587)
		(end 20.889468 -413.99587)
		(width 0.381)
		(layer "B.Cu")
		(net "GND")
	)
	(segment
		(start 375.202958 -204.701902)
		(end 375.202958 -204.085952)
		(width 0.381)
		(layer "B.Cu")
		(net "GND")
	)
	(segment
		(start 247.249442 -327.201022)
		(end 246.022876 -327.201022)
		(width 0.3556)
		(layer "B.Cu")
		(net "GND")
	)
	(segment
		(start 100.013516 -271.503902)
		(end 99.861116 -271.656302)
		(width 0.3556)
		(layer "B.Cu")
		(net "GND")
	)
	(segment
		(start 252.559566 -326.566022)
		(end 253.822962 -326.566022)
		(width 0.3556)
		(layer "B.Cu")
		(net "GND")
	)
	(segment
		(start 62.68847 -15.18031)
		(end 62.051184 -15.18031)
		(width 0.4572)
		(layer "B.Cu")
		(net "GND")
	)
	(segment
		(start 233.013758 -224.797366)
		(end 233.013758 -225.3742)
		(width 0.4572)
		(layer "B.Cu")
		(net "GND")
	)
	(segment
		(start 110.16234 -61.61786)
		(end 110.16234 -61.12256)
		(width 0.4572)
		(layer "B.Cu")
		(net "GND")
	)
	(segment
		(start 360.233976 -416.923474)
		(end 360.233976 -417.10356)
		(width 0.4572)
		(layer "B.Cu")
		(net "GND")
	)
	(segment
		(start 43.532552 -384.28676)
		(end 43.690032 -384.28676)
		(width 0.254)
		(layer "B.Cu")
		(net "GND")
	)
	(segment
		(start 232.857802 -247.692672)
		(end 232.857802 -246.975122)
		(width 0.3302)
		(layer "B.Cu")
		(net "GND")
	)
	(segment
		(start 235.225336 -328.085704)
		(end 235.942124 -328.085704)
		(width 0.381)
		(layer "B.Cu")
		(net "GND")
	)
	(segment
		(start 187.325 -425.967906)
		(end 187.54598 -426.188886)
		(width 0.4572)
		(layer "B.Cu")
		(net "GND")
	)
	(segment
		(start 96.886522 -151.099012)
		(end 97.902522 -151.099012)
		(width 0.381)
		(layer "B.Cu")
		(net "GND")
	)
	(segment
		(start 213.217252 -328.110088)
		(end 213.111334 -328.00417)
		(width 0.381)
		(layer "B.Cu")
		(net "GND")
	)
	(segment
		(start 235.243878 -324.793102)
		(end 235.960666 -324.793102)
		(width 0.381)
		(layer "B.Cu")
		(net "GND")
	)
	(segment
		(start 402.722588 -319.198752)
		(end 402.722588 -318.403986)
		(width 0.4572)
		(layer "B.Cu")
		(net "GND")
	)
	(segment
		(start 184.732168 -113.46307)
		(end 184.732168 -113.357914)
		(width 0.254)
		(layer "B.Cu")
		(net "GND")
	)
	(segment
		(start 51.766978 -430.876964)
		(end 51.766978 -431.504852)
		(width 0.381)
		(layer "B.Cu")
		(net "GND")
	)
	(segment
		(start 304.81905 -355.854)
		(end 305.058318 -355.854)
		(width 0.4572)
		(layer "B.Cu")
		(net "GND")
	)
	(segment
		(start 235.185966 -321.652138)
		(end 235.902754 -321.652138)
		(width 0.381)
		(layer "B.Cu")
		(net "GND")
	)
	(segment
		(start 139.34694 -13.92174)
		(end 139.34694 -14.72946)
		(width 0.4572)
		(layer "B.Cu")
		(net "GND")
	)
	(segment
		(start 35.640518 -193.9798)
		(end 35.640264 -193.980054)
		(width 0.381)
		(layer "B.Cu")
		(net "GND")
	)
	(segment
		(start 162.378136 -429.189134)
		(end 162.378136 -427.494446)
		(width 0.4572)
		(layer "B.Cu")
		(net "GND")
	)
	(segment
		(start 183.83504 -144.399)
		(end 184.322212 -144.399)
		(width 0.381)
		(layer "B.Cu")
		(net "GND")
	)
	(segment
		(start 375.456958 -208.130902)
		(end 375.456958 -207.521302)
		(width 0.381)
		(layer "B.Cu")
		(net "GND")
	)
	(segment
		(start 370.505228 -144.520158)
		(end 369.895628 -144.520158)
		(width 0.381)
		(layer "B.Cu")
		(net "GND")
	)
	(segment
		(start 449.562474 -8.75665)
		(end 450.313044 -9.50722)
		(width 0.4572)
		(layer "B.Cu")
		(net "GND")
	)
	(segment
		(start 252.559566 -327.201022)
		(end 253.563628 -327.201022)
		(width 0.3556)
		(layer "B.Cu")
		(net "GND")
	)
	(segment
		(start 179.281582 -413.565086)
		(end 179.496974 -413.349694)
		(width 0.4572)
		(layer "B.Cu")
		(net "GND")
	)
	(segment
		(start 115.784884 -271.395952)
		(end 115.784884 -271.606518)
		(width 0.254)
		(layer "B.Cu")
		(net "GND")
	)
	(segment
		(start 391.104628 -314.580524)
		(end 391.104628 -314.90793)
		(width 0.4572)
		(layer "B.Cu")
		(net "GND")
	)
	(segment
		(start 9.666732 -407.262584)
		(end 8.923782 -407.262584)
		(width 0.4572)
		(layer "B.Cu")
		(net "GND")
	)
	(segment
		(start 366.63249 -392.1252)
		(end 367.16589 -392.1252)
		(width 0.254)
		(layer "B.Cu")
		(net "GND")
	)
	(segment
		(start 43.735752 -385.91236)
		(end 44.065952 -385.58216)
		(width 0.254)
		(layer "B.Cu")
		(net "GND")
	)
	(segment
		(start 177.841402 -133.2738)
		(end 177.841402 -133.294882)
		(width 0.3556)
		(layer "B.Cu")
		(net "GND")
	)
	(segment
		(start 94.060264 -307.730652)
		(end 93.811344 -307.730652)
		(width 0.381)
		(layer "B.Cu")
		(net "GND")
	)
	(segment
		(start 383.224278 -137.135108)
		(end 383.224278 -136.513824)
		(width 0.381)
		(layer "B.Cu")
		(net "GND")
	)
	(segment
		(start 437.877966 -420.231824)
		(end 438.620916 -420.231824)
		(width 0.381)
		(layer "B.Cu")
		(net "GND")
	)
	(segment
		(start 191.068452 -19.311366)
		(end 191.301116 -19.311366)
		(width 0.4572)
		(layer "B.Cu")
		(net "GND")
	)
	(segment
		(start 192.287652 -80.720184)
		(end 192.744852 -81.177384)
		(width 0.4572)
		(layer "B.Cu")
		(net "GND")
	)
	(segment
		(start 100.123244 -424.235372)
		(end 100.123244 -423.610532)
		(width 0.381)
		(layer "B.Cu")
		(net "GND")
	)
	(segment
		(start 305.058318 -355.854)
		(end 305.430936 -356.226618)
		(width 0.4572)
		(layer "B.Cu")
		(net "GND")
	)
	(segment
		(start 137.928604 -65.792604)
		(end 138.8872 -66.7512)
		(width 0.4572)
		(layer "B.Cu")
		(net "GND")
	)
	(segment
		(start 171.555918 -417.078668)
		(end 171.191428 -416.714178)
		(width 0.4572)
		(layer "B.Cu")
		(net "GND")
	)
	(segment
		(start 337.610704 -72.884792)
		(end 336.827876 -72.884792)
		(width 0.4572)
		(layer "B.Cu")
		(net "GND")
	)
	(segment
		(start 399.999454 -390.035034)
		(end 399.34642 -389.382)
		(width 0.4572)
		(layer "B.Cu")
		(net "GND")
	)
	(segment
		(start 15.1892 -132.38988)
		(end 14.4272 -133.15188)
		(width 0.3556)
		(layer "B.Cu")
		(net "GND")
	)
	(segment
		(start 459.21295 -44.416726)
		(end 459.158594 -44.471082)
		(width 0.4572)
		(layer "B.Cu")
		(net "GND")
	)
	(segment
		(start 187.111894 -112.66297)
		(end 187.234576 -112.66297)
		(width 0.254)
		(layer "B.Cu")
		(net "GND")
	)
	(segment
		(start 379.520958 -208.130902)
		(end 380.536958 -208.130902)
		(width 0.4572)
		(layer "B.Cu")
		(net "GND")
	)
	(segment
		(start 89.193878 -145.90141)
		(end 89.809828 -145.90141)
		(width 0.381)
		(layer "B.Cu")
		(net "GND")
	)
	(segment
		(start 401.554696 -344.450162)
		(end 400.897344 -344.450162)
		(width 0.4572)
		(layer "B.Cu")
		(net "GND")
	)
	(segment
		(start 186.711844 -113.062766)
		(end 186.606688 -113.062766)
		(width 0.254)
		(layer "B.Cu")
		(net "GND")
	)
	(segment
		(start 370.505228 -145.536158)
		(end 369.895628 -145.536158)
		(width 0.381)
		(layer "B.Cu")
		(net "GND")
	)
	(segment
		(start 306.94122 -193.99631)
		(end 306.212494 -193.99631)
		(width 0.381)
		(layer "B.Cu")
		(net "GND")
	)
	(segment
		(start 323.386704 -72.884792)
		(end 322.603876 -72.884792)
		(width 0.4572)
		(layer "B.Cu")
		(net "GND")
	)
	(segment
		(start 201.39533 -68.953126)
		(end 202.550776 -68.953126)
		(width 0.381)
		(layer "B.Cu")
		(net "GND")
	)
	(segment
		(start 110.250986 -413.004)
		(end 109.869986 -413.385)
		(width 0.4572)
		(layer "B.Cu")
		(net "GND")
	)
	(segment
		(start 213.76005 -67.58051)
		(end 214.921846 -67.58051)
		(width 0.381)
		(layer "B.Cu")
		(net "GND")
	)
	(segment
		(start 110.632494 -385.58216)
		(end 111.165894 -385.58216)
		(width 0.254)
		(layer "B.Cu")
		(net "GND")
	)
	(segment
		(start 159.664908 -415.531046)
		(end 159.664908 -415.073592)
		(width 0.381)
		(layer "B.Cu")
		(net "GND")
	)
	(segment
		(start 148.463 -205.069948)
		(end 148.844 -205.450948)
		(width 0.4572)
		(layer "B.Cu")
		(net "GND")
	)
	(segment
		(start 259.565394 -51.613562)
		(end 259.565394 -52.160932)
		(width 0.4572)
		(layer "B.Cu")
		(net "GND")
	)
	(segment
		(start 230.886 -231.75595)
		(end 230.886 -230.886)
		(width 0.381)
		(layer "B.Cu")
		(net "GND")
	)
	(segment
		(start 180.65115 -106.31043)
		(end 180.830982 -106.490262)
		(width 0.254)
		(layer "B.Cu")
		(net "GND")
	)
	(segment
		(start 76.0603 -385.58216)
		(end 76.5937 -385.58216)
		(width 0.254)
		(layer "B.Cu")
		(net "GND")
	)
	(segment
		(start 155.895294 -200.766172)
		(end 155.567634 -200.438512)
		(width 0.4064)
		(layer "B.Cu")
		(net "GND")
	)
	(segment
		(start 421.919654 -425.909232)
		(end 421.919654 -424.594274)
		(width 0.3556)
		(layer "B.Cu")
		(net "GND")
	)
	(segment
		(start 93.430344 -307.349652)
		(end 93.430344 -307.214524)
		(width 0.381)
		(layer "B.Cu")
		(net "GND")
	)
	(segment
		(start 145.610834 -320.417952)
		(end 145.102834 -319.909952)
		(width 0.4572)
		(layer "B.Cu")
		(net "GND")
	)
	(segment
		(start 68.916296 -387.973062)
		(end 68.711826 -387.768592)
		(width 0.3048)
		(layer "B.Cu")
		(net "GND")
	)
	(segment
		(start 179.27701 -420.974774)
		(end 179.27701 -420.349172)
		(width 0.4572)
		(layer "B.Cu")
		(net "GND")
	)
	(segment
		(start 363.741208 -271.62252)
		(end 363.774736 -271.656048)
		(width 0.4572)
		(layer "B.Cu")
		(net "GND")
	)
	(segment
		(start 101.785928 -142.59941)
		(end 101.785928 -141.58341)
		(width 0.381)
		(layer "B.Cu")
		(net "GND")
	)
	(segment
		(start 437.886602 -422.52011)
		(end 438.629552 -422.52011)
		(width 0.381)
		(layer "B.Cu")
		(net "GND")
	)
	(segment
		(start 215.914478 -74.055986)
		(end 216.60612 -74.055986)
		(width 0.4572)
		(layer "B.Cu")
		(net "GND")
	)
	(segment
		(start 395.123162 -200.363582)
		(end 396.134336 -200.363582)
		(width 0.4572)
		(layer "B.Cu")
		(net "GND")
	)
	(segment
		(start 72.825864 -9.97458)
		(end 72.825864 -10.16508)
		(width 0.381)
		(layer "B.Cu")
		(net "GND")
	)
	(segment
		(start 237.910878 -289.482022)
		(end 238.380778 -289.012122)
		(width 0.4572)
		(layer "B.Cu")
		(net "GND")
	)
	(segment
		(start 326.319642 -391.2616)
		(end 326.319642 -391.639806)
		(width 0.254)
		(layer "B.Cu")
		(net "GND")
	)
	(segment
		(start 169.050462 -382.28905)
		(end 169.102024 -382.237488)
		(width 0.254)
		(layer "B.Cu")
		(net "GND")
	)
	(segment
		(start 259.063744 -52.662582)
		(end 259.063744 -53.457602)
		(width 0.4572)
		(layer "B.Cu")
		(net "GND")
	)
	(segment
		(start 339.846158 -310.134762)
		(end 339.562694 -310.418226)
		(width 0.381)
		(layer "B.Cu")
		(net "GND")
	)
	(segment
		(start 85.45195 -146.939)
		(end 84.709 -146.939)
		(width 0.4572)
		(layer "B.Cu")
		(net "GND")
	)
	(segment
		(start 307.3019 -428.0916)
		(end 307.485034 -428.0916)
		(width 0.254)
		(layer "B.Cu")
		(net "GND")
	)
	(segment
		(start 108.570014 -415.98596)
		(end 108.570014 -416.545014)
		(width 0.4572)
		(layer "B.Cu")
		(net "GND")
	)
	(segment
		(start 99.916234 -246.269002)
		(end 99.725734 -246.269002)
		(width 0.3556)
		(layer "B.Cu")
		(net "GND")
	)
	(segment
		(start 288.642806 -427.770798)
		(end 288.922968 -428.05096)
		(width 0.4572)
		(layer "B.Cu")
		(net "GND")
	)
	(segment
		(start 143.160242 -384.66268)
		(end 143.693642 -384.66268)
		(width 0.254)
		(layer "B.Cu")
		(net "GND")
	)
	(segment
		(start 185.496708 -421.808402)
		(end 185.496708 -421.1447)
		(width 0.4572)
		(layer "B.Cu")
		(net "GND")
	)
	(segment
		(start 171.191428 -416.714178)
		(end 171.191428 -416.379406)
		(width 0.4572)
		(layer "B.Cu")
		(net "GND")
	)
	(segment
		(start 180.535834 -417.426394)
		(end 179.346606 -417.426394)
		(width 0.3302)
		(layer "B.Cu")
		(net "GND")
	)
	(segment
		(start 317.091822 -199.998838)
		(end 316.673992 -199.581008)
		(width 0.4572)
		(layer "B.Cu")
		(net "GND")
	)
	(segment
		(start 422.45915 -429.080676)
		(end 422.721024 -429.34255)
		(width 0.254)
		(layer "B.Cu")
		(net "GND")
	)
	(segment
		(start 201.041 -137.52195)
		(end 201.78395 -137.52195)
		(width 0.4572)
		(layer "B.Cu")
		(net "GND")
	)
	(segment
		(start 51.015392 -421.17518)
		(end 51.015392 -420.536624)
		(width 0.381)
		(layer "B.Cu")
		(net "GND")
	)
	(segment
		(start 435.145942 -8.717026)
		(end 435.145942 -8.754618)
		(width 0.4572)
		(layer "B.Cu")
		(net "GND")
	)
	(segment
		(start 332.060042 -392.1252)
		(end 332.593442 -392.1252)
		(width 0.254)
		(layer "B.Cu")
		(net "GND")
	)
	(segment
		(start 167.777668 -416.946588)
		(end 167.777668 -416.094926)
		(width 0.4572)
		(layer "B.Cu")
		(net "GND")
	)
	(segment
		(start 16.2941 -110.482888)
		(end 16.189452 -110.587536)
		(width 0.3556)
		(layer "B.Cu")
		(net "GND")
	)
	(segment
		(start 168.452292 -435.860698)
		(end 168.10863 -436.20436)
		(width 0.4572)
		(layer "B.Cu")
		(net "GND")
	)
	(segment
		(start 197.745858 -124.877576)
		(end 197.822058 -124.801376)
		(width 0.4572)
		(layer "B.Cu")
		(net "GND")
	)
	(segment
		(start 184.480708 -421.808402)
		(end 184.480708 -421.137588)
		(width 0.4572)
		(layer "B.Cu")
		(net "GND")
	)
	(segment
		(start 309.030624 -74.184764)
		(end 308.395624 -74.184764)
		(width 0.4572)
		(layer "B.Cu")
		(net "GND")
	)
	(segment
		(start 97.191068 -424.191684)
		(end 96.49333 -424.191684)
		(width 0.4572)
		(layer "B.Cu")
		(net "GND")
	)
	(segment
		(start 212.853016 -325.456296)
		(end 212.230716 -325.456296)
		(width 0.381)
		(layer "B.Cu")
		(net "GND")
	)
	(segment
		(start 241.173 -222.65005)
		(end 241.91595 -222.65005)
		(width 0.381)
		(layer "B.Cu")
		(net "GND")
	)
	(segment
		(start 172.660056 -103.942388)
		(end 172.684948 -103.96728)
		(width 0.4572)
		(layer "B.Cu")
		(net "GND")
	)
	(segment
		(start 403.05609 -323.067172)
		(end 402.938996 -322.950078)
		(width 0.3556)
		(layer "B.Cu")
		(net "GND")
	)
	(segment
		(start 396.817088 -200.354946)
		(end 397.00073 -200.538588)
		(width 0.4572)
		(layer "B.Cu")
		(net "GND")
	)
	(segment
		(start 347.918786 -399.024602)
		(end 347.918786 -398.542002)
		(width 0.254)
		(layer "B.Cu")
		(net "GND")
	)
	(segment
		(start 143.160242 -385.58216)
		(end 143.693642 -385.58216)
		(width 0.254)
		(layer "B.Cu")
		(net "GND")
	)
	(segment
		(start 100.123244 -423.610532)
		(end 100.285296 -423.44848)
		(width 0.381)
		(layer "B.Cu")
		(net "GND")
	)
	(segment
		(start 167.273224 -430.676558)
		(end 167.496744 -430.453038)
		(width 0.4572)
		(layer "B.Cu")
		(net "GND")
	)
	(segment
		(start 225.966528 -289.828732)
		(end 225.966528 -289.524186)
		(width 0.381)
		(layer "B.Cu")
		(net "GND")
	)
	(segment
		(start 74.55408 -3.851148)
		(end 74.467212 -3.76428)
		(width 0.4572)
		(layer "B.Cu")
		(net "GND")
	)
	(segment
		(start 164.979604 -434.155596)
		(end 165.01618 -434.11902)
		(width 0.4572)
		(layer "B.Cu")
		(net "GND")
	)
	(segment
		(start 228.879654 -327.56602)
		(end 229.596442 -327.56602)
		(width 0.381)
		(layer "B.Cu")
		(net "GND")
	)
	(segment
		(start 166.552372 -430.676558)
		(end 167.273224 -430.676558)
		(width 0.4572)
		(layer "B.Cu")
		(net "GND")
	)
	(segment
		(start 167.39743 -105.355644)
		(end 167.39743 -105.264712)
		(width 0.4572)
		(layer "B.Cu")
		(net "GND")
	)
	(segment
		(start 421.90289 -425.925996)
		(end 421.919654 -425.909232)
		(width 0.3556)
		(layer "B.Cu")
		(net "GND")
	)
	(segment
		(start 391.104628 -314.90793)
		(end 391.3759 -315.179202)
		(width 0.4572)
		(layer "B.Cu")
		(net "GND")
	)
	(segment
		(start 372.321328 -136.608058)
		(end 372.321328 -135.97382)
		(width 0.381)
		(layer "B.Cu")
		(net "GND")
	)
	(segment
		(start 408.271726 -141.40942)
		(end 408.271726 -142.57782)
		(width 0.4572)
		(layer "B.Cu")
		(net "GND")
	)
	(segment
		(start 430.79289 -436.49265)
		(end 430.572164 -436.271924)
		(width 0.4572)
		(layer "B.Cu")
		(net "GND")
	)
	(segment
		(start 166.438834 -434.11902)
		(end 166.552372 -434.232558)
		(width 0.4572)
		(layer "B.Cu")
		(net "GND")
	)
	(segment
		(start 186.67095 -422.402)
		(end 186.67095 -421.087804)
		(width 0.4572)
		(layer "B.Cu")
		(net "GND")
	)
	(segment
		(start 191.377316 -72.129904)
		(end 191.657224 -72.129904)
		(width 0.4572)
		(layer "B.Cu")
		(net "GND")
	)
	(segment
		(start 114.86896 -418.225986)
		(end 114.86896 -418.519864)
		(width 0.4572)
		(layer "B.Cu")
		(net "GND")
	)
	(segment
		(start 184.732168 -113.357914)
		(end 184.43702 -113.062766)
		(width 0.254)
		(layer "B.Cu")
		(net "GND")
	)
	(segment
		(start 253.66599 -325.931022)
		(end 253.823216 -325.773796)
		(width 0.3556)
		(layer "B.Cu")
		(net "GND")
	)
	(segment
		(start 20.519136 -193.996564)
		(end 20.55241 -193.996564)
		(width 0.381)
		(layer "B.Cu")
		(net "GND")
	)
	(segment
		(start 363.741208 -271.395952)
		(end 363.741208 -271.62252)
		(width 0.4572)
		(layer "B.Cu")
		(net "GND")
	)
	(segment
		(start 228.905308 -323.263768)
		(end 229.622096 -323.263768)
		(width 0.381)
		(layer "B.Cu")
		(net "GND")
	)
	(segment
		(start 213.111334 -328.00417)
		(end 212.51418 -328.00417)
		(width 0.381)
		(layer "B.Cu")
		(net "GND")
	)
	(segment
		(start 172.813726 -19.209258)
		(end 172.813726 -18.09242)
		(width 0.4572)
		(layer "B.Cu")
		(net "GND")
	)
	(segment
		(start 47.70628 -428.46498)
		(end 47.054516 -428.46498)
		(width 0.381)
		(layer "B.Cu")
		(net "GND")
	)
	(segment
		(start 398.043908 -326.671432)
		(end 398.043908 -326.394572)
		(width 0.381)
		(layer "B.Cu")
		(net "GND")
	)
	(segment
		(start 187.234576 -112.66297)
		(end 187.511944 -112.385602)
		(width 0.254)
		(layer "B.Cu")
		(net "GND")
	)
	(segment
		(start 182.732426 -113.768886)
		(end 182.42661 -113.46307)
		(width 0.254)
		(layer "B.Cu")
		(net "GND")
	)
	(segment
		(start 295.150286 -424.118786)
		(end 294.574214 -424.118786)
		(width 0.254)
		(layer "B.Cu")
		(net "GND")
	)
	(segment
		(start 73.295764 -9.50468)
		(end 72.825864 -9.97458)
		(width 0.381)
		(layer "B.Cu")
		(net "GND")
	)
	(segment
		(start 103.632 -416.32505)
		(end 103.14305 -416.814)
		(width 0.4572)
		(layer "B.Cu")
		(net "GND")
	)
	(segment
		(start 444.622936 -417.277804)
		(end 444.617602 -417.283138)
		(width 0.4572)
		(layer "B.Cu")
		(net "GND")
	)
	(segment
		(start 313.90463 -76.239878)
		(end 313.26963 -76.239878)
		(width 0.4572)
		(layer "B.Cu")
		(net "GND")
	)
	(segment
		(start 145.610834 -320.525902)
		(end 145.610834 -320.417952)
		(width 0.4572)
		(layer "B.Cu")
		(net "GND")
	)
	(segment
		(start 395.102334 -200.342754)
		(end 395.123162 -200.363582)
		(width 0.4572)
		(layer "B.Cu")
		(net "GND")
	)
	(segment
		(start 366.63249 -393.04468)
		(end 367.16589 -393.04468)
		(width 0.254)
		(layer "B.Cu")
		(net "GND")
	)
	(segment
		(start 108.507784 -271.469612)
		(end 108.321094 -271.656302)
		(width 0.3556)
		(layer "B.Cu")
		(net "GND")
	)
	(segment
		(start 238.8743 -331.47)
		(end 238.379 -331.47)
		(width 0.381)
		(layer "B.Cu")
		(net "GND")
	)
	(segment
		(start 225.4123 -332.105)
		(end 224.79 -332.105)
		(width 0.254)
		(layer "B.Cu")
		(net "GND")
	)
	(segment
		(start 148.463 -204.315568)
		(end 148.463 -205.069948)
		(width 0.4572)
		(layer "B.Cu")
		(net "GND")
	)
	(segment
		(start 47.668942 -420.81069)
		(end 48.321468 -420.78529)
		(width 0.381)
		(layer "B.Cu")
		(net "GND")
	)
	(segment
		(start 228.783642 -290.564062)
		(end 228.783642 -291.224462)
		(width 0.381)
		(layer "B.Cu")
		(net "GND")
	)
	(segment
		(start 366.645698 -138.680698)
		(end 367.271808 -138.054588)
		(width 0.381)
		(layer "B.Cu")
		(net "GND")
	)
	(segment
		(start 35.640264 -193.980054)
		(end 35.640264 -193.996564)
		(width 0.381)
		(layer "B.Cu")
		(net "GND")
	)
	(segment
		(start 177.396902 -133.739382)
		(end 177.396902 -134.099046)
		(width 0.3556)
		(layer "B.Cu")
		(net "GND")
	)
	(segment
		(start 398.043908 -326.394572)
		(end 398.43964 -325.99884)
		(width 0.381)
		(layer "B.Cu")
		(net "GND")
	)
	(segment
		(start 428.5869 -39.055548)
		(end 427.97095 -39.055548)
		(width 0.4064)
		(layer "B.Cu")
		(net "GND")
	)
	(segment
		(start 201.5236 -116.971572)
		(end 202.203812 -116.971572)
		(width 0.4572)
		(layer "B.Cu")
		(net "GND")
	)
	(segment
		(start 367.271808 -136.986772)
		(end 366.661954 -136.986772)
		(width 0.381)
		(layer "B.Cu")
		(net "GND")
	)
	(segment
		(start 239.790478 -225.277172)
		(end 239.790478 -224.253044)
		(width 0.4572)
		(layer "B.Cu")
		(net "GND")
	)
	(segment
		(start 182.732426 -113.862866)
		(end 182.732426 -113.768886)
		(width 0.254)
		(layer "B.Cu")
		(net "GND")
	)
	(segment
		(start 7.79272 -113.161826)
		(end 7.79272 -112.04702)
		(width 0.3556)
		(layer "B.Cu")
		(net "GND")
	)
	(segment
		(start 179.162964 -426.70476)
		(end 179.162964 -427.752256)
		(width 0.4572)
		(layer "B.Cu")
		(net "GND")
	)
	(segment
		(start 215.168988 -67.333368)
		(end 215.376506 -67.333368)
		(width 0.4572)
		(layer "B.Cu")
		(net "GND")
	)
	(segment
		(start 165.677596 -414.797748)
		(end 165.677596 -414.112964)
		(width 0.4572)
		(layer "B.Cu")
		(net "GND")
	)
	(segment
		(start 343.574624 -74.184764)
		(end 342.939624 -74.184764)
		(width 0.4572)
		(layer "B.Cu")
		(net "GND")
	)
	(segment
		(start 7.79272 -112.04702)
		(end 7.79272 -111.288068)
		(width 0.3556)
		(layer "B.Cu")
		(net "GND")
	)
	(segment
		(start 164.403532 -436.33263)
		(end 166.152322 -436.33263)
		(width 0.4572)
		(layer "B.Cu")
		(net "GND")
	)
	(segment
		(start 173.130718 -17.775428)
		(end 173.468284 -17.775428)
		(width 0.4572)
		(layer "B.Cu")
		(net "GND")
	)
	(segment
		(start 357.239316 -396.150592)
		(end 357.443786 -396.355062)
		(width 0.3048)
		(layer "B.Cu")
		(net "GND")
	)
	(segment
		(start 427.693328 -436.014622)
		(end 427.411896 -436.296054)
		(width 0.4572)
		(layer "B.Cu")
		(net "GND")
	)
	(segment
		(start 115.784884 -271.606518)
		(end 115.834668 -271.656302)
		(width 0.254)
		(layer "B.Cu")
		(net "GND")
	)
	(segment
		(start 147.722336 -314.47105)
		(end 147.02282 -314.47105)
		(width 0.4572)
		(layer "B.Cu")
		(net "GND")
	)
	(segment
		(start 332.060042 -393.96416)
		(end 332.593442 -393.96416)
		(width 0.254)
		(layer "B.Cu")
		(net "GND")
	)
	(segment
		(start 117.094 -418.35705)
		(end 117.094 -419.1)
		(width 0.4572)
		(layer "B.Cu")
		(net "GND")
	)
	(segment
		(start 405.700738 -339.672422)
		(end 406.850088 -339.672422)
		(width 0.4572)
		(layer "B.Cu")
		(net "GND")
	)
	(segment
		(start 51.766978 -426.4406)
		(end 51.766978 -427.017942)
		(width 0.381)
		(layer "B.Cu")
		(net "GND")
	)
	(segment
		(start 325.286624 -74.184764)
		(end 324.651624 -74.184764)
		(width 0.4572)
		(layer "B.Cu")
		(net "GND")
	)
	(segment
		(start 356.006908 -246.149876)
		(end 355.961188 -246.104156)
		(width 0.254)
		(layer "B.Cu")
		(net "GND")
	)
	(segment
		(start 13.909548 -113.028222)
		(end 13.400532 -112.519206)
		(width 0.2032)
		(layer "B.Cu")
		(net "GND")
	)
	(segment
		(start 422.721024 -429.34255)
		(end 422.721024 -429.461676)
		(width 0.254)
		(layer "B.Cu")
		(net "GND")
	)
	(segment
		(start 435.405784 -26.486358)
		(end 435.7497 -26.142442)
		(width 0.4064)
		(layer "B.Cu")
		(net "GND")
	)
	(segment
		(start 13.400532 -112.519206)
		(end 12.876784 -112.519206)
		(width 0.2032)
		(layer "B.Cu")
		(net "GND")
	)
	(segment
		(start 315.80455 -77.53985)
		(end 316.43955 -77.53985)
		(width 0.4572)
		(layer "B.Cu")
		(net "GND")
	)
	(segment
		(start 92.396056 -301.716948)
		(end 92.458794 -301.779686)
		(width 0.4572)
		(layer "B.Cu")
		(net "GND")
	)
	(segment
		(start 59.391296 -390.642602)
		(end 59.391296 -390.160002)
		(width 0.254)
		(layer "B.Cu")
		(net "GND")
	)
	(segment
		(start 51.72964 -426.403262)
		(end 51.766978 -426.4406)
		(width 0.381)
		(layer "B.Cu")
		(net "GND")
	)
	(segment
		(start 299.532294 -391.88136)
		(end 299.821854 -391.88136)
		(width 0.254)
		(layer "B.Cu")
		(net "GND")
	)
	(segment
		(start 370.505228 -146.552158)
		(end 369.895628 -146.552158)
		(width 0.381)
		(layer "B.Cu")
		(net "GND")
	)
	(segment
		(start 169.881042 -98.535998)
		(end 169.5577 -98.85934)
		(width 0.4572)
		(layer "B.Cu")
		(net "GND")
	)
	(segment
		(start 329.3237 -34.139886)
		(end 330.199492 -34.139886)
		(width 0.4572)
		(layer "B.Cu")
		(net "GND")
	)
	(segment
		(start 93.811344 -307.730652)
		(end 93.430344 -307.349652)
		(width 0.381)
		(layer "B.Cu")
		(net "GND")
	)
	(segment
		(start 256.13741 -324.045072)
		(end 256.75971 -324.045072)
		(width 0.381)
		(layer "B.Cu")
		(net "GND")
	)
	(segment
		(start 70.3199 -383.257806)
		(end 70.12559 -383.452116)
		(width 0.254)
		(layer "B.Cu")
		(net "GND")
	)
	(segment
		(start 188.90996 -420.03091)
		(end 188.90996 -420.961058)
		(width 0.4572)
		(layer "B.Cu")
		(net "GND")
	)
	(segment
		(start 22.07895 -365.76)
		(end 21.463 -365.76)
		(width 0.4572)
		(layer "B.Cu")
		(net "GND")
	)
	(segment
		(start 455.07783 -48.506888)
		(end 455.07783 -49.122838)
		(width 0.4572)
		(layer "B.Cu")
		(net "GND")
	)
	(segment
		(start 160.103312 -418.7952)
		(end 159.501332 -419.39718)
		(width 0.3302)
		(layer "B.Cu")
		(net "GND")
	)
	(segment
		(start 182.308246 -420.975536)
		(end 182.308246 -420.349934)
		(width 0.4572)
		(layer "B.Cu")
		(net "GND")
	)
	(segment
		(start 98.464878 -139.53236)
		(end 98.464878 -138.906504)
		(width 0.381)
		(layer "B.Cu")
		(net "GND")
	)
	(segment
		(start 180.830982 -106.490262)
		(end 180.830982 -106.964226)
		(width 0.254)
		(layer "B.Cu")
		(net "GND")
	)
	(segment
		(start 405.809196 -354.839778)
		(end 405.809196 -355.345746)
		(width 0.4572)
		(layer "B.Cu")
		(net "GND")
	)
	(segment
		(start 186.606688 -113.062766)
		(end 186.312048 -113.357406)
		(width 0.254)
		(layer "B.Cu")
		(net "GND")
	)
	(segment
		(start 356.311708 -271.395952)
		(end 356.311708 -271.605502)
		(width 0.254)
		(layer "B.Cu")
		(net "GND")
	)
	(segment
		(start 168.452292 -432.387248)
		(end 168.655238 -432.590194)
		(width 0.4572)
		(layer "B.Cu")
		(net "GND")
	)
	(segment
		(start 52.782978 -434.082952)
		(end 53.620162 -434.082952)
		(width 0.4572)
		(layer "B.Cu")
		(net "GND")
	)
	(segment
		(start 148.252434 -204.105002)
		(end 148.463 -204.315568)
		(width 0.4572)
		(layer "B.Cu")
		(net "GND")
	)
	(segment
		(start 326.319642 -391.639806)
		(end 326.125332 -391.834116)
		(width 0.254)
		(layer "B.Cu")
		(net "GND")
	)
	(segment
		(start 402.186394 -354.839778)
		(end 403.377146 -354.839778)
		(width 0.4572)
		(layer "B.Cu")
		(net "GND")
	)
	(segment
		(start 94.070424 -304.710592)
		(end 93.416628 -304.710592)
		(width 0.4572)
		(layer "B.Cu")
		(net "GND")
	)
	(segment
		(start 15.448788 -132.38988)
		(end 15.1892 -132.38988)
		(width 0.3556)
		(layer "B.Cu")
		(net "GND")
	)
	(segment
		(start 111.735108 -381.321818)
		(end 111.274098 -381.321818)
		(width 0.4572)
		(layer "B.Cu")
		(net "GND")
	)
	(segment
		(start 418.822886 -425.560998)
		(end 418.822886 -425.82338)
		(width 0.254)
		(layer "B.Cu")
		(net "GND")
	)
	(segment
		(start 74.467212 -3.76428)
		(end 73.914 -3.76428)
		(width 0.4572)
		(layer "B.Cu")
		(net "GND")
	)
	(segment
		(start 188.538612 -144.58823)
		(end 188.538612 -143.933418)
		(width 0.4572)
		(layer "B.Cu")
		(net "GND")
	)
	(segment
		(start 359.939844 -419.027864)
		(end 360.690668 -419.027864)
		(width 0.4572)
		(layer "B.Cu")
		(net "GND")
	)
	(segment
		(start 26.32329 -194.885564)
		(end 26.307796 -194.885564)
		(width 0.381)
		(layer "B.Cu")
		(net "GND")
	)
	(segment
		(start 234.0737 -332.74)
		(end 234.696 -332.74)
		(width 0.254)
		(layer "B.Cu")
		(net "GND")
	)
	(segment
		(start 101.512878 -139.53236)
		(end 101.512878 -138.91641)
		(width 0.381)
		(layer "B.Cu")
		(net "GND")
	)
	(segment
		(start 124.091446 -271.453102)
		(end 124.294646 -271.656302)
		(width 0.3556)
		(layer "B.Cu")
		(net "GND")
	)
	(segment
		(start 332.80477 -389.97763)
		(end 332.30566 -389.47852)
		(width 0.4572)
		(layer "B.Cu")
		(net "GND")
	)
	(segment
		(start 179.281582 -414.283144)
		(end 179.281582 -413.565086)
		(width 0.4572)
		(layer "B.Cu")
		(net "GND")
	)
	(segment
		(start 384.987292 -141.218158)
		(end 385.154678 -141.050772)
		(width 0.381)
		(layer "B.Cu")
		(net "GND")
	)
	(segment
		(start 43.532552 -383.49936)
		(end 43.822112 -383.49936)
		(width 0.254)
		(layer "B.Cu")
		(net "GND")
	)
	(segment
		(start 21.623782 -412.850584)
		(end 20.880832 -412.850584)
		(width 0.381)
		(layer "B.Cu")
		(net "GND")
	)
	(segment
		(start 79.175864 -10.86866)
		(end 78.159864 -10.86866)
		(width 0.381)
		(layer "B.Cu")
		(net "GND")
	)
	(segment
		(start 168.452292 -431.97653)
		(end 168.452292 -432.387248)
		(width 0.4572)
		(layer "B.Cu")
		(net "GND")
	)
	(segment
		(start 197.985888 -124.801376)
		(end 198.435468 -124.351796)
		(width 0.4572)
		(layer "B.Cu")
		(net "GND")
	)
	(segment
		(start 184.4294 -117.042946)
		(end 184.732168 -116.740178)
		(width 0.254)
		(layer "B.Cu")
		(net "GND")
	)
	(segment
		(start 384.513328 -139.186158)
		(end 384.513328 -140.202158)
		(width 0.381)
		(layer "B.Cu")
		(net "GND")
	)
	(segment
		(start 191.301116 -19.311366)
		(end 191.673734 -18.938748)
		(width 0.4572)
		(layer "B.Cu")
		(net "GND")
	)
	(segment
		(start 184.732168 -116.740178)
		(end 184.732168 -116.642642)
		(width 0.254)
		(layer "B.Cu")
		(net "GND")
	)
	(segment
		(start 437.886602 -423.66311)
		(end 438.629552 -423.66311)
		(width 0.381)
		(layer "B.Cu")
		(net "GND")
	)
	(segment
		(start 244.636036 -225.314002)
		(end 244.636036 -224.265744)
		(width 0.4572)
		(layer "B.Cu")
		(net "GND")
	)
	(segment
		(start 399.160238 -393.04468)
		(end 399.693638 -393.04468)
		(width 0.254)
		(layer "B.Cu")
		(net "GND")
	)
	(segment
		(start 428.5869 -38.039548)
		(end 427.97095 -38.039548)
		(width 0.4064)
		(layer "B.Cu")
		(net "GND")
	)
	(segment
		(start 407.290778 -331.790548)
		(end 407.618692 -332.118462)
		(width 0.4064)
		(layer "B.Cu")
		(net "GND")
	)
	(segment
		(start 454.068688 -13.502894)
		(end 453.408288 -13.502894)
		(width 0.381)
		(layer "B.Cu")
		(net "GND")
	)
	(segment
		(start 25.16505 -358.444038)
		(end 24.92375 -358.202738)
		(width 0.4572)
		(layer "B.Cu")
		(net "GND")
	)
	(segment
		(start 431.26406 -436.49265)
		(end 430.79289 -436.49265)
		(width 0.4572)
		(layer "B.Cu")
		(net "GND")
	)
	(segment
		(start 233.37012 -422.449498)
		(end 234.007406 -422.449498)
		(width 0.381)
		(layer "B.Cu")
		(net "GND")
	)
	(segment
		(start 61.413898 -15.18031)
		(end 62.051184 -15.18031)
		(width 0.4572)
		(layer "B.Cu")
		(net "GND")
	)
	(segment
		(start 107.329986 -416.02152)
		(end 107.022138 -415.713672)
		(width 0.4572)
		(layer "B.Cu")
		(net "GND")
	)
	(segment
		(start 49.6062 -429.764952)
		(end 49.6062 -430.504092)
		(width 0.4572)
		(layer "B.Cu")
		(net "GND")
	)
	(segment
		(start 10.16 -81.55305)
		(end 10.16 -82.169)
		(width 0.4572)
		(layer "B.Cu")
		(net "GND")
	)
	(segment
		(start 252.559566 -325.931022)
		(end 253.66599 -325.931022)
		(width 0.3556)
		(layer "B.Cu")
		(net "GND")
	)
	(segment
		(start 213.029546 -329.014582)
		(end 212.493098 -329.014582)
		(width 0.381)
		(layer "B.Cu")
		(net "GND")
	)
	(segment
		(start 299.689774 -392.66876)
		(end 300.065694 -393.04468)
		(width 0.254)
		(layer "B.Cu")
		(net "GND")
	)
	(segment
		(start 50.720498 -193.996564)
		(end 50.728372 -193.996564)
		(width 0.381)
		(layer "B.Cu")
		(net "GND")
	)
	(segment
		(start 257.379724 -133.025134)
		(end 257.379724 -133.641084)
		(width 0.381)
		(layer "B.Cu")
		(net "GND")
	)
	(segment
		(start 201.690986 -141.41196)
		(end 201.690986 -140.603986)
		(width 0.4572)
		(layer "B.Cu")
		(net "GND")
	)
	(segment
		(start 51.766978 -427.66488)
		(end 51.766978 -427.017942)
		(width 0.381)
		(layer "B.Cu")
		(net "GND")
	)
	(segment
		(start 323.683884 -396.150592)
		(end 324.711568 -396.150592)
		(width 0.3048)
		(layer "B.Cu")
		(net "GND")
	)
	(segment
		(start 90.609928 -139.80541)
		(end 90.609928 -139.194794)
		(width 0.4572)
		(layer "B.Cu")
		(net "GND")
	)
	(segment
		(start 399.160238 -393.96416)
		(end 399.693638 -393.96416)
		(width 0.254)
		(layer "B.Cu")
		(net "GND")
	)
	(segment
		(start 407.618692 -332.118462)
		(end 407.916634 -332.118462)
		(width 0.4064)
		(layer "B.Cu")
		(net "GND")
	)
	(segment
		(start 319.322704 -72.884792)
		(end 318.539876 -72.884792)
		(width 0.4572)
		(layer "B.Cu")
		(net "GND")
	)
	(segment
		(start 108.101384 -246.402352)
		(end 108.101384 -246.184674)
		(width 0.254)
		(layer "B.Cu")
		(net "GND")
	)
	(segment
		(start 232.537 -217.65895)
		(end 233.299 -217.65895)
		(width 0.4572)
		(layer "B.Cu")
		(net "GND")
	)
	(segment
		(start 87.777828 -148.94941)
		(end 87.168228 -148.94941)
		(width 0.381)
		(layer "B.Cu")
		(net "GND")
	)
	(segment
		(start 197.822058 -124.801376)
		(end 197.985888 -124.801376)
		(width 0.4572)
		(layer "B.Cu")
		(net "GND")
	)
	(segment
		(start 28.06319 -193.996564)
		(end 28.096464 -193.996564)
		(width 0.381)
		(layer "B.Cu")
		(net "GND")
	)
	(segment
		(start 165.01618 -434.11902)
		(end 166.438834 -434.11902)
		(width 0.4572)
		(layer "B.Cu")
		(net "GND")
	)
	(segment
		(start 235.21162 -323.746114)
		(end 235.928408 -323.746114)
		(width 0.381)
		(layer "B.Cu")
		(net "GND")
	)
	(segment
		(start 184.43702 -113.062766)
		(end 184.332372 -113.062766)
		(width 0.254)
		(layer "B.Cu")
		(net "GND")
	)
	(segment
		(start 167.39743 -105.264712)
		(end 167.86479 -104.797352)
		(width 0.4572)
		(layer "B.Cu")
		(net "GND")
	)
	(segment
		(start 381.192278 -137.135108)
		(end 381.192278 -136.509252)
		(width 0.381)
		(layer "B.Cu")
		(net "GND")
	)
	(segment
		(start 162.934142 -419.262306)
		(end 163.106354 -419.090094)
		(width 0.3302)
		(layer "B.Cu")
		(net "GND")
	)
	(segment
		(start 236.27588 -49.120044)
		(end 236.27588 -48.154844)
		(width 0.4572)
		(layer "B.Cu")
		(net "GND")
	)
	(segment
		(start 396.941548 -145.001488)
		(end 396.589504 -145.353532)
		(width 0.4572)
		(layer "B.Cu")
		(net "GND")
	)
	(segment
		(start 192.395856 -72.804528)
		(end 192.395856 -72.158098)
		(width 0.3556)
		(layer "B.Cu")
		(net "GND")
	)
	(segment
		(start 384.513328 -141.218158)
		(end 384.987292 -141.218158)
		(width 0.381)
		(layer "B.Cu")
		(net "GND")
	)
	(segment
		(start 76.552552 -381.238252)
		(end 76.1873 -380.873)
		(width 0.4572)
		(layer "B.Cu")
		(net "GND")
	)
	(segment
		(start 164.403532 -433.75453)
		(end 164.403532 -432.77663)
		(width 0.4572)
		(layer "B.Cu")
		(net "GND")
	)
	(segment
		(start 163.963858 -113.013744)
		(end 163.963858 -114.542062)
		(width 0.4572)
		(layer "B.Cu")
		(net "GND")
	)
	(segment
		(start 151.275034 -202.377802)
		(end 151.275034 -202.633072)
		(width 0.4572)
		(layer "B.Cu")
		(net "GND")
	)
	(segment
		(start 372.099586 -425.158916)
		(end 372.43004 -425.48937)
		(width 0.4572)
		(layer "B.Cu")
		(net "GND")
	)
	(segment
		(start 110.632494 -384.66268)
		(end 111.165894 -384.66268)
		(width 0.254)
		(layer "B.Cu")
		(net "GND")
	)
	(segment
		(start 58.836814 -193.832226)
		(end 59.001152 -193.996564)
		(width 0.381)
		(layer "B.Cu")
		(net "GND")
	)
	(segment
		(start 253.563628 -327.201022)
		(end 253.823216 -327.46061)
		(width 0.3556)
		(layer "B.Cu")
		(net "GND")
	)
	(segment
		(start 170.79595 -118.328948)
		(end 170.791378 -118.324376)
		(width 0.4572)
		(layer "B.Cu")
		(net "GND")
	)
	(segment
		(start 182.732426 -116.242846)
		(end 182.732426 -116.352574)
		(width 0.254)
		(layer "B.Cu")
		(net "GND")
	)
	(segment
		(start 347.97873 -271.478502)
		(end 347.801184 -271.656048)
		(width 0.4572)
		(layer "B.Cu")
		(net "GND")
	)
	(segment
		(start 393.419838 -391.639806)
		(end 393.225528 -391.834116)
		(width 0.254)
		(layer "B.Cu")
		(net "GND")
	)
	(segment
		(start 376.57659 -422.618916)
		(end 374.135396 -422.618916)
		(width 0.4572)
		(layer "B.Cu")
		(net "GND")
	)
	(segment
		(start 235.230924 -326.947022)
		(end 235.947712 -326.947022)
		(width 0.381)
		(layer "B.Cu")
		(net "GND")
	)
	(segment
		(start 437.886602 -421.37711)
		(end 438.629552 -421.37711)
		(width 0.381)
		(layer "B.Cu")
		(net "GND")
	)
	(segment
		(start 380.536958 -208.130902)
		(end 380.536958 -207.521302)
		(width 0.381)
		(layer "B.Cu")
		(net "GND")
	)
	(segment
		(start 144.308068 -381.50419)
		(end 143.63319 -381.50419)
		(width 0.4572)
		(layer "B.Cu")
		(net "GND")
	)
	(segment
		(start 380.629922 -148.70176)
		(end 381.645922 -148.70176)
		(width 0.381)
		(layer "B.Cu")
		(net "GND")
	)
	(segment
		(start 236.676692 -422.449498)
		(end 236.676692 -421.833548)
		(width 0.381)
		(layer "B.Cu")
		(net "GND")
	)
	(segment
		(start 98.918522 -151.099012)
		(end 97.902522 -151.099012)
		(width 0.381)
		(layer "B.Cu")
		(net "GND")
	)
	(segment
		(start 187.511944 -112.385602)
		(end 187.511944 -112.263174)
		(width 0.254)
		(layer "B.Cu")
		(net "GND")
	)
	(segment
		(start 187.325 -424.86199)
		(end 187.325 -425.967906)
		(width 0.4572)
		(layer "B.Cu")
		(net "GND")
	)
	(segment
		(start 22.07895 -362.204)
		(end 21.336 -362.204)
		(width 0.4572)
		(layer "B.Cu")
		(net "GND")
	)
	(segment
		(start 367.462562 -390.078722)
		(end 366.8268 -389.44296)
		(width 0.4572)
		(layer "B.Cu")
		(net "GND")
	)
	(segment
		(start 123.970034 -271.453102)
		(end 124.091446 -271.453102)
		(width 0.3556)
		(layer "B.Cu")
		(net "GND")
	)
	(segment
		(start 173.46295 -420.243)
		(end 173.46295 -420.907464)
		(width 0.4572)
		(layer "B.Cu")
		(net "GND")
	)
	(segment
		(start 403.377146 -354.839778)
		(end 404.568152 -354.839778)
		(width 0.4572)
		(layer "B.Cu")
		(net "GND")
	)
	(segment
		(start 21.623782 -410.564584)
		(end 20.880832 -410.564584)
		(width 0.381)
		(layer "B.Cu")
		(net "GND")
	)
	(segment
		(start 403.651212 -201.550524)
		(end 402.551646 -201.550524)
		(width 0.4572)
		(layer "B.Cu")
		(net "GND")
	)
	(segment
		(start 112.96904 -416.926014)
		(end 113.636298 -416.926014)
		(width 0.4572)
		(layer "B.Cu")
		(net "GND")
	)
	(segment
		(start 299.821854 -391.88136)
		(end 300.065694 -392.1252)
		(width 0.254)
		(layer "B.Cu")
		(net "GND")
	)
	(segment
		(start 228.885242 -326.49668)
		(end 229.60203 -326.49668)
		(width 0.381)
		(layer "B.Cu")
		(net "GND")
	)
	(segment
		(start 356.21595 -418.286946)
		(end 356.21595 -418.981128)
		(width 0.4572)
		(layer "B.Cu")
		(net "GND")
	)
	(segment
		(start 170.79595 -116.296948)
		(end 170.791378 -116.292376)
		(width 0.4572)
		(layer "B.Cu")
		(net "GND")
	)
	(segment
		(start 256.157476 -325.056754)
		(end 256.779776 -325.056754)
		(width 0.381)
		(layer "B.Cu")
		(net "GND")
	)
	(segment
		(start 114.86896 -418.519864)
		(end 115.341146 -418.99205)
		(width 0.4572)
		(layer "B.Cu")
		(net "GND")
	)
	(segment
		(start 99.480878 -139.53236)
		(end 99.480878 -138.891264)
		(width 0.381)
		(layer "B.Cu")
		(net "GND")
	)
	(segment
		(start 300.673008 -389.444738)
		(end 299.731938 -389.444738)
		(width 0.4572)
		(layer "B.Cu")
		(net "GND")
	)
	(segment
		(start 450.482716 -9.676892)
		(end 450.313044 -9.50722)
		(width 0.4572)
		(layer "B.Cu")
		(net "GND")
	)
	(segment
		(start 100.496878 -139.53236)
		(end 100.496878 -138.911076)
		(width 0.381)
		(layer "B.Cu")
		(net "GND")
	)
	(segment
		(start 433.16398 -437.792622)
		(end 432.505358 -437.792622)
		(width 0.4572)
		(layer "B.Cu")
		(net "GND")
	)
	(segment
		(start 354.491798 -416.986974)
		(end 354.931218 -416.547554)
		(width 0.4572)
		(layer "B.Cu")
		(net "GND")
	)
	(segment
		(start 238.8743 -330.581)
		(end 238.252 -330.581)
		(width 0.381)
		(layer "B.Cu")
		(net "GND")
	)
	(segment
		(start 363.411008 -246.376952)
		(end 363.411008 -246.16791)
		(width 0.254)
		(layer "B.Cu")
		(net "GND")
	)
	(segment
		(start 184.322212 -144.399)
		(end 184.58688 -144.663668)
		(width 0.381)
		(layer "B.Cu")
		(net "GND")
	)
	(segment
		(start 143.63319 -381.50419)
		(end 142.96644 -380.83744)
		(width 0.4572)
		(layer "B.Cu")
		(net "GND")
	)
	(segment
		(start 444.598552 -417.67506)
		(end 444.617602 -418.18306)
		(width 0.381)
		(layer "B.Cu")
		(net "GND")
	)
	(segment
		(start 180.830982 -106.964226)
		(end 180.732176 -107.063032)
		(width 0.254)
		(layer "B.Cu")
		(net "GND")
	)
	(segment
		(start 159.934656 -414.803844)
		(end 162.083242 -414.803844)
		(width 0.381)
		(layer "B.Cu")
		(net "GND")
	)
	(segment
		(start 243.31295 -323.85)
		(end 242.57 -323.85)
		(width 0.4572)
		(layer "B.Cu")
		(net "GND")
	)
	(segment
		(start 393.809728 -200.342754)
		(end 395.102334 -200.342754)
		(width 0.4572)
		(layer "B.Cu")
		(net "GND")
	)
	(segment
		(start 240.727992 -290.564062)
		(end 240.727992 -291.224462)
		(width 0.4572)
		(layer "B.Cu")
		(net "GND")
	)
	(segment
		(start 115.530884 -246.10822)
		(end 115.534694 -246.10441)
		(width 0.254)
		(layer "B.Cu")
		(net "GND")
	)
	(segment
		(start 372.537228 -143.504158)
		(end 372.537228 -142.488158)
		(width 0.381)
		(layer "B.Cu")
		(net "GND")
	)
	(segment
		(start 9.838182 -409.072334)
		(end 8.932418 -409.072334)
		(width 0.4572)
		(layer "B.Cu")
		(net "GND")
	)
	(segment
		(start 229.601014 -220.86697)
		(end 229.601014 -221.996)
		(width 0.4572)
		(layer "B.Cu")
		(net "GND")
	)
	(segment
		(start 192.744852 -81.177384)
		(end 192.775586 -81.177384)
		(width 0.4572)
		(layer "B.Cu")
		(net "GND")
	)
	(segment
		(start 14.407388 -110.604554)
		(end 13.6652 -110.604554)
		(width 0.3556)
		(layer "B.Cu")
		(net "GND")
	)
	(segment
		(start 166.858442 -424.117262)
		(end 166.602156 -423.860976)
		(width 0.3048)
		(layer "B.Cu")
		(net "GND")
	)
	(segment
		(start 244.464586 -340.421214)
		(end 245.745 -340.421214)
		(width 0.254)
		(layer "B.Cu")
		(net "GND")
	)
	(segment
		(start 360.233976 -417.10356)
		(end 359.754678 -417.582858)
		(width 0.4572)
		(layer "B.Cu")
		(net "GND")
	)
	(segment
		(start 166.152322 -436.33263)
		(end 166.249858 -436.430166)
		(width 0.4572)
		(layer "B.Cu")
		(net "GND")
	)
	(segment
		(start 50.928524 -423.026586)
		(end 50.55616 -423.39895)
		(width 0.4572)
		(layer "B.Cu")
		(net "GND")
	)
	(segment
		(start 394.179298 -155.015946)
		(end 394.179298 -154.162252)
		(width 0.4064)
		(layer "B.Cu")
		(net "GND")
	)
	(segment
		(start 111.274098 -381.321818)
		(end 110.77956 -380.82728)
		(width 0.4572)
		(layer "B.Cu")
		(net "GND")
	)
	(segment
		(start 33.813496 -194.885564)
		(end 33.867344 -194.885564)
		(width 0.381)
		(layer "B.Cu")
		(net "GND")
	)
	(segment
		(start 94.88805 -301.716948)
		(end 95.29318 -301.716948)
		(width 0.4572)
		(layer "B.Cu")
		(net "GND")
	)
	(segment
		(start 317.302388 -199.998838)
		(end 317.091822 -199.998838)
		(width 0.4572)
		(layer "B.Cu")
		(net "GND")
	)
	(segment
		(start 77.183488 -381.238252)
		(end 76.552552 -381.238252)
		(width 0.4572)
		(layer "B.Cu")
		(net "GND")
	)
	(segment
		(start 13.622782 -416.044634)
		(end 13.61567 -416.235896)
		(width 0.381)
		(layer "B.Cu")
		(net "GND")
	)
	(segment
		(start 299.448728 -428.421292)
		(end 299.167804 -428.140368)
		(width 0.254)
		(layer "B.Cu")
		(net "GND")
	)
	(segment
		(start 356.211632 -396.150592)
		(end 357.239316 -396.150592)
		(width 0.3048)
		(layer "B.Cu")
		(net "GND")
	)
	(segment
		(start 50.928524 -422.777666)
		(end 50.928524 -423.026586)
		(width 0.4572)
		(layer "B.Cu")
		(net "GND")
	)
	(segment
		(start 163.387532 -430.19853)
		(end 162.378136 -429.189134)
		(width 0.4572)
		(layer "B.Cu")
		(net "GND")
	)
	(segment
		(start 367.271808 -135.970772)
		(end 366.661954 -135.970772)
		(width 0.381)
		(layer "B.Cu")
		(net "GND")
	)
	(segment
		(start 372.537228 -139.440158)
		(end 372.537228 -140.456158)
		(width 0.381)
		(layer "B.Cu")
		(net "GND")
	)
	(segment
		(start 404.568152 -354.839778)
		(end 405.809196 -354.839778)
		(width 0.4572)
		(layer "B.Cu")
		(net "GND")
	)
	(segment
		(start 49.568862 -422.110662)
		(end 49.57826 -422.578276)
		(width 0.4572)
		(layer "B.Cu")
		(net "GND")
	)
	(segment
		(start 396.142972 -200.354946)
		(end 396.817088 -200.354946)
		(width 0.4572)
		(layer "B.Cu")
		(net "GND")
	)
	(segment
		(start 400.301968 -390.035034)
		(end 399.999454 -390.035034)
		(width 0.4572)
		(layer "B.Cu")
		(net "GND")
	)
	(segment
		(start 234.644692 -422.449498)
		(end 234.644692 -421.833548)
		(width 0.381)
		(layer "B.Cu")
		(net "GND")
	)
	(segment
		(start 398.230344 -145.001488)
		(end 396.941548 -145.001488)
		(width 0.4572)
		(layer "B.Cu")
		(net "GND")
	)
	(segment
		(start 367.271808 -138.054588)
		(end 367.271808 -136.986772)
		(width 0.381)
		(layer "B.Cu")
		(net "GND")
	)
	(segment
		(start 172.813726 -18.09242)
		(end 173.130718 -17.775428)
		(width 0.4572)
		(layer "B.Cu")
		(net "GND")
	)
	(segment
		(start 370.505228 -147.568158)
		(end 369.895628 -147.568158)
		(width 0.381)
		(layer "B.Cu")
		(net "GND")
	)
	(segment
		(start 205.82128 -193.99631)
		(end 205.092554 -193.99631)
		(width 0.381)
		(layer "B.Cu")
		(net "GND")
	)
	(segment
		(start 164.266626 -108.676948)
		(end 163.746942 -108.157264)
		(width 0.4572)
		(layer "B.Cu")
		(net "GND")
	)
	(segment
		(start 371.376702 -425.158916)
		(end 372.099586 -425.158916)
		(width 0.4572)
		(layer "B.Cu")
		(net "GND")
	)
	(segment
		(start 137.851642 -9.436354)
		(end 137.851642 -10.048748)
		(width 0.4572)
		(layer "B.Cu")
		(net "GND")
	)
	(segment
		(start 45.039788 -381.6223)
		(end 45.039788 -380.57328)
		(width 0.4572)
		(layer "B.Cu")
		(net "GND")
	)
	(segment
		(start 371.921278 -143.504158)
		(end 372.537228 -143.504158)
		(width 0.381)
		(layer "B.Cu")
		(net "GND")
	)
	(segment
		(start 407.117804 -330.93533)
		(end 407.117804 -330.97216)
		(width 0.4064)
		(layer "B.Cu")
		(net "GND")
	)
	(segment
		(start 182.732172 -112.263174)
		(end 182.586122 -112.263174)
		(width 0.254)
		(layer "B.Cu")
		(net "GND")
	)
	(segment
		(start 363.411008 -246.16791)
		(end 363.474762 -246.104156)
		(width 0.254)
		(layer "B.Cu")
		(net "GND")
	)
	(segment
		(start 402.938996 -322.38696)
		(end 402.722588 -322.170552)
		(width 0.3556)
		(layer "B.Cu")
		(net "GND")
	)
	(segment
		(start 164.403532 -433.75453)
		(end 164.578538 -433.75453)
		(width 0.4572)
		(layer "B.Cu")
		(net "GND")
	)
	(segment
		(start 228.810566 -328.638662)
		(end 229.527354 -328.638662)
		(width 0.381)
		(layer "B.Cu")
		(net "GND")
	)
	(segment
		(start 331.366876 -75.708764)
		(end 330.731876 -75.708764)
		(width 0.381)
		(layer "B.Cu")
		(net "GND")
	)
	(segment
		(start 97.191068 -425.19219)
		(end 97.191068 -424.191684)
		(width 0.4572)
		(layer "B.Cu")
		(net "GND")
	)
	(segment
		(start 445.894714 -417.991798)
		(end 446.471802 -417.41471)
		(width 0.381)
		(layer "B.Cu")
		(net "GND")
	)
	(segment
		(start 179.793646 -31.636208)
		(end 179.639722 -31.482284)
		(width 0.4572)
		(layer "B.Cu")
		(net "GND")
	)
	(segment
		(start 43.532552 -385.91236)
		(end 43.735752 -385.91236)
		(width 0.254)
		(layer "B.Cu")
		(net "GND")
	)
	(segment
		(start 166.473124 -423.990008)
		(end 166.602156 -423.860976)
		(width 0.3048)
		(layer "B.Cu")
		(net "GND")
	)
	(segment
		(start 187.111894 -117.363494)
		(end 187.111894 -117.442742)
		(width 0.254)
		(layer "B.Cu")
		(net "GND")
	)
	(segment
		(start 212.885528 -326.509888)
		(end 212.263228 -326.509888)
		(width 0.381)
		(layer "B.Cu")
		(net "GND")
	)
	(segment
		(start 407.907998 -327.466452)
		(end 408.597608 -327.466452)
		(width 0.4572)
		(layer "B.Cu")
		(net "GND")
	)
	(segment
		(start 137.419842 -382.8796)
		(end 137.419842 -382.567942)
		(width 0.254)
		(layer "B.Cu")
		(net "GND")
	)
	(segment
		(start 176.6316 -426.744638)
		(end 176.6316 -428.215298)
		(width 0.4572)
		(layer "B.Cu")
		(net "GND")
	)
	(segment
		(start 165.199568 -418.493448)
		(end 165.32733 -418.62121)
		(width 0.4572)
		(layer "B.Cu")
		(net "GND")
	)
	(segment
		(start 345.738704 -72.884792)
		(end 344.955876 -72.884792)
		(width 0.4572)
		(layer "B.Cu")
		(net "GND")
	)
	(segment
		(start 168.452292 -435.53253)
		(end 168.452292 -435.860698)
		(width 0.4572)
		(layer "B.Cu")
		(net "GND")
	)
	(segment
		(start 183.064404 -117.442742)
		(end 182.732426 -117.77472)
		(width 0.254)
		(layer "B.Cu")
		(net "GND")
	)
	(segment
		(start 106.030014 -418.27196)
		(end 106.030014 -417.562284)
		(width 0.4572)
		(layer "B.Cu")
		(net "GND")
	)
	(segment
		(start 236.119162 -224.915984)
		(end 236.119162 -225.806)
		(width 0.4572)
		(layer "B.Cu")
		(net "GND")
	)
	(segment
		(start 105.13695 -419.989)
		(end 104.521 -419.989)
		(width 0.4572)
		(layer "B.Cu")
		(net "GND")
	)
	(segment
		(start 313.094624 -74.184764)
		(end 312.459624 -74.184764)
		(width 0.4572)
		(layer "B.Cu")
		(net "GND")
	)
	(segment
		(start 407.783538 -327.341992)
		(end 407.907998 -327.466452)
		(width 0.4572)
		(layer "B.Cu")
		(net "GND")
	)
	(segment
		(start 447.563748 -10.050272)
		(end 448.01536 -9.59866)
		(width 0.4572)
		(layer "B.Cu")
		(net "GND")
	)
	(segment
		(start 172.056044 -417.078668)
		(end 171.555918 -417.078668)
		(width 0.4572)
		(layer "B.Cu")
		(net "GND")
	)
	(segment
		(start 331.514704 -72.884792)
		(end 330.731876 -72.884792)
		(width 0.4572)
		(layer "B.Cu")
		(net "GND")
	)
	(segment
		(start 108.507784 -271.395952)
		(end 108.507784 -271.469612)
		(width 0.3556)
		(layer "B.Cu")
		(net "GND")
	)
	(segment
		(start 171.601384 -103.942388)
		(end 172.660056 -103.942388)
		(width 0.4572)
		(layer "B.Cu")
		(net "GND")
	)
	(segment
		(start 126.491238 -390.642602)
		(end 126.491238 -390.160002)
		(width 0.254)
		(layer "B.Cu")
		(net "GND")
	)
	(segment
		(start 188.48705 -143.881856)
		(end 188.538612 -143.933418)
		(width 0.4572)
		(layer "B.Cu")
		(net "GND")
	)
	(segment
		(start 321.222624 -74.184764)
		(end 320.587624 -74.184764)
		(width 0.4572)
		(layer "B.Cu")
		(net "GND")
	)
	(segment
		(start 433.835302 -9.425432)
		(end 433.166774 -9.425432)
		(width 0.4572)
		(layer "B.Cu")
		(net "GND")
	)
	(segment
		(start 228.820472 -329.698858)
		(end 229.53726 -329.698858)
		(width 0.381)
		(layer "B.Cu")
		(net "GND")
	)
	(segment
		(start 21.623782 -411.707584)
		(end 20.880832 -411.707584)
		(width 0.381)
		(layer "B.Cu")
		(net "GND")
	)
	(segment
		(start 367.812828 -390.078722)
		(end 367.462562 -390.078722)
		(width 0.4572)
		(layer "B.Cu")
		(net "GND")
	)
	(segment
		(start 394.037058 -321.179952)
		(end 394.667994 -321.179952)
		(width 0.254)
		(layer "B.Cu")
		(net "GND")
	)
	(segment
		(start 159.501332 -419.39718)
		(end 159.501332 -420.144956)
		(width 0.3302)
		(layer "B.Cu")
		(net "GND")
	)
	(segment
		(start 186.944254 -429.511206)
		(end 186.944254 -430.659286)
		(width 0.4572)
		(layer "B.Cu")
		(net "GND")
	)
	(segment
		(start 435.050946 -26.486358)
		(end 435.405784 -26.486358)
		(width 0.4064)
		(layer "B.Cu")
		(net "GND")
	)
	(segment
		(start 102.023164 -425.535344)
		(end 102.023164 -426.19295)
		(width 0.4572)
		(layer "B.Cu")
		(net "GND")
	)
	(segment
		(start 407.546048 -327.341992)
		(end 407.783538 -327.341992)
		(width 0.381)
		(layer "B.Cu")
		(net "GND")
	)
	(segment
		(start 333.414624 -74.184764)
		(end 332.779624 -74.184764)
		(width 0.4572)
		(layer "B.Cu")
		(net "GND")
	)
	(segment
		(start 176.33696 -426.449998)
		(end 176.6316 -426.744638)
		(width 0.4572)
		(layer "B.Cu")
		(net "GND")
	)
	(segment
		(start 181.845458 -427.298866)
		(end 180.937916 -427.298866)
		(width 0.4572)
		(layer "B.Cu")
		(net "GND")
	)
	(segment
		(start 14.892782 -416.912552)
		(end 14.892782 -416.044634)
		(width 0.4572)
		(layer "B.Cu")
		(net "GND")
	)
	(segment
		(start 329.350624 -74.184764)
		(end 328.715624 -74.184764)
		(width 0.4572)
		(layer "B.Cu")
		(net "GND")
	)
	(segment
		(start 192.287652 -80.60309)
		(end 192.287652 -80.720184)
		(width 0.4572)
		(layer "B.Cu")
		(net "GND")
	)
	(segment
		(start 134.784084 -387.768592)
		(end 135.811768 -387.768592)
		(width 0.3048)
		(layer "B.Cu")
		(net "GND")
	)
	(segment
		(start 428.5869 -30.165548)
		(end 427.97095 -30.165548)
		(width 0.4064)
		(layer "B.Cu")
		(net "GND")
	)
	(segment
		(start 162.85337 -115.65255)
		(end 162.173158 -115.65255)
		(width 0.4572)
		(layer "B.Cu")
		(net "GND")
	)
	(segment
		(start 236.27588 -48.154844)
		(end 236.22508 -48.104044)
		(width 0.4572)
		(layer "B.Cu")
		(net "GND")
	)
	(segment
		(start 371.646958 -246.269002)
		(end 371.769894 -246.269002)
		(width 0.4572)
		(layer "B.Cu")
		(net "GND")
	)
	(segment
		(start 407.290778 -331.145134)
		(end 407.290778 -331.790548)
		(width 0.4064)
		(layer "B.Cu")
		(net "GND")
	)
	(segment
		(start 183.132222 -117.442742)
		(end 183.064404 -117.442742)
		(width 0.254)
		(layer "B.Cu")
		(net "GND")
	)
	(segment
		(start 449.894452 -424.93311)
		(end 450.529452 -424.93311)
		(width 0.381)
		(layer "B.Cu")
		(net "GND")
	)
	(segment
		(start 177.396902 -134.099046)
		(end 176.911 -134.584948)
		(width 0.3556)
		(layer "B.Cu")
		(net "GND")
	)
	(segment
		(start 330.199492 -34.139886)
		(end 330.369672 -33.969706)
		(width 0.4572)
		(layer "B.Cu")
		(net "GND")
	)
	(segment
		(start 233.172 -235.712)
		(end 233.172 -234.96905)
		(width 0.381)
		(layer "B.Cu")
		(net "GND")
	)
	(segment
		(start 347.897958 -246.269002)
		(end 347.666056 -246.269002)
		(width 0.254)
		(layer "B.Cu")
		(net "GND")
	)
	(segment
		(start 253.350776 -321.850004)
		(end 253.973076 -321.850004)
		(width 0.381)
		(layer "B.Cu")
		(net "GND")
	)
	(segment
		(start 43.822112 -383.49936)
		(end 44.065952 -383.7432)
		(width 0.254)
		(layer "B.Cu")
		(net "GND")
	)
	(segment
		(start 298.565316 -424.448986)
		(end 298.565316 -423.683684)
		(width 0.254)
		(layer "B.Cu")
		(net "GND")
	)
	(segment
		(start 91.919044 -390.642602)
		(end 91.919044 -390.160002)
		(width 0.254)
		(layer "B.Cu")
		(net "GND")
	)
	(segment
		(start 166.977568 -412.897828)
		(end 166.977568 -413.546798)
		(width 0.381)
		(layer "B.Cu")
		(net "GND")
	)
	(segment
		(start 354.31603 -416.986974)
		(end 354.491798 -416.986974)
		(width 0.4572)
		(layer "B.Cu")
		(net "GND")
	)
	(segment
		(start 87.777828 -150.19909)
		(end 87.168228 -150.19909)
		(width 0.381)
		(layer "B.Cu")
		(net "GND")
	)
	(segment
		(start 299.167804 -428.140368)
		(end 299.167804 -427.261528)
		(width 0.254)
		(layer "B.Cu")
		(net "GND")
	)
	(segment
		(start 428.087282 -436.014622)
		(end 427.693328 -436.014622)
		(width 0.4572)
		(layer "B.Cu")
		(net "GND")
	)
	(segment
		(start 90.609928 -139.194794)
		(end 90.6399 -139.164822)
		(width 0.4572)
		(layer "B.Cu")
		(net "GND")
	)
	(segment
		(start 166.473124 -424.554904)
		(end 166.473124 -423.990008)
		(width 0.3048)
		(layer "B.Cu")
		(net "GND")
	)
	(segment
		(start 202.203812 -116.971572)
		(end 202.502008 -116.673376)
		(width 0.4572)
		(layer "B.Cu")
		(net "GND")
	)
	(segment
		(start 108.101384 -246.184674)
		(end 108.02112 -246.10441)
		(width 0.254)
		(layer "B.Cu")
		(net "GND")
	)
	(segment
		(start 49.6062 -433.604924)
		(end 48.95723 -433.604924)
		(width 0.381)
		(layer "B.Cu")
		(net "GND")
	)
	(segment
		(start 135.811768 -387.768592)
		(end 136.016238 -387.973062)
		(width 0.3048)
		(layer "B.Cu")
		(net "GND")
	)
	(segment
		(start 402.938996 -322.950078)
		(end 402.938996 -322.38696)
		(width 0.3556)
		(layer "B.Cu")
		(net "GND")
	)
	(segment
		(start 201.041 -141.41196)
		(end 201.041 -142.24)
		(width 0.4572)
		(layer "B.Cu")
		(net "GND")
	)
	(segment
		(start 199.39 -143.87195)
		(end 199.39 -143.129)
		(width 0.4572)
		(layer "B.Cu")
		(net "GND")
	)
	(segment
		(start 256.144776 -323.022722)
		(end 256.767076 -323.022722)
		(width 0.381)
		(layer "B.Cu")
		(net "GND")
	)
	(segment
		(start 393.419838 -391.2616)
		(end 393.419838 -391.639806)
		(width 0.254)
		(layer "B.Cu")
		(net "GND")
	)
	(segment
		(start 372.031768 -271.453102)
		(end 372.234714 -271.656048)
		(width 0.4572)
		(layer "B.Cu")
		(net "GND")
	)
	(segment
		(start 102.395782 -143.61541)
		(end 101.785928 -143.61541)
		(width 0.381)
		(layer "B.Cu")
		(net "GND")
	)
	(segment
		(start 177.841402 -133.294882)
		(end 177.396902 -133.739382)
		(width 0.3556)
		(layer "B.Cu")
		(net "GND")
	)
	(segment
		(start 356.006908 -246.376952)
		(end 356.006908 -246.149876)
		(width 0.254)
		(layer "B.Cu")
		(net "GND")
	)
	(segment
		(start 219.608146 -326.209152)
		(end 218.299284 -326.209152)
		(width 0.3556)
		(layer "B.Cu")
		(net "GND")
	)
	(segment
		(start 148.227034 -204.079602)
		(end 148.252434 -204.105002)
		(width 0.4572)
		(layer "B.Cu")
		(net "GND")
	)
	(segment
		(start 434.710586 -9.189974)
		(end 434.07076 -9.189974)
		(width 0.4572)
		(layer "B.Cu")
		(net "GND")
	)
	(segment
		(start 447.563748 -10.167112)
		(end 447.563748 -10.050272)
		(width 0.4572)
		(layer "B.Cu")
		(net "GND")
	)
	(segment
		(start 182.732426 -116.352574)
		(end 182.442358 -116.642642)
		(width 0.254)
		(layer "B.Cu")
		(net "GND")
	)
	(segment
		(start 175.483012 -414.435544)
		(end 174.830232 -414.435544)
		(width 0.4572)
		(layer "B.Cu")
		(net "GND")
	)
	(segment
		(start 396.134336 -200.363582)
		(end 396.142972 -200.354946)
		(width 0.4572)
		(layer "B.Cu")
		(net "GND")
	)
	(segment
		(start 371.900958 -271.453102)
		(end 372.031768 -271.453102)
		(width 0.4572)
		(layer "B.Cu")
		(net "GND")
	)
	(segment
		(start 214.921846 -67.58051)
		(end 215.168988 -67.333368)
		(width 0.4572)
		(layer "B.Cu")
		(net "GND")
	)
	(segment
		(start 85.45195 -147.955)
		(end 84.709 -147.955)
		(width 0.4572)
		(layer "B.Cu")
		(net "GND")
	)
	(segment
		(start 358.84739 -391.2616)
		(end 358.84739 -391.639806)
		(width 0.254)
		(layer "B.Cu")
		(net "GND")
	)
	(segment
		(start 169.050462 -383.304288)
		(end 169.050462 -382.28905)
		(width 0.254)
		(layer "B.Cu")
		(net "GND")
	)
	(segment
		(start 422.45915 -428.757334)
		(end 422.45915 -429.080676)
		(width 0.254)
		(layer "B.Cu")
		(net "GND")
	)
	(segment
		(start 172.056044 -413.776668)
		(end 171.423076 -413.776668)
		(width 0.4572)
		(layer "B.Cu")
		(net "GND")
	)
	(segment
		(start 382.208278 -137.135108)
		(end 382.208278 -136.494012)
		(width 0.381)
		(layer "B.Cu")
		(net "GND")
	)
	(segment
		(start 110.72495 -413.004)
		(end 110.250986 -413.004)
		(width 0.4572)
		(layer "B.Cu")
		(net "GND")
	)
	(segment
		(start 153.865834 -322.503292)
		(end 153.865834 -321.842892)
		(width 0.254)
		(layer "B.Cu")
		(net "GND")
	)
	(segment
		(start 338.734908 -307.717952)
		(end 338.125308 -307.717952)
		(width 0.381)
		(layer "B.Cu")
		(net "GND")
	)
	(segment
		(start 100.144834 -271.503902)
		(end 100.013516 -271.503902)
		(width 0.3556)
		(layer "B.Cu")
		(net "GND")
	)
	(segment
		(start 384.513328 -140.202158)
		(end 384.513328 -141.218158)
		(width 0.381)
		(layer "B.Cu")
		(net "GND")
	)
	(segment
		(start 215.69045 -322.52539)
		(end 215.06815 -322.52539)
		(width 0.381)
		(layer "B.Cu")
		(net "GND")
	)
	(segment
		(start 110.16234 -61.12256)
		(end 110.34268 -60.94222)
		(width 0.4572)
		(layer "B.Cu")
		(net "GND")
	)
	(segment
		(start 237.910878 -289.828732)
		(end 237.910878 -289.482022)
		(width 0.4572)
		(layer "B.Cu")
		(net "GND")
	)
	(segment
		(start 356.311708 -271.605502)
		(end 356.261162 -271.656048)
		(width 0.254)
		(layer "B.Cu")
		(net "GND")
	)
	(segment
		(start 444.617602 -418.18306)
		(end 445.887602 -418.18306)
		(width 0.381)
		(layer "B.Cu")
		(net "GND")
	)
	(segment
		(start 49.57826 -422.578276)
		(end 49.876964 -422.864534)
		(width 0.4572)
		(layer "B.Cu")
		(net "GND")
	)
	(segment
		(start 358.84739 -391.639806)
		(end 358.65308 -391.834116)
		(width 0.254)
		(layer "B.Cu")
		(net "GND")
	)
	(segment
		(start 47.70628 -432.304952)
		(end 48.359314 -432.304952)
		(width 0.381)
		(layer "B.Cu")
		(net "GND")
	)
	(segment
		(start 347.666056 -246.269002)
		(end 347.50121 -246.104156)
		(width 0.254)
		(layer "B.Cu")
		(net "GND")
	)
	(segment
		(start 369.3033 -426.466)
		(end 369.3033 -427.0883)
		(width 0.254)
		(layer "B.Cu")
		(net "GND")
	)
	(segment
		(start 450.19976 -423.935398)
		(end 450.83476 -423.935398)
		(width 0.381)
		(layer "B.Cu")
		(net "GND")
	)
	(segment
		(start 43.690032 -384.28676)
		(end 44.065952 -384.66268)
		(width 0.254)
		(layer "B.Cu")
		(net "GND")
	)
	(segment
		(start 435.145942 -8.754618)
		(end 434.710586 -9.189974)
		(width 0.4572)
		(layer "B.Cu")
		(net "GND")
	)
	(segment
		(start 445.887602 -418.18306)
		(end 445.894714 -417.991798)
		(width 0.381)
		(layer "B.Cu")
		(net "GND")
	)
	(segment
		(start 170.791378 -116.292376)
		(end 170.18 -116.292376)
		(width 0.4572)
		(layer "B.Cu")
		(net "GND")
	)
	(segment
		(start 392.016234 -396.355062)
		(end 391.811764 -396.150592)
		(width 0.3048)
		(layer "B.Cu")
		(net "GND")
	)
	(segment
		(start 228.894132 -322.17868)
		(end 229.61092 -322.17868)
		(width 0.381)
		(layer "B.Cu")
		(net "GND")
	)
	(segment
		(start 240.919 -236.45495)
		(end 241.681 -236.45495)
		(width 0.381)
		(layer "B.Cu")
		(net "GND")
	)
	(segment
		(start 25.16505 -358.775)
		(end 25.16505 -358.444038)
		(width 0.4572)
		(layer "B.Cu")
		(net "GND")
	)
	(segment
		(start 221.510098 -340.421214)
		(end 222.758 -340.421214)
		(width 0.254)
		(layer "B.Cu")
		(net "GND")
	)
	(segment
		(start 162.20694 -419.262306)
		(end 162.934142 -419.262306)
		(width 0.3302)
		(layer "B.Cu")
		(net "GND")
	)
	(segment
		(start 203.47813 -79.444342)
		(end 202.849734 -79.444342)
		(width 0.3556)
		(layer "B.Cu")
		(net "GND")
	)
	(segment
		(start 14.892782 -416.044634)
		(end 13.622782 -416.044634)
		(width 0.381)
		(layer "B.Cu")
		(net "GND")
	)
	(segment
		(start 237.236 -218.67495)
		(end 236.45495 -218.67495)
		(width 0.4572)
		(layer "B.Cu")
		(net "GND")
	)
	(segment
		(start 137.419842 -382.567942)
		(end 137.089388 -382.237488)
		(width 0.254)
		(layer "B.Cu")
		(net "GND")
	)
	(segment
		(start 116.116354 -415.510218)
		(end 115.364768 -415.510218)
		(width 0.4572)
		(layer "B.Cu")
		(net "GND")
	)
	(segment
		(start 235.031534 -51.663346)
		(end 235.485432 -51.209448)
		(width 0.3556)
		(layer "B.Cu")
		(net "GND")
	)
	(segment
		(start 174.11319 -427.92904)
		(end 174.11319 -427.293786)
		(width 0.4572)
		(layer "B.Cu")
		(net "GND")
	)
	(segment
		(start 72.825864 -10.86866)
		(end 72.825864 -10.16508)
		(width 0.381)
		(layer "B.Cu")
		(net "GND")
	)
	(segment
		(start 243.31295 -322.834)
		(end 242.57 -322.834)
		(width 0.4572)
		(layer "B.Cu")
		(net "GND")
	)
	(segment
		(start 9.271 -81.55305)
		(end 9.271 -82.169)
		(width 0.4572)
		(layer "B.Cu")
		(net "GND")
	)
	(segment
		(start 102.847648 -383.257806)
		(end 102.653338 -383.452116)
		(width 0.254)
		(layer "B.Cu")
		(net "GND")
	)
	(segment
		(start 24.92375 -358.202738)
		(end 24.77262 -358.202738)
		(width 0.4572)
		(layer "B.Cu")
		(net "GND")
	)
	(segment
		(start 235.244894 -329.173078)
		(end 235.961682 -329.173078)
		(width 0.381)
		(layer "B.Cu")
		(net "GND")
	)
	(segment
		(start 167.606472 -424.117262)
		(end 166.858442 -424.117262)
		(width 0.3048)
		(layer "B.Cu")
		(net "GND")
	)
	(segment
		(start 101.785928 -144.63141)
		(end 102.401878 -144.63141)
		(width 0.381)
		(layer "B.Cu")
		(net "GND")
	)
	(segment
		(start 101.239574 -387.768592)
		(end 100.21189 -387.768592)
		(width 0.3048)
		(layer "B.Cu")
		(net "GND")
	)
	(segment
		(start 233.013758 -225.3742)
		(end 233.075988 -225.43643)
		(width 0.4572)
		(layer "B.Cu")
		(net "GND")
	)
	(segment
		(start 210.711288 -75.313794)
		(end 212.216746 -75.313794)
		(width 0.3556)
		(layer "B.Cu")
		(net "GND")
	)
	(segment
		(start 163.963858 -114.542062)
		(end 162.85337 -115.65255)
		(width 0.4572)
		(layer "B.Cu")
		(net "GND")
	)
	(segment
		(start 236.22508 -48.104044)
		(end 235.492036 -48.104044)
		(width 0.3556)
		(layer "B.Cu")
		(net "GND")
	)
	(segment
		(start 214.6173 -332.74)
		(end 213.995 -332.74)
		(width 0.381)
		(layer "B.Cu")
		(net "GND")
	)
	(segment
		(start 123.83008 -246.269002)
		(end 123.994672 -246.10441)
		(width 0.254)
		(layer "B.Cu")
		(net "GND")
	)
	(segment
		(start 68.711826 -387.768592)
		(end 67.684142 -387.768592)
		(width 0.3048)
		(layer "B.Cu")
		(net "GND")
	)
	(segment
		(start 190.792862 -71.54545)
		(end 191.377316 -72.129904)
		(width 0.4572)
		(layer "B.Cu")
		(net "GND")
	)
	(segment
		(start 58.272426 -193.832226)
		(end 58.836814 -193.832226)
		(width 0.381)
		(layer "B.Cu")
		(net "GND")
	)
	(segment
		(start 214.6173 -330.708)
		(end 213.995 -330.708)
		(width 0.381)
		(layer "B.Cu")
		(net "GND")
	)
	(segment
		(start 425.050458 -390.67105)
		(end 425.10202 -390.619488)
		(width 0.254)
		(layer "B.Cu")
		(net "GND")
	)
	(segment
		(start 399.160238 -392.1252)
		(end 399.693638 -392.1252)
		(width 0.254)
		(layer "B.Cu")
		(net "GND")
	)
	(segment
		(start 286.749236 -428.26051)
		(end 286.749236 -428.9044)
		(width 0.4572)
		(layer "B.Cu")
		(net "GND")
	)
	(segment
		(start 296.29989 -361.269788)
		(end 297.015662 -360.554016)
		(width 0.4572)
		(layer "In2.Cu")
		(net "GND")
	)
	(segment
		(start 432.01336 -364.327948)
		(end 432.729132 -365.04372)
		(width 0.4572)
		(layer "In2.Cu")
		(net "GND")
	)
	(segment
		(start 327.235312 -351.21596)
		(end 327.951084 -351.931732)
		(width 0.4572)
		(layer "In2.Cu")
		(net "GND")
	)
	(segment
		(start 295.584118 -361.98556)
		(end 296.29989 -361.269788)
		(width 0.4572)
		(layer "In2.Cu")
		(net "GND")
	)
	(segment
		(start 432.01336 -364.327948)
		(end 432.729132 -363.612176)
		(width 0.4572)
		(layer "In2.Cu")
		(net "GND")
	)
	(segment
		(start 431.297588 -365.04372)
		(end 432.01336 -364.327948)
		(width 0.4572)
		(layer "In2.Cu")
		(net "GND")
	)
	(segment
		(start 327.235312 -352.647504)
		(end 327.951084 -351.931732)
		(width 0.4572)
		(layer "In2.Cu")
		(net "GND")
	)
	(segment
		(start 327.951084 -351.931732)
		(end 328.666856 -352.647504)
		(width 0.4572)
		(layer "In2.Cu")
		(net "GND")
	)
	(segment
		(start 335.411064 -351.931732)
		(end 336.126836 -352.647504)
		(width 0.4572)
		(layer "In2.Cu")
		(net "GND")
	)
	(segment
		(start 334.695292 -352.647504)
		(end 335.411064 -351.931732)
		(width 0.4572)
		(layer "In2.Cu")
		(net "GND")
	)
	(segment
		(start 335.411064 -351.931732)
		(end 336.126836 -351.21596)
		(width 0.4572)
		(layer "In2.Cu")
		(net "GND")
	)
	(segment
		(start 334.695292 -351.21596)
		(end 335.411064 -351.931732)
		(width 0.4572)
		(layer "In2.Cu")
		(net "GND")
	)
	(segment
		(start 296.29989 -361.269788)
		(end 297.015662 -361.98556)
		(width 0.4572)
		(layer "In2.Cu")
		(net "GND")
	)
	(segment
		(start 431.297588 -363.612176)
		(end 432.01336 -364.327948)
		(width 0.4572)
		(layer "In2.Cu")
		(net "GND")
	)
	(segment
		(start 327.951084 -351.931732)
		(end 328.666856 -351.21596)
		(width 0.4572)
		(layer "In2.Cu")
		(net "GND")
	)
	(segment
		(start 295.584118 -360.554016)
		(end 296.29989 -361.269788)
		(width 0.4572)
		(layer "In2.Cu")
		(net "GND")
	)
	(segment
		(start 295.584118 -361.98556)
		(end 296.29989 -361.269788)
		(width 0.4572)
		(layer "In4.Cu")
		(net "GND")
	)
	(segment
		(start 327.235312 -351.21596)
		(end 327.951084 -351.931732)
		(width 0.4572)
		(layer "In4.Cu")
		(net "GND")
	)
	(segment
		(start 334.695292 -351.21596)
		(end 335.411064 -351.931732)
		(width 0.4572)
		(layer "In4.Cu")
		(net "GND")
	)
	(segment
		(start 296.29989 -361.269788)
		(end 297.015662 -361.98556)
		(width 0.4572)
		(layer "In4.Cu")
		(net "GND")
	)
	(segment
		(start 335.411064 -351.931732)
		(end 336.126836 -351.21596)
		(width 0.4572)
		(layer "In4.Cu")
		(net "GND")
	)
	(segment
		(start 296.29989 -361.269788)
		(end 297.015662 -360.554016)
		(width 0.4572)
		(layer "In4.Cu")
		(net "GND")
	)
	(segment
		(start 295.584118 -360.554016)
		(end 296.29989 -361.269788)
		(width 0.4572)
		(layer "In4.Cu")
		(net "GND")
	)
	(segment
		(start 327.235312 -352.647504)
		(end 327.951084 -351.931732)
		(width 0.4572)
		(layer "In4.Cu")
		(net "GND")
	)
	(segment
		(start 327.951084 -351.931732)
		(end 328.666856 -352.647504)
		(width 0.4572)
		(layer "In4.Cu")
		(net "GND")
	)
	(segment
		(start 334.695292 -352.647504)
		(end 335.411064 -351.931732)
		(width 0.4572)
		(layer "In4.Cu")
		(net "GND")
	)
	(segment
		(start 335.411064 -351.931732)
		(end 336.126836 -352.647504)
		(width 0.4572)
		(layer "In4.Cu")
		(net "GND")
	)
	(segment
		(start 327.951084 -351.931732)
		(end 328.666856 -351.21596)
		(width 0.4572)
		(layer "In4.Cu")
		(net "GND")
	)
	(segment
		(start 295.584118 -361.98556)
		(end 296.29989 -361.269788)
		(width 0.4572)
		(layer "In6.Cu")
		(net "GND")
	)
	(segment
		(start 327.235312 -352.647504)
		(end 327.951084 -351.931732)
		(width 0.4572)
		(layer "In6.Cu")
		(net "GND")
	)
	(segment
		(start 327.235312 -351.21596)
		(end 327.951084 -351.931732)
		(width 0.4572)
		(layer "In6.Cu")
		(net "GND")
	)
	(segment
		(start 327.951084 -351.931732)
		(end 328.666856 -351.21596)
		(width 0.4572)
		(layer "In6.Cu")
		(net "GND")
	)
	(segment
		(start 334.695292 -352.647504)
		(end 335.411064 -351.931732)
		(width 0.4572)
		(layer "In6.Cu")
		(net "GND")
	)
	(segment
		(start 335.411064 -351.931732)
		(end 336.126836 -351.21596)
		(width 0.4572)
		(layer "In6.Cu")
		(net "GND")
	)
	(segment
		(start 335.411064 -351.931732)
		(end 336.126836 -352.647504)
		(width 0.4572)
		(layer "In6.Cu")
		(net "GND")
	)
	(segment
		(start 327.951084 -351.931732)
		(end 328.666856 -352.647504)
		(width 0.4572)
		(layer "In6.Cu")
		(net "GND")
	)
	(segment
		(start 296.29989 -361.269788)
		(end 297.015662 -360.554016)
		(width 0.4572)
		(layer "In6.Cu")
		(net "GND")
	)
	(segment
		(start 334.695292 -351.21596)
		(end 335.411064 -351.931732)
		(width 0.4572)
		(layer "In6.Cu")
		(net "GND")
	)
	(segment
		(start 295.584118 -360.554016)
		(end 296.29989 -361.269788)
		(width 0.4572)
		(layer "In6.Cu")
		(net "GND")
	)
	(segment
		(start 296.29989 -361.269788)
		(end 297.015662 -361.98556)
		(width 0.4572)
		(layer "In6.Cu")
		(net "GND")
	)
	(segment
		(start 327.951084 -351.931732)
		(end 328.720704 -352.701352)
		(width 0.508)
		(layer "In11.Cu")
		(net "GND")
	)
	(segment
		(start 295.53027 -362.039408)
		(end 296.29989 -361.269788)
		(width 0.508)
		(layer "In11.Cu")
		(net "GND")
	)
	(segment
		(start 304.436018 -410.596842)
		(end 303.5427 -411.49016)
		(width 0.254)
		(layer "In11.Cu")
		(net "GND")
	)
	(segment
		(start 296.29989 -361.269788)
		(end 297.06951 -362.039408)
		(width 0.508)
		(layer "In11.Cu")
		(net "GND")
	)
	(segment
		(start 334.641444 -352.701352)
		(end 335.411064 -351.931732)
		(width 0.508)
		(layer "In11.Cu")
		(net "GND")
	)
	(segment
		(start 296.29989 -361.269788)
		(end 297.06951 -360.500168)
		(width 0.508)
		(layer "In11.Cu")
		(net "GND")
	)
	(segment
		(start 335.411064 -351.931732)
		(end 336.180684 -352.701352)
		(width 0.508)
		(layer "In11.Cu")
		(net "GND")
	)
	(segment
		(start 327.181464 -351.162112)
		(end 327.951084 -351.931732)
		(width 0.508)
		(layer "In11.Cu")
		(net "GND")
	)
	(segment
		(start 295.53027 -360.500168)
		(end 296.29989 -361.269788)
		(width 0.508)
		(layer "In11.Cu")
		(net "GND")
	)
	(segment
		(start 327.951084 -351.931732)
		(end 328.720704 -351.162112)
		(width 0.508)
		(layer "In11.Cu")
		(net "GND")
	)
	(segment
		(start 304.436018 -409.623514)
		(end 304.436018 -410.596842)
		(width 0.254)
		(layer "In11.Cu")
		(net "GND")
	)
	(segment
		(start 335.411064 -351.931732)
		(end 336.180684 -351.162112)
		(width 0.508)
		(layer "In11.Cu")
		(net "GND")
	)
	(segment
		(start 327.181464 -352.701352)
		(end 327.951084 -351.931732)
		(width 0.508)
		(layer "In11.Cu")
		(net "GND")
	)
	(segment
		(start 334.641444 -351.162112)
		(end 335.411064 -351.931732)
		(width 0.508)
		(layer "In11.Cu")
		(net "GND")
	)
	(segment
		(start 296.29989 -361.269788)
		(end 297.015662 -361.98556)
		(width 0.4572)
		(layer "In13.Cu")
		(net "GND")
	)
	(segment
		(start 431.297588 -365.04372)
		(end 432.01336 -364.327948)
		(width 0.4572)
		(layer "In13.Cu")
		(net "GND")
	)
	(segment
		(start 295.584118 -360.554016)
		(end 296.29989 -361.269788)
		(width 0.4572)
		(layer "In13.Cu")
		(net "GND")
	)
	(segment
		(start 432.01336 -364.327948)
		(end 432.729132 -365.04372)
		(width 0.4572)
		(layer "In13.Cu")
		(net "GND")
	)
	(segment
		(start 431.297588 -363.612176)
		(end 432.01336 -364.327948)
		(width 0.4572)
		(layer "In13.Cu")
		(net "GND")
	)
	(segment
		(start 432.01336 -364.327948)
		(end 432.729132 -363.612176)
		(width 0.4572)
		(layer "In13.Cu")
		(net "GND")
	)
	(segment
		(start 296.29989 -361.269788)
		(end 297.015662 -360.554016)
		(width 0.4572)
		(layer "In13.Cu")
		(net "GND")
	)
	(segment
		(start 295.584118 -361.98556)
		(end 296.29989 -361.269788)
		(width 0.4572)
		(layer "In13.Cu")
		(net "GND")
	)
	(segment
		(start 139.222226 -388.77113)
		(end 139.222226 -389.064754)
		(width 0.254)
		(layer "In15.Cu")
		(net "GND")
	)
	(segment
		(start 432.01336 -364.327948)
		(end 432.729132 -365.04372)
		(width 0.4572)
		(layer "In15.Cu")
		(net "GND")
	)
	(segment
		(start 295.584118 -360.554016)
		(end 296.29989 -361.269788)
		(width 0.4572)
		(layer "In15.Cu")
		(net "GND")
	)
	(segment
		(start 138.85672 -389.43026)
		(end 138.30554 -389.43026)
		(width 0.254)
		(layer "In15.Cu")
		(net "GND")
	)
	(segment
		(start 296.29989 -361.269788)
		(end 297.015662 -361.98556)
		(width 0.4572)
		(layer "In15.Cu")
		(net "GND")
	)
	(segment
		(start 431.297588 -363.612176)
		(end 432.01336 -364.327948)
		(width 0.4572)
		(layer "In15.Cu")
		(net "GND")
	)
	(segment
		(start 139.222226 -389.064754)
		(end 138.85672 -389.43026)
		(width 0.254)
		(layer "In15.Cu")
		(net "GND")
	)
	(segment
		(start 432.01336 -364.327948)
		(end 432.729132 -363.612176)
		(width 0.4572)
		(layer "In15.Cu")
		(net "GND")
	)
	(segment
		(start 296.29989 -361.269788)
		(end 297.015662 -360.554016)
		(width 0.4572)
		(layer "In15.Cu")
		(net "GND")
	)
	(segment
		(start 431.297588 -365.04372)
		(end 432.01336 -364.327948)
		(width 0.4572)
		(layer "In15.Cu")
		(net "GND")
	)
	(segment
		(start 295.584118 -361.98556)
		(end 296.29989 -361.269788)
		(width 0.4572)
		(layer "In15.Cu")
		(net "GND")
	)
	(segment
		(start 122.587766 -236.650276)
		(end 123.054618 -236.384338)
		(width 0.12954)
		(layer "F.Cu")
		(net "GMI_CPU1_G3_CPU0_G1_TX_DP<9>")
	)
	(segment
		(start 348.907862 -236.650022)
		(end 348.44101 -236.384084)
		(width 0.12954)
		(layer "F.Cu")
		(net "GMI_CPU1_G3_CPU0_G1_TX_DP<9>")
	)
	(segment
		(start 150.598886 -193.717164)
		(end 146.364452 -197.188836)
		(width 0.14224)
		(layer "In11.Cu")
		(net "GMI_CPU1_G3_CPU0_G1_TX_DP<9>")
	)
	(segment
		(start 350.038924 -234.276138)
		(end 350.041718 -234.274614)
		(width 0.1143)
		(layer "In11.Cu")
		(net "GMI_CPU1_G3_CPU0_G1_TX_DP<9>")
	)
	(segment
		(start 151.122126 -193.46545)
		(end 150.791926 -193.736214)
		(width 0.14224)
		(layer "In11.Cu")
		(net "GMI_CPU1_G3_CPU0_G1_TX_DP<9>")
	)
	(segment
		(start 121.454164 -234.274868)
		(end 121.456958 -234.276392)
		(width 0.1143)
		(layer "In11.Cu")
		(net "GMI_CPU1_G3_CPU0_G1_TX_DP<9>")
	)
	(segment
		(start 121.45772 -232.011728)
		(end 121.456958 -232.012236)
		(width 0.1143)
		(layer "In11.Cu")
		(net "GMI_CPU1_G3_CPU0_G1_TX_DP<9>")
	)
	(segment
		(start 153.408634 -191.590422)
		(end 153.215594 -191.571372)
		(width 0.14224)
		(layer "In11.Cu")
		(net "GMI_CPU1_G3_CPU0_G1_TX_DP<9>")
	)
	(segment
		(start 153.215594 -191.571372)
		(end 152.885648 -191.841882)
		(width 0.14224)
		(layer "In11.Cu")
		(net "GMI_CPU1_G3_CPU0_G1_TX_DP<9>")
	)
	(segment
		(start 120.987566 -224.721928)
		(end 120.957086 -224.739708)
		(width 0.1143)
		(layer "In11.Cu")
		(net "GMI_CPU1_G3_CPU0_G1_TX_DP<9>")
	)
	(segment
		(start 350.695768 -221.376494)
		(end 350.725232 -221.34703)
		(width 0.1143)
		(layer "In11.Cu")
		(net "GMI_CPU1_G3_CPU0_G1_TX_DP<9>")
	)
	(segment
		(start 121.026682 -224.699068)
		(end 120.987566 -224.721928)
		(width 0.1143)
		(layer "In11.Cu")
		(net "GMI_CPU1_G3_CPU0_G1_TX_DP<9>")
	)
	(segment
		(start 121.45772 -234.2769)
		(end 121.489216 -234.295188)
		(width 0.1143)
		(layer "In11.Cu")
		(net "GMI_CPU1_G3_CPU0_G1_TX_DP<9>")
	)
	(segment
		(start 120.957086 -223.729296)
		(end 120.987566 -223.747076)
		(width 0.1143)
		(layer "In11.Cu")
		(net "GMI_CPU1_G3_CPU0_G1_TX_DP<9>")
	)
	(segment
		(start 120.987566 -233.466894)
		(end 121.026682 -233.489754)
		(width 0.1143)
		(layer "In11.Cu")
		(net "GMI_CPU1_G3_CPU0_G1_TX_DP<9>")
	)
	(segment
		(start 350.538796 -227.979478)
		(end 350.4692 -227.938838)
		(width 0.1143)
		(layer "In11.Cu")
		(net "GMI_CPU1_G3_CPU0_G1_TX_DP<9>")
	)
	(segment
		(start 155.502356 -189.69609)
		(end 155.483306 -189.88913)
		(width 0.14224)
		(layer "In11.Cu")
		(net "GMI_CPU1_G3_CPU0_G1_TX_DP<9>")
	)
	(segment
		(start 121.026682 -226.31908)
		(end 120.987566 -226.34194)
		(width 0.1143)
		(layer "In11.Cu")
		(net "GMI_CPU1_G3_CPU0_G1_TX_DP<9>")
	)
	(segment
		(start 121.46026 -232.010204)
		(end 121.458736 -232.01122)
		(width 0.1143)
		(layer "In11.Cu")
		(net "GMI_CPU1_G3_CPU0_G1_TX_DP<9>")
	)
	(segment
		(start 121.89714 -235.069126)
		(end 121.966736 -235.109766)
		(width 0.1143)
		(layer "In11.Cu")
		(net "GMI_CPU1_G3_CPU0_G1_TX_DP<9>")
	)
	(segment
		(start 151.664162 -193.02095)
		(end 151.471122 -193.0019)
		(width 0.14224)
		(layer "In11.Cu")
		(net "GMI_CPU1_G3_CPU0_G1_TX_DP<9>")
	)
	(segment
		(start 155.832302 -189.42558)
		(end 155.502356 -189.69609)
		(width 0.14224)
		(layer "In11.Cu")
		(net "GMI_CPU1_G3_CPU0_G1_TX_DP<9>")
	)
	(segment
		(start 120.957086 -233.449114)
		(end 120.987566 -233.466894)
		(width 0.1143)
		(layer "In11.Cu")
		(net "GMI_CPU1_G3_CPU0_G1_TX_DP<9>")
	)
	(segment
		(start 350.035368 -232.00995)
		(end 350.033844 -232.008934)
		(width 0.1143)
		(layer "In11.Cu")
		(net "GMI_CPU1_G3_CPU0_G1_TX_DP<9>")
	)
	(segment
		(start 156.374592 -188.980826)
		(end 156.355542 -189.173866)
		(width 0.14224)
		(layer "In11.Cu")
		(net "GMI_CPU1_G3_CPU0_G1_TX_DP<9>")
	)
	(segment
		(start 350.005904 -234.295442)
		(end 350.006666 -234.294934)
		(width 0.1143)
		(layer "In11.Cu")
		(net "GMI_CPU1_G3_CPU0_G1_TX_DP<9>")
	)
	(segment
		(start 121.462546 -232.008934)
		(end 121.461276 -232.009696)
		(width 0.1143)
		(layer "In11.Cu")
		(net "GMI_CPU1_G3_CPU0_G1_TX_DP<9>")
	)
	(segment
		(start 121.45772 -231.036876)
		(end 121.496836 -231.059736)
		(width 0.1143)
		(layer "In11.Cu")
		(net "GMI_CPU1_G3_CPU0_G1_TX_DP<9>")
	)
	(segment
		(start 120.957086 -225.349308)
		(end 120.987566 -225.367088)
		(width 0.1143)
		(layer "In11.Cu")
		(net "GMI_CPU1_G3_CPU0_G1_TX_DP<9>")
	)
	(segment
		(start 166.678102 -182.741316)
		(end 161.891218 -184.45734)
		(width 0.14224)
		(layer "In11.Cu")
		(net "GMI_CPU1_G3_CPU0_G1_TX_DP<9>")
	)
	(segment
		(start 350.538796 -226.359466)
		(end 350.4692 -226.318826)
		(width 0.1143)
		(layer "In11.Cu")
		(net "GMI_CPU1_G3_CPU0_G1_TX_DP<9>")
	)
	(segment
		(start 157.246828 -188.265562)
		(end 157.227778 -188.458602)
		(width 0.14224)
		(layer "In11.Cu")
		(net "GMI_CPU1_G3_CPU0_G1_TX_DP<9>")
	)
	(segment
		(start 153.757884 -191.126618)
		(end 153.738834 -191.319658)
		(width 0.14224)
		(layer "In11.Cu")
		(net "GMI_CPU1_G3_CPU0_G1_TX_DP<9>")
	)
	(segment
		(start 121.451116 -234.27309)
		(end 121.451878 -234.273598)
		(width 0.1143)
		(layer "In11.Cu")
		(net "GMI_CPU1_G3_CPU0_G1_TX_DP<9>")
	)
	(segment
		(start 120.987566 -226.9871)
		(end 121.026682 -227.00996)
		(width 0.1143)
		(layer "In11.Cu")
		(net "GMI_CPU1_G3_CPU0_G1_TX_DP<9>")
	)
	(segment
		(start 154.63012 -190.411354)
		(end 154.61107 -190.604394)
		(width 0.14224)
		(layer "In11.Cu")
		(net "GMI_CPU1_G3_CPU0_G1_TX_DP<9>")
	)
	(segment
		(start 121.451878 -234.273598)
		(end 121.453402 -234.27436)
		(width 0.1143)
		(layer "In11.Cu")
		(net "GMI_CPU1_G3_CPU0_G1_TX_DP<9>")
	)
	(segment
		(start 154.08783 -190.856108)
		(end 153.757884 -191.126618)
		(width 0.14224)
		(layer "In11.Cu")
		(net "GMI_CPU1_G3_CPU0_G1_TX_DP<9>")
	)
	(segment
		(start 350.4692 -228.629718)
		(end 350.538796 -228.589078)
		(width 0.1143)
		(layer "In11.Cu")
		(net "GMI_CPU1_G3_CPU0_G1_TX_DP<9>")
	)
	(segment
		(start 350.4692 -233.4895)
		(end 350.538796 -233.44886)
		(width 0.1143)
		(layer "In11.Cu")
		(net "GMI_CPU1_G3_CPU0_G1_TX_DP<9>")
	)
	(segment
		(start 302.891952 -183.534812)
		(end 166.678102 -182.741316)
		(width 0.14224)
		(layer "In11.Cu")
		(net "GMI_CPU1_G3_CPU0_G1_TX_DP<9>")
	)
	(segment
		(start 350.044766 -232.015284)
		(end 350.044004 -232.014776)
		(width 0.1143)
		(layer "In11.Cu")
		(net "GMI_CPU1_G3_CPU0_G1_TX_DP<9>")
	)
	(segment
		(start 122.756676 -236.384338)
		(end 123.054618 -236.384338)
		(width 0.1143)
		(layer "In11.Cu")
		(net "GMI_CPU1_G3_CPU0_G1_TX_DP<9>")
	)
	(segment
		(start 121.463562 -232.008426)
		(end 121.462546 -232.008934)
		(width 0.1143)
		(layer "In11.Cu")
		(net "GMI_CPU1_G3_CPU0_G1_TX_DP<9>")
	)
	(segment
		(start 350.679512 -221.071694)
		(end 350.679512 -219.540836)
		(width 0.14224)
		(layer "In11.Cu")
		(net "GMI_CPU1_G3_CPU0_G1_TX_DP<9>")
	)
	(segment
		(start 350.041718 -232.013506)
		(end 350.038924 -232.011982)
		(width 0.1143)
		(layer "In11.Cu")
		(net "GMI_CPU1_G3_CPU0_G1_TX_DP<9>")
	)
	(segment
		(start 121.026682 -223.079056)
		(end 120.987566 -223.101916)
		(width 0.1143)
		(layer "In11.Cu")
		(net "GMI_CPU1_G3_CPU0_G1_TX_DP<9>")
	)
	(segment
		(start 120.987566 -223.747076)
		(end 121.026682 -223.769936)
		(width 0.1143)
		(layer "In11.Cu")
		(net "GMI_CPU1_G3_CPU0_G1_TX_DP<9>")
	)
	(segment
		(start 146.364452 -197.188836)
		(end 144.995138 -197.603364)
		(width 0.14224)
		(layer "In11.Cu")
		(net "GMI_CPU1_G3_CPU0_G1_TX_DP<9>")
	)
	(segment
		(start 350.679512 -219.540836)
		(end 348.2848 -215.50757)
		(width 0.14224)
		(layer "In11.Cu")
		(net "GMI_CPU1_G3_CPU0_G1_TX_DP<9>")
	)
	(segment
		(start 120.77065 -221.347284)
		(end 120.800114 -221.376748)
		(width 0.1143)
		(layer "In11.Cu")
		(net "GMI_CPU1_G3_CPU0_G1_TX_DP<9>")
	)
	(segment
		(start 350.038162 -234.276646)
		(end 350.038924 -234.276138)
		(width 0.1143)
		(layer "In11.Cu")
		(net "GMI_CPU1_G3_CPU0_G1_TX_DP<9>")
	)
	(segment
		(start 120.81637 -221.083378)
		(end 120.77065 -221.129098)
		(width 0.1143)
		(layer "In11.Cu")
		(net "GMI_CPU1_G3_CPU0_G1_TX_DP<9>")
	)
	(segment
		(start 348.44101 -236.384084)
		(end 348.739206 -236.384084)
		(width 0.1143)
		(layer "In11.Cu")
		(net "GMI_CPU1_G3_CPU0_G1_TX_DP<9>")
	)
	(segment
		(start 121.469404 -232.005124)
		(end 121.46534 -232.00741)
		(width 0.1143)
		(layer "In11.Cu")
		(net "GMI_CPU1_G3_CPU0_G1_TX_DP<9>")
	)
	(segment
		(start 150.791926 -193.736214)
		(end 150.598886 -193.717164)
		(width 0.14224)
		(layer "In11.Cu")
		(net "GMI_CPU1_G3_CPU0_G1_TX_DP<9>")
	)
	(segment
		(start 153.738834 -191.319658)
		(end 153.408634 -191.590422)
		(width 0.14224)
		(layer "In11.Cu")
		(net "GMI_CPU1_G3_CPU0_G1_TX_DP<9>")
	)
	(segment
		(start 120.987566 -229.581964)
		(end 120.955054 -229.60076)
		(width 0.1143)
		(layer "In11.Cu")
		(net "GMI_CPU1_G3_CPU0_G1_TX_DP<9>")
	)
	(segment
		(start 156.025342 -189.44463)
		(end 155.832302 -189.42558)
		(width 0.14224)
		(layer "In11.Cu")
		(net "GMI_CPU1_G3_CPU0_G1_TX_DP<9>")
	)
	(segment
		(start 350.04248 -234.274106)
		(end 350.044004 -234.273344)
		(width 0.1143)
		(layer "In11.Cu")
		(net "GMI_CPU1_G3_CPU0_G1_TX_DP<9>")
	)
	(segment
		(start 350.04248 -232.014014)
		(end 350.041718 -232.013506)
		(width 0.1143)
		(layer "In11.Cu")
		(net "GMI_CPU1_G3_CPU0_G1_TX_DP<9>")
	)
	(segment
		(start 349.529146 -235.109512)
		(end 349.598742 -235.068872)
		(width 0.1143)
		(layer "In11.Cu")
		(net "GMI_CPU1_G3_CPU0_G1_TX_DP<9>")
	)
	(segment
		(start 350.695768 -221.80423)
		(end 350.695768 -221.376494)
		(width 0.1143)
		(layer "In11.Cu")
		(net "GMI_CPU1_G3_CPU0_G1_TX_DP<9>")
	)
	(segment
		(start 350.4692 -227.009706)
		(end 350.538796 -226.969066)
		(width 0.1143)
		(layer "In11.Cu")
		(net "GMI_CPU1_G3_CPU0_G1_TX_DP<9>")
	)
	(segment
		(start 348.2848 -215.50757)
		(end 313.82716 -187.253372)
		(width 0.14224)
		(layer "In11.Cu")
		(net "GMI_CPU1_G3_CPU0_G1_TX_DP<9>")
	)
	(segment
		(start 350.032828 -232.008426)
		(end 350.030034 -232.006902)
		(width 0.1143)
		(layer "In11.Cu")
		(net "GMI_CPU1_G3_CPU0_G1_TX_DP<9>")
	)
	(segment
		(start 122.39752 -235.89742)
		(end 122.401584 -235.899706)
		(width 0.1143)
		(layer "In11.Cu")
		(net "GMI_CPU1_G3_CPU0_G1_TX_DP<9>")
	)
	(segment
		(start 156.704538 -188.710316)
		(end 156.374592 -188.980826)
		(width 0.14224)
		(layer "In11.Cu")
		(net "GMI_CPU1_G3_CPU0_G1_TX_DP<9>")
	)
	(segment
		(start 155.153106 -190.159894)
		(end 154.960066 -190.140844)
		(width 0.14224)
		(layer "In11.Cu")
		(net "GMI_CPU1_G3_CPU0_G1_TX_DP<9>")
	)
	(segment
		(start 151.471122 -193.0019)
		(end 151.141176 -193.27241)
		(width 0.14224)
		(layer "In11.Cu")
		(net "GMI_CPU1_G3_CPU0_G1_TX_DP<9>")
	)
	(segment
		(start 120.987566 -227.961952)
		(end 120.957086 -227.979732)
		(width 0.1143)
		(layer "In11.Cu")
		(net "GMI_CPU1_G3_CPU0_G1_TX_DP<9>")
	)
	(segment
		(start 152.536398 -192.305686)
		(end 152.343358 -192.286636)
		(width 0.14224)
		(layer "In11.Cu")
		(net "GMI_CPU1_G3_CPU0_G1_TX_DP<9>")
	)
	(segment
		(start 155.483306 -189.88913)
		(end 155.153106 -190.159894)
		(width 0.14224)
		(layer "In11.Cu")
		(net "GMI_CPU1_G3_CPU0_G1_TX_DP<9>")
	)
	(segment
		(start 120.987566 -226.34194)
		(end 120.957086 -226.35972)
		(width 0.1143)
		(layer "In11.Cu")
		(net "GMI_CPU1_G3_CPU0_G1_TX_DP<9>")
	)
	(segment
		(start 123.266708 -215.41994)
		(end 120.81637 -219.620338)
		(width 0.14224)
		(layer "In11.Cu")
		(net "GMI_CPU1_G3_CPU0_G1_TX_DP<9>")
	)
	(segment
		(start 121.424192 -231.017318)
		(end 121.45772 -231.036876)
		(width 0.1143)
		(layer "In11.Cu")
		(net "GMI_CPU1_G3_CPU0_G1_TX_DP<9>")
	)
	(segment
		(start 121.470166 -232.004616)
		(end 121.469404 -232.005124)
		(width 0.1143)
		(layer "In11.Cu")
		(net "GMI_CPU1_G3_CPU0_G1_TX_DP<9>")
	)
	(segment
		(start 350.508316 -229.58171)
		(end 350.4692 -229.55885)
		(width 0.1143)
		(layer "In11.Cu")
		(net "GMI_CPU1_G3_CPU0_G1_TX_DP<9>")
	)
	(segment
		(start 121.42597 -234.258612)
		(end 121.4501 -234.272582)
		(width 0.1143)
		(layer "In11.Cu")
		(net "GMI_CPU1_G3_CPU0_G1_TX_DP<9>")
	)
	(segment
		(start 122.673872 -236.301534)
		(end 122.756676 -236.384338)
		(width 0.1143)
		(layer "In11.Cu")
		(net "GMI_CPU1_G3_CPU0_G1_TX_DP<9>")
	)
	(segment
		(start 121.456958 -234.276392)
		(end 121.45772 -234.2769)
		(width 0.1143)
		(layer "In11.Cu")
		(net "GMI_CPU1_G3_CPU0_G1_TX_DP<9>")
	)
	(segment
		(start 350.044766 -234.272836)
		(end 350.069912 -234.258358)
		(width 0.1143)
		(layer "In11.Cu")
		(net "GMI_CPU1_G3_CPU0_G1_TX_DP<9>")
	)
	(segment
		(start 156.355542 -189.173866)
		(end 156.025342 -189.44463)
		(width 0.14224)
		(layer "In11.Cu")
		(net "GMI_CPU1_G3_CPU0_G1_TX_DP<9>")
	)
	(segment
		(start 120.77065 -221.129098)
		(end 120.77065 -221.347284)
		(width 0.1143)
		(layer "In11.Cu")
		(net "GMI_CPU1_G3_CPU0_G1_TX_DP<9>")
	)
	(segment
		(start 313.82716 -187.253372)
		(end 308.012084 -183.961532)
		(width 0.14224)
		(layer "In11.Cu")
		(net "GMI_CPU1_G3_CPU0_G1_TX_DP<9>")
	)
	(segment
		(start 121.46534 -232.00741)
		(end 121.463562 -232.008426)
		(width 0.1143)
		(layer "In11.Cu")
		(net "GMI_CPU1_G3_CPU0_G1_TX_DP<9>")
	)
	(segment
		(start 350.038162 -232.011474)
		(end 350.037146 -232.010966)
		(width 0.1143)
		(layer "In11.Cu")
		(net "GMI_CPU1_G3_CPU0_G1_TX_DP<9>")
	)
	(segment
		(start 306.818538 -183.534812)
		(end 302.891952 -183.534812)
		(width 0.14224)
		(layer "In11.Cu")
		(net "GMI_CPU1_G3_CPU0_G1_TX_DP<9>")
	)
	(segment
		(start 350.4692 -222.14967)
		(end 350.538796 -222.10903)
		(width 0.1143)
		(layer "In11.Cu")
		(net "GMI_CPU1_G3_CPU0_G1_TX_DP<9>")
	)
	(segment
		(start 349.999046 -231.059482)
		(end 350.07169 -231.017064)
		(width 0.1143)
		(layer "In11.Cu")
		(net "GMI_CPU1_G3_CPU0_G1_TX_DP<9>")
	)
	(segment
		(start 157.227778 -188.458602)
		(end 156.897578 -188.729366)
		(width 0.14224)
		(layer "In11.Cu")
		(net "GMI_CPU1_G3_CPU0_G1_TX_DP<9>")
	)
	(segment
		(start 350.538796 -232.83926)
		(end 350.4692 -232.79862)
		(width 0.1143)
		(layer "In11.Cu")
		(net "GMI_CPU1_G3_CPU0_G1_TX_DP<9>")
	)
	(segment
		(start 121.458736 -232.01122)
		(end 121.45772 -232.011728)
		(width 0.1143)
		(layer "In11.Cu")
		(net "GMI_CPU1_G3_CPU0_G1_TX_DP<9>")
	)
	(segment
		(start 154.61107 -190.604394)
		(end 154.28087 -190.875158)
		(width 0.14224)
		(layer "In11.Cu")
		(net "GMI_CPU1_G3_CPU0_G1_TX_DP<9>")
	)
	(segment
		(start 144.995138 -197.603364)
		(end 123.266708 -215.41994)
		(width 0.14224)
		(layer "In11.Cu")
		(net "GMI_CPU1_G3_CPU0_G1_TX_DP<9>")
	)
	(segment
		(start 154.960066 -190.140844)
		(end 154.63012 -190.411354)
		(width 0.14224)
		(layer "In11.Cu")
		(net "GMI_CPU1_G3_CPU0_G1_TX_DP<9>")
	)
	(segment
		(start 349.094298 -235.899452)
		(end 349.098362 -235.897166)
		(width 0.1143)
		(layer "In11.Cu")
		(net "GMI_CPU1_G3_CPU0_G1_TX_DP<9>")
	)
	(segment
		(start 161.891218 -184.45734)
		(end 157.246828 -188.265562)
		(width 0.14224)
		(layer "In11.Cu")
		(net "GMI_CPU1_G3_CPU0_G1_TX_DP<9>")
	)
	(segment
		(start 350.041718 -234.274614)
		(end 350.04248 -234.274106)
		(width 0.1143)
		(layer "In11.Cu")
		(net "GMI_CPU1_G3_CPU0_G1_TX_DP<9>")
	)
	(segment
		(start 121.026682 -227.939092)
		(end 120.987566 -227.961952)
		(width 0.1143)
		(layer "In11.Cu")
		(net "GMI_CPU1_G3_CPU0_G1_TX_DP<9>")
	)
	(segment
		(start 121.456958 -232.012236)
		(end 121.42597 -232.030016)
		(width 0.1143)
		(layer "In11.Cu")
		(net "GMI_CPU1_G3_CPU0_G1_TX_DP<9>")
	)
	(segment
		(start 121.489216 -234.295188)
		(end 121.489978 -234.295696)
		(width 0.1143)
		(layer "In11.Cu")
		(net "GMI_CPU1_G3_CPU0_G1_TX_DP<9>")
	)
	(segment
		(start 121.4501 -234.272582)
		(end 121.451116 -234.27309)
		(width 0.1143)
		(layer "In11.Cu")
		(net "GMI_CPU1_G3_CPU0_G1_TX_DP<9>")
	)
	(segment
		(start 350.037146 -232.010966)
		(end 350.035368 -232.00995)
		(width 0.1143)
		(layer "In11.Cu")
		(net "GMI_CPU1_G3_CPU0_G1_TX_DP<9>")
	)
	(segment
		(start 350.538796 -224.739454)
		(end 350.4692 -224.698814)
		(width 0.1143)
		(layer "In11.Cu")
		(net "GMI_CPU1_G3_CPU0_G1_TX_DP<9>")
	)
	(segment
		(start 350.006666 -234.294934)
		(end 350.038162 -234.276646)
		(width 0.1143)
		(layer "In11.Cu")
		(net "GMI_CPU1_G3_CPU0_G1_TX_DP<9>")
	)
	(segment
		(start 121.489978 -234.295696)
		(end 121.496836 -234.29976)
		(width 0.1143)
		(layer "In11.Cu")
		(net "GMI_CPU1_G3_CPU0_G1_TX_DP<9>")
	)
	(segment
		(start 349.098362 -235.897166)
		(end 349.099378 -235.896658)
		(width 0.1143)
		(layer "In11.Cu")
		(net "GMI_CPU1_G3_CPU0_G1_TX_DP<9>")
	)
	(segment
		(start 121.496836 -231.988868)
		(end 121.470166 -232.004616)
		(width 0.1143)
		(layer "In11.Cu")
		(net "GMI_CPU1_G3_CPU0_G1_TX_DP<9>")
	)
	(segment
		(start 350.4692 -225.389694)
		(end 350.538796 -225.349054)
		(width 0.1143)
		(layer "In11.Cu")
		(net "GMI_CPU1_G3_CPU0_G1_TX_DP<9>")
	)
	(segment
		(start 350.069912 -232.029762)
		(end 350.044766 -232.015284)
		(width 0.1143)
		(layer "In11.Cu")
		(net "GMI_CPU1_G3_CPU0_G1_TX_DP<9>")
	)
	(segment
		(start 121.026682 -229.559104)
		(end 120.987566 -229.581964)
		(width 0.1143)
		(layer "In11.Cu")
		(net "GMI_CPU1_G3_CPU0_G1_TX_DP<9>")
	)
	(segment
		(start 120.81637 -221.071948)
		(end 120.81637 -221.083378)
		(width 0.1143)
		(layer "In11.Cu")
		(net "GMI_CPU1_G3_CPU0_G1_TX_DP<9>")
	)
	(segment
		(start 120.957086 -222.109284)
		(end 120.987566 -222.127064)
		(width 0.1143)
		(layer "In11.Cu")
		(net "GMI_CPU1_G3_CPU0_G1_TX_DP<9>")
	)
	(segment
		(start 152.866598 -192.034922)
		(end 152.536398 -192.305686)
		(width 0.14224)
		(layer "In11.Cu")
		(net "GMI_CPU1_G3_CPU0_G1_TX_DP<9>")
	)
	(segment
		(start 120.987566 -228.607112)
		(end 121.026682 -228.629972)
		(width 0.1143)
		(layer "In11.Cu")
		(net "GMI_CPU1_G3_CPU0_G1_TX_DP<9>")
	)
	(segment
		(start 151.994362 -192.750186)
		(end 151.664162 -193.02095)
		(width 0.14224)
		(layer "In11.Cu")
		(net "GMI_CPU1_G3_CPU0_G1_TX_DP<9>")
	)
	(segment
		(start 120.957086 -230.20909)
		(end 121.024142 -230.248206)
		(width 0.1143)
		(layer "In11.Cu")
		(net "GMI_CPU1_G3_CPU0_G1_TX_DP<9>")
	)
	(segment
		(start 120.957086 -228.589332)
		(end 120.987566 -228.607112)
		(width 0.1143)
		(layer "In11.Cu")
		(net "GMI_CPU1_G3_CPU0_G1_TX_DP<9>")
	)
	(segment
		(start 350.030034 -232.006902)
		(end 349.999046 -231.988614)
		(width 0.1143)
		(layer "In11.Cu")
		(net "GMI_CPU1_G3_CPU0_G1_TX_DP<9>")
	)
	(segment
		(start 348.739206 -236.384084)
		(end 348.82201 -236.30128)
		(width 0.1143)
		(layer "In11.Cu")
		(net "GMI_CPU1_G3_CPU0_G1_TX_DP<9>")
	)
	(segment
		(start 350.038924 -232.011982)
		(end 350.038162 -232.011474)
		(width 0.1143)
		(layer "In11.Cu")
		(net "GMI_CPU1_G3_CPU0_G1_TX_DP<9>")
	)
	(segment
		(start 350.679512 -221.083124)
		(end 350.679512 -221.071694)
		(width 0.1143)
		(layer "In11.Cu")
		(net "GMI_CPU1_G3_CPU0_G1_TX_DP<9>")
	)
	(segment
		(start 120.800114 -221.376748)
		(end 120.800114 -221.804484)
		(width 0.1143)
		(layer "In11.Cu")
		(net "GMI_CPU1_G3_CPU0_G1_TX_DP<9>")
	)
	(segment
		(start 151.141176 -193.27241)
		(end 151.122126 -193.46545)
		(width 0.14224)
		(layer "In11.Cu")
		(net "GMI_CPU1_G3_CPU0_G1_TX_DP<9>")
	)
	(segment
		(start 350.033844 -232.008934)
		(end 350.032828 -232.008426)
		(width 0.1143)
		(layer "In11.Cu")
		(net "GMI_CPU1_G3_CPU0_G1_TX_DP<9>")
	)
	(segment
		(start 350.4692 -223.769682)
		(end 350.538796 -223.729042)
		(width 0.1143)
		(layer "In11.Cu")
		(net "GMI_CPU1_G3_CPU0_G1_TX_DP<9>")
	)
	(segment
		(start 120.987566 -232.821734)
		(end 120.957086 -232.839514)
		(width 0.1143)
		(layer "In11.Cu")
		(net "GMI_CPU1_G3_CPU0_G1_TX_DP<9>")
	)
	(segment
		(start 350.47174 -230.247952)
		(end 350.538796 -230.208836)
		(width 0.1143)
		(layer "In11.Cu")
		(net "GMI_CPU1_G3_CPU0_G1_TX_DP<9>")
	)
	(segment
		(start 120.987566 -222.127064)
		(end 121.026682 -222.149924)
		(width 0.1143)
		(layer "In11.Cu")
		(net "GMI_CPU1_G3_CPU0_G1_TX_DP<9>")
	)
	(segment
		(start 152.885648 -191.841882)
		(end 152.866598 -192.034922)
		(width 0.14224)
		(layer "In11.Cu")
		(net "GMI_CPU1_G3_CPU0_G1_TX_DP<9>")
	)
	(segment
		(start 152.013412 -192.557146)
		(end 151.994362 -192.750186)
		(width 0.14224)
		(layer "In11.Cu")
		(net "GMI_CPU1_G3_CPU0_G1_TX_DP<9>")
	)
	(segment
		(start 120.987566 -223.101916)
		(end 120.957086 -223.119696)
		(width 0.1143)
		(layer "In11.Cu")
		(net "GMI_CPU1_G3_CPU0_G1_TX_DP<9>")
	)
	(segment
		(start 154.28087 -190.875158)
		(end 154.08783 -190.856108)
		(width 0.14224)
		(layer "In11.Cu")
		(net "GMI_CPU1_G3_CPU0_G1_TX_DP<9>")
	)
	(segment
		(start 121.461276 -232.009696)
		(end 121.46026 -232.010204)
		(width 0.1143)
		(layer "In11.Cu")
		(net "GMI_CPU1_G3_CPU0_G1_TX_DP<9>")
	)
	(segment
		(start 120.987566 -225.367088)
		(end 121.026682 -225.389948)
		(width 0.1143)
		(layer "In11.Cu")
		(net "GMI_CPU1_G3_CPU0_G1_TX_DP<9>")
	)
	(segment
		(start 308.012084 -183.961532)
		(end 306.818538 -183.534812)
		(width 0.14224)
		(layer "In11.Cu")
		(net "GMI_CPU1_G3_CPU0_G1_TX_DP<9>")
	)
	(segment
		(start 121.026682 -232.798874)
		(end 120.987566 -232.821734)
		(width 0.1143)
		(layer "In11.Cu")
		(net "GMI_CPU1_G3_CPU0_G1_TX_DP<9>")
	)
	(segment
		(start 120.957086 -226.96932)
		(end 120.987566 -226.9871)
		(width 0.1143)
		(layer "In11.Cu")
		(net "GMI_CPU1_G3_CPU0_G1_TX_DP<9>")
	)
	(segment
		(start 156.897578 -188.729366)
		(end 156.704538 -188.710316)
		(width 0.14224)
		(layer "In11.Cu")
		(net "GMI_CPU1_G3_CPU0_G1_TX_DP<9>")
	)
	(segment
		(start 350.044004 -232.014776)
		(end 350.04248 -232.014014)
		(width 0.1143)
		(layer "In11.Cu")
		(net "GMI_CPU1_G3_CPU0_G1_TX_DP<9>")
	)
	(segment
		(start 152.343358 -192.286636)
		(end 152.013412 -192.557146)
		(width 0.14224)
		(layer "In11.Cu")
		(net "GMI_CPU1_G3_CPU0_G1_TX_DP<9>")
	)
	(segment
		(start 350.538796 -223.119442)
		(end 350.4692 -223.078802)
		(width 0.1143)
		(layer "In11.Cu")
		(net "GMI_CPU1_G3_CPU0_G1_TX_DP<9>")
	)
	(segment
		(start 120.81637 -219.620338)
		(end 120.81637 -221.071948)
		(width 0.14224)
		(layer "In11.Cu")
		(net "GMI_CPU1_G3_CPU0_G1_TX_DP<9>")
	)
	(segment
		(start 350.540828 -229.600506)
		(end 350.508316 -229.58171)
		(width 0.1143)
		(layer "In11.Cu")
		(net "GMI_CPU1_G3_CPU0_G1_TX_DP<9>")
	)
	(segment
		(start 121.453402 -234.27436)
		(end 121.454164 -234.274868)
		(width 0.1143)
		(layer "In11.Cu")
		(net "GMI_CPU1_G3_CPU0_G1_TX_DP<9>")
	)
	(segment
		(start 350.725232 -221.34703)
		(end 350.725232 -221.128844)
		(width 0.1143)
		(layer "In11.Cu")
		(net "GMI_CPU1_G3_CPU0_G1_TX_DP<9>")
	)
	(segment
		(start 350.044004 -234.273344)
		(end 350.044766 -234.272836)
		(width 0.1143)
		(layer "In11.Cu")
		(net "GMI_CPU1_G3_CPU0_G1_TX_DP<9>")
	)
	(segment
		(start 350.725232 -221.128844)
		(end 350.679512 -221.083124)
		(width 0.1143)
		(layer "In11.Cu")
		(net "GMI_CPU1_G3_CPU0_G1_TX_DP<9>")
	)
	(segment
		(start 122.396504 -235.896912)
		(end 122.39752 -235.89742)
		(width 0.1143)
		(layer "In11.Cu")
		(net "GMI_CPU1_G3_CPU0_G1_TX_DP<9>")
	)
	(segment
		(start 349.999046 -234.299506)
		(end 350.005904 -234.295442)
		(width 0.1143)
		(layer "In11.Cu")
		(net "GMI_CPU1_G3_CPU0_G1_TX_DP<9>")
	)
	(arc
		(start 349.999046 -231.988614)
		(mid 349.755719 -231.524048)
		(end 349.999046 -231.059482)
		(width 0.1143)
		(layer "In11.Cu")
		(net "GMI_CPU1_G3_CPU0_G1_TX_DP<9>")
	)
	(arc
		(start 350.4692 -227.938838)
		(mid 350.225873 -227.474272)
		(end 350.4692 -227.009706)
		(width 0.1143)
		(layer "In11.Cu")
		(net "GMI_CPU1_G3_CPU0_G1_TX_DP<9>")
	)
	(arc
		(start 349.285814 -235.574078)
		(mid 349.350329 -235.311859)
		(end 349.529146 -235.109512)
		(width 0.1143)
		(layer "In11.Cu")
		(net "GMI_CPU1_G3_CPU0_G1_TX_DP<9>")
	)
	(arc
		(start 121.024142 -230.248206)
		(mid 121.204794 -230.450951)
		(end 121.270014 -230.71455)
		(width 0.1143)
		(layer "In11.Cu")
		(net "GMI_CPU1_G3_CPU0_G1_TX_DP<9>")
	)
	(arc
		(start 121.026682 -227.00996)
		(mid 121.270009 -227.474526)
		(end 121.026682 -227.939092)
		(width 0.1143)
		(layer "In11.Cu")
		(net "GMI_CPU1_G3_CPU0_G1_TX_DP<9>")
	)
	(arc
		(start 348.82582 -236.278674)
		(mid 348.918788 -236.059845)
		(end 349.094298 -235.899452)
		(width 0.1143)
		(layer "In11.Cu")
		(net "GMI_CPU1_G3_CPU0_G1_TX_DP<9>")
	)
	(arc
		(start 120.957086 -223.119696)
		(mid 120.800109 -223.424496)
		(end 120.957086 -223.729296)
		(width 0.1143)
		(layer "In11.Cu")
		(net "GMI_CPU1_G3_CPU0_G1_TX_DP<9>")
	)
	(arc
		(start 350.538796 -225.349054)
		(mid 350.695773 -225.044254)
		(end 350.538796 -224.739454)
		(width 0.1143)
		(layer "In11.Cu")
		(net "GMI_CPU1_G3_CPU0_G1_TX_DP<9>")
	)
	(arc
		(start 121.270014 -232.334308)
		(mid 121.205499 -232.596527)
		(end 121.026682 -232.798874)
		(width 0.1143)
		(layer "In11.Cu")
		(net "GMI_CPU1_G3_CPU0_G1_TX_DP<9>")
	)
	(arc
		(start 120.800114 -221.804484)
		(mid 120.841663 -221.975906)
		(end 120.957086 -222.109284)
		(width 0.1143)
		(layer "In11.Cu")
		(net "GMI_CPU1_G3_CPU0_G1_TX_DP<9>")
	)
	(arc
		(start 350.4692 -226.318826)
		(mid 350.225873 -225.85426)
		(end 350.4692 -225.389694)
		(width 0.1143)
		(layer "In11.Cu")
		(net "GMI_CPU1_G3_CPU0_G1_TX_DP<9>")
	)
	(arc
		(start 350.4692 -229.55885)
		(mid 350.225873 -229.094284)
		(end 350.4692 -228.629718)
		(width 0.1143)
		(layer "In11.Cu")
		(net "GMI_CPU1_G3_CPU0_G1_TX_DP<9>")
	)
	(arc
		(start 350.225868 -232.334054)
		(mid 350.184613 -232.163083)
		(end 350.069912 -232.029762)
		(width 0.1143)
		(layer "In11.Cu")
		(net "GMI_CPU1_G3_CPU0_G1_TX_DP<9>")
	)
	(arc
		(start 350.538796 -226.969066)
		(mid 350.695773 -226.664266)
		(end 350.538796 -226.359466)
		(width 0.1143)
		(layer "In11.Cu")
		(net "GMI_CPU1_G3_CPU0_G1_TX_DP<9>")
	)
	(arc
		(start 121.496836 -231.059736)
		(mid 121.740163 -231.524302)
		(end 121.496836 -231.988868)
		(width 0.1143)
		(layer "In11.Cu")
		(net "GMI_CPU1_G3_CPU0_G1_TX_DP<9>")
	)
	(arc
		(start 350.538796 -223.729042)
		(mid 350.695773 -223.424242)
		(end 350.538796 -223.119442)
		(width 0.1143)
		(layer "In11.Cu")
		(net "GMI_CPU1_G3_CPU0_G1_TX_DP<9>")
	)
	(arc
		(start 350.538796 -230.208836)
		(mid 350.654223 -230.07546)
		(end 350.695768 -229.904036)
		(width 0.1143)
		(layer "In11.Cu")
		(net "GMI_CPU1_G3_CPU0_G1_TX_DP<9>")
	)
	(arc
		(start 121.966736 -235.109766)
		(mid 122.145549 -235.312116)
		(end 122.210068 -235.574332)
		(width 0.1143)
		(layer "In11.Cu")
		(net "GMI_CPU1_G3_CPU0_G1_TX_DP<9>")
	)
	(arc
		(start 121.026682 -225.389948)
		(mid 121.270009 -225.854514)
		(end 121.026682 -226.31908)
		(width 0.1143)
		(layer "In11.Cu")
		(net "GMI_CPU1_G3_CPU0_G1_TX_DP<9>")
	)
	(arc
		(start 121.42597 -232.030016)
		(mid 121.311294 -232.16335)
		(end 121.270014 -232.334308)
		(width 0.1143)
		(layer "In11.Cu")
		(net "GMI_CPU1_G3_CPU0_G1_TX_DP<9>")
	)
	(arc
		(start 350.695768 -229.904036)
		(mid 350.654802 -229.73363)
		(end 350.540828 -229.600506)
		(width 0.1143)
		(layer "In11.Cu")
		(net "GMI_CPU1_G3_CPU0_G1_TX_DP<9>")
	)
	(arc
		(start 350.225868 -230.714296)
		(mid 350.291104 -230.450705)
		(end 350.47174 -230.247952)
		(width 0.1143)
		(layer "In11.Cu")
		(net "GMI_CPU1_G3_CPU0_G1_TX_DP<9>")
	)
	(arc
		(start 350.4692 -223.078802)
		(mid 350.225873 -222.614236)
		(end 350.4692 -222.14967)
		(width 0.1143)
		(layer "In11.Cu")
		(net "GMI_CPU1_G3_CPU0_G1_TX_DP<9>")
	)
	(arc
		(start 121.026682 -222.149924)
		(mid 121.270009 -222.61449)
		(end 121.026682 -223.079056)
		(width 0.1143)
		(layer "In11.Cu")
		(net "GMI_CPU1_G3_CPU0_G1_TX_DP<9>")
	)
	(arc
		(start 350.4692 -232.79862)
		(mid 350.290387 -232.59627)
		(end 350.225868 -232.334054)
		(width 0.1143)
		(layer "In11.Cu")
		(net "GMI_CPU1_G3_CPU0_G1_TX_DP<9>")
	)
	(arc
		(start 121.026682 -228.629972)
		(mid 121.270009 -229.094538)
		(end 121.026682 -229.559104)
		(width 0.1143)
		(layer "In11.Cu")
		(net "GMI_CPU1_G3_CPU0_G1_TX_DP<9>")
	)
	(arc
		(start 349.598742 -235.068872)
		(mid 349.714169 -234.935496)
		(end 349.755714 -234.764072)
		(width 0.1143)
		(layer "In11.Cu")
		(net "GMI_CPU1_G3_CPU0_G1_TX_DP<9>")
	)
	(arc
		(start 120.957086 -227.979732)
		(mid 120.800109 -228.284532)
		(end 120.957086 -228.589332)
		(width 0.1143)
		(layer "In11.Cu")
		(net "GMI_CPU1_G3_CPU0_G1_TX_DP<9>")
	)
	(arc
		(start 350.07169 -231.017064)
		(mid 350.185097 -230.884175)
		(end 350.225868 -230.714296)
		(width 0.1143)
		(layer "In11.Cu")
		(net "GMI_CPU1_G3_CPU0_G1_TX_DP<9>")
	)
	(arc
		(start 121.496836 -234.29976)
		(mid 121.675649 -234.50211)
		(end 121.740168 -234.764326)
		(width 0.1143)
		(layer "In11.Cu")
		(net "GMI_CPU1_G3_CPU0_G1_TX_DP<9>")
	)
	(arc
		(start 350.225868 -233.954066)
		(mid 350.290383 -233.691847)
		(end 350.4692 -233.4895)
		(width 0.1143)
		(layer "In11.Cu")
		(net "GMI_CPU1_G3_CPU0_G1_TX_DP<9>")
	)
	(arc
		(start 121.740168 -234.764326)
		(mid 121.781717 -234.935748)
		(end 121.89714 -235.069126)
		(width 0.1143)
		(layer "In11.Cu")
		(net "GMI_CPU1_G3_CPU0_G1_TX_DP<9>")
	)
	(arc
		(start 121.270014 -230.71455)
		(mid 121.310776 -230.884434)
		(end 121.424192 -231.017318)
		(width 0.1143)
		(layer "In11.Cu")
		(net "GMI_CPU1_G3_CPU0_G1_TX_DP<9>")
	)
	(arc
		(start 350.538796 -228.589078)
		(mid 350.695773 -228.284278)
		(end 350.538796 -227.979478)
		(width 0.1143)
		(layer "In11.Cu")
		(net "GMI_CPU1_G3_CPU0_G1_TX_DP<9>")
	)
	(arc
		(start 122.670062 -236.278928)
		(mid 122.672081 -236.290212)
		(end 122.673872 -236.301534)
		(width 0.1143)
		(layer "In11.Cu")
		(net "GMI_CPU1_G3_CPU0_G1_TX_DP<9>")
	)
	(arc
		(start 349.755714 -234.764072)
		(mid 349.820229 -234.501853)
		(end 349.999046 -234.299506)
		(width 0.1143)
		(layer "In11.Cu")
		(net "GMI_CPU1_G3_CPU0_G1_TX_DP<9>")
	)
	(arc
		(start 350.538796 -233.44886)
		(mid 350.695773 -233.14406)
		(end 350.538796 -232.83926)
		(width 0.1143)
		(layer "In11.Cu")
		(net "GMI_CPU1_G3_CPU0_G1_TX_DP<9>")
	)
	(arc
		(start 121.026682 -223.769936)
		(mid 121.270009 -224.234502)
		(end 121.026682 -224.699068)
		(width 0.1143)
		(layer "In11.Cu")
		(net "GMI_CPU1_G3_CPU0_G1_TX_DP<9>")
	)
	(arc
		(start 122.401584 -235.899706)
		(mid 122.577098 -236.060096)
		(end 122.670062 -236.278928)
		(width 0.1143)
		(layer "In11.Cu")
		(net "GMI_CPU1_G3_CPU0_G1_TX_DP<9>")
	)
	(arc
		(start 350.538796 -222.10903)
		(mid 350.654223 -221.975654)
		(end 350.695768 -221.80423)
		(width 0.1143)
		(layer "In11.Cu")
		(net "GMI_CPU1_G3_CPU0_G1_TX_DP<9>")
	)
	(arc
		(start 350.4692 -224.698814)
		(mid 350.225873 -224.234248)
		(end 350.4692 -223.769682)
		(width 0.1143)
		(layer "In11.Cu")
		(net "GMI_CPU1_G3_CPU0_G1_TX_DP<9>")
	)
	(arc
		(start 120.957086 -232.839514)
		(mid 120.800109 -233.144314)
		(end 120.957086 -233.449114)
		(width 0.1143)
		(layer "In11.Cu")
		(net "GMI_CPU1_G3_CPU0_G1_TX_DP<9>")
	)
	(arc
		(start 122.210068 -235.574332)
		(mid 122.260023 -235.760632)
		(end 122.396504 -235.896912)
		(width 0.1143)
		(layer "In11.Cu")
		(net "GMI_CPU1_G3_CPU0_G1_TX_DP<9>")
	)
	(arc
		(start 349.099378 -235.896658)
		(mid 349.235826 -235.760359)
		(end 349.285814 -235.574078)
		(width 0.1143)
		(layer "In11.Cu")
		(net "GMI_CPU1_G3_CPU0_G1_TX_DP<9>")
	)
	(arc
		(start 121.270014 -233.95432)
		(mid 121.311269 -234.125291)
		(end 121.42597 -234.258612)
		(width 0.1143)
		(layer "In11.Cu")
		(net "GMI_CPU1_G3_CPU0_G1_TX_DP<9>")
	)
	(arc
		(start 120.957086 -226.35972)
		(mid 120.800109 -226.66452)
		(end 120.957086 -226.96932)
		(width 0.1143)
		(layer "In11.Cu")
		(net "GMI_CPU1_G3_CPU0_G1_TX_DP<9>")
	)
	(arc
		(start 348.82201 -236.30128)
		(mid 348.823799 -236.289958)
		(end 348.82582 -236.278674)
		(width 0.1143)
		(layer "In11.Cu")
		(net "GMI_CPU1_G3_CPU0_G1_TX_DP<9>")
	)
	(arc
		(start 121.026682 -233.489754)
		(mid 121.205495 -233.692104)
		(end 121.270014 -233.95432)
		(width 0.1143)
		(layer "In11.Cu")
		(net "GMI_CPU1_G3_CPU0_G1_TX_DP<9>")
	)
	(arc
		(start 120.955054 -229.60076)
		(mid 120.841125 -229.733907)
		(end 120.800114 -229.90429)
		(width 0.1143)
		(layer "In11.Cu")
		(net "GMI_CPU1_G3_CPU0_G1_TX_DP<9>")
	)
	(arc
		(start 350.069912 -234.258358)
		(mid 350.184588 -234.125024)
		(end 350.225868 -233.954066)
		(width 0.1143)
		(layer "In11.Cu")
		(net "GMI_CPU1_G3_CPU0_G1_TX_DP<9>")
	)
	(arc
		(start 120.800114 -229.90429)
		(mid 120.841663 -230.075712)
		(end 120.957086 -230.20909)
		(width 0.1143)
		(layer "In11.Cu")
		(net "GMI_CPU1_G3_CPU0_G1_TX_DP<9>")
	)
	(arc
		(start 120.957086 -224.739708)
		(mid 120.800109 -225.044508)
		(end 120.957086 -225.349308)
		(width 0.1143)
		(layer "In11.Cu")
		(net "GMI_CPU1_G3_CPU0_G1_TX_DP<9>")
	)
	(segment
		(start 351.728024 -233.409998)
		(end 351.261172 -233.14406)
		(width 0.12954)
		(layer "F.Cu")
		(net "GMI_CPU1_G3_CPU0_G1_TX_DP<8>")
	)
	(segment
		(start 119.767858 -233.410252)
		(end 120.23471 -233.144314)
		(width 0.12954)
		(layer "F.Cu")
		(net "GMI_CPU1_G3_CPU0_G1_TX_DP<8>")
	)
	(segment
		(start 155.226512 -188.530738)
		(end 154.896566 -188.801248)
		(width 0.14224)
		(layer "In11.Cu")
		(net "GMI_CPU1_G3_CPU0_G1_TX_DP<8>")
	)
	(segment
		(start 155.419552 -188.549788)
		(end 155.226512 -188.530738)
		(width 0.14224)
		(layer "In11.Cu")
		(net "GMI_CPU1_G3_CPU0_G1_TX_DP<8>")
	)
	(segment
		(start 120.086628 -224.699068)
		(end 120.047512 -224.721928)
		(width 0.1143)
		(layer "In11.Cu")
		(net "GMI_CPU1_G3_CPU0_G1_TX_DP<8>")
	)
	(segment
		(start 120.017032 -222.109284)
		(end 120.047512 -222.127064)
		(width 0.1143)
		(layer "In11.Cu")
		(net "GMI_CPU1_G3_CPU0_G1_TX_DP<8>")
	)
	(segment
		(start 119.936768 -233.144314)
		(end 120.23471 -233.144314)
		(width 0.1143)
		(layer "In11.Cu")
		(net "GMI_CPU1_G3_CPU0_G1_TX_DP<8>")
	)
	(segment
		(start 120.517666 -232.011728)
		(end 120.516904 -232.012236)
		(width 0.1143)
		(layer "In11.Cu")
		(net "GMI_CPU1_G3_CPU0_G1_TX_DP<8>")
	)
	(segment
		(start 350.978978 -232.011982)
		(end 350.978216 -232.011474)
		(width 0.1143)
		(layer "In11.Cu")
		(net "GMI_CPU1_G3_CPU0_G1_TX_DP<8>")
	)
	(segment
		(start 153.002234 -190.532258)
		(end 152.672034 -190.803022)
		(width 0.14224)
		(layer "In11.Cu")
		(net "GMI_CPU1_G3_CPU0_G1_TX_DP<8>")
	)
	(segment
		(start 120.086628 -232.798874)
		(end 120.047512 -232.821734)
		(width 0.1143)
		(layer "In11.Cu")
		(net "GMI_CPU1_G3_CPU0_G1_TX_DP<8>")
	)
	(segment
		(start 120.086628 -227.939092)
		(end 120.047512 -227.961952)
		(width 0.1143)
		(layer "In11.Cu")
		(net "GMI_CPU1_G3_CPU0_G1_TX_DP<8>")
	)
	(segment
		(start 161.119312 -183.698388)
		(end 155.768802 -188.085984)
		(width 0.14224)
		(layer "In11.Cu")
		(net "GMI_CPU1_G3_CPU0_G1_TX_DP<8>")
	)
	(segment
		(start 351.261172 -233.14406)
		(end 351.559114 -233.14406)
		(width 0.1143)
		(layer "In11.Cu")
		(net "GMI_CPU1_G3_CPU0_G1_TX_DP<8>")
	)
	(segment
		(start 147.47113 -194.889374)
		(end 145.90903 -196.170296)
		(width 0.14224)
		(layer "In11.Cu")
		(net "GMI_CPU1_G3_CPU0_G1_TX_DP<8>")
	)
	(segment
		(start 120.047512 -228.607112)
		(end 120.086628 -228.629972)
		(width 0.1143)
		(layer "In11.Cu")
		(net "GMI_CPU1_G3_CPU0_G1_TX_DP<8>")
	)
	(segment
		(start 351.47885 -224.739454)
		(end 351.409254 -224.698814)
		(width 0.1143)
		(layer "In11.Cu")
		(net "GMI_CPU1_G3_CPU0_G1_TX_DP<8>")
	)
	(segment
		(start 350.98482 -232.015284)
		(end 350.984058 -232.014776)
		(width 0.1143)
		(layer "In11.Cu")
		(net "GMI_CPU1_G3_CPU0_G1_TX_DP<8>")
	)
	(segment
		(start 120.047512 -229.581964)
		(end 120.015 -229.60076)
		(width 0.1143)
		(layer "In11.Cu")
		(net "GMI_CPU1_G3_CPU0_G1_TX_DP<8>")
	)
	(segment
		(start 351.411794 -230.247952)
		(end 351.47885 -230.208836)
		(width 0.1143)
		(layer "In11.Cu")
		(net "GMI_CPU1_G3_CPU0_G1_TX_DP<8>")
	)
	(segment
		(start 166.434516 -181.798214)
		(end 161.119312 -183.698388)
		(width 0.14224)
		(layer "In11.Cu")
		(net "GMI_CPU1_G3_CPU0_G1_TX_DP<8>")
	)
	(segment
		(start 151.276812 -191.769492)
		(end 151.257762 -191.962532)
		(width 0.14224)
		(layer "In11.Cu")
		(net "GMI_CPU1_G3_CPU0_G1_TX_DP<8>")
	)
	(segment
		(start 120.484138 -231.017318)
		(end 120.517666 -231.036876)
		(width 0.1143)
		(layer "In11.Cu")
		(net "GMI_CPU1_G3_CPU0_G1_TX_DP<8>")
	)
	(segment
		(start 151.799798 -191.518286)
		(end 151.606758 -191.498982)
		(width 0.14224)
		(layer "In11.Cu")
		(net "GMI_CPU1_G3_CPU0_G1_TX_DP<8>")
	)
	(segment
		(start 351.635822 -221.80423)
		(end 351.635822 -221.381066)
		(width 0.1143)
		(layer "In11.Cu")
		(net "GMI_CPU1_G3_CPU0_G1_TX_DP<8>")
	)
	(segment
		(start 120.017032 -223.729296)
		(end 120.047512 -223.747076)
		(width 0.1143)
		(layer "In11.Cu")
		(net "GMI_CPU1_G3_CPU0_G1_TX_DP<8>")
	)
	(segment
		(start 314.465462 -186.532012)
		(end 308.31536 -183.050434)
		(width 0.14224)
		(layer "In11.Cu")
		(net "GMI_CPU1_G3_CPU0_G1_TX_DP<8>")
	)
	(segment
		(start 152.478994 -190.783972)
		(end 152.149048 -191.054482)
		(width 0.14224)
		(layer "In11.Cu")
		(net "GMI_CPU1_G3_CPU0_G1_TX_DP<8>")
	)
	(segment
		(start 119.826024 -221.129098)
		(end 119.826024 -221.347284)
		(width 0.1143)
		(layer "In11.Cu")
		(net "GMI_CPU1_G3_CPU0_G1_TX_DP<8>")
	)
	(segment
		(start 351.009966 -232.029762)
		(end 350.98482 -232.015284)
		(width 0.1143)
		(layer "In11.Cu")
		(net "GMI_CPU1_G3_CPU0_G1_TX_DP<8>")
	)
	(segment
		(start 120.017032 -225.349308)
		(end 120.047512 -225.367088)
		(width 0.1143)
		(layer "In11.Cu")
		(net "GMI_CPU1_G3_CPU0_G1_TX_DP<8>")
	)
	(segment
		(start 120.047512 -226.34194)
		(end 120.017032 -226.35972)
		(width 0.1143)
		(layer "In11.Cu")
		(net "GMI_CPU1_G3_CPU0_G1_TX_DP<8>")
	)
	(segment
		(start 351.47885 -226.359466)
		(end 351.409254 -226.318826)
		(width 0.1143)
		(layer "In11.Cu")
		(net "GMI_CPU1_G3_CPU0_G1_TX_DP<8>")
	)
	(segment
		(start 120.047512 -225.367088)
		(end 120.086628 -225.389948)
		(width 0.1143)
		(layer "In11.Cu")
		(net "GMI_CPU1_G3_CPU0_G1_TX_DP<8>")
	)
	(segment
		(start 350.978216 -232.011474)
		(end 350.9391 -231.988614)
		(width 0.1143)
		(layer "In11.Cu")
		(net "GMI_CPU1_G3_CPU0_G1_TX_DP<8>")
	)
	(segment
		(start 351.409254 -225.389694)
		(end 351.47885 -225.349054)
		(width 0.1143)
		(layer "In11.Cu")
		(net "GMI_CPU1_G3_CPU0_G1_TX_DP<8>")
	)
	(segment
		(start 147.471384 -194.889374)
		(end 147.47113 -194.889374)
		(width 0.14224)
		(layer "In11.Cu")
		(net "GMI_CPU1_G3_CPU0_G1_TX_DP<8>")
	)
	(segment
		(start 153.54427 -190.087504)
		(end 153.35123 -190.068454)
		(width 0.14224)
		(layer "In11.Cu")
		(net "GMI_CPU1_G3_CPU0_G1_TX_DP<8>")
	)
	(segment
		(start 119.826024 -221.347284)
		(end 119.86006 -221.38132)
		(width 0.1143)
		(layer "In11.Cu")
		(net "GMI_CPU1_G3_CPU0_G1_TX_DP<8>")
	)
	(segment
		(start 153.87447 -189.81674)
		(end 153.54427 -190.087504)
		(width 0.14224)
		(layer "In11.Cu")
		(net "GMI_CPU1_G3_CPU0_G1_TX_DP<8>")
	)
	(segment
		(start 155.768802 -188.085984)
		(end 155.749752 -188.279024)
		(width 0.14224)
		(layer "In11.Cu")
		(net "GMI_CPU1_G3_CPU0_G1_TX_DP<8>")
	)
	(segment
		(start 152.149048 -191.054482)
		(end 152.129998 -191.247522)
		(width 0.14224)
		(layer "In11.Cu")
		(net "GMI_CPU1_G3_CPU0_G1_TX_DP<8>")
	)
	(segment
		(start 351.409254 -222.14967)
		(end 351.47885 -222.10903)
		(width 0.1143)
		(layer "In11.Cu")
		(net "GMI_CPU1_G3_CPU0_G1_TX_DP<8>")
	)
	(segment
		(start 308.31536 -183.050434)
		(end 307.036978 -182.593488)
		(width 0.14224)
		(layer "In11.Cu")
		(net "GMI_CPU1_G3_CPU0_G1_TX_DP<8>")
	)
	(segment
		(start 122.566176 -214.768176)
		(end 119.871744 -219.380562)
		(width 0.14224)
		(layer "In11.Cu")
		(net "GMI_CPU1_G3_CPU0_G1_TX_DP<8>")
	)
	(segment
		(start 120.518682 -232.01122)
		(end 120.517666 -232.011728)
		(width 0.1143)
		(layer "In11.Cu")
		(net "GMI_CPU1_G3_CPU0_G1_TX_DP<8>")
	)
	(segment
		(start 144.86001 -196.487796)
		(end 122.566176 -214.768176)
		(width 0.14224)
		(layer "In11.Cu")
		(net "GMI_CPU1_G3_CPU0_G1_TX_DP<8>")
	)
	(segment
		(start 152.672034 -190.803022)
		(end 152.478994 -190.783972)
		(width 0.14224)
		(layer "In11.Cu")
		(net "GMI_CPU1_G3_CPU0_G1_TX_DP<8>")
	)
	(segment
		(start 150.385526 -192.677796)
		(end 150.055326 -192.94856)
		(width 0.14224)
		(layer "In11.Cu")
		(net "GMI_CPU1_G3_CPU0_G1_TX_DP<8>")
	)
	(segment
		(start 351.47885 -223.119442)
		(end 351.409254 -223.078802)
		(width 0.1143)
		(layer "In11.Cu")
		(net "GMI_CPU1_G3_CPU0_G1_TX_DP<8>")
	)
	(segment
		(start 149.862286 -192.929256)
		(end 149.53234 -193.199766)
		(width 0.14224)
		(layer "In11.Cu")
		(net "GMI_CPU1_G3_CPU0_G1_TX_DP<8>")
	)
	(segment
		(start 302.895 -182.593488)
		(end 166.434516 -181.798214)
		(width 0.14224)
		(layer "In11.Cu")
		(net "GMI_CPU1_G3_CPU0_G1_TX_DP<8>")
	)
	(segment
		(start 119.866918 -233.074464)
		(end 119.936768 -233.144314)
		(width 0.1143)
		(layer "In11.Cu")
		(net "GMI_CPU1_G3_CPU0_G1_TX_DP<8>")
	)
	(segment
		(start 120.047512 -223.747076)
		(end 120.086628 -223.769936)
		(width 0.1143)
		(layer "In11.Cu")
		(net "GMI_CPU1_G3_CPU0_G1_TX_DP<8>")
	)
	(segment
		(start 150.055326 -192.94856)
		(end 149.862286 -192.929256)
		(width 0.14224)
		(layer "In11.Cu")
		(net "GMI_CPU1_G3_CPU0_G1_TX_DP<8>")
	)
	(segment
		(start 119.871744 -221.071948)
		(end 119.871744 -221.083378)
		(width 0.1143)
		(layer "In11.Cu")
		(net "GMI_CPU1_G3_CPU0_G1_TX_DP<8>")
	)
	(segment
		(start 350.980248 -232.012744)
		(end 350.978978 -232.011982)
		(width 0.1143)
		(layer "In11.Cu")
		(net "GMI_CPU1_G3_CPU0_G1_TX_DP<8>")
	)
	(segment
		(start 119.871744 -219.380562)
		(end 119.871744 -221.071948)
		(width 0.14224)
		(layer "In11.Cu")
		(net "GMI_CPU1_G3_CPU0_G1_TX_DP<8>")
	)
	(segment
		(start 120.047512 -226.9871)
		(end 120.086628 -227.00996)
		(width 0.1143)
		(layer "In11.Cu")
		(net "GMI_CPU1_G3_CPU0_G1_TX_DP<8>")
	)
	(segment
		(start 151.257762 -191.962532)
		(end 150.927562 -192.233296)
		(width 0.14224)
		(layer "In11.Cu")
		(net "GMI_CPU1_G3_CPU0_G1_TX_DP<8>")
	)
	(segment
		(start 120.047512 -223.101916)
		(end 120.017032 -223.119696)
		(width 0.1143)
		(layer "In11.Cu")
		(net "GMI_CPU1_G3_CPU0_G1_TX_DP<8>")
	)
	(segment
		(start 120.086628 -229.559104)
		(end 120.047512 -229.581964)
		(width 0.1143)
		(layer "In11.Cu")
		(net "GMI_CPU1_G3_CPU0_G1_TX_DP<8>")
	)
	(segment
		(start 154.896566 -188.801248)
		(end 154.877516 -188.994288)
		(width 0.14224)
		(layer "In11.Cu")
		(net "GMI_CPU1_G3_CPU0_G1_TX_DP<8>")
	)
	(segment
		(start 351.409254 -228.629718)
		(end 351.47885 -228.589078)
		(width 0.1143)
		(layer "In11.Cu")
		(net "GMI_CPU1_G3_CPU0_G1_TX_DP<8>")
	)
	(segment
		(start 119.871744 -221.083378)
		(end 119.826024 -221.129098)
		(width 0.1143)
		(layer "In11.Cu")
		(net "GMI_CPU1_G3_CPU0_G1_TX_DP<8>")
	)
	(segment
		(start 307.036978 -182.593488)
		(end 302.895 -182.593488)
		(width 0.14224)
		(layer "In11.Cu")
		(net "GMI_CPU1_G3_CPU0_G1_TX_DP<8>")
	)
	(segment
		(start 120.520206 -232.010204)
		(end 120.518682 -232.01122)
		(width 0.1143)
		(layer "In11.Cu")
		(net "GMI_CPU1_G3_CPU0_G1_TX_DP<8>")
	)
	(segment
		(start 350.982534 -232.014014)
		(end 350.981772 -232.013506)
		(width 0.1143)
		(layer "In11.Cu")
		(net "GMI_CPU1_G3_CPU0_G1_TX_DP<8>")
	)
	(segment
		(start 351.480882 -229.600506)
		(end 351.44837 -229.58171)
		(width 0.1143)
		(layer "In11.Cu")
		(net "GMI_CPU1_G3_CPU0_G1_TX_DP<8>")
	)
	(segment
		(start 120.516904 -232.012236)
		(end 120.485916 -232.030016)
		(width 0.1143)
		(layer "In11.Cu")
		(net "GMI_CPU1_G3_CPU0_G1_TX_DP<8>")
	)
	(segment
		(start 120.086628 -223.079056)
		(end 120.047512 -223.101916)
		(width 0.1143)
		(layer "In11.Cu")
		(net "GMI_CPU1_G3_CPU0_G1_TX_DP<8>")
	)
	(segment
		(start 351.669858 -221.34703)
		(end 351.669858 -221.128844)
		(width 0.1143)
		(layer "In11.Cu")
		(net "GMI_CPU1_G3_CPU0_G1_TX_DP<8>")
	)
	(segment
		(start 150.404576 -192.484756)
		(end 150.385526 -192.677796)
		(width 0.14224)
		(layer "In11.Cu")
		(net "GMI_CPU1_G3_CPU0_G1_TX_DP<8>")
	)
	(segment
		(start 150.927562 -192.233296)
		(end 150.734522 -192.214246)
		(width 0.14224)
		(layer "In11.Cu")
		(net "GMI_CPU1_G3_CPU0_G1_TX_DP<8>")
	)
	(segment
		(start 148.99005 -193.644266)
		(end 147.471384 -194.889374)
		(width 0.14224)
		(layer "In11.Cu")
		(net "GMI_CPU1_G3_CPU0_G1_TX_DP<8>")
	)
	(segment
		(start 349.006414 -214.853774)
		(end 314.465462 -186.532012)
		(width 0.14224)
		(layer "In11.Cu")
		(net "GMI_CPU1_G3_CPU0_G1_TX_DP<8>")
	)
	(segment
		(start 154.877516 -188.994288)
		(end 154.547316 -189.265052)
		(width 0.14224)
		(layer "In11.Cu")
		(net "GMI_CPU1_G3_CPU0_G1_TX_DP<8>")
	)
	(segment
		(start 350.981772 -232.013506)
		(end 350.980248 -232.012744)
		(width 0.1143)
		(layer "In11.Cu")
		(net "GMI_CPU1_G3_CPU0_G1_TX_DP<8>")
	)
	(segment
		(start 153.89352 -189.6237)
		(end 153.87447 -189.81674)
		(width 0.14224)
		(layer "In11.Cu")
		(net "GMI_CPU1_G3_CPU0_G1_TX_DP<8>")
	)
	(segment
		(start 145.90903 -196.170296)
		(end 144.86001 -196.487796)
		(width 0.14224)
		(layer "In11.Cu")
		(net "GMI_CPU1_G3_CPU0_G1_TX_DP<8>")
	)
	(segment
		(start 151.606758 -191.498982)
		(end 151.276812 -191.769492)
		(width 0.14224)
		(layer "In11.Cu")
		(net "GMI_CPU1_G3_CPU0_G1_TX_DP<8>")
	)
	(segment
		(start 154.547316 -189.265052)
		(end 154.354276 -189.246002)
		(width 0.14224)
		(layer "In11.Cu")
		(net "GMI_CPU1_G3_CPU0_G1_TX_DP<8>")
	)
	(segment
		(start 150.734522 -192.214246)
		(end 150.404576 -192.484756)
		(width 0.14224)
		(layer "In11.Cu")
		(net "GMI_CPU1_G3_CPU0_G1_TX_DP<8>")
	)
	(segment
		(start 153.021284 -190.338964)
		(end 153.021284 -190.339218)
		(width 0.14224)
		(layer "In11.Cu")
		(net "GMI_CPU1_G3_CPU0_G1_TX_DP<8>")
	)
	(segment
		(start 154.354276 -189.246002)
		(end 153.89352 -189.6237)
		(width 0.14224)
		(layer "In11.Cu")
		(net "GMI_CPU1_G3_CPU0_G1_TX_DP<8>")
	)
	(segment
		(start 120.086628 -226.31908)
		(end 120.047512 -226.34194)
		(width 0.1143)
		(layer "In11.Cu")
		(net "GMI_CPU1_G3_CPU0_G1_TX_DP<8>")
	)
	(segment
		(start 120.047512 -222.127064)
		(end 120.086628 -222.149924)
		(width 0.1143)
		(layer "In11.Cu")
		(net "GMI_CPU1_G3_CPU0_G1_TX_DP<8>")
	)
	(segment
		(start 351.409254 -227.009706)
		(end 351.47885 -226.969066)
		(width 0.1143)
		(layer "In11.Cu")
		(net "GMI_CPU1_G3_CPU0_G1_TX_DP<8>")
	)
	(segment
		(start 120.047512 -232.821734)
		(end 120.017032 -232.839514)
		(width 0.1143)
		(layer "In11.Cu")
		(net "GMI_CPU1_G3_CPU0_G1_TX_DP<8>")
	)
	(segment
		(start 351.44837 -229.58171)
		(end 351.409254 -229.55885)
		(width 0.1143)
		(layer "In11.Cu")
		(net "GMI_CPU1_G3_CPU0_G1_TX_DP<8>")
	)
	(segment
		(start 120.047512 -224.721928)
		(end 120.017032 -224.739708)
		(width 0.1143)
		(layer "In11.Cu")
		(net "GMI_CPU1_G3_CPU0_G1_TX_DP<8>")
	)
	(segment
		(start 152.129998 -191.247522)
		(end 151.799798 -191.518286)
		(width 0.14224)
		(layer "In11.Cu")
		(net "GMI_CPU1_G3_CPU0_G1_TX_DP<8>")
	)
	(segment
		(start 351.624138 -219.26296)
		(end 349.006414 -214.853774)
		(width 0.14224)
		(layer "In11.Cu")
		(net "GMI_CPU1_G3_CPU0_G1_TX_DP<8>")
	)
	(segment
		(start 120.017032 -226.96932)
		(end 120.047512 -226.9871)
		(width 0.1143)
		(layer "In11.Cu")
		(net "GMI_CPU1_G3_CPU0_G1_TX_DP<8>")
	)
	(segment
		(start 149.18309 -193.66357)
		(end 148.99005 -193.644266)
		(width 0.14224)
		(layer "In11.Cu")
		(net "GMI_CPU1_G3_CPU0_G1_TX_DP<8>")
	)
	(segment
		(start 120.047512 -227.961952)
		(end 120.017032 -227.979732)
		(width 0.1143)
		(layer "In11.Cu")
		(net "GMI_CPU1_G3_CPU0_G1_TX_DP<8>")
	)
	(segment
		(start 350.984058 -232.014776)
		(end 350.982534 -232.014014)
		(width 0.1143)
		(layer "In11.Cu")
		(net "GMI_CPU1_G3_CPU0_G1_TX_DP<8>")
	)
	(segment
		(start 120.017032 -230.20909)
		(end 120.084088 -230.248206)
		(width 0.1143)
		(layer "In11.Cu")
		(net "GMI_CPU1_G3_CPU0_G1_TX_DP<8>")
	)
	(segment
		(start 149.53234 -193.199766)
		(end 149.51329 -193.392806)
		(width 0.14224)
		(layer "In11.Cu")
		(net "GMI_CPU1_G3_CPU0_G1_TX_DP<8>")
	)
	(segment
		(start 120.517666 -231.036876)
		(end 120.556782 -231.059736)
		(width 0.1143)
		(layer "In11.Cu")
		(net "GMI_CPU1_G3_CPU0_G1_TX_DP<8>")
	)
	(segment
		(start 351.47885 -232.83926)
		(end 351.409254 -232.79862)
		(width 0.1143)
		(layer "In11.Cu")
		(net "GMI_CPU1_G3_CPU0_G1_TX_DP<8>")
	)
	(segment
		(start 153.021284 -190.339218)
		(end 153.002234 -190.532258)
		(width 0.14224)
		(layer "In11.Cu")
		(net "GMI_CPU1_G3_CPU0_G1_TX_DP<8>")
	)
	(segment
		(start 351.624138 -221.083124)
		(end 351.624138 -219.26296)
		(width 0.14224)
		(layer "In11.Cu")
		(net "GMI_CPU1_G3_CPU0_G1_TX_DP<8>")
	)
	(segment
		(start 351.669858 -221.128844)
		(end 351.624138 -221.083124)
		(width 0.1143)
		(layer "In11.Cu")
		(net "GMI_CPU1_G3_CPU0_G1_TX_DP<8>")
	)
	(segment
		(start 153.35123 -190.068454)
		(end 153.021284 -190.338964)
		(width 0.14224)
		(layer "In11.Cu")
		(net "GMI_CPU1_G3_CPU0_G1_TX_DP<8>")
	)
	(segment
		(start 351.409254 -223.769682)
		(end 351.47885 -223.729042)
		(width 0.1143)
		(layer "In11.Cu")
		(net "GMI_CPU1_G3_CPU0_G1_TX_DP<8>")
	)
	(segment
		(start 120.556782 -231.988868)
		(end 120.520206 -232.010204)
		(width 0.1143)
		(layer "In11.Cu")
		(net "GMI_CPU1_G3_CPU0_G1_TX_DP<8>")
	)
	(segment
		(start 155.749752 -188.279024)
		(end 155.419552 -188.549788)
		(width 0.14224)
		(layer "In11.Cu")
		(net "GMI_CPU1_G3_CPU0_G1_TX_DP<8>")
	)
	(segment
		(start 351.559114 -233.14406)
		(end 351.628964 -233.07421)
		(width 0.1143)
		(layer "In11.Cu")
		(net "GMI_CPU1_G3_CPU0_G1_TX_DP<8>")
	)
	(segment
		(start 350.9391 -231.059482)
		(end 351.011744 -231.017064)
		(width 0.1143)
		(layer "In11.Cu")
		(net "GMI_CPU1_G3_CPU0_G1_TX_DP<8>")
	)
	(segment
		(start 351.635822 -221.381066)
		(end 351.669858 -221.34703)
		(width 0.1143)
		(layer "In11.Cu")
		(net "GMI_CPU1_G3_CPU0_G1_TX_DP<8>")
	)
	(segment
		(start 351.47885 -227.979478)
		(end 351.409254 -227.938838)
		(width 0.1143)
		(layer "In11.Cu")
		(net "GMI_CPU1_G3_CPU0_G1_TX_DP<8>")
	)
	(segment
		(start 120.017032 -228.589332)
		(end 120.047512 -228.607112)
		(width 0.1143)
		(layer "In11.Cu")
		(net "GMI_CPU1_G3_CPU0_G1_TX_DP<8>")
	)
	(segment
		(start 119.86006 -221.38132)
		(end 119.86006 -221.804484)
		(width 0.1143)
		(layer "In11.Cu")
		(net "GMI_CPU1_G3_CPU0_G1_TX_DP<8>")
	)
	(segment
		(start 149.51329 -193.392806)
		(end 149.18309 -193.66357)
		(width 0.14224)
		(layer "In11.Cu")
		(net "GMI_CPU1_G3_CPU0_G1_TX_DP<8>")
	)
	(arc
		(start 351.409254 -223.078802)
		(mid 351.165927 -222.614236)
		(end 351.409254 -222.14967)
		(width 0.1143)
		(layer "In11.Cu")
		(net "GMI_CPU1_G3_CPU0_G1_TX_DP<8>")
	)
	(arc
		(start 351.628964 -233.07421)
		(mid 351.576547 -232.942279)
		(end 351.47885 -232.83926)
		(width 0.1143)
		(layer "In11.Cu")
		(net "GMI_CPU1_G3_CPU0_G1_TX_DP<8>")
	)
	(arc
		(start 120.017032 -226.35972)
		(mid 119.860055 -226.66452)
		(end 120.017032 -226.96932)
		(width 0.1143)
		(layer "In11.Cu")
		(net "GMI_CPU1_G3_CPU0_G1_TX_DP<8>")
	)
	(arc
		(start 120.485916 -232.030016)
		(mid 120.37124 -232.16335)
		(end 120.32996 -232.334308)
		(width 0.1143)
		(layer "In11.Cu")
		(net "GMI_CPU1_G3_CPU0_G1_TX_DP<8>")
	)
	(arc
		(start 351.47885 -226.969066)
		(mid 351.635827 -226.664266)
		(end 351.47885 -226.359466)
		(width 0.1143)
		(layer "In11.Cu")
		(net "GMI_CPU1_G3_CPU0_G1_TX_DP<8>")
	)
	(arc
		(start 351.635822 -229.904036)
		(mid 351.594856 -229.73363)
		(end 351.480882 -229.600506)
		(width 0.1143)
		(layer "In11.Cu")
		(net "GMI_CPU1_G3_CPU0_G1_TX_DP<8>")
	)
	(arc
		(start 120.086628 -223.769936)
		(mid 120.329955 -224.234502)
		(end 120.086628 -224.699068)
		(width 0.1143)
		(layer "In11.Cu")
		(net "GMI_CPU1_G3_CPU0_G1_TX_DP<8>")
	)
	(arc
		(start 120.32996 -230.71455)
		(mid 120.370722 -230.884434)
		(end 120.484138 -231.017318)
		(width 0.1143)
		(layer "In11.Cu")
		(net "GMI_CPU1_G3_CPU0_G1_TX_DP<8>")
	)
	(arc
		(start 120.017032 -223.119696)
		(mid 119.860055 -223.424496)
		(end 120.017032 -223.729296)
		(width 0.1143)
		(layer "In11.Cu")
		(net "GMI_CPU1_G3_CPU0_G1_TX_DP<8>")
	)
	(arc
		(start 120.017032 -232.839514)
		(mid 119.919267 -232.94249)
		(end 119.866918 -233.074464)
		(width 0.1143)
		(layer "In11.Cu")
		(net "GMI_CPU1_G3_CPU0_G1_TX_DP<8>")
	)
	(arc
		(start 119.86006 -221.804484)
		(mid 119.901609 -221.975906)
		(end 120.017032 -222.109284)
		(width 0.1143)
		(layer "In11.Cu")
		(net "GMI_CPU1_G3_CPU0_G1_TX_DP<8>")
	)
	(arc
		(start 351.47885 -225.349054)
		(mid 351.635827 -225.044254)
		(end 351.47885 -224.739454)
		(width 0.1143)
		(layer "In11.Cu")
		(net "GMI_CPU1_G3_CPU0_G1_TX_DP<8>")
	)
	(arc
		(start 120.017032 -224.739708)
		(mid 119.860055 -225.044508)
		(end 120.017032 -225.349308)
		(width 0.1143)
		(layer "In11.Cu")
		(net "GMI_CPU1_G3_CPU0_G1_TX_DP<8>")
	)
	(arc
		(start 351.165922 -232.334054)
		(mid 351.124667 -232.163083)
		(end 351.009966 -232.029762)
		(width 0.1143)
		(layer "In11.Cu")
		(net "GMI_CPU1_G3_CPU0_G1_TX_DP<8>")
	)
	(arc
		(start 120.086628 -222.149924)
		(mid 120.329955 -222.61449)
		(end 120.086628 -223.079056)
		(width 0.1143)
		(layer "In11.Cu")
		(net "GMI_CPU1_G3_CPU0_G1_TX_DP<8>")
	)
	(arc
		(start 351.409254 -229.55885)
		(mid 351.165927 -229.094284)
		(end 351.409254 -228.629718)
		(width 0.1143)
		(layer "In11.Cu")
		(net "GMI_CPU1_G3_CPU0_G1_TX_DP<8>")
	)
	(arc
		(start 120.086628 -228.629972)
		(mid 120.329955 -229.094538)
		(end 120.086628 -229.559104)
		(width 0.1143)
		(layer "In11.Cu")
		(net "GMI_CPU1_G3_CPU0_G1_TX_DP<8>")
	)
	(arc
		(start 119.86006 -229.90429)
		(mid 119.901609 -230.075712)
		(end 120.017032 -230.20909)
		(width 0.1143)
		(layer "In11.Cu")
		(net "GMI_CPU1_G3_CPU0_G1_TX_DP<8>")
	)
	(arc
		(start 120.084088 -230.248206)
		(mid 120.26474 -230.450951)
		(end 120.32996 -230.71455)
		(width 0.1143)
		(layer "In11.Cu")
		(net "GMI_CPU1_G3_CPU0_G1_TX_DP<8>")
	)
	(arc
		(start 351.409254 -232.79862)
		(mid 351.230441 -232.59627)
		(end 351.165922 -232.334054)
		(width 0.1143)
		(layer "In11.Cu")
		(net "GMI_CPU1_G3_CPU0_G1_TX_DP<8>")
	)
	(arc
		(start 351.409254 -224.698814)
		(mid 351.165927 -224.234248)
		(end 351.409254 -223.769682)
		(width 0.1143)
		(layer "In11.Cu")
		(net "GMI_CPU1_G3_CPU0_G1_TX_DP<8>")
	)
	(arc
		(start 120.32996 -232.334308)
		(mid 120.265445 -232.596527)
		(end 120.086628 -232.798874)
		(width 0.1143)
		(layer "In11.Cu")
		(net "GMI_CPU1_G3_CPU0_G1_TX_DP<8>")
	)
	(arc
		(start 351.011744 -231.017064)
		(mid 351.125151 -230.884175)
		(end 351.165922 -230.714296)
		(width 0.1143)
		(layer "In11.Cu")
		(net "GMI_CPU1_G3_CPU0_G1_TX_DP<8>")
	)
	(arc
		(start 351.47885 -228.589078)
		(mid 351.635827 -228.284278)
		(end 351.47885 -227.979478)
		(width 0.1143)
		(layer "In11.Cu")
		(net "GMI_CPU1_G3_CPU0_G1_TX_DP<8>")
	)
	(arc
		(start 350.9391 -231.988614)
		(mid 350.695773 -231.524048)
		(end 350.9391 -231.059482)
		(width 0.1143)
		(layer "In11.Cu")
		(net "GMI_CPU1_G3_CPU0_G1_TX_DP<8>")
	)
	(arc
		(start 351.47885 -230.208836)
		(mid 351.594277 -230.07546)
		(end 351.635822 -229.904036)
		(width 0.1143)
		(layer "In11.Cu")
		(net "GMI_CPU1_G3_CPU0_G1_TX_DP<8>")
	)
	(arc
		(start 120.556782 -231.059736)
		(mid 120.800109 -231.524302)
		(end 120.556782 -231.988868)
		(width 0.1143)
		(layer "In11.Cu")
		(net "GMI_CPU1_G3_CPU0_G1_TX_DP<8>")
	)
	(arc
		(start 120.017032 -227.979732)
		(mid 119.860055 -228.284532)
		(end 120.017032 -228.589332)
		(width 0.1143)
		(layer "In11.Cu")
		(net "GMI_CPU1_G3_CPU0_G1_TX_DP<8>")
	)
	(arc
		(start 351.47885 -223.729042)
		(mid 351.635827 -223.424242)
		(end 351.47885 -223.119442)
		(width 0.1143)
		(layer "In11.Cu")
		(net "GMI_CPU1_G3_CPU0_G1_TX_DP<8>")
	)
	(arc
		(start 351.409254 -226.318826)
		(mid 351.165927 -225.85426)
		(end 351.409254 -225.389694)
		(width 0.1143)
		(layer "In11.Cu")
		(net "GMI_CPU1_G3_CPU0_G1_TX_DP<8>")
	)
	(arc
		(start 120.086628 -225.389948)
		(mid 120.329955 -225.854514)
		(end 120.086628 -226.31908)
		(width 0.1143)
		(layer "In11.Cu")
		(net "GMI_CPU1_G3_CPU0_G1_TX_DP<8>")
	)
	(arc
		(start 120.015 -229.60076)
		(mid 119.901071 -229.733907)
		(end 119.86006 -229.90429)
		(width 0.1143)
		(layer "In11.Cu")
		(net "GMI_CPU1_G3_CPU0_G1_TX_DP<8>")
	)
	(arc
		(start 351.47885 -222.10903)
		(mid 351.594277 -221.975654)
		(end 351.635822 -221.80423)
		(width 0.1143)
		(layer "In11.Cu")
		(net "GMI_CPU1_G3_CPU0_G1_TX_DP<8>")
	)
	(arc
		(start 351.165922 -230.714296)
		(mid 351.231158 -230.450705)
		(end 351.411794 -230.247952)
		(width 0.1143)
		(layer "In11.Cu")
		(net "GMI_CPU1_G3_CPU0_G1_TX_DP<8>")
	)
	(arc
		(start 120.086628 -227.00996)
		(mid 120.329955 -227.474526)
		(end 120.086628 -227.939092)
		(width 0.1143)
		(layer "In11.Cu")
		(net "GMI_CPU1_G3_CPU0_G1_TX_DP<8>")
	)
	(arc
		(start 351.409254 -227.938838)
		(mid 351.165927 -227.474272)
		(end 351.409254 -227.009706)
		(width 0.1143)
		(layer "In11.Cu")
		(net "GMI_CPU1_G3_CPU0_G1_TX_DP<8>")
	)
	(segment
		(start 351.728024 -231.789986)
		(end 351.261172 -231.524048)
		(width 0.12954)
		(layer "F.Cu")
		(net "GMI_CPU1_G3_CPU0_G1_TX_DP<7>")
	)
	(segment
		(start 119.767858 -231.79024)
		(end 120.23471 -231.524302)
		(width 0.12954)
		(layer "F.Cu")
		(net "GMI_CPU1_G3_CPU0_G1_TX_DP<7>")
	)
	(segment
		(start 352.403918 -226.977448)
		(end 352.387916 -226.9871)
		(width 0.1143)
		(layer "In11.Cu")
		(net "GMI_CPU1_G3_CPU0_G1_TX_DP<7>")
	)
	(segment
		(start 154.977084 -187.51169)
		(end 154.995118 -187.329318)
		(width 0.14224)
		(layer "In11.Cu")
		(net "GMI_CPU1_G3_CPU0_G1_TX_DP<7>")
	)
	(segment
		(start 153.804112 -188.473588)
		(end 154.12847 -188.20765)
		(width 0.14224)
		(layer "In11.Cu")
		(net "GMI_CPU1_G3_CPU0_G1_TX_DP<7>")
	)
	(segment
		(start 352.366834 -223.089216)
		(end 352.368612 -223.090232)
		(width 0.1143)
		(layer "In11.Cu")
		(net "GMI_CPU1_G3_CPU0_G1_TX_DP<7>")
	)
	(segment
		(start 119.146828 -225.389694)
		(end 119.107966 -225.367342)
		(width 0.1143)
		(layer "In11.Cu")
		(net "GMI_CPU1_G3_CPU0_G1_TX_DP<7>")
	)
	(segment
		(start 352.321368 -224.679002)
		(end 352.349054 -224.699068)
		(width 0.1143)
		(layer "In11.Cu")
		(net "GMI_CPU1_G3_CPU0_G1_TX_DP<7>")
	)
	(segment
		(start 352.38817 -228.606858)
		(end 352.351848 -228.62794)
		(width 0.1143)
		(layer "In11.Cu")
		(net "GMI_CPU1_G3_CPU0_G1_TX_DP<7>")
	)
	(segment
		(start 119.146828 -223.769682)
		(end 119.107966 -223.74733)
		(width 0.1143)
		(layer "In11.Cu")
		(net "GMI_CPU1_G3_CPU0_G1_TX_DP<7>")
	)
	(segment
		(start 352.403918 -225.357436)
		(end 352.387916 -225.367088)
		(width 0.1143)
		(layer "In11.Cu")
		(net "GMI_CPU1_G3_CPU0_G1_TX_DP<7>")
	)
	(segment
		(start 118.920006 -221.804484)
		(end 118.920006 -221.3864)
		(width 0.1143)
		(layer "In11.Cu")
		(net "GMI_CPU1_G3_CPU0_G1_TX_DP<7>")
	)
	(segment
		(start 352.387916 -226.9871)
		(end 352.349054 -227.009452)
		(width 0.1143)
		(layer "In11.Cu")
		(net "GMI_CPU1_G3_CPU0_G1_TX_DP<7>")
	)
	(segment
		(start 352.575876 -229.903782)
		(end 352.575876 -229.904036)
		(width 0.1143)
		(layer "In11.Cu")
		(net "GMI_CPU1_G3_CPU0_G1_TX_DP<7>")
	)
	(segment
		(start 155.843732 -186.633358)
		(end 160.294828 -182.983632)
		(width 0.14224)
		(layer "In11.Cu")
		(net "GMI_CPU1_G3_CPU0_G1_TX_DP<7>")
	)
	(segment
		(start 119.107458 -230.226616)
		(end 119.105934 -230.225854)
		(width 0.1143)
		(layer "In11.Cu")
		(net "GMI_CPU1_G3_CPU0_G1_TX_DP<7>")
	)
	(segment
		(start 119.075962 -227.98024)
		(end 119.146828 -227.939346)
		(width 0.1143)
		(layer "In11.Cu")
		(net "GMI_CPU1_G3_CPU0_G1_TX_DP<7>")
	)
	(segment
		(start 166.226744 -180.862478)
		(end 302.898048 -181.659276)
		(width 0.14224)
		(layer "In11.Cu")
		(net "GMI_CPU1_G3_CPU0_G1_TX_DP<7>")
	)
	(segment
		(start 315.24702 -185.883296)
		(end 349.628206 -214.074756)
		(width 0.14224)
		(layer "In11.Cu")
		(net "GMI_CPU1_G3_CPU0_G1_TX_DP<7>")
	)
	(segment
		(start 154.995118 -187.329318)
		(end 155.318968 -187.063634)
		(width 0.14224)
		(layer "In11.Cu")
		(net "GMI_CPU1_G3_CPU0_G1_TX_DP<7>")
	)
	(segment
		(start 349.628206 -214.074756)
		(end 352.569272 -219.028518)
		(width 0.14224)
		(layer "In11.Cu")
		(net "GMI_CPU1_G3_CPU0_G1_TX_DP<7>")
	)
	(segment
		(start 150.845012 -190.732664)
		(end 151.038052 -190.751714)
		(width 0.14224)
		(layer "In11.Cu")
		(net "GMI_CPU1_G3_CPU0_G1_TX_DP<7>")
	)
	(segment
		(start 352.569272 -221.083124)
		(end 352.614992 -221.128844)
		(width 0.1143)
		(layer "In11.Cu")
		(net "GMI_CPU1_G3_CPU0_G1_TX_DP<7>")
	)
	(segment
		(start 119.936768 -231.524302)
		(end 119.853964 -231.441498)
		(width 0.1143)
		(layer "In11.Cu")
		(net "GMI_CPU1_G3_CPU0_G1_TX_DP<7>")
	)
	(segment
		(start 119.107712 -228.607112)
		(end 119.075962 -228.588824)
		(width 0.1143)
		(layer "In11.Cu")
		(net "GMI_CPU1_G3_CPU0_G1_TX_DP<7>")
	)
	(segment
		(start 119.091964 -226.977702)
		(end 119.075962 -226.968558)
		(width 0.1143)
		(layer "In11.Cu")
		(net "GMI_CPU1_G3_CPU0_G1_TX_DP<7>")
	)
	(segment
		(start 352.387154 -230.227124)
		(end 352.386138 -230.227632)
		(width 0.1143)
		(layer "In11.Cu")
		(net "GMI_CPU1_G3_CPU0_G1_TX_DP<7>")
	)
	(segment
		(start 352.349054 -224.699068)
		(end 352.41992 -224.739962)
		(width 0.1143)
		(layer "In11.Cu")
		(net "GMI_CPU1_G3_CPU0_G1_TX_DP<7>")
	)
	(segment
		(start 352.569272 -219.028518)
		(end 352.569272 -221.071694)
		(width 0.14224)
		(layer "In11.Cu")
		(net "GMI_CPU1_G3_CPU0_G1_TX_DP<7>")
	)
	(segment
		(start 160.294828 -182.983632)
		(end 166.226744 -180.862478)
		(width 0.14224)
		(layer "In11.Cu")
		(net "GMI_CPU1_G3_CPU0_G1_TX_DP<7>")
	)
	(segment
		(start 352.351848 -229.560628)
		(end 352.421698 -229.601268)
		(width 0.1143)
		(layer "In11.Cu")
		(net "GMI_CPU1_G3_CPU0_G1_TX_DP<7>")
	)
	(segment
		(start 119.107966 -225.367342)
		(end 119.091964 -225.35769)
		(width 0.1143)
		(layer "In11.Cu")
		(net "GMI_CPU1_G3_CPU0_G1_TX_DP<7>")
	)
	(segment
		(start 307.21808 -181.659276)
		(end 308.75859 -182.210456)
		(width 0.14224)
		(layer "In11.Cu")
		(net "GMI_CPU1_G3_CPU0_G1_TX_DP<7>")
	)
	(segment
		(start 119.616728 -231.059736)
		(end 119.547894 -231.019858)
		(width 0.1143)
		(layer "In11.Cu")
		(net "GMI_CPU1_G3_CPU0_G1_TX_DP<7>")
	)
	(segment
		(start 150.515066 -191.003174)
		(end 150.845012 -190.732664)
		(width 0.14224)
		(layer "In11.Cu")
		(net "GMI_CPU1_G3_CPU0_G1_TX_DP<7>")
	)
	(segment
		(start 153.161492 -189.000638)
		(end 153.179526 -188.818266)
		(width 0.14224)
		(layer "In11.Cu")
		(net "GMI_CPU1_G3_CPU0_G1_TX_DP<7>")
	)
	(segment
		(start 155.50134 -187.081668)
		(end 155.825698 -186.81573)
		(width 0.14224)
		(layer "In11.Cu")
		(net "GMI_CPU1_G3_CPU0_G1_TX_DP<7>")
	)
	(segment
		(start 153.179526 -188.818266)
		(end 153.621994 -188.455554)
		(width 0.14224)
		(layer "In11.Cu")
		(net "GMI_CPU1_G3_CPU0_G1_TX_DP<7>")
	)
	(segment
		(start 119.108728 -230.227378)
		(end 119.107458 -230.226616)
		(width 0.1143)
		(layer "In11.Cu")
		(net "GMI_CPU1_G3_CPU0_G1_TX_DP<7>")
	)
	(segment
		(start 118.88089 -221.129098)
		(end 118.92661 -221.083378)
		(width 0.1143)
		(layer "In11.Cu")
		(net "GMI_CPU1_G3_CPU0_G1_TX_DP<7>")
	)
	(segment
		(start 151.038052 -190.751714)
		(end 151.368252 -190.48095)
		(width 0.14224)
		(layer "In11.Cu")
		(net "GMI_CPU1_G3_CPU0_G1_TX_DP<7>")
	)
	(segment
		(start 352.41992 -226.968304)
		(end 352.403918 -226.977448)
		(width 0.1143)
		(layer "In11.Cu")
		(net "GMI_CPU1_G3_CPU0_G1_TX_DP<7>")
	)
	(segment
		(start 119.174514 -225.40976)
		(end 119.146828 -225.389694)
		(width 0.1143)
		(layer "In11.Cu")
		(net "GMI_CPU1_G3_CPU0_G1_TX_DP<7>")
	)
	(segment
		(start 352.569272 -221.071694)
		(end 352.569272 -221.083124)
		(width 0.1143)
		(layer "In11.Cu")
		(net "GMI_CPU1_G3_CPU0_G1_TX_DP<7>")
	)
	(segment
		(start 119.146828 -226.319334)
		(end 119.174514 -226.299268)
		(width 0.1143)
		(layer "In11.Cu")
		(net "GMI_CPU1_G3_CPU0_G1_TX_DP<7>")
	)
	(segment
		(start 152.259538 -189.572646)
		(end 152.654762 -189.248542)
		(width 0.14224)
		(layer "In11.Cu")
		(net "GMI_CPU1_G3_CPU0_G1_TX_DP<7>")
	)
	(segment
		(start 119.12727 -223.090486)
		(end 119.129048 -223.08947)
		(width 0.1143)
		(layer "In11.Cu")
		(net "GMI_CPU1_G3_CPU0_G1_TX_DP<7>")
	)
	(segment
		(start 154.652726 -187.777628)
		(end 154.977084 -187.51169)
		(width 0.14224)
		(layer "In11.Cu")
		(net "GMI_CPU1_G3_CPU0_G1_TX_DP<7>")
	)
	(segment
		(start 119.146828 -224.699322)
		(end 119.174514 -224.679256)
		(width 0.1143)
		(layer "In11.Cu")
		(net "GMI_CPU1_G3_CPU0_G1_TX_DP<7>")
	)
	(segment
		(start 119.075962 -226.968558)
		(end 119.075962 -226.968812)
		(width 0.1143)
		(layer "In11.Cu")
		(net "GMI_CPU1_G3_CPU0_G1_TX_DP<7>")
	)
	(segment
		(start 145.12163 -195.42506)
		(end 149.10054 -192.162938)
		(width 0.14224)
		(layer "In11.Cu")
		(net "GMI_CPU1_G3_CPU0_G1_TX_DP<7>")
	)
	(segment
		(start 352.41992 -226.968558)
		(end 352.41992 -226.968304)
		(width 0.1143)
		(layer "In11.Cu")
		(net "GMI_CPU1_G3_CPU0_G1_TX_DP<7>")
	)
	(segment
		(start 121.87682 -214.089742)
		(end 144.357852 -195.656708)
		(width 0.14224)
		(layer "In11.Cu")
		(net "GMI_CPU1_G3_CPU0_G1_TX_DP<7>")
	)
	(segment
		(start 153.621994 -188.455554)
		(end 153.804112 -188.473588)
		(width 0.14224)
		(layer "In11.Cu")
		(net "GMI_CPU1_G3_CPU0_G1_TX_DP<7>")
	)
	(segment
		(start 154.470354 -187.759594)
		(end 154.652726 -187.777628)
		(width 0.14224)
		(layer "In11.Cu")
		(net "GMI_CPU1_G3_CPU0_G1_TX_DP<7>")
	)
	(segment
		(start 149.10054 -192.162938)
		(end 149.29358 -192.182242)
		(width 0.14224)
		(layer "In11.Cu")
		(net "GMI_CPU1_G3_CPU0_G1_TX_DP<7>")
	)
	(segment
		(start 352.403918 -223.737424)
		(end 352.387916 -223.747076)
		(width 0.1143)
		(layer "In11.Cu")
		(net "GMI_CPU1_G3_CPU0_G1_TX_DP<7>")
	)
	(segment
		(start 119.075962 -223.728534)
		(end 119.075962 -223.728788)
		(width 0.1143)
		(layer "In11.Cu")
		(net "GMI_CPU1_G3_CPU0_G1_TX_DP<7>")
	)
	(segment
		(start 154.146504 -188.025278)
		(end 154.470354 -187.759594)
		(width 0.14224)
		(layer "In11.Cu")
		(net "GMI_CPU1_G3_CPU0_G1_TX_DP<7>")
	)
	(segment
		(start 119.389906 -230.71455)
		(end 119.389906 -230.586026)
		(width 0.1143)
		(layer "In11.Cu")
		(net "GMI_CPU1_G3_CPU0_G1_TX_DP<7>")
	)
	(segment
		(start 352.41992 -222.108522)
		(end 352.366834 -222.139256)
		(width 0.1143)
		(layer "In11.Cu")
		(net "GMI_CPU1_G3_CPU0_G1_TX_DP<7>")
	)
	(segment
		(start 119.144034 -228.628194)
		(end 119.107712 -228.607112)
		(width 0.1143)
		(layer "In11.Cu")
		(net "GMI_CPU1_G3_CPU0_G1_TX_DP<7>")
	)
	(segment
		(start 155.318968 -187.063634)
		(end 155.50134 -187.081668)
		(width 0.14224)
		(layer "In11.Cu")
		(net "GMI_CPU1_G3_CPU0_G1_TX_DP<7>")
	)
	(segment
		(start 352.388424 -230.226362)
		(end 352.387154 -230.227124)
		(width 0.1143)
		(layer "In11.Cu")
		(net "GMI_CPU1_G3_CPU0_G1_TX_DP<7>")
	)
	(segment
		(start 302.898048 -181.659276)
		(end 307.21808 -181.659276)
		(width 0.14224)
		(layer "In11.Cu")
		(net "GMI_CPU1_G3_CPU0_G1_TX_DP<7>")
	)
	(segment
		(start 119.075962 -225.348546)
		(end 119.075962 -225.3488)
		(width 0.1143)
		(layer "In11.Cu")
		(net "GMI_CPU1_G3_CPU0_G1_TX_DP<7>")
	)
	(segment
		(start 352.369374 -223.09074)
		(end 352.38817 -223.101662)
		(width 0.1143)
		(layer "In11.Cu")
		(net "GMI_CPU1_G3_CPU0_G1_TX_DP<7>")
	)
	(segment
		(start 119.107966 -223.74733)
		(end 119.091964 -223.737678)
		(width 0.1143)
		(layer "In11.Cu")
		(net "GMI_CPU1_G3_CPU0_G1_TX_DP<7>")
	)
	(segment
		(start 152.837134 -189.266576)
		(end 153.161492 -189.000638)
		(width 0.14224)
		(layer "In11.Cu")
		(net "GMI_CPU1_G3_CPU0_G1_TX_DP<7>")
	)
	(segment
		(start 351.947988 -231.019604)
		(end 351.879154 -231.059482)
		(width 0.1143)
		(layer "In11.Cu")
		(net "GMI_CPU1_G3_CPU0_G1_TX_DP<7>")
	)
	(segment
		(start 352.387916 -225.367088)
		(end 352.349054 -225.38944)
		(width 0.1143)
		(layer "In11.Cu")
		(net "GMI_CPU1_G3_CPU0_G1_TX_DP<7>")
	)
	(segment
		(start 149.64283 -191.718438)
		(end 149.972776 -191.447928)
		(width 0.14224)
		(layer "In11.Cu")
		(net "GMI_CPU1_G3_CPU0_G1_TX_DP<7>")
	)
	(segment
		(start 119.146828 -227.939346)
		(end 119.174514 -227.91928)
		(width 0.1143)
		(layer "In11.Cu")
		(net "GMI_CPU1_G3_CPU0_G1_TX_DP<7>")
	)
	(segment
		(start 352.349054 -227.939092)
		(end 352.41992 -227.979986)
		(width 0.1143)
		(layer "In11.Cu")
		(net "GMI_CPU1_G3_CPU0_G1_TX_DP<7>")
	)
	(segment
		(start 352.38817 -223.101662)
		(end 352.41992 -223.11995)
		(width 0.1143)
		(layer "In11.Cu")
		(net "GMI_CPU1_G3_CPU0_G1_TX_DP<7>")
	)
	(segment
		(start 352.41992 -228.58857)
		(end 352.38817 -228.606858)
		(width 0.1143)
		(layer "In11.Cu")
		(net "GMI_CPU1_G3_CPU0_G1_TX_DP<7>")
	)
	(segment
		(start 352.321368 -227.919026)
		(end 352.349054 -227.939092)
		(width 0.1143)
		(layer "In11.Cu")
		(net "GMI_CPU1_G3_CPU0_G1_TX_DP<7>")
	)
	(segment
		(start 352.387916 -223.747076)
		(end 352.349054 -223.769428)
		(width 0.1143)
		(layer "In11.Cu")
		(net "GMI_CPU1_G3_CPU0_G1_TX_DP<7>")
	)
	(segment
		(start 352.41992 -225.348546)
		(end 352.41992 -225.348292)
		(width 0.1143)
		(layer "In11.Cu")
		(net "GMI_CPU1_G3_CPU0_G1_TX_DP<7>")
	)
	(segment
		(start 119.075962 -224.740216)
		(end 119.146828 -224.699322)
		(width 0.1143)
		(layer "In11.Cu")
		(net "GMI_CPU1_G3_CPU0_G1_TX_DP<7>")
	)
	(segment
		(start 351.559114 -231.524048)
		(end 351.261172 -231.524048)
		(width 0.1143)
		(layer "In11.Cu")
		(net "GMI_CPU1_G3_CPU0_G1_TX_DP<7>")
	)
	(segment
		(start 149.972776 -191.447928)
		(end 150.165816 -191.466978)
		(width 0.14224)
		(layer "In11.Cu")
		(net "GMI_CPU1_G3_CPU0_G1_TX_DP<7>")
	)
	(segment
		(start 352.349054 -227.009452)
		(end 352.321368 -227.029518)
		(width 0.1143)
		(layer "In11.Cu")
		(net "GMI_CPU1_G3_CPU0_G1_TX_DP<7>")
	)
	(segment
		(start 144.357852 -195.656708)
		(end 145.12163 -195.42506)
		(width 0.14224)
		(layer "In11.Cu")
		(net "GMI_CPU1_G3_CPU0_G1_TX_DP<7>")
	)
	(segment
		(start 351.641918 -231.441244)
		(end 351.559114 -231.524048)
		(width 0.1143)
		(layer "In11.Cu")
		(net "GMI_CPU1_G3_CPU0_G1_TX_DP<7>")
	)
	(segment
		(start 352.41992 -223.728534)
		(end 352.41992 -223.72828)
		(width 0.1143)
		(layer "In11.Cu")
		(net "GMI_CPU1_G3_CPU0_G1_TX_DP<7>")
	)
	(segment
		(start 352.389948 -230.2256)
		(end 352.388424 -230.226362)
		(width 0.1143)
		(layer "In11.Cu")
		(net "GMI_CPU1_G3_CPU0_G1_TX_DP<7>")
	)
	(segment
		(start 119.146828 -227.009706)
		(end 119.107966 -226.987354)
		(width 0.1143)
		(layer "In11.Cu")
		(net "GMI_CPU1_G3_CPU0_G1_TX_DP<7>")
	)
	(segment
		(start 118.92661 -221.071948)
		(end 118.92661 -219.131134)
		(width 0.14224)
		(layer "In11.Cu")
		(net "GMI_CPU1_G3_CPU0_G1_TX_DP<7>")
	)
	(segment
		(start 119.107712 -223.101916)
		(end 119.126508 -223.090994)
		(width 0.1143)
		(layer "In11.Cu")
		(net "GMI_CPU1_G3_CPU0_G1_TX_DP<7>")
	)
	(segment
		(start 151.368252 -190.48095)
		(end 151.387302 -190.28791)
		(width 0.14224)
		(layer "In11.Cu")
		(net "GMI_CPU1_G3_CPU0_G1_TX_DP<7>")
	)
	(segment
		(start 150.165816 -191.466978)
		(end 150.496016 -191.196214)
		(width 0.14224)
		(layer "In11.Cu")
		(net "GMI_CPU1_G3_CPU0_G1_TX_DP<7>")
	)
	(segment
		(start 119.074184 -229.601522)
		(end 119.144034 -229.560882)
		(width 0.1143)
		(layer "In11.Cu")
		(net "GMI_CPU1_G3_CPU0_G1_TX_DP<7>")
	)
	(segment
		(start 151.717248 -190.0174)
		(end 151.910288 -190.03645)
		(width 0.14224)
		(layer "In11.Cu")
		(net "GMI_CPU1_G3_CPU0_G1_TX_DP<7>")
	)
	(segment
		(start 352.105976 -230.585772)
		(end 352.105976 -230.714296)
		(width 0.1143)
		(layer "In11.Cu")
		(net "GMI_CPU1_G3_CPU0_G1_TX_DP<7>")
	)
	(segment
		(start 118.92661 -221.083378)
		(end 118.92661 -221.071948)
		(width 0.1143)
		(layer "In11.Cu")
		(net "GMI_CPU1_G3_CPU0_G1_TX_DP<7>")
	)
	(segment
		(start 118.88089 -221.347284)
		(end 118.88089 -221.129098)
		(width 0.1143)
		(layer "In11.Cu")
		(net "GMI_CPU1_G3_CPU0_G1_TX_DP<7>")
	)
	(segment
		(start 118.920006 -229.90429)
		(end 118.920006 -229.904036)
		(width 0.1143)
		(layer "In11.Cu")
		(net "GMI_CPU1_G3_CPU0_G1_TX_DP<7>")
	)
	(segment
		(start 352.321368 -226.299014)
		(end 352.349054 -226.31908)
		(width 0.1143)
		(layer "In11.Cu")
		(net "GMI_CPU1_G3_CPU0_G1_TX_DP<7>")
	)
	(segment
		(start 152.654762 -189.248542)
		(end 152.837134 -189.266576)
		(width 0.14224)
		(layer "In11.Cu")
		(net "GMI_CPU1_G3_CPU0_G1_TX_DP<7>")
	)
	(segment
		(start 352.575876 -221.386146)
		(end 352.575876 -221.80423)
		(width 0.1143)
		(layer "In11.Cu")
		(net "GMI_CPU1_G3_CPU0_G1_TX_DP<7>")
	)
	(segment
		(start 151.910288 -190.03645)
		(end 152.240488 -189.765686)
		(width 0.14224)
		(layer "In11.Cu")
		(net "GMI_CPU1_G3_CPU0_G1_TX_DP<7>")
	)
	(segment
		(start 119.147336 -230.250238)
		(end 119.108728 -230.227378)
		(width 0.1143)
		(layer "In11.Cu")
		(net "GMI_CPU1_G3_CPU0_G1_TX_DP<7>")
	)
	(segment
		(start 150.496016 -191.196214)
		(end 150.515066 -191.003174)
		(width 0.14224)
		(layer "In11.Cu")
		(net "GMI_CPU1_G3_CPU0_G1_TX_DP<7>")
	)
	(segment
		(start 352.614992 -221.34703)
		(end 352.575876 -221.386146)
		(width 0.1143)
		(layer "In11.Cu")
		(net "GMI_CPU1_G3_CPU0_G1_TX_DP<7>")
	)
	(segment
		(start 149.62378 -191.911478)
		(end 149.64283 -191.718438)
		(width 0.14224)
		(layer "In11.Cu")
		(net "GMI_CPU1_G3_CPU0_G1_TX_DP<7>")
	)
	(segment
		(start 352.349054 -226.31908)
		(end 352.41992 -226.359974)
		(width 0.1143)
		(layer "In11.Cu")
		(net "GMI_CPU1_G3_CPU0_G1_TX_DP<7>")
	)
	(segment
		(start 352.349054 -223.769428)
		(end 352.321368 -223.789494)
		(width 0.1143)
		(layer "In11.Cu")
		(net "GMI_CPU1_G3_CPU0_G1_TX_DP<7>")
	)
	(segment
		(start 119.075962 -226.360228)
		(end 119.146828 -226.319334)
		(width 0.1143)
		(layer "In11.Cu")
		(net "GMI_CPU1_G3_CPU0_G1_TX_DP<7>")
	)
	(segment
		(start 352.349054 -225.38944)
		(end 352.321368 -225.409506)
		(width 0.1143)
		(layer "In11.Cu")
		(net "GMI_CPU1_G3_CPU0_G1_TX_DP<7>")
	)
	(segment
		(start 352.368612 -223.090232)
		(end 352.369374 -223.09074)
		(width 0.1143)
		(layer "In11.Cu")
		(net "GMI_CPU1_G3_CPU0_G1_TX_DP<7>")
	)
	(segment
		(start 119.174514 -227.029772)
		(end 119.146828 -227.009706)
		(width 0.1143)
		(layer "In11.Cu")
		(net "GMI_CPU1_G3_CPU0_G1_TX_DP<7>")
	)
	(segment
		(start 118.920006 -221.3864)
		(end 118.88089 -221.347284)
		(width 0.1143)
		(layer "In11.Cu")
		(net "GMI_CPU1_G3_CPU0_G1_TX_DP<7>")
	)
	(segment
		(start 154.12847 -188.20765)
		(end 154.146504 -188.025278)
		(width 0.14224)
		(layer "In11.Cu")
		(net "GMI_CPU1_G3_CPU0_G1_TX_DP<7>")
	)
	(segment
		(start 120.23471 -231.524302)
		(end 119.936768 -231.524302)
		(width 0.1143)
		(layer "In11.Cu")
		(net "GMI_CPU1_G3_CPU0_G1_TX_DP<7>")
	)
	(segment
		(start 352.614992 -221.128844)
		(end 352.614992 -221.34703)
		(width 0.1143)
		(layer "In11.Cu")
		(net "GMI_CPU1_G3_CPU0_G1_TX_DP<7>")
	)
	(segment
		(start 352.41992 -223.72828)
		(end 352.403918 -223.737424)
		(width 0.1143)
		(layer "In11.Cu")
		(net "GMI_CPU1_G3_CPU0_G1_TX_DP<7>")
	)
	(segment
		(start 308.75859 -182.210456)
		(end 315.24702 -185.883296)
		(width 0.14224)
		(layer "In11.Cu")
		(net "GMI_CPU1_G3_CPU0_G1_TX_DP<7>")
	)
	(segment
		(start 119.091964 -223.737678)
		(end 119.075962 -223.728534)
		(width 0.1143)
		(layer "In11.Cu")
		(net "GMI_CPU1_G3_CPU0_G1_TX_DP<7>")
	)
	(segment
		(start 119.129048 -222.13951)
		(end 119.075962 -222.108776)
		(width 0.1143)
		(layer "In11.Cu")
		(net "GMI_CPU1_G3_CPU0_G1_TX_DP<7>")
	)
	(segment
		(start 119.091964 -225.35769)
		(end 119.075962 -225.348546)
		(width 0.1143)
		(layer "In11.Cu")
		(net "GMI_CPU1_G3_CPU0_G1_TX_DP<7>")
	)
	(segment
		(start 155.825698 -186.81573)
		(end 155.843732 -186.633358)
		(width 0.14224)
		(layer "In11.Cu")
		(net "GMI_CPU1_G3_CPU0_G1_TX_DP<7>")
	)
	(segment
		(start 352.348546 -230.249984)
		(end 352.236786 -230.330502)
		(width 0.1143)
		(layer "In11.Cu")
		(net "GMI_CPU1_G3_CPU0_G1_TX_DP<7>")
	)
	(segment
		(start 152.240488 -189.765686)
		(end 152.259538 -189.572646)
		(width 0.14224)
		(layer "In11.Cu")
		(net "GMI_CPU1_G3_CPU0_G1_TX_DP<7>")
	)
	(segment
		(start 151.387302 -190.28791)
		(end 151.717248 -190.0174)
		(width 0.14224)
		(layer "In11.Cu")
		(net "GMI_CPU1_G3_CPU0_G1_TX_DP<7>")
	)
	(segment
		(start 352.41992 -225.348292)
		(end 352.403918 -225.357436)
		(width 0.1143)
		(layer "In11.Cu")
		(net "GMI_CPU1_G3_CPU0_G1_TX_DP<7>")
	)
	(segment
		(start 352.386138 -230.227632)
		(end 352.348546 -230.249984)
		(width 0.1143)
		(layer "In11.Cu")
		(net "GMI_CPU1_G3_CPU0_G1_TX_DP<7>")
	)
	(segment
		(start 119.107966 -226.987354)
		(end 119.091964 -226.977702)
		(width 0.1143)
		(layer "In11.Cu")
		(net "GMI_CPU1_G3_CPU0_G1_TX_DP<7>")
	)
	(segment
		(start 119.075962 -223.120204)
		(end 119.107712 -223.101916)
		(width 0.1143)
		(layer "In11.Cu")
		(net "GMI_CPU1_G3_CPU0_G1_TX_DP<7>")
	)
	(segment
		(start 119.174514 -223.789748)
		(end 119.146828 -223.769682)
		(width 0.1143)
		(layer "In11.Cu")
		(net "GMI_CPU1_G3_CPU0_G1_TX_DP<7>")
	)
	(segment
		(start 149.29358 -192.182242)
		(end 149.62378 -191.911478)
		(width 0.14224)
		(layer "In11.Cu")
		(net "GMI_CPU1_G3_CPU0_G1_TX_DP<7>")
	)
	(segment
		(start 118.92661 -219.131134)
		(end 121.87682 -214.089742)
		(width 0.14224)
		(layer "In11.Cu")
		(net "GMI_CPU1_G3_CPU0_G1_TX_DP<7>")
	)
	(segment
		(start 119.259096 -230.330756)
		(end 119.147336 -230.250238)
		(width 0.1143)
		(layer "In11.Cu")
		(net "GMI_CPU1_G3_CPU0_G1_TX_DP<7>")
	)
	(segment
		(start 119.126508 -223.090994)
		(end 119.12727 -223.090486)
		(width 0.1143)
		(layer "In11.Cu")
		(net "GMI_CPU1_G3_CPU0_G1_TX_DP<7>")
	)
	(arc
		(start 352.321368 -227.029518)
		(mid 352.093368 -227.474272)
		(end 352.321368 -227.919026)
		(width 0.1143)
		(layer "In11.Cu")
		(net "GMI_CPU1_G3_CPU0_G1_TX_DP<7>")
	)
	(arc
		(start 352.41992 -226.359974)
		(mid 352.575848 -226.664266)
		(end 352.41992 -226.968558)
		(width 0.1143)
		(layer "In11.Cu")
		(net "GMI_CPU1_G3_CPU0_G1_TX_DP<7>")
	)
	(arc
		(start 119.105934 -230.225854)
		(mid 118.969853 -230.090006)
		(end 118.920006 -229.90429)
		(width 0.1143)
		(layer "In11.Cu")
		(net "GMI_CPU1_G3_CPU0_G1_TX_DP<7>")
	)
	(arc
		(start 119.547894 -231.019858)
		(mid 119.431847 -230.886387)
		(end 119.389906 -230.71455)
		(width 0.1143)
		(layer "In11.Cu")
		(net "GMI_CPU1_G3_CPU0_G1_TX_DP<7>")
	)
	(arc
		(start 352.41992 -227.979986)
		(mid 352.575848 -228.284278)
		(end 352.41992 -228.58857)
		(width 0.1143)
		(layer "In11.Cu")
		(net "GMI_CPU1_G3_CPU0_G1_TX_DP<7>")
	)
	(arc
		(start 352.41992 -223.11995)
		(mid 352.575848 -223.424242)
		(end 352.41992 -223.728534)
		(width 0.1143)
		(layer "In11.Cu")
		(net "GMI_CPU1_G3_CPU0_G1_TX_DP<7>")
	)
	(arc
		(start 119.850154 -231.418638)
		(mid 119.768721 -231.21624)
		(end 119.616728 -231.059736)
		(width 0.1143)
		(layer "In11.Cu")
		(net "GMI_CPU1_G3_CPU0_G1_TX_DP<7>")
	)
	(arc
		(start 119.389906 -230.586026)
		(mid 119.355297 -230.442611)
		(end 119.259096 -230.330756)
		(width 0.1143)
		(layer "In11.Cu")
		(net "GMI_CPU1_G3_CPU0_G1_TX_DP<7>")
	)
	(arc
		(start 119.853964 -231.441498)
		(mid 119.852176 -231.430049)
		(end 119.850154 -231.418638)
		(width 0.1143)
		(layer "In11.Cu")
		(net "GMI_CPU1_G3_CPU0_G1_TX_DP<7>")
	)
	(arc
		(start 352.575876 -221.80423)
		(mid 352.534621 -221.975201)
		(end 352.41992 -222.108522)
		(width 0.1143)
		(layer "In11.Cu")
		(net "GMI_CPU1_G3_CPU0_G1_TX_DP<7>")
	)
	(arc
		(start 118.920006 -229.904036)
		(mid 118.960825 -229.734293)
		(end 119.074184 -229.601522)
		(width 0.1143)
		(layer "In11.Cu")
		(net "GMI_CPU1_G3_CPU0_G1_TX_DP<7>")
	)
	(arc
		(start 119.129048 -223.08947)
		(mid 119.402599 -222.61449)
		(end 119.129048 -222.13951)
		(width 0.1143)
		(layer "In11.Cu")
		(net "GMI_CPU1_G3_CPU0_G1_TX_DP<7>")
	)
	(arc
		(start 352.366834 -222.139256)
		(mid 352.093283 -222.614236)
		(end 352.366834 -223.089216)
		(width 0.1143)
		(layer "In11.Cu")
		(net "GMI_CPU1_G3_CPU0_G1_TX_DP<7>")
	)
	(arc
		(start 119.075962 -228.588824)
		(mid 118.920034 -228.284532)
		(end 119.075962 -227.98024)
		(width 0.1143)
		(layer "In11.Cu")
		(net "GMI_CPU1_G3_CPU0_G1_TX_DP<7>")
	)
	(arc
		(start 351.879154 -231.059482)
		(mid 351.727167 -231.21599)
		(end 351.645728 -231.418384)
		(width 0.1143)
		(layer "In11.Cu")
		(net "GMI_CPU1_G3_CPU0_G1_TX_DP<7>")
	)
	(arc
		(start 119.174514 -224.679256)
		(mid 119.402514 -224.234502)
		(end 119.174514 -223.789748)
		(width 0.1143)
		(layer "In11.Cu")
		(net "GMI_CPU1_G3_CPU0_G1_TX_DP<7>")
	)
	(arc
		(start 119.174514 -227.91928)
		(mid 119.402514 -227.474526)
		(end 119.174514 -227.029772)
		(width 0.1143)
		(layer "In11.Cu")
		(net "GMI_CPU1_G3_CPU0_G1_TX_DP<7>")
	)
	(arc
		(start 119.144034 -229.560882)
		(mid 119.325925 -229.355775)
		(end 119.389906 -229.089204)
		(width 0.1143)
		(layer "In11.Cu")
		(net "GMI_CPU1_G3_CPU0_G1_TX_DP<7>")
	)
	(arc
		(start 352.105976 -230.714296)
		(mid 352.064097 -230.886165)
		(end 351.947988 -231.019604)
		(width 0.1143)
		(layer "In11.Cu")
		(net "GMI_CPU1_G3_CPU0_G1_TX_DP<7>")
	)
	(arc
		(start 352.321368 -223.789494)
		(mid 352.093368 -224.234248)
		(end 352.321368 -224.679002)
		(width 0.1143)
		(layer "In11.Cu")
		(net "GMI_CPU1_G3_CPU0_G1_TX_DP<7>")
	)
	(arc
		(start 352.236786 -230.330502)
		(mid 352.140575 -230.442352)
		(end 352.105976 -230.585772)
		(width 0.1143)
		(layer "In11.Cu")
		(net "GMI_CPU1_G3_CPU0_G1_TX_DP<7>")
	)
	(arc
		(start 119.159274 -228.638862)
		(mid 119.151698 -228.633466)
		(end 119.144034 -228.628194)
		(width 0.1143)
		(layer "In11.Cu")
		(net "GMI_CPU1_G3_CPU0_G1_TX_DP<7>")
	)
	(arc
		(start 352.575876 -229.904036)
		(mid 352.526053 -230.089766)
		(end 352.389948 -230.2256)
		(width 0.1143)
		(layer "In11.Cu")
		(net "GMI_CPU1_G3_CPU0_G1_TX_DP<7>")
	)
	(arc
		(start 119.075962 -222.108776)
		(mid 118.961286 -221.975442)
		(end 118.920006 -221.804484)
		(width 0.1143)
		(layer "In11.Cu")
		(net "GMI_CPU1_G3_CPU0_G1_TX_DP<7>")
	)
	(arc
		(start 352.105976 -229.08895)
		(mid 352.169951 -229.355525)
		(end 352.351848 -229.560628)
		(width 0.1143)
		(layer "In11.Cu")
		(net "GMI_CPU1_G3_CPU0_G1_TX_DP<7>")
	)
	(arc
		(start 119.075962 -223.728788)
		(mid 118.920034 -223.424496)
		(end 119.075962 -223.120204)
		(width 0.1143)
		(layer "In11.Cu")
		(net "GMI_CPU1_G3_CPU0_G1_TX_DP<7>")
	)
	(arc
		(start 351.645728 -231.418384)
		(mid 351.643705 -231.429794)
		(end 351.641918 -231.441244)
		(width 0.1143)
		(layer "In11.Cu")
		(net "GMI_CPU1_G3_CPU0_G1_TX_DP<7>")
	)
	(arc
		(start 352.336608 -228.638608)
		(mid 352.170363 -228.837708)
		(end 352.105976 -229.08895)
		(width 0.1143)
		(layer "In11.Cu")
		(net "GMI_CPU1_G3_CPU0_G1_TX_DP<7>")
	)
	(arc
		(start 119.174514 -226.299268)
		(mid 119.402514 -225.854514)
		(end 119.174514 -225.40976)
		(width 0.1143)
		(layer "In11.Cu")
		(net "GMI_CPU1_G3_CPU0_G1_TX_DP<7>")
	)
	(arc
		(start 119.075962 -225.3488)
		(mid 118.920034 -225.044508)
		(end 119.075962 -224.740216)
		(width 0.1143)
		(layer "In11.Cu")
		(net "GMI_CPU1_G3_CPU0_G1_TX_DP<7>")
	)
	(arc
		(start 352.351848 -228.62794)
		(mid 352.344184 -228.633211)
		(end 352.336608 -228.638608)
		(width 0.1143)
		(layer "In11.Cu")
		(net "GMI_CPU1_G3_CPU0_G1_TX_DP<7>")
	)
	(arc
		(start 119.389906 -229.089204)
		(mid 119.325444 -228.838)
		(end 119.159274 -228.638862)
		(width 0.1143)
		(layer "In11.Cu")
		(net "GMI_CPU1_G3_CPU0_G1_TX_DP<7>")
	)
	(arc
		(start 352.41992 -224.739962)
		(mid 352.575848 -225.044254)
		(end 352.41992 -225.348546)
		(width 0.1143)
		(layer "In11.Cu")
		(net "GMI_CPU1_G3_CPU0_G1_TX_DP<7>")
	)
	(arc
		(start 352.321368 -225.409506)
		(mid 352.093368 -225.85426)
		(end 352.321368 -226.299014)
		(width 0.1143)
		(layer "In11.Cu")
		(net "GMI_CPU1_G3_CPU0_G1_TX_DP<7>")
	)
	(arc
		(start 119.075962 -226.968812)
		(mid 118.920034 -226.66452)
		(end 119.075962 -226.360228)
		(width 0.1143)
		(layer "In11.Cu")
		(net "GMI_CPU1_G3_CPU0_G1_TX_DP<7>")
	)
	(arc
		(start 352.421698 -229.601268)
		(mid 352.535047 -229.734043)
		(end 352.575876 -229.903782)
		(width 0.1143)
		(layer "In11.Cu")
		(net "GMI_CPU1_G3_CPU0_G1_TX_DP<7>")
	)
	(segment
		(start 119.767858 -235.030264)
		(end 120.23471 -234.764326)
		(width 0.12954)
		(layer "F.Cu")
		(net "GMI_CPU1_G3_CPU0_G1_TX_DP<6>")
	)
	(segment
		(start 351.728024 -235.03001)
		(end 351.261172 -234.764072)
		(width 0.12954)
		(layer "F.Cu")
		(net "GMI_CPU1_G3_CPU0_G1_TX_DP<6>")
	)
	(segment
		(start 117.98173 -218.864434)
		(end 121.124726 -213.500208)
		(width 0.14224)
		(layer "In11.Cu")
		(net "GMI_CPU1_G3_CPU0_G1_TX_DP<6>")
	)
	(segment
		(start 353.559872 -221.128844)
		(end 353.559872 -221.34703)
		(width 0.1143)
		(layer "In11.Cu")
		(net "GMI_CPU1_G3_CPU0_G1_TX_DP<6>")
	)
	(segment
		(start 154.994356 -185.93943)
		(end 159.441896 -182.292244)
		(width 0.14224)
		(layer "In11.Cu")
		(net "GMI_CPU1_G3_CPU0_G1_TX_DP<6>")
	)
	(segment
		(start 118.167658 -228.607112)
		(end 118.137178 -228.589332)
		(width 0.1143)
		(layer "In11.Cu")
		(net "GMI_CPU1_G3_CPU0_G1_TX_DP<6>")
	)
	(segment
		(start 149.954996 -190.071756)
		(end 150.148036 -190.090806)
		(width 0.14224)
		(layer "In11.Cu")
		(net "GMI_CPU1_G3_CPU0_G1_TX_DP<6>")
	)
	(segment
		(start 149.2758 -190.80607)
		(end 149.606 -190.535306)
		(width 0.14224)
		(layer "In11.Cu")
		(net "GMI_CPU1_G3_CPU0_G1_TX_DP<6>")
	)
	(segment
		(start 352.395028 -233.462576)
		(end 352.390964 -233.464862)
		(width 0.1143)
		(layer "In11.Cu")
		(net "GMI_CPU1_G3_CPU0_G1_TX_DP<6>")
	)
	(segment
		(start 121.124726 -213.500208)
		(end 144.000982 -194.743324)
		(width 0.14224)
		(layer "In11.Cu")
		(net "GMI_CPU1_G3_CPU0_G1_TX_DP<6>")
	)
	(segment
		(start 353.514152 -221.071694)
		(end 353.514152 -221.083124)
		(width 0.1143)
		(layer "In11.Cu")
		(net "GMI_CPU1_G3_CPU0_G1_TX_DP<6>")
	)
	(segment
		(start 154.975306 -186.13247)
		(end 154.994356 -185.93943)
		(width 0.14224)
		(layer "In11.Cu")
		(net "GMI_CPU1_G3_CPU0_G1_TX_DP<6>")
	)
	(segment
		(start 353.514152 -218.79306)
		(end 353.514152 -221.071694)
		(width 0.14224)
		(layer "In11.Cu")
		(net "GMI_CPU1_G3_CPU0_G1_TX_DP<6>")
	)
	(segment
		(start 154.10307 -186.847734)
		(end 154.12212 -186.654694)
		(width 0.14224)
		(layer "In11.Cu")
		(net "GMI_CPU1_G3_CPU0_G1_TX_DP<6>")
	)
	(segment
		(start 119.616728 -234.29976)
		(end 119.577612 -234.2769)
		(width 0.1143)
		(layer "In11.Cu")
		(net "GMI_CPU1_G3_CPU0_G1_TX_DP<6>")
	)
	(segment
		(start 118.206774 -227.00996)
		(end 118.167658 -226.9871)
		(width 0.1143)
		(layer "In11.Cu")
		(net "GMI_CPU1_G3_CPU0_G1_TX_DP<6>")
	)
	(segment
		(start 148.210524 -191.502284)
		(end 148.403564 -191.521334)
		(width 0.14224)
		(layer "In11.Cu")
		(net "GMI_CPU1_G3_CPU0_G1_TX_DP<6>")
	)
	(segment
		(start 302.901096 -180.711348)
		(end 307.388006 -180.711348)
		(width 0.14224)
		(layer "In11.Cu")
		(net "GMI_CPU1_G3_CPU0_G1_TX_DP<6>")
	)
	(segment
		(start 352.38563 -233.468164)
		(end 352.349054 -233.4895)
		(width 0.1143)
		(layer "In11.Cu")
		(net "GMI_CPU1_G3_CPU0_G1_TX_DP<6>")
	)
	(segment
		(start 353.328224 -229.58171)
		(end 353.360736 -229.600506)
		(width 0.1143)
		(layer "In11.Cu")
		(net "GMI_CPU1_G3_CPU0_G1_TX_DP<6>")
	)
	(segment
		(start 119.107712 -233.466894)
		(end 119.10695 -233.466386)
		(width 0.1143)
		(layer "In11.Cu")
		(net "GMI_CPU1_G3_CPU0_G1_TX_DP<6>")
	)
	(segment
		(start 118.167658 -222.127064)
		(end 118.137178 -222.109284)
		(width 0.1143)
		(layer "In11.Cu")
		(net "GMI_CPU1_G3_CPU0_G1_TX_DP<6>")
	)
	(segment
		(start 352.891598 -231.017064)
		(end 352.85807 -231.036622)
		(width 0.1143)
		(layer "In11.Cu")
		(net "GMI_CPU1_G3_CPU0_G1_TX_DP<6>")
	)
	(segment
		(start 118.206774 -225.389948)
		(end 118.167658 -225.367088)
		(width 0.1143)
		(layer "In11.Cu")
		(net "GMI_CPU1_G3_CPU0_G1_TX_DP<6>")
	)
	(segment
		(start 118.167658 -224.721928)
		(end 118.206774 -224.699068)
		(width 0.1143)
		(layer "In11.Cu")
		(net "GMI_CPU1_G3_CPU0_G1_TX_DP<6>")
	)
	(segment
		(start 119.10695 -233.466386)
		(end 119.104918 -233.465116)
		(width 0.1143)
		(layer "In11.Cu")
		(net "GMI_CPU1_G3_CPU0_G1_TX_DP<6>")
	)
	(segment
		(start 353.358704 -223.729042)
		(end 353.289108 -223.769682)
		(width 0.1143)
		(layer "In11.Cu")
		(net "GMI_CPU1_G3_CPU0_G1_TX_DP<6>")
	)
	(segment
		(start 148.733764 -191.25057)
		(end 148.752814 -191.05753)
		(width 0.14224)
		(layer "In11.Cu")
		(net "GMI_CPU1_G3_CPU0_G1_TX_DP<6>")
	)
	(segment
		(start 353.289108 -224.698814)
		(end 353.358704 -224.739454)
		(width 0.1143)
		(layer "In11.Cu")
		(net "GMI_CPU1_G3_CPU0_G1_TX_DP<6>")
	)
	(segment
		(start 352.85807 -232.011474)
		(end 352.859086 -232.011982)
		(width 0.1143)
		(layer "In11.Cu")
		(net "GMI_CPU1_G3_CPU0_G1_TX_DP<6>")
	)
	(segment
		(start 309.41137 -181.434486)
		(end 315.531246 -184.898792)
		(width 0.14224)
		(layer "In11.Cu")
		(net "GMI_CPU1_G3_CPU0_G1_TX_DP<6>")
	)
	(segment
		(start 117.98173 -221.071948)
		(end 117.98173 -218.864434)
		(width 0.14224)
		(layer "In11.Cu")
		(net "GMI_CPU1_G3_CPU0_G1_TX_DP<6>")
	)
	(segment
		(start 151.892508 -188.660278)
		(end 152.222708 -188.389514)
		(width 0.14224)
		(layer "In11.Cu")
		(net "GMI_CPU1_G3_CPU0_G1_TX_DP<6>")
	)
	(segment
		(start 151.020272 -189.375542)
		(end 151.350472 -189.104778)
		(width 0.14224)
		(layer "In11.Cu")
		(net "GMI_CPU1_G3_CPU0_G1_TX_DP<6>")
	)
	(segment
		(start 159.441896 -182.292244)
		(end 166.093648 -179.913534)
		(width 0.14224)
		(layer "In11.Cu")
		(net "GMI_CPU1_G3_CPU0_G1_TX_DP<6>")
	)
	(segment
		(start 153.094944 -187.67425)
		(end 153.113994 -187.48121)
		(width 0.14224)
		(layer "In11.Cu")
		(net "GMI_CPU1_G3_CPU0_G1_TX_DP<6>")
	)
	(segment
		(start 150.148036 -190.090806)
		(end 150.478236 -189.820042)
		(width 0.14224)
		(layer "In11.Cu")
		(net "GMI_CPU1_G3_CPU0_G1_TX_DP<6>")
	)
	(segment
		(start 353.358704 -225.349054)
		(end 353.289108 -225.389694)
		(width 0.1143)
		(layer "In11.Cu")
		(net "GMI_CPU1_G3_CPU0_G1_TX_DP<6>")
	)
	(segment
		(start 353.289108 -226.318826)
		(end 353.358704 -226.359466)
		(width 0.1143)
		(layer "In11.Cu")
		(net "GMI_CPU1_G3_CPU0_G1_TX_DP<6>")
	)
	(segment
		(start 118.931944 -233.17835)
		(end 118.931944 -233.15295)
		(width 0.1143)
		(layer "In11.Cu")
		(net "GMI_CPU1_G3_CPU0_G1_TX_DP<6>")
	)
	(segment
		(start 152.241758 -188.196474)
		(end 152.571704 -187.925964)
		(width 0.14224)
		(layer "In11.Cu")
		(net "GMI_CPU1_G3_CPU0_G1_TX_DP<6>")
	)
	(segment
		(start 352.890582 -232.637584)
		(end 352.84537 -232.663746)
		(width 0.1143)
		(layer "In11.Cu")
		(net "GMI_CPU1_G3_CPU0_G1_TX_DP<6>")
	)
	(segment
		(start 118.167658 -223.747076)
		(end 118.137178 -223.729296)
		(width 0.1143)
		(layer "In11.Cu")
		(net "GMI_CPU1_G3_CPU0_G1_TX_DP<6>")
	)
	(segment
		(start 149.08276 -190.78702)
		(end 149.2758 -190.80607)
		(width 0.14224)
		(layer "In11.Cu")
		(net "GMI_CPU1_G3_CPU0_G1_TX_DP<6>")
	)
	(segment
		(start 353.515676 -221.391226)
		(end 353.515676 -221.80423)
		(width 0.1143)
		(layer "In11.Cu")
		(net "GMI_CPU1_G3_CPU0_G1_TX_DP<6>")
	)
	(segment
		(start 117.98173 -221.083378)
		(end 117.98173 -221.071948)
		(width 0.1143)
		(layer "In11.Cu")
		(net "GMI_CPU1_G3_CPU0_G1_TX_DP<6>")
	)
	(segment
		(start 118.206774 -222.149924)
		(end 118.167658 -222.127064)
		(width 0.1143)
		(layer "In11.Cu")
		(net "GMI_CPU1_G3_CPU0_G1_TX_DP<6>")
	)
	(segment
		(start 352.38817 -233.46664)
		(end 352.387154 -233.467148)
		(width 0.1143)
		(layer "In11.Cu")
		(net "GMI_CPU1_G3_CPU0_G1_TX_DP<6>")
	)
	(segment
		(start 151.699468 -188.641228)
		(end 151.892508 -188.660278)
		(width 0.14224)
		(layer "In11.Cu")
		(net "GMI_CPU1_G3_CPU0_G1_TX_DP<6>")
	)
	(segment
		(start 149.62505 -190.342266)
		(end 149.954996 -190.071756)
		(width 0.14224)
		(layer "In11.Cu")
		(net "GMI_CPU1_G3_CPU0_G1_TX_DP<6>")
	)
	(segment
		(start 153.113994 -187.48121)
		(end 153.57983 -187.099448)
		(width 0.14224)
		(layer "In11.Cu")
		(net "GMI_CPU1_G3_CPU0_G1_TX_DP<6>")
	)
	(segment
		(start 315.531246 -184.898792)
		(end 350.332802 -213.434676)
		(width 0.14224)
		(layer "In11.Cu")
		(net "GMI_CPU1_G3_CPU0_G1_TX_DP<6>")
	)
	(segment
		(start 118.137178 -227.979732)
		(end 118.167658 -227.961952)
		(width 0.1143)
		(layer "In11.Cu")
		(net "GMI_CPU1_G3_CPU0_G1_TX_DP<6>")
	)
	(segment
		(start 153.77287 -187.118498)
		(end 154.10307 -186.847734)
		(width 0.14224)
		(layer "In11.Cu")
		(net "GMI_CPU1_G3_CPU0_G1_TX_DP<6>")
	)
	(segment
		(start 353.358704 -230.208836)
		(end 353.291648 -230.247952)
		(width 0.1143)
		(layer "In11.Cu")
		(net "GMI_CPU1_G3_CPU0_G1_TX_DP<6>")
	)
	(segment
		(start 351.94875 -234.258866)
		(end 351.879154 -234.299506)
		(width 0.1143)
		(layer "In11.Cu")
		(net "GMI_CPU1_G3_CPU0_G1_TX_DP<6>")
	)
	(segment
		(start 118.650512 -232.664)
		(end 118.6053 -232.637838)
		(width 0.1143)
		(layer "In11.Cu")
		(net "GMI_CPU1_G3_CPU0_G1_TX_DP<6>")
	)
	(segment
		(start 154.645106 -186.403234)
		(end 154.975306 -186.13247)
		(width 0.14224)
		(layer "In11.Cu")
		(net "GMI_CPU1_G3_CPU0_G1_TX_DP<6>")
	)
	(segment
		(start 117.980206 -221.804484)
		(end 117.980206 -221.39148)
		(width 0.1143)
		(layer "In11.Cu")
		(net "GMI_CPU1_G3_CPU0_G1_TX_DP<6>")
	)
	(segment
		(start 353.358704 -228.589078)
		(end 353.289108 -228.629718)
		(width 0.1143)
		(layer "In11.Cu")
		(net "GMI_CPU1_G3_CPU0_G1_TX_DP<6>")
	)
	(segment
		(start 150.827232 -189.356492)
		(end 151.020272 -189.375542)
		(width 0.14224)
		(layer "In11.Cu")
		(net "GMI_CPU1_G3_CPU0_G1_TX_DP<6>")
	)
	(segment
		(start 151.350472 -189.104778)
		(end 151.369522 -188.911738)
		(width 0.14224)
		(layer "In11.Cu")
		(net "GMI_CPU1_G3_CPU0_G1_TX_DP<6>")
	)
	(segment
		(start 152.571704 -187.925964)
		(end 152.764744 -187.945014)
		(width 0.14224)
		(layer "In11.Cu")
		(net "GMI_CPU1_G3_CPU0_G1_TX_DP<6>")
	)
	(segment
		(start 352.821748 -231.990392)
		(end 352.85807 -232.011474)
		(width 0.1143)
		(layer "In11.Cu")
		(net "GMI_CPU1_G3_CPU0_G1_TX_DP<6>")
	)
	(segment
		(start 118.636796 -232.012236)
		(end 118.637812 -232.011728)
		(width 0.1143)
		(layer "In11.Cu")
		(net "GMI_CPU1_G3_CPU0_G1_TX_DP<6>")
	)
	(segment
		(start 120.23471 -234.764326)
		(end 119.936768 -234.764326)
		(width 0.1143)
		(layer "In11.Cu")
		(net "GMI_CPU1_G3_CPU0_G1_TX_DP<6>")
	)
	(segment
		(start 118.637812 -232.011728)
		(end 118.674134 -231.990646)
		(width 0.1143)
		(layer "In11.Cu")
		(net "GMI_CPU1_G3_CPU0_G1_TX_DP<6>")
	)
	(segment
		(start 153.57983 -187.099448)
		(end 153.77287 -187.118498)
		(width 0.14224)
		(layer "In11.Cu")
		(net "GMI_CPU1_G3_CPU0_G1_TX_DP<6>")
	)
	(segment
		(start 118.137178 -226.35972)
		(end 118.167658 -226.34194)
		(width 0.1143)
		(layer "In11.Cu")
		(net "GMI_CPU1_G3_CPU0_G1_TX_DP<6>")
	)
	(segment
		(start 118.167658 -223.101916)
		(end 118.206774 -223.079056)
		(width 0.1143)
		(layer "In11.Cu")
		(net "GMI_CPU1_G3_CPU0_G1_TX_DP<6>")
	)
	(segment
		(start 353.559872 -221.34703)
		(end 353.515676 -221.391226)
		(width 0.1143)
		(layer "In11.Cu")
		(net "GMI_CPU1_G3_CPU0_G1_TX_DP<6>")
	)
	(segment
		(start 118.167658 -226.34194)
		(end 118.206774 -226.31908)
		(width 0.1143)
		(layer "In11.Cu")
		(net "GMI_CPU1_G3_CPU0_G1_TX_DP<6>")
	)
	(segment
		(start 118.204234 -230.248206)
		(end 118.137178 -230.20909)
		(width 0.1143)
		(layer "In11.Cu")
		(net "GMI_CPU1_G3_CPU0_G1_TX_DP<6>")
	)
	(segment
		(start 166.093648 -179.913534)
		(end 302.901096 -180.711348)
		(width 0.14224)
		(layer "In11.Cu")
		(net "GMI_CPU1_G3_CPU0_G1_TX_DP<6>")
	)
	(segment
		(start 118.674134 -231.057958)
		(end 118.637812 -231.036876)
		(width 0.1143)
		(layer "In11.Cu")
		(net "GMI_CPU1_G3_CPU0_G1_TX_DP<6>")
	)
	(segment
		(start 351.641918 -234.681268)
		(end 351.559114 -234.764072)
		(width 0.1143)
		(layer "In11.Cu")
		(net "GMI_CPU1_G3_CPU0_G1_TX_DP<6>")
	)
	(segment
		(start 118.206774 -228.629972)
		(end 118.167658 -228.607112)
		(width 0.1143)
		(layer "In11.Cu")
		(net "GMI_CPU1_G3_CPU0_G1_TX_DP<6>")
	)
	(segment
		(start 352.388932 -233.466132)
		(end 352.38817 -233.46664)
		(width 0.1143)
		(layer "In11.Cu")
		(net "GMI_CPU1_G3_CPU0_G1_TX_DP<6>")
	)
	(segment
		(start 119.146828 -233.489754)
		(end 119.107712 -233.466894)
		(width 0.1143)
		(layer "In11.Cu")
		(net "GMI_CPU1_G3_CPU0_G1_TX_DP<6>")
	)
	(segment
		(start 353.358704 -222.10903)
		(end 353.289108 -222.14967)
		(width 0.1143)
		(layer "In11.Cu")
		(net "GMI_CPU1_G3_CPU0_G1_TX_DP<6>")
	)
	(segment
		(start 353.514152 -221.083124)
		(end 353.559872 -221.128844)
		(width 0.1143)
		(layer "In11.Cu")
		(net "GMI_CPU1_G3_CPU0_G1_TX_DP<6>")
	)
	(segment
		(start 118.135146 -229.60076)
		(end 118.167658 -229.581964)
		(width 0.1143)
		(layer "In11.Cu")
		(net "GMI_CPU1_G3_CPU0_G1_TX_DP<6>")
	)
	(segment
		(start 118.206774 -223.769936)
		(end 118.167658 -223.747076)
		(width 0.1143)
		(layer "In11.Cu")
		(net "GMI_CPU1_G3_CPU0_G1_TX_DP<6>")
	)
	(segment
		(start 350.332802 -213.434676)
		(end 353.514152 -218.79306)
		(width 0.14224)
		(layer "In11.Cu")
		(net "GMI_CPU1_G3_CPU0_G1_TX_DP<6>")
	)
	(segment
		(start 352.85807 -231.036622)
		(end 352.821748 -231.057704)
		(width 0.1143)
		(layer "In11.Cu")
		(net "GMI_CPU1_G3_CPU0_G1_TX_DP<6>")
	)
	(segment
		(start 150.497286 -189.627002)
		(end 150.827232 -189.356492)
		(width 0.14224)
		(layer "In11.Cu")
		(net "GMI_CPU1_G3_CPU0_G1_TX_DP<6>")
	)
	(segment
		(start 119.936768 -234.764326)
		(end 119.853964 -234.681522)
		(width 0.1143)
		(layer "In11.Cu")
		(net "GMI_CPU1_G3_CPU0_G1_TX_DP<6>")
	)
	(segment
		(start 150.478236 -189.820042)
		(end 150.497286 -189.627002)
		(width 0.14224)
		(layer "In11.Cu")
		(net "GMI_CPU1_G3_CPU0_G1_TX_DP<6>")
	)
	(segment
		(start 149.606 -190.535306)
		(end 149.62505 -190.342266)
		(width 0.14224)
		(layer "In11.Cu")
		(net "GMI_CPU1_G3_CPU0_G1_TX_DP<6>")
	)
	(segment
		(start 151.369522 -188.911738)
		(end 151.699468 -188.641228)
		(width 0.14224)
		(layer "In11.Cu")
		(net "GMI_CPU1_G3_CPU0_G1_TX_DP<6>")
	)
	(segment
		(start 117.93601 -221.129098)
		(end 117.98173 -221.083378)
		(width 0.1143)
		(layer "In11.Cu")
		(net "GMI_CPU1_G3_CPU0_G1_TX_DP<6>")
	)
	(segment
		(start 152.222708 -188.389514)
		(end 152.241758 -188.196474)
		(width 0.14224)
		(layer "In11.Cu")
		(net "GMI_CPU1_G3_CPU0_G1_TX_DP<6>")
	)
	(segment
		(start 353.289108 -223.078802)
		(end 353.358704 -223.119442)
		(width 0.1143)
		(layer "In11.Cu")
		(net "GMI_CPU1_G3_CPU0_G1_TX_DP<6>")
	)
	(segment
		(start 144.408144 -194.620134)
		(end 146.330924 -193.043302)
		(width 0.14224)
		(layer "In11.Cu")
		(net "GMI_CPU1_G3_CPU0_G1_TX_DP<6>")
	)
	(segment
		(start 146.331178 -193.043302)
		(end 148.210524 -191.502284)
		(width 0.14224)
		(layer "In11.Cu")
		(net "GMI_CPU1_G3_CPU0_G1_TX_DP<6>")
	)
	(segment
		(start 154.12212 -186.654694)
		(end 154.452066 -186.384184)
		(width 0.14224)
		(layer "In11.Cu")
		(net "GMI_CPU1_G3_CPU0_G1_TX_DP<6>")
	)
	(segment
		(start 352.563938 -233.152696)
		(end 352.563938 -233.178096)
		(width 0.1143)
		(layer "In11.Cu")
		(net "GMI_CPU1_G3_CPU0_G1_TX_DP<6>")
	)
	(segment
		(start 352.387154 -233.467148)
		(end 352.38563 -233.468164)
		(width 0.1143)
		(layer "In11.Cu")
		(net "GMI_CPU1_G3_CPU0_G1_TX_DP<6>")
	)
	(segment
		(start 119.104918 -233.465116)
		(end 119.100854 -233.46283)
		(width 0.1143)
		(layer "In11.Cu")
		(net "GMI_CPU1_G3_CPU0_G1_TX_DP<6>")
	)
	(segment
		(start 117.980206 -221.39148)
		(end 117.93601 -221.347284)
		(width 0.1143)
		(layer "In11.Cu")
		(net "GMI_CPU1_G3_CPU0_G1_TX_DP<6>")
	)
	(segment
		(start 118.167658 -226.9871)
		(end 118.137178 -226.96932)
		(width 0.1143)
		(layer "In11.Cu")
		(net "GMI_CPU1_G3_CPU0_G1_TX_DP<6>")
	)
	(segment
		(start 146.330924 -193.043302)
		(end 146.331178 -193.043302)
		(width 0.14224)
		(layer "In11.Cu")
		(net "GMI_CPU1_G3_CPU0_G1_TX_DP<6>")
	)
	(segment
		(start 148.752814 -191.05753)
		(end 149.08276 -190.78702)
		(width 0.14224)
		(layer "In11.Cu")
		(net "GMI_CPU1_G3_CPU0_G1_TX_DP<6>")
	)
	(segment
		(start 351.559114 -234.764072)
		(end 351.261172 -234.764072)
		(width 0.1143)
		(layer "In11.Cu")
		(net "GMI_CPU1_G3_CPU0_G1_TX_DP<6>")
	)
	(segment
		(start 118.167658 -227.961952)
		(end 118.206774 -227.939092)
		(width 0.1143)
		(layer "In11.Cu")
		(net "GMI_CPU1_G3_CPU0_G1_TX_DP<6>")
	)
	(segment
		(start 353.358704 -226.969066)
		(end 353.289108 -227.009706)
		(width 0.1143)
		(layer "In11.Cu")
		(net "GMI_CPU1_G3_CPU0_G1_TX_DP<6>")
	)
	(segment
		(start 118.137178 -223.119696)
		(end 118.167658 -223.101916)
		(width 0.1143)
		(layer "In11.Cu")
		(net "GMI_CPU1_G3_CPU0_G1_TX_DP<6>")
	)
	(segment
		(start 144.000982 -194.743324)
		(end 144.408144 -194.620134)
		(width 0.14224)
		(layer "In11.Cu")
		(net "GMI_CPU1_G3_CPU0_G1_TX_DP<6>")
	)
	(segment
		(start 307.388006 -180.711348)
		(end 309.41137 -181.434486)
		(width 0.14224)
		(layer "In11.Cu")
		(net "GMI_CPU1_G3_CPU0_G1_TX_DP<6>")
	)
	(segment
		(start 118.137178 -224.739708)
		(end 118.167658 -224.721928)
		(width 0.1143)
		(layer "In11.Cu")
		(net "GMI_CPU1_G3_CPU0_G1_TX_DP<6>")
	)
	(segment
		(start 154.452066 -186.384184)
		(end 154.645106 -186.403234)
		(width 0.14224)
		(layer "In11.Cu")
		(net "GMI_CPU1_G3_CPU0_G1_TX_DP<6>")
	)
	(segment
		(start 352.390964 -233.464862)
		(end 352.388932 -233.466132)
		(width 0.1143)
		(layer "In11.Cu")
		(net "GMI_CPU1_G3_CPU0_G1_TX_DP<6>")
	)
	(segment
		(start 152.764744 -187.945014)
		(end 153.094944 -187.67425)
		(width 0.14224)
		(layer "In11.Cu")
		(net "GMI_CPU1_G3_CPU0_G1_TX_DP<6>")
	)
	(segment
		(start 148.403564 -191.521334)
		(end 148.733764 -191.25057)
		(width 0.14224)
		(layer "In11.Cu")
		(net "GMI_CPU1_G3_CPU0_G1_TX_DP<6>")
	)
	(segment
		(start 118.637812 -231.036876)
		(end 118.604284 -231.017318)
		(width 0.1143)
		(layer "In11.Cu")
		(net "GMI_CPU1_G3_CPU0_G1_TX_DP<6>")
	)
	(segment
		(start 119.577612 -234.2769)
		(end 119.547132 -234.25912)
		(width 0.1143)
		(layer "In11.Cu")
		(net "GMI_CPU1_G3_CPU0_G1_TX_DP<6>")
	)
	(segment
		(start 118.167658 -229.581964)
		(end 118.206774 -229.559104)
		(width 0.1143)
		(layer "In11.Cu")
		(net "GMI_CPU1_G3_CPU0_G1_TX_DP<6>")
	)
	(segment
		(start 353.289108 -229.55885)
		(end 353.328224 -229.58171)
		(width 0.1143)
		(layer "In11.Cu")
		(net "GMI_CPU1_G3_CPU0_G1_TX_DP<6>")
	)
	(segment
		(start 117.93601 -221.347284)
		(end 117.93601 -221.129098)
		(width 0.1143)
		(layer "In11.Cu")
		(net "GMI_CPU1_G3_CPU0_G1_TX_DP<6>")
	)
	(segment
		(start 353.289108 -227.938838)
		(end 353.358704 -227.979478)
		(width 0.1143)
		(layer "In11.Cu")
		(net "GMI_CPU1_G3_CPU0_G1_TX_DP<6>")
	)
	(segment
		(start 118.167658 -225.367088)
		(end 118.137178 -225.349308)
		(width 0.1143)
		(layer "In11.Cu")
		(net "GMI_CPU1_G3_CPU0_G1_TX_DP<6>")
	)
	(arc
		(start 353.358704 -226.359466)
		(mid 353.515681 -226.664266)
		(end 353.358704 -226.969066)
		(width 0.1143)
		(layer "In11.Cu")
		(net "GMI_CPU1_G3_CPU0_G1_TX_DP<6>")
	)
	(arc
		(start 352.105722 -233.954066)
		(mid 352.064173 -234.125488)
		(end 351.94875 -234.258866)
		(width 0.1143)
		(layer "In11.Cu")
		(net "GMI_CPU1_G3_CPU0_G1_TX_DP<6>")
	)
	(arc
		(start 118.137178 -230.20909)
		(mid 118.021751 -230.075714)
		(end 117.980206 -229.90429)
		(width 0.1143)
		(layer "In11.Cu")
		(net "GMI_CPU1_G3_CPU0_G1_TX_DP<6>")
	)
	(arc
		(start 352.821748 -231.057704)
		(mid 352.575858 -231.524048)
		(end 352.821748 -231.990392)
		(width 0.1143)
		(layer "In11.Cu")
		(net "GMI_CPU1_G3_CPU0_G1_TX_DP<6>")
	)
	(arc
		(start 353.515676 -221.80423)
		(mid 353.474127 -221.975652)
		(end 353.358704 -222.10903)
		(width 0.1143)
		(layer "In11.Cu")
		(net "GMI_CPU1_G3_CPU0_G1_TX_DP<6>")
	)
	(arc
		(start 353.045776 -230.714296)
		(mid 353.005014 -230.88418)
		(end 352.891598 -231.017064)
		(width 0.1143)
		(layer "In11.Cu")
		(net "GMI_CPU1_G3_CPU0_G1_TX_DP<6>")
	)
	(arc
		(start 351.879154 -234.299506)
		(mid 351.727167 -234.456014)
		(end 351.645728 -234.658408)
		(width 0.1143)
		(layer "In11.Cu")
		(net "GMI_CPU1_G3_CPU0_G1_TX_DP<6>")
	)
	(arc
		(start 118.206774 -226.31908)
		(mid 118.450101 -225.854514)
		(end 118.206774 -225.389948)
		(width 0.1143)
		(layer "In11.Cu")
		(net "GMI_CPU1_G3_CPU0_G1_TX_DP<6>")
	)
	(arc
		(start 352.859086 -232.011982)
		(mid 353.045323 -232.316255)
		(end 352.890582 -232.637584)
		(width 0.1143)
		(layer "In11.Cu")
		(net "GMI_CPU1_G3_CPU0_G1_TX_DP<6>")
	)
	(arc
		(start 118.137178 -228.589332)
		(mid 117.980201 -228.284532)
		(end 118.137178 -227.979732)
		(width 0.1143)
		(layer "In11.Cu")
		(net "GMI_CPU1_G3_CPU0_G1_TX_DP<6>")
	)
	(arc
		(start 118.604284 -231.017318)
		(mid 118.490877 -230.884429)
		(end 118.450106 -230.71455)
		(width 0.1143)
		(layer "In11.Cu")
		(net "GMI_CPU1_G3_CPU0_G1_TX_DP<6>")
	)
	(arc
		(start 353.358704 -224.739454)
		(mid 353.515681 -225.044254)
		(end 353.358704 -225.349054)
		(width 0.1143)
		(layer "In11.Cu")
		(net "GMI_CPU1_G3_CPU0_G1_TX_DP<6>")
	)
	(arc
		(start 353.360736 -229.600506)
		(mid 353.474665 -229.733653)
		(end 353.515676 -229.904036)
		(width 0.1143)
		(layer "In11.Cu")
		(net "GMI_CPU1_G3_CPU0_G1_TX_DP<6>")
	)
	(arc
		(start 352.84537 -232.663746)
		(mid 352.639302 -232.870609)
		(end 352.563938 -233.152696)
		(width 0.1143)
		(layer "In11.Cu")
		(net "GMI_CPU1_G3_CPU0_G1_TX_DP<6>")
	)
	(arc
		(start 118.137178 -222.109284)
		(mid 118.021751 -221.975908)
		(end 117.980206 -221.804484)
		(width 0.1143)
		(layer "In11.Cu")
		(net "GMI_CPU1_G3_CPU0_G1_TX_DP<6>")
	)
	(arc
		(start 118.674134 -231.990646)
		(mid 118.920024 -231.524302)
		(end 118.674134 -231.057958)
		(width 0.1143)
		(layer "In11.Cu")
		(net "GMI_CPU1_G3_CPU0_G1_TX_DP<6>")
	)
	(arc
		(start 118.137178 -225.349308)
		(mid 117.980201 -225.044508)
		(end 118.137178 -224.739708)
		(width 0.1143)
		(layer "In11.Cu")
		(net "GMI_CPU1_G3_CPU0_G1_TX_DP<6>")
	)
	(arc
		(start 119.39016 -233.95432)
		(mid 119.325645 -233.692101)
		(end 119.146828 -233.489754)
		(width 0.1143)
		(layer "In11.Cu")
		(net "GMI_CPU1_G3_CPU0_G1_TX_DP<6>")
	)
	(arc
		(start 118.931944 -233.15295)
		(mid 118.856557 -232.870877)
		(end 118.650512 -232.664)
		(width 0.1143)
		(layer "In11.Cu")
		(net "GMI_CPU1_G3_CPU0_G1_TX_DP<6>")
	)
	(arc
		(start 353.289108 -227.009706)
		(mid 353.045781 -227.474272)
		(end 353.289108 -227.938838)
		(width 0.1143)
		(layer "In11.Cu")
		(net "GMI_CPU1_G3_CPU0_G1_TX_DP<6>")
	)
	(arc
		(start 118.137178 -223.729296)
		(mid 117.980201 -223.424496)
		(end 118.137178 -223.119696)
		(width 0.1143)
		(layer "In11.Cu")
		(net "GMI_CPU1_G3_CPU0_G1_TX_DP<6>")
	)
	(arc
		(start 118.206774 -229.559104)
		(mid 118.450101 -229.094538)
		(end 118.206774 -228.629972)
		(width 0.1143)
		(layer "In11.Cu")
		(net "GMI_CPU1_G3_CPU0_G1_TX_DP<6>")
	)
	(arc
		(start 118.206774 -227.939092)
		(mid 118.450101 -227.474526)
		(end 118.206774 -227.00996)
		(width 0.1143)
		(layer "In11.Cu")
		(net "GMI_CPU1_G3_CPU0_G1_TX_DP<6>")
	)
	(arc
		(start 117.980206 -229.90429)
		(mid 118.021172 -229.733884)
		(end 118.135146 -229.60076)
		(width 0.1143)
		(layer "In11.Cu")
		(net "GMI_CPU1_G3_CPU0_G1_TX_DP<6>")
	)
	(arc
		(start 118.206774 -223.079056)
		(mid 118.450101 -222.61449)
		(end 118.206774 -222.149924)
		(width 0.1143)
		(layer "In11.Cu")
		(net "GMI_CPU1_G3_CPU0_G1_TX_DP<6>")
	)
	(arc
		(start 353.358704 -227.979478)
		(mid 353.515681 -228.284278)
		(end 353.358704 -228.589078)
		(width 0.1143)
		(layer "In11.Cu")
		(net "GMI_CPU1_G3_CPU0_G1_TX_DP<6>")
	)
	(arc
		(start 351.645728 -234.658408)
		(mid 351.643705 -234.669818)
		(end 351.641918 -234.681268)
		(width 0.1143)
		(layer "In11.Cu")
		(net "GMI_CPU1_G3_CPU0_G1_TX_DP<6>")
	)
	(arc
		(start 353.289108 -225.389694)
		(mid 353.045781 -225.85426)
		(end 353.289108 -226.318826)
		(width 0.1143)
		(layer "In11.Cu")
		(net "GMI_CPU1_G3_CPU0_G1_TX_DP<6>")
	)
	(arc
		(start 118.6053 -232.637838)
		(mid 118.450762 -232.316519)
		(end 118.636796 -232.012236)
		(width 0.1143)
		(layer "In11.Cu")
		(net "GMI_CPU1_G3_CPU0_G1_TX_DP<6>")
	)
	(arc
		(start 119.547132 -234.25912)
		(mid 119.431705 -234.125744)
		(end 119.39016 -233.95432)
		(width 0.1143)
		(layer "In11.Cu")
		(net "GMI_CPU1_G3_CPU0_G1_TX_DP<6>")
	)
	(arc
		(start 353.289108 -228.629718)
		(mid 353.045781 -229.094284)
		(end 353.289108 -229.55885)
		(width 0.1143)
		(layer "In11.Cu")
		(net "GMI_CPU1_G3_CPU0_G1_TX_DP<6>")
	)
	(arc
		(start 353.289108 -223.769682)
		(mid 353.045781 -224.234248)
		(end 353.289108 -224.698814)
		(width 0.1143)
		(layer "In11.Cu")
		(net "GMI_CPU1_G3_CPU0_G1_TX_DP<6>")
	)
	(arc
		(start 119.853964 -234.681522)
		(mid 119.774885 -234.466077)
		(end 119.616728 -234.29976)
		(width 0.1143)
		(layer "In11.Cu")
		(net "GMI_CPU1_G3_CPU0_G1_TX_DP<6>")
	)
	(arc
		(start 119.100854 -233.46283)
		(mid 118.977385 -233.343762)
		(end 118.931944 -233.17835)
		(width 0.1143)
		(layer "In11.Cu")
		(net "GMI_CPU1_G3_CPU0_G1_TX_DP<6>")
	)
	(arc
		(start 118.450106 -230.71455)
		(mid 118.38487 -230.450959)
		(end 118.204234 -230.248206)
		(width 0.1143)
		(layer "In11.Cu")
		(net "GMI_CPU1_G3_CPU0_G1_TX_DP<6>")
	)
	(arc
		(start 353.291648 -230.247952)
		(mid 353.110996 -230.450697)
		(end 353.045776 -230.714296)
		(width 0.1143)
		(layer "In11.Cu")
		(net "GMI_CPU1_G3_CPU0_G1_TX_DP<6>")
	)
	(arc
		(start 118.206774 -224.699068)
		(mid 118.450101 -224.234502)
		(end 118.206774 -223.769936)
		(width 0.1143)
		(layer "In11.Cu")
		(net "GMI_CPU1_G3_CPU0_G1_TX_DP<6>")
	)
	(arc
		(start 353.358704 -223.119442)
		(mid 353.515681 -223.424242)
		(end 353.358704 -223.729042)
		(width 0.1143)
		(layer "In11.Cu")
		(net "GMI_CPU1_G3_CPU0_G1_TX_DP<6>")
	)
	(arc
		(start 352.563938 -233.178096)
		(mid 352.518536 -233.343531)
		(end 352.395028 -233.462576)
		(width 0.1143)
		(layer "In11.Cu")
		(net "GMI_CPU1_G3_CPU0_G1_TX_DP<6>")
	)
	(arc
		(start 352.349054 -233.4895)
		(mid 352.170241 -233.69185)
		(end 352.105722 -233.954066)
		(width 0.1143)
		(layer "In11.Cu")
		(net "GMI_CPU1_G3_CPU0_G1_TX_DP<6>")
	)
	(arc
		(start 118.137178 -226.96932)
		(mid 117.980201 -226.66452)
		(end 118.137178 -226.35972)
		(width 0.1143)
		(layer "In11.Cu")
		(net "GMI_CPU1_G3_CPU0_G1_TX_DP<6>")
	)
	(arc
		(start 353.289108 -222.14967)
		(mid 353.045781 -222.614236)
		(end 353.289108 -223.078802)
		(width 0.1143)
		(layer "In11.Cu")
		(net "GMI_CPU1_G3_CPU0_G1_TX_DP<6>")
	)
	(arc
		(start 353.515676 -229.904036)
		(mid 353.474127 -230.075458)
		(end 353.358704 -230.208836)
		(width 0.1143)
		(layer "In11.Cu")
		(net "GMI_CPU1_G3_CPU0_G1_TX_DP<6>")
	)
	(segment
		(start 116.94795 -233.410252)
		(end 117.414802 -233.144314)
		(width 0.12954)
		(layer "F.Cu")
		(net "GMI_CPU1_G3_CPU0_G1_TX_DP<5>")
	)
	(segment
		(start 354.547932 -233.409998)
		(end 354.08108 -233.14406)
		(width 0.12954)
		(layer "F.Cu")
		(net "GMI_CPU1_G3_CPU0_G1_TX_DP<5>")
	)
	(segment
		(start 117.227604 -228.607112)
		(end 117.26672 -228.629972)
		(width 0.1143)
		(layer "In11.Cu")
		(net "GMI_CPU1_G3_CPU0_G1_TX_DP<5>")
	)
	(segment
		(start 117.227604 -226.34194)
		(end 117.197124 -226.35972)
		(width 0.1143)
		(layer "In11.Cu")
		(net "GMI_CPU1_G3_CPU0_G1_TX_DP<5>")
	)
	(segment
		(start 150.053548 -188.777118)
		(end 149.860508 -188.757814)
		(width 0.14224)
		(layer "In11.Cu")
		(net "GMI_CPU1_G3_CPU0_G1_TX_DP<5>")
	)
	(segment
		(start 117.227604 -232.821734)
		(end 117.197124 -232.839514)
		(width 0.1143)
		(layer "In11.Cu")
		(net "GMI_CPU1_G3_CPU0_G1_TX_DP<5>")
	)
	(segment
		(start 353.805744 -232.015792)
		(end 353.804728 -232.015284)
		(width 0.1143)
		(layer "In11.Cu")
		(net "GMI_CPU1_G3_CPU0_G1_TX_DP<5>")
	)
	(segment
		(start 117.26672 -229.559104)
		(end 117.227604 -229.581964)
		(width 0.1143)
		(layer "In11.Cu")
		(net "GMI_CPU1_G3_CPU0_G1_TX_DP<5>")
	)
	(segment
		(start 153.516584 -185.760614)
		(end 153.19248 -186.026298)
		(width 0.14224)
		(layer "In11.Cu")
		(net "GMI_CPU1_G3_CPU0_G1_TX_DP<5>")
	)
	(segment
		(start 151.311864 -187.735464)
		(end 150.987506 -188.001402)
		(width 0.14224)
		(layer "In11.Cu")
		(net "GMI_CPU1_G3_CPU0_G1_TX_DP<5>")
	)
	(segment
		(start 354.229162 -228.629718)
		(end 354.298758 -228.589078)
		(width 0.1143)
		(layer "In11.Cu")
		(net "GMI_CPU1_G3_CPU0_G1_TX_DP<5>")
	)
	(segment
		(start 117.697758 -232.011728)
		(end 117.696996 -232.012236)
		(width 0.1143)
		(layer "In11.Cu")
		(net "GMI_CPU1_G3_CPU0_G1_TX_DP<5>")
	)
	(segment
		(start 153.51633 -185.76036)
		(end 153.516584 -185.760614)
		(width 0.14224)
		(layer "In11.Cu")
		(net "GMI_CPU1_G3_CPU0_G1_TX_DP<5>")
	)
	(segment
		(start 152.256998 -186.793378)
		(end 152.256744 -186.793124)
		(width 0.14224)
		(layer "In11.Cu")
		(net "GMI_CPU1_G3_CPU0_G1_TX_DP<5>")
	)
	(segment
		(start 144.378426 -193.252344)
		(end 144.149318 -193.32194)
		(width 0.14224)
		(layer "In11.Cu")
		(net "GMI_CPU1_G3_CPU0_G1_TX_DP<5>")
	)
	(segment
		(start 149.530816 -189.028578)
		(end 149.530562 -189.028324)
		(width 0.14224)
		(layer "In11.Cu")
		(net "GMI_CPU1_G3_CPU0_G1_TX_DP<5>")
	)
	(segment
		(start 117.26672 -226.31908)
		(end 117.227604 -226.34194)
		(width 0.1143)
		(layer "In11.Cu")
		(net "GMI_CPU1_G3_CPU0_G1_TX_DP<5>")
	)
	(segment
		(start 353.80168 -232.013506)
		(end 353.800156 -232.012744)
		(width 0.1143)
		(layer "In11.Cu")
		(net "GMI_CPU1_G3_CPU0_G1_TX_DP<5>")
	)
	(segment
		(start 351.05086 -212.817456)
		(end 316.022736 -184.09539)
		(width 0.14224)
		(layer "In11.Cu")
		(net "GMI_CPU1_G3_CPU0_G1_TX_DP<5>")
	)
	(segment
		(start 151.914352 -187.241434)
		(end 151.732234 -187.2234)
		(width 0.14224)
		(layer "In11.Cu")
		(net "GMI_CPU1_G3_CPU0_G1_TX_DP<5>")
	)
	(segment
		(start 150.383748 -188.506354)
		(end 150.053548 -188.777118)
		(width 0.14224)
		(layer "In11.Cu")
		(net "GMI_CPU1_G3_CPU0_G1_TX_DP<5>")
	)
	(segment
		(start 148.116036 -190.188088)
		(end 146.269202 -191.702182)
		(width 0.14224)
		(layer "In11.Cu")
		(net "GMI_CPU1_G3_CPU0_G1_TX_DP<5>")
	)
	(segment
		(start 117.227604 -229.581964)
		(end 117.195092 -229.60076)
		(width 0.1143)
		(layer "In11.Cu")
		(net "GMI_CPU1_G3_CPU0_G1_TX_DP<5>")
	)
	(segment
		(start 354.492306 -221.128844)
		(end 354.446586 -221.083124)
		(width 0.1143)
		(layer "In11.Cu")
		(net "GMI_CPU1_G3_CPU0_G1_TX_DP<5>")
	)
	(segment
		(start 117.003576 -221.129098)
		(end 117.003576 -221.347284)
		(width 0.1143)
		(layer "In11.Cu")
		(net "GMI_CPU1_G3_CPU0_G1_TX_DP<5>")
	)
	(segment
		(start 152.667716 -186.456574)
		(end 152.256998 -186.793378)
		(width 0.14224)
		(layer "In11.Cu")
		(net "GMI_CPU1_G3_CPU0_G1_TX_DP<5>")
	)
	(segment
		(start 117.227604 -223.747076)
		(end 117.26672 -223.769936)
		(width 0.1143)
		(layer "In11.Cu")
		(net "GMI_CPU1_G3_CPU0_G1_TX_DP<5>")
	)
	(segment
		(start 307.568854 -179.774088)
		(end 302.904144 -179.774088)
		(width 0.14224)
		(layer "In11.Cu")
		(net "GMI_CPU1_G3_CPU0_G1_TX_DP<5>")
	)
	(segment
		(start 354.30079 -229.600506)
		(end 354.268278 -229.58171)
		(width 0.1143)
		(layer "In11.Cu")
		(net "GMI_CPU1_G3_CPU0_G1_TX_DP<5>")
	)
	(segment
		(start 152.23871 -186.975496)
		(end 151.914352 -187.241434)
		(width 0.14224)
		(layer "In11.Cu")
		(net "GMI_CPU1_G3_CPU0_G1_TX_DP<5>")
	)
	(segment
		(start 153.19248 -186.026298)
		(end 153.192226 -186.026044)
		(width 0.14224)
		(layer "In11.Cu")
		(net "GMI_CPU1_G3_CPU0_G1_TX_DP<5>")
	)
	(segment
		(start 117.227604 -226.9871)
		(end 117.26672 -227.00996)
		(width 0.1143)
		(layer "In11.Cu")
		(net "GMI_CPU1_G3_CPU0_G1_TX_DP<5>")
	)
	(segment
		(start 353.759008 -231.059482)
		(end 353.831652 -231.017064)
		(width 0.1143)
		(layer "In11.Cu")
		(net "GMI_CPU1_G3_CPU0_G1_TX_DP<5>")
	)
	(segment
		(start 354.446586 -221.083124)
		(end 354.446586 -221.071694)
		(width 0.1143)
		(layer "In11.Cu")
		(net "GMI_CPU1_G3_CPU0_G1_TX_DP<5>")
	)
	(segment
		(start 148.658326 -189.743588)
		(end 148.639276 -189.936628)
		(width 0.14224)
		(layer "In11.Cu")
		(net "GMI_CPU1_G3_CPU0_G1_TX_DP<5>")
	)
	(segment
		(start 354.231702 -230.247952)
		(end 354.298758 -230.208836)
		(width 0.1143)
		(layer "In11.Cu")
		(net "GMI_CPU1_G3_CPU0_G1_TX_DP<5>")
	)
	(segment
		(start 150.987506 -188.001402)
		(end 150.805388 -187.983368)
		(width 0.14224)
		(layer "In11.Cu")
		(net "GMI_CPU1_G3_CPU0_G1_TX_DP<5>")
	)
	(segment
		(start 117.04701 -233.074464)
		(end 117.11686 -233.144314)
		(width 0.1143)
		(layer "In11.Cu")
		(net "GMI_CPU1_G3_CPU0_G1_TX_DP<5>")
	)
	(segment
		(start 353.804728 -232.015284)
		(end 353.803966 -232.014776)
		(width 0.1143)
		(layer "In11.Cu")
		(net "GMI_CPU1_G3_CPU0_G1_TX_DP<5>")
	)
	(segment
		(start 117.049296 -221.071948)
		(end 117.049296 -221.083378)
		(width 0.1143)
		(layer "In11.Cu")
		(net "GMI_CPU1_G3_CPU0_G1_TX_DP<5>")
	)
	(segment
		(start 117.227604 -225.367088)
		(end 117.26672 -225.389948)
		(width 0.1143)
		(layer "In11.Cu")
		(net "GMI_CPU1_G3_CPU0_G1_TX_DP<5>")
	)
	(segment
		(start 154.364944 -185.064654)
		(end 154.365198 -185.064908)
		(width 0.14224)
		(layer "In11.Cu")
		(net "GMI_CPU1_G3_CPU0_G1_TX_DP<5>")
	)
	(segment
		(start 117.197124 -222.109284)
		(end 117.227604 -222.127064)
		(width 0.1143)
		(layer "In11.Cu")
		(net "GMI_CPU1_G3_CPU0_G1_TX_DP<5>")
	)
	(segment
		(start 149.530562 -189.028324)
		(end 149.511512 -189.221364)
		(width 0.14224)
		(layer "In11.Cu")
		(net "GMI_CPU1_G3_CPU0_G1_TX_DP<5>")
	)
	(segment
		(start 144.149318 -193.32194)
		(end 120.45569 -212.749638)
		(width 0.14224)
		(layer "In11.Cu")
		(net "GMI_CPU1_G3_CPU0_G1_TX_DP<5>")
	)
	(segment
		(start 117.003576 -221.347284)
		(end 117.040152 -221.38386)
		(width 0.1143)
		(layer "In11.Cu")
		(net "GMI_CPU1_G3_CPU0_G1_TX_DP<5>")
	)
	(segment
		(start 309.794656 -180.56987)
		(end 307.568854 -179.774088)
		(width 0.14224)
		(layer "In11.Cu")
		(net "GMI_CPU1_G3_CPU0_G1_TX_DP<5>")
	)
	(segment
		(start 152.849834 -186.474354)
		(end 152.667462 -186.45632)
		(width 0.14224)
		(layer "In11.Cu")
		(net "GMI_CPU1_G3_CPU0_G1_TX_DP<5>")
	)
	(segment
		(start 149.181312 -189.492128)
		(end 148.988272 -189.473078)
		(width 0.14224)
		(layer "In11.Cu")
		(net "GMI_CPU1_G3_CPU0_G1_TX_DP<5>")
	)
	(segment
		(start 154.365198 -185.064908)
		(end 154.041094 -185.330846)
		(width 0.14224)
		(layer "In11.Cu")
		(net "GMI_CPU1_G3_CPU0_G1_TX_DP<5>")
	)
	(segment
		(start 153.174192 -186.208416)
		(end 152.849834 -186.474354)
		(width 0.14224)
		(layer "In11.Cu")
		(net "GMI_CPU1_G3_CPU0_G1_TX_DP<5>")
	)
	(segment
		(start 120.45569 -212.749638)
		(end 117.049296 -218.560904)
		(width 0.14224)
		(layer "In11.Cu")
		(net "GMI_CPU1_G3_CPU0_G1_TX_DP<5>")
	)
	(segment
		(start 354.45573 -221.80423)
		(end 354.45573 -221.383606)
		(width 0.1143)
		(layer "In11.Cu")
		(net "GMI_CPU1_G3_CPU0_G1_TX_DP<5>")
	)
	(segment
		(start 354.229162 -227.009706)
		(end 354.298758 -226.969066)
		(width 0.1143)
		(layer "In11.Cu")
		(net "GMI_CPU1_G3_CPU0_G1_TX_DP<5>")
	)
	(segment
		(start 353.829874 -232.029762)
		(end 353.805744 -232.015792)
		(width 0.1143)
		(layer "In11.Cu")
		(net "GMI_CPU1_G3_CPU0_G1_TX_DP<5>")
	)
	(segment
		(start 354.379022 -233.14406)
		(end 354.448872 -233.07421)
		(width 0.1143)
		(layer "In11.Cu")
		(net "GMI_CPU1_G3_CPU0_G1_TX_DP<5>")
	)
	(segment
		(start 149.860508 -188.757814)
		(end 149.860762 -188.758068)
		(width 0.14224)
		(layer "In11.Cu")
		(net "GMI_CPU1_G3_CPU0_G1_TX_DP<5>")
	)
	(segment
		(start 117.049296 -221.083378)
		(end 117.003576 -221.129098)
		(width 0.1143)
		(layer "In11.Cu")
		(net "GMI_CPU1_G3_CPU0_G1_TX_DP<5>")
	)
	(segment
		(start 153.698448 -185.778648)
		(end 153.51633 -185.76036)
		(width 0.14224)
		(layer "In11.Cu")
		(net "GMI_CPU1_G3_CPU0_G1_TX_DP<5>")
	)
	(segment
		(start 117.040152 -221.38386)
		(end 117.040152 -221.804484)
		(width 0.1143)
		(layer "In11.Cu")
		(net "GMI_CPU1_G3_CPU0_G1_TX_DP<5>")
	)
	(segment
		(start 353.798886 -232.011982)
		(end 353.798124 -232.011474)
		(width 0.1143)
		(layer "In11.Cu")
		(net "GMI_CPU1_G3_CPU0_G1_TX_DP<5>")
	)
	(segment
		(start 117.227604 -222.127064)
		(end 117.26672 -222.149924)
		(width 0.1143)
		(layer "In11.Cu")
		(net "GMI_CPU1_G3_CPU0_G1_TX_DP<5>")
	)
	(segment
		(start 148.309076 -190.207392)
		(end 148.116036 -190.188088)
		(width 0.14224)
		(layer "In11.Cu")
		(net "GMI_CPU1_G3_CPU0_G1_TX_DP<5>")
	)
	(segment
		(start 353.802442 -232.014014)
		(end 353.80168 -232.013506)
		(width 0.1143)
		(layer "In11.Cu")
		(net "GMI_CPU1_G3_CPU0_G1_TX_DP<5>")
	)
	(segment
		(start 353.798124 -232.011474)
		(end 353.797108 -232.010966)
		(width 0.1143)
		(layer "In11.Cu")
		(net "GMI_CPU1_G3_CPU0_G1_TX_DP<5>")
	)
	(segment
		(start 152.256744 -186.793124)
		(end 152.23871 -186.975496)
		(width 0.14224)
		(layer "In11.Cu")
		(net "GMI_CPU1_G3_CPU0_G1_TX_DP<5>")
	)
	(segment
		(start 354.446586 -221.071694)
		(end 354.446586 -218.536012)
		(width 0.14224)
		(layer "In11.Cu")
		(net "GMI_CPU1_G3_CPU0_G1_TX_DP<5>")
	)
	(segment
		(start 354.268278 -229.58171)
		(end 354.229162 -229.55885)
		(width 0.1143)
		(layer "In11.Cu")
		(net "GMI_CPU1_G3_CPU0_G1_TX_DP<5>")
	)
	(segment
		(start 354.446586 -218.536012)
		(end 351.05086 -212.817456)
		(width 0.14224)
		(layer "In11.Cu")
		(net "GMI_CPU1_G3_CPU0_G1_TX_DP<5>")
	)
	(segment
		(start 117.26672 -232.798874)
		(end 117.227604 -232.821734)
		(width 0.1143)
		(layer "In11.Cu")
		(net "GMI_CPU1_G3_CPU0_G1_TX_DP<5>")
	)
	(segment
		(start 353.797108 -232.010966)
		(end 353.795584 -232.00995)
		(width 0.1143)
		(layer "In11.Cu")
		(net "GMI_CPU1_G3_CPU0_G1_TX_DP<5>")
	)
	(segment
		(start 154.547062 -185.082942)
		(end 154.364944 -185.064654)
		(width 0.14224)
		(layer "In11.Cu")
		(net "GMI_CPU1_G3_CPU0_G1_TX_DP<5>")
	)
	(segment
		(start 154.87142 -184.817004)
		(end 154.547062 -185.082942)
		(width 0.14224)
		(layer "In11.Cu")
		(net "GMI_CPU1_G3_CPU0_G1_TX_DP<5>")
	)
	(segment
		(start 117.698774 -232.01122)
		(end 117.697758 -232.011728)
		(width 0.1143)
		(layer "In11.Cu")
		(net "GMI_CPU1_G3_CPU0_G1_TX_DP<5>")
	)
	(segment
		(start 117.11686 -233.144314)
		(end 117.414802 -233.144314)
		(width 0.1143)
		(layer "In11.Cu")
		(net "GMI_CPU1_G3_CPU0_G1_TX_DP<5>")
	)
	(segment
		(start 152.667462 -186.45632)
		(end 152.667716 -186.456574)
		(width 0.14224)
		(layer "In11.Cu")
		(net "GMI_CPU1_G3_CPU0_G1_TX_DP<5>")
	)
	(segment
		(start 354.298758 -227.979478)
		(end 354.229162 -227.938838)
		(width 0.1143)
		(layer "In11.Cu")
		(net "GMI_CPU1_G3_CPU0_G1_TX_DP<5>")
	)
	(segment
		(start 354.229162 -225.389694)
		(end 354.298758 -225.349054)
		(width 0.1143)
		(layer "In11.Cu")
		(net "GMI_CPU1_G3_CPU0_G1_TX_DP<5>")
	)
	(segment
		(start 146.269202 -191.702182)
		(end 146.268948 -191.702436)
		(width 0.14224)
		(layer "In11.Cu")
		(net "GMI_CPU1_G3_CPU0_G1_TX_DP<5>")
	)
	(segment
		(start 165.865556 -178.97475)
		(end 158.644082 -181.556914)
		(width 0.14224)
		(layer "In11.Cu")
		(net "GMI_CPU1_G3_CPU0_G1_TX_DP<5>")
	)
	(segment
		(start 354.08108 -233.14406)
		(end 354.379022 -233.14406)
		(width 0.1143)
		(layer "In11.Cu")
		(net "GMI_CPU1_G3_CPU0_G1_TX_DP<5>")
	)
	(segment
		(start 354.298758 -232.83926)
		(end 354.229162 -232.79862)
		(width 0.1143)
		(layer "In11.Cu")
		(net "GMI_CPU1_G3_CPU0_G1_TX_DP<5>")
	)
	(segment
		(start 150.402798 -188.313314)
		(end 150.383748 -188.506354)
		(width 0.14224)
		(layer "In11.Cu")
		(net "GMI_CPU1_G3_CPU0_G1_TX_DP<5>")
	)
	(segment
		(start 149.511512 -189.221364)
		(end 149.181312 -189.492128)
		(width 0.14224)
		(layer "In11.Cu")
		(net "GMI_CPU1_G3_CPU0_G1_TX_DP<5>")
	)
	(segment
		(start 354.298758 -226.359466)
		(end 354.229162 -226.318826)
		(width 0.1143)
		(layer "In11.Cu")
		(net "GMI_CPU1_G3_CPU0_G1_TX_DP<5>")
	)
	(segment
		(start 117.227604 -227.961952)
		(end 117.197124 -227.979732)
		(width 0.1143)
		(layer "In11.Cu")
		(net "GMI_CPU1_G3_CPU0_G1_TX_DP<5>")
	)
	(segment
		(start 117.227604 -223.101916)
		(end 117.197124 -223.119696)
		(width 0.1143)
		(layer "In11.Cu")
		(net "GMI_CPU1_G3_CPU0_G1_TX_DP<5>")
	)
	(segment
		(start 117.197124 -228.589332)
		(end 117.227604 -228.607112)
		(width 0.1143)
		(layer "In11.Cu")
		(net "GMI_CPU1_G3_CPU0_G1_TX_DP<5>")
	)
	(segment
		(start 117.227604 -224.721928)
		(end 117.197124 -224.739708)
		(width 0.1143)
		(layer "In11.Cu")
		(net "GMI_CPU1_G3_CPU0_G1_TX_DP<5>")
	)
	(segment
		(start 117.049296 -218.560904)
		(end 117.049296 -221.071948)
		(width 0.14224)
		(layer "In11.Cu")
		(net "GMI_CPU1_G3_CPU0_G1_TX_DP<5>")
	)
	(segment
		(start 117.26672 -224.699068)
		(end 117.227604 -224.721928)
		(width 0.1143)
		(layer "In11.Cu")
		(net "GMI_CPU1_G3_CPU0_G1_TX_DP<5>")
	)
	(segment
		(start 151.329898 -187.553092)
		(end 151.311864 -187.735464)
		(width 0.14224)
		(layer "In11.Cu")
		(net "GMI_CPU1_G3_CPU0_G1_TX_DP<5>")
	)
	(segment
		(start 117.26672 -223.079056)
		(end 117.227604 -223.101916)
		(width 0.1143)
		(layer "In11.Cu")
		(net "GMI_CPU1_G3_CPU0_G1_TX_DP<5>")
	)
	(segment
		(start 354.229162 -223.769682)
		(end 354.298758 -223.729042)
		(width 0.1143)
		(layer "In11.Cu")
		(net "GMI_CPU1_G3_CPU0_G1_TX_DP<5>")
	)
	(segment
		(start 117.197124 -223.729296)
		(end 117.227604 -223.747076)
		(width 0.1143)
		(layer "In11.Cu")
		(net "GMI_CPU1_G3_CPU0_G1_TX_DP<5>")
	)
	(segment
		(start 154.041094 -185.330846)
		(end 154.04084 -185.330338)
		(width 0.14224)
		(layer "In11.Cu")
		(net "GMI_CPU1_G3_CPU0_G1_TX_DP<5>")
	)
	(segment
		(start 353.800156 -232.012744)
		(end 353.798886 -232.011982)
		(width 0.1143)
		(layer "In11.Cu")
		(net "GMI_CPU1_G3_CPU0_G1_TX_DP<5>")
	)
	(segment
		(start 354.298758 -223.119442)
		(end 354.229162 -223.078802)
		(width 0.1143)
		(layer "In11.Cu")
		(net "GMI_CPU1_G3_CPU0_G1_TX_DP<5>")
	)
	(segment
		(start 117.736874 -231.988868)
		(end 117.700298 -232.010204)
		(width 0.1143)
		(layer "In11.Cu")
		(net "GMI_CPU1_G3_CPU0_G1_TX_DP<5>")
	)
	(segment
		(start 148.988272 -189.473078)
		(end 148.658326 -189.743588)
		(width 0.14224)
		(layer "In11.Cu")
		(net "GMI_CPU1_G3_CPU0_G1_TX_DP<5>")
	)
	(segment
		(start 354.229162 -222.14967)
		(end 354.298758 -222.10903)
		(width 0.1143)
		(layer "In11.Cu")
		(net "GMI_CPU1_G3_CPU0_G1_TX_DP<5>")
	)
	(segment
		(start 117.697758 -231.036876)
		(end 117.736874 -231.059736)
		(width 0.1143)
		(layer "In11.Cu")
		(net "GMI_CPU1_G3_CPU0_G1_TX_DP<5>")
	)
	(segment
		(start 153.192226 -186.026044)
		(end 153.174192 -186.208416)
		(width 0.14224)
		(layer "In11.Cu")
		(net "GMI_CPU1_G3_CPU0_G1_TX_DP<5>")
	)
	(segment
		(start 302.904144 -179.774088)
		(end 165.865556 -178.97475)
		(width 0.14224)
		(layer "In11.Cu")
		(net "GMI_CPU1_G3_CPU0_G1_TX_DP<5>")
	)
	(segment
		(start 354.45573 -221.383606)
		(end 354.492306 -221.34703)
		(width 0.1143)
		(layer "In11.Cu")
		(net "GMI_CPU1_G3_CPU0_G1_TX_DP<5>")
	)
	(segment
		(start 117.197124 -225.349308)
		(end 117.227604 -225.367088)
		(width 0.1143)
		(layer "In11.Cu")
		(net "GMI_CPU1_G3_CPU0_G1_TX_DP<5>")
	)
	(segment
		(start 154.04084 -185.330338)
		(end 154.022806 -185.51271)
		(width 0.14224)
		(layer "In11.Cu")
		(net "GMI_CPU1_G3_CPU0_G1_TX_DP<5>")
	)
	(segment
		(start 148.639276 -189.936628)
		(end 148.309076 -190.207392)
		(width 0.14224)
		(layer "In11.Cu")
		(net "GMI_CPU1_G3_CPU0_G1_TX_DP<5>")
	)
	(segment
		(start 354.492306 -221.34703)
		(end 354.492306 -221.128844)
		(width 0.1143)
		(layer "In11.Cu")
		(net "GMI_CPU1_G3_CPU0_G1_TX_DP<5>")
	)
	(segment
		(start 151.732234 -187.2234)
		(end 151.329898 -187.553092)
		(width 0.14224)
		(layer "In11.Cu")
		(net "GMI_CPU1_G3_CPU0_G1_TX_DP<5>")
	)
	(segment
		(start 316.022736 -184.09539)
		(end 309.794656 -180.56987)
		(width 0.14224)
		(layer "In11.Cu")
		(net "GMI_CPU1_G3_CPU0_G1_TX_DP<5>")
	)
	(segment
		(start 353.795584 -232.00995)
		(end 353.759008 -231.988614)
		(width 0.1143)
		(layer "In11.Cu")
		(net "GMI_CPU1_G3_CPU0_G1_TX_DP<5>")
	)
	(segment
		(start 117.197124 -226.96932)
		(end 117.227604 -226.9871)
		(width 0.1143)
		(layer "In11.Cu")
		(net "GMI_CPU1_G3_CPU0_G1_TX_DP<5>")
	)
	(segment
		(start 117.26672 -227.939092)
		(end 117.227604 -227.961952)
		(width 0.1143)
		(layer "In11.Cu")
		(net "GMI_CPU1_G3_CPU0_G1_TX_DP<5>")
	)
	(segment
		(start 146.268948 -191.702436)
		(end 144.378426 -193.252344)
		(width 0.14224)
		(layer "In11.Cu")
		(net "GMI_CPU1_G3_CPU0_G1_TX_DP<5>")
	)
	(segment
		(start 117.700298 -232.010204)
		(end 117.698774 -232.01122)
		(width 0.1143)
		(layer "In11.Cu")
		(net "GMI_CPU1_G3_CPU0_G1_TX_DP<5>")
	)
	(segment
		(start 117.696996 -232.012236)
		(end 117.666008 -232.030016)
		(width 0.1143)
		(layer "In11.Cu")
		(net "GMI_CPU1_G3_CPU0_G1_TX_DP<5>")
	)
	(segment
		(start 154.022806 -185.51271)
		(end 153.698448 -185.778648)
		(width 0.14224)
		(layer "In11.Cu")
		(net "GMI_CPU1_G3_CPU0_G1_TX_DP<5>")
	)
	(segment
		(start 117.197124 -230.20909)
		(end 117.26418 -230.248206)
		(width 0.1143)
		(layer "In11.Cu")
		(net "GMI_CPU1_G3_CPU0_G1_TX_DP<5>")
	)
	(segment
		(start 158.644082 -181.556914)
		(end 154.889454 -184.634632)
		(width 0.14224)
		(layer "In11.Cu")
		(net "GMI_CPU1_G3_CPU0_G1_TX_DP<5>")
	)
	(segment
		(start 117.66423 -231.017318)
		(end 117.697758 -231.036876)
		(width 0.1143)
		(layer "In11.Cu")
		(net "GMI_CPU1_G3_CPU0_G1_TX_DP<5>")
	)
	(segment
		(start 353.803966 -232.014776)
		(end 353.802442 -232.014014)
		(width 0.1143)
		(layer "In11.Cu")
		(net "GMI_CPU1_G3_CPU0_G1_TX_DP<5>")
	)
	(segment
		(start 154.889454 -184.634632)
		(end 154.87142 -184.817004)
		(width 0.14224)
		(layer "In11.Cu")
		(net "GMI_CPU1_G3_CPU0_G1_TX_DP<5>")
	)
	(segment
		(start 150.805388 -187.983368)
		(end 150.402798 -188.313314)
		(width 0.14224)
		(layer "In11.Cu")
		(net "GMI_CPU1_G3_CPU0_G1_TX_DP<5>")
	)
	(segment
		(start 354.298758 -224.739454)
		(end 354.229162 -224.698814)
		(width 0.1143)
		(layer "In11.Cu")
		(net "GMI_CPU1_G3_CPU0_G1_TX_DP<5>")
	)
	(segment
		(start 149.860762 -188.758068)
		(end 149.530816 -189.028578)
		(width 0.14224)
		(layer "In11.Cu")
		(net "GMI_CPU1_G3_CPU0_G1_TX_DP<5>")
	)
	(arc
		(start 117.197124 -226.35972)
		(mid 117.040147 -226.66452)
		(end 117.197124 -226.96932)
		(width 0.1143)
		(layer "In11.Cu")
		(net "GMI_CPU1_G3_CPU0_G1_TX_DP<5>")
	)
	(arc
		(start 117.040152 -229.90429)
		(mid 117.081701 -230.075712)
		(end 117.197124 -230.20909)
		(width 0.1143)
		(layer "In11.Cu")
		(net "GMI_CPU1_G3_CPU0_G1_TX_DP<5>")
	)
	(arc
		(start 117.26418 -230.248206)
		(mid 117.444832 -230.450951)
		(end 117.510052 -230.71455)
		(width 0.1143)
		(layer "In11.Cu")
		(net "GMI_CPU1_G3_CPU0_G1_TX_DP<5>")
	)
	(arc
		(start 353.98583 -232.334054)
		(mid 353.944575 -232.163083)
		(end 353.829874 -232.029762)
		(width 0.1143)
		(layer "In11.Cu")
		(net "GMI_CPU1_G3_CPU0_G1_TX_DP<5>")
	)
	(arc
		(start 354.229162 -226.318826)
		(mid 353.985835 -225.85426)
		(end 354.229162 -225.389694)
		(width 0.1143)
		(layer "In11.Cu")
		(net "GMI_CPU1_G3_CPU0_G1_TX_DP<5>")
	)
	(arc
		(start 354.45573 -229.904036)
		(mid 354.414764 -229.73363)
		(end 354.30079 -229.600506)
		(width 0.1143)
		(layer "In11.Cu")
		(net "GMI_CPU1_G3_CPU0_G1_TX_DP<5>")
	)
	(arc
		(start 354.448872 -233.07421)
		(mid 354.396455 -232.942279)
		(end 354.298758 -232.83926)
		(width 0.1143)
		(layer "In11.Cu")
		(net "GMI_CPU1_G3_CPU0_G1_TX_DP<5>")
	)
	(arc
		(start 117.26672 -228.629972)
		(mid 117.510047 -229.094538)
		(end 117.26672 -229.559104)
		(width 0.1143)
		(layer "In11.Cu")
		(net "GMI_CPU1_G3_CPU0_G1_TX_DP<5>")
	)
	(arc
		(start 117.26672 -225.389948)
		(mid 117.510047 -225.854514)
		(end 117.26672 -226.31908)
		(width 0.1143)
		(layer "In11.Cu")
		(net "GMI_CPU1_G3_CPU0_G1_TX_DP<5>")
	)
	(arc
		(start 117.197124 -224.739708)
		(mid 117.040147 -225.044508)
		(end 117.197124 -225.349308)
		(width 0.1143)
		(layer "In11.Cu")
		(net "GMI_CPU1_G3_CPU0_G1_TX_DP<5>")
	)
	(arc
		(start 117.197124 -232.839514)
		(mid 117.099359 -232.94249)
		(end 117.04701 -233.074464)
		(width 0.1143)
		(layer "In11.Cu")
		(net "GMI_CPU1_G3_CPU0_G1_TX_DP<5>")
	)
	(arc
		(start 354.298758 -226.969066)
		(mid 354.455735 -226.664266)
		(end 354.298758 -226.359466)
		(width 0.1143)
		(layer "In11.Cu")
		(net "GMI_CPU1_G3_CPU0_G1_TX_DP<5>")
	)
	(arc
		(start 117.197124 -227.979732)
		(mid 117.040147 -228.284532)
		(end 117.197124 -228.589332)
		(width 0.1143)
		(layer "In11.Cu")
		(net "GMI_CPU1_G3_CPU0_G1_TX_DP<5>")
	)
	(arc
		(start 354.229162 -223.078802)
		(mid 353.985835 -222.614236)
		(end 354.229162 -222.14967)
		(width 0.1143)
		(layer "In11.Cu")
		(net "GMI_CPU1_G3_CPU0_G1_TX_DP<5>")
	)
	(arc
		(start 354.298758 -228.589078)
		(mid 354.455735 -228.284278)
		(end 354.298758 -227.979478)
		(width 0.1143)
		(layer "In11.Cu")
		(net "GMI_CPU1_G3_CPU0_G1_TX_DP<5>")
	)
	(arc
		(start 354.229162 -227.938838)
		(mid 353.985835 -227.474272)
		(end 354.229162 -227.009706)
		(width 0.1143)
		(layer "In11.Cu")
		(net "GMI_CPU1_G3_CPU0_G1_TX_DP<5>")
	)
	(arc
		(start 117.666008 -232.030016)
		(mid 117.551332 -232.16335)
		(end 117.510052 -232.334308)
		(width 0.1143)
		(layer "In11.Cu")
		(net "GMI_CPU1_G3_CPU0_G1_TX_DP<5>")
	)
	(arc
		(start 117.510052 -232.334308)
		(mid 117.445537 -232.596527)
		(end 117.26672 -232.798874)
		(width 0.1143)
		(layer "In11.Cu")
		(net "GMI_CPU1_G3_CPU0_G1_TX_DP<5>")
	)
	(arc
		(start 117.197124 -223.119696)
		(mid 117.040147 -223.424496)
		(end 117.197124 -223.729296)
		(width 0.1143)
		(layer "In11.Cu")
		(net "GMI_CPU1_G3_CPU0_G1_TX_DP<5>")
	)
	(arc
		(start 117.510052 -230.71455)
		(mid 117.550814 -230.884434)
		(end 117.66423 -231.017318)
		(width 0.1143)
		(layer "In11.Cu")
		(net "GMI_CPU1_G3_CPU0_G1_TX_DP<5>")
	)
	(arc
		(start 117.26672 -223.769936)
		(mid 117.510047 -224.234502)
		(end 117.26672 -224.699068)
		(width 0.1143)
		(layer "In11.Cu")
		(net "GMI_CPU1_G3_CPU0_G1_TX_DP<5>")
	)
	(arc
		(start 353.759008 -231.988614)
		(mid 353.515681 -231.524048)
		(end 353.759008 -231.059482)
		(width 0.1143)
		(layer "In11.Cu")
		(net "GMI_CPU1_G3_CPU0_G1_TX_DP<5>")
	)
	(arc
		(start 354.298758 -222.10903)
		(mid 354.414185 -221.975654)
		(end 354.45573 -221.80423)
		(width 0.1143)
		(layer "In11.Cu")
		(net "GMI_CPU1_G3_CPU0_G1_TX_DP<5>")
	)
	(arc
		(start 117.736874 -231.059736)
		(mid 117.980201 -231.524302)
		(end 117.736874 -231.988868)
		(width 0.1143)
		(layer "In11.Cu")
		(net "GMI_CPU1_G3_CPU0_G1_TX_DP<5>")
	)
	(arc
		(start 117.26672 -227.00996)
		(mid 117.510047 -227.474526)
		(end 117.26672 -227.939092)
		(width 0.1143)
		(layer "In11.Cu")
		(net "GMI_CPU1_G3_CPU0_G1_TX_DP<5>")
	)
	(arc
		(start 354.298758 -223.729042)
		(mid 354.455735 -223.424242)
		(end 354.298758 -223.119442)
		(width 0.1143)
		(layer "In11.Cu")
		(net "GMI_CPU1_G3_CPU0_G1_TX_DP<5>")
	)
	(arc
		(start 354.229162 -229.55885)
		(mid 353.985835 -229.094284)
		(end 354.229162 -228.629718)
		(width 0.1143)
		(layer "In11.Cu")
		(net "GMI_CPU1_G3_CPU0_G1_TX_DP<5>")
	)
	(arc
		(start 354.298758 -225.349054)
		(mid 354.455735 -225.044254)
		(end 354.298758 -224.739454)
		(width 0.1143)
		(layer "In11.Cu")
		(net "GMI_CPU1_G3_CPU0_G1_TX_DP<5>")
	)
	(arc
		(start 353.831652 -231.017064)
		(mid 353.945059 -230.884175)
		(end 353.98583 -230.714296)
		(width 0.1143)
		(layer "In11.Cu")
		(net "GMI_CPU1_G3_CPU0_G1_TX_DP<5>")
	)
	(arc
		(start 353.98583 -230.714296)
		(mid 354.051066 -230.450705)
		(end 354.231702 -230.247952)
		(width 0.1143)
		(layer "In11.Cu")
		(net "GMI_CPU1_G3_CPU0_G1_TX_DP<5>")
	)
	(arc
		(start 354.229162 -232.79862)
		(mid 354.050349 -232.59627)
		(end 353.98583 -232.334054)
		(width 0.1143)
		(layer "In11.Cu")
		(net "GMI_CPU1_G3_CPU0_G1_TX_DP<5>")
	)
	(arc
		(start 117.195092 -229.60076)
		(mid 117.081163 -229.733907)
		(end 117.040152 -229.90429)
		(width 0.1143)
		(layer "In11.Cu")
		(net "GMI_CPU1_G3_CPU0_G1_TX_DP<5>")
	)
	(arc
		(start 354.298758 -230.208836)
		(mid 354.414185 -230.07546)
		(end 354.45573 -229.904036)
		(width 0.1143)
		(layer "In11.Cu")
		(net "GMI_CPU1_G3_CPU0_G1_TX_DP<5>")
	)
	(arc
		(start 117.040152 -221.804484)
		(mid 117.081701 -221.975906)
		(end 117.197124 -222.109284)
		(width 0.1143)
		(layer "In11.Cu")
		(net "GMI_CPU1_G3_CPU0_G1_TX_DP<5>")
	)
	(arc
		(start 354.229162 -224.698814)
		(mid 353.985835 -224.234248)
		(end 354.229162 -223.769682)
		(width 0.1143)
		(layer "In11.Cu")
		(net "GMI_CPU1_G3_CPU0_G1_TX_DP<5>")
	)
	(arc
		(start 117.26672 -222.149924)
		(mid 117.510047 -222.61449)
		(end 117.26672 -223.079056)
		(width 0.1143)
		(layer "In11.Cu")
		(net "GMI_CPU1_G3_CPU0_G1_TX_DP<5>")
	)
	(segment
		(start 116.94795 -231.79024)
		(end 117.414802 -231.524302)
		(width 0.12954)
		(layer "F.Cu")
		(net "GMI_CPU1_G3_CPU0_G1_TX_DP<4>")
	)
	(segment
		(start 354.547932 -231.789986)
		(end 354.08108 -231.524048)
		(width 0.12954)
		(layer "F.Cu")
		(net "GMI_CPU1_G3_CPU0_G1_TX_DP<4>")
	)
	(segment
		(start 116.288058 -225.367342)
		(end 116.272056 -225.35769)
		(width 0.1143)
		(layer "In11.Cu")
		(net "GMI_CPU1_G3_CPU0_G1_TX_DP<4>")
	)
	(segment
		(start 116.32692 -226.319334)
		(end 116.354606 -226.299268)
		(width 0.1143)
		(layer "In11.Cu")
		(net "GMI_CPU1_G3_CPU0_G1_TX_DP<4>")
	)
	(segment
		(start 116.272056 -225.35769)
		(end 116.256054 -225.348546)
		(width 0.1143)
		(layer "In11.Cu")
		(net "GMI_CPU1_G3_CPU0_G1_TX_DP<4>")
	)
	(segment
		(start 117.414802 -231.524302)
		(end 117.11686 -231.524302)
		(width 0.1143)
		(layer "In11.Cu")
		(net "GMI_CPU1_G3_CPU0_G1_TX_DP<4>")
	)
	(segment
		(start 149.958044 -187.458096)
		(end 149.977094 -187.265056)
		(width 0.14224)
		(layer "In11.Cu")
		(net "GMI_CPU1_G3_CPU0_G1_TX_DP<4>")
	)
	(segment
		(start 148.562568 -188.42482)
		(end 148.755608 -188.444124)
		(width 0.14224)
		(layer "In11.Cu")
		(net "GMI_CPU1_G3_CPU0_G1_TX_DP<4>")
	)
	(segment
		(start 116.79682 -231.059736)
		(end 116.727986 -231.019858)
		(width 0.1143)
		(layer "In11.Cu")
		(net "GMI_CPU1_G3_CPU0_G1_TX_DP<4>")
	)
	(segment
		(start 355.20376 -223.099376)
		(end 355.208078 -223.101662)
		(width 0.1143)
		(layer "In11.Cu")
		(net "GMI_CPU1_G3_CPU0_G1_TX_DP<4>")
	)
	(segment
		(start 355.206046 -230.227632)
		(end 355.168454 -230.249984)
		(width 0.1143)
		(layer "In11.Cu")
		(net "GMI_CPU1_G3_CPU0_G1_TX_DP<4>")
	)
	(segment
		(start 355.202236 -223.09836)
		(end 355.20376 -223.099376)
		(width 0.1143)
		(layer "In11.Cu")
		(net "GMI_CPU1_G3_CPU0_G1_TX_DP<4>")
	)
	(segment
		(start 147.883372 -189.159134)
		(end 148.213572 -188.88837)
		(width 0.14224)
		(layer "In11.Cu")
		(net "GMI_CPU1_G3_CPU0_G1_TX_DP<4>")
	)
	(segment
		(start 116.32692 -224.699322)
		(end 116.354606 -224.679256)
		(width 0.1143)
		(layer "In11.Cu")
		(net "GMI_CPU1_G3_CPU0_G1_TX_DP<4>")
	)
	(segment
		(start 150.849584 -186.5503)
		(end 151.17953 -186.27979)
		(width 0.14224)
		(layer "In11.Cu")
		(net "GMI_CPU1_G3_CPU0_G1_TX_DP<4>")
	)
	(segment
		(start 116.354606 -225.40976)
		(end 116.32692 -225.389694)
		(width 0.1143)
		(layer "In11.Cu")
		(net "GMI_CPU1_G3_CPU0_G1_TX_DP<4>")
	)
	(segment
		(start 116.256054 -225.348546)
		(end 116.256054 -225.3488)
		(width 0.1143)
		(layer "In11.Cu")
		(net "GMI_CPU1_G3_CPU0_G1_TX_DP<4>")
	)
	(segment
		(start 149.105112 -187.980574)
		(end 149.435058 -187.710064)
		(width 0.14224)
		(layer "In11.Cu")
		(net "GMI_CPU1_G3_CPU0_G1_TX_DP<4>")
	)
	(segment
		(start 354.461826 -231.441244)
		(end 354.379022 -231.524048)
		(width 0.1143)
		(layer "In11.Cu")
		(net "GMI_CPU1_G3_CPU0_G1_TX_DP<4>")
	)
	(segment
		(start 116.045996 -221.129098)
		(end 116.091716 -221.083378)
		(width 0.1143)
		(layer "In11.Cu")
		(net "GMI_CPU1_G3_CPU0_G1_TX_DP<4>")
	)
	(segment
		(start 355.239828 -223.72828)
		(end 355.223826 -223.737424)
		(width 0.1143)
		(layer "In11.Cu")
		(net "GMI_CPU1_G3_CPU0_G1_TX_DP<4>")
	)
	(segment
		(start 152.593802 -185.119518)
		(end 157.824932 -180.830728)
		(width 0.14224)
		(layer "In11.Cu")
		(net "GMI_CPU1_G3_CPU0_G1_TX_DP<4>")
	)
	(segment
		(start 116.100098 -221.401386)
		(end 116.045996 -221.347284)
		(width 0.1143)
		(layer "In11.Cu")
		(net "GMI_CPU1_G3_CPU0_G1_TX_DP<4>")
	)
	(segment
		(start 147.690586 -189.140338)
		(end 147.690332 -189.13983)
		(width 0.14224)
		(layer "In11.Cu")
		(net "GMI_CPU1_G3_CPU0_G1_TX_DP<4>")
	)
	(segment
		(start 119.768874 -212.033866)
		(end 132.858002 -201.301858)
		(width 0.14224)
		(layer "In11.Cu")
		(net "GMI_CPU1_G3_CPU0_G1_TX_DP<4>")
	)
	(segment
		(start 117.11686 -231.524302)
		(end 117.034056 -231.441498)
		(width 0.1143)
		(layer "In11.Cu")
		(net "GMI_CPU1_G3_CPU0_G1_TX_DP<4>")
	)
	(segment
		(start 152.574752 -185.312304)
		(end 152.593802 -185.119518)
		(width 0.14224)
		(layer "In11.Cu")
		(net "GMI_CPU1_G3_CPU0_G1_TX_DP<4>")
	)
	(segment
		(start 355.208078 -223.101662)
		(end 355.239828 -223.11995)
		(width 0.1143)
		(layer "In11.Cu")
		(net "GMI_CPU1_G3_CPU0_G1_TX_DP<4>")
	)
	(segment
		(start 116.091716 -221.071948)
		(end 116.091716 -218.226894)
		(width 0.14224)
		(layer "In11.Cu")
		(net "GMI_CPU1_G3_CPU0_G1_TX_DP<4>")
	)
	(segment
		(start 165.655498 -178.030632)
		(end 302.907192 -178.831748)
		(width 0.14224)
		(layer "In11.Cu")
		(net "GMI_CPU1_G3_CPU0_G1_TX_DP<4>")
	)
	(segment
		(start 149.104858 -187.98032)
		(end 149.105112 -187.980574)
		(width 0.14224)
		(layer "In11.Cu")
		(net "GMI_CPU1_G3_CPU0_G1_TX_DP<4>")
	)
	(segment
		(start 149.977348 -187.265564)
		(end 150.307294 -186.9948)
		(width 0.14224)
		(layer "In11.Cu")
		(net "GMI_CPU1_G3_CPU0_G1_TX_DP<4>")
	)
	(segment
		(start 355.168962 -223.769428)
		(end 355.141276 -223.789494)
		(width 0.1143)
		(layer "In11.Cu")
		(net "GMI_CPU1_G3_CPU0_G1_TX_DP<4>")
	)
	(segment
		(start 116.091716 -221.083378)
		(end 116.091716 -221.071948)
		(width 0.1143)
		(layer "In11.Cu")
		(net "GMI_CPU1_G3_CPU0_G1_TX_DP<4>")
	)
	(segment
		(start 355.207824 -226.9871)
		(end 355.168962 -227.009452)
		(width 0.1143)
		(layer "In11.Cu")
		(net "GMI_CPU1_G3_CPU0_G1_TX_DP<4>")
	)
	(segment
		(start 157.824932 -180.830728)
		(end 165.655498 -178.030632)
		(width 0.14224)
		(layer "In11.Cu")
		(net "GMI_CPU1_G3_CPU0_G1_TX_DP<4>")
	)
	(segment
		(start 146.48815 -190.125604)
		(end 146.488404 -190.126112)
		(width 0.14224)
		(layer "In11.Cu")
		(net "GMI_CPU1_G3_CPU0_G1_TX_DP<4>")
	)
	(segment
		(start 148.232876 -188.695838)
		(end 148.562822 -188.425328)
		(width 0.14224)
		(layer "In11.Cu")
		(net "GMI_CPU1_G3_CPU0_G1_TX_DP<4>")
	)
	(segment
		(start 152.051512 -185.564018)
		(end 152.244552 -185.583322)
		(width 0.14224)
		(layer "In11.Cu")
		(net "GMI_CPU1_G3_CPU0_G1_TX_DP<4>")
	)
	(segment
		(start 116.28882 -230.227378)
		(end 116.28755 -230.226616)
		(width 0.1143)
		(layer "In11.Cu")
		(net "GMI_CPU1_G3_CPU0_G1_TX_DP<4>")
	)
	(segment
		(start 150.50008 -187.01385)
		(end 150.83028 -186.742832)
		(width 0.14224)
		(layer "In11.Cu")
		(net "GMI_CPU1_G3_CPU0_G1_TX_DP<4>")
	)
	(segment
		(start 355.239828 -223.728534)
		(end 355.239828 -223.72828)
		(width 0.1143)
		(layer "In11.Cu")
		(net "GMI_CPU1_G3_CPU0_G1_TX_DP<4>")
	)
	(segment
		(start 151.721566 -185.834528)
		(end 151.722074 -185.835036)
		(width 0.14224)
		(layer "In11.Cu")
		(net "GMI_CPU1_G3_CPU0_G1_TX_DP<4>")
	)
	(segment
		(start 355.208332 -230.226362)
		(end 355.207062 -230.227124)
		(width 0.1143)
		(layer "In11.Cu")
		(net "GMI_CPU1_G3_CPU0_G1_TX_DP<4>")
	)
	(segment
		(start 355.200712 -223.097598)
		(end 355.202236 -223.09836)
		(width 0.1143)
		(layer "In11.Cu")
		(net "GMI_CPU1_G3_CPU0_G1_TX_DP<4>")
	)
	(segment
		(start 355.449886 -221.34703)
		(end 355.395784 -221.401132)
		(width 0.1143)
		(layer "In11.Cu")
		(net "GMI_CPU1_G3_CPU0_G1_TX_DP<4>")
	)
	(segment
		(start 147.011136 -189.874144)
		(end 147.341336 -189.60338)
		(width 0.14224)
		(layer "In11.Cu")
		(net "GMI_CPU1_G3_CPU0_G1_TX_DP<4>")
	)
	(segment
		(start 150.84933 -186.549792)
		(end 150.849584 -186.5503)
		(width 0.14224)
		(layer "In11.Cu")
		(net "GMI_CPU1_G3_CPU0_G1_TX_DP<4>")
	)
	(segment
		(start 355.395784 -229.903782)
		(end 355.395784 -229.904036)
		(width 0.1143)
		(layer "In11.Cu")
		(net "GMI_CPU1_G3_CPU0_G1_TX_DP<4>")
	)
	(segment
		(start 355.239828 -228.58857)
		(end 355.208078 -228.606858)
		(width 0.1143)
		(layer "In11.Cu")
		(net "GMI_CPU1_G3_CPU0_G1_TX_DP<4>")
	)
	(segment
		(start 116.439188 -230.330756)
		(end 116.327428 -230.250238)
		(width 0.1143)
		(layer "In11.Cu")
		(net "GMI_CPU1_G3_CPU0_G1_TX_DP<4>")
	)
	(segment
		(start 152.051766 -185.564526)
		(end 152.051512 -185.564018)
		(width 0.14224)
		(layer "In11.Cu")
		(net "GMI_CPU1_G3_CPU0_G1_TX_DP<4>")
	)
	(segment
		(start 116.254276 -229.601522)
		(end 116.324126 -229.560882)
		(width 0.1143)
		(layer "In11.Cu")
		(net "GMI_CPU1_G3_CPU0_G1_TX_DP<4>")
	)
	(segment
		(start 355.207824 -225.367088)
		(end 355.168962 -225.38944)
		(width 0.1143)
		(layer "In11.Cu")
		(net "GMI_CPU1_G3_CPU0_G1_TX_DP<4>")
	)
	(segment
		(start 302.907192 -178.831748)
		(end 307.805836 -178.831748)
		(width 0.14224)
		(layer "In11.Cu")
		(net "GMI_CPU1_G3_CPU0_G1_TX_DP<4>")
	)
	(segment
		(start 116.324126 -228.628194)
		(end 116.287804 -228.607112)
		(width 0.1143)
		(layer "In11.Cu")
		(net "GMI_CPU1_G3_CPU0_G1_TX_DP<4>")
	)
	(segment
		(start 355.404166 -218.322398)
		(end 355.404166 -221.071694)
		(width 0.14224)
		(layer "In11.Cu")
		(net "GMI_CPU1_G3_CPU0_G1_TX_DP<4>")
	)
	(segment
		(start 355.171756 -229.560628)
		(end 355.241606 -229.601268)
		(width 0.1143)
		(layer "In11.Cu")
		(net "GMI_CPU1_G3_CPU0_G1_TX_DP<4>")
	)
	(segment
		(start 145.946876 -190.570358)
		(end 146.1389 -190.589408)
		(width 0.14224)
		(layer "In11.Cu")
		(net "GMI_CPU1_G3_CPU0_G1_TX_DP<4>")
	)
	(segment
		(start 150.83028 -186.742832)
		(end 150.84933 -186.549792)
		(width 0.14224)
		(layer "In11.Cu")
		(net "GMI_CPU1_G3_CPU0_G1_TX_DP<4>")
	)
	(segment
		(start 116.256054 -224.740216)
		(end 116.32692 -224.699322)
		(width 0.1143)
		(layer "In11.Cu")
		(net "GMI_CPU1_G3_CPU0_G1_TX_DP<4>")
	)
	(segment
		(start 151.179276 -186.279282)
		(end 151.372316 -186.298586)
		(width 0.14224)
		(layer "In11.Cu")
		(net "GMI_CPU1_G3_CPU0_G1_TX_DP<4>")
	)
	(segment
		(start 355.239828 -225.348546)
		(end 355.239828 -225.348292)
		(width 0.1143)
		(layer "In11.Cu")
		(net "GMI_CPU1_G3_CPU0_G1_TX_DP<4>")
	)
	(segment
		(start 148.232622 -188.69533)
		(end 148.232876 -188.695838)
		(width 0.14224)
		(layer "In11.Cu")
		(net "GMI_CPU1_G3_CPU0_G1_TX_DP<4>")
	)
	(segment
		(start 355.168962 -227.009452)
		(end 355.141276 -227.029518)
		(width 0.1143)
		(layer "In11.Cu")
		(net "GMI_CPU1_G3_CPU0_G1_TX_DP<4>")
	)
	(segment
		(start 149.977094 -187.265056)
		(end 149.977348 -187.265564)
		(width 0.14224)
		(layer "In11.Cu")
		(net "GMI_CPU1_G3_CPU0_G1_TX_DP<4>")
	)
	(segment
		(start 116.272056 -223.737678)
		(end 116.256054 -223.728534)
		(width 0.1143)
		(layer "In11.Cu")
		(net "GMI_CPU1_G3_CPU0_G1_TX_DP<4>")
	)
	(segment
		(start 116.307362 -223.090486)
		(end 116.30914 -223.08947)
		(width 0.1143)
		(layer "In11.Cu")
		(net "GMI_CPU1_G3_CPU0_G1_TX_DP<4>")
	)
	(segment
		(start 116.354606 -227.029772)
		(end 116.32692 -227.009706)
		(width 0.1143)
		(layer "In11.Cu")
		(net "GMI_CPU1_G3_CPU0_G1_TX_DP<4>")
	)
	(segment
		(start 151.17953 -186.27979)
		(end 151.179276 -186.279282)
		(width 0.14224)
		(layer "In11.Cu")
		(net "GMI_CPU1_G3_CPU0_G1_TX_DP<4>")
	)
	(segment
		(start 355.168962 -224.699068)
		(end 355.239828 -224.739962)
		(width 0.1143)
		(layer "In11.Cu")
		(net "GMI_CPU1_G3_CPU0_G1_TX_DP<4>")
	)
	(segment
		(start 355.239828 -222.108522)
		(end 355.186742 -222.139256)
		(width 0.1143)
		(layer "In11.Cu")
		(net "GMI_CPU1_G3_CPU0_G1_TX_DP<4>")
	)
	(segment
		(start 116.256054 -226.360228)
		(end 116.32692 -226.319334)
		(width 0.1143)
		(layer "In11.Cu")
		(net "GMI_CPU1_G3_CPU0_G1_TX_DP<4>")
	)
	(segment
		(start 355.209856 -230.2256)
		(end 355.208332 -230.226362)
		(width 0.1143)
		(layer "In11.Cu")
		(net "GMI_CPU1_G3_CPU0_G1_TX_DP<4>")
	)
	(segment
		(start 116.256054 -227.98024)
		(end 116.32692 -227.939346)
		(width 0.1143)
		(layer "In11.Cu")
		(net "GMI_CPU1_G3_CPU0_G1_TX_DP<4>")
	)
	(segment
		(start 355.196902 -223.095312)
		(end 355.200712 -223.097598)
		(width 0.1143)
		(layer "In11.Cu")
		(net "GMI_CPU1_G3_CPU0_G1_TX_DP<4>")
	)
	(segment
		(start 147.36064 -189.410848)
		(end 147.690586 -189.140338)
		(width 0.14224)
		(layer "In11.Cu")
		(net "GMI_CPU1_G3_CPU0_G1_TX_DP<4>")
	)
	(segment
		(start 146.1389 -190.589408)
		(end 146.4691 -190.318644)
		(width 0.14224)
		(layer "In11.Cu")
		(net "GMI_CPU1_G3_CPU0_G1_TX_DP<4>")
	)
	(segment
		(start 355.19614 -223.094804)
		(end 355.196902 -223.095312)
		(width 0.1143)
		(layer "In11.Cu")
		(net "GMI_CPU1_G3_CPU0_G1_TX_DP<4>")
	)
	(segment
		(start 116.091716 -218.226894)
		(end 119.768874 -212.033866)
		(width 0.14224)
		(layer "In11.Cu")
		(net "GMI_CPU1_G3_CPU0_G1_TX_DP<4>")
	)
	(segment
		(start 355.207824 -223.747076)
		(end 355.168962 -223.769428)
		(width 0.1143)
		(layer "In11.Cu")
		(net "GMI_CPU1_G3_CPU0_G1_TX_DP<4>")
	)
	(segment
		(start 151.372316 -186.298586)
		(end 151.702516 -186.027568)
		(width 0.14224)
		(layer "In11.Cu")
		(net "GMI_CPU1_G3_CPU0_G1_TX_DP<4>")
	)
	(segment
		(start 355.141276 -224.679002)
		(end 355.168962 -224.699068)
		(width 0.1143)
		(layer "In11.Cu")
		(net "GMI_CPU1_G3_CPU0_G1_TX_DP<4>")
	)
	(segment
		(start 152.244552 -185.583322)
		(end 152.574752 -185.312304)
		(width 0.14224)
		(layer "In11.Cu")
		(net "GMI_CPU1_G3_CPU0_G1_TX_DP<4>")
	)
	(segment
		(start 355.223826 -226.977448)
		(end 355.207824 -226.9871)
		(width 0.1143)
		(layer "In11.Cu")
		(net "GMI_CPU1_G3_CPU0_G1_TX_DP<4>")
	)
	(segment
		(start 116.32692 -227.939346)
		(end 116.354606 -227.91928)
		(width 0.1143)
		(layer "In11.Cu")
		(net "GMI_CPU1_G3_CPU0_G1_TX_DP<4>")
	)
	(segment
		(start 355.194616 -223.094042)
		(end 355.19614 -223.094804)
		(width 0.1143)
		(layer "In11.Cu")
		(net "GMI_CPU1_G3_CPU0_G1_TX_DP<4>")
	)
	(segment
		(start 355.141276 -227.919026)
		(end 355.168962 -227.939092)
		(width 0.1143)
		(layer "In11.Cu")
		(net "GMI_CPU1_G3_CPU0_G1_TX_DP<4>")
	)
	(segment
		(start 147.341336 -189.60338)
		(end 147.360386 -189.41034)
		(width 0.14224)
		(layer "In11.Cu")
		(net "GMI_CPU1_G3_CPU0_G1_TX_DP<4>")
	)
	(segment
		(start 355.18852 -223.090232)
		(end 355.190044 -223.091248)
		(width 0.1143)
		(layer "In11.Cu")
		(net "GMI_CPU1_G3_CPU0_G1_TX_DP<4>")
	)
	(segment
		(start 355.207062 -230.227124)
		(end 355.206046 -230.227632)
		(width 0.1143)
		(layer "In11.Cu")
		(net "GMI_CPU1_G3_CPU0_G1_TX_DP<4>")
	)
	(segment
		(start 355.208078 -228.606858)
		(end 355.171756 -228.62794)
		(width 0.1143)
		(layer "In11.Cu")
		(net "GMI_CPU1_G3_CPU0_G1_TX_DP<4>")
	)
	(segment
		(start 116.287804 -228.607112)
		(end 116.256054 -228.588824)
		(width 0.1143)
		(layer "In11.Cu")
		(net "GMI_CPU1_G3_CPU0_G1_TX_DP<4>")
	)
	(segment
		(start 355.449886 -221.128844)
		(end 355.449886 -221.34703)
		(width 0.1143)
		(layer "In11.Cu")
		(net "GMI_CPU1_G3_CPU0_G1_TX_DP<4>")
	)
	(segment
		(start 355.168962 -227.939092)
		(end 355.239828 -227.979986)
		(width 0.1143)
		(layer "In11.Cu")
		(net "GMI_CPU1_G3_CPU0_G1_TX_DP<4>")
	)
	(segment
		(start 355.141276 -226.299014)
		(end 355.168962 -226.31908)
		(width 0.1143)
		(layer "In11.Cu")
		(net "GMI_CPU1_G3_CPU0_G1_TX_DP<4>")
	)
	(segment
		(start 147.360386 -189.41034)
		(end 147.36064 -189.410848)
		(width 0.14224)
		(layer "In11.Cu")
		(net "GMI_CPU1_G3_CPU0_G1_TX_DP<4>")
	)
	(segment
		(start 354.767896 -231.019604)
		(end 354.699062 -231.059482)
		(width 0.1143)
		(layer "In11.Cu")
		(net "GMI_CPU1_G3_CPU0_G1_TX_DP<4>")
	)
	(segment
		(start 354.925884 -230.585772)
		(end 354.925884 -230.714296)
		(width 0.1143)
		(layer "In11.Cu")
		(net "GMI_CPU1_G3_CPU0_G1_TX_DP<4>")
	)
	(segment
		(start 354.379022 -231.524048)
		(end 354.08108 -231.524048)
		(width 0.1143)
		(layer "In11.Cu")
		(net "GMI_CPU1_G3_CPU0_G1_TX_DP<4>")
	)
	(segment
		(start 116.327428 -230.250238)
		(end 116.28882 -230.227378)
		(width 0.1143)
		(layer "In11.Cu")
		(net "GMI_CPU1_G3_CPU0_G1_TX_DP<4>")
	)
	(segment
		(start 116.100098 -221.804484)
		(end 116.100098 -221.401386)
		(width 0.1143)
		(layer "In11.Cu")
		(net "GMI_CPU1_G3_CPU0_G1_TX_DP<4>")
	)
	(segment
		(start 116.3066 -223.090994)
		(end 116.307362 -223.090486)
		(width 0.1143)
		(layer "In11.Cu")
		(net "GMI_CPU1_G3_CPU0_G1_TX_DP<4>")
	)
	(segment
		(start 355.168454 -230.249984)
		(end 355.056694 -230.330502)
		(width 0.1143)
		(layer "In11.Cu")
		(net "GMI_CPU1_G3_CPU0_G1_TX_DP<4>")
	)
	(segment
		(start 132.858002 -201.301858)
		(end 132.858002 -201.302112)
		(width 0.14224)
		(layer "In11.Cu")
		(net "GMI_CPU1_G3_CPU0_G1_TX_DP<4>")
	)
	(segment
		(start 148.755608 -188.444124)
		(end 149.085808 -188.17336)
		(width 0.14224)
		(layer "In11.Cu")
		(net "GMI_CPU1_G3_CPU0_G1_TX_DP<4>")
	)
	(segment
		(start 116.100098 -229.90429)
		(end 116.100098 -229.904036)
		(width 0.1143)
		(layer "In11.Cu")
		(net "GMI_CPU1_G3_CPU0_G1_TX_DP<4>")
	)
	(segment
		(start 148.213572 -188.88837)
		(end 148.232622 -188.69533)
		(width 0.14224)
		(layer "In11.Cu")
		(net "GMI_CPU1_G3_CPU0_G1_TX_DP<4>")
	)
	(segment
		(start 116.256054 -223.120204)
		(end 116.287804 -223.101916)
		(width 0.1143)
		(layer "In11.Cu")
		(net "GMI_CPU1_G3_CPU0_G1_TX_DP<4>")
	)
	(segment
		(start 116.272056 -226.977702)
		(end 116.256054 -226.968558)
		(width 0.1143)
		(layer "In11.Cu")
		(net "GMI_CPU1_G3_CPU0_G1_TX_DP<4>")
	)
	(segment
		(start 116.354606 -223.789748)
		(end 116.32692 -223.769682)
		(width 0.1143)
		(layer "In11.Cu")
		(net "GMI_CPU1_G3_CPU0_G1_TX_DP<4>")
	)
	(segment
		(start 116.288058 -226.987354)
		(end 116.272056 -226.977702)
		(width 0.1143)
		(layer "In11.Cu")
		(net "GMI_CPU1_G3_CPU0_G1_TX_DP<4>")
	)
	(segment
		(start 116.256054 -226.968558)
		(end 116.256054 -226.968812)
		(width 0.1143)
		(layer "In11.Cu")
		(net "GMI_CPU1_G3_CPU0_G1_TX_DP<4>")
	)
	(segment
		(start 355.223826 -223.737424)
		(end 355.207824 -223.747076)
		(width 0.1143)
		(layer "In11.Cu")
		(net "GMI_CPU1_G3_CPU0_G1_TX_DP<4>")
	)
	(segment
		(start 355.186742 -223.089216)
		(end 355.18852 -223.090232)
		(width 0.1143)
		(layer "In11.Cu")
		(net "GMI_CPU1_G3_CPU0_G1_TX_DP<4>")
	)
	(segment
		(start 116.32692 -227.009706)
		(end 116.288058 -226.987354)
		(width 0.1143)
		(layer "In11.Cu")
		(net "GMI_CPU1_G3_CPU0_G1_TX_DP<4>")
	)
	(segment
		(start 116.256054 -223.728534)
		(end 116.256054 -223.728788)
		(width 0.1143)
		(layer "In11.Cu")
		(net "GMI_CPU1_G3_CPU0_G1_TX_DP<4>")
	)
	(segment
		(start 146.4691 -190.318644)
		(end 146.48815 -190.125604)
		(width 0.14224)
		(layer "In11.Cu")
		(net "GMI_CPU1_G3_CPU0_G1_TX_DP<4>")
	)
	(segment
		(start 355.239828 -226.968304)
		(end 355.223826 -226.977448)
		(width 0.1143)
		(layer "In11.Cu")
		(net "GMI_CPU1_G3_CPU0_G1_TX_DP<4>")
	)
	(segment
		(start 116.287804 -223.101916)
		(end 116.3066 -223.090994)
		(width 0.1143)
		(layer "In11.Cu")
		(net "GMI_CPU1_G3_CPU0_G1_TX_DP<4>")
	)
	(segment
		(start 146.818096 -189.855094)
		(end 147.011136 -189.874144)
		(width 0.14224)
		(layer "In11.Cu")
		(net "GMI_CPU1_G3_CPU0_G1_TX_DP<4>")
	)
	(segment
		(start 355.239828 -225.348292)
		(end 355.223826 -225.357436)
		(width 0.1143)
		(layer "In11.Cu")
		(net "GMI_CPU1_G3_CPU0_G1_TX_DP<4>")
	)
	(segment
		(start 149.085808 -188.17336)
		(end 149.104858 -187.98032)
		(width 0.14224)
		(layer "In11.Cu")
		(net "GMI_CPU1_G3_CPU0_G1_TX_DP<4>")
	)
	(segment
		(start 132.858002 -201.302112)
		(end 145.946876 -190.570358)
		(width 0.14224)
		(layer "In11.Cu")
		(net "GMI_CPU1_G3_CPU0_G1_TX_DP<4>")
	)
	(segment
		(start 150.307294 -186.9948)
		(end 150.30704 -186.994546)
		(width 0.14224)
		(layer "In11.Cu")
		(net "GMI_CPU1_G3_CPU0_G1_TX_DP<4>")
	)
	(segment
		(start 355.192838 -223.092772)
		(end 355.194616 -223.094042)
		(width 0.1143)
		(layer "In11.Cu")
		(net "GMI_CPU1_G3_CPU0_G1_TX_DP<4>")
	)
	(segment
		(start 149.627844 -187.729114)
		(end 149.958044 -187.458096)
		(width 0.14224)
		(layer "In11.Cu")
		(net "GMI_CPU1_G3_CPU0_G1_TX_DP<4>")
	)
	(segment
		(start 316.53861 -183.312816)
		(end 351.769172 -212.20049)
		(width 0.14224)
		(layer "In11.Cu")
		(net "GMI_CPU1_G3_CPU0_G1_TX_DP<4>")
	)
	(segment
		(start 355.404166 -221.083124)
		(end 355.449886 -221.128844)
		(width 0.1143)
		(layer "In11.Cu")
		(net "GMI_CPU1_G3_CPU0_G1_TX_DP<4>")
	)
	(segment
		(start 307.805836 -178.831748)
		(end 310.023256 -179.624482)
		(width 0.14224)
		(layer "In11.Cu")
		(net "GMI_CPU1_G3_CPU0_G1_TX_DP<4>")
	)
	(segment
		(start 150.30704 -186.994546)
		(end 150.50008 -187.01385)
		(width 0.14224)
		(layer "In11.Cu")
		(net "GMI_CPU1_G3_CPU0_G1_TX_DP<4>")
	)
	(segment
		(start 355.239828 -226.968558)
		(end 355.239828 -226.968304)
		(width 0.1143)
		(layer "In11.Cu")
		(net "GMI_CPU1_G3_CPU0_G1_TX_DP<4>")
	)
	(segment
		(start 116.569998 -230.71455)
		(end 116.569998 -230.586026)
		(width 0.1143)
		(layer "In11.Cu")
		(net "GMI_CPU1_G3_CPU0_G1_TX_DP<4>")
	)
	(segment
		(start 116.28755 -230.226616)
		(end 116.286026 -230.225854)
		(width 0.1143)
		(layer "In11.Cu")
		(net "GMI_CPU1_G3_CPU0_G1_TX_DP<4>")
	)
	(segment
		(start 310.023256 -179.624482)
		(end 316.53861 -183.312816)
		(width 0.14224)
		(layer "In11.Cu")
		(net "GMI_CPU1_G3_CPU0_G1_TX_DP<4>")
	)
	(segment
		(start 147.690332 -189.13983)
		(end 147.883372 -189.159134)
		(width 0.14224)
		(layer "In11.Cu")
		(net "GMI_CPU1_G3_CPU0_G1_TX_DP<4>")
	)
	(segment
		(start 116.30914 -222.13951)
		(end 116.256054 -222.108776)
		(width 0.1143)
		(layer "In11.Cu")
		(net "GMI_CPU1_G3_CPU0_G1_TX_DP<4>")
	)
	(segment
		(start 151.702516 -186.027568)
		(end 151.721566 -185.834528)
		(width 0.14224)
		(layer "In11.Cu")
		(net "GMI_CPU1_G3_CPU0_G1_TX_DP<4>")
	)
	(segment
		(start 355.404166 -221.071694)
		(end 355.404166 -221.083124)
		(width 0.1143)
		(layer "In11.Cu")
		(net "GMI_CPU1_G3_CPU0_G1_TX_DP<4>")
	)
	(segment
		(start 146.488404 -190.126112)
		(end 146.81835 -189.855602)
		(width 0.14224)
		(layer "In11.Cu")
		(net "GMI_CPU1_G3_CPU0_G1_TX_DP<4>")
	)
	(segment
		(start 355.168962 -225.38944)
		(end 355.141276 -225.409506)
		(width 0.1143)
		(layer "In11.Cu")
		(net "GMI_CPU1_G3_CPU0_G1_TX_DP<4>")
	)
	(segment
		(start 355.168962 -226.31908)
		(end 355.239828 -226.359974)
		(width 0.1143)
		(layer "In11.Cu")
		(net "GMI_CPU1_G3_CPU0_G1_TX_DP<4>")
	)
	(segment
		(start 151.722074 -185.835036)
		(end 152.051766 -185.564526)
		(width 0.14224)
		(layer "In11.Cu")
		(net "GMI_CPU1_G3_CPU0_G1_TX_DP<4>")
	)
	(segment
		(start 116.288058 -223.74733)
		(end 116.272056 -223.737678)
		(width 0.1143)
		(layer "In11.Cu")
		(net "GMI_CPU1_G3_CPU0_G1_TX_DP<4>")
	)
	(segment
		(start 148.562822 -188.425328)
		(end 148.562568 -188.42482)
		(width 0.14224)
		(layer "In11.Cu")
		(net "GMI_CPU1_G3_CPU0_G1_TX_DP<4>")
	)
	(segment
		(start 355.395784 -221.401132)
		(end 355.395784 -221.80423)
		(width 0.1143)
		(layer "In11.Cu")
		(net "GMI_CPU1_G3_CPU0_G1_TX_DP<4>")
	)
	(segment
		(start 351.769172 -212.20049)
		(end 355.404166 -218.322398)
		(width 0.14224)
		(layer "In11.Cu")
		(net "GMI_CPU1_G3_CPU0_G1_TX_DP<4>")
	)
	(segment
		(start 149.434804 -187.70981)
		(end 149.627844 -187.729114)
		(width 0.14224)
		(layer "In11.Cu")
		(net "GMI_CPU1_G3_CPU0_G1_TX_DP<4>")
	)
	(segment
		(start 116.045996 -221.347284)
		(end 116.045996 -221.129098)
		(width 0.1143)
		(layer "In11.Cu")
		(net "GMI_CPU1_G3_CPU0_G1_TX_DP<4>")
	)
	(segment
		(start 355.223826 -225.357436)
		(end 355.207824 -225.367088)
		(width 0.1143)
		(layer "In11.Cu")
		(net "GMI_CPU1_G3_CPU0_G1_TX_DP<4>")
	)
	(segment
		(start 116.32692 -225.389694)
		(end 116.288058 -225.367342)
		(width 0.1143)
		(layer "In11.Cu")
		(net "GMI_CPU1_G3_CPU0_G1_TX_DP<4>")
	)
	(segment
		(start 116.32692 -223.769682)
		(end 116.288058 -223.74733)
		(width 0.1143)
		(layer "In11.Cu")
		(net "GMI_CPU1_G3_CPU0_G1_TX_DP<4>")
	)
	(segment
		(start 355.190044 -223.091248)
		(end 355.192838 -223.092772)
		(width 0.1143)
		(layer "In11.Cu")
		(net "GMI_CPU1_G3_CPU0_G1_TX_DP<4>")
	)
	(segment
		(start 149.435058 -187.710064)
		(end 149.434804 -187.70981)
		(width 0.14224)
		(layer "In11.Cu")
		(net "GMI_CPU1_G3_CPU0_G1_TX_DP<4>")
	)
	(segment
		(start 146.81835 -189.855602)
		(end 146.818096 -189.855094)
		(width 0.14224)
		(layer "In11.Cu")
		(net "GMI_CPU1_G3_CPU0_G1_TX_DP<4>")
	)
	(arc
		(start 116.727986 -231.019858)
		(mid 116.611939 -230.886387)
		(end 116.569998 -230.71455)
		(width 0.1143)
		(layer "In11.Cu")
		(net "GMI_CPU1_G3_CPU0_G1_TX_DP<4>")
	)
	(arc
		(start 355.141276 -227.029518)
		(mid 354.913276 -227.474272)
		(end 355.141276 -227.919026)
		(width 0.1143)
		(layer "In11.Cu")
		(net "GMI_CPU1_G3_CPU0_G1_TX_DP<4>")
	)
	(arc
		(start 354.465636 -231.418384)
		(mid 354.463613 -231.429794)
		(end 354.461826 -231.441244)
		(width 0.1143)
		(layer "In11.Cu")
		(net "GMI_CPU1_G3_CPU0_G1_TX_DP<4>")
	)
	(arc
		(start 116.30914 -223.08947)
		(mid 116.582691 -222.61449)
		(end 116.30914 -222.13951)
		(width 0.1143)
		(layer "In11.Cu")
		(net "GMI_CPU1_G3_CPU0_G1_TX_DP<4>")
	)
	(arc
		(start 117.030246 -231.418638)
		(mid 116.948813 -231.21624)
		(end 116.79682 -231.059736)
		(width 0.1143)
		(layer "In11.Cu")
		(net "GMI_CPU1_G3_CPU0_G1_TX_DP<4>")
	)
	(arc
		(start 354.925884 -230.714296)
		(mid 354.884005 -230.886165)
		(end 354.767896 -231.019604)
		(width 0.1143)
		(layer "In11.Cu")
		(net "GMI_CPU1_G3_CPU0_G1_TX_DP<4>")
	)
	(arc
		(start 355.395784 -229.904036)
		(mid 355.345961 -230.089766)
		(end 355.209856 -230.2256)
		(width 0.1143)
		(layer "In11.Cu")
		(net "GMI_CPU1_G3_CPU0_G1_TX_DP<4>")
	)
	(arc
		(start 116.354606 -224.679256)
		(mid 116.582606 -224.234502)
		(end 116.354606 -223.789748)
		(width 0.1143)
		(layer "In11.Cu")
		(net "GMI_CPU1_G3_CPU0_G1_TX_DP<4>")
	)
	(arc
		(start 116.569998 -229.089204)
		(mid 116.505536 -228.838)
		(end 116.339366 -228.638862)
		(width 0.1143)
		(layer "In11.Cu")
		(net "GMI_CPU1_G3_CPU0_G1_TX_DP<4>")
	)
	(arc
		(start 355.171756 -228.62794)
		(mid 355.164092 -228.633211)
		(end 355.156516 -228.638608)
		(width 0.1143)
		(layer "In11.Cu")
		(net "GMI_CPU1_G3_CPU0_G1_TX_DP<4>")
	)
	(arc
		(start 116.324126 -229.560882)
		(mid 116.506017 -229.355775)
		(end 116.569998 -229.089204)
		(width 0.1143)
		(layer "In11.Cu")
		(net "GMI_CPU1_G3_CPU0_G1_TX_DP<4>")
	)
	(arc
		(start 355.239828 -224.739962)
		(mid 355.395756 -225.044254)
		(end 355.239828 -225.348546)
		(width 0.1143)
		(layer "In11.Cu")
		(net "GMI_CPU1_G3_CPU0_G1_TX_DP<4>")
	)
	(arc
		(start 116.256054 -222.108776)
		(mid 116.141378 -221.975442)
		(end 116.100098 -221.804484)
		(width 0.1143)
		(layer "In11.Cu")
		(net "GMI_CPU1_G3_CPU0_G1_TX_DP<4>")
	)
	(arc
		(start 116.286026 -230.225854)
		(mid 116.149945 -230.090006)
		(end 116.100098 -229.90429)
		(width 0.1143)
		(layer "In11.Cu")
		(net "GMI_CPU1_G3_CPU0_G1_TX_DP<4>")
	)
	(arc
		(start 116.569998 -230.586026)
		(mid 116.535389 -230.442611)
		(end 116.439188 -230.330756)
		(width 0.1143)
		(layer "In11.Cu")
		(net "GMI_CPU1_G3_CPU0_G1_TX_DP<4>")
	)
	(arc
		(start 355.186742 -222.139256)
		(mid 354.913191 -222.614236)
		(end 355.186742 -223.089216)
		(width 0.1143)
		(layer "In11.Cu")
		(net "GMI_CPU1_G3_CPU0_G1_TX_DP<4>")
	)
	(arc
		(start 116.256054 -223.728788)
		(mid 116.100126 -223.424496)
		(end 116.256054 -223.120204)
		(width 0.1143)
		(layer "In11.Cu")
		(net "GMI_CPU1_G3_CPU0_G1_TX_DP<4>")
	)
	(arc
		(start 116.354606 -226.299268)
		(mid 116.582606 -225.854514)
		(end 116.354606 -225.40976)
		(width 0.1143)
		(layer "In11.Cu")
		(net "GMI_CPU1_G3_CPU0_G1_TX_DP<4>")
	)
	(arc
		(start 116.354606 -227.91928)
		(mid 116.582606 -227.474526)
		(end 116.354606 -227.029772)
		(width 0.1143)
		(layer "In11.Cu")
		(net "GMI_CPU1_G3_CPU0_G1_TX_DP<4>")
	)
	(arc
		(start 355.056694 -230.330502)
		(mid 354.960483 -230.442352)
		(end 354.925884 -230.585772)
		(width 0.1143)
		(layer "In11.Cu")
		(net "GMI_CPU1_G3_CPU0_G1_TX_DP<4>")
	)
	(arc
		(start 355.395784 -221.80423)
		(mid 355.354529 -221.975201)
		(end 355.239828 -222.108522)
		(width 0.1143)
		(layer "In11.Cu")
		(net "GMI_CPU1_G3_CPU0_G1_TX_DP<4>")
	)
	(arc
		(start 354.699062 -231.059482)
		(mid 354.547075 -231.21599)
		(end 354.465636 -231.418384)
		(width 0.1143)
		(layer "In11.Cu")
		(net "GMI_CPU1_G3_CPU0_G1_TX_DP<4>")
	)
	(arc
		(start 116.256054 -226.968812)
		(mid 116.100126 -226.66452)
		(end 116.256054 -226.360228)
		(width 0.1143)
		(layer "In11.Cu")
		(net "GMI_CPU1_G3_CPU0_G1_TX_DP<4>")
	)
	(arc
		(start 355.239828 -227.979986)
		(mid 355.395756 -228.284278)
		(end 355.239828 -228.58857)
		(width 0.1143)
		(layer "In11.Cu")
		(net "GMI_CPU1_G3_CPU0_G1_TX_DP<4>")
	)
	(arc
		(start 116.100098 -229.904036)
		(mid 116.140917 -229.734293)
		(end 116.254276 -229.601522)
		(width 0.1143)
		(layer "In11.Cu")
		(net "GMI_CPU1_G3_CPU0_G1_TX_DP<4>")
	)
	(arc
		(start 354.925884 -229.08895)
		(mid 354.989859 -229.355525)
		(end 355.171756 -229.560628)
		(width 0.1143)
		(layer "In11.Cu")
		(net "GMI_CPU1_G3_CPU0_G1_TX_DP<4>")
	)
	(arc
		(start 355.241606 -229.601268)
		(mid 355.354955 -229.734043)
		(end 355.395784 -229.903782)
		(width 0.1143)
		(layer "In11.Cu")
		(net "GMI_CPU1_G3_CPU0_G1_TX_DP<4>")
	)
	(arc
		(start 355.141276 -225.409506)
		(mid 354.913276 -225.85426)
		(end 355.141276 -226.299014)
		(width 0.1143)
		(layer "In11.Cu")
		(net "GMI_CPU1_G3_CPU0_G1_TX_DP<4>")
	)
	(arc
		(start 355.141276 -223.789494)
		(mid 354.913276 -224.234248)
		(end 355.141276 -224.679002)
		(width 0.1143)
		(layer "In11.Cu")
		(net "GMI_CPU1_G3_CPU0_G1_TX_DP<4>")
	)
	(arc
		(start 116.339366 -228.638862)
		(mid 116.33179 -228.633466)
		(end 116.324126 -228.628194)
		(width 0.1143)
		(layer "In11.Cu")
		(net "GMI_CPU1_G3_CPU0_G1_TX_DP<4>")
	)
	(arc
		(start 116.256054 -228.588824)
		(mid 116.100126 -228.284532)
		(end 116.256054 -227.98024)
		(width 0.1143)
		(layer "In11.Cu")
		(net "GMI_CPU1_G3_CPU0_G1_TX_DP<4>")
	)
	(arc
		(start 355.156516 -228.638608)
		(mid 354.990271 -228.837708)
		(end 354.925884 -229.08895)
		(width 0.1143)
		(layer "In11.Cu")
		(net "GMI_CPU1_G3_CPU0_G1_TX_DP<4>")
	)
	(arc
		(start 355.239828 -226.359974)
		(mid 355.395756 -226.664266)
		(end 355.239828 -226.968558)
		(width 0.1143)
		(layer "In11.Cu")
		(net "GMI_CPU1_G3_CPU0_G1_TX_DP<4>")
	)
	(arc
		(start 355.239828 -223.11995)
		(mid 355.395756 -223.424242)
		(end 355.239828 -223.728534)
		(width 0.1143)
		(layer "In11.Cu")
		(net "GMI_CPU1_G3_CPU0_G1_TX_DP<4>")
	)
	(arc
		(start 116.256054 -225.3488)
		(mid 116.100126 -225.044508)
		(end 116.256054 -224.740216)
		(width 0.1143)
		(layer "In11.Cu")
		(net "GMI_CPU1_G3_CPU0_G1_TX_DP<4>")
	)
	(arc
		(start 117.034056 -231.441498)
		(mid 117.032268 -231.430049)
		(end 117.030246 -231.418638)
		(width 0.1143)
		(layer "In11.Cu")
		(net "GMI_CPU1_G3_CPU0_G1_TX_DP<4>")
	)
	(segment
		(start 354.547932 -235.03001)
		(end 354.08108 -234.764072)
		(width 0.12954)
		(layer "F.Cu")
		(net "GMI_CPU1_G3_CPU0_G1_TX_DP<3>")
	)
	(segment
		(start 116.94795 -235.030264)
		(end 117.414802 -234.764326)
		(width 0.12954)
		(layer "F.Cu")
		(net "GMI_CPU1_G3_CPU0_G1_TX_DP<3>")
	)
	(segment
		(start 115.341908 -226.983798)
		(end 115.343432 -226.98456)
		(width 0.1143)
		(layer "In11.Cu")
		(net "GMI_CPU1_G3_CPU0_G1_TX_DP<3>")
	)
	(segment
		(start 356.136448 -231.853486)
		(end 356.137464 -231.852978)
		(width 0.1143)
		(layer "In11.Cu")
		(net "GMI_CPU1_G3_CPU0_G1_TX_DP<3>")
	)
	(segment
		(start 356.160324 -227.96881)
		(end 356.159054 -227.968048)
		(width 0.1143)
		(layer "In11.Cu")
		(net "GMI_CPU1_G3_CPU0_G1_TX_DP<3>")
	)
	(segment
		(start 356.147116 -226.341178)
		(end 356.145592 -226.340162)
		(width 0.1143)
		(layer "In11.Cu")
		(net "GMI_CPU1_G3_CPU0_G1_TX_DP<3>")
	)
	(segment
		(start 356.144576 -231.84866)
		(end 356.145592 -231.848152)
		(width 0.1143)
		(layer "In11.Cu")
		(net "GMI_CPU1_G3_CPU0_G1_TX_DP<3>")
	)
	(segment
		(start 356.160324 -224.728786)
		(end 356.159054 -224.728024)
		(width 0.1143)
		(layer "In11.Cu")
		(net "GMI_CPU1_G3_CPU0_G1_TX_DP<3>")
	)
	(segment
		(start 115.343432 -224.724468)
		(end 115.316 -224.740216)
		(width 0.1143)
		(layer "In11.Cu")
		(net "GMI_CPU1_G3_CPU0_G1_TX_DP<3>")
	)
	(segment
		(start 115.346988 -226.342448)
		(end 115.344194 -226.343972)
		(width 0.1143)
		(layer "In11.Cu")
		(net "GMI_CPU1_G3_CPU0_G1_TX_DP<3>")
	)
	(segment
		(start 356.335838 -221.405704)
		(end 356.394512 -221.34703)
		(width 0.1143)
		(layer "In11.Cu")
		(net "GMI_CPU1_G3_CPU0_G1_TX_DP<3>")
	)
	(segment
		(start 317.22949 -182.588154)
		(end 310.47563 -178.764946)
		(width 0.14224)
		(layer "In11.Cu")
		(net "GMI_CPU1_G3_CPU0_G1_TX_DP<3>")
	)
	(segment
		(start 356.109016 -227.009706)
		(end 356.136448 -226.993704)
		(width 0.1143)
		(layer "In11.Cu")
		(net "GMI_CPU1_G3_CPU0_G1_TX_DP<3>")
	)
	(segment
		(start 115.34775 -224.721928)
		(end 115.346988 -224.722436)
		(width 0.1143)
		(layer "In11.Cu")
		(net "GMI_CPU1_G3_CPU0_G1_TX_DP<3>")
	)
	(segment
		(start 115.34775 -223.747076)
		(end 115.379246 -223.765364)
		(width 0.1143)
		(layer "In11.Cu")
		(net "GMI_CPU1_G3_CPU0_G1_TX_DP<3>")
	)
	(segment
		(start 115.34775 -228.607112)
		(end 115.379246 -228.6254)
		(width 0.1143)
		(layer "In11.Cu")
		(net "GMI_CPU1_G3_CPU0_G1_TX_DP<3>")
	)
	(segment
		(start 115.344194 -223.103948)
		(end 115.343432 -223.104456)
		(width 0.1143)
		(layer "In11.Cu")
		(net "GMI_CPU1_G3_CPU0_G1_TX_DP<3>")
	)
	(segment
		(start 115.34013 -228.602794)
		(end 115.341146 -228.603302)
		(width 0.1143)
		(layer "In11.Cu")
		(net "GMI_CPU1_G3_CPU0_G1_TX_DP<3>")
	)
	(segment
		(start 116.7892 -234.295188)
		(end 116.79682 -234.29976)
		(width 0.1143)
		(layer "In11.Cu")
		(net "GMI_CPU1_G3_CPU0_G1_TX_DP<3>")
	)
	(segment
		(start 115.343432 -223.104456)
		(end 115.316 -223.120204)
		(width 0.1143)
		(layer "In11.Cu")
		(net "GMI_CPU1_G3_CPU0_G1_TX_DP<3>")
	)
	(segment
		(start 115.356132 -227.957126)
		(end 115.353084 -227.958904)
		(width 0.1143)
		(layer "In11.Cu")
		(net "GMI_CPU1_G3_CPU0_G1_TX_DP<3>")
	)
	(segment
		(start 356.159054 -226.348036)
		(end 356.158038 -226.347528)
		(width 0.1143)
		(layer "In11.Cu")
		(net "GMI_CPU1_G3_CPU0_G1_TX_DP<3>")
	)
	(segment
		(start 115.346988 -224.722436)
		(end 115.344194 -224.72396)
		(width 0.1143)
		(layer "In11.Cu")
		(net "GMI_CPU1_G3_CPU0_G1_TX_DP<3>")
	)
	(segment
		(start 354.847906 -215.544654)
		(end 354.634038 -215.184228)
		(width 0.14224)
		(layer "In11.Cu")
		(net "GMI_CPU1_G3_CPU0_G1_TX_DP<3>")
	)
	(segment
		(start 356.140766 -225.371152)
		(end 356.144576 -225.368866)
		(width 0.1143)
		(layer "In11.Cu")
		(net "GMI_CPU1_G3_CPU0_G1_TX_DP<3>")
	)
	(segment
		(start 115.341146 -226.98329)
		(end 115.341908 -226.983798)
		(width 0.1143)
		(layer "In11.Cu")
		(net "GMI_CPU1_G3_CPU0_G1_TX_DP<3>")
	)
	(segment
		(start 116.782596 -215.189308)
		(end 116.570506 -215.551004)
		(width 0.14224)
		(layer "In11.Cu")
		(net "GMI_CPU1_G3_CPU0_G1_TX_DP<3>")
	)
	(segment
		(start 116.736368 -215.012016)
		(end 116.782596 -215.189308)
		(width 0.14224)
		(layer "In11.Cu")
		(net "GMI_CPU1_G3_CPU0_G1_TX_DP<3>")
	)
	(segment
		(start 302.91024 -177.894996)
		(end 165.477444 -177.092864)
		(width 0.14224)
		(layer "In11.Cu")
		(net "GMI_CPU1_G3_CPU0_G1_TX_DP<3>")
	)
	(segment
		(start 115.344194 -224.72396)
		(end 115.343432 -224.724468)
		(width 0.1143)
		(layer "In11.Cu")
		(net "GMI_CPU1_G3_CPU0_G1_TX_DP<3>")
	)
	(segment
		(start 356.138734 -223.75241)
		(end 356.13975 -223.751902)
		(width 0.1143)
		(layer "In11.Cu")
		(net "GMI_CPU1_G3_CPU0_G1_TX_DP<3>")
	)
	(segment
		(start 354.073714 -214.240618)
		(end 354.118926 -214.063072)
		(width 0.14224)
		(layer "In11.Cu")
		(net "GMI_CPU1_G3_CPU0_G1_TX_DP<3>")
	)
	(segment
		(start 356.151688 -223.103694)
		(end 356.148894 -223.10217)
		(width 0.1143)
		(layer "In11.Cu")
		(net "GMI_CPU1_G3_CPU0_G1_TX_DP<3>")
	)
	(segment
		(start 356.147116 -223.101154)
		(end 356.145592 -223.100138)
		(width 0.1143)
		(layer "In11.Cu")
		(net "GMI_CPU1_G3_CPU0_G1_TX_DP<3>")
	)
	(segment
		(start 115.343432 -225.364548)
		(end 115.344194 -225.365056)
		(width 0.1143)
		(layer "In11.Cu")
		(net "GMI_CPU1_G3_CPU0_G1_TX_DP<3>")
	)
	(segment
		(start 353.558856 -213.119208)
		(end 353.306634 -212.694266)
		(width 0.14224)
		(layer "In11.Cu")
		(net "GMI_CPU1_G3_CPU0_G1_TX_DP<3>")
	)
	(segment
		(start 356.109016 -222.14967)
		(end 356.148132 -222.12681)
		(width 0.1143)
		(layer "In11.Cu")
		(net "GMI_CPU1_G3_CPU0_G1_TX_DP<3>")
	)
	(segment
		(start 115.344194 -226.343972)
		(end 115.343432 -226.34448)
		(width 0.1143)
		(layer "In11.Cu")
		(net "GMI_CPU1_G3_CPU0_G1_TX_DP<3>")
	)
	(segment
		(start 356.394512 -221.128844)
		(end 356.348792 -221.083124)
		(width 0.1143)
		(layer "In11.Cu")
		(net "GMI_CPU1_G3_CPU0_G1_TX_DP<3>")
	)
	(segment
		(start 115.34013 -226.982782)
		(end 115.341146 -226.98329)
		(width 0.1143)
		(layer "In11.Cu")
		(net "GMI_CPU1_G3_CPU0_G1_TX_DP<3>")
	)
	(segment
		(start 356.348792 -217.818716)
		(end 356.146354 -217.47734)
		(width 0.14224)
		(layer "In11.Cu")
		(net "GMI_CPU1_G3_CPU0_G1_TX_DP<3>")
	)
	(segment
		(start 356.148894 -223.746314)
		(end 356.150164 -223.745552)
		(width 0.1143)
		(layer "In11.Cu")
		(net "GMI_CPU1_G3_CPU0_G1_TX_DP<3>")
	)
	(segment
		(start 115.353084 -227.958904)
		(end 115.35029 -227.960428)
		(width 0.1143)
		(layer "In11.Cu")
		(net "GMI_CPU1_G3_CPU0_G1_TX_DP<3>")
	)
	(segment
		(start 356.150164 -228.605588)
		(end 356.179882 -228.58857)
		(width 0.1143)
		(layer "In11.Cu")
		(net "GMI_CPU1_G3_CPU0_G1_TX_DP<3>")
	)
	(segment
		(start 355.194362 -216.127838)
		(end 355.239574 -215.950292)
		(width 0.14224)
		(layer "In11.Cu")
		(net "GMI_CPU1_G3_CPU0_G1_TX_DP<3>")
	)
	(segment
		(start 356.137464 -228.613208)
		(end 356.138734 -228.612446)
		(width 0.1143)
		(layer "In11.Cu")
		(net "GMI_CPU1_G3_CPU0_G1_TX_DP<3>")
	)
	(segment
		(start 165.477444 -177.092864)
		(end 157.369002 -179.99202)
		(width 0.14224)
		(layer "In11.Cu")
		(net "GMI_CPU1_G3_CPU0_G1_TX_DP<3>")
	)
	(segment
		(start 356.148132 -224.721674)
		(end 356.147116 -224.721166)
		(width 0.1143)
		(layer "In11.Cu")
		(net "GMI_CPU1_G3_CPU0_G1_TX_DP<3>")
	)
	(segment
		(start 356.148894 -224.722182)
		(end 356.148132 -224.721674)
		(width 0.1143)
		(layer "In11.Cu")
		(net "GMI_CPU1_G3_CPU0_G1_TX_DP<3>")
	)
	(segment
		(start 356.145592 -226.340162)
		(end 356.109016 -226.318826)
		(width 0.1143)
		(layer "In11.Cu")
		(net "GMI_CPU1_G3_CPU0_G1_TX_DP<3>")
	)
	(segment
		(start 356.148132 -223.101662)
		(end 356.147116 -223.101154)
		(width 0.1143)
		(layer "In11.Cu")
		(net "GMI_CPU1_G3_CPU0_G1_TX_DP<3>")
	)
	(segment
		(start 115.341146 -228.603302)
		(end 115.341908 -228.60381)
		(width 0.1143)
		(layer "In11.Cu")
		(net "GMI_CPU1_G3_CPU0_G1_TX_DP<3>")
	)
	(segment
		(start 356.138734 -226.992434)
		(end 356.13975 -226.991926)
		(width 0.1143)
		(layer "In11.Cu")
		(net "GMI_CPU1_G3_CPU0_G1_TX_DP<3>")
	)
	(segment
		(start 356.148132 -231.846628)
		(end 356.148894 -231.84612)
		(width 0.1143)
		(layer "In11.Cu")
		(net "GMI_CPU1_G3_CPU0_G1_TX_DP<3>")
	)
	(segment
		(start 356.137464 -223.753172)
		(end 356.138734 -223.75241)
		(width 0.1143)
		(layer "In11.Cu")
		(net "GMI_CPU1_G3_CPU0_G1_TX_DP<3>")
	)
	(segment
		(start 356.138734 -225.372422)
		(end 356.13975 -225.371914)
		(width 0.1143)
		(layer "In11.Cu")
		(net "GMI_CPU1_G3_CPU0_G1_TX_DP<3>")
	)
	(segment
		(start 356.158038 -226.347528)
		(end 356.156006 -226.346258)
		(width 0.1143)
		(layer "In11.Cu")
		(net "GMI_CPU1_G3_CPU0_G1_TX_DP<3>")
	)
	(segment
		(start 115.386866 -224.699068)
		(end 115.357656 -224.716086)
		(width 0.1143)
		(layer "In11.Cu")
		(net "GMI_CPU1_G3_CPU0_G1_TX_DP<3>")
	)
	(segment
		(start 356.18166 -231.22128)
		(end 356.109016 -231.178862)
		(width 0.1143)
		(layer "In11.Cu")
		(net "GMI_CPU1_G3_CPU0_G1_TX_DP<3>")
	)
	(segment
		(start 115.357656 -227.95611)
		(end 115.356132 -227.957126)
		(width 0.1143)
		(layer "In11.Cu")
		(net "GMI_CPU1_G3_CPU0_G1_TX_DP<3>")
	)
	(segment
		(start 115.341908 -225.363786)
		(end 115.343432 -225.364548)
		(width 0.1143)
		(layer "In11.Cu")
		(net "GMI_CPU1_G3_CPU0_G1_TX_DP<3>")
	)
	(segment
		(start 115.346988 -228.606604)
		(end 115.34775 -228.607112)
		(width 0.1143)
		(layer "In11.Cu")
		(net "GMI_CPU1_G3_CPU0_G1_TX_DP<3>")
	)
	(segment
		(start 115.346988 -226.986592)
		(end 115.34775 -226.9871)
		(width 0.1143)
		(layer "In11.Cu")
		(net "GMI_CPU1_G3_CPU0_G1_TX_DP<3>")
	)
	(segment
		(start 355.208332 -233.46664)
		(end 355.239828 -233.448098)
		(width 0.1143)
		(layer "In11.Cu")
		(net "GMI_CPU1_G3_CPU0_G1_TX_DP<3>")
	)
	(segment
		(start 356.145592 -226.98837)
		(end 356.147116 -226.987354)
		(width 0.1143)
		(layer "In11.Cu")
		(net "GMI_CPU1_G3_CPU0_G1_TX_DP<3>")
	)
	(segment
		(start 356.154736 -224.725484)
		(end 356.153974 -224.724976)
		(width 0.1143)
		(layer "In11.Cu")
		(net "GMI_CPU1_G3_CPU0_G1_TX_DP<3>")
	)
	(segment
		(start 356.13975 -223.751902)
		(end 356.140766 -223.75114)
		(width 0.1143)
		(layer "In11.Cu")
		(net "GMI_CPU1_G3_CPU0_G1_TX_DP<3>")
	)
	(segment
		(start 356.109016 -228.629718)
		(end 356.136448 -228.613716)
		(width 0.1143)
		(layer "In11.Cu")
		(net "GMI_CPU1_G3_CPU0_G1_TX_DP<3>")
	)
	(segment
		(start 356.147116 -228.607366)
		(end 356.148132 -228.606858)
		(width 0.1143)
		(layer "In11.Cu")
		(net "GMI_CPU1_G3_CPU0_G1_TX_DP<3>")
	)
	(segment
		(start 115.34775 -231.846882)
		(end 115.379246 -231.86517)
		(width 0.1143)
		(layer "In11.Cu")
		(net "GMI_CPU1_G3_CPU0_G1_TX_DP<3>")
	)
	(segment
		(start 115.380008 -223.765872)
		(end 115.386866 -223.769936)
		(width 0.1143)
		(layer "In11.Cu")
		(net "GMI_CPU1_G3_CPU0_G1_TX_DP<3>")
	)
	(segment
		(start 115.10137 -221.129098)
		(end 115.10137 -221.347284)
		(width 0.1143)
		(layer "In11.Cu")
		(net "GMI_CPU1_G3_CPU0_G1_TX_DP<3>")
	)
	(segment
		(start 115.344194 -227.963984)
		(end 115.343432 -227.964492)
		(width 0.1143)
		(layer "In11.Cu")
		(net "GMI_CPU1_G3_CPU0_G1_TX_DP<3>")
	)
	(segment
		(start 115.341146 -225.363278)
		(end 115.341908 -225.363786)
		(width 0.1143)
		(layer "In11.Cu")
		(net "GMI_CPU1_G3_CPU0_G1_TX_DP<3>")
	)
	(segment
		(start 356.13975 -226.991926)
		(end 356.140766 -226.991164)
		(width 0.1143)
		(layer "In11.Cu")
		(net "GMI_CPU1_G3_CPU0_G1_TX_DP<3>")
	)
	(segment
		(start 115.343432 -228.604572)
		(end 115.344194 -228.60508)
		(width 0.1143)
		(layer "In11.Cu")
		(net "GMI_CPU1_G3_CPU0_G1_TX_DP<3>")
	)
	(segment
		(start 115.316 -225.3488)
		(end 115.34013 -225.36277)
		(width 0.1143)
		(layer "In11.Cu")
		(net "GMI_CPU1_G3_CPU0_G1_TX_DP<3>")
	)
	(segment
		(start 356.148132 -227.961698)
		(end 356.147116 -227.96119)
		(width 0.1143)
		(layer "In11.Cu")
		(net "GMI_CPU1_G3_CPU0_G1_TX_DP<3>")
	)
	(segment
		(start 356.148132 -228.606858)
		(end 356.148894 -228.60635)
		(width 0.1143)
		(layer "In11.Cu")
		(net "GMI_CPU1_G3_CPU0_G1_TX_DP<3>")
	)
	(segment
		(start 356.140766 -231.850946)
		(end 356.144576 -231.84866)
		(width 0.1143)
		(layer "In11.Cu")
		(net "GMI_CPU1_G3_CPU0_G1_TX_DP<3>")
	)
	(segment
		(start 115.341908 -231.84358)
		(end 115.343432 -231.844342)
		(width 0.1143)
		(layer "In11.Cu")
		(net "GMI_CPU1_G3_CPU0_G1_TX_DP<3>")
	)
	(segment
		(start 356.140766 -223.75114)
		(end 356.144576 -223.748854)
		(width 0.1143)
		(layer "In11.Cu")
		(net "GMI_CPU1_G3_CPU0_G1_TX_DP<3>")
	)
	(segment
		(start 356.158038 -227.96754)
		(end 356.156006 -227.96627)
		(width 0.1143)
		(layer "In11.Cu")
		(net "GMI_CPU1_G3_CPU0_G1_TX_DP<3>")
	)
	(segment
		(start 115.346988 -225.36658)
		(end 115.34775 -225.367088)
		(width 0.1143)
		(layer "In11.Cu")
		(net "GMI_CPU1_G3_CPU0_G1_TX_DP<3>")
	)
	(segment
		(start 115.35029 -227.960428)
		(end 115.34775 -227.961952)
		(width 0.1143)
		(layer "In11.Cu")
		(net "GMI_CPU1_G3_CPU0_G1_TX_DP<3>")
	)
	(segment
		(start 356.13975 -231.851708)
		(end 356.140766 -231.850946)
		(width 0.1143)
		(layer "In11.Cu")
		(net "GMI_CPU1_G3_CPU0_G1_TX_DP<3>")
	)
	(segment
		(start 356.18166 -229.601268)
		(end 356.109016 -229.55885)
		(width 0.1143)
		(layer "In11.Cu")
		(net "GMI_CPU1_G3_CPU0_G1_TX_DP<3>")
	)
	(segment
		(start 115.379246 -231.86517)
		(end 115.386866 -231.869742)
		(width 0.1143)
		(layer "In11.Cu")
		(net "GMI_CPU1_G3_CPU0_G1_TX_DP<3>")
	)
	(segment
		(start 115.343432 -231.844342)
		(end 115.344194 -231.84485)
		(width 0.1143)
		(layer "In11.Cu")
		(net "GMI_CPU1_G3_CPU0_G1_TX_DP<3>")
	)
	(segment
		(start 356.140766 -228.611176)
		(end 356.144576 -228.60889)
		(width 0.1143)
		(layer "In11.Cu")
		(net "GMI_CPU1_G3_CPU0_G1_TX_DP<3>")
	)
	(segment
		(start 356.394512 -221.34703)
		(end 356.394512 -221.128844)
		(width 0.1143)
		(layer "In11.Cu")
		(net "GMI_CPU1_G3_CPU0_G1_TX_DP<3>")
	)
	(segment
		(start 353.306634 -212.694266)
		(end 353.128834 -212.6488)
		(width 0.14224)
		(layer "In11.Cu")
		(net "GMI_CPU1_G3_CPU0_G1_TX_DP<3>")
	)
	(segment
		(start 354.69957 -234.298998)
		(end 354.74021 -234.27563)
		(width 0.1143)
		(layer "In11.Cu")
		(net "GMI_CPU1_G3_CPU0_G1_TX_DP<3>")
	)
	(segment
		(start 356.148132 -225.366834)
		(end 356.148894 -225.366326)
		(width 0.1143)
		(layer "In11.Cu")
		(net "GMI_CPU1_G3_CPU0_G1_TX_DP<3>")
	)
	(segment
		(start 115.34775 -226.34194)
		(end 115.346988 -226.342448)
		(width 0.1143)
		(layer "In11.Cu")
		(net "GMI_CPU1_G3_CPU0_G1_TX_DP<3>")
	)
	(segment
		(start 115.316 -222.108776)
		(end 115.386866 -222.149924)
		(width 0.1143)
		(layer "In11.Cu")
		(net "GMI_CPU1_G3_CPU0_G1_TX_DP<3>")
	)
	(segment
		(start 356.160324 -226.348798)
		(end 356.159054 -226.348036)
		(width 0.1143)
		(layer "In11.Cu")
		(net "GMI_CPU1_G3_CPU0_G1_TX_DP<3>")
	)
	(segment
		(start 356.150164 -231.845358)
		(end 356.179882 -231.82834)
		(width 0.1143)
		(layer "In11.Cu")
		(net "GMI_CPU1_G3_CPU0_G1_TX_DP<3>")
	)
	(segment
		(start 115.341908 -223.743774)
		(end 115.343432 -223.744536)
		(width 0.1143)
		(layer "In11.Cu")
		(net "GMI_CPU1_G3_CPU0_G1_TX_DP<3>")
	)
	(segment
		(start 115.341908 -228.60381)
		(end 115.343432 -228.604572)
		(width 0.1143)
		(layer "In11.Cu")
		(net "GMI_CPU1_G3_CPU0_G1_TX_DP<3>")
	)
	(segment
		(start 352.70059 -211.673186)
		(end 317.22949 -182.588154)
		(width 0.14224)
		(layer "In11.Cu")
		(net "GMI_CPU1_G3_CPU0_G1_TX_DP<3>")
	)
	(segment
		(start 352.960178 -212.110828)
		(end 352.70059 -211.673186)
		(width 0.14224)
		(layer "In11.Cu")
		(net "GMI_CPU1_G3_CPU0_G1_TX_DP<3>")
	)
	(segment
		(start 115.34013 -231.842564)
		(end 115.341146 -231.843072)
		(width 0.1143)
		(layer "In11.Cu")
		(net "GMI_CPU1_G3_CPU0_G1_TX_DP<3>")
	)
	(segment
		(start 354.379022 -234.764072)
		(end 354.461826 -234.681268)
		(width 0.1143)
		(layer "In11.Cu")
		(net "GMI_CPU1_G3_CPU0_G1_TX_DP<3>")
	)
	(segment
		(start 115.379246 -227.005388)
		(end 115.380008 -227.005896)
		(width 0.1143)
		(layer "In11.Cu")
		(net "GMI_CPU1_G3_CPU0_G1_TX_DP<3>")
	)
	(segment
		(start 356.159054 -223.108012)
		(end 356.158038 -223.107504)
		(width 0.1143)
		(layer "In11.Cu")
		(net "GMI_CPU1_G3_CPU0_G1_TX_DP<3>")
	)
	(segment
		(start 356.156006 -227.96627)
		(end 356.154736 -227.965508)
		(width 0.1143)
		(layer "In11.Cu")
		(net "GMI_CPU1_G3_CPU0_G1_TX_DP<3>")
	)
	(segment
		(start 356.109016 -223.769682)
		(end 356.136448 -223.75368)
		(width 0.1143)
		(layer "In11.Cu")
		(net "GMI_CPU1_G3_CPU0_G1_TX_DP<3>")
	)
	(segment
		(start 115.341146 -231.843072)
		(end 115.341908 -231.84358)
		(width 0.1143)
		(layer "In11.Cu")
		(net "GMI_CPU1_G3_CPU0_G1_TX_DP<3>")
	)
	(segment
		(start 115.343432 -226.34448)
		(end 115.316 -226.360228)
		(width 0.1143)
		(layer "In11.Cu")
		(net "GMI_CPU1_G3_CPU0_G1_TX_DP<3>")
	)
	(segment
		(start 356.109016 -225.389694)
		(end 356.136448 -225.373692)
		(width 0.1143)
		(layer "In11.Cu")
		(net "GMI_CPU1_G3_CPU0_G1_TX_DP<3>")
	)
	(segment
		(start 356.154736 -223.105472)
		(end 356.153974 -223.104964)
		(width 0.1143)
		(layer "In11.Cu")
		(net "GMI_CPU1_G3_CPU0_G1_TX_DP<3>")
	)
	(segment
		(start 356.15245 -223.104202)
		(end 356.151688 -223.103694)
		(width 0.1143)
		(layer "In11.Cu")
		(net "GMI_CPU1_G3_CPU0_G1_TX_DP<3>")
	)
	(segment
		(start 356.159054 -224.728024)
		(end 356.158038 -224.727516)
		(width 0.1143)
		(layer "In11.Cu")
		(net "GMI_CPU1_G3_CPU0_G1_TX_DP<3>")
	)
	(segment
		(start 115.78717 -232.639108)
		(end 115.856766 -232.679748)
		(width 0.1143)
		(layer "In11.Cu")
		(net "GMI_CPU1_G3_CPU0_G1_TX_DP<3>")
	)
	(segment
		(start 115.160044 -221.405958)
		(end 115.160044 -221.804484)
		(width 0.1143)
		(layer "In11.Cu")
		(net "GMI_CPU1_G3_CPU0_G1_TX_DP<3>")
	)
	(segment
		(start 356.138734 -228.612446)
		(end 356.13975 -228.611938)
		(width 0.1143)
		(layer "In11.Cu")
		(net "GMI_CPU1_G3_CPU0_G1_TX_DP<3>")
	)
	(segment
		(start 356.153974 -226.344988)
		(end 356.15245 -226.344226)
		(width 0.1143)
		(layer "In11.Cu")
		(net "GMI_CPU1_G3_CPU0_G1_TX_DP<3>")
	)
	(segment
		(start 115.344194 -223.745044)
		(end 115.346988 -223.746568)
		(width 0.1143)
		(layer "In11.Cu")
		(net "GMI_CPU1_G3_CPU0_G1_TX_DP<3>")
	)
	(segment
		(start 116.557552 -233.935016)
		(end 116.557552 -233.945176)
		(width 0.1143)
		(layer "In11.Cu")
		(net "GMI_CPU1_G3_CPU0_G1_TX_DP<3>")
	)
	(segment
		(start 355.58603 -216.53373)
		(end 355.40823 -216.488264)
		(width 0.14224)
		(layer "In11.Cu")
		(net "GMI_CPU1_G3_CPU0_G1_TX_DP<3>")
	)
	(segment
		(start 117.11686 -234.764326)
		(end 117.414802 -234.764326)
		(width 0.1143)
		(layer "In11.Cu")
		(net "GMI_CPU1_G3_CPU0_G1_TX_DP<3>")
	)
	(segment
		(start 115.386866 -231.179116)
		(end 115.314222 -231.221534)
		(width 0.1143)
		(layer "In11.Cu")
		(net "GMI_CPU1_G3_CPU0_G1_TX_DP<3>")
	)
	(segment
		(start 356.158038 -224.727516)
		(end 356.156006 -224.726246)
		(width 0.1143)
		(layer "In11.Cu")
		(net "GMI_CPU1_G3_CPU0_G1_TX_DP<3>")
	)
	(segment
		(start 115.34013 -223.742758)
		(end 115.341146 -223.743266)
		(width 0.1143)
		(layer "In11.Cu")
		(net "GMI_CPU1_G3_CPU0_G1_TX_DP<3>")
	)
	(segment
		(start 115.386866 -229.559104)
		(end 115.314222 -229.601522)
		(width 0.1143)
		(layer "In11.Cu")
		(net "GMI_CPU1_G3_CPU0_G1_TX_DP<3>")
	)
	(segment
		(start 355.239574 -215.950292)
		(end 355.025706 -215.59012)
		(width 0.14224)
		(layer "In11.Cu")
		(net "GMI_CPU1_G3_CPU0_G1_TX_DP<3>")
	)
	(segment
		(start 356.154736 -226.345496)
		(end 356.153974 -226.344988)
		(width 0.1143)
		(layer "In11.Cu")
		(net "GMI_CPU1_G3_CPU0_G1_TX_DP<3>")
	)
	(segment
		(start 356.150164 -223.745552)
		(end 356.179882 -223.728534)
		(width 0.1143)
		(layer "In11.Cu")
		(net "GMI_CPU1_G3_CPU0_G1_TX_DP<3>")
	)
	(segment
		(start 116.747798 -234.271566)
		(end 116.756942 -234.276392)
		(width 0.1143)
		(layer "In11.Cu")
		(net "GMI_CPU1_G3_CPU0_G1_TX_DP<3>")
	)
	(segment
		(start 117.034056 -234.681522)
		(end 117.11686 -234.764326)
		(width 0.1143)
		(layer "In11.Cu")
		(net "GMI_CPU1_G3_CPU0_G1_TX_DP<3>")
	)
	(segment
		(start 115.379246 -228.6254)
		(end 115.386866 -228.629972)
		(width 0.1143)
		(layer "In11.Cu")
		(net "GMI_CPU1_G3_CPU0_G1_TX_DP<3>")
	)
	(segment
		(start 115.14709 -221.071948)
		(end 115.14709 -221.083378)
		(width 0.1143)
		(layer "In11.Cu")
		(net "GMI_CPU1_G3_CPU0_G1_TX_DP<3>")
	)
	(segment
		(start 356.148894 -225.366326)
		(end 356.150164 -225.365564)
		(width 0.1143)
		(layer "In11.Cu")
		(net "GMI_CPU1_G3_CPU0_G1_TX_DP<3>")
	)
	(segment
		(start 356.148894 -226.986338)
		(end 356.150164 -226.985576)
		(width 0.1143)
		(layer "In11.Cu")
		(net "GMI_CPU1_G3_CPU0_G1_TX_DP<3>")
	)
	(segment
		(start 353.128834 -212.6488)
		(end 352.914966 -212.28812)
		(width 0.14224)
		(layer "In11.Cu")
		(net "GMI_CPU1_G3_CPU0_G1_TX_DP<3>")
	)
	(segment
		(start 115.346988 -223.746568)
		(end 115.34775 -223.747076)
		(width 0.1143)
		(layer "In11.Cu")
		(net "GMI_CPU1_G3_CPU0_G1_TX_DP<3>")
	)
	(segment
		(start 356.150164 -226.985576)
		(end 356.179882 -226.968558)
		(width 0.1143)
		(layer "In11.Cu")
		(net "GMI_CPU1_G3_CPU0_G1_TX_DP<3>")
	)
	(segment
		(start 115.386866 -227.939092)
		(end 115.357656 -227.95611)
		(width 0.1143)
		(layer "In11.Cu")
		(net "GMI_CPU1_G3_CPU0_G1_TX_DP<3>")
	)
	(segment
		(start 115.357656 -224.716086)
		(end 115.356132 -224.717102)
		(width 0.1143)
		(layer "In11.Cu")
		(net "GMI_CPU1_G3_CPU0_G1_TX_DP<3>")
	)
	(segment
		(start 116.756942 -234.276392)
		(end 116.757704 -234.2769)
		(width 0.1143)
		(layer "In11.Cu")
		(net "GMI_CPU1_G3_CPU0_G1_TX_DP<3>")
	)
	(segment
		(start 115.316 -230.208582)
		(end 115.384326 -230.248206)
		(width 0.1143)
		(layer "In11.Cu")
		(net "GMI_CPU1_G3_CPU0_G1_TX_DP<3>")
	)
	(segment
		(start 354.118926 -214.063072)
		(end 353.905058 -213.7029)
		(width 0.14224)
		(layer "In11.Cu")
		(net "GMI_CPU1_G3_CPU0_G1_TX_DP<3>")
	)
	(segment
		(start 115.344194 -225.365056)
		(end 115.346988 -225.36658)
		(width 0.1143)
		(layer "In11.Cu")
		(net "GMI_CPU1_G3_CPU0_G1_TX_DP<3>")
	)
	(segment
		(start 115.380008 -225.385884)
		(end 115.386866 -225.389948)
		(width 0.1143)
		(layer "In11.Cu")
		(net "GMI_CPU1_G3_CPU0_G1_TX_DP<3>")
	)
	(segment
		(start 354.67925 -215.006682)
		(end 354.465382 -214.64651)
		(width 0.14224)
		(layer "In11.Cu")
		(net "GMI_CPU1_G3_CPU0_G1_TX_DP<3>")
	)
	(segment
		(start 354.93833 -233.944922)
		(end 354.93833 -233.934762)
		(width 0.1143)
		(layer "In11.Cu")
		(net "GMI_CPU1_G3_CPU0_G1_TX_DP<3>")
	)
	(segment
		(start 356.179882 -226.359974)
		(end 356.160324 -226.348798)
		(width 0.1143)
		(layer "In11.Cu")
		(net "GMI_CPU1_G3_CPU0_G1_TX_DP<3>")
	)
	(segment
		(start 356.144576 -225.368866)
		(end 356.145592 -225.368358)
		(width 0.1143)
		(layer "In11.Cu")
		(net "GMI_CPU1_G3_CPU0_G1_TX_DP<3>")
	)
	(segment
		(start 355.799898 -216.893902)
		(end 355.58603 -216.53373)
		(width 0.14224)
		(layer "In11.Cu")
		(net "GMI_CPU1_G3_CPU0_G1_TX_DP<3>")
	)
	(segment
		(start 356.145592 -231.848152)
		(end 356.147116 -231.847136)
		(width 0.1143)
		(layer "In11.Cu")
		(net "GMI_CPU1_G3_CPU0_G1_TX_DP<3>")
	)
	(segment
		(start 356.145592 -223.748346)
		(end 356.147116 -223.74733)
		(width 0.1143)
		(layer "In11.Cu")
		(net "GMI_CPU1_G3_CPU0_G1_TX_DP<3>")
	)
	(segment
		(start 115.386866 -223.079056)
		(end 115.357656 -223.096074)
		(width 0.1143)
		(layer "In11.Cu")
		(net "GMI_CPU1_G3_CPU0_G1_TX_DP<3>")
	)
	(segment
		(start 115.34775 -226.9871)
		(end 115.379246 -227.005388)
		(width 0.1143)
		(layer "In11.Cu")
		(net "GMI_CPU1_G3_CPU0_G1_TX_DP<3>")
	)
	(segment
		(start 356.148132 -226.986846)
		(end 356.148894 -226.986338)
		(width 0.1143)
		(layer "In11.Cu")
		(net "GMI_CPU1_G3_CPU0_G1_TX_DP<3>")
	)
	(segment
		(start 356.137464 -225.373184)
		(end 356.138734 -225.372422)
		(width 0.1143)
		(layer "In11.Cu")
		(net "GMI_CPU1_G3_CPU0_G1_TX_DP<3>")
	)
	(segment
		(start 356.148894 -223.10217)
		(end 356.148132 -223.101662)
		(width 0.1143)
		(layer "In11.Cu")
		(net "GMI_CPU1_G3_CPU0_G1_TX_DP<3>")
	)
	(segment
		(start 354.74021 -234.27563)
		(end 354.75164 -234.269026)
		(width 0.1143)
		(layer "In11.Cu")
		(net "GMI_CPU1_G3_CPU0_G1_TX_DP<3>")
	)
	(segment
		(start 356.153974 -223.104964)
		(end 356.15245 -223.104202)
		(width 0.1143)
		(layer "In11.Cu")
		(net "GMI_CPU1_G3_CPU0_G1_TX_DP<3>")
	)
	(segment
		(start 115.34775 -225.367088)
		(end 115.379246 -225.385376)
		(width 0.1143)
		(layer "In11.Cu")
		(net "GMI_CPU1_G3_CPU0_G1_TX_DP<3>")
	)
	(segment
		(start 116.256054 -233.448352)
		(end 116.28755 -233.466894)
		(width 0.1143)
		(layer "In11.Cu")
		(net "GMI_CPU1_G3_CPU0_G1_TX_DP<3>")
	)
	(segment
		(start 115.346988 -227.96246)
		(end 115.344194 -227.963984)
		(width 0.1143)
		(layer "In11.Cu")
		(net "GMI_CPU1_G3_CPU0_G1_TX_DP<3>")
	)
	(segment
		(start 356.147116 -231.847136)
		(end 356.148132 -231.846628)
		(width 0.1143)
		(layer "In11.Cu")
		(net "GMI_CPU1_G3_CPU0_G1_TX_DP<3>")
	)
	(segment
		(start 115.343432 -226.98456)
		(end 115.344194 -226.985068)
		(width 0.1143)
		(layer "In11.Cu")
		(net "GMI_CPU1_G3_CPU0_G1_TX_DP<3>")
	)
	(segment
		(start 115.316 -226.968812)
		(end 115.34013 -226.982782)
		(width 0.1143)
		(layer "In11.Cu")
		(net "GMI_CPU1_G3_CPU0_G1_TX_DP<3>")
	)
	(segment
		(start 356.153974 -227.965)
		(end 356.15245 -227.964238)
		(width 0.1143)
		(layer "In11.Cu")
		(net "GMI_CPU1_G3_CPU0_G1_TX_DP<3>")
	)
	(segment
		(start 356.147116 -226.987354)
		(end 356.148132 -226.986846)
		(width 0.1143)
		(layer "In11.Cu")
		(net "GMI_CPU1_G3_CPU0_G1_TX_DP<3>")
	)
	(segment
		(start 356.156006 -224.726246)
		(end 356.154736 -224.725484)
		(width 0.1143)
		(layer "In11.Cu")
		(net "GMI_CPU1_G3_CPU0_G1_TX_DP<3>")
	)
	(segment
		(start 356.111556 -230.247952)
		(end 356.148132 -230.226616)
		(width 0.1143)
		(layer "In11.Cu")
		(net "GMI_CPU1_G3_CPU0_G1_TX_DP<3>")
	)
	(segment
		(start 116.015262 -216.497662)
		(end 115.837716 -216.54389)
		(width 0.14224)
		(layer "In11.Cu")
		(net "GMI_CPU1_G3_CPU0_G1_TX_DP<3>")
	)
	(segment
		(start 356.137464 -231.852978)
		(end 356.138734 -231.852216)
		(width 0.1143)
		(layer "In11.Cu")
		(net "GMI_CPU1_G3_CPU0_G1_TX_DP<3>")
	)
	(segment
		(start 116.757704 -234.2769)
		(end 116.7892 -234.295188)
		(width 0.1143)
		(layer "In11.Cu")
		(net "GMI_CPU1_G3_CPU0_G1_TX_DP<3>")
	)
	(segment
		(start 356.137464 -226.993196)
		(end 356.138734 -226.992434)
		(width 0.1143)
		(layer "In11.Cu")
		(net "GMI_CPU1_G3_CPU0_G1_TX_DP<3>")
	)
	(segment
		(start 115.343432 -223.744536)
		(end 115.344194 -223.745044)
		(width 0.1143)
		(layer "In11.Cu")
		(net "GMI_CPU1_G3_CPU0_G1_TX_DP<3>")
	)
	(segment
		(start 115.343432 -227.964492)
		(end 115.316 -227.98024)
		(width 0.1143)
		(layer "In11.Cu")
		(net "GMI_CPU1_G3_CPU0_G1_TX_DP<3>")
	)
	(segment
		(start 356.156006 -226.346258)
		(end 356.154736 -226.345496)
		(width 0.1143)
		(layer "In11.Cu")
		(net "GMI_CPU1_G3_CPU0_G1_TX_DP<3>")
	)
	(segment
		(start 353.905058 -213.7029)
		(end 353.727512 -213.657434)
		(width 0.14224)
		(layer "In11.Cu")
		(net "GMI_CPU1_G3_CPU0_G1_TX_DP<3>")
	)
	(segment
		(start 356.147116 -225.367342)
		(end 356.148132 -225.366834)
		(width 0.1143)
		(layer "In11.Cu")
		(net "GMI_CPU1_G3_CPU0_G1_TX_DP<3>")
	)
	(segment
		(start 356.148894 -227.962206)
		(end 356.148132 -227.961698)
		(width 0.1143)
		(layer "In11.Cu")
		(net "GMI_CPU1_G3_CPU0_G1_TX_DP<3>")
	)
	(segment
		(start 115.356132 -226.337114)
		(end 115.353084 -226.338892)
		(width 0.1143)
		(layer "In11.Cu")
		(net "GMI_CPU1_G3_CPU0_G1_TX_DP<3>")
	)
	(segment
		(start 115.353084 -224.71888)
		(end 115.35029 -224.720404)
		(width 0.1143)
		(layer "In11.Cu")
		(net "GMI_CPU1_G3_CPU0_G1_TX_DP<3>")
	)
	(segment
		(start 356.153974 -224.724976)
		(end 356.15245 -224.724214)
		(width 0.1143)
		(layer "In11.Cu")
		(net "GMI_CPU1_G3_CPU0_G1_TX_DP<3>")
	)
	(segment
		(start 115.34013 -225.36277)
		(end 115.341146 -225.363278)
		(width 0.1143)
		(layer "In11.Cu")
		(net "GMI_CPU1_G3_CPU0_G1_TX_DP<3>")
	)
	(segment
		(start 356.146354 -217.47734)
		(end 355.968554 -217.432128)
		(width 0.14224)
		(layer "In11.Cu")
		(net "GMI_CPU1_G3_CPU0_G1_TX_DP<3>")
	)
	(segment
		(start 356.348792 -221.071694)
		(end 356.348792 -217.818716)
		(width 0.14224)
		(layer "In11.Cu")
		(net "GMI_CPU1_G3_CPU0_G1_TX_DP<3>")
	)
	(segment
		(start 310.47563 -178.764946)
		(end 308.042564 -177.894996)
		(width 0.14224)
		(layer "In11.Cu")
		(net "GMI_CPU1_G3_CPU0_G1_TX_DP<3>")
	)
	(segment
		(start 115.344194 -231.84485)
		(end 115.346988 -231.846374)
		(width 0.1143)
		(layer "In11.Cu")
		(net "GMI_CPU1_G3_CPU0_G1_TX_DP<3>")
	)
	(segment
		(start 356.148894 -226.342194)
		(end 356.148132 -226.341686)
		(width 0.1143)
		(layer "In11.Cu")
		(net "GMI_CPU1_G3_CPU0_G1_TX_DP<3>")
	)
	(segment
		(start 356.13975 -228.611938)
		(end 356.140766 -228.611176)
		(width 0.1143)
		(layer "In11.Cu")
		(net "GMI_CPU1_G3_CPU0_G1_TX_DP<3>")
	)
	(segment
		(start 356.147116 -223.74733)
		(end 356.148132 -223.746822)
		(width 0.1143)
		(layer "In11.Cu")
		(net "GMI_CPU1_G3_CPU0_G1_TX_DP<3>")
	)
	(segment
		(start 356.109016 -231.869488)
		(end 356.136448 -231.853486)
		(width 0.1143)
		(layer "In11.Cu")
		(net "GMI_CPU1_G3_CPU0_G1_TX_DP<3>")
	)
	(segment
		(start 356.179882 -227.979986)
		(end 356.160324 -227.96881)
		(width 0.1143)
		(layer "In11.Cu")
		(net "GMI_CPU1_G3_CPU0_G1_TX_DP<3>")
	)
	(segment
		(start 354.698808 -234.299506)
		(end 354.69957 -234.298998)
		(width 0.1143)
		(layer "In11.Cu")
		(net "GMI_CPU1_G3_CPU0_G1_TX_DP<3>")
	)
	(segment
		(start 115.316 -228.588824)
		(end 115.34013 -228.602794)
		(width 0.1143)
		(layer "In11.Cu")
		(net "GMI_CPU1_G3_CPU0_G1_TX_DP<3>")
	)
	(segment
		(start 115.316 -223.728788)
		(end 115.34013 -223.742758)
		(width 0.1143)
		(layer "In11.Cu")
		(net "GMI_CPU1_G3_CPU0_G1_TX_DP<3>")
	)
	(segment
		(start 356.348792 -221.083124)
		(end 356.348792 -221.071694)
		(width 0.1143)
		(layer "In11.Cu")
		(net "GMI_CPU1_G3_CPU0_G1_TX_DP<3>")
	)
	(segment
		(start 115.356132 -223.09709)
		(end 115.353084 -223.098868)
		(width 0.1143)
		(layer "In11.Cu")
		(net "GMI_CPU1_G3_CPU0_G1_TX_DP<3>")
	)
	(segment
		(start 356.145592 -223.100138)
		(end 356.109016 -223.078802)
		(width 0.1143)
		(layer "In11.Cu")
		(net "GMI_CPU1_G3_CPU0_G1_TX_DP<3>")
	)
	(segment
		(start 115.34775 -227.961952)
		(end 115.346988 -227.96246)
		(width 0.1143)
		(layer "In11.Cu")
		(net "GMI_CPU1_G3_CPU0_G1_TX_DP<3>")
	)
	(segment
		(start 356.145592 -225.368358)
		(end 356.147116 -225.367342)
		(width 0.1143)
		(layer "In11.Cu")
		(net "GMI_CPU1_G3_CPU0_G1_TX_DP<3>")
	)
	(segment
		(start 354.287582 -214.601044)
		(end 354.073714 -214.240618)
		(width 0.14224)
		(layer "In11.Cu")
		(net "GMI_CPU1_G3_CPU0_G1_TX_DP<3>")
	)
	(segment
		(start 115.379246 -223.765364)
		(end 115.380008 -223.765872)
		(width 0.1143)
		(layer "In11.Cu")
		(net "GMI_CPU1_G3_CPU0_G1_TX_DP<3>")
	)
	(segment
		(start 116.570506 -215.551004)
		(end 116.39296 -215.597232)
		(width 0.14224)
		(layer "In11.Cu")
		(net "GMI_CPU1_G3_CPU0_G1_TX_DP<3>")
	)
	(segment
		(start 356.144576 -226.988878)
		(end 356.145592 -226.98837)
		(width 0.1143)
		(layer "In11.Cu")
		(net "GMI_CPU1_G3_CPU0_G1_TX_DP<3>")
	)
	(segment
		(start 355.639116 -232.679494)
		(end 355.708712 -232.638854)
		(width 0.1143)
		(layer "In11.Cu")
		(net "GMI_CPU1_G3_CPU0_G1_TX_DP<3>")
	)
	(segment
		(start 356.145592 -227.960174)
		(end 356.109016 -227.938838)
		(width 0.1143)
		(layer "In11.Cu")
		(net "GMI_CPU1_G3_CPU0_G1_TX_DP<3>")
	)
	(segment
		(start 356.140766 -226.991164)
		(end 356.144576 -226.988878)
		(width 0.1143)
		(layer "In11.Cu")
		(net "GMI_CPU1_G3_CPU0_G1_TX_DP<3>")
	)
	(segment
		(start 115.380008 -227.005896)
		(end 115.386866 -227.00996)
		(width 0.1143)
		(layer "In11.Cu")
		(net "GMI_CPU1_G3_CPU0_G1_TX_DP<3>")
	)
	(segment
		(start 356.136448 -223.75368)
		(end 356.137464 -223.753172)
		(width 0.1143)
		(layer "In11.Cu")
		(net "GMI_CPU1_G3_CPU0_G1_TX_DP<3>")
	)
	(segment
		(start 115.386866 -226.31908)
		(end 115.357656 -226.336098)
		(width 0.1143)
		(layer "In11.Cu")
		(net "GMI_CPU1_G3_CPU0_G1_TX_DP<3>")
	)
	(segment
		(start 115.35029 -223.100392)
		(end 115.34775 -223.101916)
		(width 0.1143)
		(layer "In11.Cu")
		(net "GMI_CPU1_G3_CPU0_G1_TX_DP<3>")
	)
	(segment
		(start 116.181124 -215.958674)
		(end 116.227352 -216.135966)
		(width 0.14224)
		(layer "In11.Cu")
		(net "GMI_CPU1_G3_CPU0_G1_TX_DP<3>")
	)
	(segment
		(start 115.344194 -228.60508)
		(end 115.346988 -228.606604)
		(width 0.1143)
		(layer "In11.Cu")
		(net "GMI_CPU1_G3_CPU0_G1_TX_DP<3>")
	)
	(segment
		(start 356.148132 -223.746822)
		(end 356.148894 -223.746314)
		(width 0.1143)
		(layer "In11.Cu")
		(net "GMI_CPU1_G3_CPU0_G1_TX_DP<3>")
	)
	(segment
		(start 115.316 -231.828594)
		(end 115.34013 -231.842564)
		(width 0.1143)
		(layer "In11.Cu")
		(net "GMI_CPU1_G3_CPU0_G1_TX_DP<3>")
	)
	(segment
		(start 356.154736 -227.965508)
		(end 356.153974 -227.965)
		(width 0.1143)
		(layer "In11.Cu")
		(net "GMI_CPU1_G3_CPU0_G1_TX_DP<3>")
	)
	(segment
		(start 356.148894 -228.60635)
		(end 356.150164 -228.605588)
		(width 0.1143)
		(layer "In11.Cu")
		(net "GMI_CPU1_G3_CPU0_G1_TX_DP<3>")
	)
	(segment
		(start 115.837716 -216.54389)
		(end 115.837716 -216.544144)
		(width 0.14224)
		(layer "In11.Cu")
		(net "GMI_CPU1_G3_CPU0_G1_TX_DP<3>")
	)
	(segment
		(start 115.14709 -221.083378)
		(end 115.10137 -221.129098)
		(width 0.1143)
		(layer "In11.Cu")
		(net "GMI_CPU1_G3_CPU0_G1_TX_DP<3>")
	)
	(segment
		(start 356.144576 -223.748854)
		(end 356.145592 -223.748346)
		(width 0.1143)
		(layer "In11.Cu")
		(net "GMI_CPU1_G3_CPU0_G1_TX_DP<3>")
	)
	(segment
		(start 356.136448 -225.373692)
		(end 356.137464 -225.373184)
		(width 0.1143)
		(layer "In11.Cu")
		(net "GMI_CPU1_G3_CPU0_G1_TX_DP<3>")
	)
	(segment
		(start 356.151688 -227.96373)
		(end 356.148894 -227.962206)
		(width 0.1143)
		(layer "In11.Cu")
		(net "GMI_CPU1_G3_CPU0_G1_TX_DP<3>")
	)
	(segment
		(start 115.35029 -226.340416)
		(end 115.34775 -226.34194)
		(width 0.1143)
		(layer "In11.Cu")
		(net "GMI_CPU1_G3_CPU0_G1_TX_DP<3>")
	)
	(segment
		(start 353.727512 -213.657434)
		(end 353.51339 -213.296754)
		(width 0.14224)
		(layer "In11.Cu")
		(net "GMI_CPU1_G3_CPU0_G1_TX_DP<3>")
	)
	(segment
		(start 356.144576 -228.60889)
		(end 356.145592 -228.608382)
		(width 0.1143)
		(layer "In11.Cu")
		(net "GMI_CPU1_G3_CPU0_G1_TX_DP<3>")
	)
	(segment
		(start 356.136448 -226.993704)
		(end 356.137464 -226.993196)
		(width 0.1143)
		(layer "In11.Cu")
		(net "GMI_CPU1_G3_CPU0_G1_TX_DP<3>")
	)
	(segment
		(start 356.148132 -222.12681)
		(end 356.179882 -222.108522)
		(width 0.1143)
		(layer "In11.Cu")
		(net "GMI_CPU1_G3_CPU0_G1_TX_DP<3>")
	)
	(segment
		(start 115.356132 -224.717102)
		(end 115.353084 -224.71888)
		(width 0.1143)
		(layer "In11.Cu")
		(net "GMI_CPU1_G3_CPU0_G1_TX_DP<3>")
	)
	(segment
		(start 115.341146 -223.743266)
		(end 115.341908 -223.743774)
		(width 0.1143)
		(layer "In11.Cu")
		(net "GMI_CPU1_G3_CPU0_G1_TX_DP<3>")
	)
	(segment
		(start 355.754686 -217.071448)
		(end 355.799898 -216.893902)
		(width 0.14224)
		(layer "In11.Cu")
		(net "GMI_CPU1_G3_CPU0_G1_TX_DP<3>")
	)
	(segment
		(start 356.147116 -224.721166)
		(end 356.145592 -224.72015)
		(width 0.1143)
		(layer "In11.Cu")
		(net "GMI_CPU1_G3_CPU0_G1_TX_DP<3>")
	)
	(segment
		(start 356.148894 -231.84612)
		(end 356.150164 -231.845358)
		(width 0.1143)
		(layer "In11.Cu")
		(net "GMI_CPU1_G3_CPU0_G1_TX_DP<3>")
	)
	(segment
		(start 115.346988 -223.102424)
		(end 115.344194 -223.103948)
		(width 0.1143)
		(layer "In11.Cu")
		(net "GMI_CPU1_G3_CPU0_G1_TX_DP<3>")
	)
	(segment
		(start 356.160324 -223.108774)
		(end 356.159054 -223.108012)
		(width 0.1143)
		(layer "In11.Cu")
		(net "GMI_CPU1_G3_CPU0_G1_TX_DP<3>")
	)
	(segment
		(start 115.357656 -226.336098)
		(end 115.356132 -226.337114)
		(width 0.1143)
		(layer "In11.Cu")
		(net "GMI_CPU1_G3_CPU0_G1_TX_DP<3>")
	)
	(segment
		(start 356.335838 -221.80423)
		(end 356.335838 -221.405704)
		(width 0.1143)
		(layer "In11.Cu")
		(net "GMI_CPU1_G3_CPU0_G1_TX_DP<3>")
	)
	(segment
		(start 354.634038 -215.184228)
		(end 354.67925 -215.006682)
		(width 0.14224)
		(layer "In11.Cu")
		(net "GMI_CPU1_G3_CPU0_G1_TX_DP<3>")
	)
	(segment
		(start 356.156006 -223.106234)
		(end 356.154736 -223.105472)
		(width 0.1143)
		(layer "In11.Cu")
		(net "GMI_CPU1_G3_CPU0_G1_TX_DP<3>")
	)
	(segment
		(start 356.158038 -223.107504)
		(end 356.156006 -223.106234)
		(width 0.1143)
		(layer "In11.Cu")
		(net "GMI_CPU1_G3_CPU0_G1_TX_DP<3>")
	)
	(segment
		(start 354.465382 -214.64651)
		(end 354.287582 -214.601044)
		(width 0.14224)
		(layer "In11.Cu")
		(net "GMI_CPU1_G3_CPU0_G1_TX_DP<3>")
	)
	(segment
		(start 115.34775 -223.101916)
		(end 115.346988 -223.102424)
		(width 0.1143)
		(layer "In11.Cu")
		(net "GMI_CPU1_G3_CPU0_G1_TX_DP<3>")
	)
	(segment
		(start 115.353084 -223.098868)
		(end 115.35029 -223.100392)
		(width 0.1143)
		(layer "In11.Cu")
		(net "GMI_CPU1_G3_CPU0_G1_TX_DP<3>")
	)
	(segment
		(start 355.968554 -217.432128)
		(end 355.754686 -217.071448)
		(width 0.14224)
		(layer "In11.Cu")
		(net "GMI_CPU1_G3_CPU0_G1_TX_DP<3>")
	)
	(segment
		(start 115.344194 -226.985068)
		(end 115.346988 -226.986592)
		(width 0.1143)
		(layer "In11.Cu")
		(net "GMI_CPU1_G3_CPU0_G1_TX_DP<3>")
	)
	(segment
		(start 308.042564 -177.894996)
		(end 302.91024 -177.894996)
		(width 0.14224)
		(layer "In11.Cu")
		(net "GMI_CPU1_G3_CPU0_G1_TX_DP<3>")
	)
	(segment
		(start 356.148132 -226.341686)
		(end 356.147116 -226.341178)
		(width 0.1143)
		(layer "In11.Cu")
		(net "GMI_CPU1_G3_CPU0_G1_TX_DP<3>")
	)
	(segment
		(start 115.379246 -225.385376)
		(end 115.380008 -225.385884)
		(width 0.1143)
		(layer "In11.Cu")
		(net "GMI_CPU1_G3_CPU0_G1_TX_DP<3>")
	)
	(segment
		(start 115.357656 -223.096074)
		(end 115.356132 -223.09709)
		(width 0.1143)
		(layer "In11.Cu")
		(net "GMI_CPU1_G3_CPU0_G1_TX_DP<3>")
	)
	(segment
		(start 356.138734 -231.852216)
		(end 356.13975 -231.851708)
		(width 0.1143)
		(layer "In11.Cu")
		(net "GMI_CPU1_G3_CPU0_G1_TX_DP<3>")
	)
	(segment
		(start 356.136448 -228.613716)
		(end 356.137464 -228.613208)
		(width 0.1143)
		(layer "In11.Cu")
		(net "GMI_CPU1_G3_CPU0_G1_TX_DP<3>")
	)
	(segment
		(start 356.151688 -224.723706)
		(end 356.148894 -224.722182)
		(width 0.1143)
		(layer "In11.Cu")
		(net "GMI_CPU1_G3_CPU0_G1_TX_DP<3>")
	)
	(segment
		(start 355.025706 -215.59012)
		(end 354.847906 -215.544654)
		(width 0.14224)
		(layer "In11.Cu")
		(net "GMI_CPU1_G3_CPU0_G1_TX_DP<3>")
	)
	(segment
		(start 356.15245 -224.724214)
		(end 356.151688 -224.723706)
		(width 0.1143)
		(layer "In11.Cu")
		(net "GMI_CPU1_G3_CPU0_G1_TX_DP<3>")
	)
	(segment
		(start 356.13975 -225.371914)
		(end 356.140766 -225.371152)
		(width 0.1143)
		(layer "In11.Cu")
		(net "GMI_CPU1_G3_CPU0_G1_TX_DP<3>")
	)
	(segment
		(start 356.147116 -227.96119)
		(end 356.145592 -227.960174)
		(width 0.1143)
		(layer "In11.Cu")
		(net "GMI_CPU1_G3_CPU0_G1_TX_DP<3>")
	)
	(segment
		(start 115.35029 -224.720404)
		(end 115.34775 -224.721928)
		(width 0.1143)
		(layer "In11.Cu")
		(net "GMI_CPU1_G3_CPU0_G1_TX_DP<3>")
	)
	(segment
		(start 115.353084 -226.338892)
		(end 115.35029 -226.340416)
		(width 0.1143)
		(layer "In11.Cu")
		(net "GMI_CPU1_G3_CPU0_G1_TX_DP<3>")
	)
	(segment
		(start 356.150164 -225.365564)
		(end 356.179882 -225.348546)
		(width 0.1143)
		(layer "In11.Cu")
		(net "GMI_CPU1_G3_CPU0_G1_TX_DP<3>")
	)
	(segment
		(start 354.699062 -234.299506)
		(end 354.698808 -234.299506)
		(width 0.1143)
		(layer "In11.Cu")
		(net "GMI_CPU1_G3_CPU0_G1_TX_DP<3>")
	)
	(segment
		(start 116.39296 -215.597232)
		(end 116.181124 -215.958674)
		(width 0.14224)
		(layer "In11.Cu")
		(net "GMI_CPU1_G3_CPU0_G1_TX_DP<3>")
	)
	(segment
		(start 118.660164 -211.731606)
		(end 116.736368 -215.012016)
		(width 0.14224)
		(layer "In11.Cu")
		(net "GMI_CPU1_G3_CPU0_G1_TX_DP<3>")
	)
	(segment
		(start 356.15245 -226.344226)
		(end 356.151688 -226.343718)
		(width 0.1143)
		(layer "In11.Cu")
		(net "GMI_CPU1_G3_CPU0_G1_TX_DP<3>")
	)
	(segment
		(start 356.148132 -230.226616)
		(end 356.179882 -230.208328)
		(width 0.1143)
		(layer "In11.Cu")
		(net "GMI_CPU1_G3_CPU0_G1_TX_DP<3>")
	)
	(segment
		(start 356.179882 -224.739962)
		(end 356.160324 -224.728786)
		(width 0.1143)
		(layer "In11.Cu")
		(net "GMI_CPU1_G3_CPU0_G1_TX_DP<3>")
	)
	(segment
		(start 356.179882 -223.11995)
		(end 356.160324 -223.108774)
		(width 0.1143)
		(layer "In11.Cu")
		(net "GMI_CPU1_G3_CPU0_G1_TX_DP<3>")
	)
	(segment
		(start 355.40823 -216.488264)
		(end 355.194362 -216.127838)
		(width 0.14224)
		(layer "In11.Cu")
		(net "GMI_CPU1_G3_CPU0_G1_TX_DP<3>")
	)
	(segment
		(start 115.837716 -216.544144)
		(end 115.14709 -217.721688)
		(width 0.14224)
		(layer "In11.Cu")
		(net "GMI_CPU1_G3_CPU0_G1_TX_DP<3>")
	)
	(segment
		(start 356.151688 -226.343718)
		(end 356.148894 -226.342194)
		(width 0.1143)
		(layer "In11.Cu")
		(net "GMI_CPU1_G3_CPU0_G1_TX_DP<3>")
	)
	(segment
		(start 115.10137 -221.347284)
		(end 115.160044 -221.405958)
		(width 0.1143)
		(layer "In11.Cu")
		(net "GMI_CPU1_G3_CPU0_G1_TX_DP<3>")
	)
	(segment
		(start 353.51339 -213.296754)
		(end 353.558856 -213.119208)
		(width 0.14224)
		(layer "In11.Cu")
		(net "GMI_CPU1_G3_CPU0_G1_TX_DP<3>")
	)
	(segment
		(start 356.145592 -228.608382)
		(end 356.147116 -228.607366)
		(width 0.1143)
		(layer "In11.Cu")
		(net "GMI_CPU1_G3_CPU0_G1_TX_DP<3>")
	)
	(segment
		(start 116.227352 -216.135966)
		(end 116.015262 -216.497662)
		(width 0.14224)
		(layer "In11.Cu")
		(net "GMI_CPU1_G3_CPU0_G1_TX_DP<3>")
	)
	(segment
		(start 356.145592 -224.72015)
		(end 356.109016 -224.698814)
		(width 0.1143)
		(layer "In11.Cu")
		(net "GMI_CPU1_G3_CPU0_G1_TX_DP<3>")
	)
	(segment
		(start 115.346988 -231.846374)
		(end 115.34775 -231.846882)
		(width 0.1143)
		(layer "In11.Cu")
		(net "GMI_CPU1_G3_CPU0_G1_TX_DP<3>")
	)
	(segment
		(start 157.369002 -179.99202)
		(end 118.660164 -211.731606)
		(width 0.14224)
		(layer "In11.Cu")
		(net "GMI_CPU1_G3_CPU0_G1_TX_DP<3>")
	)
	(segment
		(start 352.914966 -212.28812)
		(end 352.960178 -212.110828)
		(width 0.14224)
		(layer "In11.Cu")
		(net "GMI_CPU1_G3_CPU0_G1_TX_DP<3>")
	)
	(segment
		(start 356.159054 -227.968048)
		(end 356.158038 -227.96754)
		(width 0.1143)
		(layer "In11.Cu")
		(net "GMI_CPU1_G3_CPU0_G1_TX_DP<3>")
	)
	(segment
		(start 354.75164 -234.269026)
		(end 354.751894 -234.269026)
		(width 0.1143)
		(layer "In11.Cu")
		(net "GMI_CPU1_G3_CPU0_G1_TX_DP<3>")
	)
	(segment
		(start 354.08108 -234.764072)
		(end 354.379022 -234.764072)
		(width 0.1143)
		(layer "In11.Cu")
		(net "GMI_CPU1_G3_CPU0_G1_TX_DP<3>")
	)
	(segment
		(start 115.14709 -217.721688)
		(end 115.14709 -221.071948)
		(width 0.14224)
		(layer "In11.Cu")
		(net "GMI_CPU1_G3_CPU0_G1_TX_DP<3>")
	)
	(segment
		(start 356.15245 -227.964238)
		(end 356.151688 -227.96373)
		(width 0.1143)
		(layer "In11.Cu")
		(net "GMI_CPU1_G3_CPU0_G1_TX_DP<3>")
	)
	(arc
		(start 356.179882 -228.58857)
		(mid 356.33581 -228.284278)
		(end 356.179882 -227.979986)
		(width 0.1143)
		(layer "In11.Cu")
		(net "GMI_CPU1_G3_CPU0_G1_TX_DP<3>")
	)
	(arc
		(start 355.239828 -233.448098)
		(mid 355.288738 -233.406127)
		(end 355.329744 -233.356404)
		(width 0.1143)
		(layer "In11.Cu")
		(net "GMI_CPU1_G3_CPU0_G1_TX_DP<3>")
	)
	(arc
		(start 356.179882 -225.348546)
		(mid 356.33581 -225.044254)
		(end 356.179882 -224.739962)
		(width 0.1143)
		(layer "In11.Cu")
		(net "GMI_CPU1_G3_CPU0_G1_TX_DP<3>")
	)
	(arc
		(start 356.179882 -230.208328)
		(mid 356.294558 -230.074994)
		(end 356.335838 -229.904036)
		(width 0.1143)
		(layer "In11.Cu")
		(net "GMI_CPU1_G3_CPU0_G1_TX_DP<3>")
	)
	(arc
		(start 115.386866 -227.00996)
		(mid 115.630193 -227.474526)
		(end 115.386866 -227.939092)
		(width 0.1143)
		(layer "In11.Cu")
		(net "GMI_CPU1_G3_CPU0_G1_TX_DP<3>")
	)
	(arc
		(start 115.630198 -232.334308)
		(mid 115.671747 -232.50573)
		(end 115.78717 -232.639108)
		(width 0.1143)
		(layer "In11.Cu")
		(net "GMI_CPU1_G3_CPU0_G1_TX_DP<3>")
	)
	(arc
		(start 115.314222 -229.601522)
		(mid 115.200815 -229.734411)
		(end 115.160044 -229.90429)
		(width 0.1143)
		(layer "In11.Cu")
		(net "GMI_CPU1_G3_CPU0_G1_TX_DP<3>")
	)
	(arc
		(start 116.166138 -233.356658)
		(mid 116.207127 -233.406399)
		(end 116.256054 -233.448352)
		(width 0.1143)
		(layer "In11.Cu")
		(net "GMI_CPU1_G3_CPU0_G1_TX_DP<3>")
	)
	(arc
		(start 115.160044 -231.524302)
		(mid 115.201299 -231.695273)
		(end 115.316 -231.828594)
		(width 0.1143)
		(layer "In11.Cu")
		(net "GMI_CPU1_G3_CPU0_G1_TX_DP<3>")
	)
	(arc
		(start 356.109016 -223.078802)
		(mid 355.865689 -222.614236)
		(end 356.109016 -222.14967)
		(width 0.1143)
		(layer "In11.Cu")
		(net "GMI_CPU1_G3_CPU0_G1_TX_DP<3>")
	)
	(arc
		(start 356.179882 -231.82834)
		(mid 356.294558 -231.695006)
		(end 356.335838 -231.524048)
		(width 0.1143)
		(layer "In11.Cu")
		(net "GMI_CPU1_G3_CPU0_G1_TX_DP<3>")
	)
	(arc
		(start 356.179882 -226.968558)
		(mid 356.33581 -226.664266)
		(end 356.179882 -226.359974)
		(width 0.1143)
		(layer "In11.Cu")
		(net "GMI_CPU1_G3_CPU0_G1_TX_DP<3>")
	)
	(arc
		(start 355.865684 -230.714296)
		(mid 355.93092 -230.450705)
		(end 356.111556 -230.247952)
		(width 0.1143)
		(layer "In11.Cu")
		(net "GMI_CPU1_G3_CPU0_G1_TX_DP<3>")
	)
	(arc
		(start 354.751894 -234.269026)
		(mid 354.888406 -234.131876)
		(end 354.93833 -233.944922)
		(width 0.1143)
		(layer "In11.Cu")
		(net "GMI_CPU1_G3_CPU0_G1_TX_DP<3>")
	)
	(arc
		(start 116.79682 -234.29976)
		(mid 116.948807 -234.456268)
		(end 117.030246 -234.658662)
		(width 0.1143)
		(layer "In11.Cu")
		(net "GMI_CPU1_G3_CPU0_G1_TX_DP<3>")
	)
	(arc
		(start 356.179882 -222.108522)
		(mid 356.294558 -221.975188)
		(end 356.335838 -221.80423)
		(width 0.1143)
		(layer "In11.Cu")
		(net "GMI_CPU1_G3_CPU0_G1_TX_DP<3>")
	)
	(arc
		(start 356.109016 -231.178862)
		(mid 355.930203 -230.976512)
		(end 355.865684 -230.714296)
		(width 0.1143)
		(layer "In11.Cu")
		(net "GMI_CPU1_G3_CPU0_G1_TX_DP<3>")
	)
	(arc
		(start 354.461826 -234.681268)
		(mid 354.463614 -234.669819)
		(end 354.465636 -234.658408)
		(width 0.1143)
		(layer "In11.Cu")
		(net "GMI_CPU1_G3_CPU0_G1_TX_DP<3>")
	)
	(arc
		(start 115.314222 -231.221534)
		(mid 115.200815 -231.354423)
		(end 115.160044 -231.524302)
		(width 0.1143)
		(layer "In11.Cu")
		(net "GMI_CPU1_G3_CPU0_G1_TX_DP<3>")
	)
	(arc
		(start 356.109016 -229.55885)
		(mid 355.865689 -229.094284)
		(end 356.109016 -228.629718)
		(width 0.1143)
		(layer "In11.Cu")
		(net "GMI_CPU1_G3_CPU0_G1_TX_DP<3>")
	)
	(arc
		(start 115.316 -224.740216)
		(mid 115.160072 -225.044508)
		(end 115.316 -225.3488)
		(width 0.1143)
		(layer "In11.Cu")
		(net "GMI_CPU1_G3_CPU0_G1_TX_DP<3>")
	)
	(arc
		(start 115.386866 -223.769936)
		(mid 115.630193 -224.234502)
		(end 115.386866 -224.699068)
		(width 0.1143)
		(layer "In11.Cu")
		(net "GMI_CPU1_G3_CPU0_G1_TX_DP<3>")
	)
	(arc
		(start 115.386866 -225.389948)
		(mid 115.630193 -225.854514)
		(end 115.386866 -226.31908)
		(width 0.1143)
		(layer "In11.Cu")
		(net "GMI_CPU1_G3_CPU0_G1_TX_DP<3>")
	)
	(arc
		(start 354.465636 -234.658408)
		(mid 354.547069 -234.45601)
		(end 354.699062 -234.299506)
		(width 0.1143)
		(layer "In11.Cu")
		(net "GMI_CPU1_G3_CPU0_G1_TX_DP<3>")
	)
	(arc
		(start 115.316 -227.98024)
		(mid 115.160072 -228.284532)
		(end 115.316 -228.588824)
		(width 0.1143)
		(layer "In11.Cu")
		(net "GMI_CPU1_G3_CPU0_G1_TX_DP<3>")
	)
	(arc
		(start 115.386866 -228.629972)
		(mid 115.630193 -229.094538)
		(end 115.386866 -229.559104)
		(width 0.1143)
		(layer "In11.Cu")
		(net "GMI_CPU1_G3_CPU0_G1_TX_DP<3>")
	)
	(arc
		(start 356.109016 -226.318826)
		(mid 355.865689 -225.85426)
		(end 356.109016 -225.389694)
		(width 0.1143)
		(layer "In11.Cu")
		(net "GMI_CPU1_G3_CPU0_G1_TX_DP<3>")
	)
	(arc
		(start 356.335838 -229.904036)
		(mid 356.295076 -229.734152)
		(end 356.18166 -229.601268)
		(width 0.1143)
		(layer "In11.Cu")
		(net "GMI_CPU1_G3_CPU0_G1_TX_DP<3>")
	)
	(arc
		(start 356.109016 -227.938838)
		(mid 355.865689 -227.474272)
		(end 356.109016 -227.009706)
		(width 0.1143)
		(layer "In11.Cu")
		(net "GMI_CPU1_G3_CPU0_G1_TX_DP<3>")
	)
	(arc
		(start 115.384326 -230.248206)
		(mid 115.630214 -230.713)
		(end 115.386866 -231.179116)
		(width 0.1143)
		(layer "In11.Cu")
		(net "GMI_CPU1_G3_CPU0_G1_TX_DP<3>")
	)
	(arc
		(start 356.179882 -223.728534)
		(mid 356.33581 -223.424242)
		(end 356.179882 -223.11995)
		(width 0.1143)
		(layer "In11.Cu")
		(net "GMI_CPU1_G3_CPU0_G1_TX_DP<3>")
	)
	(arc
		(start 115.160044 -221.804484)
		(mid 115.201299 -221.975455)
		(end 115.316 -222.108776)
		(width 0.1143)
		(layer "In11.Cu")
		(net "GMI_CPU1_G3_CPU0_G1_TX_DP<3>")
	)
	(arc
		(start 115.316 -223.120204)
		(mid 115.160072 -223.424496)
		(end 115.316 -223.728788)
		(width 0.1143)
		(layer "In11.Cu")
		(net "GMI_CPU1_G3_CPU0_G1_TX_DP<3>")
	)
	(arc
		(start 356.335838 -231.524048)
		(mid 356.295076 -231.354164)
		(end 356.18166 -231.22128)
		(width 0.1143)
		(layer "In11.Cu")
		(net "GMI_CPU1_G3_CPU0_G1_TX_DP<3>")
	)
	(arc
		(start 117.030246 -234.658662)
		(mid 117.032269 -234.670072)
		(end 117.034056 -234.681522)
		(width 0.1143)
		(layer "In11.Cu")
		(net "GMI_CPU1_G3_CPU0_G1_TX_DP<3>")
	)
	(arc
		(start 115.160044 -229.90429)
		(mid 115.201299 -230.075261)
		(end 115.316 -230.208582)
		(width 0.1143)
		(layer "In11.Cu")
		(net "GMI_CPU1_G3_CPU0_G1_TX_DP<3>")
	)
	(arc
		(start 115.386866 -231.869742)
		(mid 115.565679 -232.072092)
		(end 115.630198 -232.334308)
		(width 0.1143)
		(layer "In11.Cu")
		(net "GMI_CPU1_G3_CPU0_G1_TX_DP<3>")
	)
	(arc
		(start 115.386866 -222.149924)
		(mid 115.630193 -222.61449)
		(end 115.386866 -223.079056)
		(width 0.1143)
		(layer "In11.Cu")
		(net "GMI_CPU1_G3_CPU0_G1_TX_DP<3>")
	)
	(arc
		(start 115.316 -226.360228)
		(mid 115.160072 -226.66452)
		(end 115.316 -226.968812)
		(width 0.1143)
		(layer "In11.Cu")
		(net "GMI_CPU1_G3_CPU0_G1_TX_DP<3>")
	)
	(arc
		(start 116.100098 -233.144314)
		(mid 116.116969 -233.255515)
		(end 116.166138 -233.356658)
		(width 0.1143)
		(layer "In11.Cu")
		(net "GMI_CPU1_G3_CPU0_G1_TX_DP<3>")
	)
	(arc
		(start 355.865684 -232.334054)
		(mid 355.930199 -232.071835)
		(end 356.109016 -231.869488)
		(width 0.1143)
		(layer "In11.Cu")
		(net "GMI_CPU1_G3_CPU0_G1_TX_DP<3>")
	)
	(arc
		(start 356.109016 -224.698814)
		(mid 355.865689 -224.234248)
		(end 356.109016 -223.769682)
		(width 0.1143)
		(layer "In11.Cu")
		(net "GMI_CPU1_G3_CPU0_G1_TX_DP<3>")
	)
	(arc
		(start 116.557552 -233.945176)
		(mid 116.608581 -234.134077)
		(end 116.747798 -234.271566)
		(width 0.1143)
		(layer "In11.Cu")
		(net "GMI_CPU1_G3_CPU0_G1_TX_DP<3>")
	)
	(arc
		(start 355.708712 -232.638854)
		(mid 355.824139 -232.505478)
		(end 355.865684 -232.334054)
		(width 0.1143)
		(layer "In11.Cu")
		(net "GMI_CPU1_G3_CPU0_G1_TX_DP<3>")
	)
	(arc
		(start 355.329744 -233.356404)
		(mid 355.378828 -233.255235)
		(end 355.395784 -233.14406)
		(width 0.1143)
		(layer "In11.Cu")
		(net "GMI_CPU1_G3_CPU0_G1_TX_DP<3>")
	)
	(arc
		(start 115.856766 -232.679748)
		(mid 116.035579 -232.882098)
		(end 116.100098 -233.144314)
		(width 0.1143)
		(layer "In11.Cu")
		(net "GMI_CPU1_G3_CPU0_G1_TX_DP<3>")
	)
	(arc
		(start 354.93833 -233.934762)
		(mid 355.010672 -233.664564)
		(end 355.208332 -233.46664)
		(width 0.1143)
		(layer "In11.Cu")
		(net "GMI_CPU1_G3_CPU0_G1_TX_DP<3>")
	)
	(arc
		(start 355.395784 -233.14406)
		(mid 355.460299 -232.881841)
		(end 355.639116 -232.679494)
		(width 0.1143)
		(layer "In11.Cu")
		(net "GMI_CPU1_G3_CPU0_G1_TX_DP<3>")
	)
	(arc
		(start 116.28755 -233.466894)
		(mid 116.485229 -233.664807)
		(end 116.557552 -233.935016)
		(width 0.1143)
		(layer "In11.Cu")
		(net "GMI_CPU1_G3_CPU0_G1_TX_DP<3>")
	)
	(segment
		(start 114.597942 -232.600246)
		(end 115.064794 -232.334308)
		(width 0.12954)
		(layer "F.Cu")
		(net "GMI_CPU1_G3_CPU0_G1_TX_DP<2>")
	)
	(segment
		(start 356.89794 -232.599992)
		(end 356.431088 -232.334054)
		(width 0.12954)
		(layer "F.Cu")
		(net "GMI_CPU1_G3_CPU0_G1_TX_DP<2>")
	)
	(segment
		(start 357.088948 -231.84612)
		(end 357.089456 -231.845866)
		(width 0.1143)
		(layer "In11.Cu")
		(net "GMI_CPU1_G3_CPU0_G1_TX_DP<2>")
	)
	(segment
		(start 114.446812 -227.939092)
		(end 114.410236 -227.960428)
		(width 0.1143)
		(layer "In11.Cu")
		(net "GMI_CPU1_G3_CPU0_G1_TX_DP<2>")
	)
	(segment
		(start 302.913288 -176.955196)
		(end 165.305994 -176.151286)
		(width 0.14224)
		(layer "In11.Cu")
		(net "GMI_CPU1_G3_CPU0_G1_TX_DP<2>")
	)
	(segment
		(start 355.781356 -215.026494)
		(end 355.567488 -214.666068)
		(width 0.14224)
		(layer "In11.Cu")
		(net "GMI_CPU1_G3_CPU0_G1_TX_DP<2>")
	)
	(segment
		(start 114.439954 -223.765872)
		(end 114.446812 -223.769936)
		(width 0.1143)
		(layer "In11.Cu")
		(net "GMI_CPU1_G3_CPU0_G1_TX_DP<2>")
	)
	(segment
		(start 357.339392 -221.128844)
		(end 357.293672 -221.083124)
		(width 0.1143)
		(layer "In11.Cu")
		(net "GMI_CPU1_G3_CPU0_G1_TX_DP<2>")
	)
	(segment
		(start 357.088186 -227.961698)
		(end 357.08717 -227.96119)
		(width 0.1143)
		(layer "In11.Cu")
		(net "GMI_CPU1_G3_CPU0_G1_TX_DP<2>")
	)
	(segment
		(start 357.119936 -223.728534)
		(end 357.139748 -223.71431)
		(width 0.1143)
		(layer "In11.Cu")
		(net "GMI_CPU1_G3_CPU0_G1_TX_DP<2>")
	)
	(segment
		(start 114.406934 -227.96246)
		(end 114.375946 -227.98024)
		(width 0.1143)
		(layer "In11.Cu")
		(net "GMI_CPU1_G3_CPU0_G1_TX_DP<2>")
	)
	(segment
		(start 114.439954 -231.865678)
		(end 114.446812 -231.869742)
		(width 0.1143)
		(layer "In11.Cu")
		(net "GMI_CPU1_G3_CPU0_G1_TX_DP<2>")
	)
	(segment
		(start 114.15649 -221.129098)
		(end 114.15649 -221.347284)
		(width 0.1143)
		(layer "In11.Cu")
		(net "GMI_CPU1_G3_CPU0_G1_TX_DP<2>")
	)
	(segment
		(start 114.20221 -221.071948)
		(end 114.20221 -221.083378)
		(width 0.1143)
		(layer "In11.Cu")
		(net "GMI_CPU1_G3_CPU0_G1_TX_DP<2>")
	)
	(segment
		(start 357.09479 -222.123)
		(end 357.095806 -222.122492)
		(width 0.1143)
		(layer "In11.Cu")
		(net "GMI_CPU1_G3_CPU0_G1_TX_DP<2>")
	)
	(segment
		(start 355.398832 -214.12835)
		(end 355.221032 -214.082884)
		(width 0.14224)
		(layer "In11.Cu")
		(net "GMI_CPU1_G3_CPU0_G1_TX_DP<2>")
	)
	(segment
		(start 114.375946 -228.588824)
		(end 114.406934 -228.606604)
		(width 0.1143)
		(layer "In11.Cu")
		(net "GMI_CPU1_G3_CPU0_G1_TX_DP<2>")
	)
	(segment
		(start 114.446812 -223.079056)
		(end 114.410236 -223.100392)
		(width 0.1143)
		(layer "In11.Cu")
		(net "GMI_CPU1_G3_CPU0_G1_TX_DP<2>")
	)
	(segment
		(start 114.439192 -227.005388)
		(end 114.439954 -227.005896)
		(width 0.1143)
		(layer "In11.Cu")
		(net "GMI_CPU1_G3_CPU0_G1_TX_DP<2>")
	)
	(segment
		(start 355.052376 -213.544912)
		(end 354.838508 -213.18474)
		(width 0.14224)
		(layer "In11.Cu")
		(net "GMI_CPU1_G3_CPU0_G1_TX_DP<2>")
	)
	(segment
		(start 114.408712 -230.227378)
		(end 114.439192 -230.245158)
		(width 0.1143)
		(layer "In11.Cu")
		(net "GMI_CPU1_G3_CPU0_G1_TX_DP<2>")
	)
	(segment
		(start 114.407696 -231.201976)
		(end 114.374168 -231.221534)
		(width 0.1143)
		(layer "In11.Cu")
		(net "GMI_CPU1_G3_CPU0_G1_TX_DP<2>")
	)
	(segment
		(start 357.08717 -223.74733)
		(end 357.088186 -223.746822)
		(width 0.1143)
		(layer "In11.Cu")
		(net "GMI_CPU1_G3_CPU0_G1_TX_DP<2>")
	)
	(segment
		(start 114.702336 -216.36863)
		(end 114.20221 -217.221054)
		(width 0.14224)
		(layer "In11.Cu")
		(net "GMI_CPU1_G3_CPU0_G1_TX_DP<2>")
	)
	(segment
		(start 114.879882 -216.322656)
		(end 114.702336 -216.36863)
		(width 0.14224)
		(layer "In11.Cu")
		(net "GMI_CPU1_G3_CPU0_G1_TX_DP<2>")
	)
	(segment
		(start 114.408712 -227.961444)
		(end 114.407696 -227.961952)
		(width 0.1143)
		(layer "In11.Cu")
		(net "GMI_CPU1_G3_CPU0_G1_TX_DP<2>")
	)
	(segment
		(start 156.917136 -179.151026)
		(end 117.64772 -211.349844)
		(width 0.14224)
		(layer "In11.Cu")
		(net "GMI_CPU1_G3_CPU0_G1_TX_DP<2>")
	)
	(segment
		(start 114.439192 -223.765364)
		(end 114.439954 -223.765872)
		(width 0.1143)
		(layer "In11.Cu")
		(net "GMI_CPU1_G3_CPU0_G1_TX_DP<2>")
	)
	(segment
		(start 114.446812 -229.559104)
		(end 114.407696 -229.581964)
		(width 0.1143)
		(layer "In11.Cu")
		(net "GMI_CPU1_G3_CPU0_G1_TX_DP<2>")
	)
	(segment
		(start 356.688136 -216.553288)
		(end 356.733348 -216.375742)
		(width 0.14224)
		(layer "In11.Cu")
		(net "GMI_CPU1_G3_CPU0_G1_TX_DP<2>")
	)
	(segment
		(start 114.439954 -230.245666)
		(end 114.444272 -230.248206)
		(width 0.1143)
		(layer "In11.Cu")
		(net "GMI_CPU1_G3_CPU0_G1_TX_DP<2>")
	)
	(segment
		(start 114.403378 -222.124524)
		(end 114.40414 -222.125032)
		(width 0.1143)
		(layer "In11.Cu")
		(net "GMI_CPU1_G3_CPU0_G1_TX_DP<2>")
	)
	(segment
		(start 357.04907 -227.009706)
		(end 357.085646 -226.98837)
		(width 0.1143)
		(layer "In11.Cu")
		(net "GMI_CPU1_G3_CPU0_G1_TX_DP<2>")
	)
	(segment
		(start 356.902004 -216.913968)
		(end 356.688136 -216.553288)
		(width 0.14224)
		(layer "In11.Cu")
		(net "GMI_CPU1_G3_CPU0_G1_TX_DP<2>")
	)
	(segment
		(start 114.407696 -228.607112)
		(end 114.439192 -228.6254)
		(width 0.1143)
		(layer "In11.Cu")
		(net "GMI_CPU1_G3_CPU0_G1_TX_DP<2>")
	)
	(segment
		(start 114.406934 -222.126556)
		(end 114.407696 -222.127064)
		(width 0.1143)
		(layer "In11.Cu")
		(net "GMI_CPU1_G3_CPU0_G1_TX_DP<2>")
	)
	(segment
		(start 357.08336 -230.22941)
		(end 357.08717 -230.227124)
		(width 0.1143)
		(layer "In11.Cu")
		(net "GMI_CPU1_G3_CPU0_G1_TX_DP<2>")
	)
	(segment
		(start 114.446812 -226.31908)
		(end 114.410236 -226.340416)
		(width 0.1143)
		(layer "In11.Cu")
		(net "GMI_CPU1_G3_CPU0_G1_TX_DP<2>")
	)
	(segment
		(start 357.08717 -226.987354)
		(end 357.088186 -226.986846)
		(width 0.1143)
		(layer "In11.Cu")
		(net "GMI_CPU1_G3_CPU0_G1_TX_DP<2>")
	)
	(segment
		(start 357.08717 -231.847136)
		(end 357.088186 -231.846628)
		(width 0.1143)
		(layer "In11.Cu")
		(net "GMI_CPU1_G3_CPU0_G1_TX_DP<2>")
	)
	(segment
		(start 114.407696 -223.101916)
		(end 114.406934 -223.102424)
		(width 0.1143)
		(layer "In11.Cu")
		(net "GMI_CPU1_G3_CPU0_G1_TX_DP<2>")
	)
	(segment
		(start 317.647828 -181.723284)
		(end 310.648096 -177.760884)
		(width 0.14224)
		(layer "In11.Cu")
		(net "GMI_CPU1_G3_CPU0_G1_TX_DP<2>")
	)
	(segment
		(start 357.119936 -223.11995)
		(end 357.088948 -223.10217)
		(width 0.1143)
		(layer "In11.Cu")
		(net "GMI_CPU1_G3_CPU0_G1_TX_DP<2>")
	)
	(segment
		(start 114.401854 -222.123762)
		(end 114.403378 -222.124524)
		(width 0.1143)
		(layer "In11.Cu")
		(net "GMI_CPU1_G3_CPU0_G1_TX_DP<2>")
	)
	(segment
		(start 114.375946 -226.968812)
		(end 114.406934 -226.986592)
		(width 0.1143)
		(layer "In11.Cu")
		(net "GMI_CPU1_G3_CPU0_G1_TX_DP<2>")
	)
	(segment
		(start 357.082598 -230.229918)
		(end 357.08336 -230.22941)
		(width 0.1143)
		(layer "In11.Cu")
		(net "GMI_CPU1_G3_CPU0_G1_TX_DP<2>")
	)
	(segment
		(start 114.406934 -223.102424)
		(end 114.375946 -223.120204)
		(width 0.1143)
		(layer "In11.Cu")
		(net "GMI_CPU1_G3_CPU0_G1_TX_DP<2>")
	)
	(segment
		(start 114.406934 -225.36658)
		(end 114.407696 -225.367088)
		(width 0.1143)
		(layer "In11.Cu")
		(net "GMI_CPU1_G3_CPU0_G1_TX_DP<2>")
	)
	(segment
		(start 114.410236 -226.340416)
		(end 114.408712 -226.341432)
		(width 0.1143)
		(layer "In11.Cu")
		(net "GMI_CPU1_G3_CPU0_G1_TX_DP<2>")
	)
	(segment
		(start 114.439954 -227.005896)
		(end 114.446812 -227.00996)
		(width 0.1143)
		(layer "In11.Cu")
		(net "GMI_CPU1_G3_CPU0_G1_TX_DP<2>")
	)
	(segment
		(start 115.64747 -215.014556)
		(end 115.43538 -215.376252)
		(width 0.14224)
		(layer "In11.Cu")
		(net "GMI_CPU1_G3_CPU0_G1_TX_DP<2>")
	)
	(segment
		(start 114.406934 -231.846374)
		(end 114.407696 -231.846882)
		(width 0.1143)
		(layer "In11.Cu")
		(net "GMI_CPU1_G3_CPU0_G1_TX_DP<2>")
	)
	(segment
		(start 114.375946 -223.120204)
		(end 114.356134 -223.134428)
		(width 0.1143)
		(layer "In11.Cu")
		(net "GMI_CPU1_G3_CPU0_G1_TX_DP<2>")
	)
	(segment
		(start 357.088948 -224.722182)
		(end 357.088186 -224.721674)
		(width 0.1143)
		(layer "In11.Cu")
		(net "GMI_CPU1_G3_CPU0_G1_TX_DP<2>")
	)
	(segment
		(start 356.34168 -215.970358)
		(end 356.127812 -215.609678)
		(width 0.14224)
		(layer "In11.Cu")
		(net "GMI_CPU1_G3_CPU0_G1_TX_DP<2>")
	)
	(segment
		(start 114.375946 -223.728788)
		(end 114.406934 -223.746568)
		(width 0.1143)
		(layer "In11.Cu")
		(net "GMI_CPU1_G3_CPU0_G1_TX_DP<2>")
	)
	(segment
		(start 114.15649 -221.347284)
		(end 114.21999 -221.410784)
		(width 0.1143)
		(layer "In11.Cu")
		(net "GMI_CPU1_G3_CPU0_G1_TX_DP<2>")
	)
	(segment
		(start 355.567488 -214.666068)
		(end 355.6127 -214.488522)
		(width 0.14224)
		(layer "In11.Cu")
		(net "GMI_CPU1_G3_CPU0_G1_TX_DP<2>")
	)
	(segment
		(start 114.406934 -226.342448)
		(end 114.375946 -226.360228)
		(width 0.1143)
		(layer "In11.Cu")
		(net "GMI_CPU1_G3_CPU0_G1_TX_DP<2>")
	)
	(segment
		(start 114.410236 -223.100392)
		(end 114.408712 -223.101408)
		(width 0.1143)
		(layer "In11.Cu")
		(net "GMI_CPU1_G3_CPU0_G1_TX_DP<2>")
	)
	(segment
		(start 114.408712 -226.341432)
		(end 114.407696 -226.34194)
		(width 0.1143)
		(layer "In11.Cu")
		(net "GMI_CPU1_G3_CPU0_G1_TX_DP<2>")
	)
	(segment
		(start 357.079804 -216.95918)
		(end 356.902004 -216.913968)
		(width 0.14224)
		(layer "In11.Cu")
		(net "GMI_CPU1_G3_CPU0_G1_TX_DP<2>")
	)
	(segment
		(start 357.08717 -225.367342)
		(end 357.088186 -225.366834)
		(width 0.1143)
		(layer "In11.Cu")
		(net "GMI_CPU1_G3_CPU0_G1_TX_DP<2>")
	)
	(segment
		(start 114.406934 -228.606604)
		(end 114.407696 -228.607112)
		(width 0.1143)
		(layer "In11.Cu")
		(net "GMI_CPU1_G3_CPU0_G1_TX_DP<2>")
	)
	(segment
		(start 356.51948 -216.01557)
		(end 356.34168 -215.970358)
		(width 0.14224)
		(layer "In11.Cu")
		(net "GMI_CPU1_G3_CPU0_G1_TX_DP<2>")
	)
	(segment
		(start 114.406426 -231.84612)
		(end 114.406934 -231.846374)
		(width 0.1143)
		(layer "In11.Cu")
		(net "GMI_CPU1_G3_CPU0_G1_TX_DP<2>")
	)
	(segment
		(start 357.085646 -227.960174)
		(end 357.04907 -227.938838)
		(width 0.1143)
		(layer "In11.Cu")
		(net "GMI_CPU1_G3_CPU0_G1_TX_DP<2>")
	)
	(segment
		(start 357.05669 -230.244904)
		(end 357.082598 -230.229918)
		(width 0.1143)
		(layer "In11.Cu")
		(net "GMI_CPU1_G3_CPU0_G1_TX_DP<2>")
	)
	(segment
		(start 114.408712 -224.72142)
		(end 114.407696 -224.721928)
		(width 0.1143)
		(layer "In11.Cu")
		(net "GMI_CPU1_G3_CPU0_G1_TX_DP<2>")
	)
	(segment
		(start 114.375946 -222.108776)
		(end 114.400076 -222.122746)
		(width 0.1143)
		(layer "In11.Cu")
		(net "GMI_CPU1_G3_CPU0_G1_TX_DP<2>")
	)
	(segment
		(start 356.127812 -215.609678)
		(end 356.173024 -215.432132)
		(width 0.14224)
		(layer "In11.Cu")
		(net "GMI_CPU1_G3_CPU0_G1_TX_DP<2>")
	)
	(segment
		(start 114.406934 -226.986592)
		(end 114.407696 -226.9871)
		(width 0.1143)
		(layer "In11.Cu")
		(net "GMI_CPU1_G3_CPU0_G1_TX_DP<2>")
	)
	(segment
		(start 357.293672 -221.071694)
		(end 357.293672 -217.319352)
		(width 0.14224)
		(layer "In11.Cu")
		(net "GMI_CPU1_G3_CPU0_G1_TX_DP<2>")
	)
	(segment
		(start 357.121714 -231.22128)
		(end 357.04907 -231.178862)
		(width 0.1143)
		(layer "In11.Cu")
		(net "GMI_CPU1_G3_CPU0_G1_TX_DP<2>")
	)
	(segment
		(start 357.088186 -228.606858)
		(end 357.088948 -228.60635)
		(width 0.1143)
		(layer "In11.Cu")
		(net "GMI_CPU1_G3_CPU0_G1_TX_DP<2>")
	)
	(segment
		(start 357.05161 -230.247952)
		(end 357.055928 -230.245412)
		(width 0.1143)
		(layer "In11.Cu")
		(net "GMI_CPU1_G3_CPU0_G1_TX_DP<2>")
	)
	(segment
		(start 357.085646 -225.368358)
		(end 357.08717 -225.367342)
		(width 0.1143)
		(layer "In11.Cu")
		(net "GMI_CPU1_G3_CPU0_G1_TX_DP<2>")
	)
	(segment
		(start 357.088186 -224.721674)
		(end 357.08717 -224.721166)
		(width 0.1143)
		(layer "In11.Cu")
		(net "GMI_CPU1_G3_CPU0_G1_TX_DP<2>")
	)
	(segment
		(start 354.838508 -213.18474)
		(end 354.660962 -213.139274)
		(width 0.14224)
		(layer "In11.Cu")
		(net "GMI_CPU1_G3_CPU0_G1_TX_DP<2>")
	)
	(segment
		(start 357.08717 -222.127318)
		(end 357.088186 -222.12681)
		(width 0.1143)
		(layer "In11.Cu")
		(net "GMI_CPU1_G3_CPU0_G1_TX_DP<2>")
	)
	(segment
		(start 115.045744 -215.783668)
		(end 115.091972 -215.96096)
		(width 0.14224)
		(layer "In11.Cu")
		(net "GMI_CPU1_G3_CPU0_G1_TX_DP<2>")
	)
	(segment
		(start 114.40414 -222.125032)
		(end 114.406934 -222.126556)
		(width 0.1143)
		(layer "In11.Cu")
		(net "GMI_CPU1_G3_CPU0_G1_TX_DP<2>")
	)
	(segment
		(start 357.08717 -224.721166)
		(end 357.085646 -224.72015)
		(width 0.1143)
		(layer "In11.Cu")
		(net "GMI_CPU1_G3_CPU0_G1_TX_DP<2>")
	)
	(segment
		(start 357.119936 -227.979986)
		(end 357.088948 -227.962206)
		(width 0.1143)
		(layer "In11.Cu")
		(net "GMI_CPU1_G3_CPU0_G1_TX_DP<2>")
	)
	(segment
		(start 357.119936 -224.739962)
		(end 357.088948 -224.722182)
		(width 0.1143)
		(layer "In11.Cu")
		(net "GMI_CPU1_G3_CPU0_G1_TX_DP<2>")
	)
	(segment
		(start 357.04907 -223.769682)
		(end 357.085646 -223.748346)
		(width 0.1143)
		(layer "In11.Cu")
		(net "GMI_CPU1_G3_CPU0_G1_TX_DP<2>")
	)
	(segment
		(start 114.20221 -217.221054)
		(end 114.20221 -221.071948)
		(width 0.14224)
		(layer "In11.Cu")
		(net "GMI_CPU1_G3_CPU0_G1_TX_DP<2>")
	)
	(segment
		(start 114.375946 -225.3488)
		(end 114.406934 -225.36658)
		(width 0.1143)
		(layer "In11.Cu")
		(net "GMI_CPU1_G3_CPU0_G1_TX_DP<2>")
	)
	(segment
		(start 356.72903 -232.334054)
		(end 356.811834 -232.25125)
		(width 0.1143)
		(layer "In11.Cu")
		(net "GMI_CPU1_G3_CPU0_G1_TX_DP<2>")
	)
	(segment
		(start 357.293672 -217.319352)
		(end 357.079804 -216.95918)
		(width 0.14224)
		(layer "In11.Cu")
		(net "GMI_CPU1_G3_CPU0_G1_TX_DP<2>")
	)
	(segment
		(start 357.088948 -227.962206)
		(end 357.088186 -227.961698)
		(width 0.1143)
		(layer "In11.Cu")
		(net "GMI_CPU1_G3_CPU0_G1_TX_DP<2>")
	)
	(segment
		(start 357.088186 -226.341686)
		(end 357.08717 -226.341178)
		(width 0.1143)
		(layer "In11.Cu")
		(net "GMI_CPU1_G3_CPU0_G1_TX_DP<2>")
	)
	(segment
		(start 355.959156 -215.07196)
		(end 355.781356 -215.026494)
		(width 0.14224)
		(layer "In11.Cu")
		(net "GMI_CPU1_G3_CPU0_G1_TX_DP<2>")
	)
	(segment
		(start 357.04907 -231.869488)
		(end 357.085646 -231.848152)
		(width 0.1143)
		(layer "In11.Cu")
		(net "GMI_CPU1_G3_CPU0_G1_TX_DP<2>")
	)
	(segment
		(start 114.407696 -227.961952)
		(end 114.406934 -227.96246)
		(width 0.1143)
		(layer "In11.Cu")
		(net "GMI_CPU1_G3_CPU0_G1_TX_DP<2>")
	)
	(segment
		(start 117.64772 -211.349844)
		(end 116.15674 -213.89086)
		(width 0.14224)
		(layer "In11.Cu")
		(net "GMI_CPU1_G3_CPU0_G1_TX_DP<2>")
	)
	(segment
		(start 354.492306 -212.601302)
		(end 353.720654 -211.301076)
		(width 0.14224)
		(layer "In11.Cu")
		(net "GMI_CPU1_G3_CPU0_G1_TX_DP<2>")
	)
	(segment
		(start 115.813332 -214.475822)
		(end 115.601242 -214.837264)
		(width 0.14224)
		(layer "In11.Cu")
		(net "GMI_CPU1_G3_CPU0_G1_TX_DP<2>")
	)
	(segment
		(start 114.407696 -222.127064)
		(end 114.408712 -222.127572)
		(width 0.1143)
		(layer "In11.Cu")
		(net "GMI_CPU1_G3_CPU0_G1_TX_DP<2>")
	)
	(segment
		(start 357.04907 -222.14967)
		(end 357.08717 -222.127318)
		(width 0.1143)
		(layer "In11.Cu")
		(net "GMI_CPU1_G3_CPU0_G1_TX_DP<2>")
	)
	(segment
		(start 357.088186 -231.846628)
		(end 357.088948 -231.84612)
		(width 0.1143)
		(layer "In11.Cu")
		(net "GMI_CPU1_G3_CPU0_G1_TX_DP<2>")
	)
	(segment
		(start 357.139748 -227.99421)
		(end 357.119936 -227.979986)
		(width 0.1143)
		(layer "In11.Cu")
		(net "GMI_CPU1_G3_CPU0_G1_TX_DP<2>")
	)
	(segment
		(start 357.091742 -222.124778)
		(end 357.092504 -222.12427)
		(width 0.1143)
		(layer "In11.Cu")
		(net "GMI_CPU1_G3_CPU0_G1_TX_DP<2>")
	)
	(segment
		(start 114.408712 -222.127572)
		(end 114.446812 -222.149924)
		(width 0.1143)
		(layer "In11.Cu")
		(net "GMI_CPU1_G3_CPU0_G1_TX_DP<2>")
	)
	(segment
		(start 357.339392 -221.34703)
		(end 357.339392 -221.128844)
		(width 0.1143)
		(layer "In11.Cu")
		(net "GMI_CPU1_G3_CPU0_G1_TX_DP<2>")
	)
	(segment
		(start 357.088186 -222.12681)
		(end 357.088948 -222.126302)
		(width 0.1143)
		(layer "In11.Cu")
		(net "GMI_CPU1_G3_CPU0_G1_TX_DP<2>")
	)
	(segment
		(start 310.648096 -177.760884)
		(end 308.394862 -176.955196)
		(width 0.14224)
		(layer "In11.Cu")
		(net "GMI_CPU1_G3_CPU0_G1_TX_DP<2>")
	)
	(segment
		(start 357.293672 -221.083124)
		(end 357.293672 -221.071694)
		(width 0.1143)
		(layer "In11.Cu")
		(net "GMI_CPU1_G3_CPU0_G1_TX_DP<2>")
	)
	(segment
		(start 115.43538 -215.376252)
		(end 115.257834 -215.422226)
		(width 0.14224)
		(layer "In11.Cu")
		(net "GMI_CPU1_G3_CPU0_G1_TX_DP<2>")
	)
	(segment
		(start 357.085646 -231.848152)
		(end 357.08717 -231.847136)
		(width 0.1143)
		(layer "In11.Cu")
		(net "GMI_CPU1_G3_CPU0_G1_TX_DP<2>")
	)
	(segment
		(start 114.407696 -223.747076)
		(end 114.439192 -223.765364)
		(width 0.1143)
		(layer "In11.Cu")
		(net "GMI_CPU1_G3_CPU0_G1_TX_DP<2>")
	)
	(segment
		(start 357.119936 -228.58857)
		(end 357.139748 -228.574346)
		(width 0.1143)
		(layer "In11.Cu")
		(net "GMI_CPU1_G3_CPU0_G1_TX_DP<2>")
	)
	(segment
		(start 114.405918 -230.225854)
		(end 114.408712 -230.227378)
		(width 0.1143)
		(layer "In11.Cu")
		(net "GMI_CPU1_G3_CPU0_G1_TX_DP<2>")
	)
	(segment
		(start 357.088186 -225.366834)
		(end 357.088948 -225.366326)
		(width 0.1143)
		(layer "In11.Cu")
		(net "GMI_CPU1_G3_CPU0_G1_TX_DP<2>")
	)
	(segment
		(start 357.085646 -228.608382)
		(end 357.08717 -228.607366)
		(width 0.1143)
		(layer "In11.Cu")
		(net "GMI_CPU1_G3_CPU0_G1_TX_DP<2>")
	)
	(segment
		(start 115.601242 -214.837264)
		(end 115.64747 -215.014556)
		(width 0.14224)
		(layer "In11.Cu")
		(net "GMI_CPU1_G3_CPU0_G1_TX_DP<2>")
	)
	(segment
		(start 114.356134 -228.5746)
		(end 114.375946 -228.588824)
		(width 0.1143)
		(layer "In11.Cu")
		(net "GMI_CPU1_G3_CPU0_G1_TX_DP<2>")
	)
	(segment
		(start 114.401092 -222.123254)
		(end 114.401854 -222.123762)
		(width 0.1143)
		(layer "In11.Cu")
		(net "GMI_CPU1_G3_CPU0_G1_TX_DP<2>")
	)
	(segment
		(start 357.092504 -222.12427)
		(end 357.094028 -222.123508)
		(width 0.1143)
		(layer "In11.Cu")
		(net "GMI_CPU1_G3_CPU0_G1_TX_DP<2>")
	)
	(segment
		(start 355.6127 -214.488522)
		(end 355.398832 -214.12835)
		(width 0.14224)
		(layer "In11.Cu")
		(net "GMI_CPU1_G3_CPU0_G1_TX_DP<2>")
	)
	(segment
		(start 114.407696 -225.367088)
		(end 114.439192 -225.385376)
		(width 0.1143)
		(layer "In11.Cu")
		(net "GMI_CPU1_G3_CPU0_G1_TX_DP<2>")
	)
	(segment
		(start 357.08717 -226.341178)
		(end 357.085646 -226.340162)
		(width 0.1143)
		(layer "In11.Cu")
		(net "GMI_CPU1_G3_CPU0_G1_TX_DP<2>")
	)
	(segment
		(start 165.305994 -176.151286)
		(end 156.917136 -179.151026)
		(width 0.14224)
		(layer "In11.Cu")
		(net "GMI_CPU1_G3_CPU0_G1_TX_DP<2>")
	)
	(segment
		(start 357.088948 -223.10217)
		(end 357.088186 -223.101662)
		(width 0.1143)
		(layer "In11.Cu")
		(net "GMI_CPU1_G3_CPU0_G1_TX_DP<2>")
	)
	(segment
		(start 357.088948 -228.60635)
		(end 357.119936 -228.58857)
		(width 0.1143)
		(layer "In11.Cu")
		(net "GMI_CPU1_G3_CPU0_G1_TX_DP<2>")
	)
	(segment
		(start 357.119936 -226.359974)
		(end 357.088948 -226.342194)
		(width 0.1143)
		(layer "In11.Cu")
		(net "GMI_CPU1_G3_CPU0_G1_TX_DP<2>")
	)
	(segment
		(start 357.08717 -230.227124)
		(end 357.089964 -230.2256)
		(width 0.1143)
		(layer "In11.Cu")
		(net "GMI_CPU1_G3_CPU0_G1_TX_DP<2>")
	)
	(segment
		(start 114.410236 -227.960428)
		(end 114.408712 -227.961444)
		(width 0.1143)
		(layer "In11.Cu")
		(net "GMI_CPU1_G3_CPU0_G1_TX_DP<2>")
	)
	(segment
		(start 357.095806 -222.122492)
		(end 357.119936 -222.108522)
		(width 0.1143)
		(layer "In11.Cu")
		(net "GMI_CPU1_G3_CPU0_G1_TX_DP<2>")
	)
	(segment
		(start 354.660962 -213.139274)
		(end 354.44684 -212.778594)
		(width 0.14224)
		(layer "In11.Cu")
		(net "GMI_CPU1_G3_CPU0_G1_TX_DP<2>")
	)
	(segment
		(start 308.394862 -176.955196)
		(end 302.913288 -176.955196)
		(width 0.14224)
		(layer "In11.Cu")
		(net "GMI_CPU1_G3_CPU0_G1_TX_DP<2>")
	)
	(segment
		(start 114.375946 -227.98024)
		(end 114.356134 -227.994464)
		(width 0.1143)
		(layer "In11.Cu")
		(net "GMI_CPU1_G3_CPU0_G1_TX_DP<2>")
	)
	(segment
		(start 115.091972 -215.96096)
		(end 114.879882 -216.322656)
		(width 0.14224)
		(layer "In11.Cu")
		(net "GMI_CPU1_G3_CPU0_G1_TX_DP<2>")
	)
	(segment
		(start 114.408712 -223.101408)
		(end 114.407696 -223.101916)
		(width 0.1143)
		(layer "In11.Cu")
		(net "GMI_CPU1_G3_CPU0_G1_TX_DP<2>")
	)
	(segment
		(start 357.088948 -222.126302)
		(end 357.091742 -222.124778)
		(width 0.1143)
		(layer "In11.Cu")
		(net "GMI_CPU1_G3_CPU0_G1_TX_DP<2>")
	)
	(segment
		(start 114.356134 -223.714564)
		(end 114.375946 -223.728788)
		(width 0.1143)
		(layer "In11.Cu")
		(net "GMI_CPU1_G3_CPU0_G1_TX_DP<2>")
	)
	(segment
		(start 357.085646 -224.72015)
		(end 357.04907 -224.698814)
		(width 0.1143)
		(layer "In11.Cu")
		(net "GMI_CPU1_G3_CPU0_G1_TX_DP<2>")
	)
	(segment
		(start 357.085646 -226.98837)
		(end 357.08717 -226.987354)
		(width 0.1143)
		(layer "In11.Cu")
		(net "GMI_CPU1_G3_CPU0_G1_TX_DP<2>")
	)
	(segment
		(start 114.439192 -230.245158)
		(end 114.439954 -230.245666)
		(width 0.1143)
		(layer "In11.Cu")
		(net "GMI_CPU1_G3_CPU0_G1_TX_DP<2>")
	)
	(segment
		(start 357.139748 -223.134174)
		(end 357.119936 -223.11995)
		(width 0.1143)
		(layer "In11.Cu")
		(net "GMI_CPU1_G3_CPU0_G1_TX_DP<2>")
	)
	(segment
		(start 354.44684 -212.778594)
		(end 354.492306 -212.601302)
		(width 0.14224)
		(layer "In11.Cu")
		(net "GMI_CPU1_G3_CPU0_G1_TX_DP<2>")
	)
	(segment
		(start 114.406934 -224.722436)
		(end 114.375946 -224.740216)
		(width 0.1143)
		(layer "In11.Cu")
		(net "GMI_CPU1_G3_CPU0_G1_TX_DP<2>")
	)
	(segment
		(start 355.007164 -213.722458)
		(end 355.052376 -213.544912)
		(width 0.14224)
		(layer "In11.Cu")
		(net "GMI_CPU1_G3_CPU0_G1_TX_DP<2>")
	)
	(segment
		(start 114.446812 -224.699068)
		(end 114.410236 -224.720404)
		(width 0.1143)
		(layer "In11.Cu")
		(net "GMI_CPU1_G3_CPU0_G1_TX_DP<2>")
	)
	(segment
		(start 357.088948 -226.986338)
		(end 357.119936 -226.968558)
		(width 0.1143)
		(layer "In11.Cu")
		(net "GMI_CPU1_G3_CPU0_G1_TX_DP<2>")
	)
	(segment
		(start 114.407696 -226.9871)
		(end 114.439192 -227.005388)
		(width 0.1143)
		(layer "In11.Cu")
		(net "GMI_CPU1_G3_CPU0_G1_TX_DP<2>")
	)
	(segment
		(start 357.275892 -221.41053)
		(end 357.339392 -221.34703)
		(width 0.1143)
		(layer "In11.Cu")
		(net "GMI_CPU1_G3_CPU0_G1_TX_DP<2>")
	)
	(segment
		(start 115.257834 -215.422226)
		(end 115.045744 -215.783668)
		(width 0.14224)
		(layer "In11.Cu")
		(net "GMI_CPU1_G3_CPU0_G1_TX_DP<2>")
	)
	(segment
		(start 114.439954 -228.625908)
		(end 114.446812 -228.629972)
		(width 0.1143)
		(layer "In11.Cu")
		(net "GMI_CPU1_G3_CPU0_G1_TX_DP<2>")
	)
	(segment
		(start 114.446812 -231.179116)
		(end 114.407696 -231.201976)
		(width 0.1143)
		(layer "In11.Cu")
		(net "GMI_CPU1_G3_CPU0_G1_TX_DP<2>")
	)
	(segment
		(start 353.720654 -211.301076)
		(end 317.647828 -181.723284)
		(width 0.14224)
		(layer "In11.Cu")
		(net "GMI_CPU1_G3_CPU0_G1_TX_DP<2>")
	)
	(segment
		(start 357.088948 -223.746314)
		(end 357.119936 -223.728534)
		(width 0.1143)
		(layer "In11.Cu")
		(net "GMI_CPU1_G3_CPU0_G1_TX_DP<2>")
	)
	(segment
		(start 357.08717 -223.101154)
		(end 357.085646 -223.100138)
		(width 0.1143)
		(layer "In11.Cu")
		(net "GMI_CPU1_G3_CPU0_G1_TX_DP<2>")
	)
	(segment
		(start 357.085646 -223.100138)
		(end 357.04907 -223.078802)
		(width 0.1143)
		(layer "In11.Cu")
		(net "GMI_CPU1_G3_CPU0_G1_TX_DP<2>")
	)
	(segment
		(start 114.410236 -224.720404)
		(end 114.408712 -224.72142)
		(width 0.1143)
		(layer "In11.Cu")
		(net "GMI_CPU1_G3_CPU0_G1_TX_DP<2>")
	)
	(segment
		(start 357.04907 -228.629718)
		(end 357.085646 -228.608382)
		(width 0.1143)
		(layer "In11.Cu")
		(net "GMI_CPU1_G3_CPU0_G1_TX_DP<2>")
	)
	(segment
		(start 116.15674 -213.89086)
		(end 116.202968 -214.068152)
		(width 0.14224)
		(layer "In11.Cu")
		(net "GMI_CPU1_G3_CPU0_G1_TX_DP<2>")
	)
	(segment
		(start 357.088186 -223.101662)
		(end 357.08717 -223.101154)
		(width 0.1143)
		(layer "In11.Cu")
		(net "GMI_CPU1_G3_CPU0_G1_TX_DP<2>")
	)
	(segment
		(start 356.733348 -216.375742)
		(end 356.51948 -216.01557)
		(width 0.14224)
		(layer "In11.Cu")
		(net "GMI_CPU1_G3_CPU0_G1_TX_DP<2>")
	)
	(segment
		(start 357.04907 -225.389694)
		(end 357.085646 -225.368358)
		(width 0.1143)
		(layer "In11.Cu")
		(net "GMI_CPU1_G3_CPU0_G1_TX_DP<2>")
	)
	(segment
		(start 357.085646 -226.340162)
		(end 357.04907 -226.318826)
		(width 0.1143)
		(layer "In11.Cu")
		(net "GMI_CPU1_G3_CPU0_G1_TX_DP<2>")
	)
	(segment
		(start 114.20221 -221.083378)
		(end 114.15649 -221.129098)
		(width 0.1143)
		(layer "In11.Cu")
		(net "GMI_CPU1_G3_CPU0_G1_TX_DP<2>")
	)
	(segment
		(start 357.088948 -225.366326)
		(end 357.119936 -225.348546)
		(width 0.1143)
		(layer "In11.Cu")
		(net "GMI_CPU1_G3_CPU0_G1_TX_DP<2>")
	)
	(segment
		(start 114.407696 -224.721928)
		(end 114.406934 -224.722436)
		(width 0.1143)
		(layer "In11.Cu")
		(net "GMI_CPU1_G3_CPU0_G1_TX_DP<2>")
	)
	(segment
		(start 114.684048 -232.251504)
		(end 114.766852 -232.334308)
		(width 0.1143)
		(layer "In11.Cu")
		(net "GMI_CPU1_G3_CPU0_G1_TX_DP<2>")
	)
	(segment
		(start 114.407696 -226.34194)
		(end 114.406934 -226.342448)
		(width 0.1143)
		(layer "In11.Cu")
		(net "GMI_CPU1_G3_CPU0_G1_TX_DP<2>")
	)
	(segment
		(start 115.990878 -214.429848)
		(end 115.813332 -214.475822)
		(width 0.14224)
		(layer "In11.Cu")
		(net "GMI_CPU1_G3_CPU0_G1_TX_DP<2>")
	)
	(segment
		(start 114.407696 -231.846882)
		(end 114.439192 -231.86517)
		(width 0.1143)
		(layer "In11.Cu")
		(net "GMI_CPU1_G3_CPU0_G1_TX_DP<2>")
	)
	(segment
		(start 114.439192 -225.385376)
		(end 114.439954 -225.385884)
		(width 0.1143)
		(layer "In11.Cu")
		(net "GMI_CPU1_G3_CPU0_G1_TX_DP<2>")
	)
	(segment
		(start 116.202968 -214.068152)
		(end 115.990878 -214.429848)
		(width 0.14224)
		(layer "In11.Cu")
		(net "GMI_CPU1_G3_CPU0_G1_TX_DP<2>")
	)
	(segment
		(start 357.08717 -227.96119)
		(end 357.085646 -227.960174)
		(width 0.1143)
		(layer "In11.Cu")
		(net "GMI_CPU1_G3_CPU0_G1_TX_DP<2>")
	)
	(segment
		(start 357.08717 -228.607366)
		(end 357.088186 -228.606858)
		(width 0.1143)
		(layer "In11.Cu")
		(net "GMI_CPU1_G3_CPU0_G1_TX_DP<2>")
	)
	(segment
		(start 114.406934 -223.746568)
		(end 114.407696 -223.747076)
		(width 0.1143)
		(layer "In11.Cu")
		(net "GMI_CPU1_G3_CPU0_G1_TX_DP<2>")
	)
	(segment
		(start 114.439192 -228.6254)
		(end 114.439954 -228.625908)
		(width 0.1143)
		(layer "In11.Cu")
		(net "GMI_CPU1_G3_CPU0_G1_TX_DP<2>")
	)
	(segment
		(start 357.088186 -226.986846)
		(end 357.088948 -226.986338)
		(width 0.1143)
		(layer "In11.Cu")
		(net "GMI_CPU1_G3_CPU0_G1_TX_DP<2>")
	)
	(segment
		(start 357.094028 -222.123508)
		(end 357.09479 -222.123)
		(width 0.1143)
		(layer "In11.Cu")
		(net "GMI_CPU1_G3_CPU0_G1_TX_DP<2>")
	)
	(segment
		(start 114.439192 -231.86517)
		(end 114.439954 -231.865678)
		(width 0.1143)
		(layer "In11.Cu")
		(net "GMI_CPU1_G3_CPU0_G1_TX_DP<2>")
	)
	(segment
		(start 357.055928 -230.245412)
		(end 357.05669 -230.244904)
		(width 0.1143)
		(layer "In11.Cu")
		(net "GMI_CPU1_G3_CPU0_G1_TX_DP<2>")
	)
	(segment
		(start 357.121714 -229.601268)
		(end 357.04907 -229.55885)
		(width 0.1143)
		(layer "In11.Cu")
		(net "GMI_CPU1_G3_CPU0_G1_TX_DP<2>")
	)
	(segment
		(start 114.407696 -229.581964)
		(end 114.374168 -229.601522)
		(width 0.1143)
		(layer "In11.Cu")
		(net "GMI_CPU1_G3_CPU0_G1_TX_DP<2>")
	)
	(segment
		(start 114.439954 -225.385884)
		(end 114.446812 -225.389948)
		(width 0.1143)
		(layer "In11.Cu")
		(net "GMI_CPU1_G3_CPU0_G1_TX_DP<2>")
	)
	(segment
		(start 356.431088 -232.334054)
		(end 356.72903 -232.334054)
		(width 0.1143)
		(layer "In11.Cu")
		(net "GMI_CPU1_G3_CPU0_G1_TX_DP<2>")
	)
	(segment
		(start 357.088948 -226.342194)
		(end 357.088186 -226.341686)
		(width 0.1143)
		(layer "In11.Cu")
		(net "GMI_CPU1_G3_CPU0_G1_TX_DP<2>")
	)
	(segment
		(start 114.21999 -221.410784)
		(end 114.21999 -221.804484)
		(width 0.1143)
		(layer "In11.Cu")
		(net "GMI_CPU1_G3_CPU0_G1_TX_DP<2>")
	)
	(segment
		(start 114.766852 -232.334308)
		(end 115.064794 -232.334308)
		(width 0.1143)
		(layer "In11.Cu")
		(net "GMI_CPU1_G3_CPU0_G1_TX_DP<2>")
	)
	(segment
		(start 114.400076 -222.122746)
		(end 114.401092 -222.123254)
		(width 0.1143)
		(layer "In11.Cu")
		(net "GMI_CPU1_G3_CPU0_G1_TX_DP<2>")
	)
	(segment
		(start 356.173024 -215.432132)
		(end 355.959156 -215.07196)
		(width 0.14224)
		(layer "In11.Cu")
		(net "GMI_CPU1_G3_CPU0_G1_TX_DP<2>")
	)
	(segment
		(start 357.085646 -223.748346)
		(end 357.08717 -223.74733)
		(width 0.1143)
		(layer "In11.Cu")
		(net "GMI_CPU1_G3_CPU0_G1_TX_DP<2>")
	)
	(segment
		(start 355.221032 -214.082884)
		(end 355.007164 -213.722458)
		(width 0.14224)
		(layer "In11.Cu")
		(net "GMI_CPU1_G3_CPU0_G1_TX_DP<2>")
	)
	(segment
		(start 357.088186 -223.746822)
		(end 357.088948 -223.746314)
		(width 0.1143)
		(layer "In11.Cu")
		(net "GMI_CPU1_G3_CPU0_G1_TX_DP<2>")
	)
	(segment
		(start 357.275892 -221.80423)
		(end 357.275892 -221.41053)
		(width 0.1143)
		(layer "In11.Cu")
		(net "GMI_CPU1_G3_CPU0_G1_TX_DP<2>")
	)
	(arc
		(start 357.139748 -223.71431)
		(mid 357.288462 -223.424242)
		(end 357.139748 -223.134174)
		(width 0.1143)
		(layer "In11.Cu")
		(net "GMI_CPU1_G3_CPU0_G1_TX_DP<2>")
	)
	(arc
		(start 114.446812 -225.389948)
		(mid 114.690139 -225.854514)
		(end 114.446812 -226.31908)
		(width 0.1143)
		(layer "In11.Cu")
		(net "GMI_CPU1_G3_CPU0_G1_TX_DP<2>")
	)
	(arc
		(start 114.690144 -230.71455)
		(mid 114.625629 -230.976769)
		(end 114.446812 -231.179116)
		(width 0.1143)
		(layer "In11.Cu")
		(net "GMI_CPU1_G3_CPU0_G1_TX_DP<2>")
	)
	(arc
		(start 114.374168 -229.601522)
		(mid 114.260761 -229.734411)
		(end 114.21999 -229.90429)
		(width 0.1143)
		(layer "In11.Cu")
		(net "GMI_CPU1_G3_CPU0_G1_TX_DP<2>")
	)
	(arc
		(start 114.356134 -223.134428)
		(mid 114.20742 -223.424496)
		(end 114.356134 -223.714564)
		(width 0.1143)
		(layer "In11.Cu")
		(net "GMI_CPU1_G3_CPU0_G1_TX_DP<2>")
	)
	(arc
		(start 357.119936 -226.968558)
		(mid 357.269033 -226.664266)
		(end 357.119936 -226.359974)
		(width 0.1143)
		(layer "In11.Cu")
		(net "GMI_CPU1_G3_CPU0_G1_TX_DP<2>")
	)
	(arc
		(start 114.446812 -223.769936)
		(mid 114.690139 -224.234502)
		(end 114.446812 -224.699068)
		(width 0.1143)
		(layer "In11.Cu")
		(net "GMI_CPU1_G3_CPU0_G1_TX_DP<2>")
	)
	(arc
		(start 356.811834 -232.25125)
		(mid 356.813622 -232.239801)
		(end 356.815644 -232.22839)
		(width 0.1143)
		(layer "In11.Cu")
		(net "GMI_CPU1_G3_CPU0_G1_TX_DP<2>")
	)
	(arc
		(start 357.089456 -231.845866)
		(mid 357.225874 -231.709993)
		(end 357.275892 -231.524048)
		(width 0.1143)
		(layer "In11.Cu")
		(net "GMI_CPU1_G3_CPU0_G1_TX_DP<2>")
	)
	(arc
		(start 357.04907 -231.178862)
		(mid 356.870257 -230.976512)
		(end 356.805738 -230.714296)
		(width 0.1143)
		(layer "In11.Cu")
		(net "GMI_CPU1_G3_CPU0_G1_TX_DP<2>")
	)
	(arc
		(start 114.21999 -231.524302)
		(mid 114.269955 -231.710278)
		(end 114.406426 -231.84612)
		(width 0.1143)
		(layer "In11.Cu")
		(net "GMI_CPU1_G3_CPU0_G1_TX_DP<2>")
	)
	(arc
		(start 114.680238 -232.228644)
		(mid 114.682261 -232.240054)
		(end 114.684048 -232.251504)
		(width 0.1143)
		(layer "In11.Cu")
		(net "GMI_CPU1_G3_CPU0_G1_TX_DP<2>")
	)
	(arc
		(start 357.119936 -222.108522)
		(mid 357.234612 -221.975188)
		(end 357.275892 -221.80423)
		(width 0.1143)
		(layer "In11.Cu")
		(net "GMI_CPU1_G3_CPU0_G1_TX_DP<2>")
	)
	(arc
		(start 356.805738 -230.714296)
		(mid 356.870974 -230.450705)
		(end 357.05161 -230.247952)
		(width 0.1143)
		(layer "In11.Cu")
		(net "GMI_CPU1_G3_CPU0_G1_TX_DP<2>")
	)
	(arc
		(start 114.446812 -228.629972)
		(mid 114.690139 -229.094538)
		(end 114.446812 -229.559104)
		(width 0.1143)
		(layer "In11.Cu")
		(net "GMI_CPU1_G3_CPU0_G1_TX_DP<2>")
	)
	(arc
		(start 114.446812 -227.00996)
		(mid 114.690139 -227.474526)
		(end 114.446812 -227.939092)
		(width 0.1143)
		(layer "In11.Cu")
		(net "GMI_CPU1_G3_CPU0_G1_TX_DP<2>")
	)
	(arc
		(start 357.275892 -231.524048)
		(mid 357.23513 -231.354164)
		(end 357.121714 -231.22128)
		(width 0.1143)
		(layer "In11.Cu")
		(net "GMI_CPU1_G3_CPU0_G1_TX_DP<2>")
	)
	(arc
		(start 356.815644 -232.22839)
		(mid 356.897077 -232.025992)
		(end 357.04907 -231.869488)
		(width 0.1143)
		(layer "In11.Cu")
		(net "GMI_CPU1_G3_CPU0_G1_TX_DP<2>")
	)
	(arc
		(start 357.04907 -223.078802)
		(mid 356.805743 -222.614236)
		(end 357.04907 -222.14967)
		(width 0.1143)
		(layer "In11.Cu")
		(net "GMI_CPU1_G3_CPU0_G1_TX_DP<2>")
	)
	(arc
		(start 357.04907 -224.698814)
		(mid 356.805743 -224.234248)
		(end 357.04907 -223.769682)
		(width 0.1143)
		(layer "In11.Cu")
		(net "GMI_CPU1_G3_CPU0_G1_TX_DP<2>")
	)
	(arc
		(start 114.375946 -226.360228)
		(mid 114.226849 -226.66452)
		(end 114.375946 -226.968812)
		(width 0.1143)
		(layer "In11.Cu")
		(net "GMI_CPU1_G3_CPU0_G1_TX_DP<2>")
	)
	(arc
		(start 114.21999 -229.90429)
		(mid 114.269813 -230.09002)
		(end 114.405918 -230.225854)
		(width 0.1143)
		(layer "In11.Cu")
		(net "GMI_CPU1_G3_CPU0_G1_TX_DP<2>")
	)
	(arc
		(start 357.139748 -228.574346)
		(mid 357.288462 -228.284278)
		(end 357.139748 -227.99421)
		(width 0.1143)
		(layer "In11.Cu")
		(net "GMI_CPU1_G3_CPU0_G1_TX_DP<2>")
	)
	(arc
		(start 114.444272 -230.248206)
		(mid 114.624924 -230.450951)
		(end 114.690144 -230.71455)
		(width 0.1143)
		(layer "In11.Cu")
		(net "GMI_CPU1_G3_CPU0_G1_TX_DP<2>")
	)
	(arc
		(start 114.356134 -227.994464)
		(mid 114.20742 -228.284532)
		(end 114.356134 -228.5746)
		(width 0.1143)
		(layer "In11.Cu")
		(net "GMI_CPU1_G3_CPU0_G1_TX_DP<2>")
	)
	(arc
		(start 114.446812 -222.149924)
		(mid 114.690139 -222.61449)
		(end 114.446812 -223.079056)
		(width 0.1143)
		(layer "In11.Cu")
		(net "GMI_CPU1_G3_CPU0_G1_TX_DP<2>")
	)
	(arc
		(start 357.04907 -226.318826)
		(mid 356.805743 -225.85426)
		(end 357.04907 -225.389694)
		(width 0.1143)
		(layer "In11.Cu")
		(net "GMI_CPU1_G3_CPU0_G1_TX_DP<2>")
	)
	(arc
		(start 357.275892 -229.904036)
		(mid 357.23513 -229.734152)
		(end 357.121714 -229.601268)
		(width 0.1143)
		(layer "In11.Cu")
		(net "GMI_CPU1_G3_CPU0_G1_TX_DP<2>")
	)
	(arc
		(start 114.375946 -224.740216)
		(mid 114.226849 -225.044508)
		(end 114.375946 -225.3488)
		(width 0.1143)
		(layer "In11.Cu")
		(net "GMI_CPU1_G3_CPU0_G1_TX_DP<2>")
	)
	(arc
		(start 114.446812 -231.869742)
		(mid 114.598799 -232.02625)
		(end 114.680238 -232.228644)
		(width 0.1143)
		(layer "In11.Cu")
		(net "GMI_CPU1_G3_CPU0_G1_TX_DP<2>")
	)
	(arc
		(start 357.04907 -229.55885)
		(mid 356.805743 -229.094284)
		(end 357.04907 -228.629718)
		(width 0.1143)
		(layer "In11.Cu")
		(net "GMI_CPU1_G3_CPU0_G1_TX_DP<2>")
	)
	(arc
		(start 114.21999 -221.804484)
		(mid 114.261245 -221.975455)
		(end 114.375946 -222.108776)
		(width 0.1143)
		(layer "In11.Cu")
		(net "GMI_CPU1_G3_CPU0_G1_TX_DP<2>")
	)
	(arc
		(start 114.374168 -231.221534)
		(mid 114.260761 -231.354423)
		(end 114.21999 -231.524302)
		(width 0.1143)
		(layer "In11.Cu")
		(net "GMI_CPU1_G3_CPU0_G1_TX_DP<2>")
	)
	(arc
		(start 357.089964 -230.2256)
		(mid 357.226045 -230.089752)
		(end 357.275892 -229.904036)
		(width 0.1143)
		(layer "In11.Cu")
		(net "GMI_CPU1_G3_CPU0_G1_TX_DP<2>")
	)
	(arc
		(start 357.119936 -225.348546)
		(mid 357.269033 -225.044254)
		(end 357.119936 -224.739962)
		(width 0.1143)
		(layer "In11.Cu")
		(net "GMI_CPU1_G3_CPU0_G1_TX_DP<2>")
	)
	(arc
		(start 357.04907 -227.938838)
		(mid 356.805743 -227.474272)
		(end 357.04907 -227.009706)
		(width 0.1143)
		(layer "In11.Cu")
		(net "GMI_CPU1_G3_CPU0_G1_TX_DP<2>")
	)
	(segment
		(start 114.597942 -234.220258)
		(end 115.064794 -233.95432)
		(width 0.12954)
		(layer "F.Cu")
		(net "GMI_CPU1_G3_CPU0_G1_TX_DP<1>")
	)
	(segment
		(start 356.89794 -234.220004)
		(end 356.431088 -233.954066)
		(width 0.12954)
		(layer "F.Cu")
		(net "GMI_CPU1_G3_CPU0_G1_TX_DP<1>")
	)
	(segment
		(start 356.357682 -213.654894)
		(end 356.179882 -213.609428)
		(width 0.14224)
		(layer "In11.Cu")
		(net "GMI_CPU1_G3_CPU0_G1_TX_DP<1>")
	)
	(segment
		(start 358.05872 -227.979478)
		(end 357.989124 -227.938838)
		(width 0.1143)
		(layer "In11.Cu")
		(net "GMI_CPU1_G3_CPU0_G1_TX_DP<1>")
	)
	(segment
		(start 358.215946 -221.80423)
		(end 358.215946 -221.405704)
		(width 0.1143)
		(layer "In11.Cu")
		(net "GMI_CPU1_G3_CPU0_G1_TX_DP<1>")
	)
	(segment
		(start 113.467642 -223.747076)
		(end 113.506758 -223.769936)
		(width 0.1143)
		(layer "In11.Cu")
		(net "GMI_CPU1_G3_CPU0_G1_TX_DP<1>")
	)
	(segment
		(start 358.038654 -216.485724)
		(end 357.860854 -216.440512)
		(width 0.14224)
		(layer "In11.Cu")
		(net "GMI_CPU1_G3_CPU0_G1_TX_DP<1>")
	)
	(segment
		(start 113.457228 -222.121222)
		(end 113.459768 -222.122492)
		(width 0.1143)
		(layer "In11.Cu")
		(net "GMI_CPU1_G3_CPU0_G1_TX_DP<1>")
	)
	(segment
		(start 356.918006 -214.598504)
		(end 356.740206 -214.553038)
		(width 0.14224)
		(layer "In11.Cu")
		(net "GMI_CPU1_G3_CPU0_G1_TX_DP<1>")
	)
	(segment
		(start 355.40569 -212.305138)
		(end 355.451156 -212.127846)
		(width 0.14224)
		(layer "In11.Cu")
		(net "GMI_CPU1_G3_CPU0_G1_TX_DP<1>")
	)
	(segment
		(start 357.989124 -227.009706)
		(end 358.05872 -226.969066)
		(width 0.1143)
		(layer "In11.Cu")
		(net "GMI_CPU1_G3_CPU0_G1_TX_DP<1>")
	)
	(segment
		(start 357.085646 -233.468164)
		(end 357.08717 -233.467148)
		(width 0.1143)
		(layer "In11.Cu")
		(net "GMI_CPU1_G3_CPU0_G1_TX_DP<1>")
	)
	(segment
		(start 113.437162 -231.829102)
		(end 113.467642 -231.846882)
		(width 0.1143)
		(layer "In11.Cu")
		(net "GMI_CPU1_G3_CPU0_G1_TX_DP<1>")
	)
	(segment
		(start 113.46942 -216.338912)
		(end 113.46942 -216.339166)
		(width 0.14224)
		(layer "In11.Cu")
		(net "GMI_CPU1_G3_CPU0_G1_TX_DP<1>")
	)
	(segment
		(start 114.684048 -233.871516)
		(end 114.766852 -233.95432)
		(width 0.1143)
		(layer "In11.Cu")
		(net "GMI_CPU1_G3_CPU0_G1_TX_DP<1>")
	)
	(segment
		(start 113.459768 -222.122492)
		(end 113.461038 -222.123254)
		(width 0.1143)
		(layer "In11.Cu")
		(net "GMI_CPU1_G3_CPU0_G1_TX_DP<1>")
	)
	(segment
		(start 114.766852 -233.95432)
		(end 115.064794 -233.95432)
		(width 0.1143)
		(layer "In11.Cu")
		(net "GMI_CPU1_G3_CPU0_G1_TX_DP<1>")
	)
	(segment
		(start 355.966014 -213.249002)
		(end 356.011226 -213.071456)
		(width 0.14224)
		(layer "In11.Cu")
		(net "GMI_CPU1_G3_CPU0_G1_TX_DP<1>")
	)
	(segment
		(start 357.558086 -232.656634)
		(end 357.589836 -232.638346)
		(width 0.1143)
		(layer "In11.Cu")
		(net "GMI_CPU1_G3_CPU0_G1_TX_DP<1>")
	)
	(segment
		(start 114.92484 -213.86165)
		(end 114.971068 -214.038942)
		(width 0.14224)
		(layer "In11.Cu")
		(net "GMI_CPU1_G3_CPU0_G1_TX_DP<1>")
	)
	(segment
		(start 113.46688 -222.126556)
		(end 113.467642 -222.127064)
		(width 0.1143)
		(layer "In11.Cu")
		(net "GMI_CPU1_G3_CPU0_G1_TX_DP<1>")
	)
	(segment
		(start 356.431088 -233.954066)
		(end 356.72903 -233.954066)
		(width 0.1143)
		(layer "In11.Cu")
		(net "GMI_CPU1_G3_CPU0_G1_TX_DP<1>")
	)
	(segment
		(start 113.279936 -221.405958)
		(end 113.279936 -221.804484)
		(width 0.1143)
		(layer "In11.Cu")
		(net "GMI_CPU1_G3_CPU0_G1_TX_DP<1>")
	)
	(segment
		(start 302.916336 -176.022762)
		(end 165.050216 -175.216566)
		(width 0.14224)
		(layer "In11.Cu")
		(net "GMI_CPU1_G3_CPU0_G1_TX_DP<1>")
	)
	(segment
		(start 113.463324 -222.124524)
		(end 113.464086 -222.125032)
		(width 0.1143)
		(layer "In11.Cu")
		(net "GMI_CPU1_G3_CPU0_G1_TX_DP<1>")
	)
	(segment
		(start 358.2289 -221.071694)
		(end 358.2289 -216.806018)
		(width 0.14224)
		(layer "In11.Cu")
		(net "GMI_CPU1_G3_CPU0_G1_TX_DP<1>")
	)
	(segment
		(start 358.034844 -222.123)
		(end 358.05999 -222.108522)
		(width 0.1143)
		(layer "In11.Cu")
		(net "GMI_CPU1_G3_CPU0_G1_TX_DP<1>")
	)
	(segment
		(start 113.467642 -225.367088)
		(end 113.506758 -225.389948)
		(width 0.1143)
		(layer "In11.Cu")
		(net "GMI_CPU1_G3_CPU0_G1_TX_DP<1>")
	)
	(segment
		(start 113.464086 -222.125032)
		(end 113.46688 -222.126556)
		(width 0.1143)
		(layer "In11.Cu")
		(net "GMI_CPU1_G3_CPU0_G1_TX_DP<1>")
	)
	(segment
		(start 357.088948 -233.466132)
		(end 357.119936 -233.448352)
		(width 0.1143)
		(layer "In11.Cu")
		(net "GMI_CPU1_G3_CPU0_G1_TX_DP<1>")
	)
	(segment
		(start 114.406934 -233.466386)
		(end 114.407696 -233.466894)
		(width 0.1143)
		(layer "In11.Cu")
		(net "GMI_CPU1_G3_CPU0_G1_TX_DP<1>")
	)
	(segment
		(start 113.437162 -223.729296)
		(end 113.467642 -223.747076)
		(width 0.1143)
		(layer "In11.Cu")
		(net "GMI_CPU1_G3_CPU0_G1_TX_DP<1>")
	)
	(segment
		(start 357.989124 -228.629718)
		(end 358.05872 -228.589078)
		(width 0.1143)
		(layer "In11.Cu")
		(net "GMI_CPU1_G3_CPU0_G1_TX_DP<1>")
	)
	(segment
		(start 356.526338 -214.192612)
		(end 356.57155 -214.015066)
		(width 0.14224)
		(layer "In11.Cu")
		(net "GMI_CPU1_G3_CPU0_G1_TX_DP<1>")
	)
	(segment
		(start 358.2289 -216.806018)
		(end 358.038654 -216.485724)
		(width 0.14224)
		(layer "In11.Cu")
		(net "GMI_CPU1_G3_CPU0_G1_TX_DP<1>")
	)
	(segment
		(start 357.131874 -214.958676)
		(end 356.918006 -214.598504)
		(width 0.14224)
		(layer "In11.Cu")
		(net "GMI_CPU1_G3_CPU0_G1_TX_DP<1>")
	)
	(segment
		(start 113.937796 -232.656888)
		(end 113.974118 -232.67797)
		(width 0.1143)
		(layer "In11.Cu")
		(net "GMI_CPU1_G3_CPU0_G1_TX_DP<1>")
	)
	(segment
		(start 354.73513 -210.921346)
		(end 318.00673 -180.805582)
		(width 0.14224)
		(layer "In11.Cu")
		(net "GMI_CPU1_G3_CPU0_G1_TX_DP<1>")
	)
	(segment
		(start 113.4618 -222.123762)
		(end 113.463324 -222.124524)
		(width 0.1143)
		(layer "In11.Cu")
		(net "GMI_CPU1_G3_CPU0_G1_TX_DP<1>")
	)
	(segment
		(start 113.468658 -222.127572)
		(end 113.506758 -222.149924)
		(width 0.1143)
		(layer "In11.Cu")
		(net "GMI_CPU1_G3_CPU0_G1_TX_DP<1>")
	)
	(segment
		(start 113.467642 -231.201976)
		(end 113.43513 -231.220772)
		(width 0.1143)
		(layer "In11.Cu")
		(net "GMI_CPU1_G3_CPU0_G1_TX_DP<1>")
	)
	(segment
		(start 165.050216 -175.216566)
		(end 156.513276 -178.269138)
		(width 0.14224)
		(layer "In11.Cu")
		(net "GMI_CPU1_G3_CPU0_G1_TX_DP<1>")
	)
	(segment
		(start 113.46942 -216.339166)
		(end 113.266982 -216.68359)
		(width 0.14224)
		(layer "In11.Cu")
		(net "GMI_CPU1_G3_CPU0_G1_TX_DP<1>")
	)
	(segment
		(start 358.02824 -231.201722)
		(end 357.989124 -231.178862)
		(width 0.1143)
		(layer "In11.Cu")
		(net "GMI_CPU1_G3_CPU0_G1_TX_DP<1>")
	)
	(segment
		(start 357.088186 -233.46664)
		(end 357.088948 -233.466132)
		(width 0.1143)
		(layer "In11.Cu")
		(net "GMI_CPU1_G3_CPU0_G1_TX_DP<1>")
	)
	(segment
		(start 113.506758 -223.079056)
		(end 113.467642 -223.101916)
		(width 0.1143)
		(layer "In11.Cu")
		(net "GMI_CPU1_G3_CPU0_G1_TX_DP<1>")
	)
	(segment
		(start 357.04907 -233.4895)
		(end 357.085646 -233.468164)
		(width 0.1143)
		(layer "In11.Cu")
		(net "GMI_CPU1_G3_CPU0_G1_TX_DP<1>")
	)
	(segment
		(start 156.513276 -178.269138)
		(end 116.614956 -210.984338)
		(width 0.14224)
		(layer "In11.Cu")
		(net "GMI_CPU1_G3_CPU0_G1_TX_DP<1>")
	)
	(segment
		(start 113.467642 -229.581964)
		(end 113.43513 -229.60076)
		(width 0.1143)
		(layer "In11.Cu")
		(net "GMI_CPU1_G3_CPU0_G1_TX_DP<1>")
	)
	(segment
		(start 113.437162 -230.20909)
		(end 113.504218 -230.248206)
		(width 0.1143)
		(layer "In11.Cu")
		(net "GMI_CPU1_G3_CPU0_G1_TX_DP<1>")
	)
	(segment
		(start 357.692198 -215.902286)
		(end 357.47833 -215.542114)
		(width 0.14224)
		(layer "In11.Cu")
		(net "GMI_CPU1_G3_CPU0_G1_TX_DP<1>")
	)
	(segment
		(start 358.05872 -224.739454)
		(end 357.989124 -224.698814)
		(width 0.1143)
		(layer "In11.Cu")
		(net "GMI_CPU1_G3_CPU0_G1_TX_DP<1>")
	)
	(segment
		(start 358.032558 -222.12427)
		(end 358.034082 -222.123508)
		(width 0.1143)
		(layer "In11.Cu")
		(net "GMI_CPU1_G3_CPU0_G1_TX_DP<1>")
	)
	(segment
		(start 357.989124 -225.389694)
		(end 358.05872 -225.349054)
		(width 0.1143)
		(layer "In11.Cu")
		(net "GMI_CPU1_G3_CPU0_G1_TX_DP<1>")
	)
	(segment
		(start 113.266982 -216.68359)
		(end 113.266982 -221.071948)
		(width 0.14224)
		(layer "In11.Cu")
		(net "GMI_CPU1_G3_CPU0_G1_TX_DP<1>")
	)
	(segment
		(start 113.467642 -224.721928)
		(end 113.437162 -224.739708)
		(width 0.1143)
		(layer "In11.Cu")
		(net "GMI_CPU1_G3_CPU0_G1_TX_DP<1>")
	)
	(segment
		(start 114.971068 -214.038942)
		(end 114.758724 -214.400384)
		(width 0.14224)
		(layer "In11.Cu")
		(net "GMI_CPU1_G3_CPU0_G1_TX_DP<1>")
	)
	(segment
		(start 114.202972 -215.346534)
		(end 114.025426 -215.392762)
		(width 0.14224)
		(layer "In11.Cu")
		(net "GMI_CPU1_G3_CPU0_G1_TX_DP<1>")
	)
	(segment
		(start 113.506758 -224.699068)
		(end 113.467642 -224.721928)
		(width 0.1143)
		(layer "In11.Cu")
		(net "GMI_CPU1_G3_CPU0_G1_TX_DP<1>")
	)
	(segment
		(start 113.467642 -228.607112)
		(end 113.506758 -228.629972)
		(width 0.1143)
		(layer "In11.Cu")
		(net "GMI_CPU1_G3_CPU0_G1_TX_DP<1>")
	)
	(segment
		(start 357.989124 -222.14967)
		(end 358.027224 -222.127318)
		(width 0.1143)
		(layer "In11.Cu")
		(net "GMI_CPU1_G3_CPU0_G1_TX_DP<1>")
	)
	(segment
		(start 357.30053 -215.496902)
		(end 357.086662 -215.136222)
		(width 0.14224)
		(layer "In11.Cu")
		(net "GMI_CPU1_G3_CPU0_G1_TX_DP<1>")
	)
	(segment
		(start 358.2289 -221.083124)
		(end 358.2289 -221.071694)
		(width 0.1143)
		(layer "In11.Cu")
		(net "GMI_CPU1_G3_CPU0_G1_TX_DP<1>")
	)
	(segment
		(start 357.08717 -233.467148)
		(end 357.088186 -233.46664)
		(width 0.1143)
		(layer "In11.Cu")
		(net "GMI_CPU1_G3_CPU0_G1_TX_DP<1>")
	)
	(segment
		(start 357.521764 -232.677716)
		(end 357.558086 -232.656634)
		(width 0.1143)
		(layer "In11.Cu")
		(net "GMI_CPU1_G3_CPU0_G1_TX_DP<1>")
	)
	(segment
		(start 311.250584 -176.981104)
		(end 308.57063 -176.022762)
		(width 0.14224)
		(layer "In11.Cu")
		(net "GMI_CPU1_G3_CPU0_G1_TX_DP<1>")
	)
	(segment
		(start 114.415316 -214.985092)
		(end 114.202972 -215.346534)
		(width 0.14224)
		(layer "In11.Cu")
		(net "GMI_CPU1_G3_CPU0_G1_TX_DP<1>")
	)
	(segment
		(start 358.02824 -222.12681)
		(end 358.029002 -222.126302)
		(width 0.1143)
		(layer "In11.Cu")
		(net "GMI_CPU1_G3_CPU0_G1_TX_DP<1>")
	)
	(segment
		(start 113.266982 -221.083378)
		(end 113.221262 -221.129098)
		(width 0.1143)
		(layer "In11.Cu")
		(net "GMI_CPU1_G3_CPU0_G1_TX_DP<1>")
	)
	(segment
		(start 114.758724 -214.400384)
		(end 114.581178 -214.446612)
		(width 0.14224)
		(layer "In11.Cu")
		(net "GMI_CPU1_G3_CPU0_G1_TX_DP<1>")
	)
	(segment
		(start 358.02824 -229.58171)
		(end 357.989124 -229.55885)
		(width 0.1143)
		(layer "In11.Cu")
		(net "GMI_CPU1_G3_CPU0_G1_TX_DP<1>")
	)
	(segment
		(start 358.060752 -231.220518)
		(end 358.02824 -231.201722)
		(width 0.1143)
		(layer "In11.Cu")
		(net "GMI_CPU1_G3_CPU0_G1_TX_DP<1>")
	)
	(segment
		(start 113.506758 -227.939092)
		(end 113.467642 -227.961952)
		(width 0.1143)
		(layer "In11.Cu")
		(net "GMI_CPU1_G3_CPU0_G1_TX_DP<1>")
	)
	(segment
		(start 113.467642 -226.34194)
		(end 113.437162 -226.35972)
		(width 0.1143)
		(layer "In11.Cu")
		(net "GMI_CPU1_G3_CPU0_G1_TX_DP<1>")
	)
	(segment
		(start 358.27462 -221.128844)
		(end 358.2289 -221.083124)
		(width 0.1143)
		(layer "In11.Cu")
		(net "GMI_CPU1_G3_CPU0_G1_TX_DP<1>")
	)
	(segment
		(start 357.989124 -231.869488)
		(end 358.05872 -231.828848)
		(width 0.1143)
		(layer "In11.Cu")
		(net "GMI_CPU1_G3_CPU0_G1_TX_DP<1>")
	)
	(segment
		(start 357.989124 -223.769682)
		(end 358.05872 -223.729042)
		(width 0.1143)
		(layer "In11.Cu")
		(net "GMI_CPU1_G3_CPU0_G1_TX_DP<1>")
	)
	(segment
		(start 318.00673 -180.805582)
		(end 314.628784 -178.89347)
		(width 0.14224)
		(layer "In11.Cu")
		(net "GMI_CPU1_G3_CPU0_G1_TX_DP<1>")
	)
	(segment
		(start 114.407696 -233.466894)
		(end 114.446812 -233.489754)
		(width 0.1143)
		(layer "In11.Cu")
		(net "GMI_CPU1_G3_CPU0_G1_TX_DP<1>")
	)
	(segment
		(start 356.72903 -233.954066)
		(end 356.811834 -233.871262)
		(width 0.1143)
		(layer "In11.Cu")
		(net "GMI_CPU1_G3_CPU0_G1_TX_DP<1>")
	)
	(segment
		(start 358.060752 -229.600506)
		(end 358.02824 -229.58171)
		(width 0.1143)
		(layer "In11.Cu")
		(net "GMI_CPU1_G3_CPU0_G1_TX_DP<1>")
	)
	(segment
		(start 356.179882 -213.609428)
		(end 355.966014 -213.249002)
		(width 0.14224)
		(layer "In11.Cu")
		(net "GMI_CPU1_G3_CPU0_G1_TX_DP<1>")
	)
	(segment
		(start 114.369088 -214.8078)
		(end 114.415316 -214.985092)
		(width 0.14224)
		(layer "In11.Cu")
		(net "GMI_CPU1_G3_CPU0_G1_TX_DP<1>")
	)
	(segment
		(start 113.506758 -229.559104)
		(end 113.467642 -229.581964)
		(width 0.1143)
		(layer "In11.Cu")
		(net "GMI_CPU1_G3_CPU0_G1_TX_DP<1>")
	)
	(segment
		(start 358.029002 -222.126302)
		(end 358.031796 -222.124778)
		(width 0.1143)
		(layer "In11.Cu")
		(net "GMI_CPU1_G3_CPU0_G1_TX_DP<1>")
	)
	(segment
		(start 113.506758 -231.179116)
		(end 113.467642 -231.201976)
		(width 0.1143)
		(layer "In11.Cu")
		(net "GMI_CPU1_G3_CPU0_G1_TX_DP<1>")
	)
	(segment
		(start 357.860854 -216.440512)
		(end 357.646986 -216.079832)
		(width 0.14224)
		(layer "In11.Cu")
		(net "GMI_CPU1_G3_CPU0_G1_TX_DP<1>")
	)
	(segment
		(start 355.797358 -212.711284)
		(end 355.619812 -212.665818)
		(width 0.14224)
		(layer "In11.Cu")
		(net "GMI_CPU1_G3_CPU0_G1_TX_DP<1>")
	)
	(segment
		(start 113.467642 -222.127064)
		(end 113.468658 -222.127572)
		(width 0.1143)
		(layer "In11.Cu")
		(net "GMI_CPU1_G3_CPU0_G1_TX_DP<1>")
	)
	(segment
		(start 113.506758 -226.31908)
		(end 113.467642 -226.34194)
		(width 0.1143)
		(layer "In11.Cu")
		(net "GMI_CPU1_G3_CPU0_G1_TX_DP<1>")
	)
	(segment
		(start 113.467642 -223.101916)
		(end 113.437162 -223.119696)
		(width 0.1143)
		(layer "In11.Cu")
		(net "GMI_CPU1_G3_CPU0_G1_TX_DP<1>")
	)
	(segment
		(start 357.991664 -230.247952)
		(end 358.05872 -230.208836)
		(width 0.1143)
		(layer "In11.Cu")
		(net "GMI_CPU1_G3_CPU0_G1_TX_DP<1>")
	)
	(segment
		(start 113.813336 -215.75395)
		(end 113.85931 -215.931242)
		(width 0.14224)
		(layer "In11.Cu")
		(net "GMI_CPU1_G3_CPU0_G1_TX_DP<1>")
	)
	(segment
		(start 113.467642 -226.9871)
		(end 113.506758 -227.00996)
		(width 0.1143)
		(layer "In11.Cu")
		(net "GMI_CPU1_G3_CPU0_G1_TX_DP<1>")
	)
	(segment
		(start 357.47833 -215.542114)
		(end 357.30053 -215.496902)
		(width 0.14224)
		(layer "In11.Cu")
		(net "GMI_CPU1_G3_CPU0_G1_TX_DP<1>")
	)
	(segment
		(start 113.437162 -226.96932)
		(end 113.467642 -226.9871)
		(width 0.1143)
		(layer "In11.Cu")
		(net "GMI_CPU1_G3_CPU0_G1_TX_DP<1>")
	)
	(segment
		(start 355.619812 -212.665818)
		(end 355.40569 -212.305138)
		(width 0.14224)
		(layer "In11.Cu")
		(net "GMI_CPU1_G3_CPU0_G1_TX_DP<1>")
	)
	(segment
		(start 113.437162 -228.589332)
		(end 113.467642 -228.607112)
		(width 0.1143)
		(layer "In11.Cu")
		(net "GMI_CPU1_G3_CPU0_G1_TX_DP<1>")
	)
	(segment
		(start 355.451156 -212.127846)
		(end 354.73513 -210.921346)
		(width 0.14224)
		(layer "In11.Cu")
		(net "GMI_CPU1_G3_CPU0_G1_TX_DP<1>")
	)
	(segment
		(start 113.435892 -222.108776)
		(end 113.457228 -222.121222)
		(width 0.1143)
		(layer "In11.Cu")
		(net "GMI_CPU1_G3_CPU0_G1_TX_DP<1>")
	)
	(segment
		(start 113.266982 -221.071948)
		(end 113.266982 -221.083378)
		(width 0.1143)
		(layer "In11.Cu")
		(net "GMI_CPU1_G3_CPU0_G1_TX_DP<1>")
	)
	(segment
		(start 113.437162 -225.349308)
		(end 113.467642 -225.367088)
		(width 0.1143)
		(layer "In11.Cu")
		(net "GMI_CPU1_G3_CPU0_G1_TX_DP<1>")
	)
	(segment
		(start 113.467642 -227.961952)
		(end 113.437162 -227.979732)
		(width 0.1143)
		(layer "In11.Cu")
		(net "GMI_CPU1_G3_CPU0_G1_TX_DP<1>")
	)
	(segment
		(start 308.57063 -176.022762)
		(end 302.916336 -176.022762)
		(width 0.14224)
		(layer "In11.Cu")
		(net "GMI_CPU1_G3_CPU0_G1_TX_DP<1>")
	)
	(segment
		(start 114.375946 -233.448606)
		(end 114.406934 -233.466386)
		(width 0.1143)
		(layer "In11.Cu")
		(net "GMI_CPU1_G3_CPU0_G1_TX_DP<1>")
	)
	(segment
		(start 113.85931 -215.931242)
		(end 113.646966 -216.292684)
		(width 0.14224)
		(layer "In11.Cu")
		(net "GMI_CPU1_G3_CPU0_G1_TX_DP<1>")
	)
	(segment
		(start 314.628784 -178.89347)
		(end 311.250584 -176.981104)
		(width 0.14224)
		(layer "In11.Cu")
		(net "GMI_CPU1_G3_CPU0_G1_TX_DP<1>")
	)
	(segment
		(start 114.025426 -215.392762)
		(end 113.813336 -215.75395)
		(width 0.14224)
		(layer "In11.Cu")
		(net "GMI_CPU1_G3_CPU0_G1_TX_DP<1>")
	)
	(segment
		(start 113.467642 -231.846882)
		(end 113.506758 -231.869742)
		(width 0.1143)
		(layer "In11.Cu")
		(net "GMI_CPU1_G3_CPU0_G1_TX_DP<1>")
	)
	(segment
		(start 113.646966 -216.292684)
		(end 113.46942 -216.338912)
		(width 0.14224)
		(layer "In11.Cu")
		(net "GMI_CPU1_G3_CPU0_G1_TX_DP<1>")
	)
	(segment
		(start 358.27462 -221.34703)
		(end 358.27462 -221.128844)
		(width 0.1143)
		(layer "In11.Cu")
		(net "GMI_CPU1_G3_CPU0_G1_TX_DP<1>")
	)
	(segment
		(start 113.906046 -232.6386)
		(end 113.937796 -232.656888)
		(width 0.1143)
		(layer "In11.Cu")
		(net "GMI_CPU1_G3_CPU0_G1_TX_DP<1>")
	)
	(segment
		(start 358.215946 -221.405704)
		(end 358.27462 -221.34703)
		(width 0.1143)
		(layer "In11.Cu")
		(net "GMI_CPU1_G3_CPU0_G1_TX_DP<1>")
	)
	(segment
		(start 113.221262 -221.347284)
		(end 113.279936 -221.405958)
		(width 0.1143)
		(layer "In11.Cu")
		(net "GMI_CPU1_G3_CPU0_G1_TX_DP<1>")
	)
	(segment
		(start 358.027224 -222.127318)
		(end 358.02824 -222.12681)
		(width 0.1143)
		(layer "In11.Cu")
		(net "GMI_CPU1_G3_CPU0_G1_TX_DP<1>")
	)
	(segment
		(start 357.646986 -216.079832)
		(end 357.692198 -215.902286)
		(width 0.14224)
		(layer "In11.Cu")
		(net "GMI_CPU1_G3_CPU0_G1_TX_DP<1>")
	)
	(segment
		(start 356.011226 -213.071456)
		(end 355.797358 -212.711284)
		(width 0.14224)
		(layer "In11.Cu")
		(net "GMI_CPU1_G3_CPU0_G1_TX_DP<1>")
	)
	(segment
		(start 116.614956 -210.984338)
		(end 114.92484 -213.86165)
		(width 0.14224)
		(layer "In11.Cu")
		(net "GMI_CPU1_G3_CPU0_G1_TX_DP<1>")
	)
	(segment
		(start 356.740206 -214.553038)
		(end 356.526338 -214.192612)
		(width 0.14224)
		(layer "In11.Cu")
		(net "GMI_CPU1_G3_CPU0_G1_TX_DP<1>")
	)
	(segment
		(start 114.581178 -214.446612)
		(end 114.369088 -214.8078)
		(width 0.14224)
		(layer "In11.Cu")
		(net "GMI_CPU1_G3_CPU0_G1_TX_DP<1>")
	)
	(segment
		(start 357.086662 -215.136222)
		(end 357.131874 -214.958676)
		(width 0.14224)
		(layer "In11.Cu")
		(net "GMI_CPU1_G3_CPU0_G1_TX_DP<1>")
	)
	(segment
		(start 358.05872 -226.359466)
		(end 357.989124 -226.318826)
		(width 0.1143)
		(layer "In11.Cu")
		(net "GMI_CPU1_G3_CPU0_G1_TX_DP<1>")
	)
	(segment
		(start 358.034082 -222.123508)
		(end 358.034844 -222.123)
		(width 0.1143)
		(layer "In11.Cu")
		(net "GMI_CPU1_G3_CPU0_G1_TX_DP<1>")
	)
	(segment
		(start 358.05872 -223.119442)
		(end 357.989124 -223.078802)
		(width 0.1143)
		(layer "In11.Cu")
		(net "GMI_CPU1_G3_CPU0_G1_TX_DP<1>")
	)
	(segment
		(start 358.031796 -222.124778)
		(end 358.032558 -222.12427)
		(width 0.1143)
		(layer "In11.Cu")
		(net "GMI_CPU1_G3_CPU0_G1_TX_DP<1>")
	)
	(segment
		(start 113.221262 -221.129098)
		(end 113.221262 -221.347284)
		(width 0.1143)
		(layer "In11.Cu")
		(net "GMI_CPU1_G3_CPU0_G1_TX_DP<1>")
	)
	(segment
		(start 113.461038 -222.123254)
		(end 113.4618 -222.123762)
		(width 0.1143)
		(layer "In11.Cu")
		(net "GMI_CPU1_G3_CPU0_G1_TX_DP<1>")
	)
	(segment
		(start 356.57155 -214.015066)
		(end 356.357682 -213.654894)
		(width 0.14224)
		(layer "In11.Cu")
		(net "GMI_CPU1_G3_CPU0_G1_TX_DP<1>")
	)
	(arc
		(start 357.119936 -233.448352)
		(mid 357.231733 -233.313551)
		(end 357.275892 -233.14406)
		(width 0.1143)
		(layer "In11.Cu")
		(net "GMI_CPU1_G3_CPU0_G1_TX_DP<1>")
	)
	(arc
		(start 357.589836 -232.638346)
		(mid 357.704512 -232.505012)
		(end 357.745792 -232.334054)
		(width 0.1143)
		(layer "In11.Cu")
		(net "GMI_CPU1_G3_CPU0_G1_TX_DP<1>")
	)
	(arc
		(start 113.506758 -222.149924)
		(mid 113.750085 -222.61449)
		(end 113.506758 -223.079056)
		(width 0.1143)
		(layer "In11.Cu")
		(net "GMI_CPU1_G3_CPU0_G1_TX_DP<1>")
	)
	(arc
		(start 113.75009 -232.334308)
		(mid 113.791345 -232.505279)
		(end 113.906046 -232.6386)
		(width 0.1143)
		(layer "In11.Cu")
		(net "GMI_CPU1_G3_CPU0_G1_TX_DP<1>")
	)
	(arc
		(start 113.437162 -224.739708)
		(mid 113.280185 -225.044508)
		(end 113.437162 -225.349308)
		(width 0.1143)
		(layer "In11.Cu")
		(net "GMI_CPU1_G3_CPU0_G1_TX_DP<1>")
	)
	(arc
		(start 358.05872 -223.729042)
		(mid 358.215697 -223.424242)
		(end 358.05872 -223.119442)
		(width 0.1143)
		(layer "In11.Cu")
		(net "GMI_CPU1_G3_CPU0_G1_TX_DP<1>")
	)
	(arc
		(start 113.506758 -228.629972)
		(mid 113.750085 -229.094538)
		(end 113.506758 -229.559104)
		(width 0.1143)
		(layer "In11.Cu")
		(net "GMI_CPU1_G3_CPU0_G1_TX_DP<1>")
	)
	(arc
		(start 357.989124 -223.078802)
		(mid 357.745797 -222.614236)
		(end 357.989124 -222.14967)
		(width 0.1143)
		(layer "In11.Cu")
		(net "GMI_CPU1_G3_CPU0_G1_TX_DP<1>")
	)
	(arc
		(start 357.745792 -232.334054)
		(mid 357.810307 -232.071835)
		(end 357.989124 -231.869488)
		(width 0.1143)
		(layer "In11.Cu")
		(net "GMI_CPU1_G3_CPU0_G1_TX_DP<1>")
	)
	(arc
		(start 113.28019 -231.524302)
		(mid 113.321739 -231.695724)
		(end 113.437162 -231.829102)
		(width 0.1143)
		(layer "In11.Cu")
		(net "GMI_CPU1_G3_CPU0_G1_TX_DP<1>")
	)
	(arc
		(start 114.446812 -233.489754)
		(mid 114.605017 -233.656041)
		(end 114.684048 -233.871516)
		(width 0.1143)
		(layer "In11.Cu")
		(net "GMI_CPU1_G3_CPU0_G1_TX_DP<1>")
	)
	(arc
		(start 358.05872 -230.208836)
		(mid 358.174147 -230.07546)
		(end 358.215692 -229.904036)
		(width 0.1143)
		(layer "In11.Cu")
		(net "GMI_CPU1_G3_CPU0_G1_TX_DP<1>")
	)
	(arc
		(start 113.506758 -231.869742)
		(mid 113.685571 -232.072092)
		(end 113.75009 -232.334308)
		(width 0.1143)
		(layer "In11.Cu")
		(net "GMI_CPU1_G3_CPU0_G1_TX_DP<1>")
	)
	(arc
		(start 357.989124 -226.318826)
		(mid 357.745797 -225.85426)
		(end 357.989124 -225.389694)
		(width 0.1143)
		(layer "In11.Cu")
		(net "GMI_CPU1_G3_CPU0_G1_TX_DP<1>")
	)
	(arc
		(start 357.989124 -224.698814)
		(mid 357.745797 -224.234248)
		(end 357.989124 -223.769682)
		(width 0.1143)
		(layer "In11.Cu")
		(net "GMI_CPU1_G3_CPU0_G1_TX_DP<1>")
	)
	(arc
		(start 358.05872 -226.969066)
		(mid 358.215697 -226.664266)
		(end 358.05872 -226.359466)
		(width 0.1143)
		(layer "In11.Cu")
		(net "GMI_CPU1_G3_CPU0_G1_TX_DP<1>")
	)
	(arc
		(start 113.989358 -232.688638)
		(mid 114.155603 -232.887738)
		(end 114.21999 -233.13898)
		(width 0.1143)
		(layer "In11.Cu")
		(net "GMI_CPU1_G3_CPU0_G1_TX_DP<1>")
	)
	(arc
		(start 358.05872 -225.349054)
		(mid 358.215697 -225.044254)
		(end 358.05872 -224.739454)
		(width 0.1143)
		(layer "In11.Cu")
		(net "GMI_CPU1_G3_CPU0_G1_TX_DP<1>")
	)
	(arc
		(start 357.275892 -233.138726)
		(mid 357.340354 -232.887522)
		(end 357.506524 -232.688384)
		(width 0.1143)
		(layer "In11.Cu")
		(net "GMI_CPU1_G3_CPU0_G1_TX_DP<1>")
	)
	(arc
		(start 113.506758 -227.00996)
		(mid 113.750085 -227.474526)
		(end 113.506758 -227.939092)
		(width 0.1143)
		(layer "In11.Cu")
		(net "GMI_CPU1_G3_CPU0_G1_TX_DP<1>")
	)
	(arc
		(start 356.815644 -233.848402)
		(mid 356.897077 -233.646004)
		(end 357.04907 -233.4895)
		(width 0.1143)
		(layer "In11.Cu")
		(net "GMI_CPU1_G3_CPU0_G1_TX_DP<1>")
	)
	(arc
		(start 357.275892 -233.14406)
		(mid 357.275886 -233.141393)
		(end 357.275892 -233.138726)
		(width 0.1143)
		(layer "In11.Cu")
		(net "GMI_CPU1_G3_CPU0_G1_TX_DP<1>")
	)
	(arc
		(start 357.989124 -231.178862)
		(mid 357.810311 -230.976512)
		(end 357.745792 -230.714296)
		(width 0.1143)
		(layer "In11.Cu")
		(net "GMI_CPU1_G3_CPU0_G1_TX_DP<1>")
	)
	(arc
		(start 357.506524 -232.688384)
		(mid 357.5141 -232.682988)
		(end 357.521764 -232.677716)
		(width 0.1143)
		(layer "In11.Cu")
		(net "GMI_CPU1_G3_CPU0_G1_TX_DP<1>")
	)
	(arc
		(start 113.506758 -225.389948)
		(mid 113.750085 -225.854514)
		(end 113.506758 -226.31908)
		(width 0.1143)
		(layer "In11.Cu")
		(net "GMI_CPU1_G3_CPU0_G1_TX_DP<1>")
	)
	(arc
		(start 357.745792 -230.714296)
		(mid 357.811028 -230.450705)
		(end 357.991664 -230.247952)
		(width 0.1143)
		(layer "In11.Cu")
		(net "GMI_CPU1_G3_CPU0_G1_TX_DP<1>")
	)
	(arc
		(start 113.437162 -226.35972)
		(mid 113.280185 -226.66452)
		(end 113.437162 -226.96932)
		(width 0.1143)
		(layer "In11.Cu")
		(net "GMI_CPU1_G3_CPU0_G1_TX_DP<1>")
	)
	(arc
		(start 113.437162 -227.979732)
		(mid 113.280185 -228.284532)
		(end 113.437162 -228.589332)
		(width 0.1143)
		(layer "In11.Cu")
		(net "GMI_CPU1_G3_CPU0_G1_TX_DP<1>")
	)
	(arc
		(start 113.974118 -232.67797)
		(mid 113.981782 -232.683241)
		(end 113.989358 -232.688638)
		(width 0.1143)
		(layer "In11.Cu")
		(net "GMI_CPU1_G3_CPU0_G1_TX_DP<1>")
	)
	(arc
		(start 358.215692 -231.524048)
		(mid 358.174726 -231.353642)
		(end 358.060752 -231.220518)
		(width 0.1143)
		(layer "In11.Cu")
		(net "GMI_CPU1_G3_CPU0_G1_TX_DP<1>")
	)
	(arc
		(start 113.506758 -223.769936)
		(mid 113.750085 -224.234502)
		(end 113.506758 -224.699068)
		(width 0.1143)
		(layer "In11.Cu")
		(net "GMI_CPU1_G3_CPU0_G1_TX_DP<1>")
	)
	(arc
		(start 113.437162 -223.119696)
		(mid 113.280185 -223.424496)
		(end 113.437162 -223.729296)
		(width 0.1143)
		(layer "In11.Cu")
		(net "GMI_CPU1_G3_CPU0_G1_TX_DP<1>")
	)
	(arc
		(start 113.43513 -229.60076)
		(mid 113.321201 -229.733907)
		(end 113.28019 -229.90429)
		(width 0.1143)
		(layer "In11.Cu")
		(net "GMI_CPU1_G3_CPU0_G1_TX_DP<1>")
	)
	(arc
		(start 113.75009 -230.71455)
		(mid 113.685575 -230.976769)
		(end 113.506758 -231.179116)
		(width 0.1143)
		(layer "In11.Cu")
		(net "GMI_CPU1_G3_CPU0_G1_TX_DP<1>")
	)
	(arc
		(start 113.43513 -231.220772)
		(mid 113.321201 -231.353919)
		(end 113.28019 -231.524302)
		(width 0.1143)
		(layer "In11.Cu")
		(net "GMI_CPU1_G3_CPU0_G1_TX_DP<1>")
	)
	(arc
		(start 113.504218 -230.248206)
		(mid 113.68487 -230.450951)
		(end 113.75009 -230.71455)
		(width 0.1143)
		(layer "In11.Cu")
		(net "GMI_CPU1_G3_CPU0_G1_TX_DP<1>")
	)
	(arc
		(start 114.21999 -233.13898)
		(mid 114.219997 -233.141647)
		(end 114.21999 -233.144314)
		(width 0.1143)
		(layer "In11.Cu")
		(net "GMI_CPU1_G3_CPU0_G1_TX_DP<1>")
	)
	(arc
		(start 358.05999 -222.108522)
		(mid 358.174666 -221.975188)
		(end 358.215946 -221.80423)
		(width 0.1143)
		(layer "In11.Cu")
		(net "GMI_CPU1_G3_CPU0_G1_TX_DP<1>")
	)
	(arc
		(start 358.05872 -231.828848)
		(mid 358.174147 -231.695472)
		(end 358.215692 -231.524048)
		(width 0.1143)
		(layer "In11.Cu")
		(net "GMI_CPU1_G3_CPU0_G1_TX_DP<1>")
	)
	(arc
		(start 356.811834 -233.871262)
		(mid 356.813622 -233.859813)
		(end 356.815644 -233.848402)
		(width 0.1143)
		(layer "In11.Cu")
		(net "GMI_CPU1_G3_CPU0_G1_TX_DP<1>")
	)
	(arc
		(start 357.989124 -229.55885)
		(mid 357.745797 -229.094284)
		(end 357.989124 -228.629718)
		(width 0.1143)
		(layer "In11.Cu")
		(net "GMI_CPU1_G3_CPU0_G1_TX_DP<1>")
	)
	(arc
		(start 357.989124 -227.938838)
		(mid 357.745797 -227.474272)
		(end 357.989124 -227.009706)
		(width 0.1143)
		(layer "In11.Cu")
		(net "GMI_CPU1_G3_CPU0_G1_TX_DP<1>")
	)
	(arc
		(start 114.21999 -233.144314)
		(mid 114.264061 -233.31385)
		(end 114.375946 -233.448606)
		(width 0.1143)
		(layer "In11.Cu")
		(net "GMI_CPU1_G3_CPU0_G1_TX_DP<1>")
	)
	(arc
		(start 358.05872 -228.589078)
		(mid 358.215697 -228.284278)
		(end 358.05872 -227.979478)
		(width 0.1143)
		(layer "In11.Cu")
		(net "GMI_CPU1_G3_CPU0_G1_TX_DP<1>")
	)
	(arc
		(start 113.279936 -221.804484)
		(mid 113.321191 -221.975455)
		(end 113.435892 -222.108776)
		(width 0.1143)
		(layer "In11.Cu")
		(net "GMI_CPU1_G3_CPU0_G1_TX_DP<1>")
	)
	(arc
		(start 113.28019 -229.90429)
		(mid 113.321739 -230.075712)
		(end 113.437162 -230.20909)
		(width 0.1143)
		(layer "In11.Cu")
		(net "GMI_CPU1_G3_CPU0_G1_TX_DP<1>")
	)
	(arc
		(start 358.215692 -229.904036)
		(mid 358.174726 -229.73363)
		(end 358.060752 -229.600506)
		(width 0.1143)
		(layer "In11.Cu")
		(net "GMI_CPU1_G3_CPU0_G1_TX_DP<1>")
	)
	(segment
		(start 346.087954 -235.03001)
		(end 345.621102 -234.764072)
		(width 0.12954)
		(layer "F.Cu")
		(net "GMI_CPU1_G3_CPU0_G1_TX_DP<15>")
	)
	(segment
		(start 125.407928 -235.030264)
		(end 125.87478 -234.764326)
		(width 0.12954)
		(layer "F.Cu")
		(net "GMI_CPU1_G3_CPU0_G1_TX_DP<15>")
	)
	(segment
		(start 125.87478 -234.764326)
		(end 125.576838 -234.764326)
		(width 0.1143)
		(layer "In11.Cu")
		(net "GMI_CPU1_G3_CPU0_G1_TX_DP<15>")
	)
	(segment
		(start 344.82913 -226.318826)
		(end 344.898726 -226.359466)
		(width 0.1143)
		(layer "In11.Cu")
		(net "GMI_CPU1_G3_CPU0_G1_TX_DP<15>")
	)
	(segment
		(start 344.43162 -231.017064)
		(end 344.398092 -231.036622)
		(width 0.1143)
		(layer "In11.Cu")
		(net "GMI_CPU1_G3_CPU0_G1_TX_DP<15>")
	)
	(segment
		(start 161.59734 -193.224404)
		(end 161.61639 -193.031364)
		(width 0.14224)
		(layer "In11.Cu")
		(net "GMI_CPU1_G3_CPU0_G1_TX_DP<15>")
	)
	(segment
		(start 344.830654 -232.799636)
		(end 344.898726 -232.83926)
		(width 0.1143)
		(layer "In11.Cu")
		(net "GMI_CPU1_G3_CPU0_G1_TX_DP<15>")
	)
	(segment
		(start 156.03347 -197.786752)
		(end 156.36367 -197.515988)
		(width 0.14224)
		(layer "In11.Cu")
		(net "GMI_CPU1_G3_CPU0_G1_TX_DP<15>")
	)
	(segment
		(start 345.338146 -233.631486)
		(end 345.338908 -233.631994)
		(width 0.1143)
		(layer "In11.Cu")
		(net "GMI_CPU1_G3_CPU0_G1_TX_DP<15>")
	)
	(segment
		(start 126.627636 -229.581964)
		(end 126.666752 -229.559104)
		(width 0.1143)
		(layer "In11.Cu")
		(net "GMI_CPU1_G3_CPU0_G1_TX_DP<15>")
	)
	(segment
		(start 344.398346 -231.036876)
		(end 344.356436 -231.06126)
		(width 0.1143)
		(layer "In11.Cu")
		(net "GMI_CPU1_G3_CPU0_G1_TX_DP<15>")
	)
	(segment
		(start 344.898726 -223.729042)
		(end 344.82913 -223.769682)
		(width 0.1143)
		(layer "In11.Cu")
		(net "GMI_CPU1_G3_CPU0_G1_TX_DP<15>")
	)
	(segment
		(start 154.967686 -198.482966)
		(end 154.968194 -198.482966)
		(width 0.14224)
		(layer "In11.Cu")
		(net "GMI_CPU1_G3_CPU0_G1_TX_DP<15>")
	)
	(segment
		(start 158.658814 -195.633848)
		(end 158.980378 -195.370196)
		(width 0.14224)
		(layer "In11.Cu")
		(net "GMI_CPU1_G3_CPU0_G1_TX_DP<15>")
	)
	(segment
		(start 126.158752 -233.631232)
		(end 126.160276 -233.630216)
		(width 0.1143)
		(layer "In11.Cu")
		(net "GMI_CPU1_G3_CPU0_G1_TX_DP<15>")
	)
	(segment
		(start 262.841486 -190.954914)
		(end 303.7332 -191.33185)
		(width 0.14224)
		(layer "In11.Cu")
		(net "GMI_CPU1_G3_CPU0_G1_TX_DP<15>")
	)
	(segment
		(start 162.632898 -191.688212)
		(end 162.964876 -191.415416)
		(width 0.14224)
		(layer "In11.Cu")
		(net "GMI_CPU1_G3_CPU0_G1_TX_DP<15>")
	)
	(segment
		(start 344.82913 -224.698814)
		(end 344.898726 -224.739454)
		(width 0.1143)
		(layer "In11.Cu")
		(net "GMI_CPU1_G3_CPU0_G1_TX_DP<15>")
	)
	(segment
		(start 162.14471 -192.59804)
		(end 162.632898 -191.688212)
		(width 0.14224)
		(layer "In11.Cu")
		(net "GMI_CPU1_G3_CPU0_G1_TX_DP<15>")
	)
	(segment
		(start 126.597156 -224.739708)
		(end 126.627636 -224.721928)
		(width 0.1143)
		(layer "In11.Cu")
		(net "GMI_CPU1_G3_CPU0_G1_TX_DP<15>")
	)
	(segment
		(start 159.522414 -194.925696)
		(end 159.852614 -194.654932)
		(width 0.14224)
		(layer "In11.Cu")
		(net "GMI_CPU1_G3_CPU0_G1_TX_DP<15>")
	)
	(segment
		(start 345.055444 -221.24416)
		(end 345.055444 -221.804484)
		(width 0.1143)
		(layer "In11.Cu")
		(net "GMI_CPU1_G3_CPU0_G1_TX_DP<15>")
	)
	(segment
		(start 345.055444 -221.804484)
		(end 345.05519 -221.80423)
		(width 0.1143)
		(layer "In11.Cu")
		(net "GMI_CPU1_G3_CPU0_G1_TX_DP<15>")
	)
	(segment
		(start 126.664212 -230.248206)
		(end 126.597156 -230.20909)
		(width 0.1143)
		(layer "In11.Cu")
		(net "GMI_CPU1_G3_CPU0_G1_TX_DP<15>")
	)
	(segment
		(start 231.94772 -200.883012)
		(end 236.278928 -201.64679)
		(width 0.14224)
		(layer "In11.Cu")
		(net "GMI_CPU1_G3_CPU0_G1_TX_DP<15>")
	)
	(segment
		(start 126.440692 -221.804484)
		(end 126.440438 -221.804738)
		(width 0.1143)
		(layer "In11.Cu")
		(net "GMI_CPU1_G3_CPU0_G1_TX_DP<15>")
	)
	(segment
		(start 126.597156 -226.35972)
		(end 126.627636 -226.34194)
		(width 0.1143)
		(layer "In11.Cu")
		(net "GMI_CPU1_G3_CPU0_G1_TX_DP<15>")
	)
	(segment
		(start 240.324132 -200.933304)
		(end 251.791724 -192.903094)
		(width 0.14224)
		(layer "In11.Cu")
		(net "GMI_CPU1_G3_CPU0_G1_TX_DP<15>")
	)
	(segment
		(start 158.980378 -195.370196)
		(end 158.999428 -195.177156)
		(width 0.14224)
		(layer "In11.Cu")
		(net "GMI_CPU1_G3_CPU0_G1_TX_DP<15>")
	)
	(segment
		(start 236.278928 -201.64679)
		(end 240.324132 -200.933304)
		(width 0.14224)
		(layer "In11.Cu")
		(net "GMI_CPU1_G3_CPU0_G1_TX_DP<15>")
	)
	(segment
		(start 126.597156 -223.119696)
		(end 126.666752 -223.079056)
		(width 0.1143)
		(layer "In11.Cu")
		(net "GMI_CPU1_G3_CPU0_G1_TX_DP<15>")
	)
	(segment
		(start 147.418044 -203.237592)
		(end 150.194772 -202.396344)
		(width 0.14224)
		(layer "In11.Cu")
		(net "GMI_CPU1_G3_CPU0_G1_TX_DP<15>")
	)
	(segment
		(start 156.36367 -197.515988)
		(end 156.38272 -197.322948)
		(width 0.14224)
		(layer "In11.Cu")
		(net "GMI_CPU1_G3_CPU0_G1_TX_DP<15>")
	)
	(segment
		(start 160.7439 -193.746628)
		(end 161.073846 -193.476118)
		(width 0.14224)
		(layer "In11.Cu")
		(net "GMI_CPU1_G3_CPU0_G1_TX_DP<15>")
	)
	(segment
		(start 127.09779 -231.036876)
		(end 127.064262 -231.017318)
		(width 0.1143)
		(layer "In11.Cu")
		(net "GMI_CPU1_G3_CPU0_G1_TX_DP<15>")
	)
	(segment
		(start 126.597156 -232.839514)
		(end 126.665228 -232.79989)
		(width 0.1143)
		(layer "In11.Cu")
		(net "GMI_CPU1_G3_CPU0_G1_TX_DP<15>")
	)
	(segment
		(start 344.82913 -227.938838)
		(end 344.898726 -227.979478)
		(width 0.1143)
		(layer "In11.Cu")
		(net "GMI_CPU1_G3_CPU0_G1_TX_DP<15>")
	)
	(segment
		(start 157.254956 -196.607684)
		(end 157.584902 -196.337174)
		(width 0.14224)
		(layer "In11.Cu")
		(net "GMI_CPU1_G3_CPU0_G1_TX_DP<15>")
	)
	(segment
		(start 126.157736 -233.63174)
		(end 126.158752 -233.631232)
		(width 0.1143)
		(layer "In11.Cu")
		(net "GMI_CPU1_G3_CPU0_G1_TX_DP<15>")
	)
	(segment
		(start 345.988894 -234.694222)
		(end 345.919044 -234.764072)
		(width 0.1143)
		(layer "In11.Cu")
		(net "GMI_CPU1_G3_CPU0_G1_TX_DP<15>")
	)
	(segment
		(start 345.34475 -233.635296)
		(end 345.345766 -233.635804)
		(width 0.1143)
		(layer "In11.Cu")
		(net "GMI_CPU1_G3_CPU0_G1_TX_DP<15>")
	)
	(segment
		(start 344.397838 -232.012744)
		(end 344.40368 -232.016046)
		(width 0.1143)
		(layer "In11.Cu")
		(net "GMI_CPU1_G3_CPU0_G1_TX_DP<15>")
	)
	(segment
		(start 209.73542 -191.682624)
		(end 231.94772 -200.883012)
		(width 0.14224)
		(layer "In11.Cu")
		(net "GMI_CPU1_G3_CPU0_G1_TX_DP<15>")
	)
	(segment
		(start 157.777942 -196.356224)
		(end 158.108142 -196.08546)
		(width 0.14224)
		(layer "In11.Cu")
		(net "GMI_CPU1_G3_CPU0_G1_TX_DP<15>")
	)
	(segment
		(start 126.440438 -221.804738)
		(end 126.440438 -221.244414)
		(width 0.1143)
		(layer "In11.Cu")
		(net "GMI_CPU1_G3_CPU0_G1_TX_DP<15>")
	)
	(segment
		(start 345.342464 -233.634026)
		(end 345.343988 -233.634788)
		(width 0.1143)
		(layer "In11.Cu")
		(net "GMI_CPU1_G3_CPU0_G1_TX_DP<15>")
	)
	(segment
		(start 126.595124 -229.60076)
		(end 126.627636 -229.581964)
		(width 0.1143)
		(layer "In11.Cu")
		(net "GMI_CPU1_G3_CPU0_G1_TX_DP<15>")
	)
	(segment
		(start 344.868246 -229.58171)
		(end 344.900758 -229.600506)
		(width 0.1143)
		(layer "In11.Cu")
		(net "GMI_CPU1_G3_CPU0_G1_TX_DP<15>")
	)
	(segment
		(start 161.266886 -193.495168)
		(end 161.59734 -193.224404)
		(width 0.14224)
		(layer "In11.Cu")
		(net "GMI_CPU1_G3_CPU0_G1_TX_DP<15>")
	)
	(segment
		(start 126.156974 -233.632248)
		(end 126.157736 -233.63174)
		(width 0.1143)
		(layer "In11.Cu")
		(net "GMI_CPU1_G3_CPU0_G1_TX_DP<15>")
	)
	(segment
		(start 126.627636 -228.607112)
		(end 126.597156 -228.589332)
		(width 0.1143)
		(layer "In11.Cu")
		(net "GMI_CPU1_G3_CPU0_G1_TX_DP<15>")
	)
	(segment
		(start 251.791724 -192.903094)
		(end 262.841486 -190.954914)
		(width 0.14224)
		(layer "In11.Cu")
		(net "GMI_CPU1_G3_CPU0_G1_TX_DP<15>")
	)
	(segment
		(start 344.898726 -225.349054)
		(end 344.82913 -225.389694)
		(width 0.1143)
		(layer "In11.Cu")
		(net "GMI_CPU1_G3_CPU0_G1_TX_DP<15>")
	)
	(segment
		(start 126.627636 -227.961952)
		(end 126.666752 -227.939092)
		(width 0.1143)
		(layer "In11.Cu")
		(net "GMI_CPU1_G3_CPU0_G1_TX_DP<15>")
	)
	(segment
		(start 126.485904 -221.198948)
		(end 126.485904 -221.125034)
		(width 0.14224)
		(layer "In11.Cu")
		(net "GMI_CPU1_G3_CPU0_G1_TX_DP<15>")
	)
	(segment
		(start 316.413896 -197.02018)
		(end 344.36812 -219.94114)
		(width 0.14224)
		(layer "In11.Cu")
		(net "GMI_CPU1_G3_CPU0_G1_TX_DP<15>")
	)
	(segment
		(start 155.510484 -198.038212)
		(end 155.84043 -197.767702)
		(width 0.14224)
		(layer "In11.Cu")
		(net "GMI_CPU1_G3_CPU0_G1_TX_DP<15>")
	)
	(segment
		(start 126.627636 -226.9871)
		(end 126.597156 -226.96932)
		(width 0.1143)
		(layer "In11.Cu")
		(net "GMI_CPU1_G3_CPU0_G1_TX_DP<15>")
	)
	(segment
		(start 344.82913 -229.55885)
		(end 344.868246 -229.58171)
		(width 0.1143)
		(layer "In11.Cu")
		(net "GMI_CPU1_G3_CPU0_G1_TX_DP<15>")
	)
	(segment
		(start 155.84043 -197.767702)
		(end 156.03347 -197.786752)
		(width 0.14224)
		(layer "In11.Cu")
		(net "GMI_CPU1_G3_CPU0_G1_TX_DP<15>")
	)
	(segment
		(start 345.29903 -233.608626)
		(end 345.333574 -233.628692)
		(width 0.1143)
		(layer "In11.Cu")
		(net "GMI_CPU1_G3_CPU0_G1_TX_DP<15>")
	)
	(segment
		(start 158.127192 -195.89242)
		(end 158.457138 -195.62191)
		(width 0.14224)
		(layer "In11.Cu")
		(net "GMI_CPU1_G3_CPU0_G1_TX_DP<15>")
	)
	(segment
		(start 345.338908 -233.631994)
		(end 345.341702 -233.633518)
		(width 0.1143)
		(layer "In11.Cu")
		(net "GMI_CPU1_G3_CPU0_G1_TX_DP<15>")
	)
	(segment
		(start 344.82913 -223.078802)
		(end 344.898726 -223.119442)
		(width 0.1143)
		(layer "In11.Cu")
		(net "GMI_CPU1_G3_CPU0_G1_TX_DP<15>")
	)
	(segment
		(start 345.345766 -233.635804)
		(end 345.369896 -233.649774)
		(width 0.1143)
		(layer "In11.Cu")
		(net "GMI_CPU1_G3_CPU0_G1_TX_DP<15>")
	)
	(segment
		(start 207.161384 -191.228472)
		(end 209.73542 -191.682624)
		(width 0.14224)
		(layer "In11.Cu")
		(net "GMI_CPU1_G3_CPU0_G1_TX_DP<15>")
	)
	(segment
		(start 155.161234 -198.502016)
		(end 155.491434 -198.231252)
		(width 0.14224)
		(layer "In11.Cu")
		(net "GMI_CPU1_G3_CPU0_G1_TX_DP<15>")
	)
	(segment
		(start 344.898726 -230.208836)
		(end 344.83167 -230.247952)
		(width 0.1143)
		(layer "In11.Cu")
		(net "GMI_CPU1_G3_CPU0_G1_TX_DP<15>")
	)
	(segment
		(start 154.968194 -198.482966)
		(end 155.161234 -198.502016)
		(width 0.14224)
		(layer "In11.Cu")
		(net "GMI_CPU1_G3_CPU0_G1_TX_DP<15>")
	)
	(segment
		(start 127.32512 -219.712286)
		(end 147.418044 -203.237592)
		(width 0.14224)
		(layer "In11.Cu")
		(net "GMI_CPU1_G3_CPU0_G1_TX_DP<15>")
	)
	(segment
		(start 126.597156 -227.979732)
		(end 126.627636 -227.961952)
		(width 0.1143)
		(layer "In11.Cu")
		(net "GMI_CPU1_G3_CPU0_G1_TX_DP<15>")
	)
	(segment
		(start 159.329374 -194.906646)
		(end 159.522414 -194.925696)
		(width 0.14224)
		(layer "In11.Cu")
		(net "GMI_CPU1_G3_CPU0_G1_TX_DP<15>")
	)
	(segment
		(start 345.343988 -233.634788)
		(end 345.34475 -233.635296)
		(width 0.1143)
		(layer "In11.Cu")
		(net "GMI_CPU1_G3_CPU0_G1_TX_DP<15>")
	)
	(segment
		(start 161.61639 -193.031364)
		(end 162.14471 -192.59804)
		(width 0.14224)
		(layer "In11.Cu")
		(net "GMI_CPU1_G3_CPU0_G1_TX_DP<15>")
	)
	(segment
		(start 158.108142 -196.08546)
		(end 158.127192 -195.89242)
		(width 0.14224)
		(layer "In11.Cu")
		(net "GMI_CPU1_G3_CPU0_G1_TX_DP<15>")
	)
	(segment
		(start 158.457138 -195.62191)
		(end 158.650178 -195.64096)
		(width 0.14224)
		(layer "In11.Cu")
		(net "GMI_CPU1_G3_CPU0_G1_TX_DP<15>")
	)
	(segment
		(start 345.919044 -234.764072)
		(end 345.621102 -234.764072)
		(width 0.1143)
		(layer "In11.Cu")
		(net "GMI_CPU1_G3_CPU0_G1_TX_DP<15>")
	)
	(segment
		(start 126.666752 -223.769936)
		(end 126.627636 -223.747076)
		(width 0.1143)
		(layer "In11.Cu")
		(net "GMI_CPU1_G3_CPU0_G1_TX_DP<15>")
	)
	(segment
		(start 127.139446 -231.061514)
		(end 127.097536 -231.03713)
		(width 0.1143)
		(layer "In11.Cu")
		(net "GMI_CPU1_G3_CPU0_G1_TX_DP<15>")
	)
	(segment
		(start 344.898726 -228.589078)
		(end 344.82913 -228.629718)
		(width 0.1143)
		(layer "In11.Cu")
		(net "GMI_CPU1_G3_CPU0_G1_TX_DP<15>")
	)
	(segment
		(start 126.160276 -233.630216)
		(end 126.196852 -233.60888)
		(width 0.1143)
		(layer "In11.Cu")
		(net "GMI_CPU1_G3_CPU0_G1_TX_DP<15>")
	)
	(segment
		(start 126.627636 -224.721928)
		(end 126.666752 -224.699068)
		(width 0.1143)
		(layer "In11.Cu")
		(net "GMI_CPU1_G3_CPU0_G1_TX_DP<15>")
	)
	(segment
		(start 345.33713 -233.630978)
		(end 345.338146 -233.631486)
		(width 0.1143)
		(layer "In11.Cu")
		(net "GMI_CPU1_G3_CPU0_G1_TX_DP<15>")
	)
	(segment
		(start 126.485904 -221.125034)
		(end 127.32512 -219.712286)
		(width 0.14224)
		(layer "In11.Cu")
		(net "GMI_CPU1_G3_CPU0_G1_TX_DP<15>")
	)
	(segment
		(start 159.871664 -194.461892)
		(end 160.20161 -194.191382)
		(width 0.14224)
		(layer "In11.Cu")
		(net "GMI_CPU1_G3_CPU0_G1_TX_DP<15>")
	)
	(segment
		(start 344.36812 -219.94114)
		(end 345.009978 -221.021402)
		(width 0.14224)
		(layer "In11.Cu")
		(net "GMI_CPU1_G3_CPU0_G1_TX_DP<15>")
	)
	(segment
		(start 127.097536 -231.03713)
		(end 127.09779 -231.036876)
		(width 0.1143)
		(layer "In11.Cu")
		(net "GMI_CPU1_G3_CPU0_G1_TX_DP<15>")
	)
	(segment
		(start 160.39465 -194.210432)
		(end 160.72485 -193.939668)
		(width 0.14224)
		(layer "In11.Cu")
		(net "GMI_CPU1_G3_CPU0_G1_TX_DP<15>")
	)
	(segment
		(start 126.665482 -222.148908)
		(end 126.59741 -222.109284)
		(width 0.1143)
		(layer "In11.Cu")
		(net "GMI_CPU1_G3_CPU0_G1_TX_DP<15>")
	)
	(segment
		(start 345.341702 -233.633518)
		(end 345.342464 -233.634026)
		(width 0.1143)
		(layer "In11.Cu")
		(net "GMI_CPU1_G3_CPU0_G1_TX_DP<15>")
	)
	(segment
		(start 161.073846 -193.476118)
		(end 161.266886 -193.495168)
		(width 0.14224)
		(layer "In11.Cu")
		(net "GMI_CPU1_G3_CPU0_G1_TX_DP<15>")
	)
	(segment
		(start 308.267862 -191.33185)
		(end 316.413896 -197.02018)
		(width 0.14224)
		(layer "In11.Cu")
		(net "GMI_CPU1_G3_CPU0_G1_TX_DP<15>")
	)
	(segment
		(start 126.125986 -233.650028)
		(end 126.156974 -233.632248)
		(width 0.1143)
		(layer "In11.Cu")
		(net "GMI_CPU1_G3_CPU0_G1_TX_DP<15>")
	)
	(segment
		(start 127.092202 -232.0163)
		(end 127.098044 -232.012998)
		(width 0.1143)
		(layer "In11.Cu")
		(net "GMI_CPU1_G3_CPU0_G1_TX_DP<15>")
	)
	(segment
		(start 345.769184 -234.418632)
		(end 345.83878 -234.459272)
		(width 0.1143)
		(layer "In11.Cu")
		(net "GMI_CPU1_G3_CPU0_G1_TX_DP<15>")
	)
	(segment
		(start 156.905706 -197.071488)
		(end 157.235906 -196.800724)
		(width 0.14224)
		(layer "In11.Cu")
		(net "GMI_CPU1_G3_CPU0_G1_TX_DP<15>")
	)
	(segment
		(start 303.7332 -191.33185)
		(end 308.267862 -191.33185)
		(width 0.14224)
		(layer "In11.Cu")
		(net "GMI_CPU1_G3_CPU0_G1_TX_DP<15>")
	)
	(segment
		(start 344.898726 -226.969066)
		(end 344.82913 -227.009706)
		(width 0.1143)
		(layer "In11.Cu")
		(net "GMI_CPU1_G3_CPU0_G1_TX_DP<15>")
	)
	(segment
		(start 150.194772 -202.396344)
		(end 154.967686 -198.482966)
		(width 0.14224)
		(layer "In11.Cu")
		(net "GMI_CPU1_G3_CPU0_G1_TX_DP<15>")
	)
	(segment
		(start 162.964876 -191.415416)
		(end 207.161384 -191.228472)
		(width 0.14224)
		(layer "In11.Cu")
		(net "GMI_CPU1_G3_CPU0_G1_TX_DP<15>")
	)
	(segment
		(start 344.898472 -222.10903)
		(end 344.8304 -222.148654)
		(width 0.1143)
		(layer "In11.Cu")
		(net "GMI_CPU1_G3_CPU0_G1_TX_DP<15>")
	)
	(segment
		(start 157.584902 -196.337174)
		(end 157.777942 -196.356224)
		(width 0.14224)
		(layer "In11.Cu")
		(net "GMI_CPU1_G3_CPU0_G1_TX_DP<15>")
	)
	(segment
		(start 126.666752 -225.389948)
		(end 126.627636 -225.367088)
		(width 0.1143)
		(layer "In11.Cu")
		(net "GMI_CPU1_G3_CPU0_G1_TX_DP<15>")
	)
	(segment
		(start 344.398092 -231.036622)
		(end 344.398346 -231.036876)
		(width 0.1143)
		(layer "In11.Cu")
		(net "GMI_CPU1_G3_CPU0_G1_TX_DP<15>")
	)
	(segment
		(start 159.852614 -194.654932)
		(end 159.871664 -194.461892)
		(width 0.14224)
		(layer "In11.Cu")
		(net "GMI_CPU1_G3_CPU0_G1_TX_DP<15>")
	)
	(segment
		(start 155.491434 -198.231252)
		(end 155.510484 -198.038212)
		(width 0.14224)
		(layer "In11.Cu")
		(net "GMI_CPU1_G3_CPU0_G1_TX_DP<15>")
	)
	(segment
		(start 158.650178 -195.64096)
		(end 158.658814 -195.633848)
		(width 0.14224)
		(layer "In11.Cu")
		(net "GMI_CPU1_G3_CPU0_G1_TX_DP<15>")
	)
	(segment
		(start 126.627636 -223.747076)
		(end 126.597156 -223.729296)
		(width 0.1143)
		(layer "In11.Cu")
		(net "GMI_CPU1_G3_CPU0_G1_TX_DP<15>")
	)
	(segment
		(start 345.009978 -221.198694)
		(end 345.055444 -221.24416)
		(width 0.1143)
		(layer "In11.Cu")
		(net "GMI_CPU1_G3_CPU0_G1_TX_DP<15>")
	)
	(segment
		(start 160.20161 -194.191382)
		(end 160.39465 -194.210432)
		(width 0.14224)
		(layer "In11.Cu")
		(net "GMI_CPU1_G3_CPU0_G1_TX_DP<15>")
	)
	(segment
		(start 345.333574 -233.628692)
		(end 345.33586 -233.630216)
		(width 0.1143)
		(layer "In11.Cu")
		(net "GMI_CPU1_G3_CPU0_G1_TX_DP<15>")
	)
	(segment
		(start 345.009978 -221.021402)
		(end 345.009978 -221.198694)
		(width 0.14224)
		(layer "In11.Cu")
		(net "GMI_CPU1_G3_CPU0_G1_TX_DP<15>")
	)
	(segment
		(start 158.999428 -195.177156)
		(end 159.329374 -194.906646)
		(width 0.14224)
		(layer "In11.Cu")
		(net "GMI_CPU1_G3_CPU0_G1_TX_DP<15>")
	)
	(segment
		(start 126.666752 -227.00996)
		(end 126.627636 -226.9871)
		(width 0.1143)
		(layer "In11.Cu")
		(net "GMI_CPU1_G3_CPU0_G1_TX_DP<15>")
	)
	(segment
		(start 126.666752 -228.629972)
		(end 126.627636 -228.607112)
		(width 0.1143)
		(layer "In11.Cu")
		(net "GMI_CPU1_G3_CPU0_G1_TX_DP<15>")
	)
	(segment
		(start 125.687582 -234.441746)
		(end 125.726698 -234.418886)
		(width 0.1143)
		(layer "In11.Cu")
		(net "GMI_CPU1_G3_CPU0_G1_TX_DP<15>")
	)
	(segment
		(start 126.627636 -226.34194)
		(end 126.666752 -226.31908)
		(width 0.1143)
		(layer "In11.Cu")
		(net "GMI_CPU1_G3_CPU0_G1_TX_DP<15>")
	)
	(segment
		(start 125.576838 -234.764326)
		(end 125.506988 -234.694476)
		(width 0.1143)
		(layer "In11.Cu")
		(net "GMI_CPU1_G3_CPU0_G1_TX_DP<15>")
	)
	(segment
		(start 125.657102 -234.459526)
		(end 125.687582 -234.441746)
		(width 0.1143)
		(layer "In11.Cu")
		(net "GMI_CPU1_G3_CPU0_G1_TX_DP<15>")
	)
	(segment
		(start 345.33586 -233.630216)
		(end 345.33713 -233.630978)
		(width 0.1143)
		(layer "In11.Cu")
		(net "GMI_CPU1_G3_CPU0_G1_TX_DP<15>")
	)
	(segment
		(start 160.72485 -193.939668)
		(end 160.7439 -193.746628)
		(width 0.14224)
		(layer "In11.Cu")
		(net "GMI_CPU1_G3_CPU0_G1_TX_DP<15>")
	)
	(segment
		(start 157.235906 -196.800724)
		(end 157.254956 -196.607684)
		(width 0.14224)
		(layer "In11.Cu")
		(net "GMI_CPU1_G3_CPU0_G1_TX_DP<15>")
	)
	(segment
		(start 156.712666 -197.052438)
		(end 156.905706 -197.071488)
		(width 0.14224)
		(layer "In11.Cu")
		(net "GMI_CPU1_G3_CPU0_G1_TX_DP<15>")
	)
	(segment
		(start 126.627636 -225.367088)
		(end 126.597156 -225.349308)
		(width 0.1143)
		(layer "In11.Cu")
		(net "GMI_CPU1_G3_CPU0_G1_TX_DP<15>")
	)
	(segment
		(start 156.38272 -197.322948)
		(end 156.712666 -197.052438)
		(width 0.14224)
		(layer "In11.Cu")
		(net "GMI_CPU1_G3_CPU0_G1_TX_DP<15>")
	)
	(segment
		(start 126.440438 -221.244414)
		(end 126.485904 -221.198948)
		(width 0.1143)
		(layer "In11.Cu")
		(net "GMI_CPU1_G3_CPU0_G1_TX_DP<15>")
	)
	(arc
		(start 126.59741 -222.109284)
		(mid 126.548998 -222.068127)
		(end 126.508256 -222.019368)
		(width 0.1143)
		(layer "In11.Cu")
		(net "GMI_CPU1_G3_CPU0_G1_TX_DP<15>")
	)
	(arc
		(start 126.597156 -230.20909)
		(mid 126.481729 -230.075714)
		(end 126.440184 -229.90429)
		(width 0.1143)
		(layer "In11.Cu")
		(net "GMI_CPU1_G3_CPU0_G1_TX_DP<15>")
	)
	(arc
		(start 344.82913 -227.009706)
		(mid 344.585803 -227.474272)
		(end 344.82913 -227.938838)
		(width 0.1143)
		(layer "In11.Cu")
		(net "GMI_CPU1_G3_CPU0_G1_TX_DP<15>")
	)
	(arc
		(start 126.597156 -225.349308)
		(mid 126.440179 -225.044508)
		(end 126.597156 -224.739708)
		(width 0.1143)
		(layer "In11.Cu")
		(net "GMI_CPU1_G3_CPU0_G1_TX_DP<15>")
	)
	(arc
		(start 344.82913 -228.629718)
		(mid 344.585803 -229.094284)
		(end 344.82913 -229.55885)
		(width 0.1143)
		(layer "In11.Cu")
		(net "GMI_CPU1_G3_CPU0_G1_TX_DP<15>")
	)
	(arc
		(start 127.064262 -231.017318)
		(mid 126.950855 -230.884429)
		(end 126.910084 -230.71455)
		(width 0.1143)
		(layer "In11.Cu")
		(net "GMI_CPU1_G3_CPU0_G1_TX_DP<15>")
	)
	(arc
		(start 126.666752 -226.31908)
		(mid 126.910079 -225.854514)
		(end 126.666752 -225.389948)
		(width 0.1143)
		(layer "In11.Cu")
		(net "GMI_CPU1_G3_CPU0_G1_TX_DP<15>")
	)
	(arc
		(start 345.055698 -229.904036)
		(mid 345.014149 -230.075458)
		(end 344.898726 -230.208836)
		(width 0.1143)
		(layer "In11.Cu")
		(net "GMI_CPU1_G3_CPU0_G1_TX_DP<15>")
	)
	(arc
		(start 126.90983 -232.334308)
		(mid 126.95865 -232.150999)
		(end 127.092202 -232.0163)
		(width 0.1143)
		(layer "In11.Cu")
		(net "GMI_CPU1_G3_CPU0_G1_TX_DP<15>")
	)
	(arc
		(start 125.726698 -234.418886)
		(mid 125.905511 -234.216536)
		(end 125.97003 -233.95432)
		(width 0.1143)
		(layer "In11.Cu")
		(net "GMI_CPU1_G3_CPU0_G1_TX_DP<15>")
	)
	(arc
		(start 125.506988 -234.694476)
		(mid 125.559405 -234.562545)
		(end 125.657102 -234.459526)
		(width 0.1143)
		(layer "In11.Cu")
		(net "GMI_CPU1_G3_CPU0_G1_TX_DP<15>")
	)
	(arc
		(start 126.665228 -232.79989)
		(mid 126.84502 -232.597302)
		(end 126.90983 -232.334308)
		(width 0.1143)
		(layer "In11.Cu")
		(net "GMI_CPU1_G3_CPU0_G1_TX_DP<15>")
	)
	(arc
		(start 344.82913 -225.389694)
		(mid 344.585803 -225.85426)
		(end 344.82913 -226.318826)
		(width 0.1143)
		(layer "In11.Cu")
		(net "GMI_CPU1_G3_CPU0_G1_TX_DP<15>")
	)
	(arc
		(start 345.525852 -233.954066)
		(mid 345.590367 -234.216285)
		(end 345.769184 -234.418632)
		(width 0.1143)
		(layer "In11.Cu")
		(net "GMI_CPU1_G3_CPU0_G1_TX_DP<15>")
	)
	(arc
		(start 126.910084 -230.71455)
		(mid 126.844848 -230.450959)
		(end 126.664212 -230.248206)
		(width 0.1143)
		(layer "In11.Cu")
		(net "GMI_CPU1_G3_CPU0_G1_TX_DP<15>")
	)
	(arc
		(start 125.97003 -233.95432)
		(mid 126.011285 -233.783349)
		(end 126.125986 -233.650028)
		(width 0.1143)
		(layer "In11.Cu")
		(net "GMI_CPU1_G3_CPU0_G1_TX_DP<15>")
	)
	(arc
		(start 344.900758 -229.600506)
		(mid 345.014687 -229.733653)
		(end 345.055698 -229.904036)
		(width 0.1143)
		(layer "In11.Cu")
		(net "GMI_CPU1_G3_CPU0_G1_TX_DP<15>")
	)
	(arc
		(start 344.83167 -230.247952)
		(mid 344.651018 -230.450697)
		(end 344.585798 -230.714296)
		(width 0.1143)
		(layer "In11.Cu")
		(net "GMI_CPU1_G3_CPU0_G1_TX_DP<15>")
	)
	(arc
		(start 344.898726 -232.83926)
		(mid 345.014153 -232.972636)
		(end 345.055698 -233.14406)
		(width 0.1143)
		(layer "In11.Cu")
		(net "GMI_CPU1_G3_CPU0_G1_TX_DP<15>")
	)
	(arc
		(start 345.055698 -233.14406)
		(mid 345.120213 -233.406279)
		(end 345.29903 -233.608626)
		(width 0.1143)
		(layer "In11.Cu")
		(net "GMI_CPU1_G3_CPU0_G1_TX_DP<15>")
	)
	(arc
		(start 126.666752 -229.559104)
		(mid 126.910079 -229.094538)
		(end 126.666752 -228.629972)
		(width 0.1143)
		(layer "In11.Cu")
		(net "GMI_CPU1_G3_CPU0_G1_TX_DP<15>")
	)
	(arc
		(start 344.115898 -231.524048)
		(mid 344.191447 -231.80613)
		(end 344.397838 -232.012744)
		(width 0.1143)
		(layer "In11.Cu")
		(net "GMI_CPU1_G3_CPU0_G1_TX_DP<15>")
	)
	(arc
		(start 126.666752 -227.939092)
		(mid 126.910079 -227.474526)
		(end 126.666752 -227.00996)
		(width 0.1143)
		(layer "In11.Cu")
		(net "GMI_CPU1_G3_CPU0_G1_TX_DP<15>")
	)
	(arc
		(start 126.440184 -233.144314)
		(mid 126.481733 -232.972892)
		(end 126.597156 -232.839514)
		(width 0.1143)
		(layer "In11.Cu")
		(net "GMI_CPU1_G3_CPU0_G1_TX_DP<15>")
	)
	(arc
		(start 126.508256 -222.019368)
		(mid 126.457905 -221.917131)
		(end 126.440692 -221.804484)
		(width 0.1143)
		(layer "In11.Cu")
		(net "GMI_CPU1_G3_CPU0_G1_TX_DP<15>")
	)
	(arc
		(start 344.898726 -226.359466)
		(mid 345.055703 -226.664266)
		(end 344.898726 -226.969066)
		(width 0.1143)
		(layer "In11.Cu")
		(net "GMI_CPU1_G3_CPU0_G1_TX_DP<15>")
	)
	(arc
		(start 126.666752 -224.699068)
		(mid 126.910079 -224.234502)
		(end 126.666752 -223.769936)
		(width 0.1143)
		(layer "In11.Cu")
		(net "GMI_CPU1_G3_CPU0_G1_TX_DP<15>")
	)
	(arc
		(start 126.597156 -228.589332)
		(mid 126.440179 -228.284532)
		(end 126.597156 -227.979732)
		(width 0.1143)
		(layer "In11.Cu")
		(net "GMI_CPU1_G3_CPU0_G1_TX_DP<15>")
	)
	(arc
		(start 127.098044 -232.012998)
		(mid 127.304486 -231.806413)
		(end 127.379984 -231.524302)
		(width 0.1143)
		(layer "In11.Cu")
		(net "GMI_CPU1_G3_CPU0_G1_TX_DP<15>")
	)
	(arc
		(start 344.8304 -222.148654)
		(mid 344.58569 -222.613425)
		(end 344.82913 -223.078802)
		(width 0.1143)
		(layer "In11.Cu")
		(net "GMI_CPU1_G3_CPU0_G1_TX_DP<15>")
	)
	(arc
		(start 344.898726 -227.979478)
		(mid 345.055703 -228.284278)
		(end 344.898726 -228.589078)
		(width 0.1143)
		(layer "In11.Cu")
		(net "GMI_CPU1_G3_CPU0_G1_TX_DP<15>")
	)
	(arc
		(start 127.379984 -231.524302)
		(mid 127.316308 -231.263498)
		(end 127.139446 -231.061514)
		(width 0.1143)
		(layer "In11.Cu")
		(net "GMI_CPU1_G3_CPU0_G1_TX_DP<15>")
	)
	(arc
		(start 344.82913 -223.769682)
		(mid 344.585803 -224.234248)
		(end 344.82913 -224.698814)
		(width 0.1143)
		(layer "In11.Cu")
		(net "GMI_CPU1_G3_CPU0_G1_TX_DP<15>")
	)
	(arc
		(start 345.05519 -221.80423)
		(mid 345.037927 -221.916862)
		(end 344.987626 -222.019114)
		(width 0.1143)
		(layer "In11.Cu")
		(net "GMI_CPU1_G3_CPU0_G1_TX_DP<15>")
	)
	(arc
		(start 345.369896 -233.649774)
		(mid 345.484572 -233.783108)
		(end 345.525852 -233.954066)
		(width 0.1143)
		(layer "In11.Cu")
		(net "GMI_CPU1_G3_CPU0_G1_TX_DP<15>")
	)
	(arc
		(start 126.196852 -233.60888)
		(mid 126.375665 -233.40653)
		(end 126.440184 -233.144314)
		(width 0.1143)
		(layer "In11.Cu")
		(net "GMI_CPU1_G3_CPU0_G1_TX_DP<15>")
	)
	(arc
		(start 344.898726 -223.119442)
		(mid 345.055703 -223.424242)
		(end 344.898726 -223.729042)
		(width 0.1143)
		(layer "In11.Cu")
		(net "GMI_CPU1_G3_CPU0_G1_TX_DP<15>")
	)
	(arc
		(start 344.898726 -224.739454)
		(mid 345.055703 -225.044254)
		(end 344.898726 -225.349054)
		(width 0.1143)
		(layer "In11.Cu")
		(net "GMI_CPU1_G3_CPU0_G1_TX_DP<15>")
	)
	(arc
		(start 344.356436 -231.06126)
		(mid 344.179544 -231.263228)
		(end 344.115898 -231.524048)
		(width 0.1143)
		(layer "In11.Cu")
		(net "GMI_CPU1_G3_CPU0_G1_TX_DP<15>")
	)
	(arc
		(start 345.83878 -234.459272)
		(mid 345.936545 -234.562248)
		(end 345.988894 -234.694222)
		(width 0.1143)
		(layer "In11.Cu")
		(net "GMI_CPU1_G3_CPU0_G1_TX_DP<15>")
	)
	(arc
		(start 344.40368 -232.016046)
		(mid 344.537186 -232.150772)
		(end 344.586052 -232.334054)
		(width 0.1143)
		(layer "In11.Cu")
		(net "GMI_CPU1_G3_CPU0_G1_TX_DP<15>")
	)
	(arc
		(start 126.440184 -229.90429)
		(mid 126.48115 -229.733884)
		(end 126.595124 -229.60076)
		(width 0.1143)
		(layer "In11.Cu")
		(net "GMI_CPU1_G3_CPU0_G1_TX_DP<15>")
	)
	(arc
		(start 344.586052 -232.334054)
		(mid 344.65087 -232.597043)
		(end 344.830654 -232.799636)
		(width 0.1143)
		(layer "In11.Cu")
		(net "GMI_CPU1_G3_CPU0_G1_TX_DP<15>")
	)
	(arc
		(start 126.597156 -223.729296)
		(mid 126.440179 -223.424496)
		(end 126.597156 -223.119696)
		(width 0.1143)
		(layer "In11.Cu")
		(net "GMI_CPU1_G3_CPU0_G1_TX_DP<15>")
	)
	(arc
		(start 344.585798 -230.714296)
		(mid 344.545036 -230.88418)
		(end 344.43162 -231.017064)
		(width 0.1143)
		(layer "In11.Cu")
		(net "GMI_CPU1_G3_CPU0_G1_TX_DP<15>")
	)
	(arc
		(start 344.987626 -222.019114)
		(mid 344.946873 -222.067863)
		(end 344.898472 -222.10903)
		(width 0.1143)
		(layer "In11.Cu")
		(net "GMI_CPU1_G3_CPU0_G1_TX_DP<15>")
	)
	(arc
		(start 126.597156 -226.96932)
		(mid 126.440179 -226.66452)
		(end 126.597156 -226.35972)
		(width 0.1143)
		(layer "In11.Cu")
		(net "GMI_CPU1_G3_CPU0_G1_TX_DP<15>")
	)
	(arc
		(start 126.666752 -223.079056)
		(mid 126.910078 -222.613679)
		(end 126.665482 -222.148908)
		(width 0.1143)
		(layer "In11.Cu")
		(net "GMI_CPU1_G3_CPU0_G1_TX_DP<15>")
	)
	(segment
		(start 346.087954 -233.409998)
		(end 345.621102 -233.14406)
		(width 0.12954)
		(layer "F.Cu")
		(net "GMI_CPU1_G3_CPU0_G1_TX_DP<14>")
	)
	(segment
		(start 125.407928 -233.410252)
		(end 125.87478 -233.144314)
		(width 0.12954)
		(layer "F.Cu")
		(net "GMI_CPU1_G3_CPU0_G1_TX_DP<14>")
	)
	(segment
		(start 125.87478 -233.144314)
		(end 125.576838 -233.144314)
		(width 0.1143)
		(layer "In11.Cu")
		(net "GMI_CPU1_G3_CPU0_G1_TX_DP<14>")
	)
	(segment
		(start 157.831282 -194.921886)
		(end 158.161482 -194.650868)
		(width 0.14224)
		(layer "In11.Cu")
		(net "GMI_CPU1_G3_CPU0_G1_TX_DP<14>")
	)
	(segment
		(start 126.158752 -232.01122)
		(end 126.160276 -232.010204)
		(width 0.1143)
		(layer "In11.Cu")
		(net "GMI_CPU1_G3_CPU0_G1_TX_DP<14>")
	)
	(segment
		(start 154.691334 -197.318376)
		(end 155.02128 -197.047866)
		(width 0.14224)
		(layer "In11.Cu")
		(net "GMI_CPU1_G3_CPU0_G1_TX_DP<14>")
	)
	(segment
		(start 125.687582 -223.747076)
		(end 125.657102 -223.729296)
		(width 0.1143)
		(layer "In11.Cu")
		(net "GMI_CPU1_G3_CPU0_G1_TX_DP<14>")
	)
	(segment
		(start 126.166118 -232.006902)
		(end 126.196852 -231.988868)
		(width 0.1143)
		(layer "In11.Cu")
		(net "GMI_CPU1_G3_CPU0_G1_TX_DP<14>")
	)
	(segment
		(start 159.382714 -193.472308)
		(end 159.575754 -193.491612)
		(width 0.14224)
		(layer "In11.Cu")
		(net "GMI_CPU1_G3_CPU0_G1_TX_DP<14>")
	)
	(segment
		(start 125.500384 -221.458028)
		(end 125.495304 -221.452948)
		(width 0.1143)
		(layer "In11.Cu")
		(net "GMI_CPU1_G3_CPU0_G1_TX_DP<14>")
	)
	(segment
		(start 262.765794 -190.013844)
		(end 303.7332 -190.391796)
		(width 0.14224)
		(layer "In11.Cu")
		(net "GMI_CPU1_G3_CPU0_G1_TX_DP<14>")
	)
	(segment
		(start 236.299756 -200.696068)
		(end 239.94237 -200.053448)
		(width 0.14224)
		(layer "In11.Cu")
		(net "GMI_CPU1_G3_CPU0_G1_TX_DP<14>")
	)
	(segment
		(start 159.575754 -193.491612)
		(end 159.905954 -193.220594)
		(width 0.14224)
		(layer "In11.Cu")
		(net "GMI_CPU1_G3_CPU0_G1_TX_DP<14>")
	)
	(segment
		(start 345.769184 -226.318826)
		(end 345.83878 -226.359466)
		(width 0.1143)
		(layer "In11.Cu")
		(net "GMI_CPU1_G3_CPU0_G1_TX_DP<14>")
	)
	(segment
		(start 159.925004 -193.027554)
		(end 160.25495 -192.757044)
		(width 0.14224)
		(layer "In11.Cu")
		(net "GMI_CPU1_G3_CPU0_G1_TX_DP<14>")
	)
	(segment
		(start 125.495304 -221.248732)
		(end 125.541024 -221.203012)
		(width 0.1143)
		(layer "In11.Cu")
		(net "GMI_CPU1_G3_CPU0_G1_TX_DP<14>")
	)
	(segment
		(start 345.838526 -222.10903)
		(end 345.808046 -222.12681)
		(width 0.1143)
		(layer "In11.Cu")
		(net "GMI_CPU1_G3_CPU0_G1_TX_DP<14>")
	)
	(segment
		(start 149.48027 -201.590656)
		(end 154.149044 -197.76313)
		(width 0.14224)
		(layer "In11.Cu")
		(net "GMI_CPU1_G3_CPU0_G1_TX_DP<14>")
	)
	(segment
		(start 156.435806 -195.888102)
		(end 156.435806 -195.888356)
		(width 0.14224)
		(layer "In11.Cu")
		(net "GMI_CPU1_G3_CPU0_G1_TX_DP<14>")
	)
	(segment
		(start 155.89377 -196.332856)
		(end 156.086556 -196.351906)
		(width 0.14224)
		(layer "In11.Cu")
		(net "GMI_CPU1_G3_CPU0_G1_TX_DP<14>")
	)
	(segment
		(start 125.726698 -223.769936)
		(end 125.687582 -223.747076)
		(width 0.1143)
		(layer "In11.Cu")
		(net "GMI_CPU1_G3_CPU0_G1_TX_DP<14>")
	)
	(segment
		(start 126.125986 -232.030016)
		(end 126.155704 -232.012998)
		(width 0.1143)
		(layer "In11.Cu")
		(net "GMI_CPU1_G3_CPU0_G1_TX_DP<14>")
	)
	(segment
		(start 155.21432 -197.06717)
		(end 155.54452 -196.796406)
		(width 0.14224)
		(layer "In11.Cu")
		(net "GMI_CPU1_G3_CPU0_G1_TX_DP<14>")
	)
	(segment
		(start 126.156974 -232.012236)
		(end 126.157736 -232.011728)
		(width 0.1143)
		(layer "In11.Cu")
		(net "GMI_CPU1_G3_CPU0_G1_TX_DP<14>")
	)
	(segment
		(start 345.769184 -232.79862)
		(end 345.83878 -232.83926)
		(width 0.1143)
		(layer "In11.Cu")
		(net "GMI_CPU1_G3_CPU0_G1_TX_DP<14>")
	)
	(segment
		(start 125.687582 -225.367088)
		(end 125.657102 -225.349308)
		(width 0.1143)
		(layer "In11.Cu")
		(net "GMI_CPU1_G3_CPU0_G1_TX_DP<14>")
	)
	(segment
		(start 125.687582 -227.961952)
		(end 125.726698 -227.939092)
		(width 0.1143)
		(layer "In11.Cu")
		(net "GMI_CPU1_G3_CPU0_G1_TX_DP<14>")
	)
	(segment
		(start 125.726698 -225.389948)
		(end 125.687582 -225.367088)
		(width 0.1143)
		(layer "In11.Cu")
		(net "GMI_CPU1_G3_CPU0_G1_TX_DP<14>")
	)
	(segment
		(start 317.09868 -196.341746)
		(end 345.126056 -219.322142)
		(width 0.14224)
		(layer "In11.Cu")
		(net "GMI_CPU1_G3_CPU0_G1_TX_DP<14>")
	)
	(segment
		(start 345.341702 -232.013506)
		(end 345.342464 -232.014014)
		(width 0.1143)
		(layer "In11.Cu")
		(net "GMI_CPU1_G3_CPU0_G1_TX_DP<14>")
	)
	(segment
		(start 345.769184 -224.698814)
		(end 345.83878 -224.739454)
		(width 0.1143)
		(layer "In11.Cu")
		(net "GMI_CPU1_G3_CPU0_G1_TX_DP<14>")
	)
	(segment
		(start 125.541024 -221.174564)
		(end 125.541024 -220.897958)
		(width 0.14224)
		(layer "In11.Cu")
		(net "GMI_CPU1_G3_CPU0_G1_TX_DP<14>")
	)
	(segment
		(start 345.954858 -220.716348)
		(end 345.954858 -221.17431)
		(width 0.14224)
		(layer "In11.Cu")
		(net "GMI_CPU1_G3_CPU0_G1_TX_DP<14>")
	)
	(segment
		(start 345.954858 -221.17431)
		(end 345.954858 -221.202758)
		(width 0.1143)
		(layer "In11.Cu")
		(net "GMI_CPU1_G3_CPU0_G1_TX_DP<14>")
	)
	(segment
		(start 125.687582 -223.101916)
		(end 125.726698 -223.079056)
		(width 0.1143)
		(layer "In11.Cu")
		(net "GMI_CPU1_G3_CPU0_G1_TX_DP<14>")
	)
	(segment
		(start 156.416756 -196.081142)
		(end 156.435806 -195.888102)
		(width 0.14224)
		(layer "In11.Cu")
		(net "GMI_CPU1_G3_CPU0_G1_TX_DP<14>")
	)
	(segment
		(start 155.56357 -196.603366)
		(end 155.89377 -196.332856)
		(width 0.14224)
		(layer "In11.Cu")
		(net "GMI_CPU1_G3_CPU0_G1_TX_DP<14>")
	)
	(segment
		(start 159.905954 -193.220594)
		(end 159.925004 -193.027554)
		(width 0.14224)
		(layer "In11.Cu")
		(net "GMI_CPU1_G3_CPU0_G1_TX_DP<14>")
	)
	(segment
		(start 158.180532 -194.457828)
		(end 158.510478 -194.187318)
		(width 0.14224)
		(layer "In11.Cu")
		(net "GMI_CPU1_G3_CPU0_G1_TX_DP<14>")
	)
	(segment
		(start 125.657102 -224.739708)
		(end 125.687582 -224.721928)
		(width 0.1143)
		(layer "In11.Cu")
		(net "GMI_CPU1_G3_CPU0_G1_TX_DP<14>")
	)
	(segment
		(start 126.157736 -232.011728)
		(end 126.158752 -232.01122)
		(width 0.1143)
		(layer "In11.Cu")
		(net "GMI_CPU1_G3_CPU0_G1_TX_DP<14>")
	)
	(segment
		(start 158.161482 -194.650868)
		(end 158.180532 -194.457828)
		(width 0.14224)
		(layer "In11.Cu")
		(net "GMI_CPU1_G3_CPU0_G1_TX_DP<14>")
	)
	(segment
		(start 158.510478 -194.187318)
		(end 158.658814 -194.20205)
		(width 0.14224)
		(layer "In11.Cu")
		(net "GMI_CPU1_G3_CPU0_G1_TX_DP<14>")
	)
	(segment
		(start 345.995498 -221.457774)
		(end 345.995498 -221.80423)
		(width 0.1143)
		(layer "In11.Cu")
		(net "GMI_CPU1_G3_CPU0_G1_TX_DP<14>")
	)
	(segment
		(start 126.160276 -232.010204)
		(end 126.161292 -232.009696)
		(width 0.1143)
		(layer "In11.Cu")
		(net "GMI_CPU1_G3_CPU0_G1_TX_DP<14>")
	)
	(segment
		(start 126.56947 -219.08135)
		(end 146.974814 -202.350116)
		(width 0.14224)
		(layer "In11.Cu")
		(net "GMI_CPU1_G3_CPU0_G1_TX_DP<14>")
	)
	(segment
		(start 158.658814 -194.20205)
		(end 158.703518 -194.206622)
		(width 0.14224)
		(layer "In11.Cu")
		(net "GMI_CPU1_G3_CPU0_G1_TX_DP<14>")
	)
	(segment
		(start 345.34475 -232.015284)
		(end 345.34602 -232.016046)
		(width 0.1143)
		(layer "In11.Cu")
		(net "GMI_CPU1_G3_CPU0_G1_TX_DP<14>")
	)
	(segment
		(start 345.371674 -231.017064)
		(end 345.29903 -231.059482)
		(width 0.1143)
		(layer "In11.Cu")
		(net "GMI_CPU1_G3_CPU0_G1_TX_DP<14>")
	)
	(segment
		(start 125.687582 -232.821734)
		(end 125.726698 -232.798874)
		(width 0.1143)
		(layer "In11.Cu")
		(net "GMI_CPU1_G3_CPU0_G1_TX_DP<14>")
	)
	(segment
		(start 125.500384 -221.804484)
		(end 125.500384 -221.458028)
		(width 0.1143)
		(layer "In11.Cu")
		(net "GMI_CPU1_G3_CPU0_G1_TX_DP<14>")
	)
	(segment
		(start 125.657102 -223.119696)
		(end 125.687582 -223.101916)
		(width 0.1143)
		(layer "In11.Cu")
		(net "GMI_CPU1_G3_CPU0_G1_TX_DP<14>")
	)
	(segment
		(start 126.157736 -231.036876)
		(end 126.124208 -231.017318)
		(width 0.1143)
		(layer "In11.Cu")
		(net "GMI_CPU1_G3_CPU0_G1_TX_DP<14>")
	)
	(segment
		(start 345.33713 -232.010966)
		(end 345.338146 -232.011474)
		(width 0.1143)
		(layer "In11.Cu")
		(net "GMI_CPU1_G3_CPU0_G1_TX_DP<14>")
	)
	(segment
		(start 345.126056 -219.322142)
		(end 345.954858 -220.716348)
		(width 0.14224)
		(layer "In11.Cu")
		(net "GMI_CPU1_G3_CPU0_G1_TX_DP<14>")
	)
	(segment
		(start 345.83878 -228.589078)
		(end 345.769184 -228.629718)
		(width 0.1143)
		(layer "In11.Cu")
		(net "GMI_CPU1_G3_CPU0_G1_TX_DP<14>")
	)
	(segment
		(start 345.988894 -233.07421)
		(end 345.919044 -233.14406)
		(width 0.1143)
		(layer "In11.Cu")
		(net "GMI_CPU1_G3_CPU0_G1_TX_DP<14>")
	)
	(segment
		(start 303.7332 -190.391796)
		(end 308.646068 -190.391796)
		(width 0.14224)
		(layer "In11.Cu")
		(net "GMI_CPU1_G3_CPU0_G1_TX_DP<14>")
	)
	(segment
		(start 125.541024 -221.203012)
		(end 125.541024 -221.174564)
		(width 0.1143)
		(layer "In11.Cu")
		(net "GMI_CPU1_G3_CPU0_G1_TX_DP<14>")
	)
	(segment
		(start 162.630612 -190.480188)
		(end 207.257142 -190.291212)
		(width 0.14224)
		(layer "In11.Cu")
		(net "GMI_CPU1_G3_CPU0_G1_TX_DP<14>")
	)
	(segment
		(start 161.691066 -191.251078)
		(end 162.630612 -190.480188)
		(width 0.14224)
		(layer "In11.Cu")
		(net "GMI_CPU1_G3_CPU0_G1_TX_DP<14>")
	)
	(segment
		(start 239.94237 -200.053448)
		(end 251.423424 -192.01384)
		(width 0.14224)
		(layer "In11.Cu")
		(net "GMI_CPU1_G3_CPU0_G1_TX_DP<14>")
	)
	(segment
		(start 126.155704 -232.012998)
		(end 126.156974 -232.012236)
		(width 0.1143)
		(layer "In11.Cu")
		(net "GMI_CPU1_G3_CPU0_G1_TX_DP<14>")
	)
	(segment
		(start 346.000578 -221.452694)
		(end 345.995498 -221.457774)
		(width 0.1143)
		(layer "In11.Cu")
		(net "GMI_CPU1_G3_CPU0_G1_TX_DP<14>")
	)
	(segment
		(start 125.541024 -220.897958)
		(end 125.545596 -220.890084)
		(width 0.14224)
		(layer "In11.Cu")
		(net "GMI_CPU1_G3_CPU0_G1_TX_DP<14>")
	)
	(segment
		(start 345.338908 -232.011982)
		(end 345.341702 -232.013506)
		(width 0.1143)
		(layer "In11.Cu")
		(net "GMI_CPU1_G3_CPU0_G1_TX_DP<14>")
	)
	(segment
		(start 345.343988 -232.014776)
		(end 345.34475 -232.015284)
		(width 0.1143)
		(layer "In11.Cu")
		(net "GMI_CPU1_G3_CPU0_G1_TX_DP<14>")
	)
	(segment
		(start 125.576838 -233.144314)
		(end 125.506988 -233.074464)
		(width 0.1143)
		(layer "In11.Cu")
		(net "GMI_CPU1_G3_CPU0_G1_TX_DP<14>")
	)
	(segment
		(start 156.766006 -195.617846)
		(end 156.765752 -195.617592)
		(width 0.14224)
		(layer "In11.Cu")
		(net "GMI_CPU1_G3_CPU0_G1_TX_DP<14>")
	)
	(segment
		(start 125.687582 -229.581964)
		(end 125.726698 -229.559104)
		(width 0.1143)
		(layer "In11.Cu")
		(net "GMI_CPU1_G3_CPU0_G1_TX_DP<14>")
	)
	(segment
		(start 146.974814 -202.350116)
		(end 149.48027 -201.590656)
		(width 0.14224)
		(layer "In11.Cu")
		(net "GMI_CPU1_G3_CPU0_G1_TX_DP<14>")
	)
	(segment
		(start 155.54452 -196.796406)
		(end 155.56357 -196.603366)
		(width 0.14224)
		(layer "In11.Cu")
		(net "GMI_CPU1_G3_CPU0_G1_TX_DP<14>")
	)
	(segment
		(start 345.305888 -231.992678)
		(end 345.30665 -231.993186)
		(width 0.1143)
		(layer "In11.Cu")
		(net "GMI_CPU1_G3_CPU0_G1_TX_DP<14>")
	)
	(segment
		(start 251.423424 -192.01384)
		(end 262.765794 -190.013844)
		(width 0.14224)
		(layer "In11.Cu")
		(net "GMI_CPU1_G3_CPU0_G1_TX_DP<14>")
	)
	(segment
		(start 345.769184 -227.938838)
		(end 345.83878 -227.979478)
		(width 0.1143)
		(layer "In11.Cu")
		(net "GMI_CPU1_G3_CPU0_G1_TX_DP<14>")
	)
	(segment
		(start 345.34602 -232.016046)
		(end 345.34856 -232.017316)
		(width 0.1143)
		(layer "In11.Cu")
		(net "GMI_CPU1_G3_CPU0_G1_TX_DP<14>")
	)
	(segment
		(start 154.342084 -197.78218)
		(end 154.672284 -197.511416)
		(width 0.14224)
		(layer "In11.Cu")
		(net "GMI_CPU1_G3_CPU0_G1_TX_DP<14>")
	)
	(segment
		(start 125.545596 -220.88983)
		(end 126.56947 -219.08135)
		(width 0.14224)
		(layer "In11.Cu")
		(net "GMI_CPU1_G3_CPU0_G1_TX_DP<14>")
	)
	(segment
		(start 154.149044 -197.76313)
		(end 154.342084 -197.78218)
		(width 0.14224)
		(layer "In11.Cu")
		(net "GMI_CPU1_G3_CPU0_G1_TX_DP<14>")
	)
	(segment
		(start 207.257142 -190.291212)
		(end 210.794092 -190.915544)
		(width 0.14224)
		(layer "In11.Cu")
		(net "GMI_CPU1_G3_CPU0_G1_TX_DP<14>")
	)
	(segment
		(start 155.02128 -197.047866)
		(end 155.21432 -197.06717)
		(width 0.14224)
		(layer "In11.Cu")
		(net "GMI_CPU1_G3_CPU0_G1_TX_DP<14>")
	)
	(segment
		(start 160.44799 -192.776348)
		(end 160.77819 -192.505584)
		(width 0.14224)
		(layer "In11.Cu")
		(net "GMI_CPU1_G3_CPU0_G1_TX_DP<14>")
	)
	(segment
		(start 345.34856 -232.017316)
		(end 345.369896 -232.029762)
		(width 0.1143)
		(layer "In11.Cu")
		(net "GMI_CPU1_G3_CPU0_G1_TX_DP<14>")
	)
	(segment
		(start 125.724158 -230.248206)
		(end 125.657102 -230.20909)
		(width 0.1143)
		(layer "In11.Cu")
		(net "GMI_CPU1_G3_CPU0_G1_TX_DP<14>")
	)
	(segment
		(start 125.657102 -227.979732)
		(end 125.687582 -227.961952)
		(width 0.1143)
		(layer "In11.Cu")
		(net "GMI_CPU1_G3_CPU0_G1_TX_DP<14>")
	)
	(segment
		(start 156.086556 -196.351906)
		(end 156.416756 -196.081142)
		(width 0.14224)
		(layer "In11.Cu")
		(net "GMI_CPU1_G3_CPU0_G1_TX_DP<14>")
	)
	(segment
		(start 345.808046 -222.12681)
		(end 345.770454 -222.148654)
		(width 0.1143)
		(layer "In11.Cu")
		(net "GMI_CPU1_G3_CPU0_G1_TX_DP<14>")
	)
	(segment
		(start 345.769184 -229.55885)
		(end 345.8083 -229.58171)
		(width 0.1143)
		(layer "In11.Cu")
		(net "GMI_CPU1_G3_CPU0_G1_TX_DP<14>")
	)
	(segment
		(start 345.83878 -226.969066)
		(end 345.769184 -227.009706)
		(width 0.1143)
		(layer "In11.Cu")
		(net "GMI_CPU1_G3_CPU0_G1_TX_DP<14>")
	)
	(segment
		(start 308.646068 -190.391796)
		(end 317.09868 -196.341746)
		(width 0.14224)
		(layer "In11.Cu")
		(net "GMI_CPU1_G3_CPU0_G1_TX_DP<14>")
	)
	(segment
		(start 125.725428 -222.148908)
		(end 125.687836 -222.127064)
		(width 0.1143)
		(layer "In11.Cu")
		(net "GMI_CPU1_G3_CPU0_G1_TX_DP<14>")
	)
	(segment
		(start 125.495304 -221.452948)
		(end 125.495304 -221.248732)
		(width 0.1143)
		(layer "In11.Cu")
		(net "GMI_CPU1_G3_CPU0_G1_TX_DP<14>")
	)
	(segment
		(start 157.288992 -195.366132)
		(end 157.308042 -195.173092)
		(width 0.14224)
		(layer "In11.Cu")
		(net "GMI_CPU1_G3_CPU0_G1_TX_DP<14>")
	)
	(segment
		(start 125.687582 -226.34194)
		(end 125.726698 -226.31908)
		(width 0.1143)
		(layer "In11.Cu")
		(net "GMI_CPU1_G3_CPU0_G1_TX_DP<14>")
	)
	(segment
		(start 125.657102 -232.839514)
		(end 125.687582 -232.821734)
		(width 0.1143)
		(layer "In11.Cu")
		(net "GMI_CPU1_G3_CPU0_G1_TX_DP<14>")
	)
	(segment
		(start 125.726698 -228.629972)
		(end 125.687582 -228.607112)
		(width 0.1143)
		(layer "In11.Cu")
		(net "GMI_CPU1_G3_CPU0_G1_TX_DP<14>")
	)
	(segment
		(start 126.196852 -231.059736)
		(end 126.157736 -231.036876)
		(width 0.1143)
		(layer "In11.Cu")
		(net "GMI_CPU1_G3_CPU0_G1_TX_DP<14>")
	)
	(segment
		(start 160.79724 -192.312544)
		(end 161.377884 -191.836294)
		(width 0.14224)
		(layer "In11.Cu")
		(net "GMI_CPU1_G3_CPU0_G1_TX_DP<14>")
	)
	(segment
		(start 156.958792 -195.636896)
		(end 157.288992 -195.366132)
		(width 0.14224)
		(layer "In11.Cu")
		(net "GMI_CPU1_G3_CPU0_G1_TX_DP<14>")
	)
	(segment
		(start 210.794092 -190.915544)
		(end 233.006646 -200.115678)
		(width 0.14224)
		(layer "In11.Cu")
		(net "GMI_CPU1_G3_CPU0_G1_TX_DP<14>")
	)
	(segment
		(start 345.30665 -231.993186)
		(end 345.33713 -232.010966)
		(width 0.1143)
		(layer "In11.Cu")
		(net "GMI_CPU1_G3_CPU0_G1_TX_DP<14>")
	)
	(segment
		(start 156.435806 -195.888356)
		(end 156.766006 -195.617846)
		(width 0.14224)
		(layer "In11.Cu")
		(net "GMI_CPU1_G3_CPU0_G1_TX_DP<14>")
	)
	(segment
		(start 233.006646 -200.115678)
		(end 236.299756 -200.696068)
		(width 0.14224)
		(layer "In11.Cu")
		(net "GMI_CPU1_G3_CPU0_G1_TX_DP<14>")
	)
	(segment
		(start 125.687582 -226.9871)
		(end 125.657102 -226.96932)
		(width 0.1143)
		(layer "In11.Cu")
		(net "GMI_CPU1_G3_CPU0_G1_TX_DP<14>")
	)
	(segment
		(start 345.83878 -223.729042)
		(end 345.769184 -223.769682)
		(width 0.1143)
		(layer "In11.Cu")
		(net "GMI_CPU1_G3_CPU0_G1_TX_DP<14>")
	)
	(segment
		(start 125.657102 -226.35972)
		(end 125.687582 -226.34194)
		(width 0.1143)
		(layer "In11.Cu")
		(net "GMI_CPU1_G3_CPU0_G1_TX_DP<14>")
	)
	(segment
		(start 125.687582 -224.721928)
		(end 125.726698 -224.699068)
		(width 0.1143)
		(layer "In11.Cu")
		(net "GMI_CPU1_G3_CPU0_G1_TX_DP<14>")
	)
	(segment
		(start 345.954858 -221.202758)
		(end 346.000578 -221.248478)
		(width 0.1143)
		(layer "In11.Cu")
		(net "GMI_CPU1_G3_CPU0_G1_TX_DP<14>")
	)
	(segment
		(start 158.703518 -194.206622)
		(end 159.033718 -193.935604)
		(width 0.14224)
		(layer "In11.Cu")
		(net "GMI_CPU1_G3_CPU0_G1_TX_DP<14>")
	)
	(segment
		(start 159.052768 -193.742818)
		(end 159.382714 -193.472308)
		(width 0.14224)
		(layer "In11.Cu")
		(net "GMI_CPU1_G3_CPU0_G1_TX_DP<14>")
	)
	(segment
		(start 345.83878 -225.349054)
		(end 345.769184 -225.389694)
		(width 0.1143)
		(layer "In11.Cu")
		(net "GMI_CPU1_G3_CPU0_G1_TX_DP<14>")
	)
	(segment
		(start 125.726698 -227.00996)
		(end 125.687582 -226.9871)
		(width 0.1143)
		(layer "In11.Cu")
		(net "GMI_CPU1_G3_CPU0_G1_TX_DP<14>")
	)
	(segment
		(start 345.919044 -233.14406)
		(end 345.621102 -233.14406)
		(width 0.1143)
		(layer "In11.Cu")
		(net "GMI_CPU1_G3_CPU0_G1_TX_DP<14>")
	)
	(segment
		(start 345.342464 -232.014014)
		(end 345.343988 -232.014776)
		(width 0.1143)
		(layer "In11.Cu")
		(net "GMI_CPU1_G3_CPU0_G1_TX_DP<14>")
	)
	(segment
		(start 160.25495 -192.757044)
		(end 160.44799 -192.776348)
		(width 0.14224)
		(layer "In11.Cu")
		(net "GMI_CPU1_G3_CPU0_G1_TX_DP<14>")
	)
	(segment
		(start 156.765752 -195.617592)
		(end 156.958792 -195.636896)
		(width 0.14224)
		(layer "In11.Cu")
		(net "GMI_CPU1_G3_CPU0_G1_TX_DP<14>")
	)
	(segment
		(start 159.033718 -193.935604)
		(end 159.052768 -193.742818)
		(width 0.14224)
		(layer "In11.Cu")
		(net "GMI_CPU1_G3_CPU0_G1_TX_DP<14>")
	)
	(segment
		(start 346.000578 -221.248478)
		(end 346.000578 -221.452694)
		(width 0.1143)
		(layer "In11.Cu")
		(net "GMI_CPU1_G3_CPU0_G1_TX_DP<14>")
	)
	(segment
		(start 125.65507 -229.60076)
		(end 125.687582 -229.581964)
		(width 0.1143)
		(layer "In11.Cu")
		(net "GMI_CPU1_G3_CPU0_G1_TX_DP<14>")
	)
	(segment
		(start 157.308296 -195.173092)
		(end 157.638242 -194.902582)
		(width 0.14224)
		(layer "In11.Cu")
		(net "GMI_CPU1_G3_CPU0_G1_TX_DP<14>")
	)
	(segment
		(start 160.77819 -192.505584)
		(end 160.79724 -192.312544)
		(width 0.14224)
		(layer "In11.Cu")
		(net "GMI_CPU1_G3_CPU0_G1_TX_DP<14>")
	)
	(segment
		(start 161.377884 -191.836294)
		(end 161.691066 -191.251078)
		(width 0.14224)
		(layer "In11.Cu")
		(net "GMI_CPU1_G3_CPU0_G1_TX_DP<14>")
	)
	(segment
		(start 157.638242 -194.902582)
		(end 157.831282 -194.921886)
		(width 0.14224)
		(layer "In11.Cu")
		(net "GMI_CPU1_G3_CPU0_G1_TX_DP<14>")
	)
	(segment
		(start 345.29903 -231.988614)
		(end 345.305888 -231.992678)
		(width 0.1143)
		(layer "In11.Cu")
		(net "GMI_CPU1_G3_CPU0_G1_TX_DP<14>")
	)
	(segment
		(start 126.161292 -232.009696)
		(end 126.166118 -232.006902)
		(width 0.1143)
		(layer "In11.Cu")
		(net "GMI_CPU1_G3_CPU0_G1_TX_DP<14>")
	)
	(segment
		(start 154.672284 -197.511416)
		(end 154.691334 -197.318376)
		(width 0.14224)
		(layer "In11.Cu")
		(net "GMI_CPU1_G3_CPU0_G1_TX_DP<14>")
	)
	(segment
		(start 345.769184 -223.078802)
		(end 345.83878 -223.119442)
		(width 0.1143)
		(layer "In11.Cu")
		(net "GMI_CPU1_G3_CPU0_G1_TX_DP<14>")
	)
	(segment
		(start 345.83878 -230.208836)
		(end 345.771724 -230.247952)
		(width 0.1143)
		(layer "In11.Cu")
		(net "GMI_CPU1_G3_CPU0_G1_TX_DP<14>")
	)
	(segment
		(start 125.687836 -222.127064)
		(end 125.657356 -222.109284)
		(width 0.1143)
		(layer "In11.Cu")
		(net "GMI_CPU1_G3_CPU0_G1_TX_DP<14>")
	)
	(segment
		(start 125.545596 -220.890084)
		(end 125.545596 -220.88983)
		(width 0.14224)
		(layer "In11.Cu")
		(net "GMI_CPU1_G3_CPU0_G1_TX_DP<14>")
	)
	(segment
		(start 345.338146 -232.011474)
		(end 345.338908 -232.011982)
		(width 0.1143)
		(layer "In11.Cu")
		(net "GMI_CPU1_G3_CPU0_G1_TX_DP<14>")
	)
	(segment
		(start 157.308042 -195.173092)
		(end 157.308296 -195.173092)
		(width 0.14224)
		(layer "In11.Cu")
		(net "GMI_CPU1_G3_CPU0_G1_TX_DP<14>")
	)
	(segment
		(start 125.687582 -228.607112)
		(end 125.657102 -228.589332)
		(width 0.1143)
		(layer "In11.Cu")
		(net "GMI_CPU1_G3_CPU0_G1_TX_DP<14>")
	)
	(segment
		(start 345.8083 -229.58171)
		(end 345.840812 -229.600506)
		(width 0.1143)
		(layer "In11.Cu")
		(net "GMI_CPU1_G3_CPU0_G1_TX_DP<14>")
	)
	(arc
		(start 125.726698 -229.559104)
		(mid 125.970025 -229.094538)
		(end 125.726698 -228.629972)
		(width 0.1143)
		(layer "In11.Cu")
		(net "GMI_CPU1_G3_CPU0_G1_TX_DP<14>")
	)
	(arc
		(start 345.525852 -230.714296)
		(mid 345.48509 -230.88418)
		(end 345.371674 -231.017064)
		(width 0.1143)
		(layer "In11.Cu")
		(net "GMI_CPU1_G3_CPU0_G1_TX_DP<14>")
	)
	(arc
		(start 345.769184 -225.389694)
		(mid 345.525857 -225.85426)
		(end 345.769184 -226.318826)
		(width 0.1143)
		(layer "In11.Cu")
		(net "GMI_CPU1_G3_CPU0_G1_TX_DP<14>")
	)
	(arc
		(start 345.29903 -231.059482)
		(mid 345.055703 -231.524048)
		(end 345.29903 -231.988614)
		(width 0.1143)
		(layer "In11.Cu")
		(net "GMI_CPU1_G3_CPU0_G1_TX_DP<14>")
	)
	(arc
		(start 125.657102 -225.349308)
		(mid 125.500125 -225.044508)
		(end 125.657102 -224.739708)
		(width 0.1143)
		(layer "In11.Cu")
		(net "GMI_CPU1_G3_CPU0_G1_TX_DP<14>")
	)
	(arc
		(start 125.657102 -230.20909)
		(mid 125.541675 -230.075714)
		(end 125.50013 -229.90429)
		(width 0.1143)
		(layer "In11.Cu")
		(net "GMI_CPU1_G3_CPU0_G1_TX_DP<14>")
	)
	(arc
		(start 345.83878 -227.979478)
		(mid 345.995757 -228.284278)
		(end 345.83878 -228.589078)
		(width 0.1143)
		(layer "In11.Cu")
		(net "GMI_CPU1_G3_CPU0_G1_TX_DP<14>")
	)
	(arc
		(start 345.771724 -230.247952)
		(mid 345.591072 -230.450697)
		(end 345.525852 -230.714296)
		(width 0.1143)
		(layer "In11.Cu")
		(net "GMI_CPU1_G3_CPU0_G1_TX_DP<14>")
	)
	(arc
		(start 125.726698 -227.939092)
		(mid 125.970025 -227.474526)
		(end 125.726698 -227.00996)
		(width 0.1143)
		(layer "In11.Cu")
		(net "GMI_CPU1_G3_CPU0_G1_TX_DP<14>")
	)
	(arc
		(start 125.97003 -232.334308)
		(mid 126.011285 -232.163337)
		(end 126.125986 -232.030016)
		(width 0.1143)
		(layer "In11.Cu")
		(net "GMI_CPU1_G3_CPU0_G1_TX_DP<14>")
	)
	(arc
		(start 125.506988 -233.074464)
		(mid 125.559405 -232.942533)
		(end 125.657102 -232.839514)
		(width 0.1143)
		(layer "In11.Cu")
		(net "GMI_CPU1_G3_CPU0_G1_TX_DP<14>")
	)
	(arc
		(start 125.726698 -223.079056)
		(mid 125.905511 -222.876706)
		(end 125.97003 -222.61449)
		(width 0.1143)
		(layer "In11.Cu")
		(net "GMI_CPU1_G3_CPU0_G1_TX_DP<14>")
	)
	(arc
		(start 345.995498 -221.80423)
		(mid 345.953949 -221.975652)
		(end 345.838526 -222.10903)
		(width 0.1143)
		(layer "In11.Cu")
		(net "GMI_CPU1_G3_CPU0_G1_TX_DP<14>")
	)
	(arc
		(start 125.657102 -226.96932)
		(mid 125.500125 -226.66452)
		(end 125.657102 -226.35972)
		(width 0.1143)
		(layer "In11.Cu")
		(net "GMI_CPU1_G3_CPU0_G1_TX_DP<14>")
	)
	(arc
		(start 345.369896 -232.029762)
		(mid 345.484572 -232.163096)
		(end 345.525852 -232.334054)
		(width 0.1143)
		(layer "In11.Cu")
		(net "GMI_CPU1_G3_CPU0_G1_TX_DP<14>")
	)
	(arc
		(start 125.50013 -229.90429)
		(mid 125.541096 -229.733884)
		(end 125.65507 -229.60076)
		(width 0.1143)
		(layer "In11.Cu")
		(net "GMI_CPU1_G3_CPU0_G1_TX_DP<14>")
	)
	(arc
		(start 345.83878 -224.739454)
		(mid 345.995757 -225.044254)
		(end 345.83878 -225.349054)
		(width 0.1143)
		(layer "In11.Cu")
		(net "GMI_CPU1_G3_CPU0_G1_TX_DP<14>")
	)
	(arc
		(start 345.83878 -226.359466)
		(mid 345.995757 -226.664266)
		(end 345.83878 -226.969066)
		(width 0.1143)
		(layer "In11.Cu")
		(net "GMI_CPU1_G3_CPU0_G1_TX_DP<14>")
	)
	(arc
		(start 345.769184 -227.009706)
		(mid 345.525857 -227.474272)
		(end 345.769184 -227.938838)
		(width 0.1143)
		(layer "In11.Cu")
		(net "GMI_CPU1_G3_CPU0_G1_TX_DP<14>")
	)
	(arc
		(start 345.769184 -228.629718)
		(mid 345.525857 -229.094284)
		(end 345.769184 -229.55885)
		(width 0.1143)
		(layer "In11.Cu")
		(net "GMI_CPU1_G3_CPU0_G1_TX_DP<14>")
	)
	(arc
		(start 125.657102 -223.729296)
		(mid 125.500125 -223.424496)
		(end 125.657102 -223.119696)
		(width 0.1143)
		(layer "In11.Cu")
		(net "GMI_CPU1_G3_CPU0_G1_TX_DP<14>")
	)
	(arc
		(start 126.124208 -231.017318)
		(mid 126.010801 -230.884429)
		(end 125.97003 -230.71455)
		(width 0.1143)
		(layer "In11.Cu")
		(net "GMI_CPU1_G3_CPU0_G1_TX_DP<14>")
	)
	(arc
		(start 345.83878 -232.83926)
		(mid 345.936545 -232.942236)
		(end 345.988894 -233.07421)
		(width 0.1143)
		(layer "In11.Cu")
		(net "GMI_CPU1_G3_CPU0_G1_TX_DP<14>")
	)
	(arc
		(start 345.995752 -229.904036)
		(mid 345.954203 -230.075458)
		(end 345.83878 -230.208836)
		(width 0.1143)
		(layer "In11.Cu")
		(net "GMI_CPU1_G3_CPU0_G1_TX_DP<14>")
	)
	(arc
		(start 125.726698 -226.31908)
		(mid 125.970025 -225.854514)
		(end 125.726698 -225.389948)
		(width 0.1143)
		(layer "In11.Cu")
		(net "GMI_CPU1_G3_CPU0_G1_TX_DP<14>")
	)
	(arc
		(start 345.840812 -229.600506)
		(mid 345.954741 -229.733653)
		(end 345.995752 -229.904036)
		(width 0.1143)
		(layer "In11.Cu")
		(net "GMI_CPU1_G3_CPU0_G1_TX_DP<14>")
	)
	(arc
		(start 345.525852 -232.334054)
		(mid 345.590367 -232.596273)
		(end 345.769184 -232.79862)
		(width 0.1143)
		(layer "In11.Cu")
		(net "GMI_CPU1_G3_CPU0_G1_TX_DP<14>")
	)
	(arc
		(start 126.196852 -231.988868)
		(mid 126.440179 -231.524302)
		(end 126.196852 -231.059736)
		(width 0.1143)
		(layer "In11.Cu")
		(net "GMI_CPU1_G3_CPU0_G1_TX_DP<14>")
	)
	(arc
		(start 125.657102 -228.589332)
		(mid 125.500125 -228.284532)
		(end 125.657102 -227.979732)
		(width 0.1143)
		(layer "In11.Cu")
		(net "GMI_CPU1_G3_CPU0_G1_TX_DP<14>")
	)
	(arc
		(start 125.726698 -224.699068)
		(mid 125.970025 -224.234502)
		(end 125.726698 -223.769936)
		(width 0.1143)
		(layer "In11.Cu")
		(net "GMI_CPU1_G3_CPU0_G1_TX_DP<14>")
	)
	(arc
		(start 125.97003 -222.61449)
		(mid 125.905158 -222.351527)
		(end 125.725428 -222.148908)
		(width 0.1143)
		(layer "In11.Cu")
		(net "GMI_CPU1_G3_CPU0_G1_TX_DP<14>")
	)
	(arc
		(start 345.525852 -222.614236)
		(mid 345.590367 -222.876455)
		(end 345.769184 -223.078802)
		(width 0.1143)
		(layer "In11.Cu")
		(net "GMI_CPU1_G3_CPU0_G1_TX_DP<14>")
	)
	(arc
		(start 125.97003 -230.71455)
		(mid 125.904794 -230.450959)
		(end 125.724158 -230.248206)
		(width 0.1143)
		(layer "In11.Cu")
		(net "GMI_CPU1_G3_CPU0_G1_TX_DP<14>")
	)
	(arc
		(start 345.770454 -222.148654)
		(mid 345.590725 -222.351274)
		(end 345.525852 -222.614236)
		(width 0.1143)
		(layer "In11.Cu")
		(net "GMI_CPU1_G3_CPU0_G1_TX_DP<14>")
	)
	(arc
		(start 345.769184 -223.769682)
		(mid 345.525857 -224.234248)
		(end 345.769184 -224.698814)
		(width 0.1143)
		(layer "In11.Cu")
		(net "GMI_CPU1_G3_CPU0_G1_TX_DP<14>")
	)
	(arc
		(start 345.83878 -223.119442)
		(mid 345.995757 -223.424242)
		(end 345.83878 -223.729042)
		(width 0.1143)
		(layer "In11.Cu")
		(net "GMI_CPU1_G3_CPU0_G1_TX_DP<14>")
	)
	(arc
		(start 125.657356 -222.109284)
		(mid 125.541929 -221.975908)
		(end 125.500384 -221.804484)
		(width 0.1143)
		(layer "In11.Cu")
		(net "GMI_CPU1_G3_CPU0_G1_TX_DP<14>")
	)
	(arc
		(start 125.726698 -232.798874)
		(mid 125.905511 -232.596524)
		(end 125.97003 -232.334308)
		(width 0.1143)
		(layer "In11.Cu")
		(net "GMI_CPU1_G3_CPU0_G1_TX_DP<14>")
	)
	(segment
		(start 125.407928 -236.650276)
		(end 125.87478 -236.384338)
		(width 0.12954)
		(layer "F.Cu")
		(net "GMI_CPU1_G3_CPU0_G1_TX_DP<13>")
	)
	(segment
		(start 346.087954 -236.650022)
		(end 345.621102 -236.384084)
		(width 0.12954)
		(layer "F.Cu")
		(net "GMI_CPU1_G3_CPU0_G1_TX_DP<13>")
	)
	(segment
		(start 124.714254 -229.601522)
		(end 124.784104 -229.560882)
		(width 0.1143)
		(layer "In11.Cu")
		(net "GMI_CPU1_G3_CPU0_G1_TX_DP<13>")
	)
	(segment
		(start 346.752164 -227.963984)
		(end 346.754958 -227.965508)
		(width 0.1143)
		(layer "In11.Cu")
		(net "GMI_CPU1_G3_CPU0_G1_TX_DP<13>")
	)
	(segment
		(start 146.502374 -201.49566)
		(end 148.716492 -200.824846)
		(width 0.14224)
		(layer "In11.Cu")
		(net "GMI_CPU1_G3_CPU0_G1_TX_DP<13>")
	)
	(segment
		(start 154.759406 -196.047614)
		(end 154.778456 -195.854574)
		(width 0.14224)
		(layer "In11.Cu")
		(net "GMI_CPU1_G3_CPU0_G1_TX_DP<13>")
	)
	(segment
		(start 346.245942 -235.915454)
		(end 346.239084 -235.919518)
		(width 0.1143)
		(layer "In11.Cu")
		(net "GMI_CPU1_G3_CPU0_G1_TX_DP<13>")
	)
	(segment
		(start 346.732352 -235.095796)
		(end 346.731336 -235.096304)
		(width 0.1143)
		(layer "In11.Cu")
		(net "GMI_CPU1_G3_CPU0_G1_TX_DP<13>")
	)
	(segment
		(start 346.711778 -234.42041)
		(end 346.7481 -234.441492)
		(width 0.1143)
		(layer "In11.Cu")
		(net "GMI_CPU1_G3_CPU0_G1_TX_DP<13>")
	)
	(segment
		(start 156.173678 -194.88785)
		(end 156.503878 -194.617086)
		(width 0.14224)
		(layer "In11.Cu")
		(net "GMI_CPU1_G3_CPU0_G1_TX_DP<13>")
	)
	(segment
		(start 233.932476 -199.32396)
		(end 236.30128 -199.741536)
		(width 0.14224)
		(layer "In11.Cu")
		(net "GMI_CPU1_G3_CPU0_G1_TX_DP<13>")
	)
	(segment
		(start 153.88717 -196.762624)
		(end 153.90622 -196.569584)
		(width 0.14224)
		(layer "In11.Cu")
		(net "GMI_CPU1_G3_CPU0_G1_TX_DP<13>")
	)
	(segment
		(start 125.217682 -235.896912)
		(end 125.21692 -235.896404)
		(width 0.1143)
		(layer "In11.Cu")
		(net "GMI_CPU1_G3_CPU0_G1_TX_DP<13>")
	)
	(segment
		(start 124.748036 -227.961698)
		(end 124.749306 -227.960936)
		(width 0.1143)
		(layer "In11.Cu")
		(net "GMI_CPU1_G3_CPU0_G1_TX_DP<13>")
	)
	(segment
		(start 125.87478 -236.384338)
		(end 125.576838 -236.384338)
		(width 0.1143)
		(layer "In11.Cu")
		(net "GMI_CPU1_G3_CPU0_G1_TX_DP<13>")
	)
	(segment
		(start 124.560076 -221.462854)
		(end 124.55017 -221.452948)
		(width 0.1143)
		(layer "In11.Cu")
		(net "GMI_CPU1_G3_CPU0_G1_TX_DP<13>")
	)
	(segment
		(start 125.24994 -235.915708)
		(end 125.249178 -235.9152)
		(width 0.1143)
		(layer "In11.Cu")
		(net "GMI_CPU1_G3_CPU0_G1_TX_DP<13>")
	)
	(segment
		(start 346.899992 -220.481652)
		(end 346.899992 -221.17431)
		(width 0.14224)
		(layer "In11.Cu")
		(net "GMI_CPU1_G3_CPU0_G1_TX_DP<13>")
	)
	(segment
		(start 303.7332 -189.451488)
		(end 309.008272 -189.451488)
		(width 0.14224)
		(layer "In11.Cu")
		(net "GMI_CPU1_G3_CPU0_G1_TX_DP<13>")
	)
	(segment
		(start 124.716032 -224.740216)
		(end 124.747782 -224.721928)
		(width 0.1143)
		(layer "In11.Cu")
		(net "GMI_CPU1_G3_CPU0_G1_TX_DP<13>")
	)
	(segment
		(start 346.751402 -227.963476)
		(end 346.752164 -227.963984)
		(width 0.1143)
		(layer "In11.Cu")
		(net "GMI_CPU1_G3_CPU0_G1_TX_DP<13>")
	)
	(segment
		(start 124.560076 -221.816676)
		(end 124.560076 -221.462854)
		(width 0.1143)
		(layer "In11.Cu")
		(net "GMI_CPU1_G3_CPU0_G1_TX_DP<13>")
	)
	(segment
		(start 124.747274 -227.962206)
		(end 124.748036 -227.961698)
		(width 0.1143)
		(layer "In11.Cu")
		(net "GMI_CPU1_G3_CPU0_G1_TX_DP<13>")
	)
	(segment
		(start 124.59589 -221.203012)
		(end 124.59589 -221.174564)
		(width 0.1143)
		(layer "In11.Cu")
		(net "GMI_CPU1_G3_CPU0_G1_TX_DP<13>")
	)
	(segment
		(start 124.59589 -220.633544)
		(end 125.872748 -218.410282)
		(width 0.14224)
		(layer "In11.Cu")
		(net "GMI_CPU1_G3_CPU0_G1_TX_DP<13>")
	)
	(segment
		(start 346.77985 -233.448098)
		(end 346.711778 -233.487722)
		(width 0.1143)
		(layer "In11.Cu")
		(net "GMI_CPU1_G3_CPU0_G1_TX_DP<13>")
	)
	(segment
		(start 262.688832 -189.07252)
		(end 303.7332 -189.451488)
		(width 0.14224)
		(layer "In11.Cu")
		(net "GMI_CPU1_G3_CPU0_G1_TX_DP<13>")
	)
	(segment
		(start 346.945712 -221.452694)
		(end 346.935806 -221.4626)
		(width 0.1143)
		(layer "In11.Cu")
		(net "GMI_CPU1_G3_CPU0_G1_TX_DP<13>")
	)
	(segment
		(start 154.429206 -196.318378)
		(end 154.759406 -196.047614)
		(width 0.14224)
		(layer "In11.Cu")
		(net "GMI_CPU1_G3_CPU0_G1_TX_DP<13>")
	)
	(segment
		(start 159.992822 -191.75603)
		(end 160.011872 -191.56299)
		(width 0.14224)
		(layer "In11.Cu")
		(net "GMI_CPU1_G3_CPU0_G1_TX_DP<13>")
	)
	(segment
		(start 236.30128 -199.741536)
		(end 239.571784 -199.164702)
		(width 0.14224)
		(layer "In11.Cu")
		(net "GMI_CPU1_G3_CPU0_G1_TX_DP<13>")
	)
	(segment
		(start 346.724478 -235.100114)
		(end 346.719144 -235.103416)
		(width 0.1143)
		(layer "In11.Cu")
		(net "GMI_CPU1_G3_CPU0_G1_TX_DP<13>")
	)
	(segment
		(start 346.945712 -221.248478)
		(end 346.945712 -221.452694)
		(width 0.1143)
		(layer "In11.Cu")
		(net "GMI_CPU1_G3_CPU0_G1_TX_DP<13>")
	)
	(segment
		(start 124.716032 -234.460034)
		(end 124.747782 -234.441746)
		(width 0.1143)
		(layer "In11.Cu")
		(net "GMI_CPU1_G3_CPU0_G1_TX_DP<13>")
	)
	(segment
		(start 346.899992 -221.17431)
		(end 346.899992 -221.202758)
		(width 0.1143)
		(layer "In11.Cu")
		(net "GMI_CPU1_G3_CPU0_G1_TX_DP<13>")
	)
	(segment
		(start 346.731336 -235.096304)
		(end 346.730574 -235.096812)
		(width 0.1143)
		(layer "In11.Cu")
		(net "GMI_CPU1_G3_CPU0_G1_TX_DP<13>")
	)
	(segment
		(start 125.217682 -232.011728)
		(end 125.218698 -232.01122)
		(width 0.1143)
		(layer "In11.Cu")
		(net "GMI_CPU1_G3_CPU0_G1_TX_DP<13>")
	)
	(segment
		(start 346.719144 -235.103416)
		(end 346.71 -235.10875)
		(width 0.1143)
		(layer "In11.Cu")
		(net "GMI_CPU1_G3_CPU0_G1_TX_DP<13>")
	)
	(segment
		(start 346.77985 -235.068364)
		(end 346.741496 -235.090208)
		(width 0.1143)
		(layer "In11.Cu")
		(net "GMI_CPU1_G3_CPU0_G1_TX_DP<13>")
	)
	(segment
		(start 346.77985 -226.968558)
		(end 346.726764 -226.999292)
		(width 0.1143)
		(layer "In11.Cu")
		(net "GMI_CPU1_G3_CPU0_G1_TX_DP<13>")
	)
	(segment
		(start 125.217682 -231.036876)
		(end 125.184154 -231.017318)
		(width 0.1143)
		(layer "In11.Cu")
		(net "GMI_CPU1_G3_CPU0_G1_TX_DP<13>")
	)
	(segment
		(start 346.711778 -229.560628)
		(end 346.781628 -229.601268)
		(width 0.1143)
		(layer "In11.Cu")
		(net "GMI_CPU1_G3_CPU0_G1_TX_DP<13>")
	)
	(segment
		(start 157.376114 -193.901822)
		(end 157.395164 -193.708782)
		(width 0.14224)
		(layer "In11.Cu")
		(net "GMI_CPU1_G3_CPU0_G1_TX_DP<13>")
	)
	(segment
		(start 124.747528 -226.34448)
		(end 124.748544 -226.343972)
		(width 0.1143)
		(layer "In11.Cu")
		(net "GMI_CPU1_G3_CPU0_G1_TX_DP<13>")
	)
	(segment
		(start 346.77985 -225.348546)
		(end 346.711778 -225.387916)
		(width 0.1143)
		(layer "In11.Cu")
		(net "GMI_CPU1_G3_CPU0_G1_TX_DP<13>")
	)
	(segment
		(start 346.75191 -230.222044)
		(end 346.747084 -230.224838)
		(width 0.1143)
		(layer "In11.Cu")
		(net "GMI_CPU1_G3_CPU0_G1_TX_DP<13>")
	)
	(segment
		(start 309.008272 -189.451488)
		(end 318.140334 -195.887848)
		(width 0.14224)
		(layer "In11.Cu")
		(net "GMI_CPU1_G3_CPU0_G1_TX_DP<13>")
	)
	(segment
		(start 157.395164 -193.708782)
		(end 157.395164 -193.708274)
		(width 0.14224)
		(layer "In11.Cu")
		(net "GMI_CPU1_G3_CPU0_G1_TX_DP<13>")
	)
	(segment
		(start 239.571784 -199.164702)
		(end 251.05487 -191.124078)
		(width 0.14224)
		(layer "In11.Cu")
		(net "GMI_CPU1_G3_CPU0_G1_TX_DP<13>")
	)
	(segment
		(start 124.762768 -235.095542)
		(end 124.762768 -235.095288)
		(width 0.1143)
		(layer "In11.Cu")
		(net "GMI_CPU1_G3_CPU0_G1_TX_DP<13>")
	)
	(segment
		(start 125.214126 -235.895134)
		(end 125.213618 -235.89488)
		(width 0.1143)
		(layer "In11.Cu")
		(net "GMI_CPU1_G3_CPU0_G1_TX_DP<13>")
	)
	(segment
		(start 346.2782 -235.896658)
		(end 346.246704 -235.914946)
		(width 0.1143)
		(layer "In11.Cu")
		(net "GMI_CPU1_G3_CPU0_G1_TX_DP<13>")
	)
	(segment
		(start 155.980638 -194.8688)
		(end 156.173678 -194.88785)
		(width 0.14224)
		(layer "In11.Cu")
		(net "GMI_CPU1_G3_CPU0_G1_TX_DP<13>")
	)
	(segment
		(start 155.301442 -195.603114)
		(end 155.631642 -195.33235)
		(width 0.14224)
		(layer "In11.Cu")
		(net "GMI_CPU1_G3_CPU0_G1_TX_DP<13>")
	)
	(segment
		(start 124.748798 -230.225092)
		(end 124.743972 -230.222298)
		(width 0.1143)
		(layer "In11.Cu")
		(net "GMI_CPU1_G3_CPU0_G1_TX_DP<13>")
	)
	(segment
		(start 124.760482 -227.954332)
		(end 124.768102 -227.950014)
		(width 0.1143)
		(layer "In11.Cu")
		(net "GMI_CPU1_G3_CPU0_G1_TX_DP<13>")
	)
	(segment
		(start 157.91815 -193.457322)
		(end 158.24835 -193.186558)
		(width 0.14224)
		(layer "In11.Cu")
		(net "GMI_CPU1_G3_CPU0_G1_TX_DP<13>")
	)
	(segment
		(start 124.747782 -224.721928)
		(end 124.784104 -224.700846)
		(width 0.1143)
		(layer "In11.Cu")
		(net "GMI_CPU1_G3_CPU0_G1_TX_DP<13>")
	)
	(segment
		(start 346.27566 -232.00995)
		(end 346.277184 -232.010966)
		(width 0.1143)
		(layer "In11.Cu")
		(net "GMI_CPU1_G3_CPU0_G1_TX_DP<13>")
	)
	(segment
		(start 124.59589 -221.174564)
		(end 124.59589 -220.633544)
		(width 0.14224)
		(layer "In11.Cu")
		(net "GMI_CPU1_G3_CPU0_G1_TX_DP<13>")
	)
	(segment
		(start 160.855406 -190.70955)
		(end 162.27933 -189.541658)
		(width 0.14224)
		(layer "In11.Cu")
		(net "GMI_CPU1_G3_CPU0_G1_TX_DP<13>")
	)
	(segment
		(start 346.747846 -232.82275)
		(end 346.75064 -232.824274)
		(width 0.1143)
		(layer "In11.Cu")
		(net "GMI_CPU1_G3_CPU0_G1_TX_DP<13>")
	)
	(segment
		(start 346.727272 -235.09859)
		(end 346.724478 -235.100114)
		(width 0.1143)
		(layer "In11.Cu")
		(net "GMI_CPU1_G3_CPU0_G1_TX_DP<13>")
	)
	(segment
		(start 207.337406 -189.350396)
		(end 211.720684 -190.123318)
		(width 0.14224)
		(layer "In11.Cu")
		(net "GMI_CPU1_G3_CPU0_G1_TX_DP<13>")
	)
	(segment
		(start 148.716492 -200.824846)
		(end 153.363422 -197.014338)
		(width 0.14224)
		(layer "In11.Cu")
		(net "GMI_CPU1_G3_CPU0_G1_TX_DP<13>")
	)
	(segment
		(start 158.790386 -192.742058)
		(end 159.120586 -192.471294)
		(width 0.14224)
		(layer "In11.Cu")
		(net "GMI_CPU1_G3_CPU0_G1_TX_DP<13>")
	)
	(segment
		(start 125.256798 -231.059736)
		(end 125.217682 -231.036876)
		(width 0.1143)
		(layer "In11.Cu")
		(net "GMI_CPU1_G3_CPU0_G1_TX_DP<13>")
	)
	(segment
		(start 346.2782 -232.011474)
		(end 346.278962 -232.011982)
		(width 0.1143)
		(layer "In11.Cu")
		(net "GMI_CPU1_G3_CPU0_G1_TX_DP<13>")
	)
	(segment
		(start 124.748544 -228.605334)
		(end 124.747528 -228.604826)
		(width 0.1143)
		(layer "In11.Cu")
		(net "GMI_CPU1_G3_CPU0_G1_TX_DP<13>")
	)
	(segment
		(start 159.139636 -192.278254)
		(end 159.469582 -192.007744)
		(width 0.14224)
		(layer "In11.Cu")
		(net "GMI_CPU1_G3_CPU0_G1_TX_DP<13>")
	)
	(segment
		(start 157.045914 -194.172586)
		(end 157.376114 -193.901822)
		(width 0.14224)
		(layer "In11.Cu")
		(net "GMI_CPU1_G3_CPU0_G1_TX_DP<13>")
	)
	(segment
		(start 251.05487 -191.124078)
		(end 262.688832 -189.07252)
		(width 0.14224)
		(layer "In11.Cu")
		(net "GMI_CPU1_G3_CPU0_G1_TX_DP<13>")
	)
	(segment
		(start 124.748544 -223.745044)
		(end 124.747528 -223.744536)
		(width 0.1143)
		(layer "In11.Cu")
		(net "GMI_CPU1_G3_CPU0_G1_TX_DP<13>")
	)
	(segment
		(start 153.55697 -197.033388)
		(end 153.88717 -196.762624)
		(width 0.14224)
		(layer "In11.Cu")
		(net "GMI_CPU1_G3_CPU0_G1_TX_DP<13>")
	)
	(segment
		(start 125.218698 -232.01122)
		(end 125.220222 -232.010204)
		(width 0.1143)
		(layer "In11.Cu")
		(net "GMI_CPU1_G3_CPU0_G1_TX_DP<13>")
	)
	(segment
		(start 346.754958 -227.965508)
		(end 346.77985 -227.979986)
		(width 0.1143)
		(layer "In11.Cu")
		(net "GMI_CPU1_G3_CPU0_G1_TX_DP<13>")
	)
	(segment
		(start 346.748354 -228.604572)
		(end 346.747338 -228.60508)
		(width 0.1143)
		(layer "In11.Cu")
		(net "GMI_CPU1_G3_CPU0_G1_TX_DP<13>")
	)
	(segment
		(start 124.55017 -221.248732)
		(end 124.59589 -221.203012)
		(width 0.1143)
		(layer "In11.Cu")
		(net "GMI_CPU1_G3_CPU0_G1_TX_DP<13>")
	)
	(segment
		(start 125.21692 -232.012236)
		(end 125.217682 -232.011728)
		(width 0.1143)
		(layer "In11.Cu")
		(net "GMI_CPU1_G3_CPU0_G1_TX_DP<13>")
	)
	(segment
		(start 153.363422 -197.014338)
		(end 153.36393 -197.014338)
		(width 0.14224)
		(layer "In11.Cu")
		(net "GMI_CPU1_G3_CPU0_G1_TX_DP<13>")
	)
	(segment
		(start 157.72511 -193.438272)
		(end 157.91815 -193.457322)
		(width 0.14224)
		(layer "In11.Cu")
		(net "GMI_CPU1_G3_CPU0_G1_TX_DP<13>")
	)
	(segment
		(start 125.187964 -232.029)
		(end 125.21692 -232.012236)
		(width 0.1143)
		(layer "In11.Cu")
		(net "GMI_CPU1_G3_CPU0_G1_TX_DP<13>")
	)
	(segment
		(start 346.72778 -227.94976)
		(end 346.7354 -227.954078)
		(width 0.1143)
		(layer "In11.Cu")
		(net "GMI_CPU1_G3_CPU0_G1_TX_DP<13>")
	)
	(segment
		(start 157.724856 -193.438272)
		(end 157.72511 -193.438272)
		(width 0.14224)
		(layer "In11.Cu")
		(net "GMI_CPU1_G3_CPU0_G1_TX_DP<13>")
	)
	(segment
		(start 318.140334 -195.887848)
		(end 345.725496 -218.505532)
		(width 0.14224)
		(layer "In11.Cu")
		(net "GMI_CPU1_G3_CPU0_G1_TX_DP<13>")
	)
	(segment
		(start 124.747782 -234.441746)
		(end 124.784104 -234.420664)
		(width 0.1143)
		(layer "In11.Cu")
		(net "GMI_CPU1_G3_CPU0_G1_TX_DP<13>")
	)
	(segment
		(start 125.872748 -218.410282)
		(end 146.502374 -201.49566)
		(width 0.14224)
		(layer "In11.Cu")
		(net "GMI_CPU1_G3_CPU0_G1_TX_DP<13>")
	)
	(segment
		(start 155.108402 -195.584064)
		(end 155.301442 -195.603114)
		(width 0.14224)
		(layer "In11.Cu")
		(net "GMI_CPU1_G3_CPU0_G1_TX_DP<13>")
	)
	(segment
		(start 154.778456 -195.854574)
		(end 155.108402 -195.584064)
		(width 0.14224)
		(layer "In11.Cu")
		(net "GMI_CPU1_G3_CPU0_G1_TX_DP<13>")
	)
	(segment
		(start 346.278962 -235.89615)
		(end 346.2782 -235.896658)
		(width 0.1143)
		(layer "In11.Cu")
		(net "GMI_CPU1_G3_CPU0_G1_TX_DP<13>")
	)
	(segment
		(start 124.784104 -233.487976)
		(end 124.716032 -233.448352)
		(width 0.1143)
		(layer "In11.Cu")
		(net "GMI_CPU1_G3_CPU0_G1_TX_DP<13>")
	)
	(segment
		(start 346.281756 -235.89488)
		(end 346.278962 -235.89615)
		(width 0.1143)
		(layer "In11.Cu")
		(net "GMI_CPU1_G3_CPU0_G1_TX_DP<13>")
	)
	(segment
		(start 124.784104 -225.38817)
		(end 124.716032 -225.3488)
		(width 0.1143)
		(layer "In11.Cu")
		(net "GMI_CPU1_G3_CPU0_G1_TX_DP<13>")
	)
	(segment
		(start 125.576838 -236.384338)
		(end 125.494034 -236.301534)
		(width 0.1143)
		(layer "In11.Cu")
		(net "GMI_CPU1_G3_CPU0_G1_TX_DP<13>")
	)
	(segment
		(start 346.935806 -221.4626)
		(end 346.935806 -221.816422)
		(width 0.1143)
		(layer "In11.Cu")
		(net "GMI_CPU1_G3_CPU0_G1_TX_DP<13>")
	)
	(segment
		(start 346.246704 -235.914946)
		(end 346.245942 -235.915454)
		(width 0.1143)
		(layer "In11.Cu")
		(net "GMI_CPU1_G3_CPU0_G1_TX_DP<13>")
	)
	(segment
		(start 158.24835 -193.186558)
		(end 158.2674 -192.993518)
		(width 0.14224)
		(layer "In11.Cu")
		(net "GMI_CPU1_G3_CPU0_G1_TX_DP<13>")
	)
	(segment
		(start 124.55017 -221.452948)
		(end 124.55017 -221.248732)
		(width 0.1143)
		(layer "In11.Cu")
		(net "GMI_CPU1_G3_CPU0_G1_TX_DP<13>")
	)
	(segment
		(start 153.36393 -197.014338)
		(end 153.55697 -197.033388)
		(width 0.14224)
		(layer "In11.Cu")
		(net "GMI_CPU1_G3_CPU0_G1_TX_DP<13>")
	)
	(segment
		(start 346.733114 -235.095288)
		(end 346.732352 -235.095796)
		(width 0.1143)
		(layer "In11.Cu")
		(net "GMI_CPU1_G3_CPU0_G1_TX_DP<13>")
	)
	(segment
		(start 124.785882 -235.109004)
		(end 124.762768 -235.095542)
		(width 0.1143)
		(layer "In11.Cu")
		(net "GMI_CPU1_G3_CPU0_G1_TX_DP<13>")
	)
	(segment
		(start 159.662622 -192.026794)
		(end 159.992822 -191.75603)
		(width 0.14224)
		(layer "In11.Cu")
		(net "GMI_CPU1_G3_CPU0_G1_TX_DP<13>")
	)
	(segment
		(start 155.631642 -195.33235)
		(end 155.650692 -195.13931)
		(width 0.14224)
		(layer "In11.Cu")
		(net "GMI_CPU1_G3_CPU0_G1_TX_DP<13>")
	)
	(segment
		(start 124.762768 -235.095288)
		(end 124.757688 -235.09224)
		(width 0.1143)
		(layer "In11.Cu")
		(net "GMI_CPU1_G3_CPU0_G1_TX_DP<13>")
	)
	(segment
		(start 346.738194 -235.091986)
		(end 346.733114 -235.095034)
		(width 0.1143)
		(layer "In11.Cu")
		(net "GMI_CPU1_G3_CPU0_G1_TX_DP<13>")
	)
	(segment
		(start 346.748608 -227.961952)
		(end 346.751402 -227.963476)
		(width 0.1143)
		(layer "In11.Cu")
		(net "GMI_CPU1_G3_CPU0_G1_TX_DP<13>")
	)
	(segment
		(start 156.503878 -194.617086)
		(end 156.522928 -194.424046)
		(width 0.14224)
		(layer "In11.Cu")
		(net "GMI_CPU1_G3_CPU0_G1_TX_DP<13>")
	)
	(segment
		(start 125.21692 -235.896404)
		(end 125.214126 -235.895134)
		(width 0.1143)
		(layer "In11.Cu")
		(net "GMI_CPU1_G3_CPU0_G1_TX_DP<13>")
	)
	(segment
		(start 346.741496 -235.090208)
		(end 346.738194 -235.091986)
		(width 0.1143)
		(layer "In11.Cu")
		(net "GMI_CPU1_G3_CPU0_G1_TX_DP<13>")
	)
	(segment
		(start 346.001848 -236.30128)
		(end 345.919044 -236.384084)
		(width 0.1143)
		(layer "In11.Cu")
		(net "GMI_CPU1_G3_CPU0_G1_TX_DP<13>")
	)
	(segment
		(start 159.469582 -192.007744)
		(end 159.662622 -192.026794)
		(width 0.14224)
		(layer "In11.Cu")
		(net "GMI_CPU1_G3_CPU0_G1_TX_DP<13>")
	)
	(segment
		(start 346.779342 -222.120714)
		(end 346.70111 -222.167196)
		(width 0.1143)
		(layer "In11.Cu")
		(net "GMI_CPU1_G3_CPU0_G1_TX_DP<13>")
	)
	(segment
		(start 124.716032 -227.98024)
		(end 124.745242 -227.963476)
		(width 0.1143)
		(layer "In11.Cu")
		(net "GMI_CPU1_G3_CPU0_G1_TX_DP<13>")
	)
	(segment
		(start 346.747338 -226.343718)
		(end 346.748354 -226.344226)
		(width 0.1143)
		(layer "In11.Cu")
		(net "GMI_CPU1_G3_CPU0_G1_TX_DP<13>")
	)
	(segment
		(start 346.282264 -235.894626)
		(end 346.281756 -235.89488)
		(width 0.1143)
		(layer "In11.Cu")
		(net "GMI_CPU1_G3_CPU0_G1_TX_DP<13>")
	)
	(segment
		(start 156.852874 -194.153536)
		(end 157.045914 -194.172586)
		(width 0.14224)
		(layer "In11.Cu")
		(net "GMI_CPU1_G3_CPU0_G1_TX_DP<13>")
	)
	(segment
		(start 211.720684 -190.123318)
		(end 233.932476 -199.32396)
		(width 0.14224)
		(layer "In11.Cu")
		(net "GMI_CPU1_G3_CPU0_G1_TX_DP<13>")
	)
	(segment
		(start 346.278962 -232.011982)
		(end 346.307918 -232.028746)
		(width 0.1143)
		(layer "In11.Cu")
		(net "GMI_CPU1_G3_CPU0_G1_TX_DP<13>")
	)
	(segment
		(start 346.748354 -223.744282)
		(end 346.747338 -223.74479)
		(width 0.1143)
		(layer "In11.Cu")
		(net "GMI_CPU1_G3_CPU0_G1_TX_DP<13>")
	)
	(segment
		(start 346.730574 -235.096812)
		(end 346.728034 -235.098082)
		(width 0.1143)
		(layer "In11.Cu")
		(net "GMI_CPU1_G3_CPU0_G1_TX_DP<13>")
	)
	(segment
		(start 124.751338 -227.95992)
		(end 124.760482 -227.954332)
		(width 0.1143)
		(layer "In11.Cu")
		(net "GMI_CPU1_G3_CPU0_G1_TX_DP<13>")
	)
	(segment
		(start 346.7481 -234.441492)
		(end 346.77985 -234.45978)
		(width 0.1143)
		(layer "In11.Cu")
		(net "GMI_CPU1_G3_CPU0_G1_TX_DP<13>")
	)
	(segment
		(start 124.745242 -232.824528)
		(end 124.748036 -232.823004)
		(width 0.1143)
		(layer "In11.Cu")
		(net "GMI_CPU1_G3_CPU0_G1_TX_DP<13>")
	)
	(segment
		(start 157.395164 -193.708274)
		(end 157.724856 -193.438272)
		(width 0.14224)
		(layer "In11.Cu")
		(net "GMI_CPU1_G3_CPU0_G1_TX_DP<13>")
	)
	(segment
		(start 153.90622 -196.569584)
		(end 154.236166 -196.299074)
		(width 0.14224)
		(layer "In11.Cu")
		(net "GMI_CPU1_G3_CPU0_G1_TX_DP<13>")
	)
	(segment
		(start 162.27933 -189.541658)
		(end 207.337406 -189.350396)
		(width 0.14224)
		(layer "In11.Cu")
		(net "GMI_CPU1_G3_CPU0_G1_TX_DP<13>")
	)
	(segment
		(start 346.277184 -232.010966)
		(end 346.2782 -232.011474)
		(width 0.1143)
		(layer "In11.Cu")
		(net "GMI_CPU1_G3_CPU0_G1_TX_DP<13>")
	)
	(segment
		(start 125.249178 -235.9152)
		(end 125.217682 -235.896912)
		(width 0.1143)
		(layer "In11.Cu")
		(net "GMI_CPU1_G3_CPU0_G1_TX_DP<13>")
	)
	(segment
		(start 346.711778 -224.700592)
		(end 346.7481 -224.721674)
		(width 0.1143)
		(layer "In11.Cu")
		(net "GMI_CPU1_G3_CPU0_G1_TX_DP<13>")
	)
	(segment
		(start 346.899992 -221.202758)
		(end 346.945712 -221.248478)
		(width 0.1143)
		(layer "In11.Cu")
		(net "GMI_CPU1_G3_CPU0_G1_TX_DP<13>")
	)
	(segment
		(start 124.749306 -227.960936)
		(end 124.751338 -227.95992)
		(width 0.1143)
		(layer "In11.Cu")
		(net "GMI_CPU1_G3_CPU0_G1_TX_DP<13>")
	)
	(segment
		(start 159.120586 -192.471294)
		(end 159.139636 -192.278254)
		(width 0.14224)
		(layer "In11.Cu")
		(net "GMI_CPU1_G3_CPU0_G1_TX_DP<13>")
	)
	(segment
		(start 346.746576 -227.960682)
		(end 346.747846 -227.961444)
		(width 0.1143)
		(layer "In11.Cu")
		(net "GMI_CPU1_G3_CPU0_G1_TX_DP<13>")
	)
	(segment
		(start 160.011872 -191.56299)
		(end 160.700466 -190.998348)
		(width 0.14224)
		(layer "In11.Cu")
		(net "GMI_CPU1_G3_CPU0_G1_TX_DP<13>")
	)
	(segment
		(start 124.716032 -223.120204)
		(end 124.75464 -223.097852)
		(width 0.1143)
		(layer "In11.Cu")
		(net "GMI_CPU1_G3_CPU0_G1_TX_DP<13>")
	)
	(segment
		(start 346.311728 -231.017064)
		(end 346.239084 -231.059482)
		(width 0.1143)
		(layer "In11.Cu")
		(net "GMI_CPU1_G3_CPU0_G1_TX_DP<13>")
	)
	(segment
		(start 346.239084 -231.988614)
		(end 346.27566 -232.00995)
		(width 0.1143)
		(layer "In11.Cu")
		(net "GMI_CPU1_G3_CPU0_G1_TX_DP<13>")
	)
	(segment
		(start 156.522928 -194.424046)
		(end 156.852874 -194.153536)
		(width 0.14224)
		(layer "In11.Cu")
		(net "GMI_CPU1_G3_CPU0_G1_TX_DP<13>")
	)
	(segment
		(start 125.220222 -232.010204)
		(end 125.256798 -231.988868)
		(width 0.1143)
		(layer "In11.Cu")
		(net "GMI_CPU1_G3_CPU0_G1_TX_DP<13>")
	)
	(segment
		(start 125.256798 -235.919772)
		(end 125.24994 -235.915708)
		(width 0.1143)
		(layer "In11.Cu")
		(net "GMI_CPU1_G3_CPU0_G1_TX_DP<13>")
	)
	(segment
		(start 346.733114 -235.095034)
		(end 346.733114 -235.095288)
		(width 0.1143)
		(layer "In11.Cu")
		(net "GMI_CPU1_G3_CPU0_G1_TX_DP<13>")
	)
	(segment
		(start 124.745242 -227.963476)
		(end 124.747274 -227.962206)
		(width 0.1143)
		(layer "In11.Cu")
		(net "GMI_CPU1_G3_CPU0_G1_TX_DP<13>")
	)
	(segment
		(start 346.744544 -227.959666)
		(end 346.746576 -227.960682)
		(width 0.1143)
		(layer "In11.Cu")
		(net "GMI_CPU1_G3_CPU0_G1_TX_DP<13>")
	)
	(segment
		(start 155.650692 -195.13931)
		(end 155.980638 -194.8688)
		(width 0.14224)
		(layer "In11.Cu")
		(net "GMI_CPU1_G3_CPU0_G1_TX_DP<13>")
	)
	(segment
		(start 345.919044 -236.384084)
		(end 345.621102 -236.384084)
		(width 0.1143)
		(layer "In11.Cu")
		(net "GMI_CPU1_G3_CPU0_G1_TX_DP<13>")
	)
	(segment
		(start 160.700466 -190.998348)
		(end 160.855406 -190.70955)
		(width 0.14224)
		(layer "In11.Cu")
		(net "GMI_CPU1_G3_CPU0_G1_TX_DP<13>")
	)
	(segment
		(start 346.747846 -227.961444)
		(end 346.748608 -227.961952)
		(width 0.1143)
		(layer "In11.Cu")
		(net "GMI_CPU1_G3_CPU0_G1_TX_DP<13>")
	)
	(segment
		(start 154.236166 -196.299074)
		(end 154.429206 -196.318378)
		(width 0.14224)
		(layer "In11.Cu")
		(net "GMI_CPU1_G3_CPU0_G1_TX_DP<13>")
	)
	(segment
		(start 124.757688 -235.09224)
		(end 124.716032 -235.068618)
		(width 0.1143)
		(layer "In11.Cu")
		(net "GMI_CPU1_G3_CPU0_G1_TX_DP<13>")
	)
	(segment
		(start 158.597346 -192.723008)
		(end 158.790386 -192.742058)
		(width 0.14224)
		(layer "In11.Cu")
		(net "GMI_CPU1_G3_CPU0_G1_TX_DP<13>")
	)
	(segment
		(start 346.7354 -227.954078)
		(end 346.744544 -227.959666)
		(width 0.1143)
		(layer "In11.Cu")
		(net "GMI_CPU1_G3_CPU0_G1_TX_DP<13>")
	)
	(segment
		(start 124.794772 -222.16745)
		(end 124.71654 -222.120968)
		(width 0.1143)
		(layer "In11.Cu")
		(net "GMI_CPU1_G3_CPU0_G1_TX_DP<13>")
	)
	(segment
		(start 345.725496 -218.505532)
		(end 346.899992 -220.481652)
		(width 0.14224)
		(layer "In11.Cu")
		(net "GMI_CPU1_G3_CPU0_G1_TX_DP<13>")
	)
	(segment
		(start 124.769118 -226.999546)
		(end 124.716032 -226.968812)
		(width 0.1143)
		(layer "In11.Cu")
		(net "GMI_CPU1_G3_CPU0_G1_TX_DP<13>")
	)
	(segment
		(start 346.7481 -224.721674)
		(end 346.77985 -224.739962)
		(width 0.1143)
		(layer "In11.Cu")
		(net "GMI_CPU1_G3_CPU0_G1_TX_DP<13>")
	)
	(segment
		(start 158.2674 -192.993518)
		(end 158.597346 -192.723008)
		(width 0.14224)
		(layer "In11.Cu")
		(net "GMI_CPU1_G3_CPU0_G1_TX_DP<13>")
	)
	(segment
		(start 346.741242 -223.097598)
		(end 346.77985 -223.11995)
		(width 0.1143)
		(layer "In11.Cu")
		(net "GMI_CPU1_G3_CPU0_G1_TX_DP<13>")
	)
	(segment
		(start 346.728034 -235.098082)
		(end 346.727272 -235.09859)
		(width 0.1143)
		(layer "In11.Cu")
		(net "GMI_CPU1_G3_CPU0_G1_TX_DP<13>")
	)
	(arc
		(start 124.784104 -224.700846)
		(mid 125.029701 -224.213182)
		(end 124.748544 -223.745044)
		(width 0.1143)
		(layer "In11.Cu")
		(net "GMI_CPU1_G3_CPU0_G1_TX_DP<13>")
	)
	(arc
		(start 125.029976 -230.71455)
		(mid 124.954684 -230.432304)
		(end 124.748798 -230.225092)
		(width 0.1143)
		(layer "In11.Cu")
		(net "GMI_CPU1_G3_CPU0_G1_TX_DP<13>")
	)
	(arc
		(start 346.935806 -221.816422)
		(mid 346.894365 -221.987502)
		(end 346.779342 -222.120714)
		(width 0.1143)
		(layer "In11.Cu")
		(net "GMI_CPU1_G3_CPU0_G1_TX_DP<13>")
	)
	(arc
		(start 346.465906 -235.574078)
		(mid 346.416745 -235.758794)
		(end 346.282264 -235.894626)
		(width 0.1143)
		(layer "In11.Cu")
		(net "GMI_CPU1_G3_CPU0_G1_TX_DP<13>")
	)
	(arc
		(start 124.784104 -234.420664)
		(mid 124.791768 -234.415393)
		(end 124.799344 -234.409996)
		(width 0.1143)
		(layer "In11.Cu")
		(net "GMI_CPU1_G3_CPU0_G1_TX_DP<13>")
	)
	(arc
		(start 125.184154 -231.017318)
		(mid 125.070747 -230.884429)
		(end 125.029976 -230.71455)
		(width 0.1143)
		(layer "In11.Cu")
		(net "GMI_CPU1_G3_CPU0_G1_TX_DP<13>")
	)
	(arc
		(start 124.743972 -230.222298)
		(mid 124.609402 -230.087951)
		(end 124.560076 -229.90429)
		(width 0.1143)
		(layer "In11.Cu")
		(net "GMI_CPU1_G3_CPU0_G1_TX_DP<13>")
	)
	(arc
		(start 346.747338 -223.74479)
		(mid 346.466052 -224.212923)
		(end 346.711778 -224.700592)
		(width 0.1143)
		(layer "In11.Cu")
		(net "GMI_CPU1_G3_CPU0_G1_TX_DP<13>")
	)
	(arc
		(start 346.71 -235.10875)
		(mid 346.530655 -235.311353)
		(end 346.465906 -235.574078)
		(width 0.1143)
		(layer "In11.Cu")
		(net "GMI_CPU1_G3_CPU0_G1_TX_DP<13>")
	)
	(arc
		(start 346.935806 -229.904036)
		(mid 346.886532 -230.087727)
		(end 346.75191 -230.222044)
		(width 0.1143)
		(layer "In11.Cu")
		(net "GMI_CPU1_G3_CPU0_G1_TX_DP<13>")
	)
	(arc
		(start 346.748354 -226.344226)
		(mid 346.934187 -226.647811)
		(end 346.77985 -226.968558)
		(width 0.1143)
		(layer "In11.Cu")
		(net "GMI_CPU1_G3_CPU0_G1_TX_DP<13>")
	)
	(arc
		(start 124.716032 -233.448352)
		(mid 124.561319 -233.128467)
		(end 124.745242 -232.824528)
		(width 0.1143)
		(layer "In11.Cu")
		(net "GMI_CPU1_G3_CPU0_G1_TX_DP<13>")
	)
	(arc
		(start 346.239084 -231.059482)
		(mid 345.995757 -231.524048)
		(end 346.239084 -231.988614)
		(width 0.1143)
		(layer "In11.Cu")
		(net "GMI_CPU1_G3_CPU0_G1_TX_DP<13>")
	)
	(arc
		(start 346.711778 -225.387916)
		(mid 346.466181 -225.87558)
		(end 346.747338 -226.343718)
		(width 0.1143)
		(layer "In11.Cu")
		(net "GMI_CPU1_G3_CPU0_G1_TX_DP<13>")
	)
	(arc
		(start 346.726764 -226.999292)
		(mid 346.453213 -227.474839)
		(end 346.72778 -227.94976)
		(width 0.1143)
		(layer "In11.Cu")
		(net "GMI_CPU1_G3_CPU0_G1_TX_DP<13>")
	)
	(arc
		(start 124.75464 -223.097852)
		(mid 125.03112 -222.643754)
		(end 124.794772 -222.16745)
		(width 0.1143)
		(layer "In11.Cu")
		(net "GMI_CPU1_G3_CPU0_G1_TX_DP<13>")
	)
	(arc
		(start 125.029976 -235.574332)
		(mid 124.965254 -235.311593)
		(end 124.785882 -235.109004)
		(width 0.1143)
		(layer "In11.Cu")
		(net "GMI_CPU1_G3_CPU0_G1_TX_DP<13>")
	)
	(arc
		(start 124.799344 -234.409996)
		(mid 125.024515 -233.95432)
		(end 124.799344 -233.498644)
		(width 0.1143)
		(layer "In11.Cu")
		(net "GMI_CPU1_G3_CPU0_G1_TX_DP<13>")
	)
	(arc
		(start 346.747338 -228.60508)
		(mid 346.466269 -229.073031)
		(end 346.711778 -229.560628)
		(width 0.1143)
		(layer "In11.Cu")
		(net "GMI_CPU1_G3_CPU0_G1_TX_DP<13>")
	)
	(arc
		(start 346.747084 -230.224838)
		(mid 346.54123 -230.432069)
		(end 346.465906 -230.714296)
		(width 0.1143)
		(layer "In11.Cu")
		(net "GMI_CPU1_G3_CPU0_G1_TX_DP<13>")
	)
	(arc
		(start 124.784104 -229.560882)
		(mid 125.029703 -229.073282)
		(end 124.748544 -228.605334)
		(width 0.1143)
		(layer "In11.Cu")
		(net "GMI_CPU1_G3_CPU0_G1_TX_DP<13>")
	)
	(arc
		(start 346.005658 -236.27842)
		(mid 346.003635 -236.28983)
		(end 346.001848 -236.30128)
		(width 0.1143)
		(layer "In11.Cu")
		(net "GMI_CPU1_G3_CPU0_G1_TX_DP<13>")
	)
	(arc
		(start 124.71654 -222.120968)
		(mid 124.601622 -221.987702)
		(end 124.560076 -221.816676)
		(width 0.1143)
		(layer "In11.Cu")
		(net "GMI_CPU1_G3_CPU0_G1_TX_DP<13>")
	)
	(arc
		(start 124.747528 -228.604826)
		(mid 124.561478 -228.301061)
		(end 124.716032 -227.98024)
		(width 0.1143)
		(layer "In11.Cu")
		(net "GMI_CPU1_G3_CPU0_G1_TX_DP<13>")
	)
	(arc
		(start 346.307918 -232.028746)
		(mid 346.423965 -232.162217)
		(end 346.465906 -232.334054)
		(width 0.1143)
		(layer "In11.Cu")
		(net "GMI_CPU1_G3_CPU0_G1_TX_DP<13>")
	)
	(arc
		(start 124.748544 -226.343972)
		(mid 125.02983 -225.875839)
		(end 124.784104 -225.38817)
		(width 0.1143)
		(layer "In11.Cu")
		(net "GMI_CPU1_G3_CPU0_G1_TX_DP<13>")
	)
	(arc
		(start 346.70111 -222.167196)
		(mid 346.464607 -222.643507)
		(end 346.741242 -223.097598)
		(width 0.1143)
		(layer "In11.Cu")
		(net "GMI_CPU1_G3_CPU0_G1_TX_DP<13>")
	)
	(arc
		(start 125.494034 -236.301534)
		(mid 125.414955 -236.086089)
		(end 125.256798 -235.919772)
		(width 0.1143)
		(layer "In11.Cu")
		(net "GMI_CPU1_G3_CPU0_G1_TX_DP<13>")
	)
	(arc
		(start 346.77985 -223.11995)
		(mid 346.934189 -223.440697)
		(end 346.748354 -223.744282)
		(width 0.1143)
		(layer "In11.Cu")
		(net "GMI_CPU1_G3_CPU0_G1_TX_DP<13>")
	)
	(arc
		(start 346.696538 -234.409742)
		(mid 346.704114 -234.415138)
		(end 346.711778 -234.42041)
		(width 0.1143)
		(layer "In11.Cu")
		(net "GMI_CPU1_G3_CPU0_G1_TX_DP<13>")
	)
	(arc
		(start 346.465906 -230.714296)
		(mid 346.425144 -230.88418)
		(end 346.311728 -231.017064)
		(width 0.1143)
		(layer "In11.Cu")
		(net "GMI_CPU1_G3_CPU0_G1_TX_DP<13>")
	)
	(arc
		(start 346.465906 -232.334054)
		(mid 346.541455 -232.616136)
		(end 346.747846 -232.82275)
		(width 0.1143)
		(layer "In11.Cu")
		(net "GMI_CPU1_G3_CPU0_G1_TX_DP<13>")
	)
	(arc
		(start 124.748036 -232.823004)
		(mid 124.954478 -232.616419)
		(end 125.029976 -232.334308)
		(width 0.1143)
		(layer "In11.Cu")
		(net "GMI_CPU1_G3_CPU0_G1_TX_DP<13>")
	)
	(arc
		(start 124.747528 -223.744536)
		(mid 124.561695 -223.440951)
		(end 124.716032 -223.120204)
		(width 0.1143)
		(layer "In11.Cu")
		(net "GMI_CPU1_G3_CPU0_G1_TX_DP<13>")
	)
	(arc
		(start 346.239084 -235.919518)
		(mid 346.087097 -236.076026)
		(end 346.005658 -236.27842)
		(width 0.1143)
		(layer "In11.Cu")
		(net "GMI_CPU1_G3_CPU0_G1_TX_DP<13>")
	)
	(arc
		(start 346.77985 -227.979986)
		(mid 346.934186 -228.300796)
		(end 346.748354 -228.604572)
		(width 0.1143)
		(layer "In11.Cu")
		(net "GMI_CPU1_G3_CPU0_G1_TX_DP<13>")
	)
	(arc
		(start 124.799344 -233.498644)
		(mid 124.791768 -233.493248)
		(end 124.784104 -233.487976)
		(width 0.1143)
		(layer "In11.Cu")
		(net "GMI_CPU1_G3_CPU0_G1_TX_DP<13>")
	)
	(arc
		(start 124.716032 -226.968812)
		(mid 124.561693 -226.648065)
		(end 124.747528 -226.34448)
		(width 0.1143)
		(layer "In11.Cu")
		(net "GMI_CPU1_G3_CPU0_G1_TX_DP<13>")
	)
	(arc
		(start 125.029976 -232.334308)
		(mid 125.071855 -232.162439)
		(end 125.187964 -232.029)
		(width 0.1143)
		(layer "In11.Cu")
		(net "GMI_CPU1_G3_CPU0_G1_TX_DP<13>")
	)
	(arc
		(start 125.213618 -235.89488)
		(mid 125.079146 -235.759042)
		(end 125.029976 -235.574332)
		(width 0.1143)
		(layer "In11.Cu")
		(net "GMI_CPU1_G3_CPU0_G1_TX_DP<13>")
	)
	(arc
		(start 346.696538 -233.49839)
		(mid 346.471367 -233.954066)
		(end 346.696538 -234.409742)
		(width 0.1143)
		(layer "In11.Cu")
		(net "GMI_CPU1_G3_CPU0_G1_TX_DP<13>")
	)
	(arc
		(start 346.75064 -232.824274)
		(mid 346.934398 -233.128221)
		(end 346.77985 -233.448098)
		(width 0.1143)
		(layer "In11.Cu")
		(net "GMI_CPU1_G3_CPU0_G1_TX_DP<13>")
	)
	(arc
		(start 124.716032 -225.3488)
		(mid 124.560104 -225.044508)
		(end 124.716032 -224.740216)
		(width 0.1143)
		(layer "In11.Cu")
		(net "GMI_CPU1_G3_CPU0_G1_TX_DP<13>")
	)
	(arc
		(start 346.77985 -234.45978)
		(mid 346.935778 -234.764072)
		(end 346.77985 -235.068364)
		(width 0.1143)
		(layer "In11.Cu")
		(net "GMI_CPU1_G3_CPU0_G1_TX_DP<13>")
	)
	(arc
		(start 346.77985 -224.739962)
		(mid 346.935778 -225.044254)
		(end 346.77985 -225.348546)
		(width 0.1143)
		(layer "In11.Cu")
		(net "GMI_CPU1_G3_CPU0_G1_TX_DP<13>")
	)
	(arc
		(start 124.716032 -235.068618)
		(mid 124.560104 -234.764326)
		(end 124.716032 -234.460034)
		(width 0.1143)
		(layer "In11.Cu")
		(net "GMI_CPU1_G3_CPU0_G1_TX_DP<13>")
	)
	(arc
		(start 346.711778 -233.487722)
		(mid 346.704114 -233.492993)
		(end 346.696538 -233.49839)
		(width 0.1143)
		(layer "In11.Cu")
		(net "GMI_CPU1_G3_CPU0_G1_TX_DP<13>")
	)
	(arc
		(start 124.560076 -229.90429)
		(mid 124.600838 -229.734406)
		(end 124.714254 -229.601522)
		(width 0.1143)
		(layer "In11.Cu")
		(net "GMI_CPU1_G3_CPU0_G1_TX_DP<13>")
	)
	(arc
		(start 346.781628 -229.601268)
		(mid 346.895035 -229.734157)
		(end 346.935806 -229.904036)
		(width 0.1143)
		(layer "In11.Cu")
		(net "GMI_CPU1_G3_CPU0_G1_TX_DP<13>")
	)
	(arc
		(start 125.256798 -231.988868)
		(mid 125.500125 -231.524302)
		(end 125.256798 -231.059736)
		(width 0.1143)
		(layer "In11.Cu")
		(net "GMI_CPU1_G3_CPU0_G1_TX_DP<13>")
	)
	(arc
		(start 124.768102 -227.950014)
		(mid 125.042599 -227.475093)
		(end 124.769118 -226.999546)
		(width 0.1143)
		(layer "In11.Cu")
		(net "GMI_CPU1_G3_CPU0_G1_TX_DP<13>")
	)
	(segment
		(start 348.907862 -235.03001)
		(end 348.44101 -234.764072)
		(width 0.12954)
		(layer "F.Cu")
		(net "GMI_CPU1_G3_CPU0_G1_TX_DP<12>")
	)
	(segment
		(start 122.587766 -235.030264)
		(end 123.054618 -234.764326)
		(width 0.12954)
		(layer "F.Cu")
		(net "GMI_CPU1_G3_CPU0_G1_TX_DP<12>")
	)
	(segment
		(start 348.158308 -233.631486)
		(end 348.15907 -233.631994)
		(width 0.1143)
		(layer "In11.Cu")
		(net "GMI_CPU1_G3_CPU0_G1_TX_DP<12>")
	)
	(segment
		(start 348.452186 -234.775248)
		(end 348.44101 -234.764072)
		(width 0.1143)
		(layer "In11.Cu")
		(net "GMI_CPU1_G3_CPU0_G1_TX_DP<12>")
	)
	(segment
		(start 348.809056 -234.694222)
		(end 348.72803 -234.775248)
		(width 0.1143)
		(layer "In11.Cu")
		(net "GMI_CPU1_G3_CPU0_G1_TX_DP<12>")
	)
	(segment
		(start 347.692472 -226.344226)
		(end 347.693996 -226.344988)
		(width 0.1143)
		(layer "In11.Cu")
		(net "GMI_CPU1_G3_CPU0_G1_TX_DP<12>")
	)
	(segment
		(start 123.305824 -233.650536)
		(end 123.336812 -233.632248)
		(width 0.1143)
		(layer "In11.Cu")
		(net "GMI_CPU1_G3_CPU0_G1_TX_DP<12>")
	)
	(segment
		(start 235.277406 -198.61403)
		(end 236.27969 -198.79056)
		(width 0.14224)
		(layer "In11.Cu")
		(net "GMI_CPU1_G3_CPU0_G1_TX_DP<12>")
	)
	(segment
		(start 123.808744 -227.961444)
		(end 123.810268 -227.960428)
		(width 0.1143)
		(layer "In11.Cu")
		(net "GMI_CPU1_G3_CPU0_G1_TX_DP<12>")
	)
	(segment
		(start 348.607888 -234.427776)
		(end 348.626684 -234.438698)
		(width 0.1143)
		(layer "In11.Cu")
		(net "GMI_CPU1_G3_CPU0_G1_TX_DP<12>")
	)
	(segment
		(start 122.756676 -234.764326)
		(end 122.686826 -234.694476)
		(width 0.1143)
		(layer "In11.Cu")
		(net "GMI_CPU1_G3_CPU0_G1_TX_DP<12>")
	)
	(segment
		(start 161.95929 -188.574426)
		(end 207.257142 -188.381894)
		(width 0.14224)
		(layer "In11.Cu")
		(net "GMI_CPU1_G3_CPU0_G1_TX_DP<12>")
	)
	(segment
		(start 123.844304 -230.248206)
		(end 123.807728 -230.22687)
		(width 0.1143)
		(layer "In11.Cu")
		(net "GMI_CPU1_G3_CPU0_G1_TX_DP<12>")
	)
	(segment
		(start 347.695774 -224.725992)
		(end 347.719904 -224.739962)
		(width 0.1143)
		(layer "In11.Cu")
		(net "GMI_CPU1_G3_CPU0_G1_TX_DP<12>")
	)
	(segment
		(start 123.846844 -223.769936)
		(end 123.839986 -223.765872)
		(width 0.1143)
		(layer "In11.Cu")
		(net "GMI_CPU1_G3_CPU0_G1_TX_DP<12>")
	)
	(segment
		(start 347.685614 -226.340162)
		(end 347.687138 -226.341178)
		(width 0.1143)
		(layer "In11.Cu")
		(net "GMI_CPU1_G3_CPU0_G1_TX_DP<12>")
	)
	(segment
		(start 122.869198 -234.438952)
		(end 122.887994 -234.42803)
		(width 0.1143)
		(layer "In11.Cu")
		(net "GMI_CPU1_G3_CPU0_G1_TX_DP<12>")
	)
	(segment
		(start 347.688916 -232.821988)
		(end 347.69171 -232.823512)
		(width 0.1143)
		(layer "In11.Cu")
		(net "GMI_CPU1_G3_CPU0_G1_TX_DP<12>")
	)
	(segment
		(start 153.815542 -195.429378)
		(end 154.145742 -195.158614)
		(width 0.14224)
		(layer "In11.Cu")
		(net "GMI_CPU1_G3_CPU0_G1_TX_DP<12>")
	)
	(segment
		(start 123.650756 -221.071948)
		(end 123.650756 -220.394022)
		(width 0.14224)
		(layer "In11.Cu")
		(net "GMI_CPU1_G3_CPU0_G1_TX_DP<12>")
	)
	(segment
		(start 347.890846 -221.128844)
		(end 347.890846 -221.34703)
		(width 0.1143)
		(layer "In11.Cu")
		(net "GMI_CPU1_G3_CPU0_G1_TX_DP<12>")
	)
	(segment
		(start 123.620022 -221.804484)
		(end 123.620022 -221.36227)
		(width 0.1143)
		(layer "In11.Cu")
		(net "GMI_CPU1_G3_CPU0_G1_TX_DP<12>")
	)
	(segment
		(start 123.807728 -223.747076)
		(end 123.806966 -223.746568)
		(width 0.1143)
		(layer "In11.Cu")
		(net "GMI_CPU1_G3_CPU0_G1_TX_DP<12>")
	)
	(segment
		(start 347.655896 -228.625654)
		(end 347.649038 -228.629718)
		(width 0.1143)
		(layer "In11.Cu")
		(net "GMI_CPU1_G3_CPU0_G1_TX_DP<12>")
	)
	(segment
		(start 123.81484 -232.81767)
		(end 123.846844 -232.798874)
		(width 0.1143)
		(layer "In11.Cu")
		(net "GMI_CPU1_G3_CPU0_G1_TX_DP<12>")
	)
	(segment
		(start 239.204246 -198.27494)
		(end 250.68657 -190.234824)
		(width 0.14224)
		(layer "In11.Cu")
		(net "GMI_CPU1_G3_CPU0_G1_TX_DP<12>")
	)
	(segment
		(start 347.649038 -232.79862)
		(end 347.685614 -232.819956)
		(width 0.1143)
		(layer "In11.Cu")
		(net "GMI_CPU1_G3_CPU0_G1_TX_DP<12>")
	)
	(segment
		(start 347.69171 -224.723706)
		(end 347.692472 -224.724214)
		(width 0.1143)
		(layer "In11.Cu")
		(net "GMI_CPU1_G3_CPU0_G1_TX_DP<12>")
	)
	(segment
		(start 123.807728 -226.9871)
		(end 123.806966 -226.986592)
		(width 0.1143)
		(layer "In11.Cu")
		(net "GMI_CPU1_G3_CPU0_G1_TX_DP<12>")
	)
	(segment
		(start 347.687138 -227.96119)
		(end 347.688154 -227.961698)
		(width 0.1143)
		(layer "In11.Cu")
		(net "GMI_CPU1_G3_CPU0_G1_TX_DP<12>")
	)
	(segment
		(start 123.805696 -226.98583)
		(end 123.775978 -226.968812)
		(width 0.1143)
		(layer "In11.Cu")
		(net "GMI_CPU1_G3_CPU0_G1_TX_DP<12>")
	)
	(segment
		(start 347.250766 -231.017826)
		(end 347.218254 -231.036622)
		(width 0.1143)
		(layer "In11.Cu")
		(net "GMI_CPU1_G3_CPU0_G1_TX_DP<12>")
	)
	(segment
		(start 159.3088 -190.74765)
		(end 159.50184 -190.7667)
		(width 0.14224)
		(layer "In11.Cu")
		(net "GMI_CPU1_G3_CPU0_G1_TX_DP<12>")
	)
	(segment
		(start 347.688154 -225.366834)
		(end 347.656658 -225.385122)
		(width 0.1143)
		(layer "In11.Cu")
		(net "GMI_CPU1_G3_CPU0_G1_TX_DP<12>")
	)
	(segment
		(start 155.909264 -193.5353)
		(end 156.692092 -192.893442)
		(width 0.14224)
		(layer "In11.Cu")
		(net "GMI_CPU1_G3_CPU0_G1_TX_DP<12>")
	)
	(segment
		(start 309.346346 -188.483748)
		(end 318.637666 -195.032376)
		(width 0.14224)
		(layer "In11.Cu")
		(net "GMI_CPU1_G3_CPU0_G1_TX_DP<12>")
	)
	(segment
		(start 123.775978 -224.740216)
		(end 123.806966 -224.722436)
		(width 0.1143)
		(layer "In11.Cu")
		(net "GMI_CPU1_G3_CPU0_G1_TX_DP<12>")
	)
	(segment
		(start 347.688154 -226.986846)
		(end 347.656658 -227.005134)
		(width 0.1143)
		(layer "In11.Cu")
		(net "GMI_CPU1_G3_CPU0_G1_TX_DP<12>")
	)
	(segment
		(start 155.037028 -194.25031)
		(end 155.366974 -193.9798)
		(width 0.14224)
		(layer "In11.Cu")
		(net "GMI_CPU1_G3_CPU0_G1_TX_DP<12>")
	)
	(segment
		(start 347.719904 -230.208328)
		(end 347.688154 -230.226616)
		(width 0.1143)
		(layer "In11.Cu")
		(net "GMI_CPU1_G3_CPU0_G1_TX_DP<12>")
	)
	(segment
		(start 158.106618 -191.733424)
		(end 158.436564 -191.462914)
		(width 0.14224)
		(layer "In11.Cu")
		(net "GMI_CPU1_G3_CPU0_G1_TX_DP<12>")
	)
	(segment
		(start 123.839986 -225.385884)
		(end 123.839224 -225.385376)
		(width 0.1143)
		(layer "In11.Cu")
		(net "GMI_CPU1_G3_CPU0_G1_TX_DP<12>")
	)
	(segment
		(start 152.943052 -196.144896)
		(end 153.273252 -195.873878)
		(width 0.14224)
		(layer "In11.Cu")
		(net "GMI_CPU1_G3_CPU0_G1_TX_DP<12>")
	)
	(segment
		(start 347.685614 -232.819956)
		(end 347.687138 -232.820972)
		(width 0.1143)
		(layer "In11.Cu")
		(net "GMI_CPU1_G3_CPU0_G1_TX_DP<12>")
	)
	(segment
		(start 347.655896 -227.005642)
		(end 347.649038 -227.009706)
		(width 0.1143)
		(layer "In11.Cu")
		(net "GMI_CPU1_G3_CPU0_G1_TX_DP<12>")
	)
	(segment
		(start 159.83204 -190.495936)
		(end 159.851344 -190.302896)
		(width 0.14224)
		(layer "In11.Cu")
		(net "GMI_CPU1_G3_CPU0_G1_TX_DP<12>")
	)
	(segment
		(start 123.839224 -223.765364)
		(end 123.807728 -223.747076)
		(width 0.1143)
		(layer "In11.Cu")
		(net "GMI_CPU1_G3_CPU0_G1_TX_DP<12>")
	)
	(segment
		(start 123.805696 -228.605842)
		(end 123.775978 -228.588824)
		(width 0.1143)
		(layer "In11.Cu")
		(net "GMI_CPU1_G3_CPU0_G1_TX_DP<12>")
	)
	(segment
		(start 347.685614 -224.72015)
		(end 347.687138 -224.721166)
		(width 0.1143)
		(layer "In11.Cu")
		(net "GMI_CPU1_G3_CPU0_G1_TX_DP<12>")
	)
	(segment
		(start 348.626684 -234.438698)
		(end 348.6277 -234.439206)
		(width 0.1143)
		(layer "In11.Cu")
		(net "GMI_CPU1_G3_CPU0_G1_TX_DP<12>")
	)
	(segment
		(start 123.81484 -223.097852)
		(end 123.846844 -223.079056)
		(width 0.1143)
		(layer "In11.Cu")
		(net "GMI_CPU1_G3_CPU0_G1_TX_DP<12>")
	)
	(segment
		(start 123.839986 -227.005896)
		(end 123.839224 -227.005388)
		(width 0.1143)
		(layer "In11.Cu")
		(net "GMI_CPU1_G3_CPU0_G1_TX_DP<12>")
	)
	(segment
		(start 122.686826 -234.694476)
		(end 122.686572 -234.694476)
		(width 0.1143)
		(layer "In11.Cu")
		(net "GMI_CPU1_G3_CPU0_G1_TX_DP<12>")
	)
	(segment
		(start 347.69171 -223.103694)
		(end 347.692472 -223.104202)
		(width 0.1143)
		(layer "In11.Cu")
		(net "GMI_CPU1_G3_CPU0_G1_TX_DP<12>")
	)
	(segment
		(start 123.81484 -224.717864)
		(end 123.846844 -224.699068)
		(width 0.1143)
		(layer "In11.Cu")
		(net "GMI_CPU1_G3_CPU0_G1_TX_DP<12>")
	)
	(segment
		(start 347.845126 -220.246956)
		(end 347.845126 -221.071694)
		(width 0.14224)
		(layer "In11.Cu")
		(net "GMI_CPU1_G3_CPU0_G1_TX_DP<12>")
	)
	(segment
		(start 156.885132 -192.912492)
		(end 157.215332 -192.641728)
		(width 0.14224)
		(layer "In11.Cu")
		(net "GMI_CPU1_G3_CPU0_G1_TX_DP<12>")
	)
	(segment
		(start 154.145742 -195.158614)
		(end 154.164792 -194.965574)
		(width 0.14224)
		(layer "In11.Cu")
		(net "GMI_CPU1_G3_CPU0_G1_TX_DP<12>")
	)
	(segment
		(start 347.692472 -224.724214)
		(end 347.693996 -224.724976)
		(width 0.1143)
		(layer "In11.Cu")
		(net "GMI_CPU1_G3_CPU0_G1_TX_DP<12>")
	)
	(segment
		(start 347.69171 -226.343718)
		(end 347.692472 -226.344226)
		(width 0.1143)
		(layer "In11.Cu")
		(net "GMI_CPU1_G3_CPU0_G1_TX_DP<12>")
	)
	(segment
		(start 156.692092 -192.893442)
		(end 156.692092 -192.893188)
		(width 0.14224)
		(layer "In11.Cu")
		(net "GMI_CPU1_G3_CPU0_G1_TX_DP<12>")
	)
	(segment
		(start 124.277628 -231.036876)
		(end 124.245116 -231.01808)
		(width 0.1143)
		(layer "In11.Cu")
		(net "GMI_CPU1_G3_CPU0_G1_TX_DP<12>")
	)
	(segment
		(start 123.806966 -223.746568)
		(end 123.805696 -223.745806)
		(width 0.1143)
		(layer "In11.Cu")
		(net "GMI_CPU1_G3_CPU0_G1_TX_DP<12>")
	)
	(segment
		(start 123.806966 -225.36658)
		(end 123.805696 -225.365818)
		(width 0.1143)
		(layer "In11.Cu")
		(net "GMI_CPU1_G3_CPU0_G1_TX_DP<12>")
	)
	(segment
		(start 347.692472 -227.964238)
		(end 347.693996 -227.965)
		(width 0.1143)
		(layer "In11.Cu")
		(net "GMI_CPU1_G3_CPU0_G1_TX_DP<12>")
	)
	(segment
		(start 123.839224 -225.385376)
		(end 123.807728 -225.367088)
		(width 0.1143)
		(layer "In11.Cu")
		(net "GMI_CPU1_G3_CPU0_G1_TX_DP<12>")
	)
	(segment
		(start 155.017978 -194.44335)
		(end 155.037028 -194.25031)
		(width 0.14224)
		(layer "In11.Cu")
		(net "GMI_CPU1_G3_CPU0_G1_TX_DP<12>")
	)
	(segment
		(start 123.81484 -227.957888)
		(end 123.846844 -227.939092)
		(width 0.1143)
		(layer "In11.Cu")
		(net "GMI_CPU1_G3_CPU0_G1_TX_DP<12>")
	)
	(segment
		(start 347.692472 -223.104202)
		(end 347.693996 -223.104964)
		(width 0.1143)
		(layer "In11.Cu")
		(net "GMI_CPU1_G3_CPU0_G1_TX_DP<12>")
	)
	(segment
		(start 123.775978 -223.120204)
		(end 123.806966 -223.102424)
		(width 0.1143)
		(layer "In11.Cu")
		(net "GMI_CPU1_G3_CPU0_G1_TX_DP<12>")
	)
	(segment
		(start 347.845126 -221.083124)
		(end 347.890846 -221.128844)
		(width 0.1143)
		(layer "In11.Cu")
		(net "GMI_CPU1_G3_CPU0_G1_TX_DP<12>")
	)
	(segment
		(start 347.693996 -232.824782)
		(end 347.694758 -232.82529)
		(width 0.1143)
		(layer "In11.Cu")
		(net "GMI_CPU1_G3_CPU0_G1_TX_DP<12>")
	)
	(segment
		(start 123.337574 -233.63174)
		(end 123.37669 -233.60888)
		(width 0.1143)
		(layer "In11.Cu")
		(net "GMI_CPU1_G3_CPU0_G1_TX_DP<12>")
	)
	(segment
		(start 207.257142 -188.381894)
		(end 213.034372 -189.400688)
		(width 0.14224)
		(layer "In11.Cu")
		(net "GMI_CPU1_G3_CPU0_G1_TX_DP<12>")
	)
	(segment
		(start 347.695774 -223.10598)
		(end 347.719904 -223.11995)
		(width 0.1143)
		(layer "In11.Cu")
		(net "GMI_CPU1_G3_CPU0_G1_TX_DP<12>")
	)
	(segment
		(start 347.688154 -230.226616)
		(end 347.651578 -230.247952)
		(width 0.1143)
		(layer "In11.Cu")
		(net "GMI_CPU1_G3_CPU0_G1_TX_DP<12>")
	)
	(segment
		(start 347.688154 -224.721674)
		(end 347.688916 -224.722182)
		(width 0.1143)
		(layer "In11.Cu")
		(net "GMI_CPU1_G3_CPU0_G1_TX_DP<12>")
	)
	(segment
		(start 159.50184 -190.7667)
		(end 159.83204 -190.495936)
		(width 0.14224)
		(layer "In11.Cu")
		(net "GMI_CPU1_G3_CPU0_G1_TX_DP<12>")
	)
	(segment
		(start 123.807728 -222.127064)
		(end 123.775978 -222.108776)
		(width 0.1143)
		(layer "In11.Cu")
		(net "GMI_CPU1_G3_CPU0_G1_TX_DP<12>")
	)
	(segment
		(start 123.336812 -233.632248)
		(end 123.337574 -233.63174)
		(width 0.1143)
		(layer "In11.Cu")
		(net "GMI_CPU1_G3_CPU0_G1_TX_DP<12>")
	)
	(segment
		(start 122.887994 -234.42803)
		(end 122.889264 -234.427014)
		(width 0.1143)
		(layer "In11.Cu")
		(net "GMI_CPU1_G3_CPU0_G1_TX_DP<12>")
	)
	(segment
		(start 347.656658 -223.76511)
		(end 347.655896 -223.765618)
		(width 0.1143)
		(layer "In11.Cu")
		(net "GMI_CPU1_G3_CPU0_G1_TX_DP<12>")
	)
	(segment
		(start 347.890846 -221.34703)
		(end 347.87586 -221.362016)
		(width 0.1143)
		(layer "In11.Cu")
		(net "GMI_CPU1_G3_CPU0_G1_TX_DP<12>")
	)
	(segment
		(start 348.606618 -234.42676)
		(end 348.607888 -234.427776)
		(width 0.1143)
		(layer "In11.Cu")
		(net "GMI_CPU1_G3_CPU0_G1_TX_DP<12>")
	)
	(segment
		(start 125.30328 -217.53068)
		(end 145.878042 -200.66)
		(width 0.14224)
		(layer "In11.Cu")
		(net "GMI_CPU1_G3_CPU0_G1_TX_DP<12>")
	)
	(segment
		(start 123.805696 -225.365818)
		(end 123.775978 -225.3488)
		(width 0.1143)
		(layer "In11.Cu")
		(net "GMI_CPU1_G3_CPU0_G1_TX_DP<12>")
	)
	(segment
		(start 123.846844 -228.629972)
		(end 123.839986 -228.625908)
		(width 0.1143)
		(layer "In11.Cu")
		(net "GMI_CPU1_G3_CPU0_G1_TX_DP<12>")
	)
	(segment
		(start 154.494738 -194.695064)
		(end 154.687778 -194.714114)
		(width 0.14224)
		(layer "In11.Cu")
		(net "GMI_CPU1_G3_CPU0_G1_TX_DP<12>")
	)
	(segment
		(start 348.72803 -234.775248)
		(end 348.452186 -234.775248)
		(width 0.1143)
		(layer "In11.Cu")
		(net "GMI_CPU1_G3_CPU0_G1_TX_DP<12>")
	)
	(segment
		(start 347.690186 -228.605588)
		(end 347.688916 -228.60635)
		(width 0.1143)
		(layer "In11.Cu")
		(net "GMI_CPU1_G3_CPU0_G1_TX_DP<12>")
	)
	(segment
		(start 346.406724 -217.823542)
		(end 347.845126 -220.246956)
		(width 0.14224)
		(layer "In11.Cu")
		(net "GMI_CPU1_G3_CPU0_G1_TX_DP<12>")
	)
	(segment
		(start 148.0058 -200.015856)
		(end 152.750012 -196.125846)
		(width 0.14224)
		(layer "In11.Cu")
		(net "GMI_CPU1_G3_CPU0_G1_TX_DP<12>")
	)
	(segment
		(start 123.620022 -221.36227)
		(end 123.605036 -221.347284)
		(width 0.1143)
		(layer "In11.Cu")
		(net "GMI_CPU1_G3_CPU0_G1_TX_DP<12>")
	)
	(segment
		(start 123.806966 -226.342448)
		(end 123.807728 -226.34194)
		(width 0.1143)
		(layer "In11.Cu")
		(net "GMI_CPU1_G3_CPU0_G1_TX_DP<12>")
	)
	(segment
		(start 347.688916 -223.10217)
		(end 347.69171 -223.103694)
		(width 0.1143)
		(layer "In11.Cu")
		(net "GMI_CPU1_G3_CPU0_G1_TX_DP<12>")
	)
	(segment
		(start 347.690186 -225.365564)
		(end 347.688916 -225.366326)
		(width 0.1143)
		(layer "In11.Cu")
		(net "GMI_CPU1_G3_CPU0_G1_TX_DP<12>")
	)
	(segment
		(start 123.650756 -221.083378)
		(end 123.650756 -221.071948)
		(width 0.1143)
		(layer "In11.Cu")
		(net "GMI_CPU1_G3_CPU0_G1_TX_DP<12>")
	)
	(segment
		(start 152.750012 -196.125846)
		(end 152.943052 -196.144896)
		(width 0.14224)
		(layer "In11.Cu")
		(net "GMI_CPU1_G3_CPU0_G1_TX_DP<12>")
	)
	(segment
		(start 145.878042 -200.66)
		(end 148.0058 -200.015856)
		(width 0.14224)
		(layer "In11.Cu")
		(net "GMI_CPU1_G3_CPU0_G1_TX_DP<12>")
	)
	(segment
		(start 347.688916 -226.342194)
		(end 347.69171 -226.343718)
		(width 0.1143)
		(layer "In11.Cu")
		(net "GMI_CPU1_G3_CPU0_G1_TX_DP<12>")
	)
	(segment
		(start 347.649038 -226.318826)
		(end 347.685614 -226.340162)
		(width 0.1143)
		(layer "In11.Cu")
		(net "GMI_CPU1_G3_CPU0_G1_TX_DP<12>")
	)
	(segment
		(start 347.685614 -227.960174)
		(end 347.687138 -227.96119)
		(width 0.1143)
		(layer "In11.Cu")
		(net "GMI_CPU1_G3_CPU0_G1_TX_DP<12>")
	)
	(segment
		(start 123.807728 -226.34194)
		(end 123.808744 -226.341432)
		(width 0.1143)
		(layer "In11.Cu")
		(net "GMI_CPU1_G3_CPU0_G1_TX_DP<12>")
	)
	(segment
		(start 157.757368 -192.197228)
		(end 158.087568 -191.926464)
		(width 0.14224)
		(layer "In11.Cu")
		(net "GMI_CPU1_G3_CPU0_G1_TX_DP<12>")
	)
	(segment
		(start 347.687138 -226.341178)
		(end 347.688154 -226.341686)
		(width 0.1143)
		(layer "In11.Cu")
		(net "GMI_CPU1_G3_CPU0_G1_TX_DP<12>")
	)
	(segment
		(start 347.693996 -226.344988)
		(end 347.694758 -226.345496)
		(width 0.1143)
		(layer "In11.Cu")
		(net "GMI_CPU1_G3_CPU0_G1_TX_DP<12>")
	)
	(segment
		(start 348.80931 -234.694222)
		(end 348.809056 -234.694222)
		(width 0.1143)
		(layer "In11.Cu")
		(net "GMI_CPU1_G3_CPU0_G1_TX_DP<12>")
	)
	(segment
		(start 123.808744 -232.821226)
		(end 123.810268 -232.82021)
		(width 0.1143)
		(layer "In11.Cu")
		(net "GMI_CPU1_G3_CPU0_G1_TX_DP<12>")
	)
	(segment
		(start 123.81484 -226.337876)
		(end 123.846844 -226.31908)
		(width 0.1143)
		(layer "In11.Cu")
		(net "GMI_CPU1_G3_CPU0_G1_TX_DP<12>")
	)
	(segment
		(start 158.629604 -191.481964)
		(end 158.658814 -191.458088)
		(width 0.14224)
		(layer "In11.Cu")
		(net "GMI_CPU1_G3_CPU0_G1_TX_DP<12>")
	)
	(segment
		(start 347.655896 -223.765618)
		(end 347.649038 -223.769682)
		(width 0.1143)
		(layer "In11.Cu")
		(net "GMI_CPU1_G3_CPU0_G1_TX_DP<12>")
	)
	(segment
		(start 347.719904 -222.108522)
		(end 347.688154 -222.12681)
		(width 0.1143)
		(layer "In11.Cu")
		(net "GMI_CPU1_G3_CPU0_G1_TX_DP<12>")
	)
	(segment
		(start 347.688154 -223.101662)
		(end 347.688916 -223.10217)
		(width 0.1143)
		(layer "In11.Cu")
		(net "GMI_CPU1_G3_CPU0_G1_TX_DP<12>")
	)
	(segment
		(start 155.560014 -193.99885)
		(end 155.890214 -193.728086)
		(width 0.14224)
		(layer "In11.Cu")
		(net "GMI_CPU1_G3_CPU0_G1_TX_DP<12>")
	)
	(segment
		(start 318.759586 -195.154042)
		(end 346.406724 -217.823542)
		(width 0.14224)
		(layer "In11.Cu")
		(net "GMI_CPU1_G3_CPU0_G1_TX_DP<12>")
	)
	(segment
		(start 347.719904 -225.348546)
		(end 347.690186 -225.365564)
		(width 0.1143)
		(layer "In11.Cu")
		(net "GMI_CPU1_G3_CPU0_G1_TX_DP<12>")
	)
	(segment
		(start 123.810268 -227.960428)
		(end 123.81484 -227.957888)
		(width 0.1143)
		(layer "In11.Cu")
		(net "GMI_CPU1_G3_CPU0_G1_TX_DP<12>")
	)
	(segment
		(start 348.15907 -233.631994)
		(end 348.190058 -233.650282)
		(width 0.1143)
		(layer "In11.Cu")
		(net "GMI_CPU1_G3_CPU0_G1_TX_DP<12>")
	)
	(segment
		(start 157.215332 -192.641728)
		(end 157.234382 -192.448688)
		(width 0.14224)
		(layer "In11.Cu")
		(net "GMI_CPU1_G3_CPU0_G1_TX_DP<12>")
	)
	(segment
		(start 347.687138 -232.820972)
		(end 347.688154 -232.82148)
		(width 0.1143)
		(layer "In11.Cu")
		(net "GMI_CPU1_G3_CPU0_G1_TX_DP<12>")
	)
	(segment
		(start 347.690186 -226.985576)
		(end 347.688916 -226.986338)
		(width 0.1143)
		(layer "In11.Cu")
		(net "GMI_CPU1_G3_CPU0_G1_TX_DP<12>")
	)
	(segment
		(start 123.806966 -223.102424)
		(end 123.807728 -223.101916)
		(width 0.1143)
		(layer "In11.Cu")
		(net "GMI_CPU1_G3_CPU0_G1_TX_DP<12>")
	)
	(segment
		(start 123.775978 -226.360228)
		(end 123.806966 -226.342448)
		(width 0.1143)
		(layer "In11.Cu")
		(net "GMI_CPU1_G3_CPU0_G1_TX_DP<12>")
	)
	(segment
		(start 154.164792 -194.965574)
		(end 154.494738 -194.695064)
		(width 0.14224)
		(layer "In11.Cu")
		(net "GMI_CPU1_G3_CPU0_G1_TX_DP<12>")
	)
	(segment
		(start 123.806966 -224.722436)
		(end 123.807728 -224.721928)
		(width 0.1143)
		(layer "In11.Cu")
		(net "GMI_CPU1_G3_CPU0_G1_TX_DP<12>")
	)
	(segment
		(start 158.978854 -191.01816)
		(end 159.3088 -190.74765)
		(width 0.14224)
		(layer "In11.Cu")
		(net "GMI_CPU1_G3_CPU0_G1_TX_DP<12>")
	)
	(segment
		(start 123.846844 -227.00996)
		(end 123.839986 -227.005896)
		(width 0.1143)
		(layer "In11.Cu")
		(net "GMI_CPU1_G3_CPU0_G1_TX_DP<12>")
	)
	(segment
		(start 347.688916 -228.60635)
		(end 347.688154 -228.606858)
		(width 0.1143)
		(layer "In11.Cu")
		(net "GMI_CPU1_G3_CPU0_G1_TX_DP<12>")
	)
	(segment
		(start 123.605036 -221.129098)
		(end 123.650756 -221.083378)
		(width 0.1143)
		(layer "In11.Cu")
		(net "GMI_CPU1_G3_CPU0_G1_TX_DP<12>")
	)
	(segment
		(start 347.690186 -223.745552)
		(end 347.688916 -223.746314)
		(width 0.1143)
		(layer "In11.Cu")
		(net "GMI_CPU1_G3_CPU0_G1_TX_DP<12>")
	)
	(segment
		(start 123.806966 -227.96246)
		(end 123.807728 -227.961952)
		(width 0.1143)
		(layer "In11.Cu")
		(net "GMI_CPU1_G3_CPU0_G1_TX_DP<12>")
	)
	(segment
		(start 124.277628 -232.011728)
		(end 124.316744 -231.988868)
		(width 0.1143)
		(layer "In11.Cu")
		(net "GMI_CPU1_G3_CPU0_G1_TX_DP<12>")
	)
	(segment
		(start 123.807728 -223.101916)
		(end 123.808744 -223.101408)
		(width 0.1143)
		(layer "In11.Cu")
		(net "GMI_CPU1_G3_CPU0_G1_TX_DP<12>")
	)
	(segment
		(start 122.866404 -234.440476)
		(end 122.868182 -234.43946)
		(width 0.1143)
		(layer "In11.Cu")
		(net "GMI_CPU1_G3_CPU0_G1_TX_DP<12>")
	)
	(segment
		(start 347.719904 -228.58857)
		(end 347.690186 -228.605588)
		(width 0.1143)
		(layer "In11.Cu")
		(net "GMI_CPU1_G3_CPU0_G1_TX_DP<12>")
	)
	(segment
		(start 123.808744 -223.101408)
		(end 123.810268 -223.100392)
		(width 0.1143)
		(layer "In11.Cu")
		(net "GMI_CPU1_G3_CPU0_G1_TX_DP<12>")
	)
	(segment
		(start 123.808744 -226.341432)
		(end 123.810268 -226.340416)
		(width 0.1143)
		(layer "In11.Cu")
		(net "GMI_CPU1_G3_CPU0_G1_TX_DP<12>")
	)
	(segment
		(start 347.179138 -231.988614)
		(end 347.248734 -232.029254)
		(width 0.1143)
		(layer "In11.Cu")
		(net "GMI_CPU1_G3_CPU0_G1_TX_DP<12>")
	)
	(segment
		(start 155.890214 -193.728086)
		(end 155.909264 -193.535046)
		(width 0.14224)
		(layer "In11.Cu")
		(net "GMI_CPU1_G3_CPU0_G1_TX_DP<12>")
	)
	(segment
		(start 347.845126 -221.071694)
		(end 347.845126 -221.083124)
		(width 0.1143)
		(layer "In11.Cu")
		(net "GMI_CPU1_G3_CPU0_G1_TX_DP<12>")
	)
	(segment
		(start 158.436564 -191.462914)
		(end 158.629604 -191.481964)
		(width 0.14224)
		(layer "In11.Cu")
		(net "GMI_CPU1_G3_CPU0_G1_TX_DP<12>")
	)
	(segment
		(start 155.366974 -193.9798)
		(end 155.560014 -193.99885)
		(width 0.14224)
		(layer "In11.Cu")
		(net "GMI_CPU1_G3_CPU0_G1_TX_DP<12>")
	)
	(segment
		(start 347.693996 -227.965)
		(end 347.694758 -227.965508)
		(width 0.1143)
		(layer "In11.Cu")
		(net "GMI_CPU1_G3_CPU0_G1_TX_DP<12>")
	)
	(segment
		(start 123.810268 -224.720404)
		(end 123.81484 -224.717864)
		(width 0.1143)
		(layer "In11.Cu")
		(net "GMI_CPU1_G3_CPU0_G1_TX_DP<12>")
	)
	(segment
		(start 347.688916 -224.722182)
		(end 347.69171 -224.723706)
		(width 0.1143)
		(layer "In11.Cu")
		(net "GMI_CPU1_G3_CPU0_G1_TX_DP<12>")
	)
	(segment
		(start 155.909264 -193.535046)
		(end 155.909264 -193.5353)
		(width 0.14224)
		(layer "In11.Cu")
		(net "GMI_CPU1_G3_CPU0_G1_TX_DP<12>")
	)
	(segment
		(start 123.806966 -228.606604)
		(end 123.805696 -228.605842)
		(width 0.1143)
		(layer "In11.Cu")
		(net "GMI_CPU1_G3_CPU0_G1_TX_DP<12>")
	)
	(segment
		(start 123.810268 -226.340416)
		(end 123.81484 -226.337876)
		(width 0.1143)
		(layer "In11.Cu")
		(net "GMI_CPU1_G3_CPU0_G1_TX_DP<12>")
	)
	(segment
		(start 158.658814 -191.458088)
		(end 158.959804 -191.2112)
		(width 0.14224)
		(layer "In11.Cu")
		(net "GMI_CPU1_G3_CPU0_G1_TX_DP<12>")
	)
	(segment
		(start 318.637666 -195.032376)
		(end 318.759586 -195.154042)
		(width 0.14224)
		(layer "In11.Cu")
		(net "GMI_CPU1_G3_CPU0_G1_TX_DP<12>")
	)
	(segment
		(start 158.087568 -191.926464)
		(end 158.106618 -191.733424)
		(width 0.14224)
		(layer "In11.Cu")
		(net "GMI_CPU1_G3_CPU0_G1_TX_DP<12>")
	)
	(segment
		(start 347.688154 -223.746822)
		(end 347.656658 -223.76511)
		(width 0.1143)
		(layer "In11.Cu")
		(net "GMI_CPU1_G3_CPU0_G1_TX_DP<12>")
	)
	(segment
		(start 123.810268 -223.100392)
		(end 123.81484 -223.097852)
		(width 0.1143)
		(layer "In11.Cu")
		(net "GMI_CPU1_G3_CPU0_G1_TX_DP<12>")
	)
	(segment
		(start 123.775978 -227.98024)
		(end 123.806966 -227.96246)
		(width 0.1143)
		(layer "In11.Cu")
		(net "GMI_CPU1_G3_CPU0_G1_TX_DP<12>")
	)
	(segment
		(start 123.805696 -223.745806)
		(end 123.775978 -223.728788)
		(width 0.1143)
		(layer "In11.Cu")
		(net "GMI_CPU1_G3_CPU0_G1_TX_DP<12>")
	)
	(segment
		(start 348.119192 -233.608626)
		(end 348.158308 -233.631486)
		(width 0.1143)
		(layer "In11.Cu")
		(net "GMI_CPU1_G3_CPU0_G1_TX_DP<12>")
	)
	(segment
		(start 123.808744 -224.72142)
		(end 123.810268 -224.720404)
		(width 0.1143)
		(layer "In11.Cu")
		(net "GMI_CPU1_G3_CPU0_G1_TX_DP<12>")
	)
	(segment
		(start 123.810268 -232.82021)
		(end 123.81484 -232.81767)
		(width 0.1143)
		(layer "In11.Cu")
		(net "GMI_CPU1_G3_CPU0_G1_TX_DP<12>")
	)
	(segment
		(start 347.694758 -226.345496)
		(end 347.695774 -226.346004)
		(width 0.1143)
		(layer "In11.Cu")
		(net "GMI_CPU1_G3_CPU0_G1_TX_DP<12>")
	)
	(segment
		(start 347.719904 -226.968558)
		(end 347.690186 -226.985576)
		(width 0.1143)
		(layer "In11.Cu")
		(net "GMI_CPU1_G3_CPU0_G1_TX_DP<12>")
	)
	(segment
		(start 123.807728 -225.367088)
		(end 123.806966 -225.36658)
		(width 0.1143)
		(layer "In11.Cu")
		(net "GMI_CPU1_G3_CPU0_G1_TX_DP<12>")
	)
	(segment
		(start 347.69171 -227.96373)
		(end 347.692472 -227.964238)
		(width 0.1143)
		(layer "In11.Cu")
		(net "GMI_CPU1_G3_CPU0_G1_TX_DP<12>")
	)
	(segment
		(start 153.292556 -195.680838)
		(end 153.622502 -195.410328)
		(width 0.14224)
		(layer "In11.Cu")
		(net "GMI_CPU1_G3_CPU0_G1_TX_DP<12>")
	)
	(segment
		(start 153.273252 -195.873878)
		(end 153.292556 -195.680838)
		(width 0.14224)
		(layer "In11.Cu")
		(net "GMI_CPU1_G3_CPU0_G1_TX_DP<12>")
	)
	(segment
		(start 154.687778 -194.714114)
		(end 155.017978 -194.44335)
		(width 0.14224)
		(layer "In11.Cu")
		(net "GMI_CPU1_G3_CPU0_G1_TX_DP<12>")
	)
	(segment
		(start 124.247148 -232.029508)
		(end 124.277628 -232.011728)
		(width 0.1143)
		(layer "In11.Cu")
		(net "GMI_CPU1_G3_CPU0_G1_TX_DP<12>")
	)
	(segment
		(start 347.688916 -223.746314)
		(end 347.688154 -223.746822)
		(width 0.1143)
		(layer "In11.Cu")
		(net "GMI_CPU1_G3_CPU0_G1_TX_DP<12>")
	)
	(segment
		(start 347.688154 -227.961698)
		(end 347.688916 -227.962206)
		(width 0.1143)
		(layer "In11.Cu")
		(net "GMI_CPU1_G3_CPU0_G1_TX_DP<12>")
	)
	(segment
		(start 347.694758 -227.965508)
		(end 347.695774 -227.966016)
		(width 0.1143)
		(layer "In11.Cu")
		(net "GMI_CPU1_G3_CPU0_G1_TX_DP<12>")
	)
	(segment
		(start 347.649038 -223.078802)
		(end 347.685614 -223.100138)
		(width 0.1143)
		(layer "In11.Cu")
		(net "GMI_CPU1_G3_CPU0_G1_TX_DP<12>")
	)
	(segment
		(start 123.054618 -234.764326)
		(end 122.756676 -234.764326)
		(width 0.1143)
		(layer "In11.Cu")
		(net "GMI_CPU1_G3_CPU0_G1_TX_DP<12>")
	)
	(segment
		(start 347.695774 -227.966016)
		(end 347.719904 -227.979986)
		(width 0.1143)
		(layer "In11.Cu")
		(net "GMI_CPU1_G3_CPU0_G1_TX_DP<12>")
	)
	(segment
		(start 250.68657 -190.234824)
		(end 262.760968 -188.105542)
		(width 0.14224)
		(layer "In11.Cu")
		(net "GMI_CPU1_G3_CPU0_G1_TX_DP<12>")
	)
	(segment
		(start 159.851344 -190.302896)
		(end 161.95929 -188.574426)
		(width 0.14224)
		(layer "In11.Cu")
		(net "GMI_CPU1_G3_CPU0_G1_TX_DP<12>")
	)
	(segment
		(start 347.695774 -226.346004)
		(end 347.719904 -226.359974)
		(width 0.1143)
		(layer "In11.Cu")
		(net "GMI_CPU1_G3_CPU0_G1_TX_DP<12>")
	)
	(segment
		(start 123.846844 -225.389948)
		(end 123.839986 -225.385884)
		(width 0.1143)
		(layer "In11.Cu")
		(net "GMI_CPU1_G3_CPU0_G1_TX_DP<12>")
	)
	(segment
		(start 123.846844 -222.149924)
		(end 123.807728 -222.127064)
		(width 0.1143)
		(layer "In11.Cu")
		(net "GMI_CPU1_G3_CPU0_G1_TX_DP<12>")
	)
	(segment
		(start 347.693996 -223.104964)
		(end 347.694758 -223.105472)
		(width 0.1143)
		(layer "In11.Cu")
		(net "GMI_CPU1_G3_CPU0_G1_TX_DP<12>")
	)
	(segment
		(start 153.622502 -195.410328)
		(end 153.815542 -195.429378)
		(width 0.14224)
		(layer "In11.Cu")
		(net "GMI_CPU1_G3_CPU0_G1_TX_DP<12>")
	)
	(segment
		(start 123.807728 -228.607112)
		(end 123.806966 -228.606604)
		(width 0.1143)
		(layer "In11.Cu")
		(net "GMI_CPU1_G3_CPU0_G1_TX_DP<12>")
	)
	(segment
		(start 123.605036 -221.347284)
		(end 123.605036 -221.129098)
		(width 0.1143)
		(layer "In11.Cu")
		(net "GMI_CPU1_G3_CPU0_G1_TX_DP<12>")
	)
	(segment
		(start 123.839986 -223.765872)
		(end 123.839224 -223.765364)
		(width 0.1143)
		(layer "In11.Cu")
		(net "GMI_CPU1_G3_CPU0_G1_TX_DP<12>")
	)
	(segment
		(start 157.564328 -192.178178)
		(end 157.757368 -192.197228)
		(width 0.14224)
		(layer "In11.Cu")
		(net "GMI_CPU1_G3_CPU0_G1_TX_DP<12>")
	)
	(segment
		(start 347.693996 -224.724976)
		(end 347.694758 -224.725484)
		(width 0.1143)
		(layer "In11.Cu")
		(net "GMI_CPU1_G3_CPU0_G1_TX_DP<12>")
	)
	(segment
		(start 347.687138 -224.721166)
		(end 347.688154 -224.721674)
		(width 0.1143)
		(layer "In11.Cu")
		(net "GMI_CPU1_G3_CPU0_G1_TX_DP<12>")
	)
	(segment
		(start 123.807728 -224.721928)
		(end 123.808744 -224.72142)
		(width 0.1143)
		(layer "In11.Cu")
		(net "GMI_CPU1_G3_CPU0_G1_TX_DP<12>")
	)
	(segment
		(start 347.688154 -226.341686)
		(end 347.688916 -226.342194)
		(width 0.1143)
		(layer "In11.Cu")
		(net "GMI_CPU1_G3_CPU0_G1_TX_DP<12>")
	)
	(segment
		(start 348.6277 -234.439206)
		(end 348.629478 -234.440222)
		(width 0.1143)
		(layer "In11.Cu")
		(net "GMI_CPU1_G3_CPU0_G1_TX_DP<12>")
	)
	(segment
		(start 347.694758 -232.82529)
		(end 347.695774 -232.825798)
		(width 0.1143)
		(layer "In11.Cu")
		(net "GMI_CPU1_G3_CPU0_G1_TX_DP<12>")
	)
	(segment
		(start 347.656658 -228.625146)
		(end 347.655896 -228.625654)
		(width 0.1143)
		(layer "In11.Cu")
		(net "GMI_CPU1_G3_CPU0_G1_TX_DP<12>")
	)
	(segment
		(start 123.839986 -228.625908)
		(end 123.839224 -228.6254)
		(width 0.1143)
		(layer "In11.Cu")
		(net "GMI_CPU1_G3_CPU0_G1_TX_DP<12>")
	)
	(segment
		(start 158.959804 -191.2112)
		(end 158.978854 -191.01816)
		(width 0.14224)
		(layer "In11.Cu")
		(net "GMI_CPU1_G3_CPU0_G1_TX_DP<12>")
	)
	(segment
		(start 123.7742 -229.601522)
		(end 123.807728 -229.581964)
		(width 0.1143)
		(layer "In11.Cu")
		(net "GMI_CPU1_G3_CPU0_G1_TX_DP<12>")
	)
	(segment
		(start 347.719904 -223.728534)
		(end 347.690186 -223.745552)
		(width 0.1143)
		(layer "In11.Cu")
		(net "GMI_CPU1_G3_CPU0_G1_TX_DP<12>")
	)
	(segment
		(start 347.688154 -228.606858)
		(end 347.656658 -228.625146)
		(width 0.1143)
		(layer "In11.Cu")
		(net "GMI_CPU1_G3_CPU0_G1_TX_DP<12>")
	)
	(segment
		(start 347.688916 -226.986338)
		(end 347.688154 -226.986846)
		(width 0.1143)
		(layer "In11.Cu")
		(net "GMI_CPU1_G3_CPU0_G1_TX_DP<12>")
	)
	(segment
		(start 123.806966 -226.986592)
		(end 123.805696 -226.98583)
		(width 0.1143)
		(layer "In11.Cu")
		(net "GMI_CPU1_G3_CPU0_G1_TX_DP<12>")
	)
	(segment
		(start 123.839224 -227.005388)
		(end 123.807728 -226.9871)
		(width 0.1143)
		(layer "In11.Cu")
		(net "GMI_CPU1_G3_CPU0_G1_TX_DP<12>")
	)
	(segment
		(start 347.649038 -224.698814)
		(end 347.685614 -224.72015)
		(width 0.1143)
		(layer "In11.Cu")
		(net "GMI_CPU1_G3_CPU0_G1_TX_DP<12>")
	)
	(segment
		(start 156.692092 -192.893188)
		(end 156.885132 -192.912492)
		(width 0.14224)
		(layer "In11.Cu")
		(net "GMI_CPU1_G3_CPU0_G1_TX_DP<12>")
	)
	(segment
		(start 123.839224 -228.6254)
		(end 123.807728 -228.607112)
		(width 0.1143)
		(layer "In11.Cu")
		(net "GMI_CPU1_G3_CPU0_G1_TX_DP<12>")
	)
	(segment
		(start 122.868182 -234.43946)
		(end 122.869198 -234.438952)
		(width 0.1143)
		(layer "In11.Cu")
		(net "GMI_CPU1_G3_CPU0_G1_TX_DP<12>")
	)
	(segment
		(start 347.687138 -223.101154)
		(end 347.688154 -223.101662)
		(width 0.1143)
		(layer "In11.Cu")
		(net "GMI_CPU1_G3_CPU0_G1_TX_DP<12>")
	)
	(segment
		(start 262.760968 -188.105542)
		(end 303.70526 -188.483748)
		(width 0.14224)
		(layer "In11.Cu")
		(net "GMI_CPU1_G3_CPU0_G1_TX_DP<12>")
	)
	(segment
		(start 213.034372 -189.400688)
		(end 235.277406 -198.61403)
		(width 0.14224)
		(layer "In11.Cu")
		(net "GMI_CPU1_G3_CPU0_G1_TX_DP<12>")
	)
	(segment
		(start 347.694758 -224.725484)
		(end 347.695774 -224.725992)
		(width 0.1143)
		(layer "In11.Cu")
		(net "GMI_CPU1_G3_CPU0_G1_TX_DP<12>")
	)
	(segment
		(start 303.70526 -188.483748)
		(end 309.346346 -188.483748)
		(width 0.14224)
		(layer "In11.Cu")
		(net "GMI_CPU1_G3_CPU0_G1_TX_DP<12>")
	)
	(segment
		(start 123.806966 -232.822242)
		(end 123.807728 -232.821734)
		(width 0.1143)
		(layer "In11.Cu")
		(net "GMI_CPU1_G3_CPU0_G1_TX_DP<12>")
	)
	(segment
		(start 347.87586 -221.362016)
		(end 347.87586 -221.80423)
		(width 0.1143)
		(layer "In11.Cu")
		(net "GMI_CPU1_G3_CPU0_G1_TX_DP<12>")
	)
	(segment
		(start 124.316744 -231.059736)
		(end 124.277628 -231.036876)
		(width 0.1143)
		(layer "In11.Cu")
		(net "GMI_CPU1_G3_CPU0_G1_TX_DP<12>")
	)
	(segment
		(start 347.656658 -225.385122)
		(end 347.655896 -225.38563)
		(width 0.1143)
		(layer "In11.Cu")
		(net "GMI_CPU1_G3_CPU0_G1_TX_DP<12>")
	)
	(segment
		(start 123.807728 -229.581964)
		(end 123.846844 -229.559104)
		(width 0.1143)
		(layer "In11.Cu")
		(net "GMI_CPU1_G3_CPU0_G1_TX_DP<12>")
	)
	(segment
		(start 347.656658 -227.005134)
		(end 347.655896 -227.005642)
		(width 0.1143)
		(layer "In11.Cu")
		(net "GMI_CPU1_G3_CPU0_G1_TX_DP<12>")
	)
	(segment
		(start 347.688154 -232.82148)
		(end 347.688916 -232.821988)
		(width 0.1143)
		(layer "In11.Cu")
		(net "GMI_CPU1_G3_CPU0_G1_TX_DP<12>")
	)
	(segment
		(start 123.807728 -227.961952)
		(end 123.808744 -227.961444)
		(width 0.1143)
		(layer "In11.Cu")
		(net "GMI_CPU1_G3_CPU0_G1_TX_DP<12>")
	)
	(segment
		(start 347.688916 -227.962206)
		(end 347.69171 -227.96373)
		(width 0.1143)
		(layer "In11.Cu")
		(net "GMI_CPU1_G3_CPU0_G1_TX_DP<12>")
	)
	(segment
		(start 347.69171 -232.823512)
		(end 347.692472 -232.82402)
		(width 0.1143)
		(layer "In11.Cu")
		(net "GMI_CPU1_G3_CPU0_G1_TX_DP<12>")
	)
	(segment
		(start 157.234382 -192.448688)
		(end 157.564328 -192.178178)
		(width 0.14224)
		(layer "In11.Cu")
		(net "GMI_CPU1_G3_CPU0_G1_TX_DP<12>")
	)
	(segment
		(start 347.695774 -232.825798)
		(end 347.719904 -232.839768)
		(width 0.1143)
		(layer "In11.Cu")
		(net "GMI_CPU1_G3_CPU0_G1_TX_DP<12>")
	)
	(segment
		(start 347.649038 -227.938838)
		(end 347.685614 -227.960174)
		(width 0.1143)
		(layer "In11.Cu")
		(net "GMI_CPU1_G3_CPU0_G1_TX_DP<12>")
	)
	(segment
		(start 347.688154 -222.12681)
		(end 347.649038 -222.14967)
		(width 0.1143)
		(layer "In11.Cu")
		(net "GMI_CPU1_G3_CPU0_G1_TX_DP<12>")
	)
	(segment
		(start 123.807728 -232.821734)
		(end 123.808744 -232.821226)
		(width 0.1143)
		(layer "In11.Cu")
		(net "GMI_CPU1_G3_CPU0_G1_TX_DP<12>")
	)
	(segment
		(start 347.685614 -223.100138)
		(end 347.687138 -223.101154)
		(width 0.1143)
		(layer "In11.Cu")
		(net "GMI_CPU1_G3_CPU0_G1_TX_DP<12>")
	)
	(segment
		(start 347.688916 -225.366326)
		(end 347.688154 -225.366834)
		(width 0.1143)
		(layer "In11.Cu")
		(net "GMI_CPU1_G3_CPU0_G1_TX_DP<12>")
	)
	(segment
		(start 123.775978 -232.840022)
		(end 123.806966 -232.822242)
		(width 0.1143)
		(layer "In11.Cu")
		(net "GMI_CPU1_G3_CPU0_G1_TX_DP<12>")
	)
	(segment
		(start 123.807728 -230.22687)
		(end 123.775978 -230.208582)
		(width 0.1143)
		(layer "In11.Cu")
		(net "GMI_CPU1_G3_CPU0_G1_TX_DP<12>")
	)
	(segment
		(start 347.649038 -229.55885)
		(end 347.721682 -229.601268)
		(width 0.1143)
		(layer "In11.Cu")
		(net "GMI_CPU1_G3_CPU0_G1_TX_DP<12>")
	)
	(segment
		(start 347.692472 -232.82402)
		(end 347.693996 -232.824782)
		(width 0.1143)
		(layer "In11.Cu")
		(net "GMI_CPU1_G3_CPU0_G1_TX_DP<12>")
	)
	(segment
		(start 347.694758 -223.105472)
		(end 347.695774 -223.10598)
		(width 0.1143)
		(layer "In11.Cu")
		(net "GMI_CPU1_G3_CPU0_G1_TX_DP<12>")
	)
	(segment
		(start 123.650756 -220.394022)
		(end 125.30328 -217.53068)
		(width 0.14224)
		(layer "In11.Cu")
		(net "GMI_CPU1_G3_CPU0_G1_TX_DP<12>")
	)
	(segment
		(start 347.655896 -225.38563)
		(end 347.649038 -225.389694)
		(width 0.1143)
		(layer "In11.Cu")
		(net "GMI_CPU1_G3_CPU0_G1_TX_DP<12>")
	)
	(segment
		(start 347.218254 -231.036622)
		(end 347.179138 -231.059482)
		(width 0.1143)
		(layer "In11.Cu")
		(net "GMI_CPU1_G3_CPU0_G1_TX_DP<12>")
	)
	(segment
		(start 236.27969 -198.79056)
		(end 239.204246 -198.27494)
		(width 0.14224)
		(layer "In11.Cu")
		(net "GMI_CPU1_G3_CPU0_G1_TX_DP<12>")
	)
	(arc
		(start 124.090176 -230.71455)
		(mid 124.02494 -230.450959)
		(end 123.844304 -230.248206)
		(width 0.1143)
		(layer "In11.Cu")
		(net "GMI_CPU1_G3_CPU0_G1_TX_DP<12>")
	)
	(arc
		(start 124.245116 -231.01808)
		(mid 124.131187 -230.884933)
		(end 124.090176 -230.71455)
		(width 0.1143)
		(layer "In11.Cu")
		(net "GMI_CPU1_G3_CPU0_G1_TX_DP<12>")
	)
	(arc
		(start 347.719904 -232.839768)
		(mid 347.83458 -232.973102)
		(end 347.87586 -233.14406)
		(width 0.1143)
		(layer "In11.Cu")
		(net "GMI_CPU1_G3_CPU0_G1_TX_DP<12>")
	)
	(arc
		(start 347.405706 -230.714296)
		(mid 347.36474 -230.884702)
		(end 347.250766 -231.017826)
		(width 0.1143)
		(layer "In11.Cu")
		(net "GMI_CPU1_G3_CPU0_G1_TX_DP<12>")
	)
	(arc
		(start 347.649038 -227.009706)
		(mid 347.405711 -227.474272)
		(end 347.649038 -227.938838)
		(width 0.1143)
		(layer "In11.Cu")
		(net "GMI_CPU1_G3_CPU0_G1_TX_DP<12>")
	)
	(arc
		(start 347.719904 -224.739962)
		(mid 347.875832 -225.044254)
		(end 347.719904 -225.348546)
		(width 0.1143)
		(layer "In11.Cu")
		(net "GMI_CPU1_G3_CPU0_G1_TX_DP<12>")
	)
	(arc
		(start 123.775978 -225.3488)
		(mid 123.62005 -225.044508)
		(end 123.775978 -224.740216)
		(width 0.1143)
		(layer "In11.Cu")
		(net "GMI_CPU1_G3_CPU0_G1_TX_DP<12>")
	)
	(arc
		(start 123.775978 -223.728788)
		(mid 123.62005 -223.424496)
		(end 123.775978 -223.120204)
		(width 0.1143)
		(layer "In11.Cu")
		(net "GMI_CPU1_G3_CPU0_G1_TX_DP<12>")
	)
	(arc
		(start 123.775978 -222.108776)
		(mid 123.661302 -221.975442)
		(end 123.620022 -221.804484)
		(width 0.1143)
		(layer "In11.Cu")
		(net "GMI_CPU1_G3_CPU0_G1_TX_DP<12>")
	)
	(arc
		(start 122.889264 -234.427014)
		(mid 123.080455 -234.224237)
		(end 123.149868 -233.95432)
		(width 0.1143)
		(layer "In11.Cu")
		(net "GMI_CPU1_G3_CPU0_G1_TX_DP<12>")
	)
	(arc
		(start 347.719904 -227.979986)
		(mid 347.875832 -228.284278)
		(end 347.719904 -228.58857)
		(width 0.1143)
		(layer "In11.Cu")
		(net "GMI_CPU1_G3_CPU0_G1_TX_DP<12>")
	)
	(arc
		(start 123.775978 -228.588824)
		(mid 123.62005 -228.284532)
		(end 123.775978 -227.98024)
		(width 0.1143)
		(layer "In11.Cu")
		(net "GMI_CPU1_G3_CPU0_G1_TX_DP<12>")
	)
	(arc
		(start 123.775978 -226.968812)
		(mid 123.62005 -226.66452)
		(end 123.775978 -226.360228)
		(width 0.1143)
		(layer "In11.Cu")
		(net "GMI_CPU1_G3_CPU0_G1_TX_DP<12>")
	)
	(arc
		(start 123.620022 -229.90429)
		(mid 123.660784 -229.734406)
		(end 123.7742 -229.601522)
		(width 0.1143)
		(layer "In11.Cu")
		(net "GMI_CPU1_G3_CPU0_G1_TX_DP<12>")
	)
	(arc
		(start 123.846844 -232.798874)
		(mid 124.025657 -232.596524)
		(end 124.090176 -232.334308)
		(width 0.1143)
		(layer "In11.Cu")
		(net "GMI_CPU1_G3_CPU0_G1_TX_DP<12>")
	)
	(arc
		(start 347.405706 -232.334054)
		(mid 347.470221 -232.596273)
		(end 347.649038 -232.79862)
		(width 0.1143)
		(layer "In11.Cu")
		(net "GMI_CPU1_G3_CPU0_G1_TX_DP<12>")
	)
	(arc
		(start 347.721682 -229.601268)
		(mid 347.835089 -229.734157)
		(end 347.87586 -229.904036)
		(width 0.1143)
		(layer "In11.Cu")
		(net "GMI_CPU1_G3_CPU0_G1_TX_DP<12>")
	)
	(arc
		(start 347.719904 -223.11995)
		(mid 347.875832 -223.424242)
		(end 347.719904 -223.728534)
		(width 0.1143)
		(layer "In11.Cu")
		(net "GMI_CPU1_G3_CPU0_G1_TX_DP<12>")
	)
	(arc
		(start 347.87586 -221.80423)
		(mid 347.834605 -221.975201)
		(end 347.719904 -222.108522)
		(width 0.1143)
		(layer "In11.Cu")
		(net "GMI_CPU1_G3_CPU0_G1_TX_DP<12>")
	)
	(arc
		(start 123.846844 -224.699068)
		(mid 124.090171 -224.234502)
		(end 123.846844 -223.769936)
		(width 0.1143)
		(layer "In11.Cu")
		(net "GMI_CPU1_G3_CPU0_G1_TX_DP<12>")
	)
	(arc
		(start 347.248734 -232.029254)
		(mid 347.364161 -232.16263)
		(end 347.405706 -232.334054)
		(width 0.1143)
		(layer "In11.Cu")
		(net "GMI_CPU1_G3_CPU0_G1_TX_DP<12>")
	)
	(arc
		(start 348.629478 -234.440222)
		(mid 348.746999 -234.547671)
		(end 348.80931 -234.694222)
		(width 0.1143)
		(layer "In11.Cu")
		(net "GMI_CPU1_G3_CPU0_G1_TX_DP<12>")
	)
	(arc
		(start 123.149868 -233.95432)
		(mid 123.191185 -233.783604)
		(end 123.305824 -233.650536)
		(width 0.1143)
		(layer "In11.Cu")
		(net "GMI_CPU1_G3_CPU0_G1_TX_DP<12>")
	)
	(arc
		(start 123.846844 -223.079056)
		(mid 124.090171 -222.61449)
		(end 123.846844 -222.149924)
		(width 0.1143)
		(layer "In11.Cu")
		(net "GMI_CPU1_G3_CPU0_G1_TX_DP<12>")
	)
	(arc
		(start 123.846844 -227.939092)
		(mid 124.090171 -227.474526)
		(end 123.846844 -227.00996)
		(width 0.1143)
		(layer "In11.Cu")
		(net "GMI_CPU1_G3_CPU0_G1_TX_DP<12>")
	)
	(arc
		(start 347.87586 -233.14406)
		(mid 347.940375 -233.406279)
		(end 348.119192 -233.608626)
		(width 0.1143)
		(layer "In11.Cu")
		(net "GMI_CPU1_G3_CPU0_G1_TX_DP<12>")
	)
	(arc
		(start 123.620022 -233.144314)
		(mid 123.661277 -232.973343)
		(end 123.775978 -232.840022)
		(width 0.1143)
		(layer "In11.Cu")
		(net "GMI_CPU1_G3_CPU0_G1_TX_DP<12>")
	)
	(arc
		(start 348.346014 -233.954066)
		(mid 348.415423 -234.223985)
		(end 348.606618 -234.42676)
		(width 0.1143)
		(layer "In11.Cu")
		(net "GMI_CPU1_G3_CPU0_G1_TX_DP<12>")
	)
	(arc
		(start 347.179138 -231.059482)
		(mid 346.935811 -231.524048)
		(end 347.179138 -231.988614)
		(width 0.1143)
		(layer "In11.Cu")
		(net "GMI_CPU1_G3_CPU0_G1_TX_DP<12>")
	)
	(arc
		(start 122.686572 -234.694476)
		(mid 122.748846 -234.5479)
		(end 122.866404 -234.440476)
		(width 0.1143)
		(layer "In11.Cu")
		(net "GMI_CPU1_G3_CPU0_G1_TX_DP<12>")
	)
	(arc
		(start 123.846844 -229.559104)
		(mid 124.090171 -229.094538)
		(end 123.846844 -228.629972)
		(width 0.1143)
		(layer "In11.Cu")
		(net "GMI_CPU1_G3_CPU0_G1_TX_DP<12>")
	)
	(arc
		(start 123.775978 -230.208582)
		(mid 123.661302 -230.075248)
		(end 123.620022 -229.90429)
		(width 0.1143)
		(layer "In11.Cu")
		(net "GMI_CPU1_G3_CPU0_G1_TX_DP<12>")
	)
	(arc
		(start 347.719904 -226.359974)
		(mid 347.875832 -226.664266)
		(end 347.719904 -226.968558)
		(width 0.1143)
		(layer "In11.Cu")
		(net "GMI_CPU1_G3_CPU0_G1_TX_DP<12>")
	)
	(arc
		(start 123.37669 -233.60888)
		(mid 123.555503 -233.40653)
		(end 123.620022 -233.144314)
		(width 0.1143)
		(layer "In11.Cu")
		(net "GMI_CPU1_G3_CPU0_G1_TX_DP<12>")
	)
	(arc
		(start 347.649038 -222.14967)
		(mid 347.405711 -222.614236)
		(end 347.649038 -223.078802)
		(width 0.1143)
		(layer "In11.Cu")
		(net "GMI_CPU1_G3_CPU0_G1_TX_DP<12>")
	)
	(arc
		(start 348.190058 -233.650282)
		(mid 348.304677 -233.78336)
		(end 348.346014 -233.954066)
		(width 0.1143)
		(layer "In11.Cu")
		(net "GMI_CPU1_G3_CPU0_G1_TX_DP<12>")
	)
	(arc
		(start 124.316744 -231.988868)
		(mid 124.560071 -231.524302)
		(end 124.316744 -231.059736)
		(width 0.1143)
		(layer "In11.Cu")
		(net "GMI_CPU1_G3_CPU0_G1_TX_DP<12>")
	)
	(arc
		(start 347.649038 -228.629718)
		(mid 347.405711 -229.094284)
		(end 347.649038 -229.55885)
		(width 0.1143)
		(layer "In11.Cu")
		(net "GMI_CPU1_G3_CPU0_G1_TX_DP<12>")
	)
	(arc
		(start 124.090176 -232.334308)
		(mid 124.131725 -232.162886)
		(end 124.247148 -232.029508)
		(width 0.1143)
		(layer "In11.Cu")
		(net "GMI_CPU1_G3_CPU0_G1_TX_DP<12>")
	)
	(arc
		(start 123.846844 -226.31908)
		(mid 124.090171 -225.854514)
		(end 123.846844 -225.389948)
		(width 0.1143)
		(layer "In11.Cu")
		(net "GMI_CPU1_G3_CPU0_G1_TX_DP<12>")
	)
	(arc
		(start 347.649038 -225.389694)
		(mid 347.405711 -225.85426)
		(end 347.649038 -226.318826)
		(width 0.1143)
		(layer "In11.Cu")
		(net "GMI_CPU1_G3_CPU0_G1_TX_DP<12>")
	)
	(arc
		(start 347.649038 -223.769682)
		(mid 347.405711 -224.234248)
		(end 347.649038 -224.698814)
		(width 0.1143)
		(layer "In11.Cu")
		(net "GMI_CPU1_G3_CPU0_G1_TX_DP<12>")
	)
	(arc
		(start 347.651578 -230.247952)
		(mid 347.470926 -230.450697)
		(end 347.405706 -230.714296)
		(width 0.1143)
		(layer "In11.Cu")
		(net "GMI_CPU1_G3_CPU0_G1_TX_DP<12>")
	)
	(arc
		(start 347.87586 -229.904036)
		(mid 347.834605 -230.075007)
		(end 347.719904 -230.208328)
		(width 0.1143)
		(layer "In11.Cu")
		(net "GMI_CPU1_G3_CPU0_G1_TX_DP<12>")
	)
	(segment
		(start 122.587766 -233.410252)
		(end 123.054618 -233.144314)
		(width 0.12954)
		(layer "F.Cu")
		(net "GMI_CPU1_G3_CPU0_G1_TX_DP<11>")
	)
	(segment
		(start 348.907862 -233.409998)
		(end 348.44101 -233.14406)
		(width 0.12954)
		(layer "F.Cu")
		(net "GMI_CPU1_G3_CPU0_G1_TX_DP<11>")
	)
	(segment
		(start 123.376944 -231.059736)
		(end 123.337828 -231.036876)
		(width 0.1143)
		(layer "In11.Cu")
		(net "GMI_CPU1_G3_CPU0_G1_TX_DP<11>")
	)
	(segment
		(start 123.341384 -232.009696)
		(end 123.342654 -232.008934)
		(width 0.1143)
		(layer "In11.Cu")
		(net "GMI_CPU1_G3_CPU0_G1_TX_DP<11>")
	)
	(segment
		(start 151.564086 -195.871592)
		(end 151.581866 -195.692776)
		(width 0.14224)
		(layer "In11.Cu")
		(net "GMI_CPU1_G3_CPU0_G1_TX_DP<11>")
	)
	(segment
		(start 122.867674 -229.581964)
		(end 122.90679 -229.559104)
		(width 0.1143)
		(layer "In11.Cu")
		(net "GMI_CPU1_G3_CPU0_G1_TX_DP<11>")
	)
	(segment
		(start 156.233876 -191.878204)
		(end 156.412438 -191.89573)
		(width 0.14224)
		(layer "In11.Cu")
		(net "GMI_CPU1_G3_CPU0_G1_TX_DP<11>")
	)
	(segment
		(start 145.36039 -199.804274)
		(end 147.273772 -199.224646)
		(width 0.14224)
		(layer "In11.Cu")
		(net "GMI_CPU1_G3_CPU0_G1_TX_DP<11>")
	)
	(segment
		(start 348.808802 -233.07421)
		(end 348.738952 -233.14406)
		(width 0.1143)
		(layer "In11.Cu")
		(net "GMI_CPU1_G3_CPU0_G1_TX_DP<11>")
	)
	(segment
		(start 306.370736 -185.41492)
		(end 307.261006 -185.782966)
		(width 0.14224)
		(layer "In11.Cu")
		(net "GMI_CPU1_G3_CPU0_G1_TX_DP<11>")
	)
	(segment
		(start 122.90425 -230.248206)
		(end 122.837194 -230.20909)
		(width 0.1143)
		(layer "In11.Cu")
		(net "GMI_CPU1_G3_CPU0_G1_TX_DP<11>")
	)
	(segment
		(start 122.70613 -221.071948)
		(end 122.70613 -220.14688)
		(width 0.14224)
		(layer "In11.Cu")
		(net "GMI_CPU1_G3_CPU0_G1_TX_DP<11>")
	)
	(segment
		(start 122.867674 -222.127064)
		(end 122.837194 -222.109284)
		(width 0.1143)
		(layer "In11.Cu")
		(net "GMI_CPU1_G3_CPU0_G1_TX_DP<11>")
	)
	(segment
		(start 307.261006 -185.782966)
		(end 314.093606 -190.047626)
		(width 0.14224)
		(layer "In11.Cu")
		(net "GMI_CPU1_G3_CPU0_G1_TX_DP<11>")
	)
	(segment
		(start 122.70613 -221.083378)
		(end 122.70613 -221.071948)
		(width 0.1143)
		(layer "In11.Cu")
		(net "GMI_CPU1_G3_CPU0_G1_TX_DP<11>")
	)
	(segment
		(start 348.835472 -221.34703)
		(end 348.81566 -221.366842)
		(width 0.1143)
		(layer "In11.Cu")
		(net "GMI_CPU1_G3_CPU0_G1_TX_DP<11>")
	)
	(segment
		(start 157.552136 -190.961264)
		(end 157.569662 -190.782448)
		(width 0.14224)
		(layer "In11.Cu")
		(net "GMI_CPU1_G3_CPU0_G1_TX_DP<11>")
	)
	(segment
		(start 122.867674 -225.367088)
		(end 122.837194 -225.349308)
		(width 0.1143)
		(layer "In11.Cu")
		(net "GMI_CPU1_G3_CPU0_G1_TX_DP<11>")
	)
	(segment
		(start 123.350274 -232.004616)
		(end 123.376944 -231.988868)
		(width 0.1143)
		(layer "In11.Cu")
		(net "GMI_CPU1_G3_CPU0_G1_TX_DP<11>")
	)
	(segment
		(start 152.59431 -195.039996)
		(end 152.61336 -194.846956)
		(width 0.14224)
		(layer "In11.Cu")
		(net "GMI_CPU1_G3_CPU0_G1_TX_DP<11>")
	)
	(segment
		(start 348.589092 -229.55885)
		(end 348.628208 -229.58171)
		(width 0.1143)
		(layer "In11.Cu")
		(net "GMI_CPU1_G3_CPU0_G1_TX_DP<11>")
	)
	(segment
		(start 122.837194 -223.119696)
		(end 122.867674 -223.101916)
		(width 0.1143)
		(layer "In11.Cu")
		(net "GMI_CPU1_G3_CPU0_G1_TX_DP<11>")
	)
	(segment
		(start 122.867674 -227.961952)
		(end 122.90679 -227.939092)
		(width 0.1143)
		(layer "In11.Cu")
		(net "GMI_CPU1_G3_CPU0_G1_TX_DP<11>")
	)
	(segment
		(start 153.815542 -193.861182)
		(end 154.008582 -193.880232)
		(width 0.14224)
		(layer "In11.Cu")
		(net "GMI_CPU1_G3_CPU0_G1_TX_DP<11>")
	)
	(segment
		(start 122.867674 -224.721928)
		(end 122.90679 -224.699068)
		(width 0.1143)
		(layer "In11.Cu")
		(net "GMI_CPU1_G3_CPU0_G1_TX_DP<11>")
	)
	(segment
		(start 123.342654 -232.008934)
		(end 123.34367 -232.008426)
		(width 0.1143)
		(layer "In11.Cu")
		(net "GMI_CPU1_G3_CPU0_G1_TX_DP<11>")
	)
	(segment
		(start 158.377128 -190.284608)
		(end 158.394908 -190.106046)
		(width 0.14224)
		(layer "In11.Cu")
		(net "GMI_CPU1_G3_CPU0_G1_TX_DP<11>")
	)
	(segment
		(start 122.867674 -226.9871)
		(end 122.837194 -226.96932)
		(width 0.1143)
		(layer "In11.Cu")
		(net "GMI_CPU1_G3_CPU0_G1_TX_DP<11>")
	)
	(segment
		(start 123.337828 -232.011728)
		(end 123.338844 -232.01122)
		(width 0.1143)
		(layer "In11.Cu")
		(net "GMI_CPU1_G3_CPU0_G1_TX_DP<11>")
	)
	(segment
		(start 155.211018 -192.894204)
		(end 155.230068 -192.701164)
		(width 0.14224)
		(layer "In11.Cu")
		(net "GMI_CPU1_G3_CPU0_G1_TX_DP<11>")
	)
	(segment
		(start 348.789752 -220.011244)
		(end 348.789752 -221.071694)
		(width 0.14224)
		(layer "In11.Cu")
		(net "GMI_CPU1_G3_CPU0_G1_TX_DP<11>")
	)
	(segment
		(start 154.880818 -193.164968)
		(end 155.211018 -192.894204)
		(width 0.14224)
		(layer "In11.Cu")
		(net "GMI_CPU1_G3_CPU0_G1_TX_DP<11>")
	)
	(segment
		(start 149.193758 -197.6501)
		(end 149.194012 -197.6501)
		(width 0.14224)
		(layer "In11.Cu")
		(net "GMI_CPU1_G3_CPU0_G1_TX_DP<11>")
	)
	(segment
		(start 122.867674 -226.34194)
		(end 122.90679 -226.31908)
		(width 0.1143)
		(layer "In11.Cu")
		(net "GMI_CPU1_G3_CPU0_G1_TX_DP<11>")
	)
	(segment
		(start 348.589092 -226.318826)
		(end 348.658688 -226.359466)
		(width 0.1143)
		(layer "In11.Cu")
		(net "GMI_CPU1_G3_CPU0_G1_TX_DP<11>")
	)
	(segment
		(start 122.66041 -221.129098)
		(end 122.70613 -221.083378)
		(width 0.1143)
		(layer "In11.Cu")
		(net "GMI_CPU1_G3_CPU0_G1_TX_DP<11>")
	)
	(segment
		(start 122.835162 -229.60076)
		(end 122.867674 -229.581964)
		(width 0.1143)
		(layer "In11.Cu")
		(net "GMI_CPU1_G3_CPU0_G1_TX_DP<11>")
	)
	(segment
		(start 122.90679 -228.629972)
		(end 122.867674 -228.607112)
		(width 0.1143)
		(layer "In11.Cu")
		(net "GMI_CPU1_G3_CPU0_G1_TX_DP<11>")
	)
	(segment
		(start 163.330636 -186.058556)
		(end 167.331898 -184.62752)
		(width 0.14224)
		(layer "In11.Cu")
		(net "GMI_CPU1_G3_CPU0_G1_TX_DP<11>")
	)
	(segment
		(start 154.008582 -193.880232)
		(end 154.338782 -193.609468)
		(width 0.14224)
		(layer "In11.Cu")
		(net "GMI_CPU1_G3_CPU0_G1_TX_DP<11>")
	)
	(segment
		(start 156.727144 -191.63792)
		(end 156.74467 -191.459104)
		(width 0.14224)
		(layer "In11.Cu")
		(net "GMI_CPU1_G3_CPU0_G1_TX_DP<11>")
	)
	(segment
		(start 122.837194 -224.739708)
		(end 122.867674 -224.721928)
		(width 0.1143)
		(layer "In11.Cu")
		(net "GMI_CPU1_G3_CPU0_G1_TX_DP<11>")
	)
	(segment
		(start 122.837194 -232.839514)
		(end 122.867674 -232.821734)
		(width 0.1143)
		(layer "In11.Cu")
		(net "GMI_CPU1_G3_CPU0_G1_TX_DP<11>")
	)
	(segment
		(start 123.34367 -232.008426)
		(end 123.345448 -232.00741)
		(width 0.1143)
		(layer "In11.Cu")
		(net "GMI_CPU1_G3_CPU0_G1_TX_DP<11>")
	)
	(segment
		(start 123.340368 -232.010204)
		(end 123.341384 -232.009696)
		(width 0.1143)
		(layer "In11.Cu")
		(net "GMI_CPU1_G3_CPU0_G1_TX_DP<11>")
	)
	(segment
		(start 158.062676 -190.542672)
		(end 158.377128 -190.284608)
		(width 0.14224)
		(layer "In11.Cu")
		(net "GMI_CPU1_G3_CPU0_G1_TX_DP<11>")
	)
	(segment
		(start 314.093606 -190.047626)
		(end 347.038676 -217.061542)
		(width 0.14224)
		(layer "In11.Cu")
		(net "GMI_CPU1_G3_CPU0_G1_TX_DP<11>")
	)
	(segment
		(start 154.338782 -193.609468)
		(end 154.357832 -193.416428)
		(width 0.14224)
		(layer "In11.Cu")
		(net "GMI_CPU1_G3_CPU0_G1_TX_DP<11>")
	)
	(segment
		(start 154.357832 -193.416428)
		(end 154.687778 -193.145918)
		(width 0.14224)
		(layer "In11.Cu")
		(net "GMI_CPU1_G3_CPU0_G1_TX_DP<11>")
	)
	(segment
		(start 123.337828 -231.036876)
		(end 123.3043 -231.017318)
		(width 0.1143)
		(layer "In11.Cu")
		(net "GMI_CPU1_G3_CPU0_G1_TX_DP<11>")
	)
	(segment
		(start 348.164658 -232.015284)
		(end 348.165674 -232.015792)
		(width 0.1143)
		(layer "In11.Cu")
		(net "GMI_CPU1_G3_CPU0_G1_TX_DP<11>")
	)
	(segment
		(start 348.658688 -223.729042)
		(end 348.589092 -223.769682)
		(width 0.1143)
		(layer "In11.Cu")
		(net "GMI_CPU1_G3_CPU0_G1_TX_DP<11>")
	)
	(segment
		(start 157.569662 -190.782448)
		(end 157.88386 -190.524892)
		(width 0.14224)
		(layer "In11.Cu")
		(net "GMI_CPU1_G3_CPU0_G1_TX_DP<11>")
	)
	(segment
		(start 348.835472 -221.128844)
		(end 348.835472 -221.34703)
		(width 0.1143)
		(layer "In11.Cu")
		(net "GMI_CPU1_G3_CPU0_G1_TX_DP<11>")
	)
	(segment
		(start 157.88386 -190.524892)
		(end 158.062676 -190.542672)
		(width 0.14224)
		(layer "In11.Cu")
		(net "GMI_CPU1_G3_CPU0_G1_TX_DP<11>")
	)
	(segment
		(start 122.90679 -225.389948)
		(end 122.867674 -225.367088)
		(width 0.1143)
		(layer "In11.Cu")
		(net "GMI_CPU1_G3_CPU0_G1_TX_DP<11>")
	)
	(segment
		(start 348.628208 -229.58171)
		(end 348.66072 -229.600506)
		(width 0.1143)
		(layer "In11.Cu")
		(net "GMI_CPU1_G3_CPU0_G1_TX_DP<11>")
	)
	(segment
		(start 122.66041 -221.347284)
		(end 122.66041 -221.129098)
		(width 0.1143)
		(layer "In11.Cu")
		(net "GMI_CPU1_G3_CPU0_G1_TX_DP<11>")
	)
	(segment
		(start 157.237684 -191.219074)
		(end 157.552136 -190.961264)
		(width 0.14224)
		(layer "In11.Cu")
		(net "GMI_CPU1_G3_CPU0_G1_TX_DP<11>")
	)
	(segment
		(start 151.581866 -195.692776)
		(end 152.07107 -195.29171)
		(width 0.14224)
		(layer "In11.Cu")
		(net "GMI_CPU1_G3_CPU0_G1_TX_DP<11>")
	)
	(segment
		(start 155.230068 -192.701164)
		(end 156.233876 -191.878204)
		(width 0.14224)
		(layer "In11.Cu")
		(net "GMI_CPU1_G3_CPU0_G1_TX_DP<11>")
	)
	(segment
		(start 348.658688 -230.208836)
		(end 348.591632 -230.247952)
		(width 0.1143)
		(layer "In11.Cu")
		(net "GMI_CPU1_G3_CPU0_G1_TX_DP<11>")
	)
	(segment
		(start 122.90679 -227.00996)
		(end 122.867674 -226.9871)
		(width 0.1143)
		(layer "In11.Cu")
		(net "GMI_CPU1_G3_CPU0_G1_TX_DP<11>")
	)
	(segment
		(start 122.70613 -220.14688)
		(end 124.659898 -216.777824)
		(width 0.14224)
		(layer "In11.Cu")
		(net "GMI_CPU1_G3_CPU0_G1_TX_DP<11>")
	)
	(segment
		(start 153.485596 -194.131692)
		(end 153.815542 -193.861182)
		(width 0.14224)
		(layer "In11.Cu")
		(net "GMI_CPU1_G3_CPU0_G1_TX_DP<11>")
	)
	(segment
		(start 122.680222 -221.367096)
		(end 122.66041 -221.347284)
		(width 0.1143)
		(layer "In11.Cu")
		(net "GMI_CPU1_G3_CPU0_G1_TX_DP<11>")
	)
	(segment
		(start 152.943306 -194.576446)
		(end 153.136346 -194.595496)
		(width 0.14224)
		(layer "In11.Cu")
		(net "GMI_CPU1_G3_CPU0_G1_TX_DP<11>")
	)
	(segment
		(start 348.589092 -232.79862)
		(end 348.658688 -232.83926)
		(width 0.1143)
		(layer "In11.Cu")
		(net "GMI_CPU1_G3_CPU0_G1_TX_DP<11>")
	)
	(segment
		(start 348.191582 -231.017064)
		(end 348.118938 -231.059482)
		(width 0.1143)
		(layer "In11.Cu")
		(net "GMI_CPU1_G3_CPU0_G1_TX_DP<11>")
	)
	(segment
		(start 152.61336 -194.846956)
		(end 152.943306 -194.576446)
		(width 0.14224)
		(layer "In11.Cu")
		(net "GMI_CPU1_G3_CPU0_G1_TX_DP<11>")
	)
	(segment
		(start 348.658688 -228.589078)
		(end 348.589092 -228.629718)
		(width 0.1143)
		(layer "In11.Cu")
		(net "GMI_CPU1_G3_CPU0_G1_TX_DP<11>")
	)
	(segment
		(start 147.273772 -199.224646)
		(end 149.193758 -197.6501)
		(width 0.14224)
		(layer "In11.Cu")
		(net "GMI_CPU1_G3_CPU0_G1_TX_DP<11>")
	)
	(segment
		(start 124.659898 -216.777824)
		(end 145.36039 -199.804274)
		(width 0.14224)
		(layer "In11.Cu")
		(net "GMI_CPU1_G3_CPU0_G1_TX_DP<11>")
	)
	(segment
		(start 348.158054 -232.011474)
		(end 348.158816 -232.011982)
		(width 0.1143)
		(layer "In11.Cu")
		(net "GMI_CPU1_G3_CPU0_G1_TX_DP<11>")
	)
	(segment
		(start 348.789752 -221.083124)
		(end 348.835472 -221.128844)
		(width 0.1143)
		(layer "In11.Cu")
		(net "GMI_CPU1_G3_CPU0_G1_TX_DP<11>")
	)
	(segment
		(start 154.687778 -193.145918)
		(end 154.880818 -193.164968)
		(width 0.14224)
		(layer "In11.Cu")
		(net "GMI_CPU1_G3_CPU0_G1_TX_DP<11>")
	)
	(segment
		(start 348.165674 -232.015792)
		(end 348.189804 -232.029762)
		(width 0.1143)
		(layer "In11.Cu")
		(net "GMI_CPU1_G3_CPU0_G1_TX_DP<11>")
	)
	(segment
		(start 157.058868 -191.201548)
		(end 157.237684 -191.219074)
		(width 0.14224)
		(layer "In11.Cu")
		(net "GMI_CPU1_G3_CPU0_G1_TX_DP<11>")
	)
	(segment
		(start 348.118938 -231.988614)
		(end 348.152974 -232.008426)
		(width 0.1143)
		(layer "In11.Cu")
		(net "GMI_CPU1_G3_CPU0_G1_TX_DP<11>")
	)
	(segment
		(start 122.867674 -223.747076)
		(end 122.837194 -223.729296)
		(width 0.1143)
		(layer "In11.Cu")
		(net "GMI_CPU1_G3_CPU0_G1_TX_DP<11>")
	)
	(segment
		(start 348.81566 -221.366842)
		(end 348.81566 -221.80423)
		(width 0.1143)
		(layer "In11.Cu")
		(net "GMI_CPU1_G3_CPU0_G1_TX_DP<11>")
	)
	(segment
		(start 122.90679 -222.149924)
		(end 122.867674 -222.127064)
		(width 0.1143)
		(layer "In11.Cu")
		(net "GMI_CPU1_G3_CPU0_G1_TX_DP<11>")
	)
	(segment
		(start 153.136346 -194.595496)
		(end 153.466546 -194.324732)
		(width 0.14224)
		(layer "In11.Cu")
		(net "GMI_CPU1_G3_CPU0_G1_TX_DP<11>")
	)
	(segment
		(start 123.345448 -232.00741)
		(end 123.349512 -232.005124)
		(width 0.1143)
		(layer "In11.Cu")
		(net "GMI_CPU1_G3_CPU0_G1_TX_DP<11>")
	)
	(segment
		(start 348.158816 -232.011982)
		(end 348.16161 -232.013506)
		(width 0.1143)
		(layer "In11.Cu")
		(net "GMI_CPU1_G3_CPU0_G1_TX_DP<11>")
	)
	(segment
		(start 302.604932 -185.41492)
		(end 306.370736 -185.41492)
		(width 0.14224)
		(layer "In11.Cu")
		(net "GMI_CPU1_G3_CPU0_G1_TX_DP<11>")
	)
	(segment
		(start 149.194012 -197.6501)
		(end 151.070818 -196.111622)
		(width 0.14224)
		(layer "In11.Cu")
		(net "GMI_CPU1_G3_CPU0_G1_TX_DP<11>")
	)
	(segment
		(start 123.054618 -233.144314)
		(end 122.75693 -233.144314)
		(width 0.1143)
		(layer "In11.Cu")
		(net "GMI_CPU1_G3_CPU0_G1_TX_DP<11>")
	)
	(segment
		(start 348.15399 -232.008934)
		(end 348.158054 -232.011474)
		(width 0.1143)
		(layer "In11.Cu")
		(net "GMI_CPU1_G3_CPU0_G1_TX_DP<11>")
	)
	(segment
		(start 123.337066 -232.012236)
		(end 123.337828 -232.011728)
		(width 0.1143)
		(layer "In11.Cu")
		(net "GMI_CPU1_G3_CPU0_G1_TX_DP<11>")
	)
	(segment
		(start 158.394908 -190.106046)
		(end 163.330636 -186.058556)
		(width 0.14224)
		(layer "In11.Cu")
		(net "GMI_CPU1_G3_CPU0_G1_TX_DP<11>")
	)
	(segment
		(start 122.837194 -226.35972)
		(end 122.867674 -226.34194)
		(width 0.1143)
		(layer "In11.Cu")
		(net "GMI_CPU1_G3_CPU0_G1_TX_DP<11>")
	)
	(segment
		(start 348.658688 -225.349054)
		(end 348.589092 -225.389694)
		(width 0.1143)
		(layer "In11.Cu")
		(net "GMI_CPU1_G3_CPU0_G1_TX_DP<11>")
	)
	(segment
		(start 123.306078 -232.030016)
		(end 123.337066 -232.012236)
		(width 0.1143)
		(layer "In11.Cu")
		(net "GMI_CPU1_G3_CPU0_G1_TX_DP<11>")
	)
	(segment
		(start 348.789752 -221.071694)
		(end 348.789752 -221.083124)
		(width 0.1143)
		(layer "In11.Cu")
		(net "GMI_CPU1_G3_CPU0_G1_TX_DP<11>")
	)
	(segment
		(start 151.249634 -196.129402)
		(end 151.564086 -195.871592)
		(width 0.14224)
		(layer "In11.Cu")
		(net "GMI_CPU1_G3_CPU0_G1_TX_DP<11>")
	)
	(segment
		(start 156.412438 -191.89573)
		(end 156.727144 -191.63792)
		(width 0.14224)
		(layer "In11.Cu")
		(net "GMI_CPU1_G3_CPU0_G1_TX_DP<11>")
	)
	(segment
		(start 152.07107 -195.29171)
		(end 152.26411 -195.31076)
		(width 0.14224)
		(layer "In11.Cu")
		(net "GMI_CPU1_G3_CPU0_G1_TX_DP<11>")
	)
	(segment
		(start 348.152974 -232.008426)
		(end 348.15399 -232.008934)
		(width 0.1143)
		(layer "In11.Cu")
		(net "GMI_CPU1_G3_CPU0_G1_TX_DP<11>")
	)
	(segment
		(start 122.680222 -221.804484)
		(end 122.680222 -221.367096)
		(width 0.1143)
		(layer "In11.Cu")
		(net "GMI_CPU1_G3_CPU0_G1_TX_DP<11>")
	)
	(segment
		(start 152.26411 -195.31076)
		(end 152.59431 -195.039996)
		(width 0.14224)
		(layer "In11.Cu")
		(net "GMI_CPU1_G3_CPU0_G1_TX_DP<11>")
	)
	(segment
		(start 348.658688 -222.10903)
		(end 348.589092 -222.14967)
		(width 0.1143)
		(layer "In11.Cu")
		(net "GMI_CPU1_G3_CPU0_G1_TX_DP<11>")
	)
	(segment
		(start 347.038676 -217.061542)
		(end 348.789752 -220.011244)
		(width 0.14224)
		(layer "In11.Cu")
		(net "GMI_CPU1_G3_CPU0_G1_TX_DP<11>")
	)
	(segment
		(start 348.658688 -226.969066)
		(end 348.589092 -227.009706)
		(width 0.1143)
		(layer "In11.Cu")
		(net "GMI_CPU1_G3_CPU0_G1_TX_DP<11>")
	)
	(segment
		(start 122.867674 -223.101916)
		(end 122.90679 -223.079056)
		(width 0.1143)
		(layer "In11.Cu")
		(net "GMI_CPU1_G3_CPU0_G1_TX_DP<11>")
	)
	(segment
		(start 153.466546 -194.324732)
		(end 153.485596 -194.131692)
		(width 0.14224)
		(layer "In11.Cu")
		(net "GMI_CPU1_G3_CPU0_G1_TX_DP<11>")
	)
	(segment
		(start 348.589092 -227.938838)
		(end 348.658688 -227.979478)
		(width 0.1143)
		(layer "In11.Cu")
		(net "GMI_CPU1_G3_CPU0_G1_TX_DP<11>")
	)
	(segment
		(start 123.338844 -232.01122)
		(end 123.340368 -232.010204)
		(width 0.1143)
		(layer "In11.Cu")
		(net "GMI_CPU1_G3_CPU0_G1_TX_DP<11>")
	)
	(segment
		(start 122.837194 -227.979732)
		(end 122.867674 -227.961952)
		(width 0.1143)
		(layer "In11.Cu")
		(net "GMI_CPU1_G3_CPU0_G1_TX_DP<11>")
	)
	(segment
		(start 123.349512 -232.005124)
		(end 123.350274 -232.004616)
		(width 0.1143)
		(layer "In11.Cu")
		(net "GMI_CPU1_G3_CPU0_G1_TX_DP<11>")
	)
	(segment
		(start 122.90679 -223.769936)
		(end 122.867674 -223.747076)
		(width 0.1143)
		(layer "In11.Cu")
		(net "GMI_CPU1_G3_CPU0_G1_TX_DP<11>")
	)
	(segment
		(start 348.16161 -232.013506)
		(end 348.162372 -232.014014)
		(width 0.1143)
		(layer "In11.Cu")
		(net "GMI_CPU1_G3_CPU0_G1_TX_DP<11>")
	)
	(segment
		(start 122.867674 -228.607112)
		(end 122.837194 -228.589332)
		(width 0.1143)
		(layer "In11.Cu")
		(net "GMI_CPU1_G3_CPU0_G1_TX_DP<11>")
	)
	(segment
		(start 348.589092 -224.698814)
		(end 348.658688 -224.739454)
		(width 0.1143)
		(layer "In11.Cu")
		(net "GMI_CPU1_G3_CPU0_G1_TX_DP<11>")
	)
	(segment
		(start 348.589092 -223.078802)
		(end 348.658688 -223.119442)
		(width 0.1143)
		(layer "In11.Cu")
		(net "GMI_CPU1_G3_CPU0_G1_TX_DP<11>")
	)
	(segment
		(start 156.74467 -191.459104)
		(end 157.058868 -191.201548)
		(width 0.14224)
		(layer "In11.Cu")
		(net "GMI_CPU1_G3_CPU0_G1_TX_DP<11>")
	)
	(segment
		(start 151.070818 -196.111622)
		(end 151.249634 -196.129402)
		(width 0.14224)
		(layer "In11.Cu")
		(net "GMI_CPU1_G3_CPU0_G1_TX_DP<11>")
	)
	(segment
		(start 122.867674 -232.821734)
		(end 122.90679 -232.798874)
		(width 0.1143)
		(layer "In11.Cu")
		(net "GMI_CPU1_G3_CPU0_G1_TX_DP<11>")
	)
	(segment
		(start 167.331898 -184.62752)
		(end 302.604932 -185.41492)
		(width 0.14224)
		(layer "In11.Cu")
		(net "GMI_CPU1_G3_CPU0_G1_TX_DP<11>")
	)
	(segment
		(start 122.75693 -233.144314)
		(end 122.68708 -233.074464)
		(width 0.1143)
		(layer "In11.Cu")
		(net "GMI_CPU1_G3_CPU0_G1_TX_DP<11>")
	)
	(segment
		(start 348.162372 -232.014014)
		(end 348.163896 -232.014776)
		(width 0.1143)
		(layer "In11.Cu")
		(net "GMI_CPU1_G3_CPU0_G1_TX_DP<11>")
	)
	(segment
		(start 348.738952 -233.14406)
		(end 348.44101 -233.14406)
		(width 0.1143)
		(layer "In11.Cu")
		(net "GMI_CPU1_G3_CPU0_G1_TX_DP<11>")
	)
	(segment
		(start 348.163896 -232.014776)
		(end 348.164658 -232.015284)
		(width 0.1143)
		(layer "In11.Cu")
		(net "GMI_CPU1_G3_CPU0_G1_TX_DP<11>")
	)
	(arc
		(start 123.376944 -231.988868)
		(mid 123.620271 -231.524302)
		(end 123.376944 -231.059736)
		(width 0.1143)
		(layer "In11.Cu")
		(net "GMI_CPU1_G3_CPU0_G1_TX_DP<11>")
	)
	(arc
		(start 122.90679 -226.31908)
		(mid 123.150117 -225.854514)
		(end 122.90679 -225.389948)
		(width 0.1143)
		(layer "In11.Cu")
		(net "GMI_CPU1_G3_CPU0_G1_TX_DP<11>")
	)
	(arc
		(start 123.150122 -232.334308)
		(mid 123.191377 -232.163337)
		(end 123.306078 -232.030016)
		(width 0.1143)
		(layer "In11.Cu")
		(net "GMI_CPU1_G3_CPU0_G1_TX_DP<11>")
	)
	(arc
		(start 348.66072 -229.600506)
		(mid 348.774649 -229.733653)
		(end 348.81566 -229.904036)
		(width 0.1143)
		(layer "In11.Cu")
		(net "GMI_CPU1_G3_CPU0_G1_TX_DP<11>")
	)
	(arc
		(start 122.90679 -223.079056)
		(mid 123.150117 -222.61449)
		(end 122.90679 -222.149924)
		(width 0.1143)
		(layer "In11.Cu")
		(net "GMI_CPU1_G3_CPU0_G1_TX_DP<11>")
	)
	(arc
		(start 348.34576 -232.334054)
		(mid 348.410275 -232.596273)
		(end 348.589092 -232.79862)
		(width 0.1143)
		(layer "In11.Cu")
		(net "GMI_CPU1_G3_CPU0_G1_TX_DP<11>")
	)
	(arc
		(start 348.591632 -230.247952)
		(mid 348.41098 -230.450697)
		(end 348.34576 -230.714296)
		(width 0.1143)
		(layer "In11.Cu")
		(net "GMI_CPU1_G3_CPU0_G1_TX_DP<11>")
	)
	(arc
		(start 123.150122 -230.71455)
		(mid 123.084886 -230.450959)
		(end 122.90425 -230.248206)
		(width 0.1143)
		(layer "In11.Cu")
		(net "GMI_CPU1_G3_CPU0_G1_TX_DP<11>")
	)
	(arc
		(start 348.658688 -223.119442)
		(mid 348.815665 -223.424242)
		(end 348.658688 -223.729042)
		(width 0.1143)
		(layer "In11.Cu")
		(net "GMI_CPU1_G3_CPU0_G1_TX_DP<11>")
	)
	(arc
		(start 348.81566 -221.80423)
		(mid 348.774111 -221.975652)
		(end 348.658688 -222.10903)
		(width 0.1143)
		(layer "In11.Cu")
		(net "GMI_CPU1_G3_CPU0_G1_TX_DP<11>")
	)
	(arc
		(start 122.837194 -223.729296)
		(mid 122.680217 -223.424496)
		(end 122.837194 -223.119696)
		(width 0.1143)
		(layer "In11.Cu")
		(net "GMI_CPU1_G3_CPU0_G1_TX_DP<11>")
	)
	(arc
		(start 122.90679 -232.798874)
		(mid 123.085603 -232.596524)
		(end 123.150122 -232.334308)
		(width 0.1143)
		(layer "In11.Cu")
		(net "GMI_CPU1_G3_CPU0_G1_TX_DP<11>")
	)
	(arc
		(start 348.189804 -232.029762)
		(mid 348.30448 -232.163096)
		(end 348.34576 -232.334054)
		(width 0.1143)
		(layer "In11.Cu")
		(net "GMI_CPU1_G3_CPU0_G1_TX_DP<11>")
	)
	(arc
		(start 122.90679 -227.939092)
		(mid 123.150117 -227.474526)
		(end 122.90679 -227.00996)
		(width 0.1143)
		(layer "In11.Cu")
		(net "GMI_CPU1_G3_CPU0_G1_TX_DP<11>")
	)
	(arc
		(start 348.658688 -226.359466)
		(mid 348.815665 -226.664266)
		(end 348.658688 -226.969066)
		(width 0.1143)
		(layer "In11.Cu")
		(net "GMI_CPU1_G3_CPU0_G1_TX_DP<11>")
	)
	(arc
		(start 348.81566 -229.904036)
		(mid 348.774111 -230.075458)
		(end 348.658688 -230.208836)
		(width 0.1143)
		(layer "In11.Cu")
		(net "GMI_CPU1_G3_CPU0_G1_TX_DP<11>")
	)
	(arc
		(start 122.90679 -229.559104)
		(mid 123.150117 -229.094538)
		(end 122.90679 -228.629972)
		(width 0.1143)
		(layer "In11.Cu")
		(net "GMI_CPU1_G3_CPU0_G1_TX_DP<11>")
	)
	(arc
		(start 122.837194 -230.20909)
		(mid 122.721767 -230.075714)
		(end 122.680222 -229.90429)
		(width 0.1143)
		(layer "In11.Cu")
		(net "GMI_CPU1_G3_CPU0_G1_TX_DP<11>")
	)
	(arc
		(start 122.837194 -226.96932)
		(mid 122.680217 -226.66452)
		(end 122.837194 -226.35972)
		(width 0.1143)
		(layer "In11.Cu")
		(net "GMI_CPU1_G3_CPU0_G1_TX_DP<11>")
	)
	(arc
		(start 348.658688 -224.739454)
		(mid 348.815665 -225.044254)
		(end 348.658688 -225.349054)
		(width 0.1143)
		(layer "In11.Cu")
		(net "GMI_CPU1_G3_CPU0_G1_TX_DP<11>")
	)
	(arc
		(start 348.589092 -227.009706)
		(mid 348.345765 -227.474272)
		(end 348.589092 -227.938838)
		(width 0.1143)
		(layer "In11.Cu")
		(net "GMI_CPU1_G3_CPU0_G1_TX_DP<11>")
	)
	(arc
		(start 122.90679 -224.699068)
		(mid 123.150117 -224.234502)
		(end 122.90679 -223.769936)
		(width 0.1143)
		(layer "In11.Cu")
		(net "GMI_CPU1_G3_CPU0_G1_TX_DP<11>")
	)
	(arc
		(start 348.658688 -232.83926)
		(mid 348.756453 -232.942236)
		(end 348.808802 -233.07421)
		(width 0.1143)
		(layer "In11.Cu")
		(net "GMI_CPU1_G3_CPU0_G1_TX_DP<11>")
	)
	(arc
		(start 122.837194 -225.349308)
		(mid 122.680217 -225.044508)
		(end 122.837194 -224.739708)
		(width 0.1143)
		(layer "In11.Cu")
		(net "GMI_CPU1_G3_CPU0_G1_TX_DP<11>")
	)
	(arc
		(start 122.837194 -228.589332)
		(mid 122.680217 -228.284532)
		(end 122.837194 -227.979732)
		(width 0.1143)
		(layer "In11.Cu")
		(net "GMI_CPU1_G3_CPU0_G1_TX_DP<11>")
	)
	(arc
		(start 122.837194 -222.109284)
		(mid 122.721767 -221.975908)
		(end 122.680222 -221.804484)
		(width 0.1143)
		(layer "In11.Cu")
		(net "GMI_CPU1_G3_CPU0_G1_TX_DP<11>")
	)
	(arc
		(start 348.118938 -231.059482)
		(mid 347.875611 -231.524048)
		(end 348.118938 -231.988614)
		(width 0.1143)
		(layer "In11.Cu")
		(net "GMI_CPU1_G3_CPU0_G1_TX_DP<11>")
	)
	(arc
		(start 348.658688 -227.979478)
		(mid 348.815665 -228.284278)
		(end 348.658688 -228.589078)
		(width 0.1143)
		(layer "In11.Cu")
		(net "GMI_CPU1_G3_CPU0_G1_TX_DP<11>")
	)
	(arc
		(start 348.34576 -230.714296)
		(mid 348.304998 -230.88418)
		(end 348.191582 -231.017064)
		(width 0.1143)
		(layer "In11.Cu")
		(net "GMI_CPU1_G3_CPU0_G1_TX_DP<11>")
	)
	(arc
		(start 348.589092 -223.769682)
		(mid 348.345765 -224.234248)
		(end 348.589092 -224.698814)
		(width 0.1143)
		(layer "In11.Cu")
		(net "GMI_CPU1_G3_CPU0_G1_TX_DP<11>")
	)
	(arc
		(start 348.589092 -228.629718)
		(mid 348.345765 -229.094284)
		(end 348.589092 -229.55885)
		(width 0.1143)
		(layer "In11.Cu")
		(net "GMI_CPU1_G3_CPU0_G1_TX_DP<11>")
	)
	(arc
		(start 122.680222 -229.90429)
		(mid 122.721188 -229.733884)
		(end 122.835162 -229.60076)
		(width 0.1143)
		(layer "In11.Cu")
		(net "GMI_CPU1_G3_CPU0_G1_TX_DP<11>")
	)
	(arc
		(start 348.589092 -222.14967)
		(mid 348.345765 -222.614236)
		(end 348.589092 -223.078802)
		(width 0.1143)
		(layer "In11.Cu")
		(net "GMI_CPU1_G3_CPU0_G1_TX_DP<11>")
	)
	(arc
		(start 348.589092 -225.389694)
		(mid 348.345765 -225.85426)
		(end 348.589092 -226.318826)
		(width 0.1143)
		(layer "In11.Cu")
		(net "GMI_CPU1_G3_CPU0_G1_TX_DP<11>")
	)
	(arc
		(start 122.68708 -233.074464)
		(mid 122.739497 -232.942533)
		(end 122.837194 -232.839514)
		(width 0.1143)
		(layer "In11.Cu")
		(net "GMI_CPU1_G3_CPU0_G1_TX_DP<11>")
	)
	(arc
		(start 123.3043 -231.017318)
		(mid 123.190893 -230.884429)
		(end 123.150122 -230.71455)
		(width 0.1143)
		(layer "In11.Cu")
		(net "GMI_CPU1_G3_CPU0_G1_TX_DP<11>")
	)
	(segment
		(start 122.587766 -231.79024)
		(end 123.054618 -231.524302)
		(width 0.12954)
		(layer "F.Cu")
		(net "GMI_CPU1_G3_CPU0_G1_TX_DP<10>")
	)
	(segment
		(start 348.907862 -231.789986)
		(end 348.44101 -231.524048)
		(width 0.12954)
		(layer "F.Cu")
		(net "GMI_CPU1_G3_CPU0_G1_TX_DP<10>")
	)
	(segment
		(start 349.528892 -225.38944)
		(end 349.501206 -225.409506)
		(width 0.1143)
		(layer "In11.Cu")
		(net "GMI_CPU1_G3_CPU0_G1_TX_DP<10>")
	)
	(segment
		(start 155.735274 -190.895986)
		(end 155.917392 -190.91402)
		(width 0.14224)
		(layer "In11.Cu")
		(net "GMI_CPU1_G3_CPU0_G1_TX_DP<10>")
	)
	(segment
		(start 349.599758 -223.72828)
		(end 349.583756 -223.737424)
		(width 0.1143)
		(layer "In11.Cu")
		(net "GMI_CPU1_G3_CPU0_G1_TX_DP<10>")
	)
	(segment
		(start 349.755714 -221.371668)
		(end 349.755714 -221.80423)
		(width 0.1143)
		(layer "In11.Cu")
		(net "GMI_CPU1_G3_CPU0_G1_TX_DP<10>")
	)
	(segment
		(start 121.76125 -219.878148)
		(end 123.974098 -216.074498)
		(width 0.14224)
		(layer "In11.Cu")
		(net "GMI_CPU1_G3_CPU0_G1_TX_DP<10>")
	)
	(segment
		(start 312.96737 -187.8584)
		(end 347.686884 -216.32672)
		(width 0.14224)
		(layer "In11.Cu")
		(net "GMI_CPU1_G3_CPU0_G1_TX_DP<10>")
	)
	(segment
		(start 349.528892 -224.699068)
		(end 349.599758 -224.739962)
		(width 0.1143)
		(layer "In11.Cu")
		(net "GMI_CPU1_G3_CPU0_G1_TX_DP<10>")
	)
	(segment
		(start 349.569786 -230.2256)
		(end 349.568262 -230.226362)
		(width 0.1143)
		(layer "In11.Cu")
		(net "GMI_CPU1_G3_CPU0_G1_TX_DP<10>")
	)
	(segment
		(start 121.740168 -229.90429)
		(end 121.740168 -229.904036)
		(width 0.1143)
		(layer "In11.Cu")
		(net "GMI_CPU1_G3_CPU0_G1_TX_DP<10>")
	)
	(segment
		(start 349.567754 -226.9871)
		(end 349.528892 -227.009452)
		(width 0.1143)
		(layer "In11.Cu")
		(net "GMI_CPU1_G3_CPU0_G1_TX_DP<10>")
	)
	(segment
		(start 121.96699 -225.389694)
		(end 121.928128 -225.367342)
		(width 0.1143)
		(layer "In11.Cu")
		(net "GMI_CPU1_G3_CPU0_G1_TX_DP<10>")
	)
	(segment
		(start 349.528892 -226.31908)
		(end 349.599758 -226.359974)
		(width 0.1143)
		(layer "In11.Cu")
		(net "GMI_CPU1_G3_CPU0_G1_TX_DP<10>")
	)
	(segment
		(start 157.108398 -189.770258)
		(end 157.432502 -189.504574)
		(width 0.14224)
		(layer "In11.Cu")
		(net "GMI_CPU1_G3_CPU0_G1_TX_DP<10>")
	)
	(segment
		(start 349.583756 -225.357436)
		(end 349.567754 -225.367088)
		(width 0.1143)
		(layer "In11.Cu")
		(net "GMI_CPU1_G3_CPU0_G1_TX_DP<10>")
	)
	(segment
		(start 162.591242 -185.275474)
		(end 167.0431 -183.68391)
		(width 0.14224)
		(layer "In11.Cu")
		(net "GMI_CPU1_G3_CPU0_G1_TX_DP<10>")
	)
	(segment
		(start 349.54845 -223.090232)
		(end 349.549974 -223.091248)
		(width 0.1143)
		(layer "In11.Cu")
		(net "GMI_CPU1_G3_CPU0_G1_TX_DP<10>")
	)
	(segment
		(start 349.780352 -221.34703)
		(end 349.755714 -221.371668)
		(width 0.1143)
		(layer "In11.Cu")
		(net "GMI_CPU1_G3_CPU0_G1_TX_DP<10>")
	)
	(segment
		(start 121.928128 -226.987354)
		(end 121.912126 -226.977702)
		(width 0.1143)
		(layer "In11.Cu")
		(net "GMI_CPU1_G3_CPU0_G1_TX_DP<10>")
	)
	(segment
		(start 349.567754 -225.367088)
		(end 349.528892 -225.38944)
		(width 0.1143)
		(layer "In11.Cu")
		(net "GMI_CPU1_G3_CPU0_G1_TX_DP<10>")
	)
	(segment
		(start 145.905982 -198.495158)
		(end 146.793712 -198.226172)
		(width 0.14224)
		(layer "In11.Cu")
		(net "GMI_CPU1_G3_CPU0_G1_TX_DP<10>")
	)
	(segment
		(start 349.599758 -223.728534)
		(end 349.599758 -223.72828)
		(width 0.1143)
		(layer "In11.Cu")
		(net "GMI_CPU1_G3_CPU0_G1_TX_DP<10>")
	)
	(segment
		(start 349.501206 -226.299014)
		(end 349.528892 -226.31908)
		(width 0.1143)
		(layer "In11.Cu")
		(net "GMI_CPU1_G3_CPU0_G1_TX_DP<10>")
	)
	(segment
		(start 121.912126 -226.977702)
		(end 121.896124 -226.968558)
		(width 0.1143)
		(layer "In11.Cu")
		(net "GMI_CPU1_G3_CPU0_G1_TX_DP<10>")
	)
	(segment
		(start 151.379936 -194.46621)
		(end 151.572976 -194.485514)
		(width 0.14224)
		(layer "In11.Cu")
		(net "GMI_CPU1_G3_CPU0_G1_TX_DP<10>")
	)
	(segment
		(start 349.599758 -226.968558)
		(end 349.599758 -226.968304)
		(width 0.1143)
		(layer "In11.Cu")
		(net "GMI_CPU1_G3_CPU0_G1_TX_DP<10>")
	)
	(segment
		(start 153.647648 -192.78473)
		(end 153.666698 -192.59169)
		(width 0.14224)
		(layer "In11.Cu")
		(net "GMI_CPU1_G3_CPU0_G1_TX_DP<10>")
	)
	(segment
		(start 152.794462 -193.3067)
		(end 153.124408 -193.03619)
		(width 0.14224)
		(layer "In11.Cu")
		(net "GMI_CPU1_G3_CPU0_G1_TX_DP<10>")
	)
	(segment
		(start 347.686884 -216.32672)
		(end 349.734632 -219.775532)
		(width 0.14224)
		(layer "In11.Cu")
		(net "GMI_CPU1_G3_CPU0_G1_TX_DP<10>")
	)
	(segment
		(start 155.06192 -191.625474)
		(end 155.39212 -191.35471)
		(width 0.14224)
		(layer "In11.Cu")
		(net "GMI_CPU1_G3_CPU0_G1_TX_DP<10>")
	)
	(segment
		(start 349.599758 -226.968304)
		(end 349.583756 -226.977448)
		(width 0.1143)
		(layer "In11.Cu")
		(net "GMI_CPU1_G3_CPU0_G1_TX_DP<10>")
	)
	(segment
		(start 349.501206 -224.679002)
		(end 349.528892 -224.699068)
		(width 0.1143)
		(layer "In11.Cu")
		(net "GMI_CPU1_G3_CPU0_G1_TX_DP<10>")
	)
	(segment
		(start 155.917392 -190.91402)
		(end 156.24175 -190.648082)
		(width 0.14224)
		(layer "In11.Cu")
		(net "GMI_CPU1_G3_CPU0_G1_TX_DP<10>")
	)
	(segment
		(start 349.755714 -229.903782)
		(end 349.755714 -229.904036)
		(width 0.1143)
		(layer "In11.Cu")
		(net "GMI_CPU1_G3_CPU0_G1_TX_DP<10>")
	)
	(segment
		(start 349.599758 -228.58857)
		(end 349.568008 -228.606858)
		(width 0.1143)
		(layer "In11.Cu")
		(net "GMI_CPU1_G3_CPU0_G1_TX_DP<10>")
	)
	(segment
		(start 145.905728 -198.495158)
		(end 145.905982 -198.495158)
		(width 0.14224)
		(layer "In11.Cu")
		(net "GMI_CPU1_G3_CPU0_G1_TX_DP<10>")
	)
	(segment
		(start 152.775412 -193.49974)
		(end 152.794462 -193.3067)
		(width 0.14224)
		(layer "In11.Cu")
		(net "GMI_CPU1_G3_CPU0_G1_TX_DP<10>")
	)
	(segment
		(start 121.94921 -222.13951)
		(end 121.896124 -222.108776)
		(width 0.1143)
		(layer "In11.Cu")
		(net "GMI_CPU1_G3_CPU0_G1_TX_DP<10>")
	)
	(segment
		(start 167.0431 -183.68391)
		(end 302.888904 -184.474866)
		(width 0.14224)
		(layer "In11.Cu")
		(net "GMI_CPU1_G3_CPU0_G1_TX_DP<10>")
	)
	(segment
		(start 121.92762 -230.226616)
		(end 121.926096 -230.225854)
		(width 0.1143)
		(layer "In11.Cu")
		(net "GMI_CPU1_G3_CPU0_G1_TX_DP<10>")
	)
	(segment
		(start 121.894346 -229.601522)
		(end 121.964196 -229.560882)
		(width 0.1143)
		(layer "In11.Cu")
		(net "GMI_CPU1_G3_CPU0_G1_TX_DP<10>")
	)
	(segment
		(start 349.599758 -225.348292)
		(end 349.583756 -225.357436)
		(width 0.1143)
		(layer "In11.Cu")
		(net "GMI_CPU1_G3_CPU0_G1_TX_DP<10>")
	)
	(segment
		(start 349.549974 -223.091248)
		(end 349.551498 -223.09201)
		(width 0.1143)
		(layer "In11.Cu")
		(net "GMI_CPU1_G3_CPU0_G1_TX_DP<10>")
	)
	(segment
		(start 349.565976 -230.227632)
		(end 349.528384 -230.249984)
		(width 0.1143)
		(layer "In11.Cu")
		(net "GMI_CPU1_G3_CPU0_G1_TX_DP<10>")
	)
	(segment
		(start 121.967498 -230.250238)
		(end 121.92889 -230.227378)
		(width 0.1143)
		(layer "In11.Cu")
		(net "GMI_CPU1_G3_CPU0_G1_TX_DP<10>")
	)
	(segment
		(start 121.71553 -221.129098)
		(end 121.76125 -221.083378)
		(width 0.1143)
		(layer "In11.Cu")
		(net "GMI_CPU1_G3_CPU0_G1_TX_DP<10>")
	)
	(segment
		(start 121.896124 -224.740216)
		(end 121.96699 -224.699322)
		(width 0.1143)
		(layer "In11.Cu")
		(net "GMI_CPU1_G3_CPU0_G1_TX_DP<10>")
	)
	(segment
		(start 151.922226 -194.02171)
		(end 152.252172 -193.7512)
		(width 0.14224)
		(layer "In11.Cu")
		(net "GMI_CPU1_G3_CPU0_G1_TX_DP<10>")
	)
	(segment
		(start 121.71553 -221.347284)
		(end 121.71553 -221.129098)
		(width 0.1143)
		(layer "In11.Cu")
		(net "GMI_CPU1_G3_CPU0_G1_TX_DP<10>")
	)
	(segment
		(start 156.259784 -190.465964)
		(end 156.583888 -190.20028)
		(width 0.14224)
		(layer "In11.Cu")
		(net "GMI_CPU1_G3_CPU0_G1_TX_DP<10>")
	)
	(segment
		(start 121.92889 -230.227378)
		(end 121.92762 -230.226616)
		(width 0.1143)
		(layer "In11.Cu")
		(net "GMI_CPU1_G3_CPU0_G1_TX_DP<10>")
	)
	(segment
		(start 121.927874 -228.607112)
		(end 121.896124 -228.588824)
		(width 0.1143)
		(layer "In11.Cu")
		(net "GMI_CPU1_G3_CPU0_G1_TX_DP<10>")
	)
	(segment
		(start 349.734632 -221.071694)
		(end 349.734632 -221.083124)
		(width 0.1143)
		(layer "In11.Cu")
		(net "GMI_CPU1_G3_CPU0_G1_TX_DP<10>")
	)
	(segment
		(start 157.957012 -189.074552)
		(end 162.591242 -185.275474)
		(width 0.14224)
		(layer "In11.Cu")
		(net "GMI_CPU1_G3_CPU0_G1_TX_DP<10>")
	)
	(segment
		(start 121.994676 -223.789748)
		(end 121.96699 -223.769682)
		(width 0.1143)
		(layer "In11.Cu")
		(net "GMI_CPU1_G3_CPU0_G1_TX_DP<10>")
	)
	(segment
		(start 122.75693 -231.524302)
		(end 122.674126 -231.441498)
		(width 0.1143)
		(layer "In11.Cu")
		(net "GMI_CPU1_G3_CPU0_G1_TX_DP<10>")
	)
	(segment
		(start 349.285814 -230.585772)
		(end 349.285814 -230.714296)
		(width 0.1143)
		(layer "In11.Cu")
		(net "GMI_CPU1_G3_CPU0_G1_TX_DP<10>")
	)
	(segment
		(start 348.821756 -231.441244)
		(end 348.738952 -231.524048)
		(width 0.1143)
		(layer "In11.Cu")
		(net "GMI_CPU1_G3_CPU0_G1_TX_DP<10>")
	)
	(segment
		(start 349.734632 -221.083124)
		(end 349.780352 -221.128844)
		(width 0.1143)
		(layer "In11.Cu")
		(net "GMI_CPU1_G3_CPU0_G1_TX_DP<10>")
	)
	(segment
		(start 157.432502 -189.504574)
		(end 157.61462 -189.522862)
		(width 0.14224)
		(layer "In11.Cu")
		(net "GMI_CPU1_G3_CPU0_G1_TX_DP<10>")
	)
	(segment
		(start 349.546672 -223.089216)
		(end 349.54845 -223.090232)
		(width 0.1143)
		(layer "In11.Cu")
		(net "GMI_CPU1_G3_CPU0_G1_TX_DP<10>")
	)
	(segment
		(start 121.994676 -225.40976)
		(end 121.96699 -225.389694)
		(width 0.1143)
		(layer "In11.Cu")
		(net "GMI_CPU1_G3_CPU0_G1_TX_DP<10>")
	)
	(segment
		(start 121.76125 -221.083378)
		(end 121.76125 -221.071948)
		(width 0.1143)
		(layer "In11.Cu")
		(net "GMI_CPU1_G3_CPU0_G1_TX_DP<10>")
	)
	(segment
		(start 121.96699 -227.009706)
		(end 121.928128 -226.987354)
		(width 0.1143)
		(layer "In11.Cu")
		(net "GMI_CPU1_G3_CPU0_G1_TX_DP<10>")
	)
	(segment
		(start 123.974098 -216.074498)
		(end 145.125186 -198.731886)
		(width 0.14224)
		(layer "In11.Cu")
		(net "GMI_CPU1_G3_CPU0_G1_TX_DP<10>")
	)
	(segment
		(start 349.528892 -223.769428)
		(end 349.501206 -223.789494)
		(width 0.1143)
		(layer "In11.Cu")
		(net "GMI_CPU1_G3_CPU0_G1_TX_DP<10>")
	)
	(segment
		(start 154.86888 -191.60617)
		(end 155.06192 -191.625474)
		(width 0.14224)
		(layer "In11.Cu")
		(net "GMI_CPU1_G3_CPU0_G1_TX_DP<10>")
	)
	(segment
		(start 349.568008 -223.101662)
		(end 349.599758 -223.11995)
		(width 0.1143)
		(layer "In11.Cu")
		(net "GMI_CPU1_G3_CPU0_G1_TX_DP<10>")
	)
	(segment
		(start 349.780352 -221.128844)
		(end 349.780352 -221.34703)
		(width 0.1143)
		(layer "In11.Cu")
		(net "GMI_CPU1_G3_CPU0_G1_TX_DP<10>")
	)
	(segment
		(start 121.928128 -223.74733)
		(end 121.912126 -223.737678)
		(width 0.1143)
		(layer "In11.Cu")
		(net "GMI_CPU1_G3_CPU0_G1_TX_DP<10>")
	)
	(segment
		(start 349.501206 -227.919026)
		(end 349.528892 -227.939092)
		(width 0.1143)
		(layer "In11.Cu")
		(net "GMI_CPU1_G3_CPU0_G1_TX_DP<10>")
	)
	(segment
		(start 121.96699 -226.319334)
		(end 121.994676 -226.299268)
		(width 0.1143)
		(layer "In11.Cu")
		(net "GMI_CPU1_G3_CPU0_G1_TX_DP<10>")
	)
	(segment
		(start 349.127826 -231.019604)
		(end 349.058992 -231.059482)
		(width 0.1143)
		(layer "In11.Cu")
		(net "GMI_CPU1_G3_CPU0_G1_TX_DP<10>")
	)
	(segment
		(start 306.652168 -184.474866)
		(end 308.421786 -185.28538)
		(width 0.14224)
		(layer "In11.Cu")
		(net "GMI_CPU1_G3_CPU0_G1_TX_DP<10>")
	)
	(segment
		(start 122.079258 -230.330756)
		(end 121.967498 -230.250238)
		(width 0.1143)
		(layer "In11.Cu")
		(net "GMI_CPU1_G3_CPU0_G1_TX_DP<10>")
	)
	(segment
		(start 349.562928 -223.098868)
		(end 349.56369 -223.099376)
		(width 0.1143)
		(layer "In11.Cu")
		(net "GMI_CPU1_G3_CPU0_G1_TX_DP<10>")
	)
	(segment
		(start 121.96699 -224.699322)
		(end 121.994676 -224.679256)
		(width 0.1143)
		(layer "In11.Cu")
		(net "GMI_CPU1_G3_CPU0_G1_TX_DP<10>")
	)
	(segment
		(start 156.583888 -190.20028)
		(end 156.766006 -190.218568)
		(width 0.14224)
		(layer "In11.Cu")
		(net "GMI_CPU1_G3_CPU0_G1_TX_DP<10>")
	)
	(segment
		(start 155.41117 -191.16167)
		(end 155.735274 -190.895986)
		(width 0.14224)
		(layer "In11.Cu")
		(net "GMI_CPU1_G3_CPU0_G1_TX_DP<10>")
	)
	(segment
		(start 157.938978 -189.25667)
		(end 157.957012 -189.074552)
		(width 0.14224)
		(layer "In11.Cu")
		(net "GMI_CPU1_G3_CPU0_G1_TX_DP<10>")
	)
	(segment
		(start 121.896124 -225.348546)
		(end 121.896124 -225.3488)
		(width 0.1143)
		(layer "In11.Cu")
		(net "GMI_CPU1_G3_CPU0_G1_TX_DP<10>")
	)
	(segment
		(start 145.125186 -198.731886)
		(end 145.905728 -198.495158)
		(width 0.14224)
		(layer "In11.Cu")
		(net "GMI_CPU1_G3_CPU0_G1_TX_DP<10>")
	)
	(segment
		(start 121.994676 -227.029772)
		(end 121.96699 -227.009706)
		(width 0.1143)
		(layer "In11.Cu")
		(net "GMI_CPU1_G3_CPU0_G1_TX_DP<10>")
	)
	(segment
		(start 349.599758 -225.348546)
		(end 349.599758 -225.348292)
		(width 0.1143)
		(layer "In11.Cu")
		(net "GMI_CPU1_G3_CPU0_G1_TX_DP<10>")
	)
	(segment
		(start 156.24175 -190.648082)
		(end 156.259784 -190.465964)
		(width 0.14224)
		(layer "In11.Cu")
		(net "GMI_CPU1_G3_CPU0_G1_TX_DP<10>")
	)
	(segment
		(start 121.912126 -223.737678)
		(end 121.896124 -223.728534)
		(width 0.1143)
		(layer "In11.Cu")
		(net "GMI_CPU1_G3_CPU0_G1_TX_DP<10>")
	)
	(segment
		(start 349.528892 -227.009452)
		(end 349.501206 -227.029518)
		(width 0.1143)
		(layer "In11.Cu")
		(net "GMI_CPU1_G3_CPU0_G1_TX_DP<10>")
	)
	(segment
		(start 349.55226 -223.092518)
		(end 349.562928 -223.098868)
		(width 0.1143)
		(layer "In11.Cu")
		(net "GMI_CPU1_G3_CPU0_G1_TX_DP<10>")
	)
	(segment
		(start 121.896124 -223.728534)
		(end 121.896124 -223.728788)
		(width 0.1143)
		(layer "In11.Cu")
		(net "GMI_CPU1_G3_CPU0_G1_TX_DP<10>")
	)
	(segment
		(start 121.96699 -227.939346)
		(end 121.994676 -227.91928)
		(width 0.1143)
		(layer "In11.Cu")
		(net "GMI_CPU1_G3_CPU0_G1_TX_DP<10>")
	)
	(segment
		(start 121.896124 -227.98024)
		(end 121.96699 -227.939346)
		(width 0.1143)
		(layer "In11.Cu")
		(net "GMI_CPU1_G3_CPU0_G1_TX_DP<10>")
	)
	(segment
		(start 122.43689 -231.059736)
		(end 122.368056 -231.019858)
		(width 0.1143)
		(layer "In11.Cu")
		(net "GMI_CPU1_G3_CPU0_G1_TX_DP<10>")
	)
	(segment
		(start 153.666698 -192.59169)
		(end 153.996644 -192.32118)
		(width 0.14224)
		(layer "In11.Cu")
		(net "GMI_CPU1_G3_CPU0_G1_TX_DP<10>")
	)
	(segment
		(start 121.896124 -226.360228)
		(end 121.96699 -226.319334)
		(width 0.1143)
		(layer "In11.Cu")
		(net "GMI_CPU1_G3_CPU0_G1_TX_DP<10>")
	)
	(segment
		(start 349.528384 -230.249984)
		(end 349.416624 -230.330502)
		(width 0.1143)
		(layer "In11.Cu")
		(net "GMI_CPU1_G3_CPU0_G1_TX_DP<10>")
	)
	(segment
		(start 154.519884 -192.06972)
		(end 154.538934 -191.87668)
		(width 0.14224)
		(layer "In11.Cu")
		(net "GMI_CPU1_G3_CPU0_G1_TX_DP<10>")
	)
	(segment
		(start 152.445212 -193.770504)
		(end 152.775412 -193.49974)
		(width 0.14224)
		(layer "In11.Cu")
		(net "GMI_CPU1_G3_CPU0_G1_TX_DP<10>")
	)
	(segment
		(start 123.054618 -231.524302)
		(end 122.75693 -231.524302)
		(width 0.1143)
		(layer "In11.Cu")
		(net "GMI_CPU1_G3_CPU0_G1_TX_DP<10>")
	)
	(segment
		(start 121.912126 -225.35769)
		(end 121.896124 -225.348546)
		(width 0.1143)
		(layer "In11.Cu")
		(net "GMI_CPU1_G3_CPU0_G1_TX_DP<10>")
	)
	(segment
		(start 146.793712 -198.226172)
		(end 151.379936 -194.46621)
		(width 0.14224)
		(layer "In11.Cu")
		(net "GMI_CPU1_G3_CPU0_G1_TX_DP<10>")
	)
	(segment
		(start 157.61462 -189.522862)
		(end 157.938978 -189.25667)
		(width 0.14224)
		(layer "In11.Cu")
		(net "GMI_CPU1_G3_CPU0_G1_TX_DP<10>")
	)
	(segment
		(start 349.567754 -223.747076)
		(end 349.528892 -223.769428)
		(width 0.1143)
		(layer "In11.Cu")
		(net "GMI_CPU1_G3_CPU0_G1_TX_DP<10>")
	)
	(segment
		(start 121.896124 -226.968558)
		(end 121.896124 -226.968812)
		(width 0.1143)
		(layer "In11.Cu")
		(net "GMI_CPU1_G3_CPU0_G1_TX_DP<10>")
	)
	(segment
		(start 348.738952 -231.524048)
		(end 348.44101 -231.524048)
		(width 0.1143)
		(layer "In11.Cu")
		(net "GMI_CPU1_G3_CPU0_G1_TX_DP<10>")
	)
	(segment
		(start 121.964196 -228.628194)
		(end 121.927874 -228.607112)
		(width 0.1143)
		(layer "In11.Cu")
		(net "GMI_CPU1_G3_CPU0_G1_TX_DP<10>")
	)
	(segment
		(start 121.94667 -223.090994)
		(end 121.947432 -223.090486)
		(width 0.1143)
		(layer "In11.Cu")
		(net "GMI_CPU1_G3_CPU0_G1_TX_DP<10>")
	)
	(segment
		(start 349.528892 -227.939092)
		(end 349.599758 -227.979986)
		(width 0.1143)
		(layer "In11.Cu")
		(net "GMI_CPU1_G3_CPU0_G1_TX_DP<10>")
	)
	(segment
		(start 349.568008 -228.606858)
		(end 349.531686 -228.62794)
		(width 0.1143)
		(layer "In11.Cu")
		(net "GMI_CPU1_G3_CPU0_G1_TX_DP<10>")
	)
	(segment
		(start 154.538934 -191.87668)
		(end 154.86888 -191.60617)
		(width 0.14224)
		(layer "In11.Cu")
		(net "GMI_CPU1_G3_CPU0_G1_TX_DP<10>")
	)
	(segment
		(start 349.583756 -226.977448)
		(end 349.567754 -226.9871)
		(width 0.1143)
		(layer "In11.Cu")
		(net "GMI_CPU1_G3_CPU0_G1_TX_DP<10>")
	)
	(segment
		(start 121.928128 -225.367342)
		(end 121.912126 -225.35769)
		(width 0.1143)
		(layer "In11.Cu")
		(net "GMI_CPU1_G3_CPU0_G1_TX_DP<10>")
	)
	(segment
		(start 302.888904 -184.474866)
		(end 306.652168 -184.474866)
		(width 0.14224)
		(layer "In11.Cu")
		(net "GMI_CPU1_G3_CPU0_G1_TX_DP<10>")
	)
	(segment
		(start 308.421786 -185.28538)
		(end 312.96737 -187.8584)
		(width 0.14224)
		(layer "In11.Cu")
		(net "GMI_CPU1_G3_CPU0_G1_TX_DP<10>")
	)
	(segment
		(start 122.210068 -230.71455)
		(end 122.210068 -230.586026)
		(width 0.1143)
		(layer "In11.Cu")
		(net "GMI_CPU1_G3_CPU0_G1_TX_DP<10>")
	)
	(segment
		(start 349.56369 -223.099376)
		(end 349.568008 -223.101662)
		(width 0.1143)
		(layer "In11.Cu")
		(net "GMI_CPU1_G3_CPU0_G1_TX_DP<10>")
	)
	(segment
		(start 151.903176 -194.21475)
		(end 151.922226 -194.02171)
		(width 0.14224)
		(layer "In11.Cu")
		(net "GMI_CPU1_G3_CPU0_G1_TX_DP<10>")
	)
	(segment
		(start 151.572976 -194.485514)
		(end 151.903176 -194.21475)
		(width 0.14224)
		(layer "In11.Cu")
		(net "GMI_CPU1_G3_CPU0_G1_TX_DP<10>")
	)
	(segment
		(start 157.090364 -189.952376)
		(end 157.108398 -189.770258)
		(width 0.14224)
		(layer "In11.Cu")
		(net "GMI_CPU1_G3_CPU0_G1_TX_DP<10>")
	)
	(segment
		(start 121.927874 -223.101916)
		(end 121.94667 -223.090994)
		(width 0.1143)
		(layer "In11.Cu")
		(net "GMI_CPU1_G3_CPU0_G1_TX_DP<10>")
	)
	(segment
		(start 153.124408 -193.03619)
		(end 153.317448 -193.055494)
		(width 0.14224)
		(layer "In11.Cu")
		(net "GMI_CPU1_G3_CPU0_G1_TX_DP<10>")
	)
	(segment
		(start 153.317448 -193.055494)
		(end 153.647648 -192.78473)
		(width 0.14224)
		(layer "In11.Cu")
		(net "GMI_CPU1_G3_CPU0_G1_TX_DP<10>")
	)
	(segment
		(start 154.189684 -192.340484)
		(end 154.519884 -192.06972)
		(width 0.14224)
		(layer "In11.Cu")
		(net "GMI_CPU1_G3_CPU0_G1_TX_DP<10>")
	)
	(segment
		(start 349.566992 -230.227124)
		(end 349.565976 -230.227632)
		(width 0.1143)
		(layer "In11.Cu")
		(net "GMI_CPU1_G3_CPU0_G1_TX_DP<10>")
	)
	(segment
		(start 121.740168 -221.371922)
		(end 121.71553 -221.347284)
		(width 0.1143)
		(layer "In11.Cu")
		(net "GMI_CPU1_G3_CPU0_G1_TX_DP<10>")
	)
	(segment
		(start 156.766006 -190.218568)
		(end 157.090364 -189.952376)
		(width 0.14224)
		(layer "In11.Cu")
		(net "GMI_CPU1_G3_CPU0_G1_TX_DP<10>")
	)
	(segment
		(start 349.531686 -229.560628)
		(end 349.601536 -229.601268)
		(width 0.1143)
		(layer "In11.Cu")
		(net "GMI_CPU1_G3_CPU0_G1_TX_DP<10>")
	)
	(segment
		(start 153.996644 -192.32118)
		(end 154.189684 -192.340484)
		(width 0.14224)
		(layer "In11.Cu")
		(net "GMI_CPU1_G3_CPU0_G1_TX_DP<10>")
	)
	(segment
		(start 349.551498 -223.09201)
		(end 349.55226 -223.092518)
		(width 0.1143)
		(layer "In11.Cu")
		(net "GMI_CPU1_G3_CPU0_G1_TX_DP<10>")
	)
	(segment
		(start 349.568262 -230.226362)
		(end 349.566992 -230.227124)
		(width 0.1143)
		(layer "In11.Cu")
		(net "GMI_CPU1_G3_CPU0_G1_TX_DP<10>")
	)
	(segment
		(start 121.896124 -223.120204)
		(end 121.927874 -223.101916)
		(width 0.1143)
		(layer "In11.Cu")
		(net "GMI_CPU1_G3_CPU0_G1_TX_DP<10>")
	)
	(segment
		(start 349.599758 -222.108522)
		(end 349.546672 -222.139256)
		(width 0.1143)
		(layer "In11.Cu")
		(net "GMI_CPU1_G3_CPU0_G1_TX_DP<10>")
	)
	(segment
		(start 121.76125 -221.071948)
		(end 121.76125 -219.878148)
		(width 0.14224)
		(layer "In11.Cu")
		(net "GMI_CPU1_G3_CPU0_G1_TX_DP<10>")
	)
	(segment
		(start 155.39212 -191.35471)
		(end 155.41117 -191.16167)
		(width 0.14224)
		(layer "In11.Cu")
		(net "GMI_CPU1_G3_CPU0_G1_TX_DP<10>")
	)
	(segment
		(start 121.96699 -223.769682)
		(end 121.928128 -223.74733)
		(width 0.1143)
		(layer "In11.Cu")
		(net "GMI_CPU1_G3_CPU0_G1_TX_DP<10>")
	)
	(segment
		(start 121.740168 -221.804484)
		(end 121.740168 -221.371922)
		(width 0.1143)
		(layer "In11.Cu")
		(net "GMI_CPU1_G3_CPU0_G1_TX_DP<10>")
	)
	(segment
		(start 349.734632 -219.775532)
		(end 349.734632 -221.071694)
		(width 0.14224)
		(layer "In11.Cu")
		(net "GMI_CPU1_G3_CPU0_G1_TX_DP<10>")
	)
	(segment
		(start 349.583756 -223.737424)
		(end 349.567754 -223.747076)
		(width 0.1143)
		(layer "In11.Cu")
		(net "GMI_CPU1_G3_CPU0_G1_TX_DP<10>")
	)
	(segment
		(start 152.252172 -193.7512)
		(end 152.445212 -193.770504)
		(width 0.14224)
		(layer "In11.Cu")
		(net "GMI_CPU1_G3_CPU0_G1_TX_DP<10>")
	)
	(segment
		(start 121.947432 -223.090486)
		(end 121.94921 -223.08947)
		(width 0.1143)
		(layer "In11.Cu")
		(net "GMI_CPU1_G3_CPU0_G1_TX_DP<10>")
	)
	(arc
		(start 122.210068 -229.089204)
		(mid 122.145606 -228.838)
		(end 121.979436 -228.638862)
		(width 0.1143)
		(layer "In11.Cu")
		(net "GMI_CPU1_G3_CPU0_G1_TX_DP<10>")
	)
	(arc
		(start 349.546672 -222.139256)
		(mid 349.273121 -222.614236)
		(end 349.546672 -223.089216)
		(width 0.1143)
		(layer "In11.Cu")
		(net "GMI_CPU1_G3_CPU0_G1_TX_DP<10>")
	)
	(arc
		(start 121.896124 -225.3488)
		(mid 121.740196 -225.044508)
		(end 121.896124 -224.740216)
		(width 0.1143)
		(layer "In11.Cu")
		(net "GMI_CPU1_G3_CPU0_G1_TX_DP<10>")
	)
	(arc
		(start 122.210068 -230.586026)
		(mid 122.175459 -230.442611)
		(end 122.079258 -230.330756)
		(width 0.1143)
		(layer "In11.Cu")
		(net "GMI_CPU1_G3_CPU0_G1_TX_DP<10>")
	)
	(arc
		(start 349.501206 -223.789494)
		(mid 349.273206 -224.234248)
		(end 349.501206 -224.679002)
		(width 0.1143)
		(layer "In11.Cu")
		(net "GMI_CPU1_G3_CPU0_G1_TX_DP<10>")
	)
	(arc
		(start 122.674126 -231.441498)
		(mid 122.595047 -231.226053)
		(end 122.43689 -231.059736)
		(width 0.1143)
		(layer "In11.Cu")
		(net "GMI_CPU1_G3_CPU0_G1_TX_DP<10>")
	)
	(arc
		(start 349.599758 -223.11995)
		(mid 349.755686 -223.424242)
		(end 349.599758 -223.728534)
		(width 0.1143)
		(layer "In11.Cu")
		(net "GMI_CPU1_G3_CPU0_G1_TX_DP<10>")
	)
	(arc
		(start 122.368056 -231.019858)
		(mid 122.252009 -230.886387)
		(end 122.210068 -230.71455)
		(width 0.1143)
		(layer "In11.Cu")
		(net "GMI_CPU1_G3_CPU0_G1_TX_DP<10>")
	)
	(arc
		(start 349.058992 -231.059482)
		(mid 348.907005 -231.21599)
		(end 348.825566 -231.418384)
		(width 0.1143)
		(layer "In11.Cu")
		(net "GMI_CPU1_G3_CPU0_G1_TX_DP<10>")
	)
	(arc
		(start 121.979436 -228.638862)
		(mid 121.97186 -228.633466)
		(end 121.964196 -228.628194)
		(width 0.1143)
		(layer "In11.Cu")
		(net "GMI_CPU1_G3_CPU0_G1_TX_DP<10>")
	)
	(arc
		(start 121.740168 -229.904036)
		(mid 121.780987 -229.734293)
		(end 121.894346 -229.601522)
		(width 0.1143)
		(layer "In11.Cu")
		(net "GMI_CPU1_G3_CPU0_G1_TX_DP<10>")
	)
	(arc
		(start 349.416624 -230.330502)
		(mid 349.320413 -230.442352)
		(end 349.285814 -230.585772)
		(width 0.1143)
		(layer "In11.Cu")
		(net "GMI_CPU1_G3_CPU0_G1_TX_DP<10>")
	)
	(arc
		(start 349.601536 -229.601268)
		(mid 349.714885 -229.734043)
		(end 349.755714 -229.903782)
		(width 0.1143)
		(layer "In11.Cu")
		(net "GMI_CPU1_G3_CPU0_G1_TX_DP<10>")
	)
	(arc
		(start 121.994676 -224.679256)
		(mid 122.222676 -224.234502)
		(end 121.994676 -223.789748)
		(width 0.1143)
		(layer "In11.Cu")
		(net "GMI_CPU1_G3_CPU0_G1_TX_DP<10>")
	)
	(arc
		(start 349.516446 -228.638608)
		(mid 349.350201 -228.837708)
		(end 349.285814 -229.08895)
		(width 0.1143)
		(layer "In11.Cu")
		(net "GMI_CPU1_G3_CPU0_G1_TX_DP<10>")
	)
	(arc
		(start 349.755714 -229.904036)
		(mid 349.705891 -230.089766)
		(end 349.569786 -230.2256)
		(width 0.1143)
		(layer "In11.Cu")
		(net "GMI_CPU1_G3_CPU0_G1_TX_DP<10>")
	)
	(arc
		(start 121.896124 -222.108776)
		(mid 121.781448 -221.975442)
		(end 121.740168 -221.804484)
		(width 0.1143)
		(layer "In11.Cu")
		(net "GMI_CPU1_G3_CPU0_G1_TX_DP<10>")
	)
	(arc
		(start 121.94921 -223.08947)
		(mid 122.222761 -222.61449)
		(end 121.94921 -222.13951)
		(width 0.1143)
		(layer "In11.Cu")
		(net "GMI_CPU1_G3_CPU0_G1_TX_DP<10>")
	)
	(arc
		(start 349.531686 -228.62794)
		(mid 349.524022 -228.633211)
		(end 349.516446 -228.638608)
		(width 0.1143)
		(layer "In11.Cu")
		(net "GMI_CPU1_G3_CPU0_G1_TX_DP<10>")
	)
	(arc
		(start 121.896124 -228.588824)
		(mid 121.740196 -228.284532)
		(end 121.896124 -227.98024)
		(width 0.1143)
		(layer "In11.Cu")
		(net "GMI_CPU1_G3_CPU0_G1_TX_DP<10>")
	)
	(arc
		(start 349.599758 -226.359974)
		(mid 349.755686 -226.664266)
		(end 349.599758 -226.968558)
		(width 0.1143)
		(layer "In11.Cu")
		(net "GMI_CPU1_G3_CPU0_G1_TX_DP<10>")
	)
	(arc
		(start 348.825566 -231.418384)
		(mid 348.823543 -231.429794)
		(end 348.821756 -231.441244)
		(width 0.1143)
		(layer "In11.Cu")
		(net "GMI_CPU1_G3_CPU0_G1_TX_DP<10>")
	)
	(arc
		(start 349.501206 -225.409506)
		(mid 349.273206 -225.85426)
		(end 349.501206 -226.299014)
		(width 0.1143)
		(layer "In11.Cu")
		(net "GMI_CPU1_G3_CPU0_G1_TX_DP<10>")
	)
	(arc
		(start 349.285814 -230.714296)
		(mid 349.243935 -230.886165)
		(end 349.127826 -231.019604)
		(width 0.1143)
		(layer "In11.Cu")
		(net "GMI_CPU1_G3_CPU0_G1_TX_DP<10>")
	)
	(arc
		(start 121.994676 -226.299268)
		(mid 122.222676 -225.854514)
		(end 121.994676 -225.40976)
		(width 0.1143)
		(layer "In11.Cu")
		(net "GMI_CPU1_G3_CPU0_G1_TX_DP<10>")
	)
	(arc
		(start 121.896124 -226.968812)
		(mid 121.740196 -226.66452)
		(end 121.896124 -226.360228)
		(width 0.1143)
		(layer "In11.Cu")
		(net "GMI_CPU1_G3_CPU0_G1_TX_DP<10>")
	)
	(arc
		(start 349.285814 -229.08895)
		(mid 349.349789 -229.355525)
		(end 349.531686 -229.560628)
		(width 0.1143)
		(layer "In11.Cu")
		(net "GMI_CPU1_G3_CPU0_G1_TX_DP<10>")
	)
	(arc
		(start 121.994676 -227.91928)
		(mid 122.222676 -227.474526)
		(end 121.994676 -227.029772)
		(width 0.1143)
		(layer "In11.Cu")
		(net "GMI_CPU1_G3_CPU0_G1_TX_DP<10>")
	)
	(arc
		(start 121.896124 -223.728788)
		(mid 121.740196 -223.424496)
		(end 121.896124 -223.120204)
		(width 0.1143)
		(layer "In11.Cu")
		(net "GMI_CPU1_G3_CPU0_G1_TX_DP<10>")
	)
	(arc
		(start 349.599758 -227.979986)
		(mid 349.755686 -228.284278)
		(end 349.599758 -228.58857)
		(width 0.1143)
		(layer "In11.Cu")
		(net "GMI_CPU1_G3_CPU0_G1_TX_DP<10>")
	)
	(arc
		(start 121.964196 -229.560882)
		(mid 122.146087 -229.355775)
		(end 122.210068 -229.089204)
		(width 0.1143)
		(layer "In11.Cu")
		(net "GMI_CPU1_G3_CPU0_G1_TX_DP<10>")
	)
	(arc
		(start 349.599758 -224.739962)
		(mid 349.755686 -225.044254)
		(end 349.599758 -225.348546)
		(width 0.1143)
		(layer "In11.Cu")
		(net "GMI_CPU1_G3_CPU0_G1_TX_DP<10>")
	)
	(arc
		(start 349.501206 -227.029518)
		(mid 349.273206 -227.474272)
		(end 349.501206 -227.919026)
		(width 0.1143)
		(layer "In11.Cu")
		(net "GMI_CPU1_G3_CPU0_G1_TX_DP<10>")
	)
	(arc
		(start 349.755714 -221.80423)
		(mid 349.714459 -221.975201)
		(end 349.599758 -222.108522)
		(width 0.1143)
		(layer "In11.Cu")
		(net "GMI_CPU1_G3_CPU0_G1_TX_DP<10>")
	)
	(arc
		(start 121.926096 -230.225854)
		(mid 121.790015 -230.090006)
		(end 121.740168 -229.90429)
		(width 0.1143)
		(layer "In11.Cu")
		(net "GMI_CPU1_G3_CPU0_G1_TX_DP<10>")
	)
	(segment
		(start 114.597942 -235.84027)
		(end 115.064794 -235.574332)
		(width 0.12954)
		(layer "F.Cu")
		(net "GMI_CPU1_G3_CPU0_G1_TX_DP<0>")
	)
	(segment
		(start 356.89794 -235.840016)
		(end 356.431088 -235.574078)
		(width 0.12954)
		(layer "F.Cu")
		(net "GMI_CPU1_G3_CPU0_G1_TX_DP<0>")
	)
	(segment
		(start 112.31245 -221.083378)
		(end 112.26673 -221.129098)
		(width 0.1143)
		(layer "In11.Cu")
		(net "GMI_CPU1_G3_CPU0_G1_TX_DP<0>")
	)
	(segment
		(start 114.766852 -235.574332)
		(end 115.064794 -235.574332)
		(width 0.1143)
		(layer "In11.Cu")
		(net "GMI_CPU1_G3_CPU0_G1_TX_DP<0>")
	)
	(segment
		(start 358.1654 -214.84082)
		(end 357.951532 -214.480394)
		(width 0.14224)
		(layer "In11.Cu")
		(net "GMI_CPU1_G3_CPU0_G1_TX_DP<0>")
	)
	(segment
		(start 358.511856 -215.42375)
		(end 358.557068 -215.246458)
		(width 0.14224)
		(layer "In11.Cu")
		(net "GMI_CPU1_G3_CPU0_G1_TX_DP<0>")
	)
	(segment
		(start 114.193574 -213.00059)
		(end 113.98123 -213.361778)
		(width 0.14224)
		(layer "In11.Cu")
		(net "GMI_CPU1_G3_CPU0_G1_TX_DP<0>")
	)
	(segment
		(start 358.482392 -232.665524)
		(end 358.482646 -232.665778)
		(width 0.1143)
		(layer "In11.Cu")
		(net "GMI_CPU1_G3_CPU0_G1_TX_DP<0>")
	)
	(segment
		(start 357.605076 -213.89721)
		(end 357.391208 -213.536784)
		(width 0.14224)
		(layer "In11.Cu")
		(net "GMI_CPU1_G3_CPU0_G1_TX_DP<0>")
	)
	(segment
		(start 113.437162 -233.449114)
		(end 113.506758 -233.489754)
		(width 0.1143)
		(layer "In11.Cu")
		(net "GMI_CPU1_G3_CPU0_G1_TX_DP<0>")
	)
	(segment
		(start 302.919384 -175.066452)
		(end 164.808408 -174.258478)
		(width 0.14224)
		(layer "In11.Cu")
		(net "GMI_CPU1_G3_CPU0_G1_TX_DP<0>")
	)
	(segment
		(start 112.26673 -221.129098)
		(end 112.26673 -221.276418)
		(width 0.1143)
		(layer "In11.Cu")
		(net "GMI_CPU1_G3_CPU0_G1_TX_DP<0>")
	)
	(segment
		(start 359.229152 -221.369636)
		(end 359.229152 -221.128844)
		(width 0.1143)
		(layer "In11.Cu")
		(net "GMI_CPU1_G3_CPU0_G1_TX_DP<0>")
	)
	(segment
		(start 359.006648 -231.558084)
		(end 359.006648 -222.488506)
		(width 0.1143)
		(layer "In11.Cu")
		(net "GMI_CPU1_G3_CPU0_G1_TX_DP<0>")
	)
	(segment
		(start 113.470944 -214.48522)
		(end 113.2586 -214.846916)
		(width 0.14224)
		(layer "In11.Cu")
		(net "GMI_CPU1_G3_CPU0_G1_TX_DP<0>")
	)
	(segment
		(start 113.637314 -213.94674)
		(end 113.42497 -214.307928)
		(width 0.14224)
		(layer "In11.Cu")
		(net "GMI_CPU1_G3_CPU0_G1_TX_DP<0>")
	)
	(segment
		(start 112.959642 -232.635044)
		(end 113.013236 -232.666032)
		(width 0.1143)
		(layer "In11.Cu")
		(net "GMI_CPU1_G3_CPU0_G1_TX_DP<0>")
	)
	(segment
		(start 112.489234 -222.394526)
		(end 112.489234 -231.558592)
		(width 0.1143)
		(layer "In11.Cu")
		(net "GMI_CPU1_G3_CPU0_G1_TX_DP<0>")
	)
	(segment
		(start 114.92738 -212.008466)
		(end 114.749834 -212.05444)
		(width 0.14224)
		(layer "In11.Cu")
		(net "GMI_CPU1_G3_CPU0_G1_TX_DP<0>")
	)
	(segment
		(start 357.996744 -214.302848)
		(end 357.782876 -213.942676)
		(width 0.14224)
		(layer "In11.Cu")
		(net "GMI_CPU1_G3_CPU0_G1_TX_DP<0>")
	)
	(segment
		(start 114.583464 -212.59292)
		(end 114.37112 -212.954616)
		(width 0.14224)
		(layer "In11.Cu")
		(net "GMI_CPU1_G3_CPU0_G1_TX_DP<0>")
	)
	(segment
		(start 357.521764 -234.297728)
		(end 357.558086 -234.276646)
		(width 0.1143)
		(layer "In11.Cu")
		(net "GMI_CPU1_G3_CPU0_G1_TX_DP<0>")
	)
	(segment
		(start 113.81486 -213.900766)
		(end 113.637314 -213.94674)
		(width 0.14224)
		(layer "In11.Cu")
		(net "GMI_CPU1_G3_CPU0_G1_TX_DP<0>")
	)
	(segment
		(start 113.01349 -232.665778)
		(end 113.037366 -232.680002)
		(width 0.1143)
		(layer "In11.Cu")
		(net "GMI_CPU1_G3_CPU0_G1_TX_DP<0>")
	)
	(segment
		(start 358.561386 -232.613708)
		(end 358.576626 -232.595928)
		(width 0.1143)
		(layer "In11.Cu")
		(net "GMI_CPU1_G3_CPU0_G1_TX_DP<0>")
	)
	(segment
		(start 113.937796 -234.2769)
		(end 113.974118 -234.297982)
		(width 0.1143)
		(layer "In11.Cu")
		(net "GMI_CPU1_G3_CPU0_G1_TX_DP<0>")
	)
	(segment
		(start 357.049832 -235.109004)
		(end 357.110792 -235.073698)
		(width 0.1143)
		(layer "In11.Cu")
		(net "GMI_CPU1_G3_CPU0_G1_TX_DP<0>")
	)
	(segment
		(start 112.70234 -215.793066)
		(end 112.524794 -215.83904)
		(width 0.14224)
		(layer "In11.Cu")
		(net "GMI_CPU1_G3_CPU0_G1_TX_DP<0>")
	)
	(segment
		(start 358.482646 -232.665778)
		(end 358.53624 -232.63479)
		(width 0.1143)
		(layer "In11.Cu")
		(net "GMI_CPU1_G3_CPU0_G1_TX_DP<0>")
	)
	(segment
		(start 114.40414 -235.085128)
		(end 114.407696 -235.086906)
		(width 0.1143)
		(layer "In11.Cu")
		(net "GMI_CPU1_G3_CPU0_G1_TX_DP<0>")
	)
	(segment
		(start 358.3432 -214.886286)
		(end 358.1654 -214.84082)
		(width 0.14224)
		(layer "In11.Cu")
		(net "GMI_CPU1_G3_CPU0_G1_TX_DP<0>")
	)
	(segment
		(start 114.439954 -235.105702)
		(end 114.446812 -235.109766)
		(width 0.1143)
		(layer "In11.Cu")
		(net "GMI_CPU1_G3_CPU0_G1_TX_DP<0>")
	)
	(segment
		(start 359.183432 -216.300812)
		(end 358.903524 -215.829642)
		(width 0.14224)
		(layer "In11.Cu")
		(net "GMI_CPU1_G3_CPU0_G1_TX_DP<0>")
	)
	(segment
		(start 308.674516 -175.066452)
		(end 302.919384 -175.066452)
		(width 0.14224)
		(layer "In11.Cu")
		(net "GMI_CPU1_G3_CPU0_G1_TX_DP<0>")
	)
	(segment
		(start 359.229152 -221.128844)
		(end 359.183432 -221.083124)
		(width 0.1143)
		(layer "In11.Cu")
		(net "GMI_CPU1_G3_CPU0_G1_TX_DP<0>")
	)
	(segment
		(start 156.105352 -177.370486)
		(end 115.627404 -210.561428)
		(width 0.14224)
		(layer "In11.Cu")
		(net "GMI_CPU1_G3_CPU0_G1_TX_DP<0>")
	)
	(segment
		(start 358.903524 -215.829642)
		(end 358.725724 -215.78443)
		(width 0.14224)
		(layer "In11.Cu")
		(net "GMI_CPU1_G3_CPU0_G1_TX_DP<0>")
	)
	(segment
		(start 358.725724 -215.78443)
		(end 358.511856 -215.42375)
		(width 0.14224)
		(layer "In11.Cu")
		(net "GMI_CPU1_G3_CPU0_G1_TX_DP<0>")
	)
	(segment
		(start 113.906046 -234.258612)
		(end 113.937796 -234.2769)
		(width 0.1143)
		(layer "In11.Cu")
		(net "GMI_CPU1_G3_CPU0_G1_TX_DP<0>")
	)
	(segment
		(start 358.458516 -232.679748)
		(end 358.482392 -232.665524)
		(width 0.1143)
		(layer "In11.Cu")
		(net "GMI_CPU1_G3_CPU0_G1_TX_DP<0>")
	)
	(segment
		(start 358.215692 -233.14406)
		(end 358.215692 -233.142028)
		(width 0.1143)
		(layer "In11.Cu")
		(net "GMI_CPU1_G3_CPU0_G1_TX_DP<0>")
	)
	(segment
		(start 356.72903 -235.574078)
		(end 356.811834 -235.491274)
		(width 0.1143)
		(layer "In11.Cu")
		(net "GMI_CPU1_G3_CPU0_G1_TX_DP<0>")
	)
	(segment
		(start 359.006648 -222.488506)
		(end 359.229152 -221.369636)
		(width 0.1143)
		(layer "In11.Cu")
		(net "GMI_CPU1_G3_CPU0_G1_TX_DP<0>")
	)
	(segment
		(start 357.782876 -213.942676)
		(end 357.605076 -213.89721)
		(width 0.14224)
		(layer "In11.Cu")
		(net "GMI_CPU1_G3_CPU0_G1_TX_DP<0>")
	)
	(segment
		(start 114.37112 -212.954616)
		(end 114.193574 -213.00059)
		(width 0.14224)
		(layer "In11.Cu")
		(net "GMI_CPU1_G3_CPU0_G1_TX_DP<0>")
	)
	(segment
		(start 112.920272 -232.597452)
		(end 112.92967 -232.608628)
		(width 0.1143)
		(layer "In11.Cu")
		(net "GMI_CPU1_G3_CPU0_G1_TX_DP<0>")
	)
	(segment
		(start 112.91443 -232.59161)
		(end 112.920272 -232.597452)
		(width 0.1143)
		(layer "In11.Cu")
		(net "GMI_CPU1_G3_CPU0_G1_TX_DP<0>")
	)
	(segment
		(start 114.53749 -212.415628)
		(end 114.583464 -212.59292)
		(width 0.14224)
		(layer "In11.Cu")
		(net "GMI_CPU1_G3_CPU0_G1_TX_DP<0>")
	)
	(segment
		(start 115.139724 -211.64677)
		(end 114.92738 -212.008466)
		(width 0.14224)
		(layer "In11.Cu")
		(net "GMI_CPU1_G3_CPU0_G1_TX_DP<0>")
	)
	(segment
		(start 112.524794 -215.83904)
		(end 112.31245 -216.200228)
		(width 0.14224)
		(layer "In11.Cu")
		(net "GMI_CPU1_G3_CPU0_G1_TX_DP<0>")
	)
	(segment
		(start 114.027204 -213.53907)
		(end 113.81486 -213.900766)
		(width 0.14224)
		(layer "In11.Cu")
		(net "GMI_CPU1_G3_CPU0_G1_TX_DP<0>")
	)
	(segment
		(start 113.28019 -233.142282)
		(end 113.28019 -233.144314)
		(width 0.1143)
		(layer "In11.Cu")
		(net "GMI_CPU1_G3_CPU0_G1_TX_DP<0>")
	)
	(segment
		(start 357.391208 -213.536784)
		(end 357.43642 -213.359238)
		(width 0.14224)
		(layer "In11.Cu")
		(net "GMI_CPU1_G3_CPU0_G1_TX_DP<0>")
	)
	(segment
		(start 113.081054 -214.89289)
		(end 112.86871 -215.254078)
		(width 0.14224)
		(layer "In11.Cu")
		(net "GMI_CPU1_G3_CPU0_G1_TX_DP<0>")
	)
	(segment
		(start 355.780594 -210.56981)
		(end 318.403732 -179.921662)
		(width 0.14224)
		(layer "In11.Cu")
		(net "GMI_CPU1_G3_CPU0_G1_TX_DP<0>")
	)
	(segment
		(start 357.989124 -233.4895)
		(end 358.05872 -233.44886)
		(width 0.1143)
		(layer "In11.Cu")
		(net "GMI_CPU1_G3_CPU0_G1_TX_DP<0>")
	)
	(segment
		(start 112.31245 -216.200228)
		(end 112.31245 -221.071948)
		(width 0.14224)
		(layer "In11.Cu")
		(net "GMI_CPU1_G3_CPU0_G1_TX_DP<0>")
	)
	(segment
		(start 357.558086 -234.276646)
		(end 357.589836 -234.258358)
		(width 0.1143)
		(layer "In11.Cu")
		(net "GMI_CPU1_G3_CPU0_G1_TX_DP<0>")
	)
	(segment
		(start 113.42497 -214.307928)
		(end 113.470944 -214.48522)
		(width 0.14224)
		(layer "In11.Cu")
		(net "GMI_CPU1_G3_CPU0_G1_TX_DP<0>")
	)
	(segment
		(start 114.749834 -212.05444)
		(end 114.53749 -212.415628)
		(width 0.14224)
		(layer "In11.Cu")
		(net "GMI_CPU1_G3_CPU0_G1_TX_DP<0>")
	)
	(segment
		(start 115.627404 -210.561428)
		(end 115.09375 -211.469478)
		(width 0.14224)
		(layer "In11.Cu")
		(net "GMI_CPU1_G3_CPU0_G1_TX_DP<0>")
	)
	(segment
		(start 113.2586 -214.846916)
		(end 113.081054 -214.89289)
		(width 0.14224)
		(layer "In11.Cu")
		(net "GMI_CPU1_G3_CPU0_G1_TX_DP<0>")
	)
	(segment
		(start 112.489234 -231.558592)
		(end 112.489488 -231.558338)
		(width 0.1143)
		(layer "In11.Cu")
		(net "GMI_CPU1_G3_CPU0_G1_TX_DP<0>")
	)
	(segment
		(start 357.436674 -213.358476)
		(end 357.43642 -213.35873)
		(width 0.14224)
		(layer "In11.Cu")
		(net "GMI_CPU1_G3_CPU0_G1_TX_DP<0>")
	)
	(segment
		(start 113.013236 -232.666032)
		(end 113.01349 -232.665778)
		(width 0.1143)
		(layer "In11.Cu")
		(net "GMI_CPU1_G3_CPU0_G1_TX_DP<0>")
	)
	(segment
		(start 114.38509 -235.073952)
		(end 114.40414 -235.085128)
		(width 0.1143)
		(layer "In11.Cu")
		(net "GMI_CPU1_G3_CPU0_G1_TX_DP<0>")
	)
	(segment
		(start 114.684048 -235.491528)
		(end 114.766852 -235.574332)
		(width 0.1143)
		(layer "In11.Cu")
		(net "GMI_CPU1_G3_CPU0_G1_TX_DP<0>")
	)
	(segment
		(start 112.31245 -221.071948)
		(end 112.31245 -221.083378)
		(width 0.1143)
		(layer "In11.Cu")
		(net "GMI_CPU1_G3_CPU0_G1_TX_DP<0>")
	)
	(segment
		(start 357.43642 -213.35873)
		(end 355.780594 -210.56981)
		(width 0.14224)
		(layer "In11.Cu")
		(net "GMI_CPU1_G3_CPU0_G1_TX_DP<0>")
	)
	(segment
		(start 164.808408 -174.258478)
		(end 156.105352 -177.370486)
		(width 0.14224)
		(layer "In11.Cu")
		(net "GMI_CPU1_G3_CPU0_G1_TX_DP<0>")
	)
	(segment
		(start 356.431088 -235.574078)
		(end 356.72903 -235.574078)
		(width 0.1143)
		(layer "In11.Cu")
		(net "GMI_CPU1_G3_CPU0_G1_TX_DP<0>")
	)
	(segment
		(start 112.914684 -215.43137)
		(end 112.70234 -215.793066)
		(width 0.14224)
		(layer "In11.Cu")
		(net "GMI_CPU1_G3_CPU0_G1_TX_DP<0>")
	)
	(segment
		(start 359.183432 -221.083124)
		(end 359.183432 -216.300812)
		(width 0.14224)
		(layer "In11.Cu")
		(net "GMI_CPU1_G3_CPU0_G1_TX_DP<0>")
	)
	(segment
		(start 318.403732 -179.921662)
		(end 311.802526 -176.184814)
		(width 0.14224)
		(layer "In11.Cu")
		(net "GMI_CPU1_G3_CPU0_G1_TX_DP<0>")
	)
	(segment
		(start 112.92967 -232.608628)
		(end 112.929924 -232.608628)
		(width 0.1143)
		(layer "In11.Cu")
		(net "GMI_CPU1_G3_CPU0_G1_TX_DP<0>")
	)
	(segment
		(start 114.439192 -235.105194)
		(end 114.439954 -235.105702)
		(width 0.1143)
		(layer "In11.Cu")
		(net "GMI_CPU1_G3_CPU0_G1_TX_DP<0>")
	)
	(segment
		(start 115.09375 -211.469478)
		(end 115.139724 -211.64677)
		(width 0.14224)
		(layer "In11.Cu")
		(net "GMI_CPU1_G3_CPU0_G1_TX_DP<0>")
	)
	(segment
		(start 357.43642 -213.359238)
		(end 357.436674 -213.358476)
		(width 0.14224)
		(layer "In11.Cu")
		(net "GMI_CPU1_G3_CPU0_G1_TX_DP<0>")
	)
	(segment
		(start 357.951532 -214.480394)
		(end 357.996744 -214.302848)
		(width 0.14224)
		(layer "In11.Cu")
		(net "GMI_CPU1_G3_CPU0_G1_TX_DP<0>")
	)
	(segment
		(start 112.86871 -215.254078)
		(end 112.914684 -215.43137)
		(width 0.14224)
		(layer "In11.Cu")
		(net "GMI_CPU1_G3_CPU0_G1_TX_DP<0>")
	)
	(segment
		(start 114.407696 -235.086906)
		(end 114.439192 -235.105194)
		(width 0.1143)
		(layer "In11.Cu")
		(net "GMI_CPU1_G3_CPU0_G1_TX_DP<0>")
	)
	(segment
		(start 358.557068 -215.246458)
		(end 358.3432 -214.886286)
		(width 0.14224)
		(layer "In11.Cu")
		(net "GMI_CPU1_G3_CPU0_G1_TX_DP<0>")
	)
	(segment
		(start 112.26673 -221.276418)
		(end 112.489234 -222.394526)
		(width 0.1143)
		(layer "In11.Cu")
		(net "GMI_CPU1_G3_CPU0_G1_TX_DP<0>")
	)
	(segment
		(start 311.802526 -176.184814)
		(end 308.674516 -175.066452)
		(width 0.14224)
		(layer "In11.Cu")
		(net "GMI_CPU1_G3_CPU0_G1_TX_DP<0>")
	)
	(segment
		(start 113.98123 -213.361778)
		(end 114.027204 -213.53907)
		(width 0.14224)
		(layer "In11.Cu")
		(net "GMI_CPU1_G3_CPU0_G1_TX_DP<0>")
	)
	(segment
		(start 112.929924 -232.608628)
		(end 112.934496 -232.613962)
		(width 0.1143)
		(layer "In11.Cu")
		(net "GMI_CPU1_G3_CPU0_G1_TX_DP<0>")
	)
	(arc
		(start 357.27386 -234.773216)
		(mid 357.275167 -234.761176)
		(end 357.275892 -234.749086)
		(width 0.1143)
		(layer "In11.Cu")
		(net "GMI_CPU1_G3_CPU0_G1_TX_DP<0>")
	)
	(arc
		(start 356.811834 -235.491274)
		(mid 356.813622 -235.479825)
		(end 356.815644 -235.468414)
		(width 0.1143)
		(layer "In11.Cu")
		(net "GMI_CPU1_G3_CPU0_G1_TX_DP<0>")
	)
	(arc
		(start 358.576626 -232.595928)
		(mid 358.89482 -232.119762)
		(end 359.006648 -231.558084)
		(width 0.1143)
		(layer "In11.Cu")
		(net "GMI_CPU1_G3_CPU0_G1_TX_DP<0>")
	)
	(arc
		(start 357.745792 -233.954066)
		(mid 357.810307 -233.691847)
		(end 357.989124 -233.4895)
		(width 0.1143)
		(layer "In11.Cu")
		(net "GMI_CPU1_G3_CPU0_G1_TX_DP<0>")
	)
	(arc
		(start 358.05872 -233.44886)
		(mid 358.174147 -233.315484)
		(end 358.215692 -233.14406)
		(width 0.1143)
		(layer "In11.Cu")
		(net "GMI_CPU1_G3_CPU0_G1_TX_DP<0>")
	)
	(arc
		(start 114.680238 -235.468668)
		(mid 114.682261 -235.480078)
		(end 114.684048 -235.491528)
		(width 0.1143)
		(layer "In11.Cu")
		(net "GMI_CPU1_G3_CPU0_G1_TX_DP<0>")
	)
	(arc
		(start 357.04907 -235.109512)
		(mid 357.049451 -235.109258)
		(end 357.049832 -235.109004)
		(width 0.1143)
		(layer "In11.Cu")
		(net "GMI_CPU1_G3_CPU0_G1_TX_DP<0>")
	)
	(arc
		(start 357.275892 -234.749086)
		(mid 357.341512 -234.499568)
		(end 357.511096 -234.305094)
		(width 0.1143)
		(layer "In11.Cu")
		(net "GMI_CPU1_G3_CPU0_G1_TX_DP<0>")
	)
	(arc
		(start 113.28019 -233.144314)
		(mid 113.321739 -233.315736)
		(end 113.437162 -233.449114)
		(width 0.1143)
		(layer "In11.Cu")
		(net "GMI_CPU1_G3_CPU0_G1_TX_DP<0>")
	)
	(arc
		(start 112.489488 -231.558338)
		(mid 112.599823 -232.116979)
		(end 112.91443 -232.59161)
		(width 0.1143)
		(layer "In11.Cu")
		(net "GMI_CPU1_G3_CPU0_G1_TX_DP<0>")
	)
	(arc
		(start 357.110792 -235.073698)
		(mid 357.219372 -234.938126)
		(end 357.27386 -234.773216)
		(width 0.1143)
		(layer "In11.Cu")
		(net "GMI_CPU1_G3_CPU0_G1_TX_DP<0>")
	)
	(arc
		(start 113.75009 -233.95432)
		(mid 113.791345 -234.125291)
		(end 113.906046 -234.258612)
		(width 0.1143)
		(layer "In11.Cu")
		(net "GMI_CPU1_G3_CPU0_G1_TX_DP<0>")
	)
	(arc
		(start 357.511096 -234.305094)
		(mid 357.51641 -234.301382)
		(end 357.521764 -234.297728)
		(width 0.1143)
		(layer "In11.Cu")
		(net "GMI_CPU1_G3_CPU0_G1_TX_DP<0>")
	)
	(arc
		(start 114.222022 -234.77347)
		(mid 114.276584 -234.93834)
		(end 114.38509 -235.073952)
		(width 0.1143)
		(layer "In11.Cu")
		(net "GMI_CPU1_G3_CPU0_G1_TX_DP<0>")
	)
	(arc
		(start 113.506758 -233.489754)
		(mid 113.685571 -233.692104)
		(end 113.75009 -233.95432)
		(width 0.1143)
		(layer "In11.Cu")
		(net "GMI_CPU1_G3_CPU0_G1_TX_DP<0>")
	)
	(arc
		(start 112.934496 -232.613962)
		(mid 112.946178 -232.625566)
		(end 112.959642 -232.635044)
		(width 0.1143)
		(layer "In11.Cu")
		(net "GMI_CPU1_G3_CPU0_G1_TX_DP<0>")
	)
	(arc
		(start 114.21999 -234.74934)
		(mid 114.220702 -234.761431)
		(end 114.222022 -234.77347)
		(width 0.1143)
		(layer "In11.Cu")
		(net "GMI_CPU1_G3_CPU0_G1_TX_DP<0>")
	)
	(arc
		(start 356.815644 -235.468414)
		(mid 356.897077 -235.266016)
		(end 357.04907 -235.109512)
		(width 0.1143)
		(layer "In11.Cu")
		(net "GMI_CPU1_G3_CPU0_G1_TX_DP<0>")
	)
	(arc
		(start 114.446812 -235.109766)
		(mid 114.598799 -235.266274)
		(end 114.680238 -235.468668)
		(width 0.1143)
		(layer "In11.Cu")
		(net "GMI_CPU1_G3_CPU0_G1_TX_DP<0>")
	)
	(arc
		(start 113.984786 -234.305348)
		(mid 114.154473 -234.499768)
		(end 114.21999 -234.74934)
		(width 0.1143)
		(layer "In11.Cu")
		(net "GMI_CPU1_G3_CPU0_G1_TX_DP<0>")
	)
	(arc
		(start 358.215692 -233.142028)
		(mid 358.2801 -232.880952)
		(end 358.458516 -232.679748)
		(width 0.1143)
		(layer "In11.Cu")
		(net "GMI_CPU1_G3_CPU0_G1_TX_DP<0>")
	)
	(arc
		(start 358.53624 -232.63479)
		(mid 358.549699 -232.625306)
		(end 358.561386 -232.613708)
		(width 0.1143)
		(layer "In11.Cu")
		(net "GMI_CPU1_G3_CPU0_G1_TX_DP<0>")
	)
	(arc
		(start 113.974118 -234.297982)
		(mid 113.979474 -234.301633)
		(end 113.984786 -234.305348)
		(width 0.1143)
		(layer "In11.Cu")
		(net "GMI_CPU1_G3_CPU0_G1_TX_DP<0>")
	)
	(arc
		(start 113.037366 -232.680002)
		(mid 113.215824 -232.881184)
		(end 113.28019 -233.142282)
		(width 0.1143)
		(layer "In11.Cu")
		(net "GMI_CPU1_G3_CPU0_G1_TX_DP<0>")
	)
	(arc
		(start 357.589836 -234.258358)
		(mid 357.704512 -234.125024)
		(end 357.745792 -233.954066)
		(width 0.1143)
		(layer "In11.Cu")
		(net "GMI_CPU1_G3_CPU0_G1_TX_DP<0>")
	)
	(segment
		(start 349.847916 -236.650022)
		(end 349.381064 -236.384084)
		(width 0.12954)
		(layer "F.Cu")
		(net "GMI_CPU1_G3_CPU0_G1_TX_DN<9>")
	)
	(segment
		(start 121.647966 -236.650276)
		(end 122.114818 -236.384338)
		(width 0.12954)
		(layer "F.Cu")
		(net "GMI_CPU1_G3_CPU0_G1_TX_DN<9>")
	)
	(segment
		(start 120.852692 -222.26905)
		(end 120.922288 -222.30969)
		(width 0.1143)
		(layer "In11.Cu")
		(net "GMI_CPU1_G3_CPU0_G1_TX_DN<9>")
	)
	(segment
		(start 350.100646 -231.22128)
		(end 350.17329 -231.178862)
		(width 0.1143)
		(layer "In11.Cu")
		(net "GMI_CPU1_G3_CPU0_G1_TX_DN<9>")
	)
	(segment
		(start 121.37263 -231.840786)
		(end 121.368566 -231.842818)
		(width 0.1143)
		(layer "In11.Cu")
		(net "GMI_CPU1_G3_CPU0_G1_TX_DN<9>")
	)
	(segment
		(start 350.573594 -222.309436)
		(end 350.64319 -222.268796)
		(width 0.1143)
		(layer "In11.Cu")
		(net "GMI_CPU1_G3_CPU0_G1_TX_DN<9>")
	)
	(segment
		(start 121.322592 -231.179116)
		(end 121.361708 -231.201976)
		(width 0.1143)
		(layer "In11.Cu")
		(net "GMI_CPU1_G3_CPU0_G1_TX_DN<9>")
	)
	(segment
		(start 120.891808 -233.63174)
		(end 120.922288 -233.64952)
		(width 0.1143)
		(layer "In11.Cu")
		(net "GMI_CPU1_G3_CPU0_G1_TX_DN<9>")
	)
	(segment
		(start 349.63227 -235.270294)
		(end 349.663258 -235.252006)
		(width 0.1143)
		(layer "In11.Cu")
		(net "GMI_CPU1_G3_CPU0_G1_TX_DN<9>")
	)
	(segment
		(start 157.067758 -188.047376)
		(end 146.22907 -196.93509)
		(width 0.14224)
		(layer "In11.Cu")
		(net "GMI_CPU1_G3_CPU0_G1_TX_DN<9>")
	)
	(segment
		(start 123.048522 -215.234012)
		(end 120.53443 -219.543884)
		(width 0.14224)
		(layer "In11.Cu")
		(net "GMI_CPU1_G3_CPU0_G1_TX_DN<9>")
	)
	(segment
		(start 350.886268 -221.80423)
		(end 350.886268 -221.455488)
		(width 0.1143)
		(layer "In11.Cu")
		(net "GMI_CPU1_G3_CPU0_G1_TX_DN<9>")
	)
	(segment
		(start 121.361708 -231.846882)
		(end 121.322592 -231.869742)
		(width 0.1143)
		(layer "In11.Cu")
		(net "GMI_CPU1_G3_CPU0_G1_TX_DN<9>")
	)
	(segment
		(start 120.891808 -223.911922)
		(end 120.922288 -223.929702)
		(width 0.1143)
		(layer "In11.Cu")
		(net "GMI_CPU1_G3_CPU0_G1_TX_DN<9>")
	)
	(segment
		(start 146.22907 -196.93509)
		(end 144.859756 -197.349618)
		(width 0.14224)
		(layer "In11.Cu")
		(net "GMI_CPU1_G3_CPU0_G1_TX_DN<9>")
	)
	(segment
		(start 121.360692 -234.441238)
		(end 121.361708 -234.441746)
		(width 0.1143)
		(layer "In11.Cu")
		(net "GMI_CPU1_G3_CPU0_G1_TX_DN<9>")
	)
	(segment
		(start 313.98718 -187.019946)
		(end 308.12994 -183.70423)
		(width 0.14224)
		(layer "In11.Cu")
		(net "GMI_CPU1_G3_CPU0_G1_TX_DN<9>")
	)
	(segment
		(start 121.358152 -234.439714)
		(end 121.359168 -234.440222)
		(width 0.1143)
		(layer "In11.Cu")
		(net "GMI_CPU1_G3_CPU0_G1_TX_DN<9>")
	)
	(segment
		(start 350.102424 -234.45978)
		(end 350.133412 -234.442)
		(width 0.1143)
		(layer "In11.Cu")
		(net "GMI_CPU1_G3_CPU0_G1_TX_DN<9>")
	)
	(segment
		(start 161.749994 -184.208166)
		(end 157.068012 -188.047376)
		(width 0.14224)
		(layer "In11.Cu")
		(net "GMI_CPU1_G3_CPU0_G1_TX_DN<9>")
	)
	(segment
		(start 122.48261 -236.314488)
		(end 122.41276 -236.384338)
		(width 0.1143)
		(layer "In11.Cu")
		(net "GMI_CPU1_G3_CPU0_G1_TX_DN<9>")
	)
	(segment
		(start 120.609614 -221.455742)
		(end 120.609614 -221.804484)
		(width 0.1143)
		(layer "In11.Cu")
		(net "GMI_CPU1_G3_CPU0_G1_TX_DN<9>")
	)
	(segment
		(start 120.53443 -221.083378)
		(end 120.58015 -221.129098)
		(width 0.1143)
		(layer "In11.Cu")
		(net "GMI_CPU1_G3_CPU0_G1_TX_DN<9>")
	)
	(segment
		(start 350.134174 -234.441492)
		(end 350.13519 -234.440984)
		(width 0.1143)
		(layer "In11.Cu")
		(net "GMI_CPU1_G3_CPU0_G1_TX_DN<9>")
	)
	(segment
		(start 350.573594 -228.789484)
		(end 350.64319 -228.748844)
		(width 0.1143)
		(layer "In11.Cu")
		(net "GMI_CPU1_G3_CPU0_G1_TX_DN<9>")
	)
	(segment
		(start 120.58015 -221.426278)
		(end 120.609614 -221.455742)
		(width 0.1143)
		(layer "In11.Cu")
		(net "GMI_CPU1_G3_CPU0_G1_TX_DN<9>")
	)
	(segment
		(start 350.915732 -221.426024)
		(end 350.915732 -221.128844)
		(width 0.1143)
		(layer "In11.Cu")
		(net "GMI_CPU1_G3_CPU0_G1_TX_DN<9>")
	)
	(segment
		(start 350.13519 -231.847136)
		(end 350.134174 -231.846628)
		(width 0.1143)
		(layer "In11.Cu")
		(net "GMI_CPU1_G3_CPU0_G1_TX_DN<9>")
	)
	(segment
		(start 120.891808 -227.797106)
		(end 120.852692 -227.819966)
		(width 0.1143)
		(layer "In11.Cu")
		(net "GMI_CPU1_G3_CPU0_G1_TX_DN<9>")
	)
	(segment
		(start 349.013272 -236.314234)
		(end 349.013018 -236.314234)
		(width 0.1143)
		(layer "In11.Cu")
		(net "GMI_CPU1_G3_CPU0_G1_TX_DN<9>")
	)
	(segment
		(start 350.573594 -223.929448)
		(end 350.64319 -223.888808)
		(width 0.1143)
		(layer "In11.Cu")
		(net "GMI_CPU1_G3_CPU0_G1_TX_DN<9>")
	)
	(segment
		(start 350.17329 -231.869488)
		(end 350.141032 -231.850692)
		(width 0.1143)
		(layer "In11.Cu")
		(net "GMI_CPU1_G3_CPU0_G1_TX_DN<9>")
	)
	(segment
		(start 121.368566 -231.842818)
		(end 121.367296 -231.84358)
		(width 0.1143)
		(layer "In11.Cu")
		(net "GMI_CPU1_G3_CPU0_G1_TX_DN<9>")
	)
	(segment
		(start 121.359168 -234.440222)
		(end 121.360692 -234.441238)
		(width 0.1143)
		(layer "In11.Cu")
		(net "GMI_CPU1_G3_CPU0_G1_TX_DN<9>")
	)
	(segment
		(start 350.141032 -231.850692)
		(end 350.14027 -231.850184)
		(width 0.1143)
		(layer "In11.Cu")
		(net "GMI_CPU1_G3_CPU0_G1_TX_DN<9>")
	)
	(segment
		(start 306.86756 -183.252872)
		(end 302.892968 -183.252872)
		(width 0.14224)
		(layer "In11.Cu")
		(net "GMI_CPU1_G3_CPU0_G1_TX_DN<9>")
	)
	(segment
		(start 121.831862 -235.251752)
		(end 121.832624 -235.25226)
		(width 0.1143)
		(layer "In11.Cu")
		(net "GMI_CPU1_G3_CPU0_G1_TX_DN<9>")
	)
	(segment
		(start 120.922288 -224.539302)
		(end 120.891808 -224.557082)
		(width 0.1143)
		(layer "In11.Cu")
		(net "GMI_CPU1_G3_CPU0_G1_TX_DN<9>")
	)
	(segment
		(start 120.92432 -229.398068)
		(end 120.891808 -229.416864)
		(width 0.1143)
		(layer "In11.Cu")
		(net "GMI_CPU1_G3_CPU0_G1_TX_DN<9>")
	)
	(segment
		(start 350.132142 -231.845358)
		(end 350.130618 -231.844596)
		(width 0.1143)
		(layer "In11.Cu")
		(net "GMI_CPU1_G3_CPU0_G1_TX_DN<9>")
	)
	(segment
		(start 121.361708 -231.201976)
		(end 121.395236 -231.221534)
		(width 0.1143)
		(layer "In11.Cu")
		(net "GMI_CPU1_G3_CPU0_G1_TX_DN<9>")
	)
	(segment
		(start 121.322592 -234.418886)
		(end 121.354088 -234.437174)
		(width 0.1143)
		(layer "In11.Cu")
		(net "GMI_CPU1_G3_CPU0_G1_TX_DN<9>")
	)
	(segment
		(start 120.53443 -221.071948)
		(end 120.53443 -221.083378)
		(width 0.1143)
		(layer "In11.Cu")
		(net "GMI_CPU1_G3_CPU0_G1_TX_DN<9>")
	)
	(segment
		(start 122.41276 -236.384338)
		(end 122.114818 -236.384338)
		(width 0.1143)
		(layer "In11.Cu")
		(net "GMI_CPU1_G3_CPU0_G1_TX_DN<9>")
	)
	(segment
		(start 308.12994 -183.70423)
		(end 306.86756 -183.252872)
		(width 0.14224)
		(layer "In11.Cu")
		(net "GMI_CPU1_G3_CPU0_G1_TX_DN<9>")
	)
	(segment
		(start 121.366534 -231.844088)
		(end 121.365264 -231.84485)
		(width 0.1143)
		(layer "In11.Cu")
		(net "GMI_CPU1_G3_CPU0_G1_TX_DN<9>")
	)
	(segment
		(start 157.068012 -188.047376)
		(end 157.067758 -188.047376)
		(width 0.14224)
		(layer "In11.Cu")
		(net "GMI_CPU1_G3_CPU0_G1_TX_DN<9>")
	)
	(segment
		(start 122.298206 -236.060488)
		(end 122.306842 -236.06506)
		(width 0.1143)
		(layer "In11.Cu")
		(net "GMI_CPU1_G3_CPU0_G1_TX_DN<9>")
	)
	(segment
		(start 121.36247 -234.442254)
		(end 121.393458 -234.460034)
		(width 0.1143)
		(layer "In11.Cu")
		(net "GMI_CPU1_G3_CPU0_G1_TX_DN<9>")
	)
	(segment
		(start 349.66402 -235.251498)
		(end 349.703136 -235.228638)
		(width 0.1143)
		(layer "In11.Cu")
		(net "GMI_CPU1_G3_CPU0_G1_TX_DN<9>")
	)
	(segment
		(start 120.922288 -222.91929)
		(end 120.891808 -222.93707)
		(width 0.1143)
		(layer "In11.Cu")
		(net "GMI_CPU1_G3_CPU0_G1_TX_DN<9>")
	)
	(segment
		(start 120.891808 -226.177094)
		(end 120.852692 -226.199954)
		(width 0.1143)
		(layer "In11.Cu")
		(net "GMI_CPU1_G3_CPU0_G1_TX_DN<9>")
	)
	(segment
		(start 350.136714 -234.439968)
		(end 350.13773 -234.43946)
		(width 0.1143)
		(layer "In11.Cu")
		(net "GMI_CPU1_G3_CPU0_G1_TX_DN<9>")
	)
	(segment
		(start 350.128078 -231.843072)
		(end 350.126554 -231.84231)
		(width 0.1143)
		(layer "In11.Cu")
		(net "GMI_CPU1_G3_CPU0_G1_TX_DN<9>")
	)
	(segment
		(start 120.53443 -219.543884)
		(end 120.53443 -221.071948)
		(width 0.14224)
		(layer "In11.Cu")
		(net "GMI_CPU1_G3_CPU0_G1_TX_DN<9>")
	)
	(segment
		(start 121.36247 -231.846374)
		(end 121.361708 -231.846882)
		(width 0.1143)
		(layer "In11.Cu")
		(net "GMI_CPU1_G3_CPU0_G1_TX_DN<9>")
	)
	(segment
		(start 121.832624 -235.25226)
		(end 121.863612 -235.270548)
		(width 0.1143)
		(layer "In11.Cu")
		(net "GMI_CPU1_G3_CPU0_G1_TX_DN<9>")
	)
	(segment
		(start 120.852692 -223.889062)
		(end 120.891808 -223.911922)
		(width 0.1143)
		(layer "In11.Cu")
		(net "GMI_CPU1_G3_CPU0_G1_TX_DN<9>")
	)
	(segment
		(start 348.50197 -215.32088)
		(end 313.98718 -187.019946)
		(width 0.14224)
		(layer "In11.Cu")
		(net "GMI_CPU1_G3_CPU0_G1_TX_DN<9>")
	)
	(segment
		(start 144.859756 -197.349618)
		(end 123.048522 -215.234012)
		(width 0.14224)
		(layer "In11.Cu")
		(net "GMI_CPU1_G3_CPU0_G1_TX_DN<9>")
	)
	(segment
		(start 350.961452 -219.463366)
		(end 348.50197 -215.32088)
		(width 0.14224)
		(layer "In11.Cu")
		(net "GMI_CPU1_G3_CPU0_G1_TX_DN<9>")
	)
	(segment
		(start 350.133412 -234.442)
		(end 350.134174 -234.441492)
		(width 0.1143)
		(layer "In11.Cu")
		(net "GMI_CPU1_G3_CPU0_G1_TX_DN<9>")
	)
	(segment
		(start 350.13773 -231.84866)
		(end 350.136714 -231.848152)
		(width 0.1143)
		(layer "In11.Cu")
		(net "GMI_CPU1_G3_CPU0_G1_TX_DN<9>")
	)
	(segment
		(start 121.367296 -231.84358)
		(end 121.366534 -231.844088)
		(width 0.1143)
		(layer "In11.Cu")
		(net "GMI_CPU1_G3_CPU0_G1_TX_DN<9>")
	)
	(segment
		(start 121.365264 -231.84485)
		(end 121.36374 -231.845612)
		(width 0.1143)
		(layer "In11.Cu")
		(net "GMI_CPU1_G3_CPU0_G1_TX_DN<9>")
	)
	(segment
		(start 350.136714 -231.848152)
		(end 350.13519 -231.847136)
		(width 0.1143)
		(layer "In11.Cu")
		(net "GMI_CPU1_G3_CPU0_G1_TX_DN<9>")
	)
	(segment
		(start 350.64319 -229.43947)
		(end 350.604074 -229.41661)
		(width 0.1143)
		(layer "In11.Cu")
		(net "GMI_CPU1_G3_CPU0_G1_TX_DN<9>")
	)
	(segment
		(start 350.915732 -221.128844)
		(end 350.961452 -221.083124)
		(width 0.1143)
		(layer "In11.Cu")
		(net "GMI_CPU1_G3_CPU0_G1_TX_DN<9>")
	)
	(segment
		(start 166.629842 -182.458868)
		(end 161.749994 -184.208166)
		(width 0.14224)
		(layer "In11.Cu")
		(net "GMI_CPU1_G3_CPU0_G1_TX_DN<9>")
	)
	(segment
		(start 349.18904 -236.064806)
		(end 349.197676 -236.060234)
		(width 0.1143)
		(layer "In11.Cu")
		(net "GMI_CPU1_G3_CPU0_G1_TX_DN<9>")
	)
	(segment
		(start 121.393458 -231.828594)
		(end 121.37263 -231.840786)
		(width 0.1143)
		(layer "In11.Cu")
		(net "GMI_CPU1_G3_CPU0_G1_TX_DN<9>")
	)
	(segment
		(start 120.855232 -230.370634)
		(end 120.922288 -230.40975)
		(width 0.1143)
		(layer "In11.Cu")
		(net "GMI_CPU1_G3_CPU0_G1_TX_DN<9>")
	)
	(segment
		(start 350.604074 -229.41661)
		(end 350.571562 -229.397814)
		(width 0.1143)
		(layer "In11.Cu")
		(net "GMI_CPU1_G3_CPU0_G1_TX_DN<9>")
	)
	(segment
		(start 120.852692 -225.509074)
		(end 120.891808 -225.531934)
		(width 0.1143)
		(layer "In11.Cu")
		(net "GMI_CPU1_G3_CPU0_G1_TX_DN<9>")
	)
	(segment
		(start 120.891808 -227.151946)
		(end 120.922288 -227.169726)
		(width 0.1143)
		(layer "In11.Cu")
		(net "GMI_CPU1_G3_CPU0_G1_TX_DN<9>")
	)
	(segment
		(start 120.922288 -232.639108)
		(end 120.891808 -232.656888)
		(width 0.1143)
		(layer "In11.Cu")
		(net "GMI_CPU1_G3_CPU0_G1_TX_DN<9>")
	)
	(segment
		(start 121.36374 -231.845612)
		(end 121.36247 -231.846374)
		(width 0.1143)
		(layer "In11.Cu")
		(net "GMI_CPU1_G3_CPU0_G1_TX_DN<9>")
	)
	(segment
		(start 350.573594 -230.409496)
		(end 350.64065 -230.37038)
		(width 0.1143)
		(layer "In11.Cu")
		(net "GMI_CPU1_G3_CPU0_G1_TX_DN<9>")
	)
	(segment
		(start 122.482864 -236.314488)
		(end 122.48261 -236.314488)
		(width 0.1143)
		(layer "In11.Cu")
		(net "GMI_CPU1_G3_CPU0_G1_TX_DN<9>")
	)
	(segment
		(start 121.792746 -235.228892)
		(end 121.831862 -235.251752)
		(width 0.1143)
		(layer "In11.Cu")
		(net "GMI_CPU1_G3_CPU0_G1_TX_DN<9>")
	)
	(segment
		(start 120.891808 -224.557082)
		(end 120.852692 -224.579942)
		(width 0.1143)
		(layer "In11.Cu")
		(net "GMI_CPU1_G3_CPU0_G1_TX_DN<9>")
	)
	(segment
		(start 350.134174 -231.846628)
		(end 350.133412 -231.84612)
		(width 0.1143)
		(layer "In11.Cu")
		(net "GMI_CPU1_G3_CPU0_G1_TX_DN<9>")
	)
	(segment
		(start 350.14027 -231.850184)
		(end 350.13773 -231.84866)
		(width 0.1143)
		(layer "In11.Cu")
		(net "GMI_CPU1_G3_CPU0_G1_TX_DN<9>")
	)
	(segment
		(start 350.64319 -227.819712)
		(end 350.573594 -227.779072)
		(width 0.1143)
		(layer "In11.Cu")
		(net "GMI_CPU1_G3_CPU0_G1_TX_DN<9>")
	)
	(segment
		(start 349.381064 -236.384084)
		(end 349.083122 -236.384084)
		(width 0.1143)
		(layer "In11.Cu")
		(net "GMI_CPU1_G3_CPU0_G1_TX_DN<9>")
	)
	(segment
		(start 350.64319 -232.679494)
		(end 350.573594 -232.638854)
		(width 0.1143)
		(layer "In11.Cu")
		(net "GMI_CPU1_G3_CPU0_G1_TX_DN<9>")
	)
	(segment
		(start 120.891808 -222.93707)
		(end 120.852692 -222.95993)
		(width 0.1143)
		(layer "In11.Cu")
		(net "GMI_CPU1_G3_CPU0_G1_TX_DN<9>")
	)
	(segment
		(start 121.361708 -234.441746)
		(end 121.36247 -234.442254)
		(width 0.1143)
		(layer "In11.Cu")
		(net "GMI_CPU1_G3_CPU0_G1_TX_DN<9>")
	)
	(segment
		(start 350.573594 -233.649266)
		(end 350.64319 -233.608626)
		(width 0.1143)
		(layer "In11.Cu")
		(net "GMI_CPU1_G3_CPU0_G1_TX_DN<9>")
	)
	(segment
		(start 120.891808 -229.416864)
		(end 120.852692 -229.439724)
		(width 0.1143)
		(layer "In11.Cu")
		(net "GMI_CPU1_G3_CPU0_G1_TX_DN<9>")
	)
	(segment
		(start 350.886268 -221.455488)
		(end 350.915732 -221.426024)
		(width 0.1143)
		(layer "In11.Cu")
		(net "GMI_CPU1_G3_CPU0_G1_TX_DN<9>")
	)
	(segment
		(start 350.133412 -231.84612)
		(end 350.132142 -231.845358)
		(width 0.1143)
		(layer "In11.Cu")
		(net "GMI_CPU1_G3_CPU0_G1_TX_DN<9>")
	)
	(segment
		(start 120.58015 -221.129098)
		(end 120.58015 -221.426278)
		(width 0.1143)
		(layer "In11.Cu")
		(net "GMI_CPU1_G3_CPU0_G1_TX_DN<9>")
	)
	(segment
		(start 350.130618 -231.844596)
		(end 350.128078 -231.843072)
		(width 0.1143)
		(layer "In11.Cu")
		(net "GMI_CPU1_G3_CPU0_G1_TX_DN<9>")
	)
	(segment
		(start 120.852692 -233.60888)
		(end 120.891808 -233.63174)
		(width 0.1143)
		(layer "In11.Cu")
		(net "GMI_CPU1_G3_CPU0_G1_TX_DN<9>")
	)
	(segment
		(start 349.083122 -236.384084)
		(end 349.013272 -236.314234)
		(width 0.1143)
		(layer "In11.Cu")
		(net "GMI_CPU1_G3_CPU0_G1_TX_DN<9>")
	)
	(segment
		(start 350.64319 -224.579688)
		(end 350.573594 -224.539048)
		(width 0.1143)
		(layer "In11.Cu")
		(net "GMI_CPU1_G3_CPU0_G1_TX_DN<9>")
	)
	(segment
		(start 121.354088 -234.437174)
		(end 121.355612 -234.43819)
		(width 0.1143)
		(layer "In11.Cu")
		(net "GMI_CPU1_G3_CPU0_G1_TX_DN<9>")
	)
	(segment
		(start 302.892968 -183.252872)
		(end 166.629842 -182.458868)
		(width 0.14224)
		(layer "In11.Cu")
		(net "GMI_CPU1_G3_CPU0_G1_TX_DN<9>")
	)
	(segment
		(start 120.891808 -232.656888)
		(end 120.852692 -232.679748)
		(width 0.1143)
		(layer "In11.Cu")
		(net "GMI_CPU1_G3_CPU0_G1_TX_DN<9>")
	)
	(segment
		(start 121.355612 -234.43819)
		(end 121.358152 -234.439714)
		(width 0.1143)
		(layer "In11.Cu")
		(net "GMI_CPU1_G3_CPU0_G1_TX_DN<9>")
	)
	(segment
		(start 120.922288 -226.159314)
		(end 120.891808 -226.177094)
		(width 0.1143)
		(layer "In11.Cu")
		(net "GMI_CPU1_G3_CPU0_G1_TX_DN<9>")
	)
	(segment
		(start 350.961452 -221.071694)
		(end 350.961452 -219.463366)
		(width 0.14224)
		(layer "In11.Cu")
		(net "GMI_CPU1_G3_CPU0_G1_TX_DN<9>")
	)
	(segment
		(start 350.64319 -226.1997)
		(end 350.573594 -226.15906)
		(width 0.1143)
		(layer "In11.Cu")
		(net "GMI_CPU1_G3_CPU0_G1_TX_DN<9>")
	)
	(segment
		(start 350.13519 -234.440984)
		(end 350.136714 -234.439968)
		(width 0.1143)
		(layer "In11.Cu")
		(net "GMI_CPU1_G3_CPU0_G1_TX_DN<9>")
	)
	(segment
		(start 350.13773 -234.43946)
		(end 350.17329 -234.418632)
		(width 0.1143)
		(layer "In11.Cu")
		(net "GMI_CPU1_G3_CPU0_G1_TX_DN<9>")
	)
	(segment
		(start 350.64319 -222.959676)
		(end 350.573594 -222.919036)
		(width 0.1143)
		(layer "In11.Cu")
		(net "GMI_CPU1_G3_CPU0_G1_TX_DN<9>")
	)
	(segment
		(start 120.922288 -227.779326)
		(end 120.891808 -227.797106)
		(width 0.1143)
		(layer "In11.Cu")
		(net "GMI_CPU1_G3_CPU0_G1_TX_DN<9>")
	)
	(segment
		(start 120.852692 -227.129086)
		(end 120.891808 -227.151946)
		(width 0.1143)
		(layer "In11.Cu")
		(net "GMI_CPU1_G3_CPU0_G1_TX_DN<9>")
	)
	(segment
		(start 120.891808 -228.771958)
		(end 120.922288 -228.789738)
		(width 0.1143)
		(layer "In11.Cu")
		(net "GMI_CPU1_G3_CPU0_G1_TX_DN<9>")
	)
	(segment
		(start 350.126554 -231.84231)
		(end 350.102424 -231.82834)
		(width 0.1143)
		(layer "In11.Cu")
		(net "GMI_CPU1_G3_CPU0_G1_TX_DN<9>")
	)
	(segment
		(start 350.573594 -225.54946)
		(end 350.64319 -225.50882)
		(width 0.1143)
		(layer "In11.Cu")
		(net "GMI_CPU1_G3_CPU0_G1_TX_DN<9>")
	)
	(segment
		(start 120.852692 -228.749098)
		(end 120.891808 -228.771958)
		(width 0.1143)
		(layer "In11.Cu")
		(net "GMI_CPU1_G3_CPU0_G1_TX_DN<9>")
	)
	(segment
		(start 350.961452 -221.083124)
		(end 350.961452 -221.071694)
		(width 0.1143)
		(layer "In11.Cu")
		(net "GMI_CPU1_G3_CPU0_G1_TX_DN<9>")
	)
	(segment
		(start 350.573594 -227.169472)
		(end 350.64319 -227.128832)
		(width 0.1143)
		(layer "In11.Cu")
		(net "GMI_CPU1_G3_CPU0_G1_TX_DN<9>")
	)
	(segment
		(start 120.891808 -225.531934)
		(end 120.922288 -225.549714)
		(width 0.1143)
		(layer "In11.Cu")
		(net "GMI_CPU1_G3_CPU0_G1_TX_DN<9>")
	)
	(segment
		(start 349.663258 -235.252006)
		(end 349.66402 -235.251498)
		(width 0.1143)
		(layer "In11.Cu")
		(net "GMI_CPU1_G3_CPU0_G1_TX_DN<9>")
	)
	(arc
		(start 120.852692 -229.439724)
		(mid 120.673879 -229.642074)
		(end 120.60936 -229.90429)
		(width 0.1143)
		(layer "In11.Cu")
		(net "GMI_CPU1_G3_CPU0_G1_TX_DN<9>")
	)
	(arc
		(start 349.013018 -236.314234)
		(mid 349.073969 -236.170421)
		(end 349.18904 -236.064806)
		(width 0.1143)
		(layer "In11.Cu")
		(net "GMI_CPU1_G3_CPU0_G1_TX_DN<9>")
	)
	(arc
		(start 120.922288 -227.169726)
		(mid 121.079265 -227.474526)
		(end 120.922288 -227.779326)
		(width 0.1143)
		(layer "In11.Cu")
		(net "GMI_CPU1_G3_CPU0_G1_TX_DN<9>")
	)
	(arc
		(start 350.64319 -228.748844)
		(mid 350.886517 -228.284278)
		(end 350.64319 -227.819712)
		(width 0.1143)
		(layer "In11.Cu")
		(net "GMI_CPU1_G3_CPU0_G1_TX_DN<9>")
	)
	(arc
		(start 120.922288 -223.929702)
		(mid 121.079265 -224.234502)
		(end 120.922288 -224.539302)
		(width 0.1143)
		(layer "In11.Cu")
		(net "GMI_CPU1_G3_CPU0_G1_TX_DN<9>")
	)
	(arc
		(start 120.609614 -221.804484)
		(mid 120.673988 -222.066688)
		(end 120.852692 -222.26905)
		(width 0.1143)
		(layer "In11.Cu")
		(net "GMI_CPU1_G3_CPU0_G1_TX_DN<9>")
	)
	(arc
		(start 120.922288 -222.30969)
		(mid 121.079265 -222.61449)
		(end 120.922288 -222.91929)
		(width 0.1143)
		(layer "In11.Cu")
		(net "GMI_CPU1_G3_CPU0_G1_TX_DN<9>")
	)
	(arc
		(start 349.476314 -235.574078)
		(mid 349.517631 -235.403362)
		(end 349.63227 -235.270294)
		(width 0.1143)
		(layer "In11.Cu")
		(net "GMI_CPU1_G3_CPU0_G1_TX_DN<9>")
	)
	(arc
		(start 350.64319 -223.888808)
		(mid 350.886517 -223.424242)
		(end 350.64319 -222.959676)
		(width 0.1143)
		(layer "In11.Cu")
		(net "GMI_CPU1_G3_CPU0_G1_TX_DN<9>")
	)
	(arc
		(start 120.852692 -222.95993)
		(mid 120.609365 -223.424496)
		(end 120.852692 -223.889062)
		(width 0.1143)
		(layer "In11.Cu")
		(net "GMI_CPU1_G3_CPU0_G1_TX_DN<9>")
	)
	(arc
		(start 350.573594 -222.919036)
		(mid 350.416617 -222.614236)
		(end 350.573594 -222.309436)
		(width 0.1143)
		(layer "In11.Cu")
		(net "GMI_CPU1_G3_CPU0_G1_TX_DN<9>")
	)
	(arc
		(start 350.573594 -226.15906)
		(mid 350.416617 -225.85426)
		(end 350.573594 -225.54946)
		(width 0.1143)
		(layer "In11.Cu")
		(net "GMI_CPU1_G3_CPU0_G1_TX_DN<9>")
	)
	(arc
		(start 120.922288 -233.64952)
		(mid 121.037715 -233.782896)
		(end 121.07926 -233.95432)
		(width 0.1143)
		(layer "In11.Cu")
		(net "GMI_CPU1_G3_CPU0_G1_TX_DN<9>")
	)
	(arc
		(start 120.922288 -225.549714)
		(mid 121.079265 -225.854514)
		(end 120.922288 -226.159314)
		(width 0.1143)
		(layer "In11.Cu")
		(net "GMI_CPU1_G3_CPU0_G1_TX_DN<9>")
	)
	(arc
		(start 350.64319 -233.608626)
		(mid 350.886517 -233.14406)
		(end 350.64319 -232.679494)
		(width 0.1143)
		(layer "In11.Cu")
		(net "GMI_CPU1_G3_CPU0_G1_TX_DN<9>")
	)
	(arc
		(start 121.863612 -235.270548)
		(mid 121.978231 -235.403626)
		(end 122.019568 -235.574332)
		(width 0.1143)
		(layer "In11.Cu")
		(net "GMI_CPU1_G3_CPU0_G1_TX_DN<9>")
	)
	(arc
		(start 121.549414 -234.764326)
		(mid 121.613929 -235.026545)
		(end 121.792746 -235.228892)
		(width 0.1143)
		(layer "In11.Cu")
		(net "GMI_CPU1_G3_CPU0_G1_TX_DN<9>")
	)
	(arc
		(start 350.64319 -225.50882)
		(mid 350.886517 -225.044254)
		(end 350.64319 -224.579688)
		(width 0.1143)
		(layer "In11.Cu")
		(net "GMI_CPU1_G3_CPU0_G1_TX_DN<9>")
	)
	(arc
		(start 120.852692 -226.199954)
		(mid 120.609365 -226.66452)
		(end 120.852692 -227.129086)
		(width 0.1143)
		(layer "In11.Cu")
		(net "GMI_CPU1_G3_CPU0_G1_TX_DN<9>")
	)
	(arc
		(start 120.852692 -232.679748)
		(mid 120.609365 -233.144314)
		(end 120.852692 -233.60888)
		(width 0.1143)
		(layer "In11.Cu")
		(net "GMI_CPU1_G3_CPU0_G1_TX_DN<9>")
	)
	(arc
		(start 120.852692 -224.579942)
		(mid 120.609365 -225.044508)
		(end 120.852692 -225.509074)
		(width 0.1143)
		(layer "In11.Cu")
		(net "GMI_CPU1_G3_CPU0_G1_TX_DN<9>")
	)
	(arc
		(start 350.416622 -232.334054)
		(mid 350.352107 -232.071835)
		(end 350.17329 -231.869488)
		(width 0.1143)
		(layer "In11.Cu")
		(net "GMI_CPU1_G3_CPU0_G1_TX_DN<9>")
	)
	(arc
		(start 121.07926 -232.334308)
		(mid 121.037711 -232.50573)
		(end 120.922288 -232.639108)
		(width 0.1143)
		(layer "In11.Cu")
		(net "GMI_CPU1_G3_CPU0_G1_TX_DN<9>")
	)
	(arc
		(start 350.886522 -229.904036)
		(mid 350.822007 -229.641817)
		(end 350.64319 -229.43947)
		(width 0.1143)
		(layer "In11.Cu")
		(net "GMI_CPU1_G3_CPU0_G1_TX_DN<9>")
	)
	(arc
		(start 350.64065 -230.37038)
		(mid 350.821302 -230.167635)
		(end 350.886522 -229.904036)
		(width 0.1143)
		(layer "In11.Cu")
		(net "GMI_CPU1_G3_CPU0_G1_TX_DN<9>")
	)
	(arc
		(start 121.07926 -230.71455)
		(mid 121.143775 -230.976769)
		(end 121.322592 -231.179116)
		(width 0.1143)
		(layer "In11.Cu")
		(net "GMI_CPU1_G3_CPU0_G1_TX_DN<9>")
	)
	(arc
		(start 120.852692 -227.819966)
		(mid 120.609365 -228.284532)
		(end 120.852692 -228.749098)
		(width 0.1143)
		(layer "In11.Cu")
		(net "GMI_CPU1_G3_CPU0_G1_TX_DN<9>")
	)
	(arc
		(start 120.60936 -229.90429)
		(mid 120.674596 -230.167881)
		(end 120.855232 -230.370634)
		(width 0.1143)
		(layer "In11.Cu")
		(net "GMI_CPU1_G3_CPU0_G1_TX_DN<9>")
	)
	(arc
		(start 350.17329 -234.418632)
		(mid 350.352103 -234.216282)
		(end 350.416622 -233.954066)
		(width 0.1143)
		(layer "In11.Cu")
		(net "GMI_CPU1_G3_CPU0_G1_TX_DN<9>")
	)
	(arc
		(start 350.416622 -230.714296)
		(mid 350.458171 -230.542874)
		(end 350.573594 -230.409496)
		(width 0.1143)
		(layer "In11.Cu")
		(net "GMI_CPU1_G3_CPU0_G1_TX_DN<9>")
	)
	(arc
		(start 122.306842 -236.06506)
		(mid 122.421899 -236.170685)
		(end 122.482864 -236.314488)
		(width 0.1143)
		(layer "In11.Cu")
		(net "GMI_CPU1_G3_CPU0_G1_TX_DN<9>")
	)
	(arc
		(start 349.946468 -234.764072)
		(mid 349.987723 -234.593101)
		(end 350.102424 -234.45978)
		(width 0.1143)
		(layer "In11.Cu")
		(net "GMI_CPU1_G3_CPU0_G1_TX_DN<9>")
	)
	(arc
		(start 121.395236 -231.221534)
		(mid 121.508643 -231.354423)
		(end 121.549414 -231.524302)
		(width 0.1143)
		(layer "In11.Cu")
		(net "GMI_CPU1_G3_CPU0_G1_TX_DN<9>")
	)
	(arc
		(start 121.07926 -233.95432)
		(mid 121.143775 -234.216539)
		(end 121.322592 -234.418886)
		(width 0.1143)
		(layer "In11.Cu")
		(net "GMI_CPU1_G3_CPU0_G1_TX_DN<9>")
	)
	(arc
		(start 350.64319 -222.268796)
		(mid 350.821833 -222.066401)
		(end 350.886268 -221.80423)
		(width 0.1143)
		(layer "In11.Cu")
		(net "GMI_CPU1_G3_CPU0_G1_TX_DN<9>")
	)
	(arc
		(start 120.922288 -228.789738)
		(mid 121.037715 -228.923114)
		(end 121.07926 -229.094538)
		(width 0.1143)
		(layer "In11.Cu")
		(net "GMI_CPU1_G3_CPU0_G1_TX_DN<9>")
	)
	(arc
		(start 121.07926 -229.094538)
		(mid 121.038294 -229.264944)
		(end 120.92432 -229.398068)
		(width 0.1143)
		(layer "In11.Cu")
		(net "GMI_CPU1_G3_CPU0_G1_TX_DN<9>")
	)
	(arc
		(start 349.946468 -231.524048)
		(mid 349.98723 -231.354164)
		(end 350.100646 -231.22128)
		(width 0.1143)
		(layer "In11.Cu")
		(net "GMI_CPU1_G3_CPU0_G1_TX_DN<9>")
	)
	(arc
		(start 350.416622 -229.094284)
		(mid 350.458171 -228.922862)
		(end 350.573594 -228.789484)
		(width 0.1143)
		(layer "In11.Cu")
		(net "GMI_CPU1_G3_CPU0_G1_TX_DN<9>")
	)
	(arc
		(start 121.322592 -231.869742)
		(mid 121.143779 -232.072092)
		(end 121.07926 -232.334308)
		(width 0.1143)
		(layer "In11.Cu")
		(net "GMI_CPU1_G3_CPU0_G1_TX_DN<9>")
	)
	(arc
		(start 122.019568 -235.574332)
		(mid 122.094117 -235.854523)
		(end 122.298206 -236.060488)
		(width 0.1143)
		(layer "In11.Cu")
		(net "GMI_CPU1_G3_CPU0_G1_TX_DN<9>")
	)
	(arc
		(start 350.17329 -231.178862)
		(mid 350.352103 -230.976512)
		(end 350.416622 -230.714296)
		(width 0.1143)
		(layer "In11.Cu")
		(net "GMI_CPU1_G3_CPU0_G1_TX_DN<9>")
	)
	(arc
		(start 350.573594 -224.539048)
		(mid 350.416617 -224.234248)
		(end 350.573594 -223.929448)
		(width 0.1143)
		(layer "In11.Cu")
		(net "GMI_CPU1_G3_CPU0_G1_TX_DN<9>")
	)
	(arc
		(start 350.102424 -231.82834)
		(mid 349.987748 -231.695006)
		(end 349.946468 -231.524048)
		(width 0.1143)
		(layer "In11.Cu")
		(net "GMI_CPU1_G3_CPU0_G1_TX_DN<9>")
	)
	(arc
		(start 350.64319 -227.128832)
		(mid 350.886517 -226.664266)
		(end 350.64319 -226.1997)
		(width 0.1143)
		(layer "In11.Cu")
		(net "GMI_CPU1_G3_CPU0_G1_TX_DN<9>")
	)
	(arc
		(start 350.571562 -229.397814)
		(mid 350.457633 -229.264667)
		(end 350.416622 -229.094284)
		(width 0.1143)
		(layer "In11.Cu")
		(net "GMI_CPU1_G3_CPU0_G1_TX_DN<9>")
	)
	(arc
		(start 349.703136 -235.228638)
		(mid 349.881949 -235.026288)
		(end 349.946468 -234.764072)
		(width 0.1143)
		(layer "In11.Cu")
		(net "GMI_CPU1_G3_CPU0_G1_TX_DN<9>")
	)
	(arc
		(start 121.549414 -231.524302)
		(mid 121.508159 -231.695273)
		(end 121.393458 -231.828594)
		(width 0.1143)
		(layer "In11.Cu")
		(net "GMI_CPU1_G3_CPU0_G1_TX_DN<9>")
	)
	(arc
		(start 350.573594 -227.779072)
		(mid 350.416617 -227.474272)
		(end 350.573594 -227.169472)
		(width 0.1143)
		(layer "In11.Cu")
		(net "GMI_CPU1_G3_CPU0_G1_TX_DN<9>")
	)
	(arc
		(start 350.416622 -233.954066)
		(mid 350.458171 -233.782644)
		(end 350.573594 -233.649266)
		(width 0.1143)
		(layer "In11.Cu")
		(net "GMI_CPU1_G3_CPU0_G1_TX_DN<9>")
	)
	(arc
		(start 350.573594 -232.638854)
		(mid 350.458167 -232.505478)
		(end 350.416622 -232.334054)
		(width 0.1143)
		(layer "In11.Cu")
		(net "GMI_CPU1_G3_CPU0_G1_TX_DN<9>")
	)
	(arc
		(start 120.922288 -230.40975)
		(mid 121.037715 -230.543126)
		(end 121.07926 -230.71455)
		(width 0.1143)
		(layer "In11.Cu")
		(net "GMI_CPU1_G3_CPU0_G1_TX_DN<9>")
	)
	(arc
		(start 121.393458 -234.460034)
		(mid 121.508134 -234.593368)
		(end 121.549414 -234.764326)
		(width 0.1143)
		(layer "In11.Cu")
		(net "GMI_CPU1_G3_CPU0_G1_TX_DN<9>")
	)
	(arc
		(start 349.197676 -236.060234)
		(mid 349.401818 -235.8543)
		(end 349.476314 -235.574078)
		(width 0.1143)
		(layer "In11.Cu")
		(net "GMI_CPU1_G3_CPU0_G1_TX_DN<9>")
	)
	(segment
		(start 352.668078 -233.409998)
		(end 352.201226 -233.14406)
		(width 0.12954)
		(layer "F.Cu")
		(net "GMI_CPU1_G3_CPU0_G1_TX_DN<8>")
	)
	(segment
		(start 118.827804 -233.410252)
		(end 119.294656 -233.144314)
		(width 0.12954)
		(layer "F.Cu")
		(net "GMI_CPU1_G3_CPU0_G1_TX_DN<8>")
	)
	(segment
		(start 120.423686 -231.845612)
		(end 120.422416 -231.846374)
		(width 0.1143)
		(layer "In11.Cu")
		(net "GMI_CPU1_G3_CPU0_G1_TX_DN<8>")
	)
	(segment
		(start 122.348244 -214.582248)
		(end 119.589804 -219.304108)
		(width 0.14224)
		(layer "In11.Cu")
		(net "GMI_CPU1_G3_CPU0_G1_TX_DN<8>")
	)
	(segment
		(start 351.113344 -231.869488)
		(end 351.081086 -231.850692)
		(width 0.1143)
		(layer "In11.Cu")
		(net "GMI_CPU1_G3_CPU0_G1_TX_DN<8>")
	)
	(segment
		(start 119.635524 -221.129098)
		(end 119.635524 -221.426278)
		(width 0.1143)
		(layer "In11.Cu")
		(net "GMI_CPU1_G3_CPU0_G1_TX_DN<8>")
	)
	(segment
		(start 119.982234 -232.639108)
		(end 119.951754 -232.656888)
		(width 0.1143)
		(layer "In11.Cu")
		(net "GMI_CPU1_G3_CPU0_G1_TX_DN<8>")
	)
	(segment
		(start 119.951754 -224.557082)
		(end 119.912638 -224.579942)
		(width 0.1143)
		(layer "In11.Cu")
		(net "GMI_CPU1_G3_CPU0_G1_TX_DN<8>")
	)
	(segment
		(start 351.075244 -231.847136)
		(end 351.074228 -231.846628)
		(width 0.1143)
		(layer "In11.Cu")
		(net "GMI_CPU1_G3_CPU0_G1_TX_DN<8>")
	)
	(segment
		(start 351.860358 -221.426024)
		(end 351.860358 -221.128844)
		(width 0.1143)
		(layer "In11.Cu")
		(net "GMI_CPU1_G3_CPU0_G1_TX_DN<8>")
	)
	(segment
		(start 119.951754 -232.656888)
		(end 119.912638 -232.679748)
		(width 0.1143)
		(layer "In11.Cu")
		(net "GMI_CPU1_G3_CPU0_G1_TX_DN<8>")
	)
	(segment
		(start 119.951754 -222.93707)
		(end 119.912638 -222.95993)
		(width 0.1143)
		(layer "In11.Cu")
		(net "GMI_CPU1_G3_CPU0_G1_TX_DN<8>")
	)
	(segment
		(start 351.513648 -227.169472)
		(end 351.583244 -227.128832)
		(width 0.1143)
		(layer "In11.Cu")
		(net "GMI_CPU1_G3_CPU0_G1_TX_DN<8>")
	)
	(segment
		(start 119.589804 -221.071948)
		(end 119.589804 -221.083378)
		(width 0.1143)
		(layer "In11.Cu")
		(net "GMI_CPU1_G3_CPU0_G1_TX_DN<8>")
	)
	(segment
		(start 155.589986 -187.867798)
		(end 155.589732 -187.86729)
		(width 0.14224)
		(layer "In11.Cu")
		(net "GMI_CPU1_G3_CPU0_G1_TX_DN<8>")
	)
	(segment
		(start 119.951754 -226.177094)
		(end 119.912638 -226.199954)
		(width 0.1143)
		(layer "In11.Cu")
		(net "GMI_CPU1_G3_CPU0_G1_TX_DN<8>")
	)
	(segment
		(start 351.077784 -231.84866)
		(end 351.076768 -231.848152)
		(width 0.1143)
		(layer "In11.Cu")
		(net "GMI_CPU1_G3_CPU0_G1_TX_DN<8>")
	)
	(segment
		(start 351.0407 -231.22128)
		(end 351.113344 -231.178862)
		(width 0.1143)
		(layer "In11.Cu")
		(net "GMI_CPU1_G3_CPU0_G1_TX_DN<8>")
	)
	(segment
		(start 119.982234 -222.91929)
		(end 119.951754 -222.93707)
		(width 0.1143)
		(layer "In11.Cu")
		(net "GMI_CPU1_G3_CPU0_G1_TX_DN<8>")
	)
	(segment
		(start 120.453404 -231.828594)
		(end 120.423686 -231.845612)
		(width 0.1143)
		(layer "In11.Cu")
		(net "GMI_CPU1_G3_CPU0_G1_TX_DN<8>")
	)
	(segment
		(start 119.589804 -219.304108)
		(end 119.589804 -221.071948)
		(width 0.14224)
		(layer "In11.Cu")
		(net "GMI_CPU1_G3_CPU0_G1_TX_DN<8>")
	)
	(segment
		(start 351.906078 -219.18549)
		(end 349.223584 -214.667084)
		(width 0.14224)
		(layer "In11.Cu")
		(net "GMI_CPU1_G3_CPU0_G1_TX_DN<8>")
	)
	(segment
		(start 351.081086 -231.850692)
		(end 351.080324 -231.850184)
		(width 0.1143)
		(layer "In11.Cu")
		(net "GMI_CPU1_G3_CPU0_G1_TX_DN<8>")
	)
	(segment
		(start 351.070672 -231.844596)
		(end 351.069402 -231.843834)
		(width 0.1143)
		(layer "In11.Cu")
		(net "GMI_CPU1_G3_CPU0_G1_TX_DN<8>")
	)
	(segment
		(start 166.38651 -181.515766)
		(end 160.978342 -183.449214)
		(width 0.14224)
		(layer "In11.Cu")
		(net "GMI_CPU1_G3_CPU0_G1_TX_DN<8>")
	)
	(segment
		(start 351.513648 -225.54946)
		(end 351.583244 -225.50882)
		(width 0.1143)
		(layer "In11.Cu")
		(net "GMI_CPU1_G3_CPU0_G1_TX_DN<8>")
	)
	(segment
		(start 351.078546 -231.849168)
		(end 351.077784 -231.84866)
		(width 0.1143)
		(layer "In11.Cu")
		(net "GMI_CPU1_G3_CPU0_G1_TX_DN<8>")
	)
	(segment
		(start 119.675402 -233.06151)
		(end 119.592598 -233.144314)
		(width 0.1143)
		(layer "In11.Cu")
		(net "GMI_CPU1_G3_CPU0_G1_TX_DN<8>")
	)
	(segment
		(start 351.544128 -229.41661)
		(end 351.511616 -229.397814)
		(width 0.1143)
		(layer "In11.Cu")
		(net "GMI_CPU1_G3_CPU0_G1_TX_DN<8>")
	)
	(segment
		(start 120.420638 -231.84739)
		(end 120.382538 -231.869742)
		(width 0.1143)
		(layer "In11.Cu")
		(net "GMI_CPU1_G3_CPU0_G1_TX_DN<8>")
	)
	(segment
		(start 120.422416 -231.846374)
		(end 120.421654 -231.846882)
		(width 0.1143)
		(layer "In11.Cu")
		(net "GMI_CPU1_G3_CPU0_G1_TX_DN<8>")
	)
	(segment
		(start 349.223584 -214.667084)
		(end 314.625482 -186.298586)
		(width 0.14224)
		(layer "In11.Cu")
		(net "GMI_CPU1_G3_CPU0_G1_TX_DN<8>")
	)
	(segment
		(start 308.433216 -182.793132)
		(end 307.086 -182.311548)
		(width 0.14224)
		(layer "In11.Cu")
		(net "GMI_CPU1_G3_CPU0_G1_TX_DN<8>")
	)
	(segment
		(start 119.982234 -226.159314)
		(end 119.951754 -226.177094)
		(width 0.1143)
		(layer "In11.Cu")
		(net "GMI_CPU1_G3_CPU0_G1_TX_DN<8>")
	)
	(segment
		(start 119.915178 -230.370634)
		(end 119.982234 -230.40975)
		(width 0.1143)
		(layer "In11.Cu")
		(net "GMI_CPU1_G3_CPU0_G1_TX_DN<8>")
	)
	(segment
		(start 119.589804 -221.083378)
		(end 119.635524 -221.129098)
		(width 0.1143)
		(layer "In11.Cu")
		(net "GMI_CPU1_G3_CPU0_G1_TX_DN<8>")
	)
	(segment
		(start 119.951754 -228.771958)
		(end 119.982234 -228.789738)
		(width 0.1143)
		(layer "In11.Cu")
		(net "GMI_CPU1_G3_CPU0_G1_TX_DN<8>")
	)
	(segment
		(start 351.583244 -224.579688)
		(end 351.513648 -224.539048)
		(width 0.1143)
		(layer "In11.Cu")
		(net "GMI_CPU1_G3_CPU0_G1_TX_DN<8>")
	)
	(segment
		(start 351.826322 -221.80423)
		(end 351.826322 -221.46006)
		(width 0.1143)
		(layer "In11.Cu")
		(net "GMI_CPU1_G3_CPU0_G1_TX_DN<8>")
	)
	(segment
		(start 351.583244 -229.43947)
		(end 351.544128 -229.41661)
		(width 0.1143)
		(layer "In11.Cu")
		(net "GMI_CPU1_G3_CPU0_G1_TX_DN<8>")
	)
	(segment
		(start 119.66956 -221.460314)
		(end 119.66956 -221.804484)
		(width 0.1143)
		(layer "In11.Cu")
		(net "GMI_CPU1_G3_CPU0_G1_TX_DN<8>")
	)
	(segment
		(start 307.086 -182.311548)
		(end 302.896016 -182.311548)
		(width 0.14224)
		(layer "In11.Cu")
		(net "GMI_CPU1_G3_CPU0_G1_TX_DN<8>")
	)
	(segment
		(start 351.826322 -221.46006)
		(end 351.860358 -221.426024)
		(width 0.1143)
		(layer "In11.Cu")
		(net "GMI_CPU1_G3_CPU0_G1_TX_DN<8>")
	)
	(segment
		(start 119.592598 -233.144314)
		(end 119.294656 -233.144314)
		(width 0.1143)
		(layer "In11.Cu")
		(net "GMI_CPU1_G3_CPU0_G1_TX_DN<8>")
	)
	(segment
		(start 302.896016 -182.311548)
		(end 166.38651 -181.515766)
		(width 0.14224)
		(layer "In11.Cu")
		(net "GMI_CPU1_G3_CPU0_G1_TX_DN<8>")
	)
	(segment
		(start 119.912638 -225.509074)
		(end 119.951754 -225.531934)
		(width 0.1143)
		(layer "In11.Cu")
		(net "GMI_CPU1_G3_CPU0_G1_TX_DN<8>")
	)
	(segment
		(start 314.625482 -186.298586)
		(end 308.433216 -182.793132)
		(width 0.14224)
		(layer "In11.Cu")
		(net "GMI_CPU1_G3_CPU0_G1_TX_DN<8>")
	)
	(segment
		(start 155.589732 -187.86729)
		(end 145.773648 -195.91655)
		(width 0.14224)
		(layer "In11.Cu")
		(net "GMI_CPU1_G3_CPU0_G1_TX_DN<8>")
	)
	(segment
		(start 119.951754 -225.531934)
		(end 119.982234 -225.549714)
		(width 0.1143)
		(layer "In11.Cu")
		(net "GMI_CPU1_G3_CPU0_G1_TX_DN<8>")
	)
	(segment
		(start 351.513648 -230.409496)
		(end 351.580704 -230.37038)
		(width 0.1143)
		(layer "In11.Cu")
		(net "GMI_CPU1_G3_CPU0_G1_TX_DN<8>")
	)
	(segment
		(start 351.906078 -221.083124)
		(end 351.906078 -219.18549)
		(width 0.14224)
		(layer "In11.Cu")
		(net "GMI_CPU1_G3_CPU0_G1_TX_DN<8>")
	)
	(segment
		(start 119.951754 -229.416864)
		(end 119.912638 -229.439724)
		(width 0.1143)
		(layer "In11.Cu")
		(net "GMI_CPU1_G3_CPU0_G1_TX_DN<8>")
	)
	(segment
		(start 119.984266 -229.398068)
		(end 119.951754 -229.416864)
		(width 0.1143)
		(layer "In11.Cu")
		(net "GMI_CPU1_G3_CPU0_G1_TX_DN<8>")
	)
	(segment
		(start 119.912638 -222.26905)
		(end 119.982234 -222.30969)
		(width 0.1143)
		(layer "In11.Cu")
		(net "GMI_CPU1_G3_CPU0_G1_TX_DN<8>")
	)
	(segment
		(start 351.583244 -232.679494)
		(end 351.513648 -232.638854)
		(width 0.1143)
		(layer "In11.Cu")
		(net "GMI_CPU1_G3_CPU0_G1_TX_DN<8>")
	)
	(segment
		(start 145.773648 -195.91655)
		(end 144.724628 -196.23405)
		(width 0.14224)
		(layer "In11.Cu")
		(net "GMI_CPU1_G3_CPU0_G1_TX_DN<8>")
	)
	(segment
		(start 351.513648 -228.789484)
		(end 351.583244 -228.748844)
		(width 0.1143)
		(layer "In11.Cu")
		(net "GMI_CPU1_G3_CPU0_G1_TX_DN<8>")
	)
	(segment
		(start 120.421654 -231.201976)
		(end 120.455182 -231.221534)
		(width 0.1143)
		(layer "In11.Cu")
		(net "GMI_CPU1_G3_CPU0_G1_TX_DN<8>")
	)
	(segment
		(start 160.978342 -183.449214)
		(end 155.589986 -187.867798)
		(width 0.14224)
		(layer "In11.Cu")
		(net "GMI_CPU1_G3_CPU0_G1_TX_DN<8>")
	)
	(segment
		(start 144.724628 -196.23405)
		(end 122.348244 -214.582248)
		(width 0.14224)
		(layer "In11.Cu")
		(net "GMI_CPU1_G3_CPU0_G1_TX_DN<8>")
	)
	(segment
		(start 351.903284 -233.14406)
		(end 351.82048 -233.061256)
		(width 0.1143)
		(layer "In11.Cu")
		(net "GMI_CPU1_G3_CPU0_G1_TX_DN<8>")
	)
	(segment
		(start 119.951754 -223.911922)
		(end 119.982234 -223.929702)
		(width 0.1143)
		(layer "In11.Cu")
		(net "GMI_CPU1_G3_CPU0_G1_TX_DN<8>")
	)
	(segment
		(start 351.513648 -223.929448)
		(end 351.583244 -223.888808)
		(width 0.1143)
		(layer "In11.Cu")
		(net "GMI_CPU1_G3_CPU0_G1_TX_DN<8>")
	)
	(segment
		(start 119.982234 -227.779326)
		(end 119.951754 -227.797106)
		(width 0.1143)
		(layer "In11.Cu")
		(net "GMI_CPU1_G3_CPU0_G1_TX_DN<8>")
	)
	(segment
		(start 351.069402 -231.843834)
		(end 351.042478 -231.82834)
		(width 0.1143)
		(layer "In11.Cu")
		(net "GMI_CPU1_G3_CPU0_G1_TX_DN<8>")
	)
	(segment
		(start 120.421654 -231.846882)
		(end 120.420638 -231.84739)
		(width 0.1143)
		(layer "In11.Cu")
		(net "GMI_CPU1_G3_CPU0_G1_TX_DN<8>")
	)
	(segment
		(start 119.951754 -227.151946)
		(end 119.982234 -227.169726)
		(width 0.1143)
		(layer "In11.Cu")
		(net "GMI_CPU1_G3_CPU0_G1_TX_DN<8>")
	)
	(segment
		(start 119.951754 -227.797106)
		(end 119.912638 -227.819966)
		(width 0.1143)
		(layer "In11.Cu")
		(net "GMI_CPU1_G3_CPU0_G1_TX_DN<8>")
	)
	(segment
		(start 119.635524 -221.426278)
		(end 119.66956 -221.460314)
		(width 0.1143)
		(layer "In11.Cu")
		(net "GMI_CPU1_G3_CPU0_G1_TX_DN<8>")
	)
	(segment
		(start 351.583244 -222.959676)
		(end 351.513648 -222.919036)
		(width 0.1143)
		(layer "In11.Cu")
		(net "GMI_CPU1_G3_CPU0_G1_TX_DN<8>")
	)
	(segment
		(start 351.860358 -221.128844)
		(end 351.906078 -221.083124)
		(width 0.1143)
		(layer "In11.Cu")
		(net "GMI_CPU1_G3_CPU0_G1_TX_DN<8>")
	)
	(segment
		(start 351.072196 -231.845358)
		(end 351.070672 -231.844596)
		(width 0.1143)
		(layer "In11.Cu")
		(net "GMI_CPU1_G3_CPU0_G1_TX_DN<8>")
	)
	(segment
		(start 351.583244 -227.819712)
		(end 351.513648 -227.779072)
		(width 0.1143)
		(layer "In11.Cu")
		(net "GMI_CPU1_G3_CPU0_G1_TX_DN<8>")
	)
	(segment
		(start 351.513648 -222.309436)
		(end 351.583244 -222.268796)
		(width 0.1143)
		(layer "In11.Cu")
		(net "GMI_CPU1_G3_CPU0_G1_TX_DN<8>")
	)
	(segment
		(start 351.583244 -226.1997)
		(end 351.513648 -226.15906)
		(width 0.1143)
		(layer "In11.Cu")
		(net "GMI_CPU1_G3_CPU0_G1_TX_DN<8>")
	)
	(segment
		(start 351.074228 -231.846628)
		(end 351.073466 -231.84612)
		(width 0.1143)
		(layer "In11.Cu")
		(net "GMI_CPU1_G3_CPU0_G1_TX_DN<8>")
	)
	(segment
		(start 119.912638 -228.749098)
		(end 119.951754 -228.771958)
		(width 0.1143)
		(layer "In11.Cu")
		(net "GMI_CPU1_G3_CPU0_G1_TX_DN<8>")
	)
	(segment
		(start 351.073466 -231.84612)
		(end 351.072196 -231.845358)
		(width 0.1143)
		(layer "In11.Cu")
		(net "GMI_CPU1_G3_CPU0_G1_TX_DN<8>")
	)
	(segment
		(start 352.201226 -233.14406)
		(end 351.903284 -233.14406)
		(width 0.1143)
		(layer "In11.Cu")
		(net "GMI_CPU1_G3_CPU0_G1_TX_DN<8>")
	)
	(segment
		(start 119.982234 -224.539302)
		(end 119.951754 -224.557082)
		(width 0.1143)
		(layer "In11.Cu")
		(net "GMI_CPU1_G3_CPU0_G1_TX_DN<8>")
	)
	(segment
		(start 119.912638 -227.129086)
		(end 119.951754 -227.151946)
		(width 0.1143)
		(layer "In11.Cu")
		(net "GMI_CPU1_G3_CPU0_G1_TX_DN<8>")
	)
	(segment
		(start 119.912638 -223.889062)
		(end 119.951754 -223.911922)
		(width 0.1143)
		(layer "In11.Cu")
		(net "GMI_CPU1_G3_CPU0_G1_TX_DN<8>")
	)
	(segment
		(start 351.076768 -231.848152)
		(end 351.075244 -231.847136)
		(width 0.1143)
		(layer "In11.Cu")
		(net "GMI_CPU1_G3_CPU0_G1_TX_DN<8>")
	)
	(segment
		(start 120.382538 -231.179116)
		(end 120.421654 -231.201976)
		(width 0.1143)
		(layer "In11.Cu")
		(net "GMI_CPU1_G3_CPU0_G1_TX_DN<8>")
	)
	(segment
		(start 351.080324 -231.850184)
		(end 351.078546 -231.849168)
		(width 0.1143)
		(layer "In11.Cu")
		(net "GMI_CPU1_G3_CPU0_G1_TX_DN<8>")
	)
	(arc
		(start 120.139206 -230.71455)
		(mid 120.203721 -230.976769)
		(end 120.382538 -231.179116)
		(width 0.1143)
		(layer "In11.Cu")
		(net "GMI_CPU1_G3_CPU0_G1_TX_DN<8>")
	)
	(arc
		(start 119.912638 -232.679748)
		(mid 119.760651 -232.836256)
		(end 119.679212 -233.03865)
		(width 0.1143)
		(layer "In11.Cu")
		(net "GMI_CPU1_G3_CPU0_G1_TX_DN<8>")
	)
	(arc
		(start 350.886522 -231.524048)
		(mid 350.927284 -231.354164)
		(end 351.0407 -231.22128)
		(width 0.1143)
		(layer "In11.Cu")
		(net "GMI_CPU1_G3_CPU0_G1_TX_DN<8>")
	)
	(arc
		(start 119.912638 -224.579942)
		(mid 119.669311 -225.044508)
		(end 119.912638 -225.509074)
		(width 0.1143)
		(layer "In11.Cu")
		(net "GMI_CPU1_G3_CPU0_G1_TX_DN<8>")
	)
	(arc
		(start 351.583244 -227.128832)
		(mid 351.826571 -226.664266)
		(end 351.583244 -226.1997)
		(width 0.1143)
		(layer "In11.Cu")
		(net "GMI_CPU1_G3_CPU0_G1_TX_DN<8>")
	)
	(arc
		(start 351.513648 -227.779072)
		(mid 351.356671 -227.474272)
		(end 351.513648 -227.169472)
		(width 0.1143)
		(layer "In11.Cu")
		(net "GMI_CPU1_G3_CPU0_G1_TX_DN<8>")
	)
	(arc
		(start 351.81667 -233.038396)
		(mid 351.735237 -232.835998)
		(end 351.583244 -232.679494)
		(width 0.1143)
		(layer "In11.Cu")
		(net "GMI_CPU1_G3_CPU0_G1_TX_DN<8>")
	)
	(arc
		(start 119.982234 -227.169726)
		(mid 120.139211 -227.474526)
		(end 119.982234 -227.779326)
		(width 0.1143)
		(layer "In11.Cu")
		(net "GMI_CPU1_G3_CPU0_G1_TX_DN<8>")
	)
	(arc
		(start 119.982234 -223.929702)
		(mid 120.139211 -224.234502)
		(end 119.982234 -224.539302)
		(width 0.1143)
		(layer "In11.Cu")
		(net "GMI_CPU1_G3_CPU0_G1_TX_DN<8>")
	)
	(arc
		(start 119.912638 -222.95993)
		(mid 119.669311 -223.424496)
		(end 119.912638 -223.889062)
		(width 0.1143)
		(layer "In11.Cu")
		(net "GMI_CPU1_G3_CPU0_G1_TX_DN<8>")
	)
	(arc
		(start 119.982234 -222.30969)
		(mid 120.139211 -222.61449)
		(end 119.982234 -222.91929)
		(width 0.1143)
		(layer "In11.Cu")
		(net "GMI_CPU1_G3_CPU0_G1_TX_DN<8>")
	)
	(arc
		(start 351.042478 -231.82834)
		(mid 350.927802 -231.695006)
		(end 350.886522 -231.524048)
		(width 0.1143)
		(layer "In11.Cu")
		(net "GMI_CPU1_G3_CPU0_G1_TX_DN<8>")
	)
	(arc
		(start 120.382538 -231.869742)
		(mid 120.203725 -232.072092)
		(end 120.139206 -232.334308)
		(width 0.1143)
		(layer "In11.Cu")
		(net "GMI_CPU1_G3_CPU0_G1_TX_DN<8>")
	)
	(arc
		(start 120.455182 -231.221534)
		(mid 120.568589 -231.354423)
		(end 120.60936 -231.524302)
		(width 0.1143)
		(layer "In11.Cu")
		(net "GMI_CPU1_G3_CPU0_G1_TX_DN<8>")
	)
	(arc
		(start 119.912638 -229.439724)
		(mid 119.733825 -229.642074)
		(end 119.669306 -229.90429)
		(width 0.1143)
		(layer "In11.Cu")
		(net "GMI_CPU1_G3_CPU0_G1_TX_DN<8>")
	)
	(arc
		(start 351.513648 -222.919036)
		(mid 351.356671 -222.614236)
		(end 351.513648 -222.309436)
		(width 0.1143)
		(layer "In11.Cu")
		(net "GMI_CPU1_G3_CPU0_G1_TX_DN<8>")
	)
	(arc
		(start 119.982234 -225.549714)
		(mid 120.139211 -225.854514)
		(end 119.982234 -226.159314)
		(width 0.1143)
		(layer "In11.Cu")
		(net "GMI_CPU1_G3_CPU0_G1_TX_DN<8>")
	)
	(arc
		(start 351.513648 -226.15906)
		(mid 351.356671 -225.85426)
		(end 351.513648 -225.54946)
		(width 0.1143)
		(layer "In11.Cu")
		(net "GMI_CPU1_G3_CPU0_G1_TX_DN<8>")
	)
	(arc
		(start 351.583244 -222.268796)
		(mid 351.761887 -222.066401)
		(end 351.826322 -221.80423)
		(width 0.1143)
		(layer "In11.Cu")
		(net "GMI_CPU1_G3_CPU0_G1_TX_DN<8>")
	)
	(arc
		(start 120.139206 -232.334308)
		(mid 120.097657 -232.50573)
		(end 119.982234 -232.639108)
		(width 0.1143)
		(layer "In11.Cu")
		(net "GMI_CPU1_G3_CPU0_G1_TX_DN<8>")
	)
	(arc
		(start 351.826576 -229.904036)
		(mid 351.762061 -229.641817)
		(end 351.583244 -229.43947)
		(width 0.1143)
		(layer "In11.Cu")
		(net "GMI_CPU1_G3_CPU0_G1_TX_DN<8>")
	)
	(arc
		(start 119.912638 -227.819966)
		(mid 119.669311 -228.284532)
		(end 119.912638 -228.749098)
		(width 0.1143)
		(layer "In11.Cu")
		(net "GMI_CPU1_G3_CPU0_G1_TX_DN<8>")
	)
	(arc
		(start 351.113344 -231.178862)
		(mid 351.292157 -230.976512)
		(end 351.356676 -230.714296)
		(width 0.1143)
		(layer "In11.Cu")
		(net "GMI_CPU1_G3_CPU0_G1_TX_DN<8>")
	)
	(arc
		(start 351.583244 -223.888808)
		(mid 351.826571 -223.424242)
		(end 351.583244 -222.959676)
		(width 0.1143)
		(layer "In11.Cu")
		(net "GMI_CPU1_G3_CPU0_G1_TX_DN<8>")
	)
	(arc
		(start 119.912638 -226.199954)
		(mid 119.669311 -226.66452)
		(end 119.912638 -227.129086)
		(width 0.1143)
		(layer "In11.Cu")
		(net "GMI_CPU1_G3_CPU0_G1_TX_DN<8>")
	)
	(arc
		(start 119.982234 -230.40975)
		(mid 120.097661 -230.543126)
		(end 120.139206 -230.71455)
		(width 0.1143)
		(layer "In11.Cu")
		(net "GMI_CPU1_G3_CPU0_G1_TX_DN<8>")
	)
	(arc
		(start 119.679212 -233.03865)
		(mid 119.677189 -233.05006)
		(end 119.675402 -233.06151)
		(width 0.1143)
		(layer "In11.Cu")
		(net "GMI_CPU1_G3_CPU0_G1_TX_DN<8>")
	)
	(arc
		(start 351.82048 -233.061256)
		(mid 351.818692 -233.049807)
		(end 351.81667 -233.038396)
		(width 0.1143)
		(layer "In11.Cu")
		(net "GMI_CPU1_G3_CPU0_G1_TX_DN<8>")
	)
	(arc
		(start 119.66956 -221.804484)
		(mid 119.733934 -222.066688)
		(end 119.912638 -222.26905)
		(width 0.1143)
		(layer "In11.Cu")
		(net "GMI_CPU1_G3_CPU0_G1_TX_DN<8>")
	)
	(arc
		(start 351.513648 -224.539048)
		(mid 351.356671 -224.234248)
		(end 351.513648 -223.929448)
		(width 0.1143)
		(layer "In11.Cu")
		(net "GMI_CPU1_G3_CPU0_G1_TX_DN<8>")
	)
	(arc
		(start 351.583244 -228.748844)
		(mid 351.826571 -228.284278)
		(end 351.583244 -227.819712)
		(width 0.1143)
		(layer "In11.Cu")
		(net "GMI_CPU1_G3_CPU0_G1_TX_DN<8>")
	)
	(arc
		(start 119.982234 -228.789738)
		(mid 120.097661 -228.923114)
		(end 120.139206 -229.094538)
		(width 0.1143)
		(layer "In11.Cu")
		(net "GMI_CPU1_G3_CPU0_G1_TX_DN<8>")
	)
	(arc
		(start 119.669306 -229.90429)
		(mid 119.734542 -230.167881)
		(end 119.915178 -230.370634)
		(width 0.1143)
		(layer "In11.Cu")
		(net "GMI_CPU1_G3_CPU0_G1_TX_DN<8>")
	)
	(arc
		(start 351.513648 -232.638854)
		(mid 351.398221 -232.505478)
		(end 351.356676 -232.334054)
		(width 0.1143)
		(layer "In11.Cu")
		(net "GMI_CPU1_G3_CPU0_G1_TX_DN<8>")
	)
	(arc
		(start 351.356676 -229.094284)
		(mid 351.398225 -228.922862)
		(end 351.513648 -228.789484)
		(width 0.1143)
		(layer "In11.Cu")
		(net "GMI_CPU1_G3_CPU0_G1_TX_DN<8>")
	)
	(arc
		(start 351.511616 -229.397814)
		(mid 351.397687 -229.264667)
		(end 351.356676 -229.094284)
		(width 0.1143)
		(layer "In11.Cu")
		(net "GMI_CPU1_G3_CPU0_G1_TX_DN<8>")
	)
	(arc
		(start 120.60936 -231.524302)
		(mid 120.568105 -231.695273)
		(end 120.453404 -231.828594)
		(width 0.1143)
		(layer "In11.Cu")
		(net "GMI_CPU1_G3_CPU0_G1_TX_DN<8>")
	)
	(arc
		(start 351.583244 -225.50882)
		(mid 351.826571 -225.044254)
		(end 351.583244 -224.579688)
		(width 0.1143)
		(layer "In11.Cu")
		(net "GMI_CPU1_G3_CPU0_G1_TX_DN<8>")
	)
	(arc
		(start 351.580704 -230.37038)
		(mid 351.761356 -230.167635)
		(end 351.826576 -229.904036)
		(width 0.1143)
		(layer "In11.Cu")
		(net "GMI_CPU1_G3_CPU0_G1_TX_DN<8>")
	)
	(arc
		(start 351.356676 -232.334054)
		(mid 351.292161 -232.071835)
		(end 351.113344 -231.869488)
		(width 0.1143)
		(layer "In11.Cu")
		(net "GMI_CPU1_G3_CPU0_G1_TX_DN<8>")
	)
	(arc
		(start 351.356676 -230.714296)
		(mid 351.398225 -230.542874)
		(end 351.513648 -230.409496)
		(width 0.1143)
		(layer "In11.Cu")
		(net "GMI_CPU1_G3_CPU0_G1_TX_DN<8>")
	)
	(arc
		(start 120.139206 -229.094538)
		(mid 120.09824 -229.264944)
		(end 119.984266 -229.398068)
		(width 0.1143)
		(layer "In11.Cu")
		(net "GMI_CPU1_G3_CPU0_G1_TX_DN<8>")
	)
	(segment
		(start 118.827804 -231.79024)
		(end 119.294656 -231.524302)
		(width 0.12954)
		(layer "F.Cu")
		(net "GMI_CPU1_G3_CPU0_G1_TX_DN<7>")
	)
	(segment
		(start 352.668078 -231.789986)
		(end 352.201226 -231.524048)
		(width 0.12954)
		(layer "F.Cu")
		(net "GMI_CPU1_G3_CPU0_G1_TX_DN<7>")
	)
	(segment
		(start 119.04345 -228.790246)
		(end 119.0117 -228.771958)
		(width 0.1143)
		(layer "In11.Cu")
		(net "GMI_CPU1_G3_CPU0_G1_TX_DN<7>")
	)
	(segment
		(start 349.845376 -213.888066)
		(end 352.851212 -218.951048)
		(width 0.14224)
		(layer "In11.Cu")
		(net "GMI_CPU1_G3_CPU0_G1_TX_DN<7>")
	)
	(segment
		(start 352.483928 -230.391462)
		(end 352.484182 -230.391716)
		(width 0.1143)
		(layer "In11.Cu")
		(net "GMI_CPU1_G3_CPU0_G1_TX_DN<7>")
	)
	(segment
		(start 352.766376 -221.46514)
		(end 352.766376 -221.80423)
		(width 0.1143)
		(layer "In11.Cu")
		(net "GMI_CPU1_G3_CPU0_G1_TX_DN<7>")
	)
	(segment
		(start 119.063262 -223.944434)
		(end 119.04345 -223.93021)
		(width 0.1143)
		(layer "In11.Cu")
		(net "GMI_CPU1_G3_CPU0_G1_TX_DN<7>")
	)
	(segment
		(start 352.484182 -230.391716)
		(end 352.48342 -230.392224)
		(width 0.1143)
		(layer "In11.Cu")
		(net "GMI_CPU1_G3_CPU0_G1_TX_DN<7>")
	)
	(segment
		(start 118.972584 -226.199954)
		(end 119.0117 -226.177094)
		(width 0.1143)
		(layer "In11.Cu")
		(net "GMI_CPU1_G3_CPU0_G1_TX_DN<7>")
	)
	(segment
		(start 307.267102 -181.377336)
		(end 308.876446 -181.953154)
		(width 0.14224)
		(layer "In11.Cu")
		(net "GMI_CPU1_G3_CPU0_G1_TX_DN<7>")
	)
	(segment
		(start 119.0117 -230.39197)
		(end 119.011954 -230.391716)
		(width 0.1143)
		(layer "In11.Cu")
		(net "GMI_CPU1_G3_CPU0_G1_TX_DN<7>")
	)
	(segment
		(start 118.972584 -229.439724)
		(end 119.042434 -229.399338)
		(width 0.1143)
		(layer "In11.Cu")
		(net "GMI_CPU1_G3_CPU0_G1_TX_DN<7>")
	)
	(segment
		(start 352.43262 -224.524316)
		(end 352.452432 -224.53854)
		(width 0.1143)
		(layer "In11.Cu")
		(net "GMI_CPU1_G3_CPU0_G1_TX_DN<7>")
	)
	(segment
		(start 119.033544 -222.304356)
		(end 119.033036 -222.304356)
		(width 0.1143)
		(layer "In11.Cu")
		(net "GMI_CPU1_G3_CPU0_G1_TX_DN<7>")
	)
	(segment
		(start 119.592598 -231.524302)
		(end 119.662448 -231.454452)
		(width 0.1143)
		(layer "In11.Cu")
		(net "GMI_CPU1_G3_CPU0_G1_TX_DN<7>")
	)
	(segment
		(start 352.462846 -222.304102)
		(end 352.462338 -222.304102)
		(width 0.1143)
		(layer "In11.Cu")
		(net "GMI_CPU1_G3_CPU0_G1_TX_DN<7>")
	)
	(segment
		(start 352.462846 -222.92437)
		(end 352.46437 -222.925386)
		(width 0.1143)
		(layer "In11.Cu")
		(net "GMI_CPU1_G3_CPU0_G1_TX_DN<7>")
	)
	(segment
		(start 352.43262 -227.76434)
		(end 352.452432 -227.778564)
		(width 0.1143)
		(layer "In11.Cu")
		(net "GMI_CPU1_G3_CPU0_G1_TX_DN<7>")
	)
	(segment
		(start 160.153858 -182.734458)
		(end 166.178484 -180.58003)
		(width 0.14224)
		(layer "In11.Cu")
		(net "GMI_CPU1_G3_CPU0_G1_TX_DN<7>")
	)
	(segment
		(start 352.523298 -228.748844)
		(end 352.484182 -228.771704)
		(width 0.1143)
		(layer "In11.Cu")
		(net "GMI_CPU1_G3_CPU0_G1_TX_DN<7>")
	)
	(segment
		(start 352.484182 -224.556828)
		(end 352.523298 -224.579688)
		(width 0.1143)
		(layer "In11.Cu")
		(net "GMI_CPU1_G3_CPU0_G1_TX_DN<7>")
	)
	(segment
		(start 118.972584 -227.819966)
		(end 119.0117 -227.797106)
		(width 0.1143)
		(layer "In11.Cu")
		(net "GMI_CPU1_G3_CPU0_G1_TX_DN<7>")
	)
	(segment
		(start 118.972584 -224.579942)
		(end 119.0117 -224.557082)
		(width 0.1143)
		(layer "In11.Cu")
		(net "GMI_CPU1_G3_CPU0_G1_TX_DN<7>")
	)
	(segment
		(start 352.484182 -228.771704)
		(end 352.452432 -228.789992)
		(width 0.1143)
		(layer "In11.Cu")
		(net "GMI_CPU1_G3_CPU0_G1_TX_DN<7>")
	)
	(segment
		(start 352.452432 -224.53854)
		(end 352.484182 -224.556828)
		(width 0.1143)
		(layer "In11.Cu")
		(net "GMI_CPU1_G3_CPU0_G1_TX_DN<7>")
	)
	(segment
		(start 119.515128 -231.221534)
		(end 119.445278 -231.180894)
		(width 0.1143)
		(layer "In11.Cu")
		(net "GMI_CPU1_G3_CPU0_G1_TX_DN<7>")
	)
	(segment
		(start 119.04345 -227.170234)
		(end 118.972584 -227.129086)
		(width 0.1143)
		(layer "In11.Cu")
		(net "GMI_CPU1_G3_CPU0_G1_TX_DN<7>")
	)
	(segment
		(start 119.199406 -230.71455)
		(end 119.199406 -230.586026)
		(width 0.1143)
		(layer "In11.Cu")
		(net "GMI_CPU1_G3_CPU0_G1_TX_DN<7>")
	)
	(segment
		(start 118.69039 -221.426278)
		(end 118.69039 -221.129098)
		(width 0.1143)
		(layer "In11.Cu")
		(net "GMI_CPU1_G3_CPU0_G1_TX_DN<7>")
	)
	(segment
		(start 351.833434 -231.454198)
		(end 351.903284 -231.524048)
		(width 0.1143)
		(layer "In11.Cu")
		(net "GMI_CPU1_G3_CPU0_G1_TX_DN<7>")
	)
	(segment
		(start 119.042434 -229.399338)
		(end 119.045228 -229.397306)
		(width 0.1143)
		(layer "In11.Cu")
		(net "GMI_CPU1_G3_CPU0_G1_TX_DN<7>")
	)
	(segment
		(start 302.899064 -181.377336)
		(end 307.267102 -181.377336)
		(width 0.14224)
		(layer "In11.Cu")
		(net "GMI_CPU1_G3_CPU0_G1_TX_DN<7>")
	)
	(segment
		(start 119.063262 -225.564446)
		(end 119.04345 -225.550222)
		(width 0.1143)
		(layer "In11.Cu")
		(net "GMI_CPU1_G3_CPU0_G1_TX_DN<7>")
	)
	(segment
		(start 352.851212 -221.071694)
		(end 352.851212 -221.083124)
		(width 0.1143)
		(layer "In11.Cu")
		(net "GMI_CPU1_G3_CPU0_G1_TX_DN<7>")
	)
	(segment
		(start 118.972584 -222.95993)
		(end 119.010684 -222.937578)
		(width 0.1143)
		(layer "In11.Cu")
		(net "GMI_CPU1_G3_CPU0_G1_TX_DN<7>")
	)
	(segment
		(start 119.04345 -224.538794)
		(end 119.063262 -224.52457)
		(width 0.1143)
		(layer "In11.Cu")
		(net "GMI_CPU1_G3_CPU0_G1_TX_DN<7>")
	)
	(segment
		(start 166.178484 -180.58003)
		(end 302.899064 -181.377336)
		(width 0.14224)
		(layer "In11.Cu")
		(net "GMI_CPU1_G3_CPU0_G1_TX_DN<7>")
	)
	(segment
		(start 118.729506 -221.465394)
		(end 118.69039 -221.426278)
		(width 0.1143)
		(layer "In11.Cu")
		(net "GMI_CPU1_G3_CPU0_G1_TX_DN<7>")
	)
	(segment
		(start 119.04345 -226.158806)
		(end 119.063262 -226.144582)
		(width 0.1143)
		(layer "In11.Cu")
		(net "GMI_CPU1_G3_CPU0_G1_TX_DN<7>")
	)
	(segment
		(start 352.523298 -227.128832)
		(end 352.452432 -227.16998)
		(width 0.1143)
		(layer "In11.Cu")
		(net "GMI_CPU1_G3_CPU0_G1_TX_DN<7>")
	)
	(segment
		(start 352.452432 -225.549968)
		(end 352.43262 -225.564192)
		(width 0.1143)
		(layer "In11.Cu")
		(net "GMI_CPU1_G3_CPU0_G1_TX_DN<7>")
	)
	(segment
		(start 352.450654 -229.397052)
		(end 352.453448 -229.399084)
		(width 0.1143)
		(layer "In11.Cu")
		(net "GMI_CPU1_G3_CPU0_G1_TX_DN<7>")
	)
	(segment
		(start 352.523298 -225.50882)
		(end 352.452432 -225.549968)
		(width 0.1143)
		(layer "In11.Cu")
		(net "GMI_CPU1_G3_CPU0_G1_TX_DN<7>")
	)
	(segment
		(start 352.48342 -230.392224)
		(end 352.452432 -230.410004)
		(width 0.1143)
		(layer "In11.Cu")
		(net "GMI_CPU1_G3_CPU0_G1_TX_DN<7>")
	)
	(segment
		(start 351.903284 -231.524048)
		(end 352.201226 -231.524048)
		(width 0.1143)
		(layer "In11.Cu")
		(net "GMI_CPU1_G3_CPU0_G1_TX_DN<7>")
	)
	(segment
		(start 352.452432 -227.16998)
		(end 352.43262 -227.184204)
		(width 0.1143)
		(layer "In11.Cu")
		(net "GMI_CPU1_G3_CPU0_G1_TX_DN<7>")
	)
	(segment
		(start 119.063262 -227.184458)
		(end 119.04345 -227.170234)
		(width 0.1143)
		(layer "In11.Cu")
		(net "GMI_CPU1_G3_CPU0_G1_TX_DN<7>")
	)
	(segment
		(start 146.953732 -193.557906)
		(end 160.153858 -182.734458)
		(width 0.14224)
		(layer "In11.Cu")
		(net "GMI_CPU1_G3_CPU0_G1_TX_DN<7>")
	)
	(segment
		(start 352.523298 -223.888808)
		(end 352.452432 -223.929956)
		(width 0.1143)
		(layer "In11.Cu")
		(net "GMI_CPU1_G3_CPU0_G1_TX_DN<7>")
	)
	(segment
		(start 352.296476 -230.585772)
		(end 352.296476 -230.714296)
		(width 0.1143)
		(layer "In11.Cu")
		(net "GMI_CPU1_G3_CPU0_G1_TX_DN<7>")
	)
	(segment
		(start 352.851212 -218.951048)
		(end 352.851212 -221.071694)
		(width 0.14224)
		(layer "In11.Cu")
		(net "GMI_CPU1_G3_CPU0_G1_TX_DN<7>")
	)
	(segment
		(start 352.452432 -227.778564)
		(end 352.484182 -227.796852)
		(width 0.1143)
		(layer "In11.Cu")
		(net "GMI_CPU1_G3_CPU0_G1_TX_DN<7>")
	)
	(segment
		(start 119.0117 -228.771958)
		(end 118.972584 -228.749098)
		(width 0.1143)
		(layer "In11.Cu")
		(net "GMI_CPU1_G3_CPU0_G1_TX_DN<7>")
	)
	(segment
		(start 119.04345 -230.410258)
		(end 119.012462 -230.392478)
		(width 0.1143)
		(layer "In11.Cu")
		(net "GMI_CPU1_G3_CPU0_G1_TX_DN<7>")
	)
	(segment
		(start 352.522536 -222.269304)
		(end 352.462846 -222.304102)
		(width 0.1143)
		(layer "In11.Cu")
		(net "GMI_CPU1_G3_CPU0_G1_TX_DN<7>")
	)
	(segment
		(start 352.452432 -223.929956)
		(end 352.43262 -223.94418)
		(width 0.1143)
		(layer "In11.Cu")
		(net "GMI_CPU1_G3_CPU0_G1_TX_DN<7>")
	)
	(segment
		(start 352.481642 -222.935546)
		(end 352.485198 -222.937324)
		(width 0.1143)
		(layer "In11.Cu")
		(net "GMI_CPU1_G3_CPU0_G1_TX_DN<7>")
	)
	(segment
		(start 352.453448 -229.399084)
		(end 352.523298 -229.43947)
		(width 0.1143)
		(layer "In11.Cu")
		(net "GMI_CPU1_G3_CPU0_G1_TX_DN<7>")
	)
	(segment
		(start 352.050604 -231.18064)
		(end 351.980754 -231.22128)
		(width 0.1143)
		(layer "In11.Cu")
		(net "GMI_CPU1_G3_CPU0_G1_TX_DN<7>")
	)
	(segment
		(start 352.48469 -230.390954)
		(end 352.483928 -230.391462)
		(width 0.1143)
		(layer "In11.Cu")
		(net "GMI_CPU1_G3_CPU0_G1_TX_DN<7>")
	)
	(segment
		(start 119.01424 -222.9358)
		(end 119.033036 -222.924624)
		(width 0.1143)
		(layer "In11.Cu")
		(net "GMI_CPU1_G3_CPU0_G1_TX_DN<7>")
	)
	(segment
		(start 118.64467 -219.05468)
		(end 121.658888 -213.903814)
		(width 0.14224)
		(layer "In11.Cu")
		(net "GMI_CPU1_G3_CPU0_G1_TX_DN<7>")
	)
	(segment
		(start 118.69039 -221.129098)
		(end 118.64467 -221.083378)
		(width 0.1143)
		(layer "In11.Cu")
		(net "GMI_CPU1_G3_CPU0_G1_TX_DN<7>")
	)
	(segment
		(start 352.485198 -222.937324)
		(end 352.523298 -222.959676)
		(width 0.1143)
		(layer "In11.Cu")
		(net "GMI_CPU1_G3_CPU0_G1_TX_DN<7>")
	)
	(segment
		(start 119.033036 -222.304356)
		(end 118.973346 -222.269558)
		(width 0.1143)
		(layer "In11.Cu")
		(net "GMI_CPU1_G3_CPU0_G1_TX_DN<7>")
	)
	(segment
		(start 119.012462 -230.392478)
		(end 119.0117 -230.39197)
		(width 0.1143)
		(layer "In11.Cu")
		(net "GMI_CPU1_G3_CPU0_G1_TX_DN<7>")
	)
	(segment
		(start 119.147844 -230.485442)
		(end 119.04345 -230.410258)
		(width 0.1143)
		(layer "In11.Cu")
		(net "GMI_CPU1_G3_CPU0_G1_TX_DN<7>")
	)
	(segment
		(start 119.04345 -227.778818)
		(end 119.063262 -227.764594)
		(width 0.1143)
		(layer "In11.Cu")
		(net "GMI_CPU1_G3_CPU0_G1_TX_DN<7>")
	)
	(segment
		(start 119.04345 -225.550222)
		(end 118.972584 -225.509074)
		(width 0.1143)
		(layer "In11.Cu")
		(net "GMI_CPU1_G3_CPU0_G1_TX_DN<7>")
	)
	(segment
		(start 308.876446 -181.953154)
		(end 315.40704 -185.64987)
		(width 0.14224)
		(layer "In11.Cu")
		(net "GMI_CPU1_G3_CPU0_G1_TX_DN<7>")
	)
	(segment
		(start 352.805492 -221.128844)
		(end 352.805492 -221.426024)
		(width 0.1143)
		(layer "In11.Cu")
		(net "GMI_CPU1_G3_CPU0_G1_TX_DN<7>")
	)
	(segment
		(start 144.985994 -195.171314)
		(end 146.953986 -193.557906)
		(width 0.14224)
		(layer "In11.Cu")
		(net "GMI_CPU1_G3_CPU0_G1_TX_DN<7>")
	)
	(segment
		(start 315.40704 -185.64987)
		(end 349.845376 -213.888066)
		(width 0.14224)
		(layer "In11.Cu")
		(net "GMI_CPU1_G3_CPU0_G1_TX_DN<7>")
	)
	(segment
		(start 119.04345 -223.93021)
		(end 118.972584 -223.889062)
		(width 0.1143)
		(layer "In11.Cu")
		(net "GMI_CPU1_G3_CPU0_G1_TX_DN<7>")
	)
	(segment
		(start 119.0117 -224.557082)
		(end 119.04345 -224.538794)
		(width 0.1143)
		(layer "In11.Cu")
		(net "GMI_CPU1_G3_CPU0_G1_TX_DN<7>")
	)
	(segment
		(start 119.033036 -222.924624)
		(end 119.03329 -222.924624)
		(width 0.1143)
		(layer "In11.Cu")
		(net "GMI_CPU1_G3_CPU0_G1_TX_DN<7>")
	)
	(segment
		(start 146.953986 -193.557906)
		(end 146.953732 -193.557906)
		(width 0.14224)
		(layer "In11.Cu")
		(net "GMI_CPU1_G3_CPU0_G1_TX_DN<7>")
	)
	(segment
		(start 352.484182 -227.796852)
		(end 352.523298 -227.819712)
		(width 0.1143)
		(layer "In11.Cu")
		(net "GMI_CPU1_G3_CPU0_G1_TX_DN<7>")
	)
	(segment
		(start 118.64467 -221.083378)
		(end 118.64467 -221.071948)
		(width 0.1143)
		(layer "In11.Cu")
		(net "GMI_CPU1_G3_CPU0_G1_TX_DN<7>")
	)
	(segment
		(start 352.452432 -230.410004)
		(end 352.348038 -230.485188)
		(width 0.1143)
		(layer "In11.Cu")
		(net "GMI_CPU1_G3_CPU0_G1_TX_DN<7>")
	)
	(segment
		(start 119.0117 -227.797106)
		(end 119.04345 -227.778818)
		(width 0.1143)
		(layer "In11.Cu")
		(net "GMI_CPU1_G3_CPU0_G1_TX_DN<7>")
	)
	(segment
		(start 352.462592 -222.92437)
		(end 352.462846 -222.92437)
		(width 0.1143)
		(layer "In11.Cu")
		(net "GMI_CPU1_G3_CPU0_G1_TX_DN<7>")
	)
	(segment
		(start 352.484182 -226.17684)
		(end 352.523298 -226.1997)
		(width 0.1143)
		(layer "In11.Cu")
		(net "GMI_CPU1_G3_CPU0_G1_TX_DN<7>")
	)
	(segment
		(start 119.0117 -226.177094)
		(end 119.04345 -226.158806)
		(width 0.1143)
		(layer "In11.Cu")
		(net "GMI_CPU1_G3_CPU0_G1_TX_DN<7>")
	)
	(segment
		(start 352.43262 -226.144328)
		(end 352.452432 -226.158552)
		(width 0.1143)
		(layer "In11.Cu")
		(net "GMI_CPU1_G3_CPU0_G1_TX_DN<7>")
	)
	(segment
		(start 118.729506 -221.804484)
		(end 118.729506 -221.465394)
		(width 0.1143)
		(layer "In11.Cu")
		(net "GMI_CPU1_G3_CPU0_G1_TX_DN<7>")
	)
	(segment
		(start 121.658888 -213.903814)
		(end 144.222216 -195.402962)
		(width 0.14224)
		(layer "In11.Cu")
		(net "GMI_CPU1_G3_CPU0_G1_TX_DN<7>")
	)
	(segment
		(start 119.294656 -231.524302)
		(end 119.592598 -231.524302)
		(width 0.1143)
		(layer "In11.Cu")
		(net "GMI_CPU1_G3_CPU0_G1_TX_DN<7>")
	)
	(segment
		(start 352.851212 -221.083124)
		(end 352.805492 -221.128844)
		(width 0.1143)
		(layer "In11.Cu")
		(net "GMI_CPU1_G3_CPU0_G1_TX_DN<7>")
	)
	(segment
		(start 352.452432 -226.158552)
		(end 352.484182 -226.17684)
		(width 0.1143)
		(layer "In11.Cu")
		(net "GMI_CPU1_G3_CPU0_G1_TX_DN<7>")
	)
	(segment
		(start 119.010684 -222.937578)
		(end 119.01424 -222.9358)
		(width 0.1143)
		(layer "In11.Cu")
		(net "GMI_CPU1_G3_CPU0_G1_TX_DN<7>")
	)
	(segment
		(start 119.011954 -230.391716)
		(end 119.011192 -230.391208)
		(width 0.1143)
		(layer "In11.Cu")
		(net "GMI_CPU1_G3_CPU0_G1_TX_DN<7>")
	)
	(segment
		(start 352.46437 -222.925386)
		(end 352.481642 -222.935546)
		(width 0.1143)
		(layer "In11.Cu")
		(net "GMI_CPU1_G3_CPU0_G1_TX_DN<7>")
	)
	(segment
		(start 118.64467 -221.071948)
		(end 118.64467 -219.05468)
		(width 0.14224)
		(layer "In11.Cu")
		(net "GMI_CPU1_G3_CPU0_G1_TX_DN<7>")
	)
	(segment
		(start 144.222216 -195.402962)
		(end 144.985994 -195.171314)
		(width 0.14224)
		(layer "In11.Cu")
		(net "GMI_CPU1_G3_CPU0_G1_TX_DN<7>")
	)
	(segment
		(start 352.805492 -221.426024)
		(end 352.766376 -221.46514)
		(width 0.1143)
		(layer "In11.Cu")
		(net "GMI_CPU1_G3_CPU0_G1_TX_DN<7>")
	)
	(arc
		(start 118.729506 -229.90429)
		(mid 118.793899 -229.642112)
		(end 118.972584 -229.439724)
		(width 0.1143)
		(layer "In11.Cu")
		(net "GMI_CPU1_G3_CPU0_G1_TX_DN<7>")
	)
	(arc
		(start 119.045228 -229.397306)
		(mid 119.158635 -229.264417)
		(end 119.199406 -229.094538)
		(width 0.1143)
		(layer "In11.Cu")
		(net "GMI_CPU1_G3_CPU0_G1_TX_DN<7>")
	)
	(arc
		(start 352.43262 -223.94418)
		(mid 352.283906 -224.234248)
		(end 352.43262 -224.524316)
		(width 0.1143)
		(layer "In11.Cu")
		(net "GMI_CPU1_G3_CPU0_G1_TX_DN<7>")
	)
	(arc
		(start 118.972584 -225.509074)
		(mid 118.729257 -225.044508)
		(end 118.972584 -224.579942)
		(width 0.1143)
		(layer "In11.Cu")
		(net "GMI_CPU1_G3_CPU0_G1_TX_DN<7>")
	)
	(arc
		(start 118.972584 -223.889062)
		(mid 118.729257 -223.424496)
		(end 118.972584 -222.95993)
		(width 0.1143)
		(layer "In11.Cu")
		(net "GMI_CPU1_G3_CPU0_G1_TX_DN<7>")
	)
	(arc
		(start 119.063262 -227.764594)
		(mid 119.211976 -227.474526)
		(end 119.063262 -227.184458)
		(width 0.1143)
		(layer "In11.Cu")
		(net "GMI_CPU1_G3_CPU0_G1_TX_DN<7>")
	)
	(arc
		(start 352.523298 -229.43947)
		(mid 352.702018 -229.641839)
		(end 352.766376 -229.904036)
		(width 0.1143)
		(layer "In11.Cu")
		(net "GMI_CPU1_G3_CPU0_G1_TX_DN<7>")
	)
	(arc
		(start 118.972584 -228.749098)
		(mid 118.729257 -228.284532)
		(end 118.972584 -227.819966)
		(width 0.1143)
		(layer "In11.Cu")
		(net "GMI_CPU1_G3_CPU0_G1_TX_DN<7>")
	)
	(arc
		(start 352.296476 -229.094284)
		(mid 352.337238 -229.264168)
		(end 352.450654 -229.397052)
		(width 0.1143)
		(layer "In11.Cu")
		(net "GMI_CPU1_G3_CPU0_G1_TX_DN<7>")
	)
	(arc
		(start 352.462338 -222.304102)
		(mid 352.283922 -222.614346)
		(end 352.462592 -222.92437)
		(width 0.1143)
		(layer "In11.Cu")
		(net "GMI_CPU1_G3_CPU0_G1_TX_DN<7>")
	)
	(arc
		(start 118.972584 -227.129086)
		(mid 118.729257 -226.66452)
		(end 118.972584 -226.199954)
		(width 0.1143)
		(layer "In11.Cu")
		(net "GMI_CPU1_G3_CPU0_G1_TX_DN<7>")
	)
	(arc
		(start 352.348038 -230.485188)
		(mid 352.310137 -230.529263)
		(end 352.296476 -230.585772)
		(width 0.1143)
		(layer "In11.Cu")
		(net "GMI_CPU1_G3_CPU0_G1_TX_DN<7>")
	)
	(arc
		(start 119.063262 -226.144582)
		(mid 119.211976 -225.854514)
		(end 119.063262 -225.564446)
		(width 0.1143)
		(layer "In11.Cu")
		(net "GMI_CPU1_G3_CPU0_G1_TX_DN<7>")
	)
	(arc
		(start 119.445278 -231.180894)
		(mid 119.264626 -230.978149)
		(end 119.199406 -230.71455)
		(width 0.1143)
		(layer "In11.Cu")
		(net "GMI_CPU1_G3_CPU0_G1_TX_DN<7>")
	)
	(arc
		(start 352.43262 -227.184204)
		(mid 352.283906 -227.474272)
		(end 352.43262 -227.76434)
		(width 0.1143)
		(layer "In11.Cu")
		(net "GMI_CPU1_G3_CPU0_G1_TX_DN<7>")
	)
	(arc
		(start 351.980754 -231.22128)
		(mid 351.884866 -231.323688)
		(end 351.833434 -231.454198)
		(width 0.1143)
		(layer "In11.Cu")
		(net "GMI_CPU1_G3_CPU0_G1_TX_DN<7>")
	)
	(arc
		(start 352.523298 -227.819712)
		(mid 352.766625 -228.284278)
		(end 352.523298 -228.748844)
		(width 0.1143)
		(layer "In11.Cu")
		(net "GMI_CPU1_G3_CPU0_G1_TX_DN<7>")
	)
	(arc
		(start 352.523298 -222.959676)
		(mid 352.766625 -223.424242)
		(end 352.523298 -223.888808)
		(width 0.1143)
		(layer "In11.Cu")
		(net "GMI_CPU1_G3_CPU0_G1_TX_DN<7>")
	)
	(arc
		(start 352.43262 -225.564192)
		(mid 352.283906 -225.85426)
		(end 352.43262 -226.144328)
		(width 0.1143)
		(layer "In11.Cu")
		(net "GMI_CPU1_G3_CPU0_G1_TX_DN<7>")
	)
	(arc
		(start 119.199406 -230.586026)
		(mid 119.185769 -230.529505)
		(end 119.147844 -230.485442)
		(width 0.1143)
		(layer "In11.Cu")
		(net "GMI_CPU1_G3_CPU0_G1_TX_DN<7>")
	)
	(arc
		(start 352.523298 -224.579688)
		(mid 352.766625 -225.044254)
		(end 352.523298 -225.50882)
		(width 0.1143)
		(layer "In11.Cu")
		(net "GMI_CPU1_G3_CPU0_G1_TX_DN<7>")
	)
	(arc
		(start 352.766376 -229.904036)
		(mid 352.690874 -230.185288)
		(end 352.48469 -230.390954)
		(width 0.1143)
		(layer "In11.Cu")
		(net "GMI_CPU1_G3_CPU0_G1_TX_DN<7>")
	)
	(arc
		(start 119.662448 -231.454452)
		(mid 119.610958 -231.323979)
		(end 119.515128 -231.221534)
		(width 0.1143)
		(layer "In11.Cu")
		(net "GMI_CPU1_G3_CPU0_G1_TX_DN<7>")
	)
	(arc
		(start 119.011192 -230.391208)
		(mid 118.80497 -230.185564)
		(end 118.729506 -229.90429)
		(width 0.1143)
		(layer "In11.Cu")
		(net "GMI_CPU1_G3_CPU0_G1_TX_DN<7>")
	)
	(arc
		(start 352.523298 -226.1997)
		(mid 352.766625 -226.664266)
		(end 352.523298 -227.128832)
		(width 0.1143)
		(layer "In11.Cu")
		(net "GMI_CPU1_G3_CPU0_G1_TX_DN<7>")
	)
	(arc
		(start 119.063262 -224.52457)
		(mid 119.211976 -224.234502)
		(end 119.063262 -223.944434)
		(width 0.1143)
		(layer "In11.Cu")
		(net "GMI_CPU1_G3_CPU0_G1_TX_DN<7>")
	)
	(arc
		(start 352.766376 -221.80423)
		(mid 352.701717 -222.066787)
		(end 352.522536 -222.269304)
		(width 0.1143)
		(layer "In11.Cu")
		(net "GMI_CPU1_G3_CPU0_G1_TX_DN<7>")
	)
	(arc
		(start 119.199406 -229.094538)
		(mid 119.15578 -228.924792)
		(end 119.04345 -228.790246)
		(width 0.1143)
		(layer "In11.Cu")
		(net "GMI_CPU1_G3_CPU0_G1_TX_DN<7>")
	)
	(arc
		(start 352.452432 -228.789992)
		(mid 352.340059 -228.924516)
		(end 352.296476 -229.094284)
		(width 0.1143)
		(layer "In11.Cu")
		(net "GMI_CPU1_G3_CPU0_G1_TX_DN<7>")
	)
	(arc
		(start 352.296476 -230.714296)
		(mid 352.23124 -230.977887)
		(end 352.050604 -231.18064)
		(width 0.1143)
		(layer "In11.Cu")
		(net "GMI_CPU1_G3_CPU0_G1_TX_DN<7>")
	)
	(arc
		(start 118.973346 -222.269558)
		(mid 118.794153 -222.067048)
		(end 118.729506 -221.804484)
		(width 0.1143)
		(layer "In11.Cu")
		(net "GMI_CPU1_G3_CPU0_G1_TX_DN<7>")
	)
	(arc
		(start 119.03329 -222.924624)
		(mid 119.211832 -222.6146)
		(end 119.033544 -222.304356)
		(width 0.1143)
		(layer "In11.Cu")
		(net "GMI_CPU1_G3_CPU0_G1_TX_DN<7>")
	)
	(segment
		(start 118.827804 -235.030264)
		(end 119.294656 -234.764326)
		(width 0.12954)
		(layer "F.Cu")
		(net "GMI_CPU1_G3_CPU0_G1_TX_DN<6>")
	)
	(segment
		(start 352.668078 -235.03001)
		(end 352.201226 -234.764072)
		(width 0.12954)
		(layer "F.Cu")
		(net "GMI_CPU1_G3_CPU0_G1_TX_DN<6>")
	)
	(segment
		(start 353.463098 -229.43947)
		(end 353.423982 -229.41661)
		(width 0.1143)
		(layer "In11.Cu")
		(net "GMI_CPU1_G3_CPU0_G1_TX_DN<6>")
	)
	(segment
		(start 118.0719 -226.177094)
		(end 118.032784 -226.199954)
		(width 0.1143)
		(layer "In11.Cu")
		(net "GMI_CPU1_G3_CPU0_G1_TX_DN<6>")
	)
	(segment
		(start 118.035324 -230.370634)
		(end 118.10238 -230.40975)
		(width 0.1143)
		(layer "In11.Cu")
		(net "GMI_CPU1_G3_CPU0_G1_TX_DN<6>")
	)
	(segment
		(start 302.902112 -180.429408)
		(end 166.045388 -179.631086)
		(width 0.14224)
		(layer "In11.Cu")
		(net "GMI_CPU1_G3_CPU0_G1_TX_DN<6>")
	)
	(segment
		(start 118.0719 -222.93707)
		(end 118.032784 -222.95993)
		(width 0.1143)
		(layer "In11.Cu")
		(net "GMI_CPU1_G3_CPU0_G1_TX_DN<6>")
	)
	(segment
		(start 119.012462 -233.632248)
		(end 119.04345 -233.650028)
		(width 0.1143)
		(layer "In11.Cu")
		(net "GMI_CPU1_G3_CPU0_G1_TX_DN<6>")
	)
	(segment
		(start 118.571518 -231.82961)
		(end 118.547134 -231.843834)
		(width 0.1143)
		(layer "In11.Cu")
		(net "GMI_CPU1_G3_CPU0_G1_TX_DN<6>")
	)
	(segment
		(start 120.906794 -213.314026)
		(end 117.69979 -218.787726)
		(width 0.14224)
		(layer "In11.Cu")
		(net "GMI_CPU1_G3_CPU0_G1_TX_DN<6>")
	)
	(segment
		(start 118.0719 -229.416864)
		(end 118.032784 -229.439724)
		(width 0.1143)
		(layer "In11.Cu")
		(net "GMI_CPU1_G3_CPU0_G1_TX_DN<6>")
	)
	(segment
		(start 351.903284 -234.764072)
		(end 351.833434 -234.694222)
		(width 0.1143)
		(layer "In11.Cu")
		(net "GMI_CPU1_G3_CPU0_G1_TX_DN<6>")
	)
	(segment
		(start 118.10238 -227.779326)
		(end 118.0719 -227.797106)
		(width 0.1143)
		(layer "In11.Cu")
		(net "GMI_CPU1_G3_CPU0_G1_TX_DN<6>")
	)
	(segment
		(start 352.452432 -233.649774)
		(end 352.48215 -233.632756)
		(width 0.1143)
		(layer "In11.Cu")
		(net "GMI_CPU1_G3_CPU0_G1_TX_DN<6>")
	)
	(segment
		(start 117.69979 -221.071948)
		(end 117.69979 -221.083378)
		(width 0.1143)
		(layer "In11.Cu")
		(net "GMI_CPU1_G3_CPU0_G1_TX_DN<6>")
	)
	(segment
		(start 119.442738 -234.418886)
		(end 119.481854 -234.441746)
		(width 0.1143)
		(layer "In11.Cu")
		(net "GMI_CPU1_G3_CPU0_G1_TX_DN<6>")
	)
	(segment
		(start 353.796092 -221.083124)
		(end 353.796092 -221.071694)
		(width 0.1143)
		(layer "In11.Cu")
		(net "GMI_CPU1_G3_CPU0_G1_TX_DN<6>")
	)
	(segment
		(start 118.50243 -232.79862)
		(end 118.555008 -232.828846)
		(width 0.1143)
		(layer "In11.Cu")
		(net "GMI_CPU1_G3_CPU0_G1_TX_DN<6>")
	)
	(segment
		(start 118.0719 -223.911922)
		(end 118.10238 -223.929702)
		(width 0.1143)
		(layer "In11.Cu")
		(net "GMI_CPU1_G3_CPU0_G1_TX_DN<6>")
	)
	(segment
		(start 352.48215 -233.632756)
		(end 352.48342 -233.631994)
		(width 0.1143)
		(layer "In11.Cu")
		(net "GMI_CPU1_G3_CPU0_G1_TX_DN<6>")
	)
	(segment
		(start 118.0719 -224.557082)
		(end 118.032784 -224.579942)
		(width 0.1143)
		(layer "In11.Cu")
		(net "GMI_CPU1_G3_CPU0_G1_TX_DN<6>")
	)
	(segment
		(start 353.706176 -221.80423)
		(end 353.706176 -221.47022)
		(width 0.1143)
		(layer "In11.Cu")
		(net "GMI_CPU1_G3_CPU0_G1_TX_DN<6>")
	)
	(segment
		(start 353.706176 -221.47022)
		(end 353.750372 -221.426024)
		(width 0.1143)
		(layer "In11.Cu")
		(net "GMI_CPU1_G3_CPU0_G1_TX_DN<6>")
	)
	(segment
		(start 353.796092 -218.71559)
		(end 350.549972 -213.247986)
		(width 0.14224)
		(layer "In11.Cu")
		(net "GMI_CPU1_G3_CPU0_G1_TX_DN<6>")
	)
	(segment
		(start 352.949002 -231.84358)
		(end 352.948748 -231.84358)
		(width 0.1143)
		(layer "In11.Cu")
		(net "GMI_CPU1_G3_CPU0_G1_TX_DN<6>")
	)
	(segment
		(start 117.74551 -221.426278)
		(end 117.789706 -221.470474)
		(width 0.1143)
		(layer "In11.Cu")
		(net "GMI_CPU1_G3_CPU0_G1_TX_DN<6>")
	)
	(segment
		(start 307.437028 -180.429408)
		(end 302.902112 -180.429408)
		(width 0.14224)
		(layer "In11.Cu")
		(net "GMI_CPU1_G3_CPU0_G1_TX_DN<6>")
	)
	(segment
		(start 117.69979 -221.083378)
		(end 117.74551 -221.129098)
		(width 0.1143)
		(layer "In11.Cu")
		(net "GMI_CPU1_G3_CPU0_G1_TX_DN<6>")
	)
	(segment
		(start 352.486976 -233.629708)
		(end 352.492564 -233.626406)
		(width 0.1143)
		(layer "In11.Cu")
		(net "GMI_CPU1_G3_CPU0_G1_TX_DN<6>")
	)
	(segment
		(start 118.741444 -233.15295)
		(end 118.741444 -233.17835)
		(width 0.1143)
		(layer "In11.Cu")
		(net "GMI_CPU1_G3_CPU0_G1_TX_DN<6>")
	)
	(segment
		(start 118.10238 -224.539302)
		(end 118.0719 -224.557082)
		(width 0.1143)
		(layer "In11.Cu")
		(net "GMI_CPU1_G3_CPU0_G1_TX_DN<6>")
	)
	(segment
		(start 353.393502 -228.789484)
		(end 353.463098 -228.748844)
		(width 0.1143)
		(layer "In11.Cu")
		(net "GMI_CPU1_G3_CPU0_G1_TX_DN<6>")
	)
	(segment
		(start 352.48342 -233.631994)
		(end 352.484182 -233.631486)
		(width 0.1143)
		(layer "In11.Cu")
		(net "GMI_CPU1_G3_CPU0_G1_TX_DN<6>")
	)
	(segment
		(start 117.74551 -221.129098)
		(end 117.74551 -221.426278)
		(width 0.1143)
		(layer "In11.Cu")
		(net "GMI_CPU1_G3_CPU0_G1_TX_DN<6>")
	)
	(segment
		(start 118.104412 -229.398068)
		(end 118.0719 -229.416864)
		(width 0.1143)
		(layer "In11.Cu")
		(net "GMI_CPU1_G3_CPU0_G1_TX_DN<6>")
	)
	(segment
		(start 350.549972 -213.247986)
		(end 315.691266 -184.665366)
		(width 0.14224)
		(layer "In11.Cu")
		(net "GMI_CPU1_G3_CPU0_G1_TX_DN<6>")
	)
	(segment
		(start 118.032784 -228.749098)
		(end 118.0719 -228.771958)
		(width 0.1143)
		(layer "In11.Cu")
		(net "GMI_CPU1_G3_CPU0_G1_TX_DN<6>")
	)
	(segment
		(start 352.948748 -231.84358)
		(end 352.924364 -231.829356)
		(width 0.1143)
		(layer "In11.Cu")
		(net "GMI_CPU1_G3_CPU0_G1_TX_DN<6>")
	)
	(segment
		(start 118.0719 -227.151946)
		(end 118.10238 -227.169726)
		(width 0.1143)
		(layer "In11.Cu")
		(net "GMI_CPU1_G3_CPU0_G1_TX_DN<6>")
	)
	(segment
		(start 352.920554 -231.22128)
		(end 352.993198 -231.178862)
		(width 0.1143)
		(layer "In11.Cu")
		(net "GMI_CPU1_G3_CPU0_G1_TX_DN<6>")
	)
	(segment
		(start 353.393502 -222.309436)
		(end 353.463098 -222.268796)
		(width 0.1143)
		(layer "In11.Cu")
		(net "GMI_CPU1_G3_CPU0_G1_TX_DN<6>")
	)
	(segment
		(start 118.0719 -225.531934)
		(end 118.10238 -225.549714)
		(width 0.1143)
		(layer "In11.Cu")
		(net "GMI_CPU1_G3_CPU0_G1_TX_DN<6>")
	)
	(segment
		(start 353.463098 -224.579688)
		(end 353.393502 -224.539048)
		(width 0.1143)
		(layer "In11.Cu")
		(net "GMI_CPU1_G3_CPU0_G1_TX_DN<6>")
	)
	(segment
		(start 352.201226 -234.764072)
		(end 351.903284 -234.764072)
		(width 0.1143)
		(layer "In11.Cu")
		(net "GMI_CPU1_G3_CPU0_G1_TX_DN<6>")
	)
	(segment
		(start 315.691266 -184.665366)
		(end 309.529226 -181.177184)
		(width 0.14224)
		(layer "In11.Cu")
		(net "GMI_CPU1_G3_CPU0_G1_TX_DN<6>")
	)
	(segment
		(start 351.983548 -234.459272)
		(end 352.053144 -234.418632)
		(width 0.1143)
		(layer "In11.Cu")
		(net "GMI_CPU1_G3_CPU0_G1_TX_DN<6>")
	)
	(segment
		(start 352.76663 -231.524048)
		(end 352.766376 -231.524048)
		(width 0.1143)
		(layer "In11.Cu")
		(net "GMI_CPU1_G3_CPU0_G1_TX_DN<6>")
	)
	(segment
		(start 117.789706 -221.470474)
		(end 117.789706 -221.804484)
		(width 0.1143)
		(layer "In11.Cu")
		(net "GMI_CPU1_G3_CPU0_G1_TX_DN<6>")
	)
	(segment
		(start 353.393502 -230.409496)
		(end 353.460558 -230.37038)
		(width 0.1143)
		(layer "In11.Cu")
		(net "GMI_CPU1_G3_CPU0_G1_TX_DN<6>")
	)
	(segment
		(start 118.10238 -222.91929)
		(end 118.0719 -222.93707)
		(width 0.1143)
		(layer "In11.Cu")
		(net "GMI_CPU1_G3_CPU0_G1_TX_DN<6>")
	)
	(segment
		(start 118.0719 -227.797106)
		(end 118.032784 -227.819966)
		(width 0.1143)
		(layer "In11.Cu")
		(net "GMI_CPU1_G3_CPU0_G1_TX_DN<6>")
	)
	(segment
		(start 118.0719 -228.771958)
		(end 118.10238 -228.789738)
		(width 0.1143)
		(layer "In11.Cu")
		(net "GMI_CPU1_G3_CPU0_G1_TX_DN<6>")
	)
	(segment
		(start 118.547134 -231.843834)
		(end 118.54688 -231.843834)
		(width 0.1143)
		(layer "In11.Cu")
		(net "GMI_CPU1_G3_CPU0_G1_TX_DN<6>")
	)
	(segment
		(start 119.008906 -233.629962)
		(end 119.0117 -233.63174)
		(width 0.1143)
		(layer "In11.Cu")
		(net "GMI_CPU1_G3_CPU0_G1_TX_DN<6>")
	)
	(segment
		(start 119.481854 -234.441746)
		(end 119.512334 -234.459526)
		(width 0.1143)
		(layer "In11.Cu")
		(net "GMI_CPU1_G3_CPU0_G1_TX_DN<6>")
	)
	(segment
		(start 352.484182 -233.631486)
		(end 352.486976 -233.629708)
		(width 0.1143)
		(layer "In11.Cu")
		(net "GMI_CPU1_G3_CPU0_G1_TX_DN<6>")
	)
	(segment
		(start 353.463098 -227.819712)
		(end 353.393502 -227.779072)
		(width 0.1143)
		(layer "In11.Cu")
		(net "GMI_CPU1_G3_CPU0_G1_TX_DN<6>")
	)
	(segment
		(start 352.940874 -232.828592)
		(end 352.993452 -232.798366)
		(width 0.1143)
		(layer "In11.Cu")
		(net "GMI_CPU1_G3_CPU0_G1_TX_DN<6>")
	)
	(segment
		(start 118.032784 -225.509074)
		(end 118.0719 -225.531934)
		(width 0.1143)
		(layer "In11.Cu")
		(net "GMI_CPU1_G3_CPU0_G1_TX_DN<6>")
	)
	(segment
		(start 144.272762 -194.366388)
		(end 143.8656 -194.489578)
		(width 0.14224)
		(layer "In11.Cu")
		(net "GMI_CPU1_G3_CPU0_G1_TX_DN<6>")
	)
	(segment
		(start 118.502684 -231.179116)
		(end 118.5418 -231.201976)
		(width 0.1143)
		(layer "In11.Cu")
		(net "GMI_CPU1_G3_CPU0_G1_TX_DN<6>")
	)
	(segment
		(start 353.393502 -227.169472)
		(end 353.463098 -227.128832)
		(width 0.1143)
		(layer "In11.Cu")
		(net "GMI_CPU1_G3_CPU0_G1_TX_DN<6>")
	)
	(segment
		(start 118.032784 -222.26905)
		(end 118.10238 -222.30969)
		(width 0.1143)
		(layer "In11.Cu")
		(net "GMI_CPU1_G3_CPU0_G1_TX_DN<6>")
	)
	(segment
		(start 117.69979 -218.787726)
		(end 117.69979 -221.071948)
		(width 0.14224)
		(layer "In11.Cu")
		(net "GMI_CPU1_G3_CPU0_G1_TX_DN<6>")
	)
	(segment
		(start 353.796092 -221.071694)
		(end 353.796092 -218.71559)
		(width 0.14224)
		(layer "In11.Cu")
		(net "GMI_CPU1_G3_CPU0_G1_TX_DN<6>")
	)
	(segment
		(start 118.729506 -231.524302)
		(end 118.729252 -231.524302)
		(width 0.1143)
		(layer "In11.Cu")
		(net "GMI_CPU1_G3_CPU0_G1_TX_DN<6>")
	)
	(segment
		(start 353.750372 -221.426024)
		(end 353.750372 -221.128844)
		(width 0.1143)
		(layer "In11.Cu")
		(net "GMI_CPU1_G3_CPU0_G1_TX_DN<6>")
	)
	(segment
		(start 119.592598 -234.764326)
		(end 119.294656 -234.764326)
		(width 0.1143)
		(layer "In11.Cu")
		(net "GMI_CPU1_G3_CPU0_G1_TX_DN<6>")
	)
	(segment
		(start 143.8656 -194.489578)
		(end 120.906794 -213.314026)
		(width 0.14224)
		(layer "In11.Cu")
		(net "GMI_CPU1_G3_CPU0_G1_TX_DN<6>")
	)
	(segment
		(start 352.754438 -233.178096)
		(end 352.754438 -233.152696)
		(width 0.1143)
		(layer "In11.Cu")
		(net "GMI_CPU1_G3_CPU0_G1_TX_DN<6>")
	)
	(segment
		(start 118.032784 -227.129086)
		(end 118.0719 -227.151946)
		(width 0.1143)
		(layer "In11.Cu")
		(net "GMI_CPU1_G3_CPU0_G1_TX_DN<6>")
	)
	(segment
		(start 119.662448 -234.694476)
		(end 119.592598 -234.764326)
		(width 0.1143)
		(layer "In11.Cu")
		(net "GMI_CPU1_G3_CPU0_G1_TX_DN<6>")
	)
	(segment
		(start 154.81554 -185.721244)
		(end 154.815286 -185.72099)
		(width 0.14224)
		(layer "In11.Cu")
		(net "GMI_CPU1_G3_CPU0_G1_TX_DN<6>")
	)
	(segment
		(start 118.10238 -226.159314)
		(end 118.0719 -226.177094)
		(width 0.1143)
		(layer "In11.Cu")
		(net "GMI_CPU1_G3_CPU0_G1_TX_DN<6>")
	)
	(segment
		(start 353.423982 -229.41661)
		(end 353.39147 -229.397814)
		(width 0.1143)
		(layer "In11.Cu")
		(net "GMI_CPU1_G3_CPU0_G1_TX_DN<6>")
	)
	(segment
		(start 118.5418 -231.201976)
		(end 118.575328 -231.221534)
		(width 0.1143)
		(layer "In11.Cu")
		(net "GMI_CPU1_G3_CPU0_G1_TX_DN<6>")
	)
	(segment
		(start 353.463098 -226.1997)
		(end 353.393502 -226.15906)
		(width 0.1143)
		(layer "In11.Cu")
		(net "GMI_CPU1_G3_CPU0_G1_TX_DN<6>")
	)
	(segment
		(start 353.463098 -222.959676)
		(end 353.393502 -222.919036)
		(width 0.1143)
		(layer "In11.Cu")
		(net "GMI_CPU1_G3_CPU0_G1_TX_DN<6>")
	)
	(segment
		(start 166.045388 -179.631086)
		(end 159.300672 -182.04307)
		(width 0.14224)
		(layer "In11.Cu")
		(net "GMI_CPU1_G3_CPU0_G1_TX_DN<6>")
	)
	(segment
		(start 119.003318 -233.62666)
		(end 119.008906 -233.629962)
		(width 0.1143)
		(layer "In11.Cu")
		(net "GMI_CPU1_G3_CPU0_G1_TX_DN<6>")
	)
	(segment
		(start 353.393502 -223.929448)
		(end 353.463098 -223.888808)
		(width 0.1143)
		(layer "In11.Cu")
		(net "GMI_CPU1_G3_CPU0_G1_TX_DN<6>")
	)
	(segment
		(start 119.0117 -233.63174)
		(end 119.012462 -233.632248)
		(width 0.1143)
		(layer "In11.Cu")
		(net "GMI_CPU1_G3_CPU0_G1_TX_DN<6>")
	)
	(segment
		(start 353.393502 -225.54946)
		(end 353.463098 -225.50882)
		(width 0.1143)
		(layer "In11.Cu")
		(net "GMI_CPU1_G3_CPU0_G1_TX_DN<6>")
	)
	(segment
		(start 309.529226 -181.177184)
		(end 307.437028 -180.429408)
		(width 0.14224)
		(layer "In11.Cu")
		(net "GMI_CPU1_G3_CPU0_G1_TX_DN<6>")
	)
	(segment
		(start 118.032784 -223.889062)
		(end 118.0719 -223.911922)
		(width 0.1143)
		(layer "In11.Cu")
		(net "GMI_CPU1_G3_CPU0_G1_TX_DN<6>")
	)
	(segment
		(start 154.815286 -185.72099)
		(end 144.272762 -194.366388)
		(width 0.14224)
		(layer "In11.Cu")
		(net "GMI_CPU1_G3_CPU0_G1_TX_DN<6>")
	)
	(segment
		(start 353.750372 -221.128844)
		(end 353.796092 -221.083124)
		(width 0.1143)
		(layer "In11.Cu")
		(net "GMI_CPU1_G3_CPU0_G1_TX_DN<6>")
	)
	(segment
		(start 159.300672 -182.04307)
		(end 154.81554 -185.721244)
		(width 0.14224)
		(layer "In11.Cu")
		(net "GMI_CPU1_G3_CPU0_G1_TX_DN<6>")
	)
	(arc
		(start 353.23653 -229.094284)
		(mid 353.278079 -228.922862)
		(end 353.393502 -228.789484)
		(width 0.1143)
		(layer "In11.Cu")
		(net "GMI_CPU1_G3_CPU0_G1_TX_DN<6>")
	)
	(arc
		(start 118.10238 -225.549714)
		(mid 118.259357 -225.854514)
		(end 118.10238 -226.159314)
		(width 0.1143)
		(layer "In11.Cu")
		(net "GMI_CPU1_G3_CPU0_G1_TX_DN<6>")
	)
	(arc
		(start 118.032784 -222.95993)
		(mid 117.789457 -223.424496)
		(end 118.032784 -223.889062)
		(width 0.1143)
		(layer "In11.Cu")
		(net "GMI_CPU1_G3_CPU0_G1_TX_DN<6>")
	)
	(arc
		(start 353.393502 -224.539048)
		(mid 353.236525 -224.234248)
		(end 353.393502 -223.929448)
		(width 0.1143)
		(layer "In11.Cu")
		(net "GMI_CPU1_G3_CPU0_G1_TX_DN<6>")
	)
	(arc
		(start 352.053144 -234.418632)
		(mid 352.231957 -234.216282)
		(end 352.296476 -233.954066)
		(width 0.1143)
		(layer "In11.Cu")
		(net "GMI_CPU1_G3_CPU0_G1_TX_DN<6>")
	)
	(arc
		(start 352.993198 -231.178862)
		(mid 353.172011 -230.976512)
		(end 353.23653 -230.714296)
		(width 0.1143)
		(layer "In11.Cu")
		(net "GMI_CPU1_G3_CPU0_G1_TX_DN<6>")
	)
	(arc
		(start 118.555008 -232.828846)
		(mid 118.69152 -232.965996)
		(end 118.741444 -233.15295)
		(width 0.1143)
		(layer "In11.Cu")
		(net "GMI_CPU1_G3_CPU0_G1_TX_DN<6>")
	)
	(arc
		(start 118.729252 -231.524302)
		(mid 118.687512 -231.696155)
		(end 118.571518 -231.82961)
		(width 0.1143)
		(layer "In11.Cu")
		(net "GMI_CPU1_G3_CPU0_G1_TX_DN<6>")
	)
	(arc
		(start 353.460558 -230.37038)
		(mid 353.64121 -230.167635)
		(end 353.70643 -229.904036)
		(width 0.1143)
		(layer "In11.Cu")
		(net "GMI_CPU1_G3_CPU0_G1_TX_DN<6>")
	)
	(arc
		(start 118.10238 -230.40975)
		(mid 118.217807 -230.543126)
		(end 118.259352 -230.71455)
		(width 0.1143)
		(layer "In11.Cu")
		(net "GMI_CPU1_G3_CPU0_G1_TX_DN<6>")
	)
	(arc
		(start 119.04345 -233.650028)
		(mid 119.158126 -233.783362)
		(end 119.199406 -233.95432)
		(width 0.1143)
		(layer "In11.Cu")
		(net "GMI_CPU1_G3_CPU0_G1_TX_DN<6>")
	)
	(arc
		(start 352.754438 -233.152696)
		(mid 352.804374 -232.965749)
		(end 352.940874 -232.828592)
		(width 0.1143)
		(layer "In11.Cu")
		(net "GMI_CPU1_G3_CPU0_G1_TX_DN<6>")
	)
	(arc
		(start 352.492564 -233.626406)
		(mid 352.684198 -233.437701)
		(end 352.754438 -233.178096)
		(width 0.1143)
		(layer "In11.Cu")
		(net "GMI_CPU1_G3_CPU0_G1_TX_DN<6>")
	)
	(arc
		(start 351.833434 -234.694222)
		(mid 351.885851 -234.562291)
		(end 351.983548 -234.459272)
		(width 0.1143)
		(layer "In11.Cu")
		(net "GMI_CPU1_G3_CPU0_G1_TX_DN<6>")
	)
	(arc
		(start 118.032784 -226.199954)
		(mid 117.789457 -226.66452)
		(end 118.032784 -227.129086)
		(width 0.1143)
		(layer "In11.Cu")
		(net "GMI_CPU1_G3_CPU0_G1_TX_DN<6>")
	)
	(arc
		(start 353.463098 -228.748844)
		(mid 353.706425 -228.284278)
		(end 353.463098 -227.819712)
		(width 0.1143)
		(layer "In11.Cu")
		(net "GMI_CPU1_G3_CPU0_G1_TX_DN<6>")
	)
	(arc
		(start 352.993452 -232.798366)
		(mid 353.235991 -232.308631)
		(end 352.949002 -231.84358)
		(width 0.1143)
		(layer "In11.Cu")
		(net "GMI_CPU1_G3_CPU0_G1_TX_DN<6>")
	)
	(arc
		(start 117.789706 -221.804484)
		(mid 117.85408 -222.066688)
		(end 118.032784 -222.26905)
		(width 0.1143)
		(layer "In11.Cu")
		(net "GMI_CPU1_G3_CPU0_G1_TX_DN<6>")
	)
	(arc
		(start 118.575328 -231.221534)
		(mid 118.688735 -231.354423)
		(end 118.729506 -231.524302)
		(width 0.1143)
		(layer "In11.Cu")
		(net "GMI_CPU1_G3_CPU0_G1_TX_DN<6>")
	)
	(arc
		(start 353.70643 -229.904036)
		(mid 353.641915 -229.641817)
		(end 353.463098 -229.43947)
		(width 0.1143)
		(layer "In11.Cu")
		(net "GMI_CPU1_G3_CPU0_G1_TX_DN<6>")
	)
	(arc
		(start 118.032784 -227.819966)
		(mid 117.789457 -228.284532)
		(end 118.032784 -228.749098)
		(width 0.1143)
		(layer "In11.Cu")
		(net "GMI_CPU1_G3_CPU0_G1_TX_DN<6>")
	)
	(arc
		(start 352.924364 -231.829356)
		(mid 352.808485 -231.695842)
		(end 352.76663 -231.524048)
		(width 0.1143)
		(layer "In11.Cu")
		(net "GMI_CPU1_G3_CPU0_G1_TX_DN<6>")
	)
	(arc
		(start 118.54688 -231.843834)
		(mid 118.259948 -232.308888)
		(end 118.50243 -232.79862)
		(width 0.1143)
		(layer "In11.Cu")
		(net "GMI_CPU1_G3_CPU0_G1_TX_DN<6>")
	)
	(arc
		(start 353.463098 -223.888808)
		(mid 353.706425 -223.424242)
		(end 353.463098 -222.959676)
		(width 0.1143)
		(layer "In11.Cu")
		(net "GMI_CPU1_G3_CPU0_G1_TX_DN<6>")
	)
	(arc
		(start 353.463098 -227.128832)
		(mid 353.706425 -226.664266)
		(end 353.463098 -226.1997)
		(width 0.1143)
		(layer "In11.Cu")
		(net "GMI_CPU1_G3_CPU0_G1_TX_DN<6>")
	)
	(arc
		(start 118.032784 -229.439724)
		(mid 117.853971 -229.642074)
		(end 117.789452 -229.90429)
		(width 0.1143)
		(layer "In11.Cu")
		(net "GMI_CPU1_G3_CPU0_G1_TX_DN<6>")
	)
	(arc
		(start 118.10238 -222.30969)
		(mid 118.259357 -222.61449)
		(end 118.10238 -222.91929)
		(width 0.1143)
		(layer "In11.Cu")
		(net "GMI_CPU1_G3_CPU0_G1_TX_DN<6>")
	)
	(arc
		(start 118.10238 -227.169726)
		(mid 118.259357 -227.474526)
		(end 118.10238 -227.779326)
		(width 0.1143)
		(layer "In11.Cu")
		(net "GMI_CPU1_G3_CPU0_G1_TX_DN<6>")
	)
	(arc
		(start 117.789452 -229.90429)
		(mid 117.854688 -230.167881)
		(end 118.035324 -230.370634)
		(width 0.1143)
		(layer "In11.Cu")
		(net "GMI_CPU1_G3_CPU0_G1_TX_DN<6>")
	)
	(arc
		(start 118.741444 -233.17835)
		(mid 118.811715 -233.437937)
		(end 119.003318 -233.62666)
		(width 0.1143)
		(layer "In11.Cu")
		(net "GMI_CPU1_G3_CPU0_G1_TX_DN<6>")
	)
	(arc
		(start 353.393502 -227.779072)
		(mid 353.236525 -227.474272)
		(end 353.393502 -227.169472)
		(width 0.1143)
		(layer "In11.Cu")
		(net "GMI_CPU1_G3_CPU0_G1_TX_DN<6>")
	)
	(arc
		(start 118.259352 -230.71455)
		(mid 118.323867 -230.976769)
		(end 118.502684 -231.179116)
		(width 0.1143)
		(layer "In11.Cu")
		(net "GMI_CPU1_G3_CPU0_G1_TX_DN<6>")
	)
	(arc
		(start 352.766376 -231.524048)
		(mid 352.807138 -231.354164)
		(end 352.920554 -231.22128)
		(width 0.1143)
		(layer "In11.Cu")
		(net "GMI_CPU1_G3_CPU0_G1_TX_DN<6>")
	)
	(arc
		(start 353.23653 -230.714296)
		(mid 353.278079 -230.542874)
		(end 353.393502 -230.409496)
		(width 0.1143)
		(layer "In11.Cu")
		(net "GMI_CPU1_G3_CPU0_G1_TX_DN<6>")
	)
	(arc
		(start 118.10238 -228.789738)
		(mid 118.217807 -228.923114)
		(end 118.259352 -229.094538)
		(width 0.1143)
		(layer "In11.Cu")
		(net "GMI_CPU1_G3_CPU0_G1_TX_DN<6>")
	)
	(arc
		(start 353.393502 -222.919036)
		(mid 353.236525 -222.614236)
		(end 353.393502 -222.309436)
		(width 0.1143)
		(layer "In11.Cu")
		(net "GMI_CPU1_G3_CPU0_G1_TX_DN<6>")
	)
	(arc
		(start 119.199406 -233.95432)
		(mid 119.263921 -234.216539)
		(end 119.442738 -234.418886)
		(width 0.1143)
		(layer "In11.Cu")
		(net "GMI_CPU1_G3_CPU0_G1_TX_DN<6>")
	)
	(arc
		(start 118.032784 -224.579942)
		(mid 117.789457 -225.044508)
		(end 118.032784 -225.509074)
		(width 0.1143)
		(layer "In11.Cu")
		(net "GMI_CPU1_G3_CPU0_G1_TX_DN<6>")
	)
	(arc
		(start 353.393502 -226.15906)
		(mid 353.236525 -225.85426)
		(end 353.393502 -225.54946)
		(width 0.1143)
		(layer "In11.Cu")
		(net "GMI_CPU1_G3_CPU0_G1_TX_DN<6>")
	)
	(arc
		(start 118.259352 -229.094538)
		(mid 118.218386 -229.264944)
		(end 118.104412 -229.398068)
		(width 0.1143)
		(layer "In11.Cu")
		(net "GMI_CPU1_G3_CPU0_G1_TX_DN<6>")
	)
	(arc
		(start 352.296476 -233.954066)
		(mid 352.337731 -233.783095)
		(end 352.452432 -233.649774)
		(width 0.1143)
		(layer "In11.Cu")
		(net "GMI_CPU1_G3_CPU0_G1_TX_DN<6>")
	)
	(arc
		(start 353.463098 -222.268796)
		(mid 353.641741 -222.066401)
		(end 353.706176 -221.80423)
		(width 0.1143)
		(layer "In11.Cu")
		(net "GMI_CPU1_G3_CPU0_G1_TX_DN<6>")
	)
	(arc
		(start 353.463098 -225.50882)
		(mid 353.706425 -225.044254)
		(end 353.463098 -224.579688)
		(width 0.1143)
		(layer "In11.Cu")
		(net "GMI_CPU1_G3_CPU0_G1_TX_DN<6>")
	)
	(arc
		(start 353.39147 -229.397814)
		(mid 353.277541 -229.264667)
		(end 353.23653 -229.094284)
		(width 0.1143)
		(layer "In11.Cu")
		(net "GMI_CPU1_G3_CPU0_G1_TX_DN<6>")
	)
	(arc
		(start 119.512334 -234.459526)
		(mid 119.610099 -234.562502)
		(end 119.662448 -234.694476)
		(width 0.1143)
		(layer "In11.Cu")
		(net "GMI_CPU1_G3_CPU0_G1_TX_DN<6>")
	)
	(arc
		(start 118.10238 -223.929702)
		(mid 118.259357 -224.234502)
		(end 118.10238 -224.539302)
		(width 0.1143)
		(layer "In11.Cu")
		(net "GMI_CPU1_G3_CPU0_G1_TX_DN<6>")
	)
	(segment
		(start 355.487986 -233.409998)
		(end 355.021134 -233.14406)
		(width 0.12954)
		(layer "F.Cu")
		(net "GMI_CPU1_G3_CPU0_G1_TX_DN<5>")
	)
	(segment
		(start 116.007896 -233.410252)
		(end 116.474748 -233.144314)
		(width 0.12954)
		(layer "F.Cu")
		(net "GMI_CPU1_G3_CPU0_G1_TX_DN<5>")
	)
	(segment
		(start 353.860608 -231.22128)
		(end 353.933252 -231.178862)
		(width 0.1143)
		(layer "In11.Cu")
		(net "GMI_CPU1_G3_CPU0_G1_TX_DN<5>")
	)
	(segment
		(start 165.817296 -178.692302)
		(end 158.503112 -181.30774)
		(width 0.14224)
		(layer "In11.Cu")
		(net "GMI_CPU1_G3_CPU0_G1_TX_DN<5>")
	)
	(segment
		(start 116.767356 -221.083378)
		(end 116.813076 -221.129098)
		(width 0.1143)
		(layer "In11.Cu")
		(net "GMI_CPU1_G3_CPU0_G1_TX_DN<5>")
	)
	(segment
		(start 353.893374 -231.84612)
		(end 353.892104 -231.845358)
		(width 0.1143)
		(layer "In11.Cu")
		(net "GMI_CPU1_G3_CPU0_G1_TX_DN<5>")
	)
	(segment
		(start 117.09273 -222.26905)
		(end 117.162326 -222.30969)
		(width 0.1143)
		(layer "In11.Cu")
		(net "GMI_CPU1_G3_CPU0_G1_TX_DN<5>")
	)
	(segment
		(start 354.64623 -221.80423)
		(end 354.64623 -221.4626)
		(width 0.1143)
		(layer "In11.Cu")
		(net "GMI_CPU1_G3_CPU0_G1_TX_DN<5>")
	)
	(segment
		(start 117.131846 -232.656888)
		(end 117.09273 -232.679748)
		(width 0.1143)
		(layer "In11.Cu")
		(net "GMI_CPU1_G3_CPU0_G1_TX_DN<5>")
	)
	(segment
		(start 117.131846 -227.797106)
		(end 117.09273 -227.819966)
		(width 0.1143)
		(layer "In11.Cu")
		(net "GMI_CPU1_G3_CPU0_G1_TX_DN<5>")
	)
	(segment
		(start 353.900232 -231.850184)
		(end 353.898454 -231.849168)
		(width 0.1143)
		(layer "In11.Cu")
		(net "GMI_CPU1_G3_CPU0_G1_TX_DN<5>")
	)
	(segment
		(start 117.09273 -228.749098)
		(end 117.131846 -228.771958)
		(width 0.1143)
		(layer "In11.Cu")
		(net "GMI_CPU1_G3_CPU0_G1_TX_DN<5>")
	)
	(segment
		(start 117.131846 -226.177094)
		(end 117.09273 -226.199954)
		(width 0.1143)
		(layer "In11.Cu")
		(net "GMI_CPU1_G3_CPU0_G1_TX_DN<5>")
	)
	(segment
		(start 354.403152 -229.43947)
		(end 354.364036 -229.41661)
		(width 0.1143)
		(layer "In11.Cu")
		(net "GMI_CPU1_G3_CPU0_G1_TX_DN<5>")
	)
	(segment
		(start 117.162326 -226.159314)
		(end 117.131846 -226.177094)
		(width 0.1143)
		(layer "In11.Cu")
		(net "GMI_CPU1_G3_CPU0_G1_TX_DN<5>")
	)
	(segment
		(start 354.728526 -221.083124)
		(end 354.728526 -221.071694)
		(width 0.1143)
		(layer "In11.Cu")
		(net "GMI_CPU1_G3_CPU0_G1_TX_DN<5>")
	)
	(segment
		(start 116.849652 -221.462854)
		(end 116.849652 -221.804484)
		(width 0.1143)
		(layer "In11.Cu")
		(net "GMI_CPU1_G3_CPU0_G1_TX_DN<5>")
	)
	(segment
		(start 116.767356 -218.484196)
		(end 116.767356 -221.071948)
		(width 0.14224)
		(layer "In11.Cu")
		(net "GMI_CPU1_G3_CPU0_G1_TX_DN<5>")
	)
	(segment
		(start 117.131846 -227.151946)
		(end 117.162326 -227.169726)
		(width 0.1143)
		(layer "In11.Cu")
		(net "GMI_CPU1_G3_CPU0_G1_TX_DN<5>")
	)
	(segment
		(start 353.933252 -231.869488)
		(end 353.901756 -231.8512)
		(width 0.1143)
		(layer "In11.Cu")
		(net "GMI_CPU1_G3_CPU0_G1_TX_DN<5>")
	)
	(segment
		(start 116.813076 -221.426278)
		(end 116.849652 -221.462854)
		(width 0.1143)
		(layer "In11.Cu")
		(net "GMI_CPU1_G3_CPU0_G1_TX_DN<5>")
	)
	(segment
		(start 117.633496 -231.828594)
		(end 117.603778 -231.845612)
		(width 0.1143)
		(layer "In11.Cu")
		(net "GMI_CPU1_G3_CPU0_G1_TX_DN<5>")
	)
	(segment
		(start 354.723192 -233.14406)
		(end 354.640388 -233.061256)
		(width 0.1143)
		(layer "In11.Cu")
		(net "GMI_CPU1_G3_CPU0_G1_TX_DN<5>")
	)
	(segment
		(start 353.895152 -231.847136)
		(end 353.894136 -231.846628)
		(width 0.1143)
		(layer "In11.Cu")
		(net "GMI_CPU1_G3_CPU0_G1_TX_DN<5>")
	)
	(segment
		(start 354.682806 -221.128844)
		(end 354.728526 -221.083124)
		(width 0.1143)
		(layer "In11.Cu")
		(net "GMI_CPU1_G3_CPU0_G1_TX_DN<5>")
	)
	(segment
		(start 353.898454 -231.849168)
		(end 353.897692 -231.84866)
		(width 0.1143)
		(layer "In11.Cu")
		(net "GMI_CPU1_G3_CPU0_G1_TX_DN<5>")
	)
	(segment
		(start 351.26803 -212.630766)
		(end 316.182756 -183.861964)
		(width 0.14224)
		(layer "In11.Cu")
		(net "GMI_CPU1_G3_CPU0_G1_TX_DN<5>")
	)
	(segment
		(start 158.503112 -181.30774)
		(end 154.620214 -184.490614)
		(width 0.14224)
		(layer "In11.Cu")
		(net "GMI_CPU1_G3_CPU0_G1_TX_DN<5>")
	)
	(segment
		(start 354.364036 -229.41661)
		(end 354.331524 -229.397814)
		(width 0.1143)
		(layer "In11.Cu")
		(net "GMI_CPU1_G3_CPU0_G1_TX_DN<5>")
	)
	(segment
		(start 354.728526 -218.458542)
		(end 351.26803 -212.630766)
		(width 0.14224)
		(layer "In11.Cu")
		(net "GMI_CPU1_G3_CPU0_G1_TX_DN<5>")
	)
	(segment
		(start 117.60073 -231.84739)
		(end 117.56263 -231.869742)
		(width 0.1143)
		(layer "In11.Cu")
		(net "GMI_CPU1_G3_CPU0_G1_TX_DN<5>")
	)
	(segment
		(start 354.333556 -230.409496)
		(end 354.400612 -230.37038)
		(width 0.1143)
		(layer "In11.Cu")
		(net "GMI_CPU1_G3_CPU0_G1_TX_DN<5>")
	)
	(segment
		(start 117.09273 -227.129086)
		(end 117.131846 -227.151946)
		(width 0.1143)
		(layer "In11.Cu")
		(net "GMI_CPU1_G3_CPU0_G1_TX_DN<5>")
	)
	(segment
		(start 353.892104 -231.845358)
		(end 353.862386 -231.82834)
		(width 0.1143)
		(layer "In11.Cu")
		(net "GMI_CPU1_G3_CPU0_G1_TX_DN<5>")
	)
	(segment
		(start 154.61996 -184.491122)
		(end 150.223982 -188.095128)
		(width 0.14224)
		(layer "In11.Cu")
		(net "GMI_CPU1_G3_CPU0_G1_TX_DN<5>")
	)
	(segment
		(start 117.09273 -223.889062)
		(end 117.131846 -223.911922)
		(width 0.1143)
		(layer "In11.Cu")
		(net "GMI_CPU1_G3_CPU0_G1_TX_DN<5>")
	)
	(segment
		(start 117.56263 -231.179116)
		(end 117.601746 -231.201976)
		(width 0.1143)
		(layer "In11.Cu")
		(net "GMI_CPU1_G3_CPU0_G1_TX_DN<5>")
	)
	(segment
		(start 354.333556 -228.789484)
		(end 354.403152 -228.748844)
		(width 0.1143)
		(layer "In11.Cu")
		(net "GMI_CPU1_G3_CPU0_G1_TX_DN<5>")
	)
	(segment
		(start 354.403152 -224.579688)
		(end 354.333556 -224.539048)
		(width 0.1143)
		(layer "In11.Cu")
		(net "GMI_CPU1_G3_CPU0_G1_TX_DN<5>")
	)
	(segment
		(start 150.223982 -188.095382)
		(end 144.24279 -192.998598)
		(width 0.14224)
		(layer "In11.Cu")
		(net "GMI_CPU1_G3_CPU0_G1_TX_DN<5>")
	)
	(segment
		(start 117.602508 -231.846374)
		(end 117.601746 -231.846882)
		(width 0.1143)
		(layer "In11.Cu")
		(net "GMI_CPU1_G3_CPU0_G1_TX_DN<5>")
	)
	(segment
		(start 117.601746 -231.201976)
		(end 117.635274 -231.221534)
		(width 0.1143)
		(layer "In11.Cu")
		(net "GMI_CPU1_G3_CPU0_G1_TX_DN<5>")
	)
	(segment
		(start 354.64623 -221.4626)
		(end 354.682806 -221.426024)
		(width 0.1143)
		(layer "In11.Cu")
		(net "GMI_CPU1_G3_CPU0_G1_TX_DN<5>")
	)
	(segment
		(start 117.131846 -228.771958)
		(end 117.162326 -228.789738)
		(width 0.1143)
		(layer "In11.Cu")
		(net "GMI_CPU1_G3_CPU0_G1_TX_DN<5>")
	)
	(segment
		(start 354.333556 -227.169472)
		(end 354.403152 -227.128832)
		(width 0.1143)
		(layer "In11.Cu")
		(net "GMI_CPU1_G3_CPU0_G1_TX_DN<5>")
	)
	(segment
		(start 117.162326 -227.779326)
		(end 117.131846 -227.797106)
		(width 0.1143)
		(layer "In11.Cu")
		(net "GMI_CPU1_G3_CPU0_G1_TX_DN<5>")
	)
	(segment
		(start 116.813076 -221.129098)
		(end 116.813076 -221.426278)
		(width 0.1143)
		(layer "In11.Cu")
		(net "GMI_CPU1_G3_CPU0_G1_TX_DN<5>")
	)
	(segment
		(start 307.617876 -179.492148)
		(end 302.90516 -179.492148)
		(width 0.14224)
		(layer "In11.Cu")
		(net "GMI_CPU1_G3_CPU0_G1_TX_DN<5>")
	)
	(segment
		(start 354.403152 -227.819712)
		(end 354.333556 -227.779072)
		(width 0.1143)
		(layer "In11.Cu")
		(net "GMI_CPU1_G3_CPU0_G1_TX_DN<5>")
	)
	(segment
		(start 120.238012 -212.563456)
		(end 116.767356 -218.484196)
		(width 0.14224)
		(layer "In11.Cu")
		(net "GMI_CPU1_G3_CPU0_G1_TX_DN<5>")
	)
	(segment
		(start 117.603778 -231.845612)
		(end 117.602508 -231.846374)
		(width 0.1143)
		(layer "In11.Cu")
		(net "GMI_CPU1_G3_CPU0_G1_TX_DN<5>")
	)
	(segment
		(start 117.09273 -225.509074)
		(end 117.131846 -225.531934)
		(width 0.1143)
		(layer "In11.Cu")
		(net "GMI_CPU1_G3_CPU0_G1_TX_DN<5>")
	)
	(segment
		(start 354.403152 -232.679494)
		(end 354.333556 -232.638854)
		(width 0.1143)
		(layer "In11.Cu")
		(net "GMI_CPU1_G3_CPU0_G1_TX_DN<5>")
	)
	(segment
		(start 117.164358 -229.398068)
		(end 117.131846 -229.416864)
		(width 0.1143)
		(layer "In11.Cu")
		(net "GMI_CPU1_G3_CPU0_G1_TX_DN<5>")
	)
	(segment
		(start 117.131846 -224.557082)
		(end 117.09273 -224.579942)
		(width 0.1143)
		(layer "In11.Cu")
		(net "GMI_CPU1_G3_CPU0_G1_TX_DN<5>")
	)
	(segment
		(start 355.021134 -233.14406)
		(end 354.723192 -233.14406)
		(width 0.1143)
		(layer "In11.Cu")
		(net "GMI_CPU1_G3_CPU0_G1_TX_DN<5>")
	)
	(segment
		(start 117.131846 -229.416864)
		(end 117.09273 -229.439724)
		(width 0.1143)
		(layer "In11.Cu")
		(net "GMI_CPU1_G3_CPU0_G1_TX_DN<5>")
	)
	(segment
		(start 302.90516 -179.492148)
		(end 165.817296 -178.692302)
		(width 0.14224)
		(layer "In11.Cu")
		(net "GMI_CPU1_G3_CPU0_G1_TX_DN<5>")
	)
	(segment
		(start 116.767356 -221.071948)
		(end 116.767356 -221.083378)
		(width 0.1143)
		(layer "In11.Cu")
		(net "GMI_CPU1_G3_CPU0_G1_TX_DN<5>")
	)
	(segment
		(start 116.855494 -233.06151)
		(end 116.77269 -233.144314)
		(width 0.1143)
		(layer "In11.Cu")
		(net "GMI_CPU1_G3_CPU0_G1_TX_DN<5>")
	)
	(segment
		(start 117.131846 -225.531934)
		(end 117.162326 -225.549714)
		(width 0.1143)
		(layer "In11.Cu")
		(net "GMI_CPU1_G3_CPU0_G1_TX_DN<5>")
	)
	(segment
		(start 117.162326 -232.639108)
		(end 117.131846 -232.656888)
		(width 0.1143)
		(layer "In11.Cu")
		(net "GMI_CPU1_G3_CPU0_G1_TX_DN<5>")
	)
	(segment
		(start 117.601746 -231.846882)
		(end 117.60073 -231.84739)
		(width 0.1143)
		(layer "In11.Cu")
		(net "GMI_CPU1_G3_CPU0_G1_TX_DN<5>")
	)
	(segment
		(start 117.162326 -222.91929)
		(end 117.131846 -222.93707)
		(width 0.1143)
		(layer "In11.Cu")
		(net "GMI_CPU1_G3_CPU0_G1_TX_DN<5>")
	)
	(segment
		(start 117.09527 -230.370634)
		(end 117.162326 -230.40975)
		(width 0.1143)
		(layer "In11.Cu")
		(net "GMI_CPU1_G3_CPU0_G1_TX_DN<5>")
	)
	(segment
		(start 354.403152 -222.959676)
		(end 354.333556 -222.919036)
		(width 0.1143)
		(layer "In11.Cu")
		(net "GMI_CPU1_G3_CPU0_G1_TX_DN<5>")
	)
	(segment
		(start 116.77269 -233.144314)
		(end 116.474748 -233.144314)
		(width 0.1143)
		(layer "In11.Cu")
		(net "GMI_CPU1_G3_CPU0_G1_TX_DN<5>")
	)
	(segment
		(start 144.24279 -192.998598)
		(end 144.013682 -193.068194)
		(width 0.14224)
		(layer "In11.Cu")
		(net "GMI_CPU1_G3_CPU0_G1_TX_DN<5>")
	)
	(segment
		(start 117.162326 -224.539302)
		(end 117.131846 -224.557082)
		(width 0.1143)
		(layer "In11.Cu")
		(net "GMI_CPU1_G3_CPU0_G1_TX_DN<5>")
	)
	(segment
		(start 316.182756 -183.861964)
		(end 309.912512 -180.312568)
		(width 0.14224)
		(layer "In11.Cu")
		(net "GMI_CPU1_G3_CPU0_G1_TX_DN<5>")
	)
	(segment
		(start 354.403152 -226.1997)
		(end 354.333556 -226.15906)
		(width 0.1143)
		(layer "In11.Cu")
		(net "GMI_CPU1_G3_CPU0_G1_TX_DN<5>")
	)
	(segment
		(start 353.894136 -231.846628)
		(end 353.893374 -231.84612)
		(width 0.1143)
		(layer "In11.Cu")
		(net "GMI_CPU1_G3_CPU0_G1_TX_DN<5>")
	)
	(segment
		(start 154.620214 -184.490614)
		(end 154.61996 -184.491122)
		(width 0.14224)
		(layer "In11.Cu")
		(net "GMI_CPU1_G3_CPU0_G1_TX_DN<5>")
	)
	(segment
		(start 144.013682 -193.068194)
		(end 120.238012 -212.563456)
		(width 0.14224)
		(layer "In11.Cu")
		(net "GMI_CPU1_G3_CPU0_G1_TX_DN<5>")
	)
	(segment
		(start 117.131846 -222.93707)
		(end 117.09273 -222.95993)
		(width 0.1143)
		(layer "In11.Cu")
		(net "GMI_CPU1_G3_CPU0_G1_TX_DN<5>")
	)
	(segment
		(start 117.131846 -223.911922)
		(end 117.162326 -223.929702)
		(width 0.1143)
		(layer "In11.Cu")
		(net "GMI_CPU1_G3_CPU0_G1_TX_DN<5>")
	)
	(segment
		(start 354.333556 -222.309436)
		(end 354.403152 -222.268796)
		(width 0.1143)
		(layer "In11.Cu")
		(net "GMI_CPU1_G3_CPU0_G1_TX_DN<5>")
	)
	(segment
		(start 150.223982 -188.095128)
		(end 150.223982 -188.095382)
		(width 0.14224)
		(layer "In11.Cu")
		(net "GMI_CPU1_G3_CPU0_G1_TX_DN<5>")
	)
	(segment
		(start 353.897692 -231.84866)
		(end 353.896676 -231.848152)
		(width 0.1143)
		(layer "In11.Cu")
		(net "GMI_CPU1_G3_CPU0_G1_TX_DN<5>")
	)
	(segment
		(start 354.728526 -221.071694)
		(end 354.728526 -218.458542)
		(width 0.14224)
		(layer "In11.Cu")
		(net "GMI_CPU1_G3_CPU0_G1_TX_DN<5>")
	)
	(segment
		(start 354.333556 -223.929448)
		(end 354.403152 -223.888808)
		(width 0.1143)
		(layer "In11.Cu")
		(net "GMI_CPU1_G3_CPU0_G1_TX_DN<5>")
	)
	(segment
		(start 353.896676 -231.848152)
		(end 353.895152 -231.847136)
		(width 0.1143)
		(layer "In11.Cu")
		(net "GMI_CPU1_G3_CPU0_G1_TX_DN<5>")
	)
	(segment
		(start 309.912512 -180.312568)
		(end 307.617876 -179.492148)
		(width 0.14224)
		(layer "In11.Cu")
		(net "GMI_CPU1_G3_CPU0_G1_TX_DN<5>")
	)
	(segment
		(start 354.333556 -225.54946)
		(end 354.403152 -225.50882)
		(width 0.1143)
		(layer "In11.Cu")
		(net "GMI_CPU1_G3_CPU0_G1_TX_DN<5>")
	)
	(segment
		(start 354.682806 -221.426024)
		(end 354.682806 -221.128844)
		(width 0.1143)
		(layer "In11.Cu")
		(net "GMI_CPU1_G3_CPU0_G1_TX_DN<5>")
	)
	(segment
		(start 353.901756 -231.8512)
		(end 353.900232 -231.850184)
		(width 0.1143)
		(layer "In11.Cu")
		(net "GMI_CPU1_G3_CPU0_G1_TX_DN<5>")
	)
	(arc
		(start 354.333556 -222.919036)
		(mid 354.176579 -222.614236)
		(end 354.333556 -222.309436)
		(width 0.1143)
		(layer "In11.Cu")
		(net "GMI_CPU1_G3_CPU0_G1_TX_DN<5>")
	)
	(arc
		(start 354.403152 -223.888808)
		(mid 354.646479 -223.424242)
		(end 354.403152 -222.959676)
		(width 0.1143)
		(layer "In11.Cu")
		(net "GMI_CPU1_G3_CPU0_G1_TX_DN<5>")
	)
	(arc
		(start 117.09273 -227.819966)
		(mid 116.849403 -228.284532)
		(end 117.09273 -228.749098)
		(width 0.1143)
		(layer "In11.Cu")
		(net "GMI_CPU1_G3_CPU0_G1_TX_DN<5>")
	)
	(arc
		(start 116.859304 -233.03865)
		(mid 116.857281 -233.05006)
		(end 116.855494 -233.06151)
		(width 0.1143)
		(layer "In11.Cu")
		(net "GMI_CPU1_G3_CPU0_G1_TX_DN<5>")
	)
	(arc
		(start 354.400612 -230.37038)
		(mid 354.581264 -230.167635)
		(end 354.646484 -229.904036)
		(width 0.1143)
		(layer "In11.Cu")
		(net "GMI_CPU1_G3_CPU0_G1_TX_DN<5>")
	)
	(arc
		(start 117.162326 -222.30969)
		(mid 117.319303 -222.61449)
		(end 117.162326 -222.91929)
		(width 0.1143)
		(layer "In11.Cu")
		(net "GMI_CPU1_G3_CPU0_G1_TX_DN<5>")
	)
	(arc
		(start 117.789452 -231.524302)
		(mid 117.748197 -231.695273)
		(end 117.633496 -231.828594)
		(width 0.1143)
		(layer "In11.Cu")
		(net "GMI_CPU1_G3_CPU0_G1_TX_DN<5>")
	)
	(arc
		(start 354.333556 -227.779072)
		(mid 354.176579 -227.474272)
		(end 354.333556 -227.169472)
		(width 0.1143)
		(layer "In11.Cu")
		(net "GMI_CPU1_G3_CPU0_G1_TX_DN<5>")
	)
	(arc
		(start 117.162326 -223.929702)
		(mid 117.319303 -224.234502)
		(end 117.162326 -224.539302)
		(width 0.1143)
		(layer "In11.Cu")
		(net "GMI_CPU1_G3_CPU0_G1_TX_DN<5>")
	)
	(arc
		(start 354.646484 -229.904036)
		(mid 354.581969 -229.641817)
		(end 354.403152 -229.43947)
		(width 0.1143)
		(layer "In11.Cu")
		(net "GMI_CPU1_G3_CPU0_G1_TX_DN<5>")
	)
	(arc
		(start 116.849652 -221.804484)
		(mid 116.914026 -222.066688)
		(end 117.09273 -222.26905)
		(width 0.1143)
		(layer "In11.Cu")
		(net "GMI_CPU1_G3_CPU0_G1_TX_DN<5>")
	)
	(arc
		(start 116.849398 -229.90429)
		(mid 116.914634 -230.167881)
		(end 117.09527 -230.370634)
		(width 0.1143)
		(layer "In11.Cu")
		(net "GMI_CPU1_G3_CPU0_G1_TX_DN<5>")
	)
	(arc
		(start 354.176584 -232.334054)
		(mid 354.112069 -232.071835)
		(end 353.933252 -231.869488)
		(width 0.1143)
		(layer "In11.Cu")
		(net "GMI_CPU1_G3_CPU0_G1_TX_DN<5>")
	)
	(arc
		(start 354.333556 -232.638854)
		(mid 354.218129 -232.505478)
		(end 354.176584 -232.334054)
		(width 0.1143)
		(layer "In11.Cu")
		(net "GMI_CPU1_G3_CPU0_G1_TX_DN<5>")
	)
	(arc
		(start 117.319298 -232.334308)
		(mid 117.277749 -232.50573)
		(end 117.162326 -232.639108)
		(width 0.1143)
		(layer "In11.Cu")
		(net "GMI_CPU1_G3_CPU0_G1_TX_DN<5>")
	)
	(arc
		(start 353.70643 -231.524048)
		(mid 353.747192 -231.354164)
		(end 353.860608 -231.22128)
		(width 0.1143)
		(layer "In11.Cu")
		(net "GMI_CPU1_G3_CPU0_G1_TX_DN<5>")
	)
	(arc
		(start 354.403152 -225.50882)
		(mid 354.646479 -225.044254)
		(end 354.403152 -224.579688)
		(width 0.1143)
		(layer "In11.Cu")
		(net "GMI_CPU1_G3_CPU0_G1_TX_DN<5>")
	)
	(arc
		(start 354.333556 -226.15906)
		(mid 354.176579 -225.85426)
		(end 354.333556 -225.54946)
		(width 0.1143)
		(layer "In11.Cu")
		(net "GMI_CPU1_G3_CPU0_G1_TX_DN<5>")
	)
	(arc
		(start 353.933252 -231.178862)
		(mid 354.112065 -230.976512)
		(end 354.176584 -230.714296)
		(width 0.1143)
		(layer "In11.Cu")
		(net "GMI_CPU1_G3_CPU0_G1_TX_DN<5>")
	)
	(arc
		(start 117.319298 -229.094538)
		(mid 117.278332 -229.264944)
		(end 117.164358 -229.398068)
		(width 0.1143)
		(layer "In11.Cu")
		(net "GMI_CPU1_G3_CPU0_G1_TX_DN<5>")
	)
	(arc
		(start 354.176584 -229.094284)
		(mid 354.218133 -228.922862)
		(end 354.333556 -228.789484)
		(width 0.1143)
		(layer "In11.Cu")
		(net "GMI_CPU1_G3_CPU0_G1_TX_DN<5>")
	)
	(arc
		(start 354.403152 -222.268796)
		(mid 354.581795 -222.066401)
		(end 354.64623 -221.80423)
		(width 0.1143)
		(layer "In11.Cu")
		(net "GMI_CPU1_G3_CPU0_G1_TX_DN<5>")
	)
	(arc
		(start 354.640388 -233.061256)
		(mid 354.6386 -233.049807)
		(end 354.636578 -233.038396)
		(width 0.1143)
		(layer "In11.Cu")
		(net "GMI_CPU1_G3_CPU0_G1_TX_DN<5>")
	)
	(arc
		(start 354.636578 -233.038396)
		(mid 354.555145 -232.835998)
		(end 354.403152 -232.679494)
		(width 0.1143)
		(layer "In11.Cu")
		(net "GMI_CPU1_G3_CPU0_G1_TX_DN<5>")
	)
	(arc
		(start 117.319298 -230.71455)
		(mid 117.383813 -230.976769)
		(end 117.56263 -231.179116)
		(width 0.1143)
		(layer "In11.Cu")
		(net "GMI_CPU1_G3_CPU0_G1_TX_DN<5>")
	)
	(arc
		(start 117.635274 -231.221534)
		(mid 117.748681 -231.354423)
		(end 117.789452 -231.524302)
		(width 0.1143)
		(layer "In11.Cu")
		(net "GMI_CPU1_G3_CPU0_G1_TX_DN<5>")
	)
	(arc
		(start 117.56263 -231.869742)
		(mid 117.383817 -232.072092)
		(end 117.319298 -232.334308)
		(width 0.1143)
		(layer "In11.Cu")
		(net "GMI_CPU1_G3_CPU0_G1_TX_DN<5>")
	)
	(arc
		(start 117.09273 -222.95993)
		(mid 116.849403 -223.424496)
		(end 117.09273 -223.889062)
		(width 0.1143)
		(layer "In11.Cu")
		(net "GMI_CPU1_G3_CPU0_G1_TX_DN<5>")
	)
	(arc
		(start 354.333556 -224.539048)
		(mid 354.176579 -224.234248)
		(end 354.333556 -223.929448)
		(width 0.1143)
		(layer "In11.Cu")
		(net "GMI_CPU1_G3_CPU0_G1_TX_DN<5>")
	)
	(arc
		(start 354.176584 -230.714296)
		(mid 354.218133 -230.542874)
		(end 354.333556 -230.409496)
		(width 0.1143)
		(layer "In11.Cu")
		(net "GMI_CPU1_G3_CPU0_G1_TX_DN<5>")
	)
	(arc
		(start 354.403152 -228.748844)
		(mid 354.646479 -228.284278)
		(end 354.403152 -227.819712)
		(width 0.1143)
		(layer "In11.Cu")
		(net "GMI_CPU1_G3_CPU0_G1_TX_DN<5>")
	)
	(arc
		(start 117.162326 -230.40975)
		(mid 117.277753 -230.543126)
		(end 117.319298 -230.71455)
		(width 0.1143)
		(layer "In11.Cu")
		(net "GMI_CPU1_G3_CPU0_G1_TX_DN<5>")
	)
	(arc
		(start 354.331524 -229.397814)
		(mid 354.217595 -229.264667)
		(end 354.176584 -229.094284)
		(width 0.1143)
		(layer "In11.Cu")
		(net "GMI_CPU1_G3_CPU0_G1_TX_DN<5>")
	)
	(arc
		(start 353.862386 -231.82834)
		(mid 353.74771 -231.695006)
		(end 353.70643 -231.524048)
		(width 0.1143)
		(layer "In11.Cu")
		(net "GMI_CPU1_G3_CPU0_G1_TX_DN<5>")
	)
	(arc
		(start 354.403152 -227.128832)
		(mid 354.646479 -226.664266)
		(end 354.403152 -226.1997)
		(width 0.1143)
		(layer "In11.Cu")
		(net "GMI_CPU1_G3_CPU0_G1_TX_DN<5>")
	)
	(arc
		(start 117.09273 -224.579942)
		(mid 116.849403 -225.044508)
		(end 117.09273 -225.509074)
		(width 0.1143)
		(layer "In11.Cu")
		(net "GMI_CPU1_G3_CPU0_G1_TX_DN<5>")
	)
	(arc
		(start 117.09273 -232.679748)
		(mid 116.940743 -232.836256)
		(end 116.859304 -233.03865)
		(width 0.1143)
		(layer "In11.Cu")
		(net "GMI_CPU1_G3_CPU0_G1_TX_DN<5>")
	)
	(arc
		(start 117.162326 -225.549714)
		(mid 117.319303 -225.854514)
		(end 117.162326 -226.159314)
		(width 0.1143)
		(layer "In11.Cu")
		(net "GMI_CPU1_G3_CPU0_G1_TX_DN<5>")
	)
	(arc
		(start 117.09273 -226.199954)
		(mid 116.849403 -226.66452)
		(end 117.09273 -227.129086)
		(width 0.1143)
		(layer "In11.Cu")
		(net "GMI_CPU1_G3_CPU0_G1_TX_DN<5>")
	)
	(arc
		(start 117.162326 -227.169726)
		(mid 117.319303 -227.474526)
		(end 117.162326 -227.779326)
		(width 0.1143)
		(layer "In11.Cu")
		(net "GMI_CPU1_G3_CPU0_G1_TX_DN<5>")
	)
	(arc
		(start 117.09273 -229.439724)
		(mid 116.913917 -229.642074)
		(end 116.849398 -229.90429)
		(width 0.1143)
		(layer "In11.Cu")
		(net "GMI_CPU1_G3_CPU0_G1_TX_DN<5>")
	)
	(arc
		(start 117.162326 -228.789738)
		(mid 117.277753 -228.923114)
		(end 117.319298 -229.094538)
		(width 0.1143)
		(layer "In11.Cu")
		(net "GMI_CPU1_G3_CPU0_G1_TX_DN<5>")
	)
	(segment
		(start 355.487986 -231.789986)
		(end 355.021134 -231.524048)
		(width 0.12954)
		(layer "F.Cu")
		(net "GMI_CPU1_G3_CPU0_G1_TX_DN<4>")
	)
	(segment
		(start 116.007896 -231.79024)
		(end 116.474748 -231.524302)
		(width 0.12954)
		(layer "F.Cu")
		(net "GMI_CPU1_G3_CPU0_G1_TX_DN<4>")
	)
	(segment
		(start 355.282754 -222.304102)
		(end 355.282246 -222.304102)
		(width 0.1143)
		(layer "In11.Cu")
		(net "GMI_CPU1_G3_CPU0_G1_TX_DN<4>")
	)
	(segment
		(start 116.222526 -229.399338)
		(end 116.22532 -229.397306)
		(width 0.1143)
		(layer "In11.Cu")
		(net "GMI_CPU1_G3_CPU0_G1_TX_DN<4>")
	)
	(segment
		(start 355.343206 -223.888808)
		(end 355.27234 -223.929956)
		(width 0.1143)
		(layer "In11.Cu")
		(net "GMI_CPU1_G3_CPU0_G1_TX_DN<4>")
	)
	(segment
		(start 115.909598 -221.804484)
		(end 115.909598 -221.48038)
		(width 0.1143)
		(layer "In11.Cu")
		(net "GMI_CPU1_G3_CPU0_G1_TX_DN<4>")
	)
	(segment
		(start 355.284278 -222.925386)
		(end 355.286056 -222.926402)
		(width 0.1143)
		(layer "In11.Cu")
		(net "GMI_CPU1_G3_CPU0_G1_TX_DN<4>")
	)
	(segment
		(start 355.30409 -226.17684)
		(end 355.343206 -226.1997)
		(width 0.1143)
		(layer "In11.Cu")
		(net "GMI_CPU1_G3_CPU0_G1_TX_DN<4>")
	)
	(segment
		(start 116.243354 -223.944434)
		(end 116.223542 -223.93021)
		(width 0.1143)
		(layer "In11.Cu")
		(net "GMI_CPU1_G3_CPU0_G1_TX_DN<4>")
	)
	(segment
		(start 355.252528 -224.524316)
		(end 355.27234 -224.53854)
		(width 0.1143)
		(layer "In11.Cu")
		(net "GMI_CPU1_G3_CPU0_G1_TX_DN<4>")
	)
	(segment
		(start 355.286056 -222.926402)
		(end 355.288088 -222.927418)
		(width 0.1143)
		(layer "In11.Cu")
		(net "GMI_CPU1_G3_CPU0_G1_TX_DN<4>")
	)
	(segment
		(start 316.69863 -183.07939)
		(end 351.986342 -212.0138)
		(width 0.14224)
		(layer "In11.Cu")
		(net "GMI_CPU1_G3_CPU0_G1_TX_DN<4>")
	)
	(segment
		(start 355.343206 -228.748844)
		(end 355.30409 -228.771704)
		(width 0.1143)
		(layer "In11.Cu")
		(net "GMI_CPU1_G3_CPU0_G1_TX_DN<4>")
	)
	(segment
		(start 116.152676 -222.95993)
		(end 116.190776 -222.937578)
		(width 0.1143)
		(layer "In11.Cu")
		(net "GMI_CPU1_G3_CPU0_G1_TX_DN<4>")
	)
	(segment
		(start 355.640386 -221.128844)
		(end 355.640386 -221.426024)
		(width 0.1143)
		(layer "In11.Cu")
		(net "GMI_CPU1_G3_CPU0_G1_TX_DN<4>")
	)
	(segment
		(start 355.288088 -222.927418)
		(end 355.289612 -222.928434)
		(width 0.1143)
		(layer "In11.Cu")
		(net "GMI_CPU1_G3_CPU0_G1_TX_DN<4>")
	)
	(segment
		(start 355.586284 -221.480126)
		(end 355.586284 -221.80423)
		(width 0.1143)
		(layer "In11.Cu")
		(net "GMI_CPU1_G3_CPU0_G1_TX_DN<4>")
	)
	(segment
		(start 355.686106 -221.071694)
		(end 355.686106 -221.083124)
		(width 0.1143)
		(layer "In11.Cu")
		(net "GMI_CPU1_G3_CPU0_G1_TX_DN<4>")
	)
	(segment
		(start 302.908208 -178.549808)
		(end 307.854858 -178.549808)
		(width 0.14224)
		(layer "In11.Cu")
		(net "GMI_CPU1_G3_CPU0_G1_TX_DN<4>")
	)
	(segment
		(start 354.653342 -231.454198)
		(end 354.723192 -231.524048)
		(width 0.1143)
		(layer "In11.Cu")
		(net "GMI_CPU1_G3_CPU0_G1_TX_DN<4>")
	)
	(segment
		(start 116.152676 -227.819966)
		(end 116.191792 -227.797106)
		(width 0.1143)
		(layer "In11.Cu")
		(net "GMI_CPU1_G3_CPU0_G1_TX_DN<4>")
	)
	(segment
		(start 119.551704 -211.847176)
		(end 152.41524 -184.90184)
		(width 0.14224)
		(layer "In11.Cu")
		(net "GMI_CPU1_G3_CPU0_G1_TX_DN<4>")
	)
	(segment
		(start 355.299518 -222.934276)
		(end 355.30155 -222.935546)
		(width 0.1143)
		(layer "In11.Cu")
		(net "GMI_CPU1_G3_CPU0_G1_TX_DN<4>")
	)
	(segment
		(start 355.27234 -227.16998)
		(end 355.252528 -227.184204)
		(width 0.1143)
		(layer "In11.Cu")
		(net "GMI_CPU1_G3_CPU0_G1_TX_DN<4>")
	)
	(segment
		(start 116.243354 -225.564446)
		(end 116.223542 -225.550222)
		(width 0.1143)
		(layer "In11.Cu")
		(net "GMI_CPU1_G3_CPU0_G1_TX_DN<4>")
	)
	(segment
		(start 355.30155 -222.935546)
		(end 355.305106 -222.937324)
		(width 0.1143)
		(layer "In11.Cu")
		(net "GMI_CPU1_G3_CPU0_G1_TX_DN<4>")
	)
	(segment
		(start 115.809776 -221.083378)
		(end 115.809776 -221.071948)
		(width 0.1143)
		(layer "In11.Cu")
		(net "GMI_CPU1_G3_CPU0_G1_TX_DN<4>")
	)
	(segment
		(start 351.986342 -212.0138)
		(end 355.686106 -218.244928)
		(width 0.14224)
		(layer "In11.Cu")
		(net "GMI_CPU1_G3_CPU0_G1_TX_DN<4>")
	)
	(segment
		(start 307.854858 -178.549808)
		(end 310.141112 -179.36718)
		(width 0.14224)
		(layer "In11.Cu")
		(net "GMI_CPU1_G3_CPU0_G1_TX_DN<4>")
	)
	(segment
		(start 355.252528 -227.76434)
		(end 355.27234 -227.778564)
		(width 0.1143)
		(layer "In11.Cu")
		(net "GMI_CPU1_G3_CPU0_G1_TX_DN<4>")
	)
	(segment
		(start 354.870512 -231.18064)
		(end 354.800662 -231.22128)
		(width 0.1143)
		(layer "In11.Cu")
		(net "GMI_CPU1_G3_CPU0_G1_TX_DN<4>")
	)
	(segment
		(start 355.116384 -230.585772)
		(end 355.116384 -230.714296)
		(width 0.1143)
		(layer "In11.Cu")
		(net "GMI_CPU1_G3_CPU0_G1_TX_DN<4>")
	)
	(segment
		(start 116.152676 -229.439724)
		(end 116.222526 -229.399338)
		(width 0.1143)
		(layer "In11.Cu")
		(net "GMI_CPU1_G3_CPU0_G1_TX_DN<4>")
	)
	(segment
		(start 355.273356 -229.399084)
		(end 355.343206 -229.43947)
		(width 0.1143)
		(layer "In11.Cu")
		(net "GMI_CPU1_G3_CPU0_G1_TX_DN<4>")
	)
	(segment
		(start 116.223542 -227.778818)
		(end 116.243354 -227.764594)
		(width 0.1143)
		(layer "In11.Cu")
		(net "GMI_CPU1_G3_CPU0_G1_TX_DN<4>")
	)
	(segment
		(start 115.809776 -218.149424)
		(end 119.551704 -211.847176)
		(width 0.14224)
		(layer "In11.Cu")
		(net "GMI_CPU1_G3_CPU0_G1_TX_DN<4>")
	)
	(segment
		(start 116.69522 -231.221534)
		(end 116.62537 -231.180894)
		(width 0.1143)
		(layer "In11.Cu")
		(net "GMI_CPU1_G3_CPU0_G1_TX_DN<4>")
	)
	(segment
		(start 116.223542 -228.790246)
		(end 116.191792 -228.771958)
		(width 0.1143)
		(layer "In11.Cu")
		(net "GMI_CPU1_G3_CPU0_G1_TX_DN<4>")
	)
	(segment
		(start 116.223542 -230.410258)
		(end 116.192554 -230.392478)
		(width 0.1143)
		(layer "In11.Cu")
		(net "GMI_CPU1_G3_CPU0_G1_TX_DN<4>")
	)
	(segment
		(start 116.213128 -222.304356)
		(end 116.153438 -222.269558)
		(width 0.1143)
		(layer "In11.Cu")
		(net "GMI_CPU1_G3_CPU0_G1_TX_DN<4>")
	)
	(segment
		(start 116.191792 -228.771958)
		(end 116.152676 -228.749098)
		(width 0.1143)
		(layer "In11.Cu")
		(net "GMI_CPU1_G3_CPU0_G1_TX_DN<4>")
	)
	(segment
		(start 355.27234 -225.549968)
		(end 355.252528 -225.564192)
		(width 0.1143)
		(layer "In11.Cu")
		(net "GMI_CPU1_G3_CPU0_G1_TX_DN<4>")
	)
	(segment
		(start 355.27234 -223.929956)
		(end 355.252528 -223.94418)
		(width 0.1143)
		(layer "In11.Cu")
		(net "GMI_CPU1_G3_CPU0_G1_TX_DN<4>")
	)
	(segment
		(start 116.223542 -227.170234)
		(end 116.152676 -227.129086)
		(width 0.1143)
		(layer "In11.Cu")
		(net "GMI_CPU1_G3_CPU0_G1_TX_DN<4>")
	)
	(segment
		(start 116.192046 -230.391716)
		(end 116.191284 -230.391208)
		(width 0.1143)
		(layer "In11.Cu")
		(net "GMI_CPU1_G3_CPU0_G1_TX_DN<4>")
	)
	(segment
		(start 355.29774 -222.93326)
		(end 355.299518 -222.934276)
		(width 0.1143)
		(layer "In11.Cu")
		(net "GMI_CPU1_G3_CPU0_G1_TX_DN<4>")
	)
	(segment
		(start 116.213128 -222.924624)
		(end 116.213382 -222.924624)
		(width 0.1143)
		(layer "In11.Cu")
		(net "GMI_CPU1_G3_CPU0_G1_TX_DN<4>")
	)
	(segment
		(start 310.141112 -179.36718)
		(end 316.69863 -183.07939)
		(width 0.14224)
		(layer "In11.Cu")
		(net "GMI_CPU1_G3_CPU0_G1_TX_DN<4>")
	)
	(segment
		(start 355.27234 -227.778564)
		(end 355.30409 -227.796852)
		(width 0.1143)
		(layer "In11.Cu")
		(net "GMI_CPU1_G3_CPU0_G1_TX_DN<4>")
	)
	(segment
		(start 355.27234 -230.410004)
		(end 355.167946 -230.485188)
		(width 0.1143)
		(layer "In11.Cu")
		(net "GMI_CPU1_G3_CPU0_G1_TX_DN<4>")
	)
	(segment
		(start 157.683962 -180.581554)
		(end 165.607238 -177.748184)
		(width 0.14224)
		(layer "In11.Cu")
		(net "GMI_CPU1_G3_CPU0_G1_TX_DN<4>")
	)
	(segment
		(start 115.855496 -221.129098)
		(end 115.809776 -221.083378)
		(width 0.1143)
		(layer "In11.Cu")
		(net "GMI_CPU1_G3_CPU0_G1_TX_DN<4>")
	)
	(segment
		(start 355.29139 -222.92945)
		(end 355.294184 -222.931228)
		(width 0.1143)
		(layer "In11.Cu")
		(net "GMI_CPU1_G3_CPU0_G1_TX_DN<4>")
	)
	(segment
		(start 355.282754 -222.92437)
		(end 355.284278 -222.925386)
		(width 0.1143)
		(layer "In11.Cu")
		(net "GMI_CPU1_G3_CPU0_G1_TX_DN<4>")
	)
	(segment
		(start 355.294184 -222.931228)
		(end 355.296216 -222.932244)
		(width 0.1143)
		(layer "In11.Cu")
		(net "GMI_CPU1_G3_CPU0_G1_TX_DN<4>")
	)
	(segment
		(start 116.191792 -224.557082)
		(end 116.223542 -224.538794)
		(width 0.1143)
		(layer "In11.Cu")
		(net "GMI_CPU1_G3_CPU0_G1_TX_DN<4>")
	)
	(segment
		(start 355.30409 -227.796852)
		(end 355.343206 -227.819712)
		(width 0.1143)
		(layer "In11.Cu")
		(net "GMI_CPU1_G3_CPU0_G1_TX_DN<4>")
	)
	(segment
		(start 116.77269 -231.524302)
		(end 116.84254 -231.454452)
		(width 0.1143)
		(layer "In11.Cu")
		(net "GMI_CPU1_G3_CPU0_G1_TX_DN<4>")
	)
	(segment
		(start 116.191792 -227.797106)
		(end 116.223542 -227.778818)
		(width 0.1143)
		(layer "In11.Cu")
		(net "GMI_CPU1_G3_CPU0_G1_TX_DN<4>")
	)
	(segment
		(start 355.30409 -230.391716)
		(end 355.303328 -230.392224)
		(width 0.1143)
		(layer "In11.Cu")
		(net "GMI_CPU1_G3_CPU0_G1_TX_DN<4>")
	)
	(segment
		(start 116.223542 -224.538794)
		(end 116.243354 -224.52457)
		(width 0.1143)
		(layer "In11.Cu")
		(net "GMI_CPU1_G3_CPU0_G1_TX_DN<4>")
	)
	(segment
		(start 116.243354 -227.184458)
		(end 116.223542 -227.170234)
		(width 0.1143)
		(layer "In11.Cu")
		(net "GMI_CPU1_G3_CPU0_G1_TX_DN<4>")
	)
	(segment
		(start 355.686106 -218.244928)
		(end 355.686106 -221.071694)
		(width 0.14224)
		(layer "In11.Cu")
		(net "GMI_CPU1_G3_CPU0_G1_TX_DN<4>")
	)
	(segment
		(start 116.191792 -230.39197)
		(end 116.192046 -230.391716)
		(width 0.1143)
		(layer "In11.Cu")
		(net "GMI_CPU1_G3_CPU0_G1_TX_DN<4>")
	)
	(segment
		(start 355.252528 -226.144328)
		(end 355.27234 -226.158552)
		(width 0.1143)
		(layer "In11.Cu")
		(net "GMI_CPU1_G3_CPU0_G1_TX_DN<4>")
	)
	(segment
		(start 355.303328 -230.392224)
		(end 355.27234 -230.410004)
		(width 0.1143)
		(layer "In11.Cu")
		(net "GMI_CPU1_G3_CPU0_G1_TX_DN<4>")
	)
	(segment
		(start 116.194332 -222.9358)
		(end 116.213128 -222.924624)
		(width 0.1143)
		(layer "In11.Cu")
		(net "GMI_CPU1_G3_CPU0_G1_TX_DN<4>")
	)
	(segment
		(start 116.152676 -226.199954)
		(end 116.191792 -226.177094)
		(width 0.1143)
		(layer "In11.Cu")
		(net "GMI_CPU1_G3_CPU0_G1_TX_DN<4>")
	)
	(segment
		(start 165.607238 -177.748184)
		(end 302.908208 -178.549808)
		(width 0.14224)
		(layer "In11.Cu")
		(net "GMI_CPU1_G3_CPU0_G1_TX_DN<4>")
	)
	(segment
		(start 115.909598 -221.48038)
		(end 115.855496 -221.426278)
		(width 0.1143)
		(layer "In11.Cu")
		(net "GMI_CPU1_G3_CPU0_G1_TX_DN<4>")
	)
	(segment
		(start 152.41524 -184.90184)
		(end 152.414986 -184.901332)
		(width 0.14224)
		(layer "In11.Cu")
		(net "GMI_CPU1_G3_CPU0_G1_TX_DN<4>")
	)
	(segment
		(start 355.305106 -222.937324)
		(end 355.343206 -222.959676)
		(width 0.1143)
		(layer "In11.Cu")
		(net "GMI_CPU1_G3_CPU0_G1_TX_DN<4>")
	)
	(segment
		(start 355.342444 -222.269304)
		(end 355.282754 -222.304102)
		(width 0.1143)
		(layer "In11.Cu")
		(net "GMI_CPU1_G3_CPU0_G1_TX_DN<4>")
	)
	(segment
		(start 116.474748 -231.524302)
		(end 116.77269 -231.524302)
		(width 0.1143)
		(layer "In11.Cu")
		(net "GMI_CPU1_G3_CPU0_G1_TX_DN<4>")
	)
	(segment
		(start 116.191792 -226.177094)
		(end 116.223542 -226.158806)
		(width 0.1143)
		(layer "In11.Cu")
		(net "GMI_CPU1_G3_CPU0_G1_TX_DN<4>")
	)
	(segment
		(start 355.30409 -228.771704)
		(end 355.27234 -228.789992)
		(width 0.1143)
		(layer "In11.Cu")
		(net "GMI_CPU1_G3_CPU0_G1_TX_DN<4>")
	)
	(segment
		(start 355.303836 -230.391462)
		(end 355.30409 -230.391716)
		(width 0.1143)
		(layer "In11.Cu")
		(net "GMI_CPU1_G3_CPU0_G1_TX_DN<4>")
	)
	(segment
		(start 115.855496 -221.426278)
		(end 115.855496 -221.129098)
		(width 0.1143)
		(layer "In11.Cu")
		(net "GMI_CPU1_G3_CPU0_G1_TX_DN<4>")
	)
	(segment
		(start 355.304598 -230.390954)
		(end 355.303836 -230.391462)
		(width 0.1143)
		(layer "In11.Cu")
		(net "GMI_CPU1_G3_CPU0_G1_TX_DN<4>")
	)
	(segment
		(start 355.270562 -229.397052)
		(end 355.273356 -229.399084)
		(width 0.1143)
		(layer "In11.Cu")
		(net "GMI_CPU1_G3_CPU0_G1_TX_DN<4>")
	)
	(segment
		(start 116.152676 -224.579942)
		(end 116.191792 -224.557082)
		(width 0.1143)
		(layer "In11.Cu")
		(net "GMI_CPU1_G3_CPU0_G1_TX_DN<4>")
	)
	(segment
		(start 354.723192 -231.524048)
		(end 355.021134 -231.524048)
		(width 0.1143)
		(layer "In11.Cu")
		(net "GMI_CPU1_G3_CPU0_G1_TX_DN<4>")
	)
	(segment
		(start 355.343206 -227.128832)
		(end 355.27234 -227.16998)
		(width 0.1143)
		(layer "In11.Cu")
		(net "GMI_CPU1_G3_CPU0_G1_TX_DN<4>")
	)
	(segment
		(start 116.379498 -230.71455)
		(end 116.379498 -230.586026)
		(width 0.1143)
		(layer "In11.Cu")
		(net "GMI_CPU1_G3_CPU0_G1_TX_DN<4>")
	)
	(segment
		(start 116.223542 -223.93021)
		(end 116.152676 -223.889062)
		(width 0.1143)
		(layer "In11.Cu")
		(net "GMI_CPU1_G3_CPU0_G1_TX_DN<4>")
	)
	(segment
		(start 355.640386 -221.426024)
		(end 355.586284 -221.480126)
		(width 0.1143)
		(layer "In11.Cu")
		(net "GMI_CPU1_G3_CPU0_G1_TX_DN<4>")
	)
	(segment
		(start 116.192554 -230.392478)
		(end 116.191792 -230.39197)
		(width 0.1143)
		(layer "In11.Cu")
		(net "GMI_CPU1_G3_CPU0_G1_TX_DN<4>")
	)
	(segment
		(start 116.223542 -225.550222)
		(end 116.152676 -225.509074)
		(width 0.1143)
		(layer "In11.Cu")
		(net "GMI_CPU1_G3_CPU0_G1_TX_DN<4>")
	)
	(segment
		(start 355.296216 -222.932244)
		(end 355.29774 -222.93326)
		(width 0.1143)
		(layer "In11.Cu")
		(net "GMI_CPU1_G3_CPU0_G1_TX_DN<4>")
	)
	(segment
		(start 116.223542 -226.158806)
		(end 116.243354 -226.144582)
		(width 0.1143)
		(layer "In11.Cu")
		(net "GMI_CPU1_G3_CPU0_G1_TX_DN<4>")
	)
	(segment
		(start 355.27234 -226.158552)
		(end 355.30409 -226.17684)
		(width 0.1143)
		(layer "In11.Cu")
		(net "GMI_CPU1_G3_CPU0_G1_TX_DN<4>")
	)
	(segment
		(start 115.809776 -221.071948)
		(end 115.809776 -218.149424)
		(width 0.14224)
		(layer "In11.Cu")
		(net "GMI_CPU1_G3_CPU0_G1_TX_DN<4>")
	)
	(segment
		(start 152.414986 -184.901332)
		(end 157.683962 -180.581554)
		(width 0.14224)
		(layer "In11.Cu")
		(net "GMI_CPU1_G3_CPU0_G1_TX_DN<4>")
	)
	(segment
		(start 355.30409 -224.556828)
		(end 355.343206 -224.579688)
		(width 0.1143)
		(layer "In11.Cu")
		(net "GMI_CPU1_G3_CPU0_G1_TX_DN<4>")
	)
	(segment
		(start 355.289612 -222.928434)
		(end 355.29139 -222.92945)
		(width 0.1143)
		(layer "In11.Cu")
		(net "GMI_CPU1_G3_CPU0_G1_TX_DN<4>")
	)
	(segment
		(start 116.327936 -230.485442)
		(end 116.223542 -230.410258)
		(width 0.1143)
		(layer "In11.Cu")
		(net "GMI_CPU1_G3_CPU0_G1_TX_DN<4>")
	)
	(segment
		(start 355.27234 -224.53854)
		(end 355.30409 -224.556828)
		(width 0.1143)
		(layer "In11.Cu")
		(net "GMI_CPU1_G3_CPU0_G1_TX_DN<4>")
	)
	(segment
		(start 355.2825 -222.92437)
		(end 355.282754 -222.92437)
		(width 0.1143)
		(layer "In11.Cu")
		(net "GMI_CPU1_G3_CPU0_G1_TX_DN<4>")
	)
	(segment
		(start 355.343206 -225.50882)
		(end 355.27234 -225.549968)
		(width 0.1143)
		(layer "In11.Cu")
		(net "GMI_CPU1_G3_CPU0_G1_TX_DN<4>")
	)
	(segment
		(start 116.190776 -222.937578)
		(end 116.194332 -222.9358)
		(width 0.1143)
		(layer "In11.Cu")
		(net "GMI_CPU1_G3_CPU0_G1_TX_DN<4>")
	)
	(segment
		(start 355.686106 -221.083124)
		(end 355.640386 -221.128844)
		(width 0.1143)
		(layer "In11.Cu")
		(net "GMI_CPU1_G3_CPU0_G1_TX_DN<4>")
	)
	(segment
		(start 116.213636 -222.304356)
		(end 116.213128 -222.304356)
		(width 0.1143)
		(layer "In11.Cu")
		(net "GMI_CPU1_G3_CPU0_G1_TX_DN<4>")
	)
	(arc
		(start 116.62537 -231.180894)
		(mid 116.444718 -230.978149)
		(end 116.379498 -230.71455)
		(width 0.1143)
		(layer "In11.Cu")
		(net "GMI_CPU1_G3_CPU0_G1_TX_DN<4>")
	)
	(arc
		(start 116.152676 -227.129086)
		(mid 115.909349 -226.66452)
		(end 116.152676 -226.199954)
		(width 0.1143)
		(layer "In11.Cu")
		(net "GMI_CPU1_G3_CPU0_G1_TX_DN<4>")
	)
	(arc
		(start 355.343206 -226.1997)
		(mid 355.586533 -226.664266)
		(end 355.343206 -227.128832)
		(width 0.1143)
		(layer "In11.Cu")
		(net "GMI_CPU1_G3_CPU0_G1_TX_DN<4>")
	)
	(arc
		(start 116.243354 -226.144582)
		(mid 116.392068 -225.854514)
		(end 116.243354 -225.564446)
		(width 0.1143)
		(layer "In11.Cu")
		(net "GMI_CPU1_G3_CPU0_G1_TX_DN<4>")
	)
	(arc
		(start 355.586284 -229.904036)
		(mid 355.510782 -230.185288)
		(end 355.304598 -230.390954)
		(width 0.1143)
		(layer "In11.Cu")
		(net "GMI_CPU1_G3_CPU0_G1_TX_DN<4>")
	)
	(arc
		(start 355.252528 -227.184204)
		(mid 355.103814 -227.474272)
		(end 355.252528 -227.76434)
		(width 0.1143)
		(layer "In11.Cu")
		(net "GMI_CPU1_G3_CPU0_G1_TX_DN<4>")
	)
	(arc
		(start 116.153438 -222.269558)
		(mid 115.974245 -222.067048)
		(end 115.909598 -221.804484)
		(width 0.1143)
		(layer "In11.Cu")
		(net "GMI_CPU1_G3_CPU0_G1_TX_DN<4>")
	)
	(arc
		(start 355.27234 -228.789992)
		(mid 355.159967 -228.924516)
		(end 355.116384 -229.094284)
		(width 0.1143)
		(layer "In11.Cu")
		(net "GMI_CPU1_G3_CPU0_G1_TX_DN<4>")
	)
	(arc
		(start 355.343206 -224.579688)
		(mid 355.586533 -225.044254)
		(end 355.343206 -225.50882)
		(width 0.1143)
		(layer "In11.Cu")
		(net "GMI_CPU1_G3_CPU0_G1_TX_DN<4>")
	)
	(arc
		(start 355.343206 -229.43947)
		(mid 355.521926 -229.641839)
		(end 355.586284 -229.904036)
		(width 0.1143)
		(layer "In11.Cu")
		(net "GMI_CPU1_G3_CPU0_G1_TX_DN<4>")
	)
	(arc
		(start 354.800662 -231.22128)
		(mid 354.704774 -231.323688)
		(end 354.653342 -231.454198)
		(width 0.1143)
		(layer "In11.Cu")
		(net "GMI_CPU1_G3_CPU0_G1_TX_DN<4>")
	)
	(arc
		(start 355.252528 -225.564192)
		(mid 355.103814 -225.85426)
		(end 355.252528 -226.144328)
		(width 0.1143)
		(layer "In11.Cu")
		(net "GMI_CPU1_G3_CPU0_G1_TX_DN<4>")
	)
	(arc
		(start 116.213382 -222.924624)
		(mid 116.391924 -222.6146)
		(end 116.213636 -222.304356)
		(width 0.1143)
		(layer "In11.Cu")
		(net "GMI_CPU1_G3_CPU0_G1_TX_DN<4>")
	)
	(arc
		(start 116.22532 -229.397306)
		(mid 116.338727 -229.264417)
		(end 116.379498 -229.094538)
		(width 0.1143)
		(layer "In11.Cu")
		(net "GMI_CPU1_G3_CPU0_G1_TX_DN<4>")
	)
	(arc
		(start 116.243354 -227.764594)
		(mid 116.392068 -227.474526)
		(end 116.243354 -227.184458)
		(width 0.1143)
		(layer "In11.Cu")
		(net "GMI_CPU1_G3_CPU0_G1_TX_DN<4>")
	)
	(arc
		(start 116.152676 -228.749098)
		(mid 115.909349 -228.284532)
		(end 116.152676 -227.819966)
		(width 0.1143)
		(layer "In11.Cu")
		(net "GMI_CPU1_G3_CPU0_G1_TX_DN<4>")
	)
	(arc
		(start 355.586284 -221.80423)
		(mid 355.521625 -222.066787)
		(end 355.342444 -222.269304)
		(width 0.1143)
		(layer "In11.Cu")
		(net "GMI_CPU1_G3_CPU0_G1_TX_DN<4>")
	)
	(arc
		(start 355.282246 -222.304102)
		(mid 355.10383 -222.614346)
		(end 355.2825 -222.92437)
		(width 0.1143)
		(layer "In11.Cu")
		(net "GMI_CPU1_G3_CPU0_G1_TX_DN<4>")
	)
	(arc
		(start 355.116384 -229.094284)
		(mid 355.157146 -229.264168)
		(end 355.270562 -229.397052)
		(width 0.1143)
		(layer "In11.Cu")
		(net "GMI_CPU1_G3_CPU0_G1_TX_DN<4>")
	)
	(arc
		(start 116.191284 -230.391208)
		(mid 115.985062 -230.185564)
		(end 115.909598 -229.90429)
		(width 0.1143)
		(layer "In11.Cu")
		(net "GMI_CPU1_G3_CPU0_G1_TX_DN<4>")
	)
	(arc
		(start 355.252528 -223.94418)
		(mid 355.103814 -224.234248)
		(end 355.252528 -224.524316)
		(width 0.1143)
		(layer "In11.Cu")
		(net "GMI_CPU1_G3_CPU0_G1_TX_DN<4>")
	)
	(arc
		(start 116.84254 -231.454452)
		(mid 116.79105 -231.323979)
		(end 116.69522 -231.221534)
		(width 0.1143)
		(layer "In11.Cu")
		(net "GMI_CPU1_G3_CPU0_G1_TX_DN<4>")
	)
	(arc
		(start 116.379498 -230.586026)
		(mid 116.365861 -230.529505)
		(end 116.327936 -230.485442)
		(width 0.1143)
		(layer "In11.Cu")
		(net "GMI_CPU1_G3_CPU0_G1_TX_DN<4>")
	)
	(arc
		(start 115.909598 -229.90429)
		(mid 115.973991 -229.642112)
		(end 116.152676 -229.439724)
		(width 0.1143)
		(layer "In11.Cu")
		(net "GMI_CPU1_G3_CPU0_G1_TX_DN<4>")
	)
	(arc
		(start 116.379498 -229.094538)
		(mid 116.335872 -228.924792)
		(end 116.223542 -228.790246)
		(width 0.1143)
		(layer "In11.Cu")
		(net "GMI_CPU1_G3_CPU0_G1_TX_DN<4>")
	)
	(arc
		(start 355.167946 -230.485188)
		(mid 355.130045 -230.529263)
		(end 355.116384 -230.585772)
		(width 0.1143)
		(layer "In11.Cu")
		(net "GMI_CPU1_G3_CPU0_G1_TX_DN<4>")
	)
	(arc
		(start 355.343206 -222.959676)
		(mid 355.586533 -223.424242)
		(end 355.343206 -223.888808)
		(width 0.1143)
		(layer "In11.Cu")
		(net "GMI_CPU1_G3_CPU0_G1_TX_DN<4>")
	)
	(arc
		(start 116.243354 -224.52457)
		(mid 116.392068 -224.234502)
		(end 116.243354 -223.944434)
		(width 0.1143)
		(layer "In11.Cu")
		(net "GMI_CPU1_G3_CPU0_G1_TX_DN<4>")
	)
	(arc
		(start 116.152676 -225.509074)
		(mid 115.909349 -225.044508)
		(end 116.152676 -224.579942)
		(width 0.1143)
		(layer "In11.Cu")
		(net "GMI_CPU1_G3_CPU0_G1_TX_DN<4>")
	)
	(arc
		(start 116.152676 -223.889062)
		(mid 115.909349 -223.424496)
		(end 116.152676 -222.95993)
		(width 0.1143)
		(layer "In11.Cu")
		(net "GMI_CPU1_G3_CPU0_G1_TX_DN<4>")
	)
	(arc
		(start 355.343206 -227.819712)
		(mid 355.586533 -228.284278)
		(end 355.343206 -228.748844)
		(width 0.1143)
		(layer "In11.Cu")
		(net "GMI_CPU1_G3_CPU0_G1_TX_DN<4>")
	)
	(arc
		(start 355.116384 -230.714296)
		(mid 355.051148 -230.977887)
		(end 354.870512 -231.18064)
		(width 0.1143)
		(layer "In11.Cu")
		(net "GMI_CPU1_G3_CPU0_G1_TX_DN<4>")
	)
	(segment
		(start 116.007896 -235.030264)
		(end 116.474748 -234.764326)
		(width 0.12954)
		(layer "F.Cu")
		(net "GMI_CPU1_G3_CPU0_G1_TX_DN<3>")
	)
	(segment
		(start 355.487986 -235.03001)
		(end 355.021134 -234.764072)
		(width 0.12954)
		(layer "F.Cu")
		(net "GMI_CPU1_G3_CPU0_G1_TX_DN<3>")
	)
	(segment
		(start 356.238302 -227.154994)
		(end 356.239826 -227.154232)
		(width 0.1143)
		(layer "In11.Cu")
		(net "GMI_CPU1_G3_CPU0_G1_TX_DN<3>")
	)
	(segment
		(start 115.256818 -224.554034)
		(end 115.252246 -224.556828)
		(width 0.1143)
		(layer "In11.Cu")
		(net "GMI_CPU1_G3_CPU0_G1_TX_DN<3>")
	)
	(segment
		(start 356.24516 -222.937324)
		(end 356.244144 -222.936816)
		(width 0.1143)
		(layer "In11.Cu")
		(net "GMI_CPU1_G3_CPU0_G1_TX_DN<3>")
	)
	(segment
		(start 356.25405 -224.56267)
		(end 356.252526 -224.561654)
		(width 0.1143)
		(layer "In11.Cu")
		(net "GMI_CPU1_G3_CPU0_G1_TX_DN<3>")
	)
	(segment
		(start 116.654072 -234.437428)
		(end 116.661692 -234.441746)
		(width 0.1143)
		(layer "In11.Cu")
		(net "GMI_CPU1_G3_CPU0_G1_TX_DN<3>")
	)
	(segment
		(start 356.23754 -227.155502)
		(end 356.238302 -227.154994)
		(width 0.1143)
		(layer "In11.Cu")
		(net "GMI_CPU1_G3_CPU0_G1_TX_DN<3>")
	)
	(segment
		(start 115.250722 -222.937578)
		(end 115.249198 -222.938594)
		(width 0.1143)
		(layer "In11.Cu")
		(net "GMI_CPU1_G3_CPU0_G1_TX_DN<3>")
	)
	(segment
		(start 356.212394 -223.929956)
		(end 356.232206 -223.918526)
		(width 0.1143)
		(layer "In11.Cu")
		(net "GMI_CPU1_G3_CPU0_G1_TX_DN<3>")
	)
	(segment
		(start 356.235508 -232.016554)
		(end 356.23754 -232.015284)
		(width 0.1143)
		(layer "In11.Cu")
		(net "GMI_CPU1_G3_CPU0_G1_TX_DN<3>")
	)
	(segment
		(start 115.256818 -226.174046)
		(end 115.252246 -226.17684)
		(width 0.1143)
		(layer "In11.Cu")
		(net "GMI_CPU1_G3_CPU0_G1_TX_DN<3>")
	)
	(segment
		(start 115.248182 -228.769926)
		(end 115.249198 -228.770434)
		(width 0.1143)
		(layer "In11.Cu")
		(net "GMI_CPU1_G3_CPU0_G1_TX_DN<3>")
	)
	(segment
		(start 115.212622 -223.889062)
		(end 115.244118 -223.90735)
		(width 0.1143)
		(layer "In11.Cu")
		(net "GMI_CPU1_G3_CPU0_G1_TX_DN<3>")
	)
	(segment
		(start 115.252246 -227.796852)
		(end 115.250722 -227.797614)
		(width 0.1143)
		(layer "In11.Cu")
		(net "GMI_CPU1_G3_CPU0_G1_TX_DN<3>")
	)
	(segment
		(start 165.429438 -176.810416)
		(end 157.228032 -179.742846)
		(width 0.14224)
		(layer "In11.Cu")
		(net "GMI_CPU1_G3_CPU0_G1_TX_DN<3>")
	)
	(segment
		(start 356.242112 -227.795582)
		(end 356.212394 -227.778564)
		(width 0.1143)
		(layer "In11.Cu")
		(net "GMI_CPU1_G3_CPU0_G1_TX_DN<3>")
	)
	(segment
		(start 115.249198 -226.178618)
		(end 115.212622 -226.199954)
		(width 0.1143)
		(layer "In11.Cu")
		(net "GMI_CPU1_G3_CPU0_G1_TX_DN<3>")
	)
	(segment
		(start 115.283488 -222.918782)
		(end 115.262152 -222.931228)
		(width 0.1143)
		(layer "In11.Cu")
		(net "GMI_CPU1_G3_CPU0_G1_TX_DN<3>")
	)
	(segment
		(start 116.662454 -234.442254)
		(end 116.693442 -234.460034)
		(width 0.1143)
		(layer "In11.Cu")
		(net "GMI_CPU1_G3_CPU0_G1_TX_DN<3>")
	)
	(segment
		(start 356.239826 -225.53422)
		(end 356.240588 -225.533712)
		(width 0.1143)
		(layer "In11.Cu")
		(net "GMI_CPU1_G3_CPU0_G1_TX_DN<3>")
	)
	(segment
		(start 115.252246 -226.17684)
		(end 115.250722 -226.177602)
		(width 0.1143)
		(layer "In11.Cu")
		(net "GMI_CPU1_G3_CPU0_G1_TX_DN<3>")
	)
	(segment
		(start 355.12883 -233.944922)
		(end 355.12883 -233.934762)
		(width 0.1143)
		(layer "In11.Cu")
		(net "GMI_CPU1_G3_CPU0_G1_TX_DN<3>")
	)
	(segment
		(start 356.244144 -232.011474)
		(end 356.24516 -232.010966)
		(width 0.1143)
		(layer "In11.Cu")
		(net "GMI_CPU1_G3_CPU0_G1_TX_DN<3>")
	)
	(segment
		(start 356.244144 -223.911668)
		(end 356.24516 -223.91116)
		(width 0.1143)
		(layer "In11.Cu")
		(net "GMI_CPU1_G3_CPU0_G1_TX_DN<3>")
	)
	(segment
		(start 302.911256 -177.613056)
		(end 165.429438 -176.810416)
		(width 0.14224)
		(layer "In11.Cu")
		(net "GMI_CPU1_G3_CPU0_G1_TX_DN<3>")
	)
	(segment
		(start 356.240588 -228.773736)
		(end 356.243382 -228.772212)
		(width 0.1143)
		(layer "In11.Cu")
		(net "GMI_CPU1_G3_CPU0_G1_TX_DN<3>")
	)
	(segment
		(start 114.91087 -221.129098)
		(end 114.91087 -221.426278)
		(width 0.1143)
		(layer "In11.Cu")
		(net "GMI_CPU1_G3_CPU0_G1_TX_DN<3>")
	)
	(segment
		(start 115.252246 -222.936816)
		(end 115.250722 -222.937578)
		(width 0.1143)
		(layer "In11.Cu")
		(net "GMI_CPU1_G3_CPU0_G1_TX_DN<3>")
	)
	(segment
		(start 356.212394 -227.16998)
		(end 356.232206 -227.15855)
		(width 0.1143)
		(layer "In11.Cu")
		(net "GMI_CPU1_G3_CPU0_G1_TX_DN<3>")
	)
	(segment
		(start 115.251738 -232.011728)
		(end 115.2525 -232.012236)
		(width 0.1143)
		(layer "In11.Cu")
		(net "GMI_CPU1_G3_CPU0_G1_TX_DN<3>")
	)
	(segment
		(start 115.248182 -232.009696)
		(end 115.249198 -232.010204)
		(width 0.1143)
		(layer "In11.Cu")
		(net "GMI_CPU1_G3_CPU0_G1_TX_DN<3>")
	)
	(segment
		(start 356.243382 -227.796344)
		(end 356.242112 -227.795582)
		(width 0.1143)
		(layer "In11.Cu")
		(net "GMI_CPU1_G3_CPU0_G1_TX_DN<3>")
	)
	(segment
		(start 356.232206 -232.018332)
		(end 356.234238 -232.017316)
		(width 0.1143)
		(layer "In11.Cu")
		(net "GMI_CPU1_G3_CPU0_G1_TX_DN<3>")
	)
	(segment
		(start 356.240588 -232.013506)
		(end 356.243382 -232.011982)
		(width 0.1143)
		(layer "In11.Cu")
		(net "GMI_CPU1_G3_CPU0_G1_TX_DN<3>")
	)
	(segment
		(start 115.249198 -227.79863)
		(end 115.212622 -227.819966)
		(width 0.1143)
		(layer "In11.Cu")
		(net "GMI_CPU1_G3_CPU0_G1_TX_DN<3>")
	)
	(segment
		(start 115.259612 -227.792534)
		(end 115.258342 -227.793296)
		(width 0.1143)
		(layer "In11.Cu")
		(net "GMI_CPU1_G3_CPU0_G1_TX_DN<3>")
	)
	(segment
		(start 115.245642 -225.528378)
		(end 115.248182 -225.529902)
		(width 0.1143)
		(layer "In11.Cu")
		(net "GMI_CPU1_G3_CPU0_G1_TX_DN<3>")
	)
	(segment
		(start 115.259612 -226.172522)
		(end 115.258342 -226.173284)
		(width 0.1143)
		(layer "In11.Cu")
		(net "GMI_CPU1_G3_CPU0_G1_TX_DN<3>")
	)
	(segment
		(start 355.74351 -232.83926)
		(end 355.813106 -232.79862)
		(width 0.1143)
		(layer "In11.Cu")
		(net "GMI_CPU1_G3_CPU0_G1_TX_DN<3>")
	)
	(segment
		(start 356.24516 -224.557336)
		(end 356.244144 -224.556828)
		(width 0.1143)
		(layer "In11.Cu")
		(net "GMI_CPU1_G3_CPU0_G1_TX_DN<3>")
	)
	(segment
		(start 115.2525 -228.772466)
		(end 115.283488 -228.790246)
		(width 0.1143)
		(layer "In11.Cu")
		(net "GMI_CPU1_G3_CPU0_G1_TX_DN<3>")
	)
	(segment
		(start 356.630732 -221.071694)
		(end 356.630732 -217.740738)
		(width 0.14224)
		(layer "In11.Cu")
		(net "GMI_CPU1_G3_CPU0_G1_TX_DN<3>")
	)
	(segment
		(start 115.251738 -223.911922)
		(end 115.2525 -223.91243)
		(width 0.1143)
		(layer "In11.Cu")
		(net "GMI_CPU1_G3_CPU0_G1_TX_DN<3>")
	)
	(segment
		(start 354.846128 -234.434634)
		(end 354.847398 -234.433872)
		(width 0.1143)
		(layer "In11.Cu")
		(net "GMI_CPU1_G3_CPU0_G1_TX_DN<3>")
	)
	(segment
		(start 115.249198 -222.938594)
		(end 115.212622 -222.95993)
		(width 0.1143)
		(layer "In11.Cu")
		(net "GMI_CPU1_G3_CPU0_G1_TX_DN<3>")
	)
	(segment
		(start 115.212622 -225.509074)
		(end 115.244118 -225.527362)
		(width 0.1143)
		(layer "In11.Cu")
		(net "GMI_CPU1_G3_CPU0_G1_TX_DN<3>")
	)
	(segment
		(start 115.285266 -231.017318)
		(end 115.212622 -231.059736)
		(width 0.1143)
		(layer "In11.Cu")
		(net "GMI_CPU1_G3_CPU0_G1_TX_DN<3>")
	)
	(segment
		(start 354.723192 -234.764072)
		(end 354.653342 -234.694222)
		(width 0.1143)
		(layer "In11.Cu")
		(net "GMI_CPU1_G3_CPU0_G1_TX_DN<3>")
	)
	(segment
		(start 356.28326 -229.43947)
		(end 356.210616 -229.397052)
		(width 0.1143)
		(layer "In11.Cu")
		(net "GMI_CPU1_G3_CPU0_G1_TX_DN<3>")
	)
	(segment
		(start 356.526338 -221.484698)
		(end 356.585012 -221.426024)
		(width 0.1143)
		(layer "In11.Cu")
		(net "GMI_CPU1_G3_CPU0_G1_TX_DN<3>")
	)
	(segment
		(start 356.28326 -226.1997)
		(end 356.255066 -226.18319)
		(width 0.1143)
		(layer "In11.Cu")
		(net "GMI_CPU1_G3_CPU0_G1_TX_DN<3>")
	)
	(segment
		(start 356.243382 -226.176332)
		(end 356.242112 -226.17557)
		(width 0.1143)
		(layer "In11.Cu")
		(net "GMI_CPU1_G3_CPU0_G1_TX_DN<3>")
	)
	(segment
		(start 356.526338 -221.80423)
		(end 356.526338 -221.484698)
		(width 0.1143)
		(layer "In11.Cu")
		(net "GMI_CPU1_G3_CPU0_G1_TX_DN<3>")
	)
	(segment
		(start 356.24516 -226.177348)
		(end 356.244144 -226.17684)
		(width 0.1143)
		(layer "In11.Cu")
		(net "GMI_CPU1_G3_CPU0_G1_TX_DN<3>")
	)
	(segment
		(start 114.91087 -221.426278)
		(end 114.969544 -221.484952)
		(width 0.1143)
		(layer "In11.Cu")
		(net "GMI_CPU1_G3_CPU0_G1_TX_DN<3>")
	)
	(segment
		(start 356.238302 -223.91497)
		(end 356.239826 -223.914208)
		(width 0.1143)
		(layer "In11.Cu")
		(net "GMI_CPU1_G3_CPU0_G1_TX_DN<3>")
	)
	(segment
		(start 115.259612 -224.55251)
		(end 115.258342 -224.553272)
		(width 0.1143)
		(layer "In11.Cu")
		(net "GMI_CPU1_G3_CPU0_G1_TX_DN<3>")
	)
	(segment
		(start 356.232206 -228.778562)
		(end 356.234238 -228.777546)
		(width 0.1143)
		(layer "In11.Cu")
		(net "GMI_CPU1_G3_CPU0_G1_TX_DN<3>")
	)
	(segment
		(start 354.80244 -234.45978)
		(end 354.834952 -234.440984)
		(width 0.1143)
		(layer "In11.Cu")
		(net "GMI_CPU1_G3_CPU0_G1_TX_DN<3>")
	)
	(segment
		(start 356.246684 -223.910144)
		(end 356.28326 -223.888808)
		(width 0.1143)
		(layer "In11.Cu")
		(net "GMI_CPU1_G3_CPU0_G1_TX_DN<3>")
	)
	(segment
		(start 356.255066 -226.18319)
		(end 356.25405 -226.182682)
		(width 0.1143)
		(layer "In11.Cu")
		(net "GMI_CPU1_G3_CPU0_G1_TX_DN<3>")
	)
	(segment
		(start 356.252526 -222.941642)
		(end 356.2477 -222.938848)
		(width 0.1143)
		(layer "In11.Cu")
		(net "GMI_CPU1_G3_CPU0_G1_TX_DN<3>")
	)
	(segment
		(start 356.239826 -227.154232)
		(end 356.240588 -227.153724)
		(width 0.1143)
		(layer "In11.Cu")
		(net "GMI_CPU1_G3_CPU0_G1_TX_DN<3>")
	)
	(segment
		(start 356.2477 -222.938848)
		(end 356.246684 -222.93834)
		(width 0.1143)
		(layer "In11.Cu")
		(net "GMI_CPU1_G3_CPU0_G1_TX_DN<3>")
	)
	(segment
		(start 115.212622 -222.26905)
		(end 115.283488 -222.310198)
		(width 0.1143)
		(layer "In11.Cu")
		(net "GMI_CPU1_G3_CPU0_G1_TX_DN<3>")
	)
	(segment
		(start 115.262152 -226.171252)
		(end 115.259612 -226.172522)
		(width 0.1143)
		(layer "In11.Cu")
		(net "GMI_CPU1_G3_CPU0_G1_TX_DN<3>")
	)
	(segment
		(start 115.212622 -228.749098)
		(end 115.244118 -228.767386)
		(width 0.1143)
		(layer "In11.Cu")
		(net "GMI_CPU1_G3_CPU0_G1_TX_DN<3>")
	)
	(segment
		(start 115.259612 -222.932498)
		(end 115.258342 -222.93326)
		(width 0.1143)
		(layer "In11.Cu")
		(net "GMI_CPU1_G3_CPU0_G1_TX_DN<3>")
	)
	(segment
		(start 352.91776 -211.486496)
		(end 317.38951 -182.354728)
		(width 0.14224)
		(layer "In11.Cu")
		(net "GMI_CPU1_G3_CPU0_G1_TX_DN<3>")
	)
	(segment
		(start 356.243382 -232.011982)
		(end 356.244144 -232.011474)
		(width 0.1143)
		(layer "In11.Cu")
		(net "GMI_CPU1_G3_CPU0_G1_TX_DN<3>")
	)
	(segment
		(start 356.28326 -224.579688)
		(end 356.255066 -224.563178)
		(width 0.1143)
		(layer "In11.Cu")
		(net "GMI_CPU1_G3_CPU0_G1_TX_DN<3>")
	)
	(segment
		(start 115.256818 -227.794058)
		(end 115.252246 -227.796852)
		(width 0.1143)
		(layer "In11.Cu")
		(net "GMI_CPU1_G3_CPU0_G1_TX_DN<3>")
	)
	(segment
		(start 115.2525 -223.91243)
		(end 115.283488 -223.93021)
		(width 0.1143)
		(layer "In11.Cu")
		(net "GMI_CPU1_G3_CPU0_G1_TX_DN<3>")
	)
	(segment
		(start 356.238302 -228.775006)
		(end 356.239826 -228.774244)
		(width 0.1143)
		(layer "In11.Cu")
		(net "GMI_CPU1_G3_CPU0_G1_TX_DN<3>")
	)
	(segment
		(start 356.585012 -221.128844)
		(end 356.630732 -221.083124)
		(width 0.1143)
		(layer "In11.Cu")
		(net "GMI_CPU1_G3_CPU0_G1_TX_DN<3>")
	)
	(segment
		(start 115.245642 -227.14839)
		(end 115.248182 -227.149914)
		(width 0.1143)
		(layer "In11.Cu")
		(net "GMI_CPU1_G3_CPU0_G1_TX_DN<3>")
	)
	(segment
		(start 356.246684 -232.00995)
		(end 356.28326 -231.988614)
		(width 0.1143)
		(layer "In11.Cu")
		(net "GMI_CPU1_G3_CPU0_G1_TX_DN<3>")
	)
	(segment
		(start 115.258342 -226.173284)
		(end 115.256818 -226.174046)
		(width 0.1143)
		(layer "In11.Cu")
		(net "GMI_CPU1_G3_CPU0_G1_TX_DN<3>")
	)
	(segment
		(start 115.248182 -227.149914)
		(end 115.249198 -227.150422)
		(width 0.1143)
		(layer "In11.Cu")
		(net "GMI_CPU1_G3_CPU0_G1_TX_DN<3>")
	)
	(segment
		(start 356.238302 -225.534982)
		(end 356.239826 -225.53422)
		(width 0.1143)
		(layer "In11.Cu")
		(net "GMI_CPU1_G3_CPU0_G1_TX_DN<3>")
	)
	(segment
		(start 114.86515 -221.083378)
		(end 114.91087 -221.129098)
		(width 0.1143)
		(layer "In11.Cu")
		(net "GMI_CPU1_G3_CPU0_G1_TX_DN<3>")
	)
	(segment
		(start 115.248182 -223.90989)
		(end 115.249198 -223.910398)
		(width 0.1143)
		(layer "In11.Cu")
		(net "GMI_CPU1_G3_CPU0_G1_TX_DN<3>")
	)
	(segment
		(start 308.091586 -177.613056)
		(end 302.911256 -177.613056)
		(width 0.14224)
		(layer "In11.Cu")
		(net "GMI_CPU1_G3_CPU0_G1_TX_DN<3>")
	)
	(segment
		(start 115.2525 -227.152454)
		(end 115.283488 -227.170234)
		(width 0.1143)
		(layer "In11.Cu")
		(net "GMI_CPU1_G3_CPU0_G1_TX_DN<3>")
	)
	(segment
		(start 356.23754 -225.53549)
		(end 356.238302 -225.534982)
		(width 0.1143)
		(layer "In11.Cu")
		(net "GMI_CPU1_G3_CPU0_G1_TX_DN<3>")
	)
	(segment
		(start 356.243382 -224.55632)
		(end 356.242112 -224.555558)
		(width 0.1143)
		(layer "In11.Cu")
		(net "GMI_CPU1_G3_CPU0_G1_TX_DN<3>")
	)
	(segment
		(start 356.28326 -227.819712)
		(end 356.255066 -227.803202)
		(width 0.1143)
		(layer "In11.Cu")
		(net "GMI_CPU1_G3_CPU0_G1_TX_DN<3>")
	)
	(segment
		(start 115.262152 -224.55124)
		(end 115.259612 -224.55251)
		(width 0.1143)
		(layer "In11.Cu")
		(net "GMI_CPU1_G3_CPU0_G1_TX_DN<3>")
	)
	(segment
		(start 115.258342 -222.93326)
		(end 115.256818 -222.934022)
		(width 0.1143)
		(layer "In11.Cu")
		(net "GMI_CPU1_G3_CPU0_G1_TX_DN<3>")
	)
	(segment
		(start 356.232206 -227.15855)
		(end 356.234238 -227.157534)
		(width 0.1143)
		(layer "In11.Cu")
		(net "GMI_CPU1_G3_CPU0_G1_TX_DN<3>")
	)
	(segment
		(start 356.239826 -232.014014)
		(end 356.240588 -232.013506)
		(width 0.1143)
		(layer "In11.Cu")
		(net "GMI_CPU1_G3_CPU0_G1_TX_DN<3>")
	)
	(segment
		(start 356.234238 -227.157534)
		(end 356.235508 -227.156772)
		(width 0.1143)
		(layer "In11.Cu")
		(net "GMI_CPU1_G3_CPU0_G1_TX_DN<3>")
	)
	(segment
		(start 356.244144 -228.771704)
		(end 356.24516 -228.771196)
		(width 0.1143)
		(layer "In11.Cu")
		(net "GMI_CPU1_G3_CPU0_G1_TX_DN<3>")
	)
	(segment
		(start 115.250722 -224.55759)
		(end 115.249198 -224.558606)
		(width 0.1143)
		(layer "In11.Cu")
		(net "GMI_CPU1_G3_CPU0_G1_TX_DN<3>")
	)
	(segment
		(start 356.630732 -217.740738)
		(end 352.91776 -211.486496)
		(width 0.14224)
		(layer "In11.Cu")
		(net "GMI_CPU1_G3_CPU0_G1_TX_DN<3>")
	)
	(segment
		(start 115.251738 -228.771958)
		(end 115.2525 -228.772466)
		(width 0.1143)
		(layer "In11.Cu")
		(net "GMI_CPU1_G3_CPU0_G1_TX_DN<3>")
	)
	(segment
		(start 115.244118 -223.90735)
		(end 115.245642 -223.908366)
		(width 0.1143)
		(layer "In11.Cu")
		(net "GMI_CPU1_G3_CPU0_G1_TX_DN<3>")
	)
	(segment
		(start 356.235508 -223.916748)
		(end 356.23754 -223.915478)
		(width 0.1143)
		(layer "In11.Cu")
		(net "GMI_CPU1_G3_CPU0_G1_TX_DN<3>")
	)
	(segment
		(start 356.252526 -224.561654)
		(end 356.2477 -224.55886)
		(width 0.1143)
		(layer "In11.Cu")
		(net "GMI_CPU1_G3_CPU0_G1_TX_DN<3>")
	)
	(segment
		(start 116.84254 -234.694476)
		(end 116.77269 -234.764326)
		(width 0.1143)
		(layer "In11.Cu")
		(net "GMI_CPU1_G3_CPU0_G1_TX_DN<3>")
	)
	(segment
		(start 115.245642 -223.908366)
		(end 115.248182 -223.90989)
		(width 0.1143)
		(layer "In11.Cu")
		(net "GMI_CPU1_G3_CPU0_G1_TX_DN<3>")
	)
	(segment
		(start 115.283488 -224.538794)
		(end 115.262152 -224.55124)
		(width 0.1143)
		(layer "In11.Cu")
		(net "GMI_CPU1_G3_CPU0_G1_TX_DN<3>")
	)
	(segment
		(start 115.250722 -227.797614)
		(end 115.249198 -227.79863)
		(width 0.1143)
		(layer "In11.Cu")
		(net "GMI_CPU1_G3_CPU0_G1_TX_DN<3>")
	)
	(segment
		(start 115.245642 -228.768402)
		(end 115.248182 -228.769926)
		(width 0.1143)
		(layer "In11.Cu")
		(net "GMI_CPU1_G3_CPU0_G1_TX_DN<3>")
	)
	(segment
		(start 356.242112 -224.555558)
		(end 356.212394 -224.53854)
		(width 0.1143)
		(layer "In11.Cu")
		(net "GMI_CPU1_G3_CPU0_G1_TX_DN<3>")
	)
	(segment
		(start 355.30409 -233.631486)
		(end 355.343206 -233.608626)
		(width 0.1143)
		(layer "In11.Cu")
		(net "GMI_CPU1_G3_CPU0_G1_TX_DN<3>")
	)
	(segment
		(start 356.28326 -231.059482)
		(end 356.210616 -231.017064)
		(width 0.1143)
		(layer "In11.Cu")
		(net "GMI_CPU1_G3_CPU0_G1_TX_DN<3>")
	)
	(segment
		(start 356.244144 -224.556828)
		(end 356.243382 -224.55632)
		(width 0.1143)
		(layer "In11.Cu")
		(net "GMI_CPU1_G3_CPU0_G1_TX_DN<3>")
	)
	(segment
		(start 115.283488 -226.158806)
		(end 115.262152 -226.171252)
		(width 0.1143)
		(layer "In11.Cu")
		(net "GMI_CPU1_G3_CPU0_G1_TX_DN<3>")
	)
	(segment
		(start 356.24516 -227.79736)
		(end 356.244144 -227.796852)
		(width 0.1143)
		(layer "In11.Cu")
		(net "GMI_CPU1_G3_CPU0_G1_TX_DN<3>")
	)
	(segment
		(start 356.244144 -227.151692)
		(end 356.24516 -227.151184)
		(width 0.1143)
		(layer "In11.Cu")
		(net "GMI_CPU1_G3_CPU0_G1_TX_DN<3>")
	)
	(segment
		(start 356.243382 -222.936308)
		(end 356.242112 -222.935546)
		(width 0.1143)
		(layer "In11.Cu")
		(net "GMI_CPU1_G3_CPU0_G1_TX_DN<3>")
	)
	(segment
		(start 356.242112 -222.935546)
		(end 356.212394 -222.918528)
		(width 0.1143)
		(layer "In11.Cu")
		(net "GMI_CPU1_G3_CPU0_G1_TX_DN<3>")
	)
	(segment
		(start 115.244118 -232.007156)
		(end 115.245642 -232.008172)
		(width 0.1143)
		(layer "In11.Cu")
		(net "GMI_CPU1_G3_CPU0_G1_TX_DN<3>")
	)
	(segment
		(start 114.86515 -221.071948)
		(end 114.86515 -221.083378)
		(width 0.1143)
		(layer "In11.Cu")
		(net "GMI_CPU1_G3_CPU0_G1_TX_DN<3>")
	)
	(segment
		(start 356.246684 -228.77018)
		(end 356.28326 -228.748844)
		(width 0.1143)
		(layer "In11.Cu")
		(net "GMI_CPU1_G3_CPU0_G1_TX_DN<3>")
	)
	(segment
		(start 356.246684 -227.150168)
		(end 356.28326 -227.128832)
		(width 0.1143)
		(layer "In11.Cu")
		(net "GMI_CPU1_G3_CPU0_G1_TX_DN<3>")
	)
	(segment
		(start 356.235508 -225.53676)
		(end 356.23754 -225.53549)
		(width 0.1143)
		(layer "In11.Cu")
		(net "GMI_CPU1_G3_CPU0_G1_TX_DN<3>")
	)
	(segment
		(start 115.249198 -228.770434)
		(end 115.251738 -228.771958)
		(width 0.1143)
		(layer "In11.Cu")
		(net "GMI_CPU1_G3_CPU0_G1_TX_DN<3>")
	)
	(segment
		(start 356.23754 -232.015284)
		(end 356.238302 -232.014776)
		(width 0.1143)
		(layer "In11.Cu")
		(net "GMI_CPU1_G3_CPU0_G1_TX_DN<3>")
	)
	(segment
		(start 354.834952 -234.440984)
		(end 354.846128 -234.434634)
		(width 0.1143)
		(layer "In11.Cu")
		(net "GMI_CPU1_G3_CPU0_G1_TX_DN<3>")
	)
	(segment
		(start 355.021134 -234.764072)
		(end 354.723192 -234.764072)
		(width 0.1143)
		(layer "In11.Cu")
		(net "GMI_CPU1_G3_CPU0_G1_TX_DN<3>")
	)
	(segment
		(start 356.24516 -232.010966)
		(end 356.246684 -232.00995)
		(width 0.1143)
		(layer "In11.Cu")
		(net "GMI_CPU1_G3_CPU0_G1_TX_DN<3>")
	)
	(segment
		(start 115.262152 -222.931228)
		(end 115.259612 -222.932498)
		(width 0.1143)
		(layer "In11.Cu")
		(net "GMI_CPU1_G3_CPU0_G1_TX_DN<3>")
	)
	(segment
		(start 356.24516 -223.91116)
		(end 356.246684 -223.910144)
		(width 0.1143)
		(layer "In11.Cu")
		(net "GMI_CPU1_G3_CPU0_G1_TX_DN<3>")
	)
	(segment
		(start 356.234238 -232.017316)
		(end 356.235508 -232.016554)
		(width 0.1143)
		(layer "In11.Cu")
		(net "GMI_CPU1_G3_CPU0_G1_TX_DN<3>")
	)
	(segment
		(start 356.244144 -227.796852)
		(end 356.243382 -227.796344)
		(width 0.1143)
		(layer "In11.Cu")
		(net "GMI_CPU1_G3_CPU0_G1_TX_DN<3>")
	)
	(segment
		(start 356.24516 -227.151184)
		(end 356.246684 -227.150168)
		(width 0.1143)
		(layer "In11.Cu")
		(net "GMI_CPU1_G3_CPU0_G1_TX_DN<3>")
	)
	(segment
		(start 356.246684 -225.530156)
		(end 356.28326 -225.50882)
		(width 0.1143)
		(layer "In11.Cu")
		(net "GMI_CPU1_G3_CPU0_G1_TX_DN<3>")
	)
	(segment
		(start 115.252246 -224.556828)
		(end 115.250722 -224.55759)
		(width 0.1143)
		(layer "In11.Cu")
		(net "GMI_CPU1_G3_CPU0_G1_TX_DN<3>")
	)
	(segment
		(start 116.367052 -233.935016)
		(end 116.367052 -233.945176)
		(width 0.1143)
		(layer "In11.Cu")
		(net "GMI_CPU1_G3_CPU0_G1_TX_DN<3>")
	)
	(segment
		(start 356.212394 -232.029762)
		(end 356.232206 -232.018332)
		(width 0.1143)
		(layer "In11.Cu")
		(net "GMI_CPU1_G3_CPU0_G1_TX_DN<3>")
	)
	(segment
		(start 115.258342 -227.793296)
		(end 115.256818 -227.794058)
		(width 0.1143)
		(layer "In11.Cu")
		(net "GMI_CPU1_G3_CPU0_G1_TX_DN<3>")
	)
	(segment
		(start 115.682776 -232.798874)
		(end 115.752372 -232.839514)
		(width 0.1143)
		(layer "In11.Cu")
		(net "GMI_CPU1_G3_CPU0_G1_TX_DN<3>")
	)
	(segment
		(start 356.243382 -223.912176)
		(end 356.244144 -223.911668)
		(width 0.1143)
		(layer "In11.Cu")
		(net "GMI_CPU1_G3_CPU0_G1_TX_DN<3>")
	)
	(segment
		(start 356.28326 -222.959676)
		(end 356.255066 -222.943166)
		(width 0.1143)
		(layer "In11.Cu")
		(net "GMI_CPU1_G3_CPU0_G1_TX_DN<3>")
	)
	(segment
		(start 356.234238 -228.777546)
		(end 356.235508 -228.776784)
		(width 0.1143)
		(layer "In11.Cu")
		(net "GMI_CPU1_G3_CPU0_G1_TX_DN<3>")
	)
	(segment
		(start 115.2525 -225.532442)
		(end 115.283488 -225.550222)
		(width 0.1143)
		(layer "In11.Cu")
		(net "GMI_CPU1_G3_CPU0_G1_TX_DN<3>")
	)
	(segment
		(start 115.283488 -227.778818)
		(end 115.262152 -227.791264)
		(width 0.1143)
		(layer "In11.Cu")
		(net "GMI_CPU1_G3_CPU0_G1_TX_DN<3>")
	)
	(segment
		(start 115.212622 -227.129086)
		(end 115.244118 -227.147374)
		(width 0.1143)
		(layer "In11.Cu")
		(net "GMI_CPU1_G3_CPU0_G1_TX_DN<3>")
	)
	(segment
		(start 356.232206 -225.538538)
		(end 356.234238 -225.537522)
		(width 0.1143)
		(layer "In11.Cu")
		(net "GMI_CPU1_G3_CPU0_G1_TX_DN<3>")
	)
	(segment
		(start 116.152676 -233.60888)
		(end 116.191792 -233.63174)
		(width 0.1143)
		(layer "In11.Cu")
		(net "GMI_CPU1_G3_CPU0_G1_TX_DN<3>")
	)
	(segment
		(start 115.244118 -227.147374)
		(end 115.245642 -227.14839)
		(width 0.1143)
		(layer "In11.Cu")
		(net "GMI_CPU1_G3_CPU0_G1_TX_DN<3>")
	)
	(segment
		(start 356.243382 -228.772212)
		(end 356.244144 -228.771704)
		(width 0.1143)
		(layer "In11.Cu")
		(net "GMI_CPU1_G3_CPU0_G1_TX_DN<3>")
	)
	(segment
		(start 115.249198 -227.150422)
		(end 115.251738 -227.151946)
		(width 0.1143)
		(layer "In11.Cu")
		(net "GMI_CPU1_G3_CPU0_G1_TX_DN<3>")
	)
	(segment
		(start 356.246684 -222.93834)
		(end 356.24516 -222.937324)
		(width 0.1143)
		(layer "In11.Cu")
		(net "GMI_CPU1_G3_CPU0_G1_TX_DN<3>")
	)
	(segment
		(start 157.228032 -179.742846)
		(end 118.442486 -211.545424)
		(width 0.14224)
		(layer "In11.Cu")
		(net "GMI_CPU1_G3_CPU0_G1_TX_DN<3>")
	)
	(segment
		(start 356.25405 -222.942658)
		(end 356.252526 -222.941642)
		(width 0.1143)
		(layer "In11.Cu")
		(net "GMI_CPU1_G3_CPU0_G1_TX_DN<3>")
	)
	(segment
		(start 317.38951 -182.354728)
		(end 310.593486 -178.507644)
		(width 0.14224)
		(layer "In11.Cu")
		(net "GMI_CPU1_G3_CPU0_G1_TX_DN<3>")
	)
	(segment
		(start 356.234238 -225.537522)
		(end 356.235508 -225.53676)
		(width 0.1143)
		(layer "In11.Cu")
		(net "GMI_CPU1_G3_CPU0_G1_TX_DN<3>")
	)
	(segment
		(start 356.212394 -225.549968)
		(end 356.232206 -225.538538)
		(width 0.1143)
		(layer "In11.Cu")
		(net "GMI_CPU1_G3_CPU0_G1_TX_DN<3>")
	)
	(segment
		(start 356.585012 -221.426024)
		(end 356.585012 -221.128844)
		(width 0.1143)
		(layer "In11.Cu")
		(net "GMI_CPU1_G3_CPU0_G1_TX_DN<3>")
	)
	(segment
		(start 356.246684 -224.558352)
		(end 356.24516 -224.557336)
		(width 0.1143)
		(layer "In11.Cu")
		(net "GMI_CPU1_G3_CPU0_G1_TX_DN<3>")
	)
	(segment
		(start 356.23754 -223.915478)
		(end 356.238302 -223.91497)
		(width 0.1143)
		(layer "In11.Cu")
		(net "GMI_CPU1_G3_CPU0_G1_TX_DN<3>")
	)
	(segment
		(start 115.249198 -223.910398)
		(end 115.251738 -223.911922)
		(width 0.1143)
		(layer "In11.Cu")
		(net "GMI_CPU1_G3_CPU0_G1_TX_DN<3>")
	)
	(segment
		(start 356.212394 -228.789992)
		(end 356.232206 -228.778562)
		(width 0.1143)
		(layer "In11.Cu")
		(net "GMI_CPU1_G3_CPU0_G1_TX_DN<3>")
	)
	(segment
		(start 356.23754 -228.775514)
		(end 356.238302 -228.775006)
		(width 0.1143)
		(layer "In11.Cu")
		(net "GMI_CPU1_G3_CPU0_G1_TX_DN<3>")
	)
	(segment
		(start 115.215162 -230.370634)
		(end 115.283488 -230.410258)
		(width 0.1143)
		(layer "In11.Cu")
		(net "GMI_CPU1_G3_CPU0_G1_TX_DN<3>")
	)
	(segment
		(start 356.235508 -228.776784)
		(end 356.23754 -228.775514)
		(width 0.1143)
		(layer "In11.Cu")
		(net "GMI_CPU1_G3_CPU0_G1_TX_DN<3>")
	)
	(segment
		(start 356.238302 -232.014776)
		(end 356.239826 -232.014014)
		(width 0.1143)
		(layer "In11.Cu")
		(net "GMI_CPU1_G3_CPU0_G1_TX_DN<3>")
	)
	(segment
		(start 356.240588 -225.533712)
		(end 356.243382 -225.532188)
		(width 0.1143)
		(layer "In11.Cu")
		(net "GMI_CPU1_G3_CPU0_G1_TX_DN<3>")
	)
	(segment
		(start 116.77269 -234.764326)
		(end 116.474748 -234.764326)
		(width 0.1143)
		(layer "In11.Cu")
		(net "GMI_CPU1_G3_CPU0_G1_TX_DN<3>")
	)
	(segment
		(start 356.24516 -225.531172)
		(end 356.246684 -225.530156)
		(width 0.1143)
		(layer "In11.Cu")
		(net "GMI_CPU1_G3_CPU0_G1_TX_DN<3>")
	)
	(segment
		(start 115.2525 -232.012236)
		(end 115.283488 -232.030016)
		(width 0.1143)
		(layer "In11.Cu")
		(net "GMI_CPU1_G3_CPU0_G1_TX_DN<3>")
	)
	(segment
		(start 114.969544 -221.484952)
		(end 114.969544 -221.804484)
		(width 0.1143)
		(layer "In11.Cu")
		(net "GMI_CPU1_G3_CPU0_G1_TX_DN<3>")
	)
	(segment
		(start 356.239826 -223.914208)
		(end 356.240588 -223.9137)
		(width 0.1143)
		(layer "In11.Cu")
		(net "GMI_CPU1_G3_CPU0_G1_TX_DN<3>")
	)
	(segment
		(start 356.244144 -222.936816)
		(end 356.243382 -222.936308)
		(width 0.1143)
		(layer "In11.Cu")
		(net "GMI_CPU1_G3_CPU0_G1_TX_DN<3>")
	)
	(segment
		(start 356.246684 -226.178364)
		(end 356.24516 -226.177348)
		(width 0.1143)
		(layer "In11.Cu")
		(net "GMI_CPU1_G3_CPU0_G1_TX_DN<3>")
	)
	(segment
		(start 356.242112 -226.17557)
		(end 356.212394 -226.158552)
		(width 0.1143)
		(layer "In11.Cu")
		(net "GMI_CPU1_G3_CPU0_G1_TX_DN<3>")
	)
	(segment
		(start 115.249198 -225.53041)
		(end 115.251738 -225.531934)
		(width 0.1143)
		(layer "In11.Cu")
		(net "GMI_CPU1_G3_CPU0_G1_TX_DN<3>")
	)
	(segment
		(start 115.244118 -225.527362)
		(end 115.245642 -225.528378)
		(width 0.1143)
		(layer "In11.Cu")
		(net "GMI_CPU1_G3_CPU0_G1_TX_DN<3>")
	)
	(segment
		(start 356.255066 -227.803202)
		(end 356.25405 -227.802694)
		(width 0.1143)
		(layer "In11.Cu")
		(net "GMI_CPU1_G3_CPU0_G1_TX_DN<3>")
	)
	(segment
		(start 356.235508 -227.156772)
		(end 356.23754 -227.155502)
		(width 0.1143)
		(layer "In11.Cu")
		(net "GMI_CPU1_G3_CPU0_G1_TX_DN<3>")
	)
	(segment
		(start 115.245642 -232.008172)
		(end 115.248182 -232.009696)
		(width 0.1143)
		(layer "In11.Cu")
		(net "GMI_CPU1_G3_CPU0_G1_TX_DN<3>")
	)
	(segment
		(start 118.442486 -211.545424)
		(end 114.86515 -217.64498)
		(width 0.14224)
		(layer "In11.Cu")
		(net "GMI_CPU1_G3_CPU0_G1_TX_DN<3>")
	)
	(segment
		(start 115.249198 -224.558606)
		(end 115.212622 -224.579942)
		(width 0.1143)
		(layer "In11.Cu")
		(net "GMI_CPU1_G3_CPU0_G1_TX_DN<3>")
	)
	(segment
		(start 356.243382 -225.532188)
		(end 356.244144 -225.53168)
		(width 0.1143)
		(layer "In11.Cu")
		(net "GMI_CPU1_G3_CPU0_G1_TX_DN<3>")
	)
	(segment
		(start 356.2477 -227.798884)
		(end 356.246684 -227.798376)
		(width 0.1143)
		(layer "In11.Cu")
		(net "GMI_CPU1_G3_CPU0_G1_TX_DN<3>")
	)
	(segment
		(start 116.661692 -234.441746)
		(end 116.662454 -234.442254)
		(width 0.1143)
		(layer "In11.Cu")
		(net "GMI_CPU1_G3_CPU0_G1_TX_DN<3>")
	)
	(segment
		(start 356.244144 -225.53168)
		(end 356.24516 -225.531172)
		(width 0.1143)
		(layer "In11.Cu")
		(net "GMI_CPU1_G3_CPU0_G1_TX_DN<3>")
	)
	(segment
		(start 115.251738 -227.151946)
		(end 115.2525 -227.152454)
		(width 0.1143)
		(layer "In11.Cu")
		(net "GMI_CPU1_G3_CPU0_G1_TX_DN<3>")
	)
	(segment
		(start 356.243382 -227.1522)
		(end 356.244144 -227.151692)
		(width 0.1143)
		(layer "In11.Cu")
		(net "GMI_CPU1_G3_CPU0_G1_TX_DN<3>")
	)
	(segment
		(start 356.244144 -230.391716)
		(end 356.28072 -230.37038)
		(width 0.1143)
		(layer "In11.Cu")
		(net "GMI_CPU1_G3_CPU0_G1_TX_DN<3>")
	)
	(segment
		(start 115.248182 -225.529902)
		(end 115.249198 -225.53041)
		(width 0.1143)
		(layer "In11.Cu")
		(net "GMI_CPU1_G3_CPU0_G1_TX_DN<3>")
	)
	(segment
		(start 356.239826 -228.774244)
		(end 356.240588 -228.773736)
		(width 0.1143)
		(layer "In11.Cu")
		(net "GMI_CPU1_G3_CPU0_G1_TX_DN<3>")
	)
	(segment
		(start 356.212394 -230.410004)
		(end 356.244144 -230.391716)
		(width 0.1143)
		(layer "In11.Cu")
		(net "GMI_CPU1_G3_CPU0_G1_TX_DN<3>")
	)
	(segment
		(start 356.25405 -226.182682)
		(end 356.252526 -226.181666)
		(width 0.1143)
		(layer "In11.Cu")
		(net "GMI_CPU1_G3_CPU0_G1_TX_DN<3>")
	)
	(segment
		(start 356.2477 -224.55886)
		(end 356.246684 -224.558352)
		(width 0.1143)
		(layer "In11.Cu")
		(net "GMI_CPU1_G3_CPU0_G1_TX_DN<3>")
	)
	(segment
		(start 115.258342 -224.553272)
		(end 115.256818 -224.554034)
		(width 0.1143)
		(layer "In11.Cu")
		(net "GMI_CPU1_G3_CPU0_G1_TX_DN<3>")
	)
	(segment
		(start 356.24516 -228.771196)
		(end 356.246684 -228.77018)
		(width 0.1143)
		(layer "In11.Cu")
		(net "GMI_CPU1_G3_CPU0_G1_TX_DN<3>")
	)
	(segment
		(start 356.232206 -223.918526)
		(end 356.234238 -223.91751)
		(width 0.1143)
		(layer "In11.Cu")
		(net "GMI_CPU1_G3_CPU0_G1_TX_DN<3>")
	)
	(segment
		(start 115.212622 -231.988868)
		(end 115.244118 -232.007156)
		(width 0.1143)
		(layer "In11.Cu")
		(net "GMI_CPU1_G3_CPU0_G1_TX_DN<3>")
	)
	(segment
		(start 115.250722 -226.177602)
		(end 115.249198 -226.178618)
		(width 0.1143)
		(layer "In11.Cu")
		(net "GMI_CPU1_G3_CPU0_G1_TX_DN<3>")
	)
	(segment
		(start 356.252526 -227.801678)
		(end 356.2477 -227.798884)
		(width 0.1143)
		(layer "In11.Cu")
		(net "GMI_CPU1_G3_CPU0_G1_TX_DN<3>")
	)
	(segment
		(start 356.630732 -221.083124)
		(end 356.630732 -221.071694)
		(width 0.1143)
		(layer "In11.Cu")
		(net "GMI_CPU1_G3_CPU0_G1_TX_DN<3>")
	)
	(segment
		(start 356.252526 -226.181666)
		(end 356.2477 -226.178872)
		(width 0.1143)
		(layer "In11.Cu")
		(net "GMI_CPU1_G3_CPU0_G1_TX_DN<3>")
	)
	(segment
		(start 356.246684 -227.798376)
		(end 356.24516 -227.79736)
		(width 0.1143)
		(layer "In11.Cu")
		(net "GMI_CPU1_G3_CPU0_G1_TX_DN<3>")
	)
	(segment
		(start 356.255066 -222.943166)
		(end 356.25405 -222.942658)
		(width 0.1143)
		(layer "In11.Cu")
		(net "GMI_CPU1_G3_CPU0_G1_TX_DN<3>")
	)
	(segment
		(start 356.244144 -226.17684)
		(end 356.243382 -226.176332)
		(width 0.1143)
		(layer "In11.Cu")
		(net "GMI_CPU1_G3_CPU0_G1_TX_DN<3>")
	)
	(segment
		(start 115.262152 -227.791264)
		(end 115.259612 -227.792534)
		(width 0.1143)
		(layer "In11.Cu")
		(net "GMI_CPU1_G3_CPU0_G1_TX_DN<3>")
	)
	(segment
		(start 356.212394 -222.309944)
		(end 356.28326 -222.268796)
		(width 0.1143)
		(layer "In11.Cu")
		(net "GMI_CPU1_G3_CPU0_G1_TX_DN<3>")
	)
	(segment
		(start 356.255066 -224.563178)
		(end 356.25405 -224.56267)
		(width 0.1143)
		(layer "In11.Cu")
		(net "GMI_CPU1_G3_CPU0_G1_TX_DN<3>")
	)
	(segment
		(start 115.256818 -222.934022)
		(end 115.252246 -222.936816)
		(width 0.1143)
		(layer "In11.Cu")
		(net "GMI_CPU1_G3_CPU0_G1_TX_DN<3>")
	)
	(segment
		(start 114.86515 -217.64498)
		(end 114.86515 -221.071948)
		(width 0.14224)
		(layer "In11.Cu")
		(net "GMI_CPU1_G3_CPU0_G1_TX_DN<3>")
	)
	(segment
		(start 115.249198 -232.010204)
		(end 115.251738 -232.011728)
		(width 0.1143)
		(layer "In11.Cu")
		(net "GMI_CPU1_G3_CPU0_G1_TX_DN<3>")
	)
	(segment
		(start 356.234238 -223.91751)
		(end 356.235508 -223.916748)
		(width 0.1143)
		(layer "In11.Cu")
		(net "GMI_CPU1_G3_CPU0_G1_TX_DN<3>")
	)
	(segment
		(start 310.593486 -178.507644)
		(end 308.091586 -177.613056)
		(width 0.14224)
		(layer "In11.Cu")
		(net "GMI_CPU1_G3_CPU0_G1_TX_DN<3>")
	)
	(segment
		(start 356.240588 -227.153724)
		(end 356.243382 -227.1522)
		(width 0.1143)
		(layer "In11.Cu")
		(net "GMI_CPU1_G3_CPU0_G1_TX_DN<3>")
	)
	(segment
		(start 115.244118 -228.767386)
		(end 115.245642 -228.768402)
		(width 0.1143)
		(layer "In11.Cu")
		(net "GMI_CPU1_G3_CPU0_G1_TX_DN<3>")
	)
	(segment
		(start 115.285266 -229.397306)
		(end 115.212622 -229.439724)
		(width 0.1143)
		(layer "In11.Cu")
		(net "GMI_CPU1_G3_CPU0_G1_TX_DN<3>")
	)
	(segment
		(start 356.25405 -227.802694)
		(end 356.252526 -227.801678)
		(width 0.1143)
		(layer "In11.Cu")
		(net "GMI_CPU1_G3_CPU0_G1_TX_DN<3>")
	)
	(segment
		(start 356.240588 -223.9137)
		(end 356.243382 -223.912176)
		(width 0.1143)
		(layer "In11.Cu")
		(net "GMI_CPU1_G3_CPU0_G1_TX_DN<3>")
	)
	(segment
		(start 115.251738 -225.531934)
		(end 115.2525 -225.532442)
		(width 0.1143)
		(layer "In11.Cu")
		(net "GMI_CPU1_G3_CPU0_G1_TX_DN<3>")
	)
	(segment
		(start 356.2477 -226.178872)
		(end 356.246684 -226.178364)
		(width 0.1143)
		(layer "In11.Cu")
		(net "GMI_CPU1_G3_CPU0_G1_TX_DN<3>")
	)
	(arc
		(start 114.969544 -221.804484)
		(mid 115.033991 -222.066636)
		(end 115.212622 -222.26905)
		(width 0.1143)
		(layer "In11.Cu")
		(net "GMI_CPU1_G3_CPU0_G1_TX_DN<3>")
	)
	(arc
		(start 356.212394 -227.778564)
		(mid 356.056466 -227.474272)
		(end 356.212394 -227.16998)
		(width 0.1143)
		(layer "In11.Cu")
		(net "GMI_CPU1_G3_CPU0_G1_TX_DN<3>")
	)
	(arc
		(start 115.283488 -223.93021)
		(mid 115.439416 -224.234502)
		(end 115.283488 -224.538794)
		(width 0.1143)
		(layer "In11.Cu")
		(net "GMI_CPU1_G3_CPU0_G1_TX_DN<3>")
	)
	(arc
		(start 116.693442 -234.460034)
		(mid 116.790577 -234.562903)
		(end 116.84254 -234.694476)
		(width 0.1143)
		(layer "In11.Cu")
		(net "GMI_CPU1_G3_CPU0_G1_TX_DN<3>")
	)
	(arc
		(start 356.28326 -231.988614)
		(mid 356.526587 -231.524048)
		(end 356.28326 -231.059482)
		(width 0.1143)
		(layer "In11.Cu")
		(net "GMI_CPU1_G3_CPU0_G1_TX_DN<3>")
	)
	(arc
		(start 355.343206 -233.608626)
		(mid 355.421629 -233.543145)
		(end 355.48697 -233.464608)
		(width 0.1143)
		(layer "In11.Cu")
		(net "GMI_CPU1_G3_CPU0_G1_TX_DN<3>")
	)
	(arc
		(start 115.283488 -227.170234)
		(mid 115.439416 -227.474526)
		(end 115.283488 -227.778818)
		(width 0.1143)
		(layer "In11.Cu")
		(net "GMI_CPU1_G3_CPU0_G1_TX_DN<3>")
	)
	(arc
		(start 356.210616 -229.397052)
		(mid 356.097209 -229.264163)
		(end 356.056438 -229.094284)
		(width 0.1143)
		(layer "In11.Cu")
		(net "GMI_CPU1_G3_CPU0_G1_TX_DN<3>")
	)
	(arc
		(start 115.439444 -232.334308)
		(mid 115.503959 -232.596527)
		(end 115.682776 -232.798874)
		(width 0.1143)
		(layer "In11.Cu")
		(net "GMI_CPU1_G3_CPU0_G1_TX_DN<3>")
	)
	(arc
		(start 115.283488 -228.790246)
		(mid 115.398164 -228.92358)
		(end 115.439444 -229.094538)
		(width 0.1143)
		(layer "In11.Cu")
		(net "GMI_CPU1_G3_CPU0_G1_TX_DN<3>")
	)
	(arc
		(start 355.48697 -233.464608)
		(mid 355.561084 -233.311894)
		(end 355.586538 -233.14406)
		(width 0.1143)
		(layer "In11.Cu")
		(net "GMI_CPU1_G3_CPU0_G1_TX_DN<3>")
	)
	(arc
		(start 115.212622 -222.95993)
		(mid 114.969295 -223.424496)
		(end 115.212622 -223.889062)
		(width 0.1143)
		(layer "In11.Cu")
		(net "GMI_CPU1_G3_CPU0_G1_TX_DN<3>")
	)
	(arc
		(start 115.752372 -232.839514)
		(mid 115.867799 -232.97289)
		(end 115.909344 -233.144314)
		(width 0.1143)
		(layer "In11.Cu")
		(net "GMI_CPU1_G3_CPU0_G1_TX_DN<3>")
	)
	(arc
		(start 356.28326 -227.128832)
		(mid 356.526587 -226.664266)
		(end 356.28326 -226.1997)
		(width 0.1143)
		(layer "In11.Cu")
		(net "GMI_CPU1_G3_CPU0_G1_TX_DN<3>")
	)
	(arc
		(start 115.212622 -231.059736)
		(mid 114.969295 -231.524302)
		(end 115.212622 -231.988868)
		(width 0.1143)
		(layer "In11.Cu")
		(net "GMI_CPU1_G3_CPU0_G1_TX_DN<3>")
	)
	(arc
		(start 356.056438 -229.094284)
		(mid 356.097693 -228.923313)
		(end 356.212394 -228.789992)
		(width 0.1143)
		(layer "In11.Cu")
		(net "GMI_CPU1_G3_CPU0_G1_TX_DN<3>")
	)
	(arc
		(start 356.28326 -228.748844)
		(mid 356.526587 -228.284278)
		(end 356.28326 -227.819712)
		(width 0.1143)
		(layer "In11.Cu")
		(net "GMI_CPU1_G3_CPU0_G1_TX_DN<3>")
	)
	(arc
		(start 115.439444 -230.71455)
		(mid 115.398682 -230.884434)
		(end 115.285266 -231.017318)
		(width 0.1143)
		(layer "In11.Cu")
		(net "GMI_CPU1_G3_CPU0_G1_TX_DN<3>")
	)
	(arc
		(start 116.191792 -233.63174)
		(mid 116.320092 -233.759876)
		(end 116.367052 -233.935016)
		(width 0.1143)
		(layer "In11.Cu")
		(net "GMI_CPU1_G3_CPU0_G1_TX_DN<3>")
	)
	(arc
		(start 356.526592 -229.904036)
		(mid 356.462077 -229.641817)
		(end 356.28326 -229.43947)
		(width 0.1143)
		(layer "In11.Cu")
		(net "GMI_CPU1_G3_CPU0_G1_TX_DN<3>")
	)
	(arc
		(start 115.212622 -226.199954)
		(mid 114.969295 -226.66452)
		(end 115.212622 -227.129086)
		(width 0.1143)
		(layer "In11.Cu")
		(net "GMI_CPU1_G3_CPU0_G1_TX_DN<3>")
	)
	(arc
		(start 115.212622 -229.439724)
		(mid 114.969298 -229.90584)
		(end 115.215162 -230.370634)
		(width 0.1143)
		(layer "In11.Cu")
		(net "GMI_CPU1_G3_CPU0_G1_TX_DN<3>")
	)
	(arc
		(start 356.28326 -223.888808)
		(mid 356.526587 -223.424242)
		(end 356.28326 -222.959676)
		(width 0.1143)
		(layer "In11.Cu")
		(net "GMI_CPU1_G3_CPU0_G1_TX_DN<3>")
	)
	(arc
		(start 356.28072 -230.37038)
		(mid 356.461372 -230.167635)
		(end 356.526592 -229.904036)
		(width 0.1143)
		(layer "In11.Cu")
		(net "GMI_CPU1_G3_CPU0_G1_TX_DN<3>")
	)
	(arc
		(start 115.439444 -229.094538)
		(mid 115.398682 -229.264422)
		(end 115.285266 -229.397306)
		(width 0.1143)
		(layer "In11.Cu")
		(net "GMI_CPU1_G3_CPU0_G1_TX_DN<3>")
	)
	(arc
		(start 115.283488 -222.310198)
		(mid 115.439416 -222.61449)
		(end 115.283488 -222.918782)
		(width 0.1143)
		(layer "In11.Cu")
		(net "GMI_CPU1_G3_CPU0_G1_TX_DN<3>")
	)
	(arc
		(start 354.847398 -234.433872)
		(mid 355.053466 -234.227009)
		(end 355.12883 -233.944922)
		(width 0.1143)
		(layer "In11.Cu")
		(net "GMI_CPU1_G3_CPU0_G1_TX_DN<3>")
	)
	(arc
		(start 115.283488 -232.030016)
		(mid 115.398164 -232.16335)
		(end 115.439444 -232.334308)
		(width 0.1143)
		(layer "In11.Cu")
		(net "GMI_CPU1_G3_CPU0_G1_TX_DN<3>")
	)
	(arc
		(start 115.283488 -225.550222)
		(mid 115.439416 -225.854514)
		(end 115.283488 -226.158806)
		(width 0.1143)
		(layer "In11.Cu")
		(net "GMI_CPU1_G3_CPU0_G1_TX_DN<3>")
	)
	(arc
		(start 355.586538 -233.14406)
		(mid 355.628087 -232.972638)
		(end 355.74351 -232.83926)
		(width 0.1143)
		(layer "In11.Cu")
		(net "GMI_CPU1_G3_CPU0_G1_TX_DN<3>")
	)
	(arc
		(start 356.210616 -231.017064)
		(mid 356.097209 -230.884175)
		(end 356.056438 -230.714296)
		(width 0.1143)
		(layer "In11.Cu")
		(net "GMI_CPU1_G3_CPU0_G1_TX_DN<3>")
	)
	(arc
		(start 115.283488 -230.410258)
		(mid 115.398164 -230.543592)
		(end 115.439444 -230.71455)
		(width 0.1143)
		(layer "In11.Cu")
		(net "GMI_CPU1_G3_CPU0_G1_TX_DN<3>")
	)
	(arc
		(start 356.28326 -225.50882)
		(mid 356.526587 -225.044254)
		(end 356.28326 -224.579688)
		(width 0.1143)
		(layer "In11.Cu")
		(net "GMI_CPU1_G3_CPU0_G1_TX_DN<3>")
	)
	(arc
		(start 356.212394 -226.158552)
		(mid 356.056466 -225.85426)
		(end 356.212394 -225.549968)
		(width 0.1143)
		(layer "In11.Cu")
		(net "GMI_CPU1_G3_CPU0_G1_TX_DN<3>")
	)
	(arc
		(start 356.056438 -230.714296)
		(mid 356.097693 -230.543325)
		(end 356.212394 -230.410004)
		(width 0.1143)
		(layer "In11.Cu")
		(net "GMI_CPU1_G3_CPU0_G1_TX_DN<3>")
	)
	(arc
		(start 355.12883 -233.934762)
		(mid 355.175797 -233.759627)
		(end 355.30409 -233.631486)
		(width 0.1143)
		(layer "In11.Cu")
		(net "GMI_CPU1_G3_CPU0_G1_TX_DN<3>")
	)
	(arc
		(start 356.28326 -222.268796)
		(mid 356.461918 -222.066396)
		(end 356.526338 -221.80423)
		(width 0.1143)
		(layer "In11.Cu")
		(net "GMI_CPU1_G3_CPU0_G1_TX_DN<3>")
	)
	(arc
		(start 115.212622 -224.579942)
		(mid 114.969295 -225.044508)
		(end 115.212622 -225.509074)
		(width 0.1143)
		(layer "In11.Cu")
		(net "GMI_CPU1_G3_CPU0_G1_TX_DN<3>")
	)
	(arc
		(start 116.008912 -233.464862)
		(mid 116.074264 -233.543389)
		(end 116.152676 -233.60888)
		(width 0.1143)
		(layer "In11.Cu")
		(net "GMI_CPU1_G3_CPU0_G1_TX_DN<3>")
	)
	(arc
		(start 356.212394 -224.53854)
		(mid 356.056466 -224.234248)
		(end 356.212394 -223.929956)
		(width 0.1143)
		(layer "In11.Cu")
		(net "GMI_CPU1_G3_CPU0_G1_TX_DN<3>")
	)
	(arc
		(start 354.653342 -234.694222)
		(mid 354.705391 -234.562703)
		(end 354.80244 -234.45978)
		(width 0.1143)
		(layer "In11.Cu")
		(net "GMI_CPU1_G3_CPU0_G1_TX_DN<3>")
	)
	(arc
		(start 355.813106 -232.79862)
		(mid 355.991919 -232.59627)
		(end 356.056438 -232.334054)
		(width 0.1143)
		(layer "In11.Cu")
		(net "GMI_CPU1_G3_CPU0_G1_TX_DN<3>")
	)
	(arc
		(start 116.367052 -233.945176)
		(mid 116.444045 -234.230089)
		(end 116.654072 -234.437428)
		(width 0.1143)
		(layer "In11.Cu")
		(net "GMI_CPU1_G3_CPU0_G1_TX_DN<3>")
	)
	(arc
		(start 356.056438 -232.334054)
		(mid 356.097693 -232.163083)
		(end 356.212394 -232.029762)
		(width 0.1143)
		(layer "In11.Cu")
		(net "GMI_CPU1_G3_CPU0_G1_TX_DN<3>")
	)
	(arc
		(start 115.212622 -227.819966)
		(mid 114.969295 -228.284532)
		(end 115.212622 -228.749098)
		(width 0.1143)
		(layer "In11.Cu")
		(net "GMI_CPU1_G3_CPU0_G1_TX_DN<3>")
	)
	(arc
		(start 356.212394 -222.918528)
		(mid 356.056466 -222.614236)
		(end 356.212394 -222.309944)
		(width 0.1143)
		(layer "In11.Cu")
		(net "GMI_CPU1_G3_CPU0_G1_TX_DN<3>")
	)
	(arc
		(start 115.909344 -233.144314)
		(mid 115.934764 -233.312159)
		(end 116.008912 -233.464862)
		(width 0.1143)
		(layer "In11.Cu")
		(net "GMI_CPU1_G3_CPU0_G1_TX_DN<3>")
	)
	(segment
		(start 357.837994 -232.599992)
		(end 357.371142 -232.334054)
		(width 0.12954)
		(layer "F.Cu")
		(net "GMI_CPU1_G3_CPU0_G1_TX_DN<2>")
	)
	(segment
		(start 113.657888 -232.600246)
		(end 114.12474 -232.334308)
		(width 0.12954)
		(layer "F.Cu")
		(net "GMI_CPU1_G3_CPU0_G1_TX_DN<2>")
	)
	(segment
		(start 114.343434 -224.538794)
		(end 114.313716 -224.555812)
		(width 0.1143)
		(layer "In11.Cu")
		(net "GMI_CPU1_G3_CPU0_G1_TX_DN<2>")
	)
	(segment
		(start 357.184198 -224.556828)
		(end 357.183436 -224.55632)
		(width 0.1143)
		(layer "In11.Cu")
		(net "GMI_CPU1_G3_CPU0_G1_TX_DN<2>")
	)
	(segment
		(start 357.17861 -230.395018)
		(end 357.179372 -230.39451)
		(width 0.1143)
		(layer "In11.Cu")
		(net "GMI_CPU1_G3_CPU0_G1_TX_DN<2>")
	)
	(segment
		(start 357.152448 -223.929956)
		(end 357.182166 -223.912938)
		(width 0.1143)
		(layer "In11.Cu")
		(net "GMI_CPU1_G3_CPU0_G1_TX_DN<2>")
	)
	(segment
		(start 357.466392 -221.489524)
		(end 357.529892 -221.426024)
		(width 0.1143)
		(layer "In11.Cu")
		(net "GMI_CPU1_G3_CPU0_G1_TX_DN<2>")
	)
	(segment
		(start 302.914304 -176.673256)
		(end 165.257734 -175.868838)
		(width 0.14224)
		(layer "In11.Cu")
		(net "GMI_CPU1_G3_CPU0_G1_TX_DN<2>")
	)
	(segment
		(start 357.183436 -230.392224)
		(end 357.184198 -230.391716)
		(width 0.1143)
		(layer "In11.Cu")
		(net "GMI_CPU1_G3_CPU0_G1_TX_DN<2>")
	)
	(segment
		(start 114.311684 -223.911922)
		(end 114.312446 -223.91243)
		(width 0.1143)
		(layer "In11.Cu")
		(net "GMI_CPU1_G3_CPU0_G1_TX_DN<2>")
	)
	(segment
		(start 114.310668 -222.291402)
		(end 114.311684 -222.29191)
		(width 0.1143)
		(layer "In11.Cu")
		(net "GMI_CPU1_G3_CPU0_G1_TX_DN<2>")
	)
	(segment
		(start 114.311938 -230.391716)
		(end 114.311684 -230.39197)
		(width 0.1143)
		(layer "In11.Cu")
		(net "GMI_CPU1_G3_CPU0_G1_TX_DN<2>")
	)
	(segment
		(start 117.430042 -211.163662)
		(end 113.92027 -217.144346)
		(width 0.14224)
		(layer "In11.Cu")
		(net "GMI_CPU1_G3_CPU0_G1_TX_DN<2>")
	)
	(segment
		(start 156.776166 -178.901852)
		(end 117.430042 -211.163662)
		(width 0.14224)
		(layer "In11.Cu")
		(net "GMI_CPU1_G3_CPU0_G1_TX_DN<2>")
	)
	(segment
		(start 114.30889 -223.910144)
		(end 114.311684 -223.911922)
		(width 0.1143)
		(layer "In11.Cu")
		(net "GMI_CPU1_G3_CPU0_G1_TX_DN<2>")
	)
	(segment
		(start 114.311684 -231.036876)
		(end 114.275362 -231.057958)
		(width 0.1143)
		(layer "In11.Cu")
		(net "GMI_CPU1_G3_CPU0_G1_TX_DN<2>")
	)
	(segment
		(start 357.181658 -230.39324)
		(end 357.183436 -230.392224)
		(width 0.1143)
		(layer "In11.Cu")
		(net "GMI_CPU1_G3_CPU0_G1_TX_DN<2>")
	)
	(segment
		(start 114.311684 -225.531934)
		(end 114.312446 -225.532442)
		(width 0.1143)
		(layer "In11.Cu")
		(net "GMI_CPU1_G3_CPU0_G1_TX_DN<2>")
	)
	(segment
		(start 114.311176 -230.391208)
		(end 114.311938 -230.391716)
		(width 0.1143)
		(layer "In11.Cu")
		(net "GMI_CPU1_G3_CPU0_G1_TX_DN<2>")
	)
	(segment
		(start 114.312446 -226.176586)
		(end 114.311684 -226.177094)
		(width 0.1143)
		(layer "In11.Cu")
		(net "GMI_CPU1_G3_CPU0_G1_TX_DN<2>")
	)
	(segment
		(start 114.305588 -222.288354)
		(end 114.308128 -222.289878)
		(width 0.1143)
		(layer "In11.Cu")
		(net "GMI_CPU1_G3_CPU0_G1_TX_DN<2>")
	)
	(segment
		(start 357.182166 -227.795582)
		(end 357.152448 -227.778564)
		(width 0.1143)
		(layer "In11.Cu")
		(net "GMI_CPU1_G3_CPU0_G1_TX_DN<2>")
	)
	(segment
		(start 357.251 -227.839524)
		(end 357.22306 -227.819458)
		(width 0.1143)
		(layer "In11.Cu")
		(net "GMI_CPU1_G3_CPU0_G1_TX_DN<2>")
	)
	(segment
		(start 357.182166 -222.935546)
		(end 357.152448 -222.918528)
		(width 0.1143)
		(layer "In11.Cu")
		(net "GMI_CPU1_G3_CPU0_G1_TX_DN<2>")
	)
	(segment
		(start 357.183436 -228.772212)
		(end 357.184198 -228.771704)
		(width 0.1143)
		(layer "In11.Cu")
		(net "GMI_CPU1_G3_CPU0_G1_TX_DN<2>")
	)
	(segment
		(start 357.575612 -221.071694)
		(end 357.575612 -217.241882)
		(width 0.14224)
		(layer "In11.Cu")
		(net "GMI_CPU1_G3_CPU0_G1_TX_DN<2>")
	)
	(segment
		(start 114.290094 -222.94977)
		(end 114.272822 -222.959676)
		(width 0.1143)
		(layer "In11.Cu")
		(net "GMI_CPU1_G3_CPU0_G1_TX_DN<2>")
	)
	(segment
		(start 113.92027 -217.144346)
		(end 113.92027 -221.071948)
		(width 0.14224)
		(layer "In11.Cu")
		(net "GMI_CPU1_G3_CPU0_G1_TX_DN<2>")
	)
	(segment
		(start 114.345212 -231.017318)
		(end 114.311684 -231.036876)
		(width 0.1143)
		(layer "In11.Cu")
		(net "GMI_CPU1_G3_CPU0_G1_TX_DN<2>")
	)
	(segment
		(start 357.575612 -221.083124)
		(end 357.575612 -221.071694)
		(width 0.1143)
		(layer "In11.Cu")
		(net "GMI_CPU1_G3_CPU0_G1_TX_DN<2>")
	)
	(segment
		(start 114.311684 -227.151946)
		(end 114.312446 -227.152454)
		(width 0.1143)
		(layer "In11.Cu")
		(net "GMI_CPU1_G3_CPU0_G1_TX_DN<2>")
	)
	(segment
		(start 114.311684 -232.011728)
		(end 114.312446 -232.012236)
		(width 0.1143)
		(layer "In11.Cu")
		(net "GMI_CPU1_G3_CPU0_G1_TX_DN<2>")
	)
	(segment
		(start 165.257734 -175.868838)
		(end 156.776166 -178.901852)
		(width 0.14224)
		(layer "In11.Cu")
		(net "GMI_CPU1_G3_CPU0_G1_TX_DN<2>")
	)
	(segment
		(start 357.201724 -222.945198)
		(end 357.183944 -222.936308)
		(width 0.1143)
		(layer "In11.Cu")
		(net "GMI_CPU1_G3_CPU0_G1_TX_DN<2>")
	)
	(segment
		(start 114.312446 -228.772466)
		(end 114.343434 -228.790246)
		(width 0.1143)
		(layer "In11.Cu")
		(net "GMI_CPU1_G3_CPU0_G1_TX_DN<2>")
	)
	(segment
		(start 357.466392 -221.80423)
		(end 357.466392 -221.489524)
		(width 0.1143)
		(layer "In11.Cu")
		(net "GMI_CPU1_G3_CPU0_G1_TX_DN<2>")
	)
	(segment
		(start 357.22052 -226.197922)
		(end 357.184198 -226.17684)
		(width 0.1143)
		(layer "In11.Cu")
		(net "GMI_CPU1_G3_CPU0_G1_TX_DN<2>")
	)
	(segment
		(start 114.272568 -222.26905)
		(end 114.304064 -222.287338)
		(width 0.1143)
		(layer "In11.Cu")
		(net "GMI_CPU1_G3_CPU0_G1_TX_DN<2>")
	)
	(segment
		(start 357.186738 -222.290132)
		(end 357.187754 -222.289624)
		(width 0.1143)
		(layer "In11.Cu")
		(net "GMI_CPU1_G3_CPU0_G1_TX_DN<2>")
	)
	(segment
		(start 114.311684 -226.177094)
		(end 114.275362 -226.198176)
		(width 0.1143)
		(layer "In11.Cu")
		(net "GMI_CPU1_G3_CPU0_G1_TX_DN<2>")
	)
	(segment
		(start 357.185722 -227.797868)
		(end 357.183436 -227.796344)
		(width 0.1143)
		(layer "In11.Cu")
		(net "GMI_CPU1_G3_CPU0_G1_TX_DN<2>")
	)
	(segment
		(start 353.937824 -211.114386)
		(end 317.807848 -181.489858)
		(width 0.14224)
		(layer "In11.Cu")
		(net "GMI_CPU1_G3_CPU0_G1_TX_DN<2>")
	)
	(segment
		(start 317.807848 -181.489858)
		(end 310.765952 -177.503582)
		(width 0.14224)
		(layer "In11.Cu")
		(net "GMI_CPU1_G3_CPU0_G1_TX_DN<2>")
	)
	(segment
		(start 357.183436 -224.55632)
		(end 357.182166 -224.555558)
		(width 0.1143)
		(layer "In11.Cu")
		(net "GMI_CPU1_G3_CPU0_G1_TX_DN<2>")
	)
	(segment
		(start 357.152448 -225.549968)
		(end 357.182166 -225.53295)
		(width 0.1143)
		(layer "In11.Cu")
		(net "GMI_CPU1_G3_CPU0_G1_TX_DN<2>")
	)
	(segment
		(start 114.492532 -232.264458)
		(end 114.422682 -232.334308)
		(width 0.1143)
		(layer "In11.Cu")
		(net "GMI_CPU1_G3_CPU0_G1_TX_DN<2>")
	)
	(segment
		(start 114.343434 -226.158806)
		(end 114.313716 -226.175824)
		(width 0.1143)
		(layer "In11.Cu")
		(net "GMI_CPU1_G3_CPU0_G1_TX_DN<2>")
	)
	(segment
		(start 357.184198 -222.291656)
		(end 357.185214 -222.291148)
		(width 0.1143)
		(layer "In11.Cu")
		(net "GMI_CPU1_G3_CPU0_G1_TX_DN<2>")
	)
	(segment
		(start 114.275362 -225.510852)
		(end 114.311684 -225.531934)
		(width 0.1143)
		(layer "In11.Cu")
		(net "GMI_CPU1_G3_CPU0_G1_TX_DN<2>")
	)
	(segment
		(start 114.02949 -221.489778)
		(end 114.02949 -221.804484)
		(width 0.1143)
		(layer "In11.Cu")
		(net "GMI_CPU1_G3_CPU0_G1_TX_DN<2>")
	)
	(segment
		(start 357.22306 -228.749098)
		(end 357.251 -228.729032)
		(width 0.1143)
		(layer "In11.Cu")
		(net "GMI_CPU1_G3_CPU0_G1_TX_DN<2>")
	)
	(segment
		(start 357.184198 -225.53168)
		(end 357.22052 -225.510598)
		(width 0.1143)
		(layer "In11.Cu")
		(net "GMI_CPU1_G3_CPU0_G1_TX_DN<2>")
	)
	(segment
		(start 310.765952 -177.503582)
		(end 308.443884 -176.673256)
		(width 0.14224)
		(layer "In11.Cu")
		(net "GMI_CPU1_G3_CPU0_G1_TX_DN<2>")
	)
	(segment
		(start 357.183436 -222.936308)
		(end 357.182166 -222.935546)
		(width 0.1143)
		(layer "In11.Cu")
		(net "GMI_CPU1_G3_CPU0_G1_TX_DN<2>")
	)
	(segment
		(start 357.183436 -223.912176)
		(end 357.184198 -223.911668)
		(width 0.1143)
		(layer "In11.Cu")
		(net "GMI_CPU1_G3_CPU0_G1_TX_DN<2>")
	)
	(segment
		(start 357.183436 -232.011982)
		(end 357.184198 -232.011474)
		(width 0.1143)
		(layer "In11.Cu")
		(net "GMI_CPU1_G3_CPU0_G1_TX_DN<2>")
	)
	(segment
		(start 357.184198 -227.151692)
		(end 357.22052 -227.13061)
		(width 0.1143)
		(layer "In11.Cu")
		(net "GMI_CPU1_G3_CPU0_G1_TX_DN<2>")
	)
	(segment
		(start 357.183944 -222.936308)
		(end 357.183436 -222.936308)
		(width 0.1143)
		(layer "In11.Cu")
		(net "GMI_CPU1_G3_CPU0_G1_TX_DN<2>")
	)
	(segment
		(start 357.251 -222.979488)
		(end 357.22306 -222.959422)
		(width 0.1143)
		(layer "In11.Cu")
		(net "GMI_CPU1_G3_CPU0_G1_TX_DN<2>")
	)
	(segment
		(start 357.182166 -223.912938)
		(end 357.183436 -223.912176)
		(width 0.1143)
		(layer "In11.Cu")
		(net "GMI_CPU1_G3_CPU0_G1_TX_DN<2>")
	)
	(segment
		(start 114.30889 -228.77018)
		(end 114.311684 -228.771958)
		(width 0.1143)
		(layer "In11.Cu")
		(net "GMI_CPU1_G3_CPU0_G1_TX_DN<2>")
	)
	(segment
		(start 357.184198 -223.911668)
		(end 357.186992 -223.90989)
		(width 0.1143)
		(layer "In11.Cu")
		(net "GMI_CPU1_G3_CPU0_G1_TX_DN<2>")
	)
	(segment
		(start 114.313716 -224.555812)
		(end 114.312446 -224.556574)
		(width 0.1143)
		(layer "In11.Cu")
		(net "GMI_CPU1_G3_CPU0_G1_TX_DN<2>")
	)
	(segment
		(start 357.183436 -225.532188)
		(end 357.184198 -225.53168)
		(width 0.1143)
		(layer "In11.Cu")
		(net "GMI_CPU1_G3_CPU0_G1_TX_DN<2>")
	)
	(segment
		(start 114.312446 -225.532442)
		(end 114.343434 -225.550222)
		(width 0.1143)
		(layer "In11.Cu")
		(net "GMI_CPU1_G3_CPU0_G1_TX_DN<2>")
	)
	(segment
		(start 114.312446 -224.556574)
		(end 114.311684 -224.557082)
		(width 0.1143)
		(layer "In11.Cu")
		(net "GMI_CPU1_G3_CPU0_G1_TX_DN<2>")
	)
	(segment
		(start 114.313716 -226.175824)
		(end 114.312446 -226.176586)
		(width 0.1143)
		(layer "In11.Cu")
		(net "GMI_CPU1_G3_CPU0_G1_TX_DN<2>")
	)
	(segment
		(start 114.311938 -222.936562)
		(end 114.294158 -222.945452)
		(width 0.1143)
		(layer "In11.Cu")
		(net "GMI_CPU1_G3_CPU0_G1_TX_DN<2>")
	)
	(segment
		(start 357.182166 -225.53295)
		(end 357.183436 -225.532188)
		(width 0.1143)
		(layer "In11.Cu")
		(net "GMI_CPU1_G3_CPU0_G1_TX_DN<2>")
	)
	(segment
		(start 114.311684 -224.557082)
		(end 114.275362 -224.578164)
		(width 0.1143)
		(layer "In11.Cu")
		(net "GMI_CPU1_G3_CPU0_G1_TX_DN<2>")
	)
	(segment
		(start 357.529892 -221.426024)
		(end 357.529892 -221.128844)
		(width 0.1143)
		(layer "In11.Cu")
		(net "GMI_CPU1_G3_CPU0_G1_TX_DN<2>")
	)
	(segment
		(start 114.313716 -227.795836)
		(end 114.312446 -227.796598)
		(width 0.1143)
		(layer "In11.Cu")
		(net "GMI_CPU1_G3_CPU0_G1_TX_DN<2>")
	)
	(segment
		(start 114.312446 -232.012236)
		(end 114.343434 -232.030016)
		(width 0.1143)
		(layer "In11.Cu")
		(net "GMI_CPU1_G3_CPU0_G1_TX_DN<2>")
	)
	(segment
		(start 357.152448 -222.309944)
		(end 357.184198 -222.291656)
		(width 0.1143)
		(layer "In11.Cu")
		(net "GMI_CPU1_G3_CPU0_G1_TX_DN<2>")
	)
	(segment
		(start 357.529892 -221.128844)
		(end 357.575612 -221.083124)
		(width 0.1143)
		(layer "In11.Cu")
		(net "GMI_CPU1_G3_CPU0_G1_TX_DN<2>")
	)
	(segment
		(start 357.185214 -222.291148)
		(end 357.186738 -222.290132)
		(width 0.1143)
		(layer "In11.Cu")
		(net "GMI_CPU1_G3_CPU0_G1_TX_DN<2>")
	)
	(segment
		(start 357.183436 -226.176332)
		(end 357.182166 -226.17557)
		(width 0.1143)
		(layer "In11.Cu")
		(net "GMI_CPU1_G3_CPU0_G1_TX_DN<2>")
	)
	(segment
		(start 114.304064 -222.287338)
		(end 114.305588 -222.288354)
		(width 0.1143)
		(layer "In11.Cu")
		(net "GMI_CPU1_G3_CPU0_G1_TX_DN<2>")
	)
	(segment
		(start 113.96599 -221.129098)
		(end 113.96599 -221.426278)
		(width 0.1143)
		(layer "In11.Cu")
		(net "GMI_CPU1_G3_CPU0_G1_TX_DN<2>")
	)
	(segment
		(start 357.184198 -228.771704)
		(end 357.186992 -228.769926)
		(width 0.1143)
		(layer "In11.Cu")
		(net "GMI_CPU1_G3_CPU0_G1_TX_DN<2>")
	)
	(segment
		(start 114.244882 -223.86925)
		(end 114.272822 -223.889316)
		(width 0.1143)
		(layer "In11.Cu")
		(net "GMI_CPU1_G3_CPU0_G1_TX_DN<2>")
	)
	(segment
		(start 357.22052 -224.57791)
		(end 357.184198 -224.556828)
		(width 0.1143)
		(layer "In11.Cu")
		(net "GMI_CPU1_G3_CPU0_G1_TX_DN<2>")
	)
	(segment
		(start 357.186992 -223.90989)
		(end 357.22306 -223.889062)
		(width 0.1143)
		(layer "In11.Cu")
		(net "GMI_CPU1_G3_CPU0_G1_TX_DN<2>")
	)
	(segment
		(start 114.294158 -222.945452)
		(end 114.290094 -222.94977)
		(width 0.1143)
		(layer "In11.Cu")
		(net "GMI_CPU1_G3_CPU0_G1_TX_DN<2>")
	)
	(segment
		(start 357.186992 -228.769926)
		(end 357.22306 -228.749098)
		(width 0.1143)
		(layer "In11.Cu")
		(net "GMI_CPU1_G3_CPU0_G1_TX_DN<2>")
	)
	(segment
		(start 114.272822 -223.889316)
		(end 114.30889 -223.910144)
		(width 0.1143)
		(layer "In11.Cu")
		(net "GMI_CPU1_G3_CPU0_G1_TX_DN<2>")
	)
	(segment
		(start 357.182166 -224.555558)
		(end 357.152448 -224.53854)
		(width 0.1143)
		(layer "In11.Cu")
		(net "GMI_CPU1_G3_CPU0_G1_TX_DN<2>")
	)
	(segment
		(start 357.177594 -230.395526)
		(end 357.17861 -230.395018)
		(width 0.1143)
		(layer "In11.Cu")
		(net "GMI_CPU1_G3_CPU0_G1_TX_DN<2>")
	)
	(segment
		(start 357.183436 -227.796344)
		(end 357.182166 -227.795582)
		(width 0.1143)
		(layer "In11.Cu")
		(net "GMI_CPU1_G3_CPU0_G1_TX_DN<2>")
	)
	(segment
		(start 357.182166 -232.012744)
		(end 357.183436 -232.011982)
		(width 0.1143)
		(layer "In11.Cu")
		(net "GMI_CPU1_G3_CPU0_G1_TX_DN<2>")
	)
	(segment
		(start 357.184198 -231.036622)
		(end 357.15067 -231.017064)
		(width 0.1143)
		(layer "In11.Cu")
		(net "GMI_CPU1_G3_CPU0_G1_TX_DN<2>")
	)
	(segment
		(start 357.22306 -227.819458)
		(end 357.185722 -227.797868)
		(width 0.1143)
		(layer "In11.Cu")
		(net "GMI_CPU1_G3_CPU0_G1_TX_DN<2>")
	)
	(segment
		(start 357.182166 -226.17557)
		(end 357.152448 -226.158552)
		(width 0.1143)
		(layer "In11.Cu")
		(net "GMI_CPU1_G3_CPU0_G1_TX_DN<2>")
	)
	(segment
		(start 113.92027 -221.071948)
		(end 113.92027 -221.083378)
		(width 0.1143)
		(layer "In11.Cu")
		(net "GMI_CPU1_G3_CPU0_G1_TX_DN<2>")
	)
	(segment
		(start 114.312446 -230.392478)
		(end 114.343434 -230.410258)
		(width 0.1143)
		(layer "In11.Cu")
		(net "GMI_CPU1_G3_CPU0_G1_TX_DN<2>")
	)
	(segment
		(start 114.244882 -228.729286)
		(end 114.272822 -228.749352)
		(width 0.1143)
		(layer "In11.Cu")
		(net "GMI_CPU1_G3_CPU0_G1_TX_DN<2>")
	)
	(segment
		(start 114.345212 -229.397306)
		(end 114.311684 -229.416864)
		(width 0.1143)
		(layer "In11.Cu")
		(net "GMI_CPU1_G3_CPU0_G1_TX_DN<2>")
	)
	(segment
		(start 114.311684 -222.29191)
		(end 114.343434 -222.310198)
		(width 0.1143)
		(layer "In11.Cu")
		(net "GMI_CPU1_G3_CPU0_G1_TX_DN<2>")
	)
	(segment
		(start 114.275362 -227.130864)
		(end 114.311684 -227.151946)
		(width 0.1143)
		(layer "In11.Cu")
		(net "GMI_CPU1_G3_CPU0_G1_TX_DN<2>")
	)
	(segment
		(start 357.152448 -227.16998)
		(end 357.182166 -227.152962)
		(width 0.1143)
		(layer "In11.Cu")
		(net "GMI_CPU1_G3_CPU0_G1_TX_DN<2>")
	)
	(segment
		(start 114.312446 -222.936562)
		(end 114.311938 -222.936562)
		(width 0.1143)
		(layer "In11.Cu")
		(net "GMI_CPU1_G3_CPU0_G1_TX_DN<2>")
	)
	(segment
		(start 357.183944 -230.391462)
		(end 357.184706 -230.390954)
		(width 0.1143)
		(layer "In11.Cu")
		(net "GMI_CPU1_G3_CPU0_G1_TX_DN<2>")
	)
	(segment
		(start 114.31016 -227.798122)
		(end 114.272822 -227.819712)
		(width 0.1143)
		(layer "In11.Cu")
		(net "GMI_CPU1_G3_CPU0_G1_TX_DN<2>")
	)
	(segment
		(start 357.152448 -230.410004)
		(end 357.177594 -230.395526)
		(width 0.1143)
		(layer "In11.Cu")
		(net "GMI_CPU1_G3_CPU0_G1_TX_DN<2>")
	)
	(segment
		(start 114.311684 -229.416864)
		(end 114.275362 -229.437946)
		(width 0.1143)
		(layer "In11.Cu")
		(net "GMI_CPU1_G3_CPU0_G1_TX_DN<2>")
	)
	(segment
		(start 114.422682 -232.334308)
		(end 114.12474 -232.334308)
		(width 0.1143)
		(layer "In11.Cu")
		(net "GMI_CPU1_G3_CPU0_G1_TX_DN<2>")
	)
	(segment
		(start 114.311684 -228.771958)
		(end 114.312446 -228.772466)
		(width 0.1143)
		(layer "In11.Cu")
		(net "GMI_CPU1_G3_CPU0_G1_TX_DN<2>")
	)
	(segment
		(start 357.184198 -229.41661)
		(end 357.15067 -229.397052)
		(width 0.1143)
		(layer "In11.Cu")
		(net "GMI_CPU1_G3_CPU0_G1_TX_DN<2>")
	)
	(segment
		(start 114.312446 -223.91243)
		(end 114.343434 -223.93021)
		(width 0.1143)
		(layer "In11.Cu")
		(net "GMI_CPU1_G3_CPU0_G1_TX_DN<2>")
	)
	(segment
		(start 114.272822 -228.749352)
		(end 114.30889 -228.77018)
		(width 0.1143)
		(layer "In11.Cu")
		(net "GMI_CPU1_G3_CPU0_G1_TX_DN<2>")
	)
	(segment
		(start 114.343434 -227.778818)
		(end 114.313716 -227.795836)
		(width 0.1143)
		(layer "In11.Cu")
		(net "GMI_CPU1_G3_CPU0_G1_TX_DN<2>")
	)
	(segment
		(start 114.309144 -222.290386)
		(end 114.310668 -222.291402)
		(width 0.1143)
		(layer "In11.Cu")
		(net "GMI_CPU1_G3_CPU0_G1_TX_DN<2>")
	)
	(segment
		(start 357.22306 -223.889062)
		(end 357.251 -223.868996)
		(width 0.1143)
		(layer "In11.Cu")
		(net "GMI_CPU1_G3_CPU0_G1_TX_DN<2>")
	)
	(segment
		(start 114.308128 -222.289878)
		(end 114.309144 -222.290386)
		(width 0.1143)
		(layer "In11.Cu")
		(net "GMI_CPU1_G3_CPU0_G1_TX_DN<2>")
	)
	(segment
		(start 357.191818 -222.287084)
		(end 357.223314 -222.268796)
		(width 0.1143)
		(layer "In11.Cu")
		(net "GMI_CPU1_G3_CPU0_G1_TX_DN<2>")
	)
	(segment
		(start 114.343434 -222.918782)
		(end 114.313716 -222.9358)
		(width 0.1143)
		(layer "In11.Cu")
		(net "GMI_CPU1_G3_CPU0_G1_TX_DN<2>")
	)
	(segment
		(start 357.190294 -222.2881)
		(end 357.191818 -222.287084)
		(width 0.1143)
		(layer "In11.Cu")
		(net "GMI_CPU1_G3_CPU0_G1_TX_DN<2>")
	)
	(segment
		(start 114.272822 -227.819712)
		(end 114.244882 -227.839778)
		(width 0.1143)
		(layer "In11.Cu")
		(net "GMI_CPU1_G3_CPU0_G1_TX_DN<2>")
	)
	(segment
		(start 114.311684 -230.39197)
		(end 114.312446 -230.392478)
		(width 0.1143)
		(layer "In11.Cu")
		(net "GMI_CPU1_G3_CPU0_G1_TX_DN<2>")
	)
	(segment
		(start 357.152448 -232.029762)
		(end 357.182166 -232.012744)
		(width 0.1143)
		(layer "In11.Cu")
		(net "GMI_CPU1_G3_CPU0_G1_TX_DN<2>")
	)
	(segment
		(start 357.371142 -232.334054)
		(end 357.0732 -232.334054)
		(width 0.1143)
		(layer "In11.Cu")
		(net "GMI_CPU1_G3_CPU0_G1_TX_DN<2>")
	)
	(segment
		(start 357.187754 -222.289624)
		(end 357.190294 -222.2881)
		(width 0.1143)
		(layer "In11.Cu")
		(net "GMI_CPU1_G3_CPU0_G1_TX_DN<2>")
	)
	(segment
		(start 357.183436 -227.1522)
		(end 357.184198 -227.151692)
		(width 0.1143)
		(layer "In11.Cu")
		(net "GMI_CPU1_G3_CPU0_G1_TX_DN<2>")
	)
	(segment
		(start 357.22052 -231.057704)
		(end 357.184198 -231.036622)
		(width 0.1143)
		(layer "In11.Cu")
		(net "GMI_CPU1_G3_CPU0_G1_TX_DN<2>")
	)
	(segment
		(start 357.180896 -230.393748)
		(end 357.181658 -230.39324)
		(width 0.1143)
		(layer "In11.Cu")
		(net "GMI_CPU1_G3_CPU0_G1_TX_DN<2>")
	)
	(segment
		(start 357.184198 -226.17684)
		(end 357.183436 -226.176332)
		(width 0.1143)
		(layer "In11.Cu")
		(net "GMI_CPU1_G3_CPU0_G1_TX_DN<2>")
	)
	(segment
		(start 113.92027 -221.083378)
		(end 113.96599 -221.129098)
		(width 0.1143)
		(layer "In11.Cu")
		(net "GMI_CPU1_G3_CPU0_G1_TX_DN<2>")
	)
	(segment
		(start 357.182166 -227.152962)
		(end 357.183436 -227.1522)
		(width 0.1143)
		(layer "In11.Cu")
		(net "GMI_CPU1_G3_CPU0_G1_TX_DN<2>")
	)
	(segment
		(start 357.205788 -222.949516)
		(end 357.201724 -222.945198)
		(width 0.1143)
		(layer "In11.Cu")
		(net "GMI_CPU1_G3_CPU0_G1_TX_DN<2>")
	)
	(segment
		(start 113.96599 -221.426278)
		(end 114.02949 -221.489778)
		(width 0.1143)
		(layer "In11.Cu")
		(net "GMI_CPU1_G3_CPU0_G1_TX_DN<2>")
	)
	(segment
		(start 357.22306 -222.959422)
		(end 357.205788 -222.949516)
		(width 0.1143)
		(layer "In11.Cu")
		(net "GMI_CPU1_G3_CPU0_G1_TX_DN<2>")
	)
	(segment
		(start 357.0732 -232.334054)
		(end 357.00335 -232.264204)
		(width 0.1143)
		(layer "In11.Cu")
		(net "GMI_CPU1_G3_CPU0_G1_TX_DN<2>")
	)
	(segment
		(start 114.312446 -227.796598)
		(end 114.31016 -227.798122)
		(width 0.1143)
		(layer "In11.Cu")
		(net "GMI_CPU1_G3_CPU0_G1_TX_DN<2>")
	)
	(segment
		(start 357.179372 -230.39451)
		(end 357.180896 -230.393748)
		(width 0.1143)
		(layer "In11.Cu")
		(net "GMI_CPU1_G3_CPU0_G1_TX_DN<2>")
	)
	(segment
		(start 357.575612 -217.241882)
		(end 353.937824 -211.114386)
		(width 0.14224)
		(layer "In11.Cu")
		(net "GMI_CPU1_G3_CPU0_G1_TX_DN<2>")
	)
	(segment
		(start 114.313716 -222.9358)
		(end 114.312446 -222.936562)
		(width 0.1143)
		(layer "In11.Cu")
		(net "GMI_CPU1_G3_CPU0_G1_TX_DN<2>")
	)
	(segment
		(start 114.272822 -222.959676)
		(end 114.244882 -222.979742)
		(width 0.1143)
		(layer "In11.Cu")
		(net "GMI_CPU1_G3_CPU0_G1_TX_DN<2>")
	)
	(segment
		(start 357.22052 -229.437692)
		(end 357.184198 -229.41661)
		(width 0.1143)
		(layer "In11.Cu")
		(net "GMI_CPU1_G3_CPU0_G1_TX_DN<2>")
	)
	(segment
		(start 114.312446 -227.152454)
		(end 114.343434 -227.170234)
		(width 0.1143)
		(layer "In11.Cu")
		(net "GMI_CPU1_G3_CPU0_G1_TX_DN<2>")
	)
	(segment
		(start 357.182166 -228.772974)
		(end 357.183436 -228.772212)
		(width 0.1143)
		(layer "In11.Cu")
		(net "GMI_CPU1_G3_CPU0_G1_TX_DN<2>")
	)
	(segment
		(start 308.443884 -176.673256)
		(end 302.914304 -176.673256)
		(width 0.14224)
		(layer "In11.Cu")
		(net "GMI_CPU1_G3_CPU0_G1_TX_DN<2>")
	)
	(segment
		(start 357.184198 -230.391716)
		(end 357.183944 -230.391462)
		(width 0.1143)
		(layer "In11.Cu")
		(net "GMI_CPU1_G3_CPU0_G1_TX_DN<2>")
	)
	(segment
		(start 357.152448 -228.789992)
		(end 357.182166 -228.772974)
		(width 0.1143)
		(layer "In11.Cu")
		(net "GMI_CPU1_G3_CPU0_G1_TX_DN<2>")
	)
	(arc
		(start 114.49939 -230.71455)
		(mid 114.458628 -230.884434)
		(end 114.345212 -231.017318)
		(width 0.1143)
		(layer "In11.Cu")
		(net "GMI_CPU1_G3_CPU0_G1_TX_DN<2>")
	)
	(arc
		(start 357.184706 -230.390954)
		(mid 357.390928 -230.18531)
		(end 357.466392 -229.904036)
		(width 0.1143)
		(layer "In11.Cu")
		(net "GMI_CPU1_G3_CPU0_G1_TX_DN<2>")
	)
	(arc
		(start 357.152448 -222.918528)
		(mid 356.99652 -222.614236)
		(end 357.152448 -222.309944)
		(width 0.1143)
		(layer "In11.Cu")
		(net "GMI_CPU1_G3_CPU0_G1_TX_DN<2>")
	)
	(arc
		(start 357.236776 -226.209352)
		(mid 357.228698 -226.203566)
		(end 357.22052 -226.197922)
		(width 0.1143)
		(layer "In11.Cu")
		(net "GMI_CPU1_G3_CPU0_G1_TX_DN<2>")
	)
	(arc
		(start 114.343434 -225.550222)
		(mid 114.499362 -225.854514)
		(end 114.343434 -226.158806)
		(width 0.1143)
		(layer "In11.Cu")
		(net "GMI_CPU1_G3_CPU0_G1_TX_DN<2>")
	)
	(arc
		(start 114.275362 -226.198176)
		(mid 114.267184 -226.203819)
		(end 114.259106 -226.209606)
		(width 0.1143)
		(layer "In11.Cu")
		(net "GMI_CPU1_G3_CPU0_G1_TX_DN<2>")
	)
	(arc
		(start 357.15067 -231.017064)
		(mid 357.037263 -230.884175)
		(end 356.996492 -230.714296)
		(width 0.1143)
		(layer "In11.Cu")
		(net "GMI_CPU1_G3_CPU0_G1_TX_DN<2>")
	)
	(arc
		(start 356.996492 -229.094284)
		(mid 357.037747 -228.923313)
		(end 357.152448 -228.789992)
		(width 0.1143)
		(layer "In11.Cu")
		(net "GMI_CPU1_G3_CPU0_G1_TX_DN<2>")
	)
	(arc
		(start 357.22052 -225.510598)
		(mid 357.228698 -225.504955)
		(end 357.236776 -225.499168)
		(width 0.1143)
		(layer "In11.Cu")
		(net "GMI_CPU1_G3_CPU0_G1_TX_DN<2>")
	)
	(arc
		(start 357.251 -223.868996)
		(mid 357.479 -223.424242)
		(end 357.251 -222.979488)
		(width 0.1143)
		(layer "In11.Cu")
		(net "GMI_CPU1_G3_CPU0_G1_TX_DN<2>")
	)
	(arc
		(start 356.996492 -230.714296)
		(mid 357.037747 -230.543325)
		(end 357.152448 -230.410004)
		(width 0.1143)
		(layer "In11.Cu")
		(net "GMI_CPU1_G3_CPU0_G1_TX_DN<2>")
	)
	(arc
		(start 357.466392 -231.524048)
		(mid 357.401156 -231.260457)
		(end 357.22052 -231.057704)
		(width 0.1143)
		(layer "In11.Cu")
		(net "GMI_CPU1_G3_CPU0_G1_TX_DN<2>")
	)
	(arc
		(start 114.02949 -231.524302)
		(mid 114.105071 -231.805944)
		(end 114.311684 -232.011728)
		(width 0.1143)
		(layer "In11.Cu")
		(net "GMI_CPU1_G3_CPU0_G1_TX_DN<2>")
	)
	(arc
		(start 114.275362 -229.437946)
		(mid 114.09471 -229.640691)
		(end 114.02949 -229.90429)
		(width 0.1143)
		(layer "In11.Cu")
		(net "GMI_CPU1_G3_CPU0_G1_TX_DN<2>")
	)
	(arc
		(start 114.343434 -222.310198)
		(mid 114.499362 -222.61449)
		(end 114.343434 -222.918782)
		(width 0.1143)
		(layer "In11.Cu")
		(net "GMI_CPU1_G3_CPU0_G1_TX_DN<2>")
	)
	(arc
		(start 357.22052 -227.13061)
		(mid 357.228698 -227.124967)
		(end 357.236776 -227.11918)
		(width 0.1143)
		(layer "In11.Cu")
		(net "GMI_CPU1_G3_CPU0_G1_TX_DN<2>")
	)
	(arc
		(start 114.343434 -227.170234)
		(mid 114.499362 -227.474526)
		(end 114.343434 -227.778818)
		(width 0.1143)
		(layer "In11.Cu")
		(net "GMI_CPU1_G3_CPU0_G1_TX_DN<2>")
	)
	(arc
		(start 114.343434 -223.93021)
		(mid 114.499362 -224.234502)
		(end 114.343434 -224.538794)
		(width 0.1143)
		(layer "In11.Cu")
		(net "GMI_CPU1_G3_CPU0_G1_TX_DN<2>")
	)
	(arc
		(start 357.236776 -224.58934)
		(mid 357.228698 -224.583554)
		(end 357.22052 -224.57791)
		(width 0.1143)
		(layer "In11.Cu")
		(net "GMI_CPU1_G3_CPU0_G1_TX_DN<2>")
	)
	(arc
		(start 357.357172 -222.138748)
		(mid 357.438463 -221.980201)
		(end 357.466392 -221.80423)
		(width 0.1143)
		(layer "In11.Cu")
		(net "GMI_CPU1_G3_CPU0_G1_TX_DN<2>")
	)
	(arc
		(start 114.343434 -232.030016)
		(mid 114.440569 -232.132885)
		(end 114.492532 -232.264458)
		(width 0.1143)
		(layer "In11.Cu")
		(net "GMI_CPU1_G3_CPU0_G1_TX_DN<2>")
	)
	(arc
		(start 357.00335 -232.264204)
		(mid 357.055399 -232.132685)
		(end 357.152448 -232.029762)
		(width 0.1143)
		(layer "In11.Cu")
		(net "GMI_CPU1_G3_CPU0_G1_TX_DN<2>")
	)
	(arc
		(start 114.13871 -222.139002)
		(mid 114.200229 -222.209596)
		(end 114.272568 -222.26905)
		(width 0.1143)
		(layer "In11.Cu")
		(net "GMI_CPU1_G3_CPU0_G1_TX_DN<2>")
	)
	(arc
		(start 114.02949 -229.90429)
		(mid 114.104992 -230.185542)
		(end 114.311176 -230.391208)
		(width 0.1143)
		(layer "In11.Cu")
		(net "GMI_CPU1_G3_CPU0_G1_TX_DN<2>")
	)
	(arc
		(start 357.152448 -224.53854)
		(mid 356.99652 -224.234248)
		(end 357.152448 -223.929956)
		(width 0.1143)
		(layer "In11.Cu")
		(net "GMI_CPU1_G3_CPU0_G1_TX_DN<2>")
	)
	(arc
		(start 357.236776 -225.499168)
		(mid 357.45966 -225.044254)
		(end 357.236776 -224.58934)
		(width 0.1143)
		(layer "In11.Cu")
		(net "GMI_CPU1_G3_CPU0_G1_TX_DN<2>")
	)
	(arc
		(start 114.259106 -226.209606)
		(mid 114.036222 -226.66452)
		(end 114.259106 -227.119434)
		(width 0.1143)
		(layer "In11.Cu")
		(net "GMI_CPU1_G3_CPU0_G1_TX_DN<2>")
	)
	(arc
		(start 357.152448 -226.158552)
		(mid 356.99652 -225.85426)
		(end 357.152448 -225.549968)
		(width 0.1143)
		(layer "In11.Cu")
		(net "GMI_CPU1_G3_CPU0_G1_TX_DN<2>")
	)
	(arc
		(start 114.275362 -231.057958)
		(mid 114.09471 -231.260703)
		(end 114.02949 -231.524302)
		(width 0.1143)
		(layer "In11.Cu")
		(net "GMI_CPU1_G3_CPU0_G1_TX_DN<2>")
	)
	(arc
		(start 114.259106 -227.119434)
		(mid 114.267184 -227.12522)
		(end 114.275362 -227.130864)
		(width 0.1143)
		(layer "In11.Cu")
		(net "GMI_CPU1_G3_CPU0_G1_TX_DN<2>")
	)
	(arc
		(start 114.343434 -228.790246)
		(mid 114.45811 -228.92358)
		(end 114.49939 -229.094538)
		(width 0.1143)
		(layer "In11.Cu")
		(net "GMI_CPU1_G3_CPU0_G1_TX_DN<2>")
	)
	(arc
		(start 357.184198 -232.011474)
		(mid 357.390821 -231.805695)
		(end 357.466392 -231.524048)
		(width 0.1143)
		(layer "In11.Cu")
		(net "GMI_CPU1_G3_CPU0_G1_TX_DN<2>")
	)
	(arc
		(start 357.251 -228.729032)
		(mid 357.479 -228.284278)
		(end 357.251 -227.839524)
		(width 0.1143)
		(layer "In11.Cu")
		(net "GMI_CPU1_G3_CPU0_G1_TX_DN<2>")
	)
	(arc
		(start 357.152448 -227.778564)
		(mid 356.99652 -227.474272)
		(end 357.152448 -227.16998)
		(width 0.1143)
		(layer "In11.Cu")
		(net "GMI_CPU1_G3_CPU0_G1_TX_DN<2>")
	)
	(arc
		(start 357.236776 -227.11918)
		(mid 357.45966 -226.664266)
		(end 357.236776 -226.209352)
		(width 0.1143)
		(layer "In11.Cu")
		(net "GMI_CPU1_G3_CPU0_G1_TX_DN<2>")
	)
	(arc
		(start 114.275362 -224.578164)
		(mid 114.267184 -224.583807)
		(end 114.259106 -224.589594)
		(width 0.1143)
		(layer "In11.Cu")
		(net "GMI_CPU1_G3_CPU0_G1_TX_DN<2>")
	)
	(arc
		(start 114.259106 -225.499422)
		(mid 114.267184 -225.505208)
		(end 114.275362 -225.510852)
		(width 0.1143)
		(layer "In11.Cu")
		(net "GMI_CPU1_G3_CPU0_G1_TX_DN<2>")
	)
	(arc
		(start 357.466392 -229.904036)
		(mid 357.401156 -229.640445)
		(end 357.22052 -229.437692)
		(width 0.1143)
		(layer "In11.Cu")
		(net "GMI_CPU1_G3_CPU0_G1_TX_DN<2>")
	)
	(arc
		(start 357.223314 -222.268796)
		(mid 357.295641 -222.209329)
		(end 357.357172 -222.138748)
		(width 0.1143)
		(layer "In11.Cu")
		(net "GMI_CPU1_G3_CPU0_G1_TX_DN<2>")
	)
	(arc
		(start 114.244882 -222.979742)
		(mid 114.016882 -223.424496)
		(end 114.244882 -223.86925)
		(width 0.1143)
		(layer "In11.Cu")
		(net "GMI_CPU1_G3_CPU0_G1_TX_DN<2>")
	)
	(arc
		(start 114.02949 -221.804484)
		(mid 114.057406 -221.98046)
		(end 114.13871 -222.139002)
		(width 0.1143)
		(layer "In11.Cu")
		(net "GMI_CPU1_G3_CPU0_G1_TX_DN<2>")
	)
	(arc
		(start 114.259106 -224.589594)
		(mid 114.036222 -225.044508)
		(end 114.259106 -225.499422)
		(width 0.1143)
		(layer "In11.Cu")
		(net "GMI_CPU1_G3_CPU0_G1_TX_DN<2>")
	)
	(arc
		(start 357.15067 -229.397052)
		(mid 357.037263 -229.264163)
		(end 356.996492 -229.094284)
		(width 0.1143)
		(layer "In11.Cu")
		(net "GMI_CPU1_G3_CPU0_G1_TX_DN<2>")
	)
	(arc
		(start 114.49939 -229.094538)
		(mid 114.458628 -229.264422)
		(end 114.345212 -229.397306)
		(width 0.1143)
		(layer "In11.Cu")
		(net "GMI_CPU1_G3_CPU0_G1_TX_DN<2>")
	)
	(arc
		(start 114.343434 -230.410258)
		(mid 114.45811 -230.543592)
		(end 114.49939 -230.71455)
		(width 0.1143)
		(layer "In11.Cu")
		(net "GMI_CPU1_G3_CPU0_G1_TX_DN<2>")
	)
	(arc
		(start 114.244882 -227.839778)
		(mid 114.016882 -228.284532)
		(end 114.244882 -228.729286)
		(width 0.1143)
		(layer "In11.Cu")
		(net "GMI_CPU1_G3_CPU0_G1_TX_DN<2>")
	)
	(segment
		(start 357.837994 -234.220004)
		(end 357.371142 -233.954066)
		(width 0.12954)
		(layer "F.Cu")
		(net "GMI_CPU1_G3_CPU0_G1_TX_DN<1>")
	)
	(segment
		(start 113.657888 -234.220258)
		(end 114.12474 -233.95432)
		(width 0.12954)
		(layer "F.Cu")
		(net "GMI_CPU1_G3_CPU0_G1_TX_DN<1>")
	)
	(segment
		(start 114.422682 -233.95432)
		(end 114.12474 -233.95432)
		(width 0.1143)
		(layer "In11.Cu")
		(net "GMI_CPU1_G3_CPU0_G1_TX_DN<1>")
	)
	(segment
		(start 113.089436 -231.524302)
		(end 113.08969 -231.524302)
		(width 0.1143)
		(layer "In11.Cu")
		(net "GMI_CPU1_G3_CPU0_G1_TX_DN<1>")
	)
	(segment
		(start 113.402364 -226.159314)
		(end 113.371884 -226.177094)
		(width 0.1143)
		(layer "In11.Cu")
		(net "GMI_CPU1_G3_CPU0_G1_TX_DN<1>")
	)
	(segment
		(start 358.46512 -221.128844)
		(end 358.51084 -221.083124)
		(width 0.1143)
		(layer "In11.Cu")
		(net "GMI_CPU1_G3_CPU0_G1_TX_DN<1>")
	)
	(segment
		(start 358.093518 -225.54946)
		(end 358.163114 -225.50882)
		(width 0.1143)
		(layer "In11.Cu")
		(net "GMI_CPU1_G3_CPU0_G1_TX_DN<1>")
	)
	(segment
		(start 358.093518 -230.409496)
		(end 358.160574 -230.37038)
		(width 0.1143)
		(layer "In11.Cu")
		(net "GMI_CPU1_G3_CPU0_G1_TX_DN<1>")
	)
	(segment
		(start 358.093518 -223.929448)
		(end 358.163114 -223.888808)
		(width 0.1143)
		(layer "In11.Cu")
		(net "GMI_CPU1_G3_CPU0_G1_TX_DN<1>")
	)
	(segment
		(start 113.371884 -223.911922)
		(end 113.402364 -223.929702)
		(width 0.1143)
		(layer "In11.Cu")
		(net "GMI_CPU1_G3_CPU0_G1_TX_DN<1>")
	)
	(segment
		(start 113.371884 -222.93707)
		(end 113.332768 -222.95993)
		(width 0.1143)
		(layer "In11.Cu")
		(net "GMI_CPU1_G3_CPU0_G1_TX_DN<1>")
	)
	(segment
		(start 357.654098 -232.82148)
		(end 357.693214 -232.79862)
		(width 0.1143)
		(layer "In11.Cu")
		(net "GMI_CPU1_G3_CPU0_G1_TX_DN<1>")
	)
	(segment
		(start 113.802668 -232.798874)
		(end 113.841784 -232.821734)
		(width 0.1143)
		(layer "In11.Cu")
		(net "GMI_CPU1_G3_CPU0_G1_TX_DN<1>")
	)
	(segment
		(start 358.51084 -221.071694)
		(end 358.51084 -216.728548)
		(width 0.14224)
		(layer "In11.Cu")
		(net "GMI_CPU1_G3_CPU0_G1_TX_DN<1>")
	)
	(segment
		(start 113.402364 -222.91929)
		(end 113.371884 -222.93707)
		(width 0.1143)
		(layer "In11.Cu")
		(net "GMI_CPU1_G3_CPU0_G1_TX_DN<1>")
	)
	(segment
		(start 357.622348 -232.839768)
		(end 357.654098 -232.82148)
		(width 0.1143)
		(layer "In11.Cu")
		(net "GMI_CPU1_G3_CPU0_G1_TX_DN<1>")
	)
	(segment
		(start 114.492532 -233.88447)
		(end 114.422682 -233.95432)
		(width 0.1143)
		(layer "In11.Cu")
		(net "GMI_CPU1_G3_CPU0_G1_TX_DN<1>")
	)
	(segment
		(start 116.397278 -210.798156)
		(end 112.985042 -216.606882)
		(width 0.14224)
		(layer "In11.Cu")
		(net "GMI_CPU1_G3_CPU0_G1_TX_DN<1>")
	)
	(segment
		(start 358.406446 -221.484698)
		(end 358.46512 -221.426024)
		(width 0.1143)
		(layer "In11.Cu")
		(net "GMI_CPU1_G3_CPU0_G1_TX_DN<1>")
	)
	(segment
		(start 114.275362 -233.610658)
		(end 114.311684 -233.63174)
		(width 0.1143)
		(layer "In11.Cu")
		(net "GMI_CPU1_G3_CPU0_G1_TX_DN<1>")
	)
	(segment
		(start 112.985042 -221.071948)
		(end 112.985042 -221.083378)
		(width 0.1143)
		(layer "In11.Cu")
		(net "GMI_CPU1_G3_CPU0_G1_TX_DN<1>")
	)
	(segment
		(start 358.163114 -224.579688)
		(end 358.093518 -224.539048)
		(width 0.1143)
		(layer "In11.Cu")
		(net "GMI_CPU1_G3_CPU0_G1_TX_DN<1>")
	)
	(segment
		(start 113.332768 -225.509074)
		(end 113.371884 -225.531934)
		(width 0.1143)
		(layer "In11.Cu")
		(net "GMI_CPU1_G3_CPU0_G1_TX_DN<1>")
	)
	(segment
		(start 358.163114 -231.059482)
		(end 358.123998 -231.036622)
		(width 0.1143)
		(layer "In11.Cu")
		(net "GMI_CPU1_G3_CPU0_G1_TX_DN<1>")
	)
	(segment
		(start 113.030762 -221.426278)
		(end 113.089436 -221.484952)
		(width 0.1143)
		(layer "In11.Cu")
		(net "GMI_CPU1_G3_CPU0_G1_TX_DN<1>")
	)
	(segment
		(start 113.332768 -223.889062)
		(end 113.371884 -223.911922)
		(width 0.1143)
		(layer "In11.Cu")
		(net "GMI_CPU1_G3_CPU0_G1_TX_DN<1>")
	)
	(segment
		(start 358.46512 -221.426024)
		(end 358.46512 -221.128844)
		(width 0.1143)
		(layer "In11.Cu")
		(net "GMI_CPU1_G3_CPU0_G1_TX_DN<1>")
	)
	(segment
		(start 358.51084 -221.083124)
		(end 358.51084 -221.071694)
		(width 0.1143)
		(layer "In11.Cu")
		(net "GMI_CPU1_G3_CPU0_G1_TX_DN<1>")
	)
	(segment
		(start 357.152448 -233.649774)
		(end 357.182166 -233.632756)
		(width 0.1143)
		(layer "In11.Cu")
		(net "GMI_CPU1_G3_CPU0_G1_TX_DN<1>")
	)
	(segment
		(start 308.619652 -175.740822)
		(end 302.917352 -175.740822)
		(width 0.14224)
		(layer "In11.Cu")
		(net "GMI_CPU1_G3_CPU0_G1_TX_DN<1>")
	)
	(segment
		(start 358.125268 -222.291148)
		(end 358.126792 -222.290132)
		(width 0.1143)
		(layer "In11.Cu")
		(net "GMI_CPU1_G3_CPU0_G1_TX_DN<1>")
	)
	(segment
		(start 358.127808 -222.289624)
		(end 358.131364 -222.287592)
		(width 0.1143)
		(layer "In11.Cu")
		(net "GMI_CPU1_G3_CPU0_G1_TX_DN<1>")
	)
	(segment
		(start 112.985042 -216.606882)
		(end 112.985042 -221.071948)
		(width 0.14224)
		(layer "In11.Cu")
		(net "GMI_CPU1_G3_CPU0_G1_TX_DN<1>")
	)
	(segment
		(start 113.371884 -227.151946)
		(end 113.402364 -227.169726)
		(width 0.1143)
		(layer "In11.Cu")
		(net "GMI_CPU1_G3_CPU0_G1_TX_DN<1>")
	)
	(segment
		(start 358.092502 -222.309944)
		(end 358.124252 -222.291656)
		(width 0.1143)
		(layer "In11.Cu")
		(net "GMI_CPU1_G3_CPU0_G1_TX_DN<1>")
	)
	(segment
		(start 358.51084 -216.728548)
		(end 358.281224 -216.34196)
		(width 0.14224)
		(layer "In11.Cu")
		(net "GMI_CPU1_G3_CPU0_G1_TX_DN<1>")
	)
	(segment
		(start 358.131364 -222.287592)
		(end 358.132126 -222.287084)
		(width 0.1143)
		(layer "In11.Cu")
		(net "GMI_CPU1_G3_CPU0_G1_TX_DN<1>")
	)
	(segment
		(start 113.402364 -224.539302)
		(end 113.371884 -224.557082)
		(width 0.1143)
		(layer "In11.Cu")
		(net "GMI_CPU1_G3_CPU0_G1_TX_DN<1>")
	)
	(segment
		(start 357.182166 -233.632756)
		(end 357.183436 -233.631994)
		(width 0.1143)
		(layer "In11.Cu")
		(net "GMI_CPU1_G3_CPU0_G1_TX_DN<1>")
	)
	(segment
		(start 358.163114 -226.1997)
		(end 358.093518 -226.15906)
		(width 0.1143)
		(layer "In11.Cu")
		(net "GMI_CPU1_G3_CPU0_G1_TX_DN<1>")
	)
	(segment
		(start 113.370614 -222.291402)
		(end 113.37163 -222.29191)
		(width 0.1143)
		(layer "In11.Cu")
		(net "GMI_CPU1_G3_CPU0_G1_TX_DN<1>")
	)
	(segment
		(start 358.281224 -216.341706)
		(end 354.9523 -210.734656)
		(width 0.14224)
		(layer "In11.Cu")
		(net "GMI_CPU1_G3_CPU0_G1_TX_DN<1>")
	)
	(segment
		(start 302.917352 -175.740822)
		(end 165.001956 -174.934118)
		(width 0.14224)
		(layer "In11.Cu")
		(net "GMI_CPU1_G3_CPU0_G1_TX_DN<1>")
	)
	(segment
		(start 358.123998 -232.011474)
		(end 358.16032 -231.990392)
		(width 0.1143)
		(layer "In11.Cu")
		(net "GMI_CPU1_G3_CPU0_G1_TX_DN<1>")
	)
	(segment
		(start 358.093518 -228.789484)
		(end 358.163114 -228.748844)
		(width 0.1143)
		(layer "In11.Cu")
		(net "GMI_CPU1_G3_CPU0_G1_TX_DN<1>")
	)
	(segment
		(start 113.332514 -222.26905)
		(end 113.368074 -222.289878)
		(width 0.1143)
		(layer "In11.Cu")
		(net "GMI_CPU1_G3_CPU0_G1_TX_DN<1>")
	)
	(segment
		(start 113.371884 -231.036876)
		(end 113.332768 -231.059736)
		(width 0.1143)
		(layer "In11.Cu")
		(net "GMI_CPU1_G3_CPU0_G1_TX_DN<1>")
	)
	(segment
		(start 113.404396 -229.398068)
		(end 113.371884 -229.416864)
		(width 0.1143)
		(layer "In11.Cu")
		(net "GMI_CPU1_G3_CPU0_G1_TX_DN<1>")
	)
	(segment
		(start 113.371884 -229.416864)
		(end 113.332768 -229.439724)
		(width 0.1143)
		(layer "In11.Cu")
		(net "GMI_CPU1_G3_CPU0_G1_TX_DN<1>")
	)
	(segment
		(start 357.0732 -233.954066)
		(end 357.00335 -233.884216)
		(width 0.1143)
		(layer "In11.Cu")
		(net "GMI_CPU1_G3_CPU0_G1_TX_DN<1>")
	)
	(segment
		(start 358.123998 -229.41661)
		(end 358.091486 -229.397814)
		(width 0.1143)
		(layer "In11.Cu")
		(net "GMI_CPU1_G3_CPU0_G1_TX_DN<1>")
	)
	(segment
		(start 358.124252 -222.291656)
		(end 358.125268 -222.291148)
		(width 0.1143)
		(layer "In11.Cu")
		(net "GMI_CPU1_G3_CPU0_G1_TX_DN<1>")
	)
	(segment
		(start 311.36844 -176.723802)
		(end 308.619652 -175.740822)
		(width 0.14224)
		(layer "In11.Cu")
		(net "GMI_CPU1_G3_CPU0_G1_TX_DN<1>")
	)
	(segment
		(start 358.163114 -222.959676)
		(end 358.093518 -222.919036)
		(width 0.1143)
		(layer "In11.Cu")
		(net "GMI_CPU1_G3_CPU0_G1_TX_DN<1>")
	)
	(segment
		(start 113.371884 -227.797106)
		(end 113.332768 -227.819966)
		(width 0.1143)
		(layer "In11.Cu")
		(net "GMI_CPU1_G3_CPU0_G1_TX_DN<1>")
	)
	(segment
		(start 113.371884 -225.531934)
		(end 113.402364 -225.549714)
		(width 0.1143)
		(layer "In11.Cu")
		(net "GMI_CPU1_G3_CPU0_G1_TX_DN<1>")
	)
	(segment
		(start 113.841784 -232.821734)
		(end 113.873534 -232.840022)
		(width 0.1143)
		(layer "In11.Cu")
		(net "GMI_CPU1_G3_CPU0_G1_TX_DN<1>")
	)
	(segment
		(start 113.030762 -221.129098)
		(end 113.030762 -221.426278)
		(width 0.1143)
		(layer "In11.Cu")
		(net "GMI_CPU1_G3_CPU0_G1_TX_DN<1>")
	)
	(segment
		(start 357.371142 -233.954066)
		(end 357.0732 -233.954066)
		(width 0.1143)
		(layer "In11.Cu")
		(net "GMI_CPU1_G3_CPU0_G1_TX_DN<1>")
	)
	(segment
		(start 357.184198 -233.631486)
		(end 357.22052 -233.610404)
		(width 0.1143)
		(layer "In11.Cu")
		(net "GMI_CPU1_G3_CPU0_G1_TX_DN<1>")
	)
	(segment
		(start 113.332768 -228.749098)
		(end 113.371884 -228.771958)
		(width 0.1143)
		(layer "In11.Cu")
		(net "GMI_CPU1_G3_CPU0_G1_TX_DN<1>")
	)
	(segment
		(start 113.36909 -222.290386)
		(end 113.370614 -222.291402)
		(width 0.1143)
		(layer "In11.Cu")
		(net "GMI_CPU1_G3_CPU0_G1_TX_DN<1>")
	)
	(segment
		(start 358.163114 -229.43947)
		(end 358.123998 -229.41661)
		(width 0.1143)
		(layer "In11.Cu")
		(net "GMI_CPU1_G3_CPU0_G1_TX_DN<1>")
	)
	(segment
		(start 358.132126 -222.287084)
		(end 358.163368 -222.268796)
		(width 0.1143)
		(layer "In11.Cu")
		(net "GMI_CPU1_G3_CPU0_G1_TX_DN<1>")
	)
	(segment
		(start 114.311684 -233.63174)
		(end 114.312446 -233.632248)
		(width 0.1143)
		(layer "In11.Cu")
		(net "GMI_CPU1_G3_CPU0_G1_TX_DN<1>")
	)
	(segment
		(start 114.312446 -233.632248)
		(end 114.343434 -233.650028)
		(width 0.1143)
		(layer "In11.Cu")
		(net "GMI_CPU1_G3_CPU0_G1_TX_DN<1>")
	)
	(segment
		(start 113.371884 -228.771958)
		(end 113.402364 -228.789738)
		(width 0.1143)
		(layer "In11.Cu")
		(net "GMI_CPU1_G3_CPU0_G1_TX_DN<1>")
	)
	(segment
		(start 358.123998 -231.036622)
		(end 358.091486 -231.017826)
		(width 0.1143)
		(layer "In11.Cu")
		(net "GMI_CPU1_G3_CPU0_G1_TX_DN<1>")
	)
	(segment
		(start 113.37163 -222.29191)
		(end 113.40338 -222.310198)
		(width 0.1143)
		(layer "In11.Cu")
		(net "GMI_CPU1_G3_CPU0_G1_TX_DN<1>")
	)
	(segment
		(start 113.404396 -231.01808)
		(end 113.371884 -231.036876)
		(width 0.1143)
		(layer "In11.Cu")
		(net "GMI_CPU1_G3_CPU0_G1_TX_DN<1>")
	)
	(segment
		(start 165.001956 -174.934118)
		(end 156.372306 -178.019964)
		(width 0.14224)
		(layer "In11.Cu")
		(net "GMI_CPU1_G3_CPU0_G1_TX_DN<1>")
	)
	(segment
		(start 113.371884 -224.557082)
		(end 113.332768 -224.579942)
		(width 0.1143)
		(layer "In11.Cu")
		(net "GMI_CPU1_G3_CPU0_G1_TX_DN<1>")
	)
	(segment
		(start 358.093518 -227.169472)
		(end 358.163114 -227.128832)
		(width 0.1143)
		(layer "In11.Cu")
		(net "GMI_CPU1_G3_CPU0_G1_TX_DN<1>")
	)
	(segment
		(start 113.335308 -230.370634)
		(end 113.402364 -230.40975)
		(width 0.1143)
		(layer "In11.Cu")
		(net "GMI_CPU1_G3_CPU0_G1_TX_DN<1>")
	)
	(segment
		(start 358.126792 -222.290132)
		(end 358.127808 -222.289624)
		(width 0.1143)
		(layer "In11.Cu")
		(net "GMI_CPU1_G3_CPU0_G1_TX_DN<1>")
	)
	(segment
		(start 354.9523 -210.734656)
		(end 318.16675 -180.572156)
		(width 0.14224)
		(layer "In11.Cu")
		(net "GMI_CPU1_G3_CPU0_G1_TX_DN<1>")
	)
	(segment
		(start 113.371884 -226.177094)
		(end 113.332768 -226.199954)
		(width 0.1143)
		(layer "In11.Cu")
		(net "GMI_CPU1_G3_CPU0_G1_TX_DN<1>")
	)
	(segment
		(start 113.371884 -232.011728)
		(end 113.402364 -232.029508)
		(width 0.1143)
		(layer "In11.Cu")
		(net "GMI_CPU1_G3_CPU0_G1_TX_DN<1>")
	)
	(segment
		(start 358.093518 -232.029254)
		(end 358.123998 -232.011474)
		(width 0.1143)
		(layer "In11.Cu")
		(net "GMI_CPU1_G3_CPU0_G1_TX_DN<1>")
	)
	(segment
		(start 113.089436 -221.484952)
		(end 113.089436 -221.804484)
		(width 0.1143)
		(layer "In11.Cu")
		(net "GMI_CPU1_G3_CPU0_G1_TX_DN<1>")
	)
	(segment
		(start 112.985042 -221.083378)
		(end 113.030762 -221.129098)
		(width 0.1143)
		(layer "In11.Cu")
		(net "GMI_CPU1_G3_CPU0_G1_TX_DN<1>")
	)
	(segment
		(start 113.368074 -222.289878)
		(end 113.36909 -222.290386)
		(width 0.1143)
		(layer "In11.Cu")
		(net "GMI_CPU1_G3_CPU0_G1_TX_DN<1>")
	)
	(segment
		(start 156.372306 -178.019964)
		(end 116.397278 -210.798156)
		(width 0.14224)
		(layer "In11.Cu")
		(net "GMI_CPU1_G3_CPU0_G1_TX_DN<1>")
	)
	(segment
		(start 113.332768 -227.129086)
		(end 113.371884 -227.151946)
		(width 0.1143)
		(layer "In11.Cu")
		(net "GMI_CPU1_G3_CPU0_G1_TX_DN<1>")
	)
	(segment
		(start 358.406192 -231.524048)
		(end 358.406446 -231.524048)
		(width 0.1143)
		(layer "In11.Cu")
		(net "GMI_CPU1_G3_CPU0_G1_TX_DN<1>")
	)
	(segment
		(start 113.402364 -227.779326)
		(end 113.371884 -227.797106)
		(width 0.1143)
		(layer "In11.Cu")
		(net "GMI_CPU1_G3_CPU0_G1_TX_DN<1>")
	)
	(segment
		(start 357.183436 -233.631994)
		(end 357.184198 -233.631486)
		(width 0.1143)
		(layer "In11.Cu")
		(net "GMI_CPU1_G3_CPU0_G1_TX_DN<1>")
	)
	(segment
		(start 113.335562 -231.990646)
		(end 113.371884 -232.011728)
		(width 0.1143)
		(layer "In11.Cu")
		(net "GMI_CPU1_G3_CPU0_G1_TX_DN<1>")
	)
	(segment
		(start 358.406446 -221.80423)
		(end 358.406446 -221.484698)
		(width 0.1143)
		(layer "In11.Cu")
		(net "GMI_CPU1_G3_CPU0_G1_TX_DN<1>")
	)
	(segment
		(start 318.16675 -180.572156)
		(end 311.36844 -176.723802)
		(width 0.14224)
		(layer "In11.Cu")
		(net "GMI_CPU1_G3_CPU0_G1_TX_DN<1>")
	)
	(segment
		(start 358.163114 -227.819712)
		(end 358.093518 -227.779072)
		(width 0.1143)
		(layer "In11.Cu")
		(net "GMI_CPU1_G3_CPU0_G1_TX_DN<1>")
	)
	(segment
		(start 358.281224 -216.34196)
		(end 358.281224 -216.341706)
		(width 0.14224)
		(layer "In11.Cu")
		(net "GMI_CPU1_G3_CPU0_G1_TX_DN<1>")
	)
	(arc
		(start 113.559336 -230.71455)
		(mid 113.51837 -230.884956)
		(end 113.404396 -231.01808)
		(width 0.1143)
		(layer "In11.Cu")
		(net "GMI_CPU1_G3_CPU0_G1_TX_DN<1>")
	)
	(arc
		(start 358.091486 -231.017826)
		(mid 357.977557 -230.884679)
		(end 357.936546 -230.714296)
		(width 0.1143)
		(layer "In11.Cu")
		(net "GMI_CPU1_G3_CPU0_G1_TX_DN<1>")
	)
	(arc
		(start 113.559336 -222.61449)
		(mid 113.517787 -222.785912)
		(end 113.402364 -222.91929)
		(width 0.1143)
		(layer "In11.Cu")
		(net "GMI_CPU1_G3_CPU0_G1_TX_DN<1>")
	)
	(arc
		(start 113.332768 -226.199954)
		(mid 113.089441 -226.66452)
		(end 113.332768 -227.129086)
		(width 0.1143)
		(layer "In11.Cu")
		(net "GMI_CPU1_G3_CPU0_G1_TX_DN<1>")
	)
	(arc
		(start 358.406446 -229.904036)
		(mid 358.341931 -229.641817)
		(end 358.163114 -229.43947)
		(width 0.1143)
		(layer "In11.Cu")
		(net "GMI_CPU1_G3_CPU0_G1_TX_DN<1>")
	)
	(arc
		(start 114.259106 -233.599228)
		(mid 114.267184 -233.605014)
		(end 114.275362 -233.610658)
		(width 0.1143)
		(layer "In11.Cu")
		(net "GMI_CPU1_G3_CPU0_G1_TX_DN<1>")
	)
	(arc
		(start 358.163368 -222.268796)
		(mid 358.235695 -222.209329)
		(end 358.297226 -222.138748)
		(width 0.1143)
		(layer "In11.Cu")
		(net "GMI_CPU1_G3_CPU0_G1_TX_DN<1>")
	)
	(arc
		(start 357.936546 -232.334054)
		(mid 357.978095 -232.162632)
		(end 358.093518 -232.029254)
		(width 0.1143)
		(layer "In11.Cu")
		(net "GMI_CPU1_G3_CPU0_G1_TX_DN<1>")
	)
	(arc
		(start 357.693214 -232.79862)
		(mid 357.872027 -232.59627)
		(end 357.936546 -232.334054)
		(width 0.1143)
		(layer "In11.Cu")
		(net "GMI_CPU1_G3_CPU0_G1_TX_DN<1>")
	)
	(arc
		(start 113.332768 -231.059736)
		(mid 113.153955 -231.262086)
		(end 113.089436 -231.524302)
		(width 0.1143)
		(layer "In11.Cu")
		(net "GMI_CPU1_G3_CPU0_G1_TX_DN<1>")
	)
	(arc
		(start 357.466392 -233.150664)
		(mid 357.466402 -233.147362)
		(end 357.466392 -233.14406)
		(width 0.1143)
		(layer "In11.Cu")
		(net "GMI_CPU1_G3_CPU0_G1_TX_DN<1>")
	)
	(arc
		(start 357.22052 -233.610404)
		(mid 357.228698 -233.604761)
		(end 357.236776 -233.598974)
		(width 0.1143)
		(layer "In11.Cu")
		(net "GMI_CPU1_G3_CPU0_G1_TX_DN<1>")
	)
	(arc
		(start 358.163114 -228.748844)
		(mid 358.406441 -228.284278)
		(end 358.163114 -227.819712)
		(width 0.1143)
		(layer "In11.Cu")
		(net "GMI_CPU1_G3_CPU0_G1_TX_DN<1>")
	)
	(arc
		(start 113.089436 -229.90429)
		(mid 113.154672 -230.167881)
		(end 113.335308 -230.370634)
		(width 0.1143)
		(layer "In11.Cu")
		(net "GMI_CPU1_G3_CPU0_G1_TX_DN<1>")
	)
	(arc
		(start 113.198656 -222.139002)
		(mid 113.260175 -222.209596)
		(end 113.332514 -222.26905)
		(width 0.1143)
		(layer "In11.Cu")
		(net "GMI_CPU1_G3_CPU0_G1_TX_DN<1>")
	)
	(arc
		(start 113.559336 -232.334308)
		(mid 113.623851 -232.596527)
		(end 113.802668 -232.798874)
		(width 0.1143)
		(layer "In11.Cu")
		(net "GMI_CPU1_G3_CPU0_G1_TX_DN<1>")
	)
	(arc
		(start 358.163114 -225.50882)
		(mid 358.406441 -225.044254)
		(end 358.163114 -224.579688)
		(width 0.1143)
		(layer "In11.Cu")
		(net "GMI_CPU1_G3_CPU0_G1_TX_DN<1>")
	)
	(arc
		(start 114.02949 -233.150918)
		(mid 114.094362 -233.40066)
		(end 114.259106 -233.599228)
		(width 0.1143)
		(layer "In11.Cu")
		(net "GMI_CPU1_G3_CPU0_G1_TX_DN<1>")
	)
	(arc
		(start 358.091486 -229.397814)
		(mid 357.977557 -229.264667)
		(end 357.936546 -229.094284)
		(width 0.1143)
		(layer "In11.Cu")
		(net "GMI_CPU1_G3_CPU0_G1_TX_DN<1>")
	)
	(arc
		(start 113.332768 -222.95993)
		(mid 113.089441 -223.424496)
		(end 113.332768 -223.889062)
		(width 0.1143)
		(layer "In11.Cu")
		(net "GMI_CPU1_G3_CPU0_G1_TX_DN<1>")
	)
	(arc
		(start 113.089436 -221.804484)
		(mid 113.117352 -221.98046)
		(end 113.198656 -222.139002)
		(width 0.1143)
		(layer "In11.Cu")
		(net "GMI_CPU1_G3_CPU0_G1_TX_DN<1>")
	)
	(arc
		(start 113.402364 -232.029508)
		(mid 113.517791 -232.162884)
		(end 113.559336 -232.334308)
		(width 0.1143)
		(layer "In11.Cu")
		(net "GMI_CPU1_G3_CPU0_G1_TX_DN<1>")
	)
	(arc
		(start 357.936546 -229.094284)
		(mid 357.978095 -228.922862)
		(end 358.093518 -228.789484)
		(width 0.1143)
		(layer "In11.Cu")
		(net "GMI_CPU1_G3_CPU0_G1_TX_DN<1>")
	)
	(arc
		(start 113.08969 -231.524302)
		(mid 113.154926 -231.787893)
		(end 113.335562 -231.990646)
		(width 0.1143)
		(layer "In11.Cu")
		(net "GMI_CPU1_G3_CPU0_G1_TX_DN<1>")
	)
	(arc
		(start 113.40338 -222.310198)
		(mid 113.518056 -222.443532)
		(end 113.559336 -222.61449)
		(width 0.1143)
		(layer "In11.Cu")
		(net "GMI_CPU1_G3_CPU0_G1_TX_DN<1>")
	)
	(arc
		(start 113.332768 -224.579942)
		(mid 113.089441 -225.044508)
		(end 113.332768 -225.509074)
		(width 0.1143)
		(layer "In11.Cu")
		(net "GMI_CPU1_G3_CPU0_G1_TX_DN<1>")
	)
	(arc
		(start 113.402364 -223.929702)
		(mid 113.559341 -224.234502)
		(end 113.402364 -224.539302)
		(width 0.1143)
		(layer "In11.Cu")
		(net "GMI_CPU1_G3_CPU0_G1_TX_DN<1>")
	)
	(arc
		(start 113.332768 -227.819966)
		(mid 113.089441 -228.284532)
		(end 113.332768 -228.749098)
		(width 0.1143)
		(layer "In11.Cu")
		(net "GMI_CPU1_G3_CPU0_G1_TX_DN<1>")
	)
	(arc
		(start 114.02949 -233.144314)
		(mid 114.02948 -233.147616)
		(end 114.02949 -233.150918)
		(width 0.1143)
		(layer "In11.Cu")
		(net "GMI_CPU1_G3_CPU0_G1_TX_DN<1>")
	)
	(arc
		(start 358.297226 -222.138748)
		(mid 358.378517 -221.980201)
		(end 358.406446 -221.80423)
		(width 0.1143)
		(layer "In11.Cu")
		(net "GMI_CPU1_G3_CPU0_G1_TX_DN<1>")
	)
	(arc
		(start 357.236776 -233.598974)
		(mid 357.401443 -233.400367)
		(end 357.466392 -233.150664)
		(width 0.1143)
		(layer "In11.Cu")
		(net "GMI_CPU1_G3_CPU0_G1_TX_DN<1>")
	)
	(arc
		(start 357.936546 -230.714296)
		(mid 357.978095 -230.542874)
		(end 358.093518 -230.409496)
		(width 0.1143)
		(layer "In11.Cu")
		(net "GMI_CPU1_G3_CPU0_G1_TX_DN<1>")
	)
	(arc
		(start 113.402364 -227.169726)
		(mid 113.559341 -227.474526)
		(end 113.402364 -227.779326)
		(width 0.1143)
		(layer "In11.Cu")
		(net "GMI_CPU1_G3_CPU0_G1_TX_DN<1>")
	)
	(arc
		(start 358.16032 -231.990392)
		(mid 358.340972 -231.787647)
		(end 358.406192 -231.524048)
		(width 0.1143)
		(layer "In11.Cu")
		(net "GMI_CPU1_G3_CPU0_G1_TX_DN<1>")
	)
	(arc
		(start 357.466392 -233.14406)
		(mid 357.510018 -232.974314)
		(end 357.622348 -232.839768)
		(width 0.1143)
		(layer "In11.Cu")
		(net "GMI_CPU1_G3_CPU0_G1_TX_DN<1>")
	)
	(arc
		(start 358.093518 -226.15906)
		(mid 357.936541 -225.85426)
		(end 358.093518 -225.54946)
		(width 0.1143)
		(layer "In11.Cu")
		(net "GMI_CPU1_G3_CPU0_G1_TX_DN<1>")
	)
	(arc
		(start 357.936546 -222.614236)
		(mid 357.977801 -222.443265)
		(end 358.092502 -222.309944)
		(width 0.1143)
		(layer "In11.Cu")
		(net "GMI_CPU1_G3_CPU0_G1_TX_DN<1>")
	)
	(arc
		(start 113.402364 -228.789738)
		(mid 113.517791 -228.923114)
		(end 113.559336 -229.094538)
		(width 0.1143)
		(layer "In11.Cu")
		(net "GMI_CPU1_G3_CPU0_G1_TX_DN<1>")
	)
	(arc
		(start 358.093518 -222.919036)
		(mid 357.978091 -222.78566)
		(end 357.936546 -222.614236)
		(width 0.1143)
		(layer "In11.Cu")
		(net "GMI_CPU1_G3_CPU0_G1_TX_DN<1>")
	)
	(arc
		(start 113.402364 -225.549714)
		(mid 113.559341 -225.854514)
		(end 113.402364 -226.159314)
		(width 0.1143)
		(layer "In11.Cu")
		(net "GMI_CPU1_G3_CPU0_G1_TX_DN<1>")
	)
	(arc
		(start 358.163114 -223.888808)
		(mid 358.406441 -223.424242)
		(end 358.163114 -222.959676)
		(width 0.1143)
		(layer "In11.Cu")
		(net "GMI_CPU1_G3_CPU0_G1_TX_DN<1>")
	)
	(arc
		(start 113.332768 -229.439724)
		(mid 113.153955 -229.642074)
		(end 113.089436 -229.90429)
		(width 0.1143)
		(layer "In11.Cu")
		(net "GMI_CPU1_G3_CPU0_G1_TX_DN<1>")
	)
	(arc
		(start 113.559336 -229.094538)
		(mid 113.51837 -229.264944)
		(end 113.404396 -229.398068)
		(width 0.1143)
		(layer "In11.Cu")
		(net "GMI_CPU1_G3_CPU0_G1_TX_DN<1>")
	)
	(arc
		(start 114.343434 -233.650028)
		(mid 114.440569 -233.752897)
		(end 114.492532 -233.88447)
		(width 0.1143)
		(layer "In11.Cu")
		(net "GMI_CPU1_G3_CPU0_G1_TX_DN<1>")
	)
	(arc
		(start 358.406446 -231.524048)
		(mid 358.341931 -231.261829)
		(end 358.163114 -231.059482)
		(width 0.1143)
		(layer "In11.Cu")
		(net "GMI_CPU1_G3_CPU0_G1_TX_DN<1>")
	)
	(arc
		(start 113.873534 -232.840022)
		(mid 113.985907 -232.974546)
		(end 114.02949 -233.144314)
		(width 0.1143)
		(layer "In11.Cu")
		(net "GMI_CPU1_G3_CPU0_G1_TX_DN<1>")
	)
	(arc
		(start 358.093518 -227.779072)
		(mid 357.936541 -227.474272)
		(end 358.093518 -227.169472)
		(width 0.1143)
		(layer "In11.Cu")
		(net "GMI_CPU1_G3_CPU0_G1_TX_DN<1>")
	)
	(arc
		(start 357.00335 -233.884216)
		(mid 357.055399 -233.752697)
		(end 357.152448 -233.649774)
		(width 0.1143)
		(layer "In11.Cu")
		(net "GMI_CPU1_G3_CPU0_G1_TX_DN<1>")
	)
	(arc
		(start 358.093518 -224.539048)
		(mid 357.936541 -224.234248)
		(end 358.093518 -223.929448)
		(width 0.1143)
		(layer "In11.Cu")
		(net "GMI_CPU1_G3_CPU0_G1_TX_DN<1>")
	)
	(arc
		(start 113.402364 -230.40975)
		(mid 113.517791 -230.543126)
		(end 113.559336 -230.71455)
		(width 0.1143)
		(layer "In11.Cu")
		(net "GMI_CPU1_G3_CPU0_G1_TX_DN<1>")
	)
	(arc
		(start 358.160574 -230.37038)
		(mid 358.341226 -230.167635)
		(end 358.406446 -229.904036)
		(width 0.1143)
		(layer "In11.Cu")
		(net "GMI_CPU1_G3_CPU0_G1_TX_DN<1>")
	)
	(arc
		(start 358.163114 -227.128832)
		(mid 358.406441 -226.664266)
		(end 358.163114 -226.1997)
		(width 0.1143)
		(layer "In11.Cu")
		(net "GMI_CPU1_G3_CPU0_G1_TX_DN<1>")
	)
	(segment
		(start 124.467874 -235.030264)
		(end 124.934726 -234.764326)
		(width 0.12954)
		(layer "F.Cu")
		(net "GMI_CPU1_G3_CPU0_G1_TX_DN<15>")
	)
	(segment
		(start 347.028008 -235.03001)
		(end 346.561156 -234.764072)
		(width 0.12954)
		(layer "F.Cu")
		(net "GMI_CPU1_G3_CPU0_G1_TX_DN<15>")
	)
	(segment
		(start 126.492762 -229.439724)
		(end 126.531878 -229.416864)
		(width 0.1143)
		(layer "In11.Cu")
		(net "GMI_CPU1_G3_CPU0_G1_TX_DN<15>")
	)
	(segment
		(start 124.934726 -234.764326)
		(end 125.232668 -234.764326)
		(width 0.1143)
		(layer "In11.Cu")
		(net "GMI_CPU1_G3_CPU0_G1_TX_DN<15>")
	)
	(segment
		(start 127.035306 -231.221534)
		(end 126.962662 -231.179116)
		(width 0.1143)
		(layer "In11.Cu")
		(net "GMI_CPU1_G3_CPU0_G1_TX_DN<15>")
	)
	(segment
		(start 344.493596 -231.847898)
		(end 344.499692 -231.851454)
		(width 0.1143)
		(layer "In11.Cu")
		(net "GMI_CPU1_G3_CPU0_G1_TX_DN<15>")
	)
	(segment
		(start 345.436698 -233.468164)
		(end 345.437714 -233.468672)
		(width 0.1143)
		(layer "In11.Cu")
		(net "GMI_CPU1_G3_CPU0_G1_TX_DN<15>")
	)
	(segment
		(start 346.18041 -234.681268)
		(end 346.263214 -234.764072)
		(width 0.1143)
		(layer "In11.Cu")
		(net "GMI_CPU1_G3_CPU0_G1_TX_DN<15>")
	)
	(segment
		(start 126.492762 -224.579942)
		(end 126.531878 -224.557082)
		(width 0.1143)
		(layer "In11.Cu")
		(net "GMI_CPU1_G3_CPU0_G1_TX_DN<15>")
	)
	(segment
		(start 232.027222 -200.610724)
		(end 236.278928 -201.360278)
		(width 0.14224)
		(layer "In11.Cu")
		(net "GMI_CPU1_G3_CPU0_G1_TX_DN<15>")
	)
	(segment
		(start 162.863276 -191.13373)
		(end 207.185514 -190.946278)
		(width 0.14224)
		(layer "In11.Cu")
		(net "GMI_CPU1_G3_CPU0_G1_TX_DN<15>")
	)
	(segment
		(start 126.063756 -233.465624)
		(end 126.093474 -233.448606)
		(width 0.1143)
		(layer "In11.Cu")
		(net "GMI_CPU1_G3_CPU0_G1_TX_DN<15>")
	)
	(segment
		(start 126.562358 -228.789738)
		(end 126.531878 -228.771958)
		(width 0.1143)
		(layer "In11.Cu")
		(net "GMI_CPU1_G3_CPU0_G1_TX_DN<15>")
	)
	(segment
		(start 345.00058 -230.37038)
		(end 344.933524 -230.409496)
		(width 0.1143)
		(layer "In11.Cu")
		(net "GMI_CPU1_G3_CPU0_G1_TX_DN<15>")
	)
	(segment
		(start 126.061724 -233.466894)
		(end 126.062486 -233.466386)
		(width 0.1143)
		(layer "In11.Cu")
		(net "GMI_CPU1_G3_CPU0_G1_TX_DN<15>")
	)
	(segment
		(start 345.440254 -233.470196)
		(end 345.441778 -233.471212)
		(width 0.1143)
		(layer "In11.Cu")
		(net "GMI_CPU1_G3_CPU0_G1_TX_DN<15>")
	)
	(segment
		(start 344.53322 -231.178862)
		(end 344.460576 -231.22128)
		(width 0.1143)
		(layer "In11.Cu")
		(net "GMI_CPU1_G3_CPU0_G1_TX_DN<15>")
	)
	(segment
		(start 126.562358 -223.929702)
		(end 126.531878 -223.911922)
		(width 0.1143)
		(layer "In11.Cu")
		(net "GMI_CPU1_G3_CPU0_G1_TX_DN<15>")
	)
	(segment
		(start 126.531878 -223.911922)
		(end 126.492762 -223.889062)
		(width 0.1143)
		(layer "In11.Cu")
		(net "GMI_CPU1_G3_CPU0_G1_TX_DN<15>")
	)
	(segment
		(start 125.552708 -234.29976)
		(end 125.591824 -234.2769)
		(width 0.1143)
		(layer "In11.Cu")
		(net "GMI_CPU1_G3_CPU0_G1_TX_DN<15>")
	)
	(segment
		(start 344.933524 -222.919036)
		(end 345.00312 -222.959676)
		(width 0.1143)
		(layer "In11.Cu")
		(net "GMI_CPU1_G3_CPU0_G1_TX_DN<15>")
	)
	(segment
		(start 316.58433 -196.795136)
		(end 344.58529 -219.75445)
		(width 0.14224)
		(layer "In11.Cu")
		(net "GMI_CPU1_G3_CPU0_G1_TX_DN<15>")
	)
	(segment
		(start 346.263214 -234.764072)
		(end 346.561156 -234.764072)
		(width 0.1143)
		(layer "In11.Cu")
		(net "GMI_CPU1_G3_CPU0_G1_TX_DN<15>")
	)
	(segment
		(start 126.492762 -226.199954)
		(end 126.531878 -226.177094)
		(width 0.1143)
		(layer "In11.Cu")
		(net "GMI_CPU1_G3_CPU0_G1_TX_DN<15>")
	)
	(segment
		(start 126.531878 -226.177094)
		(end 126.562358 -226.159314)
		(width 0.1143)
		(layer "In11.Cu")
		(net "GMI_CPU1_G3_CPU0_G1_TX_DN<15>")
	)
	(segment
		(start 345.291918 -220.943932)
		(end 345.291918 -221.198694)
		(width 0.14224)
		(layer "In11.Cu")
		(net "GMI_CPU1_G3_CPU0_G1_TX_DN<15>")
	)
	(segment
		(start 126.203964 -221.047564)
		(end 127.10795 -219.525596)
		(width 0.14224)
		(layer "In11.Cu")
		(net "GMI_CPU1_G3_CPU0_G1_TX_DN<15>")
	)
	(segment
		(start 126.531878 -225.531934)
		(end 126.492762 -225.509074)
		(width 0.1143)
		(layer "In11.Cu")
		(net "GMI_CPU1_G3_CPU0_G1_TX_DN<15>")
	)
	(segment
		(start 126.249938 -221.804484)
		(end 126.249938 -221.244922)
		(width 0.1143)
		(layer "In11.Cu")
		(net "GMI_CPU1_G3_CPU0_G1_TX_DN<15>")
	)
	(segment
		(start 345.432126 -233.46537)
		(end 345.433396 -233.466132)
		(width 0.1143)
		(layer "In11.Cu")
		(net "GMI_CPU1_G3_CPU0_G1_TX_DN<15>")
	)
	(segment
		(start 126.022608 -233.489754)
		(end 126.061724 -233.466894)
		(width 0.1143)
		(layer "In11.Cu")
		(net "GMI_CPU1_G3_CPU0_G1_TX_DN<15>")
	)
	(segment
		(start 126.531878 -229.416864)
		(end 126.56439 -229.398068)
		(width 0.1143)
		(layer "In11.Cu")
		(net "GMI_CPU1_G3_CPU0_G1_TX_DN<15>")
	)
	(segment
		(start 126.492762 -222.95993)
		(end 126.531878 -222.93707)
		(width 0.1143)
		(layer "In11.Cu")
		(net "GMI_CPU1_G3_CPU0_G1_TX_DN<15>")
	)
	(segment
		(start 303.734724 -191.04991)
		(end 308.378606 -191.04991)
		(width 0.14224)
		(layer "In11.Cu")
		(net "GMI_CPU1_G3_CPU0_G1_TX_DN<15>")
	)
	(segment
		(start 125.232668 -234.764326)
		(end 125.315472 -234.681522)
		(width 0.1143)
		(layer "In11.Cu")
		(net "GMI_CPU1_G3_CPU0_G1_TX_DN<15>")
	)
	(segment
		(start 126.531878 -228.771958)
		(end 126.492762 -228.749098)
		(width 0.1143)
		(layer "In11.Cu")
		(net "GMI_CPU1_G3_CPU0_G1_TX_DN<15>")
	)
	(segment
		(start 345.873578 -234.258866)
		(end 345.943174 -234.299506)
		(width 0.1143)
		(layer "In11.Cu")
		(net "GMI_CPU1_G3_CPU0_G1_TX_DN<15>")
	)
	(segment
		(start 345.00312 -223.888808)
		(end 344.933524 -223.929448)
		(width 0.1143)
		(layer "In11.Cu")
		(net "GMI_CPU1_G3_CPU0_G1_TX_DN<15>")
	)
	(segment
		(start 251.681234 -192.63614)
		(end 262.818118 -190.67272)
		(width 0.14224)
		(layer "In11.Cu")
		(net "GMI_CPU1_G3_CPU0_G1_TX_DN<15>")
	)
	(segment
		(start 345.441778 -233.471212)
		(end 345.473274 -233.4895)
		(width 0.1143)
		(layer "In11.Cu")
		(net "GMI_CPU1_G3_CPU0_G1_TX_DN<15>")
	)
	(segment
		(start 345.434158 -233.46664)
		(end 345.435174 -233.467148)
		(width 0.1143)
		(layer "In11.Cu")
		(net "GMI_CPU1_G3_CPU0_G1_TX_DN<15>")
	)
	(segment
		(start 126.562358 -230.40975)
		(end 126.495302 -230.370634)
		(width 0.1143)
		(layer "In11.Cu")
		(net "GMI_CPU1_G3_CPU0_G1_TX_DN<15>")
	)
	(segment
		(start 126.99619 -231.851708)
		(end 127.002286 -231.848152)
		(width 0.1143)
		(layer "In11.Cu")
		(net "GMI_CPU1_G3_CPU0_G1_TX_DN<15>")
	)
	(segment
		(start 126.531878 -227.151946)
		(end 126.492762 -227.129086)
		(width 0.1143)
		(layer "In11.Cu")
		(net "GMI_CPU1_G3_CPU0_G1_TX_DN<15>")
	)
	(segment
		(start 126.562358 -222.30969)
		(end 126.494286 -222.270066)
		(width 0.1143)
		(layer "In11.Cu")
		(net "GMI_CPU1_G3_CPU0_G1_TX_DN<15>")
	)
	(segment
		(start 209.814922 -191.410336)
		(end 232.027222 -200.610724)
		(width 0.14224)
		(layer "In11.Cu")
		(net "GMI_CPU1_G3_CPU0_G1_TX_DN<15>")
	)
	(segment
		(start 240.213642 -200.66635)
		(end 251.681234 -192.63614)
		(width 0.14224)
		(layer "In11.Cu")
		(net "GMI_CPU1_G3_CPU0_G1_TX_DN<15>")
	)
	(segment
		(start 308.429406 -191.10071)
		(end 316.58433 -196.795136)
		(width 0.14224)
		(layer "In11.Cu")
		(net "GMI_CPU1_G3_CPU0_G1_TX_DN<15>")
	)
	(segment
		(start 344.964004 -229.41661)
		(end 345.00312 -229.43947)
		(width 0.1143)
		(layer "In11.Cu")
		(net "GMI_CPU1_G3_CPU0_G1_TX_DN<15>")
	)
	(segment
		(start 344.933524 -232.638854)
		(end 345.00312 -232.679494)
		(width 0.1143)
		(layer "In11.Cu")
		(net "GMI_CPU1_G3_CPU0_G1_TX_DN<15>")
	)
	(segment
		(start 161.922714 -192.415414)
		(end 162.410648 -191.505586)
		(width 0.14224)
		(layer "In11.Cu")
		(net "GMI_CPU1_G3_CPU0_G1_TX_DN<15>")
	)
	(segment
		(start 126.531878 -227.797106)
		(end 126.562358 -227.779326)
		(width 0.1143)
		(layer "In11.Cu")
		(net "GMI_CPU1_G3_CPU0_G1_TX_DN<15>")
	)
	(segment
		(start 126.492762 -227.819966)
		(end 126.531878 -227.797106)
		(width 0.1143)
		(layer "In11.Cu")
		(net "GMI_CPU1_G3_CPU0_G1_TX_DN<15>")
	)
	(segment
		(start 162.410648 -191.505586)
		(end 162.863276 -191.13373)
		(width 0.14224)
		(layer "In11.Cu")
		(net "GMI_CPU1_G3_CPU0_G1_TX_DN<15>")
	)
	(segment
		(start 126.492762 -232.679748)
		(end 126.562358 -232.639108)
		(width 0.1143)
		(layer "In11.Cu")
		(net "GMI_CPU1_G3_CPU0_G1_TX_DN<15>")
	)
	(segment
		(start 345.435174 -233.467148)
		(end 345.436698 -233.468164)
		(width 0.1143)
		(layer "In11.Cu")
		(net "GMI_CPU1_G3_CPU0_G1_TX_DN<15>")
	)
	(segment
		(start 147.282408 -202.983846)
		(end 150.059136 -202.142598)
		(width 0.14224)
		(layer "In11.Cu")
		(net "GMI_CPU1_G3_CPU0_G1_TX_DN<15>")
	)
	(segment
		(start 126.562358 -225.549714)
		(end 126.531878 -225.531934)
		(width 0.1143)
		(layer "In11.Cu")
		(net "GMI_CPU1_G3_CPU0_G1_TX_DN<15>")
	)
	(segment
		(start 126.562358 -227.169726)
		(end 126.531878 -227.151946)
		(width 0.1143)
		(layer "In11.Cu")
		(net "GMI_CPU1_G3_CPU0_G1_TX_DN<15>")
	)
	(segment
		(start 344.933524 -227.779072)
		(end 345.00312 -227.819712)
		(width 0.1143)
		(layer "In11.Cu")
		(net "GMI_CPU1_G3_CPU0_G1_TX_DN<15>")
	)
	(segment
		(start 150.059136 -202.142598)
		(end 161.922714 -192.415414)
		(width 0.14224)
		(layer "In11.Cu")
		(net "GMI_CPU1_G3_CPU0_G1_TX_DN<15>")
	)
	(segment
		(start 344.933524 -224.539048)
		(end 345.00312 -224.579688)
		(width 0.1143)
		(layer "In11.Cu")
		(net "GMI_CPU1_G3_CPU0_G1_TX_DN<15>")
	)
	(segment
		(start 236.278928 -201.360278)
		(end 240.213642 -200.66635)
		(width 0.14224)
		(layer "In11.Cu")
		(net "GMI_CPU1_G3_CPU0_G1_TX_DN<15>")
	)
	(segment
		(start 345.001596 -222.269812)
		(end 344.933524 -222.309436)
		(width 0.1143)
		(layer "In11.Cu")
		(net "GMI_CPU1_G3_CPU0_G1_TX_DN<15>")
	)
	(segment
		(start 308.378606 -191.04991)
		(end 308.429406 -191.10071)
		(width 0.14224)
		(layer "In11.Cu")
		(net "GMI_CPU1_G3_CPU0_G1_TX_DN<15>")
	)
	(segment
		(start 127.10795 -219.525596)
		(end 147.282408 -202.983846)
		(width 0.14224)
		(layer "In11.Cu")
		(net "GMI_CPU1_G3_CPU0_G1_TX_DN<15>")
	)
	(segment
		(start 262.818118 -190.67272)
		(end 303.734724 -191.04991)
		(width 0.14224)
		(layer "In11.Cu")
		(net "GMI_CPU1_G3_CPU0_G1_TX_DN<15>")
	)
	(segment
		(start 345.00312 -228.748844)
		(end 344.933524 -228.789484)
		(width 0.1143)
		(layer "In11.Cu")
		(net "GMI_CPU1_G3_CPU0_G1_TX_DN<15>")
	)
	(segment
		(start 344.58529 -219.75445)
		(end 345.291918 -220.943932)
		(width 0.14224)
		(layer "In11.Cu")
		(net "GMI_CPU1_G3_CPU0_G1_TX_DN<15>")
	)
	(segment
		(start 125.591824 -234.2769)
		(end 125.622304 -234.25912)
		(width 0.1143)
		(layer "In11.Cu")
		(net "GMI_CPU1_G3_CPU0_G1_TX_DN<15>")
	)
	(segment
		(start 345.245944 -221.244668)
		(end 345.245944 -221.80423)
		(width 0.1143)
		(layer "In11.Cu")
		(net "GMI_CPU1_G3_CPU0_G1_TX_DN<15>")
	)
	(segment
		(start 344.931492 -229.397814)
		(end 344.964004 -229.41661)
		(width 0.1143)
		(layer "In11.Cu")
		(net "GMI_CPU1_G3_CPU0_G1_TX_DN<15>")
	)
	(segment
		(start 126.062486 -233.466386)
		(end 126.063756 -233.465624)
		(width 0.1143)
		(layer "In11.Cu")
		(net "GMI_CPU1_G3_CPU0_G1_TX_DN<15>")
	)
	(segment
		(start 345.00312 -227.128832)
		(end 344.933524 -227.169472)
		(width 0.1143)
		(layer "In11.Cu")
		(net "GMI_CPU1_G3_CPU0_G1_TX_DN<15>")
	)
	(segment
		(start 345.437714 -233.468672)
		(end 345.440254 -233.470196)
		(width 0.1143)
		(layer "In11.Cu")
		(net "GMI_CPU1_G3_CPU0_G1_TX_DN<15>")
	)
	(segment
		(start 345.433396 -233.466132)
		(end 345.434158 -233.46664)
		(width 0.1143)
		(layer "In11.Cu")
		(net "GMI_CPU1_G3_CPU0_G1_TX_DN<15>")
	)
	(segment
		(start 345.402408 -233.448352)
		(end 345.432126 -233.46537)
		(width 0.1143)
		(layer "In11.Cu")
		(net "GMI_CPU1_G3_CPU0_G1_TX_DN<15>")
	)
	(segment
		(start 126.531878 -222.93707)
		(end 126.562358 -222.91929)
		(width 0.1143)
		(layer "In11.Cu")
		(net "GMI_CPU1_G3_CPU0_G1_TX_DN<15>")
	)
	(segment
		(start 345.00312 -225.50882)
		(end 344.933524 -225.54946)
		(width 0.1143)
		(layer "In11.Cu")
		(net "GMI_CPU1_G3_CPU0_G1_TX_DN<15>")
	)
	(segment
		(start 126.531878 -224.557082)
		(end 126.562358 -224.539302)
		(width 0.1143)
		(layer "In11.Cu")
		(net "GMI_CPU1_G3_CPU0_G1_TX_DN<15>")
	)
	(segment
		(start 207.185514 -190.946278)
		(end 209.814922 -191.410336)
		(width 0.14224)
		(layer "In11.Cu")
		(net "GMI_CPU1_G3_CPU0_G1_TX_DN<15>")
	)
	(segment
		(start 345.291918 -221.198694)
		(end 345.245944 -221.244668)
		(width 0.1143)
		(layer "In11.Cu")
		(net "GMI_CPU1_G3_CPU0_G1_TX_DN<15>")
	)
	(segment
		(start 126.249938 -221.244922)
		(end 126.203964 -221.198948)
		(width 0.1143)
		(layer "In11.Cu")
		(net "GMI_CPU1_G3_CPU0_G1_TX_DN<15>")
	)
	(segment
		(start 344.933524 -226.15906)
		(end 345.00312 -226.1997)
		(width 0.1143)
		(layer "In11.Cu")
		(net "GMI_CPU1_G3_CPU0_G1_TX_DN<15>")
	)
	(segment
		(start 126.203964 -221.198948)
		(end 126.203964 -221.047564)
		(width 0.14224)
		(layer "In11.Cu")
		(net "GMI_CPU1_G3_CPU0_G1_TX_DN<15>")
	)
	(arc
		(start 126.093474 -233.448606)
		(mid 126.20815 -233.315272)
		(end 126.24943 -233.144314)
		(width 0.1143)
		(layer "In11.Cu")
		(net "GMI_CPU1_G3_CPU0_G1_TX_DN<15>")
	)
	(arc
		(start 126.24943 -233.144314)
		(mid 126.313945 -232.882095)
		(end 126.492762 -232.679748)
		(width 0.1143)
		(layer "In11.Cu")
		(net "GMI_CPU1_G3_CPU0_G1_TX_DN<15>")
	)
	(arc
		(start 344.933524 -225.54946)
		(mid 344.776547 -225.85426)
		(end 344.933524 -226.15906)
		(width 0.1143)
		(layer "In11.Cu")
		(net "GMI_CPU1_G3_CPU0_G1_TX_DN<15>")
	)
	(arc
		(start 344.933524 -227.169472)
		(mid 344.776547 -227.474272)
		(end 344.933524 -227.779072)
		(width 0.1143)
		(layer "In11.Cu")
		(net "GMI_CPU1_G3_CPU0_G1_TX_DN<15>")
	)
	(arc
		(start 126.495302 -230.370634)
		(mid 126.31465 -230.167889)
		(end 126.24943 -229.90429)
		(width 0.1143)
		(layer "In11.Cu")
		(net "GMI_CPU1_G3_CPU0_G1_TX_DN<15>")
	)
	(arc
		(start 345.00312 -229.43947)
		(mid 345.181933 -229.64182)
		(end 345.246452 -229.904036)
		(width 0.1143)
		(layer "In11.Cu")
		(net "GMI_CPU1_G3_CPU0_G1_TX_DN<15>")
	)
	(arc
		(start 126.562358 -224.539302)
		(mid 126.719335 -224.234502)
		(end 126.562358 -223.929702)
		(width 0.1143)
		(layer "In11.Cu")
		(net "GMI_CPU1_G3_CPU0_G1_TX_DN<15>")
	)
	(arc
		(start 126.962662 -231.179116)
		(mid 126.783849 -230.976766)
		(end 126.71933 -230.71455)
		(width 0.1143)
		(layer "In11.Cu")
		(net "GMI_CPU1_G3_CPU0_G1_TX_DN<15>")
	)
	(arc
		(start 126.562358 -227.779326)
		(mid 126.719335 -227.474526)
		(end 126.562358 -227.169726)
		(width 0.1143)
		(layer "In11.Cu")
		(net "GMI_CPU1_G3_CPU0_G1_TX_DN<15>")
	)
	(arc
		(start 126.562358 -222.91929)
		(mid 126.719335 -222.61449)
		(end 126.562358 -222.30969)
		(width 0.1143)
		(layer "In11.Cu")
		(net "GMI_CPU1_G3_CPU0_G1_TX_DN<15>")
	)
	(arc
		(start 344.499692 -231.851454)
		(mid 344.702419 -232.055867)
		(end 344.776552 -232.334054)
		(width 0.1143)
		(layer "In11.Cu")
		(net "GMI_CPU1_G3_CPU0_G1_TX_DN<15>")
	)
	(arc
		(start 346.1766 -234.658408)
		(mid 346.178623 -234.669818)
		(end 346.18041 -234.681268)
		(width 0.1143)
		(layer "In11.Cu")
		(net "GMI_CPU1_G3_CPU0_G1_TX_DN<15>")
	)
	(arc
		(start 126.492762 -223.889062)
		(mid 126.249435 -223.424496)
		(end 126.492762 -222.95993)
		(width 0.1143)
		(layer "In11.Cu")
		(net "GMI_CPU1_G3_CPU0_G1_TX_DN<15>")
	)
	(arc
		(start 125.319282 -234.658662)
		(mid 125.400715 -234.456264)
		(end 125.552708 -234.29976)
		(width 0.1143)
		(layer "In11.Cu")
		(net "GMI_CPU1_G3_CPU0_G1_TX_DN<15>")
	)
	(arc
		(start 125.315472 -234.681522)
		(mid 125.31726 -234.670073)
		(end 125.319282 -234.658662)
		(width 0.1143)
		(layer "In11.Cu")
		(net "GMI_CPU1_G3_CPU0_G1_TX_DN<15>")
	)
	(arc
		(start 345.00312 -232.679494)
		(mid 345.181933 -232.881844)
		(end 345.246452 -233.14406)
		(width 0.1143)
		(layer "In11.Cu")
		(net "GMI_CPU1_G3_CPU0_G1_TX_DN<15>")
	)
	(arc
		(start 345.00312 -224.579688)
		(mid 345.246447 -225.044254)
		(end 345.00312 -225.50882)
		(width 0.1143)
		(layer "In11.Cu")
		(net "GMI_CPU1_G3_CPU0_G1_TX_DN<15>")
	)
	(arc
		(start 345.246452 -233.14406)
		(mid 345.287707 -233.315031)
		(end 345.402408 -233.448352)
		(width 0.1143)
		(layer "In11.Cu")
		(net "GMI_CPU1_G3_CPU0_G1_TX_DN<15>")
	)
	(arc
		(start 126.492762 -227.129086)
		(mid 126.249435 -226.66452)
		(end 126.492762 -226.199954)
		(width 0.1143)
		(layer "In11.Cu")
		(net "GMI_CPU1_G3_CPU0_G1_TX_DN<15>")
	)
	(arc
		(start 126.562358 -232.639108)
		(mid 126.677785 -232.505732)
		(end 126.71933 -232.334308)
		(width 0.1143)
		(layer "In11.Cu")
		(net "GMI_CPU1_G3_CPU0_G1_TX_DN<15>")
	)
	(arc
		(start 345.00312 -227.819712)
		(mid 345.246447 -228.284278)
		(end 345.00312 -228.748844)
		(width 0.1143)
		(layer "In11.Cu")
		(net "GMI_CPU1_G3_CPU0_G1_TX_DN<15>")
	)
	(arc
		(start 125.622304 -234.25912)
		(mid 125.737731 -234.125744)
		(end 125.779276 -233.95432)
		(width 0.1143)
		(layer "In11.Cu")
		(net "GMI_CPU1_G3_CPU0_G1_TX_DN<15>")
	)
	(arc
		(start 127.189484 -231.524302)
		(mid 127.148722 -231.354418)
		(end 127.035306 -231.221534)
		(width 0.1143)
		(layer "In11.Cu")
		(net "GMI_CPU1_G3_CPU0_G1_TX_DN<15>")
	)
	(arc
		(start 345.943174 -234.299506)
		(mid 346.095161 -234.456014)
		(end 346.1766 -234.658408)
		(width 0.1143)
		(layer "In11.Cu")
		(net "GMI_CPU1_G3_CPU0_G1_TX_DN<15>")
	)
	(arc
		(start 126.492762 -225.509074)
		(mid 126.249435 -225.044508)
		(end 126.492762 -224.579942)
		(width 0.1143)
		(layer "In11.Cu")
		(net "GMI_CPU1_G3_CPU0_G1_TX_DN<15>")
	)
	(arc
		(start 344.306398 -231.524048)
		(mid 344.356572 -231.711067)
		(end 344.493596 -231.847898)
		(width 0.1143)
		(layer "In11.Cu")
		(net "GMI_CPU1_G3_CPU0_G1_TX_DN<15>")
	)
	(arc
		(start 345.716606 -233.954066)
		(mid 345.758155 -234.125488)
		(end 345.873578 -234.258866)
		(width 0.1143)
		(layer "In11.Cu")
		(net "GMI_CPU1_G3_CPU0_G1_TX_DN<15>")
	)
	(arc
		(start 126.494286 -222.270066)
		(mid 126.416833 -222.205693)
		(end 126.352046 -222.128588)
		(width 0.1143)
		(layer "In11.Cu")
		(net "GMI_CPU1_G3_CPU0_G1_TX_DN<15>")
	)
	(arc
		(start 127.002286 -231.848152)
		(mid 127.13935 -231.711344)
		(end 127.189484 -231.524302)
		(width 0.1143)
		(layer "In11.Cu")
		(net "GMI_CPU1_G3_CPU0_G1_TX_DN<15>")
	)
	(arc
		(start 344.933524 -222.309436)
		(mid 344.776547 -222.614236)
		(end 344.933524 -222.919036)
		(width 0.1143)
		(layer "In11.Cu")
		(net "GMI_CPU1_G3_CPU0_G1_TX_DN<15>")
	)
	(arc
		(start 345.473274 -233.4895)
		(mid 345.652087 -233.69185)
		(end 345.716606 -233.954066)
		(width 0.1143)
		(layer "In11.Cu")
		(net "GMI_CPU1_G3_CPU0_G1_TX_DN<15>")
	)
	(arc
		(start 344.460576 -231.22128)
		(mid 344.347169 -231.354169)
		(end 344.306398 -231.524048)
		(width 0.1143)
		(layer "In11.Cu")
		(net "GMI_CPU1_G3_CPU0_G1_TX_DN<15>")
	)
	(arc
		(start 126.492762 -228.749098)
		(mid 126.249435 -228.284532)
		(end 126.492762 -227.819966)
		(width 0.1143)
		(layer "In11.Cu")
		(net "GMI_CPU1_G3_CPU0_G1_TX_DN<15>")
	)
	(arc
		(start 126.71933 -232.334308)
		(mid 126.793459 -232.056119)
		(end 126.99619 -231.851708)
		(width 0.1143)
		(layer "In11.Cu")
		(net "GMI_CPU1_G3_CPU0_G1_TX_DN<15>")
	)
	(arc
		(start 344.933524 -230.409496)
		(mid 344.818097 -230.542872)
		(end 344.776552 -230.714296)
		(width 0.1143)
		(layer "In11.Cu")
		(net "GMI_CPU1_G3_CPU0_G1_TX_DN<15>")
	)
	(arc
		(start 344.776552 -232.334054)
		(mid 344.818101 -232.505476)
		(end 344.933524 -232.638854)
		(width 0.1143)
		(layer "In11.Cu")
		(net "GMI_CPU1_G3_CPU0_G1_TX_DN<15>")
	)
	(arc
		(start 344.933524 -223.929448)
		(mid 344.776547 -224.234248)
		(end 344.933524 -224.539048)
		(width 0.1143)
		(layer "In11.Cu")
		(net "GMI_CPU1_G3_CPU0_G1_TX_DN<15>")
	)
	(arc
		(start 126.71933 -230.71455)
		(mid 126.677781 -230.543128)
		(end 126.562358 -230.40975)
		(width 0.1143)
		(layer "In11.Cu")
		(net "GMI_CPU1_G3_CPU0_G1_TX_DN<15>")
	)
	(arc
		(start 126.562358 -226.159314)
		(mid 126.719335 -225.854514)
		(end 126.562358 -225.549714)
		(width 0.1143)
		(layer "In11.Cu")
		(net "GMI_CPU1_G3_CPU0_G1_TX_DN<15>")
	)
	(arc
		(start 345.246452 -229.904036)
		(mid 345.181216 -230.167627)
		(end 345.00058 -230.37038)
		(width 0.1143)
		(layer "In11.Cu")
		(net "GMI_CPU1_G3_CPU0_G1_TX_DN<15>")
	)
	(arc
		(start 126.71933 -229.094538)
		(mid 126.677781 -228.923116)
		(end 126.562358 -228.789738)
		(width 0.1143)
		(layer "In11.Cu")
		(net "GMI_CPU1_G3_CPU0_G1_TX_DN<15>")
	)
	(arc
		(start 344.776552 -230.714296)
		(mid 344.712037 -230.976515)
		(end 344.53322 -231.178862)
		(width 0.1143)
		(layer "In11.Cu")
		(net "GMI_CPU1_G3_CPU0_G1_TX_DN<15>")
	)
	(arc
		(start 345.143836 -222.128334)
		(mid 345.079041 -222.205431)
		(end 345.001596 -222.269812)
		(width 0.1143)
		(layer "In11.Cu")
		(net "GMI_CPU1_G3_CPU0_G1_TX_DN<15>")
	)
	(arc
		(start 344.933524 -228.789484)
		(mid 344.818097 -228.92286)
		(end 344.776552 -229.094284)
		(width 0.1143)
		(layer "In11.Cu")
		(net "GMI_CPU1_G3_CPU0_G1_TX_DN<15>")
	)
	(arc
		(start 345.00312 -222.959676)
		(mid 345.246447 -223.424242)
		(end 345.00312 -223.888808)
		(width 0.1143)
		(layer "In11.Cu")
		(net "GMI_CPU1_G3_CPU0_G1_TX_DN<15>")
	)
	(arc
		(start 126.56439 -229.398068)
		(mid 126.678319 -229.264921)
		(end 126.71933 -229.094538)
		(width 0.1143)
		(layer "In11.Cu")
		(net "GMI_CPU1_G3_CPU0_G1_TX_DN<15>")
	)
	(arc
		(start 126.352046 -222.128588)
		(mid 126.276068 -221.974392)
		(end 126.249938 -221.804484)
		(width 0.1143)
		(layer "In11.Cu")
		(net "GMI_CPU1_G3_CPU0_G1_TX_DN<15>")
	)
	(arc
		(start 345.00312 -226.1997)
		(mid 345.246447 -226.664266)
		(end 345.00312 -227.128832)
		(width 0.1143)
		(layer "In11.Cu")
		(net "GMI_CPU1_G3_CPU0_G1_TX_DN<15>")
	)
	(arc
		(start 344.776552 -229.094284)
		(mid 344.817518 -229.26469)
		(end 344.931492 -229.397814)
		(width 0.1143)
		(layer "In11.Cu")
		(net "GMI_CPU1_G3_CPU0_G1_TX_DN<15>")
	)
	(arc
		(start 345.245944 -221.80423)
		(mid 345.219861 -221.974153)
		(end 345.143836 -222.128334)
		(width 0.1143)
		(layer "In11.Cu")
		(net "GMI_CPU1_G3_CPU0_G1_TX_DN<15>")
	)
	(arc
		(start 125.779276 -233.95432)
		(mid 125.843791 -233.692101)
		(end 126.022608 -233.489754)
		(width 0.1143)
		(layer "In11.Cu")
		(net "GMI_CPU1_G3_CPU0_G1_TX_DN<15>")
	)
	(arc
		(start 126.24943 -229.90429)
		(mid 126.313945 -229.642071)
		(end 126.492762 -229.439724)
		(width 0.1143)
		(layer "In11.Cu")
		(net "GMI_CPU1_G3_CPU0_G1_TX_DN<15>")
	)
	(segment
		(start 124.467874 -233.410252)
		(end 124.934726 -233.144314)
		(width 0.12954)
		(layer "F.Cu")
		(net "GMI_CPU1_G3_CPU0_G1_TX_DN<14>")
	)
	(segment
		(start 347.028008 -233.409998)
		(end 346.561156 -233.14406)
		(width 0.12954)
		(layer "F.Cu")
		(net "GMI_CPU1_G3_CPU0_G1_TX_DN<14>")
	)
	(segment
		(start 345.343226 -219.135452)
		(end 346.236798 -220.638624)
		(width 0.14224)
		(layer "In11.Cu")
		(net "GMI_CPU1_G3_CPU0_G1_TX_DN<14>")
	)
	(segment
		(start 345.434158 -231.846628)
		(end 345.435174 -231.847136)
		(width 0.1143)
		(layer "In11.Cu")
		(net "GMI_CPU1_G3_CPU0_G1_TX_DN<14>")
	)
	(segment
		(start 125.622304 -225.549714)
		(end 125.591824 -225.531934)
		(width 0.1143)
		(layer "In11.Cu")
		(net "GMI_CPU1_G3_CPU0_G1_TX_DN<14>")
	)
	(segment
		(start 345.873578 -222.919036)
		(end 345.943174 -222.959676)
		(width 0.1143)
		(layer "In11.Cu")
		(net "GMI_CPU1_G3_CPU0_G1_TX_DN<14>")
	)
	(segment
		(start 153.969974 -197.544944)
		(end 161.155634 -191.653922)
		(width 0.14224)
		(layer "In11.Cu")
		(net "GMI_CPU1_G3_CPU0_G1_TX_DN<14>")
	)
	(segment
		(start 125.259084 -221.203012)
		(end 125.259084 -221.174564)
		(width 0.1143)
		(layer "In11.Cu")
		(net "GMI_CPU1_G3_CPU0_G1_TX_DN<14>")
	)
	(segment
		(start 125.309884 -221.537022)
		(end 125.304804 -221.531942)
		(width 0.1143)
		(layer "In11.Cu")
		(net "GMI_CPU1_G3_CPU0_G1_TX_DN<14>")
	)
	(segment
		(start 126.061724 -231.201976)
		(end 126.022608 -231.179116)
		(width 0.1143)
		(layer "In11.Cu")
		(net "GMI_CPU1_G3_CPU0_G1_TX_DN<14>")
	)
	(segment
		(start 126.350014 -218.896692)
		(end 146.839178 -202.09637)
		(width 0.14224)
		(layer "In11.Cu")
		(net "GMI_CPU1_G3_CPU0_G1_TX_DN<14>")
	)
	(segment
		(start 125.309884 -221.804484)
		(end 125.309884 -221.537022)
		(width 0.1143)
		(layer "In11.Cu")
		(net "GMI_CPU1_G3_CPU0_G1_TX_DN<14>")
	)
	(segment
		(start 346.191078 -221.531688)
		(end 346.185998 -221.536768)
		(width 0.1143)
		(layer "In11.Cu")
		(net "GMI_CPU1_G3_CPU0_G1_TX_DN<14>")
	)
	(segment
		(start 317.269622 -196.116956)
		(end 345.343226 -219.135452)
		(width 0.14224)
		(layer "In11.Cu")
		(net "GMI_CPU1_G3_CPU0_G1_TX_DN<14>")
	)
	(segment
		(start 239.831626 -199.786494)
		(end 251.312934 -191.746886)
		(width 0.14224)
		(layer "In11.Cu")
		(net "GMI_CPU1_G3_CPU0_G1_TX_DN<14>")
	)
	(segment
		(start 126.095252 -231.221534)
		(end 126.061724 -231.201976)
		(width 0.1143)
		(layer "In11.Cu")
		(net "GMI_CPU1_G3_CPU0_G1_TX_DN<14>")
	)
	(segment
		(start 125.622304 -222.30969)
		(end 125.554232 -222.270066)
		(width 0.1143)
		(layer "In11.Cu")
		(net "GMI_CPU1_G3_CPU0_G1_TX_DN<14>")
	)
	(segment
		(start 125.232668 -233.144314)
		(end 125.315472 -233.06151)
		(width 0.1143)
		(layer "In11.Cu")
		(net "GMI_CPU1_G3_CPU0_G1_TX_DN<14>")
	)
	(segment
		(start 126.072138 -231.84104)
		(end 126.093474 -231.828594)
		(width 0.1143)
		(layer "In11.Cu")
		(net "GMI_CPU1_G3_CPU0_G1_TX_DN<14>")
	)
	(segment
		(start 125.552708 -232.679748)
		(end 125.591824 -232.656888)
		(width 0.1143)
		(layer "In11.Cu")
		(net "GMI_CPU1_G3_CPU0_G1_TX_DN<14>")
	)
	(segment
		(start 125.591824 -226.177094)
		(end 125.622304 -226.159314)
		(width 0.1143)
		(layer "In11.Cu")
		(net "GMI_CPU1_G3_CPU0_G1_TX_DN<14>")
	)
	(segment
		(start 125.622304 -227.169726)
		(end 125.591824 -227.151946)
		(width 0.1143)
		(layer "In11.Cu")
		(net "GMI_CPU1_G3_CPU0_G1_TX_DN<14>")
	)
	(segment
		(start 345.873578 -232.638854)
		(end 345.943174 -232.679494)
		(width 0.1143)
		(layer "In11.Cu")
		(net "GMI_CPU1_G3_CPU0_G1_TX_DN<14>")
	)
	(segment
		(start 345.873578 -226.15906)
		(end 345.943174 -226.1997)
		(width 0.1143)
		(layer "In11.Cu")
		(net "GMI_CPU1_G3_CPU0_G1_TX_DN<14>")
	)
	(segment
		(start 126.062486 -231.846374)
		(end 126.06528 -231.84485)
		(width 0.1143)
		(layer "In11.Cu")
		(net "GMI_CPU1_G3_CPU0_G1_TX_DN<14>")
	)
	(segment
		(start 124.934726 -233.144314)
		(end 125.232668 -233.144314)
		(width 0.1143)
		(layer "In11.Cu")
		(net "GMI_CPU1_G3_CPU0_G1_TX_DN<14>")
	)
	(segment
		(start 346.185998 -221.536768)
		(end 346.185998 -221.80423)
		(width 0.1143)
		(layer "In11.Cu")
		(net "GMI_CPU1_G3_CPU0_G1_TX_DN<14>")
	)
	(segment
		(start 345.904058 -229.41661)
		(end 345.943174 -229.43947)
		(width 0.1143)
		(layer "In11.Cu")
		(net "GMI_CPU1_G3_CPU0_G1_TX_DN<14>")
	)
	(segment
		(start 345.943174 -227.128832)
		(end 345.873578 -227.169472)
		(width 0.1143)
		(layer "In11.Cu")
		(net "GMI_CPU1_G3_CPU0_G1_TX_DN<14>")
	)
	(segment
		(start 125.304804 -221.248732)
		(end 125.259084 -221.203012)
		(width 0.1143)
		(layer "In11.Cu")
		(net "GMI_CPU1_G3_CPU0_G1_TX_DN<14>")
	)
	(segment
		(start 162.529266 -190.198502)
		(end 207.282288 -190.009018)
		(width 0.14224)
		(layer "In11.Cu")
		(net "GMI_CPU1_G3_CPU0_G1_TX_DN<14>")
	)
	(segment
		(start 345.943174 -223.888808)
		(end 345.873578 -223.929448)
		(width 0.1143)
		(layer "In11.Cu")
		(net "GMI_CPU1_G3_CPU0_G1_TX_DN<14>")
	)
	(segment
		(start 126.060708 -231.84739)
		(end 126.061724 -231.846882)
		(width 0.1143)
		(layer "In11.Cu")
		(net "GMI_CPU1_G3_CPU0_G1_TX_DN<14>")
	)
	(segment
		(start 346.191078 -221.248478)
		(end 346.191078 -221.531688)
		(width 0.1143)
		(layer "In11.Cu")
		(net "GMI_CPU1_G3_CPU0_G1_TX_DN<14>")
	)
	(segment
		(start 125.622304 -223.929702)
		(end 125.591824 -223.911922)
		(width 0.1143)
		(layer "In11.Cu")
		(net "GMI_CPU1_G3_CPU0_G1_TX_DN<14>")
	)
	(segment
		(start 126.068328 -231.843072)
		(end 126.069598 -231.84231)
		(width 0.1143)
		(layer "In11.Cu")
		(net "GMI_CPU1_G3_CPU0_G1_TX_DN<14>")
	)
	(segment
		(start 125.591824 -228.771958)
		(end 125.552708 -228.749098)
		(width 0.1143)
		(layer "In11.Cu")
		(net "GMI_CPU1_G3_CPU0_G1_TX_DN<14>")
	)
	(segment
		(start 303.734724 -190.109856)
		(end 308.735476 -190.109856)
		(width 0.14224)
		(layer "In11.Cu")
		(net "GMI_CPU1_G3_CPU0_G1_TX_DN<14>")
	)
	(segment
		(start 345.943174 -228.748844)
		(end 345.873578 -228.789484)
		(width 0.1143)
		(layer "In11.Cu")
		(net "GMI_CPU1_G3_CPU0_G1_TX_DN<14>")
	)
	(segment
		(start 345.436698 -231.848152)
		(end 345.437714 -231.84866)
		(width 0.1143)
		(layer "In11.Cu")
		(net "GMI_CPU1_G3_CPU0_G1_TX_DN<14>")
	)
	(segment
		(start 126.066042 -231.844342)
		(end 126.067566 -231.84358)
		(width 0.1143)
		(layer "In11.Cu")
		(net "GMI_CPU1_G3_CPU0_G1_TX_DN<14>")
	)
	(segment
		(start 125.304804 -221.531942)
		(end 125.304804 -221.248732)
		(width 0.1143)
		(layer "In11.Cu")
		(net "GMI_CPU1_G3_CPU0_G1_TX_DN<14>")
	)
	(segment
		(start 308.735476 -190.109856)
		(end 317.269622 -196.116956)
		(width 0.14224)
		(layer "In11.Cu")
		(net "GMI_CPU1_G3_CPU0_G1_TX_DN<14>")
	)
	(segment
		(start 207.282288 -190.009018)
		(end 210.873594 -190.643002)
		(width 0.14224)
		(layer "In11.Cu")
		(net "GMI_CPU1_G3_CPU0_G1_TX_DN<14>")
	)
	(segment
		(start 126.061724 -231.846882)
		(end 126.062486 -231.846374)
		(width 0.1143)
		(layer "In11.Cu")
		(net "GMI_CPU1_G3_CPU0_G1_TX_DN<14>")
	)
	(segment
		(start 251.312934 -191.746886)
		(end 262.742426 -189.73165)
		(width 0.14224)
		(layer "In11.Cu")
		(net "GMI_CPU1_G3_CPU0_G1_TX_DN<14>")
	)
	(segment
		(start 262.742426 -189.73165)
		(end 303.734724 -190.109856)
		(width 0.14224)
		(layer "In11.Cu")
		(net "GMI_CPU1_G3_CPU0_G1_TX_DN<14>")
	)
	(segment
		(start 126.067566 -231.84358)
		(end 126.068328 -231.843072)
		(width 0.1143)
		(layer "In11.Cu")
		(net "GMI_CPU1_G3_CPU0_G1_TX_DN<14>")
	)
	(segment
		(start 126.069598 -231.84231)
		(end 126.072138 -231.84104)
		(width 0.1143)
		(layer "In11.Cu")
		(net "GMI_CPU1_G3_CPU0_G1_TX_DN<14>")
	)
	(segment
		(start 125.591824 -223.911922)
		(end 125.552708 -223.889062)
		(width 0.1143)
		(layer "In11.Cu")
		(net "GMI_CPU1_G3_CPU0_G1_TX_DN<14>")
	)
	(segment
		(start 346.236798 -221.17431)
		(end 346.236798 -221.202758)
		(width 0.1143)
		(layer "In11.Cu")
		(net "GMI_CPU1_G3_CPU0_G1_TX_DN<14>")
	)
	(segment
		(start 146.839178 -202.09637)
		(end 149.344634 -201.33691)
		(width 0.14224)
		(layer "In11.Cu")
		(net "GMI_CPU1_G3_CPU0_G1_TX_DN<14>")
	)
	(segment
		(start 125.552708 -227.819966)
		(end 125.591824 -227.797106)
		(width 0.1143)
		(layer "In11.Cu")
		(net "GMI_CPU1_G3_CPU0_G1_TX_DN<14>")
	)
	(segment
		(start 125.591824 -225.531934)
		(end 125.552708 -225.509074)
		(width 0.1143)
		(layer "In11.Cu")
		(net "GMI_CPU1_G3_CPU0_G1_TX_DN<14>")
	)
	(segment
		(start 125.622304 -230.40975)
		(end 125.555248 -230.370634)
		(width 0.1143)
		(layer "In11.Cu")
		(net "GMI_CPU1_G3_CPU0_G1_TX_DN<14>")
	)
	(segment
		(start 345.873578 -224.539048)
		(end 345.943174 -224.579688)
		(width 0.1143)
		(layer "In11.Cu")
		(net "GMI_CPU1_G3_CPU0_G1_TX_DN<14>")
	)
	(segment
		(start 345.402408 -231.82834)
		(end 345.433396 -231.84612)
		(width 0.1143)
		(layer "In11.Cu")
		(net "GMI_CPU1_G3_CPU0_G1_TX_DN<14>")
	)
	(segment
		(start 125.259084 -220.823536)
		(end 126.350014 -218.896692)
		(width 0.14224)
		(layer "In11.Cu")
		(net "GMI_CPU1_G3_CPU0_G1_TX_DN<14>")
	)
	(segment
		(start 153.970228 -197.544944)
		(end 153.969974 -197.544944)
		(width 0.14224)
		(layer "In11.Cu")
		(net "GMI_CPU1_G3_CPU0_G1_TX_DN<14>")
	)
	(segment
		(start 345.433396 -231.84612)
		(end 345.434158 -231.846628)
		(width 0.1143)
		(layer "In11.Cu")
		(net "GMI_CPU1_G3_CPU0_G1_TX_DN<14>")
	)
	(segment
		(start 346.236798 -220.638624)
		(end 346.236798 -221.17431)
		(width 0.14224)
		(layer "In11.Cu")
		(net "GMI_CPU1_G3_CPU0_G1_TX_DN<14>")
	)
	(segment
		(start 346.263214 -233.14406)
		(end 346.561156 -233.14406)
		(width 0.1143)
		(layer "In11.Cu")
		(net "GMI_CPU1_G3_CPU0_G1_TX_DN<14>")
	)
	(segment
		(start 125.552708 -226.199954)
		(end 125.591824 -226.177094)
		(width 0.1143)
		(layer "In11.Cu")
		(net "GMI_CPU1_G3_CPU0_G1_TX_DN<14>")
	)
	(segment
		(start 149.344634 -201.33691)
		(end 153.970228 -197.544944)
		(width 0.14224)
		(layer "In11.Cu")
		(net "GMI_CPU1_G3_CPU0_G1_TX_DN<14>")
	)
	(segment
		(start 125.622304 -228.789738)
		(end 125.591824 -228.771958)
		(width 0.1143)
		(layer "In11.Cu")
		(net "GMI_CPU1_G3_CPU0_G1_TX_DN<14>")
	)
	(segment
		(start 125.591824 -227.797106)
		(end 125.622304 -227.779326)
		(width 0.1143)
		(layer "In11.Cu")
		(net "GMI_CPU1_G3_CPU0_G1_TX_DN<14>")
	)
	(segment
		(start 125.591824 -232.656888)
		(end 125.622304 -232.639108)
		(width 0.1143)
		(layer "In11.Cu")
		(net "GMI_CPU1_G3_CPU0_G1_TX_DN<14>")
	)
	(segment
		(start 345.943174 -225.50882)
		(end 345.873578 -225.54946)
		(width 0.1143)
		(layer "In11.Cu")
		(net "GMI_CPU1_G3_CPU0_G1_TX_DN<14>")
	)
	(segment
		(start 345.435174 -231.847136)
		(end 345.436698 -231.848152)
		(width 0.1143)
		(layer "In11.Cu")
		(net "GMI_CPU1_G3_CPU0_G1_TX_DN<14>")
	)
	(segment
		(start 125.552708 -222.95993)
		(end 125.591824 -222.93707)
		(width 0.1143)
		(layer "In11.Cu")
		(net "GMI_CPU1_G3_CPU0_G1_TX_DN<14>")
	)
	(segment
		(start 126.022608 -231.869742)
		(end 126.059184 -231.848406)
		(width 0.1143)
		(layer "In11.Cu")
		(net "GMI_CPU1_G3_CPU0_G1_TX_DN<14>")
	)
	(segment
		(start 125.591824 -224.557082)
		(end 125.622304 -224.539302)
		(width 0.1143)
		(layer "In11.Cu")
		(net "GMI_CPU1_G3_CPU0_G1_TX_DN<14>")
	)
	(segment
		(start 125.259084 -221.174564)
		(end 125.259084 -220.823536)
		(width 0.14224)
		(layer "In11.Cu")
		(net "GMI_CPU1_G3_CPU0_G1_TX_DN<14>")
	)
	(segment
		(start 125.591824 -222.93707)
		(end 125.622304 -222.91929)
		(width 0.1143)
		(layer "In11.Cu")
		(net "GMI_CPU1_G3_CPU0_G1_TX_DN<14>")
	)
	(segment
		(start 125.552708 -229.439724)
		(end 125.591824 -229.416864)
		(width 0.1143)
		(layer "In11.Cu")
		(net "GMI_CPU1_G3_CPU0_G1_TX_DN<14>")
	)
	(segment
		(start 345.871546 -229.397814)
		(end 345.904058 -229.41661)
		(width 0.1143)
		(layer "In11.Cu")
		(net "GMI_CPU1_G3_CPU0_G1_TX_DN<14>")
	)
	(segment
		(start 345.437714 -231.84866)
		(end 345.473274 -231.869488)
		(width 0.1143)
		(layer "In11.Cu")
		(net "GMI_CPU1_G3_CPU0_G1_TX_DN<14>")
	)
	(segment
		(start 126.06528 -231.84485)
		(end 126.066042 -231.844342)
		(width 0.1143)
		(layer "In11.Cu")
		(net "GMI_CPU1_G3_CPU0_G1_TX_DN<14>")
	)
	(segment
		(start 210.873594 -190.643002)
		(end 233.086148 -199.843136)
		(width 0.14224)
		(layer "In11.Cu")
		(net "GMI_CPU1_G3_CPU0_G1_TX_DN<14>")
	)
	(segment
		(start 346.18041 -233.061256)
		(end 346.263214 -233.14406)
		(width 0.1143)
		(layer "In11.Cu")
		(net "GMI_CPU1_G3_CPU0_G1_TX_DN<14>")
	)
	(segment
		(start 233.086148 -199.843136)
		(end 236.299756 -200.409556)
		(width 0.14224)
		(layer "In11.Cu")
		(net "GMI_CPU1_G3_CPU0_G1_TX_DN<14>")
	)
	(segment
		(start 161.468816 -191.068706)
		(end 162.529266 -190.198502)
		(width 0.14224)
		(layer "In11.Cu")
		(net "GMI_CPU1_G3_CPU0_G1_TX_DN<14>")
	)
	(segment
		(start 125.591824 -229.416864)
		(end 125.624336 -229.398068)
		(width 0.1143)
		(layer "In11.Cu")
		(net "GMI_CPU1_G3_CPU0_G1_TX_DN<14>")
	)
	(segment
		(start 126.059184 -231.848406)
		(end 126.060708 -231.84739)
		(width 0.1143)
		(layer "In11.Cu")
		(net "GMI_CPU1_G3_CPU0_G1_TX_DN<14>")
	)
	(segment
		(start 346.236798 -221.202758)
		(end 346.191078 -221.248478)
		(width 0.1143)
		(layer "In11.Cu")
		(net "GMI_CPU1_G3_CPU0_G1_TX_DN<14>")
	)
	(segment
		(start 161.155634 -191.653922)
		(end 161.468816 -191.068706)
		(width 0.14224)
		(layer "In11.Cu")
		(net "GMI_CPU1_G3_CPU0_G1_TX_DN<14>")
	)
	(segment
		(start 345.94165 -222.269812)
		(end 345.873578 -222.309436)
		(width 0.1143)
		(layer "In11.Cu")
		(net "GMI_CPU1_G3_CPU0_G1_TX_DN<14>")
	)
	(segment
		(start 345.940634 -230.37038)
		(end 345.873578 -230.409496)
		(width 0.1143)
		(layer "In11.Cu")
		(net "GMI_CPU1_G3_CPU0_G1_TX_DN<14>")
	)
	(segment
		(start 345.473274 -231.178862)
		(end 345.40063 -231.22128)
		(width 0.1143)
		(layer "In11.Cu")
		(net "GMI_CPU1_G3_CPU0_G1_TX_DN<14>")
	)
	(segment
		(start 236.299756 -200.409556)
		(end 239.831626 -199.786494)
		(width 0.14224)
		(layer "In11.Cu")
		(net "GMI_CPU1_G3_CPU0_G1_TX_DN<14>")
	)
	(segment
		(start 345.873578 -227.779072)
		(end 345.943174 -227.819712)
		(width 0.1143)
		(layer "In11.Cu")
		(net "GMI_CPU1_G3_CPU0_G1_TX_DN<14>")
	)
	(segment
		(start 125.591824 -227.151946)
		(end 125.552708 -227.129086)
		(width 0.1143)
		(layer "In11.Cu")
		(net "GMI_CPU1_G3_CPU0_G1_TX_DN<14>")
	)
	(segment
		(start 125.552708 -224.579942)
		(end 125.591824 -224.557082)
		(width 0.1143)
		(layer "In11.Cu")
		(net "GMI_CPU1_G3_CPU0_G1_TX_DN<14>")
	)
	(arc
		(start 125.624336 -229.398068)
		(mid 125.738265 -229.264921)
		(end 125.779276 -229.094538)
		(width 0.1143)
		(layer "In11.Cu")
		(net "GMI_CPU1_G3_CPU0_G1_TX_DN<14>")
	)
	(arc
		(start 345.716606 -232.334054)
		(mid 345.758155 -232.505476)
		(end 345.873578 -232.638854)
		(width 0.1143)
		(layer "In11.Cu")
		(net "GMI_CPU1_G3_CPU0_G1_TX_DN<14>")
	)
	(arc
		(start 345.873578 -227.169472)
		(mid 345.716601 -227.474272)
		(end 345.873578 -227.779072)
		(width 0.1143)
		(layer "In11.Cu")
		(net "GMI_CPU1_G3_CPU0_G1_TX_DN<14>")
	)
	(arc
		(start 125.779276 -229.094538)
		(mid 125.737727 -228.923116)
		(end 125.622304 -228.789738)
		(width 0.1143)
		(layer "In11.Cu")
		(net "GMI_CPU1_G3_CPU0_G1_TX_DN<14>")
	)
	(arc
		(start 125.554232 -222.270066)
		(mid 125.374595 -222.067427)
		(end 125.309884 -221.804484)
		(width 0.1143)
		(layer "In11.Cu")
		(net "GMI_CPU1_G3_CPU0_G1_TX_DN<14>")
	)
	(arc
		(start 345.943174 -232.679494)
		(mid 346.095161 -232.836002)
		(end 346.1766 -233.038396)
		(width 0.1143)
		(layer "In11.Cu")
		(net "GMI_CPU1_G3_CPU0_G1_TX_DN<14>")
	)
	(arc
		(start 345.943174 -224.579688)
		(mid 346.186501 -225.044254)
		(end 345.943174 -225.50882)
		(width 0.1143)
		(layer "In11.Cu")
		(net "GMI_CPU1_G3_CPU0_G1_TX_DN<14>")
	)
	(arc
		(start 125.315472 -233.06151)
		(mid 125.31726 -233.050061)
		(end 125.319282 -233.03865)
		(width 0.1143)
		(layer "In11.Cu")
		(net "GMI_CPU1_G3_CPU0_G1_TX_DN<14>")
	)
	(arc
		(start 345.943174 -229.43947)
		(mid 346.121987 -229.64182)
		(end 346.186506 -229.904036)
		(width 0.1143)
		(layer "In11.Cu")
		(net "GMI_CPU1_G3_CPU0_G1_TX_DN<14>")
	)
	(arc
		(start 346.1766 -233.038396)
		(mid 346.178623 -233.049806)
		(end 346.18041 -233.061256)
		(width 0.1143)
		(layer "In11.Cu")
		(net "GMI_CPU1_G3_CPU0_G1_TX_DN<14>")
	)
	(arc
		(start 125.552708 -225.509074)
		(mid 125.309381 -225.044508)
		(end 125.552708 -224.579942)
		(width 0.1143)
		(layer "In11.Cu")
		(net "GMI_CPU1_G3_CPU0_G1_TX_DN<14>")
	)
	(arc
		(start 345.943174 -222.959676)
		(mid 346.186501 -223.424242)
		(end 345.943174 -223.888808)
		(width 0.1143)
		(layer "In11.Cu")
		(net "GMI_CPU1_G3_CPU0_G1_TX_DN<14>")
	)
	(arc
		(start 125.779276 -232.334308)
		(mid 125.843791 -232.072089)
		(end 126.022608 -231.869742)
		(width 0.1143)
		(layer "In11.Cu")
		(net "GMI_CPU1_G3_CPU0_G1_TX_DN<14>")
	)
	(arc
		(start 345.40063 -231.22128)
		(mid 345.287223 -231.354169)
		(end 345.246452 -231.524048)
		(width 0.1143)
		(layer "In11.Cu")
		(net "GMI_CPU1_G3_CPU0_G1_TX_DN<14>")
	)
	(arc
		(start 126.24943 -231.524302)
		(mid 126.208668 -231.354418)
		(end 126.095252 -231.221534)
		(width 0.1143)
		(layer "In11.Cu")
		(net "GMI_CPU1_G3_CPU0_G1_TX_DN<14>")
	)
	(arc
		(start 345.873578 -222.309436)
		(mid 345.716601 -222.614236)
		(end 345.873578 -222.919036)
		(width 0.1143)
		(layer "In11.Cu")
		(net "GMI_CPU1_G3_CPU0_G1_TX_DN<14>")
	)
	(arc
		(start 125.622304 -232.639108)
		(mid 125.737731 -232.505732)
		(end 125.779276 -232.334308)
		(width 0.1143)
		(layer "In11.Cu")
		(net "GMI_CPU1_G3_CPU0_G1_TX_DN<14>")
	)
	(arc
		(start 125.309376 -229.90429)
		(mid 125.373891 -229.642071)
		(end 125.552708 -229.439724)
		(width 0.1143)
		(layer "In11.Cu")
		(net "GMI_CPU1_G3_CPU0_G1_TX_DN<14>")
	)
	(arc
		(start 345.943174 -227.819712)
		(mid 346.186501 -228.284278)
		(end 345.943174 -228.748844)
		(width 0.1143)
		(layer "In11.Cu")
		(net "GMI_CPU1_G3_CPU0_G1_TX_DN<14>")
	)
	(arc
		(start 126.022608 -231.179116)
		(mid 125.843795 -230.976766)
		(end 125.779276 -230.71455)
		(width 0.1143)
		(layer "In11.Cu")
		(net "GMI_CPU1_G3_CPU0_G1_TX_DN<14>")
	)
	(arc
		(start 125.552708 -228.749098)
		(mid 125.309381 -228.284532)
		(end 125.552708 -227.819966)
		(width 0.1143)
		(layer "In11.Cu")
		(net "GMI_CPU1_G3_CPU0_G1_TX_DN<14>")
	)
	(arc
		(start 125.552708 -223.889062)
		(mid 125.309381 -223.424496)
		(end 125.552708 -222.95993)
		(width 0.1143)
		(layer "In11.Cu")
		(net "GMI_CPU1_G3_CPU0_G1_TX_DN<14>")
	)
	(arc
		(start 345.873578 -223.929448)
		(mid 345.716601 -224.234248)
		(end 345.873578 -224.539048)
		(width 0.1143)
		(layer "In11.Cu")
		(net "GMI_CPU1_G3_CPU0_G1_TX_DN<14>")
	)
	(arc
		(start 345.873578 -230.409496)
		(mid 345.758151 -230.542872)
		(end 345.716606 -230.714296)
		(width 0.1143)
		(layer "In11.Cu")
		(net "GMI_CPU1_G3_CPU0_G1_TX_DN<14>")
	)
	(arc
		(start 345.473274 -231.869488)
		(mid 345.652087 -232.071838)
		(end 345.716606 -232.334054)
		(width 0.1143)
		(layer "In11.Cu")
		(net "GMI_CPU1_G3_CPU0_G1_TX_DN<14>")
	)
	(arc
		(start 125.622304 -227.779326)
		(mid 125.779281 -227.474526)
		(end 125.622304 -227.169726)
		(width 0.1143)
		(layer "In11.Cu")
		(net "GMI_CPU1_G3_CPU0_G1_TX_DN<14>")
	)
	(arc
		(start 125.622304 -226.159314)
		(mid 125.779281 -225.854514)
		(end 125.622304 -225.549714)
		(width 0.1143)
		(layer "In11.Cu")
		(net "GMI_CPU1_G3_CPU0_G1_TX_DN<14>")
	)
	(arc
		(start 345.716606 -230.714296)
		(mid 345.652091 -230.976515)
		(end 345.473274 -231.178862)
		(width 0.1143)
		(layer "In11.Cu")
		(net "GMI_CPU1_G3_CPU0_G1_TX_DN<14>")
	)
	(arc
		(start 125.555248 -230.370634)
		(mid 125.374596 -230.167889)
		(end 125.309376 -229.90429)
		(width 0.1143)
		(layer "In11.Cu")
		(net "GMI_CPU1_G3_CPU0_G1_TX_DN<14>")
	)
	(arc
		(start 125.319282 -233.03865)
		(mid 125.400715 -232.836252)
		(end 125.552708 -232.679748)
		(width 0.1143)
		(layer "In11.Cu")
		(net "GMI_CPU1_G3_CPU0_G1_TX_DN<14>")
	)
	(arc
		(start 126.093474 -231.828594)
		(mid 126.20815 -231.69526)
		(end 126.24943 -231.524302)
		(width 0.1143)
		(layer "In11.Cu")
		(net "GMI_CPU1_G3_CPU0_G1_TX_DN<14>")
	)
	(arc
		(start 345.246452 -231.524048)
		(mid 345.287707 -231.695019)
		(end 345.402408 -231.82834)
		(width 0.1143)
		(layer "In11.Cu")
		(net "GMI_CPU1_G3_CPU0_G1_TX_DN<14>")
	)
	(arc
		(start 125.622304 -222.91929)
		(mid 125.779281 -222.61449)
		(end 125.622304 -222.30969)
		(width 0.1143)
		(layer "In11.Cu")
		(net "GMI_CPU1_G3_CPU0_G1_TX_DN<14>")
	)
	(arc
		(start 346.186506 -229.904036)
		(mid 346.12127 -230.167627)
		(end 345.940634 -230.37038)
		(width 0.1143)
		(layer "In11.Cu")
		(net "GMI_CPU1_G3_CPU0_G1_TX_DN<14>")
	)
	(arc
		(start 345.716606 -229.094284)
		(mid 345.757572 -229.26469)
		(end 345.871546 -229.397814)
		(width 0.1143)
		(layer "In11.Cu")
		(net "GMI_CPU1_G3_CPU0_G1_TX_DN<14>")
	)
	(arc
		(start 345.873578 -228.789484)
		(mid 345.758151 -228.92286)
		(end 345.716606 -229.094284)
		(width 0.1143)
		(layer "In11.Cu")
		(net "GMI_CPU1_G3_CPU0_G1_TX_DN<14>")
	)
	(arc
		(start 125.622304 -224.539302)
		(mid 125.779281 -224.234502)
		(end 125.622304 -223.929702)
		(width 0.1143)
		(layer "In11.Cu")
		(net "GMI_CPU1_G3_CPU0_G1_TX_DN<14>")
	)
	(arc
		(start 346.185998 -221.80423)
		(mid 346.121248 -222.067152)
		(end 345.94165 -222.269812)
		(width 0.1143)
		(layer "In11.Cu")
		(net "GMI_CPU1_G3_CPU0_G1_TX_DN<14>")
	)
	(arc
		(start 345.943174 -226.1997)
		(mid 346.186501 -226.664266)
		(end 345.943174 -227.128832)
		(width 0.1143)
		(layer "In11.Cu")
		(net "GMI_CPU1_G3_CPU0_G1_TX_DN<14>")
	)
	(arc
		(start 125.779276 -230.71455)
		(mid 125.737727 -230.543128)
		(end 125.622304 -230.40975)
		(width 0.1143)
		(layer "In11.Cu")
		(net "GMI_CPU1_G3_CPU0_G1_TX_DN<14>")
	)
	(arc
		(start 345.873578 -225.54946)
		(mid 345.716601 -225.85426)
		(end 345.873578 -226.15906)
		(width 0.1143)
		(layer "In11.Cu")
		(net "GMI_CPU1_G3_CPU0_G1_TX_DN<14>")
	)
	(arc
		(start 125.552708 -227.129086)
		(mid 125.309381 -226.66452)
		(end 125.552708 -226.199954)
		(width 0.1143)
		(layer "In11.Cu")
		(net "GMI_CPU1_G3_CPU0_G1_TX_DN<14>")
	)
	(segment
		(start 347.028008 -236.650022)
		(end 346.561156 -236.384084)
		(width 0.12954)
		(layer "F.Cu")
		(net "GMI_CPU1_G3_CPU0_G1_TX_DN<13>")
	)
	(segment
		(start 124.467874 -236.650276)
		(end 124.934726 -236.384338)
		(width 0.12954)
		(layer "F.Cu")
		(net "GMI_CPU1_G3_CPU0_G1_TX_DN<13>")
	)
	(segment
		(start 124.654818 -227.795328)
		(end 124.66447 -227.78974)
		(width 0.1143)
		(layer "In11.Cu")
		(net "GMI_CPU1_G3_CPU0_G1_TX_DN<13>")
	)
	(segment
		(start 125.122432 -236.062266)
		(end 125.12167 -236.061758)
		(width 0.1143)
		(layer "In11.Cu")
		(net "GMI_CPU1_G3_CPU0_G1_TX_DN<13>")
	)
	(segment
		(start 346.825824 -235.262166)
		(end 346.818458 -235.26623)
		(width 0.1143)
		(layer "In11.Cu")
		(net "GMI_CPU1_G3_CPU0_G1_TX_DN<13>")
	)
	(segment
		(start 124.612654 -224.579942)
		(end 124.681488 -224.53981)
		(width 0.1143)
		(layer "In11.Cu")
		(net "GMI_CPU1_G3_CPU0_G1_TX_DN<13>")
	)
	(segment
		(start 234.011978 -199.051418)
		(end 236.30128 -199.455024)
		(width 0.14224)
		(layer "In11.Cu")
		(net "GMI_CPU1_G3_CPU0_G1_TX_DN<13>")
	)
	(segment
		(start 125.12167 -236.061758)
		(end 125.119384 -236.060488)
		(width 0.1143)
		(layer "In11.Cu")
		(net "GMI_CPU1_G3_CPU0_G1_TX_DN<13>")
	)
	(segment
		(start 346.848938 -227.799392)
		(end 346.850462 -227.800408)
		(width 0.1143)
		(layer "In11.Cu")
		(net "GMI_CPU1_G3_CPU0_G1_TX_DN<13>")
	)
	(segment
		(start 346.84335 -222.936308)
		(end 346.844112 -222.936816)
		(width 0.1143)
		(layer "In11.Cu")
		(net "GMI_CPU1_G3_CPU0_G1_TX_DN<13>")
	)
	(segment
		(start 346.844112 -222.936816)
		(end 346.845128 -222.937324)
		(width 0.1143)
		(layer "In11.Cu")
		(net "GMI_CPU1_G3_CPU0_G1_TX_DN<13>")
	)
	(segment
		(start 346.829126 -235.260134)
		(end 346.828364 -235.260642)
		(width 0.1143)
		(layer "In11.Cu")
		(net "GMI_CPU1_G3_CPU0_G1_TX_DN<13>")
	)
	(segment
		(start 124.66447 -227.78974)
		(end 124.666502 -227.78847)
		(width 0.1143)
		(layer "In11.Cu")
		(net "GMI_CPU1_G3_CPU0_G1_TX_DN<13>")
	)
	(segment
		(start 124.66828 -227.787454)
		(end 124.673868 -227.784406)
		(width 0.1143)
		(layer "In11.Cu")
		(net "GMI_CPU1_G3_CPU0_G1_TX_DN<13>")
	)
	(segment
		(start 346.827602 -227.7872)
		(end 346.82938 -227.788216)
		(width 0.1143)
		(layer "In11.Cu")
		(net "GMI_CPU1_G3_CPU0_G1_TX_DN<13>")
	)
	(segment
		(start 124.68352 -233.650028)
		(end 124.65177 -233.63174)
		(width 0.1143)
		(layer "In11.Cu")
		(net "GMI_CPU1_G3_CPU0_G1_TX_DN<13>")
	)
	(segment
		(start 124.681488 -225.549206)
		(end 124.612654 -225.509074)
		(width 0.1143)
		(layer "In11.Cu")
		(net "GMI_CPU1_G3_CPU0_G1_TX_DN<13>")
	)
	(segment
		(start 124.65177 -222.93707)
		(end 124.652532 -222.936562)
		(width 0.1143)
		(layer "In11.Cu")
		(net "GMI_CPU1_G3_CPU0_G1_TX_DN<13>")
	)
	(segment
		(start 346.844112 -233.631486)
		(end 346.812362 -233.649774)
		(width 0.1143)
		(layer "In11.Cu")
		(net "GMI_CPU1_G3_CPU0_G1_TX_DN<13>")
	)
	(segment
		(start 124.649992 -227.798122)
		(end 124.650754 -227.797614)
		(width 0.1143)
		(layer "In11.Cu")
		(net "GMI_CPU1_G3_CPU0_G1_TX_DN<13>")
	)
	(segment
		(start 347.126306 -221.541594)
		(end 347.126306 -221.816676)
		(width 0.1143)
		(layer "In11.Cu")
		(net "GMI_CPU1_G3_CPU0_G1_TX_DN<13>")
	)
	(segment
		(start 346.263214 -236.384084)
		(end 346.561156 -236.384084)
		(width 0.1143)
		(layer "In11.Cu")
		(net "GMI_CPU1_G3_CPU0_G1_TX_DN<13>")
	)
	(segment
		(start 124.31395 -221.174564)
		(end 124.31395 -220.558106)
		(width 0.14224)
		(layer "In11.Cu")
		(net "GMI_CPU1_G3_CPU0_G1_TX_DN<13>")
	)
	(segment
		(start 346.88272 -227.12934)
		(end 346.822268 -227.164138)
		(width 0.1143)
		(layer "In11.Cu")
		(net "GMI_CPU1_G3_CPU0_G1_TX_DN<13>")
	)
	(segment
		(start 346.83573 -222.93199)
		(end 346.841318 -222.935038)
		(width 0.1143)
		(layer "In11.Cu")
		(net "GMI_CPU1_G3_CPU0_G1_TX_DN<13>")
	)
	(segment
		(start 346.851478 -227.800916)
		(end 346.882466 -227.819204)
		(width 0.1143)
		(layer "In11.Cu")
		(net "GMI_CPU1_G3_CPU0_G1_TX_DN<13>")
	)
	(segment
		(start 124.666502 -227.78847)
		(end 124.66828 -227.787454)
		(width 0.1143)
		(layer "In11.Cu")
		(net "GMI_CPU1_G3_CPU0_G1_TX_DN<13>")
	)
	(segment
		(start 346.841064 -227.795074)
		(end 346.842588 -227.79609)
		(width 0.1143)
		(layer "In11.Cu")
		(net "GMI_CPU1_G3_CPU0_G1_TX_DN<13>")
	)
	(segment
		(start 346.883228 -222.280988)
		(end 346.804742 -222.32747)
		(width 0.1143)
		(layer "In11.Cu")
		(net "GMI_CPU1_G3_CPU0_G1_TX_DN<13>")
	)
	(segment
		(start 347.181932 -220.404182)
		(end 347.181932 -221.17431)
		(width 0.14224)
		(layer "In11.Cu")
		(net "GMI_CPU1_G3_CPU0_G1_TX_DN<13>")
	)
	(segment
		(start 162.177984 -189.259972)
		(end 207.361536 -189.068202)
		(width 0.14224)
		(layer "In11.Cu")
		(net "GMI_CPU1_G3_CPU0_G1_TX_DN<13>")
	)
	(segment
		(start 160.63341 -190.526924)
		(end 162.177984 -189.259972)
		(width 0.14224)
		(layer "In11.Cu")
		(net "GMI_CPU1_G3_CPU0_G1_TX_DN<13>")
	)
	(segment
		(start 124.934726 -236.384338)
		(end 125.232668 -236.384338)
		(width 0.1143)
		(layer "In11.Cu")
		(net "GMI_CPU1_G3_CPU0_G1_TX_DN<13>")
	)
	(segment
		(start 124.69114 -222.327724)
		(end 124.612654 -222.281242)
		(width 0.1143)
		(layer "In11.Cu")
		(net "GMI_CPU1_G3_CPU0_G1_TX_DN<13>")
	)
	(segment
		(start 125.122432 -231.846374)
		(end 125.123702 -231.845612)
		(width 0.1143)
		(layer "In11.Cu")
		(net "GMI_CPU1_G3_CPU0_G1_TX_DN<13>")
	)
	(segment
		(start 125.12167 -231.846882)
		(end 125.122432 -231.846374)
		(width 0.1143)
		(layer "In11.Cu")
		(net "GMI_CPU1_G3_CPU0_G1_TX_DN<13>")
	)
	(segment
		(start 347.181932 -221.202758)
		(end 347.136212 -221.248478)
		(width 0.1143)
		(layer "In11.Cu")
		(net "GMI_CPU1_G3_CPU0_G1_TX_DN<13>")
	)
	(segment
		(start 124.64923 -232.659936)
		(end 124.652278 -232.658158)
		(width 0.1143)
		(layer "In11.Cu")
		(net "GMI_CPU1_G3_CPU0_G1_TX_DN<13>")
	)
	(segment
		(start 125.15342 -236.080046)
		(end 125.122432 -236.062266)
		(width 0.1143)
		(layer "In11.Cu")
		(net "GMI_CPU1_G3_CPU0_G1_TX_DN<13>")
	)
	(segment
		(start 346.82938 -227.788216)
		(end 346.831412 -227.789486)
		(width 0.1143)
		(layer "In11.Cu")
		(net "GMI_CPU1_G3_CPU0_G1_TX_DN<13>")
	)
	(segment
		(start 124.65177 -233.63174)
		(end 124.612654 -233.60888)
		(width 0.1143)
		(layer "In11.Cu")
		(net "GMI_CPU1_G3_CPU0_G1_TX_DN<13>")
	)
	(segment
		(start 346.37345 -231.84612)
		(end 346.374212 -231.846628)
		(width 0.1143)
		(layer "In11.Cu")
		(net "GMI_CPU1_G3_CPU0_G1_TX_DN<13>")
	)
	(segment
		(start 346.883228 -235.228638)
		(end 346.83573 -235.256324)
		(width 0.1143)
		(layer "In11.Cu")
		(net "GMI_CPU1_G3_CPU0_G1_TX_DN<13>")
	)
	(segment
		(start 124.650754 -222.937578)
		(end 124.65177 -222.93707)
		(width 0.1143)
		(layer "In11.Cu")
		(net "GMI_CPU1_G3_CPU0_G1_TX_DN<13>")
	)
	(segment
		(start 345.942666 -218.318842)
		(end 347.181932 -220.404182)
		(width 0.14224)
		(layer "In11.Cu")
		(net "GMI_CPU1_G3_CPU0_G1_TX_DN<13>")
	)
	(segment
		(start 346.374212 -231.846628)
		(end 346.410534 -231.86771)
		(width 0.1143)
		(layer "In11.Cu")
		(net "GMI_CPU1_G3_CPU0_G1_TX_DN<13>")
	)
	(segment
		(start 346.828364 -235.260642)
		(end 346.825824 -235.262166)
		(width 0.1143)
		(layer "In11.Cu")
		(net "GMI_CPU1_G3_CPU0_G1_TX_DN<13>")
	)
	(segment
		(start 124.613416 -222.959422)
		(end 124.649992 -222.938086)
		(width 0.1143)
		(layer "In11.Cu")
		(net "GMI_CPU1_G3_CPU0_G1_TX_DN<13>")
	)
	(segment
		(start 124.31395 -220.558106)
		(end 125.6538 -218.224862)
		(width 0.14224)
		(layer "In11.Cu")
		(net "GMI_CPU1_G3_CPU0_G1_TX_DN<13>")
	)
	(segment
		(start 124.612654 -234.29976)
		(end 124.65177 -234.2769)
		(width 0.1143)
		(layer "In11.Cu")
		(net "GMI_CPU1_G3_CPU0_G1_TX_DN<13>")
	)
	(segment
		(start 346.841318 -222.935038)
		(end 346.84335 -222.936308)
		(width 0.1143)
		(layer "In11.Cu")
		(net "GMI_CPU1_G3_CPU0_G1_TX_DN<13>")
	)
	(segment
		(start 125.088142 -231.182418)
		(end 125.085348 -231.180894)
		(width 0.1143)
		(layer "In11.Cu")
		(net "GMI_CPU1_G3_CPU0_G1_TX_DN<13>")
	)
	(segment
		(start 346.814394 -229.399846)
		(end 346.885006 -229.440994)
		(width 0.1143)
		(layer "In11.Cu")
		(net "GMI_CPU1_G3_CPU0_G1_TX_DN<13>")
	)
	(segment
		(start 124.649992 -222.938086)
		(end 124.650754 -222.937578)
		(width 0.1143)
		(layer "In11.Cu")
		(net "GMI_CPU1_G3_CPU0_G1_TX_DN<13>")
	)
	(segment
		(start 125.232668 -236.384338)
		(end 125.302518 -236.314488)
		(width 0.1143)
		(layer "In11.Cu")
		(net "GMI_CPU1_G3_CPU0_G1_TX_DN<13>")
	)
	(segment
		(start 346.193364 -236.314234)
		(end 346.263214 -236.384084)
		(width 0.1143)
		(layer "In11.Cu")
		(net "GMI_CPU1_G3_CPU0_G1_TX_DN<13>")
	)
	(segment
		(start 346.83573 -235.256324)
		(end 346.834206 -235.257086)
		(width 0.1143)
		(layer "In11.Cu")
		(net "GMI_CPU1_G3_CPU0_G1_TX_DN<13>")
	)
	(segment
		(start 346.831412 -227.789486)
		(end 346.841064 -227.795074)
		(width 0.1143)
		(layer "In11.Cu")
		(net "GMI_CPU1_G3_CPU0_G1_TX_DN<13>")
	)
	(segment
		(start 346.883228 -225.50882)
		(end 346.814394 -225.548952)
		(width 0.1143)
		(layer "In11.Cu")
		(net "GMI_CPU1_G3_CPU0_G1_TX_DN<13>")
	)
	(segment
		(start 347.136212 -221.248478)
		(end 347.136212 -221.531688)
		(width 0.1143)
		(layer "In11.Cu")
		(net "GMI_CPU1_G3_CPU0_G1_TX_DN<13>")
	)
	(segment
		(start 346.37345 -236.062012)
		(end 346.342462 -236.079792)
		(width 0.1143)
		(layer "In11.Cu")
		(net "GMI_CPU1_G3_CPU0_G1_TX_DN<13>")
	)
	(segment
		(start 347.181932 -221.17431)
		(end 347.181932 -221.202758)
		(width 0.1143)
		(layer "In11.Cu")
		(net "GMI_CPU1_G3_CPU0_G1_TX_DN<13>")
	)
	(segment
		(start 160.47847 -190.815722)
		(end 160.63341 -190.526924)
		(width 0.14224)
		(layer "In11.Cu")
		(net "GMI_CPU1_G3_CPU0_G1_TX_DN<13>")
	)
	(segment
		(start 125.6538 -218.224862)
		(end 146.366738 -201.241914)
		(width 0.14224)
		(layer "In11.Cu")
		(net "GMI_CPU1_G3_CPU0_G1_TX_DN<13>")
	)
	(segment
		(start 346.831412 -235.258864)
		(end 346.829126 -235.260134)
		(width 0.1143)
		(layer "In11.Cu")
		(net "GMI_CPU1_G3_CPU0_G1_TX_DN<13>")
	)
	(segment
		(start 125.123702 -231.845612)
		(end 125.15342 -231.828594)
		(width 0.1143)
		(layer "In11.Cu")
		(net "GMI_CPU1_G3_CPU0_G1_TX_DN<13>")
	)
	(segment
		(start 346.822014 -227.784152)
		(end 346.827602 -227.7872)
		(width 0.1143)
		(layer "In11.Cu")
		(net "GMI_CPU1_G3_CPU0_G1_TX_DN<13>")
	)
	(segment
		(start 124.369576 -221.541848)
		(end 124.35967 -221.531942)
		(width 0.1143)
		(layer "In11.Cu")
		(net "GMI_CPU1_G3_CPU0_G1_TX_DN<13>")
	)
	(segment
		(start 318.311276 -195.663312)
		(end 345.942666 -218.318842)
		(width 0.14224)
		(layer "In11.Cu")
		(net "GMI_CPU1_G3_CPU0_G1_TX_DN<13>")
	)
	(segment
		(start 239.461294 -198.897748)
		(end 250.94438 -190.857124)
		(width 0.14224)
		(layer "In11.Cu")
		(net "GMI_CPU1_G3_CPU0_G1_TX_DN<13>")
	)
	(segment
		(start 250.94438 -190.857124)
		(end 262.665464 -188.790326)
		(width 0.14224)
		(layer "In11.Cu")
		(net "GMI_CPU1_G3_CPU0_G1_TX_DN<13>")
	)
	(segment
		(start 125.085348 -231.867964)
		(end 125.12167 -231.846882)
		(width 0.1143)
		(layer "In11.Cu")
		(net "GMI_CPU1_G3_CPU0_G1_TX_DN<13>")
	)
	(segment
		(start 124.35967 -221.531942)
		(end 124.35967 -221.248732)
		(width 0.1143)
		(layer "In11.Cu")
		(net "GMI_CPU1_G3_CPU0_G1_TX_DN<13>")
	)
	(segment
		(start 346.84589 -227.797868)
		(end 346.848938 -227.799392)
		(width 0.1143)
		(layer "In11.Cu")
		(net "GMI_CPU1_G3_CPU0_G1_TX_DN<13>")
	)
	(segment
		(start 124.653294 -227.796344)
		(end 124.654818 -227.795328)
		(width 0.1143)
		(layer "In11.Cu")
		(net "GMI_CPU1_G3_CPU0_G1_TX_DN<13>")
	)
	(segment
		(start 124.613416 -227.819458)
		(end 124.649992 -227.798122)
		(width 0.1143)
		(layer "In11.Cu")
		(net "GMI_CPU1_G3_CPU0_G1_TX_DN<13>")
	)
	(segment
		(start 346.883228 -233.608626)
		(end 346.844112 -233.631486)
		(width 0.1143)
		(layer "In11.Cu")
		(net "GMI_CPU1_G3_CPU0_G1_TX_DN<13>")
	)
	(segment
		(start 346.376498 -236.060234)
		(end 346.374212 -236.061504)
		(width 0.1143)
		(layer "In11.Cu")
		(net "GMI_CPU1_G3_CPU0_G1_TX_DN<13>")
	)
	(segment
		(start 124.610876 -229.441248)
		(end 124.681488 -229.4001)
		(width 0.1143)
		(layer "In11.Cu")
		(net "GMI_CPU1_G3_CPU0_G1_TX_DN<13>")
	)
	(segment
		(start 236.30128 -199.455024)
		(end 239.461294 -198.897748)
		(width 0.14224)
		(layer "In11.Cu")
		(net "GMI_CPU1_G3_CPU0_G1_TX_DN<13>")
	)
	(segment
		(start 346.834206 -235.257086)
		(end 346.831412 -235.258864)
		(width 0.1143)
		(layer "In11.Cu")
		(net "GMI_CPU1_G3_CPU0_G1_TX_DN<13>")
	)
	(segment
		(start 346.814394 -224.539556)
		(end 346.883228 -224.579688)
		(width 0.1143)
		(layer "In11.Cu")
		(net "GMI_CPU1_G3_CPU0_G1_TX_DN<13>")
	)
	(segment
		(start 125.155198 -231.221534)
		(end 125.088142 -231.182418)
		(width 0.1143)
		(layer "In11.Cu")
		(net "GMI_CPU1_G3_CPU0_G1_TX_DN<13>")
	)
	(segment
		(start 346.37218 -231.845358)
		(end 346.37345 -231.84612)
		(width 0.1143)
		(layer "In11.Cu")
		(net "GMI_CPU1_G3_CPU0_G1_TX_DN<13>")
	)
	(segment
		(start 346.84716 -230.387144)
		(end 346.842842 -230.389684)
		(width 0.1143)
		(layer "In11.Cu")
		(net "GMI_CPU1_G3_CPU0_G1_TX_DN<13>")
	)
	(segment
		(start 146.366738 -201.241914)
		(end 148.580856 -200.5711)
		(width 0.14224)
		(layer "In11.Cu")
		(net "GMI_CPU1_G3_CPU0_G1_TX_DN<13>")
	)
	(segment
		(start 303.734724 -189.169548)
		(end 309.09768 -189.169548)
		(width 0.14224)
		(layer "In11.Cu")
		(net "GMI_CPU1_G3_CPU0_G1_TX_DN<13>")
	)
	(segment
		(start 346.84589 -222.937832)
		(end 346.882466 -222.959168)
		(width 0.1143)
		(layer "In11.Cu")
		(net "GMI_CPU1_G3_CPU0_G1_TX_DN<13>")
	)
	(segment
		(start 124.68352 -235.27004)
		(end 124.612654 -235.228892)
		(width 0.1143)
		(layer "In11.Cu")
		(net "GMI_CPU1_G3_CPU0_G1_TX_DN<13>")
	)
	(segment
		(start 309.09768 -189.169548)
		(end 318.311276 -195.663312)
		(width 0.14224)
		(layer "In11.Cu")
		(net "GMI_CPU1_G3_CPU0_G1_TX_DN<13>")
	)
	(segment
		(start 346.845128 -227.79736)
		(end 346.84589 -227.797868)
		(width 0.1143)
		(layer "In11.Cu")
		(net "GMI_CPU1_G3_CPU0_G1_TX_DN<13>")
	)
	(segment
		(start 262.665464 -188.790326)
		(end 303.734724 -189.169548)
		(width 0.14224)
		(layer "In11.Cu")
		(net "GMI_CPU1_G3_CPU0_G1_TX_DN<13>")
	)
	(segment
		(start 346.815156 -235.268262)
		(end 346.812362 -235.269786)
		(width 0.1143)
		(layer "In11.Cu")
		(net "GMI_CPU1_G3_CPU0_G1_TX_DN<13>")
	)
	(segment
		(start 346.410534 -231.18064)
		(end 346.40774 -231.182164)
		(width 0.1143)
		(layer "In11.Cu")
		(net "GMI_CPU1_G3_CPU0_G1_TX_DN<13>")
	)
	(segment
		(start 346.342462 -231.82834)
		(end 346.37218 -231.845358)
		(width 0.1143)
		(layer "In11.Cu")
		(net "GMI_CPU1_G3_CPU0_G1_TX_DN<13>")
	)
	(segment
		(start 347.136212 -221.531688)
		(end 347.126306 -221.541594)
		(width 0.1143)
		(layer "In11.Cu")
		(net "GMI_CPU1_G3_CPU0_G1_TX_DN<13>")
	)
	(segment
		(start 124.65304 -230.389938)
		(end 124.648722 -230.387398)
		(width 0.1143)
		(layer "In11.Cu")
		(net "GMI_CPU1_G3_CPU0_G1_TX_DN<13>")
	)
	(segment
		(start 346.818458 -235.26623)
		(end 346.815156 -235.268262)
		(width 0.1143)
		(layer "In11.Cu")
		(net "GMI_CPU1_G3_CPU0_G1_TX_DN<13>")
	)
	(segment
		(start 346.845128 -222.937324)
		(end 346.84589 -222.937832)
		(width 0.1143)
		(layer "In11.Cu")
		(net "GMI_CPU1_G3_CPU0_G1_TX_DN<13>")
	)
	(segment
		(start 124.650754 -227.797614)
		(end 124.653294 -227.796344)
		(width 0.1143)
		(layer "In11.Cu")
		(net "GMI_CPU1_G3_CPU0_G1_TX_DN<13>")
	)
	(segment
		(start 148.580856 -200.5711)
		(end 160.47847 -190.815722)
		(width 0.14224)
		(layer "In11.Cu")
		(net "GMI_CPU1_G3_CPU0_G1_TX_DN<13>")
	)
	(segment
		(start 346.40774 -231.182164)
		(end 346.340684 -231.22128)
		(width 0.1143)
		(layer "In11.Cu")
		(net "GMI_CPU1_G3_CPU0_G1_TX_DN<13>")
	)
	(segment
		(start 211.800186 -189.850776)
		(end 234.011978 -199.051418)
		(width 0.14224)
		(layer "In11.Cu")
		(net "GMI_CPU1_G3_CPU0_G1_TX_DN<13>")
	)
	(segment
		(start 124.654564 -222.935292)
		(end 124.660152 -222.932244)
		(width 0.1143)
		(layer "In11.Cu")
		(net "GMI_CPU1_G3_CPU0_G1_TX_DN<13>")
	)
	(segment
		(start 124.35967 -221.248732)
		(end 124.31395 -221.203012)
		(width 0.1143)
		(layer "In11.Cu")
		(net "GMI_CPU1_G3_CPU0_G1_TX_DN<13>")
	)
	(segment
		(start 346.843604 -232.657904)
		(end 346.846652 -232.659682)
		(width 0.1143)
		(layer "In11.Cu")
		(net "GMI_CPU1_G3_CPU0_G1_TX_DN<13>")
	)
	(segment
		(start 124.31395 -221.203012)
		(end 124.31395 -221.174564)
		(width 0.1143)
		(layer "In11.Cu")
		(net "GMI_CPU1_G3_CPU0_G1_TX_DN<13>")
	)
	(segment
		(start 346.812362 -234.258358)
		(end 346.844112 -234.276646)
		(width 0.1143)
		(layer "In11.Cu")
		(net "GMI_CPU1_G3_CPU0_G1_TX_DN<13>")
	)
	(segment
		(start 346.850462 -227.800408)
		(end 346.851478 -227.800916)
		(width 0.1143)
		(layer "In11.Cu")
		(net "GMI_CPU1_G3_CPU0_G1_TX_DN<13>")
	)
	(segment
		(start 124.652532 -222.936562)
		(end 124.654564 -222.935292)
		(width 0.1143)
		(layer "In11.Cu")
		(net "GMI_CPU1_G3_CPU0_G1_TX_DN<13>")
	)
	(segment
		(start 346.842588 -227.79609)
		(end 346.845128 -227.79736)
		(width 0.1143)
		(layer "In11.Cu")
		(net "GMI_CPU1_G3_CPU0_G1_TX_DN<13>")
	)
	(segment
		(start 207.361536 -189.068202)
		(end 211.800186 -189.850776)
		(width 0.14224)
		(layer "In11.Cu")
		(net "GMI_CPU1_G3_CPU0_G1_TX_DN<13>")
	)
	(segment
		(start 124.65177 -234.2769)
		(end 124.68352 -234.258612)
		(width 0.1143)
		(layer "In11.Cu")
		(net "GMI_CPU1_G3_CPU0_G1_TX_DN<13>")
	)
	(segment
		(start 346.374212 -236.061504)
		(end 346.37345 -236.062012)
		(width 0.1143)
		(layer "In11.Cu")
		(net "GMI_CPU1_G3_CPU0_G1_TX_DN<13>")
	)
	(segment
		(start 346.844112 -234.276646)
		(end 346.883228 -234.299506)
		(width 0.1143)
		(layer "In11.Cu")
		(net "GMI_CPU1_G3_CPU0_G1_TX_DN<13>")
	)
	(segment
		(start 124.369576 -221.81693)
		(end 124.369576 -221.541848)
		(width 0.1143)
		(layer "In11.Cu")
		(net "GMI_CPU1_G3_CPU0_G1_TX_DN<13>")
	)
	(segment
		(start 124.673614 -227.164392)
		(end 124.613162 -227.129594)
		(width 0.1143)
		(layer "In11.Cu")
		(net "GMI_CPU1_G3_CPU0_G1_TX_DN<13>")
	)
	(arc
		(start 125.085348 -231.180894)
		(mid 125.078582 -231.176117)
		(end 125.071886 -231.171242)
		(width 0.1143)
		(layer "In11.Cu")
		(net "GMI_CPU1_G3_CPU0_G1_TX_DN<13>")
	)
	(arc
		(start 124.369576 -229.90429)
		(mid 124.433522 -229.643221)
		(end 124.610876 -229.441248)
		(width 0.1143)
		(layer "In11.Cu")
		(net "GMI_CPU1_G3_CPU0_G1_TX_DN<13>")
	)
	(arc
		(start 346.822268 -227.164138)
		(mid 346.643726 -227.474098)
		(end 346.822014 -227.784152)
		(width 0.1143)
		(layer "In11.Cu")
		(net "GMI_CPU1_G3_CPU0_G1_TX_DN<13>")
	)
	(arc
		(start 346.885006 -229.440994)
		(mid 347.062371 -229.642961)
		(end 347.126306 -229.904036)
		(width 0.1143)
		(layer "In11.Cu")
		(net "GMI_CPU1_G3_CPU0_G1_TX_DN<13>")
	)
	(arc
		(start 124.681488 -224.53981)
		(mid 124.839219 -224.219304)
		(end 124.65685 -223.912176)
		(width 0.1143)
		(layer "In11.Cu")
		(net "GMI_CPU1_G3_CPU0_G1_TX_DN<13>")
	)
	(arc
		(start 124.65685 -226.17684)
		(mid 124.839168 -225.86971)
		(end 124.681488 -225.549206)
		(width 0.1143)
		(layer "In11.Cu")
		(net "GMI_CPU1_G3_CPU0_G1_TX_DN<13>")
	)
	(arc
		(start 124.612654 -222.281242)
		(mid 124.434055 -222.078954)
		(end 124.369576 -221.81693)
		(width 0.1143)
		(layer "In11.Cu")
		(net "GMI_CPU1_G3_CPU0_G1_TX_DN<13>")
	)
	(arc
		(start 124.660152 -222.932244)
		(mid 124.840492 -222.638465)
		(end 124.69114 -222.327724)
		(width 0.1143)
		(layer "In11.Cu")
		(net "GMI_CPU1_G3_CPU0_G1_TX_DN<13>")
	)
	(arc
		(start 346.814394 -225.548952)
		(mid 346.656663 -225.869458)
		(end 346.839032 -226.176586)
		(width 0.1143)
		(layer "In11.Cu")
		(net "GMI_CPU1_G3_CPU0_G1_TX_DN<13>")
	)
	(arc
		(start 347.126306 -221.816676)
		(mid 347.0618 -222.078686)
		(end 346.883228 -222.280988)
		(width 0.1143)
		(layer "In11.Cu")
		(net "GMI_CPU1_G3_CPU0_G1_TX_DN<13>")
	)
	(arc
		(start 346.656406 -230.714296)
		(mid 346.594961 -230.970508)
		(end 346.423996 -231.170988)
		(width 0.1143)
		(layer "In11.Cu")
		(net "GMI_CPU1_G3_CPU0_G1_TX_DN<13>")
	)
	(arc
		(start 346.340684 -231.22128)
		(mid 346.227277 -231.354169)
		(end 346.186506 -231.524048)
		(width 0.1143)
		(layer "In11.Cu")
		(net "GMI_CPU1_G3_CPU0_G1_TX_DN<13>")
	)
	(arc
		(start 346.883228 -224.579688)
		(mid 347.126555 -225.044254)
		(end 346.883228 -225.50882)
		(width 0.1143)
		(layer "In11.Cu")
		(net "GMI_CPU1_G3_CPU0_G1_TX_DN<13>")
	)
	(arc
		(start 346.423996 -231.170988)
		(mid 346.417301 -231.175864)
		(end 346.410534 -231.18064)
		(width 0.1143)
		(layer "In11.Cu")
		(net "GMI_CPU1_G3_CPU0_G1_TX_DN<13>")
	)
	(arc
		(start 125.071886 -231.171242)
		(mid 124.900916 -230.970765)
		(end 124.839476 -230.71455)
		(width 0.1143)
		(layer "In11.Cu")
		(net "GMI_CPU1_G3_CPU0_G1_TX_DN<13>")
	)
	(arc
		(start 124.839476 -232.334308)
		(mid 124.904712 -232.070717)
		(end 125.085348 -231.867964)
		(width 0.1143)
		(layer "In11.Cu")
		(net "GMI_CPU1_G3_CPU0_G1_TX_DN<13>")
	)
	(arc
		(start 124.648722 -230.387398)
		(mid 124.444348 -230.18328)
		(end 124.369576 -229.90429)
		(width 0.1143)
		(layer "In11.Cu")
		(net "GMI_CPU1_G3_CPU0_G1_TX_DN<13>")
	)
	(arc
		(start 124.673868 -227.784406)
		(mid 124.852064 -227.474352)
		(end 124.673614 -227.164392)
		(width 0.1143)
		(layer "In11.Cu")
		(net "GMI_CPU1_G3_CPU0_G1_TX_DN<13>")
	)
	(arc
		(start 346.883228 -234.299506)
		(mid 347.126555 -234.764072)
		(end 346.883228 -235.228638)
		(width 0.1143)
		(layer "In11.Cu")
		(net "GMI_CPU1_G3_CPU0_G1_TX_DN<13>")
	)
	(arc
		(start 346.812362 -233.649774)
		(mid 346.661977 -233.954066)
		(end 346.812362 -234.258358)
		(width 0.1143)
		(layer "In11.Cu")
		(net "GMI_CPU1_G3_CPU0_G1_TX_DN<13>")
	)
	(arc
		(start 346.882466 -227.819204)
		(mid 347.124835 -228.307802)
		(end 346.839032 -228.772212)
		(width 0.1143)
		(layer "In11.Cu")
		(net "GMI_CPU1_G3_CPU0_G1_TX_DN<13>")
	)
	(arc
		(start 124.652278 -232.658158)
		(mid 124.789342 -232.52135)
		(end 124.839476 -232.334308)
		(width 0.1143)
		(layer "In11.Cu")
		(net "GMI_CPU1_G3_CPU0_G1_TX_DN<13>")
	)
	(arc
		(start 125.302518 -236.314488)
		(mid 125.250469 -236.182969)
		(end 125.15342 -236.080046)
		(width 0.1143)
		(layer "In11.Cu")
		(net "GMI_CPU1_G3_CPU0_G1_TX_DN<13>")
	)
	(arc
		(start 347.126306 -229.904036)
		(mid 347.051495 -230.183003)
		(end 346.84716 -230.387144)
		(width 0.1143)
		(layer "In11.Cu")
		(net "GMI_CPU1_G3_CPU0_G1_TX_DN<13>")
	)
	(arc
		(start 346.839032 -226.176586)
		(mid 347.124619 -226.640829)
		(end 346.88272 -227.12934)
		(width 0.1143)
		(layer "In11.Cu")
		(net "GMI_CPU1_G3_CPU0_G1_TX_DN<13>")
	)
	(arc
		(start 125.15342 -231.828594)
		(mid 125.268096 -231.69526)
		(end 125.309376 -231.524302)
		(width 0.1143)
		(layer "In11.Cu")
		(net "GMI_CPU1_G3_CPU0_G1_TX_DN<13>")
	)
	(arc
		(start 346.342462 -236.079792)
		(mid 346.245327 -236.182661)
		(end 346.193364 -236.314234)
		(width 0.1143)
		(layer "In11.Cu")
		(net "GMI_CPU1_G3_CPU0_G1_TX_DN<13>")
	)
	(arc
		(start 124.681488 -229.4001)
		(mid 124.839219 -229.079594)
		(end 124.65685 -228.772466)
		(width 0.1143)
		(layer "In11.Cu")
		(net "GMI_CPU1_G3_CPU0_G1_TX_DN<13>")
	)
	(arc
		(start 346.882466 -222.959168)
		(mid 347.124623 -223.447574)
		(end 346.839032 -223.911922)
		(width 0.1143)
		(layer "In11.Cu")
		(net "GMI_CPU1_G3_CPU0_G1_TX_DN<13>")
	)
	(arc
		(start 346.410534 -231.86771)
		(mid 346.591186 -232.070455)
		(end 346.656406 -232.334054)
		(width 0.1143)
		(layer "In11.Cu")
		(net "GMI_CPU1_G3_CPU0_G1_TX_DN<13>")
	)
	(arc
		(start 124.612654 -225.509074)
		(mid 124.369327 -225.044508)
		(end 124.612654 -224.579942)
		(width 0.1143)
		(layer "In11.Cu")
		(net "GMI_CPU1_G3_CPU0_G1_TX_DN<13>")
	)
	(arc
		(start 346.839032 -223.911922)
		(mid 346.656714 -224.219052)
		(end 346.814394 -224.539556)
		(width 0.1143)
		(layer "In11.Cu")
		(net "GMI_CPU1_G3_CPU0_G1_TX_DN<13>")
	)
	(arc
		(start 124.65685 -228.772466)
		(mid 124.371255 -228.308046)
		(end 124.613416 -227.819458)
		(width 0.1143)
		(layer "In11.Cu")
		(net "GMI_CPU1_G3_CPU0_G1_TX_DN<13>")
	)
	(arc
		(start 125.119384 -236.060488)
		(mid 124.914439 -235.854826)
		(end 124.839476 -235.574332)
		(width 0.1143)
		(layer "In11.Cu")
		(net "GMI_CPU1_G3_CPU0_G1_TX_DN<13>")
	)
	(arc
		(start 125.309376 -231.524302)
		(mid 125.268614 -231.354418)
		(end 125.155198 -231.221534)
		(width 0.1143)
		(layer "In11.Cu")
		(net "GMI_CPU1_G3_CPU0_G1_TX_DN<13>")
	)
	(arc
		(start 124.68352 -234.258612)
		(mid 124.833905 -233.95432)
		(end 124.68352 -233.650028)
		(width 0.1143)
		(layer "In11.Cu")
		(net "GMI_CPU1_G3_CPU0_G1_TX_DN<13>")
	)
	(arc
		(start 346.839032 -228.772212)
		(mid 346.656714 -229.079342)
		(end 346.814394 -229.399846)
		(width 0.1143)
		(layer "In11.Cu")
		(net "GMI_CPU1_G3_CPU0_G1_TX_DN<13>")
	)
	(arc
		(start 346.186506 -231.524048)
		(mid 346.227761 -231.695019)
		(end 346.342462 -231.82834)
		(width 0.1143)
		(layer "In11.Cu")
		(net "GMI_CPU1_G3_CPU0_G1_TX_DN<13>")
	)
	(arc
		(start 346.812362 -235.269786)
		(mid 346.697686 -235.40312)
		(end 346.656406 -235.574078)
		(width 0.1143)
		(layer "In11.Cu")
		(net "GMI_CPU1_G3_CPU0_G1_TX_DN<13>")
	)
	(arc
		(start 124.839476 -235.574332)
		(mid 124.798221 -235.403361)
		(end 124.68352 -235.27004)
		(width 0.1143)
		(layer "In11.Cu")
		(net "GMI_CPU1_G3_CPU0_G1_TX_DN<13>")
	)
	(arc
		(start 124.613162 -227.129594)
		(mid 124.37112 -226.641077)
		(end 124.65685 -226.17684)
		(width 0.1143)
		(layer "In11.Cu")
		(net "GMI_CPU1_G3_CPU0_G1_TX_DN<13>")
	)
	(arc
		(start 346.846652 -232.659682)
		(mid 347.125278 -233.124135)
		(end 346.883228 -233.608626)
		(width 0.1143)
		(layer "In11.Cu")
		(net "GMI_CPU1_G3_CPU0_G1_TX_DN<13>")
	)
	(arc
		(start 124.612654 -233.60888)
		(mid 124.370661 -233.124391)
		(end 124.64923 -232.659936)
		(width 0.1143)
		(layer "In11.Cu")
		(net "GMI_CPU1_G3_CPU0_G1_TX_DN<13>")
	)
	(arc
		(start 346.656406 -235.574078)
		(mid 346.581426 -235.854562)
		(end 346.376498 -236.060234)
		(width 0.1143)
		(layer "In11.Cu")
		(net "GMI_CPU1_G3_CPU0_G1_TX_DN<13>")
	)
	(arc
		(start 124.612654 -235.228892)
		(mid 124.369327 -234.764326)
		(end 124.612654 -234.29976)
		(width 0.1143)
		(layer "In11.Cu")
		(net "GMI_CPU1_G3_CPU0_G1_TX_DN<13>")
	)
	(arc
		(start 346.842842 -230.389684)
		(mid 346.706367 -230.527138)
		(end 346.656406 -230.714296)
		(width 0.1143)
		(layer "In11.Cu")
		(net "GMI_CPU1_G3_CPU0_G1_TX_DN<13>")
	)
	(arc
		(start 124.65685 -223.912176)
		(mid 124.371258 -223.447828)
		(end 124.613416 -222.959422)
		(width 0.1143)
		(layer "In11.Cu")
		(net "GMI_CPU1_G3_CPU0_G1_TX_DN<13>")
	)
	(arc
		(start 346.656406 -232.334054)
		(mid 346.70658 -232.521073)
		(end 346.843604 -232.657904)
		(width 0.1143)
		(layer "In11.Cu")
		(net "GMI_CPU1_G3_CPU0_G1_TX_DN<13>")
	)
	(arc
		(start 346.804742 -222.32747)
		(mid 346.655277 -222.638217)
		(end 346.83573 -222.93199)
		(width 0.1143)
		(layer "In11.Cu")
		(net "GMI_CPU1_G3_CPU0_G1_TX_DN<13>")
	)
	(arc
		(start 124.839476 -230.71455)
		(mid 124.789559 -230.527367)
		(end 124.65304 -230.389938)
		(width 0.1143)
		(layer "In11.Cu")
		(net "GMI_CPU1_G3_CPU0_G1_TX_DN<13>")
	)
	(segment
		(start 121.647966 -235.030264)
		(end 122.114818 -234.764326)
		(width 0.12954)
		(layer "F.Cu")
		(net "GMI_CPU1_G3_CPU0_G1_TX_DN<12>")
	)
	(segment
		(start 349.847916 -235.03001)
		(end 349.381064 -234.764072)
		(width 0.12954)
		(layer "F.Cu")
		(net "GMI_CPU1_G3_CPU0_G1_TX_DN<12>")
	)
	(segment
		(start 348.06636 -221.44101)
		(end 348.06636 -221.80423)
		(width 0.1143)
		(layer "In11.Cu")
		(net "GMI_CPU1_G3_CPU0_G1_TX_DN<12>")
	)
	(segment
		(start 347.752416 -224.53854)
		(end 347.779848 -224.554288)
		(width 0.1143)
		(layer "In11.Cu")
		(net "GMI_CPU1_G3_CPU0_G1_TX_DN<12>")
	)
	(segment
		(start 123.712478 -224.556574)
		(end 123.715272 -224.55505)
		(width 0.1143)
		(layer "In11.Cu")
		(net "GMI_CPU1_G3_CPU0_G1_TX_DN<12>")
	)
	(segment
		(start 123.71705 -222.934022)
		(end 123.717812 -222.933514)
		(width 0.1143)
		(layer "In11.Cu")
		(net "GMI_CPU1_G3_CPU0_G1_TX_DN<12>")
	)
	(segment
		(start 348.081346 -221.128844)
		(end 348.081346 -221.426024)
		(width 0.1143)
		(layer "In11.Cu")
		(net "GMI_CPU1_G3_CPU0_G1_TX_DN<12>")
	)
	(segment
		(start 123.71705 -226.174046)
		(end 123.717812 -226.173538)
		(width 0.1143)
		(layer "In11.Cu")
		(net "GMI_CPU1_G3_CPU0_G1_TX_DN<12>")
	)
	(segment
		(start 235.356908 -198.341488)
		(end 236.27969 -198.504048)
		(width 0.14224)
		(layer "In11.Cu")
		(net "GMI_CPU1_G3_CPU0_G1_TX_DN<12>")
	)
	(segment
		(start 347.787722 -224.55886)
		(end 347.790262 -224.560384)
		(width 0.1143)
		(layer "In11.Cu")
		(net "GMI_CPU1_G3_CPU0_G1_TX_DN<12>")
	)
	(segment
		(start 347.784166 -224.556828)
		(end 347.785182 -224.557336)
		(width 0.1143)
		(layer "In11.Cu")
		(net "GMI_CPU1_G3_CPU0_G1_TX_DN<12>")
	)
	(segment
		(start 123.715272 -232.654856)
		(end 123.716034 -232.654348)
		(width 0.1143)
		(layer "In11.Cu")
		(net "GMI_CPU1_G3_CPU0_G1_TX_DN<12>")
	)
	(segment
		(start 123.712478 -226.176586)
		(end 123.715272 -226.175062)
		(width 0.1143)
		(layer "In11.Cu")
		(net "GMI_CPU1_G3_CPU0_G1_TX_DN<12>")
	)
	(segment
		(start 349.083122 -234.764072)
		(end 349.381064 -234.764072)
		(width 0.1143)
		(layer "In11.Cu")
		(net "GMI_CPU1_G3_CPU0_G1_TX_DN<12>")
	)
	(segment
		(start 123.718828 -224.553018)
		(end 123.743466 -224.538794)
		(width 0.1143)
		(layer "In11.Cu")
		(net "GMI_CPU1_G3_CPU0_G1_TX_DN<12>")
	)
	(segment
		(start 122.773948 -234.273852)
		(end 122.775218 -234.27309)
		(width 0.1143)
		(layer "In11.Cu")
		(net "GMI_CPU1_G3_CPU0_G1_TX_DN<12>")
	)
	(segment
		(start 347.786706 -224.558352)
		(end 347.787722 -224.55886)
		(width 0.1143)
		(layer "In11.Cu")
		(net "GMI_CPU1_G3_CPU0_G1_TX_DN<12>")
	)
	(segment
		(start 347.783404 -227.796344)
		(end 347.784166 -227.796852)
		(width 0.1143)
		(layer "In11.Cu")
		(net "GMI_CPU1_G3_CPU0_G1_TX_DN<12>")
	)
	(segment
		(start 123.718828 -232.652824)
		(end 123.743466 -232.6386)
		(width 0.1143)
		(layer "In11.Cu")
		(net "GMI_CPU1_G3_CPU0_G1_TX_DN<12>")
	)
	(segment
		(start 123.711716 -225.531934)
		(end 123.7107 -225.531426)
		(width 0.1143)
		(layer "In11.Cu")
		(net "GMI_CPU1_G3_CPU0_G1_TX_DN<12>")
	)
	(segment
		(start 123.6726 -229.439724)
		(end 123.711716 -229.416864)
		(width 0.1143)
		(layer "In11.Cu")
		(net "GMI_CPU1_G3_CPU0_G1_TX_DN<12>")
	)
	(segment
		(start 123.717812 -222.933514)
		(end 123.718828 -222.933006)
		(width 0.1143)
		(layer "In11.Cu")
		(net "GMI_CPU1_G3_CPU0_G1_TX_DN<12>")
	)
	(segment
		(start 123.715272 -224.55505)
		(end 123.716034 -224.554542)
		(width 0.1143)
		(layer "In11.Cu")
		(net "GMI_CPU1_G3_CPU0_G1_TX_DN<12>")
	)
	(segment
		(start 318.819784 -194.815714)
		(end 318.94907 -194.944746)
		(width 0.14224)
		(layer "In11.Cu")
		(net "GMI_CPU1_G3_CPU0_G1_TX_DN<12>")
	)
	(segment
		(start 348.723966 -234.274614)
		(end 348.724728 -234.275122)
		(width 0.1143)
		(layer "In11.Cu")
		(net "GMI_CPU1_G3_CPU0_G1_TX_DN<12>")
	)
	(segment
		(start 347.353128 -231.178862)
		(end 347.314012 -231.201722)
		(width 0.1143)
		(layer "In11.Cu")
		(net "GMI_CPU1_G3_CPU0_G1_TX_DN<12>")
	)
	(segment
		(start 122.114818 -234.764326)
		(end 122.41276 -234.764326)
		(width 0.1143)
		(layer "In11.Cu")
		(net "GMI_CPU1_G3_CPU0_G1_TX_DN<12>")
	)
	(segment
		(start 347.790262 -232.66019)
		(end 347.791786 -232.661206)
		(width 0.1143)
		(layer "In11.Cu")
		(net "GMI_CPU1_G3_CPU0_G1_TX_DN<12>")
	)
	(segment
		(start 347.787722 -226.178872)
		(end 347.790262 -226.180396)
		(width 0.1143)
		(layer "In11.Cu")
		(net "GMI_CPU1_G3_CPU0_G1_TX_DN<12>")
	)
	(segment
		(start 123.6726 -222.95993)
		(end 123.711716 -222.93707)
		(width 0.1143)
		(layer "In11.Cu")
		(net "GMI_CPU1_G3_CPU0_G1_TX_DN<12>")
	)
	(segment
		(start 347.787722 -222.938848)
		(end 347.790262 -222.940372)
		(width 0.1143)
		(layer "In11.Cu")
		(net "GMI_CPU1_G3_CPU0_G1_TX_DN<12>")
	)
	(segment
		(start 123.7107 -227.151438)
		(end 123.709176 -227.150422)
		(width 0.1143)
		(layer "In11.Cu")
		(net "GMI_CPU1_G3_CPU0_G1_TX_DN<12>")
	)
	(segment
		(start 348.720664 -234.272836)
		(end 348.721934 -234.273598)
		(width 0.1143)
		(layer "In11.Cu")
		(net "GMI_CPU1_G3_CPU0_G1_TX_DN<12>")
	)
	(segment
		(start 123.711716 -224.557082)
		(end 123.712478 -224.556574)
		(width 0.1143)
		(layer "In11.Cu")
		(net "GMI_CPU1_G3_CPU0_G1_TX_DN<12>")
	)
	(segment
		(start 123.71705 -232.65384)
		(end 123.717812 -232.653332)
		(width 0.1143)
		(layer "In11.Cu")
		(net "GMI_CPU1_G3_CPU0_G1_TX_DN<12>")
	)
	(segment
		(start 347.784166 -227.796852)
		(end 347.785182 -227.79736)
		(width 0.1143)
		(layer "In11.Cu")
		(net "GMI_CPU1_G3_CPU0_G1_TX_DN<12>")
	)
	(segment
		(start 145.74266 -200.406254)
		(end 147.870418 -199.76211)
		(width 0.14224)
		(layer "In11.Cu")
		(net "GMI_CPU1_G3_CPU0_G1_TX_DN<12>")
	)
	(segment
		(start 123.368816 -220.31833)
		(end 125.084586 -217.345006)
		(width 0.14224)
		(layer "In11.Cu")
		(net "GMI_CPU1_G3_CPU0_G1_TX_DN<12>")
	)
	(segment
		(start 123.368816 -221.071948)
		(end 123.368816 -220.31833)
		(width 0.14224)
		(layer "In11.Cu")
		(net "GMI_CPU1_G3_CPU0_G1_TX_DN<12>")
	)
	(segment
		(start 123.717812 -226.173538)
		(end 123.718828 -226.17303)
		(width 0.1143)
		(layer "In11.Cu")
		(net "GMI_CPU1_G3_CPU0_G1_TX_DN<12>")
	)
	(segment
		(start 347.752416 -226.158552)
		(end 347.779848 -226.1743)
		(width 0.1143)
		(layer "In11.Cu")
		(net "GMI_CPU1_G3_CPU0_G1_TX_DN<12>")
	)
	(segment
		(start 123.6726 -232.679748)
		(end 123.711716 -232.656888)
		(width 0.1143)
		(layer "In11.Cu")
		(net "GMI_CPU1_G3_CPU0_G1_TX_DN<12>")
	)
	(segment
		(start 123.414536 -221.426278)
		(end 123.414536 -221.129098)
		(width 0.1143)
		(layer "In11.Cu")
		(net "GMI_CPU1_G3_CPU0_G1_TX_DN<12>")
	)
	(segment
		(start 123.711716 -229.416864)
		(end 123.745244 -229.397306)
		(width 0.1143)
		(layer "In11.Cu")
		(net "GMI_CPU1_G3_CPU0_G1_TX_DN<12>")
	)
	(segment
		(start 207.281272 -188.0997)
		(end 210.194906 -188.613542)
		(width 0.14224)
		(layer "In11.Cu")
		(net "GMI_CPU1_G3_CPU0_G1_TX_DN<12>")
	)
	(segment
		(start 347.779848 -232.654094)
		(end 347.78061 -232.654602)
		(width 0.1143)
		(layer "In11.Cu")
		(net "GMI_CPU1_G3_CPU0_G1_TX_DN<12>")
	)
	(segment
		(start 347.783404 -223.912176)
		(end 347.752416 -223.929956)
		(width 0.1143)
		(layer "In11.Cu")
		(net "GMI_CPU1_G3_CPU0_G1_TX_DN<12>")
	)
	(segment
		(start 123.718828 -227.793042)
		(end 123.743466 -227.778818)
		(width 0.1143)
		(layer "In11.Cu")
		(net "GMI_CPU1_G3_CPU0_G1_TX_DN<12>")
	)
	(segment
		(start 123.712478 -227.152454)
		(end 123.711716 -227.151946)
		(width 0.1143)
		(layer "In11.Cu")
		(net "GMI_CPU1_G3_CPU0_G1_TX_DN<12>")
	)
	(segment
		(start 347.785182 -224.557336)
		(end 347.786706 -224.558352)
		(width 0.1143)
		(layer "In11.Cu")
		(net "GMI_CPU1_G3_CPU0_G1_TX_DN<12>")
	)
	(segment
		(start 347.779848 -227.794312)
		(end 347.78061 -227.79482)
		(width 0.1143)
		(layer "In11.Cu")
		(net "GMI_CPU1_G3_CPU0_G1_TX_DN<12>")
	)
	(segment
		(start 124.18187 -231.201976)
		(end 124.142754 -231.179116)
		(width 0.1143)
		(layer "In11.Cu")
		(net "GMI_CPU1_G3_CPU0_G1_TX_DN<12>")
	)
	(segment
		(start 347.784166 -223.911668)
		(end 347.783404 -223.912176)
		(width 0.1143)
		(layer "In11.Cu")
		(net "GMI_CPU1_G3_CPU0_G1_TX_DN<12>")
	)
	(segment
		(start 347.784166 -232.656634)
		(end 347.785182 -232.657142)
		(width 0.1143)
		(layer "In11.Cu")
		(net "GMI_CPU1_G3_CPU0_G1_TX_DN<12>")
	)
	(segment
		(start 123.711716 -223.911922)
		(end 123.7107 -223.911414)
		(width 0.1143)
		(layer "In11.Cu")
		(net "GMI_CPU1_G3_CPU0_G1_TX_DN<12>")
	)
	(segment
		(start 347.752416 -232.638346)
		(end 347.779848 -232.654094)
		(width 0.1143)
		(layer "In11.Cu")
		(net "GMI_CPU1_G3_CPU0_G1_TX_DN<12>")
	)
	(segment
		(start 347.750638 -229.397052)
		(end 347.823282 -229.43947)
		(width 0.1143)
		(layer "In11.Cu")
		(net "GMI_CPU1_G3_CPU0_G1_TX_DN<12>")
	)
	(segment
		(start 347.314012 -231.201722)
		(end 347.2815 -231.220518)
		(width 0.1143)
		(layer "In11.Cu")
		(net "GMI_CPU1_G3_CPU0_G1_TX_DN<12>")
	)
	(segment
		(start 348.223586 -233.44886)
		(end 348.293182 -233.4895)
		(width 0.1143)
		(layer "In11.Cu")
		(net "GMI_CPU1_G3_CPU0_G1_TX_DN<12>")
	)
	(segment
		(start 347.752416 -227.778564)
		(end 347.779848 -227.794312)
		(width 0.1143)
		(layer "In11.Cu")
		(net "GMI_CPU1_G3_CPU0_G1_TX_DN<12>")
	)
	(segment
		(start 122.771916 -234.274868)
		(end 122.773948 -234.273852)
		(width 0.1143)
		(layer "In11.Cu")
		(net "GMI_CPU1_G3_CPU0_G1_TX_DN<12>")
	)
	(segment
		(start 347.785182 -222.937324)
		(end 347.786706 -222.93834)
		(width 0.1143)
		(layer "In11.Cu")
		(net "GMI_CPU1_G3_CPU0_G1_TX_DN<12>")
	)
	(segment
		(start 347.787722 -227.798884)
		(end 347.790262 -227.800408)
		(width 0.1143)
		(layer "In11.Cu")
		(net "GMI_CPU1_G3_CPU0_G1_TX_DN<12>")
	)
	(segment
		(start 347.786706 -225.530156)
		(end 347.785182 -225.531172)
		(width 0.1143)
		(layer "In11.Cu")
		(net "GMI_CPU1_G3_CPU0_G1_TX_DN<12>")
	)
	(segment
		(start 347.779848 -222.934276)
		(end 347.78061 -222.934784)
		(width 0.1143)
		(layer "In11.Cu")
		(net "GMI_CPU1_G3_CPU0_G1_TX_DN<12>")
	)
	(segment
		(start 347.786706 -228.77018)
		(end 347.785182 -228.771196)
		(width 0.1143)
		(layer "In11.Cu")
		(net "GMI_CPU1_G3_CPU0_G1_TX_DN<12>")
	)
	(segment
		(start 347.783404 -227.1522)
		(end 347.752416 -227.16998)
		(width 0.1143)
		(layer "In11.Cu")
		(net "GMI_CPU1_G3_CPU0_G1_TX_DN<12>")
	)
	(segment
		(start 123.711716 -228.771958)
		(end 123.7107 -228.77145)
		(width 0.1143)
		(layer "In11.Cu")
		(net "GMI_CPU1_G3_CPU0_G1_TX_DN<12>")
	)
	(segment
		(start 123.743466 -223.93021)
		(end 123.712478 -223.91243)
		(width 0.1143)
		(layer "In11.Cu")
		(net "GMI_CPU1_G3_CPU0_G1_TX_DN<12>")
	)
	(segment
		(start 348.721934 -234.273598)
		(end 348.723966 -234.274614)
		(width 0.1143)
		(layer "In11.Cu")
		(net "GMI_CPU1_G3_CPU0_G1_TX_DN<12>")
	)
	(segment
		(start 303.706784 -188.201808)
		(end 309.435754 -188.201808)
		(width 0.14224)
		(layer "In11.Cu")
		(net "GMI_CPU1_G3_CPU0_G1_TX_DN<12>")
	)
	(segment
		(start 161.857944 -188.29274)
		(end 207.281272 -188.0997)
		(width 0.14224)
		(layer "In11.Cu")
		(net "GMI_CPU1_G3_CPU0_G1_TX_DN<12>")
	)
	(segment
		(start 236.27969 -198.504048)
		(end 239.093756 -198.007986)
		(width 0.14224)
		(layer "In11.Cu")
		(net "GMI_CPU1_G3_CPU0_G1_TX_DN<12>")
	)
	(segment
		(start 123.6726 -224.579942)
		(end 123.711716 -224.557082)
		(width 0.1143)
		(layer "In11.Cu")
		(net "GMI_CPU1_G3_CPU0_G1_TX_DN<12>")
	)
	(segment
		(start 347.78061 -226.174808)
		(end 347.783404 -226.176332)
		(width 0.1143)
		(layer "In11.Cu")
		(net "GMI_CPU1_G3_CPU0_G1_TX_DN<12>")
	)
	(segment
		(start 123.712478 -225.532442)
		(end 123.711716 -225.531934)
		(width 0.1143)
		(layer "In11.Cu")
		(net "GMI_CPU1_G3_CPU0_G1_TX_DN<12>")
	)
	(segment
		(start 347.784166 -228.771704)
		(end 347.783404 -228.772212)
		(width 0.1143)
		(layer "In11.Cu")
		(net "GMI_CPU1_G3_CPU0_G1_TX_DN<12>")
	)
	(segment
		(start 123.743466 -227.170234)
		(end 123.712478 -227.152454)
		(width 0.1143)
		(layer "In11.Cu")
		(net "GMI_CPU1_G3_CPU0_G1_TX_DN<12>")
	)
	(segment
		(start 123.712478 -228.772466)
		(end 123.711716 -228.771958)
		(width 0.1143)
		(layer "In11.Cu")
		(net "GMI_CPU1_G3_CPU0_G1_TX_DN<12>")
	)
	(segment
		(start 347.783404 -228.772212)
		(end 347.752416 -228.789992)
		(width 0.1143)
		(layer "In11.Cu")
		(net "GMI_CPU1_G3_CPU0_G1_TX_DN<12>")
	)
	(segment
		(start 347.786706 -226.178364)
		(end 347.787722 -226.178872)
		(width 0.1143)
		(layer "In11.Cu")
		(net "GMI_CPU1_G3_CPU0_G1_TX_DN<12>")
	)
	(segment
		(start 123.715272 -226.175062)
		(end 123.716034 -226.174554)
		(width 0.1143)
		(layer "In11.Cu")
		(net "GMI_CPU1_G3_CPU0_G1_TX_DN<12>")
	)
	(segment
		(start 123.717812 -224.553526)
		(end 123.718828 -224.553018)
		(width 0.1143)
		(layer "In11.Cu")
		(net "GMI_CPU1_G3_CPU0_G1_TX_DN<12>")
	)
	(segment
		(start 123.716034 -224.554542)
		(end 123.71705 -224.554034)
		(width 0.1143)
		(layer "In11.Cu")
		(net "GMI_CPU1_G3_CPU0_G1_TX_DN<12>")
	)
	(segment
		(start 347.785182 -225.531172)
		(end 347.784166 -225.53168)
		(width 0.1143)
		(layer "In11.Cu")
		(net "GMI_CPU1_G3_CPU0_G1_TX_DN<12>")
	)
	(segment
		(start 210.194906 -188.613542)
		(end 213.113874 -189.128146)
		(width 0.14224)
		(layer "In11.Cu")
		(net "GMI_CPU1_G3_CPU0_G1_TX_DN<12>")
	)
	(segment
		(start 347.784166 -227.151692)
		(end 347.783404 -227.1522)
		(width 0.1143)
		(layer "In11.Cu")
		(net "GMI_CPU1_G3_CPU0_G1_TX_DN<12>")
	)
	(segment
		(start 123.743466 -230.410258)
		(end 123.711716 -230.39197)
		(width 0.1143)
		(layer "In11.Cu")
		(net "GMI_CPU1_G3_CPU0_G1_TX_DN<12>")
	)
	(segment
		(start 123.715272 -227.795074)
		(end 123.716034 -227.794566)
		(width 0.1143)
		(layer "In11.Cu")
		(net "GMI_CPU1_G3_CPU0_G1_TX_DN<12>")
	)
	(segment
		(start 346.623894 -217.636852)
		(end 348.127066 -220.169486)
		(width 0.14224)
		(layer "In11.Cu")
		(net "GMI_CPU1_G3_CPU0_G1_TX_DN<12>")
	)
	(segment
		(start 348.724728 -234.275122)
		(end 348.724982 -234.275376)
		(width 0.1143)
		(layer "In11.Cu")
		(net "GMI_CPU1_G3_CPU0_G1_TX_DN<12>")
	)
	(segment
		(start 347.823282 -228.748844)
		(end 347.786706 -228.77018)
		(width 0.1143)
		(layer "In11.Cu")
		(net "GMI_CPU1_G3_CPU0_G1_TX_DN<12>")
	)
	(segment
		(start 347.786706 -223.910144)
		(end 347.785182 -223.91116)
		(width 0.1143)
		(layer "In11.Cu")
		(net "GMI_CPU1_G3_CPU0_G1_TX_DN<12>")
	)
	(segment
		(start 347.783404 -222.936308)
		(end 347.784166 -222.936816)
		(width 0.1143)
		(layer "In11.Cu")
		(net "GMI_CPU1_G3_CPU0_G1_TX_DN<12>")
	)
	(segment
		(start 347.283532 -231.828848)
		(end 347.353128 -231.869488)
		(width 0.1143)
		(layer "In11.Cu")
		(net "GMI_CPU1_G3_CPU0_G1_TX_DN<12>")
	)
	(segment
		(start 347.783404 -232.656126)
		(end 347.784166 -232.656634)
		(width 0.1143)
		(layer "In11.Cu")
		(net "GMI_CPU1_G3_CPU0_G1_TX_DN<12>")
	)
	(segment
		(start 347.785182 -232.657142)
		(end 347.786706 -232.658158)
		(width 0.1143)
		(layer "In11.Cu")
		(net "GMI_CPU1_G3_CPU0_G1_TX_DN<12>")
	)
	(segment
		(start 123.711716 -230.39197)
		(end 123.67514 -230.370634)
		(width 0.1143)
		(layer "In11.Cu")
		(net "GMI_CPU1_G3_CPU0_G1_TX_DN<12>")
	)
	(segment
		(start 123.414536 -221.129098)
		(end 123.368816 -221.083378)
		(width 0.1143)
		(layer "In11.Cu")
		(net "GMI_CPU1_G3_CPU0_G1_TX_DN<12>")
	)
	(segment
		(start 347.790262 -222.940372)
		(end 347.791786 -222.941388)
		(width 0.1143)
		(layer "In11.Cu")
		(net "GMI_CPU1_G3_CPU0_G1_TX_DN<12>")
	)
	(segment
		(start 347.785182 -226.177348)
		(end 347.786706 -226.178364)
		(width 0.1143)
		(layer "In11.Cu")
		(net "GMI_CPU1_G3_CPU0_G1_TX_DN<12>")
	)
	(segment
		(start 123.712478 -227.796598)
		(end 123.715272 -227.795074)
		(width 0.1143)
		(layer "In11.Cu")
		(net "GMI_CPU1_G3_CPU0_G1_TX_DN<12>")
	)
	(segment
		(start 123.711716 -232.656888)
		(end 123.712478 -232.65638)
		(width 0.1143)
		(layer "In11.Cu")
		(net "GMI_CPU1_G3_CPU0_G1_TX_DN<12>")
	)
	(segment
		(start 213.113874 -189.128146)
		(end 235.356908 -198.341488)
		(width 0.14224)
		(layer "In11.Cu")
		(net "GMI_CPU1_G3_CPU0_G1_TX_DN<12>")
	)
	(segment
		(start 347.783404 -225.532188)
		(end 347.752416 -225.549968)
		(width 0.1143)
		(layer "In11.Cu")
		(net "GMI_CPU1_G3_CPU0_G1_TX_DN<12>")
	)
	(segment
		(start 124.142754 -231.869742)
		(end 124.18187 -231.846882)
		(width 0.1143)
		(layer "In11.Cu")
		(net "GMI_CPU1_G3_CPU0_G1_TX_DN<12>")
	)
	(segment
		(start 123.7107 -223.911414)
		(end 123.709176 -223.910398)
		(width 0.1143)
		(layer "In11.Cu")
		(net "GMI_CPU1_G3_CPU0_G1_TX_DN<12>")
	)
	(segment
		(start 123.743466 -228.790246)
		(end 123.712478 -228.772466)
		(width 0.1143)
		(layer "In11.Cu")
		(net "GMI_CPU1_G3_CPU0_G1_TX_DN<12>")
	)
	(segment
		(start 347.779848 -226.1743)
		(end 347.78061 -226.174808)
		(width 0.1143)
		(layer "In11.Cu")
		(net "GMI_CPU1_G3_CPU0_G1_TX_DN<12>")
	)
	(segment
		(start 347.790262 -224.560384)
		(end 347.791786 -224.5614)
		(width 0.1143)
		(layer "In11.Cu")
		(net "GMI_CPU1_G3_CPU0_G1_TX_DN<12>")
	)
	(segment
		(start 159.582104 -190.158624)
		(end 159.672274 -190.08471)
		(width 0.14224)
		(layer "In11.Cu")
		(net "GMI_CPU1_G3_CPU0_G1_TX_DN<12>")
	)
	(segment
		(start 122.7709 -234.27563)
		(end 122.771154 -234.275376)
		(width 0.1143)
		(layer "In11.Cu")
		(net "GMI_CPU1_G3_CPU0_G1_TX_DN<12>")
	)
	(segment
		(start 347.820742 -230.37038)
		(end 347.784166 -230.391716)
		(width 0.1143)
		(layer "In11.Cu")
		(net "GMI_CPU1_G3_CPU0_G1_TX_DN<12>")
	)
	(segment
		(start 347.784166 -222.936816)
		(end 347.785182 -222.937324)
		(width 0.1143)
		(layer "In11.Cu")
		(net "GMI_CPU1_G3_CPU0_G1_TX_DN<12>")
	)
	(segment
		(start 123.712478 -222.936562)
		(end 123.715272 -222.935038)
		(width 0.1143)
		(layer "In11.Cu")
		(net "GMI_CPU1_G3_CPU0_G1_TX_DN<12>")
	)
	(segment
		(start 347.786706 -227.798376)
		(end 347.787722 -227.798884)
		(width 0.1143)
		(layer "In11.Cu")
		(net "GMI_CPU1_G3_CPU0_G1_TX_DN<12>")
	)
	(segment
		(start 124.214382 -231.220772)
		(end 124.18187 -231.201976)
		(width 0.1143)
		(layer "In11.Cu")
		(net "GMI_CPU1_G3_CPU0_G1_TX_DN<12>")
	)
	(segment
		(start 122.771154 -234.275376)
		(end 122.771916 -234.274868)
		(width 0.1143)
		(layer "In11.Cu")
		(net "GMI_CPU1_G3_CPU0_G1_TX_DN<12>")
	)
	(segment
		(start 347.791786 -227.801424)
		(end 347.823282 -227.819712)
		(width 0.1143)
		(layer "In11.Cu")
		(net "GMI_CPU1_G3_CPU0_G1_TX_DN<12>")
	)
	(segment
		(start 123.711716 -227.797106)
		(end 123.712478 -227.796598)
		(width 0.1143)
		(layer "In11.Cu")
		(net "GMI_CPU1_G3_CPU0_G1_TX_DN<12>")
	)
	(segment
		(start 347.791786 -232.661206)
		(end 347.823282 -232.679494)
		(width 0.1143)
		(layer "In11.Cu")
		(net "GMI_CPU1_G3_CPU0_G1_TX_DN<12>")
	)
	(segment
		(start 347.784166 -225.53168)
		(end 347.783404 -225.532188)
		(width 0.1143)
		(layer "In11.Cu")
		(net "GMI_CPU1_G3_CPU0_G1_TX_DN<12>")
	)
	(segment
		(start 123.715272 -222.935038)
		(end 123.716034 -222.93453)
		(width 0.1143)
		(layer "In11.Cu")
		(net "GMI_CPU1_G3_CPU0_G1_TX_DN<12>")
	)
	(segment
		(start 123.429522 -221.441264)
		(end 123.414536 -221.426278)
		(width 0.1143)
		(layer "In11.Cu")
		(net "GMI_CPU1_G3_CPU0_G1_TX_DN<12>")
	)
	(segment
		(start 123.717812 -227.79355)
		(end 123.718828 -227.793042)
		(width 0.1143)
		(layer "In11.Cu")
		(net "GMI_CPU1_G3_CPU0_G1_TX_DN<12>")
	)
	(segment
		(start 124.18187 -231.846882)
		(end 124.21235 -231.829102)
		(width 0.1143)
		(layer "In11.Cu")
		(net "GMI_CPU1_G3_CPU0_G1_TX_DN<12>")
	)
	(segment
		(start 347.78061 -224.554796)
		(end 347.783404 -224.55632)
		(width 0.1143)
		(layer "In11.Cu")
		(net "GMI_CPU1_G3_CPU0_G1_TX_DN<12>")
	)
	(segment
		(start 347.779848 -224.554288)
		(end 347.78061 -224.554796)
		(width 0.1143)
		(layer "In11.Cu")
		(net "GMI_CPU1_G3_CPU0_G1_TX_DN<12>")
	)
	(segment
		(start 150.22068 -197.834758)
		(end 159.58185 -190.159132)
		(width 0.14224)
		(layer "In11.Cu")
		(net "GMI_CPU1_G3_CPU0_G1_TX_DN<12>")
	)
	(segment
		(start 262.7376 -187.823348)
		(end 303.706784 -188.201808)
		(width 0.14224)
		(layer "In11.Cu")
		(net "GMI_CPU1_G3_CPU0_G1_TX_DN<12>")
	)
	(segment
		(start 347.785182 -223.91116)
		(end 347.784166 -223.911668)
		(width 0.1143)
		(layer "In11.Cu")
		(net "GMI_CPU1_G3_CPU0_G1_TX_DN<12>")
	)
	(segment
		(start 347.823282 -227.128832)
		(end 347.786706 -227.150168)
		(width 0.1143)
		(layer "In11.Cu")
		(net "GMI_CPU1_G3_CPU0_G1_TX_DN<12>")
	)
	(segment
		(start 123.7107 -225.531426)
		(end 123.709176 -225.53041)
		(width 0.1143)
		(layer "In11.Cu")
		(net "GMI_CPU1_G3_CPU0_G1_TX_DN<12>")
	)
	(segment
		(start 348.127066 -221.083124)
		(end 348.081346 -221.128844)
		(width 0.1143)
		(layer "In11.Cu")
		(net "GMI_CPU1_G3_CPU0_G1_TX_DN<12>")
	)
	(segment
		(start 347.785182 -228.771196)
		(end 347.784166 -228.771704)
		(width 0.1143)
		(layer "In11.Cu")
		(net "GMI_CPU1_G3_CPU0_G1_TX_DN<12>")
	)
	(segment
		(start 348.127066 -221.071694)
		(end 348.127066 -221.083124)
		(width 0.1143)
		(layer "In11.Cu")
		(net "GMI_CPU1_G3_CPU0_G1_TX_DN<12>")
	)
	(segment
		(start 123.6726 -226.199954)
		(end 123.711716 -226.177094)
		(width 0.1143)
		(layer "In11.Cu")
		(net "GMI_CPU1_G3_CPU0_G1_TX_DN<12>")
	)
	(segment
		(start 123.711716 -222.93707)
		(end 123.712478 -222.936562)
		(width 0.1143)
		(layer "In11.Cu")
		(net "GMI_CPU1_G3_CPU0_G1_TX_DN<12>")
	)
	(segment
		(start 347.785182 -227.151184)
		(end 347.784166 -227.151692)
		(width 0.1143)
		(layer "In11.Cu")
		(net "GMI_CPU1_G3_CPU0_G1_TX_DN<12>")
	)
	(segment
		(start 123.718828 -222.933006)
		(end 123.743466 -222.918782)
		(width 0.1143)
		(layer "In11.Cu")
		(net "GMI_CPU1_G3_CPU0_G1_TX_DN<12>")
	)
	(segment
		(start 123.711716 -227.151946)
		(end 123.7107 -227.151438)
		(width 0.1143)
		(layer "In11.Cu")
		(net "GMI_CPU1_G3_CPU0_G1_TX_DN<12>")
	)
	(segment
		(start 123.368816 -221.083378)
		(end 123.368816 -221.071948)
		(width 0.1143)
		(layer "In11.Cu")
		(net "GMI_CPU1_G3_CPU0_G1_TX_DN<12>")
	)
	(segment
		(start 347.823282 -222.268796)
		(end 347.752416 -222.309944)
		(width 0.1143)
		(layer "In11.Cu")
		(net "GMI_CPU1_G3_CPU0_G1_TX_DN<12>")
	)
	(segment
		(start 347.78061 -227.79482)
		(end 347.783404 -227.796344)
		(width 0.1143)
		(layer "In11.Cu")
		(net "GMI_CPU1_G3_CPU0_G1_TX_DN<12>")
	)
	(segment
		(start 123.712478 -232.65638)
		(end 123.715272 -232.654856)
		(width 0.1143)
		(layer "In11.Cu")
		(net "GMI_CPU1_G3_CPU0_G1_TX_DN<12>")
	)
	(segment
		(start 123.711716 -226.177094)
		(end 123.712478 -226.176586)
		(width 0.1143)
		(layer "In11.Cu")
		(net "GMI_CPU1_G3_CPU0_G1_TX_DN<12>")
	)
	(segment
		(start 347.787722 -232.658666)
		(end 347.790262 -232.66019)
		(width 0.1143)
		(layer "In11.Cu")
		(net "GMI_CPU1_G3_CPU0_G1_TX_DN<12>")
	)
	(segment
		(start 123.712478 -223.91243)
		(end 123.711716 -223.911922)
		(width 0.1143)
		(layer "In11.Cu")
		(net "GMI_CPU1_G3_CPU0_G1_TX_DN<12>")
	)
	(segment
		(start 348.081346 -221.426024)
		(end 348.06636 -221.44101)
		(width 0.1143)
		(layer "In11.Cu")
		(net "GMI_CPU1_G3_CPU0_G1_TX_DN<12>")
	)
	(segment
		(start 123.429522 -221.804484)
		(end 123.429522 -221.441264)
		(width 0.1143)
		(layer "In11.Cu")
		(net "GMI_CPU1_G3_CPU0_G1_TX_DN<12>")
	)
	(segment
		(start 159.672274 -190.08471)
		(end 159.672528 -190.08471)
		(width 0.14224)
		(layer "In11.Cu")
		(net "GMI_CPU1_G3_CPU0_G1_TX_DN<12>")
	)
	(segment
		(start 123.716034 -227.794566)
		(end 123.71705 -227.794058)
		(width 0.1143)
		(layer "In11.Cu")
		(net "GMI_CPU1_G3_CPU0_G1_TX_DN<12>")
	)
	(segment
		(start 347.823282 -223.888808)
		(end 347.786706 -223.910144)
		(width 0.1143)
		(layer "In11.Cu")
		(net "GMI_CPU1_G3_CPU0_G1_TX_DN<12>")
	)
	(segment
		(start 123.743466 -222.310198)
		(end 123.6726 -222.26905)
		(width 0.1143)
		(layer "In11.Cu")
		(net "GMI_CPU1_G3_CPU0_G1_TX_DN<12>")
	)
	(segment
		(start 159.58185 -190.159132)
		(end 159.582104 -190.158624)
		(width 0.14224)
		(layer "In11.Cu")
		(net "GMI_CPU1_G3_CPU0_G1_TX_DN<12>")
	)
	(segment
		(start 347.785182 -227.79736)
		(end 347.786706 -227.798376)
		(width 0.1143)
		(layer "In11.Cu")
		(net "GMI_CPU1_G3_CPU0_G1_TX_DN<12>")
	)
	(segment
		(start 347.791786 -226.181412)
		(end 347.823282 -226.1997)
		(width 0.1143)
		(layer "In11.Cu")
		(net "GMI_CPU1_G3_CPU0_G1_TX_DN<12>")
	)
	(segment
		(start 250.57608 -189.96787)
		(end 262.7376 -187.823348)
		(width 0.14224)
		(layer "In11.Cu")
		(net "GMI_CPU1_G3_CPU0_G1_TX_DN<12>")
	)
	(segment
		(start 123.743466 -225.550222)
		(end 123.712478 -225.532442)
		(width 0.1143)
		(layer "In11.Cu")
		(net "GMI_CPU1_G3_CPU0_G1_TX_DN<12>")
	)
	(segment
		(start 347.78061 -222.934784)
		(end 347.783404 -222.936308)
		(width 0.1143)
		(layer "In11.Cu")
		(net "GMI_CPU1_G3_CPU0_G1_TX_DN<12>")
	)
	(segment
		(start 123.709176 -223.910398)
		(end 123.6726 -223.889062)
		(width 0.1143)
		(layer "In11.Cu")
		(net "GMI_CPU1_G3_CPU0_G1_TX_DN<12>")
	)
	(segment
		(start 347.786706 -222.93834)
		(end 347.787722 -222.938848)
		(width 0.1143)
		(layer "In11.Cu")
		(net "GMI_CPU1_G3_CPU0_G1_TX_DN<12>")
	)
	(segment
		(start 122.41276 -234.764326)
		(end 122.495564 -234.681522)
		(width 0.1143)
		(layer "In11.Cu")
		(net "GMI_CPU1_G3_CPU0_G1_TX_DN<12>")
	)
	(segment
		(start 239.093756 -198.007986)
		(end 250.57608 -189.96787)
		(width 0.14224)
		(layer "In11.Cu")
		(net "GMI_CPU1_G3_CPU0_G1_TX_DN<12>")
	)
	(segment
		(start 347.786706 -227.150168)
		(end 347.785182 -227.151184)
		(width 0.1143)
		(layer "In11.Cu")
		(net "GMI_CPU1_G3_CPU0_G1_TX_DN<12>")
	)
	(segment
		(start 123.709176 -227.150422)
		(end 123.6726 -227.129086)
		(width 0.1143)
		(layer "In11.Cu")
		(net "GMI_CPU1_G3_CPU0_G1_TX_DN<12>")
	)
	(segment
		(start 123.716034 -232.654348)
		(end 123.71705 -232.65384)
		(width 0.1143)
		(layer "In11.Cu")
		(net "GMI_CPU1_G3_CPU0_G1_TX_DN<12>")
	)
	(segment
		(start 123.709176 -228.770434)
		(end 123.6726 -228.749098)
		(width 0.1143)
		(layer "In11.Cu")
		(net "GMI_CPU1_G3_CPU0_G1_TX_DN<12>")
	)
	(segment
		(start 347.784166 -230.391716)
		(end 347.752416 -230.410004)
		(width 0.1143)
		(layer "In11.Cu")
		(net "GMI_CPU1_G3_CPU0_G1_TX_DN<12>")
	)
	(segment
		(start 318.94907 -194.944746)
		(end 346.623894 -217.636852)
		(width 0.14224)
		(layer "In11.Cu")
		(net "GMI_CPU1_G3_CPU0_G1_TX_DN<12>")
	)
	(segment
		(start 349.000318 -234.681268)
		(end 349.083122 -234.764072)
		(width 0.1143)
		(layer "In11.Cu")
		(net "GMI_CPU1_G3_CPU0_G1_TX_DN<12>")
	)
	(segment
		(start 347.752416 -222.918528)
		(end 347.779848 -222.934276)
		(width 0.1143)
		(layer "In11.Cu")
		(net "GMI_CPU1_G3_CPU0_G1_TX_DN<12>")
	)
	(segment
		(start 125.084586 -217.345006)
		(end 145.74266 -200.406254)
		(width 0.14224)
		(layer "In11.Cu")
		(net "GMI_CPU1_G3_CPU0_G1_TX_DN<12>")
	)
	(segment
		(start 123.716034 -226.174554)
		(end 123.71705 -226.174046)
		(width 0.1143)
		(layer "In11.Cu")
		(net "GMI_CPU1_G3_CPU0_G1_TX_DN<12>")
	)
	(segment
		(start 123.716034 -222.93453)
		(end 123.71705 -222.934022)
		(width 0.1143)
		(layer "In11.Cu")
		(net "GMI_CPU1_G3_CPU0_G1_TX_DN<12>")
	)
	(segment
		(start 347.790262 -226.180396)
		(end 347.791786 -226.181412)
		(width 0.1143)
		(layer "In11.Cu")
		(net "GMI_CPU1_G3_CPU0_G1_TX_DN<12>")
	)
	(segment
		(start 347.786706 -232.658158)
		(end 347.787722 -232.658666)
		(width 0.1143)
		(layer "In11.Cu")
		(net "GMI_CPU1_G3_CPU0_G1_TX_DN<12>")
	)
	(segment
		(start 347.783404 -224.55632)
		(end 347.784166 -224.556828)
		(width 0.1143)
		(layer "In11.Cu")
		(net "GMI_CPU1_G3_CPU0_G1_TX_DN<12>")
	)
	(segment
		(start 347.791786 -224.5614)
		(end 347.823282 -224.579688)
		(width 0.1143)
		(layer "In11.Cu")
		(net "GMI_CPU1_G3_CPU0_G1_TX_DN<12>")
	)
	(segment
		(start 347.784166 -226.17684)
		(end 347.785182 -226.177348)
		(width 0.1143)
		(layer "In11.Cu")
		(net "GMI_CPU1_G3_CPU0_G1_TX_DN<12>")
	)
	(segment
		(start 123.71705 -224.554034)
		(end 123.717812 -224.553526)
		(width 0.1143)
		(layer "In11.Cu")
		(net "GMI_CPU1_G3_CPU0_G1_TX_DN<12>")
	)
	(segment
		(start 347.791786 -222.941388)
		(end 347.823282 -222.959676)
		(width 0.1143)
		(layer "In11.Cu")
		(net "GMI_CPU1_G3_CPU0_G1_TX_DN<12>")
	)
	(segment
		(start 348.127066 -220.169486)
		(end 348.127066 -221.071694)
		(width 0.14224)
		(layer "In11.Cu")
		(net "GMI_CPU1_G3_CPU0_G1_TX_DN<12>")
	)
	(segment
		(start 123.717812 -232.653332)
		(end 123.718828 -232.652824)
		(width 0.1143)
		(layer "In11.Cu")
		(net "GMI_CPU1_G3_CPU0_G1_TX_DN<12>")
	)
	(segment
		(start 123.71705 -227.794058)
		(end 123.717812 -227.79355)
		(width 0.1143)
		(layer "In11.Cu")
		(net "GMI_CPU1_G3_CPU0_G1_TX_DN<12>")
	)
	(segment
		(start 123.2027 -233.489754)
		(end 123.272296 -233.449114)
		(width 0.1143)
		(layer "In11.Cu")
		(net "GMI_CPU1_G3_CPU0_G1_TX_DN<12>")
	)
	(segment
		(start 347.790262 -227.800408)
		(end 347.791786 -227.801424)
		(width 0.1143)
		(layer "In11.Cu")
		(net "GMI_CPU1_G3_CPU0_G1_TX_DN<12>")
	)
	(segment
		(start 309.435754 -188.201808)
		(end 318.819784 -194.815714)
		(width 0.14224)
		(layer "In11.Cu")
		(net "GMI_CPU1_G3_CPU0_G1_TX_DN<12>")
	)
	(segment
		(start 147.870418 -199.76211)
		(end 150.220934 -197.834758)
		(width 0.14224)
		(layer "In11.Cu")
		(net "GMI_CPU1_G3_CPU0_G1_TX_DN<12>")
	)
	(segment
		(start 123.7107 -228.77145)
		(end 123.709176 -228.770434)
		(width 0.1143)
		(layer "In11.Cu")
		(net "GMI_CPU1_G3_CPU0_G1_TX_DN<12>")
	)
	(segment
		(start 150.220934 -197.834758)
		(end 150.22068 -197.834758)
		(width 0.14224)
		(layer "In11.Cu")
		(net "GMI_CPU1_G3_CPU0_G1_TX_DN<12>")
	)
	(segment
		(start 123.718828 -226.17303)
		(end 123.743466 -226.158806)
		(width 0.1143)
		(layer "In11.Cu")
		(net "GMI_CPU1_G3_CPU0_G1_TX_DN<12>")
	)
	(segment
		(start 347.823282 -225.50882)
		(end 347.786706 -225.530156)
		(width 0.1143)
		(layer "In11.Cu")
		(net "GMI_CPU1_G3_CPU0_G1_TX_DN<12>")
	)
	(segment
		(start 347.78061 -232.654602)
		(end 347.783404 -232.656126)
		(width 0.1143)
		(layer "In11.Cu")
		(net "GMI_CPU1_G3_CPU0_G1_TX_DN<12>")
	)
	(segment
		(start 123.709176 -225.53041)
		(end 123.6726 -225.509074)
		(width 0.1143)
		(layer "In11.Cu")
		(net "GMI_CPU1_G3_CPU0_G1_TX_DN<12>")
	)
	(segment
		(start 123.6726 -227.819966)
		(end 123.711716 -227.797106)
		(width 0.1143)
		(layer "In11.Cu")
		(net "GMI_CPU1_G3_CPU0_G1_TX_DN<12>")
	)
	(segment
		(start 347.783404 -226.176332)
		(end 347.784166 -226.17684)
		(width 0.1143)
		(layer "In11.Cu")
		(net "GMI_CPU1_G3_CPU0_G1_TX_DN<12>")
	)
	(segment
		(start 159.672528 -190.08471)
		(end 161.857944 -188.29274)
		(width 0.14224)
		(layer "In11.Cu")
		(net "GMI_CPU1_G3_CPU0_G1_TX_DN<12>")
	)
	(arc
		(start 347.823282 -227.819712)
		(mid 348.066609 -228.284278)
		(end 347.823282 -228.748844)
		(width 0.1143)
		(layer "In11.Cu")
		(net "GMI_CPU1_G3_CPU0_G1_TX_DN<12>")
	)
	(arc
		(start 347.59646 -232.334054)
		(mid 347.637715 -232.505025)
		(end 347.752416 -232.638346)
		(width 0.1143)
		(layer "In11.Cu")
		(net "GMI_CPU1_G3_CPU0_G1_TX_DN<12>")
	)
	(arc
		(start 123.67514 -230.370634)
		(mid 123.494488 -230.167889)
		(end 123.429268 -229.90429)
		(width 0.1143)
		(layer "In11.Cu")
		(net "GMI_CPU1_G3_CPU0_G1_TX_DN<12>")
	)
	(arc
		(start 348.708218 -234.26547)
		(mid 348.714405 -234.269213)
		(end 348.720664 -234.272836)
		(width 0.1143)
		(layer "In11.Cu")
		(net "GMI_CPU1_G3_CPU0_G1_TX_DN<12>")
	)
	(arc
		(start 347.752416 -225.549968)
		(mid 347.596488 -225.85426)
		(end 347.752416 -226.158552)
		(width 0.1143)
		(layer "In11.Cu")
		(net "GMI_CPU1_G3_CPU0_G1_TX_DN<12>")
	)
	(arc
		(start 123.272296 -233.449114)
		(mid 123.387723 -233.315738)
		(end 123.429268 -233.144314)
		(width 0.1143)
		(layer "In11.Cu")
		(net "GMI_CPU1_G3_CPU0_G1_TX_DN<12>")
	)
	(arc
		(start 347.823282 -229.43947)
		(mid 348.002095 -229.64182)
		(end 348.066614 -229.904036)
		(width 0.1143)
		(layer "In11.Cu")
		(net "GMI_CPU1_G3_CPU0_G1_TX_DN<12>")
	)
	(arc
		(start 124.21235 -231.829102)
		(mid 124.327777 -231.695726)
		(end 124.369322 -231.524302)
		(width 0.1143)
		(layer "In11.Cu")
		(net "GMI_CPU1_G3_CPU0_G1_TX_DN<12>")
	)
	(arc
		(start 123.429268 -233.144314)
		(mid 123.493783 -232.882095)
		(end 123.6726 -232.679748)
		(width 0.1143)
		(layer "In11.Cu")
		(net "GMI_CPU1_G3_CPU0_G1_TX_DN<12>")
	)
	(arc
		(start 124.142754 -231.179116)
		(mid 123.963941 -230.976766)
		(end 123.899422 -230.71455)
		(width 0.1143)
		(layer "In11.Cu")
		(net "GMI_CPU1_G3_CPU0_G1_TX_DN<12>")
	)
	(arc
		(start 123.743466 -227.778818)
		(mid 123.899394 -227.474526)
		(end 123.743466 -227.170234)
		(width 0.1143)
		(layer "In11.Cu")
		(net "GMI_CPU1_G3_CPU0_G1_TX_DN<12>")
	)
	(arc
		(start 347.59646 -230.714296)
		(mid 347.531945 -230.976515)
		(end 347.353128 -231.178862)
		(width 0.1143)
		(layer "In11.Cu")
		(net "GMI_CPU1_G3_CPU0_G1_TX_DN<12>")
	)
	(arc
		(start 123.6726 -225.509074)
		(mid 123.429273 -225.044508)
		(end 123.6726 -224.579942)
		(width 0.1143)
		(layer "In11.Cu")
		(net "GMI_CPU1_G3_CPU0_G1_TX_DN<12>")
	)
	(arc
		(start 347.59646 -229.094284)
		(mid 347.637222 -229.264168)
		(end 347.750638 -229.397052)
		(width 0.1143)
		(layer "In11.Cu")
		(net "GMI_CPU1_G3_CPU0_G1_TX_DN<12>")
	)
	(arc
		(start 123.899422 -229.094538)
		(mid 123.858167 -228.923567)
		(end 123.743466 -228.790246)
		(width 0.1143)
		(layer "In11.Cu")
		(net "GMI_CPU1_G3_CPU0_G1_TX_DN<12>")
	)
	(arc
		(start 123.743466 -232.6386)
		(mid 123.858142 -232.505266)
		(end 123.899422 -232.334308)
		(width 0.1143)
		(layer "In11.Cu")
		(net "GMI_CPU1_G3_CPU0_G1_TX_DN<12>")
	)
	(arc
		(start 123.745244 -229.397306)
		(mid 123.858651 -229.264417)
		(end 123.899422 -229.094538)
		(width 0.1143)
		(layer "In11.Cu")
		(net "GMI_CPU1_G3_CPU0_G1_TX_DN<12>")
	)
	(arc
		(start 123.6726 -222.26905)
		(mid 123.493942 -222.06665)
		(end 123.429522 -221.804484)
		(width 0.1143)
		(layer "In11.Cu")
		(net "GMI_CPU1_G3_CPU0_G1_TX_DN<12>")
	)
	(arc
		(start 123.6726 -223.889062)
		(mid 123.429273 -223.424496)
		(end 123.6726 -222.95993)
		(width 0.1143)
		(layer "In11.Cu")
		(net "GMI_CPU1_G3_CPU0_G1_TX_DN<12>")
	)
	(arc
		(start 347.2815 -231.220518)
		(mid 347.167571 -231.353665)
		(end 347.12656 -231.524048)
		(width 0.1143)
		(layer "In11.Cu")
		(net "GMI_CPU1_G3_CPU0_G1_TX_DN<12>")
	)
	(arc
		(start 347.752416 -227.16998)
		(mid 347.596488 -227.474272)
		(end 347.752416 -227.778564)
		(width 0.1143)
		(layer "In11.Cu")
		(net "GMI_CPU1_G3_CPU0_G1_TX_DN<12>")
	)
	(arc
		(start 348.066614 -233.14406)
		(mid 348.108163 -233.315482)
		(end 348.223586 -233.44886)
		(width 0.1143)
		(layer "In11.Cu")
		(net "GMI_CPU1_G3_CPU0_G1_TX_DN<12>")
	)
	(arc
		(start 347.823282 -232.679494)
		(mid 348.002095 -232.881844)
		(end 348.066614 -233.14406)
		(width 0.1143)
		(layer "In11.Cu")
		(net "GMI_CPU1_G3_CPU0_G1_TX_DN<12>")
	)
	(arc
		(start 347.752416 -228.789992)
		(mid 347.63774 -228.923326)
		(end 347.59646 -229.094284)
		(width 0.1143)
		(layer "In11.Cu")
		(net "GMI_CPU1_G3_CPU0_G1_TX_DN<12>")
	)
	(arc
		(start 122.959368 -233.95432)
		(mid 123.023883 -233.692101)
		(end 123.2027 -233.489754)
		(width 0.1143)
		(layer "In11.Cu")
		(net "GMI_CPU1_G3_CPU0_G1_TX_DN<12>")
	)
	(arc
		(start 348.066614 -229.904036)
		(mid 348.001378 -230.167627)
		(end 347.820742 -230.37038)
		(width 0.1143)
		(layer "In11.Cu")
		(net "GMI_CPU1_G3_CPU0_G1_TX_DN<12>")
	)
	(arc
		(start 347.752416 -230.410004)
		(mid 347.63774 -230.543338)
		(end 347.59646 -230.714296)
		(width 0.1143)
		(layer "In11.Cu")
		(net "GMI_CPU1_G3_CPU0_G1_TX_DN<12>")
	)
	(arc
		(start 123.899422 -230.71455)
		(mid 123.858167 -230.543579)
		(end 123.743466 -230.410258)
		(width 0.1143)
		(layer "In11.Cu")
		(net "GMI_CPU1_G3_CPU0_G1_TX_DN<12>")
	)
	(arc
		(start 123.429268 -229.90429)
		(mid 123.493783 -229.642071)
		(end 123.6726 -229.439724)
		(width 0.1143)
		(layer "In11.Cu")
		(net "GMI_CPU1_G3_CPU0_G1_TX_DN<12>")
	)
	(arc
		(start 122.775218 -234.27309)
		(mid 122.781478 -234.269469)
		(end 122.787664 -234.265724)
		(width 0.1143)
		(layer "In11.Cu")
		(net "GMI_CPU1_G3_CPU0_G1_TX_DN<12>")
	)
	(arc
		(start 347.353128 -231.869488)
		(mid 347.531941 -232.071838)
		(end 347.59646 -232.334054)
		(width 0.1143)
		(layer "In11.Cu")
		(net "GMI_CPU1_G3_CPU0_G1_TX_DN<12>")
	)
	(arc
		(start 347.823282 -224.579688)
		(mid 348.066609 -225.044254)
		(end 347.823282 -225.50882)
		(width 0.1143)
		(layer "In11.Cu")
		(net "GMI_CPU1_G3_CPU0_G1_TX_DN<12>")
	)
	(arc
		(start 347.823282 -226.1997)
		(mid 348.066609 -226.664266)
		(end 347.823282 -227.128832)
		(width 0.1143)
		(layer "In11.Cu")
		(net "GMI_CPU1_G3_CPU0_G1_TX_DN<12>")
	)
	(arc
		(start 122.495564 -234.681522)
		(mid 122.586829 -234.447081)
		(end 122.7709 -234.27563)
		(width 0.1143)
		(layer "In11.Cu")
		(net "GMI_CPU1_G3_CPU0_G1_TX_DN<12>")
	)
	(arc
		(start 123.743466 -222.918782)
		(mid 123.899394 -222.61449)
		(end 123.743466 -222.310198)
		(width 0.1143)
		(layer "In11.Cu")
		(net "GMI_CPU1_G3_CPU0_G1_TX_DN<12>")
	)
	(arc
		(start 124.369322 -231.524302)
		(mid 124.328356 -231.353896)
		(end 124.214382 -231.220772)
		(width 0.1143)
		(layer "In11.Cu")
		(net "GMI_CPU1_G3_CPU0_G1_TX_DN<12>")
	)
	(arc
		(start 347.12656 -231.524048)
		(mid 347.168109 -231.69547)
		(end 347.283532 -231.828848)
		(width 0.1143)
		(layer "In11.Cu")
		(net "GMI_CPU1_G3_CPU0_G1_TX_DN<12>")
	)
	(arc
		(start 348.536514 -233.954066)
		(mid 348.582279 -234.131876)
		(end 348.708218 -234.26547)
		(width 0.1143)
		(layer "In11.Cu")
		(net "GMI_CPU1_G3_CPU0_G1_TX_DN<12>")
	)
	(arc
		(start 122.787664 -234.265724)
		(mid 122.913576 -234.132115)
		(end 122.959368 -233.95432)
		(width 0.1143)
		(layer "In11.Cu")
		(net "GMI_CPU1_G3_CPU0_G1_TX_DN<12>")
	)
	(arc
		(start 348.293182 -233.4895)
		(mid 348.471995 -233.69185)
		(end 348.536514 -233.954066)
		(width 0.1143)
		(layer "In11.Cu")
		(net "GMI_CPU1_G3_CPU0_G1_TX_DN<12>")
	)
	(arc
		(start 347.752416 -223.929956)
		(mid 347.596488 -224.234248)
		(end 347.752416 -224.53854)
		(width 0.1143)
		(layer "In11.Cu")
		(net "GMI_CPU1_G3_CPU0_G1_TX_DN<12>")
	)
	(arc
		(start 123.743466 -226.158806)
		(mid 123.899394 -225.854514)
		(end 123.743466 -225.550222)
		(width 0.1143)
		(layer "In11.Cu")
		(net "GMI_CPU1_G3_CPU0_G1_TX_DN<12>")
	)
	(arc
		(start 347.823282 -222.959676)
		(mid 348.066609 -223.424242)
		(end 347.823282 -223.888808)
		(width 0.1143)
		(layer "In11.Cu")
		(net "GMI_CPU1_G3_CPU0_G1_TX_DN<12>")
	)
	(arc
		(start 123.743466 -224.538794)
		(mid 123.899394 -224.234502)
		(end 123.743466 -223.93021)
		(width 0.1143)
		(layer "In11.Cu")
		(net "GMI_CPU1_G3_CPU0_G1_TX_DN<12>")
	)
	(arc
		(start 348.06636 -221.80423)
		(mid 348.001913 -222.066382)
		(end 347.823282 -222.268796)
		(width 0.1143)
		(layer "In11.Cu")
		(net "GMI_CPU1_G3_CPU0_G1_TX_DN<12>")
	)
	(arc
		(start 123.6726 -227.129086)
		(mid 123.429273 -226.66452)
		(end 123.6726 -226.199954)
		(width 0.1143)
		(layer "In11.Cu")
		(net "GMI_CPU1_G3_CPU0_G1_TX_DN<12>")
	)
	(arc
		(start 347.752416 -222.309944)
		(mid 347.596488 -222.614236)
		(end 347.752416 -222.918528)
		(width 0.1143)
		(layer "In11.Cu")
		(net "GMI_CPU1_G3_CPU0_G1_TX_DN<12>")
	)
	(arc
		(start 348.724982 -234.275376)
		(mid 348.909022 -234.446873)
		(end 349.000318 -234.681268)
		(width 0.1143)
		(layer "In11.Cu")
		(net "GMI_CPU1_G3_CPU0_G1_TX_DN<12>")
	)
	(arc
		(start 123.6726 -228.749098)
		(mid 123.429273 -228.284532)
		(end 123.6726 -227.819966)
		(width 0.1143)
		(layer "In11.Cu")
		(net "GMI_CPU1_G3_CPU0_G1_TX_DN<12>")
	)
	(arc
		(start 123.899422 -232.334308)
		(mid 123.963937 -232.072089)
		(end 124.142754 -231.869742)
		(width 0.1143)
		(layer "In11.Cu")
		(net "GMI_CPU1_G3_CPU0_G1_TX_DN<12>")
	)
	(segment
		(start 121.647966 -233.410252)
		(end 122.114818 -233.144314)
		(width 0.12954)
		(layer "F.Cu")
		(net "GMI_CPU1_G3_CPU0_G1_TX_DN<11>")
	)
	(segment
		(start 349.847916 -233.409998)
		(end 349.381064 -233.14406)
		(width 0.12954)
		(layer "F.Cu")
		(net "GMI_CPU1_G3_CPU0_G1_TX_DN<11>")
	)
	(segment
		(start 122.114818 -233.144314)
		(end 122.41276 -233.144314)
		(width 0.1143)
		(layer "In11.Cu")
		(net "GMI_CPU1_G3_CPU0_G1_TX_DN<11>")
	)
	(segment
		(start 348.760542 -230.37038)
		(end 348.693486 -230.409496)
		(width 0.1143)
		(layer "In11.Cu")
		(net "GMI_CPU1_G3_CPU0_G1_TX_DN<11>")
	)
	(segment
		(start 145.224754 -199.550528)
		(end 147.138136 -198.9709)
		(width 0.14224)
		(layer "In11.Cu")
		(net "GMI_CPU1_G3_CPU0_G1_TX_DN<11>")
	)
	(segment
		(start 122.771916 -222.93707)
		(end 122.802396 -222.91929)
		(width 0.1143)
		(layer "In11.Cu")
		(net "GMI_CPU1_G3_CPU0_G1_TX_DN<11>")
	)
	(segment
		(start 123.241816 -231.846882)
		(end 123.242578 -231.846374)
		(width 0.1143)
		(layer "In11.Cu")
		(net "GMI_CPU1_G3_CPU0_G1_TX_DN<11>")
	)
	(segment
		(start 348.253304 -231.84612)
		(end 348.254066 -231.846628)
		(width 0.1143)
		(layer "In11.Cu")
		(net "GMI_CPU1_G3_CPU0_G1_TX_DN<11>")
	)
	(segment
		(start 122.42419 -220.070934)
		(end 124.441458 -216.59215)
		(width 0.14224)
		(layer "In11.Cu")
		(net "GMI_CPU1_G3_CPU0_G1_TX_DN<11>")
	)
	(segment
		(start 122.771916 -224.557082)
		(end 122.802396 -224.539302)
		(width 0.1143)
		(layer "In11.Cu")
		(net "GMI_CPU1_G3_CPU0_G1_TX_DN<11>")
	)
	(segment
		(start 349.071692 -219.933774)
		(end 349.071692 -221.071694)
		(width 0.14224)
		(layer "In11.Cu")
		(net "GMI_CPU1_G3_CPU0_G1_TX_DN<11>")
	)
	(segment
		(start 348.255082 -231.847136)
		(end 348.256606 -231.848152)
		(width 0.1143)
		(layer "In11.Cu")
		(net "GMI_CPU1_G3_CPU0_G1_TX_DN<11>")
	)
	(segment
		(start 122.7328 -232.679748)
		(end 122.771916 -232.656888)
		(width 0.1143)
		(layer "In11.Cu")
		(net "GMI_CPU1_G3_CPU0_G1_TX_DN<11>")
	)
	(segment
		(start 348.25051 -231.844596)
		(end 348.252034 -231.845358)
		(width 0.1143)
		(layer "In11.Cu")
		(net "GMI_CPU1_G3_CPU0_G1_TX_DN<11>")
	)
	(segment
		(start 158.215838 -189.88786)
		(end 158.216092 -189.88786)
		(width 0.14224)
		(layer "In11.Cu")
		(net "GMI_CPU1_G3_CPU0_G1_TX_DN<11>")
	)
	(segment
		(start 302.605948 -185.13298)
		(end 306.42687 -185.13298)
		(width 0.14224)
		(layer "In11.Cu")
		(net "GMI_CPU1_G3_CPU0_G1_TX_DN<11>")
	)
	(segment
		(start 122.7328 -227.819966)
		(end 122.771916 -227.797106)
		(width 0.1143)
		(layer "In11.Cu")
		(net "GMI_CPU1_G3_CPU0_G1_TX_DN<11>")
	)
	(segment
		(start 348.261686 -231.8512)
		(end 348.293182 -231.869488)
		(width 0.1143)
		(layer "In11.Cu")
		(net "GMI_CPU1_G3_CPU0_G1_TX_DN<11>")
	)
	(segment
		(start 349.00616 -221.445836)
		(end 349.00616 -221.80423)
		(width 0.1143)
		(layer "In11.Cu")
		(net "GMI_CPU1_G3_CPU0_G1_TX_DN<11>")
	)
	(segment
		(start 348.257622 -231.84866)
		(end 348.260162 -231.850184)
		(width 0.1143)
		(layer "In11.Cu")
		(net "GMI_CPU1_G3_CPU0_G1_TX_DN<11>")
	)
	(segment
		(start 348.222316 -231.82834)
		(end 348.24924 -231.843834)
		(width 0.1143)
		(layer "In11.Cu")
		(net "GMI_CPU1_G3_CPU0_G1_TX_DN<11>")
	)
	(segment
		(start 348.293182 -231.178862)
		(end 348.220538 -231.22128)
		(width 0.1143)
		(layer "In11.Cu")
		(net "GMI_CPU1_G3_CPU0_G1_TX_DN<11>")
	)
	(segment
		(start 122.771916 -227.797106)
		(end 122.802396 -227.779326)
		(width 0.1143)
		(layer "In11.Cu")
		(net "GMI_CPU1_G3_CPU0_G1_TX_DN<11>")
	)
	(segment
		(start 123.275344 -231.221534)
		(end 123.241816 -231.201976)
		(width 0.1143)
		(layer "In11.Cu")
		(net "GMI_CPU1_G3_CPU0_G1_TX_DN<11>")
	)
	(segment
		(start 122.802396 -222.30969)
		(end 122.7328 -222.26905)
		(width 0.1143)
		(layer "In11.Cu")
		(net "GMI_CPU1_G3_CPU0_G1_TX_DN<11>")
	)
	(segment
		(start 348.254066 -231.846628)
		(end 348.255082 -231.847136)
		(width 0.1143)
		(layer "In11.Cu")
		(net "GMI_CPU1_G3_CPU0_G1_TX_DN<11>")
	)
	(segment
		(start 122.771916 -225.531934)
		(end 122.7328 -225.509074)
		(width 0.1143)
		(layer "In11.Cu")
		(net "GMI_CPU1_G3_CPU0_G1_TX_DN<11>")
	)
	(segment
		(start 122.771916 -223.911922)
		(end 122.7328 -223.889062)
		(width 0.1143)
		(layer "In11.Cu")
		(net "GMI_CPU1_G3_CPU0_G1_TX_DN<11>")
	)
	(segment
		(start 122.489722 -221.804484)
		(end 122.489722 -221.44609)
		(width 0.1143)
		(layer "In11.Cu")
		(net "GMI_CPU1_G3_CPU0_G1_TX_DN<11>")
	)
	(segment
		(start 348.723966 -229.41661)
		(end 348.763082 -229.43947)
		(width 0.1143)
		(layer "In11.Cu")
		(net "GMI_CPU1_G3_CPU0_G1_TX_DN<11>")
	)
	(segment
		(start 122.7328 -224.579942)
		(end 122.771916 -224.557082)
		(width 0.1143)
		(layer "In11.Cu")
		(net "GMI_CPU1_G3_CPU0_G1_TX_DN<11>")
	)
	(segment
		(start 123.245372 -231.84485)
		(end 123.246642 -231.844088)
		(width 0.1143)
		(layer "In11.Cu")
		(net "GMI_CPU1_G3_CPU0_G1_TX_DN<11>")
	)
	(segment
		(start 348.763082 -228.748844)
		(end 348.693486 -228.789484)
		(width 0.1143)
		(layer "In11.Cu")
		(net "GMI_CPU1_G3_CPU0_G1_TX_DN<11>")
	)
	(segment
		(start 349.000318 -233.061256)
		(end 349.083122 -233.14406)
		(width 0.1143)
		(layer "In11.Cu")
		(net "GMI_CPU1_G3_CPU0_G1_TX_DN<11>")
	)
	(segment
		(start 147.138136 -198.9709)
		(end 158.125414 -189.961266)
		(width 0.14224)
		(layer "In11.Cu")
		(net "GMI_CPU1_G3_CPU0_G1_TX_DN<11>")
	)
	(segment
		(start 349.071692 -221.071694)
		(end 349.071692 -221.083124)
		(width 0.1143)
		(layer "In11.Cu")
		(net "GMI_CPU1_G3_CPU0_G1_TX_DN<11>")
	)
	(segment
		(start 122.42419 -221.083378)
		(end 122.42419 -221.071948)
		(width 0.1143)
		(layer "In11.Cu")
		(net "GMI_CPU1_G3_CPU0_G1_TX_DN<11>")
	)
	(segment
		(start 122.802396 -225.549714)
		(end 122.771916 -225.531934)
		(width 0.1143)
		(layer "In11.Cu")
		(net "GMI_CPU1_G3_CPU0_G1_TX_DN<11>")
	)
	(segment
		(start 122.7328 -229.439724)
		(end 122.771916 -229.416864)
		(width 0.1143)
		(layer "In11.Cu")
		(net "GMI_CPU1_G3_CPU0_G1_TX_DN<11>")
	)
	(segment
		(start 123.247404 -231.84358)
		(end 123.248674 -231.842818)
		(width 0.1143)
		(layer "In11.Cu")
		(net "GMI_CPU1_G3_CPU0_G1_TX_DN<11>")
	)
	(segment
		(start 349.071692 -221.083124)
		(end 349.025972 -221.128844)
		(width 0.1143)
		(layer "In11.Cu")
		(net "GMI_CPU1_G3_CPU0_G1_TX_DN<11>")
	)
	(segment
		(start 158.216092 -189.88786)
		(end 163.189412 -185.809382)
		(width 0.14224)
		(layer "In11.Cu")
		(net "GMI_CPU1_G3_CPU0_G1_TX_DN<11>")
	)
	(segment
		(start 348.693486 -224.539048)
		(end 348.763082 -224.579688)
		(width 0.1143)
		(layer "In11.Cu")
		(net "GMI_CPU1_G3_CPU0_G1_TX_DN<11>")
	)
	(segment
		(start 348.763082 -227.128832)
		(end 348.693486 -227.169472)
		(width 0.1143)
		(layer "In11.Cu")
		(net "GMI_CPU1_G3_CPU0_G1_TX_DN<11>")
	)
	(segment
		(start 163.189412 -185.809382)
		(end 167.283638 -184.345072)
		(width 0.14224)
		(layer "In11.Cu")
		(net "GMI_CPU1_G3_CPU0_G1_TX_DN<11>")
	)
	(segment
		(start 122.802396 -223.929702)
		(end 122.771916 -223.911922)
		(width 0.1143)
		(layer "In11.Cu")
		(net "GMI_CPU1_G3_CPU0_G1_TX_DN<11>")
	)
	(segment
		(start 122.771916 -228.771958)
		(end 122.7328 -228.749098)
		(width 0.1143)
		(layer "In11.Cu")
		(net "GMI_CPU1_G3_CPU0_G1_TX_DN<11>")
	)
	(segment
		(start 348.24924 -231.843834)
		(end 348.25051 -231.844596)
		(width 0.1143)
		(layer "In11.Cu")
		(net "GMI_CPU1_G3_CPU0_G1_TX_DN<11>")
	)
	(segment
		(start 122.802396 -227.169726)
		(end 122.771916 -227.151946)
		(width 0.1143)
		(layer "In11.Cu")
		(net "GMI_CPU1_G3_CPU0_G1_TX_DN<11>")
	)
	(segment
		(start 123.241816 -231.201976)
		(end 123.2027 -231.179116)
		(width 0.1143)
		(layer "In11.Cu")
		(net "GMI_CPU1_G3_CPU0_G1_TX_DN<11>")
	)
	(segment
		(start 348.763082 -222.268796)
		(end 348.693486 -222.309436)
		(width 0.1143)
		(layer "In11.Cu")
		(net "GMI_CPU1_G3_CPU0_G1_TX_DN<11>")
	)
	(segment
		(start 122.802396 -228.789738)
		(end 122.771916 -228.771958)
		(width 0.1143)
		(layer "In11.Cu")
		(net "GMI_CPU1_G3_CPU0_G1_TX_DN<11>")
	)
	(segment
		(start 158.125668 -189.961774)
		(end 158.215838 -189.88786)
		(width 0.14224)
		(layer "In11.Cu")
		(net "GMI_CPU1_G3_CPU0_G1_TX_DN<11>")
	)
	(segment
		(start 123.246642 -231.844088)
		(end 123.247404 -231.84358)
		(width 0.1143)
		(layer "In11.Cu")
		(net "GMI_CPU1_G3_CPU0_G1_TX_DN<11>")
	)
	(segment
		(start 348.691454 -229.397814)
		(end 348.723966 -229.41661)
		(width 0.1143)
		(layer "In11.Cu")
		(net "GMI_CPU1_G3_CPU0_G1_TX_DN<11>")
	)
	(segment
		(start 122.802396 -230.40975)
		(end 122.73534 -230.370634)
		(width 0.1143)
		(layer "In11.Cu")
		(net "GMI_CPU1_G3_CPU0_G1_TX_DN<11>")
	)
	(segment
		(start 122.771916 -229.416864)
		(end 122.804428 -229.398068)
		(width 0.1143)
		(layer "In11.Cu")
		(net "GMI_CPU1_G3_CPU0_G1_TX_DN<11>")
	)
	(segment
		(start 167.283638 -184.345072)
		(end 302.605948 -185.13298)
		(width 0.14224)
		(layer "In11.Cu")
		(net "GMI_CPU1_G3_CPU0_G1_TX_DN<11>")
	)
	(segment
		(start 349.025972 -221.128844)
		(end 349.025972 -221.426024)
		(width 0.1143)
		(layer "In11.Cu")
		(net "GMI_CPU1_G3_CPU0_G1_TX_DN<11>")
	)
	(segment
		(start 123.2027 -231.869742)
		(end 123.241816 -231.846882)
		(width 0.1143)
		(layer "In11.Cu")
		(net "GMI_CPU1_G3_CPU0_G1_TX_DN<11>")
	)
	(segment
		(start 348.763082 -223.888808)
		(end 348.693486 -223.929448)
		(width 0.1143)
		(layer "In11.Cu")
		(net "GMI_CPU1_G3_CPU0_G1_TX_DN<11>")
	)
	(segment
		(start 122.42419 -221.071948)
		(end 122.42419 -220.070934)
		(width 0.14224)
		(layer "In11.Cu")
		(net "GMI_CPU1_G3_CPU0_G1_TX_DN<11>")
	)
	(segment
		(start 348.763082 -225.50882)
		(end 348.693486 -225.54946)
		(width 0.1143)
		(layer "In11.Cu")
		(net "GMI_CPU1_G3_CPU0_G1_TX_DN<11>")
	)
	(segment
		(start 122.7328 -226.199954)
		(end 122.771916 -226.177094)
		(width 0.1143)
		(layer "In11.Cu")
		(net "GMI_CPU1_G3_CPU0_G1_TX_DN<11>")
	)
	(segment
		(start 122.771916 -232.656888)
		(end 122.802396 -232.639108)
		(width 0.1143)
		(layer "In11.Cu")
		(net "GMI_CPU1_G3_CPU0_G1_TX_DN<11>")
	)
	(segment
		(start 123.248674 -231.842818)
		(end 123.252738 -231.840786)
		(width 0.1143)
		(layer "In11.Cu")
		(net "GMI_CPU1_G3_CPU0_G1_TX_DN<11>")
	)
	(segment
		(start 122.46991 -221.129098)
		(end 122.42419 -221.083378)
		(width 0.1143)
		(layer "In11.Cu")
		(net "GMI_CPU1_G3_CPU0_G1_TX_DN<11>")
	)
	(segment
		(start 124.441458 -216.59215)
		(end 145.224754 -199.550528)
		(width 0.14224)
		(layer "In11.Cu")
		(net "GMI_CPU1_G3_CPU0_G1_TX_DN<11>")
	)
	(segment
		(start 348.693486 -227.779072)
		(end 348.763082 -227.819712)
		(width 0.1143)
		(layer "In11.Cu")
		(net "GMI_CPU1_G3_CPU0_G1_TX_DN<11>")
	)
	(segment
		(start 347.255846 -216.874852)
		(end 349.071692 -219.933774)
		(width 0.14224)
		(layer "In11.Cu")
		(net "GMI_CPU1_G3_CPU0_G1_TX_DN<11>")
	)
	(segment
		(start 307.390546 -185.531252)
		(end 314.258452 -189.817756)
		(width 0.14224)
		(layer "In11.Cu")
		(net "GMI_CPU1_G3_CPU0_G1_TX_DN<11>")
	)
	(segment
		(start 122.771916 -227.151946)
		(end 122.7328 -227.129086)
		(width 0.1143)
		(layer "In11.Cu")
		(net "GMI_CPU1_G3_CPU0_G1_TX_DN<11>")
	)
	(segment
		(start 348.252034 -231.845358)
		(end 348.253304 -231.84612)
		(width 0.1143)
		(layer "In11.Cu")
		(net "GMI_CPU1_G3_CPU0_G1_TX_DN<11>")
	)
	(segment
		(start 122.46991 -221.426278)
		(end 122.46991 -221.129098)
		(width 0.1143)
		(layer "In11.Cu")
		(net "GMI_CPU1_G3_CPU0_G1_TX_DN<11>")
	)
	(segment
		(start 314.258452 -189.817756)
		(end 347.255846 -216.874852)
		(width 0.14224)
		(layer "In11.Cu")
		(net "GMI_CPU1_G3_CPU0_G1_TX_DN<11>")
	)
	(segment
		(start 348.693486 -222.919036)
		(end 348.763082 -222.959676)
		(width 0.1143)
		(layer "In11.Cu")
		(net "GMI_CPU1_G3_CPU0_G1_TX_DN<11>")
	)
	(segment
		(start 122.771916 -226.177094)
		(end 122.802396 -226.159314)
		(width 0.1143)
		(layer "In11.Cu")
		(net "GMI_CPU1_G3_CPU0_G1_TX_DN<11>")
	)
	(segment
		(start 349.083122 -233.14406)
		(end 349.381064 -233.14406)
		(width 0.1143)
		(layer "In11.Cu")
		(net "GMI_CPU1_G3_CPU0_G1_TX_DN<11>")
	)
	(segment
		(start 349.025972 -221.426024)
		(end 349.00616 -221.445836)
		(width 0.1143)
		(layer "In11.Cu")
		(net "GMI_CPU1_G3_CPU0_G1_TX_DN<11>")
	)
	(segment
		(start 348.693486 -226.15906)
		(end 348.763082 -226.1997)
		(width 0.1143)
		(layer "In11.Cu")
		(net "GMI_CPU1_G3_CPU0_G1_TX_DN<11>")
	)
	(segment
		(start 122.489722 -221.44609)
		(end 122.46991 -221.426278)
		(width 0.1143)
		(layer "In11.Cu")
		(net "GMI_CPU1_G3_CPU0_G1_TX_DN<11>")
	)
	(segment
		(start 123.252738 -231.840786)
		(end 123.273566 -231.828594)
		(width 0.1143)
		(layer "In11.Cu")
		(net "GMI_CPU1_G3_CPU0_G1_TX_DN<11>")
	)
	(segment
		(start 123.242578 -231.846374)
		(end 123.243848 -231.845612)
		(width 0.1143)
		(layer "In11.Cu")
		(net "GMI_CPU1_G3_CPU0_G1_TX_DN<11>")
	)
	(segment
		(start 306.42687 -185.13298)
		(end 307.390546 -185.531252)
		(width 0.14224)
		(layer "In11.Cu")
		(net "GMI_CPU1_G3_CPU0_G1_TX_DN<11>")
	)
	(segment
		(start 158.125414 -189.961266)
		(end 158.125668 -189.961774)
		(width 0.14224)
		(layer "In11.Cu")
		(net "GMI_CPU1_G3_CPU0_G1_TX_DN<11>")
	)
	(segment
		(start 122.7328 -222.95993)
		(end 122.771916 -222.93707)
		(width 0.1143)
		(layer "In11.Cu")
		(net "GMI_CPU1_G3_CPU0_G1_TX_DN<11>")
	)
	(segment
		(start 348.693486 -232.638854)
		(end 348.763082 -232.679494)
		(width 0.1143)
		(layer "In11.Cu")
		(net "GMI_CPU1_G3_CPU0_G1_TX_DN<11>")
	)
	(segment
		(start 348.260162 -231.850184)
		(end 348.261686 -231.8512)
		(width 0.1143)
		(layer "In11.Cu")
		(net "GMI_CPU1_G3_CPU0_G1_TX_DN<11>")
	)
	(segment
		(start 122.41276 -233.144314)
		(end 122.495564 -233.06151)
		(width 0.1143)
		(layer "In11.Cu")
		(net "GMI_CPU1_G3_CPU0_G1_TX_DN<11>")
	)
	(segment
		(start 348.256606 -231.848152)
		(end 348.257622 -231.84866)
		(width 0.1143)
		(layer "In11.Cu")
		(net "GMI_CPU1_G3_CPU0_G1_TX_DN<11>")
	)
	(segment
		(start 123.243848 -231.845612)
		(end 123.245372 -231.84485)
		(width 0.1143)
		(layer "In11.Cu")
		(net "GMI_CPU1_G3_CPU0_G1_TX_DN<11>")
	)
	(arc
		(start 122.802396 -232.639108)
		(mid 122.917823 -232.505732)
		(end 122.959368 -232.334308)
		(width 0.1143)
		(layer "In11.Cu")
		(net "GMI_CPU1_G3_CPU0_G1_TX_DN<11>")
	)
	(arc
		(start 122.802396 -227.779326)
		(mid 122.959373 -227.474526)
		(end 122.802396 -227.169726)
		(width 0.1143)
		(layer "In11.Cu")
		(net "GMI_CPU1_G3_CPU0_G1_TX_DN<11>")
	)
	(arc
		(start 348.763082 -227.819712)
		(mid 349.006409 -228.284278)
		(end 348.763082 -228.748844)
		(width 0.1143)
		(layer "In11.Cu")
		(net "GMI_CPU1_G3_CPU0_G1_TX_DN<11>")
	)
	(arc
		(start 122.959368 -230.71455)
		(mid 122.917819 -230.543128)
		(end 122.802396 -230.40975)
		(width 0.1143)
		(layer "In11.Cu")
		(net "GMI_CPU1_G3_CPU0_G1_TX_DN<11>")
	)
	(arc
		(start 348.536514 -232.334054)
		(mid 348.578063 -232.505476)
		(end 348.693486 -232.638854)
		(width 0.1143)
		(layer "In11.Cu")
		(net "GMI_CPU1_G3_CPU0_G1_TX_DN<11>")
	)
	(arc
		(start 349.006414 -229.904036)
		(mid 348.941178 -230.167627)
		(end 348.760542 -230.37038)
		(width 0.1143)
		(layer "In11.Cu")
		(net "GMI_CPU1_G3_CPU0_G1_TX_DN<11>")
	)
	(arc
		(start 348.693486 -228.789484)
		(mid 348.578059 -228.92286)
		(end 348.536514 -229.094284)
		(width 0.1143)
		(layer "In11.Cu")
		(net "GMI_CPU1_G3_CPU0_G1_TX_DN<11>")
	)
	(arc
		(start 122.7328 -227.129086)
		(mid 122.489473 -226.66452)
		(end 122.7328 -226.199954)
		(width 0.1143)
		(layer "In11.Cu")
		(net "GMI_CPU1_G3_CPU0_G1_TX_DN<11>")
	)
	(arc
		(start 348.763082 -232.679494)
		(mid 348.915069 -232.836002)
		(end 348.996508 -233.038396)
		(width 0.1143)
		(layer "In11.Cu")
		(net "GMI_CPU1_G3_CPU0_G1_TX_DN<11>")
	)
	(arc
		(start 122.499374 -233.03865)
		(mid 122.580807 -232.836252)
		(end 122.7328 -232.679748)
		(width 0.1143)
		(layer "In11.Cu")
		(net "GMI_CPU1_G3_CPU0_G1_TX_DN<11>")
	)
	(arc
		(start 348.693486 -223.929448)
		(mid 348.536509 -224.234248)
		(end 348.693486 -224.539048)
		(width 0.1143)
		(layer "In11.Cu")
		(net "GMI_CPU1_G3_CPU0_G1_TX_DN<11>")
	)
	(arc
		(start 122.804428 -229.398068)
		(mid 122.918357 -229.264921)
		(end 122.959368 -229.094538)
		(width 0.1143)
		(layer "In11.Cu")
		(net "GMI_CPU1_G3_CPU0_G1_TX_DN<11>")
	)
	(arc
		(start 122.73534 -230.370634)
		(mid 122.554688 -230.167889)
		(end 122.489468 -229.90429)
		(width 0.1143)
		(layer "In11.Cu")
		(net "GMI_CPU1_G3_CPU0_G1_TX_DN<11>")
	)
	(arc
		(start 348.693486 -222.309436)
		(mid 348.536509 -222.614236)
		(end 348.693486 -222.919036)
		(width 0.1143)
		(layer "In11.Cu")
		(net "GMI_CPU1_G3_CPU0_G1_TX_DN<11>")
	)
	(arc
		(start 348.693486 -230.409496)
		(mid 348.578059 -230.542872)
		(end 348.536514 -230.714296)
		(width 0.1143)
		(layer "In11.Cu")
		(net "GMI_CPU1_G3_CPU0_G1_TX_DN<11>")
	)
	(arc
		(start 348.536514 -229.094284)
		(mid 348.57748 -229.26469)
		(end 348.691454 -229.397814)
		(width 0.1143)
		(layer "In11.Cu")
		(net "GMI_CPU1_G3_CPU0_G1_TX_DN<11>")
	)
	(arc
		(start 122.7328 -222.26905)
		(mid 122.554157 -222.066655)
		(end 122.489722 -221.804484)
		(width 0.1143)
		(layer "In11.Cu")
		(net "GMI_CPU1_G3_CPU0_G1_TX_DN<11>")
	)
	(arc
		(start 122.802396 -224.539302)
		(mid 122.959373 -224.234502)
		(end 122.802396 -223.929702)
		(width 0.1143)
		(layer "In11.Cu")
		(net "GMI_CPU1_G3_CPU0_G1_TX_DN<11>")
	)
	(arc
		(start 348.763082 -222.959676)
		(mid 349.006409 -223.424242)
		(end 348.763082 -223.888808)
		(width 0.1143)
		(layer "In11.Cu")
		(net "GMI_CPU1_G3_CPU0_G1_TX_DN<11>")
	)
	(arc
		(start 349.00616 -221.80423)
		(mid 348.941786 -222.066434)
		(end 348.763082 -222.268796)
		(width 0.1143)
		(layer "In11.Cu")
		(net "GMI_CPU1_G3_CPU0_G1_TX_DN<11>")
	)
	(arc
		(start 122.802396 -222.91929)
		(mid 122.959373 -222.61449)
		(end 122.802396 -222.30969)
		(width 0.1143)
		(layer "In11.Cu")
		(net "GMI_CPU1_G3_CPU0_G1_TX_DN<11>")
	)
	(arc
		(start 348.763082 -224.579688)
		(mid 349.006409 -225.044254)
		(end 348.763082 -225.50882)
		(width 0.1143)
		(layer "In11.Cu")
		(net "GMI_CPU1_G3_CPU0_G1_TX_DN<11>")
	)
	(arc
		(start 123.2027 -231.179116)
		(mid 123.023887 -230.976766)
		(end 122.959368 -230.71455)
		(width 0.1143)
		(layer "In11.Cu")
		(net "GMI_CPU1_G3_CPU0_G1_TX_DN<11>")
	)
	(arc
		(start 123.429522 -231.524302)
		(mid 123.38876 -231.354418)
		(end 123.275344 -231.221534)
		(width 0.1143)
		(layer "In11.Cu")
		(net "GMI_CPU1_G3_CPU0_G1_TX_DN<11>")
	)
	(arc
		(start 348.996508 -233.038396)
		(mid 348.998531 -233.049806)
		(end 349.000318 -233.061256)
		(width 0.1143)
		(layer "In11.Cu")
		(net "GMI_CPU1_G3_CPU0_G1_TX_DN<11>")
	)
	(arc
		(start 348.763082 -229.43947)
		(mid 348.941895 -229.64182)
		(end 349.006414 -229.904036)
		(width 0.1143)
		(layer "In11.Cu")
		(net "GMI_CPU1_G3_CPU0_G1_TX_DN<11>")
	)
	(arc
		(start 122.7328 -223.889062)
		(mid 122.489473 -223.424496)
		(end 122.7328 -222.95993)
		(width 0.1143)
		(layer "In11.Cu")
		(net "GMI_CPU1_G3_CPU0_G1_TX_DN<11>")
	)
	(arc
		(start 122.959368 -229.094538)
		(mid 122.917819 -228.923116)
		(end 122.802396 -228.789738)
		(width 0.1143)
		(layer "In11.Cu")
		(net "GMI_CPU1_G3_CPU0_G1_TX_DN<11>")
	)
	(arc
		(start 122.959368 -232.334308)
		(mid 123.023883 -232.072089)
		(end 123.2027 -231.869742)
		(width 0.1143)
		(layer "In11.Cu")
		(net "GMI_CPU1_G3_CPU0_G1_TX_DN<11>")
	)
	(arc
		(start 348.536514 -230.714296)
		(mid 348.471999 -230.976515)
		(end 348.293182 -231.178862)
		(width 0.1143)
		(layer "In11.Cu")
		(net "GMI_CPU1_G3_CPU0_G1_TX_DN<11>")
	)
	(arc
		(start 123.273566 -231.828594)
		(mid 123.388242 -231.69526)
		(end 123.429522 -231.524302)
		(width 0.1143)
		(layer "In11.Cu")
		(net "GMI_CPU1_G3_CPU0_G1_TX_DN<11>")
	)
	(arc
		(start 348.693486 -225.54946)
		(mid 348.536509 -225.85426)
		(end 348.693486 -226.15906)
		(width 0.1143)
		(layer "In11.Cu")
		(net "GMI_CPU1_G3_CPU0_G1_TX_DN<11>")
	)
	(arc
		(start 348.693486 -227.169472)
		(mid 348.536509 -227.474272)
		(end 348.693486 -227.779072)
		(width 0.1143)
		(layer "In11.Cu")
		(net "GMI_CPU1_G3_CPU0_G1_TX_DN<11>")
	)
	(arc
		(start 122.495564 -233.06151)
		(mid 122.497352 -233.050061)
		(end 122.499374 -233.03865)
		(width 0.1143)
		(layer "In11.Cu")
		(net "GMI_CPU1_G3_CPU0_G1_TX_DN<11>")
	)
	(arc
		(start 348.220538 -231.22128)
		(mid 348.107131 -231.354169)
		(end 348.06636 -231.524048)
		(width 0.1143)
		(layer "In11.Cu")
		(net "GMI_CPU1_G3_CPU0_G1_TX_DN<11>")
	)
	(arc
		(start 122.7328 -225.509074)
		(mid 122.489473 -225.044508)
		(end 122.7328 -224.579942)
		(width 0.1143)
		(layer "In11.Cu")
		(net "GMI_CPU1_G3_CPU0_G1_TX_DN<11>")
	)
	(arc
		(start 348.763082 -226.1997)
		(mid 349.006409 -226.664266)
		(end 348.763082 -227.128832)
		(width 0.1143)
		(layer "In11.Cu")
		(net "GMI_CPU1_G3_CPU0_G1_TX_DN<11>")
	)
	(arc
		(start 348.293182 -231.869488)
		(mid 348.471995 -232.071838)
		(end 348.536514 -232.334054)
		(width 0.1143)
		(layer "In11.Cu")
		(net "GMI_CPU1_G3_CPU0_G1_TX_DN<11>")
	)
	(arc
		(start 122.489468 -229.90429)
		(mid 122.553983 -229.642071)
		(end 122.7328 -229.439724)
		(width 0.1143)
		(layer "In11.Cu")
		(net "GMI_CPU1_G3_CPU0_G1_TX_DN<11>")
	)
	(arc
		(start 122.802396 -226.159314)
		(mid 122.959373 -225.854514)
		(end 122.802396 -225.549714)
		(width 0.1143)
		(layer "In11.Cu")
		(net "GMI_CPU1_G3_CPU0_G1_TX_DN<11>")
	)
	(arc
		(start 348.06636 -231.524048)
		(mid 348.107615 -231.695019)
		(end 348.222316 -231.82834)
		(width 0.1143)
		(layer "In11.Cu")
		(net "GMI_CPU1_G3_CPU0_G1_TX_DN<11>")
	)
	(arc
		(start 122.7328 -228.749098)
		(mid 122.489473 -228.284532)
		(end 122.7328 -227.819966)
		(width 0.1143)
		(layer "In11.Cu")
		(net "GMI_CPU1_G3_CPU0_G1_TX_DN<11>")
	)
	(segment
		(start 349.847916 -231.789986)
		(end 349.381064 -231.524048)
		(width 0.12954)
		(layer "F.Cu")
		(net "GMI_CPU1_G3_CPU0_G1_TX_DN<10>")
	)
	(segment
		(start 121.647966 -231.79024)
		(end 122.114818 -231.524302)
		(width 0.12954)
		(layer "F.Cu")
		(net "GMI_CPU1_G3_CPU0_G1_TX_DN<10>")
	)
	(segment
		(start 121.863612 -230.410258)
		(end 121.832624 -230.392478)
		(width 0.1143)
		(layer "In11.Cu")
		(net "GMI_CPU1_G3_CPU0_G1_TX_DN<10>")
	)
	(segment
		(start 349.63227 -225.549968)
		(end 349.612458 -225.564192)
		(width 0.1143)
		(layer "In11.Cu")
		(net "GMI_CPU1_G3_CPU0_G1_TX_DN<10>")
	)
	(segment
		(start 121.52503 -221.426278)
		(end 121.52503 -221.129098)
		(width 0.1143)
		(layer "In11.Cu")
		(net "GMI_CPU1_G3_CPU0_G1_TX_DN<10>")
	)
	(segment
		(start 121.862596 -229.399338)
		(end 121.86539 -229.397306)
		(width 0.1143)
		(layer "In11.Cu")
		(net "GMI_CPU1_G3_CPU0_G1_TX_DN<10>")
	)
	(segment
		(start 349.664528 -230.390954)
		(end 349.663766 -230.391462)
		(width 0.1143)
		(layer "In11.Cu")
		(net "GMI_CPU1_G3_CPU0_G1_TX_DN<10>")
	)
	(segment
		(start 302.88992 -184.192926)
		(end 306.71389 -184.192926)
		(width 0.14224)
		(layer "In11.Cu")
		(net "GMI_CPU1_G3_CPU0_G1_TX_DN<10>")
	)
	(segment
		(start 349.970852 -221.426024)
		(end 349.946214 -221.450662)
		(width 0.1143)
		(layer "In11.Cu")
		(net "GMI_CPU1_G3_CPU0_G1_TX_DN<10>")
	)
	(segment
		(start 121.792746 -224.579942)
		(end 121.831862 -224.557082)
		(width 0.1143)
		(layer "In11.Cu")
		(net "GMI_CPU1_G3_CPU0_G1_TX_DN<10>")
	)
	(segment
		(start 349.63227 -227.16998)
		(end 349.612458 -227.184204)
		(width 0.1143)
		(layer "In11.Cu")
		(net "GMI_CPU1_G3_CPU0_G1_TX_DN<10>")
	)
	(segment
		(start 349.476314 -230.585772)
		(end 349.476314 -230.714296)
		(width 0.1143)
		(layer "In11.Cu")
		(net "GMI_CPU1_G3_CPU0_G1_TX_DN<10>")
	)
	(segment
		(start 121.792746 -226.199954)
		(end 121.831862 -226.177094)
		(width 0.1143)
		(layer "In11.Cu")
		(net "GMI_CPU1_G3_CPU0_G1_TX_DN<10>")
	)
	(segment
		(start 121.52503 -221.129098)
		(end 121.47931 -221.083378)
		(width 0.1143)
		(layer "In11.Cu")
		(net "GMI_CPU1_G3_CPU0_G1_TX_DN<10>")
	)
	(segment
		(start 144.98955 -198.47814)
		(end 146.658076 -197.972426)
		(width 0.14224)
		(layer "In11.Cu")
		(net "GMI_CPU1_G3_CPU0_G1_TX_DN<10>")
	)
	(segment
		(start 349.630492 -229.397052)
		(end 349.633286 -229.399084)
		(width 0.1143)
		(layer "In11.Cu")
		(net "GMI_CPU1_G3_CPU0_G1_TX_DN<10>")
	)
	(segment
		(start 122.33529 -231.221534)
		(end 122.26544 -231.180894)
		(width 0.1143)
		(layer "In11.Cu")
		(net "GMI_CPU1_G3_CPU0_G1_TX_DN<10>")
	)
	(segment
		(start 313.12739 -187.624974)
		(end 347.904054 -216.14003)
		(width 0.14224)
		(layer "In11.Cu")
		(net "GMI_CPU1_G3_CPU0_G1_TX_DN<10>")
	)
	(segment
		(start 349.633286 -229.399084)
		(end 349.703136 -229.43947)
		(width 0.1143)
		(layer "In11.Cu")
		(net "GMI_CPU1_G3_CPU0_G1_TX_DN<10>")
	)
	(segment
		(start 121.853706 -222.304356)
		(end 121.853198 -222.304356)
		(width 0.1143)
		(layer "In11.Cu")
		(net "GMI_CPU1_G3_CPU0_G1_TX_DN<10>")
	)
	(segment
		(start 121.863612 -227.778818)
		(end 121.883424 -227.764594)
		(width 0.1143)
		(layer "In11.Cu")
		(net "GMI_CPU1_G3_CPU0_G1_TX_DN<10>")
	)
	(segment
		(start 121.831862 -224.557082)
		(end 121.863612 -224.538794)
		(width 0.1143)
		(layer "In11.Cu")
		(net "GMI_CPU1_G3_CPU0_G1_TX_DN<10>")
	)
	(segment
		(start 121.47931 -221.071948)
		(end 121.47931 -219.801948)
		(width 0.14224)
		(layer "In11.Cu")
		(net "GMI_CPU1_G3_CPU0_G1_TX_DN<10>")
	)
	(segment
		(start 349.642684 -222.304102)
		(end 349.642176 -222.304102)
		(width 0.1143)
		(layer "In11.Cu")
		(net "GMI_CPU1_G3_CPU0_G1_TX_DN<10>")
	)
	(segment
		(start 349.645986 -222.926402)
		(end 349.648018 -222.927418)
		(width 0.1143)
		(layer "In11.Cu")
		(net "GMI_CPU1_G3_CPU0_G1_TX_DN<10>")
	)
	(segment
		(start 121.863612 -223.93021)
		(end 121.792746 -223.889062)
		(width 0.1143)
		(layer "In11.Cu")
		(net "GMI_CPU1_G3_CPU0_G1_TX_DN<10>")
	)
	(segment
		(start 122.114818 -231.524302)
		(end 122.41276 -231.524302)
		(width 0.1143)
		(layer "In11.Cu")
		(net "GMI_CPU1_G3_CPU0_G1_TX_DN<10>")
	)
	(segment
		(start 121.863612 -226.158806)
		(end 121.883424 -226.144582)
		(width 0.1143)
		(layer "In11.Cu")
		(net "GMI_CPU1_G3_CPU0_G1_TX_DN<10>")
	)
	(segment
		(start 349.63227 -227.778564)
		(end 349.66402 -227.796852)
		(width 0.1143)
		(layer "In11.Cu")
		(net "GMI_CPU1_G3_CPU0_G1_TX_DN<10>")
	)
	(segment
		(start 121.47931 -221.083378)
		(end 121.47931 -221.071948)
		(width 0.1143)
		(layer "In11.Cu")
		(net "GMI_CPU1_G3_CPU0_G1_TX_DN<10>")
	)
	(segment
		(start 349.230442 -231.18064)
		(end 349.160592 -231.22128)
		(width 0.1143)
		(layer "In11.Cu")
		(net "GMI_CPU1_G3_CPU0_G1_TX_DN<10>")
	)
	(segment
		(start 349.612458 -226.144328)
		(end 349.63227 -226.158552)
		(width 0.1143)
		(layer "In11.Cu")
		(net "GMI_CPU1_G3_CPU0_G1_TX_DN<10>")
	)
	(segment
		(start 349.644208 -222.925386)
		(end 349.645986 -222.926402)
		(width 0.1143)
		(layer "In11.Cu")
		(net "GMI_CPU1_G3_CPU0_G1_TX_DN<10>")
	)
	(segment
		(start 122.41276 -231.524302)
		(end 122.48261 -231.454452)
		(width 0.1143)
		(layer "In11.Cu")
		(net "GMI_CPU1_G3_CPU0_G1_TX_DN<10>")
	)
	(segment
		(start 349.64243 -222.92437)
		(end 349.642684 -222.92437)
		(width 0.1143)
		(layer "In11.Cu")
		(net "GMI_CPU1_G3_CPU0_G1_TX_DN<10>")
	)
	(segment
		(start 121.792746 -227.819966)
		(end 121.831862 -227.797106)
		(width 0.1143)
		(layer "In11.Cu")
		(net "GMI_CPU1_G3_CPU0_G1_TX_DN<10>")
	)
	(segment
		(start 121.830846 -222.937578)
		(end 121.834402 -222.9358)
		(width 0.1143)
		(layer "In11.Cu")
		(net "GMI_CPU1_G3_CPU0_G1_TX_DN<10>")
	)
	(segment
		(start 349.946214 -221.450662)
		(end 349.946214 -221.80423)
		(width 0.1143)
		(layer "In11.Cu")
		(net "GMI_CPU1_G3_CPU0_G1_TX_DN<10>")
	)
	(segment
		(start 349.66402 -226.17684)
		(end 349.703136 -226.1997)
		(width 0.1143)
		(layer "In11.Cu")
		(net "GMI_CPU1_G3_CPU0_G1_TX_DN<10>")
	)
	(segment
		(start 349.702374 -222.269304)
		(end 349.642684 -222.304102)
		(width 0.1143)
		(layer "In11.Cu")
		(net "GMI_CPU1_G3_CPU0_G1_TX_DN<10>")
	)
	(segment
		(start 121.863612 -227.170234)
		(end 121.792746 -227.129086)
		(width 0.1143)
		(layer "In11.Cu")
		(net "GMI_CPU1_G3_CPU0_G1_TX_DN<10>")
	)
	(segment
		(start 349.63227 -223.929956)
		(end 349.612458 -223.94418)
		(width 0.1143)
		(layer "In11.Cu")
		(net "GMI_CPU1_G3_CPU0_G1_TX_DN<10>")
	)
	(segment
		(start 349.66148 -222.935546)
		(end 349.665036 -222.937324)
		(width 0.1143)
		(layer "In11.Cu")
		(net "GMI_CPU1_G3_CPU0_G1_TX_DN<10>")
	)
	(segment
		(start 166.995094 -183.401462)
		(end 302.88992 -184.192926)
		(width 0.14224)
		(layer "In11.Cu")
		(net "GMI_CPU1_G3_CPU0_G1_TX_DN<10>")
	)
	(segment
		(start 121.883424 -223.944434)
		(end 121.863612 -223.93021)
		(width 0.1143)
		(layer "In11.Cu")
		(net "GMI_CPU1_G3_CPU0_G1_TX_DN<10>")
	)
	(segment
		(start 349.648018 -222.927418)
		(end 349.649542 -222.928434)
		(width 0.1143)
		(layer "In11.Cu")
		(net "GMI_CPU1_G3_CPU0_G1_TX_DN<10>")
	)
	(segment
		(start 349.663258 -230.392224)
		(end 349.63227 -230.410004)
		(width 0.1143)
		(layer "In11.Cu")
		(net "GMI_CPU1_G3_CPU0_G1_TX_DN<10>")
	)
	(segment
		(start 162.450272 -185.0263)
		(end 166.995094 -183.401462)
		(width 0.14224)
		(layer "In11.Cu")
		(net "GMI_CPU1_G3_CPU0_G1_TX_DN<10>")
	)
	(segment
		(start 349.649542 -222.928434)
		(end 349.66148 -222.935546)
		(width 0.1143)
		(layer "In11.Cu")
		(net "GMI_CPU1_G3_CPU0_G1_TX_DN<10>")
	)
	(segment
		(start 349.66402 -230.391716)
		(end 349.663258 -230.392224)
		(width 0.1143)
		(layer "In11.Cu")
		(net "GMI_CPU1_G3_CPU0_G1_TX_DN<10>")
	)
	(segment
		(start 350.016572 -221.071694)
		(end 350.016572 -221.083124)
		(width 0.1143)
		(layer "In11.Cu")
		(net "GMI_CPU1_G3_CPU0_G1_TX_DN<10>")
	)
	(segment
		(start 122.019568 -230.71455)
		(end 122.019568 -230.586026)
		(width 0.1143)
		(layer "In11.Cu")
		(net "GMI_CPU1_G3_CPU0_G1_TX_DN<10>")
	)
	(segment
		(start 308.55031 -185.03392)
		(end 313.12739 -187.624974)
		(width 0.14224)
		(layer "In11.Cu")
		(net "GMI_CPU1_G3_CPU0_G1_TX_DN<10>")
	)
	(segment
		(start 349.612458 -227.76434)
		(end 349.63227 -227.778564)
		(width 0.1143)
		(layer "In11.Cu")
		(net "GMI_CPU1_G3_CPU0_G1_TX_DN<10>")
	)
	(segment
		(start 121.863612 -225.550222)
		(end 121.792746 -225.509074)
		(width 0.1143)
		(layer "In11.Cu")
		(net "GMI_CPU1_G3_CPU0_G1_TX_DN<10>")
	)
	(segment
		(start 349.63227 -224.53854)
		(end 349.66402 -224.556828)
		(width 0.1143)
		(layer "In11.Cu")
		(net "GMI_CPU1_G3_CPU0_G1_TX_DN<10>")
	)
	(segment
		(start 121.549668 -221.450916)
		(end 121.52503 -221.426278)
		(width 0.1143)
		(layer "In11.Cu")
		(net "GMI_CPU1_G3_CPU0_G1_TX_DN<10>")
	)
	(segment
		(start 349.66402 -224.556828)
		(end 349.703136 -224.579688)
		(width 0.1143)
		(layer "In11.Cu")
		(net "GMI_CPU1_G3_CPU0_G1_TX_DN<10>")
	)
	(segment
		(start 349.63227 -226.158552)
		(end 349.66402 -226.17684)
		(width 0.1143)
		(layer "In11.Cu")
		(net "GMI_CPU1_G3_CPU0_G1_TX_DN<10>")
	)
	(segment
		(start 306.71389 -184.192926)
		(end 308.55031 -185.03392)
		(width 0.14224)
		(layer "In11.Cu")
		(net "GMI_CPU1_G3_CPU0_G1_TX_DN<10>")
	)
	(segment
		(start 121.883424 -225.564446)
		(end 121.863612 -225.550222)
		(width 0.1143)
		(layer "In11.Cu")
		(net "GMI_CPU1_G3_CPU0_G1_TX_DN<10>")
	)
	(segment
		(start 349.970852 -221.128844)
		(end 349.970852 -221.426024)
		(width 0.1143)
		(layer "In11.Cu")
		(net "GMI_CPU1_G3_CPU0_G1_TX_DN<10>")
	)
	(segment
		(start 347.904054 -216.14003)
		(end 350.016572 -219.698062)
		(width 0.14224)
		(layer "In11.Cu")
		(net "GMI_CPU1_G3_CPU0_G1_TX_DN<10>")
	)
	(segment
		(start 123.755912 -215.88857)
		(end 144.98955 -198.47814)
		(width 0.14224)
		(layer "In11.Cu")
		(net "GMI_CPU1_G3_CPU0_G1_TX_DN<10>")
	)
	(segment
		(start 121.832116 -230.391716)
		(end 121.831354 -230.391208)
		(width 0.1143)
		(layer "In11.Cu")
		(net "GMI_CPU1_G3_CPU0_G1_TX_DN<10>")
	)
	(segment
		(start 121.834402 -222.9358)
		(end 121.853198 -222.924624)
		(width 0.1143)
		(layer "In11.Cu")
		(net "GMI_CPU1_G3_CPU0_G1_TX_DN<10>")
	)
	(segment
		(start 121.863612 -224.538794)
		(end 121.883424 -224.52457)
		(width 0.1143)
		(layer "In11.Cu")
		(net "GMI_CPU1_G3_CPU0_G1_TX_DN<10>")
	)
	(segment
		(start 121.831862 -230.39197)
		(end 121.832116 -230.391716)
		(width 0.1143)
		(layer "In11.Cu")
		(net "GMI_CPU1_G3_CPU0_G1_TX_DN<10>")
	)
	(segment
		(start 349.665036 -222.937324)
		(end 349.703136 -222.959676)
		(width 0.1143)
		(layer "In11.Cu")
		(net "GMI_CPU1_G3_CPU0_G1_TX_DN<10>")
	)
	(segment
		(start 121.853198 -222.304356)
		(end 121.793508 -222.269558)
		(width 0.1143)
		(layer "In11.Cu")
		(net "GMI_CPU1_G3_CPU0_G1_TX_DN<10>")
	)
	(segment
		(start 349.013272 -231.454198)
		(end 349.083122 -231.524048)
		(width 0.1143)
		(layer "In11.Cu")
		(net "GMI_CPU1_G3_CPU0_G1_TX_DN<10>")
	)
	(segment
		(start 349.083122 -231.524048)
		(end 349.381064 -231.524048)
		(width 0.1143)
		(layer "In11.Cu")
		(net "GMI_CPU1_G3_CPU0_G1_TX_DN<10>")
	)
	(segment
		(start 349.663766 -230.391462)
		(end 349.66402 -230.391716)
		(width 0.1143)
		(layer "In11.Cu")
		(net "GMI_CPU1_G3_CPU0_G1_TX_DN<10>")
	)
	(segment
		(start 349.703136 -228.748844)
		(end 349.66402 -228.771704)
		(width 0.1143)
		(layer "In11.Cu")
		(net "GMI_CPU1_G3_CPU0_G1_TX_DN<10>")
	)
	(segment
		(start 349.703136 -223.888808)
		(end 349.63227 -223.929956)
		(width 0.1143)
		(layer "In11.Cu")
		(net "GMI_CPU1_G3_CPU0_G1_TX_DN<10>")
	)
	(segment
		(start 349.703136 -227.128832)
		(end 349.63227 -227.16998)
		(width 0.1143)
		(layer "In11.Cu")
		(net "GMI_CPU1_G3_CPU0_G1_TX_DN<10>")
	)
	(segment
		(start 121.792746 -222.95993)
		(end 121.830846 -222.937578)
		(width 0.1143)
		(layer "In11.Cu")
		(net "GMI_CPU1_G3_CPU0_G1_TX_DN<10>")
	)
	(segment
		(start 349.703136 -225.50882)
		(end 349.63227 -225.549968)
		(width 0.1143)
		(layer "In11.Cu")
		(net "GMI_CPU1_G3_CPU0_G1_TX_DN<10>")
	)
	(segment
		(start 121.549668 -221.804484)
		(end 121.549668 -221.450916)
		(width 0.1143)
		(layer "In11.Cu")
		(net "GMI_CPU1_G3_CPU0_G1_TX_DN<10>")
	)
	(segment
		(start 349.66402 -227.796852)
		(end 349.703136 -227.819712)
		(width 0.1143)
		(layer "In11.Cu")
		(net "GMI_CPU1_G3_CPU0_G1_TX_DN<10>")
	)
	(segment
		(start 121.968006 -230.485442)
		(end 121.863612 -230.410258)
		(width 0.1143)
		(layer "In11.Cu")
		(net "GMI_CPU1_G3_CPU0_G1_TX_DN<10>")
	)
	(segment
		(start 349.63227 -230.410004)
		(end 349.527876 -230.485188)
		(width 0.1143)
		(layer "In11.Cu")
		(net "GMI_CPU1_G3_CPU0_G1_TX_DN<10>")
	)
	(segment
		(start 121.47931 -219.801948)
		(end 123.755912 -215.88857)
		(width 0.14224)
		(layer "In11.Cu")
		(net "GMI_CPU1_G3_CPU0_G1_TX_DN<10>")
	)
	(segment
		(start 121.853198 -222.924624)
		(end 121.853452 -222.924624)
		(width 0.1143)
		(layer "In11.Cu")
		(net "GMI_CPU1_G3_CPU0_G1_TX_DN<10>")
	)
	(segment
		(start 121.883424 -227.184458)
		(end 121.863612 -227.170234)
		(width 0.1143)
		(layer "In11.Cu")
		(net "GMI_CPU1_G3_CPU0_G1_TX_DN<10>")
	)
	(segment
		(start 350.016572 -219.698062)
		(end 350.016572 -221.071694)
		(width 0.14224)
		(layer "In11.Cu")
		(net "GMI_CPU1_G3_CPU0_G1_TX_DN<10>")
	)
	(segment
		(start 121.832624 -230.392478)
		(end 121.831862 -230.39197)
		(width 0.1143)
		(layer "In11.Cu")
		(net "GMI_CPU1_G3_CPU0_G1_TX_DN<10>")
	)
	(segment
		(start 121.831862 -228.771958)
		(end 121.792746 -228.749098)
		(width 0.1143)
		(layer "In11.Cu")
		(net "GMI_CPU1_G3_CPU0_G1_TX_DN<10>")
	)
	(segment
		(start 121.863612 -228.790246)
		(end 121.831862 -228.771958)
		(width 0.1143)
		(layer "In11.Cu")
		(net "GMI_CPU1_G3_CPU0_G1_TX_DN<10>")
	)
	(segment
		(start 349.612458 -224.524316)
		(end 349.63227 -224.53854)
		(width 0.1143)
		(layer "In11.Cu")
		(net "GMI_CPU1_G3_CPU0_G1_TX_DN<10>")
	)
	(segment
		(start 121.831862 -227.797106)
		(end 121.863612 -227.778818)
		(width 0.1143)
		(layer "In11.Cu")
		(net "GMI_CPU1_G3_CPU0_G1_TX_DN<10>")
	)
	(segment
		(start 349.66402 -228.771704)
		(end 349.63227 -228.789992)
		(width 0.1143)
		(layer "In11.Cu")
		(net "GMI_CPU1_G3_CPU0_G1_TX_DN<10>")
	)
	(segment
		(start 350.016572 -221.083124)
		(end 349.970852 -221.128844)
		(width 0.1143)
		(layer "In11.Cu")
		(net "GMI_CPU1_G3_CPU0_G1_TX_DN<10>")
	)
	(segment
		(start 121.792746 -229.439724)
		(end 121.862596 -229.399338)
		(width 0.1143)
		(layer "In11.Cu")
		(net "GMI_CPU1_G3_CPU0_G1_TX_DN<10>")
	)
	(segment
		(start 146.658076 -197.972426)
		(end 162.450272 -185.0263)
		(width 0.14224)
		(layer "In11.Cu")
		(net "GMI_CPU1_G3_CPU0_G1_TX_DN<10>")
	)
	(segment
		(start 121.831862 -226.177094)
		(end 121.863612 -226.158806)
		(width 0.1143)
		(layer "In11.Cu")
		(net "GMI_CPU1_G3_CPU0_G1_TX_DN<10>")
	)
	(segment
		(start 349.642684 -222.92437)
		(end 349.644208 -222.925386)
		(width 0.1143)
		(layer "In11.Cu")
		(net "GMI_CPU1_G3_CPU0_G1_TX_DN<10>")
	)
	(arc
		(start 349.703136 -227.819712)
		(mid 349.946463 -228.284278)
		(end 349.703136 -228.748844)
		(width 0.1143)
		(layer "In11.Cu")
		(net "GMI_CPU1_G3_CPU0_G1_TX_DN<10>")
	)
	(arc
		(start 349.612458 -223.94418)
		(mid 349.463744 -224.234248)
		(end 349.612458 -224.524316)
		(width 0.1143)
		(layer "In11.Cu")
		(net "GMI_CPU1_G3_CPU0_G1_TX_DN<10>")
	)
	(arc
		(start 349.612458 -225.564192)
		(mid 349.463744 -225.85426)
		(end 349.612458 -226.144328)
		(width 0.1143)
		(layer "In11.Cu")
		(net "GMI_CPU1_G3_CPU0_G1_TX_DN<10>")
	)
	(arc
		(start 349.703136 -229.43947)
		(mid 349.881856 -229.641839)
		(end 349.946214 -229.904036)
		(width 0.1143)
		(layer "In11.Cu")
		(net "GMI_CPU1_G3_CPU0_G1_TX_DN<10>")
	)
	(arc
		(start 349.476314 -229.094284)
		(mid 349.517076 -229.264168)
		(end 349.630492 -229.397052)
		(width 0.1143)
		(layer "In11.Cu")
		(net "GMI_CPU1_G3_CPU0_G1_TX_DN<10>")
	)
	(arc
		(start 121.792746 -223.889062)
		(mid 121.549419 -223.424496)
		(end 121.792746 -222.95993)
		(width 0.1143)
		(layer "In11.Cu")
		(net "GMI_CPU1_G3_CPU0_G1_TX_DN<10>")
	)
	(arc
		(start 349.63227 -228.789992)
		(mid 349.519897 -228.924516)
		(end 349.476314 -229.094284)
		(width 0.1143)
		(layer "In11.Cu")
		(net "GMI_CPU1_G3_CPU0_G1_TX_DN<10>")
	)
	(arc
		(start 349.703136 -224.579688)
		(mid 349.946463 -225.044254)
		(end 349.703136 -225.50882)
		(width 0.1143)
		(layer "In11.Cu")
		(net "GMI_CPU1_G3_CPU0_G1_TX_DN<10>")
	)
	(arc
		(start 122.019568 -230.586026)
		(mid 122.005931 -230.529505)
		(end 121.968006 -230.485442)
		(width 0.1143)
		(layer "In11.Cu")
		(net "GMI_CPU1_G3_CPU0_G1_TX_DN<10>")
	)
	(arc
		(start 121.793508 -222.269558)
		(mid 121.614315 -222.067048)
		(end 121.549668 -221.804484)
		(width 0.1143)
		(layer "In11.Cu")
		(net "GMI_CPU1_G3_CPU0_G1_TX_DN<10>")
	)
	(arc
		(start 349.476314 -230.714296)
		(mid 349.411078 -230.977887)
		(end 349.230442 -231.18064)
		(width 0.1143)
		(layer "In11.Cu")
		(net "GMI_CPU1_G3_CPU0_G1_TX_DN<10>")
	)
	(arc
		(start 121.792746 -228.749098)
		(mid 121.549419 -228.284532)
		(end 121.792746 -227.819966)
		(width 0.1143)
		(layer "In11.Cu")
		(net "GMI_CPU1_G3_CPU0_G1_TX_DN<10>")
	)
	(arc
		(start 349.612458 -227.184204)
		(mid 349.463744 -227.474272)
		(end 349.612458 -227.76434)
		(width 0.1143)
		(layer "In11.Cu")
		(net "GMI_CPU1_G3_CPU0_G1_TX_DN<10>")
	)
	(arc
		(start 349.703136 -226.1997)
		(mid 349.946463 -226.664266)
		(end 349.703136 -227.128832)
		(width 0.1143)
		(layer "In11.Cu")
		(net "GMI_CPU1_G3_CPU0_G1_TX_DN<10>")
	)
	(arc
		(start 121.792746 -227.129086)
		(mid 121.549419 -226.66452)
		(end 121.792746 -226.199954)
		(width 0.1143)
		(layer "In11.Cu")
		(net "GMI_CPU1_G3_CPU0_G1_TX_DN<10>")
	)
	(arc
		(start 121.831354 -230.391208)
		(mid 121.625132 -230.185564)
		(end 121.549668 -229.90429)
		(width 0.1143)
		(layer "In11.Cu")
		(net "GMI_CPU1_G3_CPU0_G1_TX_DN<10>")
	)
	(arc
		(start 122.48261 -231.454452)
		(mid 122.43112 -231.323979)
		(end 122.33529 -231.221534)
		(width 0.1143)
		(layer "In11.Cu")
		(net "GMI_CPU1_G3_CPU0_G1_TX_DN<10>")
	)
	(arc
		(start 121.883424 -227.764594)
		(mid 122.032138 -227.474526)
		(end 121.883424 -227.184458)
		(width 0.1143)
		(layer "In11.Cu")
		(net "GMI_CPU1_G3_CPU0_G1_TX_DN<10>")
	)
	(arc
		(start 349.160592 -231.22128)
		(mid 349.064704 -231.323688)
		(end 349.013272 -231.454198)
		(width 0.1143)
		(layer "In11.Cu")
		(net "GMI_CPU1_G3_CPU0_G1_TX_DN<10>")
	)
	(arc
		(start 122.019568 -229.094538)
		(mid 121.975942 -228.924792)
		(end 121.863612 -228.790246)
		(width 0.1143)
		(layer "In11.Cu")
		(net "GMI_CPU1_G3_CPU0_G1_TX_DN<10>")
	)
	(arc
		(start 349.527876 -230.485188)
		(mid 349.489975 -230.529263)
		(end 349.476314 -230.585772)
		(width 0.1143)
		(layer "In11.Cu")
		(net "GMI_CPU1_G3_CPU0_G1_TX_DN<10>")
	)
	(arc
		(start 122.26544 -231.180894)
		(mid 122.084788 -230.978149)
		(end 122.019568 -230.71455)
		(width 0.1143)
		(layer "In11.Cu")
		(net "GMI_CPU1_G3_CPU0_G1_TX_DN<10>")
	)
	(arc
		(start 121.853452 -222.924624)
		(mid 122.031994 -222.6146)
		(end 121.853706 -222.304356)
		(width 0.1143)
		(layer "In11.Cu")
		(net "GMI_CPU1_G3_CPU0_G1_TX_DN<10>")
	)
	(arc
		(start 121.549668 -229.90429)
		(mid 121.614061 -229.642112)
		(end 121.792746 -229.439724)
		(width 0.1143)
		(layer "In11.Cu")
		(net "GMI_CPU1_G3_CPU0_G1_TX_DN<10>")
	)
	(arc
		(start 349.946214 -229.904036)
		(mid 349.870712 -230.185288)
		(end 349.664528 -230.390954)
		(width 0.1143)
		(layer "In11.Cu")
		(net "GMI_CPU1_G3_CPU0_G1_TX_DN<10>")
	)
	(arc
		(start 121.86539 -229.397306)
		(mid 121.978797 -229.264417)
		(end 122.019568 -229.094538)
		(width 0.1143)
		(layer "In11.Cu")
		(net "GMI_CPU1_G3_CPU0_G1_TX_DN<10>")
	)
	(arc
		(start 121.883424 -224.52457)
		(mid 122.032138 -224.234502)
		(end 121.883424 -223.944434)
		(width 0.1143)
		(layer "In11.Cu")
		(net "GMI_CPU1_G3_CPU0_G1_TX_DN<10>")
	)
	(arc
		(start 349.642176 -222.304102)
		(mid 349.46376 -222.614346)
		(end 349.64243 -222.92437)
		(width 0.1143)
		(layer "In11.Cu")
		(net "GMI_CPU1_G3_CPU0_G1_TX_DN<10>")
	)
	(arc
		(start 121.792746 -225.509074)
		(mid 121.549419 -225.044508)
		(end 121.792746 -224.579942)
		(width 0.1143)
		(layer "In11.Cu")
		(net "GMI_CPU1_G3_CPU0_G1_TX_DN<10>")
	)
	(arc
		(start 349.703136 -222.959676)
		(mid 349.946463 -223.424242)
		(end 349.703136 -223.888808)
		(width 0.1143)
		(layer "In11.Cu")
		(net "GMI_CPU1_G3_CPU0_G1_TX_DN<10>")
	)
	(arc
		(start 121.883424 -226.144582)
		(mid 122.032138 -225.854514)
		(end 121.883424 -225.564446)
		(width 0.1143)
		(layer "In11.Cu")
		(net "GMI_CPU1_G3_CPU0_G1_TX_DN<10>")
	)
	(arc
		(start 349.946214 -221.80423)
		(mid 349.881555 -222.066787)
		(end 349.702374 -222.269304)
		(width 0.1143)
		(layer "In11.Cu")
		(net "GMI_CPU1_G3_CPU0_G1_TX_DN<10>")
	)
	(segment
		(start 357.837994 -235.840016)
		(end 357.371142 -235.574078)
		(width 0.12954)
		(layer "F.Cu")
		(net "GMI_CPU1_G3_CPU0_G1_TX_DN<0>")
	)
	(segment
		(start 113.657888 -235.84027)
		(end 114.12474 -235.574332)
		(width 0.12954)
		(layer "F.Cu")
		(net "GMI_CPU1_G3_CPU0_G1_TX_DN<0>")
	)
	(segment
		(start 358.093518 -233.649266)
		(end 358.16159 -233.609642)
		(width 0.1143)
		(layer "In11.Cu")
		(net "GMI_CPU1_G3_CPU0_G1_TX_DN<0>")
	)
	(segment
		(start 359.197148 -231.558338)
		(end 359.197148 -222.507302)
		(width 0.1143)
		(layer "In11.Cu")
		(net "GMI_CPU1_G3_CPU0_G1_TX_DN<0>")
	)
	(segment
		(start 114.422682 -235.574332)
		(end 114.12474 -235.574332)
		(width 0.1143)
		(layer "In11.Cu")
		(net "GMI_CPU1_G3_CPU0_G1_TX_DN<0>")
	)
	(segment
		(start 115.409726 -210.375246)
		(end 112.03051 -216.123266)
		(width 0.14224)
		(layer "In11.Cu")
		(net "GMI_CPU1_G3_CPU0_G1_TX_DN<0>")
	)
	(segment
		(start 357.0732 -235.574078)
		(end 357.00335 -235.504228)
		(width 0.1143)
		(layer "In11.Cu")
		(net "GMI_CPU1_G3_CPU0_G1_TX_DN<0>")
	)
	(segment
		(start 318.563752 -179.688236)
		(end 311.920382 -175.927512)
		(width 0.14224)
		(layer "In11.Cu")
		(net "GMI_CPU1_G3_CPU0_G1_TX_DN<0>")
	)
	(segment
		(start 359.465372 -216.223342)
		(end 355.997764 -210.38312)
		(width 0.14224)
		(layer "In11.Cu")
		(net "GMI_CPU1_G3_CPU0_G1_TX_DN<0>")
	)
	(segment
		(start 302.9204 -174.784512)
		(end 164.760148 -173.97603)
		(width 0.14224)
		(layer "In11.Cu")
		(net "GMI_CPU1_G3_CPU0_G1_TX_DN<0>")
	)
	(segment
		(start 358.70642 -232.73766)
		(end 358.708706 -232.73512)
		(width 0.1143)
		(layer "In11.Cu")
		(net "GMI_CPU1_G3_CPU0_G1_TX_DN<0>")
	)
	(segment
		(start 112.03051 -221.071948)
		(end 112.03051 -221.083378)
		(width 0.1143)
		(layer "In11.Cu")
		(net "GMI_CPU1_G3_CPU0_G1_TX_DN<0>")
	)
	(segment
		(start 359.419652 -221.388432)
		(end 359.419652 -221.128844)
		(width 0.1143)
		(layer "In11.Cu")
		(net "GMI_CPU1_G3_CPU0_G1_TX_DN<0>")
	)
	(segment
		(start 112.782858 -232.73004)
		(end 112.783874 -232.73131)
		(width 0.1143)
		(layer "In11.Cu")
		(net "GMI_CPU1_G3_CPU0_G1_TX_DN<0>")
	)
	(segment
		(start 112.07623 -221.129098)
		(end 112.07623 -221.295214)
		(width 0.1143)
		(layer "In11.Cu")
		(net "GMI_CPU1_G3_CPU0_G1_TX_DN<0>")
	)
	(segment
		(start 112.03051 -221.083378)
		(end 112.07623 -221.129098)
		(width 0.1143)
		(layer "In11.Cu")
		(net "GMI_CPU1_G3_CPU0_G1_TX_DN<0>")
	)
	(segment
		(start 114.274854 -235.230416)
		(end 114.311684 -235.251752)
		(width 0.1143)
		(layer "In11.Cu")
		(net "GMI_CPU1_G3_CPU0_G1_TX_DN<0>")
	)
	(segment
		(start 112.03051 -216.123266)
		(end 112.03051 -221.071948)
		(width 0.14224)
		(layer "In11.Cu")
		(net "GMI_CPU1_G3_CPU0_G1_TX_DN<0>")
	)
	(segment
		(start 308.723538 -174.784512)
		(end 302.9204 -174.784512)
		(width 0.14224)
		(layer "In11.Cu")
		(net "GMI_CPU1_G3_CPU0_G1_TX_DN<0>")
	)
	(segment
		(start 112.863884 -232.79989)
		(end 112.933734 -232.840276)
		(width 0.1143)
		(layer "In11.Cu")
		(net "GMI_CPU1_G3_CPU0_G1_TX_DN<0>")
	)
	(segment
		(start 359.419652 -221.128844)
		(end 359.465372 -221.083124)
		(width 0.1143)
		(layer "In11.Cu")
		(net "GMI_CPU1_G3_CPU0_G1_TX_DN<0>")
	)
	(segment
		(start 114.311684 -235.251752)
		(end 114.312446 -235.25226)
		(width 0.1143)
		(layer "In11.Cu")
		(net "GMI_CPU1_G3_CPU0_G1_TX_DN<0>")
	)
	(segment
		(start 357.622348 -234.45978)
		(end 357.693214 -234.418632)
		(width 0.1143)
		(layer "In11.Cu")
		(net "GMI_CPU1_G3_CPU0_G1_TX_DN<0>")
	)
	(segment
		(start 112.78108 -232.728008)
		(end 112.782858 -232.73004)
		(width 0.1143)
		(layer "In11.Cu")
		(net "GMI_CPU1_G3_CPU0_G1_TX_DN<0>")
	)
	(segment
		(start 358.708706 -232.73512)
		(end 358.717088 -232.72496)
		(width 0.1143)
		(layer "In11.Cu")
		(net "GMI_CPU1_G3_CPU0_G1_TX_DN<0>")
	)
	(segment
		(start 155.964382 -177.121312)
		(end 115.409726 -210.375246)
		(width 0.14224)
		(layer "In11.Cu")
		(net "GMI_CPU1_G3_CPU0_G1_TX_DN<0>")
	)
	(segment
		(start 357.21544 -235.233464)
		(end 357.221028 -235.230162)
		(width 0.1143)
		(layer "In11.Cu")
		(net "GMI_CPU1_G3_CPU0_G1_TX_DN<0>")
	)
	(segment
		(start 112.783874 -232.73131)
		(end 112.789462 -232.737914)
		(width 0.1143)
		(layer "In11.Cu")
		(net "GMI_CPU1_G3_CPU0_G1_TX_DN<0>")
	)
	(segment
		(start 113.802668 -234.418886)
		(end 113.873534 -234.460034)
		(width 0.1143)
		(layer "In11.Cu")
		(net "GMI_CPU1_G3_CPU0_G1_TX_DN<0>")
	)
	(segment
		(start 113.08969 -233.142282)
		(end 113.08969 -233.144314)
		(width 0.1143)
		(layer "In11.Cu")
		(net "GMI_CPU1_G3_CPU0_G1_TX_DN<0>")
	)
	(segment
		(start 114.312446 -235.25226)
		(end 114.343434 -235.27004)
		(width 0.1143)
		(layer "In11.Cu")
		(net "GMI_CPU1_G3_CPU0_G1_TX_DN<0>")
	)
	(segment
		(start 358.406192 -233.14406)
		(end 358.406192 -233.142028)
		(width 0.1143)
		(layer "In11.Cu")
		(net "GMI_CPU1_G3_CPU0_G1_TX_DN<0>")
	)
	(segment
		(start 359.465372 -221.083124)
		(end 359.465372 -216.223342)
		(width 0.14224)
		(layer "In11.Cu")
		(net "GMI_CPU1_G3_CPU0_G1_TX_DN<0>")
	)
	(segment
		(start 357.371142 -235.574078)
		(end 357.0732 -235.574078)
		(width 0.1143)
		(layer "In11.Cu")
		(net "GMI_CPU1_G3_CPU0_G1_TX_DN<0>")
	)
	(segment
		(start 355.997764 -210.38312)
		(end 318.563752 -179.688236)
		(width 0.14224)
		(layer "In11.Cu")
		(net "GMI_CPU1_G3_CPU0_G1_TX_DN<0>")
	)
	(segment
		(start 114.492532 -235.504482)
		(end 114.422682 -235.574332)
		(width 0.1143)
		(layer "In11.Cu")
		(net "GMI_CPU1_G3_CPU0_G1_TX_DN<0>")
	)
	(segment
		(start 357.152448 -235.269786)
		(end 357.21544 -235.233464)
		(width 0.1143)
		(layer "In11.Cu")
		(net "GMI_CPU1_G3_CPU0_G1_TX_DN<0>")
	)
	(segment
		(start 112.779048 -232.725722)
		(end 112.78108 -232.728008)
		(width 0.1143)
		(layer "In11.Cu")
		(net "GMI_CPU1_G3_CPU0_G1_TX_DN<0>")
	)
	(segment
		(start 112.298734 -222.41383)
		(end 112.298734 -231.558338)
		(width 0.1143)
		(layer "In11.Cu")
		(net "GMI_CPU1_G3_CPU0_G1_TX_DN<0>")
	)
	(segment
		(start 311.920382 -175.927512)
		(end 308.723538 -174.784512)
		(width 0.14224)
		(layer "In11.Cu")
		(net "GMI_CPU1_G3_CPU0_G1_TX_DN<0>")
	)
	(segment
		(start 113.334292 -233.609896)
		(end 113.402364 -233.64952)
		(width 0.1143)
		(layer "In11.Cu")
		(net "GMI_CPU1_G3_CPU0_G1_TX_DN<0>")
	)
	(segment
		(start 358.562148 -232.840022)
		(end 358.631998 -232.799636)
		(width 0.1143)
		(layer "In11.Cu")
		(net "GMI_CPU1_G3_CPU0_G1_TX_DN<0>")
	)
	(segment
		(start 112.07623 -221.295214)
		(end 112.298734 -222.41383)
		(width 0.1143)
		(layer "In11.Cu")
		(net "GMI_CPU1_G3_CPU0_G1_TX_DN<0>")
	)
	(segment
		(start 164.760148 -173.97603)
		(end 155.964382 -177.121312)
		(width 0.14224)
		(layer "In11.Cu")
		(net "GMI_CPU1_G3_CPU0_G1_TX_DN<0>")
	)
	(segment
		(start 359.197148 -222.507302)
		(end 359.419652 -221.388432)
		(width 0.1143)
		(layer "In11.Cu")
		(net "GMI_CPU1_G3_CPU0_G1_TX_DN<0>")
	)
	(arc
		(start 357.221028 -235.230162)
		(mid 357.382439 -235.037223)
		(end 357.462836 -234.79887)
		(width 0.1143)
		(layer "In11.Cu")
		(net "GMI_CPU1_G3_CPU0_G1_TX_DN<0>")
	)
	(arc
		(start 114.02949 -234.754674)
		(mid 114.030697 -234.776945)
		(end 114.033046 -234.799124)
		(width 0.1143)
		(layer "In11.Cu")
		(net "GMI_CPU1_G3_CPU0_G1_TX_DN<0>")
	)
	(arc
		(start 357.00335 -235.504228)
		(mid 357.055399 -235.372709)
		(end 357.152448 -235.269786)
		(width 0.1143)
		(layer "In11.Cu")
		(net "GMI_CPU1_G3_CPU0_G1_TX_DN<0>")
	)
	(arc
		(start 358.631998 -232.799636)
		(mid 358.671814 -232.771779)
		(end 358.70642 -232.73766)
		(width 0.1143)
		(layer "In11.Cu")
		(net "GMI_CPU1_G3_CPU0_G1_TX_DN<0>")
	)
	(arc
		(start 113.402364 -233.64952)
		(mid 113.517791 -233.782896)
		(end 113.559336 -233.95432)
		(width 0.1143)
		(layer "In11.Cu")
		(net "GMI_CPU1_G3_CPU0_G1_TX_DN<0>")
	)
	(arc
		(start 113.873534 -234.460034)
		(mid 113.986056 -234.589064)
		(end 114.02949 -234.754674)
		(width 0.1143)
		(layer "In11.Cu")
		(net "GMI_CPU1_G3_CPU0_G1_TX_DN<0>")
	)
	(arc
		(start 112.933734 -232.840276)
		(mid 113.048358 -232.972358)
		(end 113.08969 -233.142282)
		(width 0.1143)
		(layer "In11.Cu")
		(net "GMI_CPU1_G3_CPU0_G1_TX_DN<0>")
	)
	(arc
		(start 358.16159 -233.609642)
		(mid 358.341382 -233.407054)
		(end 358.406192 -233.14406)
		(width 0.1143)
		(layer "In11.Cu")
		(net "GMI_CPU1_G3_CPU0_G1_TX_DN<0>")
	)
	(arc
		(start 357.936546 -233.954066)
		(mid 357.978095 -233.782644)
		(end 358.093518 -233.649266)
		(width 0.1143)
		(layer "In11.Cu")
		(net "GMI_CPU1_G3_CPU0_G1_TX_DN<0>")
	)
	(arc
		(start 113.559336 -233.95432)
		(mid 113.623851 -234.216539)
		(end 113.802668 -234.418886)
		(width 0.1143)
		(layer "In11.Cu")
		(net "GMI_CPU1_G3_CPU0_G1_TX_DN<0>")
	)
	(arc
		(start 358.717088 -232.72496)
		(mid 359.072387 -232.189076)
		(end 359.197148 -231.558338)
		(width 0.1143)
		(layer "In11.Cu")
		(net "GMI_CPU1_G3_CPU0_G1_TX_DN<0>")
	)
	(arc
		(start 114.033046 -234.799124)
		(mid 114.113472 -235.037461)
		(end 114.274854 -235.230416)
		(width 0.1143)
		(layer "In11.Cu")
		(net "GMI_CPU1_G3_CPU0_G1_TX_DN<0>")
	)
	(arc
		(start 112.789462 -232.737914)
		(mid 112.824047 -232.772057)
		(end 112.863884 -232.79989)
		(width 0.1143)
		(layer "In11.Cu")
		(net "GMI_CPU1_G3_CPU0_G1_TX_DN<0>")
	)
	(arc
		(start 113.08969 -233.144314)
		(mid 113.154508 -233.407303)
		(end 113.334292 -233.609896)
		(width 0.1143)
		(layer "In11.Cu")
		(net "GMI_CPU1_G3_CPU0_G1_TX_DN<0>")
	)
	(arc
		(start 357.693214 -234.418632)
		(mid 357.872027 -234.216282)
		(end 357.936546 -233.954066)
		(width 0.1143)
		(layer "In11.Cu")
		(net "GMI_CPU1_G3_CPU0_G1_TX_DN<0>")
	)
	(arc
		(start 112.298734 -231.558338)
		(mid 112.423515 -232.189495)
		(end 112.779048 -232.725722)
		(width 0.1143)
		(layer "In11.Cu")
		(net "GMI_CPU1_G3_CPU0_G1_TX_DN<0>")
	)
	(arc
		(start 357.462836 -234.79887)
		(mid 357.46518 -234.77669)
		(end 357.466392 -234.75442)
		(width 0.1143)
		(layer "In11.Cu")
		(net "GMI_CPU1_G3_CPU0_G1_TX_DN<0>")
	)
	(arc
		(start 357.466392 -234.75442)
		(mid 357.509785 -234.588788)
		(end 357.622348 -234.45978)
		(width 0.1143)
		(layer "In11.Cu")
		(net "GMI_CPU1_G3_CPU0_G1_TX_DN<0>")
	)
	(arc
		(start 114.343434 -235.27004)
		(mid 114.440569 -235.372909)
		(end 114.492532 -235.504482)
		(width 0.1143)
		(layer "In11.Cu")
		(net "GMI_CPU1_G3_CPU0_G1_TX_DN<0>")
	)
	(arc
		(start 358.406192 -233.142028)
		(mid 358.447541 -232.972112)
		(end 358.562148 -232.840022)
		(width 0.1143)
		(layer "In11.Cu")
		(net "GMI_CPU1_G3_CPU0_G1_TX_DN<0>")
	)
	(segment
		(start 348.907862 -230.169974)
		(end 348.44101 -229.904036)
		(width 0.12954)
		(layer "F.Cu")
		(net "GMI_CPU1_G2_CPU0_G0_TX_DP<9>")
	)
	(segment
		(start 122.587766 -230.170228)
		(end 123.054618 -229.90429)
		(width 0.12954)
		(layer "F.Cu")
		(net "GMI_CPU1_G2_CPU0_G0_TX_DP<9>")
	)
	(segment
		(start 120.800114 -221.193868)
		(end 120.800114 -221.804484)
		(width 0.1143)
		(layer "In4.Cu")
		(net "GMI_CPU1_G2_CPU0_G0_TX_DP<9>")
	)
	(segment
		(start 154.960066 -190.140844)
		(end 154.63012 -190.411354)
		(width 0.14224)
		(layer "In4.Cu")
		(net "GMI_CPU1_G2_CPU0_G0_TX_DP<9>")
	)
	(segment
		(start 156.704538 -188.710316)
		(end 156.374592 -188.980826)
		(width 0.14224)
		(layer "In4.Cu")
		(net "GMI_CPU1_G2_CPU0_G0_TX_DP<9>")
	)
	(segment
		(start 350.038924 -227.796344)
		(end 350.069912 -227.778564)
		(width 0.1143)
		(layer "In4.Cu")
		(net "GMI_CPU1_G2_CPU0_G0_TX_DP<9>")
	)
	(segment
		(start 120.987566 -223.101916)
		(end 120.957086 -223.119696)
		(width 0.1143)
		(layer "In4.Cu")
		(net "GMI_CPU1_G2_CPU0_G0_TX_DP<9>")
	)
	(segment
		(start 120.957086 -225.349308)
		(end 120.987566 -225.367088)
		(width 0.1143)
		(layer "In4.Cu")
		(net "GMI_CPU1_G2_CPU0_G0_TX_DP<9>")
	)
	(segment
		(start 350.695514 -221.80423)
		(end 350.695768 -221.804484)
		(width 0.1143)
		(layer "In4.Cu")
		(net "GMI_CPU1_G2_CPU0_G0_TX_DP<9>")
	)
	(segment
		(start 350.477582 -222.144844)
		(end 350.539812 -222.108268)
		(width 0.1143)
		(layer "In4.Cu")
		(net "GMI_CPU1_G2_CPU0_G0_TX_DP<9>")
	)
	(segment
		(start 120.957086 -226.96932)
		(end 120.987566 -226.9871)
		(width 0.1143)
		(layer "In4.Cu")
		(net "GMI_CPU1_G2_CPU0_G0_TX_DP<9>")
	)
	(segment
		(start 121.92762 -228.607112)
		(end 121.966736 -228.629972)
		(width 0.1143)
		(layer "In4.Cu")
		(net "GMI_CPU1_G2_CPU0_G0_TX_DP<9>")
	)
	(segment
		(start 155.502356 -189.69609)
		(end 155.483306 -189.88913)
		(width 0.14224)
		(layer "In4.Cu")
		(net "GMI_CPU1_G2_CPU0_G0_TX_DP<9>")
	)
	(segment
		(start 350.695768 -221.804484)
		(end 350.695768 -221.374462)
		(width 0.1143)
		(layer "In4.Cu")
		(net "GMI_CPU1_G2_CPU0_G0_TX_DP<9>")
	)
	(segment
		(start 166.653464 -182.749952)
		(end 161.891218 -184.45734)
		(width 0.14224)
		(layer "In4.Cu")
		(net "GMI_CPU1_G2_CPU0_G0_TX_DP<9>")
	)
	(segment
		(start 122.75693 -229.90429)
		(end 123.054618 -229.90429)
		(width 0.1143)
		(layer "In4.Cu")
		(net "GMI_CPU1_G2_CPU0_G0_TX_DP<9>")
	)
	(segment
		(start 120.957086 -223.729296)
		(end 120.987566 -223.747076)
		(width 0.1143)
		(layer "In4.Cu")
		(net "GMI_CPU1_G2_CPU0_G0_TX_DP<9>")
	)
	(segment
		(start 350.538796 -226.359466)
		(end 350.4692 -226.318826)
		(width 0.1143)
		(layer "In4.Cu")
		(net "GMI_CPU1_G2_CPU0_G0_TX_DP<9>")
	)
	(segment
		(start 120.987566 -222.127064)
		(end 121.026682 -222.149924)
		(width 0.1143)
		(layer "In4.Cu")
		(net "GMI_CPU1_G2_CPU0_G0_TX_DP<9>")
	)
	(segment
		(start 120.987566 -225.367088)
		(end 121.026682 -225.389948)
		(width 0.1143)
		(layer "In4.Cu")
		(net "GMI_CPU1_G2_CPU0_G0_TX_DP<9>")
	)
	(segment
		(start 120.987566 -223.747076)
		(end 121.026682 -223.769936)
		(width 0.1143)
		(layer "In4.Cu")
		(net "GMI_CPU1_G2_CPU0_G0_TX_DP<9>")
	)
	(segment
		(start 155.483306 -189.88913)
		(end 155.153106 -190.159894)
		(width 0.14224)
		(layer "In4.Cu")
		(net "GMI_CPU1_G2_CPU0_G0_TX_DP<9>")
	)
	(segment
		(start 350.4692 -222.14967)
		(end 350.477328 -222.144844)
		(width 0.1143)
		(layer "In4.Cu")
		(net "GMI_CPU1_G2_CPU0_G0_TX_DP<9>")
	)
	(segment
		(start 150.791926 -193.736214)
		(end 150.598886 -193.717164)
		(width 0.14224)
		(layer "In4.Cu")
		(net "GMI_CPU1_G2_CPU0_G0_TX_DP<9>")
	)
	(segment
		(start 168.162224 -182.749952)
		(end 166.653464 -182.749952)
		(width 0.14224)
		(layer "In4.Cu")
		(net "GMI_CPU1_G2_CPU0_G0_TX_DP<9>")
	)
	(segment
		(start 151.122126 -193.46545)
		(end 150.791926 -193.736214)
		(width 0.14224)
		(layer "In4.Cu")
		(net "GMI_CPU1_G2_CPU0_G0_TX_DP<9>")
	)
	(segment
		(start 151.141176 -193.27241)
		(end 151.122126 -193.46545)
		(width 0.14224)
		(layer "In4.Cu")
		(net "GMI_CPU1_G2_CPU0_G0_TX_DP<9>")
	)
	(segment
		(start 152.866598 -192.034922)
		(end 152.536398 -192.305686)
		(width 0.14224)
		(layer "In4.Cu")
		(net "GMI_CPU1_G2_CPU0_G0_TX_DP<9>")
	)
	(segment
		(start 121.458736 -227.797614)
		(end 121.496836 -227.819966)
		(width 0.1143)
		(layer "In4.Cu")
		(net "GMI_CPU1_G2_CPU0_G0_TX_DP<9>")
	)
	(segment
		(start 120.987566 -226.9871)
		(end 121.026682 -227.00996)
		(width 0.1143)
		(layer "In4.Cu")
		(net "GMI_CPU1_G2_CPU0_G0_TX_DP<9>")
	)
	(segment
		(start 120.81637 -221.083378)
		(end 120.77065 -221.129098)
		(width 0.1143)
		(layer "In4.Cu")
		(net "GMI_CPU1_G2_CPU0_G0_TX_DP<9>")
	)
	(segment
		(start 349.529146 -228.629718)
		(end 349.598742 -228.589078)
		(width 0.1143)
		(layer "In4.Cu")
		(net "GMI_CPU1_G2_CPU0_G0_TX_DP<9>")
	)
	(segment
		(start 120.957086 -222.109284)
		(end 120.987566 -222.127064)
		(width 0.1143)
		(layer "In4.Cu")
		(net "GMI_CPU1_G2_CPU0_G0_TX_DP<9>")
	)
	(segment
		(start 152.885648 -191.841882)
		(end 152.866598 -192.034922)
		(width 0.14224)
		(layer "In4.Cu")
		(net "GMI_CPU1_G2_CPU0_G0_TX_DP<9>")
	)
	(segment
		(start 156.374592 -188.980826)
		(end 156.355542 -189.173866)
		(width 0.14224)
		(layer "In4.Cu")
		(net "GMI_CPU1_G2_CPU0_G0_TX_DP<9>")
	)
	(segment
		(start 121.454164 -227.795074)
		(end 121.455688 -227.795836)
		(width 0.1143)
		(layer "In4.Cu")
		(net "GMI_CPU1_G2_CPU0_G0_TX_DP<9>")
	)
	(segment
		(start 121.42597 -227.778818)
		(end 121.454164 -227.795074)
		(width 0.1143)
		(layer "In4.Cu")
		(net "GMI_CPU1_G2_CPU0_G0_TX_DP<9>")
	)
	(segment
		(start 154.61107 -190.604394)
		(end 154.28087 -190.875158)
		(width 0.14224)
		(layer "In4.Cu")
		(net "GMI_CPU1_G2_CPU0_G0_TX_DP<9>")
	)
	(segment
		(start 154.63012 -190.411354)
		(end 154.61107 -190.604394)
		(width 0.14224)
		(layer "In4.Cu")
		(net "GMI_CPU1_G2_CPU0_G0_TX_DP<9>")
	)
	(segment
		(start 121.026682 -224.699068)
		(end 120.987566 -224.721928)
		(width 0.1143)
		(layer "In4.Cu")
		(net "GMI_CPU1_G2_CPU0_G0_TX_DP<9>")
	)
	(segment
		(start 153.215594 -191.571372)
		(end 152.885648 -191.841882)
		(width 0.14224)
		(layer "In4.Cu")
		(net "GMI_CPU1_G2_CPU0_G0_TX_DP<9>")
	)
	(segment
		(start 350.695768 -221.374462)
		(end 350.725232 -221.344998)
		(width 0.1143)
		(layer "In4.Cu")
		(net "GMI_CPU1_G2_CPU0_G0_TX_DP<9>")
	)
	(segment
		(start 121.45772 -227.797106)
		(end 121.458736 -227.797614)
		(width 0.1143)
		(layer "In4.Cu")
		(net "GMI_CPU1_G2_CPU0_G0_TX_DP<9>")
	)
	(segment
		(start 151.471122 -193.0019)
		(end 151.141176 -193.27241)
		(width 0.14224)
		(layer "In4.Cu")
		(net "GMI_CPU1_G2_CPU0_G0_TX_DP<9>")
	)
	(segment
		(start 350.538796 -223.119442)
		(end 350.4692 -223.078802)
		(width 0.1143)
		(layer "In4.Cu")
		(net "GMI_CPU1_G2_CPU0_G0_TX_DP<9>")
	)
	(segment
		(start 120.77065 -221.129098)
		(end 120.77065 -221.164404)
		(width 0.1143)
		(layer "In4.Cu")
		(net "GMI_CPU1_G2_CPU0_G0_TX_DP<9>")
	)
	(segment
		(start 349.058992 -229.43947)
		(end 349.131636 -229.397052)
		(width 0.1143)
		(layer "In4.Cu")
		(net "GMI_CPU1_G2_CPU0_G0_TX_DP<9>")
	)
	(segment
		(start 121.026682 -226.31908)
		(end 120.987566 -226.34194)
		(width 0.1143)
		(layer "In4.Cu")
		(net "GMI_CPU1_G2_CPU0_G0_TX_DP<9>")
	)
	(segment
		(start 151.994362 -192.750186)
		(end 151.664162 -193.02095)
		(width 0.14224)
		(layer "In4.Cu")
		(net "GMI_CPU1_G2_CPU0_G0_TX_DP<9>")
	)
	(segment
		(start 308.012084 -183.961532)
		(end 306.818538 -183.534812)
		(width 0.14224)
		(layer "In4.Cu")
		(net "GMI_CPU1_G2_CPU0_G0_TX_DP<9>")
	)
	(segment
		(start 121.89714 -228.589332)
		(end 121.92762 -228.607112)
		(width 0.1143)
		(layer "In4.Cu")
		(net "GMI_CPU1_G2_CPU0_G0_TX_DP<9>")
	)
	(segment
		(start 151.664162 -193.02095)
		(end 151.471122 -193.0019)
		(width 0.14224)
		(layer "In4.Cu")
		(net "GMI_CPU1_G2_CPU0_G0_TX_DP<9>")
	)
	(segment
		(start 350.4692 -223.769682)
		(end 350.538796 -223.729042)
		(width 0.1143)
		(layer "In4.Cu")
		(net "GMI_CPU1_G2_CPU0_G0_TX_DP<9>")
	)
	(segment
		(start 302.891952 -183.534812)
		(end 168.162224 -182.749952)
		(width 0.14224)
		(layer "In4.Cu")
		(net "GMI_CPU1_G2_CPU0_G0_TX_DP<9>")
	)
	(segment
		(start 155.832302 -189.42558)
		(end 155.502356 -189.69609)
		(width 0.14224)
		(layer "In4.Cu")
		(net "GMI_CPU1_G2_CPU0_G0_TX_DP<9>")
	)
	(segment
		(start 150.598886 -193.717164)
		(end 146.364452 -197.188836)
		(width 0.14224)
		(layer "In4.Cu")
		(net "GMI_CPU1_G2_CPU0_G0_TX_DP<9>")
	)
	(segment
		(start 348.738952 -229.904036)
		(end 348.821756 -229.821232)
		(width 0.1143)
		(layer "In4.Cu")
		(net "GMI_CPU1_G2_CPU0_G0_TX_DP<9>")
	)
	(segment
		(start 349.999046 -227.819712)
		(end 350.037146 -227.79736)
		(width 0.1143)
		(layer "In4.Cu")
		(net "GMI_CPU1_G2_CPU0_G0_TX_DP<9>")
	)
	(segment
		(start 350.4692 -225.389694)
		(end 350.538796 -225.349054)
		(width 0.1143)
		(layer "In4.Cu")
		(net "GMI_CPU1_G2_CPU0_G0_TX_DP<9>")
	)
	(segment
		(start 120.77065 -221.164404)
		(end 120.800114 -221.193868)
		(width 0.1143)
		(layer "In4.Cu")
		(net "GMI_CPU1_G2_CPU0_G0_TX_DP<9>")
	)
	(segment
		(start 121.456958 -227.796598)
		(end 121.45772 -227.797106)
		(width 0.1143)
		(layer "In4.Cu")
		(net "GMI_CPU1_G2_CPU0_G0_TX_DP<9>")
	)
	(segment
		(start 153.738834 -191.319658)
		(end 153.408634 -191.590422)
		(width 0.14224)
		(layer "In4.Cu")
		(net "GMI_CPU1_G2_CPU0_G0_TX_DP<9>")
	)
	(segment
		(start 350.477328 -222.144844)
		(end 350.477582 -222.144844)
		(width 0.1143)
		(layer "In4.Cu")
		(net "GMI_CPU1_G2_CPU0_G0_TX_DP<9>")
	)
	(segment
		(start 350.679512 -219.498164)
		(end 348.33433 -215.54821)
		(width 0.14224)
		(layer "In4.Cu")
		(net "GMI_CPU1_G2_CPU0_G0_TX_DP<9>")
	)
	(segment
		(start 161.891218 -184.45734)
		(end 157.246828 -188.265562)
		(width 0.14224)
		(layer "In4.Cu")
		(net "GMI_CPU1_G2_CPU0_G0_TX_DP<9>")
	)
	(segment
		(start 157.227778 -188.458602)
		(end 156.897578 -188.729366)
		(width 0.14224)
		(layer "In4.Cu")
		(net "GMI_CPU1_G2_CPU0_G0_TX_DP<9>")
	)
	(segment
		(start 154.28087 -190.875158)
		(end 154.08783 -190.856108)
		(width 0.14224)
		(layer "In4.Cu")
		(net "GMI_CPU1_G2_CPU0_G0_TX_DP<9>")
	)
	(segment
		(start 350.538796 -224.739454)
		(end 350.4692 -224.698814)
		(width 0.1143)
		(layer "In4.Cu")
		(net "GMI_CPU1_G2_CPU0_G0_TX_DP<9>")
	)
	(segment
		(start 120.81637 -219.620338)
		(end 120.81637 -221.05493)
		(width 0.14224)
		(layer "In4.Cu")
		(net "GMI_CPU1_G2_CPU0_G0_TX_DP<9>")
	)
	(segment
		(start 156.355542 -189.173866)
		(end 156.025342 -189.44463)
		(width 0.14224)
		(layer "In4.Cu")
		(net "GMI_CPU1_G2_CPU0_G0_TX_DP<9>")
	)
	(segment
		(start 157.246828 -188.265562)
		(end 157.227778 -188.458602)
		(width 0.14224)
		(layer "In4.Cu")
		(net "GMI_CPU1_G2_CPU0_G0_TX_DP<9>")
	)
	(segment
		(start 156.897578 -188.729366)
		(end 156.704538 -188.710316)
		(width 0.14224)
		(layer "In4.Cu")
		(net "GMI_CPU1_G2_CPU0_G0_TX_DP<9>")
	)
	(segment
		(start 350.037146 -227.79736)
		(end 350.038162 -227.796852)
		(width 0.1143)
		(layer "In4.Cu")
		(net "GMI_CPU1_G2_CPU0_G0_TX_DP<9>")
	)
	(segment
		(start 123.266708 -215.41994)
		(end 120.81637 -219.620338)
		(width 0.14224)
		(layer "In4.Cu")
		(net "GMI_CPU1_G2_CPU0_G0_TX_DP<9>")
	)
	(segment
		(start 122.397774 -229.416864)
		(end 122.43689 -229.439724)
		(width 0.1143)
		(layer "In4.Cu")
		(net "GMI_CPU1_G2_CPU0_G0_TX_DP<9>")
	)
	(segment
		(start 156.025342 -189.44463)
		(end 155.832302 -189.42558)
		(width 0.14224)
		(layer "In4.Cu")
		(net "GMI_CPU1_G2_CPU0_G0_TX_DP<9>")
	)
	(segment
		(start 122.364246 -229.397306)
		(end 122.397774 -229.416864)
		(width 0.1143)
		(layer "In4.Cu")
		(net "GMI_CPU1_G2_CPU0_G0_TX_DP<9>")
	)
	(segment
		(start 120.987566 -226.34194)
		(end 120.957086 -226.35972)
		(width 0.1143)
		(layer "In4.Cu")
		(net "GMI_CPU1_G2_CPU0_G0_TX_DP<9>")
	)
	(segment
		(start 121.026682 -223.079056)
		(end 120.987566 -223.101916)
		(width 0.1143)
		(layer "In4.Cu")
		(net "GMI_CPU1_G2_CPU0_G0_TX_DP<9>")
	)
	(segment
		(start 350.4692 -227.009706)
		(end 350.538796 -226.969066)
		(width 0.1143)
		(layer "In4.Cu")
		(net "GMI_CPU1_G2_CPU0_G0_TX_DP<9>")
	)
	(segment
		(start 350.725232 -221.344998)
		(end 350.725232 -221.128844)
		(width 0.1143)
		(layer "In4.Cu")
		(net "GMI_CPU1_G2_CPU0_G0_TX_DP<9>")
	)
	(segment
		(start 153.408634 -191.590422)
		(end 153.215594 -191.571372)
		(width 0.14224)
		(layer "In4.Cu")
		(net "GMI_CPU1_G2_CPU0_G0_TX_DP<9>")
	)
	(segment
		(start 121.455688 -227.795836)
		(end 121.456958 -227.796598)
		(width 0.1143)
		(layer "In4.Cu")
		(net "GMI_CPU1_G2_CPU0_G0_TX_DP<9>")
	)
	(segment
		(start 153.757884 -191.126618)
		(end 153.738834 -191.319658)
		(width 0.14224)
		(layer "In4.Cu")
		(net "GMI_CPU1_G2_CPU0_G0_TX_DP<9>")
	)
	(segment
		(start 350.725232 -221.128844)
		(end 350.679512 -221.083124)
		(width 0.1143)
		(layer "In4.Cu")
		(net "GMI_CPU1_G2_CPU0_G0_TX_DP<9>")
	)
	(segment
		(start 348.33433 -215.54821)
		(end 313.82716 -187.253372)
		(width 0.14224)
		(layer "In4.Cu")
		(net "GMI_CPU1_G2_CPU0_G0_TX_DP<9>")
	)
	(segment
		(start 152.013412 -192.557146)
		(end 151.994362 -192.750186)
		(width 0.14224)
		(layer "In4.Cu")
		(net "GMI_CPU1_G2_CPU0_G0_TX_DP<9>")
	)
	(segment
		(start 348.44101 -229.904036)
		(end 348.738952 -229.904036)
		(width 0.1143)
		(layer "In4.Cu")
		(net "GMI_CPU1_G2_CPU0_G0_TX_DP<9>")
	)
	(segment
		(start 144.995138 -197.603364)
		(end 123.266708 -215.41994)
		(width 0.14224)
		(layer "In4.Cu")
		(net "GMI_CPU1_G2_CPU0_G0_TX_DP<9>")
	)
	(segment
		(start 122.674126 -229.821486)
		(end 122.75693 -229.90429)
		(width 0.1143)
		(layer "In4.Cu")
		(net "GMI_CPU1_G2_CPU0_G0_TX_DP<9>")
	)
	(segment
		(start 120.81637 -221.05493)
		(end 120.81637 -221.083378)
		(width 0.1143)
		(layer "In4.Cu")
		(net "GMI_CPU1_G2_CPU0_G0_TX_DP<9>")
	)
	(segment
		(start 306.818538 -183.534812)
		(end 302.891952 -183.534812)
		(width 0.14224)
		(layer "In4.Cu")
		(net "GMI_CPU1_G2_CPU0_G0_TX_DP<9>")
	)
	(segment
		(start 155.153106 -190.159894)
		(end 154.960066 -190.140844)
		(width 0.14224)
		(layer "In4.Cu")
		(net "GMI_CPU1_G2_CPU0_G0_TX_DP<9>")
	)
	(segment
		(start 152.343358 -192.286636)
		(end 152.013412 -192.557146)
		(width 0.14224)
		(layer "In4.Cu")
		(net "GMI_CPU1_G2_CPU0_G0_TX_DP<9>")
	)
	(segment
		(start 313.82716 -187.253372)
		(end 308.012084 -183.961532)
		(width 0.14224)
		(layer "In4.Cu")
		(net "GMI_CPU1_G2_CPU0_G0_TX_DP<9>")
	)
	(segment
		(start 146.364452 -197.188836)
		(end 144.995138 -197.603364)
		(width 0.14224)
		(layer "In4.Cu")
		(net "GMI_CPU1_G2_CPU0_G0_TX_DP<9>")
	)
	(segment
		(start 154.08783 -190.856108)
		(end 153.757884 -191.126618)
		(width 0.14224)
		(layer "In4.Cu")
		(net "GMI_CPU1_G2_CPU0_G0_TX_DP<9>")
	)
	(segment
		(start 350.038162 -227.796852)
		(end 350.038924 -227.796344)
		(width 0.1143)
		(layer "In4.Cu")
		(net "GMI_CPU1_G2_CPU0_G0_TX_DP<9>")
	)
	(segment
		(start 152.536398 -192.305686)
		(end 152.343358 -192.286636)
		(width 0.14224)
		(layer "In4.Cu")
		(net "GMI_CPU1_G2_CPU0_G0_TX_DP<9>")
	)
	(segment
		(start 350.679512 -221.083124)
		(end 350.679512 -219.498164)
		(width 0.14224)
		(layer "In4.Cu")
		(net "GMI_CPU1_G2_CPU0_G0_TX_DP<9>")
	)
	(segment
		(start 120.987566 -224.721928)
		(end 120.957086 -224.739708)
		(width 0.1143)
		(layer "In4.Cu")
		(net "GMI_CPU1_G2_CPU0_G0_TX_DP<9>")
	)
	(arc
		(start 349.131636 -229.397052)
		(mid 349.245043 -229.264163)
		(end 349.285814 -229.094284)
		(width 0.1143)
		(layer "In4.Cu")
		(net "GMI_CPU1_G2_CPU0_G0_TX_DP<9>")
	)
	(arc
		(start 120.800114 -221.804484)
		(mid 120.841663 -221.975906)
		(end 120.957086 -222.109284)
		(width 0.1143)
		(layer "In4.Cu")
		(net "GMI_CPU1_G2_CPU0_G0_TX_DP<9>")
	)
	(arc
		(start 121.026682 -227.00996)
		(mid 121.205495 -227.21231)
		(end 121.270014 -227.474526)
		(width 0.1143)
		(layer "In4.Cu")
		(net "GMI_CPU1_G2_CPU0_G0_TX_DP<9>")
	)
	(arc
		(start 121.270014 -227.474526)
		(mid 121.311269 -227.645497)
		(end 121.42597 -227.778818)
		(width 0.1143)
		(layer "In4.Cu")
		(net "GMI_CPU1_G2_CPU0_G0_TX_DP<9>")
	)
	(arc
		(start 350.538796 -225.349054)
		(mid 350.695773 -225.044254)
		(end 350.538796 -224.739454)
		(width 0.1143)
		(layer "In4.Cu")
		(net "GMI_CPU1_G2_CPU0_G0_TX_DP<9>")
	)
	(arc
		(start 122.210068 -229.094538)
		(mid 122.25083 -229.264422)
		(end 122.364246 -229.397306)
		(width 0.1143)
		(layer "In4.Cu")
		(net "GMI_CPU1_G2_CPU0_G0_TX_DP<9>")
	)
	(arc
		(start 350.4692 -223.078802)
		(mid 350.225873 -222.614236)
		(end 350.4692 -222.14967)
		(width 0.1143)
		(layer "In4.Cu")
		(net "GMI_CPU1_G2_CPU0_G0_TX_DP<9>")
	)
	(arc
		(start 348.821756 -229.821232)
		(mid 348.823544 -229.809783)
		(end 348.825566 -229.798372)
		(width 0.1143)
		(layer "In4.Cu")
		(net "GMI_CPU1_G2_CPU0_G0_TX_DP<9>")
	)
	(arc
		(start 349.285814 -229.094284)
		(mid 349.350329 -228.832065)
		(end 349.529146 -228.629718)
		(width 0.1143)
		(layer "In4.Cu")
		(net "GMI_CPU1_G2_CPU0_G0_TX_DP<9>")
	)
	(arc
		(start 350.225868 -227.474272)
		(mid 350.290383 -227.212053)
		(end 350.4692 -227.009706)
		(width 0.1143)
		(layer "In4.Cu")
		(net "GMI_CPU1_G2_CPU0_G0_TX_DP<9>")
	)
	(arc
		(start 350.538796 -223.729042)
		(mid 350.695773 -223.424242)
		(end 350.538796 -223.119442)
		(width 0.1143)
		(layer "In4.Cu")
		(net "GMI_CPU1_G2_CPU0_G0_TX_DP<9>")
	)
	(arc
		(start 350.4692 -226.318826)
		(mid 350.225873 -225.85426)
		(end 350.4692 -225.389694)
		(width 0.1143)
		(layer "In4.Cu")
		(net "GMI_CPU1_G2_CPU0_G0_TX_DP<9>")
	)
	(arc
		(start 348.825566 -229.798372)
		(mid 348.906999 -229.595974)
		(end 349.058992 -229.43947)
		(width 0.1143)
		(layer "In4.Cu")
		(net "GMI_CPU1_G2_CPU0_G0_TX_DP<9>")
	)
	(arc
		(start 349.755714 -228.284278)
		(mid 349.820229 -228.022059)
		(end 349.999046 -227.819712)
		(width 0.1143)
		(layer "In4.Cu")
		(net "GMI_CPU1_G2_CPU0_G0_TX_DP<9>")
	)
	(arc
		(start 121.740168 -228.284532)
		(mid 121.781717 -228.455954)
		(end 121.89714 -228.589332)
		(width 0.1143)
		(layer "In4.Cu")
		(net "GMI_CPU1_G2_CPU0_G0_TX_DP<9>")
	)
	(arc
		(start 121.496836 -227.819966)
		(mid 121.675649 -228.022316)
		(end 121.740168 -228.284532)
		(width 0.1143)
		(layer "In4.Cu")
		(net "GMI_CPU1_G2_CPU0_G0_TX_DP<9>")
	)
	(arc
		(start 121.026682 -222.149924)
		(mid 121.270009 -222.61449)
		(end 121.026682 -223.079056)
		(width 0.1143)
		(layer "In4.Cu")
		(net "GMI_CPU1_G2_CPU0_G0_TX_DP<9>")
	)
	(arc
		(start 350.069912 -227.778564)
		(mid 350.184588 -227.64523)
		(end 350.225868 -227.474272)
		(width 0.1143)
		(layer "In4.Cu")
		(net "GMI_CPU1_G2_CPU0_G0_TX_DP<9>")
	)
	(arc
		(start 120.957086 -226.35972)
		(mid 120.800109 -226.66452)
		(end 120.957086 -226.96932)
		(width 0.1143)
		(layer "In4.Cu")
		(net "GMI_CPU1_G2_CPU0_G0_TX_DP<9>")
	)
	(arc
		(start 349.598742 -228.589078)
		(mid 349.714169 -228.455702)
		(end 349.755714 -228.284278)
		(width 0.1143)
		(layer "In4.Cu")
		(net "GMI_CPU1_G2_CPU0_G0_TX_DP<9>")
	)
	(arc
		(start 121.026682 -223.769936)
		(mid 121.270009 -224.234502)
		(end 121.026682 -224.699068)
		(width 0.1143)
		(layer "In4.Cu")
		(net "GMI_CPU1_G2_CPU0_G0_TX_DP<9>")
	)
	(arc
		(start 120.957086 -224.739708)
		(mid 120.800109 -225.044508)
		(end 120.957086 -225.349308)
		(width 0.1143)
		(layer "In4.Cu")
		(net "GMI_CPU1_G2_CPU0_G0_TX_DP<9>")
	)
	(arc
		(start 120.957086 -223.119696)
		(mid 120.800109 -223.424496)
		(end 120.957086 -223.729296)
		(width 0.1143)
		(layer "In4.Cu")
		(net "GMI_CPU1_G2_CPU0_G0_TX_DP<9>")
	)
	(arc
		(start 350.4692 -224.698814)
		(mid 350.225873 -224.234248)
		(end 350.4692 -223.769682)
		(width 0.1143)
		(layer "In4.Cu")
		(net "GMI_CPU1_G2_CPU0_G0_TX_DP<9>")
	)
	(arc
		(start 350.539812 -222.108268)
		(mid 350.654322 -221.975033)
		(end 350.695514 -221.80423)
		(width 0.1143)
		(layer "In4.Cu")
		(net "GMI_CPU1_G2_CPU0_G0_TX_DP<9>")
	)
	(arc
		(start 350.538796 -226.969066)
		(mid 350.695773 -226.664266)
		(end 350.538796 -226.359466)
		(width 0.1143)
		(layer "In4.Cu")
		(net "GMI_CPU1_G2_CPU0_G0_TX_DP<9>")
	)
	(arc
		(start 121.026682 -225.389948)
		(mid 121.270009 -225.854514)
		(end 121.026682 -226.31908)
		(width 0.1143)
		(layer "In4.Cu")
		(net "GMI_CPU1_G2_CPU0_G0_TX_DP<9>")
	)
	(arc
		(start 121.966736 -228.629972)
		(mid 122.145549 -228.832322)
		(end 122.210068 -229.094538)
		(width 0.1143)
		(layer "In4.Cu")
		(net "GMI_CPU1_G2_CPU0_G0_TX_DP<9>")
	)
	(arc
		(start 122.43689 -229.439724)
		(mid 122.595095 -229.606011)
		(end 122.674126 -229.821486)
		(width 0.1143)
		(layer "In4.Cu")
		(net "GMI_CPU1_G2_CPU0_G0_TX_DP<9>")
	)
	(segment
		(start 351.728024 -228.550216)
		(end 351.261172 -228.284278)
		(width 0.12954)
		(layer "F.Cu")
		(net "GMI_CPU1_G2_CPU0_G0_TX_DP<8>")
	)
	(segment
		(start 119.767858 -228.55047)
		(end 120.23471 -228.284532)
		(width 0.12954)
		(layer "F.Cu")
		(net "GMI_CPU1_G2_CPU0_G0_TX_DP<8>")
	)
	(segment
		(start 149.972776 -191.447928)
		(end 150.165816 -191.466978)
		(width 0.14224)
		(layer "In4.Cu")
		(net "GMI_CPU1_G2_CPU0_G0_TX_DP<8>")
	)
	(segment
		(start 155.843732 -186.633358)
		(end 160.294828 -182.983632)
		(width 0.14224)
		(layer "In4.Cu")
		(net "GMI_CPU1_G2_CPU0_G0_TX_DP<8>")
	)
	(segment
		(start 119.174514 -223.789748)
		(end 119.146828 -223.769682)
		(width 0.1143)
		(layer "In4.Cu")
		(net "GMI_CPU1_G2_CPU0_G0_TX_DP<8>")
	)
	(segment
		(start 118.92661 -219.131134)
		(end 121.87682 -214.089742)
		(width 0.14224)
		(layer "In4.Cu")
		(net "GMI_CPU1_G2_CPU0_G0_TX_DP<8>")
	)
	(segment
		(start 151.387302 -190.28791)
		(end 151.717248 -190.0174)
		(width 0.14224)
		(layer "In4.Cu")
		(net "GMI_CPU1_G2_CPU0_G0_TX_DP<8>")
	)
	(segment
		(start 352.349054 -224.699068)
		(end 352.41992 -224.739962)
		(width 0.1143)
		(layer "In4.Cu")
		(net "GMI_CPU1_G2_CPU0_G0_TX_DP<8>")
	)
	(segment
		(start 152.259538 -189.572646)
		(end 152.654762 -189.248542)
		(width 0.14224)
		(layer "In4.Cu")
		(net "GMI_CPU1_G2_CPU0_G0_TX_DP<8>")
	)
	(segment
		(start 119.107712 -226.34194)
		(end 119.144034 -226.320858)
		(width 0.1143)
		(layer "In4.Cu")
		(net "GMI_CPU1_G2_CPU0_G0_TX_DP<8>")
	)
	(segment
		(start 352.41992 -226.968304)
		(end 352.375978 -226.994212)
		(width 0.1143)
		(layer "In4.Cu")
		(net "GMI_CPU1_G2_CPU0_G0_TX_DP<8>")
	)
	(segment
		(start 352.569272 -221.083124)
		(end 352.614992 -221.128844)
		(width 0.1143)
		(layer "In4.Cu")
		(net "GMI_CPU1_G2_CPU0_G0_TX_DP<8>")
	)
	(segment
		(start 302.898048 -181.659276)
		(end 307.21808 -181.659276)
		(width 0.14224)
		(layer "In4.Cu")
		(net "GMI_CPU1_G2_CPU0_G0_TX_DP<8>")
	)
	(segment
		(start 154.470354 -187.759594)
		(end 154.652726 -187.777628)
		(width 0.14224)
		(layer "In4.Cu")
		(net "GMI_CPU1_G2_CPU0_G0_TX_DP<8>")
	)
	(segment
		(start 352.351848 -226.320604)
		(end 352.38817 -226.341686)
		(width 0.1143)
		(layer "In4.Cu")
		(net "GMI_CPU1_G2_CPU0_G0_TX_DP<8>")
	)
	(segment
		(start 153.621994 -188.455554)
		(end 153.804112 -188.473588)
		(width 0.14224)
		(layer "In4.Cu")
		(net "GMI_CPU1_G2_CPU0_G0_TX_DP<8>")
	)
	(segment
		(start 154.977084 -187.51169)
		(end 154.995118 -187.329318)
		(width 0.14224)
		(layer "In4.Cu")
		(net "GMI_CPU1_G2_CPU0_G0_TX_DP<8>")
	)
	(segment
		(start 150.845012 -190.732664)
		(end 151.038052 -190.751714)
		(width 0.14224)
		(layer "In4.Cu")
		(net "GMI_CPU1_G2_CPU0_G0_TX_DP<8>")
	)
	(segment
		(start 119.60987 -227.815902)
		(end 119.609108 -227.815394)
		(width 0.1143)
		(layer "In4.Cu")
		(net "GMI_CPU1_G2_CPU0_G0_TX_DP<8>")
	)
	(segment
		(start 119.075962 -223.120204)
		(end 119.107712 -223.101916)
		(width 0.1143)
		(layer "In4.Cu")
		(net "GMI_CPU1_G2_CPU0_G0_TX_DP<8>")
	)
	(segment
		(start 155.50134 -187.081668)
		(end 155.825698 -186.81573)
		(width 0.14224)
		(layer "In4.Cu")
		(net "GMI_CPU1_G2_CPU0_G0_TX_DP<8>")
	)
	(segment
		(start 145.12163 -195.42506)
		(end 149.10054 -192.162938)
		(width 0.14224)
		(layer "In4.Cu")
		(net "GMI_CPU1_G2_CPU0_G0_TX_DP<8>")
	)
	(segment
		(start 352.38817 -222.12681)
		(end 352.351848 -222.147892)
		(width 0.1143)
		(layer "In4.Cu")
		(net "GMI_CPU1_G2_CPU0_G0_TX_DP<8>")
	)
	(segment
		(start 153.161492 -189.000638)
		(end 153.179526 -188.818266)
		(width 0.14224)
		(layer "In4.Cu")
		(net "GMI_CPU1_G2_CPU0_G0_TX_DP<8>")
	)
	(segment
		(start 119.144034 -222.148146)
		(end 119.107712 -222.127064)
		(width 0.1143)
		(layer "In4.Cu")
		(net "GMI_CPU1_G2_CPU0_G0_TX_DP<8>")
	)
	(segment
		(start 152.240488 -189.765686)
		(end 152.259538 -189.572646)
		(width 0.14224)
		(layer "In4.Cu")
		(net "GMI_CPU1_G2_CPU0_G0_TX_DP<8>")
	)
	(segment
		(start 155.318968 -187.063634)
		(end 155.50134 -187.081668)
		(width 0.14224)
		(layer "In4.Cu")
		(net "GMI_CPU1_G2_CPU0_G0_TX_DP<8>")
	)
	(segment
		(start 149.10054 -192.162938)
		(end 149.29358 -192.182242)
		(width 0.14224)
		(layer "In4.Cu")
		(net "GMI_CPU1_G2_CPU0_G0_TX_DP<8>")
	)
	(segment
		(start 154.146504 -188.025278)
		(end 154.470354 -187.759594)
		(width 0.14224)
		(layer "In4.Cu")
		(net "GMI_CPU1_G2_CPU0_G0_TX_DP<8>")
	)
	(segment
		(start 119.616728 -227.819966)
		(end 119.60987 -227.815902)
		(width 0.1143)
		(layer "In4.Cu")
		(net "GMI_CPU1_G2_CPU0_G0_TX_DP<8>")
	)
	(segment
		(start 307.21808 -181.659276)
		(end 308.75859 -182.210456)
		(width 0.14224)
		(layer "In4.Cu")
		(net "GMI_CPU1_G2_CPU0_G0_TX_DP<8>")
	)
	(segment
		(start 119.075962 -223.728534)
		(end 119.075962 -223.728788)
		(width 0.1143)
		(layer "In4.Cu")
		(net "GMI_CPU1_G2_CPU0_G0_TX_DP<8>")
	)
	(segment
		(start 118.920006 -221.3864)
		(end 118.88089 -221.347284)
		(width 0.1143)
		(layer "In4.Cu")
		(net "GMI_CPU1_G2_CPU0_G0_TX_DP<8>")
	)
	(segment
		(start 352.093276 -227.483924)
		(end 352.093276 -227.49637)
		(width 0.1143)
		(layer "In4.Cu")
		(net "GMI_CPU1_G2_CPU0_G0_TX_DP<8>")
	)
	(segment
		(start 352.41992 -222.108522)
		(end 352.38817 -222.12681)
		(width 0.1143)
		(layer "In4.Cu")
		(net "GMI_CPU1_G2_CPU0_G0_TX_DP<8>")
	)
	(segment
		(start 349.628206 -214.074756)
		(end 352.569272 -219.028518)
		(width 0.14224)
		(layer "In4.Cu")
		(net "GMI_CPU1_G2_CPU0_G0_TX_DP<8>")
	)
	(segment
		(start 154.12847 -188.20765)
		(end 154.146504 -188.025278)
		(width 0.14224)
		(layer "In4.Cu")
		(net "GMI_CPU1_G2_CPU0_G0_TX_DP<8>")
	)
	(segment
		(start 150.496016 -191.196214)
		(end 150.515066 -191.003174)
		(width 0.14224)
		(layer "In4.Cu")
		(net "GMI_CPU1_G2_CPU0_G0_TX_DP<8>")
	)
	(segment
		(start 352.614992 -221.34703)
		(end 352.575876 -221.386146)
		(width 0.1143)
		(layer "In4.Cu")
		(net "GMI_CPU1_G2_CPU0_G0_TX_DP<8>")
	)
	(segment
		(start 153.179526 -188.818266)
		(end 153.621994 -188.455554)
		(width 0.14224)
		(layer "In4.Cu")
		(net "GMI_CPU1_G2_CPU0_G0_TX_DP<8>")
	)
	(segment
		(start 119.936768 -228.284532)
		(end 119.853964 -228.201728)
		(width 0.1143)
		(layer "In4.Cu")
		(net "GMI_CPU1_G2_CPU0_G0_TX_DP<8>")
	)
	(segment
		(start 119.402606 -227.496624)
		(end 119.402606 -227.484178)
		(width 0.1143)
		(layer "In4.Cu")
		(net "GMI_CPU1_G2_CPU0_G0_TX_DP<8>")
	)
	(segment
		(start 119.075962 -226.360228)
		(end 119.107712 -226.34194)
		(width 0.1143)
		(layer "In4.Cu")
		(net "GMI_CPU1_G2_CPU0_G0_TX_DP<8>")
	)
	(segment
		(start 160.294828 -182.983632)
		(end 166.203376 -180.87086)
		(width 0.14224)
		(layer "In4.Cu")
		(net "GMI_CPU1_G2_CPU0_G0_TX_DP<8>")
	)
	(segment
		(start 155.825698 -186.81573)
		(end 155.843732 -186.633358)
		(width 0.14224)
		(layer "In4.Cu")
		(net "GMI_CPU1_G2_CPU0_G0_TX_DP<8>")
	)
	(segment
		(start 315.24702 -185.883296)
		(end 349.628206 -214.074756)
		(width 0.14224)
		(layer "In4.Cu")
		(net "GMI_CPU1_G2_CPU0_G0_TX_DP<8>")
	)
	(segment
		(start 352.614992 -221.128844)
		(end 352.614992 -221.34703)
		(width 0.1143)
		(layer "In4.Cu")
		(net "GMI_CPU1_G2_CPU0_G0_TX_DP<8>")
	)
	(segment
		(start 144.357852 -195.656708)
		(end 145.12163 -195.42506)
		(width 0.14224)
		(layer "In4.Cu")
		(net "GMI_CPU1_G2_CPU0_G0_TX_DP<8>")
	)
	(segment
		(start 352.575876 -221.386146)
		(end 352.575876 -221.80423)
		(width 0.1143)
		(layer "In4.Cu")
		(net "GMI_CPU1_G2_CPU0_G0_TX_DP<8>")
	)
	(segment
		(start 352.41992 -223.72828)
		(end 352.403918 -223.737424)
		(width 0.1143)
		(layer "In4.Cu")
		(net "GMI_CPU1_G2_CPU0_G0_TX_DP<8>")
	)
	(segment
		(start 119.574056 -227.795328)
		(end 119.573548 -227.795074)
		(width 0.1143)
		(layer "In4.Cu")
		(net "GMI_CPU1_G2_CPU0_G0_TX_DP<8>")
	)
	(segment
		(start 149.64283 -191.718438)
		(end 149.972776 -191.447928)
		(width 0.14224)
		(layer "In4.Cu")
		(net "GMI_CPU1_G2_CPU0_G0_TX_DP<8>")
	)
	(segment
		(start 352.38817 -225.366834)
		(end 352.351848 -225.387916)
		(width 0.1143)
		(layer "In4.Cu")
		(net "GMI_CPU1_G2_CPU0_G0_TX_DP<8>")
	)
	(segment
		(start 119.144034 -225.38817)
		(end 119.107712 -225.367088)
		(width 0.1143)
		(layer "In4.Cu")
		(net "GMI_CPU1_G2_CPU0_G0_TX_DP<8>")
	)
	(segment
		(start 352.403918 -223.737424)
		(end 352.387916 -223.747076)
		(width 0.1143)
		(layer "In4.Cu")
		(net "GMI_CPU1_G2_CPU0_G0_TX_DP<8>")
	)
	(segment
		(start 352.38817 -223.101662)
		(end 352.41992 -223.11995)
		(width 0.1143)
		(layer "In4.Cu")
		(net "GMI_CPU1_G2_CPU0_G0_TX_DP<8>")
	)
	(segment
		(start 154.652726 -187.777628)
		(end 154.977084 -187.51169)
		(width 0.14224)
		(layer "In4.Cu")
		(net "GMI_CPU1_G2_CPU0_G0_TX_DP<8>")
	)
	(segment
		(start 352.41992 -223.728534)
		(end 352.41992 -223.72828)
		(width 0.1143)
		(layer "In4.Cu")
		(net "GMI_CPU1_G2_CPU0_G0_TX_DP<8>")
	)
	(segment
		(start 118.88089 -221.347284)
		(end 118.88089 -221.129098)
		(width 0.1143)
		(layer "In4.Cu")
		(net "GMI_CPU1_G2_CPU0_G0_TX_DP<8>")
	)
	(segment
		(start 351.919032 -227.796344)
		(end 351.91827 -227.796852)
		(width 0.1143)
		(layer "In4.Cu")
		(net "GMI_CPU1_G2_CPU0_G0_TX_DP<8>")
	)
	(segment
		(start 352.351848 -223.08058)
		(end 352.38817 -223.101662)
		(width 0.1143)
		(layer "In4.Cu")
		(net "GMI_CPU1_G2_CPU0_G0_TX_DP<8>")
	)
	(segment
		(start 151.368252 -190.48095)
		(end 151.387302 -190.28791)
		(width 0.14224)
		(layer "In4.Cu")
		(net "GMI_CPU1_G2_CPU0_G0_TX_DP<8>")
	)
	(segment
		(start 119.609108 -227.815394)
		(end 119.577612 -227.797106)
		(width 0.1143)
		(layer "In4.Cu")
		(net "GMI_CPU1_G2_CPU0_G0_TX_DP<8>")
	)
	(segment
		(start 119.119904 -226.994466)
		(end 119.075962 -226.968558)
		(width 0.1143)
		(layer "In4.Cu")
		(net "GMI_CPU1_G2_CPU0_G0_TX_DP<8>")
	)
	(segment
		(start 351.559114 -228.284278)
		(end 351.261172 -228.284278)
		(width 0.1143)
		(layer "In4.Cu")
		(net "GMI_CPU1_G2_CPU0_G0_TX_DP<8>")
	)
	(segment
		(start 154.995118 -187.329318)
		(end 155.318968 -187.063634)
		(width 0.14224)
		(layer "In4.Cu")
		(net "GMI_CPU1_G2_CPU0_G0_TX_DP<8>")
	)
	(segment
		(start 151.910288 -190.03645)
		(end 152.240488 -189.765686)
		(width 0.14224)
		(layer "In4.Cu")
		(net "GMI_CPU1_G2_CPU0_G0_TX_DP<8>")
	)
	(segment
		(start 119.146828 -224.699322)
		(end 119.174514 -224.679256)
		(width 0.1143)
		(layer "In4.Cu")
		(net "GMI_CPU1_G2_CPU0_G0_TX_DP<8>")
	)
	(segment
		(start 152.654762 -189.248542)
		(end 152.837134 -189.266576)
		(width 0.14224)
		(layer "In4.Cu")
		(net "GMI_CPU1_G2_CPU0_G0_TX_DP<8>")
	)
	(segment
		(start 149.62378 -191.911478)
		(end 149.64283 -191.718438)
		(width 0.14224)
		(layer "In4.Cu")
		(net "GMI_CPU1_G2_CPU0_G0_TX_DP<8>")
	)
	(segment
		(start 151.038052 -190.751714)
		(end 151.368252 -190.48095)
		(width 0.14224)
		(layer "In4.Cu")
		(net "GMI_CPU1_G2_CPU0_G0_TX_DP<8>")
	)
	(segment
		(start 151.717248 -190.0174)
		(end 151.910288 -190.03645)
		(width 0.14224)
		(layer "In4.Cu")
		(net "GMI_CPU1_G2_CPU0_G0_TX_DP<8>")
	)
	(segment
		(start 351.922334 -227.79482)
		(end 351.921826 -227.795074)
		(width 0.1143)
		(layer "In4.Cu")
		(net "GMI_CPU1_G2_CPU0_G0_TX_DP<8>")
	)
	(segment
		(start 150.165816 -191.466978)
		(end 150.496016 -191.196214)
		(width 0.14224)
		(layer "In4.Cu")
		(net "GMI_CPU1_G2_CPU0_G0_TX_DP<8>")
	)
	(segment
		(start 119.107712 -222.127064)
		(end 119.075962 -222.108776)
		(width 0.1143)
		(layer "In4.Cu")
		(net "GMI_CPU1_G2_CPU0_G0_TX_DP<8>")
	)
	(segment
		(start 119.075962 -224.740216)
		(end 119.146828 -224.699322)
		(width 0.1143)
		(layer "In4.Cu")
		(net "GMI_CPU1_G2_CPU0_G0_TX_DP<8>")
	)
	(segment
		(start 150.515066 -191.003174)
		(end 150.845012 -190.732664)
		(width 0.14224)
		(layer "In4.Cu")
		(net "GMI_CPU1_G2_CPU0_G0_TX_DP<8>")
	)
	(segment
		(start 118.920006 -221.804484)
		(end 118.920006 -221.3864)
		(width 0.1143)
		(layer "In4.Cu")
		(net "GMI_CPU1_G2_CPU0_G0_TX_DP<8>")
	)
	(segment
		(start 119.57685 -227.796598)
		(end 119.574056 -227.795328)
		(width 0.1143)
		(layer "In4.Cu")
		(net "GMI_CPU1_G2_CPU0_G0_TX_DP<8>")
	)
	(segment
		(start 166.203376 -180.87086)
		(end 167.67429 -180.87086)
		(width 0.14224)
		(layer "In4.Cu")
		(net "GMI_CPU1_G2_CPU0_G0_TX_DP<8>")
	)
	(segment
		(start 351.641918 -228.201474)
		(end 351.559114 -228.284278)
		(width 0.1143)
		(layer "In4.Cu")
		(net "GMI_CPU1_G2_CPU0_G0_TX_DP<8>")
	)
	(segment
		(start 121.87682 -214.089742)
		(end 144.357852 -195.656708)
		(width 0.14224)
		(layer "In4.Cu")
		(net "GMI_CPU1_G2_CPU0_G0_TX_DP<8>")
	)
	(segment
		(start 119.091964 -223.737678)
		(end 119.075962 -223.728534)
		(width 0.1143)
		(layer "In4.Cu")
		(net "GMI_CPU1_G2_CPU0_G0_TX_DP<8>")
	)
	(segment
		(start 118.88089 -221.129098)
		(end 118.92661 -221.083378)
		(width 0.1143)
		(layer "In4.Cu")
		(net "GMI_CPU1_G2_CPU0_G0_TX_DP<8>")
	)
	(segment
		(start 351.921826 -227.795074)
		(end 351.919032 -227.796344)
		(width 0.1143)
		(layer "In4.Cu")
		(net "GMI_CPU1_G2_CPU0_G0_TX_DP<8>")
	)
	(segment
		(start 119.107712 -223.101916)
		(end 119.144034 -223.080834)
		(width 0.1143)
		(layer "In4.Cu")
		(net "GMI_CPU1_G2_CPU0_G0_TX_DP<8>")
	)
	(segment
		(start 120.23471 -228.284532)
		(end 119.936768 -228.284532)
		(width 0.1143)
		(layer "In4.Cu")
		(net "GMI_CPU1_G2_CPU0_G0_TX_DP<8>")
	)
	(segment
		(start 152.837134 -189.266576)
		(end 153.161492 -189.000638)
		(width 0.14224)
		(layer "In4.Cu")
		(net "GMI_CPU1_G2_CPU0_G0_TX_DP<8>")
	)
	(segment
		(start 351.91827 -227.796852)
		(end 351.879154 -227.819712)
		(width 0.1143)
		(layer "In4.Cu")
		(net "GMI_CPU1_G2_CPU0_G0_TX_DP<8>")
	)
	(segment
		(start 352.41992 -225.348546)
		(end 352.38817 -225.366834)
		(width 0.1143)
		(layer "In4.Cu")
		(net "GMI_CPU1_G2_CPU0_G0_TX_DP<8>")
	)
	(segment
		(start 153.804112 -188.473588)
		(end 154.12847 -188.20765)
		(width 0.14224)
		(layer "In4.Cu")
		(net "GMI_CPU1_G2_CPU0_G0_TX_DP<8>")
	)
	(segment
		(start 167.67429 -180.87086)
		(end 302.898048 -181.659276)
		(width 0.14224)
		(layer "In4.Cu")
		(net "GMI_CPU1_G2_CPU0_G0_TX_DP<8>")
	)
	(segment
		(start 118.92661 -221.05493)
		(end 118.92661 -219.131134)
		(width 0.14224)
		(layer "In4.Cu")
		(net "GMI_CPU1_G2_CPU0_G0_TX_DP<8>")
	)
	(segment
		(start 118.92661 -221.083378)
		(end 118.92661 -221.05493)
		(width 0.1143)
		(layer "In4.Cu")
		(net "GMI_CPU1_G2_CPU0_G0_TX_DP<8>")
	)
	(segment
		(start 352.387916 -223.747076)
		(end 352.349054 -223.769428)
		(width 0.1143)
		(layer "In4.Cu")
		(net "GMI_CPU1_G2_CPU0_G0_TX_DP<8>")
	)
	(segment
		(start 352.349054 -223.769428)
		(end 352.321368 -223.789494)
		(width 0.1143)
		(layer "In4.Cu")
		(net "GMI_CPU1_G2_CPU0_G0_TX_DP<8>")
	)
	(segment
		(start 352.38817 -226.341686)
		(end 352.41992 -226.359974)
		(width 0.1143)
		(layer "In4.Cu")
		(net "GMI_CPU1_G2_CPU0_G0_TX_DP<8>")
	)
	(segment
		(start 149.29358 -192.182242)
		(end 149.62378 -191.911478)
		(width 0.14224)
		(layer "In4.Cu")
		(net "GMI_CPU1_G2_CPU0_G0_TX_DP<8>")
	)
	(segment
		(start 119.107966 -223.74733)
		(end 119.091964 -223.737678)
		(width 0.1143)
		(layer "In4.Cu")
		(net "GMI_CPU1_G2_CPU0_G0_TX_DP<8>")
	)
	(segment
		(start 352.321368 -224.679002)
		(end 352.349054 -224.699068)
		(width 0.1143)
		(layer "In4.Cu")
		(net "GMI_CPU1_G2_CPU0_G0_TX_DP<8>")
	)
	(segment
		(start 352.569272 -219.028518)
		(end 352.569272 -221.083124)
		(width 0.14224)
		(layer "In4.Cu")
		(net "GMI_CPU1_G2_CPU0_G0_TX_DP<8>")
	)
	(segment
		(start 308.75859 -182.210456)
		(end 315.24702 -185.883296)
		(width 0.14224)
		(layer "In4.Cu")
		(net "GMI_CPU1_G2_CPU0_G0_TX_DP<8>")
	)
	(segment
		(start 119.577612 -227.797106)
		(end 119.57685 -227.796598)
		(width 0.1143)
		(layer "In4.Cu")
		(net "GMI_CPU1_G2_CPU0_G0_TX_DP<8>")
	)
	(segment
		(start 119.146828 -223.769682)
		(end 119.107966 -223.74733)
		(width 0.1143)
		(layer "In4.Cu")
		(net "GMI_CPU1_G2_CPU0_G0_TX_DP<8>")
	)
	(segment
		(start 119.107712 -225.367088)
		(end 119.075962 -225.3488)
		(width 0.1143)
		(layer "In4.Cu")
		(net "GMI_CPU1_G2_CPU0_G0_TX_DP<8>")
	)
	(arc
		(start 352.337624 -222.157798)
		(mid 352.110241 -222.614236)
		(end 352.337624 -223.070674)
		(width 0.1143)
		(layer "In4.Cu")
		(net "GMI_CPU1_G2_CPU0_G0_TX_DP<8>")
	)
	(arc
		(start 352.375978 -226.994212)
		(mid 352.16899 -227.201184)
		(end 352.093276 -227.483924)
		(width 0.1143)
		(layer "In4.Cu")
		(net "GMI_CPU1_G2_CPU0_G0_TX_DP<8>")
	)
	(arc
		(start 119.158258 -223.070928)
		(mid 119.385641 -222.61449)
		(end 119.158258 -222.158052)
		(width 0.1143)
		(layer "In4.Cu")
		(net "GMI_CPU1_G2_CPU0_G0_TX_DP<8>")
	)
	(arc
		(start 119.075962 -225.3488)
		(mid 118.920034 -225.044508)
		(end 119.075962 -224.740216)
		(width 0.1143)
		(layer "In4.Cu")
		(net "GMI_CPU1_G2_CPU0_G0_TX_DP<8>")
	)
	(arc
		(start 119.075962 -226.968558)
		(mid 118.993981 -226.887908)
		(end 118.940326 -226.786186)
		(width 0.1143)
		(layer "In4.Cu")
		(net "GMI_CPU1_G2_CPU0_G0_TX_DP<8>")
	)
	(arc
		(start 352.337624 -223.070674)
		(mid 352.344697 -223.075683)
		(end 352.351848 -223.08058)
		(width 0.1143)
		(layer "In4.Cu")
		(net "GMI_CPU1_G2_CPU0_G0_TX_DP<8>")
	)
	(arc
		(start 352.351848 -222.147892)
		(mid 352.344698 -222.15279)
		(end 352.337624 -222.157798)
		(width 0.1143)
		(layer "In4.Cu")
		(net "GMI_CPU1_G2_CPU0_G0_TX_DP<8>")
	)
	(arc
		(start 119.075962 -223.728788)
		(mid 118.920034 -223.424496)
		(end 119.075962 -223.120204)
		(width 0.1143)
		(layer "In4.Cu")
		(net "GMI_CPU1_G2_CPU0_G0_TX_DP<8>")
	)
	(arc
		(start 119.158258 -225.398076)
		(mid 119.151184 -225.393069)
		(end 119.144034 -225.38817)
		(width 0.1143)
		(layer "In4.Cu")
		(net "GMI_CPU1_G2_CPU0_G0_TX_DP<8>")
	)
	(arc
		(start 352.41992 -224.739962)
		(mid 352.575848 -225.044254)
		(end 352.41992 -225.348546)
		(width 0.1143)
		(layer "In4.Cu")
		(net "GMI_CPU1_G2_CPU0_G0_TX_DP<8>")
	)
	(arc
		(start 352.41992 -226.359974)
		(mid 352.558176 -226.550524)
		(end 352.555556 -226.785932)
		(width 0.1143)
		(layer "In4.Cu")
		(net "GMI_CPU1_G2_CPU0_G0_TX_DP<8>")
	)
	(arc
		(start 119.853964 -228.201728)
		(mid 119.774885 -227.986283)
		(end 119.616728 -227.819966)
		(width 0.1143)
		(layer "In4.Cu")
		(net "GMI_CPU1_G2_CPU0_G0_TX_DP<8>")
	)
	(arc
		(start 352.321368 -223.789494)
		(mid 352.093368 -224.234248)
		(end 352.321368 -224.679002)
		(width 0.1143)
		(layer "In4.Cu")
		(net "GMI_CPU1_G2_CPU0_G0_TX_DP<8>")
	)
	(arc
		(start 119.402606 -227.484178)
		(mid 119.326849 -227.201463)
		(end 119.119904 -226.994466)
		(width 0.1143)
		(layer "In4.Cu")
		(net "GMI_CPU1_G2_CPU0_G0_TX_DP<8>")
	)
	(arc
		(start 119.573548 -227.795074)
		(mid 119.448348 -227.6686)
		(end 119.402606 -227.496624)
		(width 0.1143)
		(layer "In4.Cu")
		(net "GMI_CPU1_G2_CPU0_G0_TX_DP<8>")
	)
	(arc
		(start 352.093276 -227.49637)
		(mid 352.04751 -227.668332)
		(end 351.922334 -227.79482)
		(width 0.1143)
		(layer "In4.Cu")
		(net "GMI_CPU1_G2_CPU0_G0_TX_DP<8>")
	)
	(arc
		(start 119.144034 -226.320858)
		(mid 119.151183 -226.315958)
		(end 119.158258 -226.310952)
		(width 0.1143)
		(layer "In4.Cu")
		(net "GMI_CPU1_G2_CPU0_G0_TX_DP<8>")
	)
	(arc
		(start 118.940326 -226.786186)
		(mid 118.937705 -226.550777)
		(end 119.075962 -226.360228)
		(width 0.1143)
		(layer "In4.Cu")
		(net "GMI_CPU1_G2_CPU0_G0_TX_DP<8>")
	)
	(arc
		(start 119.075962 -222.108776)
		(mid 118.961286 -221.975442)
		(end 118.920006 -221.804484)
		(width 0.1143)
		(layer "In4.Cu")
		(net "GMI_CPU1_G2_CPU0_G0_TX_DP<8>")
	)
	(arc
		(start 352.337624 -226.310698)
		(mid 352.344697 -226.315707)
		(end 352.351848 -226.320604)
		(width 0.1143)
		(layer "In4.Cu")
		(net "GMI_CPU1_G2_CPU0_G0_TX_DP<8>")
	)
	(arc
		(start 352.351848 -225.387916)
		(mid 352.344698 -225.392814)
		(end 352.337624 -225.397822)
		(width 0.1143)
		(layer "In4.Cu")
		(net "GMI_CPU1_G2_CPU0_G0_TX_DP<8>")
	)
	(arc
		(start 119.158258 -226.310952)
		(mid 119.385641 -225.854514)
		(end 119.158258 -225.398076)
		(width 0.1143)
		(layer "In4.Cu")
		(net "GMI_CPU1_G2_CPU0_G0_TX_DP<8>")
	)
	(arc
		(start 119.174514 -224.679256)
		(mid 119.402514 -224.234502)
		(end 119.174514 -223.789748)
		(width 0.1143)
		(layer "In4.Cu")
		(net "GMI_CPU1_G2_CPU0_G0_TX_DP<8>")
	)
	(arc
		(start 351.879154 -227.819712)
		(mid 351.720949 -227.985999)
		(end 351.641918 -228.201474)
		(width 0.1143)
		(layer "In4.Cu")
		(net "GMI_CPU1_G2_CPU0_G0_TX_DP<8>")
	)
	(arc
		(start 352.337624 -225.397822)
		(mid 352.110241 -225.85426)
		(end 352.337624 -226.310698)
		(width 0.1143)
		(layer "In4.Cu")
		(net "GMI_CPU1_G2_CPU0_G0_TX_DP<8>")
	)
	(arc
		(start 352.575876 -221.80423)
		(mid 352.534621 -221.975201)
		(end 352.41992 -222.108522)
		(width 0.1143)
		(layer "In4.Cu")
		(net "GMI_CPU1_G2_CPU0_G0_TX_DP<8>")
	)
	(arc
		(start 119.144034 -223.080834)
		(mid 119.151183 -223.075934)
		(end 119.158258 -223.070928)
		(width 0.1143)
		(layer "In4.Cu")
		(net "GMI_CPU1_G2_CPU0_G0_TX_DP<8>")
	)
	(arc
		(start 352.41992 -223.11995)
		(mid 352.575848 -223.424242)
		(end 352.41992 -223.728534)
		(width 0.1143)
		(layer "In4.Cu")
		(net "GMI_CPU1_G2_CPU0_G0_TX_DP<8>")
	)
	(arc
		(start 119.158258 -222.158052)
		(mid 119.151184 -222.153045)
		(end 119.144034 -222.148146)
		(width 0.1143)
		(layer "In4.Cu")
		(net "GMI_CPU1_G2_CPU0_G0_TX_DP<8>")
	)
	(arc
		(start 352.555556 -226.785932)
		(mid 352.50192 -226.887668)
		(end 352.41992 -226.968304)
		(width 0.1143)
		(layer "In4.Cu")
		(net "GMI_CPU1_G2_CPU0_G0_TX_DP<8>")
	)
	(segment
		(start 351.728024 -226.930204)
		(end 351.261172 -226.664266)
		(width 0.12954)
		(layer "F.Cu")
		(net "GMI_CPU1_G2_CPU0_G0_TX_DP<7>")
	)
	(segment
		(start 119.767858 -226.930458)
		(end 120.23471 -226.66452)
		(width 0.12954)
		(layer "F.Cu")
		(net "GMI_CPU1_G2_CPU0_G0_TX_DP<7>")
	)
	(segment
		(start 351.47885 -224.739454)
		(end 351.409254 -224.698814)
		(width 0.1143)
		(layer "In4.Cu")
		(net "GMI_CPU1_G2_CPU0_G0_TX_DP<7>")
	)
	(segment
		(start 155.749752 -188.279024)
		(end 155.419552 -188.549788)
		(width 0.14224)
		(layer "In4.Cu")
		(net "GMI_CPU1_G2_CPU0_G0_TX_DP<7>")
	)
	(segment
		(start 351.624392 -219.263468)
		(end 349.006414 -214.853774)
		(width 0.14224)
		(layer "In4.Cu")
		(net "GMI_CPU1_G2_CPU0_G0_TX_DP<7>")
	)
	(segment
		(start 151.799798 -191.518286)
		(end 151.606758 -191.498982)
		(width 0.14224)
		(layer "In4.Cu")
		(net "GMI_CPU1_G2_CPU0_G0_TX_DP<7>")
	)
	(segment
		(start 120.047512 -223.747076)
		(end 120.086628 -223.769936)
		(width 0.1143)
		(layer "In4.Cu")
		(net "GMI_CPU1_G2_CPU0_G0_TX_DP<7>")
	)
	(segment
		(start 147.47113 -194.889374)
		(end 145.90903 -196.170296)
		(width 0.14224)
		(layer "In4.Cu")
		(net "GMI_CPU1_G2_CPU0_G0_TX_DP<7>")
	)
	(segment
		(start 351.409254 -225.389694)
		(end 351.47885 -225.349054)
		(width 0.1143)
		(layer "In4.Cu")
		(net "GMI_CPU1_G2_CPU0_G0_TX_DP<7>")
	)
	(segment
		(start 153.35123 -190.068454)
		(end 153.021284 -190.338964)
		(width 0.14224)
		(layer "In4.Cu")
		(net "GMI_CPU1_G2_CPU0_G0_TX_DP<7>")
	)
	(segment
		(start 119.82577 -221.129098)
		(end 119.82577 -221.347284)
		(width 0.1143)
		(layer "In4.Cu")
		(net "GMI_CPU1_G2_CPU0_G0_TX_DP<7>")
	)
	(segment
		(start 154.877516 -188.994288)
		(end 154.547316 -189.265052)
		(width 0.14224)
		(layer "In4.Cu")
		(net "GMI_CPU1_G2_CPU0_G0_TX_DP<7>")
	)
	(segment
		(start 144.86001 -196.487796)
		(end 122.566176 -214.768176)
		(width 0.14224)
		(layer "In4.Cu")
		(net "GMI_CPU1_G2_CPU0_G0_TX_DP<7>")
	)
	(segment
		(start 119.86006 -221.381574)
		(end 119.86006 -221.804484)
		(width 0.1143)
		(layer "In4.Cu")
		(net "GMI_CPU1_G2_CPU0_G0_TX_DP<7>")
	)
	(segment
		(start 122.566176 -214.768176)
		(end 119.87149 -219.380816)
		(width 0.14224)
		(layer "In4.Cu")
		(net "GMI_CPU1_G2_CPU0_G0_TX_DP<7>")
	)
	(segment
		(start 155.768802 -188.08573)
		(end 155.768802 -188.085984)
		(width 0.14224)
		(layer "In4.Cu")
		(net "GMI_CPU1_G2_CPU0_G0_TX_DP<7>")
	)
	(segment
		(start 145.90903 -196.170296)
		(end 144.86001 -196.487796)
		(width 0.14224)
		(layer "In4.Cu")
		(net "GMI_CPU1_G2_CPU0_G0_TX_DP<7>")
	)
	(segment
		(start 152.478994 -190.783972)
		(end 152.149048 -191.054482)
		(width 0.14224)
		(layer "In4.Cu")
		(net "GMI_CPU1_G2_CPU0_G0_TX_DP<7>")
	)
	(segment
		(start 161.119312 -183.698388)
		(end 155.768802 -188.08573)
		(width 0.14224)
		(layer "In4.Cu")
		(net "GMI_CPU1_G2_CPU0_G0_TX_DP<7>")
	)
	(segment
		(start 302.895 -182.593488)
		(end 167.826944 -181.806342)
		(width 0.14224)
		(layer "In4.Cu")
		(net "GMI_CPU1_G2_CPU0_G0_TX_DP<7>")
	)
	(segment
		(start 149.51329 -193.392806)
		(end 149.18309 -193.66357)
		(width 0.14224)
		(layer "In4.Cu")
		(net "GMI_CPU1_G2_CPU0_G0_TX_DP<7>")
	)
	(segment
		(start 151.606758 -191.498982)
		(end 151.276812 -191.769492)
		(width 0.14224)
		(layer "In4.Cu")
		(net "GMI_CPU1_G2_CPU0_G0_TX_DP<7>")
	)
	(segment
		(start 166.411148 -181.806342)
		(end 161.119312 -183.698388)
		(width 0.14224)
		(layer "In4.Cu")
		(net "GMI_CPU1_G2_CPU0_G0_TX_DP<7>")
	)
	(segment
		(start 120.047512 -226.34194)
		(end 120.017032 -226.35972)
		(width 0.1143)
		(layer "In4.Cu")
		(net "GMI_CPU1_G2_CPU0_G0_TX_DP<7>")
	)
	(segment
		(start 153.89352 -189.6237)
		(end 153.87447 -189.81674)
		(width 0.14224)
		(layer "In4.Cu")
		(net "GMI_CPU1_G2_CPU0_G0_TX_DP<7>")
	)
	(segment
		(start 351.261172 -226.664266)
		(end 351.559114 -226.664266)
		(width 0.1143)
		(layer "In4.Cu")
		(net "GMI_CPU1_G2_CPU0_G0_TX_DP<7>")
	)
	(segment
		(start 351.635822 -221.38132)
		(end 351.670112 -221.34703)
		(width 0.1143)
		(layer "In4.Cu")
		(net "GMI_CPU1_G2_CPU0_G0_TX_DP<7>")
	)
	(segment
		(start 351.417382 -222.144844)
		(end 351.417636 -222.144844)
		(width 0.1143)
		(layer "In4.Cu")
		(net "GMI_CPU1_G2_CPU0_G0_TX_DP<7>")
	)
	(segment
		(start 120.047512 -225.367088)
		(end 120.086628 -225.389948)
		(width 0.1143)
		(layer "In4.Cu")
		(net "GMI_CPU1_G2_CPU0_G0_TX_DP<7>")
	)
	(segment
		(start 120.017032 -222.109284)
		(end 120.047512 -222.127064)
		(width 0.1143)
		(layer "In4.Cu")
		(net "GMI_CPU1_G2_CPU0_G0_TX_DP<7>")
	)
	(segment
		(start 153.021284 -190.339218)
		(end 153.002234 -190.532258)
		(width 0.14224)
		(layer "In4.Cu")
		(net "GMI_CPU1_G2_CPU0_G0_TX_DP<7>")
	)
	(segment
		(start 351.624392 -221.083124)
		(end 351.624392 -219.263468)
		(width 0.14224)
		(layer "In4.Cu")
		(net "GMI_CPU1_G2_CPU0_G0_TX_DP<7>")
	)
	(segment
		(start 152.672034 -190.803022)
		(end 152.478994 -190.783972)
		(width 0.14224)
		(layer "In4.Cu")
		(net "GMI_CPU1_G2_CPU0_G0_TX_DP<7>")
	)
	(segment
		(start 150.385526 -192.677796)
		(end 150.055326 -192.94856)
		(width 0.14224)
		(layer "In4.Cu")
		(net "GMI_CPU1_G2_CPU0_G0_TX_DP<7>")
	)
	(segment
		(start 150.734522 -192.214246)
		(end 150.404576 -192.484756)
		(width 0.14224)
		(layer "In4.Cu")
		(net "GMI_CPU1_G2_CPU0_G0_TX_DP<7>")
	)
	(segment
		(start 148.99005 -193.644266)
		(end 147.471384 -194.889374)
		(width 0.14224)
		(layer "In4.Cu")
		(net "GMI_CPU1_G2_CPU0_G0_TX_DP<7>")
	)
	(segment
		(start 351.47885 -223.119442)
		(end 351.409254 -223.078802)
		(width 0.1143)
		(layer "In4.Cu")
		(net "GMI_CPU1_G2_CPU0_G0_TX_DP<7>")
	)
	(segment
		(start 151.276812 -191.769492)
		(end 151.257762 -191.962532)
		(width 0.14224)
		(layer "In4.Cu")
		(net "GMI_CPU1_G2_CPU0_G0_TX_DP<7>")
	)
	(segment
		(start 120.086628 -224.699068)
		(end 120.047512 -224.721928)
		(width 0.1143)
		(layer "In4.Cu")
		(net "GMI_CPU1_G2_CPU0_G0_TX_DP<7>")
	)
	(segment
		(start 151.257762 -191.962532)
		(end 150.927562 -192.233296)
		(width 0.14224)
		(layer "In4.Cu")
		(net "GMI_CPU1_G2_CPU0_G0_TX_DP<7>")
	)
	(segment
		(start 120.086628 -226.31908)
		(end 120.047512 -226.34194)
		(width 0.1143)
		(layer "In4.Cu")
		(net "GMI_CPU1_G2_CPU0_G0_TX_DP<7>")
	)
	(segment
		(start 314.465462 -186.532012)
		(end 308.31536 -183.050434)
		(width 0.14224)
		(layer "In4.Cu")
		(net "GMI_CPU1_G2_CPU0_G0_TX_DP<7>")
	)
	(segment
		(start 149.18309 -193.66357)
		(end 148.99005 -193.644266)
		(width 0.14224)
		(layer "In4.Cu")
		(net "GMI_CPU1_G2_CPU0_G0_TX_DP<7>")
	)
	(segment
		(start 120.047512 -224.721928)
		(end 120.017032 -224.739708)
		(width 0.1143)
		(layer "In4.Cu")
		(net "GMI_CPU1_G2_CPU0_G0_TX_DP<7>")
	)
	(segment
		(start 351.670112 -221.34703)
		(end 351.670112 -221.128844)
		(width 0.1143)
		(layer "In4.Cu")
		(net "GMI_CPU1_G2_CPU0_G0_TX_DP<7>")
	)
	(segment
		(start 147.471384 -194.889374)
		(end 147.47113 -194.889374)
		(width 0.14224)
		(layer "In4.Cu")
		(net "GMI_CPU1_G2_CPU0_G0_TX_DP<7>")
	)
	(segment
		(start 119.87149 -221.083378)
		(end 119.82577 -221.129098)
		(width 0.1143)
		(layer "In4.Cu")
		(net "GMI_CPU1_G2_CPU0_G0_TX_DP<7>")
	)
	(segment
		(start 119.866918 -226.59467)
		(end 119.936768 -226.66452)
		(width 0.1143)
		(layer "In4.Cu")
		(net "GMI_CPU1_G2_CPU0_G0_TX_DP<7>")
	)
	(segment
		(start 155.226512 -188.530738)
		(end 154.896566 -188.801248)
		(width 0.14224)
		(layer "In4.Cu")
		(net "GMI_CPU1_G2_CPU0_G0_TX_DP<7>")
	)
	(segment
		(start 119.87149 -221.05493)
		(end 119.87149 -221.083378)
		(width 0.1143)
		(layer "In4.Cu")
		(net "GMI_CPU1_G2_CPU0_G0_TX_DP<7>")
	)
	(segment
		(start 153.54427 -190.087504)
		(end 153.35123 -190.068454)
		(width 0.14224)
		(layer "In4.Cu")
		(net "GMI_CPU1_G2_CPU0_G0_TX_DP<7>")
	)
	(segment
		(start 120.017032 -223.729296)
		(end 120.047512 -223.747076)
		(width 0.1143)
		(layer "In4.Cu")
		(net "GMI_CPU1_G2_CPU0_G0_TX_DP<7>")
	)
	(segment
		(start 154.547316 -189.265052)
		(end 154.354276 -189.246002)
		(width 0.14224)
		(layer "In4.Cu")
		(net "GMI_CPU1_G2_CPU0_G0_TX_DP<7>")
	)
	(segment
		(start 152.129998 -191.247522)
		(end 151.799798 -191.518286)
		(width 0.14224)
		(layer "In4.Cu")
		(net "GMI_CPU1_G2_CPU0_G0_TX_DP<7>")
	)
	(segment
		(start 150.927562 -192.233296)
		(end 150.734522 -192.214246)
		(width 0.14224)
		(layer "In4.Cu")
		(net "GMI_CPU1_G2_CPU0_G0_TX_DP<7>")
	)
	(segment
		(start 150.404576 -192.484756)
		(end 150.385526 -192.677796)
		(width 0.14224)
		(layer "In4.Cu")
		(net "GMI_CPU1_G2_CPU0_G0_TX_DP<7>")
	)
	(segment
		(start 351.559114 -226.664266)
		(end 351.628964 -226.594416)
		(width 0.1143)
		(layer "In4.Cu")
		(net "GMI_CPU1_G2_CPU0_G0_TX_DP<7>")
	)
	(segment
		(start 120.047512 -223.101916)
		(end 120.017032 -223.119696)
		(width 0.1143)
		(layer "In4.Cu")
		(net "GMI_CPU1_G2_CPU0_G0_TX_DP<7>")
	)
	(segment
		(start 120.086628 -223.079056)
		(end 120.047512 -223.101916)
		(width 0.1143)
		(layer "In4.Cu")
		(net "GMI_CPU1_G2_CPU0_G0_TX_DP<7>")
	)
	(segment
		(start 120.017032 -225.349308)
		(end 120.047512 -225.367088)
		(width 0.1143)
		(layer "In4.Cu")
		(net "GMI_CPU1_G2_CPU0_G0_TX_DP<7>")
	)
	(segment
		(start 119.82577 -221.347284)
		(end 119.86006 -221.381574)
		(width 0.1143)
		(layer "In4.Cu")
		(net "GMI_CPU1_G2_CPU0_G0_TX_DP<7>")
	)
	(segment
		(start 154.354276 -189.246002)
		(end 153.89352 -189.6237)
		(width 0.14224)
		(layer "In4.Cu")
		(net "GMI_CPU1_G2_CPU0_G0_TX_DP<7>")
	)
	(segment
		(start 351.47885 -226.359466)
		(end 351.409254 -226.318826)
		(width 0.1143)
		(layer "In4.Cu")
		(net "GMI_CPU1_G2_CPU0_G0_TX_DP<7>")
	)
	(segment
		(start 351.409254 -222.14967)
		(end 351.417382 -222.144844)
		(width 0.1143)
		(layer "In4.Cu")
		(net "GMI_CPU1_G2_CPU0_G0_TX_DP<7>")
	)
	(segment
		(start 155.768802 -188.085984)
		(end 155.749752 -188.279024)
		(width 0.14224)
		(layer "In4.Cu")
		(net "GMI_CPU1_G2_CPU0_G0_TX_DP<7>")
	)
	(segment
		(start 149.53234 -193.199766)
		(end 149.51329 -193.392806)
		(width 0.14224)
		(layer "In4.Cu")
		(net "GMI_CPU1_G2_CPU0_G0_TX_DP<7>")
	)
	(segment
		(start 308.31536 -183.050434)
		(end 307.036978 -182.593488)
		(width 0.14224)
		(layer "In4.Cu")
		(net "GMI_CPU1_G2_CPU0_G0_TX_DP<7>")
	)
	(segment
		(start 351.670112 -221.128844)
		(end 351.624392 -221.083124)
		(width 0.1143)
		(layer "In4.Cu")
		(net "GMI_CPU1_G2_CPU0_G0_TX_DP<7>")
	)
	(segment
		(start 153.002234 -190.532258)
		(end 152.672034 -190.803022)
		(width 0.14224)
		(layer "In4.Cu")
		(net "GMI_CPU1_G2_CPU0_G0_TX_DP<7>")
	)
	(segment
		(start 351.635822 -221.804484)
		(end 351.635822 -221.38132)
		(width 0.1143)
		(layer "In4.Cu")
		(net "GMI_CPU1_G2_CPU0_G0_TX_DP<7>")
	)
	(segment
		(start 120.047512 -222.127064)
		(end 120.086628 -222.149924)
		(width 0.1143)
		(layer "In4.Cu")
		(net "GMI_CPU1_G2_CPU0_G0_TX_DP<7>")
	)
	(segment
		(start 351.635568 -221.80423)
		(end 351.635822 -221.804484)
		(width 0.1143)
		(layer "In4.Cu")
		(net "GMI_CPU1_G2_CPU0_G0_TX_DP<7>")
	)
	(segment
		(start 149.862286 -192.929256)
		(end 149.53234 -193.199766)
		(width 0.14224)
		(layer "In4.Cu")
		(net "GMI_CPU1_G2_CPU0_G0_TX_DP<7>")
	)
	(segment
		(start 167.826944 -181.806342)
		(end 166.411148 -181.806342)
		(width 0.14224)
		(layer "In4.Cu")
		(net "GMI_CPU1_G2_CPU0_G0_TX_DP<7>")
	)
	(segment
		(start 152.149048 -191.054482)
		(end 152.129998 -191.247522)
		(width 0.14224)
		(layer "In4.Cu")
		(net "GMI_CPU1_G2_CPU0_G0_TX_DP<7>")
	)
	(segment
		(start 307.036978 -182.593488)
		(end 302.895 -182.593488)
		(width 0.14224)
		(layer "In4.Cu")
		(net "GMI_CPU1_G2_CPU0_G0_TX_DP<7>")
	)
	(segment
		(start 351.409254 -223.769682)
		(end 351.47885 -223.729042)
		(width 0.1143)
		(layer "In4.Cu")
		(net "GMI_CPU1_G2_CPU0_G0_TX_DP<7>")
	)
	(segment
		(start 119.87149 -219.380816)
		(end 119.87149 -221.05493)
		(width 0.14224)
		(layer "In4.Cu")
		(net "GMI_CPU1_G2_CPU0_G0_TX_DP<7>")
	)
	(segment
		(start 119.936768 -226.66452)
		(end 120.23471 -226.66452)
		(width 0.1143)
		(layer "In4.Cu")
		(net "GMI_CPU1_G2_CPU0_G0_TX_DP<7>")
	)
	(segment
		(start 153.87447 -189.81674)
		(end 153.54427 -190.087504)
		(width 0.14224)
		(layer "In4.Cu")
		(net "GMI_CPU1_G2_CPU0_G0_TX_DP<7>")
	)
	(segment
		(start 153.021284 -190.338964)
		(end 153.021284 -190.339218)
		(width 0.14224)
		(layer "In4.Cu")
		(net "GMI_CPU1_G2_CPU0_G0_TX_DP<7>")
	)
	(segment
		(start 150.055326 -192.94856)
		(end 149.862286 -192.929256)
		(width 0.14224)
		(layer "In4.Cu")
		(net "GMI_CPU1_G2_CPU0_G0_TX_DP<7>")
	)
	(segment
		(start 349.006414 -214.853774)
		(end 314.465462 -186.532012)
		(width 0.14224)
		(layer "In4.Cu")
		(net "GMI_CPU1_G2_CPU0_G0_TX_DP<7>")
	)
	(segment
		(start 351.417636 -222.144844)
		(end 351.479866 -222.108268)
		(width 0.1143)
		(layer "In4.Cu")
		(net "GMI_CPU1_G2_CPU0_G0_TX_DP<7>")
	)
	(segment
		(start 154.896566 -188.801248)
		(end 154.877516 -188.994288)
		(width 0.14224)
		(layer "In4.Cu")
		(net "GMI_CPU1_G2_CPU0_G0_TX_DP<7>")
	)
	(segment
		(start 155.419552 -188.549788)
		(end 155.226512 -188.530738)
		(width 0.14224)
		(layer "In4.Cu")
		(net "GMI_CPU1_G2_CPU0_G0_TX_DP<7>")
	)
	(arc
		(start 351.409254 -226.318826)
		(mid 351.165927 -225.85426)
		(end 351.409254 -225.389694)
		(width 0.1143)
		(layer "In4.Cu")
		(net "GMI_CPU1_G2_CPU0_G0_TX_DP<7>")
	)
	(arc
		(start 119.86006 -221.804484)
		(mid 119.901609 -221.975906)
		(end 120.017032 -222.109284)
		(width 0.1143)
		(layer "In4.Cu")
		(net "GMI_CPU1_G2_CPU0_G0_TX_DP<7>")
	)
	(arc
		(start 351.628964 -226.594416)
		(mid 351.576547 -226.462485)
		(end 351.47885 -226.359466)
		(width 0.1143)
		(layer "In4.Cu")
		(net "GMI_CPU1_G2_CPU0_G0_TX_DP<7>")
	)
	(arc
		(start 120.086628 -225.389948)
		(mid 120.329955 -225.854514)
		(end 120.086628 -226.31908)
		(width 0.1143)
		(layer "In4.Cu")
		(net "GMI_CPU1_G2_CPU0_G0_TX_DP<7>")
	)
	(arc
		(start 120.017032 -226.35972)
		(mid 119.919267 -226.462696)
		(end 119.866918 -226.59467)
		(width 0.1143)
		(layer "In4.Cu")
		(net "GMI_CPU1_G2_CPU0_G0_TX_DP<7>")
	)
	(arc
		(start 120.017032 -224.739708)
		(mid 119.860055 -225.044508)
		(end 120.017032 -225.349308)
		(width 0.1143)
		(layer "In4.Cu")
		(net "GMI_CPU1_G2_CPU0_G0_TX_DP<7>")
	)
	(arc
		(start 120.086628 -222.149924)
		(mid 120.329955 -222.61449)
		(end 120.086628 -223.079056)
		(width 0.1143)
		(layer "In4.Cu")
		(net "GMI_CPU1_G2_CPU0_G0_TX_DP<7>")
	)
	(arc
		(start 351.47885 -225.349054)
		(mid 351.635827 -225.044254)
		(end 351.47885 -224.739454)
		(width 0.1143)
		(layer "In4.Cu")
		(net "GMI_CPU1_G2_CPU0_G0_TX_DP<7>")
	)
	(arc
		(start 351.409254 -223.078802)
		(mid 351.165927 -222.614236)
		(end 351.409254 -222.14967)
		(width 0.1143)
		(layer "In4.Cu")
		(net "GMI_CPU1_G2_CPU0_G0_TX_DP<7>")
	)
	(arc
		(start 351.479866 -222.108268)
		(mid 351.594376 -221.975033)
		(end 351.635568 -221.80423)
		(width 0.1143)
		(layer "In4.Cu")
		(net "GMI_CPU1_G2_CPU0_G0_TX_DP<7>")
	)
	(arc
		(start 120.017032 -223.119696)
		(mid 119.860055 -223.424496)
		(end 120.017032 -223.729296)
		(width 0.1143)
		(layer "In4.Cu")
		(net "GMI_CPU1_G2_CPU0_G0_TX_DP<7>")
	)
	(arc
		(start 351.409254 -224.698814)
		(mid 351.165927 -224.234248)
		(end 351.409254 -223.769682)
		(width 0.1143)
		(layer "In4.Cu")
		(net "GMI_CPU1_G2_CPU0_G0_TX_DP<7>")
	)
	(arc
		(start 351.47885 -223.729042)
		(mid 351.635827 -223.424242)
		(end 351.47885 -223.119442)
		(width 0.1143)
		(layer "In4.Cu")
		(net "GMI_CPU1_G2_CPU0_G0_TX_DP<7>")
	)
	(arc
		(start 120.086628 -223.769936)
		(mid 120.329955 -224.234502)
		(end 120.086628 -224.699068)
		(width 0.1143)
		(layer "In4.Cu")
		(net "GMI_CPU1_G2_CPU0_G0_TX_DP<7>")
	)
	(segment
		(start 119.767858 -230.170228)
		(end 120.23471 -229.90429)
		(width 0.12954)
		(layer "F.Cu")
		(net "GMI_CPU1_G2_CPU0_G0_TX_DP<6>")
	)
	(segment
		(start 351.728024 -230.169974)
		(end 351.261172 -229.904036)
		(width 0.12954)
		(layer "F.Cu")
		(net "GMI_CPU1_G2_CPU0_G0_TX_DP<6>")
	)
	(segment
		(start 118.167658 -226.34194)
		(end 118.168674 -226.341432)
		(width 0.1143)
		(layer "In4.Cu")
		(net "GMI_CPU1_G2_CPU0_G0_TX_DP<6>")
	)
	(segment
		(start 117.93601 -221.129098)
		(end 117.98173 -221.083378)
		(width 0.1143)
		(layer "In4.Cu")
		(net "GMI_CPU1_G2_CPU0_G0_TX_DP<6>")
	)
	(segment
		(start 353.296728 -225.385122)
		(end 353.295966 -225.38563)
		(width 0.1143)
		(layer "In4.Cu")
		(net "GMI_CPU1_G2_CPU0_G0_TX_DP<6>")
	)
	(segment
		(start 153.77287 -187.118498)
		(end 154.10307 -186.847734)
		(width 0.14224)
		(layer "In4.Cu")
		(net "GMI_CPU1_G2_CPU0_G0_TX_DP<6>")
	)
	(segment
		(start 353.514152 -221.083124)
		(end 353.559872 -221.128844)
		(width 0.1143)
		(layer "In4.Cu")
		(net "GMI_CPU1_G2_CPU0_G0_TX_DP<6>")
	)
	(segment
		(start 118.19509 -227.002848)
		(end 118.194074 -227.00234)
		(width 0.1143)
		(layer "In4.Cu")
		(net "GMI_CPU1_G2_CPU0_G0_TX_DP<6>")
	)
	(segment
		(start 118.167658 -222.127064)
		(end 118.166896 -222.126556)
		(width 0.1143)
		(layer "In4.Cu")
		(net "GMI_CPU1_G2_CPU0_G0_TX_DP<6>")
	)
	(segment
		(start 167.586152 -179.92217)
		(end 302.901096 -180.711348)
		(width 0.14224)
		(layer "In4.Cu")
		(net "GMI_CPU1_G2_CPU0_G0_TX_DP<6>")
	)
	(segment
		(start 146.331178 -193.043302)
		(end 148.210524 -191.502284)
		(width 0.14224)
		(layer "In4.Cu")
		(net "GMI_CPU1_G2_CPU0_G0_TX_DP<6>")
	)
	(segment
		(start 118.135908 -226.360228)
		(end 118.166896 -226.342448)
		(width 0.1143)
		(layer "In4.Cu")
		(net "GMI_CPU1_G2_CPU0_G0_TX_DP<6>")
	)
	(segment
		(start 353.334828 -222.123)
		(end 353.334066 -222.123508)
		(width 0.1143)
		(layer "In4.Cu")
		(net "GMI_CPU1_G2_CPU0_G0_TX_DP<6>")
	)
	(segment
		(start 118.166896 -224.722436)
		(end 118.167658 -224.721928)
		(width 0.1143)
		(layer "In4.Cu")
		(net "GMI_CPU1_G2_CPU0_G0_TX_DP<6>")
	)
	(segment
		(start 353.359974 -225.348546)
		(end 353.330256 -225.365564)
		(width 0.1143)
		(layer "In4.Cu")
		(net "GMI_CPU1_G2_CPU0_G0_TX_DP<6>")
	)
	(segment
		(start 353.359974 -222.108522)
		(end 353.338638 -222.120968)
		(width 0.1143)
		(layer "In4.Cu")
		(net "GMI_CPU1_G2_CPU0_G0_TX_DP<6>")
	)
	(segment
		(start 144.408144 -194.620134)
		(end 146.330924 -193.043302)
		(width 0.14224)
		(layer "In4.Cu")
		(net "GMI_CPU1_G2_CPU0_G0_TX_DP<6>")
	)
	(segment
		(start 150.497286 -189.627002)
		(end 150.827232 -189.356492)
		(width 0.14224)
		(layer "In4.Cu")
		(net "GMI_CPU1_G2_CPU0_G0_TX_DP<6>")
	)
	(segment
		(start 118.157244 -222.121222)
		(end 118.135908 -222.108776)
		(width 0.1143)
		(layer "In4.Cu")
		(net "GMI_CPU1_G2_CPU0_G0_TX_DP<6>")
	)
	(segment
		(start 353.295966 -223.765618)
		(end 353.289108 -223.769682)
		(width 0.1143)
		(layer "In4.Cu")
		(net "GMI_CPU1_G2_CPU0_G0_TX_DP<6>")
	)
	(segment
		(start 309.41137 -181.434486)
		(end 315.531246 -184.898792)
		(width 0.14224)
		(layer "In4.Cu")
		(net "GMI_CPU1_G2_CPU0_G0_TX_DP<6>")
	)
	(segment
		(start 315.531246 -184.898792)
		(end 350.332802 -213.434676)
		(width 0.14224)
		(layer "In4.Cu")
		(net "GMI_CPU1_G2_CPU0_G0_TX_DP<6>")
	)
	(segment
		(start 154.12212 -186.654694)
		(end 154.452066 -186.384184)
		(width 0.14224)
		(layer "In4.Cu")
		(net "GMI_CPU1_G2_CPU0_G0_TX_DP<6>")
	)
	(segment
		(start 152.241758 -188.196474)
		(end 152.571704 -187.925964)
		(width 0.14224)
		(layer "In4.Cu")
		(net "GMI_CPU1_G2_CPU0_G0_TX_DP<6>")
	)
	(segment
		(start 118.170198 -223.100392)
		(end 118.206774 -223.079056)
		(width 0.1143)
		(layer "In4.Cu")
		(net "GMI_CPU1_G2_CPU0_G0_TX_DP<6>")
	)
	(segment
		(start 119.577612 -229.416864)
		(end 119.544084 -229.397306)
		(width 0.1143)
		(layer "In4.Cu")
		(net "GMI_CPU1_G2_CPU0_G0_TX_DP<6>")
	)
	(segment
		(start 353.327208 -224.721166)
		(end 353.328224 -224.721674)
		(width 0.1143)
		(layer "In4.Cu")
		(net "GMI_CPU1_G2_CPU0_G0_TX_DP<6>")
	)
	(segment
		(start 353.328986 -222.126302)
		(end 353.328224 -222.12681)
		(width 0.1143)
		(layer "In4.Cu")
		(net "GMI_CPU1_G2_CPU0_G0_TX_DP<6>")
	)
	(segment
		(start 118.170198 -224.720404)
		(end 118.206774 -224.699068)
		(width 0.1143)
		(layer "In4.Cu")
		(net "GMI_CPU1_G2_CPU0_G0_TX_DP<6>")
	)
	(segment
		(start 353.289108 -224.698814)
		(end 353.325684 -224.72015)
		(width 0.1143)
		(layer "In4.Cu")
		(net "GMI_CPU1_G2_CPU0_G0_TX_DP<6>")
	)
	(segment
		(start 153.113994 -187.48121)
		(end 153.57983 -187.099448)
		(width 0.14224)
		(layer "In4.Cu")
		(net "GMI_CPU1_G2_CPU0_G0_TX_DP<6>")
	)
	(segment
		(start 118.206774 -222.149924)
		(end 118.168674 -222.127572)
		(width 0.1143)
		(layer "In4.Cu")
		(net "GMI_CPU1_G2_CPU0_G0_TX_DP<6>")
	)
	(segment
		(start 118.164102 -222.125032)
		(end 118.16334 -222.124524)
		(width 0.1143)
		(layer "In4.Cu")
		(net "GMI_CPU1_G2_CPU0_G0_TX_DP<6>")
	)
	(segment
		(start 117.98173 -218.864434)
		(end 121.124726 -213.500208)
		(width 0.14224)
		(layer "In4.Cu")
		(net "GMI_CPU1_G2_CPU0_G0_TX_DP<6>")
	)
	(segment
		(start 118.168674 -224.72142)
		(end 118.170198 -224.720404)
		(width 0.1143)
		(layer "In4.Cu")
		(net "GMI_CPU1_G2_CPU0_G0_TX_DP<6>")
	)
	(segment
		(start 150.478236 -189.820042)
		(end 150.497286 -189.627002)
		(width 0.14224)
		(layer "In4.Cu")
		(net "GMI_CPU1_G2_CPU0_G0_TX_DP<6>")
	)
	(segment
		(start 118.170198 -226.340416)
		(end 118.206774 -226.31908)
		(width 0.1143)
		(layer "In4.Cu")
		(net "GMI_CPU1_G2_CPU0_G0_TX_DP<6>")
	)
	(segment
		(start 353.330256 -225.365564)
		(end 353.328986 -225.366326)
		(width 0.1143)
		(layer "In4.Cu")
		(net "GMI_CPU1_G2_CPU0_G0_TX_DP<6>")
	)
	(segment
		(start 353.327208 -222.127318)
		(end 353.289108 -222.14967)
		(width 0.1143)
		(layer "In4.Cu")
		(net "GMI_CPU1_G2_CPU0_G0_TX_DP<6>")
	)
	(segment
		(start 307.388006 -180.711348)
		(end 309.41137 -181.434486)
		(width 0.14224)
		(layer "In4.Cu")
		(net "GMI_CPU1_G2_CPU0_G0_TX_DP<6>")
	)
	(segment
		(start 151.892508 -188.660278)
		(end 152.222708 -188.389514)
		(width 0.14224)
		(layer "In4.Cu")
		(net "GMI_CPU1_G2_CPU0_G0_TX_DP<6>")
	)
	(segment
		(start 353.328986 -226.986338)
		(end 353.328224 -226.986846)
		(width 0.1143)
		(layer "In4.Cu")
		(net "GMI_CPU1_G2_CPU0_G0_TX_DP<6>")
	)
	(segment
		(start 118.166896 -223.746568)
		(end 118.165626 -223.745806)
		(width 0.1143)
		(layer "In4.Cu")
		(net "GMI_CPU1_G2_CPU0_G0_TX_DP<6>")
	)
	(segment
		(start 118.167658 -223.747076)
		(end 118.166896 -223.746568)
		(width 0.1143)
		(layer "In4.Cu")
		(net "GMI_CPU1_G2_CPU0_G0_TX_DP<6>")
	)
	(segment
		(start 353.033076 -227.466906)
		(end 353.033076 -227.494084)
		(width 0.1143)
		(layer "In4.Cu")
		(net "GMI_CPU1_G2_CPU0_G0_TX_DP<6>")
	)
	(segment
		(start 152.222708 -188.389514)
		(end 152.241758 -188.196474)
		(width 0.14224)
		(layer "In4.Cu")
		(net "GMI_CPU1_G2_CPU0_G0_TX_DP<6>")
	)
	(segment
		(start 166.069772 -179.92217)
		(end 167.586152 -179.92217)
		(width 0.14224)
		(layer "In4.Cu")
		(net "GMI_CPU1_G2_CPU0_G0_TX_DP<6>")
	)
	(segment
		(start 118.166896 -226.986592)
		(end 118.165626 -226.98583)
		(width 0.1143)
		(layer "In4.Cu")
		(net "GMI_CPU1_G2_CPU0_G0_TX_DP<6>")
	)
	(segment
		(start 119.145812 -228.62921)
		(end 119.11711 -228.6127)
		(width 0.1143)
		(layer "In4.Cu")
		(net "GMI_CPU1_G2_CPU0_G0_TX_DP<6>")
	)
	(segment
		(start 353.338638 -222.120968)
		(end 353.336098 -222.122238)
		(width 0.1143)
		(layer "In4.Cu")
		(net "GMI_CPU1_G2_CPU0_G0_TX_DP<6>")
	)
	(segment
		(start 353.327208 -223.101154)
		(end 353.328224 -223.101662)
		(width 0.1143)
		(layer "In4.Cu")
		(net "GMI_CPU1_G2_CPU0_G0_TX_DP<6>")
	)
	(segment
		(start 149.954996 -190.071756)
		(end 150.148036 -190.090806)
		(width 0.14224)
		(layer "In4.Cu")
		(net "GMI_CPU1_G2_CPU0_G0_TX_DP<6>")
	)
	(segment
		(start 119.616728 -229.439724)
		(end 119.577612 -229.416864)
		(width 0.1143)
		(layer "In4.Cu")
		(net "GMI_CPU1_G2_CPU0_G0_TX_DP<6>")
	)
	(segment
		(start 118.199154 -225.385376)
		(end 118.167658 -225.367088)
		(width 0.1143)
		(layer "In4.Cu")
		(net "GMI_CPU1_G2_CPU0_G0_TX_DP<6>")
	)
	(segment
		(start 353.328224 -222.12681)
		(end 353.327208 -222.127318)
		(width 0.1143)
		(layer "In4.Cu")
		(net "GMI_CPU1_G2_CPU0_G0_TX_DP<6>")
	)
	(segment
		(start 353.359974 -226.968558)
		(end 353.330256 -226.985576)
		(width 0.1143)
		(layer "In4.Cu")
		(net "GMI_CPU1_G2_CPU0_G0_TX_DP<6>")
	)
	(segment
		(start 148.733764 -191.25057)
		(end 148.752814 -191.05753)
		(width 0.14224)
		(layer "In4.Cu")
		(net "GMI_CPU1_G2_CPU0_G0_TX_DP<6>")
	)
	(segment
		(start 353.325684 -223.100138)
		(end 353.327208 -223.101154)
		(width 0.1143)
		(layer "In4.Cu")
		(net "GMI_CPU1_G2_CPU0_G0_TX_DP<6>")
	)
	(segment
		(start 119.936768 -229.90429)
		(end 119.853964 -229.821486)
		(width 0.1143)
		(layer "In4.Cu")
		(net "GMI_CPU1_G2_CPU0_G0_TX_DP<6>")
	)
	(segment
		(start 353.289108 -226.318826)
		(end 353.325684 -226.340162)
		(width 0.1143)
		(layer "In4.Cu")
		(net "GMI_CPU1_G2_CPU0_G0_TX_DP<6>")
	)
	(segment
		(start 353.328224 -224.721674)
		(end 353.328986 -224.722182)
		(width 0.1143)
		(layer "In4.Cu")
		(net "GMI_CPU1_G2_CPU0_G0_TX_DP<6>")
	)
	(segment
		(start 144.000982 -194.743324)
		(end 144.408144 -194.620134)
		(width 0.14224)
		(layer "In4.Cu")
		(net "GMI_CPU1_G2_CPU0_G0_TX_DP<6>")
	)
	(segment
		(start 353.33178 -222.124778)
		(end 353.328986 -222.126302)
		(width 0.1143)
		(layer "In4.Cu")
		(net "GMI_CPU1_G2_CPU0_G0_TX_DP<6>")
	)
	(segment
		(start 353.359974 -223.728534)
		(end 353.330256 -223.745552)
		(width 0.1143)
		(layer "In4.Cu")
		(net "GMI_CPU1_G2_CPU0_G0_TX_DP<6>")
	)
	(segment
		(start 353.328224 -223.101662)
		(end 353.328986 -223.10217)
		(width 0.1143)
		(layer "In4.Cu")
		(net "GMI_CPU1_G2_CPU0_G0_TX_DP<6>")
	)
	(segment
		(start 353.514152 -218.79306)
		(end 353.514152 -221.083124)
		(width 0.14224)
		(layer "In4.Cu")
		(net "GMI_CPU1_G2_CPU0_G0_TX_DP<6>")
	)
	(segment
		(start 353.296728 -223.76511)
		(end 353.295966 -223.765618)
		(width 0.1143)
		(layer "In4.Cu")
		(net "GMI_CPU1_G2_CPU0_G0_TX_DP<6>")
	)
	(segment
		(start 118.199154 -223.765364)
		(end 118.167658 -223.747076)
		(width 0.1143)
		(layer "In4.Cu")
		(net "GMI_CPU1_G2_CPU0_G0_TX_DP<6>")
	)
	(segment
		(start 118.167658 -224.721928)
		(end 118.168674 -224.72142)
		(width 0.1143)
		(layer "In4.Cu")
		(net "GMI_CPU1_G2_CPU0_G0_TX_DP<6>")
	)
	(segment
		(start 118.166896 -226.342448)
		(end 118.167658 -226.34194)
		(width 0.1143)
		(layer "In4.Cu")
		(net "GMI_CPU1_G2_CPU0_G0_TX_DP<6>")
	)
	(segment
		(start 118.206774 -225.389948)
		(end 118.199916 -225.385884)
		(width 0.1143)
		(layer "In4.Cu")
		(net "GMI_CPU1_G2_CPU0_G0_TX_DP<6>")
	)
	(segment
		(start 353.328224 -226.986846)
		(end 353.301808 -227.002086)
		(width 0.1143)
		(layer "In4.Cu")
		(net "GMI_CPU1_G2_CPU0_G0_TX_DP<6>")
	)
	(segment
		(start 353.328986 -223.746314)
		(end 353.328224 -223.746822)
		(width 0.1143)
		(layer "In4.Cu")
		(net "GMI_CPU1_G2_CPU0_G0_TX_DP<6>")
	)
	(segment
		(start 118.166896 -223.102424)
		(end 118.167658 -223.101916)
		(width 0.1143)
		(layer "In4.Cu")
		(net "GMI_CPU1_G2_CPU0_G0_TX_DP<6>")
	)
	(segment
		(start 353.328986 -225.366326)
		(end 353.328224 -225.366834)
		(width 0.1143)
		(layer "In4.Cu")
		(net "GMI_CPU1_G2_CPU0_G0_TX_DP<6>")
	)
	(segment
		(start 118.168674 -222.127572)
		(end 118.167658 -222.127064)
		(width 0.1143)
		(layer "In4.Cu")
		(net "GMI_CPU1_G2_CPU0_G0_TX_DP<6>")
	)
	(segment
		(start 118.16334 -222.124524)
		(end 118.161816 -222.123762)
		(width 0.1143)
		(layer "In4.Cu")
		(net "GMI_CPU1_G2_CPU0_G0_TX_DP<6>")
	)
	(segment
		(start 352.57613 -228.282754)
		(end 352.57613 -228.284024)
		(width 0.1143)
		(layer "In4.Cu")
		(net "GMI_CPU1_G2_CPU0_G0_TX_DP<6>")
	)
	(segment
		(start 352.378772 -228.612446)
		(end 352.35007 -228.628956)
		(width 0.1143)
		(layer "In4.Cu")
		(net "GMI_CPU1_G2_CPU0_G0_TX_DP<6>")
	)
	(segment
		(start 117.93601 -221.347284)
		(end 117.93601 -221.129098)
		(width 0.1143)
		(layer "In4.Cu")
		(net "GMI_CPU1_G2_CPU0_G0_TX_DP<6>")
	)
	(segment
		(start 153.094944 -187.67425)
		(end 153.113994 -187.48121)
		(width 0.14224)
		(layer "In4.Cu")
		(net "GMI_CPU1_G2_CPU0_G0_TX_DP<6>")
	)
	(segment
		(start 353.327208 -226.341178)
		(end 353.328224 -226.341686)
		(width 0.1143)
		(layer "In4.Cu")
		(net "GMI_CPU1_G2_CPU0_G0_TX_DP<6>")
	)
	(segment
		(start 154.994356 -185.93943)
		(end 159.441896 -182.292244)
		(width 0.14224)
		(layer "In4.Cu")
		(net "GMI_CPU1_G2_CPU0_G0_TX_DP<6>")
	)
	(segment
		(start 118.167658 -225.367088)
		(end 118.166896 -225.36658)
		(width 0.1143)
		(layer "In4.Cu")
		(net "GMI_CPU1_G2_CPU0_G0_TX_DP<6>")
	)
	(segment
		(start 118.161816 -222.123762)
		(end 118.161054 -222.123254)
		(width 0.1143)
		(layer "In4.Cu")
		(net "GMI_CPU1_G2_CPU0_G0_TX_DP<6>")
	)
	(segment
		(start 118.462806 -227.494338)
		(end 118.462806 -227.46716)
		(width 0.1143)
		(layer "In4.Cu")
		(net "GMI_CPU1_G2_CPU0_G0_TX_DP<6>")
	)
	(segment
		(start 120.23471 -229.90429)
		(end 119.936768 -229.90429)
		(width 0.1143)
		(layer "In4.Cu")
		(net "GMI_CPU1_G2_CPU0_G0_TX_DP<6>")
	)
	(segment
		(start 118.166896 -225.36658)
		(end 118.165626 -225.365818)
		(width 0.1143)
		(layer "In4.Cu")
		(net "GMI_CPU1_G2_CPU0_G0_TX_DP<6>")
	)
	(segment
		(start 353.330256 -226.985576)
		(end 353.328986 -226.986338)
		(width 0.1143)
		(layer "In4.Cu")
		(net "GMI_CPU1_G2_CPU0_G0_TX_DP<6>")
	)
	(segment
		(start 353.295966 -225.38563)
		(end 353.289108 -225.389694)
		(width 0.1143)
		(layer "In4.Cu")
		(net "GMI_CPU1_G2_CPU0_G0_TX_DP<6>")
	)
	(segment
		(start 118.159784 -222.122492)
		(end 118.157244 -222.121222)
		(width 0.1143)
		(layer "In4.Cu")
		(net "GMI_CPU1_G2_CPU0_G0_TX_DP<6>")
	)
	(segment
		(start 350.332802 -213.434676)
		(end 353.514152 -218.79306)
		(width 0.14224)
		(layer "In4.Cu")
		(net "GMI_CPU1_G2_CPU0_G0_TX_DP<6>")
	)
	(segment
		(start 149.606 -190.535306)
		(end 149.62505 -190.342266)
		(width 0.14224)
		(layer "In4.Cu")
		(net "GMI_CPU1_G2_CPU0_G0_TX_DP<6>")
	)
	(segment
		(start 353.325684 -224.72015)
		(end 353.327208 -224.721166)
		(width 0.1143)
		(layer "In4.Cu")
		(net "GMI_CPU1_G2_CPU0_G0_TX_DP<6>")
	)
	(segment
		(start 118.167658 -226.9871)
		(end 118.166896 -226.986592)
		(width 0.1143)
		(layer "In4.Cu")
		(net "GMI_CPU1_G2_CPU0_G0_TX_DP<6>")
	)
	(segment
		(start 118.161054 -222.123254)
		(end 118.159784 -222.122492)
		(width 0.1143)
		(layer "In4.Cu")
		(net "GMI_CPU1_G2_CPU0_G0_TX_DP<6>")
	)
	(segment
		(start 118.919752 -228.284278)
		(end 118.919752 -228.283008)
		(width 0.1143)
		(layer "In4.Cu")
		(net "GMI_CPU1_G2_CPU0_G0_TX_DP<6>")
	)
	(segment
		(start 118.168674 -226.341432)
		(end 118.170198 -226.340416)
		(width 0.1143)
		(layer "In4.Cu")
		(net "GMI_CPU1_G2_CPU0_G0_TX_DP<6>")
	)
	(segment
		(start 351.951798 -229.397052)
		(end 351.879154 -229.43947)
		(width 0.1143)
		(layer "In4.Cu")
		(net "GMI_CPU1_G2_CPU0_G0_TX_DP<6>")
	)
	(segment
		(start 353.559872 -221.34703)
		(end 353.51593 -221.390972)
		(width 0.1143)
		(layer "In4.Cu")
		(net "GMI_CPU1_G2_CPU0_G0_TX_DP<6>")
	)
	(segment
		(start 151.020272 -189.375542)
		(end 151.350472 -189.104778)
		(width 0.14224)
		(layer "In4.Cu")
		(net "GMI_CPU1_G2_CPU0_G0_TX_DP<6>")
	)
	(segment
		(start 353.336098 -222.122238)
		(end 353.334828 -222.123)
		(width 0.1143)
		(layer "In4.Cu")
		(net "GMI_CPU1_G2_CPU0_G0_TX_DP<6>")
	)
	(segment
		(start 154.10307 -186.847734)
		(end 154.12212 -186.654694)
		(width 0.14224)
		(layer "In4.Cu")
		(net "GMI_CPU1_G2_CPU0_G0_TX_DP<6>")
	)
	(segment
		(start 353.559872 -221.128844)
		(end 353.559872 -221.34703)
		(width 0.1143)
		(layer "In4.Cu")
		(net "GMI_CPU1_G2_CPU0_G0_TX_DP<6>")
	)
	(segment
		(start 118.135908 -223.120204)
		(end 118.166896 -223.102424)
		(width 0.1143)
		(layer "In4.Cu")
		(net "GMI_CPU1_G2_CPU0_G0_TX_DP<6>")
	)
	(segment
		(start 117.979952 -221.804484)
		(end 117.979952 -221.391226)
		(width 0.1143)
		(layer "In4.Cu")
		(net "GMI_CPU1_G2_CPU0_G0_TX_DP<6>")
	)
	(segment
		(start 148.752814 -191.05753)
		(end 149.08276 -190.78702)
		(width 0.14224)
		(layer "In4.Cu")
		(net "GMI_CPU1_G2_CPU0_G0_TX_DP<6>")
	)
	(segment
		(start 353.29749 -227.004626)
		(end 353.295966 -227.005642)
		(width 0.1143)
		(layer "In4.Cu")
		(net "GMI_CPU1_G2_CPU0_G0_TX_DP<6>")
	)
	(segment
		(start 118.165626 -226.98583)
		(end 118.135908 -226.968812)
		(width 0.1143)
		(layer "In4.Cu")
		(net "GMI_CPU1_G2_CPU0_G0_TX_DP<6>")
	)
	(segment
		(start 353.328986 -224.722182)
		(end 353.359974 -224.739962)
		(width 0.1143)
		(layer "In4.Cu")
		(net "GMI_CPU1_G2_CPU0_G0_TX_DP<6>")
	)
	(segment
		(start 353.328224 -226.341686)
		(end 353.328986 -226.342194)
		(width 0.1143)
		(layer "In4.Cu")
		(net "GMI_CPU1_G2_CPU0_G0_TX_DP<6>")
	)
	(segment
		(start 118.650512 -227.817172)
		(end 118.618762 -227.798376)
		(width 0.1143)
		(layer "In4.Cu")
		(net "GMI_CPU1_G2_CPU0_G0_TX_DP<6>")
	)
	(segment
		(start 118.199916 -223.765872)
		(end 118.199154 -223.765364)
		(width 0.1143)
		(layer "In4.Cu")
		(net "GMI_CPU1_G2_CPU0_G0_TX_DP<6>")
	)
	(segment
		(start 154.452066 -186.384184)
		(end 154.645106 -186.403234)
		(width 0.14224)
		(layer "In4.Cu")
		(net "GMI_CPU1_G2_CPU0_G0_TX_DP<6>")
	)
	(segment
		(start 148.403564 -191.521334)
		(end 148.733764 -191.25057)
		(width 0.14224)
		(layer "In4.Cu")
		(net "GMI_CPU1_G2_CPU0_G0_TX_DP<6>")
	)
	(segment
		(start 118.135908 -224.740216)
		(end 118.166896 -224.722436)
		(width 0.1143)
		(layer "In4.Cu")
		(net "GMI_CPU1_G2_CPU0_G0_TX_DP<6>")
	)
	(segment
		(start 117.979952 -221.391226)
		(end 117.93601 -221.347284)
		(width 0.1143)
		(layer "In4.Cu")
		(net "GMI_CPU1_G2_CPU0_G0_TX_DP<6>")
	)
	(segment
		(start 118.199916 -227.005896)
		(end 118.198392 -227.00488)
		(width 0.1143)
		(layer "In4.Cu")
		(net "GMI_CPU1_G2_CPU0_G0_TX_DP<6>")
	)
	(segment
		(start 118.168674 -223.101408)
		(end 118.170198 -223.100392)
		(width 0.1143)
		(layer "In4.Cu")
		(net "GMI_CPU1_G2_CPU0_G0_TX_DP<6>")
	)
	(segment
		(start 151.699468 -188.641228)
		(end 151.892508 -188.660278)
		(width 0.14224)
		(layer "In4.Cu")
		(net "GMI_CPU1_G2_CPU0_G0_TX_DP<6>")
	)
	(segment
		(start 118.167658 -223.101916)
		(end 118.168674 -223.101408)
		(width 0.1143)
		(layer "In4.Cu")
		(net "GMI_CPU1_G2_CPU0_G0_TX_DP<6>")
	)
	(segment
		(start 118.165626 -223.745806)
		(end 118.135908 -223.728788)
		(width 0.1143)
		(layer "In4.Cu")
		(net "GMI_CPU1_G2_CPU0_G0_TX_DP<6>")
	)
	(segment
		(start 353.289108 -223.078802)
		(end 353.325684 -223.100138)
		(width 0.1143)
		(layer "In4.Cu")
		(net "GMI_CPU1_G2_CPU0_G0_TX_DP<6>")
	)
	(segment
		(start 353.330256 -223.745552)
		(end 353.328986 -223.746314)
		(width 0.1143)
		(layer "In4.Cu")
		(net "GMI_CPU1_G2_CPU0_G0_TX_DP<6>")
	)
	(segment
		(start 353.334066 -222.123508)
		(end 353.332542 -222.12427)
		(width 0.1143)
		(layer "In4.Cu")
		(net "GMI_CPU1_G2_CPU0_G0_TX_DP<6>")
	)
	(segment
		(start 117.98173 -221.05493)
		(end 117.98173 -218.864434)
		(width 0.14224)
		(layer "In4.Cu")
		(net "GMI_CPU1_G2_CPU0_G0_TX_DP<6>")
	)
	(segment
		(start 353.332542 -222.12427)
		(end 353.33178 -222.124778)
		(width 0.1143)
		(layer "In4.Cu")
		(net "GMI_CPU1_G2_CPU0_G0_TX_DP<6>")
	)
	(segment
		(start 118.198392 -227.00488)
		(end 118.19509 -227.002848)
		(width 0.1143)
		(layer "In4.Cu")
		(net "GMI_CPU1_G2_CPU0_G0_TX_DP<6>")
	)
	(segment
		(start 121.124726 -213.500208)
		(end 144.000982 -194.743324)
		(width 0.14224)
		(layer "In4.Cu")
		(net "GMI_CPU1_G2_CPU0_G0_TX_DP<6>")
	)
	(segment
		(start 118.206774 -223.769936)
		(end 118.199916 -223.765872)
		(width 0.1143)
		(layer "In4.Cu")
		(net "GMI_CPU1_G2_CPU0_G0_TX_DP<6>")
	)
	(segment
		(start 150.148036 -190.090806)
		(end 150.478236 -189.820042)
		(width 0.14224)
		(layer "In4.Cu")
		(net "GMI_CPU1_G2_CPU0_G0_TX_DP<6>")
	)
	(segment
		(start 117.98173 -221.083378)
		(end 117.98173 -221.05493)
		(width 0.1143)
		(layer "In4.Cu")
		(net "GMI_CPU1_G2_CPU0_G0_TX_DP<6>")
	)
	(segment
		(start 149.2758 -190.80607)
		(end 149.606 -190.535306)
		(width 0.14224)
		(layer "In4.Cu")
		(net "GMI_CPU1_G2_CPU0_G0_TX_DP<6>")
	)
	(segment
		(start 149.08276 -190.78702)
		(end 149.2758 -190.80607)
		(width 0.14224)
		(layer "In4.Cu")
		(net "GMI_CPU1_G2_CPU0_G0_TX_DP<6>")
	)
	(segment
		(start 351.641918 -229.821232)
		(end 351.559114 -229.904036)
		(width 0.1143)
		(layer "In4.Cu")
		(net "GMI_CPU1_G2_CPU0_G0_TX_DP<6>")
	)
	(segment
		(start 151.369522 -188.911738)
		(end 151.699468 -188.641228)
		(width 0.14224)
		(layer "In4.Cu")
		(net "GMI_CPU1_G2_CPU0_G0_TX_DP<6>")
	)
	(segment
		(start 353.51593 -221.390972)
		(end 353.51593 -221.80423)
		(width 0.1143)
		(layer "In4.Cu")
		(net "GMI_CPU1_G2_CPU0_G0_TX_DP<6>")
	)
	(segment
		(start 150.827232 -189.356492)
		(end 151.020272 -189.375542)
		(width 0.14224)
		(layer "In4.Cu")
		(net "GMI_CPU1_G2_CPU0_G0_TX_DP<6>")
	)
	(segment
		(start 159.441896 -182.292244)
		(end 166.069772 -179.92217)
		(width 0.14224)
		(layer "In4.Cu")
		(net "GMI_CPU1_G2_CPU0_G0_TX_DP<6>")
	)
	(segment
		(start 148.210524 -191.502284)
		(end 148.403564 -191.521334)
		(width 0.14224)
		(layer "In4.Cu")
		(net "GMI_CPU1_G2_CPU0_G0_TX_DP<6>")
	)
	(segment
		(start 353.328224 -223.746822)
		(end 353.296728 -223.76511)
		(width 0.1143)
		(layer "In4.Cu")
		(net "GMI_CPU1_G2_CPU0_G0_TX_DP<6>")
	)
	(segment
		(start 351.559114 -229.904036)
		(end 351.261172 -229.904036)
		(width 0.1143)
		(layer "In4.Cu")
		(net "GMI_CPU1_G2_CPU0_G0_TX_DP<6>")
	)
	(segment
		(start 118.165626 -225.365818)
		(end 118.135908 -225.3488)
		(width 0.1143)
		(layer "In4.Cu")
		(net "GMI_CPU1_G2_CPU0_G0_TX_DP<6>")
	)
	(segment
		(start 146.330924 -193.043302)
		(end 146.331178 -193.043302)
		(width 0.14224)
		(layer "In4.Cu")
		(net "GMI_CPU1_G2_CPU0_G0_TX_DP<6>")
	)
	(segment
		(start 353.328224 -225.366834)
		(end 353.296728 -225.385122)
		(width 0.1143)
		(layer "In4.Cu")
		(net "GMI_CPU1_G2_CPU0_G0_TX_DP<6>")
	)
	(segment
		(start 118.194074 -227.00234)
		(end 118.167658 -226.9871)
		(width 0.1143)
		(layer "In4.Cu")
		(net "GMI_CPU1_G2_CPU0_G0_TX_DP<6>")
	)
	(segment
		(start 302.901096 -180.711348)
		(end 307.388006 -180.711348)
		(width 0.14224)
		(layer "In4.Cu")
		(net "GMI_CPU1_G2_CPU0_G0_TX_DP<6>")
	)
	(segment
		(start 153.57983 -187.099448)
		(end 153.77287 -187.118498)
		(width 0.14224)
		(layer "In4.Cu")
		(net "GMI_CPU1_G2_CPU0_G0_TX_DP<6>")
	)
	(segment
		(start 149.62505 -190.342266)
		(end 149.954996 -190.071756)
		(width 0.14224)
		(layer "In4.Cu")
		(net "GMI_CPU1_G2_CPU0_G0_TX_DP<6>")
	)
	(segment
		(start 353.328986 -226.342194)
		(end 353.359974 -226.359974)
		(width 0.1143)
		(layer "In4.Cu")
		(net "GMI_CPU1_G2_CPU0_G0_TX_DP<6>")
	)
	(segment
		(start 118.199916 -225.385884)
		(end 118.199154 -225.385376)
		(width 0.1143)
		(layer "In4.Cu")
		(net "GMI_CPU1_G2_CPU0_G0_TX_DP<6>")
	)
	(segment
		(start 353.300792 -227.002594)
		(end 353.29749 -227.004626)
		(width 0.1143)
		(layer "In4.Cu")
		(net "GMI_CPU1_G2_CPU0_G0_TX_DP<6>")
	)
	(segment
		(start 154.645106 -186.403234)
		(end 154.975306 -186.13247)
		(width 0.14224)
		(layer "In4.Cu")
		(net "GMI_CPU1_G2_CPU0_G0_TX_DP<6>")
	)
	(segment
		(start 353.328986 -223.10217)
		(end 353.359974 -223.11995)
		(width 0.1143)
		(layer "In4.Cu")
		(net "GMI_CPU1_G2_CPU0_G0_TX_DP<6>")
	)
	(segment
		(start 152.571704 -187.925964)
		(end 152.764744 -187.945014)
		(width 0.14224)
		(layer "In4.Cu")
		(net "GMI_CPU1_G2_CPU0_G0_TX_DP<6>")
	)
	(segment
		(start 151.350472 -189.104778)
		(end 151.369522 -188.911738)
		(width 0.14224)
		(layer "In4.Cu")
		(net "GMI_CPU1_G2_CPU0_G0_TX_DP<6>")
	)
	(segment
		(start 353.325684 -226.340162)
		(end 353.327208 -226.341178)
		(width 0.1143)
		(layer "In4.Cu")
		(net "GMI_CPU1_G2_CPU0_G0_TX_DP<6>")
	)
	(segment
		(start 352.87712 -227.798122)
		(end 352.84537 -227.816918)
		(width 0.1143)
		(layer "In4.Cu")
		(net "GMI_CPU1_G2_CPU0_G0_TX_DP<6>")
	)
	(segment
		(start 118.166896 -222.126556)
		(end 118.164102 -222.125032)
		(width 0.1143)
		(layer "In4.Cu")
		(net "GMI_CPU1_G2_CPU0_G0_TX_DP<6>")
	)
	(segment
		(start 353.301808 -227.002086)
		(end 353.300792 -227.002594)
		(width 0.1143)
		(layer "In4.Cu")
		(net "GMI_CPU1_G2_CPU0_G0_TX_DP<6>")
	)
	(segment
		(start 154.975306 -186.13247)
		(end 154.994356 -185.93943)
		(width 0.14224)
		(layer "In4.Cu")
		(net "GMI_CPU1_G2_CPU0_G0_TX_DP<6>")
	)
	(segment
		(start 152.764744 -187.945014)
		(end 153.094944 -187.67425)
		(width 0.14224)
		(layer "In4.Cu")
		(net "GMI_CPU1_G2_CPU0_G0_TX_DP<6>")
	)
	(arc
		(start 118.206774 -223.079056)
		(mid 118.450101 -222.61449)
		(end 118.206774 -222.149924)
		(width 0.1143)
		(layer "In4.Cu")
		(net "GMI_CPU1_G2_CPU0_G0_TX_DP<6>")
	)
	(arc
		(start 353.359974 -223.11995)
		(mid 353.515902 -223.424242)
		(end 353.359974 -223.728534)
		(width 0.1143)
		(layer "In4.Cu")
		(net "GMI_CPU1_G2_CPU0_G0_TX_DP<6>")
	)
	(arc
		(start 352.410776 -228.593396)
		(mid 352.395013 -228.603323)
		(end 352.378772 -228.612446)
		(width 0.1143)
		(layer "In4.Cu")
		(net "GMI_CPU1_G2_CPU0_G0_TX_DP<6>")
	)
	(arc
		(start 352.57613 -228.284024)
		(mid 352.532273 -228.459474)
		(end 352.410776 -228.593396)
		(width 0.1143)
		(layer "In4.Cu")
		(net "GMI_CPU1_G2_CPU0_G0_TX_DP<6>")
	)
	(arc
		(start 353.51593 -221.80423)
		(mid 353.474675 -221.975201)
		(end 353.359974 -222.108522)
		(width 0.1143)
		(layer "In4.Cu")
		(net "GMI_CPU1_G2_CPU0_G0_TX_DP<6>")
	)
	(arc
		(start 352.84537 -227.816918)
		(mid 352.64887 -228.014083)
		(end 352.57613 -228.282754)
		(width 0.1143)
		(layer "In4.Cu")
		(net "GMI_CPU1_G2_CPU0_G0_TX_DP<6>")
	)
	(arc
		(start 351.879154 -229.43947)
		(mid 351.727167 -229.595978)
		(end 351.645728 -229.798372)
		(width 0.1143)
		(layer "In4.Cu")
		(net "GMI_CPU1_G2_CPU0_G0_TX_DP<6>")
	)
	(arc
		(start 118.135908 -223.728788)
		(mid 117.97998 -223.424496)
		(end 118.135908 -223.120204)
		(width 0.1143)
		(layer "In4.Cu")
		(net "GMI_CPU1_G2_CPU0_G0_TX_DP<6>")
	)
	(arc
		(start 352.35007 -228.628956)
		(mid 352.170725 -228.831559)
		(end 352.105976 -229.094284)
		(width 0.1143)
		(layer "In4.Cu")
		(net "GMI_CPU1_G2_CPU0_G0_TX_DP<6>")
	)
	(arc
		(start 119.544084 -229.397306)
		(mid 119.430677 -229.264417)
		(end 119.389906 -229.094538)
		(width 0.1143)
		(layer "In4.Cu")
		(net "GMI_CPU1_G2_CPU0_G0_TX_DP<6>")
	)
	(arc
		(start 118.206774 -226.31908)
		(mid 118.450101 -225.854514)
		(end 118.206774 -225.389948)
		(width 0.1143)
		(layer "In4.Cu")
		(net "GMI_CPU1_G2_CPU0_G0_TX_DP<6>")
	)
	(arc
		(start 353.289108 -225.389694)
		(mid 353.045781 -225.85426)
		(end 353.289108 -226.318826)
		(width 0.1143)
		(layer "In4.Cu")
		(net "GMI_CPU1_G2_CPU0_G0_TX_DP<6>")
	)
	(arc
		(start 118.135908 -222.108776)
		(mid 118.021232 -221.975442)
		(end 117.979952 -221.804484)
		(width 0.1143)
		(layer "In4.Cu")
		(net "GMI_CPU1_G2_CPU0_G0_TX_DP<6>")
	)
	(arc
		(start 118.206774 -224.699068)
		(mid 118.450101 -224.234502)
		(end 118.206774 -223.769936)
		(width 0.1143)
		(layer "In4.Cu")
		(net "GMI_CPU1_G2_CPU0_G0_TX_DP<6>")
	)
	(arc
		(start 119.389906 -229.094538)
		(mid 119.325184 -228.831799)
		(end 119.145812 -228.62921)
		(width 0.1143)
		(layer "In4.Cu")
		(net "GMI_CPU1_G2_CPU0_G0_TX_DP<6>")
	)
	(arc
		(start 353.359974 -226.359974)
		(mid 353.515902 -226.664266)
		(end 353.359974 -226.968558)
		(width 0.1143)
		(layer "In4.Cu")
		(net "GMI_CPU1_G2_CPU0_G0_TX_DP<6>")
	)
	(arc
		(start 118.618762 -227.798376)
		(mid 118.504086 -227.665185)
		(end 118.462806 -227.494338)
		(width 0.1143)
		(layer "In4.Cu")
		(net "GMI_CPU1_G2_CPU0_G0_TX_DP<6>")
	)
	(arc
		(start 353.033076 -227.494084)
		(mid 352.991817 -227.664941)
		(end 352.87712 -227.798122)
		(width 0.1143)
		(layer "In4.Cu")
		(net "GMI_CPU1_G2_CPU0_G0_TX_DP<6>")
	)
	(arc
		(start 353.359974 -224.739962)
		(mid 353.515902 -225.044254)
		(end 353.359974 -225.348546)
		(width 0.1143)
		(layer "In4.Cu")
		(net "GMI_CPU1_G2_CPU0_G0_TX_DP<6>")
	)
	(arc
		(start 118.135908 -226.968812)
		(mid 117.97998 -226.66452)
		(end 118.135908 -226.360228)
		(width 0.1143)
		(layer "In4.Cu")
		(net "GMI_CPU1_G2_CPU0_G0_TX_DP<6>")
	)
	(arc
		(start 353.289108 -222.14967)
		(mid 353.045781 -222.614236)
		(end 353.289108 -223.078802)
		(width 0.1143)
		(layer "In4.Cu")
		(net "GMI_CPU1_G2_CPU0_G0_TX_DP<6>")
	)
	(arc
		(start 353.289108 -223.769682)
		(mid 353.045781 -224.234248)
		(end 353.289108 -224.698814)
		(width 0.1143)
		(layer "In4.Cu")
		(net "GMI_CPU1_G2_CPU0_G0_TX_DP<6>")
	)
	(arc
		(start 119.11711 -228.6127)
		(mid 118.972857 -228.475883)
		(end 118.919752 -228.284278)
		(width 0.1143)
		(layer "In4.Cu")
		(net "GMI_CPU1_G2_CPU0_G0_TX_DP<6>")
	)
	(arc
		(start 118.919752 -228.283008)
		(mid 118.846945 -228.014376)
		(end 118.650512 -227.817172)
		(width 0.1143)
		(layer "In4.Cu")
		(net "GMI_CPU1_G2_CPU0_G0_TX_DP<6>")
	)
	(arc
		(start 353.295966 -227.005642)
		(mid 353.103442 -227.201456)
		(end 353.033076 -227.466906)
		(width 0.1143)
		(layer "In4.Cu")
		(net "GMI_CPU1_G2_CPU0_G0_TX_DP<6>")
	)
	(arc
		(start 118.462806 -227.46716)
		(mid 118.392476 -227.20169)
		(end 118.199916 -227.005896)
		(width 0.1143)
		(layer "In4.Cu")
		(net "GMI_CPU1_G2_CPU0_G0_TX_DP<6>")
	)
	(arc
		(start 352.105976 -229.094284)
		(mid 352.065214 -229.264168)
		(end 351.951798 -229.397052)
		(width 0.1143)
		(layer "In4.Cu")
		(net "GMI_CPU1_G2_CPU0_G0_TX_DP<6>")
	)
	(arc
		(start 118.135908 -225.3488)
		(mid 117.97998 -225.044508)
		(end 118.135908 -224.740216)
		(width 0.1143)
		(layer "In4.Cu")
		(net "GMI_CPU1_G2_CPU0_G0_TX_DP<6>")
	)
	(arc
		(start 119.853964 -229.821486)
		(mid 119.774885 -229.606041)
		(end 119.616728 -229.439724)
		(width 0.1143)
		(layer "In4.Cu")
		(net "GMI_CPU1_G2_CPU0_G0_TX_DP<6>")
	)
	(arc
		(start 351.645728 -229.798372)
		(mid 351.643705 -229.809782)
		(end 351.641918 -229.821232)
		(width 0.1143)
		(layer "In4.Cu")
		(net "GMI_CPU1_G2_CPU0_G0_TX_DP<6>")
	)
	(segment
		(start 354.547932 -228.550216)
		(end 354.08108 -228.284278)
		(width 0.12954)
		(layer "F.Cu")
		(net "GMI_CPU1_G2_CPU0_G0_TX_DP<5>")
	)
	(segment
		(start 116.94795 -228.55047)
		(end 117.414802 -228.284532)
		(width 0.12954)
		(layer "F.Cu")
		(net "GMI_CPU1_G2_CPU0_G0_TX_DP<5>")
	)
	(segment
		(start 151.721566 -185.834528)
		(end 152.051512 -185.564018)
		(width 0.14224)
		(layer "In4.Cu")
		(net "GMI_CPU1_G2_CPU0_G0_TX_DP<5>")
	)
	(segment
		(start 310.023256 -179.624482)
		(end 316.53861 -183.312816)
		(width 0.14224)
		(layer "In4.Cu")
		(net "GMI_CPU1_G2_CPU0_G0_TX_DP<5>")
	)
	(segment
		(start 149.104858 -187.98032)
		(end 149.434804 -187.70981)
		(width 0.14224)
		(layer "In4.Cu")
		(net "GMI_CPU1_G2_CPU0_G0_TX_DP<5>")
	)
	(segment
		(start 116.04625 -221.347284)
		(end 116.04625 -221.129098)
		(width 0.1143)
		(layer "In4.Cu")
		(net "GMI_CPU1_G2_CPU0_G0_TX_DP<5>")
	)
	(segment
		(start 150.30704 -186.994546)
		(end 150.50008 -187.01385)
		(width 0.14224)
		(layer "In4.Cu")
		(net "GMI_CPU1_G2_CPU0_G0_TX_DP<5>")
	)
	(segment
		(start 116.256054 -223.120204)
		(end 116.287804 -223.101916)
		(width 0.1143)
		(layer "In4.Cu")
		(net "GMI_CPU1_G2_CPU0_G0_TX_DP<5>")
	)
	(segment
		(start 354.461826 -228.201474)
		(end 354.379022 -228.284278)
		(width 0.1143)
		(layer "In4.Cu")
		(net "GMI_CPU1_G2_CPU0_G0_TX_DP<5>")
	)
	(segment
		(start 152.051512 -185.564018)
		(end 152.244552 -185.583322)
		(width 0.14224)
		(layer "In4.Cu")
		(net "GMI_CPU1_G2_CPU0_G0_TX_DP<5>")
	)
	(segment
		(start 116.287804 -225.367088)
		(end 116.256054 -225.3488)
		(width 0.1143)
		(layer "In4.Cu")
		(net "GMI_CPU1_G2_CPU0_G0_TX_DP<5>")
	)
	(segment
		(start 355.207824 -223.747076)
		(end 355.168962 -223.769428)
		(width 0.1143)
		(layer "In4.Cu")
		(net "GMI_CPU1_G2_CPU0_G0_TX_DP<5>")
	)
	(segment
		(start 116.100098 -221.401132)
		(end 116.04625 -221.347284)
		(width 0.1143)
		(layer "In4.Cu")
		(net "GMI_CPU1_G2_CPU0_G0_TX_DP<5>")
	)
	(segment
		(start 116.09197 -218.226386)
		(end 119.768874 -212.033866)
		(width 0.14224)
		(layer "In4.Cu")
		(net "GMI_CPU1_G2_CPU0_G0_TX_DP<5>")
	)
	(segment
		(start 116.324126 -222.148146)
		(end 116.287804 -222.127064)
		(width 0.1143)
		(layer "In4.Cu")
		(net "GMI_CPU1_G2_CPU0_G0_TX_DP<5>")
	)
	(segment
		(start 355.449632 -221.34703)
		(end 355.395784 -221.400878)
		(width 0.1143)
		(layer "In4.Cu")
		(net "GMI_CPU1_G2_CPU0_G0_TX_DP<5>")
	)
	(segment
		(start 116.582698 -227.496624)
		(end 116.582698 -227.484178)
		(width 0.1143)
		(layer "In4.Cu")
		(net "GMI_CPU1_G2_CPU0_G0_TX_DP<5>")
	)
	(segment
		(start 116.789962 -227.815902)
		(end 116.7892 -227.815394)
		(width 0.1143)
		(layer "In4.Cu")
		(net "GMI_CPU1_G2_CPU0_G0_TX_DP<5>")
	)
	(segment
		(start 116.256054 -223.728534)
		(end 116.256054 -223.728788)
		(width 0.1143)
		(layer "In4.Cu")
		(net "GMI_CPU1_G2_CPU0_G0_TX_DP<5>")
	)
	(segment
		(start 351.769172 -212.20049)
		(end 355.403912 -218.32189)
		(width 0.14224)
		(layer "In4.Cu")
		(net "GMI_CPU1_G2_CPU0_G0_TX_DP<5>")
	)
	(segment
		(start 146.48815 -190.125604)
		(end 146.818096 -189.855094)
		(width 0.14224)
		(layer "In4.Cu")
		(net "GMI_CPU1_G2_CPU0_G0_TX_DP<5>")
	)
	(segment
		(start 147.883372 -189.159134)
		(end 148.213572 -188.88837)
		(width 0.14224)
		(layer "In4.Cu")
		(net "GMI_CPU1_G2_CPU0_G0_TX_DP<5>")
	)
	(segment
		(start 355.208078 -225.366834)
		(end 355.171756 -225.387916)
		(width 0.1143)
		(layer "In4.Cu")
		(net "GMI_CPU1_G2_CPU0_G0_TX_DP<5>")
	)
	(segment
		(start 116.09197 -221.05493)
		(end 116.09197 -218.226386)
		(width 0.14224)
		(layer "In4.Cu")
		(net "GMI_CPU1_G2_CPU0_G0_TX_DP<5>")
	)
	(segment
		(start 116.100098 -221.804484)
		(end 116.100098 -221.401132)
		(width 0.1143)
		(layer "In4.Cu")
		(net "GMI_CPU1_G2_CPU0_G0_TX_DP<5>")
	)
	(segment
		(start 116.756942 -227.796598)
		(end 116.754148 -227.795328)
		(width 0.1143)
		(layer "In4.Cu")
		(net "GMI_CPU1_G2_CPU0_G0_TX_DP<5>")
	)
	(segment
		(start 354.737162 -227.79736)
		(end 354.735638 -227.798376)
		(width 0.1143)
		(layer "In4.Cu")
		(net "GMI_CPU1_G2_CPU0_G0_TX_DP<5>")
	)
	(segment
		(start 354.913184 -227.483924)
		(end 354.913184 -227.49637)
		(width 0.1143)
		(layer "In4.Cu")
		(net "GMI_CPU1_G2_CPU0_G0_TX_DP<5>")
	)
	(segment
		(start 149.958044 -187.458096)
		(end 149.977094 -187.265056)
		(width 0.14224)
		(layer "In4.Cu")
		(net "GMI_CPU1_G2_CPU0_G0_TX_DP<5>")
	)
	(segment
		(start 116.256054 -226.360228)
		(end 116.287804 -226.34194)
		(width 0.1143)
		(layer "In4.Cu")
		(net "GMI_CPU1_G2_CPU0_G0_TX_DP<5>")
	)
	(segment
		(start 167.287448 -178.040284)
		(end 167.287702 -178.040538)
		(width 0.14224)
		(layer "In4.Cu")
		(net "GMI_CPU1_G2_CPU0_G0_TX_DP<5>")
	)
	(segment
		(start 152.574752 -185.312304)
		(end 152.593802 -185.119518)
		(width 0.14224)
		(layer "In4.Cu")
		(net "GMI_CPU1_G2_CPU0_G0_TX_DP<5>")
	)
	(segment
		(start 117.414802 -228.284532)
		(end 117.11686 -228.284532)
		(width 0.1143)
		(layer "In4.Cu")
		(net "GMI_CPU1_G2_CPU0_G0_TX_DP<5>")
	)
	(segment
		(start 354.742242 -227.79482)
		(end 354.741734 -227.795074)
		(width 0.1143)
		(layer "In4.Cu")
		(net "GMI_CPU1_G2_CPU0_G0_TX_DP<5>")
	)
	(segment
		(start 355.208078 -223.101662)
		(end 355.239828 -223.11995)
		(width 0.1143)
		(layer "In4.Cu")
		(net "GMI_CPU1_G2_CPU0_G0_TX_DP<5>")
	)
	(segment
		(start 147.011136 -189.874144)
		(end 147.341336 -189.60338)
		(width 0.14224)
		(layer "In4.Cu")
		(net "GMI_CPU1_G2_CPU0_G0_TX_DP<5>")
	)
	(segment
		(start 116.287804 -222.127064)
		(end 116.256054 -222.108776)
		(width 0.1143)
		(layer "In4.Cu")
		(net "GMI_CPU1_G2_CPU0_G0_TX_DP<5>")
	)
	(segment
		(start 148.213572 -188.88837)
		(end 148.232622 -188.69533)
		(width 0.14224)
		(layer "In4.Cu")
		(net "GMI_CPU1_G2_CPU0_G0_TX_DP<5>")
	)
	(segment
		(start 150.83028 -186.742832)
		(end 150.84933 -186.549792)
		(width 0.14224)
		(layer "In4.Cu")
		(net "GMI_CPU1_G2_CPU0_G0_TX_DP<5>")
	)
	(segment
		(start 116.09197 -221.083378)
		(end 116.09197 -221.05493)
		(width 0.1143)
		(layer "In4.Cu")
		(net "GMI_CPU1_G2_CPU0_G0_TX_DP<5>")
	)
	(segment
		(start 302.907192 -178.831748)
		(end 307.805836 -178.831748)
		(width 0.14224)
		(layer "In4.Cu")
		(net "GMI_CPU1_G2_CPU0_G0_TX_DP<5>")
	)
	(segment
		(start 146.4691 -190.318644)
		(end 146.48815 -190.125604)
		(width 0.14224)
		(layer "In4.Cu")
		(net "GMI_CPU1_G2_CPU0_G0_TX_DP<5>")
	)
	(segment
		(start 116.79682 -227.819966)
		(end 116.789962 -227.815902)
		(width 0.1143)
		(layer "In4.Cu")
		(net "GMI_CPU1_G2_CPU0_G0_TX_DP<5>")
	)
	(segment
		(start 167.287702 -178.040538)
		(end 167.323262 -178.040538)
		(width 0.14224)
		(layer "In4.Cu")
		(net "GMI_CPU1_G2_CPU0_G0_TX_DP<5>")
	)
	(segment
		(start 355.403912 -218.32189)
		(end 355.403912 -221.083124)
		(width 0.14224)
		(layer "In4.Cu")
		(net "GMI_CPU1_G2_CPU0_G0_TX_DP<5>")
	)
	(segment
		(start 146.818096 -189.855094)
		(end 147.011136 -189.874144)
		(width 0.14224)
		(layer "In4.Cu")
		(net "GMI_CPU1_G2_CPU0_G0_TX_DP<5>")
	)
	(segment
		(start 149.085808 -188.17336)
		(end 149.104858 -187.98032)
		(width 0.14224)
		(layer "In4.Cu")
		(net "GMI_CPU1_G2_CPU0_G0_TX_DP<5>")
	)
	(segment
		(start 354.73894 -227.796344)
		(end 354.738178 -227.796852)
		(width 0.1143)
		(layer "In4.Cu")
		(net "GMI_CPU1_G2_CPU0_G0_TX_DP<5>")
	)
	(segment
		(start 355.239828 -223.72828)
		(end 355.223826 -223.737424)
		(width 0.1143)
		(layer "In4.Cu")
		(net "GMI_CPU1_G2_CPU0_G0_TX_DP<5>")
	)
	(segment
		(start 167.323262 -178.040538)
		(end 302.907192 -178.831748)
		(width 0.14224)
		(layer "In4.Cu")
		(net "GMI_CPU1_G2_CPU0_G0_TX_DP<5>")
	)
	(segment
		(start 151.179276 -186.279282)
		(end 151.372316 -186.298586)
		(width 0.14224)
		(layer "In4.Cu")
		(net "GMI_CPU1_G2_CPU0_G0_TX_DP<5>")
	)
	(segment
		(start 148.232622 -188.69533)
		(end 148.562568 -188.42482)
		(width 0.14224)
		(layer "In4.Cu")
		(net "GMI_CPU1_G2_CPU0_G0_TX_DP<5>")
	)
	(segment
		(start 149.627844 -187.729114)
		(end 149.958044 -187.458096)
		(width 0.14224)
		(layer "In4.Cu")
		(net "GMI_CPU1_G2_CPU0_G0_TX_DP<5>")
	)
	(segment
		(start 355.168962 -223.769428)
		(end 355.141276 -223.789494)
		(width 0.1143)
		(layer "In4.Cu")
		(net "GMI_CPU1_G2_CPU0_G0_TX_DP<5>")
	)
	(segment
		(start 116.299996 -226.994466)
		(end 116.256054 -226.968558)
		(width 0.1143)
		(layer "In4.Cu")
		(net "GMI_CPU1_G2_CPU0_G0_TX_DP<5>")
	)
	(segment
		(start 316.53861 -183.312816)
		(end 351.769172 -212.20049)
		(width 0.14224)
		(layer "In4.Cu")
		(net "GMI_CPU1_G2_CPU0_G0_TX_DP<5>")
	)
	(segment
		(start 355.168962 -224.699068)
		(end 355.239828 -224.739962)
		(width 0.1143)
		(layer "In4.Cu")
		(net "GMI_CPU1_G2_CPU0_G0_TX_DP<5>")
	)
	(segment
		(start 152.593802 -185.119518)
		(end 157.824932 -180.830728)
		(width 0.14224)
		(layer "In4.Cu")
		(net "GMI_CPU1_G2_CPU0_G0_TX_DP<5>")
	)
	(segment
		(start 116.32692 -224.699322)
		(end 116.354606 -224.679256)
		(width 0.1143)
		(layer "In4.Cu")
		(net "GMI_CPU1_G2_CPU0_G0_TX_DP<5>")
	)
	(segment
		(start 355.208078 -222.12681)
		(end 355.171756 -222.147892)
		(width 0.1143)
		(layer "In4.Cu")
		(net "GMI_CPU1_G2_CPU0_G0_TX_DP<5>")
	)
	(segment
		(start 147.690332 -189.13983)
		(end 147.883372 -189.159134)
		(width 0.14224)
		(layer "In4.Cu")
		(net "GMI_CPU1_G2_CPU0_G0_TX_DP<5>")
	)
	(segment
		(start 151.372316 -186.298586)
		(end 151.702516 -186.027568)
		(width 0.14224)
		(layer "In4.Cu")
		(net "GMI_CPU1_G2_CPU0_G0_TX_DP<5>")
	)
	(segment
		(start 355.239828 -223.728534)
		(end 355.239828 -223.72828)
		(width 0.1143)
		(layer "In4.Cu")
		(net "GMI_CPU1_G2_CPU0_G0_TX_DP<5>")
	)
	(segment
		(start 116.287804 -223.101916)
		(end 116.324126 -223.080834)
		(width 0.1143)
		(layer "In4.Cu")
		(net "GMI_CPU1_G2_CPU0_G0_TX_DP<5>")
	)
	(segment
		(start 116.757704 -227.797106)
		(end 116.756942 -227.796598)
		(width 0.1143)
		(layer "In4.Cu")
		(net "GMI_CPU1_G2_CPU0_G0_TX_DP<5>")
	)
	(segment
		(start 355.171756 -226.320604)
		(end 355.208078 -226.341686)
		(width 0.1143)
		(layer "In4.Cu")
		(net "GMI_CPU1_G2_CPU0_G0_TX_DP<5>")
	)
	(segment
		(start 355.403912 -221.083124)
		(end 355.449632 -221.128844)
		(width 0.1143)
		(layer "In4.Cu")
		(net "GMI_CPU1_G2_CPU0_G0_TX_DP<5>")
	)
	(segment
		(start 165.629082 -178.040284)
		(end 167.287448 -178.040284)
		(width 0.14224)
		(layer "In4.Cu")
		(net "GMI_CPU1_G2_CPU0_G0_TX_DP<5>")
	)
	(segment
		(start 147.360386 -189.41034)
		(end 147.690332 -189.13983)
		(width 0.14224)
		(layer "In4.Cu")
		(net "GMI_CPU1_G2_CPU0_G0_TX_DP<5>")
	)
	(segment
		(start 355.239828 -222.108522)
		(end 355.208078 -222.12681)
		(width 0.1143)
		(layer "In4.Cu")
		(net "GMI_CPU1_G2_CPU0_G0_TX_DP<5>")
	)
	(segment
		(start 355.239828 -226.968304)
		(end 355.195886 -226.994212)
		(width 0.1143)
		(layer "In4.Cu")
		(net "GMI_CPU1_G2_CPU0_G0_TX_DP<5>")
	)
	(segment
		(start 146.1389 -190.589408)
		(end 146.4691 -190.318644)
		(width 0.14224)
		(layer "In4.Cu")
		(net "GMI_CPU1_G2_CPU0_G0_TX_DP<5>")
	)
	(segment
		(start 355.223826 -223.737424)
		(end 355.207824 -223.747076)
		(width 0.1143)
		(layer "In4.Cu")
		(net "GMI_CPU1_G2_CPU0_G0_TX_DP<5>")
	)
	(segment
		(start 355.449632 -221.128844)
		(end 355.449632 -221.34703)
		(width 0.1143)
		(layer "In4.Cu")
		(net "GMI_CPU1_G2_CPU0_G0_TX_DP<5>")
	)
	(segment
		(start 355.239828 -225.348546)
		(end 355.208078 -225.366834)
		(width 0.1143)
		(layer "In4.Cu")
		(net "GMI_CPU1_G2_CPU0_G0_TX_DP<5>")
	)
	(segment
		(start 354.735638 -227.798376)
		(end 354.699062 -227.819712)
		(width 0.1143)
		(layer "In4.Cu")
		(net "GMI_CPU1_G2_CPU0_G0_TX_DP<5>")
	)
	(segment
		(start 116.324126 -225.38817)
		(end 116.287804 -225.367088)
		(width 0.1143)
		(layer "In4.Cu")
		(net "GMI_CPU1_G2_CPU0_G0_TX_DP<5>")
	)
	(segment
		(start 119.768874 -212.033866)
		(end 145.946876 -190.570358)
		(width 0.14224)
		(layer "In4.Cu")
		(net "GMI_CPU1_G2_CPU0_G0_TX_DP<5>")
	)
	(segment
		(start 355.395784 -221.400878)
		(end 355.395784 -221.80423)
		(width 0.1143)
		(layer "In4.Cu")
		(net "GMI_CPU1_G2_CPU0_G0_TX_DP<5>")
	)
	(segment
		(start 148.562568 -188.42482)
		(end 148.755608 -188.444124)
		(width 0.14224)
		(layer "In4.Cu")
		(net "GMI_CPU1_G2_CPU0_G0_TX_DP<5>")
	)
	(segment
		(start 148.755608 -188.444124)
		(end 149.085808 -188.17336)
		(width 0.14224)
		(layer "In4.Cu")
		(net "GMI_CPU1_G2_CPU0_G0_TX_DP<5>")
	)
	(segment
		(start 116.04625 -221.129098)
		(end 116.09197 -221.083378)
		(width 0.1143)
		(layer "In4.Cu")
		(net "GMI_CPU1_G2_CPU0_G0_TX_DP<5>")
	)
	(segment
		(start 116.272056 -223.737678)
		(end 116.256054 -223.728534)
		(width 0.1143)
		(layer "In4.Cu")
		(net "GMI_CPU1_G2_CPU0_G0_TX_DP<5>")
	)
	(segment
		(start 116.288058 -223.74733)
		(end 116.272056 -223.737678)
		(width 0.1143)
		(layer "In4.Cu")
		(net "GMI_CPU1_G2_CPU0_G0_TX_DP<5>")
	)
	(segment
		(start 147.341336 -189.60338)
		(end 147.360386 -189.41034)
		(width 0.14224)
		(layer "In4.Cu")
		(net "GMI_CPU1_G2_CPU0_G0_TX_DP<5>")
	)
	(segment
		(start 116.7892 -227.815394)
		(end 116.757704 -227.797106)
		(width 0.1143)
		(layer "In4.Cu")
		(net "GMI_CPU1_G2_CPU0_G0_TX_DP<5>")
	)
	(segment
		(start 151.702516 -186.027568)
		(end 151.721566 -185.834528)
		(width 0.14224)
		(layer "In4.Cu")
		(net "GMI_CPU1_G2_CPU0_G0_TX_DP<5>")
	)
	(segment
		(start 116.256054 -224.740216)
		(end 116.32692 -224.699322)
		(width 0.1143)
		(layer "In4.Cu")
		(net "GMI_CPU1_G2_CPU0_G0_TX_DP<5>")
	)
	(segment
		(start 149.977094 -187.265056)
		(end 150.30704 -186.994546)
		(width 0.14224)
		(layer "In4.Cu")
		(net "GMI_CPU1_G2_CPU0_G0_TX_DP<5>")
	)
	(segment
		(start 355.171756 -223.08058)
		(end 355.208078 -223.101662)
		(width 0.1143)
		(layer "In4.Cu")
		(net "GMI_CPU1_G2_CPU0_G0_TX_DP<5>")
	)
	(segment
		(start 307.805836 -178.831748)
		(end 310.023256 -179.624482)
		(width 0.14224)
		(layer "In4.Cu")
		(net "GMI_CPU1_G2_CPU0_G0_TX_DP<5>")
	)
	(segment
		(start 150.50008 -187.01385)
		(end 150.83028 -186.742832)
		(width 0.14224)
		(layer "In4.Cu")
		(net "GMI_CPU1_G2_CPU0_G0_TX_DP<5>")
	)
	(segment
		(start 355.208078 -226.341686)
		(end 355.239828 -226.359974)
		(width 0.1143)
		(layer "In4.Cu")
		(net "GMI_CPU1_G2_CPU0_G0_TX_DP<5>")
	)
	(segment
		(start 117.11686 -228.284532)
		(end 117.034056 -228.201728)
		(width 0.1143)
		(layer "In4.Cu")
		(net "GMI_CPU1_G2_CPU0_G0_TX_DP<5>")
	)
	(segment
		(start 152.244552 -185.583322)
		(end 152.574752 -185.312304)
		(width 0.14224)
		(layer "In4.Cu")
		(net "GMI_CPU1_G2_CPU0_G0_TX_DP<5>")
	)
	(segment
		(start 116.754148 -227.795328)
		(end 116.75364 -227.795074)
		(width 0.1143)
		(layer "In4.Cu")
		(net "GMI_CPU1_G2_CPU0_G0_TX_DP<5>")
	)
	(segment
		(start 354.379022 -228.284278)
		(end 354.08108 -228.284278)
		(width 0.1143)
		(layer "In4.Cu")
		(net "GMI_CPU1_G2_CPU0_G0_TX_DP<5>")
	)
	(segment
		(start 145.946876 -190.570358)
		(end 146.1389 -190.589408)
		(width 0.14224)
		(layer "In4.Cu")
		(net "GMI_CPU1_G2_CPU0_G0_TX_DP<5>")
	)
	(segment
		(start 354.741734 -227.795074)
		(end 354.73894 -227.796344)
		(width 0.1143)
		(layer "In4.Cu")
		(net "GMI_CPU1_G2_CPU0_G0_TX_DP<5>")
	)
	(segment
		(start 157.824932 -180.830728)
		(end 165.629082 -178.040284)
		(width 0.14224)
		(layer "In4.Cu")
		(net "GMI_CPU1_G2_CPU0_G0_TX_DP<5>")
	)
	(segment
		(start 355.141276 -224.679002)
		(end 355.168962 -224.699068)
		(width 0.1143)
		(layer "In4.Cu")
		(net "GMI_CPU1_G2_CPU0_G0_TX_DP<5>")
	)
	(segment
		(start 354.738178 -227.796852)
		(end 354.737162 -227.79736)
		(width 0.1143)
		(layer "In4.Cu")
		(net "GMI_CPU1_G2_CPU0_G0_TX_DP<5>")
	)
	(segment
		(start 116.354606 -223.789748)
		(end 116.32692 -223.769682)
		(width 0.1143)
		(layer "In4.Cu")
		(net "GMI_CPU1_G2_CPU0_G0_TX_DP<5>")
	)
	(segment
		(start 116.32692 -223.769682)
		(end 116.288058 -223.74733)
		(width 0.1143)
		(layer "In4.Cu")
		(net "GMI_CPU1_G2_CPU0_G0_TX_DP<5>")
	)
	(segment
		(start 150.84933 -186.549792)
		(end 151.179276 -186.279282)
		(width 0.14224)
		(layer "In4.Cu")
		(net "GMI_CPU1_G2_CPU0_G0_TX_DP<5>")
	)
	(segment
		(start 149.434804 -187.70981)
		(end 149.627844 -187.729114)
		(width 0.14224)
		(layer "In4.Cu")
		(net "GMI_CPU1_G2_CPU0_G0_TX_DP<5>")
	)
	(segment
		(start 116.287804 -226.34194)
		(end 116.324126 -226.320858)
		(width 0.1143)
		(layer "In4.Cu")
		(net "GMI_CPU1_G2_CPU0_G0_TX_DP<5>")
	)
	(arc
		(start 116.120418 -226.786186)
		(mid 116.117797 -226.550777)
		(end 116.256054 -226.360228)
		(width 0.1143)
		(layer "In4.Cu")
		(net "GMI_CPU1_G2_CPU0_G0_TX_DP<5>")
	)
	(arc
		(start 354.465636 -228.178614)
		(mid 354.463613 -228.190024)
		(end 354.461826 -228.201474)
		(width 0.1143)
		(layer "In4.Cu")
		(net "GMI_CPU1_G2_CPU0_G0_TX_DP<5>")
	)
	(arc
		(start 354.699062 -227.819712)
		(mid 354.547075 -227.97622)
		(end 354.465636 -228.178614)
		(width 0.1143)
		(layer "In4.Cu")
		(net "GMI_CPU1_G2_CPU0_G0_TX_DP<5>")
	)
	(arc
		(start 355.239828 -223.11995)
		(mid 355.395756 -223.424242)
		(end 355.239828 -223.728534)
		(width 0.1143)
		(layer "In4.Cu")
		(net "GMI_CPU1_G2_CPU0_G0_TX_DP<5>")
	)
	(arc
		(start 116.354606 -224.679256)
		(mid 116.582606 -224.234502)
		(end 116.354606 -223.789748)
		(width 0.1143)
		(layer "In4.Cu")
		(net "GMI_CPU1_G2_CPU0_G0_TX_DP<5>")
	)
	(arc
		(start 355.239828 -226.359974)
		(mid 355.378084 -226.550524)
		(end 355.375464 -226.785932)
		(width 0.1143)
		(layer "In4.Cu")
		(net "GMI_CPU1_G2_CPU0_G0_TX_DP<5>")
	)
	(arc
		(start 116.582698 -227.484178)
		(mid 116.506941 -227.201463)
		(end 116.299996 -226.994466)
		(width 0.1143)
		(layer "In4.Cu")
		(net "GMI_CPU1_G2_CPU0_G0_TX_DP<5>")
	)
	(arc
		(start 116.33835 -222.158052)
		(mid 116.331276 -222.153045)
		(end 116.324126 -222.148146)
		(width 0.1143)
		(layer "In4.Cu")
		(net "GMI_CPU1_G2_CPU0_G0_TX_DP<5>")
	)
	(arc
		(start 116.256054 -222.108776)
		(mid 116.141378 -221.975442)
		(end 116.100098 -221.804484)
		(width 0.1143)
		(layer "In4.Cu")
		(net "GMI_CPU1_G2_CPU0_G0_TX_DP<5>")
	)
	(arc
		(start 355.157532 -222.157798)
		(mid 354.930149 -222.614236)
		(end 355.157532 -223.070674)
		(width 0.1143)
		(layer "In4.Cu")
		(net "GMI_CPU1_G2_CPU0_G0_TX_DP<5>")
	)
	(arc
		(start 355.395784 -221.80423)
		(mid 355.354529 -221.975201)
		(end 355.239828 -222.108522)
		(width 0.1143)
		(layer "In4.Cu")
		(net "GMI_CPU1_G2_CPU0_G0_TX_DP<5>")
	)
	(arc
		(start 355.157532 -223.070674)
		(mid 355.164605 -223.075683)
		(end 355.171756 -223.08058)
		(width 0.1143)
		(layer "In4.Cu")
		(net "GMI_CPU1_G2_CPU0_G0_TX_DP<5>")
	)
	(arc
		(start 355.157532 -225.397822)
		(mid 354.930149 -225.85426)
		(end 355.157532 -226.310698)
		(width 0.1143)
		(layer "In4.Cu")
		(net "GMI_CPU1_G2_CPU0_G0_TX_DP<5>")
	)
	(arc
		(start 117.034056 -228.201728)
		(mid 116.954977 -227.986283)
		(end 116.79682 -227.819966)
		(width 0.1143)
		(layer "In4.Cu")
		(net "GMI_CPU1_G2_CPU0_G0_TX_DP<5>")
	)
	(arc
		(start 355.157532 -226.310698)
		(mid 355.164605 -226.315707)
		(end 355.171756 -226.320604)
		(width 0.1143)
		(layer "In4.Cu")
		(net "GMI_CPU1_G2_CPU0_G0_TX_DP<5>")
	)
	(arc
		(start 116.33835 -225.398076)
		(mid 116.331276 -225.393069)
		(end 116.324126 -225.38817)
		(width 0.1143)
		(layer "In4.Cu")
		(net "GMI_CPU1_G2_CPU0_G0_TX_DP<5>")
	)
	(arc
		(start 116.33835 -223.070928)
		(mid 116.565733 -222.61449)
		(end 116.33835 -222.158052)
		(width 0.1143)
		(layer "In4.Cu")
		(net "GMI_CPU1_G2_CPU0_G0_TX_DP<5>")
	)
	(arc
		(start 116.256054 -226.968558)
		(mid 116.174073 -226.887908)
		(end 116.120418 -226.786186)
		(width 0.1143)
		(layer "In4.Cu")
		(net "GMI_CPU1_G2_CPU0_G0_TX_DP<5>")
	)
	(arc
		(start 355.195886 -226.994212)
		(mid 354.988898 -227.201184)
		(end 354.913184 -227.483924)
		(width 0.1143)
		(layer "In4.Cu")
		(net "GMI_CPU1_G2_CPU0_G0_TX_DP<5>")
	)
	(arc
		(start 116.75364 -227.795074)
		(mid 116.62844 -227.6686)
		(end 116.582698 -227.496624)
		(width 0.1143)
		(layer "In4.Cu")
		(net "GMI_CPU1_G2_CPU0_G0_TX_DP<5>")
	)
	(arc
		(start 355.171756 -222.147892)
		(mid 355.164606 -222.15279)
		(end 355.157532 -222.157798)
		(width 0.1143)
		(layer "In4.Cu")
		(net "GMI_CPU1_G2_CPU0_G0_TX_DP<5>")
	)
	(arc
		(start 116.33835 -226.310952)
		(mid 116.565733 -225.854514)
		(end 116.33835 -225.398076)
		(width 0.1143)
		(layer "In4.Cu")
		(net "GMI_CPU1_G2_CPU0_G0_TX_DP<5>")
	)
	(arc
		(start 116.256054 -223.728788)
		(mid 116.100126 -223.424496)
		(end 116.256054 -223.120204)
		(width 0.1143)
		(layer "In4.Cu")
		(net "GMI_CPU1_G2_CPU0_G0_TX_DP<5>")
	)
	(arc
		(start 355.141276 -223.789494)
		(mid 354.913276 -224.234248)
		(end 355.141276 -224.679002)
		(width 0.1143)
		(layer "In4.Cu")
		(net "GMI_CPU1_G2_CPU0_G0_TX_DP<5>")
	)
	(arc
		(start 116.256054 -225.3488)
		(mid 116.100126 -225.044508)
		(end 116.256054 -224.740216)
		(width 0.1143)
		(layer "In4.Cu")
		(net "GMI_CPU1_G2_CPU0_G0_TX_DP<5>")
	)
	(arc
		(start 116.324126 -223.080834)
		(mid 116.331275 -223.075934)
		(end 116.33835 -223.070928)
		(width 0.1143)
		(layer "In4.Cu")
		(net "GMI_CPU1_G2_CPU0_G0_TX_DP<5>")
	)
	(arc
		(start 354.913184 -227.49637)
		(mid 354.867418 -227.668332)
		(end 354.742242 -227.79482)
		(width 0.1143)
		(layer "In4.Cu")
		(net "GMI_CPU1_G2_CPU0_G0_TX_DP<5>")
	)
	(arc
		(start 355.375464 -226.785932)
		(mid 355.321828 -226.887668)
		(end 355.239828 -226.968304)
		(width 0.1143)
		(layer "In4.Cu")
		(net "GMI_CPU1_G2_CPU0_G0_TX_DP<5>")
	)
	(arc
		(start 355.171756 -225.387916)
		(mid 355.164606 -225.392814)
		(end 355.157532 -225.397822)
		(width 0.1143)
		(layer "In4.Cu")
		(net "GMI_CPU1_G2_CPU0_G0_TX_DP<5>")
	)
	(arc
		(start 116.324126 -226.320858)
		(mid 116.331275 -226.315958)
		(end 116.33835 -226.310952)
		(width 0.1143)
		(layer "In4.Cu")
		(net "GMI_CPU1_G2_CPU0_G0_TX_DP<5>")
	)
	(arc
		(start 355.239828 -224.739962)
		(mid 355.395756 -225.044254)
		(end 355.239828 -225.348546)
		(width 0.1143)
		(layer "In4.Cu")
		(net "GMI_CPU1_G2_CPU0_G0_TX_DP<5>")
	)
	(segment
		(start 116.94795 -226.930458)
		(end 117.414802 -226.66452)
		(width 0.12954)
		(layer "F.Cu")
		(net "GMI_CPU1_G2_CPU0_G0_TX_DP<4>")
	)
	(segment
		(start 354.547932 -226.930204)
		(end 354.08108 -226.664266)
		(width 0.12954)
		(layer "F.Cu")
		(net "GMI_CPU1_G2_CPU0_G0_TX_DP<4>")
	)
	(segment
		(start 154.022806 -185.51271)
		(end 153.698448 -185.778648)
		(width 0.14224)
		(layer "In4.Cu")
		(net "GMI_CPU1_G2_CPU0_G0_TX_DP<4>")
	)
	(segment
		(start 117.197124 -225.349308)
		(end 117.227604 -225.367088)
		(width 0.1143)
		(layer "In4.Cu")
		(net "GMI_CPU1_G2_CPU0_G0_TX_DP<4>")
	)
	(segment
		(start 354.45573 -221.396052)
		(end 354.504752 -221.34703)
		(width 0.1143)
		(layer "In4.Cu")
		(net "GMI_CPU1_G2_CPU0_G0_TX_DP<4>")
	)
	(segment
		(start 354.45573 -221.80423)
		(end 354.45573 -221.396052)
		(width 0.1143)
		(layer "In4.Cu")
		(net "GMI_CPU1_G2_CPU0_G0_TX_DP<4>")
	)
	(segment
		(start 150.383748 -188.506354)
		(end 150.053548 -188.777118)
		(width 0.14224)
		(layer "In4.Cu")
		(net "GMI_CPU1_G2_CPU0_G0_TX_DP<4>")
	)
	(segment
		(start 152.256744 -186.793124)
		(end 152.23871 -186.975496)
		(width 0.14224)
		(layer "In4.Cu")
		(net "GMI_CPU1_G2_CPU0_G0_TX_DP<4>")
	)
	(segment
		(start 167.476932 -178.984148)
		(end 167.441372 -178.984148)
		(width 0.14224)
		(layer "In4.Cu")
		(net "GMI_CPU1_G2_CPU0_G0_TX_DP<4>")
	)
	(segment
		(start 149.181312 -189.492128)
		(end 148.988272 -189.473078)
		(width 0.14224)
		(layer "In4.Cu")
		(net "GMI_CPU1_G2_CPU0_G0_TX_DP<4>")
	)
	(segment
		(start 149.530562 -189.028324)
		(end 149.511512 -189.221364)
		(width 0.14224)
		(layer "In4.Cu")
		(net "GMI_CPU1_G2_CPU0_G0_TX_DP<4>")
	)
	(segment
		(start 167.441118 -178.983894)
		(end 165.839902 -178.983894)
		(width 0.14224)
		(layer "In4.Cu")
		(net "GMI_CPU1_G2_CPU0_G0_TX_DP<4>")
	)
	(segment
		(start 151.914352 -187.241434)
		(end 151.732234 -187.2234)
		(width 0.14224)
		(layer "In4.Cu")
		(net "GMI_CPU1_G2_CPU0_G0_TX_DP<4>")
	)
	(segment
		(start 154.87142 -184.817004)
		(end 154.547062 -185.082942)
		(width 0.14224)
		(layer "In4.Cu")
		(net "GMI_CPU1_G2_CPU0_G0_TX_DP<4>")
	)
	(segment
		(start 152.23871 -186.975496)
		(end 151.914352 -187.241434)
		(width 0.14224)
		(layer "In4.Cu")
		(net "GMI_CPU1_G2_CPU0_G0_TX_DP<4>")
	)
	(segment
		(start 152.849834 -186.474354)
		(end 152.667462 -186.45632)
		(width 0.14224)
		(layer "In4.Cu")
		(net "GMI_CPU1_G2_CPU0_G0_TX_DP<4>")
	)
	(segment
		(start 117.03685 -218.58224)
		(end 117.03685 -221.05493)
		(width 0.14224)
		(layer "In4.Cu")
		(net "GMI_CPU1_G2_CPU0_G0_TX_DP<4>")
	)
	(segment
		(start 354.229162 -222.14967)
		(end 354.298758 -222.10903)
		(width 0.1143)
		(layer "In4.Cu")
		(net "GMI_CPU1_G2_CPU0_G0_TX_DP<4>")
	)
	(segment
		(start 153.51633 -185.76036)
		(end 153.192226 -186.026044)
		(width 0.14224)
		(layer "In4.Cu")
		(net "GMI_CPU1_G2_CPU0_G0_TX_DP<4>")
	)
	(segment
		(start 154.889454 -184.634632)
		(end 154.87142 -184.817004)
		(width 0.14224)
		(layer "In4.Cu")
		(net "GMI_CPU1_G2_CPU0_G0_TX_DP<4>")
	)
	(segment
		(start 302.904144 -179.774088)
		(end 167.476932 -178.984148)
		(width 0.14224)
		(layer "In4.Cu")
		(net "GMI_CPU1_G2_CPU0_G0_TX_DP<4>")
	)
	(segment
		(start 146.268948 -191.702436)
		(end 144.378426 -193.252344)
		(width 0.14224)
		(layer "In4.Cu")
		(net "GMI_CPU1_G2_CPU0_G0_TX_DP<4>")
	)
	(segment
		(start 117.26672 -226.31908)
		(end 117.227604 -226.34194)
		(width 0.1143)
		(layer "In4.Cu")
		(net "GMI_CPU1_G2_CPU0_G0_TX_DP<4>")
	)
	(segment
		(start 153.174192 -186.208416)
		(end 152.849834 -186.474354)
		(width 0.14224)
		(layer "In4.Cu")
		(net "GMI_CPU1_G2_CPU0_G0_TX_DP<4>")
	)
	(segment
		(start 316.022736 -184.09539)
		(end 309.794656 -180.56987)
		(width 0.14224)
		(layer "In4.Cu")
		(net "GMI_CPU1_G2_CPU0_G0_TX_DP<4>")
	)
	(segment
		(start 117.227604 -223.101916)
		(end 117.197124 -223.119696)
		(width 0.1143)
		(layer "In4.Cu")
		(net "GMI_CPU1_G2_CPU0_G0_TX_DP<4>")
	)
	(segment
		(start 151.311864 -187.735464)
		(end 150.987506 -188.001402)
		(width 0.14224)
		(layer "In4.Cu")
		(net "GMI_CPU1_G2_CPU0_G0_TX_DP<4>")
	)
	(segment
		(start 154.04084 -185.330338)
		(end 154.022806 -185.51271)
		(width 0.14224)
		(layer "In4.Cu")
		(net "GMI_CPU1_G2_CPU0_G0_TX_DP<4>")
	)
	(segment
		(start 117.197124 -222.109284)
		(end 117.227604 -222.127064)
		(width 0.1143)
		(layer "In4.Cu")
		(net "GMI_CPU1_G2_CPU0_G0_TX_DP<4>")
	)
	(segment
		(start 117.227604 -223.747076)
		(end 117.26672 -223.769936)
		(width 0.1143)
		(layer "In4.Cu")
		(net "GMI_CPU1_G2_CPU0_G0_TX_DP<4>")
	)
	(segment
		(start 149.860508 -188.757814)
		(end 149.530562 -189.028324)
		(width 0.14224)
		(layer "In4.Cu")
		(net "GMI_CPU1_G2_CPU0_G0_TX_DP<4>")
	)
	(segment
		(start 117.26672 -224.699068)
		(end 117.227604 -224.721928)
		(width 0.1143)
		(layer "In4.Cu")
		(net "GMI_CPU1_G2_CPU0_G0_TX_DP<4>")
	)
	(segment
		(start 117.227604 -224.721928)
		(end 117.197124 -224.739708)
		(width 0.1143)
		(layer "In4.Cu")
		(net "GMI_CPU1_G2_CPU0_G0_TX_DP<4>")
	)
	(segment
		(start 116.99113 -221.129098)
		(end 116.99113 -221.347284)
		(width 0.1143)
		(layer "In4.Cu")
		(net "GMI_CPU1_G2_CPU0_G0_TX_DP<4>")
	)
	(segment
		(start 154.364944 -185.064654)
		(end 154.04084 -185.330338)
		(width 0.14224)
		(layer "In4.Cu")
		(net "GMI_CPU1_G2_CPU0_G0_TX_DP<4>")
	)
	(segment
		(start 307.568854 -179.774088)
		(end 302.904144 -179.774088)
		(width 0.14224)
		(layer "In4.Cu")
		(net "GMI_CPU1_G2_CPU0_G0_TX_DP<4>")
	)
	(segment
		(start 144.149318 -193.32194)
		(end 120.45569 -212.749638)
		(width 0.14224)
		(layer "In4.Cu")
		(net "GMI_CPU1_G2_CPU0_G0_TX_DP<4>")
	)
	(segment
		(start 153.698448 -185.778648)
		(end 153.51633 -185.76036)
		(width 0.14224)
		(layer "In4.Cu")
		(net "GMI_CPU1_G2_CPU0_G0_TX_DP<4>")
	)
	(segment
		(start 117.227604 -225.367088)
		(end 117.26672 -225.389948)
		(width 0.1143)
		(layer "In4.Cu")
		(net "GMI_CPU1_G2_CPU0_G0_TX_DP<4>")
	)
	(segment
		(start 154.889708 -184.634886)
		(end 154.889454 -184.634632)
		(width 0.14224)
		(layer "In4.Cu")
		(net "GMI_CPU1_G2_CPU0_G0_TX_DP<4>")
	)
	(segment
		(start 144.378426 -193.252344)
		(end 144.149318 -193.32194)
		(width 0.14224)
		(layer "In4.Cu")
		(net "GMI_CPU1_G2_CPU0_G0_TX_DP<4>")
	)
	(segment
		(start 309.794656 -180.56987)
		(end 307.568854 -179.774088)
		(width 0.14224)
		(layer "In4.Cu")
		(net "GMI_CPU1_G2_CPU0_G0_TX_DP<4>")
	)
	(segment
		(start 116.99113 -221.347284)
		(end 117.040152 -221.396306)
		(width 0.1143)
		(layer "In4.Cu")
		(net "GMI_CPU1_G2_CPU0_G0_TX_DP<4>")
	)
	(segment
		(start 354.08108 -226.664266)
		(end 354.379022 -226.664266)
		(width 0.1143)
		(layer "In4.Cu")
		(net "GMI_CPU1_G2_CPU0_G0_TX_DP<4>")
	)
	(segment
		(start 150.805388 -187.983368)
		(end 150.402798 -188.313314)
		(width 0.14224)
		(layer "In4.Cu")
		(net "GMI_CPU1_G2_CPU0_G0_TX_DP<4>")
	)
	(segment
		(start 165.839902 -178.983894)
		(end 158.644082 -181.556914)
		(width 0.14224)
		(layer "In4.Cu")
		(net "GMI_CPU1_G2_CPU0_G0_TX_DP<4>")
	)
	(segment
		(start 154.547062 -185.082942)
		(end 154.364944 -185.064654)
		(width 0.14224)
		(layer "In4.Cu")
		(net "GMI_CPU1_G2_CPU0_G0_TX_DP<4>")
	)
	(segment
		(start 117.227604 -222.127064)
		(end 117.26672 -222.149924)
		(width 0.1143)
		(layer "In4.Cu")
		(net "GMI_CPU1_G2_CPU0_G0_TX_DP<4>")
	)
	(segment
		(start 150.987506 -188.001402)
		(end 150.805388 -187.983368)
		(width 0.14224)
		(layer "In4.Cu")
		(net "GMI_CPU1_G2_CPU0_G0_TX_DP<4>")
	)
	(segment
		(start 354.229162 -223.769682)
		(end 354.298758 -223.729042)
		(width 0.1143)
		(layer "In4.Cu")
		(net "GMI_CPU1_G2_CPU0_G0_TX_DP<4>")
	)
	(segment
		(start 120.45569 -212.749638)
		(end 117.03685 -218.58224)
		(width 0.14224)
		(layer "In4.Cu")
		(net "GMI_CPU1_G2_CPU0_G0_TX_DP<4>")
	)
	(segment
		(start 148.309076 -190.207392)
		(end 148.116036 -190.188088)
		(width 0.14224)
		(layer "In4.Cu")
		(net "GMI_CPU1_G2_CPU0_G0_TX_DP<4>")
	)
	(segment
		(start 117.26672 -223.079056)
		(end 117.227604 -223.101916)
		(width 0.1143)
		(layer "In4.Cu")
		(net "GMI_CPU1_G2_CPU0_G0_TX_DP<4>")
	)
	(segment
		(start 117.040152 -221.396306)
		(end 117.040152 -221.804484)
		(width 0.1143)
		(layer "In4.Cu")
		(net "GMI_CPU1_G2_CPU0_G0_TX_DP<4>")
	)
	(segment
		(start 153.192226 -186.026044)
		(end 153.174192 -186.208416)
		(width 0.14224)
		(layer "In4.Cu")
		(net "GMI_CPU1_G2_CPU0_G0_TX_DP<4>")
	)
	(segment
		(start 151.732234 -187.2234)
		(end 151.329898 -187.553092)
		(width 0.14224)
		(layer "In4.Cu")
		(net "GMI_CPU1_G2_CPU0_G0_TX_DP<4>")
	)
	(segment
		(start 117.227604 -226.34194)
		(end 117.197124 -226.35972)
		(width 0.1143)
		(layer "In4.Cu")
		(net "GMI_CPU1_G2_CPU0_G0_TX_DP<4>")
	)
	(segment
		(start 150.402798 -188.313314)
		(end 150.383748 -188.506354)
		(width 0.14224)
		(layer "In4.Cu")
		(net "GMI_CPU1_G2_CPU0_G0_TX_DP<4>")
	)
	(segment
		(start 354.298758 -226.359466)
		(end 354.229162 -226.318826)
		(width 0.1143)
		(layer "In4.Cu")
		(net "GMI_CPU1_G2_CPU0_G0_TX_DP<4>")
	)
	(segment
		(start 148.988272 -189.473078)
		(end 148.658326 -189.743588)
		(width 0.14224)
		(layer "In4.Cu")
		(net "GMI_CPU1_G2_CPU0_G0_TX_DP<4>")
	)
	(segment
		(start 146.269202 -191.702182)
		(end 146.268948 -191.702436)
		(width 0.14224)
		(layer "In4.Cu")
		(net "GMI_CPU1_G2_CPU0_G0_TX_DP<4>")
	)
	(segment
		(start 167.441372 -178.984148)
		(end 167.441118 -178.983894)
		(width 0.14224)
		(layer "In4.Cu")
		(net "GMI_CPU1_G2_CPU0_G0_TX_DP<4>")
	)
	(segment
		(start 117.03685 -221.083378)
		(end 116.99113 -221.129098)
		(width 0.1143)
		(layer "In4.Cu")
		(net "GMI_CPU1_G2_CPU0_G0_TX_DP<4>")
	)
	(segment
		(start 117.11686 -226.66452)
		(end 117.414802 -226.66452)
		(width 0.1143)
		(layer "In4.Cu")
		(net "GMI_CPU1_G2_CPU0_G0_TX_DP<4>")
	)
	(segment
		(start 151.329898 -187.553092)
		(end 151.311864 -187.735464)
		(width 0.14224)
		(layer "In4.Cu")
		(net "GMI_CPU1_G2_CPU0_G0_TX_DP<4>")
	)
	(segment
		(start 150.053548 -188.777118)
		(end 149.860508 -188.757814)
		(width 0.14224)
		(layer "In4.Cu")
		(net "GMI_CPU1_G2_CPU0_G0_TX_DP<4>")
	)
	(segment
		(start 354.459032 -218.557348)
		(end 351.05086 -212.817456)
		(width 0.14224)
		(layer "In4.Cu")
		(net "GMI_CPU1_G2_CPU0_G0_TX_DP<4>")
	)
	(segment
		(start 351.05086 -212.817456)
		(end 316.022736 -184.09539)
		(width 0.14224)
		(layer "In4.Cu")
		(net "GMI_CPU1_G2_CPU0_G0_TX_DP<4>")
	)
	(segment
		(start 148.658326 -189.743588)
		(end 148.639276 -189.936628)
		(width 0.14224)
		(layer "In4.Cu")
		(net "GMI_CPU1_G2_CPU0_G0_TX_DP<4>")
	)
	(segment
		(start 117.197124 -223.729296)
		(end 117.227604 -223.747076)
		(width 0.1143)
		(layer "In4.Cu")
		(net "GMI_CPU1_G2_CPU0_G0_TX_DP<4>")
	)
	(segment
		(start 354.504752 -221.34703)
		(end 354.504752 -221.128844)
		(width 0.1143)
		(layer "In4.Cu")
		(net "GMI_CPU1_G2_CPU0_G0_TX_DP<4>")
	)
	(segment
		(start 354.229162 -225.389694)
		(end 354.298758 -225.349054)
		(width 0.1143)
		(layer "In4.Cu")
		(net "GMI_CPU1_G2_CPU0_G0_TX_DP<4>")
	)
	(segment
		(start 149.511512 -189.221364)
		(end 149.181312 -189.492128)
		(width 0.14224)
		(layer "In4.Cu")
		(net "GMI_CPU1_G2_CPU0_G0_TX_DP<4>")
	)
	(segment
		(start 354.459032 -221.083124)
		(end 354.459032 -218.557348)
		(width 0.14224)
		(layer "In4.Cu")
		(net "GMI_CPU1_G2_CPU0_G0_TX_DP<4>")
	)
	(segment
		(start 148.116036 -190.188088)
		(end 146.269202 -191.702182)
		(width 0.14224)
		(layer "In4.Cu")
		(net "GMI_CPU1_G2_CPU0_G0_TX_DP<4>")
	)
	(segment
		(start 152.667462 -186.45632)
		(end 152.256744 -186.793124)
		(width 0.14224)
		(layer "In4.Cu")
		(net "GMI_CPU1_G2_CPU0_G0_TX_DP<4>")
	)
	(segment
		(start 117.03685 -221.05493)
		(end 117.03685 -221.083378)
		(width 0.1143)
		(layer "In4.Cu")
		(net "GMI_CPU1_G2_CPU0_G0_TX_DP<4>")
	)
	(segment
		(start 354.504752 -221.128844)
		(end 354.459032 -221.083124)
		(width 0.1143)
		(layer "In4.Cu")
		(net "GMI_CPU1_G2_CPU0_G0_TX_DP<4>")
	)
	(segment
		(start 354.379022 -226.664266)
		(end 354.448872 -226.594416)
		(width 0.1143)
		(layer "In4.Cu")
		(net "GMI_CPU1_G2_CPU0_G0_TX_DP<4>")
	)
	(segment
		(start 354.298758 -223.119442)
		(end 354.229162 -223.078802)
		(width 0.1143)
		(layer "In4.Cu")
		(net "GMI_CPU1_G2_CPU0_G0_TX_DP<4>")
	)
	(segment
		(start 117.04701 -226.59467)
		(end 117.11686 -226.66452)
		(width 0.1143)
		(layer "In4.Cu")
		(net "GMI_CPU1_G2_CPU0_G0_TX_DP<4>")
	)
	(segment
		(start 354.298758 -224.739454)
		(end 354.229162 -224.698814)
		(width 0.1143)
		(layer "In4.Cu")
		(net "GMI_CPU1_G2_CPU0_G0_TX_DP<4>")
	)
	(segment
		(start 158.644082 -181.556914)
		(end 154.889708 -184.634886)
		(width 0.14224)
		(layer "In4.Cu")
		(net "GMI_CPU1_G2_CPU0_G0_TX_DP<4>")
	)
	(segment
		(start 148.639276 -189.936628)
		(end 148.309076 -190.207392)
		(width 0.14224)
		(layer "In4.Cu")
		(net "GMI_CPU1_G2_CPU0_G0_TX_DP<4>")
	)
	(arc
		(start 117.197124 -223.119696)
		(mid 117.040147 -223.424496)
		(end 117.197124 -223.729296)
		(width 0.1143)
		(layer "In4.Cu")
		(net "GMI_CPU1_G2_CPU0_G0_TX_DP<4>")
	)
	(arc
		(start 354.298758 -223.729042)
		(mid 354.455735 -223.424242)
		(end 354.298758 -223.119442)
		(width 0.1143)
		(layer "In4.Cu")
		(net "GMI_CPU1_G2_CPU0_G0_TX_DP<4>")
	)
	(arc
		(start 117.26672 -222.149924)
		(mid 117.510047 -222.61449)
		(end 117.26672 -223.079056)
		(width 0.1143)
		(layer "In4.Cu")
		(net "GMI_CPU1_G2_CPU0_G0_TX_DP<4>")
	)
	(arc
		(start 117.040152 -221.804484)
		(mid 117.081701 -221.975906)
		(end 117.197124 -222.109284)
		(width 0.1143)
		(layer "In4.Cu")
		(net "GMI_CPU1_G2_CPU0_G0_TX_DP<4>")
	)
	(arc
		(start 117.26672 -223.769936)
		(mid 117.510047 -224.234502)
		(end 117.26672 -224.699068)
		(width 0.1143)
		(layer "In4.Cu")
		(net "GMI_CPU1_G2_CPU0_G0_TX_DP<4>")
	)
	(arc
		(start 117.197124 -224.739708)
		(mid 117.040147 -225.044508)
		(end 117.197124 -225.349308)
		(width 0.1143)
		(layer "In4.Cu")
		(net "GMI_CPU1_G2_CPU0_G0_TX_DP<4>")
	)
	(arc
		(start 354.298758 -225.349054)
		(mid 354.455735 -225.044254)
		(end 354.298758 -224.739454)
		(width 0.1143)
		(layer "In4.Cu")
		(net "GMI_CPU1_G2_CPU0_G0_TX_DP<4>")
	)
	(arc
		(start 354.298758 -222.10903)
		(mid 354.414185 -221.975654)
		(end 354.45573 -221.80423)
		(width 0.1143)
		(layer "In4.Cu")
		(net "GMI_CPU1_G2_CPU0_G0_TX_DP<4>")
	)
	(arc
		(start 117.26672 -225.389948)
		(mid 117.510047 -225.854514)
		(end 117.26672 -226.31908)
		(width 0.1143)
		(layer "In4.Cu")
		(net "GMI_CPU1_G2_CPU0_G0_TX_DP<4>")
	)
	(arc
		(start 354.229162 -223.078802)
		(mid 353.985835 -222.614236)
		(end 354.229162 -222.14967)
		(width 0.1143)
		(layer "In4.Cu")
		(net "GMI_CPU1_G2_CPU0_G0_TX_DP<4>")
	)
	(arc
		(start 354.229162 -224.698814)
		(mid 353.985835 -224.234248)
		(end 354.229162 -223.769682)
		(width 0.1143)
		(layer "In4.Cu")
		(net "GMI_CPU1_G2_CPU0_G0_TX_DP<4>")
	)
	(arc
		(start 354.229162 -226.318826)
		(mid 353.985835 -225.85426)
		(end 354.229162 -225.389694)
		(width 0.1143)
		(layer "In4.Cu")
		(net "GMI_CPU1_G2_CPU0_G0_TX_DP<4>")
	)
	(arc
		(start 117.197124 -226.35972)
		(mid 117.099359 -226.462696)
		(end 117.04701 -226.59467)
		(width 0.1143)
		(layer "In4.Cu")
		(net "GMI_CPU1_G2_CPU0_G0_TX_DP<4>")
	)
	(arc
		(start 354.448872 -226.594416)
		(mid 354.396455 -226.462485)
		(end 354.298758 -226.359466)
		(width 0.1143)
		(layer "In4.Cu")
		(net "GMI_CPU1_G2_CPU0_G0_TX_DP<4>")
	)
	(segment
		(start 116.94795 -230.170228)
		(end 117.414802 -229.90429)
		(width 0.12954)
		(layer "F.Cu")
		(net "GMI_CPU1_G2_CPU0_G0_TX_DP<3>")
	)
	(segment
		(start 354.547932 -230.169974)
		(end 354.08108 -229.904036)
		(width 0.12954)
		(layer "F.Cu")
		(net "GMI_CPU1_G2_CPU0_G0_TX_DP<3>")
	)
	(segment
		(start 355.665278 -227.816918)
		(end 355.697028 -227.798122)
		(width 0.1143)
		(layer "In4.Cu")
		(net "GMI_CPU1_G2_CPU0_G0_TX_DP<3>")
	)
	(segment
		(start 115.341146 -222.123254)
		(end 115.341908 -222.123762)
		(width 0.1143)
		(layer "In4.Cu")
		(net "GMI_CPU1_G2_CPU0_G0_TX_DP<3>")
	)
	(segment
		(start 317.22949 -182.588154)
		(end 310.47563 -178.764946)
		(width 0.14224)
		(layer "In4.Cu")
		(net "GMI_CPU1_G2_CPU0_G0_TX_DP<3>")
	)
	(segment
		(start 309.259478 -178.330352)
		(end 309.259224 -178.330098)
		(width 0.14224)
		(layer "In4.Cu")
		(net "GMI_CPU1_G2_CPU0_G0_TX_DP<3>")
	)
	(segment
		(start 356.151688 -224.723706)
		(end 356.150164 -224.722944)
		(width 0.1143)
		(layer "In4.Cu")
		(net "GMI_CPU1_G2_CPU0_G0_TX_DP<3>")
	)
	(segment
		(start 115.348766 -223.101408)
		(end 115.34775 -223.101916)
		(width 0.1143)
		(layer "In4.Cu")
		(net "GMI_CPU1_G2_CPU0_G0_TX_DP<3>")
	)
	(segment
		(start 115.346988 -226.342448)
		(end 115.316 -226.360228)
		(width 0.1143)
		(layer "In4.Cu")
		(net "GMI_CPU1_G2_CPU0_G0_TX_DP<3>")
	)
	(segment
		(start 356.151688 -226.343718)
		(end 356.150164 -226.342956)
		(width 0.1143)
		(layer "In4.Cu")
		(net "GMI_CPU1_G2_CPU0_G0_TX_DP<3>")
	)
	(segment
		(start 308.042564 -177.894996)
		(end 302.91024 -177.894996)
		(width 0.14224)
		(layer "In4.Cu")
		(net "GMI_CPU1_G2_CPU0_G0_TX_DP<3>")
	)
	(segment
		(start 356.335584 -221.80423)
		(end 356.335838 -221.804484)
		(width 0.1143)
		(layer "In4.Cu")
		(net "GMI_CPU1_G2_CPU0_G0_TX_DP<3>")
	)
	(segment
		(start 115.642898 -227.46716)
		(end 115.642898 -227.494338)
		(width 0.1143)
		(layer "In4.Cu")
		(net "GMI_CPU1_G2_CPU0_G0_TX_DP<3>")
	)
	(segment
		(start 353.727512 -213.657434)
		(end 353.51339 -213.296754)
		(width 0.14224)
		(layer "In4.Cu")
		(net "GMI_CPU1_G2_CPU0_G0_TX_DP<3>")
	)
	(segment
		(start 356.394512 -221.34703)
		(end 356.394512 -221.128844)
		(width 0.1143)
		(layer "In4.Cu")
		(net "GMI_CPU1_G2_CPU0_G0_TX_DP<3>")
	)
	(segment
		(start 115.34775 -226.34194)
		(end 115.346988 -226.342448)
		(width 0.1143)
		(layer "In4.Cu")
		(net "GMI_CPU1_G2_CPU0_G0_TX_DP<3>")
	)
	(segment
		(start 355.396038 -228.284024)
		(end 355.396038 -228.282754)
		(width 0.1143)
		(layer "In4.Cu")
		(net "GMI_CPU1_G2_CPU0_G0_TX_DP<3>")
	)
	(segment
		(start 115.380008 -223.765872)
		(end 115.386866 -223.769936)
		(width 0.1143)
		(layer "In4.Cu")
		(net "GMI_CPU1_G2_CPU0_G0_TX_DP<3>")
	)
	(segment
		(start 115.348766 -222.127572)
		(end 115.386866 -222.149924)
		(width 0.1143)
		(layer "In4.Cu")
		(net "GMI_CPU1_G2_CPU0_G0_TX_DP<3>")
	)
	(segment
		(start 356.154736 -222.123)
		(end 356.156006 -222.122238)
		(width 0.1143)
		(layer "In4.Cu")
		(net "GMI_CPU1_G2_CPU0_G0_TX_DP<3>")
	)
	(segment
		(start 115.345718 -226.98583)
		(end 115.346988 -226.986592)
		(width 0.1143)
		(layer "In4.Cu")
		(net "GMI_CPU1_G2_CPU0_G0_TX_DP<3>")
	)
	(segment
		(start 115.35029 -224.720404)
		(end 115.348766 -224.72142)
		(width 0.1143)
		(layer "In4.Cu")
		(net "GMI_CPU1_G2_CPU0_G0_TX_DP<3>")
	)
	(segment
		(start 115.348766 -224.72142)
		(end 115.34775 -224.721928)
		(width 0.1143)
		(layer "In4.Cu")
		(net "GMI_CPU1_G2_CPU0_G0_TX_DP<3>")
	)
	(segment
		(start 115.34775 -222.127064)
		(end 115.348766 -222.127572)
		(width 0.1143)
		(layer "In4.Cu")
		(net "GMI_CPU1_G2_CPU0_G0_TX_DP<3>")
	)
	(segment
		(start 115.316 -225.3488)
		(end 115.345718 -225.365818)
		(width 0.1143)
		(layer "In4.Cu")
		(net "GMI_CPU1_G2_CPU0_G0_TX_DP<3>")
	)
	(segment
		(start 115.10137 -221.129098)
		(end 115.10137 -221.347284)
		(width 0.1143)
		(layer "In4.Cu")
		(net "GMI_CPU1_G2_CPU0_G0_TX_DP<3>")
	)
	(segment
		(start 356.394512 -221.128844)
		(end 356.348792 -221.083124)
		(width 0.1143)
		(layer "In4.Cu")
		(net "GMI_CPU1_G2_CPU0_G0_TX_DP<3>")
	)
	(segment
		(start 115.337336 -222.121222)
		(end 115.339876 -222.122492)
		(width 0.1143)
		(layer "In4.Cu")
		(net "GMI_CPU1_G2_CPU0_G0_TX_DP<3>")
	)
	(segment
		(start 115.34775 -223.101916)
		(end 115.346988 -223.102424)
		(width 0.1143)
		(layer "In4.Cu")
		(net "GMI_CPU1_G2_CPU0_G0_TX_DP<3>")
	)
	(segment
		(start 115.346988 -223.102424)
		(end 115.316 -223.120204)
		(width 0.1143)
		(layer "In4.Cu")
		(net "GMI_CPU1_G2_CPU0_G0_TX_DP<3>")
	)
	(segment
		(start 115.344194 -222.125032)
		(end 115.346988 -222.126556)
		(width 0.1143)
		(layer "In4.Cu")
		(net "GMI_CPU1_G2_CPU0_G0_TX_DP<3>")
	)
	(segment
		(start 118.660164 -211.731606)
		(end 116.736368 -215.012016)
		(width 0.14224)
		(layer "In4.Cu")
		(net "GMI_CPU1_G2_CPU0_G0_TX_DP<3>")
	)
	(segment
		(start 356.148132 -224.721674)
		(end 356.147116 -224.721166)
		(width 0.1143)
		(layer "In4.Cu")
		(net "GMI_CPU1_G2_CPU0_G0_TX_DP<3>")
	)
	(segment
		(start 356.109016 -225.389694)
		(end 356.115874 -225.38563)
		(width 0.1143)
		(layer "In4.Cu")
		(net "GMI_CPU1_G2_CPU0_G0_TX_DP<3>")
	)
	(segment
		(start 356.148132 -226.341686)
		(end 356.147116 -226.341178)
		(width 0.1143)
		(layer "In4.Cu")
		(net "GMI_CPU1_G2_CPU0_G0_TX_DP<3>")
	)
	(segment
		(start 115.341908 -222.123762)
		(end 115.343432 -222.124524)
		(width 0.1143)
		(layer "In4.Cu")
		(net "GMI_CPU1_G2_CPU0_G0_TX_DP<3>")
	)
	(segment
		(start 166.994078 -177.1015)
		(end 165.45306 -177.1015)
		(width 0.14224)
		(layer "In4.Cu")
		(net "GMI_CPU1_G2_CPU0_G0_TX_DP<3>")
	)
	(segment
		(start 355.754686 -217.071448)
		(end 355.799898 -216.893902)
		(width 0.14224)
		(layer "In4.Cu")
		(net "GMI_CPU1_G2_CPU0_G0_TX_DP<3>")
	)
	(segment
		(start 354.699062 -229.43947)
		(end 354.771706 -229.397052)
		(width 0.1143)
		(layer "In4.Cu")
		(net "GMI_CPU1_G2_CPU0_G0_TX_DP<3>")
	)
	(segment
		(start 356.148894 -222.126302)
		(end 356.151688 -222.124778)
		(width 0.1143)
		(layer "In4.Cu")
		(net "GMI_CPU1_G2_CPU0_G0_TX_DP<3>")
	)
	(segment
		(start 115.10137 -221.347284)
		(end 115.160044 -221.405958)
		(width 0.1143)
		(layer "In4.Cu")
		(net "GMI_CPU1_G2_CPU0_G0_TX_DP<3>")
	)
	(segment
		(start 115.386866 -226.31908)
		(end 115.35029 -226.340416)
		(width 0.1143)
		(layer "In4.Cu")
		(net "GMI_CPU1_G2_CPU0_G0_TX_DP<3>")
	)
	(segment
		(start 356.117398 -227.004626)
		(end 356.1207 -227.002594)
		(width 0.1143)
		(layer "In4.Cu")
		(net "GMI_CPU1_G2_CPU0_G0_TX_DP<3>")
	)
	(segment
		(start 356.148132 -223.746822)
		(end 356.148894 -223.746314)
		(width 0.1143)
		(layer "In4.Cu")
		(net "GMI_CPU1_G2_CPU0_G0_TX_DP<3>")
	)
	(segment
		(start 115.34775 -225.367088)
		(end 115.379246 -225.385376)
		(width 0.1143)
		(layer "In4.Cu")
		(net "GMI_CPU1_G2_CPU0_G0_TX_DP<3>")
	)
	(segment
		(start 356.150164 -226.342956)
		(end 356.148894 -226.342194)
		(width 0.1143)
		(layer "In4.Cu")
		(net "GMI_CPU1_G2_CPU0_G0_TX_DP<3>")
	)
	(segment
		(start 116.570506 -215.551004)
		(end 116.39296 -215.597232)
		(width 0.14224)
		(layer "In4.Cu")
		(net "GMI_CPU1_G2_CPU0_G0_TX_DP<3>")
	)
	(segment
		(start 352.960178 -212.110828)
		(end 352.70059 -211.673186)
		(width 0.14224)
		(layer "In4.Cu")
		(net "GMI_CPU1_G2_CPU0_G0_TX_DP<3>")
	)
	(segment
		(start 116.39296 -215.597232)
		(end 116.181124 -215.958674)
		(width 0.14224)
		(layer "In4.Cu")
		(net "GMI_CPU1_G2_CPU0_G0_TX_DP<3>")
	)
	(segment
		(start 115.380008 -225.385884)
		(end 115.386866 -225.389948)
		(width 0.1143)
		(layer "In4.Cu")
		(net "GMI_CPU1_G2_CPU0_G0_TX_DP<3>")
	)
	(segment
		(start 356.148132 -225.366834)
		(end 356.148894 -225.366326)
		(width 0.1143)
		(layer "In4.Cu")
		(net "GMI_CPU1_G2_CPU0_G0_TX_DP<3>")
	)
	(segment
		(start 354.118926 -214.063072)
		(end 353.905058 -213.7029)
		(width 0.14224)
		(layer "In4.Cu")
		(net "GMI_CPU1_G2_CPU0_G0_TX_DP<3>")
	)
	(segment
		(start 115.346988 -225.36658)
		(end 115.34775 -225.367088)
		(width 0.1143)
		(layer "In4.Cu")
		(net "GMI_CPU1_G2_CPU0_G0_TX_DP<3>")
	)
	(segment
		(start 115.346988 -223.746568)
		(end 115.34775 -223.747076)
		(width 0.1143)
		(layer "In4.Cu")
		(net "GMI_CPU1_G2_CPU0_G0_TX_DP<3>")
	)
	(segment
		(start 116.099844 -228.283008)
		(end 116.099844 -228.284278)
		(width 0.1143)
		(layer "In4.Cu")
		(net "GMI_CPU1_G2_CPU0_G0_TX_DP<3>")
	)
	(segment
		(start 356.115874 -227.005642)
		(end 356.117398 -227.004626)
		(width 0.1143)
		(layer "In4.Cu")
		(net "GMI_CPU1_G2_CPU0_G0_TX_DP<3>")
	)
	(segment
		(start 356.150164 -223.745552)
		(end 356.179882 -223.728534)
		(width 0.1143)
		(layer "In4.Cu")
		(net "GMI_CPU1_G2_CPU0_G0_TX_DP<3>")
	)
	(segment
		(start 115.345718 -225.365818)
		(end 115.346988 -225.36658)
		(width 0.1143)
		(layer "In4.Cu")
		(net "GMI_CPU1_G2_CPU0_G0_TX_DP<3>")
	)
	(segment
		(start 115.339876 -222.122492)
		(end 115.341146 -222.123254)
		(width 0.1143)
		(layer "In4.Cu")
		(net "GMI_CPU1_G2_CPU0_G0_TX_DP<3>")
	)
	(segment
		(start 167.029892 -177.101754)
		(end 166.994332 -177.101754)
		(width 0.14224)
		(layer "In4.Cu")
		(net "GMI_CPU1_G2_CPU0_G0_TX_DP<3>")
	)
	(segment
		(start 356.109016 -222.14967)
		(end 356.147116 -222.127318)
		(width 0.1143)
		(layer "In4.Cu")
		(net "GMI_CPU1_G2_CPU0_G0_TX_DP<3>")
	)
	(segment
		(start 115.346988 -222.126556)
		(end 115.34775 -222.127064)
		(width 0.1143)
		(layer "In4.Cu")
		(net "GMI_CPU1_G2_CPU0_G0_TX_DP<3>")
	)
	(segment
		(start 356.109016 -223.769682)
		(end 356.115874 -223.765618)
		(width 0.1143)
		(layer "In4.Cu")
		(net "GMI_CPU1_G2_CPU0_G0_TX_DP<3>")
	)
	(segment
		(start 115.345718 -223.745806)
		(end 115.346988 -223.746568)
		(width 0.1143)
		(layer "In4.Cu")
		(net "GMI_CPU1_G2_CPU0_G0_TX_DP<3>")
	)
	(segment
		(start 356.150164 -226.985576)
		(end 356.179882 -226.968558)
		(width 0.1143)
		(layer "In4.Cu")
		(net "GMI_CPU1_G2_CPU0_G0_TX_DP<3>")
	)
	(segment
		(start 115.35029 -226.340416)
		(end 115.348766 -226.341432)
		(width 0.1143)
		(layer "In4.Cu")
		(net "GMI_CPU1_G2_CPU0_G0_TX_DP<3>")
	)
	(segment
		(start 353.905058 -213.7029)
		(end 353.727512 -213.657434)
		(width 0.14224)
		(layer "In4.Cu")
		(net "GMI_CPU1_G2_CPU0_G0_TX_DP<3>")
	)
	(segment
		(start 116.297202 -228.6127)
		(end 116.325904 -228.62921)
		(width 0.1143)
		(layer "In4.Cu")
		(net "GMI_CPU1_G2_CPU0_G0_TX_DP<3>")
	)
	(segment
		(start 115.34775 -223.747076)
		(end 115.379246 -223.765364)
		(width 0.1143)
		(layer "In4.Cu")
		(net "GMI_CPU1_G2_CPU0_G0_TX_DP<3>")
	)
	(segment
		(start 356.147116 -223.101154)
		(end 356.145592 -223.100138)
		(width 0.1143)
		(layer "In4.Cu")
		(net "GMI_CPU1_G2_CPU0_G0_TX_DP<3>")
	)
	(segment
		(start 115.837716 -216.54389)
		(end 115.14709 -217.721688)
		(width 0.14224)
		(layer "In4.Cu")
		(net "GMI_CPU1_G2_CPU0_G0_TX_DP<3>")
	)
	(segment
		(start 115.35029 -223.100392)
		(end 115.348766 -223.101408)
		(width 0.1143)
		(layer "In4.Cu")
		(net "GMI_CPU1_G2_CPU0_G0_TX_DP<3>")
	)
	(segment
		(start 356.158546 -222.120968)
		(end 356.179882 -222.108522)
		(width 0.1143)
		(layer "In4.Cu")
		(net "GMI_CPU1_G2_CPU0_G0_TX_DP<3>")
	)
	(segment
		(start 356.148894 -223.10217)
		(end 356.148132 -223.101662)
		(width 0.1143)
		(layer "In4.Cu")
		(net "GMI_CPU1_G2_CPU0_G0_TX_DP<3>")
	)
	(segment
		(start 115.386866 -224.699068)
		(end 115.35029 -224.720404)
		(width 0.1143)
		(layer "In4.Cu")
		(net "GMI_CPU1_G2_CPU0_G0_TX_DP<3>")
	)
	(segment
		(start 356.150164 -224.722944)
		(end 356.148894 -224.722182)
		(width 0.1143)
		(layer "In4.Cu")
		(net "GMI_CPU1_G2_CPU0_G0_TX_DP<3>")
	)
	(segment
		(start 354.287582 -214.601044)
		(end 354.073714 -214.240618)
		(width 0.14224)
		(layer "In4.Cu")
		(net "GMI_CPU1_G2_CPU0_G0_TX_DP<3>")
	)
	(segment
		(start 115.798854 -227.798376)
		(end 115.830604 -227.817172)
		(width 0.1143)
		(layer "In4.Cu")
		(net "GMI_CPU1_G2_CPU0_G0_TX_DP<3>")
	)
	(segment
		(start 115.379246 -225.385376)
		(end 115.380008 -225.385884)
		(width 0.1143)
		(layer "In4.Cu")
		(net "GMI_CPU1_G2_CPU0_G0_TX_DP<3>")
	)
	(segment
		(start 115.316 -223.728788)
		(end 115.345718 -223.745806)
		(width 0.1143)
		(layer "In4.Cu")
		(net "GMI_CPU1_G2_CPU0_G0_TX_DP<3>")
	)
	(segment
		(start 117.11686 -229.90429)
		(end 117.414802 -229.90429)
		(width 0.1143)
		(layer "In4.Cu")
		(net "GMI_CPU1_G2_CPU0_G0_TX_DP<3>")
	)
	(segment
		(start 116.181124 -215.958674)
		(end 116.227352 -216.135966)
		(width 0.14224)
		(layer "In4.Cu")
		(net "GMI_CPU1_G2_CPU0_G0_TX_DP<3>")
	)
	(segment
		(start 356.335838 -221.804484)
		(end 356.335838 -221.405704)
		(width 0.1143)
		(layer "In4.Cu")
		(net "GMI_CPU1_G2_CPU0_G0_TX_DP<3>")
	)
	(segment
		(start 355.968554 -217.432128)
		(end 355.754686 -217.071448)
		(width 0.14224)
		(layer "In4.Cu")
		(net "GMI_CPU1_G2_CPU0_G0_TX_DP<3>")
	)
	(segment
		(start 356.121716 -227.002086)
		(end 356.148132 -226.986846)
		(width 0.1143)
		(layer "In4.Cu")
		(net "GMI_CPU1_G2_CPU0_G0_TX_DP<3>")
	)
	(segment
		(start 356.151688 -222.124778)
		(end 356.15245 -222.12427)
		(width 0.1143)
		(layer "In4.Cu")
		(net "GMI_CPU1_G2_CPU0_G0_TX_DP<3>")
	)
	(segment
		(start 115.346988 -226.986592)
		(end 115.34775 -226.9871)
		(width 0.1143)
		(layer "In4.Cu")
		(net "GMI_CPU1_G2_CPU0_G0_TX_DP<3>")
	)
	(segment
		(start 356.147116 -226.341178)
		(end 356.145592 -226.340162)
		(width 0.1143)
		(layer "In4.Cu")
		(net "GMI_CPU1_G2_CPU0_G0_TX_DP<3>")
	)
	(segment
		(start 356.148894 -224.722182)
		(end 356.148132 -224.721674)
		(width 0.1143)
		(layer "In4.Cu")
		(net "GMI_CPU1_G2_CPU0_G0_TX_DP<3>")
	)
	(segment
		(start 356.147116 -224.721166)
		(end 356.145592 -224.72015)
		(width 0.1143)
		(layer "In4.Cu")
		(net "GMI_CPU1_G2_CPU0_G0_TX_DP<3>")
	)
	(segment
		(start 116.015262 -216.497662)
		(end 115.837716 -216.54389)
		(width 0.14224)
		(layer "In4.Cu")
		(net "GMI_CPU1_G2_CPU0_G0_TX_DP<3>")
	)
	(segment
		(start 355.40823 -216.488264)
		(end 355.194362 -216.127838)
		(width 0.14224)
		(layer "In4.Cu")
		(net "GMI_CPU1_G2_CPU0_G0_TX_DP<3>")
	)
	(segment
		(start 115.34775 -224.721928)
		(end 115.346988 -224.722436)
		(width 0.1143)
		(layer "In4.Cu")
		(net "GMI_CPU1_G2_CPU0_G0_TX_DP<3>")
	)
	(segment
		(start 356.150164 -225.365564)
		(end 356.179882 -225.348546)
		(width 0.1143)
		(layer "In4.Cu")
		(net "GMI_CPU1_G2_CPU0_G0_TX_DP<3>")
	)
	(segment
		(start 356.116636 -223.76511)
		(end 356.148132 -223.746822)
		(width 0.1143)
		(layer "In4.Cu")
		(net "GMI_CPU1_G2_CPU0_G0_TX_DP<3>")
	)
	(segment
		(start 356.116636 -225.385122)
		(end 356.148132 -225.366834)
		(width 0.1143)
		(layer "In4.Cu")
		(net "GMI_CPU1_G2_CPU0_G0_TX_DP<3>")
	)
	(segment
		(start 115.14709 -217.721688)
		(end 115.14709 -221.05493)
		(width 0.14224)
		(layer "In4.Cu")
		(net "GMI_CPU1_G2_CPU0_G0_TX_DP<3>")
	)
	(segment
		(start 354.08108 -229.904036)
		(end 354.379022 -229.904036)
		(width 0.1143)
		(layer "In4.Cu")
		(net "GMI_CPU1_G2_CPU0_G0_TX_DP<3>")
	)
	(segment
		(start 115.343432 -222.124524)
		(end 115.344194 -222.125032)
		(width 0.1143)
		(layer "In4.Cu")
		(net "GMI_CPU1_G2_CPU0_G0_TX_DP<3>")
	)
	(segment
		(start 356.148894 -225.366326)
		(end 356.150164 -225.365564)
		(width 0.1143)
		(layer "In4.Cu")
		(net "GMI_CPU1_G2_CPU0_G0_TX_DP<3>")
	)
	(segment
		(start 353.306634 -212.694266)
		(end 353.128834 -212.6488)
		(width 0.14224)
		(layer "In4.Cu")
		(net "GMI_CPU1_G2_CPU0_G0_TX_DP<3>")
	)
	(segment
		(start 355.58603 -216.53373)
		(end 355.40823 -216.488264)
		(width 0.14224)
		(layer "In4.Cu")
		(net "GMI_CPU1_G2_CPU0_G0_TX_DP<3>")
	)
	(segment
		(start 356.148894 -223.746314)
		(end 356.150164 -223.745552)
		(width 0.1143)
		(layer "In4.Cu")
		(net "GMI_CPU1_G2_CPU0_G0_TX_DP<3>")
	)
	(segment
		(start 302.91024 -177.894996)
		(end 167.029892 -177.101754)
		(width 0.14224)
		(layer "In4.Cu")
		(net "GMI_CPU1_G2_CPU0_G0_TX_DP<3>")
	)
	(segment
		(start 115.34775 -226.9871)
		(end 115.374166 -227.00234)
		(width 0.1143)
		(layer "In4.Cu")
		(net "GMI_CPU1_G2_CPU0_G0_TX_DP<3>")
	)
	(segment
		(start 356.15245 -222.12427)
		(end 356.153974 -222.123508)
		(width 0.1143)
		(layer "In4.Cu")
		(net "GMI_CPU1_G2_CPU0_G0_TX_DP<3>")
	)
	(segment
		(start 356.146354 -217.47734)
		(end 355.968554 -217.432128)
		(width 0.14224)
		(layer "In4.Cu")
		(net "GMI_CPU1_G2_CPU0_G0_TX_DP<3>")
	)
	(segment
		(start 356.348792 -221.083124)
		(end 356.348792 -217.818208)
		(width 0.14224)
		(layer "In4.Cu")
		(net "GMI_CPU1_G2_CPU0_G0_TX_DP<3>")
	)
	(segment
		(start 356.145592 -224.72015)
		(end 356.109016 -224.698814)
		(width 0.1143)
		(layer "In4.Cu")
		(net "GMI_CPU1_G2_CPU0_G0_TX_DP<3>")
	)
	(segment
		(start 354.465382 -214.64651)
		(end 354.287582 -214.601044)
		(width 0.14224)
		(layer "In4.Cu")
		(net "GMI_CPU1_G2_CPU0_G0_TX_DP<3>")
	)
	(segment
		(start 355.852984 -227.494084)
		(end 355.852984 -227.466906)
		(width 0.1143)
		(layer "In4.Cu")
		(net "GMI_CPU1_G2_CPU0_G0_TX_DP<3>")
	)
	(segment
		(start 355.169978 -228.628956)
		(end 355.19868 -228.612446)
		(width 0.1143)
		(layer "In4.Cu")
		(net "GMI_CPU1_G2_CPU0_G0_TX_DP<3>")
	)
	(segment
		(start 352.70059 -211.673186)
		(end 317.22949 -182.588154)
		(width 0.14224)
		(layer "In4.Cu")
		(net "GMI_CPU1_G2_CPU0_G0_TX_DP<3>")
	)
	(segment
		(start 115.379246 -223.765364)
		(end 115.380008 -223.765872)
		(width 0.1143)
		(layer "In4.Cu")
		(net "GMI_CPU1_G2_CPU0_G0_TX_DP<3>")
	)
	(segment
		(start 356.156006 -222.122238)
		(end 356.158546 -222.120968)
		(width 0.1143)
		(layer "In4.Cu")
		(net "GMI_CPU1_G2_CPU0_G0_TX_DP<3>")
	)
	(segment
		(start 115.348766 -226.341432)
		(end 115.34775 -226.34194)
		(width 0.1143)
		(layer "In4.Cu")
		(net "GMI_CPU1_G2_CPU0_G0_TX_DP<3>")
	)
	(segment
		(start 356.153974 -222.123508)
		(end 356.154736 -222.123)
		(width 0.1143)
		(layer "In4.Cu")
		(net "GMI_CPU1_G2_CPU0_G0_TX_DP<3>")
	)
	(segment
		(start 356.145592 -226.340162)
		(end 356.109016 -226.318826)
		(width 0.1143)
		(layer "In4.Cu")
		(net "GMI_CPU1_G2_CPU0_G0_TX_DP<3>")
	)
	(segment
		(start 115.316 -226.968812)
		(end 115.345718 -226.98583)
		(width 0.1143)
		(layer "In4.Cu")
		(net "GMI_CPU1_G2_CPU0_G0_TX_DP<3>")
	)
	(segment
		(start 356.147116 -222.127318)
		(end 356.148132 -222.12681)
		(width 0.1143)
		(layer "In4.Cu")
		(net "GMI_CPU1_G2_CPU0_G0_TX_DP<3>")
	)
	(segment
		(start 116.757704 -229.416864)
		(end 116.79682 -229.439724)
		(width 0.1143)
		(layer "In4.Cu")
		(net "GMI_CPU1_G2_CPU0_G0_TX_DP<3>")
	)
	(segment
		(start 356.179882 -224.739962)
		(end 356.151688 -224.723706)
		(width 0.1143)
		(layer "In4.Cu")
		(net "GMI_CPU1_G2_CPU0_G0_TX_DP<3>")
	)
	(segment
		(start 157.369002 -179.99202)
		(end 118.660164 -211.731606)
		(width 0.14224)
		(layer "In4.Cu")
		(net "GMI_CPU1_G2_CPU0_G0_TX_DP<3>")
	)
	(segment
		(start 115.316 -222.108776)
		(end 115.337336 -222.121222)
		(width 0.1143)
		(layer "In4.Cu")
		(net "GMI_CPU1_G2_CPU0_G0_TX_DP<3>")
	)
	(segment
		(start 356.148132 -226.986846)
		(end 356.148894 -226.986338)
		(width 0.1143)
		(layer "In4.Cu")
		(net "GMI_CPU1_G2_CPU0_G0_TX_DP<3>")
	)
	(segment
		(start 353.128834 -212.6488)
		(end 352.914966 -212.28812)
		(width 0.14224)
		(layer "In4.Cu")
		(net "GMI_CPU1_G2_CPU0_G0_TX_DP<3>")
	)
	(segment
		(start 117.034056 -229.821486)
		(end 117.11686 -229.90429)
		(width 0.1143)
		(layer "In4.Cu")
		(net "GMI_CPU1_G2_CPU0_G0_TX_DP<3>")
	)
	(segment
		(start 115.346988 -224.722436)
		(end 115.316 -224.740216)
		(width 0.1143)
		(layer "In4.Cu")
		(net "GMI_CPU1_G2_CPU0_G0_TX_DP<3>")
	)
	(segment
		(start 165.45306 -177.1015)
		(end 157.369002 -179.99202)
		(width 0.14224)
		(layer "In4.Cu")
		(net "GMI_CPU1_G2_CPU0_G0_TX_DP<3>")
	)
	(segment
		(start 356.145592 -223.100138)
		(end 356.109016 -223.078802)
		(width 0.1143)
		(layer "In4.Cu")
		(net "GMI_CPU1_G2_CPU0_G0_TX_DP<3>")
	)
	(segment
		(start 353.51339 -213.296754)
		(end 353.558856 -213.119208)
		(width 0.14224)
		(layer "In4.Cu")
		(net "GMI_CPU1_G2_CPU0_G0_TX_DP<3>")
	)
	(segment
		(start 115.374166 -227.00234)
		(end 115.375182 -227.002848)
		(width 0.1143)
		(layer "In4.Cu")
		(net "GMI_CPU1_G2_CPU0_G0_TX_DP<3>")
	)
	(segment
		(start 166.994332 -177.101754)
		(end 166.994078 -177.1015)
		(width 0.14224)
		(layer "In4.Cu")
		(net "GMI_CPU1_G2_CPU0_G0_TX_DP<3>")
	)
	(segment
		(start 355.799898 -216.893902)
		(end 355.58603 -216.53373)
		(width 0.14224)
		(layer "In4.Cu")
		(net "GMI_CPU1_G2_CPU0_G0_TX_DP<3>")
	)
	(segment
		(start 352.914966 -212.28812)
		(end 352.960178 -212.110828)
		(width 0.14224)
		(layer "In4.Cu")
		(net "GMI_CPU1_G2_CPU0_G0_TX_DP<3>")
	)
	(segment
		(start 356.148132 -222.12681)
		(end 356.148894 -222.126302)
		(width 0.1143)
		(layer "In4.Cu")
		(net "GMI_CPU1_G2_CPU0_G0_TX_DP<3>")
	)
	(segment
		(start 354.073714 -214.240618)
		(end 354.118926 -214.063072)
		(width 0.14224)
		(layer "In4.Cu")
		(net "GMI_CPU1_G2_CPU0_G0_TX_DP<3>")
	)
	(segment
		(start 115.14709 -221.083378)
		(end 115.10137 -221.129098)
		(width 0.1143)
		(layer "In4.Cu")
		(net "GMI_CPU1_G2_CPU0_G0_TX_DP<3>")
	)
	(segment
		(start 115.375182 -227.002848)
		(end 115.378484 -227.00488)
		(width 0.1143)
		(layer "In4.Cu")
		(net "GMI_CPU1_G2_CPU0_G0_TX_DP<3>")
	)
	(segment
		(start 354.67925 -215.006682)
		(end 354.465382 -214.64651)
		(width 0.14224)
		(layer "In4.Cu")
		(net "GMI_CPU1_G2_CPU0_G0_TX_DP<3>")
	)
	(segment
		(start 310.47563 -178.764946)
		(end 309.259478 -178.330352)
		(width 0.14224)
		(layer "In4.Cu")
		(net "GMI_CPU1_G2_CPU0_G0_TX_DP<3>")
	)
	(segment
		(start 115.378484 -227.00488)
		(end 115.380008 -227.005896)
		(width 0.1143)
		(layer "In4.Cu")
		(net "GMI_CPU1_G2_CPU0_G0_TX_DP<3>")
	)
	(segment
		(start 356.335838 -221.405704)
		(end 356.394512 -221.34703)
		(width 0.1143)
		(layer "In4.Cu")
		(net "GMI_CPU1_G2_CPU0_G0_TX_DP<3>")
	)
	(segment
		(start 354.634038 -215.184228)
		(end 354.67925 -215.006682)
		(width 0.14224)
		(layer "In4.Cu")
		(net "GMI_CPU1_G2_CPU0_G0_TX_DP<3>")
	)
	(segment
		(start 356.115874 -223.765618)
		(end 356.116636 -223.76511)
		(width 0.1143)
		(layer "In4.Cu")
		(net "GMI_CPU1_G2_CPU0_G0_TX_DP<3>")
	)
	(segment
		(start 115.14709 -221.05493)
		(end 115.14709 -221.083378)
		(width 0.1143)
		(layer "In4.Cu")
		(net "GMI_CPU1_G2_CPU0_G0_TX_DP<3>")
	)
	(segment
		(start 354.847906 -215.544654)
		(end 354.634038 -215.184228)
		(width 0.14224)
		(layer "In4.Cu")
		(net "GMI_CPU1_G2_CPU0_G0_TX_DP<3>")
	)
	(segment
		(start 115.386866 -223.079056)
		(end 115.35029 -223.100392)
		(width 0.1143)
		(layer "In4.Cu")
		(net "GMI_CPU1_G2_CPU0_G0_TX_DP<3>")
	)
	(segment
		(start 354.379022 -229.904036)
		(end 354.461826 -229.821232)
		(width 0.1143)
		(layer "In4.Cu")
		(net "GMI_CPU1_G2_CPU0_G0_TX_DP<3>")
	)
	(segment
		(start 116.227352 -216.135966)
		(end 116.015262 -216.497662)
		(width 0.14224)
		(layer "In4.Cu")
		(net "GMI_CPU1_G2_CPU0_G0_TX_DP<3>")
	)
	(segment
		(start 356.148894 -226.986338)
		(end 356.150164 -226.985576)
		(width 0.1143)
		(layer "In4.Cu")
		(net "GMI_CPU1_G2_CPU0_G0_TX_DP<3>")
	)
	(segment
		(start 116.782596 -215.189308)
		(end 116.570506 -215.551004)
		(width 0.14224)
		(layer "In4.Cu")
		(net "GMI_CPU1_G2_CPU0_G0_TX_DP<3>")
	)
	(segment
		(start 356.148132 -223.101662)
		(end 356.147116 -223.101154)
		(width 0.1143)
		(layer "In4.Cu")
		(net "GMI_CPU1_G2_CPU0_G0_TX_DP<3>")
	)
	(segment
		(start 355.239574 -215.950292)
		(end 355.025706 -215.59012)
		(width 0.14224)
		(layer "In4.Cu")
		(net "GMI_CPU1_G2_CPU0_G0_TX_DP<3>")
	)
	(segment
		(start 356.179882 -226.359974)
		(end 356.151688 -226.343718)
		(width 0.1143)
		(layer "In4.Cu")
		(net "GMI_CPU1_G2_CPU0_G0_TX_DP<3>")
	)
	(segment
		(start 115.160044 -221.405958)
		(end 115.160044 -221.804484)
		(width 0.1143)
		(layer "In4.Cu")
		(net "GMI_CPU1_G2_CPU0_G0_TX_DP<3>")
	)
	(segment
		(start 355.025706 -215.59012)
		(end 354.847906 -215.544654)
		(width 0.14224)
		(layer "In4.Cu")
		(net "GMI_CPU1_G2_CPU0_G0_TX_DP<3>")
	)
	(segment
		(start 356.115874 -225.38563)
		(end 356.116636 -225.385122)
		(width 0.1143)
		(layer "In4.Cu")
		(net "GMI_CPU1_G2_CPU0_G0_TX_DP<3>")
	)
	(segment
		(start 116.724176 -229.397306)
		(end 116.757704 -229.416864)
		(width 0.1143)
		(layer "In4.Cu")
		(net "GMI_CPU1_G2_CPU0_G0_TX_DP<3>")
	)
	(segment
		(start 356.348792 -217.818208)
		(end 356.146354 -217.47734)
		(width 0.14224)
		(layer "In4.Cu")
		(net "GMI_CPU1_G2_CPU0_G0_TX_DP<3>")
	)
	(segment
		(start 355.194362 -216.127838)
		(end 355.239574 -215.950292)
		(width 0.14224)
		(layer "In4.Cu")
		(net "GMI_CPU1_G2_CPU0_G0_TX_DP<3>")
	)
	(segment
		(start 309.259224 -178.330098)
		(end 308.042564 -177.894996)
		(width 0.14224)
		(layer "In4.Cu")
		(net "GMI_CPU1_G2_CPU0_G0_TX_DP<3>")
	)
	(segment
		(start 356.179882 -223.11995)
		(end 356.148894 -223.10217)
		(width 0.1143)
		(layer "In4.Cu")
		(net "GMI_CPU1_G2_CPU0_G0_TX_DP<3>")
	)
	(segment
		(start 356.148894 -226.342194)
		(end 356.148132 -226.341686)
		(width 0.1143)
		(layer "In4.Cu")
		(net "GMI_CPU1_G2_CPU0_G0_TX_DP<3>")
	)
	(segment
		(start 356.1207 -227.002594)
		(end 356.121716 -227.002086)
		(width 0.1143)
		(layer "In4.Cu")
		(net "GMI_CPU1_G2_CPU0_G0_TX_DP<3>")
	)
	(segment
		(start 116.736368 -215.012016)
		(end 116.782596 -215.189308)
		(width 0.14224)
		(layer "In4.Cu")
		(net "GMI_CPU1_G2_CPU0_G0_TX_DP<3>")
	)
	(segment
		(start 353.558856 -213.119208)
		(end 353.306634 -212.694266)
		(width 0.14224)
		(layer "In4.Cu")
		(net "GMI_CPU1_G2_CPU0_G0_TX_DP<3>")
	)
	(arc
		(start 356.109016 -226.318826)
		(mid 355.865689 -225.85426)
		(end 356.109016 -225.389694)
		(width 0.1143)
		(layer "In4.Cu")
		(net "GMI_CPU1_G2_CPU0_G0_TX_DP<3>")
	)
	(arc
		(start 354.771706 -229.397052)
		(mid 354.885113 -229.264163)
		(end 354.925884 -229.094284)
		(width 0.1143)
		(layer "In4.Cu")
		(net "GMI_CPU1_G2_CPU0_G0_TX_DP<3>")
	)
	(arc
		(start 115.386866 -225.389948)
		(mid 115.630193 -225.854514)
		(end 115.386866 -226.31908)
		(width 0.1143)
		(layer "In4.Cu")
		(net "GMI_CPU1_G2_CPU0_G0_TX_DP<3>")
	)
	(arc
		(start 115.642898 -227.494338)
		(mid 115.684157 -227.665195)
		(end 115.798854 -227.798376)
		(width 0.1143)
		(layer "In4.Cu")
		(net "GMI_CPU1_G2_CPU0_G0_TX_DP<3>")
	)
	(arc
		(start 115.386866 -222.149924)
		(mid 115.630193 -222.61449)
		(end 115.386866 -223.079056)
		(width 0.1143)
		(layer "In4.Cu")
		(net "GMI_CPU1_G2_CPU0_G0_TX_DP<3>")
	)
	(arc
		(start 356.179882 -226.968558)
		(mid 356.33581 -226.664266)
		(end 356.179882 -226.359974)
		(width 0.1143)
		(layer "In4.Cu")
		(net "GMI_CPU1_G2_CPU0_G0_TX_DP<3>")
	)
	(arc
		(start 355.230684 -228.593396)
		(mid 355.352086 -228.459423)
		(end 355.396038 -228.284024)
		(width 0.1143)
		(layer "In4.Cu")
		(net "GMI_CPU1_G2_CPU0_G0_TX_DP<3>")
	)
	(arc
		(start 115.160044 -221.804484)
		(mid 115.201299 -221.975455)
		(end 115.316 -222.108776)
		(width 0.1143)
		(layer "In4.Cu")
		(net "GMI_CPU1_G2_CPU0_G0_TX_DP<3>")
	)
	(arc
		(start 116.79682 -229.439724)
		(mid 116.955025 -229.606011)
		(end 117.034056 -229.821486)
		(width 0.1143)
		(layer "In4.Cu")
		(net "GMI_CPU1_G2_CPU0_G0_TX_DP<3>")
	)
	(arc
		(start 116.325904 -228.62921)
		(mid 116.505249 -228.831813)
		(end 116.569998 -229.094538)
		(width 0.1143)
		(layer "In4.Cu")
		(net "GMI_CPU1_G2_CPU0_G0_TX_DP<3>")
	)
	(arc
		(start 355.697028 -227.798122)
		(mid 355.811704 -227.664931)
		(end 355.852984 -227.494084)
		(width 0.1143)
		(layer "In4.Cu")
		(net "GMI_CPU1_G2_CPU0_G0_TX_DP<3>")
	)
	(arc
		(start 355.396038 -228.282754)
		(mid 355.468845 -228.014122)
		(end 355.665278 -227.816918)
		(width 0.1143)
		(layer "In4.Cu")
		(net "GMI_CPU1_G2_CPU0_G0_TX_DP<3>")
	)
	(arc
		(start 356.109016 -224.698814)
		(mid 355.865689 -224.234248)
		(end 356.109016 -223.769682)
		(width 0.1143)
		(layer "In4.Cu")
		(net "GMI_CPU1_G2_CPU0_G0_TX_DP<3>")
	)
	(arc
		(start 116.569998 -229.094538)
		(mid 116.61076 -229.264422)
		(end 116.724176 -229.397306)
		(width 0.1143)
		(layer "In4.Cu")
		(net "GMI_CPU1_G2_CPU0_G0_TX_DP<3>")
	)
	(arc
		(start 356.179882 -222.108522)
		(mid 356.224929 -222.07055)
		(end 356.263448 -222.025972)
		(width 0.1143)
		(layer "In4.Cu")
		(net "GMI_CPU1_G2_CPU0_G0_TX_DP<3>")
	)
	(arc
		(start 115.380008 -227.005896)
		(mid 115.572532 -227.20171)
		(end 115.642898 -227.46716)
		(width 0.1143)
		(layer "In4.Cu")
		(net "GMI_CPU1_G2_CPU0_G0_TX_DP<3>")
	)
	(arc
		(start 356.109016 -223.078802)
		(mid 355.865689 -222.614236)
		(end 356.109016 -222.14967)
		(width 0.1143)
		(layer "In4.Cu")
		(net "GMI_CPU1_G2_CPU0_G0_TX_DP<3>")
	)
	(arc
		(start 115.316 -223.120204)
		(mid 115.160072 -223.424496)
		(end 115.316 -223.728788)
		(width 0.1143)
		(layer "In4.Cu")
		(net "GMI_CPU1_G2_CPU0_G0_TX_DP<3>")
	)
	(arc
		(start 116.099844 -228.284278)
		(mid 116.143701 -228.459728)
		(end 116.265198 -228.59365)
		(width 0.1143)
		(layer "In4.Cu")
		(net "GMI_CPU1_G2_CPU0_G0_TX_DP<3>")
	)
	(arc
		(start 356.179882 -225.348546)
		(mid 356.33581 -225.044254)
		(end 356.179882 -224.739962)
		(width 0.1143)
		(layer "In4.Cu")
		(net "GMI_CPU1_G2_CPU0_G0_TX_DP<3>")
	)
	(arc
		(start 355.19868 -228.612446)
		(mid 355.21492 -228.603321)
		(end 355.230684 -228.593396)
		(width 0.1143)
		(layer "In4.Cu")
		(net "GMI_CPU1_G2_CPU0_G0_TX_DP<3>")
	)
	(arc
		(start 115.316 -226.360228)
		(mid 115.160072 -226.66452)
		(end 115.316 -226.968812)
		(width 0.1143)
		(layer "In4.Cu")
		(net "GMI_CPU1_G2_CPU0_G0_TX_DP<3>")
	)
	(arc
		(start 356.263448 -222.025972)
		(mid 356.31716 -221.920847)
		(end 356.335584 -221.80423)
		(width 0.1143)
		(layer "In4.Cu")
		(net "GMI_CPU1_G2_CPU0_G0_TX_DP<3>")
	)
	(arc
		(start 356.179882 -223.728534)
		(mid 356.33581 -223.424242)
		(end 356.179882 -223.11995)
		(width 0.1143)
		(layer "In4.Cu")
		(net "GMI_CPU1_G2_CPU0_G0_TX_DP<3>")
	)
	(arc
		(start 355.852984 -227.466906)
		(mid 355.923314 -227.201436)
		(end 356.115874 -227.005642)
		(width 0.1143)
		(layer "In4.Cu")
		(net "GMI_CPU1_G2_CPU0_G0_TX_DP<3>")
	)
	(arc
		(start 354.465636 -229.798372)
		(mid 354.547069 -229.595974)
		(end 354.699062 -229.43947)
		(width 0.1143)
		(layer "In4.Cu")
		(net "GMI_CPU1_G2_CPU0_G0_TX_DP<3>")
	)
	(arc
		(start 354.461826 -229.821232)
		(mid 354.463614 -229.809783)
		(end 354.465636 -229.798372)
		(width 0.1143)
		(layer "In4.Cu")
		(net "GMI_CPU1_G2_CPU0_G0_TX_DP<3>")
	)
	(arc
		(start 354.925884 -229.094284)
		(mid 354.990606 -228.831545)
		(end 355.169978 -228.628956)
		(width 0.1143)
		(layer "In4.Cu")
		(net "GMI_CPU1_G2_CPU0_G0_TX_DP<3>")
	)
	(arc
		(start 115.386866 -223.769936)
		(mid 115.630193 -224.234502)
		(end 115.386866 -224.699068)
		(width 0.1143)
		(layer "In4.Cu")
		(net "GMI_CPU1_G2_CPU0_G0_TX_DP<3>")
	)
	(arc
		(start 116.265198 -228.59365)
		(mid 116.280961 -228.603577)
		(end 116.297202 -228.6127)
		(width 0.1143)
		(layer "In4.Cu")
		(net "GMI_CPU1_G2_CPU0_G0_TX_DP<3>")
	)
	(arc
		(start 115.830604 -227.817172)
		(mid 116.027104 -228.014337)
		(end 116.099844 -228.283008)
		(width 0.1143)
		(layer "In4.Cu")
		(net "GMI_CPU1_G2_CPU0_G0_TX_DP<3>")
	)
	(arc
		(start 115.316 -224.740216)
		(mid 115.160072 -225.044508)
		(end 115.316 -225.3488)
		(width 0.1143)
		(layer "In4.Cu")
		(net "GMI_CPU1_G2_CPU0_G0_TX_DP<3>")
	)
	(segment
		(start 356.89794 -227.74021)
		(end 356.431088 -227.474272)
		(width 0.12954)
		(layer "F.Cu")
		(net "GMI_CPU1_G2_CPU0_G0_TX_DP<2>")
	)
	(segment
		(start 114.597942 -227.740464)
		(end 115.064794 -227.474526)
		(width 0.12954)
		(layer "F.Cu")
		(net "GMI_CPU1_G2_CPU0_G0_TX_DP<2>")
	)
	(segment
		(start 356.173024 -215.432132)
		(end 355.959156 -215.07196)
		(width 0.14224)
		(layer "In4.Cu")
		(net "GMI_CPU1_G2_CPU0_G0_TX_DP<2>")
	)
	(segment
		(start 356.688136 -216.553288)
		(end 356.733348 -216.375742)
		(width 0.14224)
		(layer "In4.Cu")
		(net "GMI_CPU1_G2_CPU0_G0_TX_DP<2>")
	)
	(segment
		(start 357.339392 -221.34703)
		(end 357.339392 -221.128844)
		(width 0.1143)
		(layer "In4.Cu")
		(net "GMI_CPU1_G2_CPU0_G0_TX_DP<2>")
	)
	(segment
		(start 357.04907 -225.389694)
		(end 357.08717 -225.367342)
		(width 0.1143)
		(layer "In4.Cu")
		(net "GMI_CPU1_G2_CPU0_G0_TX_DP<2>")
	)
	(segment
		(start 317.647828 -181.723284)
		(end 310.648096 -177.760884)
		(width 0.14224)
		(layer "In4.Cu")
		(net "GMI_CPU1_G2_CPU0_G0_TX_DP<2>")
	)
	(segment
		(start 114.406934 -226.342448)
		(end 114.375946 -226.360228)
		(width 0.1143)
		(layer "In4.Cu")
		(net "GMI_CPU1_G2_CPU0_G0_TX_DP<2>")
	)
	(segment
		(start 355.398832 -214.12835)
		(end 355.221032 -214.082884)
		(width 0.14224)
		(layer "In4.Cu")
		(net "GMI_CPU1_G2_CPU0_G0_TX_DP<2>")
	)
	(segment
		(start 355.052376 -213.544912)
		(end 354.838508 -213.18474)
		(width 0.14224)
		(layer "In4.Cu")
		(net "GMI_CPU1_G2_CPU0_G0_TX_DP<2>")
	)
	(segment
		(start 114.407696 -223.747076)
		(end 114.408712 -223.747584)
		(width 0.1143)
		(layer "In4.Cu")
		(net "GMI_CPU1_G2_CPU0_G0_TX_DP<2>")
	)
	(segment
		(start 114.408712 -224.72142)
		(end 114.407696 -224.721928)
		(width 0.1143)
		(layer "In4.Cu")
		(net "GMI_CPU1_G2_CPU0_G0_TX_DP<2>")
	)
	(segment
		(start 114.439192 -227.005388)
		(end 114.439954 -227.005896)
		(width 0.1143)
		(layer "In4.Cu")
		(net "GMI_CPU1_G2_CPU0_G0_TX_DP<2>")
	)
	(segment
		(start 353.720654 -211.301076)
		(end 317.647828 -181.723284)
		(width 0.14224)
		(layer "In4.Cu")
		(net "GMI_CPU1_G2_CPU0_G0_TX_DP<2>")
	)
	(segment
		(start 357.119936 -223.728534)
		(end 357.139748 -223.71431)
		(width 0.1143)
		(layer "In4.Cu")
		(net "GMI_CPU1_G2_CPU0_G0_TX_DP<2>")
	)
	(segment
		(start 355.567488 -214.666068)
		(end 355.6127 -214.488522)
		(width 0.14224)
		(layer "In4.Cu")
		(net "GMI_CPU1_G2_CPU0_G0_TX_DP<2>")
	)
	(segment
		(start 114.406934 -226.986592)
		(end 114.407696 -226.9871)
		(width 0.1143)
		(layer "In4.Cu")
		(net "GMI_CPU1_G2_CPU0_G0_TX_DP<2>")
	)
	(segment
		(start 356.72903 -227.474272)
		(end 356.811834 -227.391468)
		(width 0.1143)
		(layer "In4.Cu")
		(net "GMI_CPU1_G2_CPU0_G0_TX_DP<2>")
	)
	(segment
		(start 357.088186 -223.101662)
		(end 357.08717 -223.101154)
		(width 0.1143)
		(layer "In4.Cu")
		(net "GMI_CPU1_G2_CPU0_G0_TX_DP<2>")
	)
	(segment
		(start 357.085138 -223.7486)
		(end 357.0859 -223.748092)
		(width 0.1143)
		(layer "In4.Cu")
		(net "GMI_CPU1_G2_CPU0_G0_TX_DP<2>")
	)
	(segment
		(start 114.15649 -221.347284)
		(end 114.21999 -221.410784)
		(width 0.1143)
		(layer "In4.Cu")
		(net "GMI_CPU1_G2_CPU0_G0_TX_DP<2>")
	)
	(segment
		(start 115.990878 -214.429848)
		(end 115.813332 -214.475822)
		(width 0.14224)
		(layer "In4.Cu")
		(net "GMI_CPU1_G2_CPU0_G0_TX_DP<2>")
	)
	(segment
		(start 357.08717 -226.341178)
		(end 357.085646 -226.340162)
		(width 0.1143)
		(layer "In4.Cu")
		(net "GMI_CPU1_G2_CPU0_G0_TX_DP<2>")
	)
	(segment
		(start 356.431088 -227.474272)
		(end 356.72903 -227.474272)
		(width 0.1143)
		(layer "In4.Cu")
		(net "GMI_CPU1_G2_CPU0_G0_TX_DP<2>")
	)
	(segment
		(start 354.492306 -212.601302)
		(end 353.720654 -211.301076)
		(width 0.14224)
		(layer "In4.Cu")
		(net "GMI_CPU1_G2_CPU0_G0_TX_DP<2>")
	)
	(segment
		(start 115.813332 -214.475822)
		(end 115.601242 -214.837264)
		(width 0.14224)
		(layer "In4.Cu")
		(net "GMI_CPU1_G2_CPU0_G0_TX_DP<2>")
	)
	(segment
		(start 114.375946 -226.968812)
		(end 114.406934 -226.986592)
		(width 0.1143)
		(layer "In4.Cu")
		(net "GMI_CPU1_G2_CPU0_G0_TX_DP<2>")
	)
	(segment
		(start 355.007164 -213.722458)
		(end 355.052376 -213.544912)
		(width 0.14224)
		(layer "In4.Cu")
		(net "GMI_CPU1_G2_CPU0_G0_TX_DP<2>")
	)
	(segment
		(start 357.139748 -223.134174)
		(end 357.119936 -223.11995)
		(width 0.1143)
		(layer "In4.Cu")
		(net "GMI_CPU1_G2_CPU0_G0_TX_DP<2>")
	)
	(segment
		(start 114.408712 -226.341432)
		(end 114.407696 -226.34194)
		(width 0.1143)
		(layer "In4.Cu")
		(net "GMI_CPU1_G2_CPU0_G0_TX_DP<2>")
	)
	(segment
		(start 114.684048 -227.391722)
		(end 114.766852 -227.474526)
		(width 0.1143)
		(layer "In4.Cu")
		(net "GMI_CPU1_G2_CPU0_G0_TX_DP<2>")
	)
	(segment
		(start 357.119936 -226.359974)
		(end 357.088948 -226.342194)
		(width 0.1143)
		(layer "In4.Cu")
		(net "GMI_CPU1_G2_CPU0_G0_TX_DP<2>")
	)
	(segment
		(start 357.138732 -224.753678)
		(end 357.119936 -224.739962)
		(width 0.1143)
		(layer "In4.Cu")
		(net "GMI_CPU1_G2_CPU0_G0_TX_DP<2>")
	)
	(segment
		(start 308.394862 -176.955196)
		(end 302.913288 -176.955196)
		(width 0.14224)
		(layer "In4.Cu")
		(net "GMI_CPU1_G2_CPU0_G0_TX_DP<2>")
	)
	(segment
		(start 357.119936 -225.348546)
		(end 357.138732 -225.33483)
		(width 0.1143)
		(layer "In4.Cu")
		(net "GMI_CPU1_G2_CPU0_G0_TX_DP<2>")
	)
	(segment
		(start 114.408712 -225.367596)
		(end 114.446812 -225.389948)
		(width 0.1143)
		(layer "In4.Cu")
		(net "GMI_CPU1_G2_CPU0_G0_TX_DP<2>")
	)
	(segment
		(start 116.15674 -213.89086)
		(end 116.202968 -214.068152)
		(width 0.14224)
		(layer "In4.Cu")
		(net "GMI_CPU1_G2_CPU0_G0_TX_DP<2>")
	)
	(segment
		(start 114.375946 -224.740216)
		(end 114.35715 -224.753932)
		(width 0.1143)
		(layer "In4.Cu")
		(net "GMI_CPU1_G2_CPU0_G0_TX_DP<2>")
	)
	(segment
		(start 114.15649 -221.129098)
		(end 114.15649 -221.347284)
		(width 0.1143)
		(layer "In4.Cu")
		(net "GMI_CPU1_G2_CPU0_G0_TX_DP<2>")
	)
	(segment
		(start 357.0859 -226.988116)
		(end 357.08717 -226.987354)
		(width 0.1143)
		(layer "In4.Cu")
		(net "GMI_CPU1_G2_CPU0_G0_TX_DP<2>")
	)
	(segment
		(start 114.20221 -221.083378)
		(end 114.15649 -221.129098)
		(width 0.1143)
		(layer "In4.Cu")
		(net "GMI_CPU1_G2_CPU0_G0_TX_DP<2>")
	)
	(segment
		(start 114.879882 -216.322656)
		(end 114.702336 -216.36863)
		(width 0.14224)
		(layer "In4.Cu")
		(net "GMI_CPU1_G2_CPU0_G0_TX_DP<2>")
	)
	(segment
		(start 354.838508 -213.18474)
		(end 354.660962 -213.139274)
		(width 0.14224)
		(layer "In4.Cu")
		(net "GMI_CPU1_G2_CPU0_G0_TX_DP<2>")
	)
	(segment
		(start 357.088186 -226.986846)
		(end 357.088948 -226.986338)
		(width 0.1143)
		(layer "In4.Cu")
		(net "GMI_CPU1_G2_CPU0_G0_TX_DP<2>")
	)
	(segment
		(start 357.339392 -221.128844)
		(end 357.293672 -221.083124)
		(width 0.1143)
		(layer "In4.Cu")
		(net "GMI_CPU1_G2_CPU0_G0_TX_DP<2>")
	)
	(segment
		(start 115.601242 -214.837264)
		(end 115.64747 -215.014556)
		(width 0.14224)
		(layer "In4.Cu")
		(net "GMI_CPU1_G2_CPU0_G0_TX_DP<2>")
	)
	(segment
		(start 114.356134 -223.714564)
		(end 114.375946 -223.728788)
		(width 0.1143)
		(layer "In4.Cu")
		(net "GMI_CPU1_G2_CPU0_G0_TX_DP<2>")
	)
	(segment
		(start 357.04907 -222.14967)
		(end 357.119936 -222.108522)
		(width 0.1143)
		(layer "In4.Cu")
		(net "GMI_CPU1_G2_CPU0_G0_TX_DP<2>")
	)
	(segment
		(start 357.085138 -226.988624)
		(end 357.0859 -226.988116)
		(width 0.1143)
		(layer "In4.Cu")
		(net "GMI_CPU1_G2_CPU0_G0_TX_DP<2>")
	)
	(segment
		(start 114.408712 -223.101408)
		(end 114.407696 -223.101916)
		(width 0.1143)
		(layer "In4.Cu")
		(net "GMI_CPU1_G2_CPU0_G0_TX_DP<2>")
	)
	(segment
		(start 114.406934 -223.102424)
		(end 114.375946 -223.120204)
		(width 0.1143)
		(layer "In4.Cu")
		(net "GMI_CPU1_G2_CPU0_G0_TX_DP<2>")
	)
	(segment
		(start 114.446812 -226.31908)
		(end 114.410236 -226.340416)
		(width 0.1143)
		(layer "In4.Cu")
		(net "GMI_CPU1_G2_CPU0_G0_TX_DP<2>")
	)
	(segment
		(start 357.275892 -221.80423)
		(end 357.275892 -221.41053)
		(width 0.1143)
		(layer "In4.Cu")
		(net "GMI_CPU1_G2_CPU0_G0_TX_DP<2>")
	)
	(segment
		(start 114.406934 -223.746568)
		(end 114.407696 -223.747076)
		(width 0.1143)
		(layer "In4.Cu")
		(net "GMI_CPU1_G2_CPU0_G0_TX_DP<2>")
	)
	(segment
		(start 302.913288 -176.955196)
		(end 166.90086 -176.160684)
		(width 0.14224)
		(layer "In4.Cu")
		(net "GMI_CPU1_G2_CPU0_G0_TX_DP<2>")
	)
	(segment
		(start 114.408712 -223.747584)
		(end 114.439192 -223.765364)
		(width 0.1143)
		(layer "In4.Cu")
		(net "GMI_CPU1_G2_CPU0_G0_TX_DP<2>")
	)
	(segment
		(start 355.781356 -215.026494)
		(end 355.567488 -214.666068)
		(width 0.14224)
		(layer "In4.Cu")
		(net "GMI_CPU1_G2_CPU0_G0_TX_DP<2>")
	)
	(segment
		(start 114.439192 -223.765364)
		(end 114.439954 -223.765872)
		(width 0.1143)
		(layer "In4.Cu")
		(net "GMI_CPU1_G2_CPU0_G0_TX_DP<2>")
	)
	(segment
		(start 115.257834 -215.422226)
		(end 115.045744 -215.783668)
		(width 0.14224)
		(layer "In4.Cu")
		(net "GMI_CPU1_G2_CPU0_G0_TX_DP<2>")
	)
	(segment
		(start 166.90086 -176.160684)
		(end 165.280086 -176.160684)
		(width 0.14224)
		(layer "In4.Cu")
		(net "GMI_CPU1_G2_CPU0_G0_TX_DP<2>")
	)
	(segment
		(start 357.088186 -226.341686)
		(end 357.08717 -226.341178)
		(width 0.1143)
		(layer "In4.Cu")
		(net "GMI_CPU1_G2_CPU0_G0_TX_DP<2>")
	)
	(segment
		(start 357.08717 -223.74733)
		(end 357.088186 -223.746822)
		(width 0.1143)
		(layer "In4.Cu")
		(net "GMI_CPU1_G2_CPU0_G0_TX_DP<2>")
	)
	(segment
		(start 355.221032 -214.082884)
		(end 355.007164 -213.722458)
		(width 0.14224)
		(layer "In4.Cu")
		(net "GMI_CPU1_G2_CPU0_G0_TX_DP<2>")
	)
	(segment
		(start 357.088186 -224.721674)
		(end 357.08717 -224.721166)
		(width 0.1143)
		(layer "In4.Cu")
		(net "GMI_CPU1_G2_CPU0_G0_TX_DP<2>")
	)
	(segment
		(start 165.280086 -176.160684)
		(end 156.917136 -179.151026)
		(width 0.14224)
		(layer "In4.Cu")
		(net "GMI_CPU1_G2_CPU0_G0_TX_DP<2>")
	)
	(segment
		(start 114.375946 -223.728788)
		(end 114.406934 -223.746568)
		(width 0.1143)
		(layer "In4.Cu")
		(net "GMI_CPU1_G2_CPU0_G0_TX_DP<2>")
	)
	(segment
		(start 357.119936 -224.739962)
		(end 357.088948 -224.722182)
		(width 0.1143)
		(layer "In4.Cu")
		(net "GMI_CPU1_G2_CPU0_G0_TX_DP<2>")
	)
	(segment
		(start 357.079804 -216.95918)
		(end 356.902004 -216.913968)
		(width 0.14224)
		(layer "In4.Cu")
		(net "GMI_CPU1_G2_CPU0_G0_TX_DP<2>")
	)
	(segment
		(start 354.44684 -212.778594)
		(end 354.492306 -212.601302)
		(width 0.14224)
		(layer "In4.Cu")
		(net "GMI_CPU1_G2_CPU0_G0_TX_DP<2>")
	)
	(segment
		(start 114.21999 -221.410784)
		(end 114.21999 -221.804484)
		(width 0.1143)
		(layer "In4.Cu")
		(net "GMI_CPU1_G2_CPU0_G0_TX_DP<2>")
	)
	(segment
		(start 356.34168 -215.970358)
		(end 356.127812 -215.609678)
		(width 0.14224)
		(layer "In4.Cu")
		(net "GMI_CPU1_G2_CPU0_G0_TX_DP<2>")
	)
	(segment
		(start 355.959156 -215.07196)
		(end 355.781356 -215.026494)
		(width 0.14224)
		(layer "In4.Cu")
		(net "GMI_CPU1_G2_CPU0_G0_TX_DP<2>")
	)
	(segment
		(start 114.446812 -223.079056)
		(end 114.410236 -223.100392)
		(width 0.1143)
		(layer "In4.Cu")
		(net "GMI_CPU1_G2_CPU0_G0_TX_DP<2>")
	)
	(segment
		(start 357.088948 -226.986338)
		(end 357.119936 -226.968558)
		(width 0.1143)
		(layer "In4.Cu")
		(net "GMI_CPU1_G2_CPU0_G0_TX_DP<2>")
	)
	(segment
		(start 114.407696 -226.9871)
		(end 114.408712 -226.987608)
		(width 0.1143)
		(layer "In4.Cu")
		(net "GMI_CPU1_G2_CPU0_G0_TX_DP<2>")
	)
	(segment
		(start 114.766852 -227.474526)
		(end 115.064794 -227.474526)
		(width 0.1143)
		(layer "In4.Cu")
		(net "GMI_CPU1_G2_CPU0_G0_TX_DP<2>")
	)
	(segment
		(start 116.202968 -214.068152)
		(end 115.990878 -214.429848)
		(width 0.14224)
		(layer "In4.Cu")
		(net "GMI_CPU1_G2_CPU0_G0_TX_DP<2>")
	)
	(segment
		(start 357.088948 -223.746314)
		(end 357.119936 -223.728534)
		(width 0.1143)
		(layer "In4.Cu")
		(net "GMI_CPU1_G2_CPU0_G0_TX_DP<2>")
	)
	(segment
		(start 115.64747 -215.014556)
		(end 115.43538 -215.376252)
		(width 0.14224)
		(layer "In4.Cu")
		(net "GMI_CPU1_G2_CPU0_G0_TX_DP<2>")
	)
	(segment
		(start 357.085646 -223.100138)
		(end 357.04907 -223.078802)
		(width 0.1143)
		(layer "In4.Cu")
		(net "GMI_CPU1_G2_CPU0_G0_TX_DP<2>")
	)
	(segment
		(start 114.439954 -227.005896)
		(end 114.446812 -227.00996)
		(width 0.1143)
		(layer "In4.Cu")
		(net "GMI_CPU1_G2_CPU0_G0_TX_DP<2>")
	)
	(segment
		(start 114.406934 -225.36658)
		(end 114.407696 -225.367088)
		(width 0.1143)
		(layer "In4.Cu")
		(net "GMI_CPU1_G2_CPU0_G0_TX_DP<2>")
	)
	(segment
		(start 114.702336 -216.36863)
		(end 114.20221 -217.221054)
		(width 0.14224)
		(layer "In4.Cu")
		(net "GMI_CPU1_G2_CPU0_G0_TX_DP<2>")
	)
	(segment
		(start 357.088186 -223.746822)
		(end 357.088948 -223.746314)
		(width 0.1143)
		(layer "In4.Cu")
		(net "GMI_CPU1_G2_CPU0_G0_TX_DP<2>")
	)
	(segment
		(start 356.733348 -216.375742)
		(end 356.51948 -216.01557)
		(width 0.14224)
		(layer "In4.Cu")
		(net "GMI_CPU1_G2_CPU0_G0_TX_DP<2>")
	)
	(segment
		(start 357.0859 -223.748092)
		(end 357.08717 -223.74733)
		(width 0.1143)
		(layer "In4.Cu")
		(net "GMI_CPU1_G2_CPU0_G0_TX_DP<2>")
	)
	(segment
		(start 356.902004 -216.913968)
		(end 356.688136 -216.553288)
		(width 0.14224)
		(layer "In4.Cu")
		(net "GMI_CPU1_G2_CPU0_G0_TX_DP<2>")
	)
	(segment
		(start 114.446812 -224.699068)
		(end 114.410236 -224.720404)
		(width 0.1143)
		(layer "In4.Cu")
		(net "GMI_CPU1_G2_CPU0_G0_TX_DP<2>")
	)
	(segment
		(start 357.275892 -221.41053)
		(end 357.339392 -221.34703)
		(width 0.1143)
		(layer "In4.Cu")
		(net "GMI_CPU1_G2_CPU0_G0_TX_DP<2>")
	)
	(segment
		(start 114.20221 -221.05493)
		(end 114.20221 -221.083378)
		(width 0.1143)
		(layer "In4.Cu")
		(net "GMI_CPU1_G2_CPU0_G0_TX_DP<2>")
	)
	(segment
		(start 114.407696 -225.367088)
		(end 114.408712 -225.367596)
		(width 0.1143)
		(layer "In4.Cu")
		(net "GMI_CPU1_G2_CPU0_G0_TX_DP<2>")
	)
	(segment
		(start 357.088948 -226.342194)
		(end 357.088186 -226.341686)
		(width 0.1143)
		(layer "In4.Cu")
		(net "GMI_CPU1_G2_CPU0_G0_TX_DP<2>")
	)
	(segment
		(start 114.406934 -224.722436)
		(end 114.375946 -224.740216)
		(width 0.1143)
		(layer "In4.Cu")
		(net "GMI_CPU1_G2_CPU0_G0_TX_DP<2>")
	)
	(segment
		(start 357.08717 -223.101154)
		(end 357.085646 -223.100138)
		(width 0.1143)
		(layer "In4.Cu")
		(net "GMI_CPU1_G2_CPU0_G0_TX_DP<2>")
	)
	(segment
		(start 357.088948 -224.722182)
		(end 357.088186 -224.721674)
		(width 0.1143)
		(layer "In4.Cu")
		(net "GMI_CPU1_G2_CPU0_G0_TX_DP<2>")
	)
	(segment
		(start 114.407696 -223.101916)
		(end 114.406934 -223.102424)
		(width 0.1143)
		(layer "In4.Cu")
		(net "GMI_CPU1_G2_CPU0_G0_TX_DP<2>")
	)
	(segment
		(start 114.20221 -217.221054)
		(end 114.20221 -221.05493)
		(width 0.14224)
		(layer "In4.Cu")
		(net "GMI_CPU1_G2_CPU0_G0_TX_DP<2>")
	)
	(segment
		(start 357.119936 -223.11995)
		(end 357.088948 -223.10217)
		(width 0.1143)
		(layer "In4.Cu")
		(net "GMI_CPU1_G2_CPU0_G0_TX_DP<2>")
	)
	(segment
		(start 354.660962 -213.139274)
		(end 354.44684 -212.778594)
		(width 0.14224)
		(layer "In4.Cu")
		(net "GMI_CPU1_G2_CPU0_G0_TX_DP<2>")
	)
	(segment
		(start 357.08717 -226.987354)
		(end 357.088186 -226.986846)
		(width 0.1143)
		(layer "In4.Cu")
		(net "GMI_CPU1_G2_CPU0_G0_TX_DP<2>")
	)
	(segment
		(start 115.43538 -215.376252)
		(end 115.257834 -215.422226)
		(width 0.14224)
		(layer "In4.Cu")
		(net "GMI_CPU1_G2_CPU0_G0_TX_DP<2>")
	)
	(segment
		(start 114.407696 -224.721928)
		(end 114.406934 -224.722436)
		(width 0.1143)
		(layer "In4.Cu")
		(net "GMI_CPU1_G2_CPU0_G0_TX_DP<2>")
	)
	(segment
		(start 355.6127 -214.488522)
		(end 355.398832 -214.12835)
		(width 0.14224)
		(layer "In4.Cu")
		(net "GMI_CPU1_G2_CPU0_G0_TX_DP<2>")
	)
	(segment
		(start 117.64772 -211.349844)
		(end 116.15674 -213.89086)
		(width 0.14224)
		(layer "In4.Cu")
		(net "GMI_CPU1_G2_CPU0_G0_TX_DP<2>")
	)
	(segment
		(start 357.088948 -225.366326)
		(end 357.119936 -225.348546)
		(width 0.1143)
		(layer "In4.Cu")
		(net "GMI_CPU1_G2_CPU0_G0_TX_DP<2>")
	)
	(segment
		(start 114.407696 -222.127064)
		(end 114.446812 -222.149924)
		(width 0.1143)
		(layer "In4.Cu")
		(net "GMI_CPU1_G2_CPU0_G0_TX_DP<2>")
	)
	(segment
		(start 357.085646 -226.340162)
		(end 357.04907 -226.318826)
		(width 0.1143)
		(layer "In4.Cu")
		(net "GMI_CPU1_G2_CPU0_G0_TX_DP<2>")
	)
	(segment
		(start 356.51948 -216.01557)
		(end 356.34168 -215.970358)
		(width 0.14224)
		(layer "In4.Cu")
		(net "GMI_CPU1_G2_CPU0_G0_TX_DP<2>")
	)
	(segment
		(start 114.407696 -226.34194)
		(end 114.406934 -226.342448)
		(width 0.1143)
		(layer "In4.Cu")
		(net "GMI_CPU1_G2_CPU0_G0_TX_DP<2>")
	)
	(segment
		(start 357.08717 -225.367342)
		(end 357.088186 -225.366834)
		(width 0.1143)
		(layer "In4.Cu")
		(net "GMI_CPU1_G2_CPU0_G0_TX_DP<2>")
	)
	(segment
		(start 115.091972 -215.96096)
		(end 114.879882 -216.322656)
		(width 0.14224)
		(layer "In4.Cu")
		(net "GMI_CPU1_G2_CPU0_G0_TX_DP<2>")
	)
	(segment
		(start 357.293672 -217.319352)
		(end 357.079804 -216.95918)
		(width 0.14224)
		(layer "In4.Cu")
		(net "GMI_CPU1_G2_CPU0_G0_TX_DP<2>")
	)
	(segment
		(start 114.375946 -223.120204)
		(end 114.356134 -223.134428)
		(width 0.1143)
		(layer "In4.Cu")
		(net "GMI_CPU1_G2_CPU0_G0_TX_DP<2>")
	)
	(segment
		(start 156.917136 -179.151026)
		(end 117.64772 -211.349844)
		(width 0.14224)
		(layer "In4.Cu")
		(net "GMI_CPU1_G2_CPU0_G0_TX_DP<2>")
	)
	(segment
		(start 115.045744 -215.783668)
		(end 115.091972 -215.96096)
		(width 0.14224)
		(layer "In4.Cu")
		(net "GMI_CPU1_G2_CPU0_G0_TX_DP<2>")
	)
	(segment
		(start 114.410236 -224.720404)
		(end 114.408712 -224.72142)
		(width 0.1143)
		(layer "In4.Cu")
		(net "GMI_CPU1_G2_CPU0_G0_TX_DP<2>")
	)
	(segment
		(start 357.293672 -221.083124)
		(end 357.293672 -217.319352)
		(width 0.14224)
		(layer "In4.Cu")
		(net "GMI_CPU1_G2_CPU0_G0_TX_DP<2>")
	)
	(segment
		(start 357.085646 -224.72015)
		(end 357.04907 -224.698814)
		(width 0.1143)
		(layer "In4.Cu")
		(net "GMI_CPU1_G2_CPU0_G0_TX_DP<2>")
	)
	(segment
		(start 310.648096 -177.760884)
		(end 308.394862 -176.955196)
		(width 0.14224)
		(layer "In4.Cu")
		(net "GMI_CPU1_G2_CPU0_G0_TX_DP<2>")
	)
	(segment
		(start 357.04907 -223.769682)
		(end 357.085138 -223.7486)
		(width 0.1143)
		(layer "In4.Cu")
		(net "GMI_CPU1_G2_CPU0_G0_TX_DP<2>")
	)
	(segment
		(start 356.127812 -215.609678)
		(end 356.173024 -215.432132)
		(width 0.14224)
		(layer "In4.Cu")
		(net "GMI_CPU1_G2_CPU0_G0_TX_DP<2>")
	)
	(segment
		(start 114.410236 -226.340416)
		(end 114.408712 -226.341432)
		(width 0.1143)
		(layer "In4.Cu")
		(net "GMI_CPU1_G2_CPU0_G0_TX_DP<2>")
	)
	(segment
		(start 114.439954 -223.765872)
		(end 114.446812 -223.769936)
		(width 0.1143)
		(layer "In4.Cu")
		(net "GMI_CPU1_G2_CPU0_G0_TX_DP<2>")
	)
	(segment
		(start 357.04907 -227.009706)
		(end 357.085138 -226.988624)
		(width 0.1143)
		(layer "In4.Cu")
		(net "GMI_CPU1_G2_CPU0_G0_TX_DP<2>")
	)
	(segment
		(start 114.408712 -226.987608)
		(end 114.439192 -227.005388)
		(width 0.1143)
		(layer "In4.Cu")
		(net "GMI_CPU1_G2_CPU0_G0_TX_DP<2>")
	)
	(segment
		(start 357.088186 -225.366834)
		(end 357.088948 -225.366326)
		(width 0.1143)
		(layer "In4.Cu")
		(net "GMI_CPU1_G2_CPU0_G0_TX_DP<2>")
	)
	(segment
		(start 357.088948 -223.10217)
		(end 357.088186 -223.101662)
		(width 0.1143)
		(layer "In4.Cu")
		(net "GMI_CPU1_G2_CPU0_G0_TX_DP<2>")
	)
	(segment
		(start 114.410236 -223.100392)
		(end 114.408712 -223.101408)
		(width 0.1143)
		(layer "In4.Cu")
		(net "GMI_CPU1_G2_CPU0_G0_TX_DP<2>")
	)
	(segment
		(start 357.08717 -224.721166)
		(end 357.085646 -224.72015)
		(width 0.1143)
		(layer "In4.Cu")
		(net "GMI_CPU1_G2_CPU0_G0_TX_DP<2>")
	)
	(segment
		(start 114.35715 -225.335084)
		(end 114.375946 -225.3488)
		(width 0.1143)
		(layer "In4.Cu")
		(net "GMI_CPU1_G2_CPU0_G0_TX_DP<2>")
	)
	(segment
		(start 114.375946 -225.3488)
		(end 114.406934 -225.36658)
		(width 0.1143)
		(layer "In4.Cu")
		(net "GMI_CPU1_G2_CPU0_G0_TX_DP<2>")
	)
	(segment
		(start 114.375946 -222.108776)
		(end 114.407696 -222.127064)
		(width 0.1143)
		(layer "In4.Cu")
		(net "GMI_CPU1_G2_CPU0_G0_TX_DP<2>")
	)
	(arc
		(start 356.811834 -227.391468)
		(mid 356.813622 -227.380019)
		(end 356.815644 -227.368608)
		(width 0.1143)
		(layer "In4.Cu")
		(net "GMI_CPU1_G2_CPU0_G0_TX_DP<2>")
	)
	(arc
		(start 356.815644 -227.368608)
		(mid 356.897077 -227.16621)
		(end 357.04907 -227.009706)
		(width 0.1143)
		(layer "In4.Cu")
		(net "GMI_CPU1_G2_CPU0_G0_TX_DP<2>")
	)
	(arc
		(start 357.04907 -223.078802)
		(mid 356.805743 -222.614236)
		(end 357.04907 -222.14967)
		(width 0.1143)
		(layer "In4.Cu")
		(net "GMI_CPU1_G2_CPU0_G0_TX_DP<2>")
	)
	(arc
		(start 114.21999 -221.804484)
		(mid 114.261245 -221.975455)
		(end 114.375946 -222.108776)
		(width 0.1143)
		(layer "In4.Cu")
		(net "GMI_CPU1_G2_CPU0_G0_TX_DP<2>")
	)
	(arc
		(start 357.139748 -223.71431)
		(mid 357.288462 -223.424242)
		(end 357.139748 -223.134174)
		(width 0.1143)
		(layer "In4.Cu")
		(net "GMI_CPU1_G2_CPU0_G0_TX_DP<2>")
	)
	(arc
		(start 357.119936 -226.968558)
		(mid 357.269033 -226.664266)
		(end 357.119936 -226.359974)
		(width 0.1143)
		(layer "In4.Cu")
		(net "GMI_CPU1_G2_CPU0_G0_TX_DP<2>")
	)
	(arc
		(start 114.375946 -226.360228)
		(mid 114.226849 -226.66452)
		(end 114.375946 -226.968812)
		(width 0.1143)
		(layer "In4.Cu")
		(net "GMI_CPU1_G2_CPU0_G0_TX_DP<2>")
	)
	(arc
		(start 114.356134 -223.134428)
		(mid 114.20742 -223.424496)
		(end 114.356134 -223.714564)
		(width 0.1143)
		(layer "In4.Cu")
		(net "GMI_CPU1_G2_CPU0_G0_TX_DP<2>")
	)
	(arc
		(start 357.119936 -222.108522)
		(mid 357.234612 -221.975188)
		(end 357.275892 -221.80423)
		(width 0.1143)
		(layer "In4.Cu")
		(net "GMI_CPU1_G2_CPU0_G0_TX_DP<2>")
	)
	(arc
		(start 357.138732 -225.33483)
		(mid 357.287647 -225.044254)
		(end 357.138732 -224.753678)
		(width 0.1143)
		(layer "In4.Cu")
		(net "GMI_CPU1_G2_CPU0_G0_TX_DP<2>")
	)
	(arc
		(start 114.35715 -224.753932)
		(mid 114.208235 -225.044508)
		(end 114.35715 -225.335084)
		(width 0.1143)
		(layer "In4.Cu")
		(net "GMI_CPU1_G2_CPU0_G0_TX_DP<2>")
	)
	(arc
		(start 114.446812 -227.00996)
		(mid 114.605017 -227.176247)
		(end 114.684048 -227.391722)
		(width 0.1143)
		(layer "In4.Cu")
		(net "GMI_CPU1_G2_CPU0_G0_TX_DP<2>")
	)
	(arc
		(start 357.04907 -224.698814)
		(mid 356.805743 -224.234248)
		(end 357.04907 -223.769682)
		(width 0.1143)
		(layer "In4.Cu")
		(net "GMI_CPU1_G2_CPU0_G0_TX_DP<2>")
	)
	(arc
		(start 357.04907 -226.318826)
		(mid 356.805743 -225.85426)
		(end 357.04907 -225.389694)
		(width 0.1143)
		(layer "In4.Cu")
		(net "GMI_CPU1_G2_CPU0_G0_TX_DP<2>")
	)
	(arc
		(start 114.446812 -225.389948)
		(mid 114.690139 -225.854514)
		(end 114.446812 -226.31908)
		(width 0.1143)
		(layer "In4.Cu")
		(net "GMI_CPU1_G2_CPU0_G0_TX_DP<2>")
	)
	(arc
		(start 114.446812 -222.149924)
		(mid 114.690139 -222.61449)
		(end 114.446812 -223.079056)
		(width 0.1143)
		(layer "In4.Cu")
		(net "GMI_CPU1_G2_CPU0_G0_TX_DP<2>")
	)
	(arc
		(start 114.446812 -223.769936)
		(mid 114.690139 -224.234502)
		(end 114.446812 -224.699068)
		(width 0.1143)
		(layer "In4.Cu")
		(net "GMI_CPU1_G2_CPU0_G0_TX_DP<2>")
	)
	(segment
		(start 356.89794 -229.360222)
		(end 356.431088 -229.094284)
		(width 0.12954)
		(layer "F.Cu")
		(net "GMI_CPU1_G2_CPU0_G0_TX_DP<1>")
	)
	(segment
		(start 114.597942 -229.360476)
		(end 115.064794 -229.094538)
		(width 0.12954)
		(layer "F.Cu")
		(net "GMI_CPU1_G2_CPU0_G0_TX_DP<1>")
	)
	(segment
		(start 114.183414 -228.084126)
		(end 114.21491 -228.084126)
		(width 0.1143)
		(layer "In4.Cu")
		(net "GMI_CPU1_G2_CPU0_G0_TX_DP<1>")
	)
	(segment
		(start 358.02824 -222.12681)
		(end 358.029002 -222.126302)
		(width 0.1143)
		(layer "In4.Cu")
		(net "GMI_CPU1_G2_CPU0_G0_TX_DP<1>")
	)
	(segment
		(start 113.468658 -222.127572)
		(end 113.506758 -222.149924)
		(width 0.1143)
		(layer "In4.Cu")
		(net "GMI_CPU1_G2_CPU0_G0_TX_DP<1>")
	)
	(segment
		(start 114.766852 -229.094538)
		(end 115.064794 -229.094538)
		(width 0.1143)
		(layer "In4.Cu")
		(net "GMI_CPU1_G2_CPU0_G0_TX_DP<1>")
	)
	(segment
		(start 357.093266 -228.60381)
		(end 357.111554 -228.593396)
		(width 0.1143)
		(layer "In4.Cu")
		(net "GMI_CPU1_G2_CPU0_G0_TX_DP<1>")
	)
	(segment
		(start 114.202972 -215.346534)
		(end 114.025426 -215.392762)
		(width 0.14224)
		(layer "In4.Cu")
		(net "GMI_CPU1_G2_CPU0_G0_TX_DP<1>")
	)
	(segment
		(start 113.467134 -225.368104)
		(end 113.470182 -225.369882)
		(width 0.1143)
		(layer "In4.Cu")
		(net "GMI_CPU1_G2_CPU0_G0_TX_DP<1>")
	)
	(segment
		(start 114.402616 -228.604064)
		(end 114.406934 -228.606604)
		(width 0.1143)
		(layer "In4.Cu")
		(net "GMI_CPU1_G2_CPU0_G0_TX_DP<1>")
	)
	(segment
		(start 113.437162 -223.729296)
		(end 113.467642 -223.747076)
		(width 0.1143)
		(layer "In4.Cu")
		(net "GMI_CPU1_G2_CPU0_G0_TX_DP<1>")
	)
	(segment
		(start 113.506758 -226.31908)
		(end 113.438432 -226.358958)
		(width 0.1143)
		(layer "In4.Cu")
		(net "GMI_CPU1_G2_CPU0_G0_TX_DP<1>")
	)
	(segment
		(start 357.496364 -227.835714)
		(end 357.520494 -227.818696)
		(width 0.1143)
		(layer "In4.Cu")
		(net "GMI_CPU1_G2_CPU0_G0_TX_DP<1>")
	)
	(segment
		(start 356.918006 -214.598504)
		(end 356.740206 -214.553038)
		(width 0.14224)
		(layer "In4.Cu")
		(net "GMI_CPU1_G2_CPU0_G0_TX_DP<1>")
	)
	(segment
		(start 113.470182 -224.720404)
		(end 113.467642 -224.721928)
		(width 0.1143)
		(layer "In4.Cu")
		(net "GMI_CPU1_G2_CPU0_G0_TX_DP<1>")
	)
	(segment
		(start 356.431088 -229.094284)
		(end 356.72903 -229.094284)
		(width 0.1143)
		(layer "In4.Cu")
		(net "GMI_CPU1_G2_CPU0_G0_TX_DP<1>")
	)
	(segment
		(start 165.021768 -175.226726)
		(end 160.767522 -176.747932)
		(width 0.14224)
		(layer "In4.Cu")
		(net "GMI_CPU1_G2_CPU0_G0_TX_DP<1>")
	)
	(segment
		(start 355.451156 -212.127846)
		(end 354.73513 -210.921346)
		(width 0.14224)
		(layer "In4.Cu")
		(net "GMI_CPU1_G2_CPU0_G0_TX_DP<1>")
	)
	(segment
		(start 357.989124 -222.14967)
		(end 358.027224 -222.127318)
		(width 0.1143)
		(layer "In4.Cu")
		(net "GMI_CPU1_G2_CPU0_G0_TX_DP<1>")
	)
	(segment
		(start 358.238552 -216.822274)
		(end 358.038654 -216.485724)
		(width 0.14224)
		(layer "In4.Cu")
		(net "GMI_CPU1_G2_CPU0_G0_TX_DP<1>")
	)
	(segment
		(start 113.279936 -225.044508)
		(end 113.28019 -225.044508)
		(width 0.1143)
		(layer "In4.Cu")
		(net "GMI_CPU1_G2_CPU0_G0_TX_DP<1>")
	)
	(segment
		(start 357.989124 -223.769682)
		(end 358.05872 -223.729042)
		(width 0.1143)
		(layer "In4.Cu")
		(net "GMI_CPU1_G2_CPU0_G0_TX_DP<1>")
	)
	(segment
		(start 114.369088 -214.8078)
		(end 114.415316 -214.985092)
		(width 0.14224)
		(layer "In4.Cu")
		(net "GMI_CPU1_G2_CPU0_G0_TX_DP<1>")
	)
	(segment
		(start 113.467642 -224.721928)
		(end 113.46434 -224.723706)
		(width 0.1143)
		(layer "In4.Cu")
		(net "GMI_CPU1_G2_CPU0_G0_TX_DP<1>")
	)
	(segment
		(start 358.038654 -216.485724)
		(end 357.860854 -216.440512)
		(width 0.14224)
		(layer "In4.Cu")
		(net "GMI_CPU1_G2_CPU0_G0_TX_DP<1>")
	)
	(segment
		(start 356.57155 -214.015066)
		(end 356.357682 -213.654894)
		(width 0.14224)
		(layer "In4.Cu")
		(net "GMI_CPU1_G2_CPU0_G0_TX_DP<1>")
	)
	(segment
		(start 114.406934 -228.606604)
		(end 114.407696 -228.607112)
		(width 0.1143)
		(layer "In4.Cu")
		(net "GMI_CPU1_G2_CPU0_G0_TX_DP<1>")
	)
	(segment
		(start 355.40569 -212.305138)
		(end 355.451156 -212.127846)
		(width 0.14224)
		(layer "In4.Cu")
		(net "GMI_CPU1_G2_CPU0_G0_TX_DP<1>")
	)
	(segment
		(start 357.131874 -214.958676)
		(end 356.918006 -214.598504)
		(width 0.14224)
		(layer "In4.Cu")
		(net "GMI_CPU1_G2_CPU0_G0_TX_DP<1>")
	)
	(segment
		(start 113.279936 -221.494604)
		(end 113.279936 -221.804484)
		(width 0.1143)
		(layer "In4.Cu")
		(net "GMI_CPU1_G2_CPU0_G0_TX_DP<1>")
	)
	(segment
		(start 114.581178 -214.446612)
		(end 114.369088 -214.8078)
		(width 0.14224)
		(layer "In4.Cu")
		(net "GMI_CPU1_G2_CPU0_G0_TX_DP<1>")
	)
	(segment
		(start 357.273352 -228.295454)
		(end 357.273606 -228.294438)
		(width 0.1143)
		(layer "In4.Cu")
		(net "GMI_CPU1_G2_CPU0_G0_TX_DP<1>")
	)
	(segment
		(start 357.520494 -227.818696)
		(end 357.589836 -227.778564)
		(width 0.1143)
		(layer "In4.Cu")
		(net "GMI_CPU1_G2_CPU0_G0_TX_DP<1>")
	)
	(segment
		(start 318.00673 -180.805582)
		(end 314.628784 -178.89347)
		(width 0.14224)
		(layer "In4.Cu")
		(net "GMI_CPU1_G2_CPU0_G0_TX_DP<1>")
	)
	(segment
		(start 114.971068 -214.038942)
		(end 114.758724 -214.400384)
		(width 0.14224)
		(layer "In4.Cu")
		(net "GMI_CPU1_G2_CPU0_G0_TX_DP<1>")
	)
	(segment
		(start 308.57063 -176.022762)
		(end 302.916336 -176.022762)
		(width 0.14224)
		(layer "In4.Cu")
		(net "GMI_CPU1_G2_CPU0_G0_TX_DP<1>")
	)
	(segment
		(start 113.25733 -216.7001)
		(end 113.25733 -221.05493)
		(width 0.14224)
		(layer "In4.Cu")
		(net "GMI_CPU1_G2_CPU0_G0_TX_DP<1>")
	)
	(segment
		(start 113.459006 -222.12173)
		(end 113.46307 -222.12427)
		(width 0.1143)
		(layer "In4.Cu")
		(net "GMI_CPU1_G2_CPU0_G0_TX_DP<1>")
	)
	(segment
		(start 358.036876 -222.121476)
		(end 358.05999 -222.108522)
		(width 0.1143)
		(layer "In4.Cu")
		(net "GMI_CPU1_G2_CPU0_G0_TX_DP<1>")
	)
	(segment
		(start 114.684048 -229.011734)
		(end 114.766852 -229.094538)
		(width 0.1143)
		(layer "In4.Cu")
		(net "GMI_CPU1_G2_CPU0_G0_TX_DP<1>")
	)
	(segment
		(start 355.619812 -212.665818)
		(end 355.40569 -212.305138)
		(width 0.14224)
		(layer "In4.Cu")
		(net "GMI_CPU1_G2_CPU0_G0_TX_DP<1>")
	)
	(segment
		(start 356.526338 -214.192612)
		(end 356.57155 -214.015066)
		(width 0.14224)
		(layer "In4.Cu")
		(net "GMI_CPU1_G2_CPU0_G0_TX_DP<1>")
	)
	(segment
		(start 160.767522 -176.747932)
		(end 160.767776 -176.747932)
		(width 0.14224)
		(layer "In4.Cu")
		(net "GMI_CPU1_G2_CPU0_G0_TX_DP<1>")
	)
	(segment
		(start 114.21491 -228.084126)
		(end 114.220244 -228.269038)
		(width 0.1143)
		(layer "In4.Cu")
		(net "GMI_CPU1_G2_CPU0_G0_TX_DP<1>")
	)
	(segment
		(start 357.04907 -228.629718)
		(end 357.085646 -228.608382)
		(width 0.1143)
		(layer "In4.Cu")
		(net "GMI_CPU1_G2_CPU0_G0_TX_DP<1>")
	)
	(segment
		(start 358.238552 -221.083124)
		(end 358.238552 -216.822274)
		(width 0.14224)
		(layer "In4.Cu")
		(net "GMI_CPU1_G2_CPU0_G0_TX_DP<1>")
	)
	(segment
		(start 114.025426 -215.392762)
		(end 113.813336 -215.75395)
		(width 0.14224)
		(layer "In4.Cu")
		(net "GMI_CPU1_G2_CPU0_G0_TX_DP<1>")
	)
	(segment
		(start 358.0257 -225.369628)
		(end 358.028748 -225.36785)
		(width 0.1143)
		(layer "In4.Cu")
		(net "GMI_CPU1_G2_CPU0_G0_TX_DP<1>")
	)
	(segment
		(start 113.85931 -215.931242)
		(end 113.646966 -216.292684)
		(width 0.14224)
		(layer "In4.Cu")
		(net "GMI_CPU1_G2_CPU0_G0_TX_DP<1>")
	)
	(segment
		(start 113.46307 -222.12427)
		(end 113.46688 -222.126556)
		(width 0.1143)
		(layer "In4.Cu")
		(net "GMI_CPU1_G2_CPU0_G0_TX_DP<1>")
	)
	(segment
		(start 302.916336 -176.022762)
		(end 269.010384 -175.824642)
		(width 0.14224)
		(layer "In4.Cu")
		(net "GMI_CPU1_G2_CPU0_G0_TX_DP<1>")
	)
	(segment
		(start 114.408712 -228.60762)
		(end 114.446812 -228.629972)
		(width 0.1143)
		(layer "In4.Cu")
		(net "GMI_CPU1_G2_CPU0_G0_TX_DP<1>")
	)
	(segment
		(start 113.937796 -227.797106)
		(end 113.974118 -227.818188)
		(width 0.1143)
		(layer "In4.Cu")
		(net "GMI_CPU1_G2_CPU0_G0_TX_DP<1>")
	)
	(segment
		(start 113.506758 -223.079056)
		(end 113.440718 -223.117664)
		(width 0.1143)
		(layer "In4.Cu")
		(net "GMI_CPU1_G2_CPU0_G0_TX_DP<1>")
	)
	(segment
		(start 113.437162 -226.96932)
		(end 113.467642 -226.9871)
		(width 0.1143)
		(layer "In4.Cu")
		(net "GMI_CPU1_G2_CPU0_G0_TX_DP<1>")
	)
	(segment
		(start 357.088948 -228.60635)
		(end 357.093266 -228.60381)
		(width 0.1143)
		(layer "In4.Cu")
		(net "GMI_CPU1_G2_CPU0_G0_TX_DP<1>")
	)
	(segment
		(start 356.011226 -213.071456)
		(end 355.797358 -212.711284)
		(width 0.14224)
		(layer "In4.Cu")
		(net "GMI_CPU1_G2_CPU0_G0_TX_DP<1>")
	)
	(segment
		(start 357.860854 -216.440512)
		(end 357.646986 -216.079832)
		(width 0.14224)
		(layer "In4.Cu")
		(net "GMI_CPU1_G2_CPU0_G0_TX_DP<1>")
	)
	(segment
		(start 357.273606 -228.294438)
		(end 357.273606 -228.281738)
		(width 0.1143)
		(layer "In4.Cu")
		(net "GMI_CPU1_G2_CPU0_G0_TX_DP<1>")
	)
	(segment
		(start 358.215946 -221.80423)
		(end 358.215946 -221.49435)
		(width 0.1143)
		(layer "In4.Cu")
		(net "GMI_CPU1_G2_CPU0_G0_TX_DP<1>")
	)
	(segment
		(start 113.25733 -221.05493)
		(end 113.25733 -221.083378)
		(width 0.1143)
		(layer "In4.Cu")
		(net "GMI_CPU1_G2_CPU0_G0_TX_DP<1>")
	)
	(segment
		(start 114.92484 -213.86165)
		(end 114.971068 -214.038942)
		(width 0.14224)
		(layer "In4.Cu")
		(net "GMI_CPU1_G2_CPU0_G0_TX_DP<1>")
	)
	(segment
		(start 357.08717 -228.607366)
		(end 357.088186 -228.606858)
		(width 0.1143)
		(layer "In4.Cu")
		(net "GMI_CPU1_G2_CPU0_G0_TX_DP<1>")
	)
	(segment
		(start 113.25733 -221.083378)
		(end 113.21161 -221.129098)
		(width 0.1143)
		(layer "In4.Cu")
		(net "GMI_CPU1_G2_CPU0_G0_TX_DP<1>")
	)
	(segment
		(start 113.813336 -215.75395)
		(end 113.85931 -215.931242)
		(width 0.14224)
		(layer "In4.Cu")
		(net "GMI_CPU1_G2_CPU0_G0_TX_DP<1>")
	)
	(segment
		(start 113.646966 -216.292684)
		(end 113.46942 -216.338912)
		(width 0.14224)
		(layer "In4.Cu")
		(net "GMI_CPU1_G2_CPU0_G0_TX_DP<1>")
	)
	(segment
		(start 358.032812 -222.124016)
		(end 358.036876 -222.121476)
		(width 0.1143)
		(layer "In4.Cu")
		(net "GMI_CPU1_G2_CPU0_G0_TX_DP<1>")
	)
	(segment
		(start 357.275892 -228.279452)
		(end 357.275892 -228.26599)
		(width 0.1143)
		(layer "In4.Cu")
		(net "GMI_CPU1_G2_CPU0_G0_TX_DP<1>")
	)
	(segment
		(start 156.513276 -178.269138)
		(end 116.614956 -210.984338)
		(width 0.14224)
		(layer "In4.Cu")
		(net "GMI_CPU1_G2_CPU0_G0_TX_DP<1>")
	)
	(segment
		(start 358.215692 -225.044254)
		(end 358.215946 -225.044254)
		(width 0.1143)
		(layer "In4.Cu")
		(net "GMI_CPU1_G2_CPU0_G0_TX_DP<1>")
	)
	(segment
		(start 356.740206 -214.553038)
		(end 356.526338 -214.192612)
		(width 0.14224)
		(layer "In4.Cu")
		(net "GMI_CPU1_G2_CPU0_G0_TX_DP<1>")
	)
	(segment
		(start 358.284272 -221.426024)
		(end 358.284272 -221.128844)
		(width 0.1143)
		(layer "In4.Cu")
		(net "GMI_CPU1_G2_CPU0_G0_TX_DP<1>")
	)
	(segment
		(start 113.906046 -227.778818)
		(end 113.937796 -227.797106)
		(width 0.1143)
		(layer "In4.Cu")
		(net "GMI_CPU1_G2_CPU0_G0_TX_DP<1>")
	)
	(segment
		(start 114.415316 -214.985092)
		(end 114.202972 -215.346534)
		(width 0.14224)
		(layer "In4.Cu")
		(net "GMI_CPU1_G2_CPU0_G0_TX_DP<1>")
	)
	(segment
		(start 357.30053 -215.496902)
		(end 357.086662 -215.136222)
		(width 0.14224)
		(layer "In4.Cu")
		(net "GMI_CPU1_G2_CPU0_G0_TX_DP<1>")
	)
	(segment
		(start 113.467642 -226.9871)
		(end 113.506758 -227.00996)
		(width 0.1143)
		(layer "In4.Cu")
		(net "GMI_CPU1_G2_CPU0_G0_TX_DP<1>")
	)
	(segment
		(start 357.086662 -215.136222)
		(end 357.131874 -214.958676)
		(width 0.14224)
		(layer "In4.Cu")
		(net "GMI_CPU1_G2_CPU0_G0_TX_DP<1>")
	)
	(segment
		(start 358.055164 -223.11741)
		(end 357.989124 -223.078802)
		(width 0.1143)
		(layer "In4.Cu")
		(net "GMI_CPU1_G2_CPU0_G0_TX_DP<1>")
	)
	(segment
		(start 113.467642 -222.127064)
		(end 113.468658 -222.127572)
		(width 0.1143)
		(layer "In4.Cu")
		(net "GMI_CPU1_G2_CPU0_G0_TX_DP<1>")
	)
	(segment
		(start 114.384328 -228.59365)
		(end 114.402616 -228.604064)
		(width 0.1143)
		(layer "In4.Cu")
		(net "GMI_CPU1_G2_CPU0_G0_TX_DP<1>")
	)
	(segment
		(start 357.646986 -216.079832)
		(end 357.692198 -215.902286)
		(width 0.14224)
		(layer "In4.Cu")
		(net "GMI_CPU1_G2_CPU0_G0_TX_DP<1>")
	)
	(segment
		(start 113.435892 -222.108776)
		(end 113.459006 -222.12173)
		(width 0.1143)
		(layer "In4.Cu")
		(net "GMI_CPU1_G2_CPU0_G0_TX_DP<1>")
	)
	(segment
		(start 269.010384 -175.824642)
		(end 166.757096 -175.226726)
		(width 0.14224)
		(layer "In4.Cu")
		(net "GMI_CPU1_G2_CPU0_G0_TX_DP<1>")
	)
	(segment
		(start 116.614956 -210.984338)
		(end 114.92484 -213.86165)
		(width 0.14224)
		(layer "In4.Cu")
		(net "GMI_CPU1_G2_CPU0_G0_TX_DP<1>")
	)
	(segment
		(start 354.73513 -210.921346)
		(end 318.00673 -180.805582)
		(width 0.14224)
		(layer "In4.Cu")
		(net "GMI_CPU1_G2_CPU0_G0_TX_DP<1>")
	)
	(segment
		(start 358.029002 -222.126302)
		(end 358.032812 -222.124016)
		(width 0.1143)
		(layer "In4.Cu")
		(net "GMI_CPU1_G2_CPU0_G0_TX_DP<1>")
	)
	(segment
		(start 357.989124 -227.009706)
		(end 358.05872 -226.969066)
		(width 0.1143)
		(layer "In4.Cu")
		(net "GMI_CPU1_G2_CPU0_G0_TX_DP<1>")
	)
	(segment
		(start 356.72903 -229.094284)
		(end 356.811834 -229.01148)
		(width 0.1143)
		(layer "In4.Cu")
		(net "GMI_CPU1_G2_CPU0_G0_TX_DP<1>")
	)
	(segment
		(start 113.21161 -221.129098)
		(end 113.21161 -221.426278)
		(width 0.1143)
		(layer "In4.Cu")
		(net "GMI_CPU1_G2_CPU0_G0_TX_DP<1>")
	)
	(segment
		(start 358.05745 -226.358704)
		(end 357.989124 -226.318826)
		(width 0.1143)
		(layer "In4.Cu")
		(net "GMI_CPU1_G2_CPU0_G0_TX_DP<1>")
	)
	(segment
		(start 311.250584 -176.981104)
		(end 308.57063 -176.022762)
		(width 0.14224)
		(layer "In4.Cu")
		(net "GMI_CPU1_G2_CPU0_G0_TX_DP<1>")
	)
	(segment
		(start 357.085646 -228.608382)
		(end 357.08717 -228.607366)
		(width 0.1143)
		(layer "In4.Cu")
		(net "GMI_CPU1_G2_CPU0_G0_TX_DP<1>")
	)
	(segment
		(start 358.027224 -222.127318)
		(end 358.02824 -222.12681)
		(width 0.1143)
		(layer "In4.Cu")
		(net "GMI_CPU1_G2_CPU0_G0_TX_DP<1>")
	)
	(segment
		(start 113.46561 -225.367088)
		(end 113.467134 -225.368104)
		(width 0.1143)
		(layer "In4.Cu")
		(net "GMI_CPU1_G2_CPU0_G0_TX_DP<1>")
	)
	(segment
		(start 113.46942 -216.338912)
		(end 113.25733 -216.7001)
		(width 0.14224)
		(layer "In4.Cu")
		(net "GMI_CPU1_G2_CPU0_G0_TX_DP<1>")
	)
	(segment
		(start 357.692198 -215.902286)
		(end 357.47833 -215.542114)
		(width 0.14224)
		(layer "In4.Cu")
		(net "GMI_CPU1_G2_CPU0_G0_TX_DP<1>")
	)
	(segment
		(start 356.179882 -213.609428)
		(end 355.966014 -213.249002)
		(width 0.14224)
		(layer "In4.Cu")
		(net "GMI_CPU1_G2_CPU0_G0_TX_DP<1>")
	)
	(segment
		(start 160.767776 -176.747932)
		(end 156.513276 -178.269138)
		(width 0.14224)
		(layer "In4.Cu")
		(net "GMI_CPU1_G2_CPU0_G0_TX_DP<1>")
	)
	(segment
		(start 357.088186 -228.606858)
		(end 357.088948 -228.60635)
		(width 0.1143)
		(layer "In4.Cu")
		(net "GMI_CPU1_G2_CPU0_G0_TX_DP<1>")
	)
	(segment
		(start 358.284272 -221.128844)
		(end 358.238552 -221.083124)
		(width 0.1143)
		(layer "In4.Cu")
		(net "GMI_CPU1_G2_CPU0_G0_TX_DP<1>")
	)
	(segment
		(start 355.966014 -213.249002)
		(end 356.011226 -213.071456)
		(width 0.14224)
		(layer "In4.Cu")
		(net "GMI_CPU1_G2_CPU0_G0_TX_DP<1>")
	)
	(segment
		(start 358.028748 -225.36785)
		(end 358.030272 -225.366834)
		(width 0.1143)
		(layer "In4.Cu")
		(net "GMI_CPU1_G2_CPU0_G0_TX_DP<1>")
	)
	(segment
		(start 166.757096 -175.226726)
		(end 165.021768 -175.226726)
		(width 0.14224)
		(layer "In4.Cu")
		(net "GMI_CPU1_G2_CPU0_G0_TX_DP<1>")
	)
	(segment
		(start 113.467642 -223.747076)
		(end 113.506758 -223.769936)
		(width 0.1143)
		(layer "In4.Cu")
		(net "GMI_CPU1_G2_CPU0_G0_TX_DP<1>")
	)
	(segment
		(start 357.47833 -215.542114)
		(end 357.30053 -215.496902)
		(width 0.14224)
		(layer "In4.Cu")
		(net "GMI_CPU1_G2_CPU0_G0_TX_DP<1>")
	)
	(segment
		(start 358.031542 -224.723452)
		(end 358.02824 -224.721674)
		(width 0.1143)
		(layer "In4.Cu")
		(net "GMI_CPU1_G2_CPU0_G0_TX_DP<1>")
	)
	(segment
		(start 358.215946 -221.49435)
		(end 358.284272 -221.426024)
		(width 0.1143)
		(layer "In4.Cu")
		(net "GMI_CPU1_G2_CPU0_G0_TX_DP<1>")
	)
	(segment
		(start 355.797358 -212.711284)
		(end 355.619812 -212.665818)
		(width 0.14224)
		(layer "In4.Cu")
		(net "GMI_CPU1_G2_CPU0_G0_TX_DP<1>")
	)
	(segment
		(start 358.02824 -224.721674)
		(end 358.0257 -224.72015)
		(width 0.1143)
		(layer "In4.Cu")
		(net "GMI_CPU1_G2_CPU0_G0_TX_DP<1>")
	)
	(segment
		(start 114.407696 -228.607112)
		(end 114.408712 -228.60762)
		(width 0.1143)
		(layer "In4.Cu")
		(net "GMI_CPU1_G2_CPU0_G0_TX_DP<1>")
	)
	(segment
		(start 113.21161 -221.426278)
		(end 113.279936 -221.494604)
		(width 0.1143)
		(layer "In4.Cu")
		(net "GMI_CPU1_G2_CPU0_G0_TX_DP<1>")
	)
	(segment
		(start 356.357682 -213.654894)
		(end 356.179882 -213.609428)
		(width 0.14224)
		(layer "In4.Cu")
		(net "GMI_CPU1_G2_CPU0_G0_TX_DP<1>")
	)
	(segment
		(start 114.758724 -214.400384)
		(end 114.581178 -214.446612)
		(width 0.14224)
		(layer "In4.Cu")
		(net "GMI_CPU1_G2_CPU0_G0_TX_DP<1>")
	)
	(segment
		(start 357.273606 -228.281738)
		(end 357.275892 -228.279452)
		(width 0.1143)
		(layer "In4.Cu")
		(net "GMI_CPU1_G2_CPU0_G0_TX_DP<1>")
	)
	(segment
		(start 113.46688 -222.126556)
		(end 113.467642 -222.127064)
		(width 0.1143)
		(layer "In4.Cu")
		(net "GMI_CPU1_G2_CPU0_G0_TX_DP<1>")
	)
	(segment
		(start 314.628784 -178.89347)
		(end 311.250584 -176.981104)
		(width 0.14224)
		(layer "In4.Cu")
		(net "GMI_CPU1_G2_CPU0_G0_TX_DP<1>")
	)
	(arc
		(start 113.75009 -227.474526)
		(mid 113.791345 -227.645497)
		(end 113.906046 -227.778818)
		(width 0.1143)
		(layer "In4.Cu")
		(net "GMI_CPU1_G2_CPU0_G0_TX_DP<1>")
	)
	(arc
		(start 113.470182 -225.369882)
		(mid 113.748685 -225.834408)
		(end 113.506758 -226.31908)
		(width 0.1143)
		(layer "In4.Cu")
		(net "GMI_CPU1_G2_CPU0_G0_TX_DP<1>")
	)
	(arc
		(start 113.974118 -227.818188)
		(mid 113.979474 -227.821839)
		(end 113.984786 -227.825554)
		(width 0.1143)
		(layer "In4.Cu")
		(net "GMI_CPU1_G2_CPU0_G0_TX_DP<1>")
	)
	(arc
		(start 357.589836 -227.778564)
		(mid 357.704512 -227.64523)
		(end 357.745792 -227.474272)
		(width 0.1143)
		(layer "In4.Cu")
		(net "GMI_CPU1_G2_CPU0_G0_TX_DP<1>")
	)
	(arc
		(start 113.280444 -223.423226)
		(mid 113.280439 -223.425131)
		(end 113.280444 -223.427036)
		(width 0.1143)
		(layer "In4.Cu")
		(net "GMI_CPU1_G2_CPU0_G0_TX_DP<1>")
	)
	(arc
		(start 357.989124 -223.078802)
		(mid 357.745797 -222.614236)
		(end 357.989124 -222.14967)
		(width 0.1143)
		(layer "In4.Cu")
		(net "GMI_CPU1_G2_CPU0_G0_TX_DP<1>")
	)
	(arc
		(start 114.220244 -228.269038)
		(mid 114.221028 -228.282404)
		(end 114.22253 -228.295708)
		(width 0.1143)
		(layer "In4.Cu")
		(net "GMI_CPU1_G2_CPU0_G0_TX_DP<1>")
	)
	(arc
		(start 358.215946 -225.044254)
		(mid 358.166569 -224.859229)
		(end 358.031542 -224.723452)
		(width 0.1143)
		(layer "In4.Cu")
		(net "GMI_CPU1_G2_CPU0_G0_TX_DP<1>")
	)
	(arc
		(start 356.815644 -228.98862)
		(mid 356.897077 -228.786222)
		(end 357.04907 -228.629718)
		(width 0.1143)
		(layer "In4.Cu")
		(net "GMI_CPU1_G2_CPU0_G0_TX_DP<1>")
	)
	(arc
		(start 358.215438 -223.422972)
		(mid 358.166283 -223.253949)
		(end 358.055164 -223.11741)
		(width 0.1143)
		(layer "In4.Cu")
		(net "GMI_CPU1_G2_CPU0_G0_TX_DP<1>")
	)
	(arc
		(start 113.46434 -224.723706)
		(mid 113.329357 -224.859508)
		(end 113.279936 -225.044508)
		(width 0.1143)
		(layer "In4.Cu")
		(net "GMI_CPU1_G2_CPU0_G0_TX_DP<1>")
	)
	(arc
		(start 357.745792 -227.474272)
		(mid 357.810307 -227.212053)
		(end 357.989124 -227.009706)
		(width 0.1143)
		(layer "In4.Cu")
		(net "GMI_CPU1_G2_CPU0_G0_TX_DP<1>")
	)
	(arc
		(start 113.28019 -226.66452)
		(mid 113.321739 -226.835942)
		(end 113.437162 -226.96932)
		(width 0.1143)
		(layer "In4.Cu")
		(net "GMI_CPU1_G2_CPU0_G0_TX_DP<1>")
	)
	(arc
		(start 358.05872 -226.969066)
		(mid 358.174147 -226.83569)
		(end 358.215692 -226.664266)
		(width 0.1143)
		(layer "In4.Cu")
		(net "GMI_CPU1_G2_CPU0_G0_TX_DP<1>")
	)
	(arc
		(start 357.275892 -228.26599)
		(mid 357.334219 -228.024254)
		(end 357.496364 -227.835714)
		(width 0.1143)
		(layer "In4.Cu")
		(net "GMI_CPU1_G2_CPU0_G0_TX_DP<1>")
	)
	(arc
		(start 356.811834 -229.01148)
		(mid 356.813622 -229.000031)
		(end 356.815644 -228.98862)
		(width 0.1143)
		(layer "In4.Cu")
		(net "GMI_CPU1_G2_CPU0_G0_TX_DP<1>")
	)
	(arc
		(start 358.215438 -223.426782)
		(mid 358.215442 -223.424877)
		(end 358.215438 -223.422972)
		(width 0.1143)
		(layer "In4.Cu")
		(net "GMI_CPU1_G2_CPU0_G0_TX_DP<1>")
	)
	(arc
		(start 113.506758 -223.769936)
		(mid 113.74916 -224.255187)
		(end 113.470182 -224.720404)
		(width 0.1143)
		(layer "In4.Cu")
		(net "GMI_CPU1_G2_CPU0_G0_TX_DP<1>")
	)
	(arc
		(start 114.446812 -228.629972)
		(mid 114.605017 -228.796259)
		(end 114.684048 -229.011734)
		(width 0.1143)
		(layer "In4.Cu")
		(net "GMI_CPU1_G2_CPU0_G0_TX_DP<1>")
	)
	(arc
		(start 113.28019 -225.044508)
		(mid 113.329842 -225.230553)
		(end 113.46561 -225.367088)
		(width 0.1143)
		(layer "In4.Cu")
		(net "GMI_CPU1_G2_CPU0_G0_TX_DP<1>")
	)
	(arc
		(start 358.05999 -222.108522)
		(mid 358.174666 -221.975188)
		(end 358.215946 -221.80423)
		(width 0.1143)
		(layer "In4.Cu")
		(net "GMI_CPU1_G2_CPU0_G0_TX_DP<1>")
	)
	(arc
		(start 113.438432 -226.358958)
		(mid 113.325556 -226.49425)
		(end 113.28019 -226.66452)
		(width 0.1143)
		(layer "In4.Cu")
		(net "GMI_CPU1_G2_CPU0_G0_TX_DP<1>")
	)
	(arc
		(start 357.989124 -226.318826)
		(mid 357.747028 -225.834147)
		(end 358.0257 -225.369628)
		(width 0.1143)
		(layer "In4.Cu")
		(net "GMI_CPU1_G2_CPU0_G0_TX_DP<1>")
	)
	(arc
		(start 358.030272 -225.366834)
		(mid 358.166099 -225.230313)
		(end 358.215692 -225.044254)
		(width 0.1143)
		(layer "In4.Cu")
		(net "GMI_CPU1_G2_CPU0_G0_TX_DP<1>")
	)
	(arc
		(start 358.215692 -226.664266)
		(mid 358.170388 -226.493964)
		(end 358.05745 -226.358704)
		(width 0.1143)
		(layer "In4.Cu")
		(net "GMI_CPU1_G2_CPU0_G0_TX_DP<1>")
	)
	(arc
		(start 358.0257 -224.72015)
		(mid 357.746667 -224.254935)
		(end 357.989124 -223.769682)
		(width 0.1143)
		(layer "In4.Cu")
		(net "GMI_CPU1_G2_CPU0_G0_TX_DP<1>")
	)
	(arc
		(start 114.22253 -228.295708)
		(mid 114.277287 -228.458875)
		(end 114.384328 -228.59365)
		(width 0.1143)
		(layer "In4.Cu")
		(net "GMI_CPU1_G2_CPU0_G0_TX_DP<1>")
	)
	(arc
		(start 113.506758 -222.149924)
		(mid 113.750085 -222.61449)
		(end 113.506758 -223.079056)
		(width 0.1143)
		(layer "In4.Cu")
		(net "GMI_CPU1_G2_CPU0_G0_TX_DP<1>")
	)
	(arc
		(start 113.279936 -221.804484)
		(mid 113.321191 -221.975455)
		(end 113.435892 -222.108776)
		(width 0.1143)
		(layer "In4.Cu")
		(net "GMI_CPU1_G2_CPU0_G0_TX_DP<1>")
	)
	(arc
		(start 113.280444 -223.427036)
		(mid 113.32243 -223.597033)
		(end 113.437162 -223.729296)
		(width 0.1143)
		(layer "In4.Cu")
		(net "GMI_CPU1_G2_CPU0_G0_TX_DP<1>")
	)
	(arc
		(start 113.506758 -227.00996)
		(mid 113.685571 -227.21231)
		(end 113.75009 -227.474526)
		(width 0.1143)
		(layer "In4.Cu")
		(net "GMI_CPU1_G2_CPU0_G0_TX_DP<1>")
	)
	(arc
		(start 357.111554 -228.593396)
		(mid 357.218599 -228.458623)
		(end 357.273352 -228.295454)
		(width 0.1143)
		(layer "In4.Cu")
		(net "GMI_CPU1_G2_CPU0_G0_TX_DP<1>")
	)
	(arc
		(start 113.440718 -223.117664)
		(mid 113.329535 -223.254169)
		(end 113.280444 -223.423226)
		(width 0.1143)
		(layer "In4.Cu")
		(net "GMI_CPU1_G2_CPU0_G0_TX_DP<1>")
	)
	(arc
		(start 358.05872 -223.729042)
		(mid 358.173398 -223.596751)
		(end 358.215438 -223.426782)
		(width 0.1143)
		(layer "In4.Cu")
		(net "GMI_CPU1_G2_CPU0_G0_TX_DP<1>")
	)
	(arc
		(start 113.984786 -227.825554)
		(mid 114.103137 -227.940214)
		(end 114.183414 -228.084126)
		(width 0.1143)
		(layer "In4.Cu")
		(net "GMI_CPU1_G2_CPU0_G0_TX_DP<1>")
	)
	(segment
		(start 346.087954 -231.789986)
		(end 345.621102 -231.524048)
		(width 0.12954)
		(layer "F.Cu")
		(net "GMI_CPU1_G2_CPU0_G0_TX_DP<15>")
	)
	(segment
		(start 125.407928 -231.79024)
		(end 125.87478 -231.524302)
		(width 0.12954)
		(layer "F.Cu")
		(net "GMI_CPU1_G2_CPU0_G0_TX_DP<15>")
	)
	(segment
		(start 345.988894 -231.454198)
		(end 345.919044 -231.524048)
		(width 0.1143)
		(layer "In4.Cu")
		(net "GMI_CPU1_G2_CPU0_G0_TX_DP<15>")
	)
	(segment
		(start 126.439676 -221.248732)
		(end 126.485396 -221.203012)
		(width 0.1143)
		(layer "In4.Cu")
		(net "GMI_CPU1_G2_CPU0_G0_TX_DP<15>")
	)
	(segment
		(start 251.791724 -192.903094)
		(end 262.841486 -190.954914)
		(width 0.14224)
		(layer "In4.Cu")
		(net "GMI_CPU1_G2_CPU0_G0_TX_DP<15>")
	)
	(segment
		(start 345.010486 -221.17431)
		(end 345.010486 -221.202758)
		(width 0.1143)
		(layer "In4.Cu")
		(net "GMI_CPU1_G2_CPU0_G0_TX_DP<15>")
	)
	(segment
		(start 155.161234 -198.502016)
		(end 155.491434 -198.231252)
		(width 0.14224)
		(layer "In4.Cu")
		(net "GMI_CPU1_G2_CPU0_G0_TX_DP<15>")
	)
	(segment
		(start 157.777942 -196.356224)
		(end 158.108142 -196.08546)
		(width 0.14224)
		(layer "In4.Cu")
		(net "GMI_CPU1_G2_CPU0_G0_TX_DP<15>")
	)
	(segment
		(start 345.8083 -231.201722)
		(end 345.840812 -231.220518)
		(width 0.1143)
		(layer "In4.Cu")
		(net "GMI_CPU1_G2_CPU0_G0_TX_DP<15>")
	)
	(segment
		(start 344.82913 -227.938838)
		(end 344.898726 -227.979478)
		(width 0.1143)
		(layer "In4.Cu")
		(net "GMI_CPU1_G2_CPU0_G0_TX_DP<15>")
	)
	(segment
		(start 126.597156 -223.119696)
		(end 126.627636 -223.101916)
		(width 0.1143)
		(layer "In4.Cu")
		(net "GMI_CPU1_G2_CPU0_G0_TX_DP<15>")
	)
	(segment
		(start 161.266886 -193.495168)
		(end 161.59734 -193.224404)
		(width 0.14224)
		(layer "In4.Cu")
		(net "GMI_CPU1_G2_CPU0_G0_TX_DP<15>")
	)
	(segment
		(start 155.491434 -198.231252)
		(end 155.510484 -198.038212)
		(width 0.14224)
		(layer "In4.Cu")
		(net "GMI_CPU1_G2_CPU0_G0_TX_DP<15>")
	)
	(segment
		(start 126.627636 -226.34194)
		(end 126.666752 -226.31908)
		(width 0.1143)
		(layer "In4.Cu")
		(net "GMI_CPU1_G2_CPU0_G0_TX_DP<15>")
	)
	(segment
		(start 126.597156 -226.35972)
		(end 126.627636 -226.34194)
		(width 0.1143)
		(layer "In4.Cu")
		(net "GMI_CPU1_G2_CPU0_G0_TX_DP<15>")
	)
	(segment
		(start 158.457138 -195.62191)
		(end 158.650178 -195.64096)
		(width 0.14224)
		(layer "In4.Cu")
		(net "GMI_CPU1_G2_CPU0_G0_TX_DP<15>")
	)
	(segment
		(start 126.666752 -223.769936)
		(end 126.627636 -223.747076)
		(width 0.1143)
		(layer "In4.Cu")
		(net "GMI_CPU1_G2_CPU0_G0_TX_DP<15>")
	)
	(segment
		(start 344.82913 -226.318826)
		(end 344.898726 -226.359466)
		(width 0.1143)
		(layer "In4.Cu")
		(net "GMI_CPU1_G2_CPU0_G0_TX_DP<15>")
	)
	(segment
		(start 125.65507 -231.220772)
		(end 125.687582 -231.201976)
		(width 0.1143)
		(layer "In4.Cu")
		(net "GMI_CPU1_G2_CPU0_G0_TX_DP<15>")
	)
	(segment
		(start 126.627636 -223.747076)
		(end 126.597156 -223.729296)
		(width 0.1143)
		(layer "In4.Cu")
		(net "GMI_CPU1_G2_CPU0_G0_TX_DP<15>")
	)
	(segment
		(start 162.632898 -191.688212)
		(end 162.964876 -191.41567)
		(width 0.14224)
		(layer "In4.Cu")
		(net "GMI_CPU1_G2_CPU0_G0_TX_DP<15>")
	)
	(segment
		(start 125.687582 -231.201976)
		(end 125.726698 -231.179116)
		(width 0.1143)
		(layer "In4.Cu")
		(net "GMI_CPU1_G2_CPU0_G0_TX_DP<15>")
	)
	(segment
		(start 344.868246 -229.58171)
		(end 344.900758 -229.600506)
		(width 0.1143)
		(layer "In4.Cu")
		(net "GMI_CPU1_G2_CPU0_G0_TX_DP<15>")
	)
	(segment
		(start 147.420584 -203.23556)
		(end 150.197312 -202.394312)
		(width 0.14224)
		(layer "In4.Cu")
		(net "GMI_CPU1_G2_CPU0_G0_TX_DP<15>")
	)
	(segment
		(start 345.056206 -221.248478)
		(end 345.056206 -221.466664)
		(width 0.1143)
		(layer "In4.Cu")
		(net "GMI_CPU1_G2_CPU0_G0_TX_DP<15>")
	)
	(segment
		(start 126.485396 -221.174564)
		(end 126.485396 -221.12605)
		(width 0.14224)
		(layer "In4.Cu")
		(net "GMI_CPU1_G2_CPU0_G0_TX_DP<15>")
	)
	(segment
		(start 345.338146 -230.391716)
		(end 345.369896 -230.410004)
		(width 0.1143)
		(layer "In4.Cu")
		(net "GMI_CPU1_G2_CPU0_G0_TX_DP<15>")
	)
	(segment
		(start 126.627636 -226.9871)
		(end 126.597156 -226.96932)
		(width 0.1143)
		(layer "In4.Cu")
		(net "GMI_CPU1_G2_CPU0_G0_TX_DP<15>")
	)
	(segment
		(start 160.39465 -194.210432)
		(end 160.72485 -193.939668)
		(width 0.14224)
		(layer "In4.Cu")
		(net "GMI_CPU1_G2_CPU0_G0_TX_DP<15>")
	)
	(segment
		(start 344.898726 -222.10903)
		(end 344.82913 -222.14967)
		(width 0.1143)
		(layer "In4.Cu")
		(net "GMI_CPU1_G2_CPU0_G0_TX_DP<15>")
	)
	(segment
		(start 240.324132 -200.933304)
		(end 251.791724 -192.903094)
		(width 0.14224)
		(layer "In4.Cu")
		(net "GMI_CPU1_G2_CPU0_G0_TX_DP<15>")
	)
	(segment
		(start 126.627636 -223.101916)
		(end 126.666752 -223.079056)
		(width 0.1143)
		(layer "In4.Cu")
		(net "GMI_CPU1_G2_CPU0_G0_TX_DP<15>")
	)
	(segment
		(start 345.919044 -231.524048)
		(end 345.621102 -231.524048)
		(width 0.1143)
		(layer "In4.Cu")
		(net "GMI_CPU1_G2_CPU0_G0_TX_DP<15>")
	)
	(segment
		(start 127.32512 -219.712286)
		(end 147.420584 -203.23556)
		(width 0.14224)
		(layer "In4.Cu")
		(net "GMI_CPU1_G2_CPU0_G0_TX_DP<15>")
	)
	(segment
		(start 126.157736 -230.39197)
		(end 126.194312 -230.370634)
		(width 0.1143)
		(layer "In4.Cu")
		(net "GMI_CPU1_G2_CPU0_G0_TX_DP<15>")
	)
	(segment
		(start 345.010486 -221.202758)
		(end 345.056206 -221.248478)
		(width 0.1143)
		(layer "In4.Cu")
		(net "GMI_CPU1_G2_CPU0_G0_TX_DP<15>")
	)
	(segment
		(start 154.968194 -198.482966)
		(end 155.161234 -198.502016)
		(width 0.14224)
		(layer "In4.Cu")
		(net "GMI_CPU1_G2_CPU0_G0_TX_DP<15>")
	)
	(segment
		(start 126.440184 -221.467426)
		(end 126.439676 -221.466918)
		(width 0.1143)
		(layer "In4.Cu")
		(net "GMI_CPU1_G2_CPU0_G0_TX_DP<15>")
	)
	(segment
		(start 150.197312 -202.394312)
		(end 154.967686 -198.482966)
		(width 0.14224)
		(layer "In4.Cu")
		(net "GMI_CPU1_G2_CPU0_G0_TX_DP<15>")
	)
	(segment
		(start 159.852614 -194.654932)
		(end 159.871664 -194.461892)
		(width 0.14224)
		(layer "In4.Cu")
		(net "GMI_CPU1_G2_CPU0_G0_TX_DP<15>")
	)
	(segment
		(start 158.650178 -195.64096)
		(end 158.658814 -195.633848)
		(width 0.14224)
		(layer "In4.Cu")
		(net "GMI_CPU1_G2_CPU0_G0_TX_DP<15>")
	)
	(segment
		(start 207.15732 -191.22771)
		(end 209.73542 -191.682624)
		(width 0.14224)
		(layer "In4.Cu")
		(net "GMI_CPU1_G2_CPU0_G0_TX_DP<15>")
	)
	(segment
		(start 126.485396 -221.203012)
		(end 126.485396 -221.174564)
		(width 0.1143)
		(layer "In4.Cu")
		(net "GMI_CPU1_G2_CPU0_G0_TX_DP<15>")
	)
	(segment
		(start 345.30157 -230.37038)
		(end 345.338146 -230.391716)
		(width 0.1143)
		(layer "In4.Cu")
		(net "GMI_CPU1_G2_CPU0_G0_TX_DP<15>")
	)
	(segment
		(start 126.666752 -222.149924)
		(end 126.597156 -222.109284)
		(width 0.1143)
		(layer "In4.Cu")
		(net "GMI_CPU1_G2_CPU0_G0_TX_DP<15>")
	)
	(segment
		(start 126.627636 -225.367088)
		(end 126.597156 -225.349308)
		(width 0.1143)
		(layer "In4.Cu")
		(net "GMI_CPU1_G2_CPU0_G0_TX_DP<15>")
	)
	(segment
		(start 161.59734 -193.224404)
		(end 161.61639 -193.031364)
		(width 0.14224)
		(layer "In4.Cu")
		(net "GMI_CPU1_G2_CPU0_G0_TX_DP<15>")
	)
	(segment
		(start 126.627636 -228.607112)
		(end 126.597156 -228.589332)
		(width 0.1143)
		(layer "In4.Cu")
		(net "GMI_CPU1_G2_CPU0_G0_TX_DP<15>")
	)
	(segment
		(start 126.627636 -229.581964)
		(end 126.666752 -229.559104)
		(width 0.1143)
		(layer "In4.Cu")
		(net "GMI_CPU1_G2_CPU0_G0_TX_DP<15>")
	)
	(segment
		(start 316.413896 -197.02018)
		(end 344.4367 -219.997274)
		(width 0.14224)
		(layer "In4.Cu")
		(net "GMI_CPU1_G2_CPU0_G0_TX_DP<15>")
	)
	(segment
		(start 126.666752 -228.629972)
		(end 126.627636 -228.607112)
		(width 0.1143)
		(layer "In4.Cu")
		(net "GMI_CPU1_G2_CPU0_G0_TX_DP<15>")
	)
	(segment
		(start 156.38272 -197.322948)
		(end 156.712666 -197.052438)
		(width 0.14224)
		(layer "In4.Cu")
		(net "GMI_CPU1_G2_CPU0_G0_TX_DP<15>")
	)
	(segment
		(start 303.7332 -191.33185)
		(end 308.267862 -191.33185)
		(width 0.14224)
		(layer "In4.Cu")
		(net "GMI_CPU1_G2_CPU0_G0_TX_DP<15>")
	)
	(segment
		(start 236.278928 -201.64679)
		(end 240.324132 -200.933304)
		(width 0.14224)
		(layer "In4.Cu")
		(net "GMI_CPU1_G2_CPU0_G0_TX_DP<15>")
	)
	(segment
		(start 126.597156 -224.739708)
		(end 126.627636 -224.721928)
		(width 0.1143)
		(layer "In4.Cu")
		(net "GMI_CPU1_G2_CPU0_G0_TX_DP<15>")
	)
	(segment
		(start 344.898726 -223.729042)
		(end 344.82913 -223.769682)
		(width 0.1143)
		(layer "In4.Cu")
		(net "GMI_CPU1_G2_CPU0_G0_TX_DP<15>")
	)
	(segment
		(start 162.964876 -191.41567)
		(end 207.15732 -191.22771)
		(width 0.14224)
		(layer "In4.Cu")
		(net "GMI_CPU1_G2_CPU0_G0_TX_DP<15>")
	)
	(segment
		(start 126.595124 -229.60076)
		(end 126.627636 -229.581964)
		(width 0.1143)
		(layer "In4.Cu")
		(net "GMI_CPU1_G2_CPU0_G0_TX_DP<15>")
	)
	(segment
		(start 125.576838 -231.524302)
		(end 125.506988 -231.454452)
		(width 0.1143)
		(layer "In4.Cu")
		(net "GMI_CPU1_G2_CPU0_G0_TX_DP<15>")
	)
	(segment
		(start 126.597156 -227.979732)
		(end 126.627636 -227.961952)
		(width 0.1143)
		(layer "In4.Cu")
		(net "GMI_CPU1_G2_CPU0_G0_TX_DP<15>")
	)
	(segment
		(start 344.898726 -226.969066)
		(end 344.82913 -227.009706)
		(width 0.1143)
		(layer "In4.Cu")
		(net "GMI_CPU1_G2_CPU0_G0_TX_DP<15>")
	)
	(segment
		(start 209.73542 -191.682624)
		(end 231.94772 -200.883012)
		(width 0.14224)
		(layer "In4.Cu")
		(net "GMI_CPU1_G2_CPU0_G0_TX_DP<15>")
	)
	(segment
		(start 160.72485 -193.939668)
		(end 160.7439 -193.746628)
		(width 0.14224)
		(layer "In4.Cu")
		(net "GMI_CPU1_G2_CPU0_G0_TX_DP<15>")
	)
	(segment
		(start 160.20161 -194.191382)
		(end 160.39465 -194.210432)
		(width 0.14224)
		(layer "In4.Cu")
		(net "GMI_CPU1_G2_CPU0_G0_TX_DP<15>")
	)
	(segment
		(start 344.898726 -225.349054)
		(end 344.82913 -225.389694)
		(width 0.1143)
		(layer "In4.Cu")
		(net "GMI_CPU1_G2_CPU0_G0_TX_DP<15>")
	)
	(segment
		(start 344.898726 -228.589078)
		(end 344.82913 -228.629718)
		(width 0.1143)
		(layer "In4.Cu")
		(net "GMI_CPU1_G2_CPU0_G0_TX_DP<15>")
	)
	(segment
		(start 126.440184 -221.804484)
		(end 126.440184 -221.467426)
		(width 0.1143)
		(layer "In4.Cu")
		(net "GMI_CPU1_G2_CPU0_G0_TX_DP<15>")
	)
	(segment
		(start 157.584902 -196.337174)
		(end 157.777942 -196.356224)
		(width 0.14224)
		(layer "In4.Cu")
		(net "GMI_CPU1_G2_CPU0_G0_TX_DP<15>")
	)
	(segment
		(start 159.522414 -194.925696)
		(end 159.852614 -194.654932)
		(width 0.14224)
		(layer "In4.Cu")
		(net "GMI_CPU1_G2_CPU0_G0_TX_DP<15>")
	)
	(segment
		(start 126.439676 -221.466918)
		(end 126.439676 -221.248732)
		(width 0.1143)
		(layer "In4.Cu")
		(net "GMI_CPU1_G2_CPU0_G0_TX_DP<15>")
	)
	(segment
		(start 126.627636 -224.721928)
		(end 126.666752 -224.699068)
		(width 0.1143)
		(layer "In4.Cu")
		(net "GMI_CPU1_G2_CPU0_G0_TX_DP<15>")
	)
	(segment
		(start 344.82913 -229.55885)
		(end 344.868246 -229.58171)
		(width 0.1143)
		(layer "In4.Cu")
		(net "GMI_CPU1_G2_CPU0_G0_TX_DP<15>")
	)
	(segment
		(start 162.14471 -192.59804)
		(end 162.632898 -191.688212)
		(width 0.14224)
		(layer "In4.Cu")
		(net "GMI_CPU1_G2_CPU0_G0_TX_DP<15>")
	)
	(segment
		(start 159.329374 -194.906646)
		(end 159.522414 -194.925696)
		(width 0.14224)
		(layer "In4.Cu")
		(net "GMI_CPU1_G2_CPU0_G0_TX_DP<15>")
	)
	(segment
		(start 158.999428 -195.177156)
		(end 159.329374 -194.906646)
		(width 0.14224)
		(layer "In4.Cu")
		(net "GMI_CPU1_G2_CPU0_G0_TX_DP<15>")
	)
	(segment
		(start 154.967686 -198.482966)
		(end 154.968194 -198.482966)
		(width 0.14224)
		(layer "In4.Cu")
		(net "GMI_CPU1_G2_CPU0_G0_TX_DP<15>")
	)
	(segment
		(start 345.056206 -221.466664)
		(end 345.055698 -221.467172)
		(width 0.1143)
		(layer "In4.Cu")
		(net "GMI_CPU1_G2_CPU0_G0_TX_DP<15>")
	)
	(segment
		(start 158.108142 -196.08546)
		(end 158.127192 -195.89242)
		(width 0.14224)
		(layer "In4.Cu")
		(net "GMI_CPU1_G2_CPU0_G0_TX_DP<15>")
	)
	(segment
		(start 158.127192 -195.89242)
		(end 158.457138 -195.62191)
		(width 0.14224)
		(layer "In4.Cu")
		(net "GMI_CPU1_G2_CPU0_G0_TX_DP<15>")
	)
	(segment
		(start 345.010486 -220.963236)
		(end 345.010486 -221.17431)
		(width 0.14224)
		(layer "In4.Cu")
		(net "GMI_CPU1_G2_CPU0_G0_TX_DP<15>")
	)
	(segment
		(start 125.87478 -231.524302)
		(end 125.576838 -231.524302)
		(width 0.1143)
		(layer "In4.Cu")
		(net "GMI_CPU1_G2_CPU0_G0_TX_DP<15>")
	)
	(segment
		(start 344.4367 -219.997274)
		(end 345.010486 -220.963236)
		(width 0.14224)
		(layer "In4.Cu")
		(net "GMI_CPU1_G2_CPU0_G0_TX_DP<15>")
	)
	(segment
		(start 161.073846 -193.476118)
		(end 161.266886 -193.495168)
		(width 0.14224)
		(layer "In4.Cu")
		(net "GMI_CPU1_G2_CPU0_G0_TX_DP<15>")
	)
	(segment
		(start 344.82913 -224.698814)
		(end 344.898726 -224.739454)
		(width 0.1143)
		(layer "In4.Cu")
		(net "GMI_CPU1_G2_CPU0_G0_TX_DP<15>")
	)
	(segment
		(start 262.841486 -190.954914)
		(end 303.7332 -191.33185)
		(width 0.14224)
		(layer "In4.Cu")
		(net "GMI_CPU1_G2_CPU0_G0_TX_DP<15>")
	)
	(segment
		(start 345.769184 -231.178862)
		(end 345.8083 -231.201722)
		(width 0.1143)
		(layer "In4.Cu")
		(net "GMI_CPU1_G2_CPU0_G0_TX_DP<15>")
	)
	(segment
		(start 155.510484 -198.038212)
		(end 155.84043 -197.767702)
		(width 0.14224)
		(layer "In4.Cu")
		(net "GMI_CPU1_G2_CPU0_G0_TX_DP<15>")
	)
	(segment
		(start 160.7439 -193.746628)
		(end 161.073846 -193.476118)
		(width 0.14224)
		(layer "In4.Cu")
		(net "GMI_CPU1_G2_CPU0_G0_TX_DP<15>")
	)
	(segment
		(start 231.94772 -200.883012)
		(end 236.278928 -201.64679)
		(width 0.14224)
		(layer "In4.Cu")
		(net "GMI_CPU1_G2_CPU0_G0_TX_DP<15>")
	)
	(segment
		(start 126.666752 -225.389948)
		(end 126.627636 -225.367088)
		(width 0.1143)
		(layer "In4.Cu")
		(net "GMI_CPU1_G2_CPU0_G0_TX_DP<15>")
	)
	(segment
		(start 156.03347 -197.786752)
		(end 156.36367 -197.515988)
		(width 0.14224)
		(layer "In4.Cu")
		(net "GMI_CPU1_G2_CPU0_G0_TX_DP<15>")
	)
	(segment
		(start 155.84043 -197.767702)
		(end 156.03347 -197.786752)
		(width 0.14224)
		(layer "In4.Cu")
		(net "GMI_CPU1_G2_CPU0_G0_TX_DP<15>")
	)
	(segment
		(start 157.254956 -196.607684)
		(end 157.584902 -196.337174)
		(width 0.14224)
		(layer "In4.Cu")
		(net "GMI_CPU1_G2_CPU0_G0_TX_DP<15>")
	)
	(segment
		(start 308.267862 -191.33185)
		(end 316.413896 -197.02018)
		(width 0.14224)
		(layer "In4.Cu")
		(net "GMI_CPU1_G2_CPU0_G0_TX_DP<15>")
	)
	(segment
		(start 156.905706 -197.071488)
		(end 157.235906 -196.800724)
		(width 0.14224)
		(layer "In4.Cu")
		(net "GMI_CPU1_G2_CPU0_G0_TX_DP<15>")
	)
	(segment
		(start 156.36367 -197.515988)
		(end 156.38272 -197.322948)
		(width 0.14224)
		(layer "In4.Cu")
		(net "GMI_CPU1_G2_CPU0_G0_TX_DP<15>")
	)
	(segment
		(start 126.666752 -227.00996)
		(end 126.627636 -226.9871)
		(width 0.1143)
		(layer "In4.Cu")
		(net "GMI_CPU1_G2_CPU0_G0_TX_DP<15>")
	)
	(segment
		(start 156.712666 -197.052438)
		(end 156.905706 -197.071488)
		(width 0.14224)
		(layer "In4.Cu")
		(net "GMI_CPU1_G2_CPU0_G0_TX_DP<15>")
	)
	(segment
		(start 126.627636 -227.961952)
		(end 126.666752 -227.939092)
		(width 0.1143)
		(layer "In4.Cu")
		(net "GMI_CPU1_G2_CPU0_G0_TX_DP<15>")
	)
	(segment
		(start 344.82913 -223.078802)
		(end 344.898726 -223.119442)
		(width 0.1143)
		(layer "In4.Cu")
		(net "GMI_CPU1_G2_CPU0_G0_TX_DP<15>")
	)
	(segment
		(start 345.055698 -221.467172)
		(end 345.055698 -221.80423)
		(width 0.1143)
		(layer "In4.Cu")
		(net "GMI_CPU1_G2_CPU0_G0_TX_DP<15>")
	)
	(segment
		(start 126.125986 -230.410258)
		(end 126.157736 -230.39197)
		(width 0.1143)
		(layer "In4.Cu")
		(net "GMI_CPU1_G2_CPU0_G0_TX_DP<15>")
	)
	(segment
		(start 161.61639 -193.031364)
		(end 162.14471 -192.59804)
		(width 0.14224)
		(layer "In4.Cu")
		(net "GMI_CPU1_G2_CPU0_G0_TX_DP<15>")
	)
	(segment
		(start 126.485396 -221.12605)
		(end 127.32512 -219.712286)
		(width 0.14224)
		(layer "In4.Cu")
		(net "GMI_CPU1_G2_CPU0_G0_TX_DP<15>")
	)
	(segment
		(start 158.980378 -195.370196)
		(end 158.999428 -195.177156)
		(width 0.14224)
		(layer "In4.Cu")
		(net "GMI_CPU1_G2_CPU0_G0_TX_DP<15>")
	)
	(segment
		(start 157.235906 -196.800724)
		(end 157.254956 -196.607684)
		(width 0.14224)
		(layer "In4.Cu")
		(net "GMI_CPU1_G2_CPU0_G0_TX_DP<15>")
	)
	(segment
		(start 159.871664 -194.461892)
		(end 160.20161 -194.191382)
		(width 0.14224)
		(layer "In4.Cu")
		(net "GMI_CPU1_G2_CPU0_G0_TX_DP<15>")
	)
	(segment
		(start 158.658814 -195.633848)
		(end 158.980378 -195.370196)
		(width 0.14224)
		(layer "In4.Cu")
		(net "GMI_CPU1_G2_CPU0_G0_TX_DP<15>")
	)
	(arc
		(start 344.82913 -225.389694)
		(mid 344.585803 -225.85426)
		(end 344.82913 -226.318826)
		(width 0.1143)
		(layer "In4.Cu")
		(net "GMI_CPU1_G2_CPU0_G0_TX_DP<15>")
	)
	(arc
		(start 126.597156 -226.96932)
		(mid 126.440179 -226.66452)
		(end 126.597156 -226.35972)
		(width 0.1143)
		(layer "In4.Cu")
		(net "GMI_CPU1_G2_CPU0_G0_TX_DP<15>")
	)
	(arc
		(start 126.597156 -225.349308)
		(mid 126.440179 -225.044508)
		(end 126.597156 -224.739708)
		(width 0.1143)
		(layer "In4.Cu")
		(net "GMI_CPU1_G2_CPU0_G0_TX_DP<15>")
	)
	(arc
		(start 344.898726 -223.119442)
		(mid 345.055703 -223.424242)
		(end 344.898726 -223.729042)
		(width 0.1143)
		(layer "In4.Cu")
		(net "GMI_CPU1_G2_CPU0_G0_TX_DP<15>")
	)
	(arc
		(start 345.055698 -221.80423)
		(mid 345.014149 -221.975652)
		(end 344.898726 -222.10903)
		(width 0.1143)
		(layer "In4.Cu")
		(net "GMI_CPU1_G2_CPU0_G0_TX_DP<15>")
	)
	(arc
		(start 126.440184 -229.90429)
		(mid 126.48115 -229.733884)
		(end 126.595124 -229.60076)
		(width 0.1143)
		(layer "In4.Cu")
		(net "GMI_CPU1_G2_CPU0_G0_TX_DP<15>")
	)
	(arc
		(start 345.525852 -230.714296)
		(mid 345.590367 -230.976515)
		(end 345.769184 -231.178862)
		(width 0.1143)
		(layer "In4.Cu")
		(net "GMI_CPU1_G2_CPU0_G0_TX_DP<15>")
	)
	(arc
		(start 344.898726 -226.359466)
		(mid 345.055703 -226.664266)
		(end 344.898726 -226.969066)
		(width 0.1143)
		(layer "In4.Cu")
		(net "GMI_CPU1_G2_CPU0_G0_TX_DP<15>")
	)
	(arc
		(start 344.898726 -224.739454)
		(mid 345.055703 -225.044254)
		(end 344.898726 -225.349054)
		(width 0.1143)
		(layer "In4.Cu")
		(net "GMI_CPU1_G2_CPU0_G0_TX_DP<15>")
	)
	(arc
		(start 126.597156 -222.109284)
		(mid 126.481729 -221.975908)
		(end 126.440184 -221.804484)
		(width 0.1143)
		(layer "In4.Cu")
		(net "GMI_CPU1_G2_CPU0_G0_TX_DP<15>")
	)
	(arc
		(start 126.666752 -226.31908)
		(mid 126.910079 -225.854514)
		(end 126.666752 -225.389948)
		(width 0.1143)
		(layer "In4.Cu")
		(net "GMI_CPU1_G2_CPU0_G0_TX_DP<15>")
	)
	(arc
		(start 344.82913 -222.14967)
		(mid 344.585803 -222.614236)
		(end 344.82913 -223.078802)
		(width 0.1143)
		(layer "In4.Cu")
		(net "GMI_CPU1_G2_CPU0_G0_TX_DP<15>")
	)
	(arc
		(start 344.82913 -228.629718)
		(mid 344.585803 -229.094284)
		(end 344.82913 -229.55885)
		(width 0.1143)
		(layer "In4.Cu")
		(net "GMI_CPU1_G2_CPU0_G0_TX_DP<15>")
	)
	(arc
		(start 345.840812 -231.220518)
		(mid 345.937252 -231.323173)
		(end 345.988894 -231.454198)
		(width 0.1143)
		(layer "In4.Cu")
		(net "GMI_CPU1_G2_CPU0_G0_TX_DP<15>")
	)
	(arc
		(start 126.597156 -228.589332)
		(mid 126.440179 -228.284532)
		(end 126.597156 -227.979732)
		(width 0.1143)
		(layer "In4.Cu")
		(net "GMI_CPU1_G2_CPU0_G0_TX_DP<15>")
	)
	(arc
		(start 125.726698 -231.179116)
		(mid 125.905511 -230.976766)
		(end 125.97003 -230.71455)
		(width 0.1143)
		(layer "In4.Cu")
		(net "GMI_CPU1_G2_CPU0_G0_TX_DP<15>")
	)
	(arc
		(start 344.82913 -227.009706)
		(mid 344.585803 -227.474272)
		(end 344.82913 -227.938838)
		(width 0.1143)
		(layer "In4.Cu")
		(net "GMI_CPU1_G2_CPU0_G0_TX_DP<15>")
	)
	(arc
		(start 126.666752 -224.699068)
		(mid 126.910079 -224.234502)
		(end 126.666752 -223.769936)
		(width 0.1143)
		(layer "In4.Cu")
		(net "GMI_CPU1_G2_CPU0_G0_TX_DP<15>")
	)
	(arc
		(start 344.900758 -229.600506)
		(mid 345.014687 -229.733653)
		(end 345.055698 -229.904036)
		(width 0.1143)
		(layer "In4.Cu")
		(net "GMI_CPU1_G2_CPU0_G0_TX_DP<15>")
	)
	(arc
		(start 126.666752 -223.079056)
		(mid 126.910079 -222.61449)
		(end 126.666752 -222.149924)
		(width 0.1143)
		(layer "In4.Cu")
		(net "GMI_CPU1_G2_CPU0_G0_TX_DP<15>")
	)
	(arc
		(start 125.97003 -230.71455)
		(mid 126.011285 -230.543579)
		(end 126.125986 -230.410258)
		(width 0.1143)
		(layer "In4.Cu")
		(net "GMI_CPU1_G2_CPU0_G0_TX_DP<15>")
	)
	(arc
		(start 345.055698 -229.904036)
		(mid 345.120934 -230.167627)
		(end 345.30157 -230.37038)
		(width 0.1143)
		(layer "In4.Cu")
		(net "GMI_CPU1_G2_CPU0_G0_TX_DP<15>")
	)
	(arc
		(start 125.506988 -231.454452)
		(mid 125.558696 -231.323469)
		(end 125.65507 -231.220772)
		(width 0.1143)
		(layer "In4.Cu")
		(net "GMI_CPU1_G2_CPU0_G0_TX_DP<15>")
	)
	(arc
		(start 126.597156 -223.729296)
		(mid 126.440179 -223.424496)
		(end 126.597156 -223.119696)
		(width 0.1143)
		(layer "In4.Cu")
		(net "GMI_CPU1_G2_CPU0_G0_TX_DP<15>")
	)
	(arc
		(start 344.898726 -227.979478)
		(mid 345.055703 -228.284278)
		(end 344.898726 -228.589078)
		(width 0.1143)
		(layer "In4.Cu")
		(net "GMI_CPU1_G2_CPU0_G0_TX_DP<15>")
	)
	(arc
		(start 126.666752 -227.939092)
		(mid 126.910079 -227.474526)
		(end 126.666752 -227.00996)
		(width 0.1143)
		(layer "In4.Cu")
		(net "GMI_CPU1_G2_CPU0_G0_TX_DP<15>")
	)
	(arc
		(start 345.369896 -230.410004)
		(mid 345.484572 -230.543338)
		(end 345.525852 -230.714296)
		(width 0.1143)
		(layer "In4.Cu")
		(net "GMI_CPU1_G2_CPU0_G0_TX_DP<15>")
	)
	(arc
		(start 126.666752 -229.559104)
		(mid 126.910079 -229.094538)
		(end 126.666752 -228.629972)
		(width 0.1143)
		(layer "In4.Cu")
		(net "GMI_CPU1_G2_CPU0_G0_TX_DP<15>")
	)
	(arc
		(start 344.82913 -223.769682)
		(mid 344.585803 -224.234248)
		(end 344.82913 -224.698814)
		(width 0.1143)
		(layer "In4.Cu")
		(net "GMI_CPU1_G2_CPU0_G0_TX_DP<15>")
	)
	(arc
		(start 126.194312 -230.370634)
		(mid 126.374964 -230.167889)
		(end 126.440184 -229.90429)
		(width 0.1143)
		(layer "In4.Cu")
		(net "GMI_CPU1_G2_CPU0_G0_TX_DP<15>")
	)
	(segment
		(start 346.087954 -228.550216)
		(end 345.621102 -228.284278)
		(width 0.12954)
		(layer "F.Cu")
		(net "GMI_CPU1_G2_CPU0_G0_TX_DP<14>")
	)
	(segment
		(start 125.407928 -228.55047)
		(end 125.87478 -228.284532)
		(width 0.12954)
		(layer "F.Cu")
		(net "GMI_CPU1_G2_CPU0_G0_TX_DP<14>")
	)
	(segment
		(start 156.852874 -194.153536)
		(end 157.045914 -194.172586)
		(width 0.14224)
		(layer "In4.Cu")
		(net "GMI_CPU1_G2_CPU0_G0_TX_DP<14>")
	)
	(segment
		(start 125.042676 -227.496624)
		(end 125.042676 -227.484178)
		(width 0.1143)
		(layer "In4.Cu")
		(net "GMI_CPU1_G2_CPU0_G0_TX_DP<14>")
	)
	(segment
		(start 236.278928 -199.737726)
		(end 239.58677 -199.154288)
		(width 0.14224)
		(layer "In4.Cu")
		(net "GMI_CPU1_G2_CPU0_G0_TX_DP<14>")
	)
	(segment
		(start 251.05487 -191.124078)
		(end 262.688832 -189.07252)
		(width 0.14224)
		(layer "In4.Cu")
		(net "GMI_CPU1_G2_CPU0_G0_TX_DP<14>")
	)
	(segment
		(start 146.501866 -201.495914)
		(end 148.715984 -200.824846)
		(width 0.14224)
		(layer "In4.Cu")
		(net "GMI_CPU1_G2_CPU0_G0_TX_DP<14>")
	)
	(segment
		(start 346.282264 -227.79482)
		(end 346.281756 -227.795074)
		(width 0.1143)
		(layer "In4.Cu")
		(net "GMI_CPU1_G2_CPU0_G0_TX_DP<14>")
	)
	(segment
		(start 318.029336 -195.809616)
		(end 318.029336 -195.810124)
		(width 0.14224)
		(layer "In4.Cu")
		(net "GMI_CPU1_G2_CPU0_G0_TX_DP<14>")
	)
	(segment
		(start 154.759406 -196.047614)
		(end 154.778456 -195.854574)
		(width 0.14224)
		(layer "In4.Cu")
		(net "GMI_CPU1_G2_CPU0_G0_TX_DP<14>")
	)
	(segment
		(start 346.89034 -221.17431)
		(end 346.89034 -221.202758)
		(width 0.1143)
		(layer "In4.Cu")
		(net "GMI_CPU1_G2_CPU0_G0_TX_DP<14>")
	)
	(segment
		(start 124.716032 -223.120204)
		(end 124.747782 -223.101916)
		(width 0.1143)
		(layer "In4.Cu")
		(net "GMI_CPU1_G2_CPU0_G0_TX_DP<14>")
	)
	(segment
		(start 160.855406 -190.70955)
		(end 162.279076 -189.541658)
		(width 0.14224)
		(layer "In4.Cu")
		(net "GMI_CPU1_G2_CPU0_G0_TX_DP<14>")
	)
	(segment
		(start 346.711778 -226.320604)
		(end 346.7481 -226.341686)
		(width 0.1143)
		(layer "In4.Cu")
		(net "GMI_CPU1_G2_CPU0_G0_TX_DP<14>")
	)
	(segment
		(start 346.708984 -223.769428)
		(end 346.681298 -223.789494)
		(width 0.1143)
		(layer "In4.Cu")
		(net "GMI_CPU1_G2_CPU0_G0_TX_DP<14>")
	)
	(segment
		(start 159.139636 -192.278254)
		(end 159.469582 -192.007744)
		(width 0.14224)
		(layer "In4.Cu")
		(net "GMI_CPU1_G2_CPU0_G0_TX_DP<14>")
	)
	(segment
		(start 233.93273 -199.32396)
		(end 236.278928 -199.737726)
		(width 0.14224)
		(layer "In4.Cu")
		(net "GMI_CPU1_G2_CPU0_G0_TX_DP<14>")
	)
	(segment
		(start 309.008272 -189.451488)
		(end 318.029336 -195.809616)
		(width 0.14224)
		(layer "In4.Cu")
		(net "GMI_CPU1_G2_CPU0_G0_TX_DP<14>")
	)
	(segment
		(start 207.337406 -189.350396)
		(end 211.720684 -190.123318)
		(width 0.14224)
		(layer "In4.Cu")
		(net "GMI_CPU1_G2_CPU0_G0_TX_DP<14>")
	)
	(segment
		(start 124.784104 -225.38817)
		(end 124.747782 -225.367088)
		(width 0.1143)
		(layer "In4.Cu")
		(net "GMI_CPU1_G2_CPU0_G0_TX_DP<14>")
	)
	(segment
		(start 157.376114 -193.901822)
		(end 157.395164 -193.708782)
		(width 0.14224)
		(layer "In4.Cu")
		(net "GMI_CPU1_G2_CPU0_G0_TX_DP<14>")
	)
	(segment
		(start 159.992822 -191.75603)
		(end 160.011872 -191.56299)
		(width 0.14224)
		(layer "In4.Cu")
		(net "GMI_CPU1_G2_CPU0_G0_TX_DP<14>")
	)
	(segment
		(start 155.108402 -195.584064)
		(end 155.301442 -195.603114)
		(width 0.14224)
		(layer "In4.Cu")
		(net "GMI_CPU1_G2_CPU0_G0_TX_DP<14>")
	)
	(segment
		(start 124.747782 -222.127064)
		(end 124.716032 -222.108776)
		(width 0.1143)
		(layer "In4.Cu")
		(net "GMI_CPU1_G2_CPU0_G0_TX_DP<14>")
	)
	(segment
		(start 125.87478 -228.284532)
		(end 125.576838 -228.284532)
		(width 0.1143)
		(layer "In4.Cu")
		(net "GMI_CPU1_G2_CPU0_G0_TX_DP<14>")
	)
	(segment
		(start 157.72511 -193.438272)
		(end 157.91815 -193.457322)
		(width 0.14224)
		(layer "In4.Cu")
		(net "GMI_CPU1_G2_CPU0_G0_TX_DP<14>")
	)
	(segment
		(start 156.173678 -194.88785)
		(end 156.503878 -194.617086)
		(width 0.14224)
		(layer "In4.Cu")
		(net "GMI_CPU1_G2_CPU0_G0_TX_DP<14>")
	)
	(segment
		(start 124.732034 -223.737678)
		(end 124.716032 -223.728534)
		(width 0.1143)
		(layer "In4.Cu")
		(net "GMI_CPU1_G2_CPU0_G0_TX_DP<14>")
	)
	(segment
		(start 157.045914 -194.172586)
		(end 157.376114 -193.901822)
		(width 0.14224)
		(layer "In4.Cu")
		(net "GMI_CPU1_G2_CPU0_G0_TX_DP<14>")
	)
	(segment
		(start 125.214126 -227.795328)
		(end 125.213618 -227.795074)
		(width 0.1143)
		(layer "In4.Cu")
		(net "GMI_CPU1_G2_CPU0_G0_TX_DP<14>")
	)
	(segment
		(start 124.786898 -223.769682)
		(end 124.748036 -223.74733)
		(width 0.1143)
		(layer "In4.Cu")
		(net "GMI_CPU1_G2_CPU0_G0_TX_DP<14>")
	)
	(segment
		(start 124.747782 -223.101916)
		(end 124.784104 -223.080834)
		(width 0.1143)
		(layer "In4.Cu")
		(net "GMI_CPU1_G2_CPU0_G0_TX_DP<14>")
	)
	(segment
		(start 346.708984 -224.699068)
		(end 346.77985 -224.739962)
		(width 0.1143)
		(layer "In4.Cu")
		(net "GMI_CPU1_G2_CPU0_G0_TX_DP<14>")
	)
	(segment
		(start 154.429206 -196.318378)
		(end 154.759406 -196.047614)
		(width 0.14224)
		(layer "In4.Cu")
		(net "GMI_CPU1_G2_CPU0_G0_TX_DP<14>")
	)
	(segment
		(start 346.89034 -220.460062)
		(end 346.89034 -221.17431)
		(width 0.14224)
		(layer "In4.Cu")
		(net "GMI_CPU1_G2_CPU0_G0_TX_DP<14>")
	)
	(segment
		(start 125.576838 -228.284532)
		(end 125.494034 -228.201728)
		(width 0.1143)
		(layer "In4.Cu")
		(net "GMI_CPU1_G2_CPU0_G0_TX_DP<14>")
	)
	(segment
		(start 162.279076 -189.541658)
		(end 207.337406 -189.350396)
		(width 0.14224)
		(layer "In4.Cu")
		(net "GMI_CPU1_G2_CPU0_G0_TX_DP<14>")
	)
	(segment
		(start 124.716032 -226.360228)
		(end 124.747782 -226.34194)
		(width 0.1143)
		(layer "In4.Cu")
		(net "GMI_CPU1_G2_CPU0_G0_TX_DP<14>")
	)
	(segment
		(start 125.872748 -218.410282)
		(end 146.501866 -201.495914)
		(width 0.14224)
		(layer "In4.Cu")
		(net "GMI_CPU1_G2_CPU0_G0_TX_DP<14>")
	)
	(segment
		(start 158.790386 -192.742058)
		(end 159.120586 -192.471294)
		(width 0.14224)
		(layer "In4.Cu")
		(net "GMI_CPU1_G2_CPU0_G0_TX_DP<14>")
	)
	(segment
		(start 158.2674 -192.993518)
		(end 158.597346 -192.723008)
		(width 0.14224)
		(layer "In4.Cu")
		(net "GMI_CPU1_G2_CPU0_G0_TX_DP<14>")
	)
	(segment
		(start 124.605542 -221.174564)
		(end 124.605542 -220.61678)
		(width 0.14224)
		(layer "In4.Cu")
		(net "GMI_CPU1_G2_CPU0_G0_TX_DP<14>")
	)
	(segment
		(start 346.278962 -227.796344)
		(end 346.2782 -227.796852)
		(width 0.1143)
		(layer "In4.Cu")
		(net "GMI_CPU1_G2_CPU0_G0_TX_DP<14>")
	)
	(segment
		(start 318.029336 -195.810124)
		(end 345.747086 -218.536266)
		(width 0.14224)
		(layer "In4.Cu")
		(net "GMI_CPU1_G2_CPU0_G0_TX_DP<14>")
	)
	(segment
		(start 153.90622 -196.569584)
		(end 154.236166 -196.299074)
		(width 0.14224)
		(layer "In4.Cu")
		(net "GMI_CPU1_G2_CPU0_G0_TX_DP<14>")
	)
	(segment
		(start 159.469582 -192.007744)
		(end 159.662622 -192.026794)
		(width 0.14224)
		(layer "In4.Cu")
		(net "GMI_CPU1_G2_CPU0_G0_TX_DP<14>")
	)
	(segment
		(start 157.395164 -193.708274)
		(end 157.724856 -193.438272)
		(width 0.14224)
		(layer "In4.Cu")
		(net "GMI_CPU1_G2_CPU0_G0_TX_DP<14>")
	)
	(segment
		(start 124.560076 -221.546166)
		(end 124.559822 -221.545912)
		(width 0.1143)
		(layer "In4.Cu")
		(net "GMI_CPU1_G2_CPU0_G0_TX_DP<14>")
	)
	(segment
		(start 346.77985 -223.728534)
		(end 346.77985 -223.72828)
		(width 0.1143)
		(layer "In4.Cu")
		(net "GMI_CPU1_G2_CPU0_G0_TX_DP<14>")
	)
	(segment
		(start 124.716032 -224.740216)
		(end 124.786898 -224.699322)
		(width 0.1143)
		(layer "In4.Cu")
		(net "GMI_CPU1_G2_CPU0_G0_TX_DP<14>")
	)
	(segment
		(start 346.89034 -221.202758)
		(end 346.93606 -221.248478)
		(width 0.1143)
		(layer "In4.Cu")
		(net "GMI_CPU1_G2_CPU0_G0_TX_DP<14>")
	)
	(segment
		(start 158.597346 -192.723008)
		(end 158.790386 -192.742058)
		(width 0.14224)
		(layer "In4.Cu")
		(net "GMI_CPU1_G2_CPU0_G0_TX_DP<14>")
	)
	(segment
		(start 157.724856 -193.438272)
		(end 157.72511 -193.438272)
		(width 0.14224)
		(layer "In4.Cu")
		(net "GMI_CPU1_G2_CPU0_G0_TX_DP<14>")
	)
	(segment
		(start 155.301442 -195.603114)
		(end 155.631642 -195.33235)
		(width 0.14224)
		(layer "In4.Cu")
		(net "GMI_CPU1_G2_CPU0_G0_TX_DP<14>")
	)
	(segment
		(start 346.7481 -225.366834)
		(end 346.711778 -225.387916)
		(width 0.1143)
		(layer "In4.Cu")
		(net "GMI_CPU1_G2_CPU0_G0_TX_DP<14>")
	)
	(segment
		(start 346.2782 -227.796852)
		(end 346.277184 -227.79736)
		(width 0.1143)
		(layer "In4.Cu")
		(net "GMI_CPU1_G2_CPU0_G0_TX_DP<14>")
	)
	(segment
		(start 155.650692 -195.13931)
		(end 155.980638 -194.8688)
		(width 0.14224)
		(layer "In4.Cu")
		(net "GMI_CPU1_G2_CPU0_G0_TX_DP<14>")
	)
	(segment
		(start 124.747782 -226.34194)
		(end 124.784104 -226.320858)
		(width 0.1143)
		(layer "In4.Cu")
		(net "GMI_CPU1_G2_CPU0_G0_TX_DP<14>")
	)
	(segment
		(start 346.7481 -223.101662)
		(end 346.77985 -223.11995)
		(width 0.1143)
		(layer "In4.Cu")
		(net "GMI_CPU1_G2_CPU0_G0_TX_DP<14>")
	)
	(segment
		(start 154.778456 -195.854574)
		(end 155.108402 -195.584064)
		(width 0.14224)
		(layer "In4.Cu")
		(net "GMI_CPU1_G2_CPU0_G0_TX_DP<14>")
	)
	(segment
		(start 346.77985 -222.108522)
		(end 346.7481 -222.12681)
		(width 0.1143)
		(layer "In4.Cu")
		(net "GMI_CPU1_G2_CPU0_G0_TX_DP<14>")
	)
	(segment
		(start 153.36393 -197.014338)
		(end 153.55697 -197.033388)
		(width 0.14224)
		(layer "In4.Cu")
		(net "GMI_CPU1_G2_CPU0_G0_TX_DP<14>")
	)
	(segment
		(start 158.24835 -193.186558)
		(end 158.2674 -192.993518)
		(width 0.14224)
		(layer "In4.Cu")
		(net "GMI_CPU1_G2_CPU0_G0_TX_DP<14>")
	)
	(segment
		(start 346.77985 -225.348546)
		(end 346.7481 -225.366834)
		(width 0.1143)
		(layer "In4.Cu")
		(net "GMI_CPU1_G2_CPU0_G0_TX_DP<14>")
	)
	(segment
		(start 148.715984 -200.824846)
		(end 153.36393 -197.014338)
		(width 0.14224)
		(layer "In4.Cu")
		(net "GMI_CPU1_G2_CPU0_G0_TX_DP<14>")
	)
	(segment
		(start 346.681298 -224.679002)
		(end 346.708984 -224.699068)
		(width 0.1143)
		(layer "In4.Cu")
		(net "GMI_CPU1_G2_CPU0_G0_TX_DP<14>")
	)
	(segment
		(start 346.277184 -227.79736)
		(end 346.27566 -227.798376)
		(width 0.1143)
		(layer "In4.Cu")
		(net "GMI_CPU1_G2_CPU0_G0_TX_DP<14>")
	)
	(segment
		(start 124.559822 -221.545912)
		(end 124.559822 -221.248732)
		(width 0.1143)
		(layer "In4.Cu")
		(net "GMI_CPU1_G2_CPU0_G0_TX_DP<14>")
	)
	(segment
		(start 160.011872 -191.56299)
		(end 160.700466 -190.998348)
		(width 0.14224)
		(layer "In4.Cu")
		(net "GMI_CPU1_G2_CPU0_G0_TX_DP<14>")
	)
	(segment
		(start 346.93606 -221.545658)
		(end 346.935806 -221.545912)
		(width 0.1143)
		(layer "In4.Cu")
		(net "GMI_CPU1_G2_CPU0_G0_TX_DP<14>")
	)
	(segment
		(start 125.21692 -227.796598)
		(end 125.214126 -227.795328)
		(width 0.1143)
		(layer "In4.Cu")
		(net "GMI_CPU1_G2_CPU0_G0_TX_DP<14>")
	)
	(segment
		(start 125.249178 -227.815394)
		(end 125.217682 -227.797106)
		(width 0.1143)
		(layer "In4.Cu")
		(net "GMI_CPU1_G2_CPU0_G0_TX_DP<14>")
	)
	(segment
		(start 154.236166 -196.299074)
		(end 154.429206 -196.318378)
		(width 0.14224)
		(layer "In4.Cu")
		(net "GMI_CPU1_G2_CPU0_G0_TX_DP<14>")
	)
	(segment
		(start 346.453206 -227.483924)
		(end 346.453206 -227.49637)
		(width 0.1143)
		(layer "In4.Cu")
		(net "GMI_CPU1_G2_CPU0_G0_TX_DP<14>")
	)
	(segment
		(start 160.700466 -190.998348)
		(end 160.855406 -190.70955)
		(width 0.14224)
		(layer "In4.Cu")
		(net "GMI_CPU1_G2_CPU0_G0_TX_DP<14>")
	)
	(segment
		(start 157.395164 -193.708782)
		(end 157.395164 -193.708274)
		(width 0.14224)
		(layer "In4.Cu")
		(net "GMI_CPU1_G2_CPU0_G0_TX_DP<14>")
	)
	(segment
		(start 124.716032 -223.728534)
		(end 124.716032 -223.728788)
		(width 0.1143)
		(layer "In4.Cu")
		(net "GMI_CPU1_G2_CPU0_G0_TX_DP<14>")
	)
	(segment
		(start 155.631642 -195.33235)
		(end 155.650692 -195.13931)
		(width 0.14224)
		(layer "In4.Cu")
		(net "GMI_CPU1_G2_CPU0_G0_TX_DP<14>")
	)
	(segment
		(start 346.93606 -221.248478)
		(end 346.93606 -221.545658)
		(width 0.1143)
		(layer "In4.Cu")
		(net "GMI_CPU1_G2_CPU0_G0_TX_DP<14>")
	)
	(segment
		(start 345.747086 -218.536266)
		(end 346.89034 -220.460062)
		(width 0.14224)
		(layer "In4.Cu")
		(net "GMI_CPU1_G2_CPU0_G0_TX_DP<14>")
	)
	(segment
		(start 211.720684 -190.123318)
		(end 233.93273 -199.32396)
		(width 0.14224)
		(layer "In4.Cu")
		(net "GMI_CPU1_G2_CPU0_G0_TX_DP<14>")
	)
	(segment
		(start 345.919044 -228.284278)
		(end 345.621102 -228.284278)
		(width 0.1143)
		(layer "In4.Cu")
		(net "GMI_CPU1_G2_CPU0_G0_TX_DP<14>")
	)
	(segment
		(start 239.58677 -199.154288)
		(end 251.05487 -191.124078)
		(width 0.14224)
		(layer "In4.Cu")
		(net "GMI_CPU1_G2_CPU0_G0_TX_DP<14>")
	)
	(segment
		(start 153.55697 -197.033388)
		(end 153.88717 -196.762624)
		(width 0.14224)
		(layer "In4.Cu")
		(net "GMI_CPU1_G2_CPU0_G0_TX_DP<14>")
	)
	(segment
		(start 125.24994 -227.815902)
		(end 125.249178 -227.815394)
		(width 0.1143)
		(layer "In4.Cu")
		(net "GMI_CPU1_G2_CPU0_G0_TX_DP<14>")
	)
	(segment
		(start 346.763848 -223.737424)
		(end 346.747846 -223.747076)
		(width 0.1143)
		(layer "In4.Cu")
		(net "GMI_CPU1_G2_CPU0_G0_TX_DP<14>")
	)
	(segment
		(start 156.503878 -194.617086)
		(end 156.522928 -194.424046)
		(width 0.14224)
		(layer "In4.Cu")
		(net "GMI_CPU1_G2_CPU0_G0_TX_DP<14>")
	)
	(segment
		(start 124.814584 -223.789748)
		(end 124.786898 -223.769682)
		(width 0.1143)
		(layer "In4.Cu")
		(net "GMI_CPU1_G2_CPU0_G0_TX_DP<14>")
	)
	(segment
		(start 157.91815 -193.457322)
		(end 158.24835 -193.186558)
		(width 0.14224)
		(layer "In4.Cu")
		(net "GMI_CPU1_G2_CPU0_G0_TX_DP<14>")
	)
	(segment
		(start 124.747782 -225.367088)
		(end 124.716032 -225.3488)
		(width 0.1143)
		(layer "In4.Cu")
		(net "GMI_CPU1_G2_CPU0_G0_TX_DP<14>")
	)
	(segment
		(start 346.7481 -226.341686)
		(end 346.77985 -226.359974)
		(width 0.1143)
		(layer "In4.Cu")
		(net "GMI_CPU1_G2_CPU0_G0_TX_DP<14>")
	)
	(segment
		(start 346.281756 -227.795074)
		(end 346.278962 -227.796344)
		(width 0.1143)
		(layer "In4.Cu")
		(net "GMI_CPU1_G2_CPU0_G0_TX_DP<14>")
	)
	(segment
		(start 346.001848 -228.201474)
		(end 345.919044 -228.284278)
		(width 0.1143)
		(layer "In4.Cu")
		(net "GMI_CPU1_G2_CPU0_G0_TX_DP<14>")
	)
	(segment
		(start 124.784104 -222.148146)
		(end 124.747782 -222.127064)
		(width 0.1143)
		(layer "In4.Cu")
		(net "GMI_CPU1_G2_CPU0_G0_TX_DP<14>")
	)
	(segment
		(start 346.7481 -222.12681)
		(end 346.711778 -222.147892)
		(width 0.1143)
		(layer "In4.Cu")
		(net "GMI_CPU1_G2_CPU0_G0_TX_DP<14>")
	)
	(segment
		(start 346.77985 -223.72828)
		(end 346.763848 -223.737424)
		(width 0.1143)
		(layer "In4.Cu")
		(net "GMI_CPU1_G2_CPU0_G0_TX_DP<14>")
	)
	(segment
		(start 124.605542 -221.203012)
		(end 124.605542 -221.174564)
		(width 0.1143)
		(layer "In4.Cu")
		(net "GMI_CPU1_G2_CPU0_G0_TX_DP<14>")
	)
	(segment
		(start 124.559822 -221.248732)
		(end 124.605542 -221.203012)
		(width 0.1143)
		(layer "In4.Cu")
		(net "GMI_CPU1_G2_CPU0_G0_TX_DP<14>")
	)
	(segment
		(start 346.711778 -223.08058)
		(end 346.7481 -223.101662)
		(width 0.1143)
		(layer "In4.Cu")
		(net "GMI_CPU1_G2_CPU0_G0_TX_DP<14>")
	)
	(segment
		(start 159.120586 -192.471294)
		(end 159.139636 -192.278254)
		(width 0.14224)
		(layer "In4.Cu")
		(net "GMI_CPU1_G2_CPU0_G0_TX_DP<14>")
	)
	(segment
		(start 159.662622 -192.026794)
		(end 159.992822 -191.75603)
		(width 0.14224)
		(layer "In4.Cu")
		(net "GMI_CPU1_G2_CPU0_G0_TX_DP<14>")
	)
	(segment
		(start 303.7332 -189.451488)
		(end 309.008272 -189.451488)
		(width 0.14224)
		(layer "In4.Cu")
		(net "GMI_CPU1_G2_CPU0_G0_TX_DP<14>")
	)
	(segment
		(start 125.217682 -227.797106)
		(end 125.21692 -227.796598)
		(width 0.1143)
		(layer "In4.Cu")
		(net "GMI_CPU1_G2_CPU0_G0_TX_DP<14>")
	)
	(segment
		(start 124.786898 -224.699322)
		(end 124.814584 -224.679256)
		(width 0.1143)
		(layer "In4.Cu")
		(net "GMI_CPU1_G2_CPU0_G0_TX_DP<14>")
	)
	(segment
		(start 346.27566 -227.798376)
		(end 346.239084 -227.819712)
		(width 0.1143)
		(layer "In4.Cu")
		(net "GMI_CPU1_G2_CPU0_G0_TX_DP<14>")
	)
	(segment
		(start 346.77985 -226.968304)
		(end 346.735908 -226.994212)
		(width 0.1143)
		(layer "In4.Cu")
		(net "GMI_CPU1_G2_CPU0_G0_TX_DP<14>")
	)
	(segment
		(start 262.688832 -189.07252)
		(end 303.7332 -189.451488)
		(width 0.14224)
		(layer "In4.Cu")
		(net "GMI_CPU1_G2_CPU0_G0_TX_DP<14>")
	)
	(segment
		(start 346.935806 -221.545912)
		(end 346.935806 -221.80423)
		(width 0.1143)
		(layer "In4.Cu")
		(net "GMI_CPU1_G2_CPU0_G0_TX_DP<14>")
	)
	(segment
		(start 155.980638 -194.8688)
		(end 156.173678 -194.88785)
		(width 0.14224)
		(layer "In4.Cu")
		(net "GMI_CPU1_G2_CPU0_G0_TX_DP<14>")
	)
	(segment
		(start 346.747846 -223.747076)
		(end 346.708984 -223.769428)
		(width 0.1143)
		(layer "In4.Cu")
		(net "GMI_CPU1_G2_CPU0_G0_TX_DP<14>")
	)
	(segment
		(start 124.759974 -226.994466)
		(end 124.716032 -226.968558)
		(width 0.1143)
		(layer "In4.Cu")
		(net "GMI_CPU1_G2_CPU0_G0_TX_DP<14>")
	)
	(segment
		(start 125.256798 -227.819966)
		(end 125.24994 -227.815902)
		(width 0.1143)
		(layer "In4.Cu")
		(net "GMI_CPU1_G2_CPU0_G0_TX_DP<14>")
	)
	(segment
		(start 156.522928 -194.424046)
		(end 156.852874 -194.153536)
		(width 0.14224)
		(layer "In4.Cu")
		(net "GMI_CPU1_G2_CPU0_G0_TX_DP<14>")
	)
	(segment
		(start 124.748036 -223.74733)
		(end 124.732034 -223.737678)
		(width 0.1143)
		(layer "In4.Cu")
		(net "GMI_CPU1_G2_CPU0_G0_TX_DP<14>")
	)
	(segment
		(start 124.560076 -221.804484)
		(end 124.560076 -221.546166)
		(width 0.1143)
		(layer "In4.Cu")
		(net "GMI_CPU1_G2_CPU0_G0_TX_DP<14>")
	)
	(segment
		(start 124.605542 -220.61678)
		(end 125.872748 -218.410282)
		(width 0.14224)
		(layer "In4.Cu")
		(net "GMI_CPU1_G2_CPU0_G0_TX_DP<14>")
	)
	(segment
		(start 153.88717 -196.762624)
		(end 153.90622 -196.569584)
		(width 0.14224)
		(layer "In4.Cu")
		(net "GMI_CPU1_G2_CPU0_G0_TX_DP<14>")
	)
	(arc
		(start 346.239084 -227.819712)
		(mid 346.087097 -227.97622)
		(end 346.005658 -228.178614)
		(width 0.1143)
		(layer "In4.Cu")
		(net "GMI_CPU1_G2_CPU0_G0_TX_DP<14>")
	)
	(arc
		(start 346.681298 -223.789494)
		(mid 346.453298 -224.234248)
		(end 346.681298 -224.679002)
		(width 0.1143)
		(layer "In4.Cu")
		(net "GMI_CPU1_G2_CPU0_G0_TX_DP<14>")
	)
	(arc
		(start 346.005658 -228.178614)
		(mid 346.003635 -228.190024)
		(end 346.001848 -228.201474)
		(width 0.1143)
		(layer "In4.Cu")
		(net "GMI_CPU1_G2_CPU0_G0_TX_DP<14>")
	)
	(arc
		(start 124.580396 -226.786186)
		(mid 124.577775 -226.550777)
		(end 124.716032 -226.360228)
		(width 0.1143)
		(layer "In4.Cu")
		(net "GMI_CPU1_G2_CPU0_G0_TX_DP<14>")
	)
	(arc
		(start 346.735908 -226.994212)
		(mid 346.52892 -227.201184)
		(end 346.453206 -227.483924)
		(width 0.1143)
		(layer "In4.Cu")
		(net "GMI_CPU1_G2_CPU0_G0_TX_DP<14>")
	)
	(arc
		(start 124.798328 -223.070928)
		(mid 125.025711 -222.61449)
		(end 124.798328 -222.158052)
		(width 0.1143)
		(layer "In4.Cu")
		(net "GMI_CPU1_G2_CPU0_G0_TX_DP<14>")
	)
	(arc
		(start 346.77985 -226.359974)
		(mid 346.918106 -226.550524)
		(end 346.915486 -226.785932)
		(width 0.1143)
		(layer "In4.Cu")
		(net "GMI_CPU1_G2_CPU0_G0_TX_DP<14>")
	)
	(arc
		(start 346.453206 -227.49637)
		(mid 346.40744 -227.668332)
		(end 346.282264 -227.79482)
		(width 0.1143)
		(layer "In4.Cu")
		(net "GMI_CPU1_G2_CPU0_G0_TX_DP<14>")
	)
	(arc
		(start 346.711778 -222.147892)
		(mid 346.704628 -222.15279)
		(end 346.697554 -222.157798)
		(width 0.1143)
		(layer "In4.Cu")
		(net "GMI_CPU1_G2_CPU0_G0_TX_DP<14>")
	)
	(arc
		(start 346.697554 -226.310698)
		(mid 346.704627 -226.315707)
		(end 346.711778 -226.320604)
		(width 0.1143)
		(layer "In4.Cu")
		(net "GMI_CPU1_G2_CPU0_G0_TX_DP<14>")
	)
	(arc
		(start 124.716032 -223.728788)
		(mid 124.560104 -223.424496)
		(end 124.716032 -223.120204)
		(width 0.1143)
		(layer "In4.Cu")
		(net "GMI_CPU1_G2_CPU0_G0_TX_DP<14>")
	)
	(arc
		(start 346.77985 -223.11995)
		(mid 346.935778 -223.424242)
		(end 346.77985 -223.728534)
		(width 0.1143)
		(layer "In4.Cu")
		(net "GMI_CPU1_G2_CPU0_G0_TX_DP<14>")
	)
	(arc
		(start 124.798328 -222.158052)
		(mid 124.791254 -222.153045)
		(end 124.784104 -222.148146)
		(width 0.1143)
		(layer "In4.Cu")
		(net "GMI_CPU1_G2_CPU0_G0_TX_DP<14>")
	)
	(arc
		(start 346.915486 -226.785932)
		(mid 346.86185 -226.887668)
		(end 346.77985 -226.968304)
		(width 0.1143)
		(layer "In4.Cu")
		(net "GMI_CPU1_G2_CPU0_G0_TX_DP<14>")
	)
	(arc
		(start 125.494034 -228.201728)
		(mid 125.414955 -227.986283)
		(end 125.256798 -227.819966)
		(width 0.1143)
		(layer "In4.Cu")
		(net "GMI_CPU1_G2_CPU0_G0_TX_DP<14>")
	)
	(arc
		(start 346.697554 -225.397822)
		(mid 346.470171 -225.85426)
		(end 346.697554 -226.310698)
		(width 0.1143)
		(layer "In4.Cu")
		(net "GMI_CPU1_G2_CPU0_G0_TX_DP<14>")
	)
	(arc
		(start 125.042676 -227.484178)
		(mid 124.966919 -227.201463)
		(end 124.759974 -226.994466)
		(width 0.1143)
		(layer "In4.Cu")
		(net "GMI_CPU1_G2_CPU0_G0_TX_DP<14>")
	)
	(arc
		(start 124.798328 -226.310952)
		(mid 125.025711 -225.854514)
		(end 124.798328 -225.398076)
		(width 0.1143)
		(layer "In4.Cu")
		(net "GMI_CPU1_G2_CPU0_G0_TX_DP<14>")
	)
	(arc
		(start 124.814584 -224.679256)
		(mid 125.042584 -224.234502)
		(end 124.814584 -223.789748)
		(width 0.1143)
		(layer "In4.Cu")
		(net "GMI_CPU1_G2_CPU0_G0_TX_DP<14>")
	)
	(arc
		(start 124.716032 -225.3488)
		(mid 124.560104 -225.044508)
		(end 124.716032 -224.740216)
		(width 0.1143)
		(layer "In4.Cu")
		(net "GMI_CPU1_G2_CPU0_G0_TX_DP<14>")
	)
	(arc
		(start 124.716032 -226.968558)
		(mid 124.634051 -226.887908)
		(end 124.580396 -226.786186)
		(width 0.1143)
		(layer "In4.Cu")
		(net "GMI_CPU1_G2_CPU0_G0_TX_DP<14>")
	)
	(arc
		(start 124.798328 -225.398076)
		(mid 124.791254 -225.393069)
		(end 124.784104 -225.38817)
		(width 0.1143)
		(layer "In4.Cu")
		(net "GMI_CPU1_G2_CPU0_G0_TX_DP<14>")
	)
	(arc
		(start 346.77985 -224.739962)
		(mid 346.935778 -225.044254)
		(end 346.77985 -225.348546)
		(width 0.1143)
		(layer "In4.Cu")
		(net "GMI_CPU1_G2_CPU0_G0_TX_DP<14>")
	)
	(arc
		(start 124.784104 -226.320858)
		(mid 124.791253 -226.315958)
		(end 124.798328 -226.310952)
		(width 0.1143)
		(layer "In4.Cu")
		(net "GMI_CPU1_G2_CPU0_G0_TX_DP<14>")
	)
	(arc
		(start 346.711778 -225.387916)
		(mid 346.704628 -225.392814)
		(end 346.697554 -225.397822)
		(width 0.1143)
		(layer "In4.Cu")
		(net "GMI_CPU1_G2_CPU0_G0_TX_DP<14>")
	)
	(arc
		(start 125.213618 -227.795074)
		(mid 125.088418 -227.6686)
		(end 125.042676 -227.496624)
		(width 0.1143)
		(layer "In4.Cu")
		(net "GMI_CPU1_G2_CPU0_G0_TX_DP<14>")
	)
	(arc
		(start 124.716032 -222.108776)
		(mid 124.601356 -221.975442)
		(end 124.560076 -221.804484)
		(width 0.1143)
		(layer "In4.Cu")
		(net "GMI_CPU1_G2_CPU0_G0_TX_DP<14>")
	)
	(arc
		(start 124.784104 -223.080834)
		(mid 124.791253 -223.075934)
		(end 124.798328 -223.070928)
		(width 0.1143)
		(layer "In4.Cu")
		(net "GMI_CPU1_G2_CPU0_G0_TX_DP<14>")
	)
	(arc
		(start 346.935806 -221.80423)
		(mid 346.894551 -221.975201)
		(end 346.77985 -222.108522)
		(width 0.1143)
		(layer "In4.Cu")
		(net "GMI_CPU1_G2_CPU0_G0_TX_DP<14>")
	)
	(arc
		(start 346.697554 -222.157798)
		(mid 346.470171 -222.614236)
		(end 346.697554 -223.070674)
		(width 0.1143)
		(layer "In4.Cu")
		(net "GMI_CPU1_G2_CPU0_G0_TX_DP<14>")
	)
	(arc
		(start 346.697554 -223.070674)
		(mid 346.704627 -223.075683)
		(end 346.711778 -223.08058)
		(width 0.1143)
		(layer "In4.Cu")
		(net "GMI_CPU1_G2_CPU0_G0_TX_DP<14>")
	)
	(segment
		(start 125.407928 -226.930458)
		(end 125.87478 -226.66452)
		(width 0.12954)
		(layer "F.Cu")
		(net "GMI_CPU1_G2_CPU0_G0_TX_DP<13>")
	)
	(segment
		(start 346.087954 -226.930204)
		(end 345.621102 -226.664266)
		(width 0.12954)
		(layer "F.Cu")
		(net "GMI_CPU1_G2_CPU0_G0_TX_DP<13>")
	)
	(segment
		(start 159.052768 -193.742818)
		(end 159.382714 -193.472308)
		(width 0.14224)
		(layer "In4.Cu")
		(net "GMI_CPU1_G2_CPU0_G0_TX_DP<13>")
	)
	(segment
		(start 125.87478 -226.66452)
		(end 125.576838 -226.66452)
		(width 0.1143)
		(layer "In4.Cu")
		(net "GMI_CPU1_G2_CPU0_G0_TX_DP<13>")
	)
	(segment
		(start 157.308042 -195.173092)
		(end 157.308296 -195.173092)
		(width 0.14224)
		(layer "In4.Cu")
		(net "GMI_CPU1_G2_CPU0_G0_TX_DP<13>")
	)
	(segment
		(start 345.919044 -226.664266)
		(end 345.621102 -226.664266)
		(width 0.1143)
		(layer "In4.Cu")
		(net "GMI_CPU1_G2_CPU0_G0_TX_DP<13>")
	)
	(segment
		(start 345.950286 -221.202758)
		(end 345.996006 -221.248478)
		(width 0.1143)
		(layer "In4.Cu")
		(net "GMI_CPU1_G2_CPU0_G0_TX_DP<13>")
	)
	(segment
		(start 158.180532 -194.457828)
		(end 158.510478 -194.187318)
		(width 0.14224)
		(layer "In4.Cu")
		(net "GMI_CPU1_G2_CPU0_G0_TX_DP<13>")
	)
	(segment
		(start 125.687582 -222.127064)
		(end 125.657102 -222.109284)
		(width 0.1143)
		(layer "In4.Cu")
		(net "GMI_CPU1_G2_CPU0_G0_TX_DP<13>")
	)
	(segment
		(start 154.672284 -197.511416)
		(end 154.691334 -197.318376)
		(width 0.14224)
		(layer "In4.Cu")
		(net "GMI_CPU1_G2_CPU0_G0_TX_DP<13>")
	)
	(segment
		(start 126.56947 -219.08135)
		(end 146.974814 -202.350116)
		(width 0.14224)
		(layer "In4.Cu")
		(net "GMI_CPU1_G2_CPU0_G0_TX_DP<13>")
	)
	(segment
		(start 233.006646 -200.115678)
		(end 236.278928 -200.692512)
		(width 0.14224)
		(layer "In4.Cu")
		(net "GMI_CPU1_G2_CPU0_G0_TX_DP<13>")
	)
	(segment
		(start 345.83878 -223.729042)
		(end 345.769184 -223.769682)
		(width 0.1143)
		(layer "In4.Cu")
		(net "GMI_CPU1_G2_CPU0_G0_TX_DP<13>")
	)
	(segment
		(start 154.691334 -197.318376)
		(end 155.02128 -197.047866)
		(width 0.14224)
		(layer "In4.Cu")
		(net "GMI_CPU1_G2_CPU0_G0_TX_DP<13>")
	)
	(segment
		(start 158.703518 -194.206622)
		(end 159.033718 -193.935604)
		(width 0.14224)
		(layer "In4.Cu")
		(net "GMI_CPU1_G2_CPU0_G0_TX_DP<13>")
	)
	(segment
		(start 146.974814 -202.350116)
		(end 149.48027 -201.590656)
		(width 0.14224)
		(layer "In4.Cu")
		(net "GMI_CPU1_G2_CPU0_G0_TX_DP<13>")
	)
	(segment
		(start 156.435806 -195.888356)
		(end 156.766006 -195.617846)
		(width 0.14224)
		(layer "In4.Cu")
		(net "GMI_CPU1_G2_CPU0_G0_TX_DP<13>")
	)
	(segment
		(start 125.726698 -225.389948)
		(end 125.687582 -225.367088)
		(width 0.1143)
		(layer "In4.Cu")
		(net "GMI_CPU1_G2_CPU0_G0_TX_DP<13>")
	)
	(segment
		(start 159.382714 -193.472308)
		(end 159.575754 -193.491612)
		(width 0.14224)
		(layer "In4.Cu")
		(net "GMI_CPU1_G2_CPU0_G0_TX_DP<13>")
	)
	(segment
		(start 207.257142 -190.291212)
		(end 210.793838 -190.91529)
		(width 0.14224)
		(layer "In4.Cu")
		(net "GMI_CPU1_G2_CPU0_G0_TX_DP<13>")
	)
	(segment
		(start 161.691066 -191.251078)
		(end 162.630866 -190.480188)
		(width 0.14224)
		(layer "In4.Cu")
		(net "GMI_CPU1_G2_CPU0_G0_TX_DP<13>")
	)
	(segment
		(start 125.657102 -226.35972)
		(end 125.687582 -226.34194)
		(width 0.1143)
		(layer "In4.Cu")
		(net "GMI_CPU1_G2_CPU0_G0_TX_DP<13>")
	)
	(segment
		(start 160.77819 -192.505584)
		(end 160.79724 -192.312544)
		(width 0.14224)
		(layer "In4.Cu")
		(net "GMI_CPU1_G2_CPU0_G0_TX_DP<13>")
	)
	(segment
		(start 156.958792 -195.636896)
		(end 157.288992 -195.366132)
		(width 0.14224)
		(layer "In4.Cu")
		(net "GMI_CPU1_G2_CPU0_G0_TX_DP<13>")
	)
	(segment
		(start 157.638242 -194.902582)
		(end 157.831282 -194.921886)
		(width 0.14224)
		(layer "In4.Cu")
		(net "GMI_CPU1_G2_CPU0_G0_TX_DP<13>")
	)
	(segment
		(start 156.086556 -196.351906)
		(end 156.416756 -196.081142)
		(width 0.14224)
		(layer "In4.Cu")
		(net "GMI_CPU1_G2_CPU0_G0_TX_DP<13>")
	)
	(segment
		(start 159.575754 -193.491612)
		(end 159.905954 -193.220594)
		(width 0.14224)
		(layer "In4.Cu")
		(net "GMI_CPU1_G2_CPU0_G0_TX_DP<13>")
	)
	(segment
		(start 125.50013 -221.804484)
		(end 125.50013 -221.546166)
		(width 0.1143)
		(layer "In4.Cu")
		(net "GMI_CPU1_G2_CPU0_G0_TX_DP<13>")
	)
	(segment
		(start 125.687582 -226.34194)
		(end 125.726698 -226.31908)
		(width 0.1143)
		(layer "In4.Cu")
		(net "GMI_CPU1_G2_CPU0_G0_TX_DP<13>")
	)
	(segment
		(start 125.687582 -225.367088)
		(end 125.657102 -225.349308)
		(width 0.1143)
		(layer "In4.Cu")
		(net "GMI_CPU1_G2_CPU0_G0_TX_DP<13>")
	)
	(segment
		(start 236.278928 -200.692512)
		(end 239.955578 -200.04405)
		(width 0.14224)
		(layer "In4.Cu")
		(net "GMI_CPU1_G2_CPU0_G0_TX_DP<13>")
	)
	(segment
		(start 303.7332 -190.391796)
		(end 308.646068 -190.391796)
		(width 0.14224)
		(layer "In4.Cu")
		(net "GMI_CPU1_G2_CPU0_G0_TX_DP<13>")
	)
	(segment
		(start 125.687582 -223.101916)
		(end 125.726698 -223.079056)
		(width 0.1143)
		(layer "In4.Cu")
		(net "GMI_CPU1_G2_CPU0_G0_TX_DP<13>")
	)
	(segment
		(start 158.161482 -194.650868)
		(end 158.180532 -194.457828)
		(width 0.14224)
		(layer "In4.Cu")
		(net "GMI_CPU1_G2_CPU0_G0_TX_DP<13>")
	)
	(segment
		(start 308.646068 -190.391796)
		(end 317.09868 -196.341746)
		(width 0.14224)
		(layer "In4.Cu")
		(net "GMI_CPU1_G2_CPU0_G0_TX_DP<13>")
	)
	(segment
		(start 158.510478 -194.187318)
		(end 158.658814 -194.20205)
		(width 0.14224)
		(layer "In4.Cu")
		(net "GMI_CPU1_G2_CPU0_G0_TX_DP<13>")
	)
	(segment
		(start 345.769184 -226.318826)
		(end 345.83878 -226.359466)
		(width 0.1143)
		(layer "In4.Cu")
		(net "GMI_CPU1_G2_CPU0_G0_TX_DP<13>")
	)
	(segment
		(start 156.416756 -196.081142)
		(end 156.435806 -195.888102)
		(width 0.14224)
		(layer "In4.Cu")
		(net "GMI_CPU1_G2_CPU0_G0_TX_DP<13>")
	)
	(segment
		(start 239.955578 -200.04405)
		(end 251.423424 -192.01384)
		(width 0.14224)
		(layer "In4.Cu")
		(net "GMI_CPU1_G2_CPU0_G0_TX_DP<13>")
	)
	(segment
		(start 345.996006 -221.248478)
		(end 345.996006 -221.545658)
		(width 0.1143)
		(layer "In4.Cu")
		(net "GMI_CPU1_G2_CPU0_G0_TX_DP<13>")
	)
	(segment
		(start 345.988894 -226.594416)
		(end 345.919044 -226.664266)
		(width 0.1143)
		(layer "In4.Cu")
		(net "GMI_CPU1_G2_CPU0_G0_TX_DP<13>")
	)
	(segment
		(start 156.435806 -195.888102)
		(end 156.435806 -195.888356)
		(width 0.14224)
		(layer "In4.Cu")
		(net "GMI_CPU1_G2_CPU0_G0_TX_DP<13>")
	)
	(segment
		(start 125.545596 -220.88983)
		(end 126.56947 -219.08135)
		(width 0.14224)
		(layer "In4.Cu")
		(net "GMI_CPU1_G2_CPU0_G0_TX_DP<13>")
	)
	(segment
		(start 210.793838 -190.91529)
		(end 233.006646 -200.115678)
		(width 0.14224)
		(layer "In4.Cu")
		(net "GMI_CPU1_G2_CPU0_G0_TX_DP<13>")
	)
	(segment
		(start 156.765752 -195.617592)
		(end 156.958792 -195.636896)
		(width 0.14224)
		(layer "In4.Cu")
		(net "GMI_CPU1_G2_CPU0_G0_TX_DP<13>")
	)
	(segment
		(start 149.48027 -201.590656)
		(end 154.149044 -197.76313)
		(width 0.14224)
		(layer "In4.Cu")
		(net "GMI_CPU1_G2_CPU0_G0_TX_DP<13>")
	)
	(segment
		(start 125.726698 -223.769936)
		(end 125.687582 -223.747076)
		(width 0.1143)
		(layer "In4.Cu")
		(net "GMI_CPU1_G2_CPU0_G0_TX_DP<13>")
	)
	(segment
		(start 345.83878 -222.10903)
		(end 345.769184 -222.14967)
		(width 0.1143)
		(layer "In4.Cu")
		(net "GMI_CPU1_G2_CPU0_G0_TX_DP<13>")
	)
	(segment
		(start 125.687582 -224.721928)
		(end 125.726698 -224.699068)
		(width 0.1143)
		(layer "In4.Cu")
		(net "GMI_CPU1_G2_CPU0_G0_TX_DP<13>")
	)
	(segment
		(start 155.21432 -197.06717)
		(end 155.54452 -196.796406)
		(width 0.14224)
		(layer "In4.Cu")
		(net "GMI_CPU1_G2_CPU0_G0_TX_DP<13>")
	)
	(segment
		(start 125.657102 -224.739708)
		(end 125.687582 -224.721928)
		(width 0.1143)
		(layer "In4.Cu")
		(net "GMI_CPU1_G2_CPU0_G0_TX_DP<13>")
	)
	(segment
		(start 157.831282 -194.921886)
		(end 158.161482 -194.650868)
		(width 0.14224)
		(layer "In4.Cu")
		(net "GMI_CPU1_G2_CPU0_G0_TX_DP<13>")
	)
	(segment
		(start 154.149044 -197.76313)
		(end 154.342084 -197.78218)
		(width 0.14224)
		(layer "In4.Cu")
		(net "GMI_CPU1_G2_CPU0_G0_TX_DP<13>")
	)
	(segment
		(start 155.89377 -196.332856)
		(end 156.086556 -196.351906)
		(width 0.14224)
		(layer "In4.Cu")
		(net "GMI_CPU1_G2_CPU0_G0_TX_DP<13>")
	)
	(segment
		(start 157.308296 -195.173092)
		(end 157.638242 -194.902582)
		(width 0.14224)
		(layer "In4.Cu")
		(net "GMI_CPU1_G2_CPU0_G0_TX_DP<13>")
	)
	(segment
		(start 154.342084 -197.78218)
		(end 154.672284 -197.511416)
		(width 0.14224)
		(layer "In4.Cu")
		(net "GMI_CPU1_G2_CPU0_G0_TX_DP<13>")
	)
	(segment
		(start 157.288992 -195.366132)
		(end 157.308042 -195.173092)
		(width 0.14224)
		(layer "In4.Cu")
		(net "GMI_CPU1_G2_CPU0_G0_TX_DP<13>")
	)
	(segment
		(start 160.79724 -192.312544)
		(end 161.377884 -191.836294)
		(width 0.14224)
		(layer "In4.Cu")
		(net "GMI_CPU1_G2_CPU0_G0_TX_DP<13>")
	)
	(segment
		(start 160.44799 -192.776348)
		(end 160.77819 -192.505584)
		(width 0.14224)
		(layer "In4.Cu")
		(net "GMI_CPU1_G2_CPU0_G0_TX_DP<13>")
	)
	(segment
		(start 159.905954 -193.220594)
		(end 159.925004 -193.027554)
		(width 0.14224)
		(layer "In4.Cu")
		(net "GMI_CPU1_G2_CPU0_G0_TX_DP<13>")
	)
	(segment
		(start 125.50013 -221.546166)
		(end 125.499876 -221.545912)
		(width 0.1143)
		(layer "In4.Cu")
		(net "GMI_CPU1_G2_CPU0_G0_TX_DP<13>")
	)
	(segment
		(start 125.499876 -221.248732)
		(end 125.545596 -221.203012)
		(width 0.1143)
		(layer "In4.Cu")
		(net "GMI_CPU1_G2_CPU0_G0_TX_DP<13>")
	)
	(segment
		(start 156.766006 -195.617846)
		(end 156.765752 -195.617592)
		(width 0.14224)
		(layer "In4.Cu")
		(net "GMI_CPU1_G2_CPU0_G0_TX_DP<13>")
	)
	(segment
		(start 158.658814 -194.20205)
		(end 158.703518 -194.206622)
		(width 0.14224)
		(layer "In4.Cu")
		(net "GMI_CPU1_G2_CPU0_G0_TX_DP<13>")
	)
	(segment
		(start 251.423424 -192.01384)
		(end 262.765794 -190.013844)
		(width 0.14224)
		(layer "In4.Cu")
		(net "GMI_CPU1_G2_CPU0_G0_TX_DP<13>")
	)
	(segment
		(start 159.925004 -193.027554)
		(end 160.25495 -192.757044)
		(width 0.14224)
		(layer "In4.Cu")
		(net "GMI_CPU1_G2_CPU0_G0_TX_DP<13>")
	)
	(segment
		(start 125.545596 -221.203012)
		(end 125.545596 -221.174564)
		(width 0.1143)
		(layer "In4.Cu")
		(net "GMI_CPU1_G2_CPU0_G0_TX_DP<13>")
	)
	(segment
		(start 345.950286 -220.708728)
		(end 345.950286 -221.17431)
		(width 0.14224)
		(layer "In4.Cu")
		(net "GMI_CPU1_G2_CPU0_G0_TX_DP<13>")
	)
	(segment
		(start 125.687582 -223.747076)
		(end 125.657102 -223.729296)
		(width 0.1143)
		(layer "In4.Cu")
		(net "GMI_CPU1_G2_CPU0_G0_TX_DP<13>")
	)
	(segment
		(start 125.657102 -223.119696)
		(end 125.687582 -223.101916)
		(width 0.1143)
		(layer "In4.Cu")
		(net "GMI_CPU1_G2_CPU0_G0_TX_DP<13>")
	)
	(segment
		(start 345.83878 -225.349054)
		(end 345.769184 -225.389694)
		(width 0.1143)
		(layer "In4.Cu")
		(net "GMI_CPU1_G2_CPU0_G0_TX_DP<13>")
	)
	(segment
		(start 125.499876 -221.545912)
		(end 125.499876 -221.248732)
		(width 0.1143)
		(layer "In4.Cu")
		(net "GMI_CPU1_G2_CPU0_G0_TX_DP<13>")
	)
	(segment
		(start 125.576838 -226.66452)
		(end 125.506988 -226.59467)
		(width 0.1143)
		(layer "In4.Cu")
		(net "GMI_CPU1_G2_CPU0_G0_TX_DP<13>")
	)
	(segment
		(start 160.25495 -192.757044)
		(end 160.44799 -192.776348)
		(width 0.14224)
		(layer "In4.Cu")
		(net "GMI_CPU1_G2_CPU0_G0_TX_DP<13>")
	)
	(segment
		(start 345.769184 -223.078802)
		(end 345.83878 -223.119442)
		(width 0.1143)
		(layer "In4.Cu")
		(net "GMI_CPU1_G2_CPU0_G0_TX_DP<13>")
	)
	(segment
		(start 317.09868 -196.341746)
		(end 345.126056 -219.322142)
		(width 0.14224)
		(layer "In4.Cu")
		(net "GMI_CPU1_G2_CPU0_G0_TX_DP<13>")
	)
	(segment
		(start 162.630866 -190.480188)
		(end 207.257142 -190.291212)
		(width 0.14224)
		(layer "In4.Cu")
		(net "GMI_CPU1_G2_CPU0_G0_TX_DP<13>")
	)
	(segment
		(start 155.56357 -196.603366)
		(end 155.89377 -196.332856)
		(width 0.14224)
		(layer "In4.Cu")
		(net "GMI_CPU1_G2_CPU0_G0_TX_DP<13>")
	)
	(segment
		(start 345.995752 -221.545912)
		(end 345.995752 -221.80423)
		(width 0.1143)
		(layer "In4.Cu")
		(net "GMI_CPU1_G2_CPU0_G0_TX_DP<13>")
	)
	(segment
		(start 161.377884 -191.836294)
		(end 161.691066 -191.251078)
		(width 0.14224)
		(layer "In4.Cu")
		(net "GMI_CPU1_G2_CPU0_G0_TX_DP<13>")
	)
	(segment
		(start 125.726698 -222.149924)
		(end 125.687582 -222.127064)
		(width 0.1143)
		(layer "In4.Cu")
		(net "GMI_CPU1_G2_CPU0_G0_TX_DP<13>")
	)
	(segment
		(start 155.54452 -196.796406)
		(end 155.56357 -196.603366)
		(width 0.14224)
		(layer "In4.Cu")
		(net "GMI_CPU1_G2_CPU0_G0_TX_DP<13>")
	)
	(segment
		(start 345.126056 -219.322142)
		(end 345.950286 -220.708728)
		(width 0.14224)
		(layer "In4.Cu")
		(net "GMI_CPU1_G2_CPU0_G0_TX_DP<13>")
	)
	(segment
		(start 262.765794 -190.013844)
		(end 303.7332 -190.391796)
		(width 0.14224)
		(layer "In4.Cu")
		(net "GMI_CPU1_G2_CPU0_G0_TX_DP<13>")
	)
	(segment
		(start 159.033718 -193.935604)
		(end 159.052768 -193.742818)
		(width 0.14224)
		(layer "In4.Cu")
		(net "GMI_CPU1_G2_CPU0_G0_TX_DP<13>")
	)
	(segment
		(start 155.02128 -197.047866)
		(end 155.21432 -197.06717)
		(width 0.14224)
		(layer "In4.Cu")
		(net "GMI_CPU1_G2_CPU0_G0_TX_DP<13>")
	)
	(segment
		(start 345.950286 -221.17431)
		(end 345.950286 -221.202758)
		(width 0.1143)
		(layer "In4.Cu")
		(net "GMI_CPU1_G2_CPU0_G0_TX_DP<13>")
	)
	(segment
		(start 345.769184 -224.698814)
		(end 345.83878 -224.739454)
		(width 0.1143)
		(layer "In4.Cu")
		(net "GMI_CPU1_G2_CPU0_G0_TX_DP<13>")
	)
	(segment
		(start 125.545596 -221.174564)
		(end 125.545596 -220.88983)
		(width 0.14224)
		(layer "In4.Cu")
		(net "GMI_CPU1_G2_CPU0_G0_TX_DP<13>")
	)
	(segment
		(start 345.996006 -221.545658)
		(end 345.995752 -221.545912)
		(width 0.1143)
		(layer "In4.Cu")
		(net "GMI_CPU1_G2_CPU0_G0_TX_DP<13>")
	)
	(arc
		(start 345.83878 -223.119442)
		(mid 345.995757 -223.424242)
		(end 345.83878 -223.729042)
		(width 0.1143)
		(layer "In4.Cu")
		(net "GMI_CPU1_G2_CPU0_G0_TX_DP<13>")
	)
	(arc
		(start 125.726698 -224.699068)
		(mid 125.970025 -224.234502)
		(end 125.726698 -223.769936)
		(width 0.1143)
		(layer "In4.Cu")
		(net "GMI_CPU1_G2_CPU0_G0_TX_DP<13>")
	)
	(arc
		(start 125.657102 -222.109284)
		(mid 125.541675 -221.975908)
		(end 125.50013 -221.804484)
		(width 0.1143)
		(layer "In4.Cu")
		(net "GMI_CPU1_G2_CPU0_G0_TX_DP<13>")
	)
	(arc
		(start 345.995752 -221.80423)
		(mid 345.954203 -221.975652)
		(end 345.83878 -222.10903)
		(width 0.1143)
		(layer "In4.Cu")
		(net "GMI_CPU1_G2_CPU0_G0_TX_DP<13>")
	)
	(arc
		(start 125.506988 -226.59467)
		(mid 125.559405 -226.462739)
		(end 125.657102 -226.35972)
		(width 0.1143)
		(layer "In4.Cu")
		(net "GMI_CPU1_G2_CPU0_G0_TX_DP<13>")
	)
	(arc
		(start 345.83878 -226.359466)
		(mid 345.936545 -226.462442)
		(end 345.988894 -226.594416)
		(width 0.1143)
		(layer "In4.Cu")
		(net "GMI_CPU1_G2_CPU0_G0_TX_DP<13>")
	)
	(arc
		(start 345.83878 -224.739454)
		(mid 345.995757 -225.044254)
		(end 345.83878 -225.349054)
		(width 0.1143)
		(layer "In4.Cu")
		(net "GMI_CPU1_G2_CPU0_G0_TX_DP<13>")
	)
	(arc
		(start 125.726698 -223.079056)
		(mid 125.970025 -222.61449)
		(end 125.726698 -222.149924)
		(width 0.1143)
		(layer "In4.Cu")
		(net "GMI_CPU1_G2_CPU0_G0_TX_DP<13>")
	)
	(arc
		(start 125.657102 -223.729296)
		(mid 125.500125 -223.424496)
		(end 125.657102 -223.119696)
		(width 0.1143)
		(layer "In4.Cu")
		(net "GMI_CPU1_G2_CPU0_G0_TX_DP<13>")
	)
	(arc
		(start 345.769184 -223.769682)
		(mid 345.525857 -224.234248)
		(end 345.769184 -224.698814)
		(width 0.1143)
		(layer "In4.Cu")
		(net "GMI_CPU1_G2_CPU0_G0_TX_DP<13>")
	)
	(arc
		(start 125.726698 -226.31908)
		(mid 125.970025 -225.854514)
		(end 125.726698 -225.389948)
		(width 0.1143)
		(layer "In4.Cu")
		(net "GMI_CPU1_G2_CPU0_G0_TX_DP<13>")
	)
	(arc
		(start 345.769184 -225.389694)
		(mid 345.525857 -225.85426)
		(end 345.769184 -226.318826)
		(width 0.1143)
		(layer "In4.Cu")
		(net "GMI_CPU1_G2_CPU0_G0_TX_DP<13>")
	)
	(arc
		(start 125.657102 -225.349308)
		(mid 125.500125 -225.044508)
		(end 125.657102 -224.739708)
		(width 0.1143)
		(layer "In4.Cu")
		(net "GMI_CPU1_G2_CPU0_G0_TX_DP<13>")
	)
	(arc
		(start 345.769184 -222.14967)
		(mid 345.525857 -222.614236)
		(end 345.769184 -223.078802)
		(width 0.1143)
		(layer "In4.Cu")
		(net "GMI_CPU1_G2_CPU0_G0_TX_DP<13>")
	)
	(segment
		(start 346.087954 -230.169974)
		(end 345.621102 -229.904036)
		(width 0.12954)
		(layer "F.Cu")
		(net "GMI_CPU1_G2_CPU0_G0_TX_DP<12>")
	)
	(segment
		(start 125.407928 -230.170228)
		(end 125.87478 -229.90429)
		(width 0.12954)
		(layer "F.Cu")
		(net "GMI_CPU1_G2_CPU0_G0_TX_DP<12>")
	)
	(segment
		(start 239.269524 -198.22922)
		(end 239.26927 -198.22922)
		(width 0.14224)
		(layer "In4.Cu")
		(net "GMI_CPU1_G2_CPU0_G0_TX_DP<12>")
	)
	(segment
		(start 347.698568 -222.120968)
		(end 347.696028 -222.122238)
		(width 0.1143)
		(layer "In4.Cu")
		(net "GMI_CPU1_G2_CPU0_G0_TX_DP<12>")
	)
	(segment
		(start 347.685614 -224.72015)
		(end 347.687138 -224.721166)
		(width 0.1143)
		(layer "In4.Cu")
		(net "GMI_CPU1_G2_CPU0_G0_TX_DP<12>")
	)
	(segment
		(start 347.69171 -222.124778)
		(end 347.688916 -222.126302)
		(width 0.1143)
		(layer "In4.Cu")
		(net "GMI_CPU1_G2_CPU0_G0_TX_DP<12>")
	)
	(segment
		(start 346.93606 -228.282754)
		(end 346.93606 -228.284024)
		(width 0.1143)
		(layer "In4.Cu")
		(net "GMI_CPU1_G2_CPU0_G0_TX_DP<12>")
	)
	(segment
		(start 155.037028 -194.25031)
		(end 155.366974 -193.9798)
		(width 0.14224)
		(layer "In4.Cu")
		(net "GMI_CPU1_G2_CPU0_G0_TX_DP<12>")
	)
	(segment
		(start 158.436564 -191.462914)
		(end 158.629604 -191.481964)
		(width 0.14224)
		(layer "In4.Cu")
		(net "GMI_CPU1_G2_CPU0_G0_TX_DP<12>")
	)
	(segment
		(start 123.807728 -222.127064)
		(end 123.806966 -222.126556)
		(width 0.1143)
		(layer "In4.Cu")
		(net "GMI_CPU1_G2_CPU0_G0_TX_DP<12>")
	)
	(segment
		(start 123.839986 -225.385884)
		(end 123.839224 -225.385376)
		(width 0.1143)
		(layer "In4.Cu")
		(net "GMI_CPU1_G2_CPU0_G0_TX_DP<12>")
	)
	(segment
		(start 123.810268 -224.720404)
		(end 123.846844 -224.699068)
		(width 0.1143)
		(layer "In4.Cu")
		(net "GMI_CPU1_G2_CPU0_G0_TX_DP<12>")
	)
	(segment
		(start 347.687138 -224.721166)
		(end 347.688154 -224.721674)
		(width 0.1143)
		(layer "In4.Cu")
		(net "GMI_CPU1_G2_CPU0_G0_TX_DP<12>")
	)
	(segment
		(start 159.83204 -190.495936)
		(end 159.851344 -190.302896)
		(width 0.14224)
		(layer "In4.Cu")
		(net "GMI_CPU1_G2_CPU0_G0_TX_DP<12>")
	)
	(segment
		(start 123.838462 -227.00488)
		(end 123.83516 -227.002848)
		(width 0.1143)
		(layer "In4.Cu")
		(net "GMI_CPU1_G2_CPU0_G0_TX_DP<12>")
	)
	(segment
		(start 236.278928 -198.783448)
		(end 239.218216 -198.265034)
		(width 0.14224)
		(layer "In4.Cu")
		(net "GMI_CPU1_G2_CPU0_G0_TX_DP<12>")
	)
	(segment
		(start 347.688154 -224.721674)
		(end 347.688916 -224.722182)
		(width 0.1143)
		(layer "In4.Cu")
		(net "GMI_CPU1_G2_CPU0_G0_TX_DP<12>")
	)
	(segment
		(start 158.978854 -191.01816)
		(end 159.3088 -190.74765)
		(width 0.14224)
		(layer "In4.Cu")
		(net "GMI_CPU1_G2_CPU0_G0_TX_DP<12>")
	)
	(segment
		(start 123.807728 -226.34194)
		(end 123.808744 -226.341432)
		(width 0.1143)
		(layer "In4.Cu")
		(net "GMI_CPU1_G2_CPU0_G0_TX_DP<12>")
	)
	(segment
		(start 213.033864 -189.400434)
		(end 235.226606 -198.592948)
		(width 0.14224)
		(layer "In4.Cu")
		(net "GMI_CPU1_G2_CPU0_G0_TX_DP<12>")
	)
	(segment
		(start 159.3088 -190.74765)
		(end 159.50184 -190.7667)
		(width 0.14224)
		(layer "In4.Cu")
		(net "GMI_CPU1_G2_CPU0_G0_TX_DP<12>")
	)
	(segment
		(start 347.685614 -226.340162)
		(end 347.687138 -226.341178)
		(width 0.1143)
		(layer "In4.Cu")
		(net "GMI_CPU1_G2_CPU0_G0_TX_DP<12>")
	)
	(segment
		(start 123.834144 -227.00234)
		(end 123.807728 -226.9871)
		(width 0.1143)
		(layer "In4.Cu")
		(net "GMI_CPU1_G2_CPU0_G0_TX_DP<12>")
	)
	(segment
		(start 123.80341 -222.124524)
		(end 123.801886 -222.123762)
		(width 0.1143)
		(layer "In4.Cu")
		(net "GMI_CPU1_G2_CPU0_G0_TX_DP<12>")
	)
	(segment
		(start 123.807728 -223.101916)
		(end 123.808744 -223.101408)
		(width 0.1143)
		(layer "In4.Cu")
		(net "GMI_CPU1_G2_CPU0_G0_TX_DP<12>")
	)
	(segment
		(start 347.656658 -223.76511)
		(end 347.655896 -223.765618)
		(width 0.1143)
		(layer "In4.Cu")
		(net "GMI_CPU1_G2_CPU0_G0_TX_DP<12>")
	)
	(segment
		(start 157.234382 -192.448688)
		(end 157.564328 -192.178178)
		(width 0.14224)
		(layer "In4.Cu")
		(net "GMI_CPU1_G2_CPU0_G0_TX_DP<12>")
	)
	(segment
		(start 347.696028 -226.346258)
		(end 347.719904 -226.359974)
		(width 0.1143)
		(layer "In4.Cu")
		(net "GMI_CPU1_G2_CPU0_G0_TX_DP<12>")
	)
	(segment
		(start 123.839986 -227.005896)
		(end 123.838462 -227.00488)
		(width 0.1143)
		(layer "In4.Cu")
		(net "GMI_CPU1_G2_CPU0_G0_TX_DP<12>")
	)
	(segment
		(start 123.801886 -222.123762)
		(end 123.801124 -222.123254)
		(width 0.1143)
		(layer "In4.Cu")
		(net "GMI_CPU1_G2_CPU0_G0_TX_DP<12>")
	)
	(segment
		(start 347.719904 -223.728534)
		(end 347.690186 -223.745552)
		(width 0.1143)
		(layer "In4.Cu")
		(net "GMI_CPU1_G2_CPU0_G0_TX_DP<12>")
	)
	(segment
		(start 123.665488 -221.174564)
		(end 123.665488 -220.368622)
		(width 0.14224)
		(layer "In4.Cu")
		(net "GMI_CPU1_G2_CPU0_G0_TX_DP<12>")
	)
	(segment
		(start 347.65742 -227.004626)
		(end 347.655896 -227.005642)
		(width 0.1143)
		(layer "In4.Cu")
		(net "GMI_CPU1_G2_CPU0_G0_TX_DP<12>")
	)
	(segment
		(start 347.830394 -221.202758)
		(end 347.876114 -221.248478)
		(width 0.1143)
		(layer "In4.Cu")
		(net "GMI_CPU1_G2_CPU0_G0_TX_DP<12>")
	)
	(segment
		(start 347.688154 -226.341686)
		(end 347.688916 -226.342194)
		(width 0.1143)
		(layer "In4.Cu")
		(net "GMI_CPU1_G2_CPU0_G0_TX_DP<12>")
	)
	(segment
		(start 123.775978 -223.120204)
		(end 123.806966 -223.102424)
		(width 0.1143)
		(layer "In4.Cu")
		(net "GMI_CPU1_G2_CPU0_G0_TX_DP<12>")
	)
	(segment
		(start 125.576838 -229.90429)
		(end 125.494034 -229.821486)
		(width 0.1143)
		(layer "In4.Cu")
		(net "GMI_CPU1_G2_CPU0_G0_TX_DP<12>")
	)
	(segment
		(start 347.688154 -222.12681)
		(end 347.687138 -222.127318)
		(width 0.1143)
		(layer "In4.Cu")
		(net "GMI_CPU1_G2_CPU0_G0_TX_DP<12>")
	)
	(segment
		(start 347.649038 -224.698814)
		(end 347.685614 -224.72015)
		(width 0.1143)
		(layer "In4.Cu")
		(net "GMI_CPU1_G2_CPU0_G0_TX_DP<12>")
	)
	(segment
		(start 124.785882 -228.62921)
		(end 124.75718 -228.6127)
		(width 0.1143)
		(layer "In4.Cu")
		(net "GMI_CPU1_G2_CPU0_G0_TX_DP<12>")
	)
	(segment
		(start 347.690186 -223.745552)
		(end 347.688916 -223.746314)
		(width 0.1143)
		(layer "In4.Cu")
		(net "GMI_CPU1_G2_CPU0_G0_TX_DP<12>")
	)
	(segment
		(start 156.692092 -192.893188)
		(end 156.885132 -192.912492)
		(width 0.14224)
		(layer "In4.Cu")
		(net "GMI_CPU1_G2_CPU0_G0_TX_DP<12>")
	)
	(segment
		(start 123.806966 -222.126556)
		(end 123.804172 -222.125032)
		(width 0.1143)
		(layer "In4.Cu")
		(net "GMI_CPU1_G2_CPU0_G0_TX_DP<12>")
	)
	(segment
		(start 347.690186 -225.365564)
		(end 347.688916 -225.366326)
		(width 0.1143)
		(layer "In4.Cu")
		(net "GMI_CPU1_G2_CPU0_G0_TX_DP<12>")
	)
	(segment
		(start 347.655896 -225.38563)
		(end 347.649038 -225.389694)
		(width 0.1143)
		(layer "In4.Cu")
		(net "GMI_CPU1_G2_CPU0_G0_TX_DP<12>")
	)
	(segment
		(start 235.257086 -198.603362)
		(end 236.278928 -198.783448)
		(width 0.14224)
		(layer "In4.Cu")
		(net "GMI_CPU1_G2_CPU0_G0_TX_DP<12>")
	)
	(segment
		(start 303.70526 -188.472826)
		(end 309.330852 -188.472826)
		(width 0.14224)
		(layer "In4.Cu")
		(net "GMI_CPU1_G2_CPU0_G0_TX_DP<12>")
	)
	(segment
		(start 123.620022 -221.546166)
		(end 123.619768 -221.545912)
		(width 0.1143)
		(layer "In4.Cu")
		(net "GMI_CPU1_G2_CPU0_G0_TX_DP<12>")
	)
	(segment
		(start 155.017978 -194.44335)
		(end 155.037028 -194.25031)
		(width 0.14224)
		(layer "In4.Cu")
		(net "GMI_CPU1_G2_CPU0_G0_TX_DP<12>")
	)
	(segment
		(start 123.839224 -223.765364)
		(end 123.807728 -223.747076)
		(width 0.1143)
		(layer "In4.Cu")
		(net "GMI_CPU1_G2_CPU0_G0_TX_DP<12>")
	)
	(segment
		(start 239.218216 -198.265034)
		(end 239.269524 -198.22922)
		(width 0.14224)
		(layer "In4.Cu")
		(net "GMI_CPU1_G2_CPU0_G0_TX_DP<12>")
	)
	(segment
		(start 347.694758 -226.345496)
		(end 347.696028 -226.346258)
		(width 0.1143)
		(layer "In4.Cu")
		(net "GMI_CPU1_G2_CPU0_G0_TX_DP<12>")
	)
	(segment
		(start 347.688154 -225.366834)
		(end 347.656658 -225.385122)
		(width 0.1143)
		(layer "In4.Cu")
		(net "GMI_CPU1_G2_CPU0_G0_TX_DP<12>")
	)
	(segment
		(start 347.694758 -222.123)
		(end 347.693996 -222.123508)
		(width 0.1143)
		(layer "In4.Cu")
		(net "GMI_CPU1_G2_CPU0_G0_TX_DP<12>")
	)
	(segment
		(start 347.696028 -222.122238)
		(end 347.694758 -222.123)
		(width 0.1143)
		(layer "In4.Cu")
		(net "GMI_CPU1_G2_CPU0_G0_TX_DP<12>")
	)
	(segment
		(start 347.688154 -223.101662)
		(end 347.688916 -223.10217)
		(width 0.1143)
		(layer "In4.Cu")
		(net "GMI_CPU1_G2_CPU0_G0_TX_DP<12>")
	)
	(segment
		(start 347.688916 -226.342194)
		(end 347.69171 -226.343718)
		(width 0.1143)
		(layer "In4.Cu")
		(net "GMI_CPU1_G2_CPU0_G0_TX_DP<12>")
	)
	(segment
		(start 347.69171 -224.723706)
		(end 347.692472 -224.724214)
		(width 0.1143)
		(layer "In4.Cu")
		(net "GMI_CPU1_G2_CPU0_G0_TX_DP<12>")
	)
	(segment
		(start 347.688154 -223.746822)
		(end 347.656658 -223.76511)
		(width 0.1143)
		(layer "In4.Cu")
		(net "GMI_CPU1_G2_CPU0_G0_TX_DP<12>")
	)
	(segment
		(start 123.799854 -222.122492)
		(end 123.797314 -222.121222)
		(width 0.1143)
		(layer "In4.Cu")
		(net "GMI_CPU1_G2_CPU0_G0_TX_DP<12>")
	)
	(segment
		(start 155.909264 -193.535046)
		(end 155.909264 -193.5353)
		(width 0.14224)
		(layer "In4.Cu")
		(net "GMI_CPU1_G2_CPU0_G0_TX_DP<12>")
	)
	(segment
		(start 125.30328 -217.53068)
		(end 145.878042 -200.66)
		(width 0.14224)
		(layer "In4.Cu")
		(net "GMI_CPU1_G2_CPU0_G0_TX_DP<12>")
	)
	(segment
		(start 153.292556 -195.680838)
		(end 153.622502 -195.410328)
		(width 0.14224)
		(layer "In4.Cu")
		(net "GMI_CPU1_G2_CPU0_G0_TX_DP<12>")
	)
	(segment
		(start 347.692472 -224.724214)
		(end 347.693996 -224.724976)
		(width 0.1143)
		(layer "In4.Cu")
		(net "GMI_CPU1_G2_CPU0_G0_TX_DP<12>")
	)
	(segment
		(start 158.658814 -191.458088)
		(end 158.959804 -191.2112)
		(width 0.14224)
		(layer "In4.Cu")
		(net "GMI_CPU1_G2_CPU0_G0_TX_DP<12>")
	)
	(segment
		(start 123.805696 -223.745806)
		(end 123.775978 -223.728788)
		(width 0.1143)
		(layer "In4.Cu")
		(net "GMI_CPU1_G2_CPU0_G0_TX_DP<12>")
	)
	(segment
		(start 347.649038 -223.078802)
		(end 347.685614 -223.100138)
		(width 0.1143)
		(layer "In4.Cu")
		(net "GMI_CPU1_G2_CPU0_G0_TX_DP<12>")
	)
	(segment
		(start 123.808744 -226.341432)
		(end 123.810268 -226.340416)
		(width 0.1143)
		(layer "In4.Cu")
		(net "GMI_CPU1_G2_CPU0_G0_TX_DP<12>")
	)
	(segment
		(start 125.256798 -229.439724)
		(end 125.217682 -229.416864)
		(width 0.1143)
		(layer "In4.Cu")
		(net "GMI_CPU1_G2_CPU0_G0_TX_DP<12>")
	)
	(segment
		(start 347.688916 -222.126302)
		(end 347.688154 -222.12681)
		(width 0.1143)
		(layer "In4.Cu")
		(net "GMI_CPU1_G2_CPU0_G0_TX_DP<12>")
	)
	(segment
		(start 207.3402 -188.396626)
		(end 213.033864 -189.400434)
		(width 0.14224)
		(layer "In4.Cu")
		(net "GMI_CPU1_G2_CPU0_G0_TX_DP<12>")
	)
	(segment
		(start 148.0058 -200.015856)
		(end 152.750012 -196.125846)
		(width 0.14224)
		(layer "In4.Cu")
		(net "GMI_CPU1_G2_CPU0_G0_TX_DP<12>")
	)
	(segment
		(start 347.719904 -226.968558)
		(end 347.690186 -226.985576)
		(width 0.1143)
		(layer "In4.Cu")
		(net "GMI_CPU1_G2_CPU0_G0_TX_DP<12>")
	)
	(segment
		(start 155.560014 -193.99885)
		(end 155.890214 -193.728086)
		(width 0.14224)
		(layer "In4.Cu")
		(net "GMI_CPU1_G2_CPU0_G0_TX_DP<12>")
	)
	(segment
		(start 347.87586 -221.545912)
		(end 347.87586 -221.80423)
		(width 0.1143)
		(layer "In4.Cu")
		(net "GMI_CPU1_G2_CPU0_G0_TX_DP<12>")
	)
	(segment
		(start 347.688154 -226.986846)
		(end 347.661738 -227.002086)
		(width 0.1143)
		(layer "In4.Cu")
		(net "GMI_CPU1_G2_CPU0_G0_TX_DP<12>")
	)
	(segment
		(start 123.620022 -221.804484)
		(end 123.620022 -221.546166)
		(width 0.1143)
		(layer "In4.Cu")
		(net "GMI_CPU1_G2_CPU0_G0_TX_DP<12>")
	)
	(segment
		(start 161.952432 -188.580014)
		(end 207.3402 -188.396626)
		(width 0.14224)
		(layer "In4.Cu")
		(net "GMI_CPU1_G2_CPU0_G0_TX_DP<12>")
	)
	(segment
		(start 123.810268 -223.100392)
		(end 123.846844 -223.079056)
		(width 0.1143)
		(layer "In4.Cu")
		(net "GMI_CPU1_G2_CPU0_G0_TX_DP<12>")
	)
	(segment
		(start 123.805696 -224.723198)
		(end 123.806966 -224.722436)
		(width 0.1143)
		(layer "In4.Cu")
		(net "GMI_CPU1_G2_CPU0_G0_TX_DP<12>")
	)
	(segment
		(start 123.807728 -223.747076)
		(end 123.806966 -223.746568)
		(width 0.1143)
		(layer "In4.Cu")
		(net "GMI_CPU1_G2_CPU0_G0_TX_DP<12>")
	)
	(segment
		(start 123.775978 -226.360228)
		(end 123.805696 -226.34321)
		(width 0.1143)
		(layer "In4.Cu")
		(net "GMI_CPU1_G2_CPU0_G0_TX_DP<12>")
	)
	(segment
		(start 158.629604 -191.481964)
		(end 158.658814 -191.458088)
		(width 0.14224)
		(layer "In4.Cu")
		(net "GMI_CPU1_G2_CPU0_G0_TX_DP<12>")
	)
	(segment
		(start 123.846844 -225.389948)
		(end 123.839986 -225.385884)
		(width 0.1143)
		(layer "In4.Cu")
		(net "GMI_CPU1_G2_CPU0_G0_TX_DP<12>")
	)
	(segment
		(start 123.808744 -222.127572)
		(end 123.807728 -222.127064)
		(width 0.1143)
		(layer "In4.Cu")
		(net "GMI_CPU1_G2_CPU0_G0_TX_DP<12>")
	)
	(segment
		(start 123.797314 -222.121222)
		(end 123.775978 -222.108776)
		(width 0.1143)
		(layer "In4.Cu")
		(net "GMI_CPU1_G2_CPU0_G0_TX_DP<12>")
	)
	(segment
		(start 347.876114 -221.545658)
		(end 347.87586 -221.545912)
		(width 0.1143)
		(layer "In4.Cu")
		(net "GMI_CPU1_G2_CPU0_G0_TX_DP<12>")
	)
	(segment
		(start 318.759586 -195.154042)
		(end 346.414598 -217.830146)
		(width 0.14224)
		(layer "In4.Cu")
		(net "GMI_CPU1_G2_CPU0_G0_TX_DP<12>")
	)
	(segment
		(start 347.688916 -223.10217)
		(end 347.719904 -223.11995)
		(width 0.1143)
		(layer "In4.Cu")
		(net "GMI_CPU1_G2_CPU0_G0_TX_DP<12>")
	)
	(segment
		(start 154.687778 -194.714114)
		(end 155.017978 -194.44335)
		(width 0.14224)
		(layer "In4.Cu")
		(net "GMI_CPU1_G2_CPU0_G0_TX_DP<12>")
	)
	(segment
		(start 123.839986 -223.765872)
		(end 123.839224 -223.765364)
		(width 0.1143)
		(layer "In4.Cu")
		(net "GMI_CPU1_G2_CPU0_G0_TX_DP<12>")
	)
	(segment
		(start 153.815542 -195.429378)
		(end 154.145742 -195.158614)
		(width 0.14224)
		(layer "In4.Cu")
		(net "GMI_CPU1_G2_CPU0_G0_TX_DP<12>")
	)
	(segment
		(start 123.806966 -226.986592)
		(end 123.805696 -226.98583)
		(width 0.1143)
		(layer "In4.Cu")
		(net "GMI_CPU1_G2_CPU0_G0_TX_DP<12>")
	)
	(segment
		(start 347.830394 -220.215206)
		(end 347.830394 -221.17431)
		(width 0.14224)
		(layer "In4.Cu")
		(net "GMI_CPU1_G2_CPU0_G0_TX_DP<12>")
	)
	(segment
		(start 123.801124 -222.123254)
		(end 123.799854 -222.122492)
		(width 0.1143)
		(layer "In4.Cu")
		(net "GMI_CPU1_G2_CPU0_G0_TX_DP<12>")
	)
	(segment
		(start 347.649038 -226.318826)
		(end 347.685614 -226.340162)
		(width 0.1143)
		(layer "In4.Cu")
		(net "GMI_CPU1_G2_CPU0_G0_TX_DP<12>")
	)
	(segment
		(start 145.878042 -200.66)
		(end 148.0058 -200.015856)
		(width 0.14224)
		(layer "In4.Cu")
		(net "GMI_CPU1_G2_CPU0_G0_TX_DP<12>")
	)
	(segment
		(start 235.226606 -198.592948)
		(end 235.257086 -198.603362)
		(width 0.14224)
		(layer "In4.Cu")
		(net "GMI_CPU1_G2_CPU0_G0_TX_DP<12>")
	)
	(segment
		(start 159.50184 -190.7667)
		(end 159.83204 -190.495936)
		(width 0.14224)
		(layer "In4.Cu")
		(net "GMI_CPU1_G2_CPU0_G0_TX_DP<12>")
	)
	(segment
		(start 347.696028 -224.726246)
		(end 347.719904 -224.739962)
		(width 0.1143)
		(layer "In4.Cu")
		(net "GMI_CPU1_G2_CPU0_G0_TX_DP<12>")
	)
	(segment
		(start 123.846844 -222.149924)
		(end 123.808744 -222.127572)
		(width 0.1143)
		(layer "In4.Cu")
		(net "GMI_CPU1_G2_CPU0_G0_TX_DP<12>")
	)
	(segment
		(start 347.69171 -226.343718)
		(end 347.692472 -226.344226)
		(width 0.1143)
		(layer "In4.Cu")
		(net "GMI_CPU1_G2_CPU0_G0_TX_DP<12>")
	)
	(segment
		(start 123.805696 -226.34321)
		(end 123.806966 -226.342448)
		(width 0.1143)
		(layer "In4.Cu")
		(net "GMI_CPU1_G2_CPU0_G0_TX_DP<12>")
	)
	(segment
		(start 123.808744 -224.72142)
		(end 123.810268 -224.720404)
		(width 0.1143)
		(layer "In4.Cu")
		(net "GMI_CPU1_G2_CPU0_G0_TX_DP<12>")
	)
	(segment
		(start 155.890214 -193.728086)
		(end 155.909264 -193.535046)
		(width 0.14224)
		(layer "In4.Cu")
		(net "GMI_CPU1_G2_CPU0_G0_TX_DP<12>")
	)
	(segment
		(start 347.687138 -222.127318)
		(end 347.649038 -222.14967)
		(width 0.1143)
		(layer "In4.Cu")
		(net "GMI_CPU1_G2_CPU0_G0_TX_DP<12>")
	)
	(segment
		(start 154.494738 -194.695064)
		(end 154.687778 -194.714114)
		(width 0.14224)
		(layer "In4.Cu")
		(net "GMI_CPU1_G2_CPU0_G0_TX_DP<12>")
	)
	(segment
		(start 123.665488 -220.368622)
		(end 125.30328 -217.53068)
		(width 0.14224)
		(layer "In4.Cu")
		(net "GMI_CPU1_G2_CPU0_G0_TX_DP<12>")
	)
	(segment
		(start 347.655896 -223.765618)
		(end 347.649038 -223.769682)
		(width 0.1143)
		(layer "In4.Cu")
		(net "GMI_CPU1_G2_CPU0_G0_TX_DP<12>")
	)
	(segment
		(start 346.311728 -229.397052)
		(end 346.239084 -229.43947)
		(width 0.1143)
		(layer "In4.Cu")
		(net "GMI_CPU1_G2_CPU0_G0_TX_DP<12>")
	)
	(segment
		(start 347.687138 -226.341178)
		(end 347.688154 -226.341686)
		(width 0.1143)
		(layer "In4.Cu")
		(net "GMI_CPU1_G2_CPU0_G0_TX_DP<12>")
	)
	(segment
		(start 123.807728 -224.721928)
		(end 123.808744 -224.72142)
		(width 0.1143)
		(layer "In4.Cu")
		(net "GMI_CPU1_G2_CPU0_G0_TX_DP<12>")
	)
	(segment
		(start 347.690186 -226.985576)
		(end 347.688916 -226.986338)
		(width 0.1143)
		(layer "In4.Cu")
		(net "GMI_CPU1_G2_CPU0_G0_TX_DP<12>")
	)
	(segment
		(start 155.909264 -193.5353)
		(end 156.692092 -192.893442)
		(width 0.14224)
		(layer "In4.Cu")
		(net "GMI_CPU1_G2_CPU0_G0_TX_DP<12>")
	)
	(segment
		(start 125.87478 -229.90429)
		(end 125.576838 -229.90429)
		(width 0.1143)
		(layer "In4.Cu")
		(net "GMI_CPU1_G2_CPU0_G0_TX_DP<12>")
	)
	(segment
		(start 123.810268 -226.340416)
		(end 123.846844 -226.31908)
		(width 0.1143)
		(layer "In4.Cu")
		(net "GMI_CPU1_G2_CPU0_G0_TX_DP<12>")
	)
	(segment
		(start 123.805696 -225.365818)
		(end 123.775978 -225.3488)
		(width 0.1143)
		(layer "In4.Cu")
		(net "GMI_CPU1_G2_CPU0_G0_TX_DP<12>")
	)
	(segment
		(start 123.805696 -226.98583)
		(end 123.775978 -226.968812)
		(width 0.1143)
		(layer "In4.Cu")
		(net "GMI_CPU1_G2_CPU0_G0_TX_DP<12>")
	)
	(segment
		(start 123.619768 -221.248732)
		(end 123.665488 -221.203012)
		(width 0.1143)
		(layer "In4.Cu")
		(net "GMI_CPU1_G2_CPU0_G0_TX_DP<12>")
	)
	(segment
		(start 152.750012 -196.125846)
		(end 152.943052 -196.144896)
		(width 0.14224)
		(layer "In4.Cu")
		(net "GMI_CPU1_G2_CPU0_G0_TX_DP<12>")
	)
	(segment
		(start 152.943052 -196.144896)
		(end 153.273252 -195.873878)
		(width 0.14224)
		(layer "In4.Cu")
		(net "GMI_CPU1_G2_CPU0_G0_TX_DP<12>")
	)
	(segment
		(start 318.637412 -195.032376)
		(end 318.759586 -195.154042)
		(width 0.14224)
		(layer "In4.Cu")
		(net "GMI_CPU1_G2_CPU0_G0_TX_DP<12>")
	)
	(segment
		(start 154.164792 -194.965574)
		(end 154.494738 -194.695064)
		(width 0.14224)
		(layer "In4.Cu")
		(net "GMI_CPU1_G2_CPU0_G0_TX_DP<12>")
	)
	(segment
		(start 123.665488 -221.203012)
		(end 123.665488 -221.174564)
		(width 0.1143)
		(layer "In4.Cu")
		(net "GMI_CPU1_G2_CPU0_G0_TX_DP<12>")
	)
	(segment
		(start 124.290582 -227.817172)
		(end 124.258832 -227.798376)
		(width 0.1143)
		(layer "In4.Cu")
		(net "GMI_CPU1_G2_CPU0_G0_TX_DP<12>")
	)
	(segment
		(start 346.738702 -228.612446)
		(end 346.71 -228.628956)
		(width 0.1143)
		(layer "In4.Cu")
		(net "GMI_CPU1_G2_CPU0_G0_TX_DP<12>")
	)
	(segment
		(start 347.687138 -223.101154)
		(end 347.688154 -223.101662)
		(width 0.1143)
		(layer "In4.Cu")
		(net "GMI_CPU1_G2_CPU0_G0_TX_DP<12>")
	)
	(segment
		(start 156.692092 -192.893442)
		(end 156.692092 -192.893188)
		(width 0.14224)
		(layer "In4.Cu")
		(net "GMI_CPU1_G2_CPU0_G0_TX_DP<12>")
	)
	(segment
		(start 155.366974 -193.9798)
		(end 155.560014 -193.99885)
		(width 0.14224)
		(layer "In4.Cu")
		(net "GMI_CPU1_G2_CPU0_G0_TX_DP<12>")
	)
	(segment
		(start 347.688916 -223.746314)
		(end 347.688154 -223.746822)
		(width 0.1143)
		(layer "In4.Cu")
		(net "GMI_CPU1_G2_CPU0_G0_TX_DP<12>")
	)
	(segment
		(start 123.839224 -225.385376)
		(end 123.807728 -225.367088)
		(width 0.1143)
		(layer "In4.Cu")
		(net "GMI_CPU1_G2_CPU0_G0_TX_DP<12>")
	)
	(segment
		(start 123.775978 -224.740216)
		(end 123.805696 -224.723198)
		(width 0.1143)
		(layer "In4.Cu")
		(net "GMI_CPU1_G2_CPU0_G0_TX_DP<12>")
	)
	(segment
		(start 347.23705 -227.798122)
		(end 347.2053 -227.816918)
		(width 0.1143)
		(layer "In4.Cu")
		(net "GMI_CPU1_G2_CPU0_G0_TX_DP<12>")
	)
	(segment
		(start 347.692472 -222.12427)
		(end 347.69171 -222.124778)
		(width 0.1143)
		(layer "In4.Cu")
		(net "GMI_CPU1_G2_CPU0_G0_TX_DP<12>")
	)
	(segment
		(start 124.559822 -228.284278)
		(end 124.559822 -228.283008)
		(width 0.1143)
		(layer "In4.Cu")
		(net "GMI_CPU1_G2_CPU0_G0_TX_DP<12>")
	)
	(segment
		(start 347.688916 -226.986338)
		(end 347.688154 -226.986846)
		(width 0.1143)
		(layer "In4.Cu")
		(net "GMI_CPU1_G2_CPU0_G0_TX_DP<12>")
	)
	(segment
		(start 347.685614 -223.100138)
		(end 347.687138 -223.101154)
		(width 0.1143)
		(layer "In4.Cu")
		(net "GMI_CPU1_G2_CPU0_G0_TX_DP<12>")
	)
	(segment
		(start 157.757368 -192.197228)
		(end 158.087568 -191.926464)
		(width 0.14224)
		(layer "In4.Cu")
		(net "GMI_CPU1_G2_CPU0_G0_TX_DP<12>")
	)
	(segment
		(start 250.68657 -190.234824)
		(end 262.819896 -188.095128)
		(width 0.14224)
		(layer "In4.Cu")
		(net "GMI_CPU1_G2_CPU0_G0_TX_DP<12>")
	)
	(segment
		(start 347.719904 -222.108522)
		(end 347.698568 -222.120968)
		(width 0.1143)
		(layer "In4.Cu")
		(net "GMI_CPU1_G2_CPU0_G0_TX_DP<12>")
	)
	(segment
		(start 347.693996 -224.724976)
		(end 347.694758 -224.725484)
		(width 0.1143)
		(layer "In4.Cu")
		(net "GMI_CPU1_G2_CPU0_G0_TX_DP<12>")
	)
	(segment
		(start 347.661738 -227.002086)
		(end 347.660722 -227.002594)
		(width 0.1143)
		(layer "In4.Cu")
		(net "GMI_CPU1_G2_CPU0_G0_TX_DP<12>")
	)
	(segment
		(start 239.26927 -198.22922)
		(end 250.68657 -190.234824)
		(width 0.14224)
		(layer "In4.Cu")
		(net "GMI_CPU1_G2_CPU0_G0_TX_DP<12>")
	)
	(segment
		(start 157.215332 -192.641728)
		(end 157.234382 -192.448688)
		(width 0.14224)
		(layer "In4.Cu")
		(net "GMI_CPU1_G2_CPU0_G0_TX_DP<12>")
	)
	(segment
		(start 347.693996 -226.344988)
		(end 347.694758 -226.345496)
		(width 0.1143)
		(layer "In4.Cu")
		(net "GMI_CPU1_G2_CPU0_G0_TX_DP<12>")
	)
	(segment
		(start 347.693996 -222.123508)
		(end 347.692472 -222.12427)
		(width 0.1143)
		(layer "In4.Cu")
		(net "GMI_CPU1_G2_CPU0_G0_TX_DP<12>")
	)
	(segment
		(start 346.001848 -229.821232)
		(end 345.919044 -229.904036)
		(width 0.1143)
		(layer "In4.Cu")
		(net "GMI_CPU1_G2_CPU0_G0_TX_DP<12>")
	)
	(segment
		(start 123.806966 -226.342448)
		(end 123.807728 -226.34194)
		(width 0.1143)
		(layer "In4.Cu")
		(net "GMI_CPU1_G2_CPU0_G0_TX_DP<12>")
	)
	(segment
		(start 347.876114 -221.248478)
		(end 347.876114 -221.545658)
		(width 0.1143)
		(layer "In4.Cu")
		(net "GMI_CPU1_G2_CPU0_G0_TX_DP<12>")
	)
	(segment
		(start 158.959804 -191.2112)
		(end 158.978854 -191.01816)
		(width 0.14224)
		(layer "In4.Cu")
		(net "GMI_CPU1_G2_CPU0_G0_TX_DP<12>")
	)
	(segment
		(start 347.688916 -225.366326)
		(end 347.688154 -225.366834)
		(width 0.1143)
		(layer "In4.Cu")
		(net "GMI_CPU1_G2_CPU0_G0_TX_DP<12>")
	)
	(segment
		(start 157.564328 -192.178178)
		(end 157.757368 -192.197228)
		(width 0.14224)
		(layer "In4.Cu")
		(net "GMI_CPU1_G2_CPU0_G0_TX_DP<12>")
	)
	(segment
		(start 347.688916 -224.722182)
		(end 347.69171 -224.723706)
		(width 0.1143)
		(layer "In4.Cu")
		(net "GMI_CPU1_G2_CPU0_G0_TX_DP<12>")
	)
	(segment
		(start 123.806966 -223.102424)
		(end 123.807728 -223.101916)
		(width 0.1143)
		(layer "In4.Cu")
		(net "GMI_CPU1_G2_CPU0_G0_TX_DP<12>")
	)
	(segment
		(start 309.330852 -188.472826)
		(end 318.637412 -195.032376)
		(width 0.14224)
		(layer "In4.Cu")
		(net "GMI_CPU1_G2_CPU0_G0_TX_DP<12>")
	)
	(segment
		(start 123.808744 -223.101408)
		(end 123.810268 -223.100392)
		(width 0.1143)
		(layer "In4.Cu")
		(net "GMI_CPU1_G2_CPU0_G0_TX_DP<12>")
	)
	(segment
		(start 123.619768 -221.545912)
		(end 123.619768 -221.248732)
		(width 0.1143)
		(layer "In4.Cu")
		(net "GMI_CPU1_G2_CPU0_G0_TX_DP<12>")
	)
	(segment
		(start 125.217682 -229.416864)
		(end 125.184154 -229.397306)
		(width 0.1143)
		(layer "In4.Cu")
		(net "GMI_CPU1_G2_CPU0_G0_TX_DP<12>")
	)
	(segment
		(start 347.694758 -224.725484)
		(end 347.696028 -224.726246)
		(width 0.1143)
		(layer "In4.Cu")
		(net "GMI_CPU1_G2_CPU0_G0_TX_DP<12>")
	)
	(segment
		(start 123.806966 -225.36658)
		(end 123.805696 -225.365818)
		(width 0.1143)
		(layer "In4.Cu")
		(net "GMI_CPU1_G2_CPU0_G0_TX_DP<12>")
	)
	(segment
		(start 345.919044 -229.904036)
		(end 345.621102 -229.904036)
		(width 0.1143)
		(layer "In4.Cu")
		(net "GMI_CPU1_G2_CPU0_G0_TX_DP<12>")
	)
	(segment
		(start 347.830394 -221.17431)
		(end 347.830394 -221.202758)
		(width 0.1143)
		(layer "In4.Cu")
		(net "GMI_CPU1_G2_CPU0_G0_TX_DP<12>")
	)
	(segment
		(start 158.106618 -191.733424)
		(end 158.436564 -191.462914)
		(width 0.14224)
		(layer "In4.Cu")
		(net "GMI_CPU1_G2_CPU0_G0_TX_DP<12>")
	)
	(segment
		(start 159.851344 -190.302896)
		(end 161.952432 -188.580014)
		(width 0.14224)
		(layer "In4.Cu")
		(net "GMI_CPU1_G2_CPU0_G0_TX_DP<12>")
	)
	(segment
		(start 123.806966 -224.722436)
		(end 123.807728 -224.721928)
		(width 0.1143)
		(layer "In4.Cu")
		(net "GMI_CPU1_G2_CPU0_G0_TX_DP<12>")
	)
	(segment
		(start 347.393006 -227.466906)
		(end 347.393006 -227.494084)
		(width 0.1143)
		(layer "In4.Cu")
		(net "GMI_CPU1_G2_CPU0_G0_TX_DP<12>")
	)
	(segment
		(start 123.807728 -226.9871)
		(end 123.806966 -226.986592)
		(width 0.1143)
		(layer "In4.Cu")
		(net "GMI_CPU1_G2_CPU0_G0_TX_DP<12>")
	)
	(segment
		(start 347.660722 -227.002594)
		(end 347.65742 -227.004626)
		(width 0.1143)
		(layer "In4.Cu")
		(net "GMI_CPU1_G2_CPU0_G0_TX_DP<12>")
	)
	(segment
		(start 347.656658 -225.385122)
		(end 347.655896 -225.38563)
		(width 0.1143)
		(layer "In4.Cu")
		(net "GMI_CPU1_G2_CPU0_G0_TX_DP<12>")
	)
	(segment
		(start 158.087568 -191.926464)
		(end 158.106618 -191.733424)
		(width 0.14224)
		(layer "In4.Cu")
		(net "GMI_CPU1_G2_CPU0_G0_TX_DP<12>")
	)
	(segment
		(start 154.145742 -195.158614)
		(end 154.164792 -194.965574)
		(width 0.14224)
		(layer "In4.Cu")
		(net "GMI_CPU1_G2_CPU0_G0_TX_DP<12>")
	)
	(segment
		(start 156.885132 -192.912492)
		(end 157.215332 -192.641728)
		(width 0.14224)
		(layer "In4.Cu")
		(net "GMI_CPU1_G2_CPU0_G0_TX_DP<12>")
	)
	(segment
		(start 123.83516 -227.002848)
		(end 123.834144 -227.00234)
		(width 0.1143)
		(layer "In4.Cu")
		(net "GMI_CPU1_G2_CPU0_G0_TX_DP<12>")
	)
	(segment
		(start 123.846844 -223.769936)
		(end 123.839986 -223.765872)
		(width 0.1143)
		(layer "In4.Cu")
		(net "GMI_CPU1_G2_CPU0_G0_TX_DP<12>")
	)
	(segment
		(start 153.622502 -195.410328)
		(end 153.815542 -195.429378)
		(width 0.14224)
		(layer "In4.Cu")
		(net "GMI_CPU1_G2_CPU0_G0_TX_DP<12>")
	)
	(segment
		(start 124.102876 -227.494338)
		(end 124.102876 -227.46716)
		(width 0.1143)
		(layer "In4.Cu")
		(net "GMI_CPU1_G2_CPU0_G0_TX_DP<12>")
	)
	(segment
		(start 347.692472 -226.344226)
		(end 347.693996 -226.344988)
		(width 0.1143)
		(layer "In4.Cu")
		(net "GMI_CPU1_G2_CPU0_G0_TX_DP<12>")
	)
	(segment
		(start 123.804172 -222.125032)
		(end 123.80341 -222.124524)
		(width 0.1143)
		(layer "In4.Cu")
		(net "GMI_CPU1_G2_CPU0_G0_TX_DP<12>")
	)
	(segment
		(start 347.719904 -225.348546)
		(end 347.690186 -225.365564)
		(width 0.1143)
		(layer "In4.Cu")
		(net "GMI_CPU1_G2_CPU0_G0_TX_DP<12>")
	)
	(segment
		(start 262.819896 -188.095128)
		(end 303.70526 -188.472826)
		(width 0.14224)
		(layer "In4.Cu")
		(net "GMI_CPU1_G2_CPU0_G0_TX_DP<12>")
	)
	(segment
		(start 153.273252 -195.873878)
		(end 153.292556 -195.680838)
		(width 0.14224)
		(layer "In4.Cu")
		(net "GMI_CPU1_G2_CPU0_G0_TX_DP<12>")
	)
	(segment
		(start 123.807728 -225.367088)
		(end 123.806966 -225.36658)
		(width 0.1143)
		(layer "In4.Cu")
		(net "GMI_CPU1_G2_CPU0_G0_TX_DP<12>")
	)
	(segment
		(start 123.806966 -223.746568)
		(end 123.805696 -223.745806)
		(width 0.1143)
		(layer "In4.Cu")
		(net "GMI_CPU1_G2_CPU0_G0_TX_DP<12>")
	)
	(segment
		(start 346.414598 -217.830146)
		(end 347.830394 -220.215206)
		(width 0.14224)
		(layer "In4.Cu")
		(net "GMI_CPU1_G2_CPU0_G0_TX_DP<12>")
	)
	(arc
		(start 347.719904 -223.11995)
		(mid 347.875832 -223.424242)
		(end 347.719904 -223.728534)
		(width 0.1143)
		(layer "In4.Cu")
		(net "GMI_CPU1_G2_CPU0_G0_TX_DP<12>")
	)
	(arc
		(start 347.649038 -222.14967)
		(mid 347.405711 -222.614236)
		(end 347.649038 -223.078802)
		(width 0.1143)
		(layer "In4.Cu")
		(net "GMI_CPU1_G2_CPU0_G0_TX_DP<12>")
	)
	(arc
		(start 346.71 -228.628956)
		(mid 346.530655 -228.831559)
		(end 346.465906 -229.094284)
		(width 0.1143)
		(layer "In4.Cu")
		(net "GMI_CPU1_G2_CPU0_G0_TX_DP<12>")
	)
	(arc
		(start 124.258832 -227.798376)
		(mid 124.144156 -227.665185)
		(end 124.102876 -227.494338)
		(width 0.1143)
		(layer "In4.Cu")
		(net "GMI_CPU1_G2_CPU0_G0_TX_DP<12>")
	)
	(arc
		(start 125.184154 -229.397306)
		(mid 125.070747 -229.264417)
		(end 125.029976 -229.094538)
		(width 0.1143)
		(layer "In4.Cu")
		(net "GMI_CPU1_G2_CPU0_G0_TX_DP<12>")
	)
	(arc
		(start 347.649038 -225.389694)
		(mid 347.405711 -225.85426)
		(end 347.649038 -226.318826)
		(width 0.1143)
		(layer "In4.Cu")
		(net "GMI_CPU1_G2_CPU0_G0_TX_DP<12>")
	)
	(arc
		(start 347.719904 -224.739962)
		(mid 347.875832 -225.044254)
		(end 347.719904 -225.348546)
		(width 0.1143)
		(layer "In4.Cu")
		(net "GMI_CPU1_G2_CPU0_G0_TX_DP<12>")
	)
	(arc
		(start 347.2053 -227.816918)
		(mid 347.0088 -228.014083)
		(end 346.93606 -228.282754)
		(width 0.1143)
		(layer "In4.Cu")
		(net "GMI_CPU1_G2_CPU0_G0_TX_DP<12>")
	)
	(arc
		(start 123.775978 -225.3488)
		(mid 123.62005 -225.044508)
		(end 123.775978 -224.740216)
		(width 0.1143)
		(layer "In4.Cu")
		(net "GMI_CPU1_G2_CPU0_G0_TX_DP<12>")
	)
	(arc
		(start 124.559822 -228.283008)
		(mid 124.487015 -228.014376)
		(end 124.290582 -227.817172)
		(width 0.1143)
		(layer "In4.Cu")
		(net "GMI_CPU1_G2_CPU0_G0_TX_DP<12>")
	)
	(arc
		(start 124.75718 -228.6127)
		(mid 124.74094 -228.603575)
		(end 124.725176 -228.59365)
		(width 0.1143)
		(layer "In4.Cu")
		(net "GMI_CPU1_G2_CPU0_G0_TX_DP<12>")
	)
	(arc
		(start 123.846844 -223.079056)
		(mid 124.090171 -222.61449)
		(end 123.846844 -222.149924)
		(width 0.1143)
		(layer "In4.Cu")
		(net "GMI_CPU1_G2_CPU0_G0_TX_DP<12>")
	)
	(arc
		(start 123.775978 -226.968812)
		(mid 123.62005 -226.66452)
		(end 123.775978 -226.360228)
		(width 0.1143)
		(layer "In4.Cu")
		(net "GMI_CPU1_G2_CPU0_G0_TX_DP<12>")
	)
	(arc
		(start 347.719904 -226.359974)
		(mid 347.875832 -226.664266)
		(end 347.719904 -226.968558)
		(width 0.1143)
		(layer "In4.Cu")
		(net "GMI_CPU1_G2_CPU0_G0_TX_DP<12>")
	)
	(arc
		(start 123.846844 -226.31908)
		(mid 124.090171 -225.854514)
		(end 123.846844 -225.389948)
		(width 0.1143)
		(layer "In4.Cu")
		(net "GMI_CPU1_G2_CPU0_G0_TX_DP<12>")
	)
	(arc
		(start 124.102876 -227.46716)
		(mid 124.032546 -227.20169)
		(end 123.839986 -227.005896)
		(width 0.1143)
		(layer "In4.Cu")
		(net "GMI_CPU1_G2_CPU0_G0_TX_DP<12>")
	)
	(arc
		(start 346.93606 -228.284024)
		(mid 346.892203 -228.459474)
		(end 346.770706 -228.593396)
		(width 0.1143)
		(layer "In4.Cu")
		(net "GMI_CPU1_G2_CPU0_G0_TX_DP<12>")
	)
	(arc
		(start 347.393006 -227.494084)
		(mid 347.351747 -227.664941)
		(end 347.23705 -227.798122)
		(width 0.1143)
		(layer "In4.Cu")
		(net "GMI_CPU1_G2_CPU0_G0_TX_DP<12>")
	)
	(arc
		(start 347.655896 -227.005642)
		(mid 347.463372 -227.201456)
		(end 347.393006 -227.466906)
		(width 0.1143)
		(layer "In4.Cu")
		(net "GMI_CPU1_G2_CPU0_G0_TX_DP<12>")
	)
	(arc
		(start 125.494034 -229.821486)
		(mid 125.414955 -229.606041)
		(end 125.256798 -229.439724)
		(width 0.1143)
		(layer "In4.Cu")
		(net "GMI_CPU1_G2_CPU0_G0_TX_DP<12>")
	)
	(arc
		(start 346.465906 -229.094284)
		(mid 346.425144 -229.264168)
		(end 346.311728 -229.397052)
		(width 0.1143)
		(layer "In4.Cu")
		(net "GMI_CPU1_G2_CPU0_G0_TX_DP<12>")
	)
	(arc
		(start 347.87586 -221.80423)
		(mid 347.834605 -221.975201)
		(end 347.719904 -222.108522)
		(width 0.1143)
		(layer "In4.Cu")
		(net "GMI_CPU1_G2_CPU0_G0_TX_DP<12>")
	)
	(arc
		(start 123.775978 -223.728788)
		(mid 123.62005 -223.424496)
		(end 123.775978 -223.120204)
		(width 0.1143)
		(layer "In4.Cu")
		(net "GMI_CPU1_G2_CPU0_G0_TX_DP<12>")
	)
	(arc
		(start 125.029976 -229.094538)
		(mid 124.965254 -228.831799)
		(end 124.785882 -228.62921)
		(width 0.1143)
		(layer "In4.Cu")
		(net "GMI_CPU1_G2_CPU0_G0_TX_DP<12>")
	)
	(arc
		(start 347.649038 -223.769682)
		(mid 347.405711 -224.234248)
		(end 347.649038 -224.698814)
		(width 0.1143)
		(layer "In4.Cu")
		(net "GMI_CPU1_G2_CPU0_G0_TX_DP<12>")
	)
	(arc
		(start 346.239084 -229.43947)
		(mid 346.087097 -229.595978)
		(end 346.005658 -229.798372)
		(width 0.1143)
		(layer "In4.Cu")
		(net "GMI_CPU1_G2_CPU0_G0_TX_DP<12>")
	)
	(arc
		(start 124.725176 -228.59365)
		(mid 124.603774 -228.459677)
		(end 124.559822 -228.284278)
		(width 0.1143)
		(layer "In4.Cu")
		(net "GMI_CPU1_G2_CPU0_G0_TX_DP<12>")
	)
	(arc
		(start 123.846844 -224.699068)
		(mid 124.090171 -224.234502)
		(end 123.846844 -223.769936)
		(width 0.1143)
		(layer "In4.Cu")
		(net "GMI_CPU1_G2_CPU0_G0_TX_DP<12>")
	)
	(arc
		(start 346.005658 -229.798372)
		(mid 346.003635 -229.809782)
		(end 346.001848 -229.821232)
		(width 0.1143)
		(layer "In4.Cu")
		(net "GMI_CPU1_G2_CPU0_G0_TX_DP<12>")
	)
	(arc
		(start 346.770706 -228.593396)
		(mid 346.754943 -228.603323)
		(end 346.738702 -228.612446)
		(width 0.1143)
		(layer "In4.Cu")
		(net "GMI_CPU1_G2_CPU0_G0_TX_DP<12>")
	)
	(arc
		(start 123.775978 -222.108776)
		(mid 123.661302 -221.975442)
		(end 123.620022 -221.804484)
		(width 0.1143)
		(layer "In4.Cu")
		(net "GMI_CPU1_G2_CPU0_G0_TX_DP<12>")
	)
	(segment
		(start 348.907862 -228.550216)
		(end 348.44101 -228.284278)
		(width 0.12954)
		(layer "F.Cu")
		(net "GMI_CPU1_G2_CPU0_G0_TX_DP<11>")
	)
	(segment
		(start 122.587766 -228.55047)
		(end 123.054618 -228.284532)
		(width 0.12954)
		(layer "F.Cu")
		(net "GMI_CPU1_G2_CPU0_G0_TX_DP<11>")
	)
	(segment
		(start 348.821756 -228.201474)
		(end 348.738952 -228.284278)
		(width 0.1143)
		(layer "In4.Cu")
		(net "GMI_CPU1_G2_CPU0_G0_TX_DP<11>")
	)
	(segment
		(start 349.599758 -223.72828)
		(end 349.583756 -223.737424)
		(width 0.1143)
		(layer "In4.Cu")
		(net "GMI_CPU1_G2_CPU0_G0_TX_DP<11>")
	)
	(segment
		(start 306.652168 -184.474866)
		(end 308.421786 -185.28538)
		(width 0.14224)
		(layer "In4.Cu")
		(net "GMI_CPU1_G2_CPU0_G0_TX_DP<11>")
	)
	(segment
		(start 349.599758 -223.728534)
		(end 349.599758 -223.72828)
		(width 0.1143)
		(layer "In4.Cu")
		(net "GMI_CPU1_G2_CPU0_G0_TX_DP<11>")
	)
	(segment
		(start 121.994676 -223.789748)
		(end 121.96699 -223.769682)
		(width 0.1143)
		(layer "In4.Cu")
		(net "GMI_CPU1_G2_CPU0_G0_TX_DP<11>")
	)
	(segment
		(start 349.568008 -226.341686)
		(end 349.599758 -226.359974)
		(width 0.1143)
		(layer "In4.Cu")
		(net "GMI_CPU1_G2_CPU0_G0_TX_DP<11>")
	)
	(segment
		(start 121.927874 -225.367088)
		(end 121.896124 -225.3488)
		(width 0.1143)
		(layer "In4.Cu")
		(net "GMI_CPU1_G2_CPU0_G0_TX_DP<11>")
	)
	(segment
		(start 121.896124 -223.120204)
		(end 121.927874 -223.101916)
		(width 0.1143)
		(layer "In4.Cu")
		(net "GMI_CPU1_G2_CPU0_G0_TX_DP<11>")
	)
	(segment
		(start 153.647648 -192.78473)
		(end 153.666698 -192.59169)
		(width 0.14224)
		(layer "In4.Cu")
		(net "GMI_CPU1_G2_CPU0_G0_TX_DP<11>")
	)
	(segment
		(start 349.531686 -223.08058)
		(end 349.568008 -223.101662)
		(width 0.1143)
		(layer "In4.Cu")
		(net "GMI_CPU1_G2_CPU0_G0_TX_DP<11>")
	)
	(segment
		(start 154.86888 -191.60617)
		(end 155.06192 -191.625474)
		(width 0.14224)
		(layer "In4.Cu")
		(net "GMI_CPU1_G2_CPU0_G0_TX_DP<11>")
	)
	(segment
		(start 349.098108 -227.796852)
		(end 349.058992 -227.819712)
		(width 0.1143)
		(layer "In4.Cu")
		(net "GMI_CPU1_G2_CPU0_G0_TX_DP<11>")
	)
	(segment
		(start 121.96699 -223.769682)
		(end 121.928128 -223.74733)
		(width 0.1143)
		(layer "In4.Cu")
		(net "GMI_CPU1_G2_CPU0_G0_TX_DP<11>")
	)
	(segment
		(start 121.76125 -219.878148)
		(end 123.974098 -216.074498)
		(width 0.14224)
		(layer "In4.Cu")
		(net "GMI_CPU1_G2_CPU0_G0_TX_DP<11>")
	)
	(segment
		(start 121.964196 -225.38817)
		(end 121.927874 -225.367088)
		(width 0.1143)
		(layer "In4.Cu")
		(net "GMI_CPU1_G2_CPU0_G0_TX_DP<11>")
	)
	(segment
		(start 153.996644 -192.32118)
		(end 154.189684 -192.340484)
		(width 0.14224)
		(layer "In4.Cu")
		(net "GMI_CPU1_G2_CPU0_G0_TX_DP<11>")
	)
	(segment
		(start 121.740168 -221.371922)
		(end 121.71553 -221.347284)
		(width 0.1143)
		(layer "In4.Cu")
		(net "GMI_CPU1_G2_CPU0_G0_TX_DP<11>")
	)
	(segment
		(start 349.531686 -226.320604)
		(end 349.568008 -226.341686)
		(width 0.1143)
		(layer "In4.Cu")
		(net "GMI_CPU1_G2_CPU0_G0_TX_DP<11>")
	)
	(segment
		(start 122.394218 -227.795328)
		(end 122.39371 -227.795074)
		(width 0.1143)
		(layer "In4.Cu")
		(net "GMI_CPU1_G2_CPU0_G0_TX_DP<11>")
	)
	(segment
		(start 349.567754 -223.747076)
		(end 349.528892 -223.769428)
		(width 0.1143)
		(layer "In4.Cu")
		(net "GMI_CPU1_G2_CPU0_G0_TX_DP<11>")
	)
	(segment
		(start 349.599758 -222.108522)
		(end 349.568008 -222.12681)
		(width 0.1143)
		(layer "In4.Cu")
		(net "GMI_CPU1_G2_CPU0_G0_TX_DP<11>")
	)
	(segment
		(start 349.273114 -227.483924)
		(end 349.273114 -227.49637)
		(width 0.1143)
		(layer "In4.Cu")
		(net "GMI_CPU1_G2_CPU0_G0_TX_DP<11>")
	)
	(segment
		(start 152.775412 -193.49974)
		(end 152.794462 -193.3067)
		(width 0.14224)
		(layer "In4.Cu")
		(net "GMI_CPU1_G2_CPU0_G0_TX_DP<11>")
	)
	(segment
		(start 156.259784 -190.465964)
		(end 156.583888 -190.20028)
		(width 0.14224)
		(layer "In4.Cu")
		(net "GMI_CPU1_G2_CPU0_G0_TX_DP<11>")
	)
	(segment
		(start 155.917392 -190.91402)
		(end 156.24175 -190.648082)
		(width 0.14224)
		(layer "In4.Cu")
		(net "GMI_CPU1_G2_CPU0_G0_TX_DP<11>")
	)
	(segment
		(start 121.927874 -226.34194)
		(end 121.964196 -226.320858)
		(width 0.1143)
		(layer "In4.Cu")
		(net "GMI_CPU1_G2_CPU0_G0_TX_DP<11>")
	)
	(segment
		(start 162.591242 -185.275474)
		(end 167.02278 -183.691022)
		(width 0.14224)
		(layer "In4.Cu")
		(net "GMI_CPU1_G2_CPU0_G0_TX_DP<11>")
	)
	(segment
		(start 154.189684 -192.340484)
		(end 154.519884 -192.06972)
		(width 0.14224)
		(layer "In4.Cu")
		(net "GMI_CPU1_G2_CPU0_G0_TX_DP<11>")
	)
	(segment
		(start 152.794462 -193.3067)
		(end 153.124408 -193.03619)
		(width 0.14224)
		(layer "In4.Cu")
		(net "GMI_CPU1_G2_CPU0_G0_TX_DP<11>")
	)
	(segment
		(start 154.538934 -191.87668)
		(end 154.86888 -191.60617)
		(width 0.14224)
		(layer "In4.Cu")
		(net "GMI_CPU1_G2_CPU0_G0_TX_DP<11>")
	)
	(segment
		(start 153.317448 -193.055494)
		(end 153.647648 -192.78473)
		(width 0.14224)
		(layer "In4.Cu")
		(net "GMI_CPU1_G2_CPU0_G0_TX_DP<11>")
	)
	(segment
		(start 349.568008 -223.101662)
		(end 349.599758 -223.11995)
		(width 0.1143)
		(layer "In4.Cu")
		(net "GMI_CPU1_G2_CPU0_G0_TX_DP<11>")
	)
	(segment
		(start 145.125186 -198.731886)
		(end 145.905728 -198.495158)
		(width 0.14224)
		(layer "In4.Cu")
		(net "GMI_CPU1_G2_CPU0_G0_TX_DP<11>")
	)
	(segment
		(start 157.957012 -189.074552)
		(end 162.591242 -185.275474)
		(width 0.14224)
		(layer "In4.Cu")
		(net "GMI_CPU1_G2_CPU0_G0_TX_DP<11>")
	)
	(segment
		(start 121.964196 -222.148146)
		(end 121.927874 -222.127064)
		(width 0.1143)
		(layer "In4.Cu")
		(net "GMI_CPU1_G2_CPU0_G0_TX_DP<11>")
	)
	(segment
		(start 156.24175 -190.648082)
		(end 156.259784 -190.465964)
		(width 0.14224)
		(layer "In4.Cu")
		(net "GMI_CPU1_G2_CPU0_G0_TX_DP<11>")
	)
	(segment
		(start 302.888904 -184.474866)
		(end 306.652168 -184.474866)
		(width 0.14224)
		(layer "In4.Cu")
		(net "GMI_CPU1_G2_CPU0_G0_TX_DP<11>")
	)
	(segment
		(start 152.445212 -193.770504)
		(end 152.775412 -193.49974)
		(width 0.14224)
		(layer "In4.Cu")
		(net "GMI_CPU1_G2_CPU0_G0_TX_DP<11>")
	)
	(segment
		(start 157.938978 -189.25667)
		(end 157.957012 -189.074552)
		(width 0.14224)
		(layer "In4.Cu")
		(net "GMI_CPU1_G2_CPU0_G0_TX_DP<11>")
	)
	(segment
		(start 151.922226 -194.02171)
		(end 152.252172 -193.7512)
		(width 0.14224)
		(layer "In4.Cu")
		(net "GMI_CPU1_G2_CPU0_G0_TX_DP<11>")
	)
	(segment
		(start 349.501206 -224.679002)
		(end 349.528892 -224.699068)
		(width 0.1143)
		(layer "In4.Cu")
		(net "GMI_CPU1_G2_CPU0_G0_TX_DP<11>")
	)
	(segment
		(start 154.519884 -192.06972)
		(end 154.538934 -191.87668)
		(width 0.14224)
		(layer "In4.Cu")
		(net "GMI_CPU1_G2_CPU0_G0_TX_DP<11>")
	)
	(segment
		(start 145.905982 -198.495158)
		(end 146.793712 -198.226172)
		(width 0.14224)
		(layer "In4.Cu")
		(net "GMI_CPU1_G2_CPU0_G0_TX_DP<11>")
	)
	(segment
		(start 156.766006 -190.218568)
		(end 157.090364 -189.952376)
		(width 0.14224)
		(layer "In4.Cu")
		(net "GMI_CPU1_G2_CPU0_G0_TX_DP<11>")
	)
	(segment
		(start 349.780352 -221.34703)
		(end 349.755714 -221.371668)
		(width 0.1143)
		(layer "In4.Cu")
		(net "GMI_CPU1_G2_CPU0_G0_TX_DP<11>")
	)
	(segment
		(start 151.903176 -194.21475)
		(end 151.922226 -194.02171)
		(width 0.14224)
		(layer "In4.Cu")
		(net "GMI_CPU1_G2_CPU0_G0_TX_DP<11>")
	)
	(segment
		(start 121.896124 -226.360228)
		(end 121.927874 -226.34194)
		(width 0.1143)
		(layer "In4.Cu")
		(net "GMI_CPU1_G2_CPU0_G0_TX_DP<11>")
	)
	(segment
		(start 155.41117 -191.16167)
		(end 155.735274 -190.895986)
		(width 0.14224)
		(layer "In4.Cu")
		(net "GMI_CPU1_G2_CPU0_G0_TX_DP<11>")
	)
	(segment
		(start 121.940066 -226.994466)
		(end 121.896124 -226.968558)
		(width 0.1143)
		(layer "In4.Cu")
		(net "GMI_CPU1_G2_CPU0_G0_TX_DP<11>")
	)
	(segment
		(start 121.896124 -224.740216)
		(end 121.96699 -224.699322)
		(width 0.1143)
		(layer "In4.Cu")
		(net "GMI_CPU1_G2_CPU0_G0_TX_DP<11>")
	)
	(segment
		(start 123.054618 -228.284532)
		(end 122.75693 -228.284532)
		(width 0.1143)
		(layer "In4.Cu")
		(net "GMI_CPU1_G2_CPU0_G0_TX_DP<11>")
	)
	(segment
		(start 155.735274 -190.895986)
		(end 155.917392 -190.91402)
		(width 0.14224)
		(layer "In4.Cu")
		(net "GMI_CPU1_G2_CPU0_G0_TX_DP<11>")
	)
	(segment
		(start 121.927874 -222.127064)
		(end 121.896124 -222.108776)
		(width 0.1143)
		(layer "In4.Cu")
		(net "GMI_CPU1_G2_CPU0_G0_TX_DP<11>")
	)
	(segment
		(start 122.222768 -227.496624)
		(end 122.222768 -227.484178)
		(width 0.1143)
		(layer "In4.Cu")
		(net "GMI_CPU1_G2_CPU0_G0_TX_DP<11>")
	)
	(segment
		(start 349.734632 -221.083124)
		(end 349.780352 -221.128844)
		(width 0.1143)
		(layer "In4.Cu")
		(net "GMI_CPU1_G2_CPU0_G0_TX_DP<11>")
	)
	(segment
		(start 121.740168 -221.804484)
		(end 121.740168 -221.371922)
		(width 0.1143)
		(layer "In4.Cu")
		(net "GMI_CPU1_G2_CPU0_G0_TX_DP<11>")
	)
	(segment
		(start 157.432502 -189.504574)
		(end 157.61462 -189.522862)
		(width 0.14224)
		(layer "In4.Cu")
		(net "GMI_CPU1_G2_CPU0_G0_TX_DP<11>")
	)
	(segment
		(start 153.124408 -193.03619)
		(end 153.317448 -193.055494)
		(width 0.14224)
		(layer "In4.Cu")
		(net "GMI_CPU1_G2_CPU0_G0_TX_DP<11>")
	)
	(segment
		(start 349.568008 -225.366834)
		(end 349.531686 -225.387916)
		(width 0.1143)
		(layer "In4.Cu")
		(net "GMI_CPU1_G2_CPU0_G0_TX_DP<11>")
	)
	(segment
		(start 349.101664 -227.795074)
		(end 349.09887 -227.796344)
		(width 0.1143)
		(layer "In4.Cu")
		(net "GMI_CPU1_G2_CPU0_G0_TX_DP<11>")
	)
	(segment
		(start 155.39212 -191.35471)
		(end 155.41117 -191.16167)
		(width 0.14224)
		(layer "In4.Cu")
		(net "GMI_CPU1_G2_CPU0_G0_TX_DP<11>")
	)
	(segment
		(start 145.905728 -198.495158)
		(end 145.905982 -198.495158)
		(width 0.14224)
		(layer "In4.Cu")
		(net "GMI_CPU1_G2_CPU0_G0_TX_DP<11>")
	)
	(segment
		(start 167.02278 -183.691022)
		(end 168.267634 -183.691022)
		(width 0.14224)
		(layer "In4.Cu")
		(net "GMI_CPU1_G2_CPU0_G0_TX_DP<11>")
	)
	(segment
		(start 349.780352 -221.128844)
		(end 349.780352 -221.34703)
		(width 0.1143)
		(layer "In4.Cu")
		(net "GMI_CPU1_G2_CPU0_G0_TX_DP<11>")
	)
	(segment
		(start 349.09887 -227.796344)
		(end 349.098108 -227.796852)
		(width 0.1143)
		(layer "In4.Cu")
		(net "GMI_CPU1_G2_CPU0_G0_TX_DP<11>")
	)
	(segment
		(start 122.397012 -227.796598)
		(end 122.394218 -227.795328)
		(width 0.1143)
		(layer "In4.Cu")
		(net "GMI_CPU1_G2_CPU0_G0_TX_DP<11>")
	)
	(segment
		(start 349.102172 -227.79482)
		(end 349.101664 -227.795074)
		(width 0.1143)
		(layer "In4.Cu")
		(net "GMI_CPU1_G2_CPU0_G0_TX_DP<11>")
	)
	(segment
		(start 157.090364 -189.952376)
		(end 157.108398 -189.770258)
		(width 0.14224)
		(layer "In4.Cu")
		(net "GMI_CPU1_G2_CPU0_G0_TX_DP<11>")
	)
	(segment
		(start 121.71553 -221.129098)
		(end 121.76125 -221.083378)
		(width 0.1143)
		(layer "In4.Cu")
		(net "GMI_CPU1_G2_CPU0_G0_TX_DP<11>")
	)
	(segment
		(start 347.735144 -216.366344)
		(end 349.734632 -219.733876)
		(width 0.14224)
		(layer "In4.Cu")
		(net "GMI_CPU1_G2_CPU0_G0_TX_DP<11>")
	)
	(segment
		(start 122.397774 -227.797106)
		(end 122.397012 -227.796598)
		(width 0.1143)
		(layer "In4.Cu")
		(net "GMI_CPU1_G2_CPU0_G0_TX_DP<11>")
	)
	(segment
		(start 157.108398 -189.770258)
		(end 157.432502 -189.504574)
		(width 0.14224)
		(layer "In4.Cu")
		(net "GMI_CPU1_G2_CPU0_G0_TX_DP<11>")
	)
	(segment
		(start 121.71553 -221.347284)
		(end 121.71553 -221.129098)
		(width 0.1143)
		(layer "In4.Cu")
		(net "GMI_CPU1_G2_CPU0_G0_TX_DP<11>")
	)
	(segment
		(start 123.974098 -216.074498)
		(end 145.125186 -198.731886)
		(width 0.14224)
		(layer "In4.Cu")
		(net "GMI_CPU1_G2_CPU0_G0_TX_DP<11>")
	)
	(segment
		(start 146.793712 -198.226172)
		(end 151.379936 -194.46621)
		(width 0.14224)
		(layer "In4.Cu")
		(net "GMI_CPU1_G2_CPU0_G0_TX_DP<11>")
	)
	(segment
		(start 121.96699 -224.699322)
		(end 121.994676 -224.679256)
		(width 0.1143)
		(layer "In4.Cu")
		(net "GMI_CPU1_G2_CPU0_G0_TX_DP<11>")
	)
	(segment
		(start 349.734632 -219.733876)
		(end 349.734632 -221.083124)
		(width 0.14224)
		(layer "In4.Cu")
		(net "GMI_CPU1_G2_CPU0_G0_TX_DP<11>")
	)
	(segment
		(start 349.528892 -223.769428)
		(end 349.501206 -223.789494)
		(width 0.1143)
		(layer "In4.Cu")
		(net "GMI_CPU1_G2_CPU0_G0_TX_DP<11>")
	)
	(segment
		(start 349.568008 -222.12681)
		(end 349.531686 -222.147892)
		(width 0.1143)
		(layer "In4.Cu")
		(net "GMI_CPU1_G2_CPU0_G0_TX_DP<11>")
	)
	(segment
		(start 156.583888 -190.20028)
		(end 156.766006 -190.218568)
		(width 0.14224)
		(layer "In4.Cu")
		(net "GMI_CPU1_G2_CPU0_G0_TX_DP<11>")
	)
	(segment
		(start 153.666698 -192.59169)
		(end 153.996644 -192.32118)
		(width 0.14224)
		(layer "In4.Cu")
		(net "GMI_CPU1_G2_CPU0_G0_TX_DP<11>")
	)
	(segment
		(start 349.583756 -223.737424)
		(end 349.567754 -223.747076)
		(width 0.1143)
		(layer "In4.Cu")
		(net "GMI_CPU1_G2_CPU0_G0_TX_DP<11>")
	)
	(segment
		(start 349.599758 -226.968304)
		(end 349.555816 -226.994212)
		(width 0.1143)
		(layer "In4.Cu")
		(net "GMI_CPU1_G2_CPU0_G0_TX_DP<11>")
	)
	(segment
		(start 155.06192 -191.625474)
		(end 155.39212 -191.35471)
		(width 0.14224)
		(layer "In4.Cu")
		(net "GMI_CPU1_G2_CPU0_G0_TX_DP<11>")
	)
	(segment
		(start 348.738952 -228.284278)
		(end 348.44101 -228.284278)
		(width 0.1143)
		(layer "In4.Cu")
		(net "GMI_CPU1_G2_CPU0_G0_TX_DP<11>")
	)
	(segment
		(start 121.76125 -221.083378)
		(end 121.76125 -221.05493)
		(width 0.1143)
		(layer "In4.Cu")
		(net "GMI_CPU1_G2_CPU0_G0_TX_DP<11>")
	)
	(segment
		(start 121.927874 -223.101916)
		(end 121.964196 -223.080834)
		(width 0.1143)
		(layer "In4.Cu")
		(net "GMI_CPU1_G2_CPU0_G0_TX_DP<11>")
	)
	(segment
		(start 152.252172 -193.7512)
		(end 152.445212 -193.770504)
		(width 0.14224)
		(layer "In4.Cu")
		(net "GMI_CPU1_G2_CPU0_G0_TX_DP<11>")
	)
	(segment
		(start 121.928128 -223.74733)
		(end 121.912126 -223.737678)
		(width 0.1143)
		(layer "In4.Cu")
		(net "GMI_CPU1_G2_CPU0_G0_TX_DP<11>")
	)
	(segment
		(start 122.75693 -228.284532)
		(end 122.674126 -228.201728)
		(width 0.1143)
		(layer "In4.Cu")
		(net "GMI_CPU1_G2_CPU0_G0_TX_DP<11>")
	)
	(segment
		(start 157.61462 -189.522862)
		(end 157.938978 -189.25667)
		(width 0.14224)
		(layer "In4.Cu")
		(net "GMI_CPU1_G2_CPU0_G0_TX_DP<11>")
	)
	(segment
		(start 121.896124 -223.728534)
		(end 121.896124 -223.728788)
		(width 0.1143)
		(layer "In4.Cu")
		(net "GMI_CPU1_G2_CPU0_G0_TX_DP<11>")
	)
	(segment
		(start 121.76125 -221.05493)
		(end 121.76125 -219.878148)
		(width 0.14224)
		(layer "In4.Cu")
		(net "GMI_CPU1_G2_CPU0_G0_TX_DP<11>")
	)
	(segment
		(start 312.96737 -187.8584)
		(end 347.735144 -216.366344)
		(width 0.14224)
		(layer "In4.Cu")
		(net "GMI_CPU1_G2_CPU0_G0_TX_DP<11>")
	)
	(segment
		(start 349.755714 -221.371668)
		(end 349.755714 -221.80423)
		(width 0.1143)
		(layer "In4.Cu")
		(net "GMI_CPU1_G2_CPU0_G0_TX_DP<11>")
	)
	(segment
		(start 168.267634 -183.691022)
		(end 302.888904 -184.474866)
		(width 0.14224)
		(layer "In4.Cu")
		(net "GMI_CPU1_G2_CPU0_G0_TX_DP<11>")
	)
	(segment
		(start 151.572976 -194.485514)
		(end 151.903176 -194.21475)
		(width 0.14224)
		(layer "In4.Cu")
		(net "GMI_CPU1_G2_CPU0_G0_TX_DP<11>")
	)
	(segment
		(start 308.421786 -185.28538)
		(end 312.96737 -187.8584)
		(width 0.14224)
		(layer "In4.Cu")
		(net "GMI_CPU1_G2_CPU0_G0_TX_DP<11>")
	)
	(segment
		(start 121.912126 -223.737678)
		(end 121.896124 -223.728534)
		(width 0.1143)
		(layer "In4.Cu")
		(net "GMI_CPU1_G2_CPU0_G0_TX_DP<11>")
	)
	(segment
		(start 349.528892 -224.699068)
		(end 349.599758 -224.739962)
		(width 0.1143)
		(layer "In4.Cu")
		(net "GMI_CPU1_G2_CPU0_G0_TX_DP<11>")
	)
	(segment
		(start 151.379936 -194.46621)
		(end 151.572976 -194.485514)
		(width 0.14224)
		(layer "In4.Cu")
		(net "GMI_CPU1_G2_CPU0_G0_TX_DP<11>")
	)
	(segment
		(start 349.599758 -225.348546)
		(end 349.568008 -225.366834)
		(width 0.1143)
		(layer "In4.Cu")
		(net "GMI_CPU1_G2_CPU0_G0_TX_DP<11>")
	)
	(segment
		(start 122.43689 -227.819966)
		(end 122.397774 -227.797106)
		(width 0.1143)
		(layer "In4.Cu")
		(net "GMI_CPU1_G2_CPU0_G0_TX_DP<11>")
	)
	(arc
		(start 121.896124 -222.108776)
		(mid 121.781448 -221.975442)
		(end 121.740168 -221.804484)
		(width 0.1143)
		(layer "In4.Cu")
		(net "GMI_CPU1_G2_CPU0_G0_TX_DP<11>")
	)
	(arc
		(start 349.599758 -224.739962)
		(mid 349.755686 -225.044254)
		(end 349.599758 -225.348546)
		(width 0.1143)
		(layer "In4.Cu")
		(net "GMI_CPU1_G2_CPU0_G0_TX_DP<11>")
	)
	(arc
		(start 349.555816 -226.994212)
		(mid 349.348828 -227.201184)
		(end 349.273114 -227.483924)
		(width 0.1143)
		(layer "In4.Cu")
		(net "GMI_CPU1_G2_CPU0_G0_TX_DP<11>")
	)
	(arc
		(start 122.222768 -227.484178)
		(mid 122.147011 -227.201463)
		(end 121.940066 -226.994466)
		(width 0.1143)
		(layer "In4.Cu")
		(net "GMI_CPU1_G2_CPU0_G0_TX_DP<11>")
	)
	(arc
		(start 122.674126 -228.201728)
		(mid 122.595047 -227.986283)
		(end 122.43689 -227.819966)
		(width 0.1143)
		(layer "In4.Cu")
		(net "GMI_CPU1_G2_CPU0_G0_TX_DP<11>")
	)
	(arc
		(start 121.97842 -225.398076)
		(mid 121.971346 -225.393069)
		(end 121.964196 -225.38817)
		(width 0.1143)
		(layer "In4.Cu")
		(net "GMI_CPU1_G2_CPU0_G0_TX_DP<11>")
	)
	(arc
		(start 121.97842 -222.158052)
		(mid 121.971346 -222.153045)
		(end 121.964196 -222.148146)
		(width 0.1143)
		(layer "In4.Cu")
		(net "GMI_CPU1_G2_CPU0_G0_TX_DP<11>")
	)
	(arc
		(start 121.896124 -226.968558)
		(mid 121.814143 -226.887908)
		(end 121.760488 -226.786186)
		(width 0.1143)
		(layer "In4.Cu")
		(net "GMI_CPU1_G2_CPU0_G0_TX_DP<11>")
	)
	(arc
		(start 349.735394 -226.785932)
		(mid 349.681758 -226.887668)
		(end 349.599758 -226.968304)
		(width 0.1143)
		(layer "In4.Cu")
		(net "GMI_CPU1_G2_CPU0_G0_TX_DP<11>")
	)
	(arc
		(start 349.599758 -223.11995)
		(mid 349.755686 -223.424242)
		(end 349.599758 -223.728534)
		(width 0.1143)
		(layer "In4.Cu")
		(net "GMI_CPU1_G2_CPU0_G0_TX_DP<11>")
	)
	(arc
		(start 122.39371 -227.795074)
		(mid 122.26851 -227.6686)
		(end 122.222768 -227.496624)
		(width 0.1143)
		(layer "In4.Cu")
		(net "GMI_CPU1_G2_CPU0_G0_TX_DP<11>")
	)
	(arc
		(start 349.517462 -225.397822)
		(mid 349.290079 -225.85426)
		(end 349.517462 -226.310698)
		(width 0.1143)
		(layer "In4.Cu")
		(net "GMI_CPU1_G2_CPU0_G0_TX_DP<11>")
	)
	(arc
		(start 349.531686 -222.147892)
		(mid 349.524536 -222.15279)
		(end 349.517462 -222.157798)
		(width 0.1143)
		(layer "In4.Cu")
		(net "GMI_CPU1_G2_CPU0_G0_TX_DP<11>")
	)
	(arc
		(start 121.964196 -223.080834)
		(mid 121.971345 -223.075934)
		(end 121.97842 -223.070928)
		(width 0.1143)
		(layer "In4.Cu")
		(net "GMI_CPU1_G2_CPU0_G0_TX_DP<11>")
	)
	(arc
		(start 349.599758 -226.359974)
		(mid 349.738014 -226.550524)
		(end 349.735394 -226.785932)
		(width 0.1143)
		(layer "In4.Cu")
		(net "GMI_CPU1_G2_CPU0_G0_TX_DP<11>")
	)
	(arc
		(start 121.97842 -223.070928)
		(mid 122.205803 -222.61449)
		(end 121.97842 -222.158052)
		(width 0.1143)
		(layer "In4.Cu")
		(net "GMI_CPU1_G2_CPU0_G0_TX_DP<11>")
	)
	(arc
		(start 349.501206 -223.789494)
		(mid 349.273206 -224.234248)
		(end 349.501206 -224.679002)
		(width 0.1143)
		(layer "In4.Cu")
		(net "GMI_CPU1_G2_CPU0_G0_TX_DP<11>")
	)
	(arc
		(start 349.755714 -221.80423)
		(mid 349.714459 -221.975201)
		(end 349.599758 -222.108522)
		(width 0.1143)
		(layer "In4.Cu")
		(net "GMI_CPU1_G2_CPU0_G0_TX_DP<11>")
	)
	(arc
		(start 121.97842 -226.310952)
		(mid 122.205803 -225.854514)
		(end 121.97842 -225.398076)
		(width 0.1143)
		(layer "In4.Cu")
		(net "GMI_CPU1_G2_CPU0_G0_TX_DP<11>")
	)
	(arc
		(start 349.517462 -226.310698)
		(mid 349.524535 -226.315707)
		(end 349.531686 -226.320604)
		(width 0.1143)
		(layer "In4.Cu")
		(net "GMI_CPU1_G2_CPU0_G0_TX_DP<11>")
	)
	(arc
		(start 121.896124 -223.728788)
		(mid 121.740196 -223.424496)
		(end 121.896124 -223.120204)
		(width 0.1143)
		(layer "In4.Cu")
		(net "GMI_CPU1_G2_CPU0_G0_TX_DP<11>")
	)
	(arc
		(start 349.517462 -222.157798)
		(mid 349.290079 -222.614236)
		(end 349.517462 -223.070674)
		(width 0.1143)
		(layer "In4.Cu")
		(net "GMI_CPU1_G2_CPU0_G0_TX_DP<11>")
	)
	(arc
		(start 121.964196 -226.320858)
		(mid 121.971345 -226.315958)
		(end 121.97842 -226.310952)
		(width 0.1143)
		(layer "In4.Cu")
		(net "GMI_CPU1_G2_CPU0_G0_TX_DP<11>")
	)
	(arc
		(start 121.760488 -226.786186)
		(mid 121.757867 -226.550777)
		(end 121.896124 -226.360228)
		(width 0.1143)
		(layer "In4.Cu")
		(net "GMI_CPU1_G2_CPU0_G0_TX_DP<11>")
	)
	(arc
		(start 349.273114 -227.49637)
		(mid 349.227348 -227.668332)
		(end 349.102172 -227.79482)
		(width 0.1143)
		(layer "In4.Cu")
		(net "GMI_CPU1_G2_CPU0_G0_TX_DP<11>")
	)
	(arc
		(start 349.531686 -225.387916)
		(mid 349.524536 -225.392814)
		(end 349.517462 -225.397822)
		(width 0.1143)
		(layer "In4.Cu")
		(net "GMI_CPU1_G2_CPU0_G0_TX_DP<11>")
	)
	(arc
		(start 121.994676 -224.679256)
		(mid 122.222676 -224.234502)
		(end 121.994676 -223.789748)
		(width 0.1143)
		(layer "In4.Cu")
		(net "GMI_CPU1_G2_CPU0_G0_TX_DP<11>")
	)
	(arc
		(start 349.517462 -223.070674)
		(mid 349.524535 -223.075683)
		(end 349.531686 -223.08058)
		(width 0.1143)
		(layer "In4.Cu")
		(net "GMI_CPU1_G2_CPU0_G0_TX_DP<11>")
	)
	(arc
		(start 121.896124 -225.3488)
		(mid 121.740196 -225.044508)
		(end 121.896124 -224.740216)
		(width 0.1143)
		(layer "In4.Cu")
		(net "GMI_CPU1_G2_CPU0_G0_TX_DP<11>")
	)
	(arc
		(start 349.058992 -227.819712)
		(mid 348.900787 -227.985999)
		(end 348.821756 -228.201474)
		(width 0.1143)
		(layer "In4.Cu")
		(net "GMI_CPU1_G2_CPU0_G0_TX_DP<11>")
	)
	(segment
		(start 122.587766 -226.930458)
		(end 123.054618 -226.66452)
		(width 0.12954)
		(layer "F.Cu")
		(net "GMI_CPU1_G2_CPU0_G0_TX_DP<10>")
	)
	(segment
		(start 348.907862 -226.930204)
		(end 348.44101 -226.664266)
		(width 0.12954)
		(layer "F.Cu")
		(net "GMI_CPU1_G2_CPU0_G0_TX_DP<10>")
	)
	(segment
		(start 348.789752 -219.98813)
		(end 348.789752 -221.083124)
		(width 0.14224)
		(layer "In4.Cu")
		(net "GMI_CPU1_G2_CPU0_G0_TX_DP<10>")
	)
	(segment
		(start 122.867674 -224.721928)
		(end 122.90679 -224.699068)
		(width 0.1143)
		(layer "In4.Cu")
		(net "GMI_CPU1_G2_CPU0_G0_TX_DP<10>")
	)
	(segment
		(start 152.943306 -194.576446)
		(end 153.136346 -194.595496)
		(width 0.14224)
		(layer "In4.Cu")
		(net "GMI_CPU1_G2_CPU0_G0_TX_DP<10>")
	)
	(segment
		(start 155.230068 -192.701164)
		(end 156.233876 -191.878204)
		(width 0.14224)
		(layer "In4.Cu")
		(net "GMI_CPU1_G2_CPU0_G0_TX_DP<10>")
	)
	(segment
		(start 156.727144 -191.63792)
		(end 156.74467 -191.459104)
		(width 0.14224)
		(layer "In4.Cu")
		(net "GMI_CPU1_G2_CPU0_G0_TX_DP<10>")
	)
	(segment
		(start 157.552136 -190.961264)
		(end 157.569662 -190.782448)
		(width 0.14224)
		(layer "In4.Cu")
		(net "GMI_CPU1_G2_CPU0_G0_TX_DP<10>")
	)
	(segment
		(start 154.357832 -193.416428)
		(end 154.687778 -193.145918)
		(width 0.14224)
		(layer "In4.Cu")
		(net "GMI_CPU1_G2_CPU0_G0_TX_DP<10>")
	)
	(segment
		(start 122.837194 -223.119696)
		(end 122.867674 -223.101916)
		(width 0.1143)
		(layer "In4.Cu")
		(net "GMI_CPU1_G2_CPU0_G0_TX_DP<10>")
	)
	(segment
		(start 347.0656 -217.08364)
		(end 348.789752 -219.98813)
		(width 0.14224)
		(layer "In4.Cu")
		(net "GMI_CPU1_G2_CPU0_G0_TX_DP<10>")
	)
	(segment
		(start 153.815542 -193.861182)
		(end 154.008582 -193.880232)
		(width 0.14224)
		(layer "In4.Cu")
		(net "GMI_CPU1_G2_CPU0_G0_TX_DP<10>")
	)
	(segment
		(start 151.564086 -195.871592)
		(end 151.581866 -195.692776)
		(width 0.14224)
		(layer "In4.Cu")
		(net "GMI_CPU1_G2_CPU0_G0_TX_DP<10>")
	)
	(segment
		(start 145.36039 -199.804274)
		(end 147.273772 -199.224646)
		(width 0.14224)
		(layer "In4.Cu")
		(net "GMI_CPU1_G2_CPU0_G0_TX_DP<10>")
	)
	(segment
		(start 123.054618 -226.66452)
		(end 122.75693 -226.66452)
		(width 0.1143)
		(layer "In4.Cu")
		(net "GMI_CPU1_G2_CPU0_G0_TX_DP<10>")
	)
	(segment
		(start 154.008582 -193.880232)
		(end 154.338782 -193.609468)
		(width 0.14224)
		(layer "In4.Cu")
		(net "GMI_CPU1_G2_CPU0_G0_TX_DP<10>")
	)
	(segment
		(start 122.867674 -223.101916)
		(end 122.90679 -223.079056)
		(width 0.1143)
		(layer "In4.Cu")
		(net "GMI_CPU1_G2_CPU0_G0_TX_DP<10>")
	)
	(segment
		(start 157.058868 -191.201548)
		(end 157.237684 -191.219074)
		(width 0.14224)
		(layer "In4.Cu")
		(net "GMI_CPU1_G2_CPU0_G0_TX_DP<10>")
	)
	(segment
		(start 122.867674 -222.127064)
		(end 122.837194 -222.109284)
		(width 0.1143)
		(layer "In4.Cu")
		(net "GMI_CPU1_G2_CPU0_G0_TX_DP<10>")
	)
	(segment
		(start 156.74467 -191.459104)
		(end 157.058868 -191.201548)
		(width 0.14224)
		(layer "In4.Cu")
		(net "GMI_CPU1_G2_CPU0_G0_TX_DP<10>")
	)
	(segment
		(start 302.616108 -185.413396)
		(end 302.885856 -185.41492)
		(width 0.14224)
		(layer "In4.Cu")
		(net "GMI_CPU1_G2_CPU0_G0_TX_DP<10>")
	)
	(segment
		(start 348.658688 -223.729042)
		(end 348.589092 -223.769682)
		(width 0.1143)
		(layer "In4.Cu")
		(net "GMI_CPU1_G2_CPU0_G0_TX_DP<10>")
	)
	(segment
		(start 154.687778 -193.145918)
		(end 154.880818 -193.164968)
		(width 0.14224)
		(layer "In4.Cu")
		(net "GMI_CPU1_G2_CPU0_G0_TX_DP<10>")
	)
	(segment
		(start 348.589092 -226.318826)
		(end 348.658688 -226.359466)
		(width 0.1143)
		(layer "In4.Cu")
		(net "GMI_CPU1_G2_CPU0_G0_TX_DP<10>")
	)
	(segment
		(start 348.835472 -221.34703)
		(end 348.81566 -221.366842)
		(width 0.1143)
		(layer "In4.Cu")
		(net "GMI_CPU1_G2_CPU0_G0_TX_DP<10>")
	)
	(segment
		(start 147.273772 -199.224646)
		(end 149.193758 -197.6501)
		(width 0.14224)
		(layer "In4.Cu")
		(net "GMI_CPU1_G2_CPU0_G0_TX_DP<10>")
	)
	(segment
		(start 157.237684 -191.219074)
		(end 157.552136 -190.961264)
		(width 0.14224)
		(layer "In4.Cu")
		(net "GMI_CPU1_G2_CPU0_G0_TX_DP<10>")
	)
	(segment
		(start 152.59431 -195.039996)
		(end 152.61336 -194.846956)
		(width 0.14224)
		(layer "In4.Cu")
		(net "GMI_CPU1_G2_CPU0_G0_TX_DP<10>")
	)
	(segment
		(start 122.70613 -221.083378)
		(end 122.70613 -221.05493)
		(width 0.1143)
		(layer "In4.Cu")
		(net "GMI_CPU1_G2_CPU0_G0_TX_DP<10>")
	)
	(segment
		(start 348.789752 -221.083124)
		(end 348.835472 -221.128844)
		(width 0.1143)
		(layer "In4.Cu")
		(net "GMI_CPU1_G2_CPU0_G0_TX_DP<10>")
	)
	(segment
		(start 157.569662 -190.782448)
		(end 157.88386 -190.524892)
		(width 0.14224)
		(layer "In4.Cu")
		(net "GMI_CPU1_G2_CPU0_G0_TX_DP<10>")
	)
	(segment
		(start 158.377128 -190.284608)
		(end 158.394908 -190.106046)
		(width 0.14224)
		(layer "In4.Cu")
		(net "GMI_CPU1_G2_CPU0_G0_TX_DP<10>")
	)
	(segment
		(start 122.867674 -223.747076)
		(end 122.837194 -223.729296)
		(width 0.1143)
		(layer "In4.Cu")
		(net "GMI_CPU1_G2_CPU0_G0_TX_DP<10>")
	)
	(segment
		(start 154.338782 -193.609468)
		(end 154.357832 -193.416428)
		(width 0.14224)
		(layer "In4.Cu")
		(net "GMI_CPU1_G2_CPU0_G0_TX_DP<10>")
	)
	(segment
		(start 122.680222 -221.804484)
		(end 122.680222 -221.367096)
		(width 0.1143)
		(layer "In4.Cu")
		(net "GMI_CPU1_G2_CPU0_G0_TX_DP<10>")
	)
	(segment
		(start 153.466546 -194.324732)
		(end 153.485596 -194.131692)
		(width 0.14224)
		(layer "In4.Cu")
		(net "GMI_CPU1_G2_CPU0_G0_TX_DP<10>")
	)
	(segment
		(start 122.867674 -225.367088)
		(end 122.837194 -225.349308)
		(width 0.1143)
		(layer "In4.Cu")
		(net "GMI_CPU1_G2_CPU0_G0_TX_DP<10>")
	)
	(segment
		(start 157.88386 -190.524892)
		(end 158.062676 -190.542672)
		(width 0.14224)
		(layer "In4.Cu")
		(net "GMI_CPU1_G2_CPU0_G0_TX_DP<10>")
	)
	(segment
		(start 155.211018 -192.894204)
		(end 155.230068 -192.701164)
		(width 0.14224)
		(layer "In4.Cu")
		(net "GMI_CPU1_G2_CPU0_G0_TX_DP<10>")
	)
	(segment
		(start 122.70613 -220.14688)
		(end 124.659898 -216.777824)
		(width 0.14224)
		(layer "In4.Cu")
		(net "GMI_CPU1_G2_CPU0_G0_TX_DP<10>")
	)
	(segment
		(start 151.581866 -195.692776)
		(end 152.07107 -195.29171)
		(width 0.14224)
		(layer "In4.Cu")
		(net "GMI_CPU1_G2_CPU0_G0_TX_DP<10>")
	)
	(segment
		(start 122.75693 -226.66452)
		(end 122.68708 -226.59467)
		(width 0.1143)
		(layer "In4.Cu")
		(net "GMI_CPU1_G2_CPU0_G0_TX_DP<10>")
	)
	(segment
		(start 348.81566 -221.366842)
		(end 348.81566 -221.80423)
		(width 0.1143)
		(layer "In4.Cu")
		(net "GMI_CPU1_G2_CPU0_G0_TX_DP<10>")
	)
	(segment
		(start 167.319706 -184.632092)
		(end 168.365932 -184.632092)
		(width 0.14224)
		(layer "In4.Cu")
		(net "GMI_CPU1_G2_CPU0_G0_TX_DP<10>")
	)
	(segment
		(start 122.66041 -221.347284)
		(end 122.66041 -221.129098)
		(width 0.1143)
		(layer "In4.Cu")
		(net "GMI_CPU1_G2_CPU0_G0_TX_DP<10>")
	)
	(segment
		(start 149.194012 -197.6501)
		(end 151.070818 -196.111622)
		(width 0.14224)
		(layer "In4.Cu")
		(net "GMI_CPU1_G2_CPU0_G0_TX_DP<10>")
	)
	(segment
		(start 122.90679 -225.389948)
		(end 122.867674 -225.367088)
		(width 0.1143)
		(layer "In4.Cu")
		(net "GMI_CPU1_G2_CPU0_G0_TX_DP<10>")
	)
	(segment
		(start 156.412438 -191.89573)
		(end 156.727144 -191.63792)
		(width 0.14224)
		(layer "In4.Cu")
		(net "GMI_CPU1_G2_CPU0_G0_TX_DP<10>")
	)
	(segment
		(start 152.26411 -195.31076)
		(end 152.59431 -195.039996)
		(width 0.14224)
		(layer "In4.Cu")
		(net "GMI_CPU1_G2_CPU0_G0_TX_DP<10>")
	)
	(segment
		(start 168.365932 -184.632092)
		(end 302.60544 -185.413396)
		(width 0.14224)
		(layer "In4.Cu")
		(net "GMI_CPU1_G2_CPU0_G0_TX_DP<10>")
	)
	(segment
		(start 122.66041 -221.129098)
		(end 122.70613 -221.083378)
		(width 0.1143)
		(layer "In4.Cu")
		(net "GMI_CPU1_G2_CPU0_G0_TX_DP<10>")
	)
	(segment
		(start 122.90679 -223.769936)
		(end 122.867674 -223.747076)
		(width 0.1143)
		(layer "In4.Cu")
		(net "GMI_CPU1_G2_CPU0_G0_TX_DP<10>")
	)
	(segment
		(start 151.249634 -196.129402)
		(end 151.564086 -195.871592)
		(width 0.14224)
		(layer "In4.Cu")
		(net "GMI_CPU1_G2_CPU0_G0_TX_DP<10>")
	)
	(segment
		(start 307.261006 -185.782966)
		(end 314.093606 -190.047626)
		(width 0.14224)
		(layer "In4.Cu")
		(net "GMI_CPU1_G2_CPU0_G0_TX_DP<10>")
	)
	(segment
		(start 152.61336 -194.846956)
		(end 152.943306 -194.576446)
		(width 0.14224)
		(layer "In4.Cu")
		(net "GMI_CPU1_G2_CPU0_G0_TX_DP<10>")
	)
	(segment
		(start 153.136346 -194.595496)
		(end 153.466546 -194.324732)
		(width 0.14224)
		(layer "In4.Cu")
		(net "GMI_CPU1_G2_CPU0_G0_TX_DP<10>")
	)
	(segment
		(start 154.880818 -193.164968)
		(end 155.211018 -192.894204)
		(width 0.14224)
		(layer "In4.Cu")
		(net "GMI_CPU1_G2_CPU0_G0_TX_DP<10>")
	)
	(segment
		(start 306.370736 -185.41492)
		(end 307.261006 -185.782966)
		(width 0.14224)
		(layer "In4.Cu")
		(net "GMI_CPU1_G2_CPU0_G0_TX_DP<10>")
	)
	(segment
		(start 124.659898 -216.777824)
		(end 145.36039 -199.804274)
		(width 0.14224)
		(layer "In4.Cu")
		(net "GMI_CPU1_G2_CPU0_G0_TX_DP<10>")
	)
	(segment
		(start 348.658688 -222.10903)
		(end 348.589092 -222.14967)
		(width 0.1143)
		(layer "In4.Cu")
		(net "GMI_CPU1_G2_CPU0_G0_TX_DP<10>")
	)
	(segment
		(start 158.394908 -190.106046)
		(end 158.394908 -190.105792)
		(width 0.14224)
		(layer "In4.Cu")
		(net "GMI_CPU1_G2_CPU0_G0_TX_DP<10>")
	)
	(segment
		(start 158.062676 -190.542672)
		(end 158.377128 -190.284608)
		(width 0.14224)
		(layer "In4.Cu")
		(net "GMI_CPU1_G2_CPU0_G0_TX_DP<10>")
	)
	(segment
		(start 153.485596 -194.131692)
		(end 153.815542 -193.861182)
		(width 0.14224)
		(layer "In4.Cu")
		(net "GMI_CPU1_G2_CPU0_G0_TX_DP<10>")
	)
	(segment
		(start 122.70613 -221.05493)
		(end 122.70613 -220.14688)
		(width 0.14224)
		(layer "In4.Cu")
		(net "GMI_CPU1_G2_CPU0_G0_TX_DP<10>")
	)
	(segment
		(start 156.233876 -191.878204)
		(end 156.412438 -191.89573)
		(width 0.14224)
		(layer "In4.Cu")
		(net "GMI_CPU1_G2_CPU0_G0_TX_DP<10>")
	)
	(segment
		(start 152.07107 -195.29171)
		(end 152.26411 -195.31076)
		(width 0.14224)
		(layer "In4.Cu")
		(net "GMI_CPU1_G2_CPU0_G0_TX_DP<10>")
	)
	(segment
		(start 163.330636 -186.058556)
		(end 167.319706 -184.632092)
		(width 0.14224)
		(layer "In4.Cu")
		(net "GMI_CPU1_G2_CPU0_G0_TX_DP<10>")
	)
	(segment
		(start 122.90679 -222.149924)
		(end 122.867674 -222.127064)
		(width 0.1143)
		(layer "In4.Cu")
		(net "GMI_CPU1_G2_CPU0_G0_TX_DP<10>")
	)
	(segment
		(start 302.60544 -185.413396)
		(end 302.616108 -185.413396)
		(width 0.14224)
		(layer "In4.Cu")
		(net "GMI_CPU1_G2_CPU0_G0_TX_DP<10>")
	)
	(segment
		(start 314.093606 -190.047626)
		(end 347.0656 -217.08364)
		(width 0.14224)
		(layer "In4.Cu")
		(net "GMI_CPU1_G2_CPU0_G0_TX_DP<10>")
	)
	(segment
		(start 158.394908 -190.105792)
		(end 163.330636 -186.058556)
		(width 0.14224)
		(layer "In4.Cu")
		(net "GMI_CPU1_G2_CPU0_G0_TX_DP<10>")
	)
	(segment
		(start 149.193758 -197.6501)
		(end 149.194012 -197.6501)
		(width 0.14224)
		(layer "In4.Cu")
		(net "GMI_CPU1_G2_CPU0_G0_TX_DP<10>")
	)
	(segment
		(start 348.589092 -223.078802)
		(end 348.658688 -223.119442)
		(width 0.1143)
		(layer "In4.Cu")
		(net "GMI_CPU1_G2_CPU0_G0_TX_DP<10>")
	)
	(segment
		(start 122.837194 -226.35972)
		(end 122.867674 -226.34194)
		(width 0.1143)
		(layer "In4.Cu")
		(net "GMI_CPU1_G2_CPU0_G0_TX_DP<10>")
	)
	(segment
		(start 348.835472 -221.128844)
		(end 348.835472 -221.34703)
		(width 0.1143)
		(layer "In4.Cu")
		(net "GMI_CPU1_G2_CPU0_G0_TX_DP<10>")
	)
	(segment
		(start 122.680222 -221.367096)
		(end 122.66041 -221.347284)
		(width 0.1143)
		(layer "In4.Cu")
		(net "GMI_CPU1_G2_CPU0_G0_TX_DP<10>")
	)
	(segment
		(start 302.885856 -185.41492)
		(end 306.370736 -185.41492)
		(width 0.14224)
		(layer "In4.Cu")
		(net "GMI_CPU1_G2_CPU0_G0_TX_DP<10>")
	)
	(segment
		(start 348.658688 -225.349054)
		(end 348.589092 -225.389694)
		(width 0.1143)
		(layer "In4.Cu")
		(net "GMI_CPU1_G2_CPU0_G0_TX_DP<10>")
	)
	(segment
		(start 122.867674 -226.34194)
		(end 122.90679 -226.31908)
		(width 0.1143)
		(layer "In4.Cu")
		(net "GMI_CPU1_G2_CPU0_G0_TX_DP<10>")
	)
	(segment
		(start 348.738952 -226.664266)
		(end 348.44101 -226.664266)
		(width 0.1143)
		(layer "In4.Cu")
		(net "GMI_CPU1_G2_CPU0_G0_TX_DP<10>")
	)
	(segment
		(start 348.808802 -226.594416)
		(end 348.738952 -226.664266)
		(width 0.1143)
		(layer "In4.Cu")
		(net "GMI_CPU1_G2_CPU0_G0_TX_DP<10>")
	)
	(segment
		(start 122.837194 -224.739708)
		(end 122.867674 -224.721928)
		(width 0.1143)
		(layer "In4.Cu")
		(net "GMI_CPU1_G2_CPU0_G0_TX_DP<10>")
	)
	(segment
		(start 151.070818 -196.111622)
		(end 151.249634 -196.129402)
		(width 0.14224)
		(layer "In4.Cu")
		(net "GMI_CPU1_G2_CPU0_G0_TX_DP<10>")
	)
	(segment
		(start 348.589092 -224.698814)
		(end 348.658688 -224.739454)
		(width 0.1143)
		(layer "In4.Cu")
		(net "GMI_CPU1_G2_CPU0_G0_TX_DP<10>")
	)
	(arc
		(start 122.68708 -226.59467)
		(mid 122.739497 -226.462739)
		(end 122.837194 -226.35972)
		(width 0.1143)
		(layer "In4.Cu")
		(net "GMI_CPU1_G2_CPU0_G0_TX_DP<10>")
	)
	(arc
		(start 122.90679 -223.079056)
		(mid 123.150117 -222.61449)
		(end 122.90679 -222.149924)
		(width 0.1143)
		(layer "In4.Cu")
		(net "GMI_CPU1_G2_CPU0_G0_TX_DP<10>")
	)
	(arc
		(start 348.658688 -224.739454)
		(mid 348.815665 -225.044254)
		(end 348.658688 -225.349054)
		(width 0.1143)
		(layer "In4.Cu")
		(net "GMI_CPU1_G2_CPU0_G0_TX_DP<10>")
	)
	(arc
		(start 348.658688 -226.359466)
		(mid 348.756453 -226.462442)
		(end 348.808802 -226.594416)
		(width 0.1143)
		(layer "In4.Cu")
		(net "GMI_CPU1_G2_CPU0_G0_TX_DP<10>")
	)
	(arc
		(start 348.589092 -222.14967)
		(mid 348.345765 -222.614236)
		(end 348.589092 -223.078802)
		(width 0.1143)
		(layer "In4.Cu")
		(net "GMI_CPU1_G2_CPU0_G0_TX_DP<10>")
	)
	(arc
		(start 122.837194 -223.729296)
		(mid 122.680217 -223.424496)
		(end 122.837194 -223.119696)
		(width 0.1143)
		(layer "In4.Cu")
		(net "GMI_CPU1_G2_CPU0_G0_TX_DP<10>")
	)
	(arc
		(start 122.90679 -226.31908)
		(mid 123.150117 -225.854514)
		(end 122.90679 -225.389948)
		(width 0.1143)
		(layer "In4.Cu")
		(net "GMI_CPU1_G2_CPU0_G0_TX_DP<10>")
	)
	(arc
		(start 348.658688 -223.119442)
		(mid 348.815665 -223.424242)
		(end 348.658688 -223.729042)
		(width 0.1143)
		(layer "In4.Cu")
		(net "GMI_CPU1_G2_CPU0_G0_TX_DP<10>")
	)
	(arc
		(start 348.81566 -221.80423)
		(mid 348.774111 -221.975652)
		(end 348.658688 -222.10903)
		(width 0.1143)
		(layer "In4.Cu")
		(net "GMI_CPU1_G2_CPU0_G0_TX_DP<10>")
	)
	(arc
		(start 348.589092 -223.769682)
		(mid 348.345765 -224.234248)
		(end 348.589092 -224.698814)
		(width 0.1143)
		(layer "In4.Cu")
		(net "GMI_CPU1_G2_CPU0_G0_TX_DP<10>")
	)
	(arc
		(start 122.837194 -225.349308)
		(mid 122.680217 -225.044508)
		(end 122.837194 -224.739708)
		(width 0.1143)
		(layer "In4.Cu")
		(net "GMI_CPU1_G2_CPU0_G0_TX_DP<10>")
	)
	(arc
		(start 122.90679 -224.699068)
		(mid 123.150117 -224.234502)
		(end 122.90679 -223.769936)
		(width 0.1143)
		(layer "In4.Cu")
		(net "GMI_CPU1_G2_CPU0_G0_TX_DP<10>")
	)
	(arc
		(start 348.589092 -225.389694)
		(mid 348.345765 -225.85426)
		(end 348.589092 -226.318826)
		(width 0.1143)
		(layer "In4.Cu")
		(net "GMI_CPU1_G2_CPU0_G0_TX_DP<10>")
	)
	(arc
		(start 122.837194 -222.109284)
		(mid 122.721767 -221.975908)
		(end 122.680222 -221.804484)
		(width 0.1143)
		(layer "In4.Cu")
		(net "GMI_CPU1_G2_CPU0_G0_TX_DP<10>")
	)
	(segment
		(start 114.597942 -230.980234)
		(end 115.064794 -230.71455)
		(width 0.12954)
		(layer "F.Cu")
		(net "GMI_CPU1_G2_CPU0_G0_TX_DP<0>")
	)
	(segment
		(start 356.89794 -230.97998)
		(end 356.431088 -230.714296)
		(width 0.12954)
		(layer "F.Cu")
		(net "GMI_CPU1_G2_CPU0_G0_TX_DP<0>")
	)
	(segment
		(start 359.217976 -221.444566)
		(end 358.9782 -222.650304)
		(width 0.1143)
		(layer "In4.Cu")
		(net "GMI_CPU1_G2_CPU0_G0_TX_DP<0>")
	)
	(segment
		(start 113.506758 -228.629972)
		(end 113.437162 -228.589332)
		(width 0.1143)
		(layer "In4.Cu")
		(net "GMI_CPU1_G2_CPU0_G0_TX_DP<0>")
	)
	(segment
		(start 113.937034 -229.416356)
		(end 113.904268 -229.397306)
		(width 0.1143)
		(layer "In4.Cu")
		(net "GMI_CPU1_G2_CPU0_G0_TX_DP<0>")
	)
	(segment
		(start 112.26673 -221.129098)
		(end 112.31245 -221.083378)
		(width 0.1143)
		(layer "In4.Cu")
		(net "GMI_CPU1_G2_CPU0_G0_TX_DP<0>")
	)
	(segment
		(start 357.782876 -213.942676)
		(end 357.996744 -214.302848)
		(width 0.14224)
		(layer "In4.Cu")
		(net "GMI_CPU1_G2_CPU0_G0_TX_DP<0>")
	)
	(segment
		(start 112.914684 -215.43137)
		(end 112.86871 -215.254078)
		(width 0.14224)
		(layer "In4.Cu")
		(net "GMI_CPU1_G2_CPU0_G0_TX_DP<0>")
	)
	(segment
		(start 114.766852 -230.71455)
		(end 114.684048 -230.631746)
		(width 0.1143)
		(layer "In4.Cu")
		(net "GMI_CPU1_G2_CPU0_G0_TX_DP<0>")
	)
	(segment
		(start 357.088694 -230.226362)
		(end 357.088186 -230.226616)
		(width 0.1143)
		(layer "In4.Cu")
		(net "GMI_CPU1_G2_CPU0_G0_TX_DP<0>")
	)
	(segment
		(start 112.31245 -221.083378)
		(end 112.31245 -221.05493)
		(width 0.1143)
		(layer "In4.Cu")
		(net "GMI_CPU1_G2_CPU0_G0_TX_DP<0>")
	)
	(segment
		(start 356.72903 -230.714296)
		(end 356.431088 -230.714296)
		(width 0.1143)
		(layer "In4.Cu")
		(net "GMI_CPU1_G2_CPU0_G0_TX_DP<0>")
	)
	(segment
		(start 355.780594 -210.56981)
		(end 357.43642 -213.35873)
		(width 0.14224)
		(layer "In4.Cu")
		(net "GMI_CPU1_G2_CPU0_G0_TX_DP<0>")
	)
	(segment
		(start 359.183432 -216.300812)
		(end 359.183432 -221.17431)
		(width 0.14224)
		(layer "In4.Cu")
		(net "GMI_CPU1_G2_CPU0_G0_TX_DP<0>")
	)
	(segment
		(start 308.674516 -175.066452)
		(end 311.802526 -176.184814)
		(width 0.14224)
		(layer "In4.Cu")
		(net "GMI_CPU1_G2_CPU0_G0_TX_DP<0>")
	)
	(segment
		(start 358.3432 -214.886286)
		(end 358.557068 -215.246458)
		(width 0.14224)
		(layer "In4.Cu")
		(net "GMI_CPU1_G2_CPU0_G0_TX_DP<0>")
	)
	(segment
		(start 112.489234 -222.214948)
		(end 112.26673 -221.677738)
		(width 0.1143)
		(layer "In4.Cu")
		(net "GMI_CPU1_G2_CPU0_G0_TX_DP<0>")
	)
	(segment
		(start 115.627404 -210.561428)
		(end 156.105352 -177.370486)
		(width 0.14224)
		(layer "In4.Cu")
		(net "GMI_CPU1_G2_CPU0_G0_TX_DP<0>")
	)
	(segment
		(start 112.70234 -215.793066)
		(end 112.914684 -215.43137)
		(width 0.14224)
		(layer "In4.Cu")
		(net "GMI_CPU1_G2_CPU0_G0_TX_DP<0>")
	)
	(segment
		(start 358.557068 -215.246458)
		(end 358.511856 -215.42375)
		(width 0.14224)
		(layer "In4.Cu")
		(net "GMI_CPU1_G2_CPU0_G0_TX_DP<0>")
	)
	(segment
		(start 358.963468 -222.80118)
		(end 358.963468 -227.09886)
		(width 0.1143)
		(layer "In4.Cu")
		(net "GMI_CPU1_G2_CPU0_G0_TX_DP<0>")
	)
	(segment
		(start 113.637314 -213.94674)
		(end 113.81486 -213.900766)
		(width 0.14224)
		(layer "In4.Cu")
		(net "GMI_CPU1_G2_CPU0_G0_TX_DP<0>")
	)
	(segment
		(start 357.43642 -213.35873)
		(end 357.43642 -213.359238)
		(width 0.14224)
		(layer "In4.Cu")
		(net "GMI_CPU1_G2_CPU0_G0_TX_DP<0>")
	)
	(segment
		(start 112.31245 -221.05493)
		(end 112.31245 -216.200228)
		(width 0.14224)
		(layer "In4.Cu")
		(net "GMI_CPU1_G2_CPU0_G0_TX_DP<0>")
	)
	(segment
		(start 114.407696 -230.22687)
		(end 114.407188 -230.226616)
		(width 0.1143)
		(layer "In4.Cu")
		(net "GMI_CPU1_G2_CPU0_G0_TX_DP<0>")
	)
	(segment
		(start 357.558848 -229.416102)
		(end 357.554276 -229.418896)
		(width 0.1143)
		(layer "In4.Cu")
		(net "GMI_CPU1_G2_CPU0_G0_TX_DP<0>")
	)
	(segment
		(start 114.444272 -230.248206)
		(end 114.407696 -230.22687)
		(width 0.1143)
		(layer "In4.Cu")
		(net "GMI_CPU1_G2_CPU0_G0_TX_DP<0>")
	)
	(segment
		(start 358.680258 -227.631752)
		(end 358.566466 -227.74529)
		(width 0.1143)
		(layer "In4.Cu")
		(net "GMI_CPU1_G2_CPU0_G0_TX_DP<0>")
	)
	(segment
		(start 114.749834 -212.05444)
		(end 114.92738 -212.008466)
		(width 0.14224)
		(layer "In4.Cu")
		(net "GMI_CPU1_G2_CPU0_G0_TX_DP<0>")
	)
	(segment
		(start 114.027204 -213.53907)
		(end 113.98123 -213.361778)
		(width 0.14224)
		(layer "In4.Cu")
		(net "GMI_CPU1_G2_CPU0_G0_TX_DP<0>")
	)
	(segment
		(start 357.996744 -214.302848)
		(end 357.951532 -214.480394)
		(width 0.14224)
		(layer "In4.Cu")
		(net "GMI_CPU1_G2_CPU0_G0_TX_DP<0>")
	)
	(segment
		(start 113.037874 -227.819966)
		(end 112.997742 -227.796598)
		(width 0.1143)
		(layer "In4.Cu")
		(net "GMI_CPU1_G2_CPU0_G0_TX_DP<0>")
	)
	(segment
		(start 358.05872 -228.589078)
		(end 357.989124 -228.629718)
		(width 0.1143)
		(layer "In4.Cu")
		(net "GMI_CPU1_G2_CPU0_G0_TX_DP<0>")
	)
	(segment
		(start 357.605076 -213.89721)
		(end 357.782876 -213.942676)
		(width 0.14224)
		(layer "In4.Cu")
		(net "GMI_CPU1_G2_CPU0_G0_TX_DP<0>")
	)
	(segment
		(start 357.591614 -229.397052)
		(end 357.558848 -229.416102)
		(width 0.1143)
		(layer "In4.Cu")
		(net "GMI_CPU1_G2_CPU0_G0_TX_DP<0>")
	)
	(segment
		(start 113.941606 -229.41915)
		(end 113.937034 -229.416356)
		(width 0.1143)
		(layer "In4.Cu")
		(net "GMI_CPU1_G2_CPU0_G0_TX_DP<0>")
	)
	(segment
		(start 113.470944 -214.48522)
		(end 113.42497 -214.307928)
		(width 0.14224)
		(layer "In4.Cu")
		(net "GMI_CPU1_G2_CPU0_G0_TX_DP<0>")
	)
	(segment
		(start 113.81486 -213.900766)
		(end 114.027204 -213.53907)
		(width 0.14224)
		(layer "In4.Cu")
		(net "GMI_CPU1_G2_CPU0_G0_TX_DP<0>")
	)
	(segment
		(start 318.403732 -179.921662)
		(end 355.780594 -210.56981)
		(width 0.14224)
		(layer "In4.Cu")
		(net "GMI_CPU1_G2_CPU0_G0_TX_DP<0>")
	)
	(segment
		(start 358.511856 -215.42375)
		(end 358.725724 -215.78443)
		(width 0.14224)
		(layer "In4.Cu")
		(net "GMI_CPU1_G2_CPU0_G0_TX_DP<0>")
	)
	(segment
		(start 112.921288 -227.737924)
		(end 112.489234 -227.30587)
		(width 0.1143)
		(layer "In4.Cu")
		(net "GMI_CPU1_G2_CPU0_G0_TX_DP<0>")
	)
	(segment
		(start 113.2586 -214.846916)
		(end 113.470944 -214.48522)
		(width 0.14224)
		(layer "In4.Cu")
		(net "GMI_CPU1_G2_CPU0_G0_TX_DP<0>")
	)
	(segment
		(start 112.31245 -216.200228)
		(end 112.524794 -215.83904)
		(width 0.14224)
		(layer "In4.Cu")
		(net "GMI_CPU1_G2_CPU0_G0_TX_DP<0>")
	)
	(segment
		(start 112.524794 -215.83904)
		(end 112.70234 -215.793066)
		(width 0.14224)
		(layer "In4.Cu")
		(net "GMI_CPU1_G2_CPU0_G0_TX_DP<0>")
	)
	(segment
		(start 115.064794 -230.71455)
		(end 114.766852 -230.71455)
		(width 0.1143)
		(layer "In4.Cu")
		(net "GMI_CPU1_G2_CPU0_G0_TX_DP<0>")
	)
	(segment
		(start 358.49814 -227.796344)
		(end 358.458008 -227.819712)
		(width 0.1143)
		(layer "In4.Cu")
		(net "GMI_CPU1_G2_CPU0_G0_TX_DP<0>")
	)
	(segment
		(start 359.229152 -221.248478)
		(end 359.229152 -221.331028)
		(width 0.1143)
		(layer "In4.Cu")
		(net "GMI_CPU1_G2_CPU0_G0_TX_DP<0>")
	)
	(segment
		(start 114.92738 -212.008466)
		(end 115.139724 -211.64677)
		(width 0.14224)
		(layer "In4.Cu")
		(net "GMI_CPU1_G2_CPU0_G0_TX_DP<0>")
	)
	(segment
		(start 357.43642 -213.359238)
		(end 357.391208 -213.536784)
		(width 0.14224)
		(layer "In4.Cu")
		(net "GMI_CPU1_G2_CPU0_G0_TX_DP<0>")
	)
	(segment
		(start 302.919384 -175.066452)
		(end 308.674516 -175.066452)
		(width 0.14224)
		(layer "In4.Cu")
		(net "GMI_CPU1_G2_CPU0_G0_TX_DP<0>")
	)
	(segment
		(start 115.09375 -211.469478)
		(end 115.627404 -210.561428)
		(width 0.14224)
		(layer "In4.Cu")
		(net "GMI_CPU1_G2_CPU0_G0_TX_DP<0>")
	)
	(segment
		(start 166.650924 -174.269146)
		(end 302.919384 -175.066452)
		(width 0.14224)
		(layer "In4.Cu")
		(net "GMI_CPU1_G2_CPU0_G0_TX_DP<0>")
	)
	(segment
		(start 112.26673 -221.677738)
		(end 112.26673 -221.129098)
		(width 0.1143)
		(layer "In4.Cu")
		(net "GMI_CPU1_G2_CPU0_G0_TX_DP<0>")
	)
	(segment
		(start 357.951532 -214.480394)
		(end 358.1654 -214.84082)
		(width 0.14224)
		(layer "In4.Cu")
		(net "GMI_CPU1_G2_CPU0_G0_TX_DP<0>")
	)
	(segment
		(start 112.489234 -227.30587)
		(end 112.489234 -222.214948)
		(width 0.1143)
		(layer "In4.Cu")
		(net "GMI_CPU1_G2_CPU0_G0_TX_DP<0>")
	)
	(segment
		(start 113.42497 -214.307928)
		(end 113.637314 -213.94674)
		(width 0.14224)
		(layer "In4.Cu")
		(net "GMI_CPU1_G2_CPU0_G0_TX_DP<0>")
	)
	(segment
		(start 114.193574 -213.00059)
		(end 114.37112 -212.954616)
		(width 0.14224)
		(layer "In4.Cu")
		(net "GMI_CPU1_G2_CPU0_G0_TX_DP<0>")
	)
	(segment
		(start 359.183432 -221.202758)
		(end 359.229152 -221.248478)
		(width 0.1143)
		(layer "In4.Cu")
		(net "GMI_CPU1_G2_CPU0_G0_TX_DP<0>")
	)
	(segment
		(start 114.53749 -212.415628)
		(end 114.749834 -212.05444)
		(width 0.14224)
		(layer "In4.Cu")
		(net "GMI_CPU1_G2_CPU0_G0_TX_DP<0>")
	)
	(segment
		(start 357.088186 -230.226616)
		(end 357.05161 -230.247952)
		(width 0.1143)
		(layer "In4.Cu")
		(net "GMI_CPU1_G2_CPU0_G0_TX_DP<0>")
	)
	(segment
		(start 156.105352 -177.370486)
		(end 164.777928 -174.269146)
		(width 0.14224)
		(layer "In4.Cu")
		(net "GMI_CPU1_G2_CPU0_G0_TX_DP<0>")
	)
	(segment
		(start 358.903524 -215.829642)
		(end 359.183432 -216.300812)
		(width 0.14224)
		(layer "In4.Cu")
		(net "GMI_CPU1_G2_CPU0_G0_TX_DP<0>")
	)
	(segment
		(start 164.777928 -174.269146)
		(end 166.650924 -174.269146)
		(width 0.14224)
		(layer "In4.Cu")
		(net "GMI_CPU1_G2_CPU0_G0_TX_DP<0>")
	)
	(segment
		(start 356.811834 -230.631492)
		(end 356.72903 -230.714296)
		(width 0.1143)
		(layer "In4.Cu")
		(net "GMI_CPU1_G2_CPU0_G0_TX_DP<0>")
	)
	(segment
		(start 358.725724 -215.78443)
		(end 358.903524 -215.829642)
		(width 0.14224)
		(layer "In4.Cu")
		(net "GMI_CPU1_G2_CPU0_G0_TX_DP<0>")
	)
	(segment
		(start 113.98123 -213.361778)
		(end 114.193574 -213.00059)
		(width 0.14224)
		(layer "In4.Cu")
		(net "GMI_CPU1_G2_CPU0_G0_TX_DP<0>")
	)
	(segment
		(start 311.802526 -176.184814)
		(end 318.403732 -179.921662)
		(width 0.14224)
		(layer "In4.Cu")
		(net "GMI_CPU1_G2_CPU0_G0_TX_DP<0>")
	)
	(segment
		(start 115.139724 -211.64677)
		(end 115.09375 -211.469478)
		(width 0.14224)
		(layer "In4.Cu")
		(net "GMI_CPU1_G2_CPU0_G0_TX_DP<0>")
	)
	(segment
		(start 359.183432 -221.17431)
		(end 359.183432 -221.202758)
		(width 0.1143)
		(layer "In4.Cu")
		(net "GMI_CPU1_G2_CPU0_G0_TX_DP<0>")
	)
	(segment
		(start 113.081054 -214.89289)
		(end 113.2586 -214.846916)
		(width 0.14224)
		(layer "In4.Cu")
		(net "GMI_CPU1_G2_CPU0_G0_TX_DP<0>")
	)
	(segment
		(start 112.86871 -215.254078)
		(end 113.081054 -214.89289)
		(width 0.14224)
		(layer "In4.Cu")
		(net "GMI_CPU1_G2_CPU0_G0_TX_DP<0>")
	)
	(segment
		(start 114.583464 -212.59292)
		(end 114.53749 -212.415628)
		(width 0.14224)
		(layer "In4.Cu")
		(net "GMI_CPU1_G2_CPU0_G0_TX_DP<0>")
	)
	(segment
		(start 358.1654 -214.84082)
		(end 358.3432 -214.886286)
		(width 0.14224)
		(layer "In4.Cu")
		(net "GMI_CPU1_G2_CPU0_G0_TX_DP<0>")
	)
	(segment
		(start 114.37112 -212.954616)
		(end 114.583464 -212.59292)
		(width 0.14224)
		(layer "In4.Cu")
		(net "GMI_CPU1_G2_CPU0_G0_TX_DP<0>")
	)
	(segment
		(start 357.391208 -213.536784)
		(end 357.605076 -213.89721)
		(width 0.14224)
		(layer "In4.Cu")
		(net "GMI_CPU1_G2_CPU0_G0_TX_DP<0>")
	)
	(arc
		(start 114.680238 -230.608886)
		(mid 114.597958 -230.40519)
		(end 114.444272 -230.248206)
		(width 0.1143)
		(layer "In4.Cu")
		(net "GMI_CPU1_G2_CPU0_G0_TX_DP<0>")
	)
	(arc
		(start 113.28019 -228.284278)
		(mid 113.216087 -228.022339)
		(end 113.037874 -227.819966)
		(width 0.1143)
		(layer "In4.Cu")
		(net "GMI_CPU1_G2_CPU0_G0_TX_DP<0>")
	)
	(arc
		(start 358.566466 -227.74529)
		(mid 358.533768 -227.772778)
		(end 358.49814 -227.796344)
		(width 0.1143)
		(layer "In4.Cu")
		(net "GMI_CPU1_G2_CPU0_G0_TX_DP<0>")
	)
	(arc
		(start 114.407188 -230.226616)
		(mid 114.271127 -230.090616)
		(end 114.22126 -229.904798)
		(width 0.1143)
		(layer "In4.Cu")
		(net "GMI_CPU1_G2_CPU0_G0_TX_DP<0>")
	)
	(arc
		(start 358.215692 -228.284024)
		(mid 358.17422 -228.455611)
		(end 358.05872 -228.589078)
		(width 0.1143)
		(layer "In4.Cu")
		(net "GMI_CPU1_G2_CPU0_G0_TX_DP<0>")
	)
	(arc
		(start 357.989124 -228.629718)
		(mid 357.810311 -228.832068)
		(end 357.745792 -229.094284)
		(width 0.1143)
		(layer "In4.Cu")
		(net "GMI_CPU1_G2_CPU0_G0_TX_DP<0>")
	)
	(arc
		(start 112.997742 -227.796598)
		(mid 112.957614 -227.769739)
		(end 112.921288 -227.737924)
		(width 0.1143)
		(layer "In4.Cu")
		(net "GMI_CPU1_G2_CPU0_G0_TX_DP<0>")
	)
	(arc
		(start 358.944418 -227.21189)
		(mid 358.836046 -227.436741)
		(end 358.680258 -227.631752)
		(width 0.1143)
		(layer "In4.Cu")
		(net "GMI_CPU1_G2_CPU0_G0_TX_DP<0>")
	)
	(arc
		(start 357.05161 -230.247952)
		(mid 356.89791 -230.404927)
		(end 356.815644 -230.608632)
		(width 0.1143)
		(layer "In4.Cu")
		(net "GMI_CPU1_G2_CPU0_G0_TX_DP<0>")
	)
	(arc
		(start 358.963468 -227.09886)
		(mid 358.958715 -227.156179)
		(end 358.944418 -227.21189)
		(width 0.1143)
		(layer "In4.Cu")
		(net "GMI_CPU1_G2_CPU0_G0_TX_DP<0>")
	)
	(arc
		(start 114.22126 -229.904798)
		(mid 114.146356 -229.624583)
		(end 113.941606 -229.41915)
		(width 0.1143)
		(layer "In4.Cu")
		(net "GMI_CPU1_G2_CPU0_G0_TX_DP<0>")
	)
	(arc
		(start 359.229152 -221.331028)
		(mid 359.226351 -221.388071)
		(end 359.217976 -221.444566)
		(width 0.1143)
		(layer "In4.Cu")
		(net "GMI_CPU1_G2_CPU0_G0_TX_DP<0>")
	)
	(arc
		(start 356.815644 -230.608632)
		(mid 356.813621 -230.620042)
		(end 356.811834 -230.631492)
		(width 0.1143)
		(layer "In4.Cu")
		(net "GMI_CPU1_G2_CPU0_G0_TX_DP<0>")
	)
	(arc
		(start 357.554276 -229.418896)
		(mid 357.34956 -229.624348)
		(end 357.274622 -229.904544)
		(width 0.1143)
		(layer "In4.Cu")
		(net "GMI_CPU1_G2_CPU0_G0_TX_DP<0>")
	)
	(arc
		(start 358.458008 -227.819712)
		(mid 358.279841 -228.022109)
		(end 358.215692 -228.284024)
		(width 0.1143)
		(layer "In4.Cu")
		(net "GMI_CPU1_G2_CPU0_G0_TX_DP<0>")
	)
	(arc
		(start 113.437162 -228.589332)
		(mid 113.321752 -228.455819)
		(end 113.28019 -228.284278)
		(width 0.1143)
		(layer "In4.Cu")
		(net "GMI_CPU1_G2_CPU0_G0_TX_DP<0>")
	)
	(arc
		(start 113.75009 -229.094538)
		(mid 113.685575 -228.832319)
		(end 113.506758 -228.629972)
		(width 0.1143)
		(layer "In4.Cu")
		(net "GMI_CPU1_G2_CPU0_G0_TX_DP<0>")
	)
	(arc
		(start 358.9782 -222.650304)
		(mid 358.96713 -222.72538)
		(end 358.963468 -222.80118)
		(width 0.1143)
		(layer "In4.Cu")
		(net "GMI_CPU1_G2_CPU0_G0_TX_DP<0>")
	)
	(arc
		(start 357.274622 -229.904544)
		(mid 357.224809 -230.090393)
		(end 357.088694 -230.226362)
		(width 0.1143)
		(layer "In4.Cu")
		(net "GMI_CPU1_G2_CPU0_G0_TX_DP<0>")
	)
	(arc
		(start 357.745792 -229.094284)
		(mid 357.70503 -229.264168)
		(end 357.591614 -229.397052)
		(width 0.1143)
		(layer "In4.Cu")
		(net "GMI_CPU1_G2_CPU0_G0_TX_DP<0>")
	)
	(arc
		(start 113.904268 -229.397306)
		(mid 113.790861 -229.264417)
		(end 113.75009 -229.094538)
		(width 0.1143)
		(layer "In4.Cu")
		(net "GMI_CPU1_G2_CPU0_G0_TX_DP<0>")
	)
	(arc
		(start 114.684048 -230.631746)
		(mid 114.68226 -230.620297)
		(end 114.680238 -230.608886)
		(width 0.1143)
		(layer "In4.Cu")
		(net "GMI_CPU1_G2_CPU0_G0_TX_DP<0>")
	)
	(segment
		(start 121.647966 -230.170228)
		(end 122.114818 -229.90429)
		(width 0.12954)
		(layer "F.Cu")
		(net "GMI_CPU1_G2_CPU0_G0_TX_DN<9>")
	)
	(segment
		(start 349.847916 -230.169974)
		(end 349.381064 -229.904036)
		(width 0.12954)
		(layer "F.Cu")
		(net "GMI_CPU1_G2_CPU0_G0_TX_DN<9>")
	)
	(segment
		(start 157.067758 -188.047376)
		(end 146.22907 -196.93509)
		(width 0.14224)
		(layer "In4.Cu")
		(net "GMI_CPU1_G2_CPU0_G0_TX_DN<9>")
	)
	(segment
		(start 349.63354 -228.789484)
		(end 349.703136 -228.748844)
		(width 0.1143)
		(layer "In4.Cu")
		(net "GMI_CPU1_G2_CPU0_G0_TX_DN<9>")
	)
	(segment
		(start 120.609614 -221.272862)
		(end 120.609614 -221.804484)
		(width 0.1143)
		(layer "In4.Cu")
		(net "GMI_CPU1_G2_CPU0_G0_TX_DN<9>")
	)
	(segment
		(start 122.301762 -229.581964)
		(end 122.33529 -229.601522)
		(width 0.1143)
		(layer "In4.Cu")
		(net "GMI_CPU1_G2_CPU0_G0_TX_DN<9>")
	)
	(segment
		(start 302.892968 -183.252872)
		(end 168.16324 -182.468012)
		(width 0.14224)
		(layer "In4.Cu")
		(net "GMI_CPU1_G2_CPU0_G0_TX_DN<9>")
	)
	(segment
		(start 157.068012 -188.047376)
		(end 157.067758 -188.047376)
		(width 0.14224)
		(layer "In4.Cu")
		(net "GMI_CPU1_G2_CPU0_G0_TX_DN<9>")
	)
	(segment
		(start 350.64319 -222.959676)
		(end 350.573594 -222.919036)
		(width 0.1143)
		(layer "In4.Cu")
		(net "GMI_CPU1_G2_CPU0_G0_TX_DN<9>")
	)
	(segment
		(start 121.792746 -228.749098)
		(end 121.831862 -228.771958)
		(width 0.1143)
		(layer "In4.Cu")
		(net "GMI_CPU1_G2_CPU0_G0_TX_DN<9>")
	)
	(segment
		(start 350.64319 -224.579688)
		(end 350.573594 -224.539048)
		(width 0.1143)
		(layer "In4.Cu")
		(net "GMI_CPU1_G2_CPU0_G0_TX_DN<9>")
	)
	(segment
		(start 122.019314 -229.094538)
		(end 122.019568 -229.094538)
		(width 0.1143)
		(layer "In4.Cu")
		(net "GMI_CPU1_G2_CPU0_G0_TX_DN<9>")
	)
	(segment
		(start 349.381064 -229.904036)
		(end 349.083122 -229.904036)
		(width 0.1143)
		(layer "In4.Cu")
		(net "GMI_CPU1_G2_CPU0_G0_TX_DN<9>")
	)
	(segment
		(start 120.891808 -222.93707)
		(end 120.852692 -222.95993)
		(width 0.1143)
		(layer "In4.Cu")
		(net "GMI_CPU1_G2_CPU0_G0_TX_DN<9>")
	)
	(segment
		(start 120.922288 -222.91929)
		(end 120.891808 -222.93707)
		(width 0.1143)
		(layer "In4.Cu")
		(net "GMI_CPU1_G2_CPU0_G0_TX_DN<9>")
	)
	(segment
		(start 122.26544 -229.560882)
		(end 122.301762 -229.581964)
		(width 0.1143)
		(layer "In4.Cu")
		(net "GMI_CPU1_G2_CPU0_G0_TX_DN<9>")
	)
	(segment
		(start 121.361708 -227.961952)
		(end 121.393458 -227.98024)
		(width 0.1143)
		(layer "In4.Cu")
		(net "GMI_CPU1_G2_CPU0_G0_TX_DN<9>")
	)
	(segment
		(start 120.53443 -219.543884)
		(end 120.53443 -221.05493)
		(width 0.14224)
		(layer "In4.Cu")
		(net "GMI_CPU1_G2_CPU0_G0_TX_DN<9>")
	)
	(segment
		(start 121.831862 -228.771958)
		(end 121.862342 -228.789738)
		(width 0.1143)
		(layer "In4.Cu")
		(net "GMI_CPU1_G2_CPU0_G0_TX_DN<9>")
	)
	(segment
		(start 121.322592 -227.939092)
		(end 121.360692 -227.961444)
		(width 0.1143)
		(layer "In4.Cu")
		(net "GMI_CPU1_G2_CPU0_G0_TX_DN<9>")
	)
	(segment
		(start 120.53443 -221.083378)
		(end 120.58015 -221.129098)
		(width 0.1143)
		(layer "In4.Cu")
		(net "GMI_CPU1_G2_CPU0_G0_TX_DN<9>")
	)
	(segment
		(start 350.886268 -221.80423)
		(end 350.886268 -221.453456)
		(width 0.1143)
		(layer "In4.Cu")
		(net "GMI_CPU1_G2_CPU0_G0_TX_DN<9>")
	)
	(segment
		(start 349.083122 -229.904036)
		(end 349.013272 -229.834186)
		(width 0.1143)
		(layer "In4.Cu")
		(net "GMI_CPU1_G2_CPU0_G0_TX_DN<9>")
	)
	(segment
		(start 120.852692 -223.889062)
		(end 120.891808 -223.911922)
		(width 0.1143)
		(layer "In4.Cu")
		(net "GMI_CPU1_G2_CPU0_G0_TX_DN<9>")
	)
	(segment
		(start 350.573594 -222.309436)
		(end 350.64319 -222.268796)
		(width 0.1143)
		(layer "In4.Cu")
		(net "GMI_CPU1_G2_CPU0_G0_TX_DN<9>")
	)
	(segment
		(start 120.852692 -222.26905)
		(end 120.922288 -222.30969)
		(width 0.1143)
		(layer "In4.Cu")
		(net "GMI_CPU1_G2_CPU0_G0_TX_DN<9>")
	)
	(segment
		(start 120.891808 -224.557082)
		(end 120.852692 -224.579942)
		(width 0.1143)
		(layer "In4.Cu")
		(net "GMI_CPU1_G2_CPU0_G0_TX_DN<9>")
	)
	(segment
		(start 161.749994 -184.208166)
		(end 157.068012 -188.047376)
		(width 0.14224)
		(layer "In4.Cu")
		(net "GMI_CPU1_G2_CPU0_G0_TX_DN<9>")
	)
	(segment
		(start 120.891808 -227.151946)
		(end 120.922288 -227.169726)
		(width 0.1143)
		(layer "In4.Cu")
		(net "GMI_CPU1_G2_CPU0_G0_TX_DN<9>")
	)
	(segment
		(start 349.476314 -229.094284)
		(end 349.476568 -229.094284)
		(width 0.1143)
		(layer "In4.Cu")
		(net "GMI_CPU1_G2_CPU0_G0_TX_DN<9>")
	)
	(segment
		(start 120.922288 -226.159314)
		(end 120.891808 -226.177094)
		(width 0.1143)
		(layer "In4.Cu")
		(net "GMI_CPU1_G2_CPU0_G0_TX_DN<9>")
	)
	(segment
		(start 349.19412 -229.58171)
		(end 349.230442 -229.560628)
		(width 0.1143)
		(layer "In4.Cu")
		(net "GMI_CPU1_G2_CPU0_G0_TX_DN<9>")
	)
	(segment
		(start 350.886268 -221.453456)
		(end 350.915732 -221.423992)
		(width 0.1143)
		(layer "In4.Cu")
		(net "GMI_CPU1_G2_CPU0_G0_TX_DN<9>")
	)
	(segment
		(start 350.13519 -227.96119)
		(end 350.17329 -227.938838)
		(width 0.1143)
		(layer "In4.Cu")
		(net "GMI_CPU1_G2_CPU0_G0_TX_DN<9>")
	)
	(segment
		(start 120.852692 -225.509074)
		(end 120.891808 -225.531934)
		(width 0.1143)
		(layer "In4.Cu")
		(net "GMI_CPU1_G2_CPU0_G0_TX_DN<9>")
	)
	(segment
		(start 120.53443 -221.05493)
		(end 120.53443 -221.083378)
		(width 0.1143)
		(layer "In4.Cu")
		(net "GMI_CPU1_G2_CPU0_G0_TX_DN<9>")
	)
	(segment
		(start 350.134174 -227.961698)
		(end 350.13519 -227.96119)
		(width 0.1143)
		(layer "In4.Cu")
		(net "GMI_CPU1_G2_CPU0_G0_TX_DN<9>")
	)
	(segment
		(start 120.891808 -225.531934)
		(end 120.922288 -225.549714)
		(width 0.1143)
		(layer "In4.Cu")
		(net "GMI_CPU1_G2_CPU0_G0_TX_DN<9>")
	)
	(segment
		(start 350.573594 -227.169472)
		(end 350.64319 -227.128832)
		(width 0.1143)
		(layer "In4.Cu")
		(net "GMI_CPU1_G2_CPU0_G0_TX_DN<9>")
	)
	(segment
		(start 350.573594 -223.929448)
		(end 350.64319 -223.888808)
		(width 0.1143)
		(layer "In4.Cu")
		(net "GMI_CPU1_G2_CPU0_G0_TX_DN<9>")
	)
	(segment
		(start 349.160592 -229.601268)
		(end 349.19412 -229.58171)
		(width 0.1143)
		(layer "In4.Cu")
		(net "GMI_CPU1_G2_CPU0_G0_TX_DN<9>")
	)
	(segment
		(start 120.58015 -221.129098)
		(end 120.58015 -221.243398)
		(width 0.1143)
		(layer "In4.Cu")
		(net "GMI_CPU1_G2_CPU0_G0_TX_DN<9>")
	)
	(segment
		(start 120.852692 -227.129086)
		(end 120.891808 -227.151946)
		(width 0.1143)
		(layer "In4.Cu")
		(net "GMI_CPU1_G2_CPU0_G0_TX_DN<9>")
	)
	(segment
		(start 121.360692 -227.961444)
		(end 121.361708 -227.961952)
		(width 0.1143)
		(layer "In4.Cu")
		(net "GMI_CPU1_G2_CPU0_G0_TX_DN<9>")
	)
	(segment
		(start 350.961452 -219.420694)
		(end 348.5515 -215.36152)
		(width 0.14224)
		(layer "In4.Cu")
		(net "GMI_CPU1_G2_CPU0_G0_TX_DN<9>")
	)
	(segment
		(start 123.048522 -215.234012)
		(end 120.53443 -219.543884)
		(width 0.14224)
		(layer "In4.Cu")
		(net "GMI_CPU1_G2_CPU0_G0_TX_DN<9>")
	)
	(segment
		(start 168.16324 -182.468012)
		(end 166.604442 -182.468012)
		(width 0.14224)
		(layer "In4.Cu")
		(net "GMI_CPU1_G2_CPU0_G0_TX_DN<9>")
	)
	(segment
		(start 120.891808 -226.177094)
		(end 120.852692 -226.199954)
		(width 0.1143)
		(layer "In4.Cu")
		(net "GMI_CPU1_G2_CPU0_G0_TX_DN<9>")
	)
	(segment
		(start 146.22907 -196.93509)
		(end 144.859756 -197.349618)
		(width 0.14224)
		(layer "In4.Cu")
		(net "GMI_CPU1_G2_CPU0_G0_TX_DN<9>")
	)
	(segment
		(start 144.859756 -197.349618)
		(end 123.048522 -215.234012)
		(width 0.14224)
		(layer "In4.Cu")
		(net "GMI_CPU1_G2_CPU0_G0_TX_DN<9>")
	)
	(segment
		(start 350.961452 -221.083124)
		(end 350.961452 -219.420694)
		(width 0.14224)
		(layer "In4.Cu")
		(net "GMI_CPU1_G2_CPU0_G0_TX_DN<9>")
	)
	(segment
		(start 350.915732 -221.128844)
		(end 350.961452 -221.083124)
		(width 0.1143)
		(layer "In4.Cu")
		(net "GMI_CPU1_G2_CPU0_G0_TX_DN<9>")
	)
	(segment
		(start 122.48261 -229.83444)
		(end 122.41276 -229.90429)
		(width 0.1143)
		(layer "In4.Cu")
		(net "GMI_CPU1_G2_CPU0_G0_TX_DN<9>")
	)
	(segment
		(start 120.58015 -221.243398)
		(end 120.609614 -221.272862)
		(width 0.1143)
		(layer "In4.Cu")
		(net "GMI_CPU1_G2_CPU0_G0_TX_DN<9>")
	)
	(segment
		(start 306.86756 -183.252872)
		(end 302.892968 -183.252872)
		(width 0.14224)
		(layer "In4.Cu")
		(net "GMI_CPU1_G2_CPU0_G0_TX_DN<9>")
	)
	(segment
		(start 348.5515 -215.36152)
		(end 313.98718 -187.019946)
		(width 0.14224)
		(layer "In4.Cu")
		(net "GMI_CPU1_G2_CPU0_G0_TX_DN<9>")
	)
	(segment
		(start 122.41276 -229.90429)
		(end 122.114818 -229.90429)
		(width 0.1143)
		(layer "In4.Cu")
		(net "GMI_CPU1_G2_CPU0_G0_TX_DN<9>")
	)
	(segment
		(start 166.604442 -182.468012)
		(end 161.749994 -184.208166)
		(width 0.14224)
		(layer "In4.Cu")
		(net "GMI_CPU1_G2_CPU0_G0_TX_DN<9>")
	)
	(segment
		(start 350.915732 -221.423992)
		(end 350.915732 -221.128844)
		(width 0.1143)
		(layer "In4.Cu")
		(net "GMI_CPU1_G2_CPU0_G0_TX_DN<9>")
	)
	(segment
		(start 120.891808 -223.911922)
		(end 120.922288 -223.929702)
		(width 0.1143)
		(layer "In4.Cu")
		(net "GMI_CPU1_G2_CPU0_G0_TX_DN<9>")
	)
	(segment
		(start 120.922288 -224.539302)
		(end 120.891808 -224.557082)
		(width 0.1143)
		(layer "In4.Cu")
		(net "GMI_CPU1_G2_CPU0_G0_TX_DN<9>")
	)
	(segment
		(start 350.573594 -225.54946)
		(end 350.64319 -225.50882)
		(width 0.1143)
		(layer "In4.Cu")
		(net "GMI_CPU1_G2_CPU0_G0_TX_DN<9>")
	)
	(segment
		(start 350.64319 -226.1997)
		(end 350.573594 -226.15906)
		(width 0.1143)
		(layer "In4.Cu")
		(net "GMI_CPU1_G2_CPU0_G0_TX_DN<9>")
	)
	(segment
		(start 350.102424 -227.979986)
		(end 350.134174 -227.961698)
		(width 0.1143)
		(layer "In4.Cu")
		(net "GMI_CPU1_G2_CPU0_G0_TX_DN<9>")
	)
	(segment
		(start 313.98718 -187.019946)
		(end 308.12994 -183.70423)
		(width 0.14224)
		(layer "In4.Cu")
		(net "GMI_CPU1_G2_CPU0_G0_TX_DN<9>")
	)
	(segment
		(start 308.12994 -183.70423)
		(end 306.86756 -183.252872)
		(width 0.14224)
		(layer "In4.Cu")
		(net "GMI_CPU1_G2_CPU0_G0_TX_DN<9>")
	)
	(arc
		(start 349.946468 -228.284278)
		(mid 349.987723 -228.113307)
		(end 350.102424 -227.979986)
		(width 0.1143)
		(layer "In4.Cu")
		(net "GMI_CPU1_G2_CPU0_G0_TX_DN<9>")
	)
	(arc
		(start 350.17329 -227.938838)
		(mid 350.352103 -227.736488)
		(end 350.416622 -227.474272)
		(width 0.1143)
		(layer "In4.Cu")
		(net "GMI_CPU1_G2_CPU0_G0_TX_DN<9>")
	)
	(arc
		(start 349.230442 -229.560628)
		(mid 349.411094 -229.357883)
		(end 349.476314 -229.094284)
		(width 0.1143)
		(layer "In4.Cu")
		(net "GMI_CPU1_G2_CPU0_G0_TX_DN<9>")
	)
	(arc
		(start 120.922288 -223.929702)
		(mid 121.079265 -224.234502)
		(end 120.922288 -224.539302)
		(width 0.1143)
		(layer "In4.Cu")
		(net "GMI_CPU1_G2_CPU0_G0_TX_DN<9>")
	)
	(arc
		(start 120.852692 -222.95993)
		(mid 120.609365 -223.424496)
		(end 120.852692 -223.889062)
		(width 0.1143)
		(layer "In4.Cu")
		(net "GMI_CPU1_G2_CPU0_G0_TX_DN<9>")
	)
	(arc
		(start 350.573594 -222.919036)
		(mid 350.416617 -222.614236)
		(end 350.573594 -222.309436)
		(width 0.1143)
		(layer "In4.Cu")
		(net "GMI_CPU1_G2_CPU0_G0_TX_DN<9>")
	)
	(arc
		(start 350.64319 -223.888808)
		(mid 350.886517 -223.424242)
		(end 350.64319 -222.959676)
		(width 0.1143)
		(layer "In4.Cu")
		(net "GMI_CPU1_G2_CPU0_G0_TX_DN<9>")
	)
	(arc
		(start 350.573594 -226.15906)
		(mid 350.416617 -225.85426)
		(end 350.573594 -225.54946)
		(width 0.1143)
		(layer "In4.Cu")
		(net "GMI_CPU1_G2_CPU0_G0_TX_DN<9>")
	)
	(arc
		(start 350.64319 -225.50882)
		(mid 350.886517 -225.044254)
		(end 350.64319 -224.579688)
		(width 0.1143)
		(layer "In4.Cu")
		(net "GMI_CPU1_G2_CPU0_G0_TX_DN<9>")
	)
	(arc
		(start 350.416622 -227.474272)
		(mid 350.458171 -227.30285)
		(end 350.573594 -227.169472)
		(width 0.1143)
		(layer "In4.Cu")
		(net "GMI_CPU1_G2_CPU0_G0_TX_DN<9>")
	)
	(arc
		(start 120.922288 -222.30969)
		(mid 121.079265 -222.61449)
		(end 120.922288 -222.91929)
		(width 0.1143)
		(layer "In4.Cu")
		(net "GMI_CPU1_G2_CPU0_G0_TX_DN<9>")
	)
	(arc
		(start 121.393458 -227.98024)
		(mid 121.508134 -228.113574)
		(end 121.549414 -228.284532)
		(width 0.1143)
		(layer "In4.Cu")
		(net "GMI_CPU1_G2_CPU0_G0_TX_DN<9>")
	)
	(arc
		(start 122.019568 -229.094538)
		(mid 122.084804 -229.358129)
		(end 122.26544 -229.560882)
		(width 0.1143)
		(layer "In4.Cu")
		(net "GMI_CPU1_G2_CPU0_G0_TX_DN<9>")
	)
	(arc
		(start 350.64319 -227.128832)
		(mid 350.886517 -226.664266)
		(end 350.64319 -226.1997)
		(width 0.1143)
		(layer "In4.Cu")
		(net "GMI_CPU1_G2_CPU0_G0_TX_DN<9>")
	)
	(arc
		(start 350.573594 -224.539048)
		(mid 350.416617 -224.234248)
		(end 350.573594 -223.929448)
		(width 0.1143)
		(layer "In4.Cu")
		(net "GMI_CPU1_G2_CPU0_G0_TX_DN<9>")
	)
	(arc
		(start 120.922288 -227.169726)
		(mid 121.037715 -227.303102)
		(end 121.07926 -227.474526)
		(width 0.1143)
		(layer "In4.Cu")
		(net "GMI_CPU1_G2_CPU0_G0_TX_DN<9>")
	)
	(arc
		(start 121.07926 -227.474526)
		(mid 121.143775 -227.736745)
		(end 121.322592 -227.939092)
		(width 0.1143)
		(layer "In4.Cu")
		(net "GMI_CPU1_G2_CPU0_G0_TX_DN<9>")
	)
	(arc
		(start 349.013272 -229.834186)
		(mid 349.064762 -229.703713)
		(end 349.160592 -229.601268)
		(width 0.1143)
		(layer "In4.Cu")
		(net "GMI_CPU1_G2_CPU0_G0_TX_DN<9>")
	)
	(arc
		(start 122.33529 -229.601522)
		(mid 122.431178 -229.70393)
		(end 122.48261 -229.83444)
		(width 0.1143)
		(layer "In4.Cu")
		(net "GMI_CPU1_G2_CPU0_G0_TX_DN<9>")
	)
	(arc
		(start 121.549414 -228.284532)
		(mid 121.613929 -228.546751)
		(end 121.792746 -228.749098)
		(width 0.1143)
		(layer "In4.Cu")
		(net "GMI_CPU1_G2_CPU0_G0_TX_DN<9>")
	)
	(arc
		(start 120.852692 -226.199954)
		(mid 120.609365 -226.66452)
		(end 120.852692 -227.129086)
		(width 0.1143)
		(layer "In4.Cu")
		(net "GMI_CPU1_G2_CPU0_G0_TX_DN<9>")
	)
	(arc
		(start 120.609614 -221.804484)
		(mid 120.673988 -222.066688)
		(end 120.852692 -222.26905)
		(width 0.1143)
		(layer "In4.Cu")
		(net "GMI_CPU1_G2_CPU0_G0_TX_DN<9>")
	)
	(arc
		(start 120.852692 -224.579942)
		(mid 120.609365 -225.044508)
		(end 120.852692 -225.509074)
		(width 0.1143)
		(layer "In4.Cu")
		(net "GMI_CPU1_G2_CPU0_G0_TX_DN<9>")
	)
	(arc
		(start 120.922288 -225.549714)
		(mid 121.079265 -225.854514)
		(end 120.922288 -226.159314)
		(width 0.1143)
		(layer "In4.Cu")
		(net "GMI_CPU1_G2_CPU0_G0_TX_DN<9>")
	)
	(arc
		(start 350.64319 -222.268796)
		(mid 350.821833 -222.066401)
		(end 350.886268 -221.80423)
		(width 0.1143)
		(layer "In4.Cu")
		(net "GMI_CPU1_G2_CPU0_G0_TX_DN<9>")
	)
	(arc
		(start 349.703136 -228.748844)
		(mid 349.881949 -228.546494)
		(end 349.946468 -228.284278)
		(width 0.1143)
		(layer "In4.Cu")
		(net "GMI_CPU1_G2_CPU0_G0_TX_DN<9>")
	)
	(arc
		(start 121.862342 -228.789738)
		(mid 121.977769 -228.923114)
		(end 122.019314 -229.094538)
		(width 0.1143)
		(layer "In4.Cu")
		(net "GMI_CPU1_G2_CPU0_G0_TX_DN<9>")
	)
	(arc
		(start 349.476568 -229.094284)
		(mid 349.518117 -228.922862)
		(end 349.63354 -228.789484)
		(width 0.1143)
		(layer "In4.Cu")
		(net "GMI_CPU1_G2_CPU0_G0_TX_DN<9>")
	)
	(segment
		(start 352.668078 -228.550216)
		(end 352.201226 -228.284278)
		(width 0.12954)
		(layer "F.Cu")
		(net "GMI_CPU1_G2_CPU0_G0_TX_DN<8>")
	)
	(segment
		(start 118.827804 -228.55047)
		(end 119.294656 -228.284532)
		(width 0.12954)
		(layer "F.Cu")
		(net "GMI_CPU1_G2_CPU0_G0_TX_DN<8>")
	)
	(segment
		(start 351.833434 -228.214428)
		(end 351.903284 -228.284278)
		(width 0.1143)
		(layer "In4.Cu")
		(net "GMI_CPU1_G2_CPU0_G0_TX_DN<8>")
	)
	(segment
		(start 352.016568 -227.960428)
		(end 352.014282 -227.961698)
		(width 0.1143)
		(layer "In4.Cu")
		(net "GMI_CPU1_G2_CPU0_G0_TX_DN<8>")
	)
	(segment
		(start 166.154354 -180.58892)
		(end 167.675306 -180.58892)
		(width 0.14224)
		(layer "In4.Cu")
		(net "GMI_CPU1_G2_CPU0_G0_TX_DN<8>")
	)
	(segment
		(start 119.4816 -227.961952)
		(end 119.479314 -227.960682)
		(width 0.1143)
		(layer "In4.Cu")
		(net "GMI_CPU1_G2_CPU0_G0_TX_DN<8>")
	)
	(segment
		(start 152.080722 -189.35446)
		(end 155.664916 -186.415172)
		(width 0.14224)
		(layer "In4.Cu")
		(net "GMI_CPU1_G2_CPU0_G0_TX_DN<8>")
	)
	(segment
		(start 119.063262 -223.944434)
		(end 119.04345 -223.93021)
		(width 0.1143)
		(layer "In4.Cu")
		(net "GMI_CPU1_G2_CPU0_G0_TX_DN<8>")
	)
	(segment
		(start 352.523298 -225.50882)
		(end 352.484182 -225.53168)
		(width 0.1143)
		(layer "In4.Cu")
		(net "GMI_CPU1_G2_CPU0_G0_TX_DN<8>")
	)
	(segment
		(start 352.452432 -222.918528)
		(end 352.484182 -222.936816)
		(width 0.1143)
		(layer "In4.Cu")
		(net "GMI_CPU1_G2_CPU0_G0_TX_DN<8>")
	)
	(segment
		(start 144.222216 -195.402962)
		(end 144.985994 -195.171314)
		(width 0.14224)
		(layer "In4.Cu")
		(net "GMI_CPU1_G2_CPU0_G0_TX_DN<8>")
	)
	(segment
		(start 119.04345 -223.93021)
		(end 118.972584 -223.889062)
		(width 0.1143)
		(layer "In4.Cu")
		(net "GMI_CPU1_G2_CPU0_G0_TX_DN<8>")
	)
	(segment
		(start 118.69039 -221.129098)
		(end 118.64467 -221.083378)
		(width 0.1143)
		(layer "In4.Cu")
		(net "GMI_CPU1_G2_CPU0_G0_TX_DN<8>")
	)
	(segment
		(start 146.953986 -193.557906)
		(end 146.953732 -193.557906)
		(width 0.14224)
		(layer "In4.Cu")
		(net "GMI_CPU1_G2_CPU0_G0_TX_DN<8>")
	)
	(segment
		(start 152.080468 -189.353952)
		(end 152.080722 -189.35446)
		(width 0.14224)
		(layer "In4.Cu")
		(net "GMI_CPU1_G2_CPU0_G0_TX_DN<8>")
	)
	(segment
		(start 352.484182 -225.53168)
		(end 352.452432 -225.549968)
		(width 0.1143)
		(layer "In4.Cu")
		(net "GMI_CPU1_G2_CPU0_G0_TX_DN<8>")
	)
	(segment
		(start 352.523298 -227.128832)
		(end 352.471482 -227.159058)
		(width 0.1143)
		(layer "In4.Cu")
		(net "GMI_CPU1_G2_CPU0_G0_TX_DN<8>")
	)
	(segment
		(start 119.294656 -228.284532)
		(end 119.592598 -228.284532)
		(width 0.1143)
		(layer "In4.Cu")
		(net "GMI_CPU1_G2_CPU0_G0_TX_DN<8>")
	)
	(segment
		(start 119.0117 -225.531934)
		(end 118.972584 -225.509074)
		(width 0.1143)
		(layer "In4.Cu")
		(net "GMI_CPU1_G2_CPU0_G0_TX_DN<8>")
	)
	(segment
		(start 352.805492 -221.426024)
		(end 352.766376 -221.46514)
		(width 0.1143)
		(layer "In4.Cu")
		(net "GMI_CPU1_G2_CPU0_G0_TX_DN<8>")
	)
	(segment
		(start 349.845376 -213.888066)
		(end 352.851212 -218.951048)
		(width 0.14224)
		(layer "In4.Cu")
		(net "GMI_CPU1_G2_CPU0_G0_TX_DN<8>")
	)
	(segment
		(start 155.664916 -186.415172)
		(end 160.153858 -182.734458)
		(width 0.14224)
		(layer "In4.Cu")
		(net "GMI_CPU1_G2_CPU0_G0_TX_DN<8>")
	)
	(segment
		(start 352.851212 -221.083124)
		(end 352.805492 -221.128844)
		(width 0.1143)
		(layer "In4.Cu")
		(net "GMI_CPU1_G2_CPU0_G0_TX_DN<8>")
	)
	(segment
		(start 167.675306 -180.58892)
		(end 302.899064 -181.377336)
		(width 0.14224)
		(layer "In4.Cu")
		(net "GMI_CPU1_G2_CPU0_G0_TX_DN<8>")
	)
	(segment
		(start 352.014282 -227.961698)
		(end 352.01352 -227.962206)
		(width 0.1143)
		(layer "In4.Cu")
		(net "GMI_CPU1_G2_CPU0_G0_TX_DN<8>")
	)
	(segment
		(start 119.0117 -226.177094)
		(end 119.04345 -226.158806)
		(width 0.1143)
		(layer "In4.Cu")
		(net "GMI_CPU1_G2_CPU0_G0_TX_DN<8>")
	)
	(segment
		(start 118.972584 -224.579942)
		(end 119.0117 -224.557082)
		(width 0.1143)
		(layer "In4.Cu")
		(net "GMI_CPU1_G2_CPU0_G0_TX_DN<8>")
	)
	(segment
		(start 144.985994 -195.171314)
		(end 146.953986 -193.557906)
		(width 0.14224)
		(layer "In4.Cu")
		(net "GMI_CPU1_G2_CPU0_G0_TX_DN<8>")
	)
	(segment
		(start 308.876446 -181.953154)
		(end 315.40704 -185.64987)
		(width 0.14224)
		(layer "In4.Cu")
		(net "GMI_CPU1_G2_CPU0_G0_TX_DN<8>")
	)
	(segment
		(start 118.729506 -221.804484)
		(end 118.729506 -221.465394)
		(width 0.1143)
		(layer "In4.Cu")
		(net "GMI_CPU1_G2_CPU0_G0_TX_DN<8>")
	)
	(segment
		(start 352.452432 -226.158552)
		(end 352.484182 -226.17684)
		(width 0.1143)
		(layer "In4.Cu")
		(net "GMI_CPU1_G2_CPU0_G0_TX_DN<8>")
	)
	(segment
		(start 315.40704 -185.64987)
		(end 349.845376 -213.888066)
		(width 0.14224)
		(layer "In4.Cu")
		(net "GMI_CPU1_G2_CPU0_G0_TX_DN<8>")
	)
	(segment
		(start 119.482362 -227.96246)
		(end 119.4816 -227.961952)
		(width 0.1143)
		(layer "In4.Cu")
		(net "GMI_CPU1_G2_CPU0_G0_TX_DN<8>")
	)
	(segment
		(start 119.0244 -227.159312)
		(end 118.972584 -227.129086)
		(width 0.1143)
		(layer "In4.Cu")
		(net "GMI_CPU1_G2_CPU0_G0_TX_DN<8>")
	)
	(segment
		(start 119.0117 -222.93707)
		(end 119.04345 -222.918782)
		(width 0.1143)
		(layer "In4.Cu")
		(net "GMI_CPU1_G2_CPU0_G0_TX_DN<8>")
	)
	(segment
		(start 352.452432 -223.929956)
		(end 352.43262 -223.94418)
		(width 0.1143)
		(layer "In4.Cu")
		(net "GMI_CPU1_G2_CPU0_G0_TX_DN<8>")
	)
	(segment
		(start 118.729506 -221.465394)
		(end 118.69039 -221.426278)
		(width 0.1143)
		(layer "In4.Cu")
		(net "GMI_CPU1_G2_CPU0_G0_TX_DN<8>")
	)
	(segment
		(start 352.43262 -224.524316)
		(end 352.452432 -224.53854)
		(width 0.1143)
		(layer "In4.Cu")
		(net "GMI_CPU1_G2_CPU0_G0_TX_DN<8>")
	)
	(segment
		(start 118.64467 -221.05493)
		(end 118.64467 -219.05468)
		(width 0.14224)
		(layer "In4.Cu")
		(net "GMI_CPU1_G2_CPU0_G0_TX_DN<8>")
	)
	(segment
		(start 352.766376 -221.46514)
		(end 352.766376 -221.80423)
		(width 0.1143)
		(layer "In4.Cu")
		(net "GMI_CPU1_G2_CPU0_G0_TX_DN<8>")
	)
	(segment
		(start 118.972584 -222.95993)
		(end 119.0117 -222.93707)
		(width 0.1143)
		(layer "In4.Cu")
		(net "GMI_CPU1_G2_CPU0_G0_TX_DN<8>")
	)
	(segment
		(start 146.953732 -193.557906)
		(end 152.080468 -189.353952)
		(width 0.14224)
		(layer "In4.Cu")
		(net "GMI_CPU1_G2_CPU0_G0_TX_DN<8>")
	)
	(segment
		(start 352.283776 -227.483924)
		(end 352.283776 -227.49637)
		(width 0.1143)
		(layer "In4.Cu")
		(net "GMI_CPU1_G2_CPU0_G0_TX_DN<8>")
	)
	(segment
		(start 119.51335 -227.98024)
		(end 119.482362 -227.96246)
		(width 0.1143)
		(layer "In4.Cu")
		(net "GMI_CPU1_G2_CPU0_G0_TX_DN<8>")
	)
	(segment
		(start 119.04345 -225.550222)
		(end 119.0117 -225.531934)
		(width 0.1143)
		(layer "In4.Cu")
		(net "GMI_CPU1_G2_CPU0_G0_TX_DN<8>")
	)
	(segment
		(start 121.658888 -213.903814)
		(end 144.222216 -195.402962)
		(width 0.14224)
		(layer "In4.Cu")
		(net "GMI_CPU1_G2_CPU0_G0_TX_DN<8>")
	)
	(segment
		(start 119.0117 -224.557082)
		(end 119.04345 -224.538794)
		(width 0.1143)
		(layer "In4.Cu")
		(net "GMI_CPU1_G2_CPU0_G0_TX_DN<8>")
	)
	(segment
		(start 352.484182 -226.17684)
		(end 352.523298 -226.1997)
		(width 0.1143)
		(layer "In4.Cu")
		(net "GMI_CPU1_G2_CPU0_G0_TX_DN<8>")
	)
	(segment
		(start 160.153858 -182.734458)
		(end 166.154354 -180.58892)
		(width 0.14224)
		(layer "In4.Cu")
		(net "GMI_CPU1_G2_CPU0_G0_TX_DN<8>")
	)
	(segment
		(start 352.851212 -218.951048)
		(end 352.851212 -221.083124)
		(width 0.14224)
		(layer "In4.Cu")
		(net "GMI_CPU1_G2_CPU0_G0_TX_DN<8>")
	)
	(segment
		(start 351.903284 -228.284278)
		(end 352.201226 -228.284278)
		(width 0.1143)
		(layer "In4.Cu")
		(net "GMI_CPU1_G2_CPU0_G0_TX_DN<8>")
	)
	(segment
		(start 352.484182 -222.936816)
		(end 352.523298 -222.959676)
		(width 0.1143)
		(layer "In4.Cu")
		(net "GMI_CPU1_G2_CPU0_G0_TX_DN<8>")
	)
	(segment
		(start 119.04345 -224.538794)
		(end 119.063262 -224.52457)
		(width 0.1143)
		(layer "In4.Cu")
		(net "GMI_CPU1_G2_CPU0_G0_TX_DN<8>")
	)
	(segment
		(start 118.64467 -219.05468)
		(end 121.658888 -213.903814)
		(width 0.14224)
		(layer "In4.Cu")
		(net "GMI_CPU1_G2_CPU0_G0_TX_DN<8>")
	)
	(segment
		(start 352.452432 -224.53854)
		(end 352.484182 -224.556828)
		(width 0.1143)
		(layer "In4.Cu")
		(net "GMI_CPU1_G2_CPU0_G0_TX_DN<8>")
	)
	(segment
		(start 118.972584 -226.199954)
		(end 119.0117 -226.177094)
		(width 0.1143)
		(layer "In4.Cu")
		(net "GMI_CPU1_G2_CPU0_G0_TX_DN<8>")
	)
	(segment
		(start 119.592598 -228.284532)
		(end 119.662448 -228.214682)
		(width 0.1143)
		(layer "In4.Cu")
		(net "GMI_CPU1_G2_CPU0_G0_TX_DN<8>")
	)
	(segment
		(start 352.523298 -223.888808)
		(end 352.452432 -223.929956)
		(width 0.1143)
		(layer "In4.Cu")
		(net "GMI_CPU1_G2_CPU0_G0_TX_DN<8>")
	)
	(segment
		(start 119.04345 -222.310198)
		(end 118.972584 -222.26905)
		(width 0.1143)
		(layer "In4.Cu")
		(net "GMI_CPU1_G2_CPU0_G0_TX_DN<8>")
	)
	(segment
		(start 119.212106 -227.496624)
		(end 119.212106 -227.484178)
		(width 0.1143)
		(layer "In4.Cu")
		(net "GMI_CPU1_G2_CPU0_G0_TX_DN<8>")
	)
	(segment
		(start 307.267102 -181.377336)
		(end 308.876446 -181.953154)
		(width 0.14224)
		(layer "In4.Cu")
		(net "GMI_CPU1_G2_CPU0_G0_TX_DN<8>")
	)
	(segment
		(start 118.64467 -221.083378)
		(end 118.64467 -221.05493)
		(width 0.1143)
		(layer "In4.Cu")
		(net "GMI_CPU1_G2_CPU0_G0_TX_DN<8>")
	)
	(segment
		(start 352.805492 -221.128844)
		(end 352.805492 -221.426024)
		(width 0.1143)
		(layer "In4.Cu")
		(net "GMI_CPU1_G2_CPU0_G0_TX_DN<8>")
	)
	(segment
		(start 352.523298 -222.268796)
		(end 352.452432 -222.309944)
		(width 0.1143)
		(layer "In4.Cu")
		(net "GMI_CPU1_G2_CPU0_G0_TX_DN<8>")
	)
	(segment
		(start 352.01352 -227.962206)
		(end 351.982532 -227.979986)
		(width 0.1143)
		(layer "In4.Cu")
		(net "GMI_CPU1_G2_CPU0_G0_TX_DN<8>")
	)
	(segment
		(start 118.69039 -221.426278)
		(end 118.69039 -221.129098)
		(width 0.1143)
		(layer "In4.Cu")
		(net "GMI_CPU1_G2_CPU0_G0_TX_DN<8>")
	)
	(segment
		(start 302.899064 -181.377336)
		(end 307.267102 -181.377336)
		(width 0.14224)
		(layer "In4.Cu")
		(net "GMI_CPU1_G2_CPU0_G0_TX_DN<8>")
	)
	(segment
		(start 352.484182 -224.556828)
		(end 352.523298 -224.579688)
		(width 0.1143)
		(layer "In4.Cu")
		(net "GMI_CPU1_G2_CPU0_G0_TX_DN<8>")
	)
	(arc
		(start 118.972584 -227.129086)
		(mid 118.729257 -226.66452)
		(end 118.972584 -226.199954)
		(width 0.1143)
		(layer "In4.Cu")
		(net "GMI_CPU1_G2_CPU0_G0_TX_DN<8>")
	)
	(arc
		(start 352.43262 -223.94418)
		(mid 352.283906 -224.234248)
		(end 352.43262 -224.524316)
		(width 0.1143)
		(layer "In4.Cu")
		(net "GMI_CPU1_G2_CPU0_G0_TX_DN<8>")
	)
	(arc
		(start 118.972584 -222.26905)
		(mid 118.793926 -222.06665)
		(end 118.729506 -221.804484)
		(width 0.1143)
		(layer "In4.Cu")
		(net "GMI_CPU1_G2_CPU0_G0_TX_DN<8>")
	)
	(arc
		(start 352.452432 -225.549968)
		(mid 352.300843 -225.85426)
		(end 352.452432 -226.158552)
		(width 0.1143)
		(layer "In4.Cu")
		(net "GMI_CPU1_G2_CPU0_G0_TX_DN<8>")
	)
	(arc
		(start 352.471482 -227.159058)
		(mid 352.33405 -227.296317)
		(end 352.283776 -227.483924)
		(width 0.1143)
		(layer "In4.Cu")
		(net "GMI_CPU1_G2_CPU0_G0_TX_DN<8>")
	)
	(arc
		(start 118.972584 -223.889062)
		(mid 118.729257 -223.424496)
		(end 118.972584 -222.95993)
		(width 0.1143)
		(layer "In4.Cu")
		(net "GMI_CPU1_G2_CPU0_G0_TX_DN<8>")
	)
	(arc
		(start 119.662448 -228.214682)
		(mid 119.610399 -228.083163)
		(end 119.51335 -227.98024)
		(width 0.1143)
		(layer "In4.Cu")
		(net "GMI_CPU1_G2_CPU0_G0_TX_DN<8>")
	)
	(arc
		(start 118.972584 -225.509074)
		(mid 118.729257 -225.044508)
		(end 118.972584 -224.579942)
		(width 0.1143)
		(layer "In4.Cu")
		(net "GMI_CPU1_G2_CPU0_G0_TX_DN<8>")
	)
	(arc
		(start 351.982532 -227.979986)
		(mid 351.885397 -228.082855)
		(end 351.833434 -228.214428)
		(width 0.1143)
		(layer "In4.Cu")
		(net "GMI_CPU1_G2_CPU0_G0_TX_DN<8>")
	)
	(arc
		(start 119.212106 -227.484178)
		(mid 119.1618 -227.29659)
		(end 119.0244 -227.159312)
		(width 0.1143)
		(layer "In4.Cu")
		(net "GMI_CPU1_G2_CPU0_G0_TX_DN<8>")
	)
	(arc
		(start 352.283776 -227.49637)
		(mid 352.21219 -227.7641)
		(end 352.016568 -227.960428)
		(width 0.1143)
		(layer "In4.Cu")
		(net "GMI_CPU1_G2_CPU0_G0_TX_DN<8>")
	)
	(arc
		(start 352.523298 -226.1997)
		(mid 352.766625 -226.664266)
		(end 352.523298 -227.128832)
		(width 0.1143)
		(layer "In4.Cu")
		(net "GMI_CPU1_G2_CPU0_G0_TX_DN<8>")
	)
	(arc
		(start 119.063262 -224.52457)
		(mid 119.211976 -224.234502)
		(end 119.063262 -223.944434)
		(width 0.1143)
		(layer "In4.Cu")
		(net "GMI_CPU1_G2_CPU0_G0_TX_DN<8>")
	)
	(arc
		(start 352.523298 -224.579688)
		(mid 352.766625 -225.044254)
		(end 352.523298 -225.50882)
		(width 0.1143)
		(layer "In4.Cu")
		(net "GMI_CPU1_G2_CPU0_G0_TX_DN<8>")
	)
	(arc
		(start 119.04345 -226.158806)
		(mid 119.195039 -225.854514)
		(end 119.04345 -225.550222)
		(width 0.1143)
		(layer "In4.Cu")
		(net "GMI_CPU1_G2_CPU0_G0_TX_DN<8>")
	)
	(arc
		(start 119.479314 -227.960682)
		(mid 119.28364 -227.764384)
		(end 119.212106 -227.496624)
		(width 0.1143)
		(layer "In4.Cu")
		(net "GMI_CPU1_G2_CPU0_G0_TX_DN<8>")
	)
	(arc
		(start 352.452432 -222.309944)
		(mid 352.300843 -222.614236)
		(end 352.452432 -222.918528)
		(width 0.1143)
		(layer "In4.Cu")
		(net "GMI_CPU1_G2_CPU0_G0_TX_DN<8>")
	)
	(arc
		(start 119.04345 -222.918782)
		(mid 119.195039 -222.61449)
		(end 119.04345 -222.310198)
		(width 0.1143)
		(layer "In4.Cu")
		(net "GMI_CPU1_G2_CPU0_G0_TX_DN<8>")
	)
	(arc
		(start 352.523298 -222.959676)
		(mid 352.766625 -223.424242)
		(end 352.523298 -223.888808)
		(width 0.1143)
		(layer "In4.Cu")
		(net "GMI_CPU1_G2_CPU0_G0_TX_DN<8>")
	)
	(arc
		(start 352.766376 -221.80423)
		(mid 352.701929 -222.066382)
		(end 352.523298 -222.268796)
		(width 0.1143)
		(layer "In4.Cu")
		(net "GMI_CPU1_G2_CPU0_G0_TX_DN<8>")
	)
	(segment
		(start 118.827804 -226.930458)
		(end 119.294656 -226.66452)
		(width 0.12954)
		(layer "F.Cu")
		(net "GMI_CPU1_G2_CPU0_G0_TX_DN<7>")
	)
	(segment
		(start 352.668078 -226.930204)
		(end 352.201226 -226.664266)
		(width 0.12954)
		(layer "F.Cu")
		(net "GMI_CPU1_G2_CPU0_G0_TX_DN<7>")
	)
	(segment
		(start 351.513648 -222.309436)
		(end 351.583244 -222.268796)
		(width 0.1143)
		(layer "In4.Cu")
		(net "GMI_CPU1_G2_CPU0_G0_TX_DN<7>")
	)
	(segment
		(start 145.773648 -195.91655)
		(end 144.724628 -196.23405)
		(width 0.14224)
		(layer "In4.Cu")
		(net "GMI_CPU1_G2_CPU0_G0_TX_DN<7>")
	)
	(segment
		(start 119.951754 -223.911922)
		(end 119.982234 -223.929702)
		(width 0.1143)
		(layer "In4.Cu")
		(net "GMI_CPU1_G2_CPU0_G0_TX_DN<7>")
	)
	(segment
		(start 119.58955 -221.05493)
		(end 119.58955 -221.083378)
		(width 0.1143)
		(layer "In4.Cu")
		(net "GMI_CPU1_G2_CPU0_G0_TX_DN<7>")
	)
	(segment
		(start 160.978342 -183.449214)
		(end 145.773648 -195.91655)
		(width 0.14224)
		(layer "In4.Cu")
		(net "GMI_CPU1_G2_CPU0_G0_TX_DN<7>")
	)
	(segment
		(start 351.583244 -226.1997)
		(end 351.513648 -226.15906)
		(width 0.1143)
		(layer "In4.Cu")
		(net "GMI_CPU1_G2_CPU0_G0_TX_DN<7>")
	)
	(segment
		(start 351.826322 -221.460314)
		(end 351.860612 -221.426024)
		(width 0.1143)
		(layer "In4.Cu")
		(net "GMI_CPU1_G2_CPU0_G0_TX_DN<7>")
	)
	(segment
		(start 119.951754 -222.93707)
		(end 119.912638 -222.95993)
		(width 0.1143)
		(layer "In4.Cu")
		(net "GMI_CPU1_G2_CPU0_G0_TX_DN<7>")
	)
	(segment
		(start 351.583244 -224.579688)
		(end 351.513648 -224.539048)
		(width 0.1143)
		(layer "In4.Cu")
		(net "GMI_CPU1_G2_CPU0_G0_TX_DN<7>")
	)
	(segment
		(start 119.63527 -221.129098)
		(end 119.63527 -221.426278)
		(width 0.1143)
		(layer "In4.Cu")
		(net "GMI_CPU1_G2_CPU0_G0_TX_DN<7>")
	)
	(segment
		(start 119.58955 -219.304362)
		(end 119.58955 -221.05493)
		(width 0.14224)
		(layer "In4.Cu")
		(net "GMI_CPU1_G2_CPU0_G0_TX_DN<7>")
	)
	(segment
		(start 119.912638 -222.26905)
		(end 119.982234 -222.30969)
		(width 0.1143)
		(layer "In4.Cu")
		(net "GMI_CPU1_G2_CPU0_G0_TX_DN<7>")
	)
	(segment
		(start 119.951754 -225.531934)
		(end 119.982234 -225.549714)
		(width 0.1143)
		(layer "In4.Cu")
		(net "GMI_CPU1_G2_CPU0_G0_TX_DN<7>")
	)
	(segment
		(start 119.912638 -225.509074)
		(end 119.951754 -225.531934)
		(width 0.1143)
		(layer "In4.Cu")
		(net "GMI_CPU1_G2_CPU0_G0_TX_DN<7>")
	)
	(segment
		(start 119.592598 -226.66452)
		(end 119.294656 -226.66452)
		(width 0.1143)
		(layer "In4.Cu")
		(net "GMI_CPU1_G2_CPU0_G0_TX_DN<7>")
	)
	(segment
		(start 349.223584 -214.667084)
		(end 314.625482 -186.298586)
		(width 0.14224)
		(layer "In4.Cu")
		(net "GMI_CPU1_G2_CPU0_G0_TX_DN<7>")
	)
	(segment
		(start 352.201226 -226.664266)
		(end 351.903284 -226.664266)
		(width 0.1143)
		(layer "In4.Cu")
		(net "GMI_CPU1_G2_CPU0_G0_TX_DN<7>")
	)
	(segment
		(start 122.348244 -214.582248)
		(end 119.58955 -219.304362)
		(width 0.14224)
		(layer "In4.Cu")
		(net "GMI_CPU1_G2_CPU0_G0_TX_DN<7>")
	)
	(segment
		(start 302.896016 -182.311548)
		(end 167.82796 -181.524402)
		(width 0.14224)
		(layer "In4.Cu")
		(net "GMI_CPU1_G2_CPU0_G0_TX_DN<7>")
	)
	(segment
		(start 307.086 -182.311548)
		(end 302.896016 -182.311548)
		(width 0.14224)
		(layer "In4.Cu")
		(net "GMI_CPU1_G2_CPU0_G0_TX_DN<7>")
	)
	(segment
		(start 119.66956 -221.460568)
		(end 119.66956 -221.804484)
		(width 0.1143)
		(layer "In4.Cu")
		(net "GMI_CPU1_G2_CPU0_G0_TX_DN<7>")
	)
	(segment
		(start 119.982234 -222.91929)
		(end 119.951754 -222.93707)
		(width 0.1143)
		(layer "In4.Cu")
		(net "GMI_CPU1_G2_CPU0_G0_TX_DN<7>")
	)
	(segment
		(start 166.362126 -181.524402)
		(end 160.978342 -183.449214)
		(width 0.14224)
		(layer "In4.Cu")
		(net "GMI_CPU1_G2_CPU0_G0_TX_DN<7>")
	)
	(segment
		(start 308.433216 -182.793132)
		(end 307.086 -182.311548)
		(width 0.14224)
		(layer "In4.Cu")
		(net "GMI_CPU1_G2_CPU0_G0_TX_DN<7>")
	)
	(segment
		(start 119.63527 -221.426278)
		(end 119.66956 -221.460568)
		(width 0.1143)
		(layer "In4.Cu")
		(net "GMI_CPU1_G2_CPU0_G0_TX_DN<7>")
	)
	(segment
		(start 119.675402 -226.581716)
		(end 119.592598 -226.66452)
		(width 0.1143)
		(layer "In4.Cu")
		(net "GMI_CPU1_G2_CPU0_G0_TX_DN<7>")
	)
	(segment
		(start 119.912638 -223.889062)
		(end 119.951754 -223.911922)
		(width 0.1143)
		(layer "In4.Cu")
		(net "GMI_CPU1_G2_CPU0_G0_TX_DN<7>")
	)
	(segment
		(start 314.625482 -186.298586)
		(end 308.433216 -182.793132)
		(width 0.14224)
		(layer "In4.Cu")
		(net "GMI_CPU1_G2_CPU0_G0_TX_DN<7>")
	)
	(segment
		(start 351.906332 -219.185998)
		(end 349.223584 -214.667084)
		(width 0.14224)
		(layer "In4.Cu")
		(net "GMI_CPU1_G2_CPU0_G0_TX_DN<7>")
	)
	(segment
		(start 351.583244 -222.959676)
		(end 351.513648 -222.919036)
		(width 0.1143)
		(layer "In4.Cu")
		(net "GMI_CPU1_G2_CPU0_G0_TX_DN<7>")
	)
	(segment
		(start 119.951754 -224.557082)
		(end 119.912638 -224.579942)
		(width 0.1143)
		(layer "In4.Cu")
		(net "GMI_CPU1_G2_CPU0_G0_TX_DN<7>")
	)
	(segment
		(start 351.513648 -223.929448)
		(end 351.583244 -223.888808)
		(width 0.1143)
		(layer "In4.Cu")
		(net "GMI_CPU1_G2_CPU0_G0_TX_DN<7>")
	)
	(segment
		(start 119.982234 -224.539302)
		(end 119.951754 -224.557082)
		(width 0.1143)
		(layer "In4.Cu")
		(net "GMI_CPU1_G2_CPU0_G0_TX_DN<7>")
	)
	(segment
		(start 351.513648 -225.54946)
		(end 351.583244 -225.50882)
		(width 0.1143)
		(layer "In4.Cu")
		(net "GMI_CPU1_G2_CPU0_G0_TX_DN<7>")
	)
	(segment
		(start 119.951754 -226.177094)
		(end 119.912638 -226.199954)
		(width 0.1143)
		(layer "In4.Cu")
		(net "GMI_CPU1_G2_CPU0_G0_TX_DN<7>")
	)
	(segment
		(start 351.903284 -226.664266)
		(end 351.82048 -226.581462)
		(width 0.1143)
		(layer "In4.Cu")
		(net "GMI_CPU1_G2_CPU0_G0_TX_DN<7>")
	)
	(segment
		(start 119.982234 -226.159314)
		(end 119.951754 -226.177094)
		(width 0.1143)
		(layer "In4.Cu")
		(net "GMI_CPU1_G2_CPU0_G0_TX_DN<7>")
	)
	(segment
		(start 351.826322 -221.80423)
		(end 351.826322 -221.460314)
		(width 0.1143)
		(layer "In4.Cu")
		(net "GMI_CPU1_G2_CPU0_G0_TX_DN<7>")
	)
	(segment
		(start 351.860612 -221.128844)
		(end 351.906332 -221.083124)
		(width 0.1143)
		(layer "In4.Cu")
		(net "GMI_CPU1_G2_CPU0_G0_TX_DN<7>")
	)
	(segment
		(start 167.82796 -181.524402)
		(end 166.362126 -181.524402)
		(width 0.14224)
		(layer "In4.Cu")
		(net "GMI_CPU1_G2_CPU0_G0_TX_DN<7>")
	)
	(segment
		(start 144.724628 -196.23405)
		(end 122.348244 -214.582248)
		(width 0.14224)
		(layer "In4.Cu")
		(net "GMI_CPU1_G2_CPU0_G0_TX_DN<7>")
	)
	(segment
		(start 351.860612 -221.426024)
		(end 351.860612 -221.128844)
		(width 0.1143)
		(layer "In4.Cu")
		(net "GMI_CPU1_G2_CPU0_G0_TX_DN<7>")
	)
	(segment
		(start 119.58955 -221.083378)
		(end 119.63527 -221.129098)
		(width 0.1143)
		(layer "In4.Cu")
		(net "GMI_CPU1_G2_CPU0_G0_TX_DN<7>")
	)
	(segment
		(start 351.906332 -221.083124)
		(end 351.906332 -219.185998)
		(width 0.14224)
		(layer "In4.Cu")
		(net "GMI_CPU1_G2_CPU0_G0_TX_DN<7>")
	)
	(arc
		(start 119.912638 -226.199954)
		(mid 119.760651 -226.356462)
		(end 119.679212 -226.558856)
		(width 0.1143)
		(layer "In4.Cu")
		(net "GMI_CPU1_G2_CPU0_G0_TX_DN<7>")
	)
	(arc
		(start 119.912638 -224.579942)
		(mid 119.669311 -225.044508)
		(end 119.912638 -225.509074)
		(width 0.1143)
		(layer "In4.Cu")
		(net "GMI_CPU1_G2_CPU0_G0_TX_DN<7>")
	)
	(arc
		(start 119.66956 -221.804484)
		(mid 119.733934 -222.066688)
		(end 119.912638 -222.26905)
		(width 0.1143)
		(layer "In4.Cu")
		(net "GMI_CPU1_G2_CPU0_G0_TX_DN<7>")
	)
	(arc
		(start 351.513648 -224.539048)
		(mid 351.356671 -224.234248)
		(end 351.513648 -223.929448)
		(width 0.1143)
		(layer "In4.Cu")
		(net "GMI_CPU1_G2_CPU0_G0_TX_DN<7>")
	)
	(arc
		(start 351.513648 -222.919036)
		(mid 351.356671 -222.614236)
		(end 351.513648 -222.309436)
		(width 0.1143)
		(layer "In4.Cu")
		(net "GMI_CPU1_G2_CPU0_G0_TX_DN<7>")
	)
	(arc
		(start 351.81667 -226.558602)
		(mid 351.735237 -226.356204)
		(end 351.583244 -226.1997)
		(width 0.1143)
		(layer "In4.Cu")
		(net "GMI_CPU1_G2_CPU0_G0_TX_DN<7>")
	)
	(arc
		(start 119.982234 -223.929702)
		(mid 120.139211 -224.234502)
		(end 119.982234 -224.539302)
		(width 0.1143)
		(layer "In4.Cu")
		(net "GMI_CPU1_G2_CPU0_G0_TX_DN<7>")
	)
	(arc
		(start 119.679212 -226.558856)
		(mid 119.677189 -226.570266)
		(end 119.675402 -226.581716)
		(width 0.1143)
		(layer "In4.Cu")
		(net "GMI_CPU1_G2_CPU0_G0_TX_DN<7>")
	)
	(arc
		(start 351.583244 -225.50882)
		(mid 351.826571 -225.044254)
		(end 351.583244 -224.579688)
		(width 0.1143)
		(layer "In4.Cu")
		(net "GMI_CPU1_G2_CPU0_G0_TX_DN<7>")
	)
	(arc
		(start 119.912638 -222.95993)
		(mid 119.669311 -223.424496)
		(end 119.912638 -223.889062)
		(width 0.1143)
		(layer "In4.Cu")
		(net "GMI_CPU1_G2_CPU0_G0_TX_DN<7>")
	)
	(arc
		(start 351.583244 -223.888808)
		(mid 351.826571 -223.424242)
		(end 351.583244 -222.959676)
		(width 0.1143)
		(layer "In4.Cu")
		(net "GMI_CPU1_G2_CPU0_G0_TX_DN<7>")
	)
	(arc
		(start 351.513648 -226.15906)
		(mid 351.356671 -225.85426)
		(end 351.513648 -225.54946)
		(width 0.1143)
		(layer "In4.Cu")
		(net "GMI_CPU1_G2_CPU0_G0_TX_DN<7>")
	)
	(arc
		(start 351.583244 -222.268796)
		(mid 351.761887 -222.066401)
		(end 351.826322 -221.80423)
		(width 0.1143)
		(layer "In4.Cu")
		(net "GMI_CPU1_G2_CPU0_G0_TX_DN<7>")
	)
	(arc
		(start 119.982234 -222.30969)
		(mid 120.139211 -222.61449)
		(end 119.982234 -222.91929)
		(width 0.1143)
		(layer "In4.Cu")
		(net "GMI_CPU1_G2_CPU0_G0_TX_DN<7>")
	)
	(arc
		(start 119.982234 -225.549714)
		(mid 120.139211 -225.854514)
		(end 119.982234 -226.159314)
		(width 0.1143)
		(layer "In4.Cu")
		(net "GMI_CPU1_G2_CPU0_G0_TX_DN<7>")
	)
	(arc
		(start 351.82048 -226.581462)
		(mid 351.818692 -226.570013)
		(end 351.81667 -226.558602)
		(width 0.1143)
		(layer "In4.Cu")
		(net "GMI_CPU1_G2_CPU0_G0_TX_DN<7>")
	)
	(segment
		(start 352.668078 -230.169974)
		(end 352.201226 -229.904036)
		(width 0.12954)
		(layer "F.Cu")
		(net "GMI_CPU1_G2_CPU0_G0_TX_DN<6>")
	)
	(segment
		(start 118.827804 -230.170228)
		(end 119.294656 -229.90429)
		(width 0.12954)
		(layer "F.Cu")
		(net "GMI_CPU1_G2_CPU0_G0_TX_DN<6>")
	)
	(segment
		(start 118.069106 -223.910398)
		(end 118.07063 -223.911414)
		(width 0.1143)
		(layer "In4.Cu")
		(net "GMI_CPU1_G2_CPU0_G0_TX_DN<6>")
	)
	(segment
		(start 166.02075 -179.64023)
		(end 159.300926 -182.04307)
		(width 0.14224)
		(layer "In4.Cu")
		(net "GMI_CPU1_G2_CPU0_G0_TX_DN<6>")
	)
	(segment
		(start 353.392486 -225.549968)
		(end 353.423474 -225.532188)
		(width 0.1143)
		(layer "In4.Cu")
		(net "GMI_CPU1_G2_CPU0_G0_TX_DN<6>")
	)
	(segment
		(start 118.071646 -223.911922)
		(end 118.072408 -223.91243)
		(width 0.1143)
		(layer "In4.Cu")
		(net "GMI_CPU1_G2_CPU0_G0_TX_DN<6>")
	)
	(segment
		(start 353.70643 -221.469966)
		(end 353.750372 -221.426024)
		(width 0.1143)
		(layer "In4.Cu")
		(net "GMI_CPU1_G2_CPU0_G0_TX_DN<6>")
	)
	(segment
		(start 118.069106 -225.53041)
		(end 118.07063 -225.531426)
		(width 0.1143)
		(layer "In4.Cu")
		(net "GMI_CPU1_G2_CPU0_G0_TX_DN<6>")
	)
	(segment
		(start 118.03253 -225.509074)
		(end 118.069106 -225.53041)
		(width 0.1143)
		(layer "In4.Cu")
		(net "GMI_CPU1_G2_CPU0_G0_TX_DN<6>")
	)
	(segment
		(start 117.74551 -221.129098)
		(end 117.74551 -221.426278)
		(width 0.1143)
		(layer "In4.Cu")
		(net "GMI_CPU1_G2_CPU0_G0_TX_DN<6>")
	)
	(segment
		(start 352.452432 -228.789992)
		(end 352.482658 -228.77272)
		(width 0.1143)
		(layer "In4.Cu")
		(net "GMI_CPU1_G2_CPU0_G0_TX_DN<6>")
	)
	(segment
		(start 353.463352 -222.959676)
		(end 353.460558 -222.957644)
		(width 0.1143)
		(layer "In4.Cu")
		(net "GMI_CPU1_G2_CPU0_G0_TX_DN<6>")
	)
	(segment
		(start 119.010938 -228.77272)
		(end 119.011954 -228.773228)
		(width 0.1143)
		(layer "In4.Cu")
		(net "GMI_CPU1_G2_CPU0_G0_TX_DN<6>")
	)
	(segment
		(start 353.422204 -226.17557)
		(end 353.392486 -226.158552)
		(width 0.1143)
		(layer "In4.Cu")
		(net "GMI_CPU1_G2_CPU0_G0_TX_DN<6>")
	)
	(segment
		(start 117.74551 -221.426278)
		(end 117.789452 -221.47022)
		(width 0.1143)
		(layer "In4.Cu")
		(net "GMI_CPU1_G2_CPU0_G0_TX_DN<6>")
	)
	(segment
		(start 307.437028 -180.429408)
		(end 302.902112 -180.429408)
		(width 0.14224)
		(layer "In4.Cu")
		(net "GMI_CPU1_G2_CPU0_G0_TX_DN<6>")
	)
	(segment
		(start 350.549972 -213.247986)
		(end 315.691266 -184.665366)
		(width 0.14224)
		(layer "In4.Cu")
		(net "GMI_CPU1_G2_CPU0_G0_TX_DN<6>")
	)
	(segment
		(start 353.460558 -222.957644)
		(end 353.424236 -222.936816)
		(width 0.1143)
		(layer "In4.Cu")
		(net "GMI_CPU1_G2_CPU0_G0_TX_DN<6>")
	)
	(segment
		(start 352.482658 -228.77272)
		(end 352.483928 -228.772974)
		(width 0.1143)
		(layer "In4.Cu")
		(net "GMI_CPU1_G2_CPU0_G0_TX_DN<6>")
	)
	(segment
		(start 144.272762 -194.366388)
		(end 143.8656 -194.489578)
		(width 0.14224)
		(layer "In4.Cu")
		(net "GMI_CPU1_G2_CPU0_G0_TX_DN<6>")
	)
	(segment
		(start 118.073678 -224.555812)
		(end 118.072408 -224.556574)
		(width 0.1143)
		(layer "In4.Cu")
		(net "GMI_CPU1_G2_CPU0_G0_TX_DN<6>")
	)
	(segment
		(start 118.07063 -222.291402)
		(end 118.071646 -222.29191)
		(width 0.1143)
		(layer "In4.Cu")
		(net "GMI_CPU1_G2_CPU0_G0_TX_DN<6>")
	)
	(segment
		(start 118.103396 -224.538794)
		(end 118.073678 -224.555812)
		(width 0.1143)
		(layer "In4.Cu")
		(net "GMI_CPU1_G2_CPU0_G0_TX_DN<6>")
	)
	(segment
		(start 352.484944 -228.772466)
		(end 352.516694 -228.751892)
		(width 0.1143)
		(layer "In4.Cu")
		(net "GMI_CPU1_G2_CPU0_G0_TX_DN<6>")
	)
	(segment
		(start 118.729252 -228.28377)
		(end 118.729252 -228.284278)
		(width 0.1143)
		(layer "In4.Cu")
		(net "GMI_CPU1_G2_CPU0_G0_TX_DN<6>")
	)
	(segment
		(start 353.392486 -223.929956)
		(end 353.423474 -223.912176)
		(width 0.1143)
		(layer "In4.Cu")
		(net "GMI_CPU1_G2_CPU0_G0_TX_DN<6>")
	)
	(segment
		(start 352.201226 -229.904036)
		(end 351.903284 -229.904036)
		(width 0.1143)
		(layer "In4.Cu")
		(net "GMI_CPU1_G2_CPU0_G0_TX_DN<6>")
	)
	(segment
		(start 159.300926 -182.04307)
		(end 154.81554 -185.721244)
		(width 0.14224)
		(layer "In4.Cu")
		(net "GMI_CPU1_G2_CPU0_G0_TX_DN<6>")
	)
	(segment
		(start 353.426776 -227.150168)
		(end 353.463352 -227.128832)
		(width 0.1143)
		(layer "In4.Cu")
		(net "GMI_CPU1_G2_CPU0_G0_TX_DN<6>")
	)
	(segment
		(start 118.51513 -227.95865)
		(end 118.553992 -227.98151)
		(width 0.1143)
		(layer "In4.Cu")
		(net "GMI_CPU1_G2_CPU0_G0_TX_DN<6>")
	)
	(segment
		(start 353.425252 -222.291148)
		(end 353.426776 -222.290132)
		(width 0.1143)
		(layer "In4.Cu")
		(net "GMI_CPU1_G2_CPU0_G0_TX_DN<6>")
	)
	(segment
		(start 302.902112 -180.429408)
		(end 167.587168 -179.64023)
		(width 0.14224)
		(layer "In4.Cu")
		(net "GMI_CPU1_G2_CPU0_G0_TX_DN<6>")
	)
	(segment
		(start 117.69979 -218.787726)
		(end 117.69979 -221.05493)
		(width 0.14224)
		(layer "In4.Cu")
		(net "GMI_CPU1_G2_CPU0_G0_TX_DN<6>")
	)
	(segment
		(start 352.941382 -227.98151)
		(end 352.94189 -227.981256)
		(width 0.1143)
		(layer "In4.Cu")
		(net "GMI_CPU1_G2_CPU0_G0_TX_DN<6>")
	)
	(segment
		(start 353.796092 -218.71559)
		(end 350.549972 -213.247986)
		(width 0.14224)
		(layer "In4.Cu")
		(net "GMI_CPU1_G2_CPU0_G0_TX_DN<6>")
	)
	(segment
		(start 154.81554 -185.721244)
		(end 154.815286 -185.72099)
		(width 0.14224)
		(layer "In4.Cu")
		(net "GMI_CPU1_G2_CPU0_G0_TX_DN<6>")
	)
	(segment
		(start 118.553992 -227.98151)
		(end 118.5545 -227.981764)
		(width 0.1143)
		(layer "In4.Cu")
		(net "GMI_CPU1_G2_CPU0_G0_TX_DN<6>")
	)
	(segment
		(start 353.398582 -227.166678)
		(end 353.423474 -227.1522)
		(width 0.1143)
		(layer "In4.Cu")
		(net "GMI_CPU1_G2_CPU0_G0_TX_DN<6>")
	)
	(segment
		(start 118.071646 -222.29191)
		(end 118.103396 -222.310198)
		(width 0.1143)
		(layer "In4.Cu")
		(net "GMI_CPU1_G2_CPU0_G0_TX_DN<6>")
	)
	(segment
		(start 118.071646 -226.177094)
		(end 118.03253 -226.199954)
		(width 0.1143)
		(layer "In4.Cu")
		(net "GMI_CPU1_G2_CPU0_G0_TX_DN<6>")
	)
	(segment
		(start 353.393248 -227.169726)
		(end 353.394264 -227.169218)
		(width 0.1143)
		(layer "In4.Cu")
		(net "GMI_CPU1_G2_CPU0_G0_TX_DN<6>")
	)
	(segment
		(start 118.072408 -223.91243)
		(end 118.103396 -223.93021)
		(width 0.1143)
		(layer "In4.Cu")
		(net "GMI_CPU1_G2_CPU0_G0_TX_DN<6>")
	)
	(segment
		(start 119.445278 -229.560882)
		(end 119.4816 -229.581964)
		(width 0.1143)
		(layer "In4.Cu")
		(net "GMI_CPU1_G2_CPU0_G0_TX_DN<6>")
	)
	(segment
		(start 119.662448 -229.83444)
		(end 119.592598 -229.90429)
		(width 0.1143)
		(layer "In4.Cu")
		(net "GMI_CPU1_G2_CPU0_G0_TX_DN<6>")
	)
	(segment
		(start 353.796092 -221.083124)
		(end 353.796092 -218.71559)
		(width 0.14224)
		(layer "In4.Cu")
		(net "GMI_CPU1_G2_CPU0_G0_TX_DN<6>")
	)
	(segment
		(start 118.103396 -226.158806)
		(end 118.073678 -226.175824)
		(width 0.1143)
		(layer "In4.Cu")
		(net "GMI_CPU1_G2_CPU0_G0_TX_DN<6>")
	)
	(segment
		(start 118.072408 -227.152454)
		(end 118.0973 -227.166932)
		(width 0.1143)
		(layer "In4.Cu")
		(net "GMI_CPU1_G2_CPU0_G0_TX_DN<6>")
	)
	(segment
		(start 352.483928 -228.772974)
		(end 352.484944 -228.772466)
		(width 0.1143)
		(layer "In4.Cu")
		(net "GMI_CPU1_G2_CPU0_G0_TX_DN<6>")
	)
	(segment
		(start 353.426776 -224.558352)
		(end 353.425252 -224.557336)
		(width 0.1143)
		(layer "In4.Cu")
		(net "GMI_CPU1_G2_CPU0_G0_TX_DN<6>")
	)
	(segment
		(start 118.07063 -225.531426)
		(end 118.071646 -225.531934)
		(width 0.1143)
		(layer "In4.Cu")
		(net "GMI_CPU1_G2_CPU0_G0_TX_DN<6>")
	)
	(segment
		(start 117.69979 -221.05493)
		(end 117.69979 -221.083378)
		(width 0.1143)
		(layer "In4.Cu")
		(net "GMI_CPU1_G2_CPU0_G0_TX_DN<6>")
	)
	(segment
		(start 353.424236 -225.53168)
		(end 353.425252 -225.531172)
		(width 0.1143)
		(layer "In4.Cu")
		(net "GMI_CPU1_G2_CPU0_G0_TX_DN<6>")
	)
	(segment
		(start 118.072408 -225.532442)
		(end 118.103396 -225.550222)
		(width 0.1143)
		(layer "In4.Cu")
		(net "GMI_CPU1_G2_CPU0_G0_TX_DN<6>")
	)
	(segment
		(start 118.071646 -227.151946)
		(end 118.072408 -227.152454)
		(width 0.1143)
		(layer "In4.Cu")
		(net "GMI_CPU1_G2_CPU0_G0_TX_DN<6>")
	)
	(segment
		(start 352.014282 -229.58171)
		(end 352.050604 -229.560628)
		(width 0.1143)
		(layer "In4.Cu")
		(net "GMI_CPU1_G2_CPU0_G0_TX_DN<6>")
	)
	(segment
		(start 353.424236 -222.291656)
		(end 353.425252 -222.291148)
		(width 0.1143)
		(layer "In4.Cu")
		(net "GMI_CPU1_G2_CPU0_G0_TX_DN<6>")
	)
	(segment
		(start 353.423474 -225.532188)
		(end 353.424236 -225.53168)
		(width 0.1143)
		(layer "In4.Cu")
		(net "GMI_CPU1_G2_CPU0_G0_TX_DN<6>")
	)
	(segment
		(start 353.424236 -227.151692)
		(end 353.425252 -227.151184)
		(width 0.1143)
		(layer "In4.Cu")
		(net "GMI_CPU1_G2_CPU0_G0_TX_DN<6>")
	)
	(segment
		(start 353.463352 -224.579688)
		(end 353.426776 -224.558352)
		(width 0.1143)
		(layer "In4.Cu")
		(net "GMI_CPU1_G2_CPU0_G0_TX_DN<6>")
	)
	(segment
		(start 143.8656 -194.489578)
		(end 120.906794 -213.314026)
		(width 0.14224)
		(layer "In4.Cu")
		(net "GMI_CPU1_G2_CPU0_G0_TX_DN<6>")
	)
	(segment
		(start 353.463352 -226.1997)
		(end 353.426776 -226.178364)
		(width 0.1143)
		(layer "In4.Cu")
		(net "GMI_CPU1_G2_CPU0_G0_TX_DN<6>")
	)
	(segment
		(start 119.4816 -229.581964)
		(end 119.515128 -229.601522)
		(width 0.1143)
		(layer "In4.Cu")
		(net "GMI_CPU1_G2_CPU0_G0_TX_DN<6>")
	)
	(segment
		(start 119.011954 -228.773228)
		(end 119.013224 -228.772974)
		(width 0.1143)
		(layer "In4.Cu")
		(net "GMI_CPU1_G2_CPU0_G0_TX_DN<6>")
	)
	(segment
		(start 353.425252 -224.557336)
		(end 353.424236 -224.556828)
		(width 0.1143)
		(layer "In4.Cu")
		(net "GMI_CPU1_G2_CPU0_G0_TX_DN<6>")
	)
	(segment
		(start 353.223576 -227.494338)
		(end 353.223576 -227.46716)
		(width 0.1143)
		(layer "In4.Cu")
		(net "GMI_CPU1_G2_CPU0_G0_TX_DN<6>")
	)
	(segment
		(start 118.071646 -222.93707)
		(end 118.035324 -222.957898)
		(width 0.1143)
		(layer "In4.Cu")
		(net "GMI_CPU1_G2_CPU0_G0_TX_DN<6>")
	)
	(segment
		(start 353.426776 -225.530156)
		(end 353.463352 -225.50882)
		(width 0.1143)
		(layer "In4.Cu")
		(net "GMI_CPU1_G2_CPU0_G0_TX_DN<6>")
	)
	(segment
		(start 118.979188 -228.752146)
		(end 119.010938 -228.77272)
		(width 0.1143)
		(layer "In4.Cu")
		(net "GMI_CPU1_G2_CPU0_G0_TX_DN<6>")
	)
	(segment
		(start 118.07063 -223.911414)
		(end 118.071646 -223.911922)
		(width 0.1143)
		(layer "In4.Cu")
		(net "GMI_CPU1_G2_CPU0_G0_TX_DN<6>")
	)
	(segment
		(start 353.426776 -226.178364)
		(end 353.425252 -226.177348)
		(width 0.1143)
		(layer "In4.Cu")
		(net "GMI_CPU1_G2_CPU0_G0_TX_DN<6>")
	)
	(segment
		(start 118.098316 -227.16744)
		(end 118.101618 -227.169472)
		(width 0.1143)
		(layer "In4.Cu")
		(net "GMI_CPU1_G2_CPU0_G0_TX_DN<6>")
	)
	(segment
		(start 353.423474 -223.912176)
		(end 353.424236 -223.911668)
		(width 0.1143)
		(layer "In4.Cu")
		(net "GMI_CPU1_G2_CPU0_G0_TX_DN<6>")
	)
	(segment
		(start 353.427792 -222.289624)
		(end 353.463098 -222.26905)
		(width 0.1143)
		(layer "In4.Cu")
		(net "GMI_CPU1_G2_CPU0_G0_TX_DN<6>")
	)
	(segment
		(start 353.425252 -227.151184)
		(end 353.426776 -227.150168)
		(width 0.1143)
		(layer "In4.Cu")
		(net "GMI_CPU1_G2_CPU0_G0_TX_DN<6>")
	)
	(segment
		(start 118.272306 -227.467414)
		(end 118.272306 -227.494592)
		(width 0.1143)
		(layer "In4.Cu")
		(net "GMI_CPU1_G2_CPU0_G0_TX_DN<6>")
	)
	(segment
		(start 353.422204 -224.555558)
		(end 353.392486 -224.53854)
		(width 0.1143)
		(layer "In4.Cu")
		(net "GMI_CPU1_G2_CPU0_G0_TX_DN<6>")
	)
	(segment
		(start 353.70643 -221.804484)
		(end 353.70643 -221.469966)
		(width 0.1143)
		(layer "In4.Cu")
		(net "GMI_CPU1_G2_CPU0_G0_TX_DN<6>")
	)
	(segment
		(start 118.073678 -226.175824)
		(end 118.072408 -226.176586)
		(width 0.1143)
		(layer "In4.Cu")
		(net "GMI_CPU1_G2_CPU0_G0_TX_DN<6>")
	)
	(segment
		(start 353.425252 -223.91116)
		(end 353.426776 -223.910144)
		(width 0.1143)
		(layer "In4.Cu")
		(net "GMI_CPU1_G2_CPU0_G0_TX_DN<6>")
	)
	(segment
		(start 118.0973 -227.166932)
		(end 118.098316 -227.16744)
		(width 0.1143)
		(layer "In4.Cu")
		(net "GMI_CPU1_G2_CPU0_G0_TX_DN<6>")
	)
	(segment
		(start 351.980754 -229.601268)
		(end 352.014282 -229.58171)
		(width 0.1143)
		(layer "In4.Cu")
		(net "GMI_CPU1_G2_CPU0_G0_TX_DN<6>")
	)
	(segment
		(start 353.394264 -227.169218)
		(end 353.397566 -227.167186)
		(width 0.1143)
		(layer "In4.Cu")
		(net "GMI_CPU1_G2_CPU0_G0_TX_DN<6>")
	)
	(segment
		(start 118.072408 -226.176586)
		(end 118.071646 -226.177094)
		(width 0.1143)
		(layer "In4.Cu")
		(net "GMI_CPU1_G2_CPU0_G0_TX_DN<6>")
	)
	(segment
		(start 353.424236 -224.556828)
		(end 353.423474 -224.55632)
		(width 0.1143)
		(layer "In4.Cu")
		(net "GMI_CPU1_G2_CPU0_G0_TX_DN<6>")
	)
	(segment
		(start 118.103396 -222.918782)
		(end 118.073678 -222.9358)
		(width 0.1143)
		(layer "In4.Cu")
		(net "GMI_CPU1_G2_CPU0_G0_TX_DN<6>")
	)
	(segment
		(start 353.424236 -222.936816)
		(end 353.423474 -222.936308)
		(width 0.1143)
		(layer "In4.Cu")
		(net "GMI_CPU1_G2_CPU0_G0_TX_DN<6>")
	)
	(segment
		(start 118.069106 -227.150422)
		(end 118.07063 -227.151438)
		(width 0.1143)
		(layer "In4.Cu")
		(net "GMI_CPU1_G2_CPU0_G0_TX_DN<6>")
	)
	(segment
		(start 309.529226 -181.177184)
		(end 307.437028 -180.429408)
		(width 0.14224)
		(layer "In4.Cu")
		(net "GMI_CPU1_G2_CPU0_G0_TX_DN<6>")
	)
	(segment
		(start 118.06809 -222.289878)
		(end 118.069106 -222.290386)
		(width 0.1143)
		(layer "In4.Cu")
		(net "GMI_CPU1_G2_CPU0_G0_TX_DN<6>")
	)
	(segment
		(start 119.592598 -229.90429)
		(end 119.294656 -229.90429)
		(width 0.1143)
		(layer "In4.Cu")
		(net "GMI_CPU1_G2_CPU0_G0_TX_DN<6>")
	)
	(segment
		(start 353.423474 -224.55632)
		(end 353.422204 -224.555558)
		(width 0.1143)
		(layer "In4.Cu")
		(net "GMI_CPU1_G2_CPU0_G0_TX_DN<6>")
	)
	(segment
		(start 154.815286 -185.72099)
		(end 144.272762 -194.366388)
		(width 0.14224)
		(layer "In4.Cu")
		(net "GMI_CPU1_G2_CPU0_G0_TX_DN<6>")
	)
	(segment
		(start 353.397566 -227.167186)
		(end 353.398582 -227.166678)
		(width 0.1143)
		(layer "In4.Cu")
		(net "GMI_CPU1_G2_CPU0_G0_TX_DN<6>")
	)
	(segment
		(start 353.392486 -222.309944)
		(end 353.424236 -222.291656)
		(width 0.1143)
		(layer "In4.Cu")
		(net "GMI_CPU1_G2_CPU0_G0_TX_DN<6>")
	)
	(segment
		(start 353.426776 -223.910144)
		(end 353.463352 -223.888808)
		(width 0.1143)
		(layer "In4.Cu")
		(net "GMI_CPU1_G2_CPU0_G0_TX_DN<6>")
	)
	(segment
		(start 118.071646 -224.557082)
		(end 118.03253 -224.579942)
		(width 0.1143)
		(layer "In4.Cu")
		(net "GMI_CPU1_G2_CPU0_G0_TX_DN<6>")
	)
	(segment
		(start 352.76663 -228.284024)
		(end 352.76663 -228.283516)
		(width 0.1143)
		(layer "In4.Cu")
		(net "GMI_CPU1_G2_CPU0_G0_TX_DN<6>")
	)
	(segment
		(start 353.425252 -225.531172)
		(end 353.426776 -225.530156)
		(width 0.1143)
		(layer "In4.Cu")
		(net "GMI_CPU1_G2_CPU0_G0_TX_DN<6>")
	)
	(segment
		(start 118.03253 -227.129086)
		(end 118.069106 -227.150422)
		(width 0.1143)
		(layer "In4.Cu")
		(net "GMI_CPU1_G2_CPU0_G0_TX_DN<6>")
	)
	(segment
		(start 118.069106 -222.290386)
		(end 118.07063 -222.291402)
		(width 0.1143)
		(layer "In4.Cu")
		(net "GMI_CPU1_G2_CPU0_G0_TX_DN<6>")
	)
	(segment
		(start 353.426776 -222.290132)
		(end 353.427792 -222.289624)
		(width 0.1143)
		(layer "In4.Cu")
		(net "GMI_CPU1_G2_CPU0_G0_TX_DN<6>")
	)
	(segment
		(start 353.423474 -226.176332)
		(end 353.422204 -226.17557)
		(width 0.1143)
		(layer "In4.Cu")
		(net "GMI_CPU1_G2_CPU0_G0_TX_DN<6>")
	)
	(segment
		(start 118.071646 -225.531934)
		(end 118.072408 -225.532442)
		(width 0.1143)
		(layer "In4.Cu")
		(net "GMI_CPU1_G2_CPU0_G0_TX_DN<6>")
	)
	(segment
		(start 167.587168 -179.64023)
		(end 166.02075 -179.64023)
		(width 0.14224)
		(layer "In4.Cu")
		(net "GMI_CPU1_G2_CPU0_G0_TX_DN<6>")
	)
	(segment
		(start 353.424236 -223.911668)
		(end 353.425252 -223.91116)
		(width 0.1143)
		(layer "In4.Cu")
		(net "GMI_CPU1_G2_CPU0_G0_TX_DN<6>")
	)
	(segment
		(start 315.691266 -184.665366)
		(end 309.529226 -181.177184)
		(width 0.14224)
		(layer "In4.Cu")
		(net "GMI_CPU1_G2_CPU0_G0_TX_DN<6>")
	)
	(segment
		(start 353.422204 -222.935546)
		(end 353.392486 -222.918528)
		(width 0.1143)
		(layer "In4.Cu")
		(net "GMI_CPU1_G2_CPU0_G0_TX_DN<6>")
	)
	(segment
		(start 353.423474 -222.936308)
		(end 353.422204 -222.935546)
		(width 0.1143)
		(layer "In4.Cu")
		(net "GMI_CPU1_G2_CPU0_G0_TX_DN<6>")
	)
	(segment
		(start 353.424236 -226.17684)
		(end 353.423474 -226.176332)
		(width 0.1143)
		(layer "In4.Cu")
		(net "GMI_CPU1_G2_CPU0_G0_TX_DN<6>")
	)
	(segment
		(start 118.07063 -227.151438)
		(end 118.071646 -227.151946)
		(width 0.1143)
		(layer "In4.Cu")
		(net "GMI_CPU1_G2_CPU0_G0_TX_DN<6>")
	)
	(segment
		(start 117.789452 -221.47022)
		(end 117.789452 -221.804484)
		(width 0.1143)
		(layer "In4.Cu")
		(net "GMI_CPU1_G2_CPU0_G0_TX_DN<6>")
	)
	(segment
		(start 353.423474 -227.1522)
		(end 353.424236 -227.151692)
		(width 0.1143)
		(layer "In4.Cu")
		(net "GMI_CPU1_G2_CPU0_G0_TX_DN<6>")
	)
	(segment
		(start 118.03253 -223.889062)
		(end 118.069106 -223.910398)
		(width 0.1143)
		(layer "In4.Cu")
		(net "GMI_CPU1_G2_CPU0_G0_TX_DN<6>")
	)
	(segment
		(start 118.03253 -222.26905)
		(end 118.06809 -222.289878)
		(width 0.1143)
		(layer "In4.Cu")
		(net "GMI_CPU1_G2_CPU0_G0_TX_DN<6>")
	)
	(segment
		(start 353.750372 -221.426024)
		(end 353.750372 -221.128844)
		(width 0.1143)
		(layer "In4.Cu")
		(net "GMI_CPU1_G2_CPU0_G0_TX_DN<6>")
	)
	(segment
		(start 118.072408 -222.936562)
		(end 118.071646 -222.93707)
		(width 0.1143)
		(layer "In4.Cu")
		(net "GMI_CPU1_G2_CPU0_G0_TX_DN<6>")
	)
	(segment
		(start 351.903284 -229.904036)
		(end 351.833434 -229.834186)
		(width 0.1143)
		(layer "In4.Cu")
		(net "GMI_CPU1_G2_CPU0_G0_TX_DN<6>")
	)
	(segment
		(start 118.072408 -224.556574)
		(end 118.071646 -224.557082)
		(width 0.1143)
		(layer "In4.Cu")
		(net "GMI_CPU1_G2_CPU0_G0_TX_DN<6>")
	)
	(segment
		(start 353.750372 -221.128844)
		(end 353.796092 -221.083124)
		(width 0.1143)
		(layer "In4.Cu")
		(net "GMI_CPU1_G2_CPU0_G0_TX_DN<6>")
	)
	(segment
		(start 120.906794 -213.314026)
		(end 117.69979 -218.787726)
		(width 0.14224)
		(layer "In4.Cu")
		(net "GMI_CPU1_G2_CPU0_G0_TX_DN<6>")
	)
	(segment
		(start 118.035324 -222.957898)
		(end 118.03253 -222.95993)
		(width 0.1143)
		(layer "In4.Cu")
		(net "GMI_CPU1_G2_CPU0_G0_TX_DN<6>")
	)
	(segment
		(start 119.013224 -228.772974)
		(end 119.04345 -228.790246)
		(width 0.1143)
		(layer "In4.Cu")
		(net "GMI_CPU1_G2_CPU0_G0_TX_DN<6>")
	)
	(segment
		(start 117.69979 -221.083378)
		(end 117.74551 -221.129098)
		(width 0.1143)
		(layer "In4.Cu")
		(net "GMI_CPU1_G2_CPU0_G0_TX_DN<6>")
	)
	(segment
		(start 118.073678 -222.9358)
		(end 118.072408 -222.936562)
		(width 0.1143)
		(layer "In4.Cu")
		(net "GMI_CPU1_G2_CPU0_G0_TX_DN<6>")
	)
	(segment
		(start 352.94189 -227.981256)
		(end 352.980752 -227.958396)
		(width 0.1143)
		(layer "In4.Cu")
		(net "GMI_CPU1_G2_CPU0_G0_TX_DN<6>")
	)
	(segment
		(start 353.425252 -226.177348)
		(end 353.424236 -226.17684)
		(width 0.1143)
		(layer "In4.Cu")
		(net "GMI_CPU1_G2_CPU0_G0_TX_DN<6>")
	)
	(segment
		(start 118.101618 -227.169472)
		(end 118.102634 -227.16998)
		(width 0.1143)
		(layer "In4.Cu")
		(net "GMI_CPU1_G2_CPU0_G0_TX_DN<6>")
	)
	(arc
		(start 118.103396 -222.310198)
		(mid 118.259324 -222.61449)
		(end 118.103396 -222.918782)
		(width 0.1143)
		(layer "In4.Cu")
		(net "GMI_CPU1_G2_CPU0_G0_TX_DN<6>")
	)
	(arc
		(start 118.03253 -224.579942)
		(mid 117.789203 -225.044508)
		(end 118.03253 -225.509074)
		(width 0.1143)
		(layer "In4.Cu")
		(net "GMI_CPU1_G2_CPU0_G0_TX_DN<6>")
	)
	(arc
		(start 353.463352 -227.128832)
		(mid 353.706679 -226.664266)
		(end 353.463352 -226.1997)
		(width 0.1143)
		(layer "In4.Cu")
		(net "GMI_CPU1_G2_CPU0_G0_TX_DN<6>")
	)
	(arc
		(start 352.980752 -227.958396)
		(mid 353.159107 -227.756182)
		(end 353.223576 -227.494338)
		(width 0.1143)
		(layer "In4.Cu")
		(net "GMI_CPU1_G2_CPU0_G0_TX_DN<6>")
	)
	(arc
		(start 118.103396 -225.550222)
		(mid 118.259324 -225.854514)
		(end 118.103396 -226.158806)
		(width 0.1143)
		(layer "In4.Cu")
		(net "GMI_CPU1_G2_CPU0_G0_TX_DN<6>")
	)
	(arc
		(start 118.272306 -227.494592)
		(mid 118.336657 -227.756498)
		(end 118.51513 -227.95865)
		(width 0.1143)
		(layer "In4.Cu")
		(net "GMI_CPU1_G2_CPU0_G0_TX_DN<6>")
	)
	(arc
		(start 353.463098 -222.26905)
		(mid 353.641926 -222.066694)
		(end 353.70643 -221.804484)
		(width 0.1143)
		(layer "In4.Cu")
		(net "GMI_CPU1_G2_CPU0_G0_TX_DN<6>")
	)
	(arc
		(start 118.102634 -227.16998)
		(mid 118.226938 -227.296189)
		(end 118.272306 -227.467414)
		(width 0.1143)
		(layer "In4.Cu")
		(net "GMI_CPU1_G2_CPU0_G0_TX_DN<6>")
	)
	(arc
		(start 119.515128 -229.601522)
		(mid 119.611016 -229.70393)
		(end 119.662448 -229.83444)
		(width 0.1143)
		(layer "In4.Cu")
		(net "GMI_CPU1_G2_CPU0_G0_TX_DN<6>")
	)
	(arc
		(start 118.5545 -227.981764)
		(mid 118.681969 -228.109572)
		(end 118.729252 -228.28377)
		(width 0.1143)
		(layer "In4.Cu")
		(net "GMI_CPU1_G2_CPU0_G0_TX_DN<6>")
	)
	(arc
		(start 352.76663 -228.283516)
		(mid 352.813939 -228.109333)
		(end 352.941382 -227.98151)
		(width 0.1143)
		(layer "In4.Cu")
		(net "GMI_CPU1_G2_CPU0_G0_TX_DN<6>")
	)
	(arc
		(start 119.199406 -229.094538)
		(mid 119.264642 -229.358129)
		(end 119.445278 -229.560882)
		(width 0.1143)
		(layer "In4.Cu")
		(net "GMI_CPU1_G2_CPU0_G0_TX_DN<6>")
	)
	(arc
		(start 353.392486 -222.918528)
		(mid 353.236558 -222.614236)
		(end 353.392486 -222.309944)
		(width 0.1143)
		(layer "In4.Cu")
		(net "GMI_CPU1_G2_CPU0_G0_TX_DN<6>")
	)
	(arc
		(start 352.516694 -228.751892)
		(mid 352.700301 -228.54928)
		(end 352.76663 -228.284024)
		(width 0.1143)
		(layer "In4.Cu")
		(net "GMI_CPU1_G2_CPU0_G0_TX_DN<6>")
	)
	(arc
		(start 118.03253 -222.95993)
		(mid 117.789203 -223.424496)
		(end 118.03253 -223.889062)
		(width 0.1143)
		(layer "In4.Cu")
		(net "GMI_CPU1_G2_CPU0_G0_TX_DN<6>")
	)
	(arc
		(start 119.04345 -228.790246)
		(mid 119.158126 -228.92358)
		(end 119.199406 -229.094538)
		(width 0.1143)
		(layer "In4.Cu")
		(net "GMI_CPU1_G2_CPU0_G0_TX_DN<6>")
	)
	(arc
		(start 117.898672 -222.139002)
		(mid 117.960191 -222.209596)
		(end 118.03253 -222.26905)
		(width 0.1143)
		(layer "In4.Cu")
		(net "GMI_CPU1_G2_CPU0_G0_TX_DN<6>")
	)
	(arc
		(start 353.463352 -223.888808)
		(mid 353.706679 -223.424242)
		(end 353.463352 -222.959676)
		(width 0.1143)
		(layer "In4.Cu")
		(net "GMI_CPU1_G2_CPU0_G0_TX_DN<6>")
	)
	(arc
		(start 118.103396 -223.93021)
		(mid 118.259324 -224.234502)
		(end 118.103396 -224.538794)
		(width 0.1143)
		(layer "In4.Cu")
		(net "GMI_CPU1_G2_CPU0_G0_TX_DN<6>")
	)
	(arc
		(start 117.789452 -221.804484)
		(mid 117.817368 -221.98046)
		(end 117.898672 -222.139002)
		(width 0.1143)
		(layer "In4.Cu")
		(net "GMI_CPU1_G2_CPU0_G0_TX_DN<6>")
	)
	(arc
		(start 353.392486 -226.158552)
		(mid 353.236558 -225.85426)
		(end 353.392486 -225.549968)
		(width 0.1143)
		(layer "In4.Cu")
		(net "GMI_CPU1_G2_CPU0_G0_TX_DN<6>")
	)
	(arc
		(start 351.833434 -229.834186)
		(mid 351.884924 -229.703713)
		(end 351.980754 -229.601268)
		(width 0.1143)
		(layer "In4.Cu")
		(net "GMI_CPU1_G2_CPU0_G0_TX_DN<6>")
	)
	(arc
		(start 353.392486 -224.53854)
		(mid 353.236558 -224.234248)
		(end 353.392486 -223.929956)
		(width 0.1143)
		(layer "In4.Cu")
		(net "GMI_CPU1_G2_CPU0_G0_TX_DN<6>")
	)
	(arc
		(start 352.296476 -229.094284)
		(mid 352.337731 -228.923313)
		(end 352.452432 -228.789992)
		(width 0.1143)
		(layer "In4.Cu")
		(net "GMI_CPU1_G2_CPU0_G0_TX_DN<6>")
	)
	(arc
		(start 353.463352 -225.50882)
		(mid 353.706679 -225.044254)
		(end 353.463352 -224.579688)
		(width 0.1143)
		(layer "In4.Cu")
		(net "GMI_CPU1_G2_CPU0_G0_TX_DN<6>")
	)
	(arc
		(start 118.729252 -228.284278)
		(mid 118.7956 -228.549524)
		(end 118.979188 -228.752146)
		(width 0.1143)
		(layer "In4.Cu")
		(net "GMI_CPU1_G2_CPU0_G0_TX_DN<6>")
	)
	(arc
		(start 353.223576 -227.46716)
		(mid 353.268984 -227.295959)
		(end 353.393248 -227.169726)
		(width 0.1143)
		(layer "In4.Cu")
		(net "GMI_CPU1_G2_CPU0_G0_TX_DN<6>")
	)
	(arc
		(start 352.050604 -229.560628)
		(mid 352.231256 -229.357883)
		(end 352.296476 -229.094284)
		(width 0.1143)
		(layer "In4.Cu")
		(net "GMI_CPU1_G2_CPU0_G0_TX_DN<6>")
	)
	(arc
		(start 118.03253 -226.199954)
		(mid 117.789203 -226.66452)
		(end 118.03253 -227.129086)
		(width 0.1143)
		(layer "In4.Cu")
		(net "GMI_CPU1_G2_CPU0_G0_TX_DN<6>")
	)
	(segment
		(start 355.487986 -228.550216)
		(end 355.021134 -228.284278)
		(width 0.12954)
		(layer "F.Cu")
		(net "GMI_CPU1_G2_CPU0_G0_TX_DN<5>")
	)
	(segment
		(start 116.007896 -228.55047)
		(end 116.474748 -228.284532)
		(width 0.12954)
		(layer "F.Cu")
		(net "GMI_CPU1_G2_CPU0_G0_TX_DN<5>")
	)
	(segment
		(start 355.343206 -225.50882)
		(end 355.30409 -225.53168)
		(width 0.1143)
		(layer "In4.Cu")
		(net "GMI_CPU1_G2_CPU0_G0_TX_DN<5>")
	)
	(segment
		(start 310.141112 -179.36718)
		(end 316.69863 -183.07939)
		(width 0.14224)
		(layer "In4.Cu")
		(net "GMI_CPU1_G2_CPU0_G0_TX_DN<5>")
	)
	(segment
		(start 355.586284 -221.479872)
		(end 355.586284 -221.80423)
		(width 0.1143)
		(layer "In4.Cu")
		(net "GMI_CPU1_G2_CPU0_G0_TX_DN<5>")
	)
	(segment
		(start 355.30409 -226.17684)
		(end 355.343206 -226.1997)
		(width 0.1143)
		(layer "In4.Cu")
		(net "GMI_CPU1_G2_CPU0_G0_TX_DN<5>")
	)
	(segment
		(start 116.191792 -225.531934)
		(end 116.152676 -225.509074)
		(width 0.1143)
		(layer "In4.Cu")
		(net "GMI_CPU1_G2_CPU0_G0_TX_DN<5>")
	)
	(segment
		(start 355.27234 -226.158552)
		(end 355.30409 -226.17684)
		(width 0.1143)
		(layer "In4.Cu")
		(net "GMI_CPU1_G2_CPU0_G0_TX_DN<5>")
	)
	(segment
		(start 116.152676 -222.95993)
		(end 116.191792 -222.93707)
		(width 0.1143)
		(layer "In4.Cu")
		(net "GMI_CPU1_G2_CPU0_G0_TX_DN<5>")
	)
	(segment
		(start 355.343206 -222.268796)
		(end 355.27234 -222.309944)
		(width 0.1143)
		(layer "In4.Cu")
		(net "GMI_CPU1_G2_CPU0_G0_TX_DN<5>")
	)
	(segment
		(start 116.662454 -227.96246)
		(end 116.661692 -227.961952)
		(width 0.1143)
		(layer "In4.Cu")
		(net "GMI_CPU1_G2_CPU0_G0_TX_DN<5>")
	)
	(segment
		(start 355.685852 -218.24442)
		(end 355.685852 -221.083124)
		(width 0.14224)
		(layer "In4.Cu")
		(net "GMI_CPU1_G2_CPU0_G0_TX_DN<5>")
	)
	(segment
		(start 355.30409 -222.936816)
		(end 355.343206 -222.959676)
		(width 0.1143)
		(layer "In4.Cu")
		(net "GMI_CPU1_G2_CPU0_G0_TX_DN<5>")
	)
	(segment
		(start 307.884322 -178.549808)
		(end 307.900578 -178.566064)
		(width 0.14224)
		(layer "In4.Cu")
		(net "GMI_CPU1_G2_CPU0_G0_TX_DN<5>")
	)
	(segment
		(start 355.30409 -225.53168)
		(end 355.27234 -225.549968)
		(width 0.1143)
		(layer "In4.Cu")
		(net "GMI_CPU1_G2_CPU0_G0_TX_DN<5>")
	)
	(segment
		(start 355.343206 -227.128832)
		(end 355.29139 -227.159058)
		(width 0.1143)
		(layer "In4.Cu")
		(net "GMI_CPU1_G2_CPU0_G0_TX_DN<5>")
	)
	(segment
		(start 116.223542 -222.310198)
		(end 116.152676 -222.26905)
		(width 0.1143)
		(layer "In4.Cu")
		(net "GMI_CPU1_G2_CPU0_G0_TX_DN<5>")
	)
	(segment
		(start 354.83419 -227.961698)
		(end 354.833428 -227.962206)
		(width 0.1143)
		(layer "In4.Cu")
		(net "GMI_CPU1_G2_CPU0_G0_TX_DN<5>")
	)
	(segment
		(start 354.833428 -227.962206)
		(end 354.80244 -227.979986)
		(width 0.1143)
		(layer "In4.Cu")
		(net "GMI_CPU1_G2_CPU0_G0_TX_DN<5>")
	)
	(segment
		(start 355.30409 -224.556828)
		(end 355.343206 -224.579688)
		(width 0.1143)
		(layer "In4.Cu")
		(net "GMI_CPU1_G2_CPU0_G0_TX_DN<5>")
	)
	(segment
		(start 354.653342 -228.214428)
		(end 354.723192 -228.284278)
		(width 0.1143)
		(layer "In4.Cu")
		(net "GMI_CPU1_G2_CPU0_G0_TX_DN<5>")
	)
	(segment
		(start 116.191792 -224.557082)
		(end 116.223542 -224.538794)
		(width 0.1143)
		(layer "In4.Cu")
		(net "GMI_CPU1_G2_CPU0_G0_TX_DN<5>")
	)
	(segment
		(start 115.909598 -221.804484)
		(end 115.909598 -221.480126)
		(width 0.1143)
		(layer "In4.Cu")
		(net "GMI_CPU1_G2_CPU0_G0_TX_DN<5>")
	)
	(segment
		(start 351.986342 -212.0138)
		(end 355.685852 -218.24442)
		(width 0.14224)
		(layer "In4.Cu")
		(net "GMI_CPU1_G2_CPU0_G0_TX_DN<5>")
	)
	(segment
		(start 354.836476 -227.960428)
		(end 354.83419 -227.961698)
		(width 0.1143)
		(layer "In4.Cu")
		(net "GMI_CPU1_G2_CPU0_G0_TX_DN<5>")
	)
	(segment
		(start 167.31615 -177.758344)
		(end 302.908208 -178.549808)
		(width 0.14224)
		(layer "In4.Cu")
		(net "GMI_CPU1_G2_CPU0_G0_TX_DN<5>")
	)
	(segment
		(start 116.152676 -224.579942)
		(end 116.191792 -224.557082)
		(width 0.1143)
		(layer "In4.Cu")
		(net "GMI_CPU1_G2_CPU0_G0_TX_DN<5>")
	)
	(segment
		(start 355.640132 -221.426024)
		(end 355.586284 -221.479872)
		(width 0.1143)
		(layer "In4.Cu")
		(net "GMI_CPU1_G2_CPU0_G0_TX_DN<5>")
	)
	(segment
		(start 115.81003 -221.05493)
		(end 115.81003 -218.148916)
		(width 0.14224)
		(layer "In4.Cu")
		(net "GMI_CPU1_G2_CPU0_G0_TX_DN<5>")
	)
	(segment
		(start 116.191792 -226.177094)
		(end 116.223542 -226.158806)
		(width 0.1143)
		(layer "In4.Cu")
		(net "GMI_CPU1_G2_CPU0_G0_TX_DN<5>")
	)
	(segment
		(start 116.661692 -227.961952)
		(end 116.659406 -227.960682)
		(width 0.1143)
		(layer "In4.Cu")
		(net "GMI_CPU1_G2_CPU0_G0_TX_DN<5>")
	)
	(segment
		(start 355.685852 -221.083124)
		(end 355.640132 -221.128844)
		(width 0.1143)
		(layer "In4.Cu")
		(net "GMI_CPU1_G2_CPU0_G0_TX_DN<5>")
	)
	(segment
		(start 115.909598 -221.480126)
		(end 115.85575 -221.426278)
		(width 0.1143)
		(layer "In4.Cu")
		(net "GMI_CPU1_G2_CPU0_G0_TX_DN<5>")
	)
	(segment
		(start 355.103684 -227.483924)
		(end 355.103684 -227.49637)
		(width 0.1143)
		(layer "In4.Cu")
		(net "GMI_CPU1_G2_CPU0_G0_TX_DN<5>")
	)
	(segment
		(start 165.58006 -177.758344)
		(end 167.31615 -177.758344)
		(width 0.14224)
		(layer "In4.Cu")
		(net "GMI_CPU1_G2_CPU0_G0_TX_DN<5>")
	)
	(segment
		(start 116.77269 -228.284532)
		(end 116.84254 -228.214682)
		(width 0.1143)
		(layer "In4.Cu")
		(net "GMI_CPU1_G2_CPU0_G0_TX_DN<5>")
	)
	(segment
		(start 115.81003 -218.148916)
		(end 119.551704 -211.847176)
		(width 0.14224)
		(layer "In4.Cu")
		(net "GMI_CPU1_G2_CPU0_G0_TX_DN<5>")
	)
	(segment
		(start 115.81003 -221.083378)
		(end 115.81003 -221.05493)
		(width 0.1143)
		(layer "In4.Cu")
		(net "GMI_CPU1_G2_CPU0_G0_TX_DN<5>")
	)
	(segment
		(start 116.223542 -223.93021)
		(end 116.152676 -223.889062)
		(width 0.1143)
		(layer "In4.Cu")
		(net "GMI_CPU1_G2_CPU0_G0_TX_DN<5>")
	)
	(segment
		(start 157.683962 -180.581554)
		(end 165.58006 -177.758344)
		(width 0.14224)
		(layer "In4.Cu")
		(net "GMI_CPU1_G2_CPU0_G0_TX_DN<5>")
	)
	(segment
		(start 355.27234 -222.918528)
		(end 355.30409 -222.936816)
		(width 0.1143)
		(layer "In4.Cu")
		(net "GMI_CPU1_G2_CPU0_G0_TX_DN<5>")
	)
	(segment
		(start 355.343206 -223.888808)
		(end 355.27234 -223.929956)
		(width 0.1143)
		(layer "In4.Cu")
		(net "GMI_CPU1_G2_CPU0_G0_TX_DN<5>")
	)
	(segment
		(start 116.152676 -226.199954)
		(end 116.191792 -226.177094)
		(width 0.1143)
		(layer "In4.Cu")
		(net "GMI_CPU1_G2_CPU0_G0_TX_DN<5>")
	)
	(segment
		(start 355.252528 -224.524316)
		(end 355.27234 -224.53854)
		(width 0.1143)
		(layer "In4.Cu")
		(net "GMI_CPU1_G2_CPU0_G0_TX_DN<5>")
	)
	(segment
		(start 116.392198 -227.496624)
		(end 116.392198 -227.484178)
		(width 0.1143)
		(layer "In4.Cu")
		(net "GMI_CPU1_G2_CPU0_G0_TX_DN<5>")
	)
	(segment
		(start 302.908208 -178.549808)
		(end 307.884322 -178.549808)
		(width 0.14224)
		(layer "In4.Cu")
		(net "GMI_CPU1_G2_CPU0_G0_TX_DN<5>")
	)
	(segment
		(start 116.693442 -227.98024)
		(end 116.662454 -227.96246)
		(width 0.1143)
		(layer "In4.Cu")
		(net "GMI_CPU1_G2_CPU0_G0_TX_DN<5>")
	)
	(segment
		(start 115.85575 -221.426278)
		(end 115.85575 -221.129098)
		(width 0.1143)
		(layer "In4.Cu")
		(net "GMI_CPU1_G2_CPU0_G0_TX_DN<5>")
	)
	(segment
		(start 355.27234 -224.53854)
		(end 355.30409 -224.556828)
		(width 0.1143)
		(layer "In4.Cu")
		(net "GMI_CPU1_G2_CPU0_G0_TX_DN<5>")
	)
	(segment
		(start 116.204492 -227.159312)
		(end 116.152676 -227.129086)
		(width 0.1143)
		(layer "In4.Cu")
		(net "GMI_CPU1_G2_CPU0_G0_TX_DN<5>")
	)
	(segment
		(start 354.723192 -228.284278)
		(end 355.021134 -228.284278)
		(width 0.1143)
		(layer "In4.Cu")
		(net "GMI_CPU1_G2_CPU0_G0_TX_DN<5>")
	)
	(segment
		(start 316.69863 -183.07939)
		(end 316.71768 -183.094884)
		(width 0.14224)
		(layer "In4.Cu")
		(net "GMI_CPU1_G2_CPU0_G0_TX_DN<5>")
	)
	(segment
		(start 152.414986 -184.901332)
		(end 157.683962 -180.581554)
		(width 0.14224)
		(layer "In4.Cu")
		(net "GMI_CPU1_G2_CPU0_G0_TX_DN<5>")
	)
	(segment
		(start 119.551704 -211.847176)
		(end 151.54275 -185.616342)
		(width 0.14224)
		(layer "In4.Cu")
		(net "GMI_CPU1_G2_CPU0_G0_TX_DN<5>")
	)
	(segment
		(start 116.223542 -225.550222)
		(end 116.191792 -225.531934)
		(width 0.1143)
		(layer "In4.Cu")
		(net "GMI_CPU1_G2_CPU0_G0_TX_DN<5>")
	)
	(segment
		(start 151.54275 -185.616342)
		(end 152.414986 -184.901332)
		(width 0.14224)
		(layer "In4.Cu")
		(net "GMI_CPU1_G2_CPU0_G0_TX_DN<5>")
	)
	(segment
		(start 355.640132 -221.128844)
		(end 355.640132 -221.426024)
		(width 0.1143)
		(layer "In4.Cu")
		(net "GMI_CPU1_G2_CPU0_G0_TX_DN<5>")
	)
	(segment
		(start 116.474748 -228.284532)
		(end 116.77269 -228.284532)
		(width 0.1143)
		(layer "In4.Cu")
		(net "GMI_CPU1_G2_CPU0_G0_TX_DN<5>")
	)
	(segment
		(start 316.71768 -183.094884)
		(end 351.986342 -212.0138)
		(width 0.14224)
		(layer "In4.Cu")
		(net "GMI_CPU1_G2_CPU0_G0_TX_DN<5>")
	)
	(segment
		(start 355.27234 -223.929956)
		(end 355.252528 -223.94418)
		(width 0.1143)
		(layer "In4.Cu")
		(net "GMI_CPU1_G2_CPU0_G0_TX_DN<5>")
	)
	(segment
		(start 307.900578 -178.566064)
		(end 310.141112 -179.36718)
		(width 0.14224)
		(layer "In4.Cu")
		(net "GMI_CPU1_G2_CPU0_G0_TX_DN<5>")
	)
	(segment
		(start 116.191792 -222.93707)
		(end 116.223542 -222.918782)
		(width 0.1143)
		(layer "In4.Cu")
		(net "GMI_CPU1_G2_CPU0_G0_TX_DN<5>")
	)
	(segment
		(start 116.243354 -223.944434)
		(end 116.223542 -223.93021)
		(width 0.1143)
		(layer "In4.Cu")
		(net "GMI_CPU1_G2_CPU0_G0_TX_DN<5>")
	)
	(segment
		(start 116.223542 -224.538794)
		(end 116.243354 -224.52457)
		(width 0.1143)
		(layer "In4.Cu")
		(net "GMI_CPU1_G2_CPU0_G0_TX_DN<5>")
	)
	(segment
		(start 115.85575 -221.129098)
		(end 115.81003 -221.083378)
		(width 0.1143)
		(layer "In4.Cu")
		(net "GMI_CPU1_G2_CPU0_G0_TX_DN<5>")
	)
	(arc
		(start 116.392198 -227.484178)
		(mid 116.341892 -227.29659)
		(end 116.204492 -227.159312)
		(width 0.1143)
		(layer "In4.Cu")
		(net "GMI_CPU1_G2_CPU0_G0_TX_DN<5>")
	)
	(arc
		(start 116.223542 -226.158806)
		(mid 116.375131 -225.854514)
		(end 116.223542 -225.550222)
		(width 0.1143)
		(layer "In4.Cu")
		(net "GMI_CPU1_G2_CPU0_G0_TX_DN<5>")
	)
	(arc
		(start 116.152676 -227.129086)
		(mid 115.909349 -226.66452)
		(end 116.152676 -226.199954)
		(width 0.1143)
		(layer "In4.Cu")
		(net "GMI_CPU1_G2_CPU0_G0_TX_DN<5>")
	)
	(arc
		(start 354.80244 -227.979986)
		(mid 354.705305 -228.082855)
		(end 354.653342 -228.214428)
		(width 0.1143)
		(layer "In4.Cu")
		(net "GMI_CPU1_G2_CPU0_G0_TX_DN<5>")
	)
	(arc
		(start 116.152676 -222.26905)
		(mid 115.974018 -222.06665)
		(end 115.909598 -221.804484)
		(width 0.1143)
		(layer "In4.Cu")
		(net "GMI_CPU1_G2_CPU0_G0_TX_DN<5>")
	)
	(arc
		(start 355.103684 -227.49637)
		(mid 355.032098 -227.7641)
		(end 354.836476 -227.960428)
		(width 0.1143)
		(layer "In4.Cu")
		(net "GMI_CPU1_G2_CPU0_G0_TX_DN<5>")
	)
	(arc
		(start 116.223542 -222.918782)
		(mid 116.375131 -222.61449)
		(end 116.223542 -222.310198)
		(width 0.1143)
		(layer "In4.Cu")
		(net "GMI_CPU1_G2_CPU0_G0_TX_DN<5>")
	)
	(arc
		(start 355.343206 -226.1997)
		(mid 355.586533 -226.664266)
		(end 355.343206 -227.128832)
		(width 0.1143)
		(layer "In4.Cu")
		(net "GMI_CPU1_G2_CPU0_G0_TX_DN<5>")
	)
	(arc
		(start 355.27234 -225.549968)
		(mid 355.120751 -225.85426)
		(end 355.27234 -226.158552)
		(width 0.1143)
		(layer "In4.Cu")
		(net "GMI_CPU1_G2_CPU0_G0_TX_DN<5>")
	)
	(arc
		(start 355.343206 -222.959676)
		(mid 355.586533 -223.424242)
		(end 355.343206 -223.888808)
		(width 0.1143)
		(layer "In4.Cu")
		(net "GMI_CPU1_G2_CPU0_G0_TX_DN<5>")
	)
	(arc
		(start 355.343206 -224.579688)
		(mid 355.586533 -225.044254)
		(end 355.343206 -225.50882)
		(width 0.1143)
		(layer "In4.Cu")
		(net "GMI_CPU1_G2_CPU0_G0_TX_DN<5>")
	)
	(arc
		(start 355.252528 -223.94418)
		(mid 355.103814 -224.234248)
		(end 355.252528 -224.524316)
		(width 0.1143)
		(layer "In4.Cu")
		(net "GMI_CPU1_G2_CPU0_G0_TX_DN<5>")
	)
	(arc
		(start 116.243354 -224.52457)
		(mid 116.392068 -224.234502)
		(end 116.243354 -223.944434)
		(width 0.1143)
		(layer "In4.Cu")
		(net "GMI_CPU1_G2_CPU0_G0_TX_DN<5>")
	)
	(arc
		(start 116.659406 -227.960682)
		(mid 116.463732 -227.764384)
		(end 116.392198 -227.496624)
		(width 0.1143)
		(layer "In4.Cu")
		(net "GMI_CPU1_G2_CPU0_G0_TX_DN<5>")
	)
	(arc
		(start 116.152676 -223.889062)
		(mid 115.909349 -223.424496)
		(end 116.152676 -222.95993)
		(width 0.1143)
		(layer "In4.Cu")
		(net "GMI_CPU1_G2_CPU0_G0_TX_DN<5>")
	)
	(arc
		(start 355.29139 -227.159058)
		(mid 355.153958 -227.296317)
		(end 355.103684 -227.483924)
		(width 0.1143)
		(layer "In4.Cu")
		(net "GMI_CPU1_G2_CPU0_G0_TX_DN<5>")
	)
	(arc
		(start 355.586284 -221.80423)
		(mid 355.521837 -222.066382)
		(end 355.343206 -222.268796)
		(width 0.1143)
		(layer "In4.Cu")
		(net "GMI_CPU1_G2_CPU0_G0_TX_DN<5>")
	)
	(arc
		(start 355.27234 -222.309944)
		(mid 355.120751 -222.614236)
		(end 355.27234 -222.918528)
		(width 0.1143)
		(layer "In4.Cu")
		(net "GMI_CPU1_G2_CPU0_G0_TX_DN<5>")
	)
	(arc
		(start 116.84254 -228.214682)
		(mid 116.790491 -228.083163)
		(end 116.693442 -227.98024)
		(width 0.1143)
		(layer "In4.Cu")
		(net "GMI_CPU1_G2_CPU0_G0_TX_DN<5>")
	)
	(arc
		(start 116.152676 -225.509074)
		(mid 115.909349 -225.044508)
		(end 116.152676 -224.579942)
		(width 0.1143)
		(layer "In4.Cu")
		(net "GMI_CPU1_G2_CPU0_G0_TX_DN<5>")
	)
	(segment
		(start 355.487986 -226.930204)
		(end 355.021134 -226.664266)
		(width 0.12954)
		(layer "F.Cu")
		(net "GMI_CPU1_G2_CPU0_G0_TX_DN<4>")
	)
	(segment
		(start 116.007896 -226.930458)
		(end 116.474748 -226.66452)
		(width 0.12954)
		(layer "F.Cu")
		(net "GMI_CPU1_G2_CPU0_G0_TX_DN<4>")
	)
	(segment
		(start 117.131846 -222.93707)
		(end 117.09273 -222.95993)
		(width 0.1143)
		(layer "In4.Cu")
		(net "GMI_CPU1_G2_CPU0_G0_TX_DN<4>")
	)
	(segment
		(start 117.131846 -224.557082)
		(end 117.09273 -224.579942)
		(width 0.1143)
		(layer "In4.Cu")
		(net "GMI_CPU1_G2_CPU0_G0_TX_DN<4>")
	)
	(segment
		(start 354.64623 -221.80423)
		(end 354.64623 -221.475046)
		(width 0.1143)
		(layer "In4.Cu")
		(net "GMI_CPU1_G2_CPU0_G0_TX_DN<4>")
	)
	(segment
		(start 354.695252 -221.426024)
		(end 354.695252 -221.128844)
		(width 0.1143)
		(layer "In4.Cu")
		(net "GMI_CPU1_G2_CPU0_G0_TX_DN<4>")
	)
	(segment
		(start 165.79088 -178.701954)
		(end 158.503112 -181.30774)
		(width 0.14224)
		(layer "In4.Cu")
		(net "GMI_CPU1_G2_CPU0_G0_TX_DN<4>")
	)
	(segment
		(start 116.855494 -226.581716)
		(end 116.77269 -226.66452)
		(width 0.1143)
		(layer "In4.Cu")
		(net "GMI_CPU1_G2_CPU0_G0_TX_DN<4>")
	)
	(segment
		(start 351.26803 -212.630766)
		(end 316.182756 -183.861964)
		(width 0.14224)
		(layer "In4.Cu")
		(net "GMI_CPU1_G2_CPU0_G0_TX_DN<4>")
	)
	(segment
		(start 158.503112 -181.30774)
		(end 153.862024 -185.112152)
		(width 0.14224)
		(layer "In4.Cu")
		(net "GMI_CPU1_G2_CPU0_G0_TX_DN<4>")
	)
	(segment
		(start 116.80063 -221.426278)
		(end 116.849652 -221.4753)
		(width 0.1143)
		(layer "In4.Cu")
		(net "GMI_CPU1_G2_CPU0_G0_TX_DN<4>")
	)
	(segment
		(start 354.333556 -225.54946)
		(end 354.403152 -225.50882)
		(width 0.1143)
		(layer "In4.Cu")
		(net "GMI_CPU1_G2_CPU0_G0_TX_DN<4>")
	)
	(segment
		(start 355.021134 -226.664266)
		(end 354.723192 -226.664266)
		(width 0.1143)
		(layer "In4.Cu")
		(net "GMI_CPU1_G2_CPU0_G0_TX_DN<4>")
	)
	(segment
		(start 117.162326 -226.159314)
		(end 117.131846 -226.177094)
		(width 0.1143)
		(layer "In4.Cu")
		(net "GMI_CPU1_G2_CPU0_G0_TX_DN<4>")
	)
	(segment
		(start 354.64623 -221.475046)
		(end 354.695252 -221.426024)
		(width 0.1143)
		(layer "In4.Cu")
		(net "GMI_CPU1_G2_CPU0_G0_TX_DN<4>")
	)
	(segment
		(start 354.740972 -221.083124)
		(end 354.740972 -218.479878)
		(width 0.14224)
		(layer "In4.Cu")
		(net "GMI_CPU1_G2_CPU0_G0_TX_DN<4>")
	)
	(segment
		(start 316.182756 -183.861964)
		(end 309.912512 -180.312568)
		(width 0.14224)
		(layer "In4.Cu")
		(net "GMI_CPU1_G2_CPU0_G0_TX_DN<4>")
	)
	(segment
		(start 354.723192 -226.664266)
		(end 354.640388 -226.581462)
		(width 0.1143)
		(layer "In4.Cu")
		(net "GMI_CPU1_G2_CPU0_G0_TX_DN<4>")
	)
	(segment
		(start 117.09273 -225.509074)
		(end 117.131846 -225.531934)
		(width 0.1143)
		(layer "In4.Cu")
		(net "GMI_CPU1_G2_CPU0_G0_TX_DN<4>")
	)
	(segment
		(start 302.90516 -179.492148)
		(end 167.455596 -178.701954)
		(width 0.14224)
		(layer "In4.Cu")
		(net "GMI_CPU1_G2_CPU0_G0_TX_DN<4>")
	)
	(segment
		(start 144.24279 -192.998598)
		(end 144.013682 -193.068194)
		(width 0.14224)
		(layer "In4.Cu")
		(net "GMI_CPU1_G2_CPU0_G0_TX_DN<4>")
	)
	(segment
		(start 117.09273 -222.26905)
		(end 117.162326 -222.30969)
		(width 0.1143)
		(layer "In4.Cu")
		(net "GMI_CPU1_G2_CPU0_G0_TX_DN<4>")
	)
	(segment
		(start 116.80063 -221.129098)
		(end 116.80063 -221.426278)
		(width 0.1143)
		(layer "In4.Cu")
		(net "GMI_CPU1_G2_CPU0_G0_TX_DN<4>")
	)
	(segment
		(start 120.238012 -212.563456)
		(end 116.75491 -218.505532)
		(width 0.14224)
		(layer "In4.Cu")
		(net "GMI_CPU1_G2_CPU0_G0_TX_DN<4>")
	)
	(segment
		(start 144.013682 -193.068194)
		(end 120.238012 -212.563456)
		(width 0.14224)
		(layer "In4.Cu")
		(net "GMI_CPU1_G2_CPU0_G0_TX_DN<4>")
	)
	(segment
		(start 153.01341 -185.807858)
		(end 152.077928 -186.574938)
		(width 0.14224)
		(layer "In4.Cu")
		(net "GMI_CPU1_G2_CPU0_G0_TX_DN<4>")
	)
	(segment
		(start 153.862024 -185.112152)
		(end 153.01341 -185.807858)
		(width 0.14224)
		(layer "In4.Cu")
		(net "GMI_CPU1_G2_CPU0_G0_TX_DN<4>")
	)
	(segment
		(start 117.131846 -225.531934)
		(end 117.162326 -225.549714)
		(width 0.1143)
		(layer "In4.Cu")
		(net "GMI_CPU1_G2_CPU0_G0_TX_DN<4>")
	)
	(segment
		(start 167.455596 -178.701954)
		(end 165.79088 -178.701954)
		(width 0.14224)
		(layer "In4.Cu")
		(net "GMI_CPU1_G2_CPU0_G0_TX_DN<4>")
	)
	(segment
		(start 117.162326 -224.539302)
		(end 117.131846 -224.557082)
		(width 0.1143)
		(layer "In4.Cu")
		(net "GMI_CPU1_G2_CPU0_G0_TX_DN<4>")
	)
	(segment
		(start 117.131846 -223.911922)
		(end 117.162326 -223.929702)
		(width 0.1143)
		(layer "In4.Cu")
		(net "GMI_CPU1_G2_CPU0_G0_TX_DN<4>")
	)
	(segment
		(start 117.09273 -223.889062)
		(end 117.131846 -223.911922)
		(width 0.1143)
		(layer "In4.Cu")
		(net "GMI_CPU1_G2_CPU0_G0_TX_DN<4>")
	)
	(segment
		(start 117.131846 -226.177094)
		(end 117.09273 -226.199954)
		(width 0.1143)
		(layer "In4.Cu")
		(net "GMI_CPU1_G2_CPU0_G0_TX_DN<4>")
	)
	(segment
		(start 116.75491 -218.505532)
		(end 116.75491 -221.05493)
		(width 0.14224)
		(layer "In4.Cu")
		(net "GMI_CPU1_G2_CPU0_G0_TX_DN<4>")
	)
	(segment
		(start 354.333556 -222.309436)
		(end 354.403152 -222.268796)
		(width 0.1143)
		(layer "In4.Cu")
		(net "GMI_CPU1_G2_CPU0_G0_TX_DN<4>")
	)
	(segment
		(start 309.912512 -180.312568)
		(end 307.617876 -179.492148)
		(width 0.14224)
		(layer "In4.Cu")
		(net "GMI_CPU1_G2_CPU0_G0_TX_DN<4>")
	)
	(segment
		(start 354.740972 -218.479878)
		(end 351.26803 -212.630766)
		(width 0.14224)
		(layer "In4.Cu")
		(net "GMI_CPU1_G2_CPU0_G0_TX_DN<4>")
	)
	(segment
		(start 116.75491 -221.083378)
		(end 116.80063 -221.129098)
		(width 0.1143)
		(layer "In4.Cu")
		(net "GMI_CPU1_G2_CPU0_G0_TX_DN<4>")
	)
	(segment
		(start 354.333556 -223.929448)
		(end 354.403152 -223.888808)
		(width 0.1143)
		(layer "In4.Cu")
		(net "GMI_CPU1_G2_CPU0_G0_TX_DN<4>")
	)
	(segment
		(start 116.849652 -221.4753)
		(end 116.849652 -221.804484)
		(width 0.1143)
		(layer "In4.Cu")
		(net "GMI_CPU1_G2_CPU0_G0_TX_DN<4>")
	)
	(segment
		(start 150.223982 -188.095128)
		(end 149.351746 -188.810138)
		(width 0.14224)
		(layer "In4.Cu")
		(net "GMI_CPU1_G2_CPU0_G0_TX_DN<4>")
	)
	(segment
		(start 354.403152 -224.579688)
		(end 354.333556 -224.539048)
		(width 0.1143)
		(layer "In4.Cu")
		(net "GMI_CPU1_G2_CPU0_G0_TX_DN<4>")
	)
	(segment
		(start 354.403152 -226.1997)
		(end 354.333556 -226.15906)
		(width 0.1143)
		(layer "In4.Cu")
		(net "GMI_CPU1_G2_CPU0_G0_TX_DN<4>")
	)
	(segment
		(start 354.695252 -221.128844)
		(end 354.740972 -221.083124)
		(width 0.1143)
		(layer "In4.Cu")
		(net "GMI_CPU1_G2_CPU0_G0_TX_DN<4>")
	)
	(segment
		(start 149.351746 -188.810138)
		(end 144.24279 -192.998598)
		(width 0.14224)
		(layer "In4.Cu")
		(net "GMI_CPU1_G2_CPU0_G0_TX_DN<4>")
	)
	(segment
		(start 116.77269 -226.66452)
		(end 116.474748 -226.66452)
		(width 0.1143)
		(layer "In4.Cu")
		(net "GMI_CPU1_G2_CPU0_G0_TX_DN<4>")
	)
	(segment
		(start 307.617876 -179.492148)
		(end 302.90516 -179.492148)
		(width 0.14224)
		(layer "In4.Cu")
		(net "GMI_CPU1_G2_CPU0_G0_TX_DN<4>")
	)
	(segment
		(start 152.077928 -186.574938)
		(end 150.223982 -188.095128)
		(width 0.14224)
		(layer "In4.Cu")
		(net "GMI_CPU1_G2_CPU0_G0_TX_DN<4>")
	)
	(segment
		(start 116.75491 -221.05493)
		(end 116.75491 -221.083378)
		(width 0.1143)
		(layer "In4.Cu")
		(net "GMI_CPU1_G2_CPU0_G0_TX_DN<4>")
	)
	(segment
		(start 354.403152 -222.959676)
		(end 354.333556 -222.919036)
		(width 0.1143)
		(layer "In4.Cu")
		(net "GMI_CPU1_G2_CPU0_G0_TX_DN<4>")
	)
	(segment
		(start 117.162326 -222.91929)
		(end 117.131846 -222.93707)
		(width 0.1143)
		(layer "In4.Cu")
		(net "GMI_CPU1_G2_CPU0_G0_TX_DN<4>")
	)
	(arc
		(start 354.640388 -226.581462)
		(mid 354.6386 -226.570013)
		(end 354.636578 -226.558602)
		(width 0.1143)
		(layer "In4.Cu")
		(net "GMI_CPU1_G2_CPU0_G0_TX_DN<4>")
	)
	(arc
		(start 354.333556 -224.539048)
		(mid 354.176579 -224.234248)
		(end 354.333556 -223.929448)
		(width 0.1143)
		(layer "In4.Cu")
		(net "GMI_CPU1_G2_CPU0_G0_TX_DN<4>")
	)
	(arc
		(start 354.403152 -222.268796)
		(mid 354.581795 -222.066401)
		(end 354.64623 -221.80423)
		(width 0.1143)
		(layer "In4.Cu")
		(net "GMI_CPU1_G2_CPU0_G0_TX_DN<4>")
	)
	(arc
		(start 354.403152 -223.888808)
		(mid 354.646479 -223.424242)
		(end 354.403152 -222.959676)
		(width 0.1143)
		(layer "In4.Cu")
		(net "GMI_CPU1_G2_CPU0_G0_TX_DN<4>")
	)
	(arc
		(start 117.162326 -225.549714)
		(mid 117.319303 -225.854514)
		(end 117.162326 -226.159314)
		(width 0.1143)
		(layer "In4.Cu")
		(net "GMI_CPU1_G2_CPU0_G0_TX_DN<4>")
	)
	(arc
		(start 354.333556 -226.15906)
		(mid 354.176579 -225.85426)
		(end 354.333556 -225.54946)
		(width 0.1143)
		(layer "In4.Cu")
		(net "GMI_CPU1_G2_CPU0_G0_TX_DN<4>")
	)
	(arc
		(start 117.162326 -222.30969)
		(mid 117.319303 -222.61449)
		(end 117.162326 -222.91929)
		(width 0.1143)
		(layer "In4.Cu")
		(net "GMI_CPU1_G2_CPU0_G0_TX_DN<4>")
	)
	(arc
		(start 117.09273 -222.95993)
		(mid 116.849403 -223.424496)
		(end 117.09273 -223.889062)
		(width 0.1143)
		(layer "In4.Cu")
		(net "GMI_CPU1_G2_CPU0_G0_TX_DN<4>")
	)
	(arc
		(start 116.849652 -221.804484)
		(mid 116.914026 -222.066688)
		(end 117.09273 -222.26905)
		(width 0.1143)
		(layer "In4.Cu")
		(net "GMI_CPU1_G2_CPU0_G0_TX_DN<4>")
	)
	(arc
		(start 354.333556 -222.919036)
		(mid 354.176579 -222.614236)
		(end 354.333556 -222.309436)
		(width 0.1143)
		(layer "In4.Cu")
		(net "GMI_CPU1_G2_CPU0_G0_TX_DN<4>")
	)
	(arc
		(start 354.636578 -226.558602)
		(mid 354.555145 -226.356204)
		(end 354.403152 -226.1997)
		(width 0.1143)
		(layer "In4.Cu")
		(net "GMI_CPU1_G2_CPU0_G0_TX_DN<4>")
	)
	(arc
		(start 117.09273 -224.579942)
		(mid 116.849403 -225.044508)
		(end 117.09273 -225.509074)
		(width 0.1143)
		(layer "In4.Cu")
		(net "GMI_CPU1_G2_CPU0_G0_TX_DN<4>")
	)
	(arc
		(start 117.09273 -226.199954)
		(mid 116.940743 -226.356462)
		(end 116.859304 -226.558856)
		(width 0.1143)
		(layer "In4.Cu")
		(net "GMI_CPU1_G2_CPU0_G0_TX_DN<4>")
	)
	(arc
		(start 116.859304 -226.558856)
		(mid 116.857281 -226.570266)
		(end 116.855494 -226.581716)
		(width 0.1143)
		(layer "In4.Cu")
		(net "GMI_CPU1_G2_CPU0_G0_TX_DN<4>")
	)
	(arc
		(start 117.162326 -223.929702)
		(mid 117.319303 -224.234502)
		(end 117.162326 -224.539302)
		(width 0.1143)
		(layer "In4.Cu")
		(net "GMI_CPU1_G2_CPU0_G0_TX_DN<4>")
	)
	(arc
		(start 354.403152 -225.50882)
		(mid 354.646479 -225.044254)
		(end 354.403152 -224.579688)
		(width 0.1143)
		(layer "In4.Cu")
		(net "GMI_CPU1_G2_CPU0_G0_TX_DN<4>")
	)
	(segment
		(start 355.487986 -230.169974)
		(end 355.021134 -229.904036)
		(width 0.12954)
		(layer "F.Cu")
		(net "GMI_CPU1_G2_CPU0_G0_TX_DN<3>")
	)
	(segment
		(start 116.007896 -230.170228)
		(end 116.474748 -229.90429)
		(width 0.12954)
		(layer "F.Cu")
		(net "GMI_CPU1_G2_CPU0_G0_TX_DN<3>")
	)
	(segment
		(start 356.217474 -227.167186)
		(end 356.21849 -227.166678)
		(width 0.1143)
		(layer "In4.Cu")
		(net "GMI_CPU1_G2_CPU0_G0_TX_DN<3>")
	)
	(segment
		(start 356.630732 -221.083124)
		(end 356.630732 -217.740738)
		(width 0.14224)
		(layer "In4.Cu")
		(net "GMI_CPU1_G2_CPU0_G0_TX_DN<3>")
	)
	(segment
		(start 356.242112 -222.935546)
		(end 356.212394 -222.918528)
		(width 0.1143)
		(layer "In4.Cu")
		(net "GMI_CPU1_G2_CPU0_G0_TX_DN<3>")
	)
	(segment
		(start 115.2525 -222.936562)
		(end 115.251738 -222.93707)
		(width 0.1143)
		(layer "In4.Cu")
		(net "GMI_CPU1_G2_CPU0_G0_TX_DN<3>")
	)
	(segment
		(start 115.251738 -223.911922)
		(end 115.2525 -223.91243)
		(width 0.1143)
		(layer "In4.Cu")
		(net "GMI_CPU1_G2_CPU0_G0_TX_DN<3>")
	)
	(segment
		(start 356.630732 -217.740738)
		(end 352.91776 -211.486496)
		(width 0.14224)
		(layer "In4.Cu")
		(net "GMI_CPU1_G2_CPU0_G0_TX_DN<3>")
	)
	(segment
		(start 355.304852 -228.772466)
		(end 355.336602 -228.751892)
		(width 0.1143)
		(layer "In4.Cu")
		(net "GMI_CPU1_G2_CPU0_G0_TX_DN<3>")
	)
	(segment
		(start 356.246684 -223.910144)
		(end 356.28326 -223.888808)
		(width 0.1143)
		(layer "In4.Cu")
		(net "GMI_CPU1_G2_CPU0_G0_TX_DN<3>")
	)
	(segment
		(start 356.244144 -222.291656)
		(end 356.24516 -222.291148)
		(width 0.1143)
		(layer "In4.Cu")
		(net "GMI_CPU1_G2_CPU0_G0_TX_DN<3>")
	)
	(segment
		(start 356.212394 -223.929956)
		(end 356.243382 -223.912176)
		(width 0.1143)
		(layer "In4.Cu")
		(net "GMI_CPU1_G2_CPU0_G0_TX_DN<3>")
	)
	(segment
		(start 356.243382 -224.55632)
		(end 356.242112 -224.555558)
		(width 0.1143)
		(layer "In4.Cu")
		(net "GMI_CPU1_G2_CPU0_G0_TX_DN<3>")
	)
	(segment
		(start 114.86515 -221.05493)
		(end 114.86515 -221.083378)
		(width 0.1143)
		(layer "In4.Cu")
		(net "GMI_CPU1_G2_CPU0_G0_TX_DN<3>")
	)
	(segment
		(start 356.28326 -222.959676)
		(end 356.280466 -222.957644)
		(width 0.1143)
		(layer "In4.Cu")
		(net "GMI_CPU1_G2_CPU0_G0_TX_DN<3>")
	)
	(segment
		(start 114.91087 -221.426278)
		(end 114.969544 -221.484952)
		(width 0.1143)
		(layer "In4.Cu")
		(net "GMI_CPU1_G2_CPU0_G0_TX_DN<3>")
	)
	(segment
		(start 355.27234 -228.789992)
		(end 355.302566 -228.77272)
		(width 0.1143)
		(layer "In4.Cu")
		(net "GMI_CPU1_G2_CPU0_G0_TX_DN<3>")
	)
	(segment
		(start 115.248182 -222.289878)
		(end 115.249198 -222.290386)
		(width 0.1143)
		(layer "In4.Cu")
		(net "GMI_CPU1_G2_CPU0_G0_TX_DN<3>")
	)
	(segment
		(start 317.38951 -182.354728)
		(end 310.593486 -178.507644)
		(width 0.14224)
		(layer "In4.Cu")
		(net "GMI_CPU1_G2_CPU0_G0_TX_DN<3>")
	)
	(segment
		(start 115.25377 -222.9358)
		(end 115.2525 -222.936562)
		(width 0.1143)
		(layer "In4.Cu")
		(net "GMI_CPU1_G2_CPU0_G0_TX_DN<3>")
	)
	(segment
		(start 115.25377 -224.555812)
		(end 115.2525 -224.556574)
		(width 0.1143)
		(layer "In4.Cu")
		(net "GMI_CPU1_G2_CPU0_G0_TX_DN<3>")
	)
	(segment
		(start 115.250722 -227.151438)
		(end 115.251738 -227.151946)
		(width 0.1143)
		(layer "In4.Cu")
		(net "GMI_CPU1_G2_CPU0_G0_TX_DN<3>")
	)
	(segment
		(start 356.244144 -227.151692)
		(end 356.24516 -227.151184)
		(width 0.1143)
		(layer "In4.Cu")
		(net "GMI_CPU1_G2_CPU0_G0_TX_DN<3>")
	)
	(segment
		(start 115.28171 -227.169472)
		(end 115.282726 -227.16998)
		(width 0.1143)
		(layer "In4.Cu")
		(net "GMI_CPU1_G2_CPU0_G0_TX_DN<3>")
	)
	(segment
		(start 115.250722 -225.531426)
		(end 115.251738 -225.531934)
		(width 0.1143)
		(layer "In4.Cu")
		(net "GMI_CPU1_G2_CPU0_G0_TX_DN<3>")
	)
	(segment
		(start 356.21849 -227.166678)
		(end 356.243382 -227.1522)
		(width 0.1143)
		(layer "In4.Cu")
		(net "GMI_CPU1_G2_CPU0_G0_TX_DN<3>")
	)
	(segment
		(start 115.25377 -226.175824)
		(end 115.2525 -226.176586)
		(width 0.1143)
		(layer "In4.Cu")
		(net "GMI_CPU1_G2_CPU0_G0_TX_DN<3>")
	)
	(segment
		(start 115.695222 -227.95865)
		(end 115.734084 -227.98151)
		(width 0.1143)
		(layer "In4.Cu")
		(net "GMI_CPU1_G2_CPU0_G0_TX_DN<3>")
	)
	(segment
		(start 115.249198 -225.53041)
		(end 115.250722 -225.531426)
		(width 0.1143)
		(layer "In4.Cu")
		(net "GMI_CPU1_G2_CPU0_G0_TX_DN<3>")
	)
	(segment
		(start 356.526338 -221.484698)
		(end 356.585012 -221.426024)
		(width 0.1143)
		(layer "In4.Cu")
		(net "GMI_CPU1_G2_CPU0_G0_TX_DN<3>")
	)
	(segment
		(start 115.251738 -225.531934)
		(end 115.2525 -225.532442)
		(width 0.1143)
		(layer "In4.Cu")
		(net "GMI_CPU1_G2_CPU0_G0_TX_DN<3>")
	)
	(segment
		(start 356.246684 -227.150168)
		(end 356.28326 -227.128832)
		(width 0.1143)
		(layer "In4.Cu")
		(net "GMI_CPU1_G2_CPU0_G0_TX_DN<3>")
	)
	(segment
		(start 356.244144 -223.911668)
		(end 356.24516 -223.91116)
		(width 0.1143)
		(layer "In4.Cu")
		(net "GMI_CPU1_G2_CPU0_G0_TX_DN<3>")
	)
	(segment
		(start 356.214172 -227.169218)
		(end 356.217474 -227.167186)
		(width 0.1143)
		(layer "In4.Cu")
		(net "GMI_CPU1_G2_CPU0_G0_TX_DN<3>")
	)
	(segment
		(start 355.302566 -228.77272)
		(end 355.303836 -228.772974)
		(width 0.1143)
		(layer "In4.Cu")
		(net "GMI_CPU1_G2_CPU0_G0_TX_DN<3>")
	)
	(segment
		(start 356.242112 -224.555558)
		(end 356.212394 -224.53854)
		(width 0.1143)
		(layer "In4.Cu")
		(net "GMI_CPU1_G2_CPU0_G0_TX_DN<3>")
	)
	(segment
		(start 356.28326 -226.1997)
		(end 356.24516 -226.177348)
		(width 0.1143)
		(layer "In4.Cu")
		(net "GMI_CPU1_G2_CPU0_G0_TX_DN<3>")
	)
	(segment
		(start 310.593486 -178.507644)
		(end 308.091586 -177.613056)
		(width 0.14224)
		(layer "In4.Cu")
		(net "GMI_CPU1_G2_CPU0_G0_TX_DN<3>")
	)
	(segment
		(start 356.526338 -221.80423)
		(end 356.526338 -221.484698)
		(width 0.1143)
		(layer "In4.Cu")
		(net "GMI_CPU1_G2_CPU0_G0_TX_DN<3>")
	)
	(segment
		(start 115.283488 -224.538794)
		(end 115.25377 -224.555812)
		(width 0.1143)
		(layer "In4.Cu")
		(net "GMI_CPU1_G2_CPU0_G0_TX_DN<3>")
	)
	(segment
		(start 115.250722 -224.55759)
		(end 115.212622 -224.579942)
		(width 0.1143)
		(layer "In4.Cu")
		(net "GMI_CPU1_G2_CPU0_G0_TX_DN<3>")
	)
	(segment
		(start 356.24516 -223.91116)
		(end 356.246684 -223.910144)
		(width 0.1143)
		(layer "In4.Cu")
		(net "GMI_CPU1_G2_CPU0_G0_TX_DN<3>")
	)
	(segment
		(start 356.243382 -225.532188)
		(end 356.244144 -225.53168)
		(width 0.1143)
		(layer "In4.Cu")
		(net "GMI_CPU1_G2_CPU0_G0_TX_DN<3>")
	)
	(segment
		(start 115.277392 -227.166932)
		(end 115.278408 -227.16744)
		(width 0.1143)
		(layer "In4.Cu")
		(net "GMI_CPU1_G2_CPU0_G0_TX_DN<3>")
	)
	(segment
		(start 356.280466 -222.957644)
		(end 356.244144 -222.936816)
		(width 0.1143)
		(layer "In4.Cu")
		(net "GMI_CPU1_G2_CPU0_G0_TX_DN<3>")
	)
	(segment
		(start 115.212622 -223.889062)
		(end 115.249198 -223.910398)
		(width 0.1143)
		(layer "In4.Cu")
		(net "GMI_CPU1_G2_CPU0_G0_TX_DN<3>")
	)
	(segment
		(start 355.586538 -228.284024)
		(end 355.586538 -228.283516)
		(width 0.1143)
		(layer "In4.Cu")
		(net "GMI_CPU1_G2_CPU0_G0_TX_DN<3>")
	)
	(segment
		(start 356.212394 -225.549968)
		(end 356.243382 -225.532188)
		(width 0.1143)
		(layer "In4.Cu")
		(net "GMI_CPU1_G2_CPU0_G0_TX_DN<3>")
	)
	(segment
		(start 115.250722 -226.177602)
		(end 115.212622 -226.199954)
		(width 0.1143)
		(layer "In4.Cu")
		(net "GMI_CPU1_G2_CPU0_G0_TX_DN<3>")
	)
	(segment
		(start 116.192046 -228.773228)
		(end 116.193316 -228.772974)
		(width 0.1143)
		(layer "In4.Cu")
		(net "GMI_CPU1_G2_CPU0_G0_TX_DN<3>")
	)
	(segment
		(start 356.24516 -225.531172)
		(end 356.246684 -225.530156)
		(width 0.1143)
		(layer "In4.Cu")
		(net "GMI_CPU1_G2_CPU0_G0_TX_DN<3>")
	)
	(segment
		(start 115.251738 -222.29191)
		(end 115.283488 -222.310198)
		(width 0.1143)
		(layer "In4.Cu")
		(net "GMI_CPU1_G2_CPU0_G0_TX_DN<3>")
	)
	(segment
		(start 356.242112 -226.17557)
		(end 356.212394 -226.158552)
		(width 0.1143)
		(layer "In4.Cu")
		(net "GMI_CPU1_G2_CPU0_G0_TX_DN<3>")
	)
	(segment
		(start 115.251738 -222.93707)
		(end 115.215416 -222.957898)
		(width 0.1143)
		(layer "In4.Cu")
		(net "GMI_CPU1_G2_CPU0_G0_TX_DN<3>")
	)
	(segment
		(start 355.761798 -227.981256)
		(end 355.80066 -227.958396)
		(width 0.1143)
		(layer "In4.Cu")
		(net "GMI_CPU1_G2_CPU0_G0_TX_DN<3>")
	)
	(segment
		(start 115.909344 -228.28377)
		(end 115.909344 -228.284278)
		(width 0.1143)
		(layer "In4.Cu")
		(net "GMI_CPU1_G2_CPU0_G0_TX_DN<3>")
	)
	(segment
		(start 356.244144 -225.53168)
		(end 356.24516 -225.531172)
		(width 0.1143)
		(layer "In4.Cu")
		(net "GMI_CPU1_G2_CPU0_G0_TX_DN<3>")
	)
	(segment
		(start 356.24516 -224.557336)
		(end 356.244144 -224.556828)
		(width 0.1143)
		(layer "In4.Cu")
		(net "GMI_CPU1_G2_CPU0_G0_TX_DN<3>")
	)
	(segment
		(start 157.228032 -179.742846)
		(end 118.442486 -211.545424)
		(width 0.14224)
		(layer "In4.Cu")
		(net "GMI_CPU1_G2_CPU0_G0_TX_DN<3>")
	)
	(segment
		(start 115.212622 -225.509074)
		(end 115.249198 -225.53041)
		(width 0.1143)
		(layer "In4.Cu")
		(net "GMI_CPU1_G2_CPU0_G0_TX_DN<3>")
	)
	(segment
		(start 115.2525 -226.176586)
		(end 115.251738 -226.177094)
		(width 0.1143)
		(layer "In4.Cu")
		(net "GMI_CPU1_G2_CPU0_G0_TX_DN<3>")
	)
	(segment
		(start 115.452398 -227.467414)
		(end 115.452398 -227.494592)
		(width 0.1143)
		(layer "In4.Cu")
		(net "GMI_CPU1_G2_CPU0_G0_TX_DN<3>")
	)
	(segment
		(start 167.012112 -176.819814)
		(end 167.011858 -176.81956)
		(width 0.14224)
		(layer "In4.Cu")
		(net "GMI_CPU1_G2_CPU0_G0_TX_DN<3>")
	)
	(segment
		(start 356.585012 -221.426024)
		(end 356.585012 -221.128844)
		(width 0.1143)
		(layer "In4.Cu")
		(net "GMI_CPU1_G2_CPU0_G0_TX_DN<3>")
	)
	(segment
		(start 356.243382 -226.176332)
		(end 356.242112 -226.17557)
		(width 0.1143)
		(layer "In4.Cu")
		(net "GMI_CPU1_G2_CPU0_G0_TX_DN<3>")
	)
	(segment
		(start 115.215416 -222.957898)
		(end 115.212622 -222.95993)
		(width 0.1143)
		(layer "In4.Cu")
		(net "GMI_CPU1_G2_CPU0_G0_TX_DN<3>")
	)
	(segment
		(start 356.043484 -227.494338)
		(end 356.043484 -227.46716)
		(width 0.1143)
		(layer "In4.Cu")
		(net "GMI_CPU1_G2_CPU0_G0_TX_DN<3>")
	)
	(segment
		(start 116.77269 -229.90429)
		(end 116.474748 -229.90429)
		(width 0.1143)
		(layer "In4.Cu")
		(net "GMI_CPU1_G2_CPU0_G0_TX_DN<3>")
	)
	(segment
		(start 356.24516 -227.151184)
		(end 356.246684 -227.150168)
		(width 0.1143)
		(layer "In4.Cu")
		(net "GMI_CPU1_G2_CPU0_G0_TX_DN<3>")
	)
	(segment
		(start 356.243382 -222.936308)
		(end 356.242112 -222.935546)
		(width 0.1143)
		(layer "In4.Cu")
		(net "GMI_CPU1_G2_CPU0_G0_TX_DN<3>")
	)
	(segment
		(start 115.212622 -222.26905)
		(end 115.248182 -222.289878)
		(width 0.1143)
		(layer "In4.Cu")
		(net "GMI_CPU1_G2_CPU0_G0_TX_DN<3>")
	)
	(segment
		(start 302.911256 -177.613056)
		(end 167.048688 -176.819814)
		(width 0.14224)
		(layer "In4.Cu")
		(net "GMI_CPU1_G2_CPU0_G0_TX_DN<3>")
	)
	(segment
		(start 356.244144 -222.936816)
		(end 356.243382 -222.936308)
		(width 0.1143)
		(layer "In4.Cu")
		(net "GMI_CPU1_G2_CPU0_G0_TX_DN<3>")
	)
	(segment
		(start 115.251738 -227.151946)
		(end 115.2525 -227.152454)
		(width 0.1143)
		(layer "In4.Cu")
		(net "GMI_CPU1_G2_CPU0_G0_TX_DN<3>")
	)
	(segment
		(start 354.723192 -229.904036)
		(end 354.653342 -229.834186)
		(width 0.1143)
		(layer "In4.Cu")
		(net "GMI_CPU1_G2_CPU0_G0_TX_DN<3>")
	)
	(segment
		(start 116.62537 -229.560882)
		(end 116.661692 -229.581964)
		(width 0.1143)
		(layer "In4.Cu")
		(net "GMI_CPU1_G2_CPU0_G0_TX_DN<3>")
	)
	(segment
		(start 356.213156 -227.169726)
		(end 356.214172 -227.169218)
		(width 0.1143)
		(layer "In4.Cu")
		(net "GMI_CPU1_G2_CPU0_G0_TX_DN<3>")
	)
	(segment
		(start 355.303836 -228.772974)
		(end 355.304852 -228.772466)
		(width 0.1143)
		(layer "In4.Cu")
		(net "GMI_CPU1_G2_CPU0_G0_TX_DN<3>")
	)
	(segment
		(start 356.2477 -222.289624)
		(end 356.28326 -222.268796)
		(width 0.1143)
		(layer "In4.Cu")
		(net "GMI_CPU1_G2_CPU0_G0_TX_DN<3>")
	)
	(segment
		(start 115.2525 -225.532442)
		(end 115.283488 -225.550222)
		(width 0.1143)
		(layer "In4.Cu")
		(net "GMI_CPU1_G2_CPU0_G0_TX_DN<3>")
	)
	(segment
		(start 356.244144 -224.556828)
		(end 356.243382 -224.55632)
		(width 0.1143)
		(layer "In4.Cu")
		(net "GMI_CPU1_G2_CPU0_G0_TX_DN<3>")
	)
	(segment
		(start 115.251738 -224.557082)
		(end 115.250722 -224.55759)
		(width 0.1143)
		(layer "In4.Cu")
		(net "GMI_CPU1_G2_CPU0_G0_TX_DN<3>")
	)
	(segment
		(start 115.250722 -222.291402)
		(end 115.251738 -222.29191)
		(width 0.1143)
		(layer "In4.Cu")
		(net "GMI_CPU1_G2_CPU0_G0_TX_DN<3>")
	)
	(segment
		(start 114.91087 -221.129098)
		(end 114.91087 -221.426278)
		(width 0.1143)
		(layer "In4.Cu")
		(net "GMI_CPU1_G2_CPU0_G0_TX_DN<3>")
	)
	(segment
		(start 354.83419 -229.58171)
		(end 354.870512 -229.560628)
		(width 0.1143)
		(layer "In4.Cu")
		(net "GMI_CPU1_G2_CPU0_G0_TX_DN<3>")
	)
	(segment
		(start 356.24516 -222.291148)
		(end 356.246684 -222.290132)
		(width 0.1143)
		(layer "In4.Cu")
		(net "GMI_CPU1_G2_CPU0_G0_TX_DN<3>")
	)
	(segment
		(start 308.091586 -177.613056)
		(end 302.911256 -177.613056)
		(width 0.14224)
		(layer "In4.Cu")
		(net "GMI_CPU1_G2_CPU0_G0_TX_DN<3>")
	)
	(segment
		(start 115.2525 -224.556574)
		(end 115.251738 -224.557082)
		(width 0.1143)
		(layer "In4.Cu")
		(net "GMI_CPU1_G2_CPU0_G0_TX_DN<3>")
	)
	(segment
		(start 356.243382 -227.1522)
		(end 356.244144 -227.151692)
		(width 0.1143)
		(layer "In4.Cu")
		(net "GMI_CPU1_G2_CPU0_G0_TX_DN<3>")
	)
	(segment
		(start 165.404038 -176.81956)
		(end 157.228032 -179.742846)
		(width 0.14224)
		(layer "In4.Cu")
		(net "GMI_CPU1_G2_CPU0_G0_TX_DN<3>")
	)
	(segment
		(start 115.212622 -227.129086)
		(end 115.249198 -227.150422)
		(width 0.1143)
		(layer "In4.Cu")
		(net "GMI_CPU1_G2_CPU0_G0_TX_DN<3>")
	)
	(segment
		(start 114.86515 -221.083378)
		(end 114.91087 -221.129098)
		(width 0.1143)
		(layer "In4.Cu")
		(net "GMI_CPU1_G2_CPU0_G0_TX_DN<3>")
	)
	(segment
		(start 115.283488 -222.918782)
		(end 115.25377 -222.9358)
		(width 0.1143)
		(layer "In4.Cu")
		(net "GMI_CPU1_G2_CPU0_G0_TX_DN<3>")
	)
	(segment
		(start 354.800662 -229.601268)
		(end 354.83419 -229.58171)
		(width 0.1143)
		(layer "In4.Cu")
		(net "GMI_CPU1_G2_CPU0_G0_TX_DN<3>")
	)
	(segment
		(start 355.76129 -227.98151)
		(end 355.761798 -227.981256)
		(width 0.1143)
		(layer "In4.Cu")
		(net "GMI_CPU1_G2_CPU0_G0_TX_DN<3>")
	)
	(segment
		(start 356.28326 -224.579688)
		(end 356.24516 -224.557336)
		(width 0.1143)
		(layer "In4.Cu")
		(net "GMI_CPU1_G2_CPU0_G0_TX_DN<3>")
	)
	(segment
		(start 356.246684 -225.530156)
		(end 356.28326 -225.50882)
		(width 0.1143)
		(layer "In4.Cu")
		(net "GMI_CPU1_G2_CPU0_G0_TX_DN<3>")
	)
	(segment
		(start 167.048688 -176.819814)
		(end 167.012112 -176.819814)
		(width 0.14224)
		(layer "In4.Cu")
		(net "GMI_CPU1_G2_CPU0_G0_TX_DN<3>")
	)
	(segment
		(start 356.212394 -222.309944)
		(end 356.244144 -222.291656)
		(width 0.1143)
		(layer "In4.Cu")
		(net "GMI_CPU1_G2_CPU0_G0_TX_DN<3>")
	)
	(segment
		(start 356.244144 -226.17684)
		(end 356.243382 -226.176332)
		(width 0.1143)
		(layer "In4.Cu")
		(net "GMI_CPU1_G2_CPU0_G0_TX_DN<3>")
	)
	(segment
		(start 115.2525 -223.91243)
		(end 115.283488 -223.93021)
		(width 0.1143)
		(layer "In4.Cu")
		(net "GMI_CPU1_G2_CPU0_G0_TX_DN<3>")
	)
	(segment
		(start 115.250722 -223.911414)
		(end 115.251738 -223.911922)
		(width 0.1143)
		(layer "In4.Cu")
		(net "GMI_CPU1_G2_CPU0_G0_TX_DN<3>")
	)
	(segment
		(start 116.661692 -229.581964)
		(end 116.69522 -229.601522)
		(width 0.1143)
		(layer "In4.Cu")
		(net "GMI_CPU1_G2_CPU0_G0_TX_DN<3>")
	)
	(segment
		(start 115.283488 -226.158806)
		(end 115.25377 -226.175824)
		(width 0.1143)
		(layer "In4.Cu")
		(net "GMI_CPU1_G2_CPU0_G0_TX_DN<3>")
	)
	(segment
		(start 352.91776 -211.486496)
		(end 317.38951 -182.354728)
		(width 0.14224)
		(layer "In4.Cu")
		(net "GMI_CPU1_G2_CPU0_G0_TX_DN<3>")
	)
	(segment
		(start 115.249198 -222.290386)
		(end 115.250722 -222.291402)
		(width 0.1143)
		(layer "In4.Cu")
		(net "GMI_CPU1_G2_CPU0_G0_TX_DN<3>")
	)
	(segment
		(start 115.2525 -227.152454)
		(end 115.277392 -227.166932)
		(width 0.1143)
		(layer "In4.Cu")
		(net "GMI_CPU1_G2_CPU0_G0_TX_DN<3>")
	)
	(segment
		(start 116.15928 -228.752146)
		(end 116.19103 -228.77272)
		(width 0.1143)
		(layer "In4.Cu")
		(net "GMI_CPU1_G2_CPU0_G0_TX_DN<3>")
	)
	(segment
		(start 114.86515 -217.64498)
		(end 114.86515 -221.05493)
		(width 0.14224)
		(layer "In4.Cu")
		(net "GMI_CPU1_G2_CPU0_G0_TX_DN<3>")
	)
	(segment
		(start 115.249198 -227.150422)
		(end 115.250722 -227.151438)
		(width 0.1143)
		(layer "In4.Cu")
		(net "GMI_CPU1_G2_CPU0_G0_TX_DN<3>")
	)
	(segment
		(start 115.251738 -226.177094)
		(end 115.250722 -226.177602)
		(width 0.1143)
		(layer "In4.Cu")
		(net "GMI_CPU1_G2_CPU0_G0_TX_DN<3>")
	)
	(segment
		(start 355.021134 -229.904036)
		(end 354.723192 -229.904036)
		(width 0.1143)
		(layer "In4.Cu")
		(net "GMI_CPU1_G2_CPU0_G0_TX_DN<3>")
	)
	(segment
		(start 115.249198 -223.910398)
		(end 115.250722 -223.911414)
		(width 0.1143)
		(layer "In4.Cu")
		(net "GMI_CPU1_G2_CPU0_G0_TX_DN<3>")
	)
	(segment
		(start 115.278408 -227.16744)
		(end 115.28171 -227.169472)
		(width 0.1143)
		(layer "In4.Cu")
		(net "GMI_CPU1_G2_CPU0_G0_TX_DN<3>")
	)
	(segment
		(start 356.585012 -221.128844)
		(end 356.630732 -221.083124)
		(width 0.1143)
		(layer "In4.Cu")
		(net "GMI_CPU1_G2_CPU0_G0_TX_DN<3>")
	)
	(segment
		(start 115.734084 -227.98151)
		(end 115.734592 -227.981764)
		(width 0.1143)
		(layer "In4.Cu")
		(net "GMI_CPU1_G2_CPU0_G0_TX_DN<3>")
	)
	(segment
		(start 116.193316 -228.772974)
		(end 116.223542 -228.790246)
		(width 0.1143)
		(layer "In4.Cu")
		(net "GMI_CPU1_G2_CPU0_G0_TX_DN<3>")
	)
	(segment
		(start 114.969544 -221.484952)
		(end 114.969544 -221.804484)
		(width 0.1143)
		(layer "In4.Cu")
		(net "GMI_CPU1_G2_CPU0_G0_TX_DN<3>")
	)
	(segment
		(start 116.19103 -228.77272)
		(end 116.192046 -228.773228)
		(width 0.1143)
		(layer "In4.Cu")
		(net "GMI_CPU1_G2_CPU0_G0_TX_DN<3>")
	)
	(segment
		(start 356.24516 -226.177348)
		(end 356.244144 -226.17684)
		(width 0.1143)
		(layer "In4.Cu")
		(net "GMI_CPU1_G2_CPU0_G0_TX_DN<3>")
	)
	(segment
		(start 118.442486 -211.545424)
		(end 114.86515 -217.64498)
		(width 0.14224)
		(layer "In4.Cu")
		(net "GMI_CPU1_G2_CPU0_G0_TX_DN<3>")
	)
	(segment
		(start 356.246684 -222.290132)
		(end 356.2477 -222.289624)
		(width 0.1143)
		(layer "In4.Cu")
		(net "GMI_CPU1_G2_CPU0_G0_TX_DN<3>")
	)
	(segment
		(start 167.011858 -176.81956)
		(end 165.404038 -176.81956)
		(width 0.14224)
		(layer "In4.Cu")
		(net "GMI_CPU1_G2_CPU0_G0_TX_DN<3>")
	)
	(segment
		(start 116.84254 -229.83444)
		(end 116.77269 -229.90429)
		(width 0.1143)
		(layer "In4.Cu")
		(net "GMI_CPU1_G2_CPU0_G0_TX_DN<3>")
	)
	(segment
		(start 356.243382 -223.912176)
		(end 356.244144 -223.911668)
		(width 0.1143)
		(layer "In4.Cu")
		(net "GMI_CPU1_G2_CPU0_G0_TX_DN<3>")
	)
	(arc
		(start 115.212622 -224.579942)
		(mid 114.969295 -225.044508)
		(end 115.212622 -225.509074)
		(width 0.1143)
		(layer "In4.Cu")
		(net "GMI_CPU1_G2_CPU0_G0_TX_DN<3>")
	)
	(arc
		(start 115.452398 -227.494592)
		(mid 115.516749 -227.756498)
		(end 115.695222 -227.95865)
		(width 0.1143)
		(layer "In4.Cu")
		(net "GMI_CPU1_G2_CPU0_G0_TX_DN<3>")
	)
	(arc
		(start 116.379498 -229.094538)
		(mid 116.444734 -229.358129)
		(end 116.62537 -229.560882)
		(width 0.1143)
		(layer "In4.Cu")
		(net "GMI_CPU1_G2_CPU0_G0_TX_DN<3>")
	)
	(arc
		(start 356.28326 -223.888808)
		(mid 356.526587 -223.424242)
		(end 356.28326 -222.959676)
		(width 0.1143)
		(layer "In4.Cu")
		(net "GMI_CPU1_G2_CPU0_G0_TX_DN<3>")
	)
	(arc
		(start 115.212622 -226.199954)
		(mid 114.969295 -226.66452)
		(end 115.212622 -227.129086)
		(width 0.1143)
		(layer "In4.Cu")
		(net "GMI_CPU1_G2_CPU0_G0_TX_DN<3>")
	)
	(arc
		(start 356.417118 -222.138748)
		(mid 356.498409 -221.980201)
		(end 356.526338 -221.80423)
		(width 0.1143)
		(layer "In4.Cu")
		(net "GMI_CPU1_G2_CPU0_G0_TX_DN<3>")
	)
	(arc
		(start 355.336602 -228.751892)
		(mid 355.520209 -228.54928)
		(end 355.586538 -228.284024)
		(width 0.1143)
		(layer "In4.Cu")
		(net "GMI_CPU1_G2_CPU0_G0_TX_DN<3>")
	)
	(arc
		(start 115.283488 -223.93021)
		(mid 115.439416 -224.234502)
		(end 115.283488 -224.538794)
		(width 0.1143)
		(layer "In4.Cu")
		(net "GMI_CPU1_G2_CPU0_G0_TX_DN<3>")
	)
	(arc
		(start 115.212622 -222.95993)
		(mid 114.969295 -223.424496)
		(end 115.212622 -223.889062)
		(width 0.1143)
		(layer "In4.Cu")
		(net "GMI_CPU1_G2_CPU0_G0_TX_DN<3>")
	)
	(arc
		(start 356.28326 -227.128832)
		(mid 356.526587 -226.664266)
		(end 356.28326 -226.1997)
		(width 0.1143)
		(layer "In4.Cu")
		(net "GMI_CPU1_G2_CPU0_G0_TX_DN<3>")
	)
	(arc
		(start 356.212394 -226.158552)
		(mid 356.056466 -225.85426)
		(end 356.212394 -225.549968)
		(width 0.1143)
		(layer "In4.Cu")
		(net "GMI_CPU1_G2_CPU0_G0_TX_DN<3>")
	)
	(arc
		(start 116.69522 -229.601522)
		(mid 116.791108 -229.70393)
		(end 116.84254 -229.83444)
		(width 0.1143)
		(layer "In4.Cu")
		(net "GMI_CPU1_G2_CPU0_G0_TX_DN<3>")
	)
	(arc
		(start 115.283488 -222.310198)
		(mid 115.439416 -222.61449)
		(end 115.283488 -222.918782)
		(width 0.1143)
		(layer "In4.Cu")
		(net "GMI_CPU1_G2_CPU0_G0_TX_DN<3>")
	)
	(arc
		(start 356.28326 -225.50882)
		(mid 356.526587 -225.044254)
		(end 356.28326 -224.579688)
		(width 0.1143)
		(layer "In4.Cu")
		(net "GMI_CPU1_G2_CPU0_G0_TX_DN<3>")
	)
	(arc
		(start 356.212394 -222.918528)
		(mid 356.056466 -222.614236)
		(end 356.212394 -222.309944)
		(width 0.1143)
		(layer "In4.Cu")
		(net "GMI_CPU1_G2_CPU0_G0_TX_DN<3>")
	)
	(arc
		(start 356.28326 -222.268796)
		(mid 356.355587 -222.209329)
		(end 356.417118 -222.138748)
		(width 0.1143)
		(layer "In4.Cu")
		(net "GMI_CPU1_G2_CPU0_G0_TX_DN<3>")
	)
	(arc
		(start 116.223542 -228.790246)
		(mid 116.338218 -228.92358)
		(end 116.379498 -229.094538)
		(width 0.1143)
		(layer "In4.Cu")
		(net "GMI_CPU1_G2_CPU0_G0_TX_DN<3>")
	)
	(arc
		(start 114.969544 -221.804484)
		(mid 114.99746 -221.98046)
		(end 115.078764 -222.139002)
		(width 0.1143)
		(layer "In4.Cu")
		(net "GMI_CPU1_G2_CPU0_G0_TX_DN<3>")
	)
	(arc
		(start 115.283488 -225.550222)
		(mid 115.439416 -225.854514)
		(end 115.283488 -226.158806)
		(width 0.1143)
		(layer "In4.Cu")
		(net "GMI_CPU1_G2_CPU0_G0_TX_DN<3>")
	)
	(arc
		(start 115.078764 -222.139002)
		(mid 115.140283 -222.209596)
		(end 115.212622 -222.26905)
		(width 0.1143)
		(layer "In4.Cu")
		(net "GMI_CPU1_G2_CPU0_G0_TX_DN<3>")
	)
	(arc
		(start 115.282726 -227.16998)
		(mid 115.40703 -227.296189)
		(end 115.452398 -227.467414)
		(width 0.1143)
		(layer "In4.Cu")
		(net "GMI_CPU1_G2_CPU0_G0_TX_DN<3>")
	)
	(arc
		(start 356.212394 -224.53854)
		(mid 356.056466 -224.234248)
		(end 356.212394 -223.929956)
		(width 0.1143)
		(layer "In4.Cu")
		(net "GMI_CPU1_G2_CPU0_G0_TX_DN<3>")
	)
	(arc
		(start 355.586538 -228.283516)
		(mid 355.633847 -228.109333)
		(end 355.76129 -227.98151)
		(width 0.1143)
		(layer "In4.Cu")
		(net "GMI_CPU1_G2_CPU0_G0_TX_DN<3>")
	)
	(arc
		(start 115.909344 -228.284278)
		(mid 115.975692 -228.549524)
		(end 116.15928 -228.752146)
		(width 0.1143)
		(layer "In4.Cu")
		(net "GMI_CPU1_G2_CPU0_G0_TX_DN<3>")
	)
	(arc
		(start 354.653342 -229.834186)
		(mid 354.704832 -229.703713)
		(end 354.800662 -229.601268)
		(width 0.1143)
		(layer "In4.Cu")
		(net "GMI_CPU1_G2_CPU0_G0_TX_DN<3>")
	)
	(arc
		(start 355.116384 -229.094284)
		(mid 355.157639 -228.923313)
		(end 355.27234 -228.789992)
		(width 0.1143)
		(layer "In4.Cu")
		(net "GMI_CPU1_G2_CPU0_G0_TX_DN<3>")
	)
	(arc
		(start 356.043484 -227.46716)
		(mid 356.088892 -227.295959)
		(end 356.213156 -227.169726)
		(width 0.1143)
		(layer "In4.Cu")
		(net "GMI_CPU1_G2_CPU0_G0_TX_DN<3>")
	)
	(arc
		(start 355.80066 -227.958396)
		(mid 355.979015 -227.756182)
		(end 356.043484 -227.494338)
		(width 0.1143)
		(layer "In4.Cu")
		(net "GMI_CPU1_G2_CPU0_G0_TX_DN<3>")
	)
	(arc
		(start 115.734592 -227.981764)
		(mid 115.862061 -228.109572)
		(end 115.909344 -228.28377)
		(width 0.1143)
		(layer "In4.Cu")
		(net "GMI_CPU1_G2_CPU0_G0_TX_DN<3>")
	)
	(arc
		(start 354.870512 -229.560628)
		(mid 355.051164 -229.357883)
		(end 355.116384 -229.094284)
		(width 0.1143)
		(layer "In4.Cu")
		(net "GMI_CPU1_G2_CPU0_G0_TX_DN<3>")
	)
	(segment
		(start 113.657888 -227.740464)
		(end 114.12474 -227.474526)
		(width 0.12954)
		(layer "F.Cu")
		(net "GMI_CPU1_G2_CPU0_G0_TX_DN<2>")
	)
	(segment
		(start 357.837994 -227.74021)
		(end 357.371142 -227.474272)
		(width 0.12954)
		(layer "F.Cu")
		(net "GMI_CPU1_G2_CPU0_G0_TX_DN<2>")
	)
	(segment
		(start 357.182166 -227.152962)
		(end 357.183436 -227.1522)
		(width 0.1143)
		(layer "In4.Cu")
		(net "GMI_CPU1_G2_CPU0_G0_TX_DN<2>")
	)
	(segment
		(start 114.02949 -221.489778)
		(end 114.02949 -221.804484)
		(width 0.1143)
		(layer "In4.Cu")
		(net "GMI_CPU1_G2_CPU0_G0_TX_DN<2>")
	)
	(segment
		(start 357.185468 -222.290894)
		(end 357.22306 -222.269304)
		(width 0.1143)
		(layer "In4.Cu")
		(net "GMI_CPU1_G2_CPU0_G0_TX_DN<2>")
	)
	(segment
		(start 166.901876 -175.878744)
		(end 165.231064 -175.878744)
		(width 0.14224)
		(layer "In4.Cu")
		(net "GMI_CPU1_G2_CPU0_G0_TX_DN<2>")
	)
	(segment
		(start 114.244882 -223.86925)
		(end 114.272822 -223.889316)
		(width 0.1143)
		(layer "In4.Cu")
		(net "GMI_CPU1_G2_CPU0_G0_TX_DN<2>")
	)
	(segment
		(start 357.184198 -226.17684)
		(end 357.183436 -226.176332)
		(width 0.1143)
		(layer "In4.Cu")
		(net "GMI_CPU1_G2_CPU0_G0_TX_DN<2>")
	)
	(segment
		(start 114.312446 -227.152454)
		(end 114.343434 -227.170234)
		(width 0.1143)
		(layer "In4.Cu")
		(net "GMI_CPU1_G2_CPU0_G0_TX_DN<2>")
	)
	(segment
		(start 113.96599 -221.129098)
		(end 113.96599 -221.426278)
		(width 0.1143)
		(layer "In4.Cu")
		(net "GMI_CPU1_G2_CPU0_G0_TX_DN<2>")
	)
	(segment
		(start 114.27206 -224.579942)
		(end 114.245136 -224.5995)
		(width 0.1143)
		(layer "In4.Cu")
		(net "GMI_CPU1_G2_CPU0_G0_TX_DN<2>")
	)
	(segment
		(start 114.312446 -226.176586)
		(end 114.311684 -226.177094)
		(width 0.1143)
		(layer "In4.Cu")
		(net "GMI_CPU1_G2_CPU0_G0_TX_DN<2>")
	)
	(segment
		(start 113.96599 -221.426278)
		(end 114.02949 -221.489778)
		(width 0.1143)
		(layer "In4.Cu")
		(net "GMI_CPU1_G2_CPU0_G0_TX_DN<2>")
	)
	(segment
		(start 310.765952 -177.503582)
		(end 308.443884 -176.673256)
		(width 0.14224)
		(layer "In4.Cu")
		(net "GMI_CPU1_G2_CPU0_G0_TX_DN<2>")
	)
	(segment
		(start 357.152448 -223.929956)
		(end 357.180642 -223.9137)
		(width 0.1143)
		(layer "In4.Cu")
		(net "GMI_CPU1_G2_CPU0_G0_TX_DN<2>")
	)
	(segment
		(start 113.92027 -221.083378)
		(end 113.96599 -221.129098)
		(width 0.1143)
		(layer "In4.Cu")
		(net "GMI_CPU1_G2_CPU0_G0_TX_DN<2>")
	)
	(segment
		(start 114.311684 -227.151946)
		(end 114.312446 -227.152454)
		(width 0.1143)
		(layer "In4.Cu")
		(net "GMI_CPU1_G2_CPU0_G0_TX_DN<2>")
	)
	(segment
		(start 114.272568 -222.26905)
		(end 114.343434 -222.310198)
		(width 0.1143)
		(layer "In4.Cu")
		(net "GMI_CPU1_G2_CPU0_G0_TX_DN<2>")
	)
	(segment
		(start 357.184198 -225.53168)
		(end 357.184198 -225.531426)
		(width 0.1143)
		(layer "In4.Cu")
		(net "GMI_CPU1_G2_CPU0_G0_TX_DN<2>")
	)
	(segment
		(start 357.529892 -221.128844)
		(end 357.575612 -221.083124)
		(width 0.1143)
		(layer "In4.Cu")
		(net "GMI_CPU1_G2_CPU0_G0_TX_DN<2>")
	)
	(segment
		(start 357.152448 -225.549968)
		(end 357.184198 -225.53168)
		(width 0.1143)
		(layer "In4.Cu")
		(net "GMI_CPU1_G2_CPU0_G0_TX_DN<2>")
	)
	(segment
		(start 357.183436 -222.936308)
		(end 357.182166 -222.935546)
		(width 0.1143)
		(layer "In4.Cu")
		(net "GMI_CPU1_G2_CPU0_G0_TX_DN<2>")
	)
	(segment
		(start 114.30889 -223.910144)
		(end 114.311684 -223.911922)
		(width 0.1143)
		(layer "In4.Cu")
		(net "GMI_CPU1_G2_CPU0_G0_TX_DN<2>")
	)
	(segment
		(start 357.185722 -222.937832)
		(end 357.183436 -222.936308)
		(width 0.1143)
		(layer "In4.Cu")
		(net "GMI_CPU1_G2_CPU0_G0_TX_DN<2>")
	)
	(segment
		(start 114.272822 -223.889316)
		(end 114.30889 -223.910144)
		(width 0.1143)
		(layer "In4.Cu")
		(net "GMI_CPU1_G2_CPU0_G0_TX_DN<2>")
	)
	(segment
		(start 357.183436 -227.1522)
		(end 357.184198 -227.151692)
		(width 0.1143)
		(layer "In4.Cu")
		(net "GMI_CPU1_G2_CPU0_G0_TX_DN<2>")
	)
	(segment
		(start 357.0732 -227.474272)
		(end 357.00335 -227.404422)
		(width 0.1143)
		(layer "In4.Cu")
		(net "GMI_CPU1_G2_CPU0_G0_TX_DN<2>")
	)
	(segment
		(start 357.152448 -222.309944)
		(end 357.183944 -222.291656)
		(width 0.1143)
		(layer "In4.Cu")
		(net "GMI_CPU1_G2_CPU0_G0_TX_DN<2>")
	)
	(segment
		(start 357.250746 -224.599246)
		(end 357.223822 -224.579688)
		(width 0.1143)
		(layer "In4.Cu")
		(net "GMI_CPU1_G2_CPU0_G0_TX_DN<2>")
	)
	(segment
		(start 357.22052 -226.197922)
		(end 357.184198 -226.17684)
		(width 0.1143)
		(layer "In4.Cu")
		(net "GMI_CPU1_G2_CPU0_G0_TX_DN<2>")
	)
	(segment
		(start 114.313716 -224.555812)
		(end 114.312446 -224.556574)
		(width 0.1143)
		(layer "In4.Cu")
		(net "GMI_CPU1_G2_CPU0_G0_TX_DN<2>")
	)
	(segment
		(start 357.180642 -227.153724)
		(end 357.182166 -227.152962)
		(width 0.1143)
		(layer "In4.Cu")
		(net "GMI_CPU1_G2_CPU0_G0_TX_DN<2>")
	)
	(segment
		(start 357.184198 -227.151692)
		(end 357.22052 -227.13061)
		(width 0.1143)
		(layer "In4.Cu")
		(net "GMI_CPU1_G2_CPU0_G0_TX_DN<2>")
	)
	(segment
		(start 114.343434 -224.538794)
		(end 114.313716 -224.555812)
		(width 0.1143)
		(layer "In4.Cu")
		(net "GMI_CPU1_G2_CPU0_G0_TX_DN<2>")
	)
	(segment
		(start 114.272822 -222.959676)
		(end 114.244882 -222.979742)
		(width 0.1143)
		(layer "In4.Cu")
		(net "GMI_CPU1_G2_CPU0_G0_TX_DN<2>")
	)
	(segment
		(start 357.184198 -225.531426)
		(end 357.223822 -225.50882)
		(width 0.1143)
		(layer "In4.Cu")
		(net "GMI_CPU1_G2_CPU0_G0_TX_DN<2>")
	)
	(segment
		(start 357.182166 -226.17557)
		(end 357.152448 -226.158552)
		(width 0.1143)
		(layer "In4.Cu")
		(net "GMI_CPU1_G2_CPU0_G0_TX_DN<2>")
	)
	(segment
		(start 357.183436 -223.912176)
		(end 357.184198 -223.911668)
		(width 0.1143)
		(layer "In4.Cu")
		(net "GMI_CPU1_G2_CPU0_G0_TX_DN<2>")
	)
	(segment
		(start 357.180642 -223.9137)
		(end 357.182166 -223.912938)
		(width 0.1143)
		(layer "In4.Cu")
		(net "GMI_CPU1_G2_CPU0_G0_TX_DN<2>")
	)
	(segment
		(start 357.223822 -225.50882)
		(end 357.250746 -225.489262)
		(width 0.1143)
		(layer "In4.Cu")
		(net "GMI_CPU1_G2_CPU0_G0_TX_DN<2>")
	)
	(segment
		(start 357.529892 -221.426024)
		(end 357.529892 -221.128844)
		(width 0.1143)
		(layer "In4.Cu")
		(net "GMI_CPU1_G2_CPU0_G0_TX_DN<2>")
	)
	(segment
		(start 114.313716 -226.175824)
		(end 114.312446 -226.176586)
		(width 0.1143)
		(layer "In4.Cu")
		(net "GMI_CPU1_G2_CPU0_G0_TX_DN<2>")
	)
	(segment
		(start 156.776166 -178.901852)
		(end 117.430042 -211.163662)
		(width 0.14224)
		(layer "In4.Cu")
		(net "GMI_CPU1_G2_CPU0_G0_TX_DN<2>")
	)
	(segment
		(start 357.22306 -223.889062)
		(end 357.251 -223.868996)
		(width 0.1143)
		(layer "In4.Cu")
		(net "GMI_CPU1_G2_CPU0_G0_TX_DN<2>")
	)
	(segment
		(start 114.492532 -227.404676)
		(end 114.422682 -227.474526)
		(width 0.1143)
		(layer "In4.Cu")
		(net "GMI_CPU1_G2_CPU0_G0_TX_DN<2>")
	)
	(segment
		(start 114.311684 -225.53168)
		(end 114.311684 -225.531934)
		(width 0.1143)
		(layer "In4.Cu")
		(net "GMI_CPU1_G2_CPU0_G0_TX_DN<2>")
	)
	(segment
		(start 357.466392 -221.489524)
		(end 357.529892 -221.426024)
		(width 0.1143)
		(layer "In4.Cu")
		(net "GMI_CPU1_G2_CPU0_G0_TX_DN<2>")
	)
	(segment
		(start 114.31016 -222.938086)
		(end 114.272822 -222.959676)
		(width 0.1143)
		(layer "In4.Cu")
		(net "GMI_CPU1_G2_CPU0_G0_TX_DN<2>")
	)
	(segment
		(start 357.575612 -217.241882)
		(end 353.937824 -211.114386)
		(width 0.14224)
		(layer "In4.Cu")
		(net "GMI_CPU1_G2_CPU0_G0_TX_DN<2>")
	)
	(segment
		(start 114.311684 -224.557082)
		(end 114.27206 -224.579942)
		(width 0.1143)
		(layer "In4.Cu")
		(net "GMI_CPU1_G2_CPU0_G0_TX_DN<2>")
	)
	(segment
		(start 302.914304 -176.673256)
		(end 166.901876 -175.878744)
		(width 0.14224)
		(layer "In4.Cu")
		(net "GMI_CPU1_G2_CPU0_G0_TX_DN<2>")
	)
	(segment
		(start 357.223822 -224.579688)
		(end 357.184198 -224.556828)
		(width 0.1143)
		(layer "In4.Cu")
		(net "GMI_CPU1_G2_CPU0_G0_TX_DN<2>")
	)
	(segment
		(start 114.313716 -222.9358)
		(end 114.312446 -222.936562)
		(width 0.1143)
		(layer "In4.Cu")
		(net "GMI_CPU1_G2_CPU0_G0_TX_DN<2>")
	)
	(segment
		(start 357.466392 -221.80423)
		(end 357.466392 -221.489524)
		(width 0.1143)
		(layer "In4.Cu")
		(net "GMI_CPU1_G2_CPU0_G0_TX_DN<2>")
	)
	(segment
		(start 165.231064 -175.878744)
		(end 156.776166 -178.901852)
		(width 0.14224)
		(layer "In4.Cu")
		(net "GMI_CPU1_G2_CPU0_G0_TX_DN<2>")
	)
	(segment
		(start 113.92027 -221.05493)
		(end 113.92027 -221.083378)
		(width 0.1143)
		(layer "In4.Cu")
		(net "GMI_CPU1_G2_CPU0_G0_TX_DN<2>")
	)
	(segment
		(start 114.422682 -227.474526)
		(end 114.12474 -227.474526)
		(width 0.1143)
		(layer "In4.Cu")
		(net "GMI_CPU1_G2_CPU0_G0_TX_DN<2>")
	)
	(segment
		(start 114.312446 -224.556574)
		(end 114.311684 -224.557082)
		(width 0.1143)
		(layer "In4.Cu")
		(net "GMI_CPU1_G2_CPU0_G0_TX_DN<2>")
	)
	(segment
		(start 357.152448 -227.16998)
		(end 357.180642 -227.153724)
		(width 0.1143)
		(layer "In4.Cu")
		(net "GMI_CPU1_G2_CPU0_G0_TX_DN<2>")
	)
	(segment
		(start 357.183944 -222.291656)
		(end 357.185468 -222.290894)
		(width 0.1143)
		(layer "In4.Cu")
		(net "GMI_CPU1_G2_CPU0_G0_TX_DN<2>")
	)
	(segment
		(start 114.311684 -223.911922)
		(end 114.312446 -223.91243)
		(width 0.1143)
		(layer "In4.Cu")
		(net "GMI_CPU1_G2_CPU0_G0_TX_DN<2>")
	)
	(segment
		(start 357.371142 -227.474272)
		(end 357.0732 -227.474272)
		(width 0.1143)
		(layer "In4.Cu")
		(net "GMI_CPU1_G2_CPU0_G0_TX_DN<2>")
	)
	(segment
		(start 114.343434 -226.158806)
		(end 114.313716 -226.175824)
		(width 0.1143)
		(layer "In4.Cu")
		(net "GMI_CPU1_G2_CPU0_G0_TX_DN<2>")
	)
	(segment
		(start 114.275362 -227.130864)
		(end 114.311684 -227.151946)
		(width 0.1143)
		(layer "In4.Cu")
		(net "GMI_CPU1_G2_CPU0_G0_TX_DN<2>")
	)
	(segment
		(start 357.251 -222.979488)
		(end 357.22306 -222.959422)
		(width 0.1143)
		(layer "In4.Cu")
		(net "GMI_CPU1_G2_CPU0_G0_TX_DN<2>")
	)
	(segment
		(start 357.186992 -223.90989)
		(end 357.22306 -223.889062)
		(width 0.1143)
		(layer "In4.Cu")
		(net "GMI_CPU1_G2_CPU0_G0_TX_DN<2>")
	)
	(segment
		(start 357.22306 -222.959422)
		(end 357.185722 -222.937832)
		(width 0.1143)
		(layer "In4.Cu")
		(net "GMI_CPU1_G2_CPU0_G0_TX_DN<2>")
	)
	(segment
		(start 114.311684 -225.531934)
		(end 114.343434 -225.550222)
		(width 0.1143)
		(layer "In4.Cu")
		(net "GMI_CPU1_G2_CPU0_G0_TX_DN<2>")
	)
	(segment
		(start 114.343434 -222.918782)
		(end 114.313716 -222.9358)
		(width 0.1143)
		(layer "In4.Cu")
		(net "GMI_CPU1_G2_CPU0_G0_TX_DN<2>")
	)
	(segment
		(start 353.937824 -211.114386)
		(end 317.807848 -181.489858)
		(width 0.14224)
		(layer "In4.Cu")
		(net "GMI_CPU1_G2_CPU0_G0_TX_DN<2>")
	)
	(segment
		(start 357.182166 -223.912938)
		(end 357.183436 -223.912176)
		(width 0.1143)
		(layer "In4.Cu")
		(net "GMI_CPU1_G2_CPU0_G0_TX_DN<2>")
	)
	(segment
		(start 114.311684 -226.177094)
		(end 114.275362 -226.198176)
		(width 0.1143)
		(layer "In4.Cu")
		(net "GMI_CPU1_G2_CPU0_G0_TX_DN<2>")
	)
	(segment
		(start 308.443884 -176.673256)
		(end 302.914304 -176.673256)
		(width 0.14224)
		(layer "In4.Cu")
		(net "GMI_CPU1_G2_CPU0_G0_TX_DN<2>")
	)
	(segment
		(start 357.183436 -224.55632)
		(end 357.182166 -224.555558)
		(width 0.1143)
		(layer "In4.Cu")
		(net "GMI_CPU1_G2_CPU0_G0_TX_DN<2>")
	)
	(segment
		(start 113.92027 -217.144346)
		(end 113.92027 -221.05493)
		(width 0.14224)
		(layer "In4.Cu")
		(net "GMI_CPU1_G2_CPU0_G0_TX_DN<2>")
	)
	(segment
		(start 114.245136 -225.489516)
		(end 114.27206 -225.509074)
		(width 0.1143)
		(layer "In4.Cu")
		(net "GMI_CPU1_G2_CPU0_G0_TX_DN<2>")
	)
	(segment
		(start 357.182166 -222.935546)
		(end 357.152448 -222.918528)
		(width 0.1143)
		(layer "In4.Cu")
		(net "GMI_CPU1_G2_CPU0_G0_TX_DN<2>")
	)
	(segment
		(start 114.312446 -222.936562)
		(end 114.31016 -222.938086)
		(width 0.1143)
		(layer "In4.Cu")
		(net "GMI_CPU1_G2_CPU0_G0_TX_DN<2>")
	)
	(segment
		(start 317.807848 -181.489858)
		(end 310.765952 -177.503582)
		(width 0.14224)
		(layer "In4.Cu")
		(net "GMI_CPU1_G2_CPU0_G0_TX_DN<2>")
	)
	(segment
		(start 357.184198 -224.556828)
		(end 357.183436 -224.55632)
		(width 0.1143)
		(layer "In4.Cu")
		(net "GMI_CPU1_G2_CPU0_G0_TX_DN<2>")
	)
	(segment
		(start 357.183436 -226.176332)
		(end 357.182166 -226.17557)
		(width 0.1143)
		(layer "In4.Cu")
		(net "GMI_CPU1_G2_CPU0_G0_TX_DN<2>")
	)
	(segment
		(start 357.182166 -224.555558)
		(end 357.152448 -224.53854)
		(width 0.1143)
		(layer "In4.Cu")
		(net "GMI_CPU1_G2_CPU0_G0_TX_DN<2>")
	)
	(segment
		(start 357.575612 -221.083124)
		(end 357.575612 -217.241882)
		(width 0.14224)
		(layer "In4.Cu")
		(net "GMI_CPU1_G2_CPU0_G0_TX_DN<2>")
	)
	(segment
		(start 357.184198 -223.911668)
		(end 357.186992 -223.90989)
		(width 0.1143)
		(layer "In4.Cu")
		(net "GMI_CPU1_G2_CPU0_G0_TX_DN<2>")
	)
	(segment
		(start 114.312446 -223.91243)
		(end 114.343434 -223.93021)
		(width 0.1143)
		(layer "In4.Cu")
		(net "GMI_CPU1_G2_CPU0_G0_TX_DN<2>")
	)
	(segment
		(start 117.430042 -211.163662)
		(end 113.92027 -217.144346)
		(width 0.14224)
		(layer "In4.Cu")
		(net "GMI_CPU1_G2_CPU0_G0_TX_DN<2>")
	)
	(segment
		(start 114.27206 -225.509074)
		(end 114.311684 -225.53168)
		(width 0.1143)
		(layer "In4.Cu")
		(net "GMI_CPU1_G2_CPU0_G0_TX_DN<2>")
	)
	(arc
		(start 114.275362 -226.198176)
		(mid 114.267184 -226.203819)
		(end 114.259106 -226.209606)
		(width 0.1143)
		(layer "In4.Cu")
		(net "GMI_CPU1_G2_CPU0_G0_TX_DN<2>")
	)
	(arc
		(start 357.251 -223.868996)
		(mid 357.479 -223.424242)
		(end 357.251 -222.979488)
		(width 0.1143)
		(layer "In4.Cu")
		(net "GMI_CPU1_G2_CPU0_G0_TX_DN<2>")
	)
	(arc
		(start 114.259106 -227.119434)
		(mid 114.267184 -227.12522)
		(end 114.275362 -227.130864)
		(width 0.1143)
		(layer "In4.Cu")
		(net "GMI_CPU1_G2_CPU0_G0_TX_DN<2>")
	)
	(arc
		(start 357.00335 -227.404422)
		(mid 357.055399 -227.272903)
		(end 357.152448 -227.16998)
		(width 0.1143)
		(layer "In4.Cu")
		(net "GMI_CPU1_G2_CPU0_G0_TX_DN<2>")
	)
	(arc
		(start 114.245136 -224.5995)
		(mid 114.017458 -225.044508)
		(end 114.245136 -225.489516)
		(width 0.1143)
		(layer "In4.Cu")
		(net "GMI_CPU1_G2_CPU0_G0_TX_DN<2>")
	)
	(arc
		(start 357.236776 -226.209352)
		(mid 357.228698 -226.203566)
		(end 357.22052 -226.197922)
		(width 0.1143)
		(layer "In4.Cu")
		(net "GMI_CPU1_G2_CPU0_G0_TX_DN<2>")
	)
	(arc
		(start 357.152448 -226.158552)
		(mid 356.99652 -225.85426)
		(end 357.152448 -225.549968)
		(width 0.1143)
		(layer "In4.Cu")
		(net "GMI_CPU1_G2_CPU0_G0_TX_DN<2>")
	)
	(arc
		(start 114.343434 -222.310198)
		(mid 114.499362 -222.61449)
		(end 114.343434 -222.918782)
		(width 0.1143)
		(layer "In4.Cu")
		(net "GMI_CPU1_G2_CPU0_G0_TX_DN<2>")
	)
	(arc
		(start 357.22052 -227.13061)
		(mid 357.228698 -227.124967)
		(end 357.236776 -227.11918)
		(width 0.1143)
		(layer "In4.Cu")
		(net "GMI_CPU1_G2_CPU0_G0_TX_DN<2>")
	)
	(arc
		(start 357.250746 -225.489262)
		(mid 357.478424 -225.044254)
		(end 357.250746 -224.599246)
		(width 0.1143)
		(layer "In4.Cu")
		(net "GMI_CPU1_G2_CPU0_G0_TX_DN<2>")
	)
	(arc
		(start 357.236776 -227.11918)
		(mid 357.45966 -226.664266)
		(end 357.236776 -226.209352)
		(width 0.1143)
		(layer "In4.Cu")
		(net "GMI_CPU1_G2_CPU0_G0_TX_DN<2>")
	)
	(arc
		(start 357.22306 -222.269304)
		(mid 357.402006 -222.066723)
		(end 357.466392 -221.80423)
		(width 0.1143)
		(layer "In4.Cu")
		(net "GMI_CPU1_G2_CPU0_G0_TX_DN<2>")
	)
	(arc
		(start 114.02949 -221.804484)
		(mid 114.093937 -222.066636)
		(end 114.272568 -222.26905)
		(width 0.1143)
		(layer "In4.Cu")
		(net "GMI_CPU1_G2_CPU0_G0_TX_DN<2>")
	)
	(arc
		(start 114.244882 -222.979742)
		(mid 114.016882 -223.424496)
		(end 114.244882 -223.86925)
		(width 0.1143)
		(layer "In4.Cu")
		(net "GMI_CPU1_G2_CPU0_G0_TX_DN<2>")
	)
	(arc
		(start 114.343434 -225.550222)
		(mid 114.499362 -225.854514)
		(end 114.343434 -226.158806)
		(width 0.1143)
		(layer "In4.Cu")
		(net "GMI_CPU1_G2_CPU0_G0_TX_DN<2>")
	)
	(arc
		(start 357.152448 -222.918528)
		(mid 356.99652 -222.614236)
		(end 357.152448 -222.309944)
		(width 0.1143)
		(layer "In4.Cu")
		(net "GMI_CPU1_G2_CPU0_G0_TX_DN<2>")
	)
	(arc
		(start 114.343434 -227.170234)
		(mid 114.440569 -227.273103)
		(end 114.492532 -227.404676)
		(width 0.1143)
		(layer "In4.Cu")
		(net "GMI_CPU1_G2_CPU0_G0_TX_DN<2>")
	)
	(arc
		(start 114.343434 -223.93021)
		(mid 114.499362 -224.234502)
		(end 114.343434 -224.538794)
		(width 0.1143)
		(layer "In4.Cu")
		(net "GMI_CPU1_G2_CPU0_G0_TX_DN<2>")
	)
	(arc
		(start 114.259106 -226.209606)
		(mid 114.036222 -226.66452)
		(end 114.259106 -227.119434)
		(width 0.1143)
		(layer "In4.Cu")
		(net "GMI_CPU1_G2_CPU0_G0_TX_DN<2>")
	)
	(arc
		(start 357.152448 -224.53854)
		(mid 356.99652 -224.234248)
		(end 357.152448 -223.929956)
		(width 0.1143)
		(layer "In4.Cu")
		(net "GMI_CPU1_G2_CPU0_G0_TX_DN<2>")
	)
	(segment
		(start 357.837994 -229.360222)
		(end 357.371142 -229.094284)
		(width 0.12954)
		(layer "F.Cu")
		(net "GMI_CPU1_G2_CPU0_G0_TX_DN<1>")
	)
	(segment
		(start 113.657888 -229.360476)
		(end 114.12474 -229.094538)
		(width 0.12954)
		(layer "F.Cu")
		(net "GMI_CPU1_G2_CPU0_G0_TX_DN<1>")
	)
	(segment
		(start 113.402364 -222.91929)
		(end 113.332768 -222.95993)
		(width 0.1143)
		(layer "In4.Cu")
		(net "GMI_CPU1_G2_CPU0_G0_TX_DN<1>")
	)
	(segment
		(start 113.335562 -227.130864)
		(end 113.371884 -227.151946)
		(width 0.1143)
		(layer "In4.Cu")
		(net "GMI_CPU1_G2_CPU0_G0_TX_DN<1>")
	)
	(segment
		(start 358.092502 -222.309944)
		(end 358.124252 -222.291656)
		(width 0.1143)
		(layer "In4.Cu")
		(net "GMI_CPU1_G2_CPU0_G0_TX_DN<1>")
	)
	(segment
		(start 358.129332 -222.288608)
		(end 358.130856 -222.287846)
		(width 0.1143)
		(layer "In4.Cu")
		(net "GMI_CPU1_G2_CPU0_G0_TX_DN<1>")
	)
	(segment
		(start 114.422682 -229.094538)
		(end 114.12474 -229.094538)
		(width 0.1143)
		(layer "In4.Cu")
		(net "GMI_CPU1_G2_CPU0_G0_TX_DN<1>")
	)
	(segment
		(start 166.471854 -174.944532)
		(end 166.4716 -174.944786)
		(width 0.14224)
		(layer "In4.Cu")
		(net "GMI_CPU1_G2_CPU0_G0_TX_DN<1>")
	)
	(segment
		(start 357.462074 -228.322632)
		(end 357.466392 -228.293676)
		(width 0.1143)
		(layer "In4.Cu")
		(net "GMI_CPU1_G2_CPU0_G0_TX_DN<1>")
	)
	(segment
		(start 358.373172 -225.234754)
		(end 358.373426 -225.234754)
		(width 0.1143)
		(layer "In4.Cu")
		(net "GMI_CPU1_G2_CPU0_G0_TX_DN<1>")
	)
	(segment
		(start 358.130856 -222.287846)
		(end 358.163368 -222.268796)
		(width 0.1143)
		(layer "In4.Cu")
		(net "GMI_CPU1_G2_CPU0_G0_TX_DN<1>")
	)
	(segment
		(start 358.474772 -221.128844)
		(end 358.520492 -221.083124)
		(width 0.1143)
		(layer "In4.Cu")
		(net "GMI_CPU1_G2_CPU0_G0_TX_DN<1>")
	)
	(segment
		(start 358.520492 -221.083124)
		(end 358.520492 -216.744804)
		(width 0.14224)
		(layer "In4.Cu")
		(net "GMI_CPU1_G2_CPU0_G0_TX_DN<1>")
	)
	(segment
		(start 358.092248 -223.93021)
		(end 358.16032 -223.890586)
		(width 0.1143)
		(layer "In4.Cu")
		(net "GMI_CPU1_G2_CPU0_G0_TX_DN<1>")
	)
	(segment
		(start 358.406446 -221.573344)
		(end 358.474772 -221.505018)
		(width 0.1143)
		(layer "In4.Cu")
		(net "GMI_CPU1_G2_CPU0_G0_TX_DN<1>")
	)
	(segment
		(start 113.36655 -222.288862)
		(end 113.368074 -222.289878)
		(width 0.1143)
		(layer "In4.Cu")
		(net "GMI_CPU1_G2_CPU0_G0_TX_DN<1>")
	)
	(segment
		(start 113.371884 -227.151946)
		(end 113.402364 -227.169726)
		(width 0.1143)
		(layer "In4.Cu")
		(net "GMI_CPU1_G2_CPU0_G0_TX_DN<1>")
	)
	(segment
		(start 113.37163 -222.29191)
		(end 113.40338 -222.310198)
		(width 0.1143)
		(layer "In4.Cu")
		(net "GMI_CPU1_G2_CPU0_G0_TX_DN<1>")
	)
	(segment
		(start 113.089436 -225.044508)
		(end 113.089182 -225.044508)
		(width 0.1143)
		(layer "In4.Cu")
		(net "GMI_CPU1_G2_CPU0_G0_TX_DN<1>")
	)
	(segment
		(start 358.163114 -222.959676)
		(end 358.093518 -222.919036)
		(width 0.1143)
		(layer "In4.Cu")
		(net "GMI_CPU1_G2_CPU0_G0_TX_DN<1>")
	)
	(segment
		(start 112.97539 -221.083378)
		(end 113.02111 -221.129098)
		(width 0.1143)
		(layer "In4.Cu")
		(net "GMI_CPU1_G2_CPU0_G0_TX_DN<1>")
	)
	(segment
		(start 113.371376 -225.53295)
		(end 113.37417 -225.534474)
		(width 0.1143)
		(layer "In4.Cu")
		(net "GMI_CPU1_G2_CPU0_G0_TX_DN<1>")
	)
	(segment
		(start 358.123998 -227.151692)
		(end 358.16032 -227.13061)
		(width 0.1143)
		(layer "In4.Cu")
		(net "GMI_CPU1_G2_CPU0_G0_TX_DN<1>")
	)
	(segment
		(start 358.093518 -227.169472)
		(end 358.123998 -227.151692)
		(width 0.1143)
		(layer "In4.Cu")
		(net "GMI_CPU1_G2_CPU0_G0_TX_DN<1>")
	)
	(segment
		(start 358.126792 -222.290132)
		(end 358.127808 -222.289624)
		(width 0.1143)
		(layer "In4.Cu")
		(net "GMI_CPU1_G2_CPU0_G0_TX_DN<1>")
	)
	(segment
		(start 113.335562 -223.89084)
		(end 113.403634 -223.930464)
		(width 0.1143)
		(layer "In4.Cu")
		(net "GMI_CPU1_G2_CPU0_G0_TX_DN<1>")
	)
	(segment
		(start 357.180642 -228.773736)
		(end 357.183436 -228.772212)
		(width 0.1143)
		(layer "In4.Cu")
		(net "GMI_CPU1_G2_CPU0_G0_TX_DN<1>")
	)
	(segment
		(start 166.721282 -174.944532)
		(end 166.471854 -174.944532)
		(width 0.14224)
		(layer "In4.Cu")
		(net "GMI_CPU1_G2_CPU0_G0_TX_DN<1>")
	)
	(segment
		(start 358.129586 -225.529648)
		(end 358.131872 -225.528378)
		(width 0.1143)
		(layer "In4.Cu")
		(net "GMI_CPU1_G2_CPU0_G0_TX_DN<1>")
	)
	(segment
		(start 308.619652 -175.740822)
		(end 302.917352 -175.740822)
		(width 0.14224)
		(layer "In4.Cu")
		(net "GMI_CPU1_G2_CPU0_G0_TX_DN<1>")
	)
	(segment
		(start 113.332514 -222.26905)
		(end 113.365026 -222.2881)
		(width 0.1143)
		(layer "In4.Cu")
		(net "GMI_CPU1_G2_CPU0_G0_TX_DN<1>")
	)
	(segment
		(start 113.089436 -226.66452)
		(end 113.08969 -226.66452)
		(width 0.1143)
		(layer "In4.Cu")
		(net "GMI_CPU1_G2_CPU0_G0_TX_DN<1>")
	)
	(segment
		(start 358.406446 -221.80423)
		(end 358.406446 -221.573344)
		(width 0.1143)
		(layer "In4.Cu")
		(net "GMI_CPU1_G2_CPU0_G0_TX_DN<1>")
	)
	(segment
		(start 357.622348 -227.979986)
		(end 357.693214 -227.938838)
		(width 0.1143)
		(layer "In4.Cu")
		(net "GMI_CPU1_G2_CPU0_G0_TX_DN<1>")
	)
	(segment
		(start 358.124506 -224.556828)
		(end 358.121966 -224.555558)
		(width 0.1143)
		(layer "In4.Cu")
		(net "GMI_CPU1_G2_CPU0_G0_TX_DN<1>")
	)
	(segment
		(start 311.36844 -176.723802)
		(end 308.619652 -175.740822)
		(width 0.14224)
		(layer "In4.Cu")
		(net "GMI_CPU1_G2_CPU0_G0_TX_DN<1>")
	)
	(segment
		(start 113.40338 -226.158552)
		(end 113.332768 -226.199954)
		(width 0.1143)
		(layer "In4.Cu")
		(net "GMI_CPU1_G2_CPU0_G0_TX_DN<1>")
	)
	(segment
		(start 357.371142 -229.094284)
		(end 357.0732 -229.094284)
		(width 0.1143)
		(layer "In4.Cu")
		(net "GMI_CPU1_G2_CPU0_G0_TX_DN<1>")
	)
	(segment
		(start 116.397278 -210.798156)
		(end 112.97539 -216.623392)
		(width 0.14224)
		(layer "In4.Cu")
		(net "GMI_CPU1_G2_CPU0_G0_TX_DN<1>")
	)
	(segment
		(start 113.365026 -222.2881)
		(end 113.36655 -222.288862)
		(width 0.1143)
		(layer "In4.Cu")
		(net "GMI_CPU1_G2_CPU0_G0_TX_DN<1>")
	)
	(segment
		(start 113.122456 -225.235008)
		(end 113.12271 -225.235008)
		(width 0.1143)
		(layer "In4.Cu")
		(net "GMI_CPU1_G2_CPU0_G0_TX_DN<1>")
	)
	(segment
		(start 114.313716 -228.773228)
		(end 114.343434 -228.790246)
		(width 0.1143)
		(layer "In4.Cu")
		(net "GMI_CPU1_G2_CPU0_G0_TX_DN<1>")
	)
	(segment
		(start 164.972746 -174.944786)
		(end 156.372306 -178.019964)
		(width 0.14224)
		(layer "In4.Cu")
		(net "GMI_CPU1_G2_CPU0_G0_TX_DN<1>")
	)
	(segment
		(start 354.9523 -210.734656)
		(end 318.16675 -180.572156)
		(width 0.14224)
		(layer "In4.Cu")
		(net "GMI_CPU1_G2_CPU0_G0_TX_DN<1>")
	)
	(segment
		(start 113.366296 -225.529902)
		(end 113.371376 -225.53295)
		(width 0.1143)
		(layer "In4.Cu")
		(net "GMI_CPU1_G2_CPU0_G0_TX_DN<1>")
	)
	(segment
		(start 357.466392 -228.293676)
		(end 357.466392 -228.26599)
		(width 0.1143)
		(layer "In4.Cu")
		(net "GMI_CPU1_G2_CPU0_G0_TX_DN<1>")
	)
	(segment
		(start 318.16675 -180.572156)
		(end 311.36844 -176.723802)
		(width 0.14224)
		(layer "In4.Cu")
		(net "GMI_CPU1_G2_CPU0_G0_TX_DN<1>")
	)
	(segment
		(start 357.17988 -228.774244)
		(end 357.180642 -228.773736)
		(width 0.1143)
		(layer "In4.Cu")
		(net "GMI_CPU1_G2_CPU0_G0_TX_DN<1>")
	)
	(segment
		(start 156.372306 -178.019964)
		(end 116.397278 -210.798156)
		(width 0.14224)
		(layer "In4.Cu")
		(net "GMI_CPU1_G2_CPU0_G0_TX_DN<1>")
	)
	(segment
		(start 357.152448 -228.789992)
		(end 357.17988 -228.774244)
		(width 0.1143)
		(layer "In4.Cu")
		(net "GMI_CPU1_G2_CPU0_G0_TX_DN<1>")
	)
	(segment
		(start 302.917352 -175.740822)
		(end 166.721282 -174.944532)
		(width 0.14224)
		(layer "In4.Cu")
		(net "GMI_CPU1_G2_CPU0_G0_TX_DN<1>")
	)
	(segment
		(start 357.0732 -229.094284)
		(end 357.00335 -229.024434)
		(width 0.1143)
		(layer "In4.Cu")
		(net "GMI_CPU1_G2_CPU0_G0_TX_DN<1>")
	)
	(segment
		(start 358.125268 -222.291148)
		(end 358.126792 -222.290132)
		(width 0.1143)
		(layer "In4.Cu")
		(net "GMI_CPU1_G2_CPU0_G0_TX_DN<1>")
	)
	(segment
		(start 357.188008 -228.769164)
		(end 357.22179 -228.74986)
		(width 0.1143)
		(layer "In4.Cu")
		(net "GMI_CPU1_G2_CPU0_G0_TX_DN<1>")
	)
	(segment
		(start 113.373916 -224.555812)
		(end 113.371376 -224.557082)
		(width 0.1143)
		(layer "In4.Cu")
		(net "GMI_CPU1_G2_CPU0_G0_TX_DN<1>")
	)
	(segment
		(start 358.124506 -225.532696)
		(end 358.129586 -225.529648)
		(width 0.1143)
		(layer "In4.Cu")
		(net "GMI_CPU1_G2_CPU0_G0_TX_DN<1>")
	)
	(segment
		(start 113.370614 -222.291402)
		(end 113.37163 -222.29191)
		(width 0.1143)
		(layer "In4.Cu")
		(net "GMI_CPU1_G2_CPU0_G0_TX_DN<1>")
	)
	(segment
		(start 357.183436 -228.772212)
		(end 357.188008 -228.769164)
		(width 0.1143)
		(layer "In4.Cu")
		(net "GMI_CPU1_G2_CPU0_G0_TX_DN<1>")
	)
	(segment
		(start 113.02111 -221.505272)
		(end 113.089436 -221.573598)
		(width 0.1143)
		(layer "In4.Cu")
		(net "GMI_CPU1_G2_CPU0_G0_TX_DN<1>")
	)
	(segment
		(start 114.274092 -228.750114)
		(end 114.307874 -228.769418)
		(width 0.1143)
		(layer "In4.Cu")
		(net "GMI_CPU1_G2_CPU0_G0_TX_DN<1>")
	)
	(segment
		(start 358.4067 -225.044254)
		(end 358.406446 -225.044254)
		(width 0.1143)
		(layer "In4.Cu")
		(net "GMI_CPU1_G2_CPU0_G0_TX_DN<1>")
	)
	(segment
		(start 113.368074 -222.289878)
		(end 113.36909 -222.290386)
		(width 0.1143)
		(layer "In4.Cu")
		(net "GMI_CPU1_G2_CPU0_G0_TX_DN<1>")
	)
	(segment
		(start 358.124252 -222.291656)
		(end 358.125268 -222.291148)
		(width 0.1143)
		(layer "In4.Cu")
		(net "GMI_CPU1_G2_CPU0_G0_TX_DN<1>")
	)
	(segment
		(start 357.607362 -227.990654)
		(end 357.622348 -227.979986)
		(width 0.1143)
		(layer "In4.Cu")
		(net "GMI_CPU1_G2_CPU0_G0_TX_DN<1>")
	)
	(segment
		(start 358.127808 -222.289624)
		(end 358.129332 -222.288608)
		(width 0.1143)
		(layer "In4.Cu")
		(net "GMI_CPU1_G2_CPU0_G0_TX_DN<1>")
	)
	(segment
		(start 358.406192 -226.664266)
		(end 358.406446 -226.664266)
		(width 0.1143)
		(layer "In4.Cu")
		(net "GMI_CPU1_G2_CPU0_G0_TX_DN<1>")
	)
	(segment
		(start 113.36909 -222.290386)
		(end 113.370614 -222.291402)
		(width 0.1143)
		(layer "In4.Cu")
		(net "GMI_CPU1_G2_CPU0_G0_TX_DN<1>")
	)
	(segment
		(start 112.97539 -221.05493)
		(end 112.97539 -221.083378)
		(width 0.1143)
		(layer "In4.Cu")
		(net "GMI_CPU1_G2_CPU0_G0_TX_DN<1>")
	)
	(segment
		(start 113.02111 -221.129098)
		(end 113.02111 -221.505272)
		(width 0.1143)
		(layer "In4.Cu")
		(net "GMI_CPU1_G2_CPU0_G0_TX_DN<1>")
	)
	(segment
		(start 166.4716 -174.944786)
		(end 164.972746 -174.944786)
		(width 0.14224)
		(layer "In4.Cu")
		(net "GMI_CPU1_G2_CPU0_G0_TX_DN<1>")
	)
	(segment
		(start 114.307874 -228.769418)
		(end 114.312446 -228.772466)
		(width 0.1143)
		(layer "In4.Cu")
		(net "GMI_CPU1_G2_CPU0_G0_TX_DN<1>")
	)
	(segment
		(start 358.474772 -221.505018)
		(end 358.474772 -221.128844)
		(width 0.1143)
		(layer "In4.Cu")
		(net "GMI_CPU1_G2_CPU0_G0_TX_DN<1>")
	)
	(segment
		(start 114.492532 -229.024688)
		(end 114.422682 -229.094538)
		(width 0.1143)
		(layer "In4.Cu")
		(net "GMI_CPU1_G2_CPU0_G0_TX_DN<1>")
	)
	(segment
		(start 114.312446 -228.772466)
		(end 114.313716 -228.773228)
		(width 0.1143)
		(layer "In4.Cu")
		(net "GMI_CPU1_G2_CPU0_G0_TX_DN<1>")
	)
	(segment
		(start 114.029236 -228.274626)
		(end 114.029744 -228.274626)
		(width 0.1143)
		(layer "In4.Cu")
		(net "GMI_CPU1_G2_CPU0_G0_TX_DN<1>")
	)
	(segment
		(start 113.802668 -227.939092)
		(end 113.873534 -227.98024)
		(width 0.1143)
		(layer "In4.Cu")
		(net "GMI_CPU1_G2_CPU0_G0_TX_DN<1>")
	)
	(segment
		(start 358.121712 -225.53422)
		(end 358.124506 -225.532696)
		(width 0.1143)
		(layer "In4.Cu")
		(net "GMI_CPU1_G2_CPU0_G0_TX_DN<1>")
	)
	(segment
		(start 113.089436 -223.424496)
		(end 113.08969 -223.424496)
		(width 0.1143)
		(layer "In4.Cu")
		(net "GMI_CPU1_G2_CPU0_G0_TX_DN<1>")
	)
	(segment
		(start 112.97539 -216.623392)
		(end 112.97539 -221.05493)
		(width 0.14224)
		(layer "In4.Cu")
		(net "GMI_CPU1_G2_CPU0_G0_TX_DN<1>")
	)
	(segment
		(start 113.089436 -221.573598)
		(end 113.089436 -221.804484)
		(width 0.1143)
		(layer "In4.Cu")
		(net "GMI_CPU1_G2_CPU0_G0_TX_DN<1>")
	)
	(segment
		(start 358.520492 -216.744804)
		(end 354.9523 -210.734656)
		(width 0.14224)
		(layer "In4.Cu")
		(net "GMI_CPU1_G2_CPU0_G0_TX_DN<1>")
	)
	(segment
		(start 358.163114 -226.1997)
		(end 358.092502 -226.158298)
		(width 0.1143)
		(layer "In4.Cu")
		(net "GMI_CPU1_G2_CPU0_G0_TX_DN<1>")
	)
	(segment
		(start 113.36401 -225.528632)
		(end 113.366296 -225.529902)
		(width 0.1143)
		(layer "In4.Cu")
		(net "GMI_CPU1_G2_CPU0_G0_TX_DN<1>")
	)
	(segment
		(start 358.406192 -223.424242)
		(end 358.406446 -223.424242)
		(width 0.1143)
		(layer "In4.Cu")
		(net "GMI_CPU1_G2_CPU0_G0_TX_DN<1>")
	)
	(arc
		(start 358.406446 -225.044254)
		(mid 358.330941 -224.762676)
		(end 358.124506 -224.556828)
		(width 0.1143)
		(layer "In4.Cu")
		(net "GMI_CPU1_G2_CPU0_G0_TX_DN<1>")
	)
	(arc
		(start 113.08969 -226.656646)
		(mid 113.089551 -226.660583)
		(end 113.089436 -226.66452)
		(width 0.1143)
		(layer "In4.Cu")
		(net "GMI_CPU1_G2_CPU0_G0_TX_DN<1>")
	)
	(arc
		(start 357.00335 -229.024434)
		(mid 357.055399 -228.892915)
		(end 357.152448 -228.789992)
		(width 0.1143)
		(layer "In4.Cu")
		(net "GMI_CPU1_G2_CPU0_G0_TX_DN<1>")
	)
	(arc
		(start 358.406446 -226.664266)
		(mid 358.406333 -226.660329)
		(end 358.406192 -226.656392)
		(width 0.1143)
		(layer "In4.Cu")
		(net "GMI_CPU1_G2_CPU0_G0_TX_DN<1>")
	)
	(arc
		(start 114.033808 -228.322886)
		(mid 114.11461 -228.55863)
		(end 114.274092 -228.750114)
		(width 0.1143)
		(layer "In4.Cu")
		(net "GMI_CPU1_G2_CPU0_G0_TX_DN<1>")
	)
	(arc
		(start 357.466392 -228.26599)
		(mid 357.503685 -228.11133)
		(end 357.607362 -227.990654)
		(width 0.1143)
		(layer "In4.Cu")
		(net "GMI_CPU1_G2_CPU0_G0_TX_DN<1>")
	)
	(arc
		(start 358.131872 -225.528378)
		(mid 358.277992 -225.4025)
		(end 358.373172 -225.234754)
		(width 0.1143)
		(layer "In4.Cu")
		(net "GMI_CPU1_G2_CPU0_G0_TX_DN<1>")
	)
	(arc
		(start 113.089436 -221.804484)
		(mid 113.117352 -221.98046)
		(end 113.198656 -222.139002)
		(width 0.1143)
		(layer "In4.Cu")
		(net "GMI_CPU1_G2_CPU0_G0_TX_DN<1>")
	)
	(arc
		(start 113.371376 -224.557082)
		(mid 113.164932 -224.762924)
		(end 113.089436 -225.044508)
		(width 0.1143)
		(layer "In4.Cu")
		(net "GMI_CPU1_G2_CPU0_G0_TX_DN<1>")
	)
	(arc
		(start 113.40338 -222.310198)
		(mid 113.518056 -222.443532)
		(end 113.559336 -222.61449)
		(width 0.1143)
		(layer "In4.Cu")
		(net "GMI_CPU1_G2_CPU0_G0_TX_DN<1>")
	)
	(arc
		(start 358.373426 -225.234754)
		(mid 358.398252 -225.140936)
		(end 358.4067 -225.044254)
		(width 0.1143)
		(layer "In4.Cu")
		(net "GMI_CPU1_G2_CPU0_G0_TX_DN<1>")
	)
	(arc
		(start 357.22179 -228.74986)
		(mid 357.381234 -228.558355)
		(end 357.462074 -228.322632)
		(width 0.1143)
		(layer "In4.Cu")
		(net "GMI_CPU1_G2_CPU0_G0_TX_DN<1>")
	)
	(arc
		(start 113.559336 -222.61449)
		(mid 113.517787 -222.785912)
		(end 113.402364 -222.91929)
		(width 0.1143)
		(layer "In4.Cu")
		(net "GMI_CPU1_G2_CPU0_G0_TX_DN<1>")
	)
	(arc
		(start 357.936546 -227.474272)
		(mid 357.978095 -227.30285)
		(end 358.093518 -227.169472)
		(width 0.1143)
		(layer "In4.Cu")
		(net "GMI_CPU1_G2_CPU0_G0_TX_DN<1>")
	)
	(arc
		(start 113.08969 -223.424496)
		(mid 113.154926 -223.688087)
		(end 113.335562 -223.89084)
		(width 0.1143)
		(layer "In4.Cu")
		(net "GMI_CPU1_G2_CPU0_G0_TX_DN<1>")
	)
	(arc
		(start 358.405684 -223.409256)
		(mid 358.331761 -223.158909)
		(end 358.163114 -222.959676)
		(width 0.1143)
		(layer "In4.Cu")
		(net "GMI_CPU1_G2_CPU0_G0_TX_DN<1>")
	)
	(arc
		(start 113.873534 -227.98024)
		(mid 113.985921 -228.109179)
		(end 114.029236 -228.274626)
		(width 0.1143)
		(layer "In4.Cu")
		(net "GMI_CPU1_G2_CPU0_G0_TX_DN<1>")
	)
	(arc
		(start 114.343434 -228.790246)
		(mid 114.440569 -228.893115)
		(end 114.492532 -229.024688)
		(width 0.1143)
		(layer "In4.Cu")
		(net "GMI_CPU1_G2_CPU0_G0_TX_DN<1>")
	)
	(arc
		(start 113.332768 -222.95993)
		(mid 113.164144 -223.159175)
		(end 113.090198 -223.40951)
		(width 0.1143)
		(layer "In4.Cu")
		(net "GMI_CPU1_G2_CPU0_G0_TX_DN<1>")
	)
	(arc
		(start 358.16032 -223.890586)
		(mid 358.340972 -223.687841)
		(end 358.406192 -223.424242)
		(width 0.1143)
		(layer "In4.Cu")
		(net "GMI_CPU1_G2_CPU0_G0_TX_DN<1>")
	)
	(arc
		(start 358.163368 -222.268796)
		(mid 358.235695 -222.209329)
		(end 358.297226 -222.138748)
		(width 0.1143)
		(layer "In4.Cu")
		(net "GMI_CPU1_G2_CPU0_G0_TX_DN<1>")
	)
	(arc
		(start 113.402364 -227.169726)
		(mid 113.517791 -227.303102)
		(end 113.559336 -227.474526)
		(width 0.1143)
		(layer "In4.Cu")
		(net "GMI_CPU1_G2_CPU0_G0_TX_DN<1>")
	)
	(arc
		(start 113.12271 -225.235008)
		(mid 113.217869 -225.402771)
		(end 113.36401 -225.528632)
		(width 0.1143)
		(layer "In4.Cu")
		(net "GMI_CPU1_G2_CPU0_G0_TX_DN<1>")
	)
	(arc
		(start 113.090198 -223.40951)
		(mid 113.089773 -223.417001)
		(end 113.089436 -223.424496)
		(width 0.1143)
		(layer "In4.Cu")
		(net "GMI_CPU1_G2_CPU0_G0_TX_DN<1>")
	)
	(arc
		(start 358.121966 -224.555558)
		(mid 357.937472 -224.25095)
		(end 358.092248 -223.93021)
		(width 0.1143)
		(layer "In4.Cu")
		(net "GMI_CPU1_G2_CPU0_G0_TX_DN<1>")
	)
	(arc
		(start 113.403634 -223.930464)
		(mid 113.558427 -224.251205)
		(end 113.373916 -224.555812)
		(width 0.1143)
		(layer "In4.Cu")
		(net "GMI_CPU1_G2_CPU0_G0_TX_DN<1>")
	)
	(arc
		(start 358.297226 -222.138748)
		(mid 358.378517 -221.980201)
		(end 358.406446 -221.80423)
		(width 0.1143)
		(layer "In4.Cu")
		(net "GMI_CPU1_G2_CPU0_G0_TX_DN<1>")
	)
	(arc
		(start 357.936546 -222.614236)
		(mid 357.977801 -222.443265)
		(end 358.092502 -222.309944)
		(width 0.1143)
		(layer "In4.Cu")
		(net "GMI_CPU1_G2_CPU0_G0_TX_DN<1>")
	)
	(arc
		(start 113.559336 -227.474526)
		(mid 113.623851 -227.736745)
		(end 113.802668 -227.939092)
		(width 0.1143)
		(layer "In4.Cu")
		(net "GMI_CPU1_G2_CPU0_G0_TX_DN<1>")
	)
	(arc
		(start 113.37417 -225.534474)
		(mid 113.558144 -225.8386)
		(end 113.40338 -226.158552)
		(width 0.1143)
		(layer "In4.Cu")
		(net "GMI_CPU1_G2_CPU0_G0_TX_DN<1>")
	)
	(arc
		(start 358.406446 -223.424242)
		(mid 358.40611 -223.416747)
		(end 358.405684 -223.409256)
		(width 0.1143)
		(layer "In4.Cu")
		(net "GMI_CPU1_G2_CPU0_G0_TX_DN<1>")
	)
	(arc
		(start 358.093518 -222.919036)
		(mid 357.978091 -222.78566)
		(end 357.936546 -222.614236)
		(width 0.1143)
		(layer "In4.Cu")
		(net "GMI_CPU1_G2_CPU0_G0_TX_DN<1>")
	)
	(arc
		(start 113.198656 -222.139002)
		(mid 113.260175 -222.209596)
		(end 113.332514 -222.26905)
		(width 0.1143)
		(layer "In4.Cu")
		(net "GMI_CPU1_G2_CPU0_G0_TX_DN<1>")
	)
	(arc
		(start 358.092502 -226.158298)
		(mid 357.937792 -225.838349)
		(end 358.121712 -225.53422)
		(width 0.1143)
		(layer "In4.Cu")
		(net "GMI_CPU1_G2_CPU0_G0_TX_DN<1>")
	)
	(arc
		(start 358.16032 -227.13061)
		(mid 358.340972 -226.927865)
		(end 358.406192 -226.664266)
		(width 0.1143)
		(layer "In4.Cu")
		(net "GMI_CPU1_G2_CPU0_G0_TX_DN<1>")
	)
	(arc
		(start 358.406192 -226.656392)
		(mid 358.336575 -226.400404)
		(end 358.163114 -226.1997)
		(width 0.1143)
		(layer "In4.Cu")
		(net "GMI_CPU1_G2_CPU0_G0_TX_DN<1>")
	)
	(arc
		(start 114.029744 -228.274626)
		(mid 114.031112 -228.298812)
		(end 114.033808 -228.322886)
		(width 0.1143)
		(layer "In4.Cu")
		(net "GMI_CPU1_G2_CPU0_G0_TX_DN<1>")
	)
	(arc
		(start 113.08969 -226.66452)
		(mid 113.154926 -226.928111)
		(end 113.335562 -227.130864)
		(width 0.1143)
		(layer "In4.Cu")
		(net "GMI_CPU1_G2_CPU0_G0_TX_DN<1>")
	)
	(arc
		(start 113.089182 -225.044508)
		(mid 113.097599 -225.141195)
		(end 113.122456 -225.235008)
		(width 0.1143)
		(layer "In4.Cu")
		(net "GMI_CPU1_G2_CPU0_G0_TX_DN<1>")
	)
	(arc
		(start 357.693214 -227.938838)
		(mid 357.872027 -227.736488)
		(end 357.936546 -227.474272)
		(width 0.1143)
		(layer "In4.Cu")
		(net "GMI_CPU1_G2_CPU0_G0_TX_DN<1>")
	)
	(arc
		(start 113.332768 -226.199954)
		(mid 113.15935 -226.400681)
		(end 113.08969 -226.656646)
		(width 0.1143)
		(layer "In4.Cu")
		(net "GMI_CPU1_G2_CPU0_G0_TX_DN<1>")
	)
	(segment
		(start 124.467874 -231.79024)
		(end 124.934726 -231.524302)
		(width 0.12954)
		(layer "F.Cu")
		(net "GMI_CPU1_G2_CPU0_G0_TX_DN<15>")
	)
	(segment
		(start 347.028008 -231.789986)
		(end 346.561156 -231.524048)
		(width 0.12954)
		(layer "F.Cu")
		(net "GMI_CPU1_G2_CPU0_G0_TX_DN<15>")
	)
	(segment
		(start 126.531878 -229.416864)
		(end 126.56439 -229.398068)
		(width 0.1143)
		(layer "In4.Cu")
		(net "GMI_CPU1_G2_CPU0_G0_TX_DN<15>")
	)
	(segment
		(start 126.562358 -228.789738)
		(end 126.531878 -228.771958)
		(width 0.1143)
		(layer "In4.Cu")
		(net "GMI_CPU1_G2_CPU0_G0_TX_DN<15>")
	)
	(segment
		(start 345.871546 -231.017826)
		(end 345.904058 -231.036622)
		(width 0.1143)
		(layer "In4.Cu")
		(net "GMI_CPU1_G2_CPU0_G0_TX_DN<15>")
	)
	(segment
		(start 126.203456 -221.203012)
		(end 126.203456 -221.174564)
		(width 0.1143)
		(layer "In4.Cu")
		(net "GMI_CPU1_G2_CPU0_G0_TX_DN<15>")
	)
	(segment
		(start 126.531878 -224.557082)
		(end 126.562358 -224.539302)
		(width 0.1143)
		(layer "In4.Cu")
		(net "GMI_CPU1_G2_CPU0_G0_TX_DN<15>")
	)
	(segment
		(start 345.246706 -221.248478)
		(end 345.246706 -221.545658)
		(width 0.1143)
		(layer "In4.Cu")
		(net "GMI_CPU1_G2_CPU0_G0_TX_DN<15>")
	)
	(segment
		(start 126.531878 -228.771958)
		(end 126.492762 -228.749098)
		(width 0.1143)
		(layer "In4.Cu")
		(net "GMI_CPU1_G2_CPU0_G0_TX_DN<15>")
	)
	(segment
		(start 126.531878 -225.531934)
		(end 126.492762 -225.509074)
		(width 0.1143)
		(layer "In4.Cu")
		(net "GMI_CPU1_G2_CPU0_G0_TX_DN<15>")
	)
	(segment
		(start 126.203456 -221.174564)
		(end 126.203456 -221.04858)
		(width 0.14224)
		(layer "In4.Cu")
		(net "GMI_CPU1_G2_CPU0_G0_TX_DN<15>")
	)
	(segment
		(start 126.492762 -226.199954)
		(end 126.531878 -226.177094)
		(width 0.1143)
		(layer "In4.Cu")
		(net "GMI_CPU1_G2_CPU0_G0_TX_DN<15>")
	)
	(segment
		(start 162.410648 -191.505586)
		(end 162.863276 -191.133984)
		(width 0.14224)
		(layer "In4.Cu")
		(net "GMI_CPU1_G2_CPU0_G0_TX_DN<15>")
	)
	(segment
		(start 126.249684 -221.54642)
		(end 126.249176 -221.545912)
		(width 0.1143)
		(layer "In4.Cu")
		(net "GMI_CPU1_G2_CPU0_G0_TX_DN<15>")
	)
	(segment
		(start 316.58433 -196.795136)
		(end 344.65387 -219.810584)
		(width 0.14224)
		(layer "In4.Cu")
		(net "GMI_CPU1_G2_CPU0_G0_TX_DN<15>")
	)
	(segment
		(start 345.292426 -221.202758)
		(end 345.246706 -221.248478)
		(width 0.1143)
		(layer "In4.Cu")
		(net "GMI_CPU1_G2_CPU0_G0_TX_DN<15>")
	)
	(segment
		(start 346.263214 -231.524048)
		(end 346.561156 -231.524048)
		(width 0.1143)
		(layer "In4.Cu")
		(net "GMI_CPU1_G2_CPU0_G0_TX_DN<15>")
	)
	(segment
		(start 236.278928 -201.360278)
		(end 240.213642 -200.66635)
		(width 0.14224)
		(layer "In4.Cu")
		(net "GMI_CPU1_G2_CPU0_G0_TX_DN<15>")
	)
	(segment
		(start 147.284948 -202.981814)
		(end 150.061676 -202.140566)
		(width 0.14224)
		(layer "In4.Cu")
		(net "GMI_CPU1_G2_CPU0_G0_TX_DN<15>")
	)
	(segment
		(start 344.933524 -226.15906)
		(end 345.00312 -226.1997)
		(width 0.1143)
		(layer "In4.Cu")
		(net "GMI_CPU1_G2_CPU0_G0_TX_DN<15>")
	)
	(segment
		(start 232.027222 -200.61047)
		(end 236.278928 -201.360278)
		(width 0.14224)
		(layer "In4.Cu")
		(net "GMI_CPU1_G2_CPU0_G0_TX_DN<15>")
	)
	(segment
		(start 126.249176 -221.545912)
		(end 126.249176 -221.248732)
		(width 0.1143)
		(layer "In4.Cu")
		(net "GMI_CPU1_G2_CPU0_G0_TX_DN<15>")
	)
	(segment
		(start 162.863276 -191.133984)
		(end 207.18145 -190.945516)
		(width 0.14224)
		(layer "In4.Cu")
		(net "GMI_CPU1_G2_CPU0_G0_TX_DN<15>")
	)
	(segment
		(start 126.531878 -222.93707)
		(end 126.562358 -222.91929)
		(width 0.1143)
		(layer "In4.Cu")
		(net "GMI_CPU1_G2_CPU0_G0_TX_DN<15>")
	)
	(segment
		(start 344.933524 -222.919036)
		(end 345.00312 -222.959676)
		(width 0.1143)
		(layer "In4.Cu")
		(net "GMI_CPU1_G2_CPU0_G0_TX_DN<15>")
	)
	(segment
		(start 126.249684 -221.804484)
		(end 126.249684 -221.54642)
		(width 0.1143)
		(layer "In4.Cu")
		(net "GMI_CPU1_G2_CPU0_G0_TX_DN<15>")
	)
	(segment
		(start 124.934726 -231.524302)
		(end 125.232668 -231.524302)
		(width 0.1143)
		(layer "In4.Cu")
		(net "GMI_CPU1_G2_CPU0_G0_TX_DN<15>")
	)
	(segment
		(start 126.531878 -223.911922)
		(end 126.492762 -223.889062)
		(width 0.1143)
		(layer "In4.Cu")
		(net "GMI_CPU1_G2_CPU0_G0_TX_DN<15>")
	)
	(segment
		(start 126.562358 -225.549714)
		(end 126.531878 -225.531934)
		(width 0.1143)
		(layer "In4.Cu")
		(net "GMI_CPU1_G2_CPU0_G0_TX_DN<15>")
	)
	(segment
		(start 345.292426 -220.885766)
		(end 345.292426 -221.17431)
		(width 0.14224)
		(layer "In4.Cu")
		(net "GMI_CPU1_G2_CPU0_G0_TX_DN<15>")
	)
	(segment
		(start 345.402408 -230.208328)
		(end 345.434158 -230.226616)
		(width 0.1143)
		(layer "In4.Cu")
		(net "GMI_CPU1_G2_CPU0_G0_TX_DN<15>")
	)
	(segment
		(start 126.531878 -227.797106)
		(end 126.562358 -227.779326)
		(width 0.1143)
		(layer "In4.Cu")
		(net "GMI_CPU1_G2_CPU0_G0_TX_DN<15>")
	)
	(segment
		(start 344.931492 -229.397814)
		(end 344.964004 -229.41661)
		(width 0.1143)
		(layer "In4.Cu")
		(net "GMI_CPU1_G2_CPU0_G0_TX_DN<15>")
	)
	(segment
		(start 150.061676 -202.140566)
		(end 161.922714 -192.415414)
		(width 0.14224)
		(layer "In4.Cu")
		(net "GMI_CPU1_G2_CPU0_G0_TX_DN<15>")
	)
	(segment
		(start 344.933524 -227.779072)
		(end 345.00312 -227.819712)
		(width 0.1143)
		(layer "In4.Cu")
		(net "GMI_CPU1_G2_CPU0_G0_TX_DN<15>")
	)
	(segment
		(start 262.818118 -190.67272)
		(end 303.734724 -191.04991)
		(width 0.14224)
		(layer "In4.Cu")
		(net "GMI_CPU1_G2_CPU0_G0_TX_DN<15>")
	)
	(segment
		(start 125.232668 -231.524302)
		(end 125.315472 -231.441498)
		(width 0.1143)
		(layer "In4.Cu")
		(net "GMI_CPU1_G2_CPU0_G0_TX_DN<15>")
	)
	(segment
		(start 344.65387 -219.810584)
		(end 345.292426 -220.885766)
		(width 0.14224)
		(layer "In4.Cu")
		(net "GMI_CPU1_G2_CPU0_G0_TX_DN<15>")
	)
	(segment
		(start 126.061724 -230.22687)
		(end 126.093474 -230.208582)
		(width 0.1143)
		(layer "In4.Cu")
		(net "GMI_CPU1_G2_CPU0_G0_TX_DN<15>")
	)
	(segment
		(start 126.531878 -227.151946)
		(end 126.492762 -227.129086)
		(width 0.1143)
		(layer "In4.Cu")
		(net "GMI_CPU1_G2_CPU0_G0_TX_DN<15>")
	)
	(segment
		(start 126.492762 -229.439724)
		(end 126.531878 -229.416864)
		(width 0.1143)
		(layer "In4.Cu")
		(net "GMI_CPU1_G2_CPU0_G0_TX_DN<15>")
	)
	(segment
		(start 308.356762 -191.04991)
		(end 316.58433 -196.795136)
		(width 0.14224)
		(layer "In4.Cu")
		(net "GMI_CPU1_G2_CPU0_G0_TX_DN<15>")
	)
	(segment
		(start 251.681234 -192.63614)
		(end 262.818118 -190.67272)
		(width 0.14224)
		(layer "In4.Cu")
		(net "GMI_CPU1_G2_CPU0_G0_TX_DN<15>")
	)
	(segment
		(start 126.531878 -226.177094)
		(end 126.562358 -226.159314)
		(width 0.1143)
		(layer "In4.Cu")
		(net "GMI_CPU1_G2_CPU0_G0_TX_DN<15>")
	)
	(segment
		(start 126.562358 -222.30969)
		(end 126.492762 -222.26905)
		(width 0.1143)
		(layer "In4.Cu")
		(net "GMI_CPU1_G2_CPU0_G0_TX_DN<15>")
	)
	(segment
		(start 345.434158 -230.226616)
		(end 345.470734 -230.247952)
		(width 0.1143)
		(layer "In4.Cu")
		(net "GMI_CPU1_G2_CPU0_G0_TX_DN<15>")
	)
	(segment
		(start 126.203456 -221.04858)
		(end 127.10795 -219.525596)
		(width 0.14224)
		(layer "In4.Cu")
		(net "GMI_CPU1_G2_CPU0_G0_TX_DN<15>")
	)
	(segment
		(start 345.00312 -227.128832)
		(end 344.933524 -227.169472)
		(width 0.1143)
		(layer "In4.Cu")
		(net "GMI_CPU1_G2_CPU0_G0_TX_DN<15>")
	)
	(segment
		(start 345.246198 -221.546166)
		(end 345.246198 -221.80423)
		(width 0.1143)
		(layer "In4.Cu")
		(net "GMI_CPU1_G2_CPU0_G0_TX_DN<15>")
	)
	(segment
		(start 125.552708 -231.059736)
		(end 125.591824 -231.036876)
		(width 0.1143)
		(layer "In4.Cu")
		(net "GMI_CPU1_G2_CPU0_G0_TX_DN<15>")
	)
	(segment
		(start 125.591824 -231.036876)
		(end 125.624336 -231.01808)
		(width 0.1143)
		(layer "In4.Cu")
		(net "GMI_CPU1_G2_CPU0_G0_TX_DN<15>")
	)
	(segment
		(start 126.025148 -230.248206)
		(end 126.061724 -230.22687)
		(width 0.1143)
		(layer "In4.Cu")
		(net "GMI_CPU1_G2_CPU0_G0_TX_DN<15>")
	)
	(segment
		(start 127.10795 -219.525596)
		(end 147.284948 -202.981814)
		(width 0.14224)
		(layer "In4.Cu")
		(net "GMI_CPU1_G2_CPU0_G0_TX_DN<15>")
	)
	(segment
		(start 240.213642 -200.66635)
		(end 251.681234 -192.63614)
		(width 0.14224)
		(layer "In4.Cu")
		(net "GMI_CPU1_G2_CPU0_G0_TX_DN<15>")
	)
	(segment
		(start 126.562358 -227.169726)
		(end 126.531878 -227.151946)
		(width 0.1143)
		(layer "In4.Cu")
		(net "GMI_CPU1_G2_CPU0_G0_TX_DN<15>")
	)
	(segment
		(start 344.933524 -224.539048)
		(end 345.00312 -224.579688)
		(width 0.1143)
		(layer "In4.Cu")
		(net "GMI_CPU1_G2_CPU0_G0_TX_DN<15>")
	)
	(segment
		(start 345.904058 -231.036622)
		(end 345.943174 -231.059482)
		(width 0.1143)
		(layer "In4.Cu")
		(net "GMI_CPU1_G2_CPU0_G0_TX_DN<15>")
	)
	(segment
		(start 126.492762 -224.579942)
		(end 126.531878 -224.557082)
		(width 0.1143)
		(layer "In4.Cu")
		(net "GMI_CPU1_G2_CPU0_G0_TX_DN<15>")
	)
	(segment
		(start 345.00312 -228.748844)
		(end 344.933524 -228.789484)
		(width 0.1143)
		(layer "In4.Cu")
		(net "GMI_CPU1_G2_CPU0_G0_TX_DN<15>")
	)
	(segment
		(start 345.00312 -225.50882)
		(end 344.933524 -225.54946)
		(width 0.1143)
		(layer "In4.Cu")
		(net "GMI_CPU1_G2_CPU0_G0_TX_DN<15>")
	)
	(segment
		(start 126.492762 -227.819966)
		(end 126.531878 -227.797106)
		(width 0.1143)
		(layer "In4.Cu")
		(net "GMI_CPU1_G2_CPU0_G0_TX_DN<15>")
	)
	(segment
		(start 126.562358 -223.929702)
		(end 126.531878 -223.911922)
		(width 0.1143)
		(layer "In4.Cu")
		(net "GMI_CPU1_G2_CPU0_G0_TX_DN<15>")
	)
	(segment
		(start 303.734724 -191.04991)
		(end 308.356762 -191.04991)
		(width 0.14224)
		(layer "In4.Cu")
		(net "GMI_CPU1_G2_CPU0_G0_TX_DN<15>")
	)
	(segment
		(start 209.814922 -191.410336)
		(end 232.027222 -200.61047)
		(width 0.14224)
		(layer "In4.Cu")
		(net "GMI_CPU1_G2_CPU0_G0_TX_DN<15>")
	)
	(segment
		(start 161.922714 -192.415414)
		(end 162.410648 -191.505586)
		(width 0.14224)
		(layer "In4.Cu")
		(net "GMI_CPU1_G2_CPU0_G0_TX_DN<15>")
	)
	(segment
		(start 126.249176 -221.248732)
		(end 126.203456 -221.203012)
		(width 0.1143)
		(layer "In4.Cu")
		(net "GMI_CPU1_G2_CPU0_G0_TX_DN<15>")
	)
	(segment
		(start 346.18041 -231.441244)
		(end 346.263214 -231.524048)
		(width 0.1143)
		(layer "In4.Cu")
		(net "GMI_CPU1_G2_CPU0_G0_TX_DN<15>")
	)
	(segment
		(start 345.292426 -221.17431)
		(end 345.292426 -221.202758)
		(width 0.1143)
		(layer "In4.Cu")
		(net "GMI_CPU1_G2_CPU0_G0_TX_DN<15>")
	)
	(segment
		(start 345.246706 -221.545658)
		(end 345.246198 -221.546166)
		(width 0.1143)
		(layer "In4.Cu")
		(net "GMI_CPU1_G2_CPU0_G0_TX_DN<15>")
	)
	(segment
		(start 207.18145 -190.945516)
		(end 209.814922 -191.410336)
		(width 0.14224)
		(layer "In4.Cu")
		(net "GMI_CPU1_G2_CPU0_G0_TX_DN<15>")
	)
	(segment
		(start 345.00312 -222.268796)
		(end 344.933524 -222.309436)
		(width 0.1143)
		(layer "In4.Cu")
		(net "GMI_CPU1_G2_CPU0_G0_TX_DN<15>")
	)
	(segment
		(start 345.00312 -223.888808)
		(end 344.933524 -223.929448)
		(width 0.1143)
		(layer "In4.Cu")
		(net "GMI_CPU1_G2_CPU0_G0_TX_DN<15>")
	)
	(segment
		(start 126.492762 -222.95993)
		(end 126.531878 -222.93707)
		(width 0.1143)
		(layer "In4.Cu")
		(net "GMI_CPU1_G2_CPU0_G0_TX_DN<15>")
	)
	(segment
		(start 344.964004 -229.41661)
		(end 345.00312 -229.43947)
		(width 0.1143)
		(layer "In4.Cu")
		(net "GMI_CPU1_G2_CPU0_G0_TX_DN<15>")
	)
	(arc
		(start 344.933524 -223.929448)
		(mid 344.776547 -224.234248)
		(end 344.933524 -224.539048)
		(width 0.1143)
		(layer "In4.Cu")
		(net "GMI_CPU1_G2_CPU0_G0_TX_DN<15>")
	)
	(arc
		(start 345.246198 -221.80423)
		(mid 345.181824 -222.066434)
		(end 345.00312 -222.268796)
		(width 0.1143)
		(layer "In4.Cu")
		(net "GMI_CPU1_G2_CPU0_G0_TX_DN<15>")
	)
	(arc
		(start 126.492762 -227.129086)
		(mid 126.249435 -226.66452)
		(end 126.492762 -226.199954)
		(width 0.1143)
		(layer "In4.Cu")
		(net "GMI_CPU1_G2_CPU0_G0_TX_DN<15>")
	)
	(arc
		(start 345.716606 -230.714296)
		(mid 345.757572 -230.884702)
		(end 345.871546 -231.017826)
		(width 0.1143)
		(layer "In4.Cu")
		(net "GMI_CPU1_G2_CPU0_G0_TX_DN<15>")
	)
	(arc
		(start 125.315472 -231.441498)
		(mid 125.31726 -231.430049)
		(end 125.319282 -231.418638)
		(width 0.1143)
		(layer "In4.Cu")
		(net "GMI_CPU1_G2_CPU0_G0_TX_DN<15>")
	)
	(arc
		(start 345.943174 -231.059482)
		(mid 346.095161 -231.21599)
		(end 346.1766 -231.418384)
		(width 0.1143)
		(layer "In4.Cu")
		(net "GMI_CPU1_G2_CPU0_G0_TX_DN<15>")
	)
	(arc
		(start 126.24943 -229.90429)
		(mid 126.313945 -229.642071)
		(end 126.492762 -229.439724)
		(width 0.1143)
		(layer "In4.Cu")
		(net "GMI_CPU1_G2_CPU0_G0_TX_DN<15>")
	)
	(arc
		(start 126.093474 -230.208582)
		(mid 126.20815 -230.075248)
		(end 126.24943 -229.90429)
		(width 0.1143)
		(layer "In4.Cu")
		(net "GMI_CPU1_G2_CPU0_G0_TX_DN<15>")
	)
	(arc
		(start 126.562358 -227.779326)
		(mid 126.719335 -227.474526)
		(end 126.562358 -227.169726)
		(width 0.1143)
		(layer "In4.Cu")
		(net "GMI_CPU1_G2_CPU0_G0_TX_DN<15>")
	)
	(arc
		(start 126.56439 -229.398068)
		(mid 126.678319 -229.264921)
		(end 126.71933 -229.094538)
		(width 0.1143)
		(layer "In4.Cu")
		(net "GMI_CPU1_G2_CPU0_G0_TX_DN<15>")
	)
	(arc
		(start 345.470734 -230.247952)
		(mid 345.651386 -230.450697)
		(end 345.716606 -230.714296)
		(width 0.1143)
		(layer "In4.Cu")
		(net "GMI_CPU1_G2_CPU0_G0_TX_DN<15>")
	)
	(arc
		(start 125.779276 -230.71455)
		(mid 125.844512 -230.450959)
		(end 126.025148 -230.248206)
		(width 0.1143)
		(layer "In4.Cu")
		(net "GMI_CPU1_G2_CPU0_G0_TX_DN<15>")
	)
	(arc
		(start 345.00312 -224.579688)
		(mid 345.246447 -225.044254)
		(end 345.00312 -225.50882)
		(width 0.1143)
		(layer "In4.Cu")
		(net "GMI_CPU1_G2_CPU0_G0_TX_DN<15>")
	)
	(arc
		(start 125.319282 -231.418638)
		(mid 125.400715 -231.21624)
		(end 125.552708 -231.059736)
		(width 0.1143)
		(layer "In4.Cu")
		(net "GMI_CPU1_G2_CPU0_G0_TX_DN<15>")
	)
	(arc
		(start 126.492762 -225.509074)
		(mid 126.249435 -225.044508)
		(end 126.492762 -224.579942)
		(width 0.1143)
		(layer "In4.Cu")
		(net "GMI_CPU1_G2_CPU0_G0_TX_DN<15>")
	)
	(arc
		(start 345.00312 -229.43947)
		(mid 345.181933 -229.64182)
		(end 345.246452 -229.904036)
		(width 0.1143)
		(layer "In4.Cu")
		(net "GMI_CPU1_G2_CPU0_G0_TX_DN<15>")
	)
	(arc
		(start 126.492762 -223.889062)
		(mid 126.249435 -223.424496)
		(end 126.492762 -222.95993)
		(width 0.1143)
		(layer "In4.Cu")
		(net "GMI_CPU1_G2_CPU0_G0_TX_DN<15>")
	)
	(arc
		(start 345.00312 -226.1997)
		(mid 345.246447 -226.664266)
		(end 345.00312 -227.128832)
		(width 0.1143)
		(layer "In4.Cu")
		(net "GMI_CPU1_G2_CPU0_G0_TX_DN<15>")
	)
	(arc
		(start 344.933524 -228.789484)
		(mid 344.818097 -228.92286)
		(end 344.776552 -229.094284)
		(width 0.1143)
		(layer "In4.Cu")
		(net "GMI_CPU1_G2_CPU0_G0_TX_DN<15>")
	)
	(arc
		(start 345.246452 -229.904036)
		(mid 345.287707 -230.075007)
		(end 345.402408 -230.208328)
		(width 0.1143)
		(layer "In4.Cu")
		(net "GMI_CPU1_G2_CPU0_G0_TX_DN<15>")
	)
	(arc
		(start 125.624336 -231.01808)
		(mid 125.738265 -230.884933)
		(end 125.779276 -230.71455)
		(width 0.1143)
		(layer "In4.Cu")
		(net "GMI_CPU1_G2_CPU0_G0_TX_DN<15>")
	)
	(arc
		(start 344.933524 -227.169472)
		(mid 344.776547 -227.474272)
		(end 344.933524 -227.779072)
		(width 0.1143)
		(layer "In4.Cu")
		(net "GMI_CPU1_G2_CPU0_G0_TX_DN<15>")
	)
	(arc
		(start 126.492762 -222.26905)
		(mid 126.314119 -222.066655)
		(end 126.249684 -221.804484)
		(width 0.1143)
		(layer "In4.Cu")
		(net "GMI_CPU1_G2_CPU0_G0_TX_DN<15>")
	)
	(arc
		(start 345.00312 -227.819712)
		(mid 345.246447 -228.284278)
		(end 345.00312 -228.748844)
		(width 0.1143)
		(layer "In4.Cu")
		(net "GMI_CPU1_G2_CPU0_G0_TX_DN<15>")
	)
	(arc
		(start 344.933524 -225.54946)
		(mid 344.776547 -225.85426)
		(end 344.933524 -226.15906)
		(width 0.1143)
		(layer "In4.Cu")
		(net "GMI_CPU1_G2_CPU0_G0_TX_DN<15>")
	)
	(arc
		(start 126.562358 -222.91929)
		(mid 126.719335 -222.61449)
		(end 126.562358 -222.30969)
		(width 0.1143)
		(layer "In4.Cu")
		(net "GMI_CPU1_G2_CPU0_G0_TX_DN<15>")
	)
	(arc
		(start 126.492762 -228.749098)
		(mid 126.249435 -228.284532)
		(end 126.492762 -227.819966)
		(width 0.1143)
		(layer "In4.Cu")
		(net "GMI_CPU1_G2_CPU0_G0_TX_DN<15>")
	)
	(arc
		(start 344.776552 -229.094284)
		(mid 344.817518 -229.26469)
		(end 344.931492 -229.397814)
		(width 0.1143)
		(layer "In4.Cu")
		(net "GMI_CPU1_G2_CPU0_G0_TX_DN<15>")
	)
	(arc
		(start 126.71933 -229.094538)
		(mid 126.677781 -228.923116)
		(end 126.562358 -228.789738)
		(width 0.1143)
		(layer "In4.Cu")
		(net "GMI_CPU1_G2_CPU0_G0_TX_DN<15>")
	)
	(arc
		(start 346.1766 -231.418384)
		(mid 346.178623 -231.429794)
		(end 346.18041 -231.441244)
		(width 0.1143)
		(layer "In4.Cu")
		(net "GMI_CPU1_G2_CPU0_G0_TX_DN<15>")
	)
	(arc
		(start 344.933524 -222.309436)
		(mid 344.776547 -222.614236)
		(end 344.933524 -222.919036)
		(width 0.1143)
		(layer "In4.Cu")
		(net "GMI_CPU1_G2_CPU0_G0_TX_DN<15>")
	)
	(arc
		(start 126.562358 -226.159314)
		(mid 126.719335 -225.854514)
		(end 126.562358 -225.549714)
		(width 0.1143)
		(layer "In4.Cu")
		(net "GMI_CPU1_G2_CPU0_G0_TX_DN<15>")
	)
	(arc
		(start 126.562358 -224.539302)
		(mid 126.719335 -224.234502)
		(end 126.562358 -223.929702)
		(width 0.1143)
		(layer "In4.Cu")
		(net "GMI_CPU1_G2_CPU0_G0_TX_DN<15>")
	)
	(arc
		(start 345.00312 -222.959676)
		(mid 345.246447 -223.424242)
		(end 345.00312 -223.888808)
		(width 0.1143)
		(layer "In4.Cu")
		(net "GMI_CPU1_G2_CPU0_G0_TX_DN<15>")
	)
	(segment
		(start 124.467874 -228.55047)
		(end 124.934726 -228.284532)
		(width 0.12954)
		(layer "F.Cu")
		(net "GMI_CPU1_G2_CPU0_G0_TX_DN<14>")
	)
	(segment
		(start 347.028008 -228.550216)
		(end 346.561156 -228.284278)
		(width 0.12954)
		(layer "F.Cu")
		(net "GMI_CPU1_G2_CPU0_G0_TX_DN<14>")
	)
	(segment
		(start 346.376498 -227.960428)
		(end 346.374212 -227.961698)
		(width 0.1143)
		(layer "In4.Cu")
		(net "GMI_CPU1_G2_CPU0_G0_TX_DN<14>")
	)
	(segment
		(start 125.122432 -227.96246)
		(end 125.12167 -227.961952)
		(width 0.1143)
		(layer "In4.Cu")
		(net "GMI_CPU1_G2_CPU0_G0_TX_DN<14>")
	)
	(segment
		(start 124.612654 -226.199954)
		(end 124.65177 -226.177094)
		(width 0.1143)
		(layer "In4.Cu")
		(net "GMI_CPU1_G2_CPU0_G0_TX_DN<14>")
	)
	(segment
		(start 124.65177 -224.557082)
		(end 124.68352 -224.538794)
		(width 0.1143)
		(layer "In4.Cu")
		(net "GMI_CPU1_G2_CPU0_G0_TX_DN<14>")
	)
	(segment
		(start 346.883228 -225.50882)
		(end 346.844112 -225.53168)
		(width 0.1143)
		(layer "In4.Cu")
		(net "GMI_CPU1_G2_CPU0_G0_TX_DN<14>")
	)
	(segment
		(start 124.369576 -221.804484)
		(end 124.369576 -221.62516)
		(width 0.1143)
		(layer "In4.Cu")
		(net "GMI_CPU1_G2_CPU0_G0_TX_DN<14>")
	)
	(segment
		(start 346.812362 -226.158552)
		(end 346.844112 -226.17684)
		(width 0.1143)
		(layer "In4.Cu")
		(net "GMI_CPU1_G2_CPU0_G0_TX_DN<14>")
	)
	(segment
		(start 346.812362 -224.53854)
		(end 346.844112 -224.556828)
		(width 0.1143)
		(layer "In4.Cu")
		(net "GMI_CPU1_G2_CPU0_G0_TX_DN<14>")
	)
	(segment
		(start 124.68352 -225.550222)
		(end 124.65177 -225.531934)
		(width 0.1143)
		(layer "In4.Cu")
		(net "GMI_CPU1_G2_CPU0_G0_TX_DN<14>")
	)
	(segment
		(start 124.612654 -222.95993)
		(end 124.65177 -222.93707)
		(width 0.1143)
		(layer "In4.Cu")
		(net "GMI_CPU1_G2_CPU0_G0_TX_DN<14>")
	)
	(segment
		(start 346.79255 -224.524316)
		(end 346.812362 -224.53854)
		(width 0.1143)
		(layer "In4.Cu")
		(net "GMI_CPU1_G2_CPU0_G0_TX_DN<14>")
	)
	(segment
		(start 124.323602 -220.541342)
		(end 125.6538 -218.224862)
		(width 0.14224)
		(layer "In4.Cu")
		(net "GMI_CPU1_G2_CPU0_G0_TX_DN<14>")
	)
	(segment
		(start 150.882858 -198.683118)
		(end 160.47847 -190.815722)
		(width 0.14224)
		(layer "In4.Cu")
		(net "GMI_CPU1_G2_CPU0_G0_TX_DN<14>")
	)
	(segment
		(start 347.12656 -221.624652)
		(end 347.126306 -221.624906)
		(width 0.1143)
		(layer "In4.Cu")
		(net "GMI_CPU1_G2_CPU0_G0_TX_DN<14>")
	)
	(segment
		(start 149.73173 -199.627236)
		(end 150.882858 -198.683372)
		(width 0.14224)
		(layer "In4.Cu")
		(net "GMI_CPU1_G2_CPU0_G0_TX_DN<14>")
	)
	(segment
		(start 211.800186 -189.850776)
		(end 234.012232 -199.051418)
		(width 0.14224)
		(layer "In4.Cu")
		(net "GMI_CPU1_G2_CPU0_G0_TX_DN<14>")
	)
	(segment
		(start 125.232668 -228.284532)
		(end 125.302518 -228.214682)
		(width 0.1143)
		(layer "In4.Cu")
		(net "GMI_CPU1_G2_CPU0_G0_TX_DN<14>")
	)
	(segment
		(start 346.37345 -227.962206)
		(end 346.37218 -227.962968)
		(width 0.1143)
		(layer "In4.Cu")
		(net "GMI_CPU1_G2_CPU0_G0_TX_DN<14>")
	)
	(segment
		(start 124.934726 -228.284532)
		(end 125.232668 -228.284532)
		(width 0.1143)
		(layer "In4.Cu")
		(net "GMI_CPU1_G2_CPU0_G0_TX_DN<14>")
	)
	(segment
		(start 347.17228 -221.17431)
		(end 347.17228 -221.202758)
		(width 0.1143)
		(layer "In4.Cu")
		(net "GMI_CPU1_G2_CPU0_G0_TX_DN<14>")
	)
	(segment
		(start 124.369322 -221.624906)
		(end 124.369322 -221.248732)
		(width 0.1143)
		(layer "In4.Cu")
		(net "GMI_CPU1_G2_CPU0_G0_TX_DN<14>")
	)
	(segment
		(start 207.361536 -189.068202)
		(end 211.800186 -189.850776)
		(width 0.14224)
		(layer "In4.Cu")
		(net "GMI_CPU1_G2_CPU0_G0_TX_DN<14>")
	)
	(segment
		(start 346.844112 -224.556828)
		(end 346.883228 -224.579688)
		(width 0.1143)
		(layer "In4.Cu")
		(net "GMI_CPU1_G2_CPU0_G0_TX_DN<14>")
	)
	(segment
		(start 346.37218 -227.962968)
		(end 346.342462 -227.979986)
		(width 0.1143)
		(layer "In4.Cu")
		(net "GMI_CPU1_G2_CPU0_G0_TX_DN<14>")
	)
	(segment
		(start 150.882858 -198.683372)
		(end 150.882858 -198.683118)
		(width 0.14224)
		(layer "In4.Cu")
		(net "GMI_CPU1_G2_CPU0_G0_TX_DN<14>")
	)
	(segment
		(start 250.94438 -190.857124)
		(end 262.665464 -188.790326)
		(width 0.14224)
		(layer "In4.Cu")
		(net "GMI_CPU1_G2_CPU0_G0_TX_DN<14>")
	)
	(segment
		(start 124.369322 -221.248732)
		(end 124.323602 -221.203012)
		(width 0.1143)
		(layer "In4.Cu")
		(net "GMI_CPU1_G2_CPU0_G0_TX_DN<14>")
	)
	(segment
		(start 124.66447 -227.159312)
		(end 124.612654 -227.129086)
		(width 0.1143)
		(layer "In4.Cu")
		(net "GMI_CPU1_G2_CPU0_G0_TX_DN<14>")
	)
	(segment
		(start 262.665464 -188.790326)
		(end 303.734724 -189.169548)
		(width 0.14224)
		(layer "In4.Cu")
		(net "GMI_CPU1_G2_CPU0_G0_TX_DN<14>")
	)
	(segment
		(start 124.703332 -223.944434)
		(end 124.68352 -223.93021)
		(width 0.1143)
		(layer "In4.Cu")
		(net "GMI_CPU1_G2_CPU0_G0_TX_DN<14>")
	)
	(segment
		(start 346.374212 -227.961698)
		(end 346.37345 -227.962206)
		(width 0.1143)
		(layer "In4.Cu")
		(net "GMI_CPU1_G2_CPU0_G0_TX_DN<14>")
	)
	(segment
		(start 303.734724 -189.169548)
		(end 309.09768 -189.169548)
		(width 0.14224)
		(layer "In4.Cu")
		(net "GMI_CPU1_G2_CPU0_G0_TX_DN<14>")
	)
	(segment
		(start 124.323602 -221.203012)
		(end 124.323602 -221.174564)
		(width 0.1143)
		(layer "In4.Cu")
		(net "GMI_CPU1_G2_CPU0_G0_TX_DN<14>")
	)
	(segment
		(start 124.65177 -222.93707)
		(end 124.68352 -222.918782)
		(width 0.1143)
		(layer "In4.Cu")
		(net "GMI_CPU1_G2_CPU0_G0_TX_DN<14>")
	)
	(segment
		(start 346.263214 -228.284278)
		(end 346.561156 -228.284278)
		(width 0.1143)
		(layer "In4.Cu")
		(net "GMI_CPU1_G2_CPU0_G0_TX_DN<14>")
	)
	(segment
		(start 347.17228 -220.382592)
		(end 347.17228 -221.17431)
		(width 0.14224)
		(layer "In4.Cu")
		(net "GMI_CPU1_G2_CPU0_G0_TX_DN<14>")
	)
	(segment
		(start 346.883228 -223.888808)
		(end 346.812362 -223.929956)
		(width 0.1143)
		(layer "In4.Cu")
		(net "GMI_CPU1_G2_CPU0_G0_TX_DN<14>")
	)
	(segment
		(start 124.65177 -225.531934)
		(end 124.612654 -225.509074)
		(width 0.1143)
		(layer "In4.Cu")
		(net "GMI_CPU1_G2_CPU0_G0_TX_DN<14>")
	)
	(segment
		(start 148.580602 -200.5711)
		(end 149.731984 -199.627236)
		(width 0.14224)
		(layer "In4.Cu")
		(net "GMI_CPU1_G2_CPU0_G0_TX_DN<14>")
	)
	(segment
		(start 347.126306 -221.624906)
		(end 347.126306 -221.80423)
		(width 0.1143)
		(layer "In4.Cu")
		(net "GMI_CPU1_G2_CPU0_G0_TX_DN<14>")
	)
	(segment
		(start 124.323602 -221.174564)
		(end 124.323602 -220.541342)
		(width 0.14224)
		(layer "In4.Cu")
		(net "GMI_CPU1_G2_CPU0_G0_TX_DN<14>")
	)
	(segment
		(start 239.476026 -198.887334)
		(end 239.47628 -198.887334)
		(width 0.14224)
		(layer "In4.Cu")
		(net "GMI_CPU1_G2_CPU0_G0_TX_DN<14>")
	)
	(segment
		(start 309.09768 -189.169548)
		(end 318.311276 -195.663312)
		(width 0.14224)
		(layer "In4.Cu")
		(net "GMI_CPU1_G2_CPU0_G0_TX_DN<14>")
	)
	(segment
		(start 160.47847 -190.815722)
		(end 160.63341 -190.526924)
		(width 0.14224)
		(layer "In4.Cu")
		(net "GMI_CPU1_G2_CPU0_G0_TX_DN<14>")
	)
	(segment
		(start 124.369576 -221.62516)
		(end 124.369322 -221.624906)
		(width 0.1143)
		(layer "In4.Cu")
		(net "GMI_CPU1_G2_CPU0_G0_TX_DN<14>")
	)
	(segment
		(start 239.47628 -198.887334)
		(end 250.94438 -190.857124)
		(width 0.14224)
		(layer "In4.Cu")
		(net "GMI_CPU1_G2_CPU0_G0_TX_DN<14>")
	)
	(segment
		(start 234.012232 -199.051418)
		(end 236.278928 -199.451214)
		(width 0.14224)
		(layer "In4.Cu")
		(net "GMI_CPU1_G2_CPU0_G0_TX_DN<14>")
	)
	(segment
		(start 125.12167 -227.961952)
		(end 125.119384 -227.960682)
		(width 0.1143)
		(layer "In4.Cu")
		(net "GMI_CPU1_G2_CPU0_G0_TX_DN<14>")
	)
	(segment
		(start 146.36623 -201.242168)
		(end 148.580602 -200.5711)
		(width 0.14224)
		(layer "In4.Cu")
		(net "GMI_CPU1_G2_CPU0_G0_TX_DN<14>")
	)
	(segment
		(start 124.65177 -226.177094)
		(end 124.68352 -226.158806)
		(width 0.1143)
		(layer "In4.Cu")
		(net "GMI_CPU1_G2_CPU0_G0_TX_DN<14>")
	)
	(segment
		(start 346.883228 -227.128832)
		(end 346.831412 -227.159058)
		(width 0.1143)
		(layer "In4.Cu")
		(net "GMI_CPU1_G2_CPU0_G0_TX_DN<14>")
	)
	(segment
		(start 346.844112 -225.53168)
		(end 346.812362 -225.549968)
		(width 0.1143)
		(layer "In4.Cu")
		(net "GMI_CPU1_G2_CPU0_G0_TX_DN<14>")
	)
	(segment
		(start 346.844112 -222.936816)
		(end 346.883228 -222.959676)
		(width 0.1143)
		(layer "In4.Cu")
		(net "GMI_CPU1_G2_CPU0_G0_TX_DN<14>")
	)
	(segment
		(start 346.643706 -227.483924)
		(end 346.643706 -227.49637)
		(width 0.1143)
		(layer "In4.Cu")
		(net "GMI_CPU1_G2_CPU0_G0_TX_DN<14>")
	)
	(segment
		(start 124.612654 -224.579942)
		(end 124.65177 -224.557082)
		(width 0.1143)
		(layer "In4.Cu")
		(net "GMI_CPU1_G2_CPU0_G0_TX_DN<14>")
	)
	(segment
		(start 124.68352 -224.538794)
		(end 124.703332 -224.52457)
		(width 0.1143)
		(layer "In4.Cu")
		(net "GMI_CPU1_G2_CPU0_G0_TX_DN<14>")
	)
	(segment
		(start 125.15342 -227.98024)
		(end 125.122432 -227.96246)
		(width 0.1143)
		(layer "In4.Cu")
		(net "GMI_CPU1_G2_CPU0_G0_TX_DN<14>")
	)
	(segment
		(start 160.63341 -190.526924)
		(end 162.17773 -189.259972)
		(width 0.14224)
		(layer "In4.Cu")
		(net "GMI_CPU1_G2_CPU0_G0_TX_DN<14>")
	)
	(segment
		(start 124.68352 -222.310198)
		(end 124.612654 -222.26905)
		(width 0.1143)
		(layer "In4.Cu")
		(net "GMI_CPU1_G2_CPU0_G0_TX_DN<14>")
	)
	(segment
		(start 346.844112 -226.17684)
		(end 346.883228 -226.1997)
		(width 0.1143)
		(layer "In4.Cu")
		(net "GMI_CPU1_G2_CPU0_G0_TX_DN<14>")
	)
	(segment
		(start 345.964256 -218.349576)
		(end 347.17228 -220.382592)
		(width 0.14224)
		(layer "In4.Cu")
		(net "GMI_CPU1_G2_CPU0_G0_TX_DN<14>")
	)
	(segment
		(start 318.311276 -195.663312)
		(end 318.311276 -195.67652)
		(width 0.14224)
		(layer "In4.Cu")
		(net "GMI_CPU1_G2_CPU0_G0_TX_DN<14>")
	)
	(segment
		(start 346.812362 -223.929956)
		(end 346.79255 -223.94418)
		(width 0.1143)
		(layer "In4.Cu")
		(net "GMI_CPU1_G2_CPU0_G0_TX_DN<14>")
	)
	(segment
		(start 346.193364 -228.214428)
		(end 346.263214 -228.284278)
		(width 0.1143)
		(layer "In4.Cu")
		(net "GMI_CPU1_G2_CPU0_G0_TX_DN<14>")
	)
	(segment
		(start 346.812362 -222.918528)
		(end 346.844112 -222.936816)
		(width 0.1143)
		(layer "In4.Cu")
		(net "GMI_CPU1_G2_CPU0_G0_TX_DN<14>")
	)
	(segment
		(start 347.12656 -221.248478)
		(end 347.12656 -221.624652)
		(width 0.1143)
		(layer "In4.Cu")
		(net "GMI_CPU1_G2_CPU0_G0_TX_DN<14>")
	)
	(segment
		(start 346.883228 -222.268796)
		(end 346.812362 -222.309944)
		(width 0.1143)
		(layer "In4.Cu")
		(net "GMI_CPU1_G2_CPU0_G0_TX_DN<14>")
	)
	(segment
		(start 347.17228 -221.202758)
		(end 347.12656 -221.248478)
		(width 0.1143)
		(layer "In4.Cu")
		(net "GMI_CPU1_G2_CPU0_G0_TX_DN<14>")
	)
	(segment
		(start 162.17773 -189.259972)
		(end 207.361536 -189.068202)
		(width 0.14224)
		(layer "In4.Cu")
		(net "GMI_CPU1_G2_CPU0_G0_TX_DN<14>")
	)
	(segment
		(start 318.311276 -195.67652)
		(end 345.964256 -218.349576)
		(width 0.14224)
		(layer "In4.Cu")
		(net "GMI_CPU1_G2_CPU0_G0_TX_DN<14>")
	)
	(segment
		(start 236.278928 -199.451214)
		(end 239.476026 -198.887334)
		(width 0.14224)
		(layer "In4.Cu")
		(net "GMI_CPU1_G2_CPU0_G0_TX_DN<14>")
	)
	(segment
		(start 124.68352 -223.93021)
		(end 124.612654 -223.889062)
		(width 0.1143)
		(layer "In4.Cu")
		(net "GMI_CPU1_G2_CPU0_G0_TX_DN<14>")
	)
	(segment
		(start 125.6538 -218.224862)
		(end 146.36623 -201.242168)
		(width 0.14224)
		(layer "In4.Cu")
		(net "GMI_CPU1_G2_CPU0_G0_TX_DN<14>")
	)
	(segment
		(start 149.731984 -199.627236)
		(end 149.73173 -199.627236)
		(width 0.14224)
		(layer "In4.Cu")
		(net "GMI_CPU1_G2_CPU0_G0_TX_DN<14>")
	)
	(segment
		(start 124.852176 -227.496624)
		(end 124.852176 -227.484178)
		(width 0.1143)
		(layer "In4.Cu")
		(net "GMI_CPU1_G2_CPU0_G0_TX_DN<14>")
	)
	(arc
		(start 347.126306 -221.80423)
		(mid 347.061859 -222.066382)
		(end 346.883228 -222.268796)
		(width 0.1143)
		(layer "In4.Cu")
		(net "GMI_CPU1_G2_CPU0_G0_TX_DN<14>")
	)
	(arc
		(start 346.812362 -222.309944)
		(mid 346.660773 -222.614236)
		(end 346.812362 -222.918528)
		(width 0.1143)
		(layer "In4.Cu")
		(net "GMI_CPU1_G2_CPU0_G0_TX_DN<14>")
	)
	(arc
		(start 346.643706 -227.49637)
		(mid 346.57212 -227.7641)
		(end 346.376498 -227.960428)
		(width 0.1143)
		(layer "In4.Cu")
		(net "GMI_CPU1_G2_CPU0_G0_TX_DN<14>")
	)
	(arc
		(start 124.703332 -224.52457)
		(mid 124.852046 -224.234502)
		(end 124.703332 -223.944434)
		(width 0.1143)
		(layer "In4.Cu")
		(net "GMI_CPU1_G2_CPU0_G0_TX_DN<14>")
	)
	(arc
		(start 124.68352 -222.918782)
		(mid 124.835109 -222.61449)
		(end 124.68352 -222.310198)
		(width 0.1143)
		(layer "In4.Cu")
		(net "GMI_CPU1_G2_CPU0_G0_TX_DN<14>")
	)
	(arc
		(start 124.612654 -227.129086)
		(mid 124.369327 -226.66452)
		(end 124.612654 -226.199954)
		(width 0.1143)
		(layer "In4.Cu")
		(net "GMI_CPU1_G2_CPU0_G0_TX_DN<14>")
	)
	(arc
		(start 346.883228 -224.579688)
		(mid 347.126555 -225.044254)
		(end 346.883228 -225.50882)
		(width 0.1143)
		(layer "In4.Cu")
		(net "GMI_CPU1_G2_CPU0_G0_TX_DN<14>")
	)
	(arc
		(start 124.68352 -226.158806)
		(mid 124.835109 -225.854514)
		(end 124.68352 -225.550222)
		(width 0.1143)
		(layer "In4.Cu")
		(net "GMI_CPU1_G2_CPU0_G0_TX_DN<14>")
	)
	(arc
		(start 346.812362 -225.549968)
		(mid 346.660773 -225.85426)
		(end 346.812362 -226.158552)
		(width 0.1143)
		(layer "In4.Cu")
		(net "GMI_CPU1_G2_CPU0_G0_TX_DN<14>")
	)
	(arc
		(start 124.612654 -223.889062)
		(mid 124.369327 -223.424496)
		(end 124.612654 -222.95993)
		(width 0.1143)
		(layer "In4.Cu")
		(net "GMI_CPU1_G2_CPU0_G0_TX_DN<14>")
	)
	(arc
		(start 124.612654 -225.509074)
		(mid 124.369327 -225.044508)
		(end 124.612654 -224.579942)
		(width 0.1143)
		(layer "In4.Cu")
		(net "GMI_CPU1_G2_CPU0_G0_TX_DN<14>")
	)
	(arc
		(start 346.342462 -227.979986)
		(mid 346.245327 -228.082855)
		(end 346.193364 -228.214428)
		(width 0.1143)
		(layer "In4.Cu")
		(net "GMI_CPU1_G2_CPU0_G0_TX_DN<14>")
	)
	(arc
		(start 346.883228 -226.1997)
		(mid 347.126555 -226.664266)
		(end 346.883228 -227.128832)
		(width 0.1143)
		(layer "In4.Cu")
		(net "GMI_CPU1_G2_CPU0_G0_TX_DN<14>")
	)
	(arc
		(start 125.302518 -228.214682)
		(mid 125.250469 -228.083163)
		(end 125.15342 -227.98024)
		(width 0.1143)
		(layer "In4.Cu")
		(net "GMI_CPU1_G2_CPU0_G0_TX_DN<14>")
	)
	(arc
		(start 346.79255 -223.94418)
		(mid 346.643836 -224.234248)
		(end 346.79255 -224.524316)
		(width 0.1143)
		(layer "In4.Cu")
		(net "GMI_CPU1_G2_CPU0_G0_TX_DN<14>")
	)
	(arc
		(start 124.852176 -227.484178)
		(mid 124.80187 -227.29659)
		(end 124.66447 -227.159312)
		(width 0.1143)
		(layer "In4.Cu")
		(net "GMI_CPU1_G2_CPU0_G0_TX_DN<14>")
	)
	(arc
		(start 346.883228 -222.959676)
		(mid 347.126555 -223.424242)
		(end 346.883228 -223.888808)
		(width 0.1143)
		(layer "In4.Cu")
		(net "GMI_CPU1_G2_CPU0_G0_TX_DN<14>")
	)
	(arc
		(start 346.831412 -227.159058)
		(mid 346.69398 -227.296317)
		(end 346.643706 -227.483924)
		(width 0.1143)
		(layer "In4.Cu")
		(net "GMI_CPU1_G2_CPU0_G0_TX_DN<14>")
	)
	(arc
		(start 125.119384 -227.960682)
		(mid 124.92371 -227.764384)
		(end 124.852176 -227.496624)
		(width 0.1143)
		(layer "In4.Cu")
		(net "GMI_CPU1_G2_CPU0_G0_TX_DN<14>")
	)
	(arc
		(start 124.612654 -222.26905)
		(mid 124.433996 -222.06665)
		(end 124.369576 -221.804484)
		(width 0.1143)
		(layer "In4.Cu")
		(net "GMI_CPU1_G2_CPU0_G0_TX_DN<14>")
	)
	(segment
		(start 124.467874 -226.930458)
		(end 124.934726 -226.66452)
		(width 0.12954)
		(layer "F.Cu")
		(net "GMI_CPU1_G2_CPU0_G0_TX_DN<13>")
	)
	(segment
		(start 347.028008 -226.930204)
		(end 346.561156 -226.664266)
		(width 0.12954)
		(layer "F.Cu")
		(net "GMI_CPU1_G2_CPU0_G0_TX_DN<13>")
	)
	(segment
		(start 346.18041 -226.581462)
		(end 346.263214 -226.664266)
		(width 0.1143)
		(layer "In4.Cu")
		(net "GMI_CPU1_G2_CPU0_G0_TX_DN<13>")
	)
	(segment
		(start 345.343226 -219.135452)
		(end 346.232226 -220.631258)
		(width 0.14224)
		(layer "In4.Cu")
		(net "GMI_CPU1_G2_CPU0_G0_TX_DN<13>")
	)
	(segment
		(start 251.312934 -191.746886)
		(end 262.742426 -189.73165)
		(width 0.14224)
		(layer "In4.Cu")
		(net "GMI_CPU1_G2_CPU0_G0_TX_DN<13>")
	)
	(segment
		(start 162.52952 -190.198502)
		(end 207.281272 -190.009018)
		(width 0.14224)
		(layer "In4.Cu")
		(net "GMI_CPU1_G2_CPU0_G0_TX_DN<13>")
	)
	(segment
		(start 125.263656 -221.174564)
		(end 125.263656 -220.815408)
		(width 0.14224)
		(layer "In4.Cu")
		(net "GMI_CPU1_G2_CPU0_G0_TX_DN<13>")
	)
	(segment
		(start 345.873578 -222.919036)
		(end 345.943174 -222.959676)
		(width 0.1143)
		(layer "In4.Cu")
		(net "GMI_CPU1_G2_CPU0_G0_TX_DN<13>")
	)
	(segment
		(start 125.309376 -221.248732)
		(end 125.263656 -221.203012)
		(width 0.1143)
		(layer "In4.Cu")
		(net "GMI_CPU1_G2_CPU0_G0_TX_DN<13>")
	)
	(segment
		(start 149.344634 -201.33691)
		(end 153.970228 -197.544944)
		(width 0.14224)
		(layer "In4.Cu")
		(net "GMI_CPU1_G2_CPU0_G0_TX_DN<13>")
	)
	(segment
		(start 345.943174 -223.888808)
		(end 345.873578 -223.929448)
		(width 0.1143)
		(layer "In4.Cu")
		(net "GMI_CPU1_G2_CPU0_G0_TX_DN<13>")
	)
	(segment
		(start 317.269622 -196.116956)
		(end 345.343226 -219.135452)
		(width 0.14224)
		(layer "In4.Cu")
		(net "GMI_CPU1_G2_CPU0_G0_TX_DN<13>")
	)
	(segment
		(start 308.735476 -190.109856)
		(end 317.269622 -196.116956)
		(width 0.14224)
		(layer "In4.Cu")
		(net "GMI_CPU1_G2_CPU0_G0_TX_DN<13>")
	)
	(segment
		(start 262.742426 -189.73165)
		(end 303.734724 -190.109856)
		(width 0.14224)
		(layer "In4.Cu")
		(net "GMI_CPU1_G2_CPU0_G0_TX_DN<13>")
	)
	(segment
		(start 239.845088 -199.777096)
		(end 251.312934 -191.746886)
		(width 0.14224)
		(layer "In4.Cu")
		(net "GMI_CPU1_G2_CPU0_G0_TX_DN<13>")
	)
	(segment
		(start 126.350014 -218.896692)
		(end 146.839178 -202.09637)
		(width 0.14224)
		(layer "In4.Cu")
		(net "GMI_CPU1_G2_CPU0_G0_TX_DN<13>")
	)
	(segment
		(start 346.186252 -221.624906)
		(end 346.186252 -221.80423)
		(width 0.1143)
		(layer "In4.Cu")
		(net "GMI_CPU1_G2_CPU0_G0_TX_DN<13>")
	)
	(segment
		(start 125.552708 -224.579942)
		(end 125.591824 -224.557082)
		(width 0.1143)
		(layer "In4.Cu")
		(net "GMI_CPU1_G2_CPU0_G0_TX_DN<13>")
	)
	(segment
		(start 125.591824 -224.557082)
		(end 125.622304 -224.539302)
		(width 0.1143)
		(layer "In4.Cu")
		(net "GMI_CPU1_G2_CPU0_G0_TX_DN<13>")
	)
	(segment
		(start 125.591824 -222.93707)
		(end 125.622304 -222.91929)
		(width 0.1143)
		(layer "In4.Cu")
		(net "GMI_CPU1_G2_CPU0_G0_TX_DN<13>")
	)
	(segment
		(start 125.30963 -221.804484)
		(end 125.30963 -221.62516)
		(width 0.1143)
		(layer "In4.Cu")
		(net "GMI_CPU1_G2_CPU0_G0_TX_DN<13>")
	)
	(segment
		(start 153.969974 -197.544944)
		(end 161.155634 -191.653922)
		(width 0.14224)
		(layer "In4.Cu")
		(net "GMI_CPU1_G2_CPU0_G0_TX_DN<13>")
	)
	(segment
		(start 345.873578 -224.539048)
		(end 345.943174 -224.579688)
		(width 0.1143)
		(layer "In4.Cu")
		(net "GMI_CPU1_G2_CPU0_G0_TX_DN<13>")
	)
	(segment
		(start 346.232226 -221.17431)
		(end 346.232226 -221.202758)
		(width 0.1143)
		(layer "In4.Cu")
		(net "GMI_CPU1_G2_CPU0_G0_TX_DN<13>")
	)
	(segment
		(start 345.943174 -225.50882)
		(end 345.873578 -225.54946)
		(width 0.1143)
		(layer "In4.Cu")
		(net "GMI_CPU1_G2_CPU0_G0_TX_DN<13>")
	)
	(segment
		(start 161.468816 -191.068706)
		(end 162.52952 -190.198502)
		(width 0.14224)
		(layer "In4.Cu")
		(net "GMI_CPU1_G2_CPU0_G0_TX_DN<13>")
	)
	(segment
		(start 236.278928 -200.406)
		(end 239.84204 -199.77735)
		(width 0.14224)
		(layer "In4.Cu")
		(net "GMI_CPU1_G2_CPU0_G0_TX_DN<13>")
	)
	(segment
		(start 345.873578 -226.15906)
		(end 345.943174 -226.1997)
		(width 0.1143)
		(layer "In4.Cu")
		(net "GMI_CPU1_G2_CPU0_G0_TX_DN<13>")
	)
	(segment
		(start 125.30963 -221.62516)
		(end 125.309376 -221.624906)
		(width 0.1143)
		(layer "In4.Cu")
		(net "GMI_CPU1_G2_CPU0_G0_TX_DN<13>")
	)
	(segment
		(start 146.839178 -202.09637)
		(end 149.344634 -201.33691)
		(width 0.14224)
		(layer "In4.Cu")
		(net "GMI_CPU1_G2_CPU0_G0_TX_DN<13>")
	)
	(segment
		(start 346.232226 -220.631258)
		(end 346.232226 -221.17431)
		(width 0.14224)
		(layer "In4.Cu")
		(net "GMI_CPU1_G2_CPU0_G0_TX_DN<13>")
	)
	(segment
		(start 345.943174 -222.268796)
		(end 345.873578 -222.309436)
		(width 0.1143)
		(layer "In4.Cu")
		(net "GMI_CPU1_G2_CPU0_G0_TX_DN<13>")
	)
	(segment
		(start 124.934726 -226.66452)
		(end 125.232668 -226.66452)
		(width 0.1143)
		(layer "In4.Cu")
		(net "GMI_CPU1_G2_CPU0_G0_TX_DN<13>")
	)
	(segment
		(start 346.186506 -221.248478)
		(end 346.186506 -221.624652)
		(width 0.1143)
		(layer "In4.Cu")
		(net "GMI_CPU1_G2_CPU0_G0_TX_DN<13>")
	)
	(segment
		(start 239.84204 -199.77735)
		(end 239.844834 -199.777096)
		(width 0.14224)
		(layer "In4.Cu")
		(net "GMI_CPU1_G2_CPU0_G0_TX_DN<13>")
	)
	(segment
		(start 346.232226 -221.202758)
		(end 346.186506 -221.248478)
		(width 0.1143)
		(layer "In4.Cu")
		(net "GMI_CPU1_G2_CPU0_G0_TX_DN<13>")
	)
	(segment
		(start 125.591824 -225.531934)
		(end 125.552708 -225.509074)
		(width 0.1143)
		(layer "In4.Cu")
		(net "GMI_CPU1_G2_CPU0_G0_TX_DN<13>")
	)
	(segment
		(start 161.155634 -191.653922)
		(end 161.468816 -191.068706)
		(width 0.14224)
		(layer "In4.Cu")
		(net "GMI_CPU1_G2_CPU0_G0_TX_DN<13>")
	)
	(segment
		(start 207.281272 -190.009018)
		(end 210.87334 -190.643002)
		(width 0.14224)
		(layer "In4.Cu")
		(net "GMI_CPU1_G2_CPU0_G0_TX_DN<13>")
	)
	(segment
		(start 303.734724 -190.109856)
		(end 308.735476 -190.109856)
		(width 0.14224)
		(layer "In4.Cu")
		(net "GMI_CPU1_G2_CPU0_G0_TX_DN<13>")
	)
	(segment
		(start 125.263656 -220.815408)
		(end 126.350014 -218.896692)
		(width 0.14224)
		(layer "In4.Cu")
		(net "GMI_CPU1_G2_CPU0_G0_TX_DN<13>")
	)
	(segment
		(start 125.591824 -226.177094)
		(end 125.622304 -226.159314)
		(width 0.1143)
		(layer "In4.Cu")
		(net "GMI_CPU1_G2_CPU0_G0_TX_DN<13>")
	)
	(segment
		(start 346.263214 -226.664266)
		(end 346.561156 -226.664266)
		(width 0.1143)
		(layer "In4.Cu")
		(net "GMI_CPU1_G2_CPU0_G0_TX_DN<13>")
	)
	(segment
		(start 210.87334 -190.643002)
		(end 233.086148 -199.843136)
		(width 0.14224)
		(layer "In4.Cu")
		(net "GMI_CPU1_G2_CPU0_G0_TX_DN<13>")
	)
	(segment
		(start 239.844834 -199.777096)
		(end 239.845088 -199.777096)
		(width 0.14224)
		(layer "In4.Cu")
		(net "GMI_CPU1_G2_CPU0_G0_TX_DN<13>")
	)
	(segment
		(start 233.086148 -199.843136)
		(end 236.278928 -200.406)
		(width 0.14224)
		(layer "In4.Cu")
		(net "GMI_CPU1_G2_CPU0_G0_TX_DN<13>")
	)
	(segment
		(start 125.232668 -226.66452)
		(end 125.315472 -226.581716)
		(width 0.1143)
		(layer "In4.Cu")
		(net "GMI_CPU1_G2_CPU0_G0_TX_DN<13>")
	)
	(segment
		(start 125.622304 -222.30969)
		(end 125.552708 -222.26905)
		(width 0.1143)
		(layer "In4.Cu")
		(net "GMI_CPU1_G2_CPU0_G0_TX_DN<13>")
	)
	(segment
		(start 125.263656 -221.203012)
		(end 125.263656 -221.174564)
		(width 0.1143)
		(layer "In4.Cu")
		(net "GMI_CPU1_G2_CPU0_G0_TX_DN<13>")
	)
	(segment
		(start 125.309376 -221.624906)
		(end 125.309376 -221.248732)
		(width 0.1143)
		(layer "In4.Cu")
		(net "GMI_CPU1_G2_CPU0_G0_TX_DN<13>")
	)
	(segment
		(start 125.552708 -222.95993)
		(end 125.591824 -222.93707)
		(width 0.1143)
		(layer "In4.Cu")
		(net "GMI_CPU1_G2_CPU0_G0_TX_DN<13>")
	)
	(segment
		(start 125.591824 -223.911922)
		(end 125.552708 -223.889062)
		(width 0.1143)
		(layer "In4.Cu")
		(net "GMI_CPU1_G2_CPU0_G0_TX_DN<13>")
	)
	(segment
		(start 125.552708 -226.199954)
		(end 125.591824 -226.177094)
		(width 0.1143)
		(layer "In4.Cu")
		(net "GMI_CPU1_G2_CPU0_G0_TX_DN<13>")
	)
	(segment
		(start 125.622304 -223.929702)
		(end 125.591824 -223.911922)
		(width 0.1143)
		(layer "In4.Cu")
		(net "GMI_CPU1_G2_CPU0_G0_TX_DN<13>")
	)
	(segment
		(start 346.186506 -221.624652)
		(end 346.186252 -221.624906)
		(width 0.1143)
		(layer "In4.Cu")
		(net "GMI_CPU1_G2_CPU0_G0_TX_DN<13>")
	)
	(segment
		(start 125.622304 -225.549714)
		(end 125.591824 -225.531934)
		(width 0.1143)
		(layer "In4.Cu")
		(net "GMI_CPU1_G2_CPU0_G0_TX_DN<13>")
	)
	(segment
		(start 153.970228 -197.544944)
		(end 153.969974 -197.544944)
		(width 0.14224)
		(layer "In4.Cu")
		(net "GMI_CPU1_G2_CPU0_G0_TX_DN<13>")
	)
	(arc
		(start 125.315472 -226.581716)
		(mid 125.31726 -226.570267)
		(end 125.319282 -226.558856)
		(width 0.1143)
		(layer "In4.Cu")
		(net "GMI_CPU1_G2_CPU0_G0_TX_DN<13>")
	)
	(arc
		(start 125.622304 -222.91929)
		(mid 125.779281 -222.61449)
		(end 125.622304 -222.30969)
		(width 0.1143)
		(layer "In4.Cu")
		(net "GMI_CPU1_G2_CPU0_G0_TX_DN<13>")
	)
	(arc
		(start 125.622304 -226.159314)
		(mid 125.779281 -225.854514)
		(end 125.622304 -225.549714)
		(width 0.1143)
		(layer "In4.Cu")
		(net "GMI_CPU1_G2_CPU0_G0_TX_DN<13>")
	)
	(arc
		(start 345.873578 -225.54946)
		(mid 345.716601 -225.85426)
		(end 345.873578 -226.15906)
		(width 0.1143)
		(layer "In4.Cu")
		(net "GMI_CPU1_G2_CPU0_G0_TX_DN<13>")
	)
	(arc
		(start 345.943174 -224.579688)
		(mid 346.186501 -225.044254)
		(end 345.943174 -225.50882)
		(width 0.1143)
		(layer "In4.Cu")
		(net "GMI_CPU1_G2_CPU0_G0_TX_DN<13>")
	)
	(arc
		(start 125.552708 -225.509074)
		(mid 125.309381 -225.044508)
		(end 125.552708 -224.579942)
		(width 0.1143)
		(layer "In4.Cu")
		(net "GMI_CPU1_G2_CPU0_G0_TX_DN<13>")
	)
	(arc
		(start 125.552708 -222.26905)
		(mid 125.374065 -222.066655)
		(end 125.30963 -221.804484)
		(width 0.1143)
		(layer "In4.Cu")
		(net "GMI_CPU1_G2_CPU0_G0_TX_DN<13>")
	)
	(arc
		(start 125.319282 -226.558856)
		(mid 125.400715 -226.356458)
		(end 125.552708 -226.199954)
		(width 0.1143)
		(layer "In4.Cu")
		(net "GMI_CPU1_G2_CPU0_G0_TX_DN<13>")
	)
	(arc
		(start 345.873578 -223.929448)
		(mid 345.716601 -224.234248)
		(end 345.873578 -224.539048)
		(width 0.1143)
		(layer "In4.Cu")
		(net "GMI_CPU1_G2_CPU0_G0_TX_DN<13>")
	)
	(arc
		(start 125.552708 -223.889062)
		(mid 125.309381 -223.424496)
		(end 125.552708 -222.95993)
		(width 0.1143)
		(layer "In4.Cu")
		(net "GMI_CPU1_G2_CPU0_G0_TX_DN<13>")
	)
	(arc
		(start 345.943174 -222.959676)
		(mid 346.186501 -223.424242)
		(end 345.943174 -223.888808)
		(width 0.1143)
		(layer "In4.Cu")
		(net "GMI_CPU1_G2_CPU0_G0_TX_DN<13>")
	)
	(arc
		(start 346.186252 -221.80423)
		(mid 346.121878 -222.066434)
		(end 345.943174 -222.268796)
		(width 0.1143)
		(layer "In4.Cu")
		(net "GMI_CPU1_G2_CPU0_G0_TX_DN<13>")
	)
	(arc
		(start 345.873578 -222.309436)
		(mid 345.716601 -222.614236)
		(end 345.873578 -222.919036)
		(width 0.1143)
		(layer "In4.Cu")
		(net "GMI_CPU1_G2_CPU0_G0_TX_DN<13>")
	)
	(arc
		(start 346.1766 -226.558602)
		(mid 346.178623 -226.570012)
		(end 346.18041 -226.581462)
		(width 0.1143)
		(layer "In4.Cu")
		(net "GMI_CPU1_G2_CPU0_G0_TX_DN<13>")
	)
	(arc
		(start 345.943174 -226.1997)
		(mid 346.095161 -226.356208)
		(end 346.1766 -226.558602)
		(width 0.1143)
		(layer "In4.Cu")
		(net "GMI_CPU1_G2_CPU0_G0_TX_DN<13>")
	)
	(arc
		(start 125.622304 -224.539302)
		(mid 125.779281 -224.234502)
		(end 125.622304 -223.929702)
		(width 0.1143)
		(layer "In4.Cu")
		(net "GMI_CPU1_G2_CPU0_G0_TX_DN<13>")
	)
	(segment
		(start 347.028008 -230.169974)
		(end 346.561156 -229.904036)
		(width 0.12954)
		(layer "F.Cu")
		(net "GMI_CPU1_G2_CPU0_G0_TX_DN<12>")
	)
	(segment
		(start 124.467874 -230.170228)
		(end 124.934726 -229.90429)
		(width 0.12954)
		(layer "F.Cu")
		(net "GMI_CPU1_G2_CPU0_G0_TX_DN<12>")
	)
	(segment
		(start 123.429268 -221.248732)
		(end 123.383548 -221.203012)
		(width 0.1143)
		(layer "In4.Cu")
		(net "GMI_CPU1_G2_CPU0_G0_TX_DN<12>")
	)
	(segment
		(start 123.712478 -227.152454)
		(end 123.711716 -227.151946)
		(width 0.1143)
		(layer "In4.Cu")
		(net "GMI_CPU1_G2_CPU0_G0_TX_DN<12>")
	)
	(segment
		(start 347.752416 -224.53854)
		(end 347.782134 -224.555558)
		(width 0.1143)
		(layer "In4.Cu")
		(net "GMI_CPU1_G2_CPU0_G0_TX_DN<12>")
	)
	(segment
		(start 347.783404 -225.532188)
		(end 347.752416 -225.549968)
		(width 0.1143)
		(layer "In4.Cu")
		(net "GMI_CPU1_G2_CPU0_G0_TX_DN<12>")
	)
	(segment
		(start 347.783404 -223.912176)
		(end 347.752416 -223.929956)
		(width 0.1143)
		(layer "In4.Cu")
		(net "GMI_CPU1_G2_CPU0_G0_TX_DN<12>")
	)
	(segment
		(start 347.784166 -224.556828)
		(end 347.785182 -224.557336)
		(width 0.1143)
		(layer "In4.Cu")
		(net "GMI_CPU1_G2_CPU0_G0_TX_DN<12>")
	)
	(segment
		(start 239.107726 -197.99808)
		(end 250.57608 -189.96787)
		(width 0.14224)
		(layer "In4.Cu")
		(net "GMI_CPU1_G2_CPU0_G0_TX_DN<12>")
	)
	(segment
		(start 123.709176 -225.53041)
		(end 123.6726 -225.509074)
		(width 0.1143)
		(layer "In4.Cu")
		(net "GMI_CPU1_G2_CPU0_G0_TX_DN<12>")
	)
	(segment
		(start 159.58185 -190.159132)
		(end 159.582104 -190.158624)
		(width 0.14224)
		(layer "In4.Cu")
		(net "GMI_CPU1_G2_CPU0_G0_TX_DN<12>")
	)
	(segment
		(start 347.757496 -227.167186)
		(end 347.754194 -227.169218)
		(width 0.1143)
		(layer "In4.Cu")
		(net "GMI_CPU1_G2_CPU0_G0_TX_DN<12>")
	)
	(segment
		(start 123.709176 -222.290386)
		(end 123.70816 -222.289878)
		(width 0.1143)
		(layer "In4.Cu")
		(net "GMI_CPU1_G2_CPU0_G0_TX_DN<12>")
	)
	(segment
		(start 123.383548 -221.174564)
		(end 123.383548 -220.29293)
		(width 0.14224)
		(layer "In4.Cu")
		(net "GMI_CPU1_G2_CPU0_G0_TX_DN<12>")
	)
	(segment
		(start 347.786706 -223.910144)
		(end 347.785182 -223.91116)
		(width 0.1143)
		(layer "In4.Cu")
		(net "GMI_CPU1_G2_CPU0_G0_TX_DN<12>")
	)
	(segment
		(start 159.582104 -190.158624)
		(end 161.851086 -188.298328)
		(width 0.14224)
		(layer "In4.Cu")
		(net "GMI_CPU1_G2_CPU0_G0_TX_DN<12>")
	)
	(segment
		(start 123.6726 -224.579942)
		(end 123.7107 -224.55759)
		(width 0.1143)
		(layer "In4.Cu")
		(net "GMI_CPU1_G2_CPU0_G0_TX_DN<12>")
	)
	(segment
		(start 347.783404 -224.55632)
		(end 347.784166 -224.556828)
		(width 0.1143)
		(layer "In4.Cu")
		(net "GMI_CPU1_G2_CPU0_G0_TX_DN<12>")
	)
	(segment
		(start 123.711716 -226.177094)
		(end 123.712478 -226.176586)
		(width 0.1143)
		(layer "In4.Cu")
		(net "GMI_CPU1_G2_CPU0_G0_TX_DN<12>")
	)
	(segment
		(start 123.675394 -222.957898)
		(end 123.711716 -222.93707)
		(width 0.1143)
		(layer "In4.Cu")
		(net "GMI_CPU1_G2_CPU0_G0_TX_DN<12>")
	)
	(segment
		(start 125.155198 -229.601522)
		(end 125.12167 -229.581964)
		(width 0.1143)
		(layer "In4.Cu")
		(net "GMI_CPU1_G2_CPU0_G0_TX_DN<12>")
	)
	(segment
		(start 347.786706 -225.530156)
		(end 347.785182 -225.531172)
		(width 0.1143)
		(layer "In4.Cu")
		(net "GMI_CPU1_G2_CPU0_G0_TX_DN<12>")
	)
	(segment
		(start 347.12656 -228.283516)
		(end 347.12656 -228.284024)
		(width 0.1143)
		(layer "In4.Cu")
		(net "GMI_CPU1_G2_CPU0_G0_TX_DN<12>")
	)
	(segment
		(start 124.369322 -228.284278)
		(end 124.369322 -228.28377)
		(width 0.1143)
		(layer "In4.Cu")
		(net "GMI_CPU1_G2_CPU0_G0_TX_DN<12>")
	)
	(segment
		(start 347.823282 -227.128832)
		(end 347.786706 -227.150168)
		(width 0.1143)
		(layer "In4.Cu")
		(net "GMI_CPU1_G2_CPU0_G0_TX_DN<12>")
	)
	(segment
		(start 123.711716 -224.557082)
		(end 123.712478 -224.556574)
		(width 0.1143)
		(layer "In4.Cu")
		(net "GMI_CPU1_G2_CPU0_G0_TX_DN<12>")
	)
	(segment
		(start 161.851086 -188.298328)
		(end 207.36433 -188.114432)
		(width 0.14224)
		(layer "In4.Cu")
		(net "GMI_CPU1_G2_CPU0_G0_TX_DN<12>")
	)
	(segment
		(start 239.107218 -197.99808)
		(end 239.107726 -197.99808)
		(width 0.14224)
		(layer "In4.Cu")
		(net "GMI_CPU1_G2_CPU0_G0_TX_DN<12>")
	)
	(segment
		(start 123.7107 -225.531426)
		(end 123.709176 -225.53041)
		(width 0.1143)
		(layer "In4.Cu")
		(net "GMI_CPU1_G2_CPU0_G0_TX_DN<12>")
	)
	(segment
		(start 123.711716 -222.93707)
		(end 123.712478 -222.936562)
		(width 0.1143)
		(layer "In4.Cu")
		(net "GMI_CPU1_G2_CPU0_G0_TX_DN<12>")
	)
	(segment
		(start 347.786706 -226.178364)
		(end 347.787722 -226.178872)
		(width 0.1143)
		(layer "In4.Cu")
		(net "GMI_CPU1_G2_CPU0_G0_TX_DN<12>")
	)
	(segment
		(start 347.785182 -223.91116)
		(end 347.784166 -223.911668)
		(width 0.1143)
		(layer "In4.Cu")
		(net "GMI_CPU1_G2_CPU0_G0_TX_DN<12>")
	)
	(segment
		(start 125.232668 -229.90429)
		(end 125.302518 -229.83444)
		(width 0.1143)
		(layer "In4.Cu")
		(net "GMI_CPU1_G2_CPU0_G0_TX_DN<12>")
	)
	(segment
		(start 124.934726 -229.90429)
		(end 125.232668 -229.90429)
		(width 0.1143)
		(layer "In4.Cu")
		(net "GMI_CPU1_G2_CPU0_G0_TX_DN<12>")
	)
	(segment
		(start 348.06636 -221.624906)
		(end 348.06636 -221.80423)
		(width 0.1143)
		(layer "In4.Cu")
		(net "GMI_CPU1_G2_CPU0_G0_TX_DN<12>")
	)
	(segment
		(start 123.742704 -227.16998)
		(end 123.741688 -227.169472)
		(width 0.1143)
		(layer "In4.Cu")
		(net "GMI_CPU1_G2_CPU0_G0_TX_DN<12>")
	)
	(segment
		(start 124.653294 -228.772974)
		(end 124.652024 -228.773228)
		(width 0.1143)
		(layer "In4.Cu")
		(net "GMI_CPU1_G2_CPU0_G0_TX_DN<12>")
	)
	(segment
		(start 347.786706 -224.558352)
		(end 347.787722 -224.55886)
		(width 0.1143)
		(layer "In4.Cu")
		(net "GMI_CPU1_G2_CPU0_G0_TX_DN<12>")
	)
	(segment
		(start 123.713748 -224.555812)
		(end 123.743466 -224.538794)
		(width 0.1143)
		(layer "In4.Cu")
		(net "GMI_CPU1_G2_CPU0_G0_TX_DN<12>")
	)
	(segment
		(start 347.30182 -227.981256)
		(end 347.301312 -227.98151)
		(width 0.1143)
		(layer "In4.Cu")
		(net "GMI_CPU1_G2_CPU0_G0_TX_DN<12>")
	)
	(segment
		(start 123.7107 -226.177602)
		(end 123.711716 -226.177094)
		(width 0.1143)
		(layer "In4.Cu")
		(net "GMI_CPU1_G2_CPU0_G0_TX_DN<12>")
	)
	(segment
		(start 347.820488 -222.957644)
		(end 347.823282 -222.959676)
		(width 0.1143)
		(layer "In4.Cu")
		(net "GMI_CPU1_G2_CPU0_G0_TX_DN<12>")
	)
	(segment
		(start 346.843858 -228.772974)
		(end 346.842588 -228.77272)
		(width 0.1143)
		(layer "In4.Cu")
		(net "GMI_CPU1_G2_CPU0_G0_TX_DN<12>")
	)
	(segment
		(start 123.429268 -221.624906)
		(end 123.429268 -221.248732)
		(width 0.1143)
		(layer "In4.Cu")
		(net "GMI_CPU1_G2_CPU0_G0_TX_DN<12>")
	)
	(segment
		(start 150.22068 -197.834758)
		(end 159.58185 -190.159132)
		(width 0.14224)
		(layer "In4.Cu")
		(net "GMI_CPU1_G2_CPU0_G0_TX_DN<12>")
	)
	(segment
		(start 147.870418 -199.76211)
		(end 150.220934 -197.834758)
		(width 0.14224)
		(layer "In4.Cu")
		(net "GMI_CPU1_G2_CPU0_G0_TX_DN<12>")
	)
	(segment
		(start 303.706784 -188.190886)
		(end 309.42026 -188.190886)
		(width 0.14224)
		(layer "In4.Cu")
		(net "GMI_CPU1_G2_CPU0_G0_TX_DN<12>")
	)
	(segment
		(start 318.819784 -194.815714)
		(end 318.94907 -194.944746)
		(width 0.14224)
		(layer "In4.Cu")
		(net "GMI_CPU1_G2_CPU0_G0_TX_DN<12>")
	)
	(segment
		(start 347.823282 -225.50882)
		(end 347.786706 -225.530156)
		(width 0.1143)
		(layer "In4.Cu")
		(net "GMI_CPU1_G2_CPU0_G0_TX_DN<12>")
	)
	(segment
		(start 123.713748 -222.9358)
		(end 123.743466 -222.918782)
		(width 0.1143)
		(layer "In4.Cu")
		(net "GMI_CPU1_G2_CPU0_G0_TX_DN<12>")
	)
	(segment
		(start 318.94907 -194.944746)
		(end 346.631768 -217.643456)
		(width 0.14224)
		(layer "In4.Cu")
		(net "GMI_CPU1_G2_CPU0_G0_TX_DN<12>")
	)
	(segment
		(start 123.712478 -226.176586)
		(end 123.713748 -226.175824)
		(width 0.1143)
		(layer "In4.Cu")
		(net "GMI_CPU1_G2_CPU0_G0_TX_DN<12>")
	)
	(segment
		(start 347.752416 -226.158552)
		(end 347.782134 -226.17557)
		(width 0.1143)
		(layer "In4.Cu")
		(net "GMI_CPU1_G2_CPU0_G0_TX_DN<12>")
	)
	(segment
		(start 347.787722 -226.178872)
		(end 347.823282 -226.1997)
		(width 0.1143)
		(layer "In4.Cu")
		(net "GMI_CPU1_G2_CPU0_G0_TX_DN<12>")
	)
	(segment
		(start 123.743466 -225.550222)
		(end 123.712478 -225.532442)
		(width 0.1143)
		(layer "In4.Cu")
		(net "GMI_CPU1_G2_CPU0_G0_TX_DN<12>")
	)
	(segment
		(start 123.6726 -222.95993)
		(end 123.675394 -222.957898)
		(width 0.1143)
		(layer "In4.Cu")
		(net "GMI_CPU1_G2_CPU0_G0_TX_DN<12>")
	)
	(segment
		(start 347.823282 -223.888808)
		(end 347.786706 -223.910144)
		(width 0.1143)
		(layer "In4.Cu")
		(net "GMI_CPU1_G2_CPU0_G0_TX_DN<12>")
	)
	(segment
		(start 347.752416 -222.918528)
		(end 347.782134 -222.935546)
		(width 0.1143)
		(layer "In4.Cu")
		(net "GMI_CPU1_G2_CPU0_G0_TX_DN<12>")
	)
	(segment
		(start 124.19457 -227.981764)
		(end 124.194062 -227.98151)
		(width 0.1143)
		(layer "In4.Cu")
		(net "GMI_CPU1_G2_CPU0_G0_TX_DN<12>")
	)
	(segment
		(start 123.743466 -223.93021)
		(end 123.712478 -223.91243)
		(width 0.1143)
		(layer "In4.Cu")
		(net "GMI_CPU1_G2_CPU0_G0_TX_DN<12>")
	)
	(segment
		(start 347.785182 -227.151184)
		(end 347.784166 -227.151692)
		(width 0.1143)
		(layer "In4.Cu")
		(net "GMI_CPU1_G2_CPU0_G0_TX_DN<12>")
	)
	(segment
		(start 347.783404 -222.936308)
		(end 347.784166 -222.936816)
		(width 0.1143)
		(layer "In4.Cu")
		(net "GMI_CPU1_G2_CPU0_G0_TX_DN<12>")
	)
	(segment
		(start 347.787722 -224.55886)
		(end 347.823282 -224.579688)
		(width 0.1143)
		(layer "In4.Cu")
		(net "GMI_CPU1_G2_CPU0_G0_TX_DN<12>")
	)
	(segment
		(start 236.278928 -198.496936)
		(end 239.107218 -197.99808)
		(width 0.14224)
		(layer "In4.Cu")
		(net "GMI_CPU1_G2_CPU0_G0_TX_DN<12>")
	)
	(segment
		(start 346.631768 -217.643456)
		(end 348.112334 -220.137736)
		(width 0.14224)
		(layer "In4.Cu")
		(net "GMI_CPU1_G2_CPU0_G0_TX_DN<12>")
	)
	(segment
		(start 123.711716 -222.29191)
		(end 123.7107 -222.291402)
		(width 0.1143)
		(layer "In4.Cu")
		(net "GMI_CPU1_G2_CPU0_G0_TX_DN<12>")
	)
	(segment
		(start 123.383548 -221.203012)
		(end 123.383548 -221.174564)
		(width 0.1143)
		(layer "In4.Cu")
		(net "GMI_CPU1_G2_CPU0_G0_TX_DN<12>")
	)
	(segment
		(start 347.785182 -226.177348)
		(end 347.786706 -226.178364)
		(width 0.1143)
		(layer "In4.Cu")
		(net "GMI_CPU1_G2_CPU0_G0_TX_DN<12>")
	)
	(segment
		(start 348.112334 -221.17431)
		(end 348.112334 -221.202758)
		(width 0.1143)
		(layer "In4.Cu")
		(net "GMI_CPU1_G2_CPU0_G0_TX_DN<12>")
	)
	(segment
		(start 346.842588 -228.77272)
		(end 346.812362 -228.789992)
		(width 0.1143)
		(layer "In4.Cu")
		(net "GMI_CPU1_G2_CPU0_G0_TX_DN<12>")
	)
	(segment
		(start 123.712478 -222.936562)
		(end 123.713748 -222.9358)
		(width 0.1143)
		(layer "In4.Cu")
		(net "GMI_CPU1_G2_CPU0_G0_TX_DN<12>")
	)
	(segment
		(start 347.786706 -222.290132)
		(end 347.785182 -222.291148)
		(width 0.1143)
		(layer "In4.Cu")
		(net "GMI_CPU1_G2_CPU0_G0_TX_DN<12>")
	)
	(segment
		(start 123.712478 -224.556574)
		(end 123.713748 -224.555812)
		(width 0.1143)
		(layer "In4.Cu")
		(net "GMI_CPU1_G2_CPU0_G0_TX_DN<12>")
	)
	(segment
		(start 123.383548 -220.29293)
		(end 125.084586 -217.345006)
		(width 0.14224)
		(layer "In4.Cu")
		(net "GMI_CPU1_G2_CPU0_G0_TX_DN<12>")
	)
	(segment
		(start 346.263214 -229.904036)
		(end 346.561156 -229.904036)
		(width 0.1143)
		(layer "In4.Cu")
		(net "GMI_CPU1_G2_CPU0_G0_TX_DN<12>")
	)
	(segment
		(start 145.74266 -200.406254)
		(end 147.870418 -199.76211)
		(width 0.14224)
		(layer "In4.Cu")
		(net "GMI_CPU1_G2_CPU0_G0_TX_DN<12>")
	)
	(segment
		(start 346.193364 -229.834186)
		(end 346.263214 -229.904036)
		(width 0.1143)
		(layer "In4.Cu")
		(net "GMI_CPU1_G2_CPU0_G0_TX_DN<12>")
	)
	(segment
		(start 347.782134 -224.555558)
		(end 347.783404 -224.55632)
		(width 0.1143)
		(layer "In4.Cu")
		(net "GMI_CPU1_G2_CPU0_G0_TX_DN<12>")
	)
	(segment
		(start 123.7107 -222.291402)
		(end 123.709176 -222.290386)
		(width 0.1143)
		(layer "In4.Cu")
		(net "GMI_CPU1_G2_CPU0_G0_TX_DN<12>")
	)
	(segment
		(start 123.743466 -222.310198)
		(end 123.711716 -222.29191)
		(width 0.1143)
		(layer "In4.Cu")
		(net "GMI_CPU1_G2_CPU0_G0_TX_DN<12>")
	)
	(segment
		(start 348.066614 -221.248478)
		(end 348.066614 -221.624652)
		(width 0.1143)
		(layer "In4.Cu")
		(net "GMI_CPU1_G2_CPU0_G0_TX_DN<12>")
	)
	(segment
		(start 213.113366 -189.127892)
		(end 235.325158 -198.328534)
		(width 0.14224)
		(layer "In4.Cu")
		(net "GMI_CPU1_G2_CPU0_G0_TX_DN<12>")
	)
	(segment
		(start 124.68352 -228.790246)
		(end 124.653294 -228.772974)
		(width 0.1143)
		(layer "In4.Cu")
		(net "GMI_CPU1_G2_CPU0_G0_TX_DN<12>")
	)
	(segment
		(start 348.066614 -221.624652)
		(end 348.06636 -221.624906)
		(width 0.1143)
		(layer "In4.Cu")
		(net "GMI_CPU1_G2_CPU0_G0_TX_DN<12>")
	)
	(segment
		(start 346.374212 -229.58171)
		(end 346.340684 -229.601268)
		(width 0.1143)
		(layer "In4.Cu")
		(net "GMI_CPU1_G2_CPU0_G0_TX_DN<12>")
	)
	(segment
		(start 347.785182 -222.291148)
		(end 347.784166 -222.291656)
		(width 0.1143)
		(layer "In4.Cu")
		(net "GMI_CPU1_G2_CPU0_G0_TX_DN<12>")
	)
	(segment
		(start 346.844874 -228.772466)
		(end 346.843858 -228.772974)
		(width 0.1143)
		(layer "In4.Cu")
		(net "GMI_CPU1_G2_CPU0_G0_TX_DN<12>")
	)
	(segment
		(start 124.651008 -228.77272)
		(end 124.619258 -228.752146)
		(width 0.1143)
		(layer "In4.Cu")
		(net "GMI_CPU1_G2_CPU0_G0_TX_DN<12>")
	)
	(segment
		(start 150.220934 -197.834758)
		(end 150.22068 -197.834758)
		(width 0.14224)
		(layer "In4.Cu")
		(net "GMI_CPU1_G2_CPU0_G0_TX_DN<12>")
	)
	(segment
		(start 309.42026 -188.190886)
		(end 318.819784 -194.815714)
		(width 0.14224)
		(layer "In4.Cu")
		(net "GMI_CPU1_G2_CPU0_G0_TX_DN<12>")
	)
	(segment
		(start 123.70816 -222.289878)
		(end 123.6726 -222.26905)
		(width 0.1143)
		(layer "In4.Cu")
		(net "GMI_CPU1_G2_CPU0_G0_TX_DN<12>")
	)
	(segment
		(start 123.6726 -226.199954)
		(end 123.7107 -226.177602)
		(width 0.1143)
		(layer "In4.Cu")
		(net "GMI_CPU1_G2_CPU0_G0_TX_DN<12>")
	)
	(segment
		(start 123.741688 -227.169472)
		(end 123.738386 -227.16744)
		(width 0.1143)
		(layer "In4.Cu")
		(net "GMI_CPU1_G2_CPU0_G0_TX_DN<12>")
	)
	(segment
		(start 347.784166 -226.17684)
		(end 347.785182 -226.177348)
		(width 0.1143)
		(layer "In4.Cu")
		(net "GMI_CPU1_G2_CPU0_G0_TX_DN<12>")
	)
	(segment
		(start 123.429522 -221.62516)
		(end 123.429268 -221.624906)
		(width 0.1143)
		(layer "In4.Cu")
		(net "GMI_CPU1_G2_CPU0_G0_TX_DN<12>")
	)
	(segment
		(start 347.785182 -224.557336)
		(end 347.786706 -224.558352)
		(width 0.1143)
		(layer "In4.Cu")
		(net "GMI_CPU1_G2_CPU0_G0_TX_DN<12>")
	)
	(segment
		(start 348.112334 -220.137736)
		(end 348.112334 -221.17431)
		(width 0.14224)
		(layer "In4.Cu")
		(net "GMI_CPU1_G2_CPU0_G0_TX_DN<12>")
	)
	(segment
		(start 123.712478 -223.91243)
		(end 123.711716 -223.911922)
		(width 0.1143)
		(layer "In4.Cu")
		(net "GMI_CPU1_G2_CPU0_G0_TX_DN<12>")
	)
	(segment
		(start 262.796528 -187.812934)
		(end 303.706784 -188.190886)
		(width 0.14224)
		(layer "In4.Cu")
		(net "GMI_CPU1_G2_CPU0_G0_TX_DN<12>")
	)
	(segment
		(start 347.786706 -227.150168)
		(end 347.785182 -227.151184)
		(width 0.1143)
		(layer "In4.Cu")
		(net "GMI_CPU1_G2_CPU0_G0_TX_DN<12>")
	)
	(segment
		(start 123.711716 -223.911922)
		(end 123.7107 -223.911414)
		(width 0.1143)
		(layer "In4.Cu")
		(net "GMI_CPU1_G2_CPU0_G0_TX_DN<12>")
	)
	(segment
		(start 347.784166 -222.291656)
		(end 347.752416 -222.309944)
		(width 0.1143)
		(layer "In4.Cu")
		(net "GMI_CPU1_G2_CPU0_G0_TX_DN<12>")
	)
	(segment
		(start 235.326682 -198.329042)
		(end 236.278928 -198.496936)
		(width 0.14224)
		(layer "In4.Cu")
		(net "GMI_CPU1_G2_CPU0_G0_TX_DN<12>")
	)
	(segment
		(start 346.410534 -229.560628)
		(end 346.374212 -229.58171)
		(width 0.1143)
		(layer "In4.Cu")
		(net "GMI_CPU1_G2_CPU0_G0_TX_DN<12>")
	)
	(segment
		(start 347.784166 -225.53168)
		(end 347.783404 -225.532188)
		(width 0.1143)
		(layer "In4.Cu")
		(net "GMI_CPU1_G2_CPU0_G0_TX_DN<12>")
	)
	(segment
		(start 346.876624 -228.751892)
		(end 346.844874 -228.772466)
		(width 0.1143)
		(layer "In4.Cu")
		(net "GMI_CPU1_G2_CPU0_G0_TX_DN<12>")
	)
	(segment
		(start 347.340682 -227.958396)
		(end 347.30182 -227.981256)
		(width 0.1143)
		(layer "In4.Cu")
		(net "GMI_CPU1_G2_CPU0_G0_TX_DN<12>")
	)
	(segment
		(start 347.784166 -223.911668)
		(end 347.783404 -223.912176)
		(width 0.1143)
		(layer "In4.Cu")
		(net "GMI_CPU1_G2_CPU0_G0_TX_DN<12>")
	)
	(segment
		(start 207.36433 -188.114432)
		(end 213.113366 -189.127892)
		(width 0.14224)
		(layer "In4.Cu")
		(net "GMI_CPU1_G2_CPU0_G0_TX_DN<12>")
	)
	(segment
		(start 123.73737 -227.166932)
		(end 123.712478 -227.152454)
		(width 0.1143)
		(layer "In4.Cu")
		(net "GMI_CPU1_G2_CPU0_G0_TX_DN<12>")
	)
	(segment
		(start 347.783404 -226.176332)
		(end 347.784166 -226.17684)
		(width 0.1143)
		(layer "In4.Cu")
		(net "GMI_CPU1_G2_CPU0_G0_TX_DN<12>")
	)
	(segment
		(start 347.782134 -222.935546)
		(end 347.783404 -222.936308)
		(width 0.1143)
		(layer "In4.Cu")
		(net "GMI_CPU1_G2_CPU0_G0_TX_DN<12>")
	)
	(segment
		(start 123.711716 -225.531934)
		(end 123.7107 -225.531426)
		(width 0.1143)
		(layer "In4.Cu")
		(net "GMI_CPU1_G2_CPU0_G0_TX_DN<12>")
	)
	(segment
		(start 123.7107 -224.55759)
		(end 123.711716 -224.557082)
		(width 0.1143)
		(layer "In4.Cu")
		(net "GMI_CPU1_G2_CPU0_G0_TX_DN<12>")
	)
	(segment
		(start 123.709176 -223.910398)
		(end 123.6726 -223.889062)
		(width 0.1143)
		(layer "In4.Cu")
		(net "GMI_CPU1_G2_CPU0_G0_TX_DN<12>")
	)
	(segment
		(start 347.784166 -222.936816)
		(end 347.820488 -222.957644)
		(width 0.1143)
		(layer "In4.Cu")
		(net "GMI_CPU1_G2_CPU0_G0_TX_DN<12>")
	)
	(segment
		(start 347.782134 -226.17557)
		(end 347.783404 -226.176332)
		(width 0.1143)
		(layer "In4.Cu")
		(net "GMI_CPU1_G2_CPU0_G0_TX_DN<12>")
	)
	(segment
		(start 347.754194 -227.169218)
		(end 347.753178 -227.169726)
		(width 0.1143)
		(layer "In4.Cu")
		(net "GMI_CPU1_G2_CPU0_G0_TX_DN<12>")
	)
	(segment
		(start 347.785182 -225.531172)
		(end 347.784166 -225.53168)
		(width 0.1143)
		(layer "In4.Cu")
		(net "GMI_CPU1_G2_CPU0_G0_TX_DN<12>")
	)
	(segment
		(start 250.57608 -189.96787)
		(end 262.796528 -187.812934)
		(width 0.14224)
		(layer "In4.Cu")
		(net "GMI_CPU1_G2_CPU0_G0_TX_DN<12>")
	)
	(segment
		(start 125.084586 -217.345006)
		(end 145.74266 -200.406254)
		(width 0.14224)
		(layer "In4.Cu")
		(net "GMI_CPU1_G2_CPU0_G0_TX_DN<12>")
	)
	(segment
		(start 347.784166 -227.151692)
		(end 347.783404 -227.1522)
		(width 0.1143)
		(layer "In4.Cu")
		(net "GMI_CPU1_G2_CPU0_G0_TX_DN<12>")
	)
	(segment
		(start 347.783404 -227.1522)
		(end 347.758512 -227.166678)
		(width 0.1143)
		(layer "In4.Cu")
		(net "GMI_CPU1_G2_CPU0_G0_TX_DN<12>")
	)
	(segment
		(start 124.194062 -227.98151)
		(end 124.1552 -227.95865)
		(width 0.1143)
		(layer "In4.Cu")
		(net "GMI_CPU1_G2_CPU0_G0_TX_DN<12>")
	)
	(segment
		(start 347.583506 -227.46716)
		(end 347.583506 -227.494338)
		(width 0.1143)
		(layer "In4.Cu")
		(net "GMI_CPU1_G2_CPU0_G0_TX_DN<12>")
	)
	(segment
		(start 123.713748 -226.175824)
		(end 123.743466 -226.158806)
		(width 0.1143)
		(layer "In4.Cu")
		(net "GMI_CPU1_G2_CPU0_G0_TX_DN<12>")
	)
	(segment
		(start 125.12167 -229.581964)
		(end 125.085348 -229.560882)
		(width 0.1143)
		(layer "In4.Cu")
		(net "GMI_CPU1_G2_CPU0_G0_TX_DN<12>")
	)
	(segment
		(start 347.758512 -227.166678)
		(end 347.757496 -227.167186)
		(width 0.1143)
		(layer "In4.Cu")
		(net "GMI_CPU1_G2_CPU0_G0_TX_DN<12>")
	)
	(segment
		(start 348.112334 -221.202758)
		(end 348.066614 -221.248478)
		(width 0.1143)
		(layer "In4.Cu")
		(net "GMI_CPU1_G2_CPU0_G0_TX_DN<12>")
	)
	(segment
		(start 123.712478 -225.532442)
		(end 123.711716 -225.531934)
		(width 0.1143)
		(layer "In4.Cu")
		(net "GMI_CPU1_G2_CPU0_G0_TX_DN<12>")
	)
	(segment
		(start 123.711716 -227.151946)
		(end 123.7107 -227.151438)
		(width 0.1143)
		(layer "In4.Cu")
		(net "GMI_CPU1_G2_CPU0_G0_TX_DN<12>")
	)
	(segment
		(start 123.709176 -227.150422)
		(end 123.6726 -227.129086)
		(width 0.1143)
		(layer "In4.Cu")
		(net "GMI_CPU1_G2_CPU0_G0_TX_DN<12>")
	)
	(segment
		(start 235.325158 -198.328534)
		(end 235.326682 -198.329042)
		(width 0.14224)
		(layer "In4.Cu")
		(net "GMI_CPU1_G2_CPU0_G0_TX_DN<12>")
	)
	(segment
		(start 123.7107 -223.911414)
		(end 123.709176 -223.910398)
		(width 0.1143)
		(layer "In4.Cu")
		(net "GMI_CPU1_G2_CPU0_G0_TX_DN<12>")
	)
	(segment
		(start 123.738386 -227.16744)
		(end 123.73737 -227.166932)
		(width 0.1143)
		(layer "In4.Cu")
		(net "GMI_CPU1_G2_CPU0_G0_TX_DN<12>")
	)
	(segment
		(start 123.429522 -221.804484)
		(end 123.429522 -221.62516)
		(width 0.1143)
		(layer "In4.Cu")
		(net "GMI_CPU1_G2_CPU0_G0_TX_DN<12>")
	)
	(segment
		(start 123.7107 -227.151438)
		(end 123.709176 -227.150422)
		(width 0.1143)
		(layer "In4.Cu")
		(net "GMI_CPU1_G2_CPU0_G0_TX_DN<12>")
	)
	(segment
		(start 123.912376 -227.494592)
		(end 123.912376 -227.467414)
		(width 0.1143)
		(layer "In4.Cu")
		(net "GMI_CPU1_G2_CPU0_G0_TX_DN<12>")
	)
	(segment
		(start 347.787722 -222.289624)
		(end 347.786706 -222.290132)
		(width 0.1143)
		(layer "In4.Cu")
		(net "GMI_CPU1_G2_CPU0_G0_TX_DN<12>")
	)
	(segment
		(start 347.823282 -222.268796)
		(end 347.787722 -222.289624)
		(width 0.1143)
		(layer "In4.Cu")
		(net "GMI_CPU1_G2_CPU0_G0_TX_DN<12>")
	)
	(segment
		(start 124.652024 -228.773228)
		(end 124.651008 -228.77272)
		(width 0.1143)
		(layer "In4.Cu")
		(net "GMI_CPU1_G2_CPU0_G0_TX_DN<12>")
	)
	(arc
		(start 347.301312 -227.98151)
		(mid 347.173843 -228.109318)
		(end 347.12656 -228.283516)
		(width 0.1143)
		(layer "In4.Cu")
		(net "GMI_CPU1_G2_CPU0_G0_TX_DN<12>")
	)
	(arc
		(start 123.6726 -223.889062)
		(mid 123.429273 -223.424496)
		(end 123.6726 -222.95993)
		(width 0.1143)
		(layer "In4.Cu")
		(net "GMI_CPU1_G2_CPU0_G0_TX_DN<12>")
	)
	(arc
		(start 347.12656 -228.284024)
		(mid 347.060212 -228.54927)
		(end 346.876624 -228.751892)
		(width 0.1143)
		(layer "In4.Cu")
		(net "GMI_CPU1_G2_CPU0_G0_TX_DN<12>")
	)
	(arc
		(start 125.302518 -229.83444)
		(mid 125.251028 -229.703967)
		(end 125.155198 -229.601522)
		(width 0.1143)
		(layer "In4.Cu")
		(net "GMI_CPU1_G2_CPU0_G0_TX_DN<12>")
	)
	(arc
		(start 348.06636 -221.80423)
		(mid 348.038444 -221.980206)
		(end 347.95714 -222.138748)
		(width 0.1143)
		(layer "In4.Cu")
		(net "GMI_CPU1_G2_CPU0_G0_TX_DN<12>")
	)
	(arc
		(start 347.823282 -226.1997)
		(mid 348.066609 -226.664266)
		(end 347.823282 -227.128832)
		(width 0.1143)
		(layer "In4.Cu")
		(net "GMI_CPU1_G2_CPU0_G0_TX_DN<12>")
	)
	(arc
		(start 346.656406 -229.094284)
		(mid 346.59117 -229.357875)
		(end 346.410534 -229.560628)
		(width 0.1143)
		(layer "In4.Cu")
		(net "GMI_CPU1_G2_CPU0_G0_TX_DN<12>")
	)
	(arc
		(start 123.6726 -227.129086)
		(mid 123.429273 -226.66452)
		(end 123.6726 -226.199954)
		(width 0.1143)
		(layer "In4.Cu")
		(net "GMI_CPU1_G2_CPU0_G0_TX_DN<12>")
	)
	(arc
		(start 123.538742 -222.139002)
		(mid 123.457451 -221.980455)
		(end 123.429522 -221.804484)
		(width 0.1143)
		(layer "In4.Cu")
		(net "GMI_CPU1_G2_CPU0_G0_TX_DN<12>")
	)
	(arc
		(start 123.743466 -224.538794)
		(mid 123.899394 -224.234502)
		(end 123.743466 -223.93021)
		(width 0.1143)
		(layer "In4.Cu")
		(net "GMI_CPU1_G2_CPU0_G0_TX_DN<12>")
	)
	(arc
		(start 346.340684 -229.601268)
		(mid 346.244796 -229.703676)
		(end 346.193364 -229.834186)
		(width 0.1143)
		(layer "In4.Cu")
		(net "GMI_CPU1_G2_CPU0_G0_TX_DN<12>")
	)
	(arc
		(start 123.743466 -222.918782)
		(mid 123.899394 -222.61449)
		(end 123.743466 -222.310198)
		(width 0.1143)
		(layer "In4.Cu")
		(net "GMI_CPU1_G2_CPU0_G0_TX_DN<12>")
	)
	(arc
		(start 124.369322 -228.28377)
		(mid 124.322013 -228.109587)
		(end 124.19457 -227.981764)
		(width 0.1143)
		(layer "In4.Cu")
		(net "GMI_CPU1_G2_CPU0_G0_TX_DN<12>")
	)
	(arc
		(start 347.823282 -222.959676)
		(mid 348.066609 -223.424242)
		(end 347.823282 -223.888808)
		(width 0.1143)
		(layer "In4.Cu")
		(net "GMI_CPU1_G2_CPU0_G0_TX_DN<12>")
	)
	(arc
		(start 347.752416 -222.309944)
		(mid 347.596488 -222.614236)
		(end 347.752416 -222.918528)
		(width 0.1143)
		(layer "In4.Cu")
		(net "GMI_CPU1_G2_CPU0_G0_TX_DN<12>")
	)
	(arc
		(start 124.1552 -227.95865)
		(mid 123.976845 -227.756436)
		(end 123.912376 -227.494592)
		(width 0.1143)
		(layer "In4.Cu")
		(net "GMI_CPU1_G2_CPU0_G0_TX_DN<12>")
	)
	(arc
		(start 125.085348 -229.560882)
		(mid 124.904696 -229.358137)
		(end 124.839476 -229.094538)
		(width 0.1143)
		(layer "In4.Cu")
		(net "GMI_CPU1_G2_CPU0_G0_TX_DN<12>")
	)
	(arc
		(start 347.583506 -227.494338)
		(mid 347.519155 -227.756244)
		(end 347.340682 -227.958396)
		(width 0.1143)
		(layer "In4.Cu")
		(net "GMI_CPU1_G2_CPU0_G0_TX_DN<12>")
	)
	(arc
		(start 123.743466 -226.158806)
		(mid 123.899394 -225.854514)
		(end 123.743466 -225.550222)
		(width 0.1143)
		(layer "In4.Cu")
		(net "GMI_CPU1_G2_CPU0_G0_TX_DN<12>")
	)
	(arc
		(start 124.839476 -229.094538)
		(mid 124.798221 -228.923567)
		(end 124.68352 -228.790246)
		(width 0.1143)
		(layer "In4.Cu")
		(net "GMI_CPU1_G2_CPU0_G0_TX_DN<12>")
	)
	(arc
		(start 346.812362 -228.789992)
		(mid 346.697686 -228.923326)
		(end 346.656406 -229.094284)
		(width 0.1143)
		(layer "In4.Cu")
		(net "GMI_CPU1_G2_CPU0_G0_TX_DN<12>")
	)
	(arc
		(start 347.95714 -222.138748)
		(mid 347.895621 -222.209342)
		(end 347.823282 -222.268796)
		(width 0.1143)
		(layer "In4.Cu")
		(net "GMI_CPU1_G2_CPU0_G0_TX_DN<12>")
	)
	(arc
		(start 123.6726 -225.509074)
		(mid 123.429273 -225.044508)
		(end 123.6726 -224.579942)
		(width 0.1143)
		(layer "In4.Cu")
		(net "GMI_CPU1_G2_CPU0_G0_TX_DN<12>")
	)
	(arc
		(start 347.753178 -227.169726)
		(mid 347.628874 -227.295935)
		(end 347.583506 -227.46716)
		(width 0.1143)
		(layer "In4.Cu")
		(net "GMI_CPU1_G2_CPU0_G0_TX_DN<12>")
	)
	(arc
		(start 347.823282 -224.579688)
		(mid 348.066609 -225.044254)
		(end 347.823282 -225.50882)
		(width 0.1143)
		(layer "In4.Cu")
		(net "GMI_CPU1_G2_CPU0_G0_TX_DN<12>")
	)
	(arc
		(start 123.6726 -222.26905)
		(mid 123.600273 -222.209583)
		(end 123.538742 -222.139002)
		(width 0.1143)
		(layer "In4.Cu")
		(net "GMI_CPU1_G2_CPU0_G0_TX_DN<12>")
	)
	(arc
		(start 347.752416 -223.929956)
		(mid 347.596488 -224.234248)
		(end 347.752416 -224.53854)
		(width 0.1143)
		(layer "In4.Cu")
		(net "GMI_CPU1_G2_CPU0_G0_TX_DN<12>")
	)
	(arc
		(start 347.752416 -225.549968)
		(mid 347.596488 -225.85426)
		(end 347.752416 -226.158552)
		(width 0.1143)
		(layer "In4.Cu")
		(net "GMI_CPU1_G2_CPU0_G0_TX_DN<12>")
	)
	(arc
		(start 123.912376 -227.467414)
		(mid 123.866968 -227.296213)
		(end 123.742704 -227.16998)
		(width 0.1143)
		(layer "In4.Cu")
		(net "GMI_CPU1_G2_CPU0_G0_TX_DN<12>")
	)
	(arc
		(start 124.619258 -228.752146)
		(mid 124.435651 -228.549534)
		(end 124.369322 -228.284278)
		(width 0.1143)
		(layer "In4.Cu")
		(net "GMI_CPU1_G2_CPU0_G0_TX_DN<12>")
	)
	(segment
		(start 349.847916 -228.550216)
		(end 349.381064 -228.284278)
		(width 0.12954)
		(layer "F.Cu")
		(net "GMI_CPU1_G2_CPU0_G0_TX_DN<11>")
	)
	(segment
		(start 121.647966 -228.55047)
		(end 122.114818 -228.284532)
		(width 0.12954)
		(layer "F.Cu")
		(net "GMI_CPU1_G2_CPU0_G0_TX_DN<11>")
	)
	(segment
		(start 122.41276 -228.284532)
		(end 122.48261 -228.214682)
		(width 0.1143)
		(layer "In4.Cu")
		(net "GMI_CPU1_G2_CPU0_G0_TX_DN<11>")
	)
	(segment
		(start 349.66402 -222.936816)
		(end 349.703136 -222.959676)
		(width 0.1143)
		(layer "In4.Cu")
		(net "GMI_CPU1_G2_CPU0_G0_TX_DN<11>")
	)
	(segment
		(start 349.970852 -221.426024)
		(end 349.946214 -221.450662)
		(width 0.1143)
		(layer "In4.Cu")
		(net "GMI_CPU1_G2_CPU0_G0_TX_DN<11>")
	)
	(segment
		(start 121.47931 -219.801948)
		(end 123.755912 -215.88857)
		(width 0.14224)
		(layer "In4.Cu")
		(net "GMI_CPU1_G2_CPU0_G0_TX_DN<11>")
	)
	(segment
		(start 349.013272 -228.214428)
		(end 349.083122 -228.284278)
		(width 0.1143)
		(layer "In4.Cu")
		(net "GMI_CPU1_G2_CPU0_G0_TX_DN<11>")
	)
	(segment
		(start 146.658076 -197.972426)
		(end 162.450272 -185.0263)
		(width 0.14224)
		(layer "In4.Cu")
		(net "GMI_CPU1_G2_CPU0_G0_TX_DN<11>")
	)
	(segment
		(start 302.88992 -184.192926)
		(end 306.71389 -184.192926)
		(width 0.14224)
		(layer "In4.Cu")
		(net "GMI_CPU1_G2_CPU0_G0_TX_DN<11>")
	)
	(segment
		(start 349.63227 -223.929956)
		(end 349.612458 -223.94418)
		(width 0.1143)
		(layer "In4.Cu")
		(net "GMI_CPU1_G2_CPU0_G0_TX_DN<11>")
	)
	(segment
		(start 121.831862 -225.531934)
		(end 121.792746 -225.509074)
		(width 0.1143)
		(layer "In4.Cu")
		(net "GMI_CPU1_G2_CPU0_G0_TX_DN<11>")
	)
	(segment
		(start 349.63227 -224.53854)
		(end 349.66402 -224.556828)
		(width 0.1143)
		(layer "In4.Cu")
		(net "GMI_CPU1_G2_CPU0_G0_TX_DN<11>")
	)
	(segment
		(start 121.831862 -224.557082)
		(end 121.863612 -224.538794)
		(width 0.1143)
		(layer "In4.Cu")
		(net "GMI_CPU1_G2_CPU0_G0_TX_DN<11>")
	)
	(segment
		(start 349.193358 -227.962206)
		(end 349.16237 -227.979986)
		(width 0.1143)
		(layer "In4.Cu")
		(net "GMI_CPU1_G2_CPU0_G0_TX_DN<11>")
	)
	(segment
		(start 349.083122 -228.284278)
		(end 349.381064 -228.284278)
		(width 0.1143)
		(layer "In4.Cu")
		(net "GMI_CPU1_G2_CPU0_G0_TX_DN<11>")
	)
	(segment
		(start 121.863612 -223.93021)
		(end 121.792746 -223.889062)
		(width 0.1143)
		(layer "In4.Cu")
		(net "GMI_CPU1_G2_CPU0_G0_TX_DN<11>")
	)
	(segment
		(start 349.66402 -226.17684)
		(end 349.703136 -226.1997)
		(width 0.1143)
		(layer "In4.Cu")
		(net "GMI_CPU1_G2_CPU0_G0_TX_DN<11>")
	)
	(segment
		(start 350.016572 -219.656406)
		(end 350.016572 -221.083124)
		(width 0.14224)
		(layer "In4.Cu")
		(net "GMI_CPU1_G2_CPU0_G0_TX_DN<11>")
	)
	(segment
		(start 123.755912 -215.88857)
		(end 144.98955 -198.47814)
		(width 0.14224)
		(layer "In4.Cu")
		(net "GMI_CPU1_G2_CPU0_G0_TX_DN<11>")
	)
	(segment
		(start 349.196406 -227.960428)
		(end 349.19412 -227.961698)
		(width 0.1143)
		(layer "In4.Cu")
		(net "GMI_CPU1_G2_CPU0_G0_TX_DN<11>")
	)
	(segment
		(start 121.47931 -221.083378)
		(end 121.47931 -221.05493)
		(width 0.1143)
		(layer "In4.Cu")
		(net "GMI_CPU1_G2_CPU0_G0_TX_DN<11>")
	)
	(segment
		(start 122.333512 -227.98024)
		(end 122.302524 -227.96246)
		(width 0.1143)
		(layer "In4.Cu")
		(net "GMI_CPU1_G2_CPU0_G0_TX_DN<11>")
	)
	(segment
		(start 121.549668 -221.804484)
		(end 121.549668 -221.450916)
		(width 0.1143)
		(layer "In4.Cu")
		(net "GMI_CPU1_G2_CPU0_G0_TX_DN<11>")
	)
	(segment
		(start 121.52503 -221.426278)
		(end 121.52503 -221.129098)
		(width 0.1143)
		(layer "In4.Cu")
		(net "GMI_CPU1_G2_CPU0_G0_TX_DN<11>")
	)
	(segment
		(start 306.71389 -184.192926)
		(end 308.55031 -185.03392)
		(width 0.14224)
		(layer "In4.Cu")
		(net "GMI_CPU1_G2_CPU0_G0_TX_DN<11>")
	)
	(segment
		(start 121.792746 -222.95993)
		(end 121.831862 -222.93707)
		(width 0.1143)
		(layer "In4.Cu")
		(net "GMI_CPU1_G2_CPU0_G0_TX_DN<11>")
	)
	(segment
		(start 121.863612 -225.550222)
		(end 121.831862 -225.531934)
		(width 0.1143)
		(layer "In4.Cu")
		(net "GMI_CPU1_G2_CPU0_G0_TX_DN<11>")
	)
	(segment
		(start 313.12739 -187.624974)
		(end 347.952314 -216.179654)
		(width 0.14224)
		(layer "In4.Cu")
		(net "GMI_CPU1_G2_CPU0_G0_TX_DN<11>")
	)
	(segment
		(start 121.52503 -221.129098)
		(end 121.47931 -221.083378)
		(width 0.1143)
		(layer "In4.Cu")
		(net "GMI_CPU1_G2_CPU0_G0_TX_DN<11>")
	)
	(segment
		(start 349.703136 -223.888808)
		(end 349.63227 -223.929956)
		(width 0.1143)
		(layer "In4.Cu")
		(net "GMI_CPU1_G2_CPU0_G0_TX_DN<11>")
	)
	(segment
		(start 349.63227 -222.918528)
		(end 349.66402 -222.936816)
		(width 0.1143)
		(layer "In4.Cu")
		(net "GMI_CPU1_G2_CPU0_G0_TX_DN<11>")
	)
	(segment
		(start 162.450272 -185.0263)
		(end 166.973758 -183.409082)
		(width 0.14224)
		(layer "In4.Cu")
		(net "GMI_CPU1_G2_CPU0_G0_TX_DN<11>")
	)
	(segment
		(start 349.19412 -227.961698)
		(end 349.193358 -227.962206)
		(width 0.1143)
		(layer "In4.Cu")
		(net "GMI_CPU1_G2_CPU0_G0_TX_DN<11>")
	)
	(segment
		(start 347.952314 -216.179654)
		(end 350.016572 -219.656406)
		(width 0.14224)
		(layer "In4.Cu")
		(net "GMI_CPU1_G2_CPU0_G0_TX_DN<11>")
	)
	(segment
		(start 166.973758 -183.409082)
		(end 168.26865 -183.409082)
		(width 0.14224)
		(layer "In4.Cu")
		(net "GMI_CPU1_G2_CPU0_G0_TX_DN<11>")
	)
	(segment
		(start 122.114818 -228.284532)
		(end 122.41276 -228.284532)
		(width 0.1143)
		(layer "In4.Cu")
		(net "GMI_CPU1_G2_CPU0_G0_TX_DN<11>")
	)
	(segment
		(start 349.63227 -226.158552)
		(end 349.66402 -226.17684)
		(width 0.1143)
		(layer "In4.Cu")
		(net "GMI_CPU1_G2_CPU0_G0_TX_DN<11>")
	)
	(segment
		(start 349.703136 -225.50882)
		(end 349.66402 -225.53168)
		(width 0.1143)
		(layer "In4.Cu")
		(net "GMI_CPU1_G2_CPU0_G0_TX_DN<11>")
	)
	(segment
		(start 121.863612 -224.538794)
		(end 121.883424 -224.52457)
		(width 0.1143)
		(layer "In4.Cu")
		(net "GMI_CPU1_G2_CPU0_G0_TX_DN<11>")
	)
	(segment
		(start 122.302524 -227.96246)
		(end 122.301762 -227.961952)
		(width 0.1143)
		(layer "In4.Cu")
		(net "GMI_CPU1_G2_CPU0_G0_TX_DN<11>")
	)
	(segment
		(start 121.792746 -224.579942)
		(end 121.831862 -224.557082)
		(width 0.1143)
		(layer "In4.Cu")
		(net "GMI_CPU1_G2_CPU0_G0_TX_DN<11>")
	)
	(segment
		(start 144.98955 -198.47814)
		(end 146.658076 -197.972426)
		(width 0.14224)
		(layer "In4.Cu")
		(net "GMI_CPU1_G2_CPU0_G0_TX_DN<11>")
	)
	(segment
		(start 121.792746 -226.199954)
		(end 121.831862 -226.177094)
		(width 0.1143)
		(layer "In4.Cu")
		(net "GMI_CPU1_G2_CPU0_G0_TX_DN<11>")
	)
	(segment
		(start 350.016572 -221.083124)
		(end 349.970852 -221.128844)
		(width 0.1143)
		(layer "In4.Cu")
		(net "GMI_CPU1_G2_CPU0_G0_TX_DN<11>")
	)
	(segment
		(start 349.970852 -221.128844)
		(end 349.970852 -221.426024)
		(width 0.1143)
		(layer "In4.Cu")
		(net "GMI_CPU1_G2_CPU0_G0_TX_DN<11>")
	)
	(segment
		(start 349.463614 -227.483924)
		(end 349.463614 -227.49637)
		(width 0.1143)
		(layer "In4.Cu")
		(net "GMI_CPU1_G2_CPU0_G0_TX_DN<11>")
	)
	(segment
		(start 121.844562 -227.159312)
		(end 121.792746 -227.129086)
		(width 0.1143)
		(layer "In4.Cu")
		(net "GMI_CPU1_G2_CPU0_G0_TX_DN<11>")
	)
	(segment
		(start 121.863612 -222.310198)
		(end 121.792746 -222.26905)
		(width 0.1143)
		(layer "In4.Cu")
		(net "GMI_CPU1_G2_CPU0_G0_TX_DN<11>")
	)
	(segment
		(start 122.032268 -227.496624)
		(end 122.032268 -227.484178)
		(width 0.1143)
		(layer "In4.Cu")
		(net "GMI_CPU1_G2_CPU0_G0_TX_DN<11>")
	)
	(segment
		(start 122.301762 -227.961952)
		(end 122.299476 -227.960682)
		(width 0.1143)
		(layer "In4.Cu")
		(net "GMI_CPU1_G2_CPU0_G0_TX_DN<11>")
	)
	(segment
		(start 349.946214 -221.450662)
		(end 349.946214 -221.80423)
		(width 0.1143)
		(layer "In4.Cu")
		(net "GMI_CPU1_G2_CPU0_G0_TX_DN<11>")
	)
	(segment
		(start 121.831862 -222.93707)
		(end 121.863612 -222.918782)
		(width 0.1143)
		(layer "In4.Cu")
		(net "GMI_CPU1_G2_CPU0_G0_TX_DN<11>")
	)
	(segment
		(start 168.26865 -183.409082)
		(end 302.88992 -184.192926)
		(width 0.14224)
		(layer "In4.Cu")
		(net "GMI_CPU1_G2_CPU0_G0_TX_DN<11>")
	)
	(segment
		(start 349.66402 -224.556828)
		(end 349.703136 -224.579688)
		(width 0.1143)
		(layer "In4.Cu")
		(net "GMI_CPU1_G2_CPU0_G0_TX_DN<11>")
	)
	(segment
		(start 308.55031 -185.03392)
		(end 313.12739 -187.624974)
		(width 0.14224)
		(layer "In4.Cu")
		(net "GMI_CPU1_G2_CPU0_G0_TX_DN<11>")
	)
	(segment
		(start 121.549668 -221.450916)
		(end 121.52503 -221.426278)
		(width 0.1143)
		(layer "In4.Cu")
		(net "GMI_CPU1_G2_CPU0_G0_TX_DN<11>")
	)
	(segment
		(start 349.703136 -227.128832)
		(end 349.65132 -227.159058)
		(width 0.1143)
		(layer "In4.Cu")
		(net "GMI_CPU1_G2_CPU0_G0_TX_DN<11>")
	)
	(segment
		(start 121.47931 -221.05493)
		(end 121.47931 -219.801948)
		(width 0.14224)
		(layer "In4.Cu")
		(net "GMI_CPU1_G2_CPU0_G0_TX_DN<11>")
	)
	(segment
		(start 121.831862 -226.177094)
		(end 121.863612 -226.158806)
		(width 0.1143)
		(layer "In4.Cu")
		(net "GMI_CPU1_G2_CPU0_G0_TX_DN<11>")
	)
	(segment
		(start 349.66402 -225.53168)
		(end 349.63227 -225.549968)
		(width 0.1143)
		(layer "In4.Cu")
		(net "GMI_CPU1_G2_CPU0_G0_TX_DN<11>")
	)
	(segment
		(start 349.703136 -222.268796)
		(end 349.63227 -222.309944)
		(width 0.1143)
		(layer "In4.Cu")
		(net "GMI_CPU1_G2_CPU0_G0_TX_DN<11>")
	)
	(segment
		(start 121.883424 -223.944434)
		(end 121.863612 -223.93021)
		(width 0.1143)
		(layer "In4.Cu")
		(net "GMI_CPU1_G2_CPU0_G0_TX_DN<11>")
	)
	(segment
		(start 349.612458 -224.524316)
		(end 349.63227 -224.53854)
		(width 0.1143)
		(layer "In4.Cu")
		(net "GMI_CPU1_G2_CPU0_G0_TX_DN<11>")
	)
	(arc
		(start 349.463614 -227.49637)
		(mid 349.392028 -227.7641)
		(end 349.196406 -227.960428)
		(width 0.1143)
		(layer "In4.Cu")
		(net "GMI_CPU1_G2_CPU0_G0_TX_DN<11>")
	)
	(arc
		(start 121.883424 -224.52457)
		(mid 122.032138 -224.234502)
		(end 121.883424 -223.944434)
		(width 0.1143)
		(layer "In4.Cu")
		(net "GMI_CPU1_G2_CPU0_G0_TX_DN<11>")
	)
	(arc
		(start 349.946214 -221.80423)
		(mid 349.881767 -222.066382)
		(end 349.703136 -222.268796)
		(width 0.1143)
		(layer "In4.Cu")
		(net "GMI_CPU1_G2_CPU0_G0_TX_DN<11>")
	)
	(arc
		(start 349.612458 -223.94418)
		(mid 349.463744 -224.234248)
		(end 349.612458 -224.524316)
		(width 0.1143)
		(layer "In4.Cu")
		(net "GMI_CPU1_G2_CPU0_G0_TX_DN<11>")
	)
	(arc
		(start 122.48261 -228.214682)
		(mid 122.430561 -228.083163)
		(end 122.333512 -227.98024)
		(width 0.1143)
		(layer "In4.Cu")
		(net "GMI_CPU1_G2_CPU0_G0_TX_DN<11>")
	)
	(arc
		(start 349.703136 -222.959676)
		(mid 349.946463 -223.424242)
		(end 349.703136 -223.888808)
		(width 0.1143)
		(layer "In4.Cu")
		(net "GMI_CPU1_G2_CPU0_G0_TX_DN<11>")
	)
	(arc
		(start 121.792746 -225.509074)
		(mid 121.549419 -225.044508)
		(end 121.792746 -224.579942)
		(width 0.1143)
		(layer "In4.Cu")
		(net "GMI_CPU1_G2_CPU0_G0_TX_DN<11>")
	)
	(arc
		(start 349.63227 -225.549968)
		(mid 349.480681 -225.85426)
		(end 349.63227 -226.158552)
		(width 0.1143)
		(layer "In4.Cu")
		(net "GMI_CPU1_G2_CPU0_G0_TX_DN<11>")
	)
	(arc
		(start 349.703136 -224.579688)
		(mid 349.946463 -225.044254)
		(end 349.703136 -225.50882)
		(width 0.1143)
		(layer "In4.Cu")
		(net "GMI_CPU1_G2_CPU0_G0_TX_DN<11>")
	)
	(arc
		(start 121.792746 -227.129086)
		(mid 121.549419 -226.66452)
		(end 121.792746 -226.199954)
		(width 0.1143)
		(layer "In4.Cu")
		(net "GMI_CPU1_G2_CPU0_G0_TX_DN<11>")
	)
	(arc
		(start 349.703136 -226.1997)
		(mid 349.946463 -226.664266)
		(end 349.703136 -227.128832)
		(width 0.1143)
		(layer "In4.Cu")
		(net "GMI_CPU1_G2_CPU0_G0_TX_DN<11>")
	)
	(arc
		(start 121.863612 -226.158806)
		(mid 122.015201 -225.854514)
		(end 121.863612 -225.550222)
		(width 0.1143)
		(layer "In4.Cu")
		(net "GMI_CPU1_G2_CPU0_G0_TX_DN<11>")
	)
	(arc
		(start 349.16237 -227.979986)
		(mid 349.065235 -228.082855)
		(end 349.013272 -228.214428)
		(width 0.1143)
		(layer "In4.Cu")
		(net "GMI_CPU1_G2_CPU0_G0_TX_DN<11>")
	)
	(arc
		(start 349.65132 -227.159058)
		(mid 349.513888 -227.296317)
		(end 349.463614 -227.483924)
		(width 0.1143)
		(layer "In4.Cu")
		(net "GMI_CPU1_G2_CPU0_G0_TX_DN<11>")
	)
	(arc
		(start 121.792746 -223.889062)
		(mid 121.549419 -223.424496)
		(end 121.792746 -222.95993)
		(width 0.1143)
		(layer "In4.Cu")
		(net "GMI_CPU1_G2_CPU0_G0_TX_DN<11>")
	)
	(arc
		(start 349.63227 -222.309944)
		(mid 349.480681 -222.614236)
		(end 349.63227 -222.918528)
		(width 0.1143)
		(layer "In4.Cu")
		(net "GMI_CPU1_G2_CPU0_G0_TX_DN<11>")
	)
	(arc
		(start 122.299476 -227.960682)
		(mid 122.103802 -227.764384)
		(end 122.032268 -227.496624)
		(width 0.1143)
		(layer "In4.Cu")
		(net "GMI_CPU1_G2_CPU0_G0_TX_DN<11>")
	)
	(arc
		(start 121.863612 -222.918782)
		(mid 122.015201 -222.61449)
		(end 121.863612 -222.310198)
		(width 0.1143)
		(layer "In4.Cu")
		(net "GMI_CPU1_G2_CPU0_G0_TX_DN<11>")
	)
	(arc
		(start 121.792746 -222.26905)
		(mid 121.614088 -222.06665)
		(end 121.549668 -221.804484)
		(width 0.1143)
		(layer "In4.Cu")
		(net "GMI_CPU1_G2_CPU0_G0_TX_DN<11>")
	)
	(arc
		(start 122.032268 -227.484178)
		(mid 121.981962 -227.29659)
		(end 121.844562 -227.159312)
		(width 0.1143)
		(layer "In4.Cu")
		(net "GMI_CPU1_G2_CPU0_G0_TX_DN<11>")
	)
	(segment
		(start 121.647966 -226.930458)
		(end 122.114818 -226.66452)
		(width 0.12954)
		(layer "F.Cu")
		(net "GMI_CPU1_G2_CPU0_G0_TX_DN<10>")
	)
	(segment
		(start 349.847916 -226.930204)
		(end 349.381064 -226.664266)
		(width 0.12954)
		(layer "F.Cu")
		(net "GMI_CPU1_G2_CPU0_G0_TX_DN<10>")
	)
	(segment
		(start 122.771916 -225.531934)
		(end 122.7328 -225.509074)
		(width 0.1143)
		(layer "In4.Cu")
		(net "GMI_CPU1_G2_CPU0_G0_TX_DN<10>")
	)
	(segment
		(start 348.763082 -225.50882)
		(end 348.693486 -225.54946)
		(width 0.1143)
		(layer "In4.Cu")
		(net "GMI_CPU1_G2_CPU0_G0_TX_DN<10>")
	)
	(segment
		(start 122.42419 -220.070934)
		(end 124.441458 -216.59215)
		(width 0.14224)
		(layer "In4.Cu")
		(net "GMI_CPU1_G2_CPU0_G0_TX_DN<10>")
	)
	(segment
		(start 302.617124 -185.131456)
		(end 302.886872 -185.13298)
		(width 0.14224)
		(layer "In4.Cu")
		(net "GMI_CPU1_G2_CPU0_G0_TX_DN<10>")
	)
	(segment
		(start 348.693486 -224.539048)
		(end 348.763082 -224.579688)
		(width 0.1143)
		(layer "In4.Cu")
		(net "GMI_CPU1_G2_CPU0_G0_TX_DN<10>")
	)
	(segment
		(start 348.763082 -222.268796)
		(end 348.693486 -222.309436)
		(width 0.1143)
		(layer "In4.Cu")
		(net "GMI_CPU1_G2_CPU0_G0_TX_DN<10>")
	)
	(segment
		(start 349.083122 -226.664266)
		(end 349.381064 -226.664266)
		(width 0.1143)
		(layer "In4.Cu")
		(net "GMI_CPU1_G2_CPU0_G0_TX_DN<10>")
	)
	(segment
		(start 122.771916 -223.911922)
		(end 122.7328 -223.889062)
		(width 0.1143)
		(layer "In4.Cu")
		(net "GMI_CPU1_G2_CPU0_G0_TX_DN<10>")
	)
	(segment
		(start 122.46991 -221.426278)
		(end 122.46991 -221.129098)
		(width 0.1143)
		(layer "In4.Cu")
		(net "GMI_CPU1_G2_CPU0_G0_TX_DN<10>")
	)
	(segment
		(start 168.366948 -184.350152)
		(end 302.606456 -185.131456)
		(width 0.14224)
		(layer "In4.Cu")
		(net "GMI_CPU1_G2_CPU0_G0_TX_DN<10>")
	)
	(segment
		(start 122.771916 -226.177094)
		(end 122.802396 -226.159314)
		(width 0.1143)
		(layer "In4.Cu")
		(net "GMI_CPU1_G2_CPU0_G0_TX_DN<10>")
	)
	(segment
		(start 302.886872 -185.13298)
		(end 306.42687 -185.13298)
		(width 0.14224)
		(layer "In4.Cu")
		(net "GMI_CPU1_G2_CPU0_G0_TX_DN<10>")
	)
	(segment
		(start 349.071692 -221.083124)
		(end 349.025972 -221.128844)
		(width 0.1143)
		(layer "In4.Cu")
		(net "GMI_CPU1_G2_CPU0_G0_TX_DN<10>")
	)
	(segment
		(start 306.42687 -185.13298)
		(end 307.390292 -185.531252)
		(width 0.14224)
		(layer "In4.Cu")
		(net "GMI_CPU1_G2_CPU0_G0_TX_DN<10>")
	)
	(segment
		(start 349.025972 -221.426024)
		(end 349.00616 -221.445836)
		(width 0.1143)
		(layer "In4.Cu")
		(net "GMI_CPU1_G2_CPU0_G0_TX_DN<10>")
	)
	(segment
		(start 122.42419 -221.083378)
		(end 122.42419 -221.05493)
		(width 0.1143)
		(layer "In4.Cu")
		(net "GMI_CPU1_G2_CPU0_G0_TX_DN<10>")
	)
	(segment
		(start 307.390292 -185.531252)
		(end 314.258452 -189.817756)
		(width 0.14224)
		(layer "In4.Cu")
		(net "GMI_CPU1_G2_CPU0_G0_TX_DN<10>")
	)
	(segment
		(start 347.28277 -216.89695)
		(end 349.071692 -219.91066)
		(width 0.14224)
		(layer "In4.Cu")
		(net "GMI_CPU1_G2_CPU0_G0_TX_DN<10>")
	)
	(segment
		(start 122.802396 -225.549714)
		(end 122.771916 -225.531934)
		(width 0.1143)
		(layer "In4.Cu")
		(net "GMI_CPU1_G2_CPU0_G0_TX_DN<10>")
	)
	(segment
		(start 122.7328 -222.95993)
		(end 122.771916 -222.93707)
		(width 0.1143)
		(layer "In4.Cu")
		(net "GMI_CPU1_G2_CPU0_G0_TX_DN<10>")
	)
	(segment
		(start 122.802396 -223.929702)
		(end 122.771916 -223.911922)
		(width 0.1143)
		(layer "In4.Cu")
		(net "GMI_CPU1_G2_CPU0_G0_TX_DN<10>")
	)
	(segment
		(start 122.771916 -224.557082)
		(end 122.802396 -224.539302)
		(width 0.1143)
		(layer "In4.Cu")
		(net "GMI_CPU1_G2_CPU0_G0_TX_DN<10>")
	)
	(segment
		(start 122.114818 -226.66452)
		(end 122.41276 -226.66452)
		(width 0.1143)
		(layer "In4.Cu")
		(net "GMI_CPU1_G2_CPU0_G0_TX_DN<10>")
	)
	(segment
		(start 314.258452 -189.817756)
		(end 347.28277 -216.89695)
		(width 0.14224)
		(layer "In4.Cu")
		(net "GMI_CPU1_G2_CPU0_G0_TX_DN<10>")
	)
	(segment
		(start 122.7328 -226.199954)
		(end 122.771916 -226.177094)
		(width 0.1143)
		(layer "In4.Cu")
		(net "GMI_CPU1_G2_CPU0_G0_TX_DN<10>")
	)
	(segment
		(start 122.489722 -221.804484)
		(end 122.489722 -221.44609)
		(width 0.1143)
		(layer "In4.Cu")
		(net "GMI_CPU1_G2_CPU0_G0_TX_DN<10>")
	)
	(segment
		(start 349.071692 -219.91066)
		(end 349.071692 -221.083124)
		(width 0.14224)
		(layer "In4.Cu")
		(net "GMI_CPU1_G2_CPU0_G0_TX_DN<10>")
	)
	(segment
		(start 348.693486 -222.919036)
		(end 348.763082 -222.959676)
		(width 0.1143)
		(layer "In4.Cu")
		(net "GMI_CPU1_G2_CPU0_G0_TX_DN<10>")
	)
	(segment
		(start 122.489722 -221.44609)
		(end 122.46991 -221.426278)
		(width 0.1143)
		(layer "In4.Cu")
		(net "GMI_CPU1_G2_CPU0_G0_TX_DN<10>")
	)
	(segment
		(start 349.025972 -221.128844)
		(end 349.025972 -221.426024)
		(width 0.1143)
		(layer "In4.Cu")
		(net "GMI_CPU1_G2_CPU0_G0_TX_DN<10>")
	)
	(segment
		(start 349.000318 -226.581462)
		(end 349.083122 -226.664266)
		(width 0.1143)
		(layer "In4.Cu")
		(net "GMI_CPU1_G2_CPU0_G0_TX_DN<10>")
	)
	(segment
		(start 122.7328 -224.579942)
		(end 122.771916 -224.557082)
		(width 0.1143)
		(layer "In4.Cu")
		(net "GMI_CPU1_G2_CPU0_G0_TX_DN<10>")
	)
	(segment
		(start 122.771916 -222.93707)
		(end 122.802396 -222.91929)
		(width 0.1143)
		(layer "In4.Cu")
		(net "GMI_CPU1_G2_CPU0_G0_TX_DN<10>")
	)
	(segment
		(start 122.46991 -221.129098)
		(end 122.42419 -221.083378)
		(width 0.1143)
		(layer "In4.Cu")
		(net "GMI_CPU1_G2_CPU0_G0_TX_DN<10>")
	)
	(segment
		(start 349.00616 -221.445836)
		(end 349.00616 -221.80423)
		(width 0.1143)
		(layer "In4.Cu")
		(net "GMI_CPU1_G2_CPU0_G0_TX_DN<10>")
	)
	(segment
		(start 122.802396 -222.30969)
		(end 122.7328 -222.26905)
		(width 0.1143)
		(layer "In4.Cu")
		(net "GMI_CPU1_G2_CPU0_G0_TX_DN<10>")
	)
	(segment
		(start 167.270684 -184.350152)
		(end 168.366948 -184.350152)
		(width 0.14224)
		(layer "In4.Cu")
		(net "GMI_CPU1_G2_CPU0_G0_TX_DN<10>")
	)
	(segment
		(start 124.441458 -216.59215)
		(end 145.224754 -199.550528)
		(width 0.14224)
		(layer "In4.Cu")
		(net "GMI_CPU1_G2_CPU0_G0_TX_DN<10>")
	)
	(segment
		(start 122.42419 -221.05493)
		(end 122.42419 -220.070934)
		(width 0.14224)
		(layer "In4.Cu")
		(net "GMI_CPU1_G2_CPU0_G0_TX_DN<10>")
	)
	(segment
		(start 122.41276 -226.66452)
		(end 122.495564 -226.581716)
		(width 0.1143)
		(layer "In4.Cu")
		(net "GMI_CPU1_G2_CPU0_G0_TX_DN<10>")
	)
	(segment
		(start 348.693486 -226.15906)
		(end 348.763082 -226.1997)
		(width 0.1143)
		(layer "In4.Cu")
		(net "GMI_CPU1_G2_CPU0_G0_TX_DN<10>")
	)
	(segment
		(start 147.138136 -198.9709)
		(end 163.189666 -185.809382)
		(width 0.14224)
		(layer "In4.Cu")
		(net "GMI_CPU1_G2_CPU0_G0_TX_DN<10>")
	)
	(segment
		(start 348.763082 -223.888808)
		(end 348.693486 -223.929448)
		(width 0.1143)
		(layer "In4.Cu")
		(net "GMI_CPU1_G2_CPU0_G0_TX_DN<10>")
	)
	(segment
		(start 302.606456 -185.131456)
		(end 302.617124 -185.131456)
		(width 0.14224)
		(layer "In4.Cu")
		(net "GMI_CPU1_G2_CPU0_G0_TX_DN<10>")
	)
	(segment
		(start 163.189666 -185.809382)
		(end 167.270684 -184.350152)
		(width 0.14224)
		(layer "In4.Cu")
		(net "GMI_CPU1_G2_CPU0_G0_TX_DN<10>")
	)
	(segment
		(start 145.224754 -199.550528)
		(end 147.138136 -198.9709)
		(width 0.14224)
		(layer "In4.Cu")
		(net "GMI_CPU1_G2_CPU0_G0_TX_DN<10>")
	)
	(arc
		(start 122.7328 -223.889062)
		(mid 122.489473 -223.424496)
		(end 122.7328 -222.95993)
		(width 0.1143)
		(layer "In4.Cu")
		(net "GMI_CPU1_G2_CPU0_G0_TX_DN<10>")
	)
	(arc
		(start 348.693486 -222.309436)
		(mid 348.536509 -222.614236)
		(end 348.693486 -222.919036)
		(width 0.1143)
		(layer "In4.Cu")
		(net "GMI_CPU1_G2_CPU0_G0_TX_DN<10>")
	)
	(arc
		(start 122.7328 -225.509074)
		(mid 122.489473 -225.044508)
		(end 122.7328 -224.579942)
		(width 0.1143)
		(layer "In4.Cu")
		(net "GMI_CPU1_G2_CPU0_G0_TX_DN<10>")
	)
	(arc
		(start 122.7328 -222.26905)
		(mid 122.554157 -222.066655)
		(end 122.489722 -221.804484)
		(width 0.1143)
		(layer "In4.Cu")
		(net "GMI_CPU1_G2_CPU0_G0_TX_DN<10>")
	)
	(arc
		(start 348.996508 -226.558602)
		(mid 348.998531 -226.570012)
		(end 349.000318 -226.581462)
		(width 0.1143)
		(layer "In4.Cu")
		(net "GMI_CPU1_G2_CPU0_G0_TX_DN<10>")
	)
	(arc
		(start 348.693486 -223.929448)
		(mid 348.536509 -224.234248)
		(end 348.693486 -224.539048)
		(width 0.1143)
		(layer "In4.Cu")
		(net "GMI_CPU1_G2_CPU0_G0_TX_DN<10>")
	)
	(arc
		(start 348.763082 -226.1997)
		(mid 348.915069 -226.356208)
		(end 348.996508 -226.558602)
		(width 0.1143)
		(layer "In4.Cu")
		(net "GMI_CPU1_G2_CPU0_G0_TX_DN<10>")
	)
	(arc
		(start 348.763082 -222.959676)
		(mid 349.006409 -223.424242)
		(end 348.763082 -223.888808)
		(width 0.1143)
		(layer "In4.Cu")
		(net "GMI_CPU1_G2_CPU0_G0_TX_DN<10>")
	)
	(arc
		(start 122.499374 -226.558856)
		(mid 122.580807 -226.356458)
		(end 122.7328 -226.199954)
		(width 0.1143)
		(layer "In4.Cu")
		(net "GMI_CPU1_G2_CPU0_G0_TX_DN<10>")
	)
	(arc
		(start 122.495564 -226.581716)
		(mid 122.497352 -226.570267)
		(end 122.499374 -226.558856)
		(width 0.1143)
		(layer "In4.Cu")
		(net "GMI_CPU1_G2_CPU0_G0_TX_DN<10>")
	)
	(arc
		(start 348.693486 -225.54946)
		(mid 348.536509 -225.85426)
		(end 348.693486 -226.15906)
		(width 0.1143)
		(layer "In4.Cu")
		(net "GMI_CPU1_G2_CPU0_G0_TX_DN<10>")
	)
	(arc
		(start 348.763082 -224.579688)
		(mid 349.006409 -225.044254)
		(end 348.763082 -225.50882)
		(width 0.1143)
		(layer "In4.Cu")
		(net "GMI_CPU1_G2_CPU0_G0_TX_DN<10>")
	)
	(arc
		(start 349.00616 -221.80423)
		(mid 348.941786 -222.066434)
		(end 348.763082 -222.268796)
		(width 0.1143)
		(layer "In4.Cu")
		(net "GMI_CPU1_G2_CPU0_G0_TX_DN<10>")
	)
	(arc
		(start 122.802396 -222.91929)
		(mid 122.959373 -222.61449)
		(end 122.802396 -222.30969)
		(width 0.1143)
		(layer "In4.Cu")
		(net "GMI_CPU1_G2_CPU0_G0_TX_DN<10>")
	)
	(arc
		(start 122.802396 -226.159314)
		(mid 122.959373 -225.854514)
		(end 122.802396 -225.549714)
		(width 0.1143)
		(layer "In4.Cu")
		(net "GMI_CPU1_G2_CPU0_G0_TX_DN<10>")
	)
	(arc
		(start 122.802396 -224.539302)
		(mid 122.959373 -224.234502)
		(end 122.802396 -223.929702)
		(width 0.1143)
		(layer "In4.Cu")
		(net "GMI_CPU1_G2_CPU0_G0_TX_DN<10>")
	)
	(segment
		(start 357.837994 -230.97998)
		(end 357.371142 -230.714296)
		(width 0.12954)
		(layer "F.Cu")
		(net "GMI_CPU1_G2_CPU0_G0_TX_DN<0>")
	)
	(segment
		(start 113.657888 -230.980234)
		(end 114.12474 -230.71455)
		(width 0.12954)
		(layer "F.Cu")
		(net "GMI_CPU1_G2_CPU0_G0_TX_DN<0>")
	)
	(segment
		(start 358.709214 -227.872544)
		(end 358.709468 -227.872544)
		(width 0.1143)
		(layer "In4.Cu")
		(net "GMI_CPU1_G2_CPU0_G0_TX_DN<0>")
	)
	(segment
		(start 114.341656 -230.408988)
		(end 114.316002 -230.394256)
		(width 0.1143)
		(layer "In4.Cu")
		(net "GMI_CPU1_G2_CPU0_G0_TX_DN<0>")
	)
	(segment
		(start 200.696322 -174.186342)
		(end 200.696576 -174.186342)
		(width 0.14224)
		(layer "In4.Cu")
		(net "GMI_CPU1_G2_CPU0_G0_TX_DN<0>")
	)
	(segment
		(start 357.695246 -229.557326)
		(end 357.655114 -229.580694)
		(width 0.1143)
		(layer "In4.Cu")
		(net "GMI_CPU1_G2_CPU0_G0_TX_DN<0>")
	)
	(segment
		(start 302.9204 -174.784512)
		(end 308.723538 -174.784512)
		(width 0.14224)
		(layer "In4.Cu")
		(net "GMI_CPU1_G2_CPU0_G0_TX_DN<0>")
	)
	(segment
		(start 308.723538 -174.784512)
		(end 311.920382 -175.927512)
		(width 0.14224)
		(layer "In4.Cu")
		(net "GMI_CPU1_G2_CPU0_G0_TX_DN<0>")
	)
	(segment
		(start 115.409726 -210.375246)
		(end 155.964382 -177.121312)
		(width 0.14224)
		(layer "In4.Cu")
		(net "GMI_CPU1_G2_CPU0_G0_TX_DN<0>")
	)
	(segment
		(start 358.123998 -228.771704)
		(end 358.093518 -228.789484)
		(width 0.1143)
		(layer "In4.Cu")
		(net "GMI_CPU1_G2_CPU0_G0_TX_DN<0>")
	)
	(segment
		(start 166.65194 -173.987206)
		(end 200.696322 -174.186342)
		(width 0.14224)
		(layer "In4.Cu")
		(net "GMI_CPU1_G2_CPU0_G0_TX_DN<0>")
	)
	(segment
		(start 357.655114 -229.580694)
		(end 357.651304 -229.583234)
		(width 0.1143)
		(layer "In4.Cu")
		(net "GMI_CPU1_G2_CPU0_G0_TX_DN<0>")
	)
	(segment
		(start 113.402364 -228.789738)
		(end 113.371884 -228.771958)
		(width 0.1143)
		(layer "In4.Cu")
		(net "GMI_CPU1_G2_CPU0_G0_TX_DN<0>")
	)
	(segment
		(start 359.465372 -221.17431)
		(end 359.465372 -221.202758)
		(width 0.1143)
		(layer "In4.Cu")
		(net "GMI_CPU1_G2_CPU0_G0_TX_DN<0>")
	)
	(segment
		(start 357.180642 -230.393494)
		(end 357.17988 -230.394002)
		(width 0.1143)
		(layer "In4.Cu")
		(net "GMI_CPU1_G2_CPU0_G0_TX_DN<0>")
	)
	(segment
		(start 357.6955 -229.557326)
		(end 357.695246 -229.557326)
		(width 0.1143)
		(layer "In4.Cu")
		(net "GMI_CPU1_G2_CPU0_G0_TX_DN<0>")
	)
	(segment
		(start 357.17988 -230.394002)
		(end 357.178864 -230.39451)
		(width 0.1143)
		(layer "In4.Cu")
		(net "GMI_CPU1_G2_CPU0_G0_TX_DN<0>")
	)
	(segment
		(start 113.844578 -229.583488)
		(end 113.840768 -229.580948)
		(width 0.1143)
		(layer "In4.Cu")
		(net "GMI_CPU1_G2_CPU0_G0_TX_DN<0>")
	)
	(segment
		(start 358.16032 -228.750622)
		(end 358.123998 -228.771704)
		(width 0.1143)
		(layer "In4.Cu")
		(net "GMI_CPU1_G2_CPU0_G0_TX_DN<0>")
	)
	(segment
		(start 359.465372 -221.202758)
		(end 359.419652 -221.248478)
		(width 0.1143)
		(layer "In4.Cu")
		(net "GMI_CPU1_G2_CPU0_G0_TX_DN<0>")
	)
	(segment
		(start 112.93729 -227.982272)
		(end 112.901984 -227.961698)
		(width 0.1143)
		(layer "In4.Cu")
		(net "GMI_CPU1_G2_CPU0_G0_TX_DN<0>")
	)
	(segment
		(start 112.298734 -227.384864)
		(end 112.298734 -222.253048)
		(width 0.1143)
		(layer "In4.Cu")
		(net "GMI_CPU1_G2_CPU0_G0_TX_DN<0>")
	)
	(segment
		(start 114.12474 -230.71455)
		(end 114.422682 -230.71455)
		(width 0.1143)
		(layer "In4.Cu")
		(net "GMI_CPU1_G2_CPU0_G0_TX_DN<0>")
	)
	(segment
		(start 357.002842 -230.644192)
		(end 357.003096 -230.644192)
		(width 0.1143)
		(layer "In4.Cu")
		(net "GMI_CPU1_G2_CPU0_G0_TX_DN<0>")
	)
	(segment
		(start 164.728906 -173.987206)
		(end 166.65194 -173.987206)
		(width 0.14224)
		(layer "In4.Cu")
		(net "GMI_CPU1_G2_CPU0_G0_TX_DN<0>")
	)
	(segment
		(start 114.422682 -230.71455)
		(end 114.492786 -230.644446)
		(width 0.1143)
		(layer "In4.Cu")
		(net "GMI_CPU1_G2_CPU0_G0_TX_DN<0>")
	)
	(segment
		(start 112.07623 -221.715838)
		(end 112.07623 -221.129098)
		(width 0.1143)
		(layer "In4.Cu")
		(net "GMI_CPU1_G2_CPU0_G0_TX_DN<0>")
	)
	(segment
		(start 358.815132 -227.766626)
		(end 358.709214 -227.872544)
		(width 0.1143)
		(layer "In4.Cu")
		(net "GMI_CPU1_G2_CPU0_G0_TX_DN<0>")
	)
	(segment
		(start 358.593898 -227.961444)
		(end 358.558592 -227.982018)
		(width 0.1143)
		(layer "In4.Cu")
		(net "GMI_CPU1_G2_CPU0_G0_TX_DN<0>")
	)
	(segment
		(start 359.153968 -222.800926)
		(end 359.153968 -227.09886)
		(width 0.1143)
		(layer "In4.Cu")
		(net "GMI_CPU1_G2_CPU0_G0_TX_DN<0>")
	)
	(segment
		(start 113.800636 -229.55758)
		(end 113.800382 -229.55758)
		(width 0.1143)
		(layer "In4.Cu")
		(net "GMI_CPU1_G2_CPU0_G0_TX_DN<0>")
	)
	(segment
		(start 112.03051 -221.083378)
		(end 112.03051 -221.05493)
		(width 0.1143)
		(layer "In4.Cu")
		(net "GMI_CPU1_G2_CPU0_G0_TX_DN<0>")
	)
	(segment
		(start 113.846102 -229.583996)
		(end 113.844578 -229.583488)
		(width 0.1143)
		(layer "In4.Cu")
		(net "GMI_CPU1_G2_CPU0_G0_TX_DN<0>")
	)
	(segment
		(start 355.997764 -210.38312)
		(end 359.465372 -216.223342)
		(width 0.14224)
		(layer "In4.Cu")
		(net "GMI_CPU1_G2_CPU0_G0_TX_DN<0>")
	)
	(segment
		(start 113.371884 -228.771958)
		(end 113.335562 -228.750876)
		(width 0.1143)
		(layer "In4.Cu")
		(net "GMI_CPU1_G2_CPU0_G0_TX_DN<0>")
	)
	(segment
		(start 112.03051 -221.05493)
		(end 112.03051 -216.123266)
		(width 0.14224)
		(layer "In4.Cu")
		(net "GMI_CPU1_G2_CPU0_G0_TX_DN<0>")
	)
	(segment
		(start 318.563752 -179.688236)
		(end 355.997764 -210.38312)
		(width 0.14224)
		(layer "In4.Cu")
		(net "GMI_CPU1_G2_CPU0_G0_TX_DN<0>")
	)
	(segment
		(start 357.0732 -230.714296)
		(end 357.371142 -230.714296)
		(width 0.1143)
		(layer "In4.Cu")
		(net "GMI_CPU1_G2_CPU0_G0_TX_DN<0>")
	)
	(segment
		(start 112.07623 -221.129098)
		(end 112.03051 -221.083378)
		(width 0.1143)
		(layer "In4.Cu")
		(net "GMI_CPU1_G2_CPU0_G0_TX_DN<0>")
	)
	(segment
		(start 359.40492 -221.48165)
		(end 359.165144 -222.687388)
		(width 0.1143)
		(layer "In4.Cu")
		(net "GMI_CPU1_G2_CPU0_G0_TX_DN<0>")
	)
	(segment
		(start 112.298734 -222.253048)
		(end 112.07623 -221.715838)
		(width 0.1143)
		(layer "In4.Cu")
		(net "GMI_CPU1_G2_CPU0_G0_TX_DN<0>")
	)
	(segment
		(start 114.316002 -230.394256)
		(end 114.31524 -230.393748)
		(width 0.1143)
		(layer "In4.Cu")
		(net "GMI_CPU1_G2_CPU0_G0_TX_DN<0>")
	)
	(segment
		(start 311.920382 -175.927512)
		(end 318.563752 -179.688236)
		(width 0.14224)
		(layer "In4.Cu")
		(net "GMI_CPU1_G2_CPU0_G0_TX_DN<0>")
	)
	(segment
		(start 359.419652 -221.248478)
		(end 359.419652 -221.330774)
		(width 0.1143)
		(layer "In4.Cu")
		(net "GMI_CPU1_G2_CPU0_G0_TX_DN<0>")
	)
	(segment
		(start 112.03051 -216.123266)
		(end 115.409726 -210.375246)
		(width 0.14224)
		(layer "In4.Cu")
		(net "GMI_CPU1_G2_CPU0_G0_TX_DN<0>")
	)
	(segment
		(start 357.003096 -230.644192)
		(end 357.0732 -230.714296)
		(width 0.1143)
		(layer "In4.Cu")
		(net "GMI_CPU1_G2_CPU0_G0_TX_DN<0>")
	)
	(segment
		(start 357.651304 -229.583234)
		(end 357.64978 -229.583742)
		(width 0.1143)
		(layer "In4.Cu")
		(net "GMI_CPU1_G2_CPU0_G0_TX_DN<0>")
	)
	(segment
		(start 200.696576 -174.186342)
		(end 302.9204 -174.784512)
		(width 0.14224)
		(layer "In4.Cu")
		(net "GMI_CPU1_G2_CPU0_G0_TX_DN<0>")
	)
	(segment
		(start 112.786668 -227.872798)
		(end 112.298734 -227.384864)
		(width 0.1143)
		(layer "In4.Cu")
		(net "GMI_CPU1_G2_CPU0_G0_TX_DN<0>")
	)
	(segment
		(start 359.465372 -216.223342)
		(end 359.465372 -221.17431)
		(width 0.14224)
		(layer "In4.Cu")
		(net "GMI_CPU1_G2_CPU0_G0_TX_DN<0>")
	)
	(segment
		(start 114.492786 -230.644446)
		(end 114.49304 -230.644446)
		(width 0.1143)
		(layer "In4.Cu")
		(net "GMI_CPU1_G2_CPU0_G0_TX_DN<0>")
	)
	(segment
		(start 113.840768 -229.580948)
		(end 113.800636 -229.55758)
		(width 0.1143)
		(layer "In4.Cu")
		(net "GMI_CPU1_G2_CPU0_G0_TX_DN<0>")
	)
	(segment
		(start 357.178864 -230.39451)
		(end 357.154226 -230.408734)
		(width 0.1143)
		(layer "In4.Cu")
		(net "GMI_CPU1_G2_CPU0_G0_TX_DN<0>")
	)
	(segment
		(start 112.786414 -227.872798)
		(end 112.786668 -227.872798)
		(width 0.1143)
		(layer "In4.Cu")
		(net "GMI_CPU1_G2_CPU0_G0_TX_DN<0>")
	)
	(segment
		(start 155.964382 -177.121312)
		(end 164.728906 -173.987206)
		(width 0.14224)
		(layer "In4.Cu")
		(net "GMI_CPU1_G2_CPU0_G0_TX_DN<0>")
	)
	(arc
		(start 113.08969 -228.284024)
		(mid 113.049499 -228.11495)
		(end 112.93729 -227.982272)
		(width 0.1143)
		(layer "In4.Cu")
		(net "GMI_CPU1_G2_CPU0_G0_TX_DN<0>")
	)
	(arc
		(start 114.31524 -230.393748)
		(mid 114.107033 -230.187662)
		(end 114.03076 -229.904798)
		(width 0.1143)
		(layer "In4.Cu")
		(net "GMI_CPU1_G2_CPU0_G0_TX_DN<0>")
	)
	(arc
		(start 359.127552 -227.265992)
		(mid 359.000025 -227.534207)
		(end 358.815132 -227.766626)
		(width 0.1143)
		(layer "In4.Cu")
		(net "GMI_CPU1_G2_CPU0_G0_TX_DN<0>")
	)
	(arc
		(start 357.64978 -229.583742)
		(mid 357.51462 -229.719481)
		(end 357.465122 -229.904544)
		(width 0.1143)
		(layer "In4.Cu")
		(net "GMI_CPU1_G2_CPU0_G0_TX_DN<0>")
	)
	(arc
		(start 114.03076 -229.904798)
		(mid 113.981307 -229.719709)
		(end 113.846102 -229.583996)
		(width 0.1143)
		(layer "In4.Cu")
		(net "GMI_CPU1_G2_CPU0_G0_TX_DN<0>")
	)
	(arc
		(start 113.559336 -229.094538)
		(mid 113.517787 -228.923116)
		(end 113.402364 -228.789738)
		(width 0.1143)
		(layer "In4.Cu")
		(net "GMI_CPU1_G2_CPU0_G0_TX_DN<0>")
	)
	(arc
		(start 359.419652 -221.330774)
		(mid 359.416 -221.406575)
		(end 359.40492 -221.48165)
		(width 0.1143)
		(layer "In4.Cu")
		(net "GMI_CPU1_G2_CPU0_G0_TX_DN<0>")
	)
	(arc
		(start 358.709468 -227.872544)
		(mid 358.654568 -227.920744)
		(end 358.593898 -227.961444)
		(width 0.1143)
		(layer "In4.Cu")
		(net "GMI_CPU1_G2_CPU0_G0_TX_DN<0>")
	)
	(arc
		(start 113.335562 -228.750876)
		(mid 113.154791 -228.547907)
		(end 113.08969 -228.284024)
		(width 0.1143)
		(layer "In4.Cu")
		(net "GMI_CPU1_G2_CPU0_G0_TX_DN<0>")
	)
	(arc
		(start 357.465122 -229.904544)
		(mid 357.388895 -230.187435)
		(end 357.180642 -230.393494)
		(width 0.1143)
		(layer "In4.Cu")
		(net "GMI_CPU1_G2_CPU0_G0_TX_DN<0>")
	)
	(arc
		(start 112.901984 -227.961698)
		(mid 112.841306 -227.921009)
		(end 112.786414 -227.872798)
		(width 0.1143)
		(layer "In4.Cu")
		(net "GMI_CPU1_G2_CPU0_G0_TX_DN<0>")
	)
	(arc
		(start 359.153968 -227.09886)
		(mid 359.147445 -227.183483)
		(end 359.127552 -227.265992)
		(width 0.1143)
		(layer "In4.Cu")
		(net "GMI_CPU1_G2_CPU0_G0_TX_DN<0>")
	)
	(arc
		(start 359.165144 -222.687388)
		(mid 359.15677 -222.743883)
		(end 359.153968 -222.800926)
		(width 0.1143)
		(layer "In4.Cu")
		(net "GMI_CPU1_G2_CPU0_G0_TX_DN<0>")
	)
	(arc
		(start 358.558592 -227.982018)
		(mid 358.446463 -228.114736)
		(end 358.406192 -228.28377)
		(width 0.1143)
		(layer "In4.Cu")
		(net "GMI_CPU1_G2_CPU0_G0_TX_DN<0>")
	)
	(arc
		(start 114.49304 -230.644446)
		(mid 114.440155 -230.512051)
		(end 114.341656 -230.408988)
		(width 0.1143)
		(layer "In4.Cu")
		(net "GMI_CPU1_G2_CPU0_G0_TX_DN<0>")
	)
	(arc
		(start 113.800382 -229.55758)
		(mid 113.62317 -229.355563)
		(end 113.559336 -229.094538)
		(width 0.1143)
		(layer "In4.Cu")
		(net "GMI_CPU1_G2_CPU0_G0_TX_DN<0>")
	)
	(arc
		(start 358.406192 -228.28377)
		(mid 358.341075 -228.547644)
		(end 358.16032 -228.750622)
		(width 0.1143)
		(layer "In4.Cu")
		(net "GMI_CPU1_G2_CPU0_G0_TX_DN<0>")
	)
	(arc
		(start 357.154226 -230.408734)
		(mid 357.055749 -230.511811)
		(end 357.002842 -230.644192)
		(width 0.1143)
		(layer "In4.Cu")
		(net "GMI_CPU1_G2_CPU0_G0_TX_DN<0>")
	)
	(arc
		(start 357.936546 -229.094284)
		(mid 357.872667 -229.355285)
		(end 357.6955 -229.557326)
		(width 0.1143)
		(layer "In4.Cu")
		(net "GMI_CPU1_G2_CPU0_G0_TX_DN<0>")
	)
	(arc
		(start 358.093518 -228.789484)
		(mid 357.978091 -228.92286)
		(end 357.936546 -229.094284)
		(width 0.1143)
		(layer "In4.Cu")
		(net "GMI_CPU1_G2_CPU0_G0_TX_DN<0>")
	)
	(segment
		(start 107.547918 -241.510312)
		(end 107.081066 -241.244374)
		(width 0.12954)
		(layer "F.Cu")
		(net "GMI_CPU1_G0_CPU0_G2_TX_DP<9>")
	)
	(segment
		(start 363.947964 -241.510058)
		(end 364.414816 -241.24412)
		(width 0.12954)
		(layer "F.Cu")
		(net "GMI_CPU1_G0_CPU0_G2_TX_DP<9>")
	)
	(segment
		(start 112.344454 -221.248732)
		(end 112.390174 -221.203012)
		(width 0.1143)
		(layer "In6.Cu")
		(net "GMI_CPU1_G0_CPU0_G2_TX_DP<9>")
	)
	(segment
		(start 364.314232 -240.42751)
		(end 364.314232 -240.430812)
		(width 0.1143)
		(layer "In6.Cu")
		(net "GMI_CPU1_G0_CPU0_G2_TX_DP<9>")
	)
	(segment
		(start 169.830242 -184.775094)
		(end 169.965624 -184.64149)
		(width 0.14224)
		(layer "In6.Cu")
		(net "GMI_CPU1_G0_CPU0_G2_TX_DP<9>")
	)
	(segment
		(start 167.95242 -184.751218)
		(end 167.95242 -184.751472)
		(width 0.14224)
		(layer "In6.Cu")
		(net "GMI_CPU1_G0_CPU0_G2_TX_DP<9>")
	)
	(segment
		(start 362.2675 -232.647236)
		(end 362.251498 -232.656888)
		(width 0.1143)
		(layer "In6.Cu")
		(net "GMI_CPU1_G0_CPU0_G2_TX_DP<9>")
	)
	(segment
		(start 109.243622 -227.1522)
		(end 109.244638 -227.151438)
		(width 0.1143)
		(layer "In6.Cu")
		(net "GMI_CPU1_G0_CPU0_G2_TX_DP<9>")
	)
	(segment
		(start 362.218224 -231.05618)
		(end 362.21543 -231.057704)
		(width 0.1143)
		(layer "In6.Cu")
		(net "GMI_CPU1_G0_CPU0_G2_TX_DP<9>")
	)
	(segment
		(start 109.283246 -235.229146)
		(end 109.310932 -235.20908)
		(width 0.1143)
		(layer "In6.Cu")
		(net "GMI_CPU1_G0_CPU0_G2_TX_DP<9>")
	)
	(segment
		(start 106.783124 -241.244374)
		(end 106.713274 -241.174524)
		(width 0.1143)
		(layer "In6.Cu")
		(net "GMI_CPU1_G0_CPU0_G2_TX_DP<9>")
	)
	(segment
		(start 107.803442 -237.69955)
		(end 107.833922 -237.68177)
		(width 0.1143)
		(layer "In6.Cu")
		(net "GMI_CPU1_G0_CPU0_G2_TX_DP<9>")
	)
	(segment
		(start 173.526958 -184.662572)
		(end 302.885856 -185.41492)
		(width 0.14224)
		(layer "In6.Cu")
		(net "GMI_CPU1_G0_CPU0_G2_TX_DP<9>")
	)
	(segment
		(start 172.838364 -184.658254)
		(end 172.972222 -184.79389)
		(width 0.14224)
		(layer "In6.Cu")
		(net "GMI_CPU1_G0_CPU0_G2_TX_DP<9>")
	)
	(segment
		(start 109.243368 -232.012236)
		(end 109.24413 -232.011728)
		(width 0.1143)
		(layer "In6.Cu")
		(net "GMI_CPU1_G0_CPU0_G2_TX_DP<9>")
	)
	(segment
		(start 362.217208 -230.371396)
		(end 362.283502 -230.410004)
		(width 0.1143)
		(layer "In6.Cu")
		(net "GMI_CPU1_G0_CPU0_G2_TX_DP<9>")
	)
	(segment
		(start 109.283246 -234.299506)
		(end 109.244384 -234.277154)
		(width 0.1143)
		(layer "In6.Cu")
		(net "GMI_CPU1_G0_CPU0_G2_TX_DP<9>")
	)
	(segment
		(start 109.21238 -234.258358)
		(end 109.21238 -234.258612)
		(width 0.1143)
		(layer "In6.Cu")
		(net "GMI_CPU1_G0_CPU0_G2_TX_DP<9>")
	)
	(segment
		(start 122.901456 -210.937602)
		(end 123.948698 -210.237832)
		(width 0.14224)
		(layer "In6.Cu")
		(net "GMI_CPU1_G0_CPU0_G2_TX_DP<9>")
	)
	(segment
		(start 109.24413 -227.797106)
		(end 109.21238 -227.778818)
		(width 0.1143)
		(layer "In6.Cu")
		(net "GMI_CPU1_G0_CPU0_G2_TX_DP<9>")
	)
	(segment
		(start 364.13186 -239.136682)
		(end 364.100364 -239.15497)
		(width 0.1143)
		(layer "In6.Cu")
		(net "GMI_CPU1_G0_CPU0_G2_TX_DP<9>")
	)
	(segment
		(start 306.148232 -185.41492)
		(end 306.860702 -185.6105)
		(width 0.14224)
		(layer "In6.Cu")
		(net "GMI_CPU1_G0_CPU0_G2_TX_DP<9>")
	)
	(segment
		(start 359.105708 -220.798898)
		(end 359.105708 -221.17431)
		(width 0.14224)
		(layer "In6.Cu")
		(net "GMI_CPU1_G0_CPU0_G2_TX_DP<9>")
	)
	(segment
		(start 163.714176 -186.528964)
		(end 164.077396 -186.319414)
		(width 0.14224)
		(layer "In6.Cu")
		(net "GMI_CPU1_G0_CPU0_G2_TX_DP<9>")
	)
	(segment
		(start 109.24413 -232.011728)
		(end 109.245654 -232.010966)
		(width 0.1143)
		(layer "In6.Cu")
		(net "GMI_CPU1_G0_CPU0_G2_TX_DP<9>")
	)
	(segment
		(start 312.290968 -189.607952)
		(end 352.9965 -214.957914)
		(width 0.14224)
		(layer "In6.Cu")
		(net "GMI_CPU1_G0_CPU0_G2_TX_DP<9>")
	)
	(segment
		(start 109.21238 -232.638346)
		(end 109.21238 -232.6386)
		(width 0.1143)
		(layer "In6.Cu")
		(net "GMI_CPU1_G0_CPU0_G2_TX_DP<9>")
	)
	(segment
		(start 109.280452 -235.917994)
		(end 109.24413 -235.896912)
		(width 0.1143)
		(layer "In6.Cu")
		(net "GMI_CPU1_G0_CPU0_G2_TX_DP<9>")
	)
	(segment
		(start 362.251498 -234.2769)
		(end 362.212636 -234.299252)
		(width 0.1143)
		(layer "In6.Cu")
		(net "GMI_CPU1_G0_CPU0_G2_TX_DP<9>")
	)
	(segment
		(start 124.521214 -209.855054)
		(end 133.886702 -203.596494)
		(width 0.14224)
		(layer "In6.Cu")
		(net "GMI_CPU1_G0_CPU0_G2_TX_DP<9>")
	)
	(segment
		(start 362.283502 -234.258104)
		(end 362.2675 -234.267248)
		(width 0.1143)
		(layer "In6.Cu")
		(net "GMI_CPU1_G0_CPU0_G2_TX_DP<9>")
	)
	(segment
		(start 362.251752 -232.011474)
		(end 362.252514 -232.011982)
		(width 0.1143)
		(layer "In6.Cu")
		(net "GMI_CPU1_G0_CPU0_G2_TX_DP<9>")
	)
	(segment
		(start 107.364022 -239.136936)
		(end 107.36326 -239.136428)
		(width 0.1143)
		(layer "In6.Cu")
		(net "GMI_CPU1_G0_CPU0_G2_TX_DP<9>")
	)
	(segment
		(start 107.081066 -241.244374)
		(end 106.783124 -241.244374)
		(width 0.1143)
		(layer "In6.Cu")
		(net "GMI_CPU1_G0_CPU0_G2_TX_DP<9>")
	)
	(segment
		(start 362.28528 -229.397052)
		(end 362.218224 -229.436168)
		(width 0.1143)
		(layer "In6.Cu")
		(net "GMI_CPU1_G0_CPU0_G2_TX_DP<9>")
	)
	(segment
		(start 109.244384 -232.657142)
		(end 109.228382 -232.64749)
		(width 0.1143)
		(layer "In6.Cu")
		(net "GMI_CPU1_G0_CPU0_G2_TX_DP<9>")
	)
	(segment
		(start 363.622844 -237.658656)
		(end 363.69244 -237.699296)
		(width 0.1143)
		(layer "In6.Cu")
		(net "GMI_CPU1_G0_CPU0_G2_TX_DP<9>")
	)
	(segment
		(start 358.7877 -220.031564)
		(end 359.105708 -220.798898)
		(width 0.14224)
		(layer "In6.Cu")
		(net "GMI_CPU1_G0_CPU0_G2_TX_DP<9>")
	)
	(segment
		(start 352.9965 -214.957914)
		(end 356.478078 -217.722704)
		(width 0.14224)
		(layer "In6.Cu")
		(net "GMI_CPU1_G0_CPU0_G2_TX_DP<9>")
	)
	(segment
		(start 362.283502 -234.258358)
		(end 362.283502 -234.258104)
		(width 0.1143)
		(layer "In6.Cu")
		(net "GMI_CPU1_G0_CPU0_G2_TX_DP<9>")
	)
	(segment
		(start 107.833922 -237.68177)
		(end 107.873038 -237.65891)
		(width 0.1143)
		(layer "In6.Cu")
		(net "GMI_CPU1_G0_CPU0_G2_TX_DP<9>")
	)
	(segment
		(start 107.395518 -239.155224)
		(end 107.364022 -239.136936)
		(width 0.1143)
		(layer "In6.Cu")
		(net "GMI_CPU1_G0_CPU0_G2_TX_DP<9>")
	)
	(segment
		(start 362.251752 -228.771704)
		(end 362.283502 -228.789992)
		(width 0.1143)
		(layer "In6.Cu")
		(net "GMI_CPU1_G0_CPU0_G2_TX_DP<9>")
	)
	(segment
		(start 109.310932 -232.69956)
		(end 109.283246 -232.679494)
		(width 0.1143)
		(layer "In6.Cu")
		(net "GMI_CPU1_G0_CPU0_G2_TX_DP<9>")
	)
	(segment
		(start 107.36326 -238.492284)
		(end 107.364022 -238.491776)
		(width 0.1143)
		(layer "In6.Cu")
		(net "GMI_CPU1_G0_CPU0_G2_TX_DP<9>")
	)
	(segment
		(start 109.280452 -227.818188)
		(end 109.24413 -227.797106)
		(width 0.1143)
		(layer "In6.Cu")
		(net "GMI_CPU1_G0_CPU0_G2_TX_DP<9>")
	)
	(segment
		(start 171.312078 -184.649364)
		(end 171.730924 -184.65165)
		(width 0.14224)
		(layer "In6.Cu")
		(net "GMI_CPU1_G0_CPU0_G2_TX_DP<9>")
	)
	(segment
		(start 364.712758 -241.24412)
		(end 364.414816 -241.24412)
		(width 0.1143)
		(layer "In6.Cu")
		(net "GMI_CPU1_G0_CPU0_G2_TX_DP<9>")
	)
	(segment
		(start 364.16361 -239.118394)
		(end 364.132622 -239.136174)
		(width 0.1143)
		(layer "In6.Cu")
		(net "GMI_CPU1_G0_CPU0_G2_TX_DP<9>")
	)
	(segment
		(start 107.36326 -240.112042)
		(end 107.364022 -240.111788)
		(width 0.1143)
		(layer "In6.Cu")
		(net "GMI_CPU1_G0_CPU0_G2_TX_DP<9>")
	)
	(segment
		(start 109.245654 -232.010966)
		(end 109.280452 -231.990646)
		(width 0.1143)
		(layer "In6.Cu")
		(net "GMI_CPU1_G0_CPU0_G2_TX_DP<9>")
	)
	(segment
		(start 164.077396 -186.319414)
		(end 164.126672 -186.135264)
		(width 0.14224)
		(layer "In6.Cu")
		(net "GMI_CPU1_G0_CPU0_G2_TX_DP<9>")
	)
	(segment
		(start 359.105708 -221.202758)
		(end 359.151428 -221.248478)
		(width 0.1143)
		(layer "In6.Cu")
		(net "GMI_CPU1_G0_CPU0_G2_TX_DP<9>")
	)
	(segment
		(start 359.105708 -221.17431)
		(end 359.105708 -221.202758)
		(width 0.1143)
		(layer "In6.Cu")
		(net "GMI_CPU1_G0_CPU0_G2_TX_DP<9>")
	)
	(segment
		(start 362.21543 -228.750622)
		(end 362.251752 -228.771704)
		(width 0.1143)
		(layer "In6.Cu")
		(net "GMI_CPU1_G0_CPU0_G2_TX_DP<9>")
	)
	(segment
		(start 109.280452 -231.057958)
		(end 109.24413 -231.036876)
		(width 0.1143)
		(layer "In6.Cu")
		(net "GMI_CPU1_G0_CPU0_G2_TX_DP<9>")
	)
	(segment
		(start 362.251244 -227.151184)
		(end 362.25226 -227.151946)
		(width 0.1143)
		(layer "In6.Cu")
		(net "GMI_CPU1_G0_CPU0_G2_TX_DP<9>")
	)
	(segment
		(start 361.744006 -226.319842)
		(end 361.7849 -226.34321)
		(width 0.1143)
		(layer "In6.Cu")
		(net "GMI_CPU1_G0_CPU0_G2_TX_DP<9>")
	)
	(segment
		(start 109.21238 -235.27004)
		(end 109.283246 -235.229146)
		(width 0.1143)
		(layer "In6.Cu")
		(net "GMI_CPU1_G0_CPU0_G2_TX_DP<9>")
	)
	(segment
		(start 109.24413 -235.896912)
		(end 109.21238 -235.878624)
		(width 0.1143)
		(layer "In6.Cu")
		(net "GMI_CPU1_G0_CPU0_G2_TX_DP<9>")
	)
	(segment
		(start 364.782608 -241.17427)
		(end 364.712758 -241.24412)
		(width 0.1143)
		(layer "In6.Cu")
		(net "GMI_CPU1_G0_CPU0_G2_TX_DP<9>")
	)
	(segment
		(start 167.856662 -184.916064)
		(end 167.95242 -184.751218)
		(width 0.14224)
		(layer "In6.Cu")
		(net "GMI_CPU1_G0_CPU0_G2_TX_DP<9>")
	)
	(segment
		(start 362.212636 -232.67924)
		(end 362.18495 -232.699306)
		(width 0.1143)
		(layer "In6.Cu")
		(net "GMI_CPU1_G0_CPU0_G2_TX_DP<9>")
	)
	(segment
		(start 362.18495 -235.208826)
		(end 362.212636 -235.228892)
		(width 0.1143)
		(layer "In6.Cu")
		(net "GMI_CPU1_G0_CPU0_G2_TX_DP<9>")
	)
	(segment
		(start 109.283246 -233.609134)
		(end 109.310932 -233.589068)
		(width 0.1143)
		(layer "In6.Cu")
		(net "GMI_CPU1_G0_CPU0_G2_TX_DP<9>")
	)
	(segment
		(start 364.130844 -240.111026)
		(end 364.13186 -240.111534)
		(width 0.1143)
		(layer "In6.Cu")
		(net "GMI_CPU1_G0_CPU0_G2_TX_DP<9>")
	)
	(segment
		(start 109.277658 -229.436422)
		(end 109.210602 -229.397306)
		(width 0.1143)
		(layer "In6.Cu")
		(net "GMI_CPU1_G0_CPU0_G2_TX_DP<9>")
	)
	(segment
		(start 112.757458 -219.98559)
		(end 117.087142 -215.65616)
		(width 0.14224)
		(layer "In6.Cu")
		(net "GMI_CPU1_G0_CPU0_G2_TX_DP<9>")
	)
	(segment
		(start 362.28528 -231.017064)
		(end 362.218224 -231.05618)
		(width 0.1143)
		(layer "In6.Cu")
		(net "GMI_CPU1_G0_CPU0_G2_TX_DP<9>")
	)
	(segment
		(start 310.884316 -188.418724)
		(end 312.290968 -189.607952)
		(width 0.14224)
		(layer "In6.Cu")
		(net "GMI_CPU1_G0_CPU0_G2_TX_DP<9>")
	)
	(segment
		(start 107.364022 -238.491776)
		(end 107.365038 -238.491268)
		(width 0.1143)
		(layer "In6.Cu")
		(net "GMI_CPU1_G0_CPU0_G2_TX_DP<9>")
	)
	(segment
		(start 163.53028 -186.479688)
		(end 163.714176 -186.528964)
		(width 0.14224)
		(layer "In6.Cu")
		(net "GMI_CPU1_G0_CPU0_G2_TX_DP<9>")
	)
	(segment
		(start 362.2675 -234.267248)
		(end 362.251498 -234.2769)
		(width 0.1143)
		(layer "In6.Cu")
		(net "GMI_CPU1_G0_CPU0_G2_TX_DP<9>")
	)
	(segment
		(start 165.313106 -185.45048)
		(end 167.286686 -184.927748)
		(width 0.14224)
		(layer "In6.Cu")
		(net "GMI_CPU1_G0_CPU0_G2_TX_DP<9>")
	)
	(segment
		(start 167.286686 -184.927748)
		(end 167.451278 -185.023506)
		(width 0.14224)
		(layer "In6.Cu")
		(net "GMI_CPU1_G0_CPU0_G2_TX_DP<9>")
	)
	(segment
		(start 107.364022 -240.111788)
		(end 107.365038 -240.11128)
		(width 0.1143)
		(layer "In6.Cu")
		(net "GMI_CPU1_G0_CPU0_G2_TX_DP<9>")
	)
	(segment
		(start 364.595918 -240.917984)
		(end 364.633764 -240.940082)
		(width 0.1143)
		(layer "In6.Cu")
		(net "GMI_CPU1_G0_CPU0_G2_TX_DP<9>")
	)
	(segment
		(start 167.451278 -185.023506)
		(end 167.856662 -184.916064)
		(width 0.14224)
		(layer "In6.Cu")
		(net "GMI_CPU1_G0_CPU0_G2_TX_DP<9>")
	)
	(segment
		(start 356.478078 -217.722704)
		(end 358.7877 -220.031564)
		(width 0.14224)
		(layer "In6.Cu")
		(net "GMI_CPU1_G0_CPU0_G2_TX_DP<9>")
	)
	(segment
		(start 163.118292 -186.873388)
		(end 163.167568 -186.689238)
		(width 0.14224)
		(layer "In6.Cu")
		(net "GMI_CPU1_G0_CPU0_G2_TX_DP<9>")
	)
	(segment
		(start 362.283502 -232.638092)
		(end 362.2675 -232.647236)
		(width 0.1143)
		(layer "In6.Cu")
		(net "GMI_CPU1_G0_CPU0_G2_TX_DP<9>")
	)
	(segment
		(start 364.092744 -238.468662)
		(end 364.130844 -238.491014)
		(width 0.1143)
		(layer "In6.Cu")
		(net "GMI_CPU1_G0_CPU0_G2_TX_DP<9>")
	)
	(segment
		(start 362.251498 -232.656888)
		(end 362.212636 -232.67924)
		(width 0.1143)
		(layer "In6.Cu")
		(net "GMI_CPU1_G0_CPU0_G2_TX_DP<9>")
	)
	(segment
		(start 307.347366 -185.899806)
		(end 310.884316 -188.418724)
		(width 0.14224)
		(layer "In6.Cu")
		(net "GMI_CPU1_G0_CPU0_G2_TX_DP<9>")
	)
	(segment
		(start 163.167568 -186.689238)
		(end 163.53028 -186.479688)
		(width 0.14224)
		(layer "In6.Cu")
		(net "GMI_CPU1_G0_CPU0_G2_TX_DP<9>")
	)
	(segment
		(start 302.885856 -185.41492)
		(end 306.148232 -185.41492)
		(width 0.14224)
		(layer "In6.Cu")
		(net "GMI_CPU1_G0_CPU0_G2_TX_DP<9>")
	)
	(segment
		(start 168.402762 -184.632092)
		(end 169.27703 -184.637172)
		(width 0.14224)
		(layer "In6.Cu")
		(net "GMI_CPU1_G0_CPU0_G2_TX_DP<9>")
	)
	(segment
		(start 133.886702 -203.596494)
		(end 161.272728 -187.78347)
		(width 0.14224)
		(layer "In6.Cu")
		(net "GMI_CPU1_G0_CPU0_G2_TX_DP<9>")
	)
	(segment
		(start 362.21543 -236.850428)
		(end 362.251752 -236.87151)
		(width 0.1143)
		(layer "In6.Cu")
		(net "GMI_CPU1_G0_CPU0_G2_TX_DP<9>")
	)
	(segment
		(start 112.344454 -221.661736)
		(end 112.344454 -221.248732)
		(width 0.1143)
		(layer "In6.Cu")
		(net "GMI_CPU1_G0_CPU0_G2_TX_DP<9>")
	)
	(segment
		(start 109.244384 -234.277154)
		(end 109.228382 -234.267502)
		(width 0.1143)
		(layer "In6.Cu")
		(net "GMI_CPU1_G0_CPU0_G2_TX_DP<9>")
	)
	(segment
		(start 362.18495 -233.588814)
		(end 362.212636 -233.60888)
		(width 0.1143)
		(layer "In6.Cu")
		(net "GMI_CPU1_G0_CPU0_G2_TX_DP<9>")
	)
	(segment
		(start 167.95242 -184.751472)
		(end 168.402762 -184.632092)
		(width 0.14224)
		(layer "In6.Cu")
		(net "GMI_CPU1_G0_CPU0_G2_TX_DP<9>")
	)
	(segment
		(start 362.212636 -233.60888)
		(end 362.283502 -233.649774)
		(width 0.1143)
		(layer "In6.Cu")
		(net "GMI_CPU1_G0_CPU0_G2_TX_DP<9>")
	)
	(segment
		(start 107.18165 -240.431066)
		(end 107.18165 -240.427764)
		(width 0.1143)
		(layer "In6.Cu")
		(net "GMI_CPU1_G0_CPU0_G2_TX_DP<9>")
	)
	(segment
		(start 361.7849 -226.34321)
		(end 361.785916 -226.343718)
		(width 0.1143)
		(layer "In6.Cu")
		(net "GMI_CPU1_G0_CPU0_G2_TX_DP<9>")
	)
	(segment
		(start 109.24413 -228.771958)
		(end 109.280452 -228.750876)
		(width 0.1143)
		(layer "In6.Cu")
		(net "GMI_CPU1_G0_CPU0_G2_TX_DP<9>")
	)
	(segment
		(start 363.183424 -236.866684)
		(end 363.223556 -236.889798)
		(width 0.1143)
		(layer "In6.Cu")
		(net "GMI_CPU1_G0_CPU0_G2_TX_DP<9>")
	)
	(segment
		(start 110.03915 -225.631502)
		(end 111.872268 -223.113092)
		(width 0.1143)
		(layer "In6.Cu")
		(net "GMI_CPU1_G0_CPU0_G2_TX_DP<9>")
	)
	(segment
		(start 171.730924 -184.65165)
		(end 171.864782 -184.787286)
		(width 0.14224)
		(layer "In6.Cu")
		(net "GMI_CPU1_G0_CPU0_G2_TX_DP<9>")
	)
	(segment
		(start 172.284136 -184.789826)
		(end 172.419518 -184.655968)
		(width 0.14224)
		(layer "In6.Cu")
		(net "GMI_CPU1_G0_CPU0_G2_TX_DP<9>")
	)
	(segment
		(start 172.419518 -184.655968)
		(end 172.838364 -184.658254)
		(width 0.14224)
		(layer "In6.Cu")
		(net "GMI_CPU1_G0_CPU0_G2_TX_DP<9>")
	)
	(segment
		(start 109.709966 -226.343972)
		(end 109.710982 -226.343464)
		(width 0.1143)
		(layer "In6.Cu")
		(net "GMI_CPU1_G0_CPU0_G2_TX_DP<9>")
	)
	(segment
		(start 109.310932 -234.319572)
		(end 109.283246 -234.299506)
		(width 0.1143)
		(layer "In6.Cu")
		(net "GMI_CPU1_G0_CPU0_G2_TX_DP<9>")
	)
	(segment
		(start 109.995716 -225.880168)
		(end 109.995716 -225.87966)
		(width 0.1143)
		(layer "In6.Cu")
		(net "GMI_CPU1_G0_CPU0_G2_TX_DP<9>")
	)
	(segment
		(start 364.099602 -239.155478)
		(end 364.092744 -239.159542)
		(width 0.1143)
		(layer "In6.Cu")
		(net "GMI_CPU1_G0_CPU0_G2_TX_DP<9>")
	)
	(segment
		(start 109.21238 -232.030016)
		(end 109.243368 -232.012236)
		(width 0.1143)
		(layer "In6.Cu")
		(net "GMI_CPU1_G0_CPU0_G2_TX_DP<9>")
	)
	(segment
		(start 360.762804 -224.7773)
		(end 361.258358 -225.272854)
		(width 0.1143)
		(layer "In6.Cu")
		(net "GMI_CPU1_G0_CPU0_G2_TX_DP<9>")
	)
	(segment
		(start 169.965624 -184.64149)
		(end 170.623484 -184.6453)
		(width 0.14224)
		(layer "In6.Cu")
		(net "GMI_CPU1_G0_CPU0_G2_TX_DP<9>")
	)
	(segment
		(start 164.126672 -186.135518)
		(end 165.313106 -185.45048)
		(width 0.14224)
		(layer "In6.Cu")
		(net "GMI_CPU1_G0_CPU0_G2_TX_DP<9>")
	)
	(segment
		(start 109.21238 -228.790246)
		(end 109.24413 -228.771958)
		(width 0.1143)
		(layer "In6.Cu")
		(net "GMI_CPU1_G0_CPU0_G2_TX_DP<9>")
	)
	(segment
		(start 108.272326 -236.890052)
		(end 108.304076 -236.871764)
		(width 0.1143)
		(layer "In6.Cu")
		(net "GMI_CPU1_G0_CPU0_G2_TX_DP<9>")
	)
	(segment
		(start 359.491534 -222.874586)
		(end 360.762804 -224.7773)
		(width 0.1143)
		(layer "In6.Cu")
		(net "GMI_CPU1_G0_CPU0_G2_TX_DP<9>")
	)
	(segment
		(start 359.151428 -221.248478)
		(end 359.151428 -222.053658)
		(width 0.1143)
		(layer "In6.Cu")
		(net "GMI_CPU1_G0_CPU0_G2_TX_DP<9>")
	)
	(segment
		(start 123.948698 -210.237832)
		(end 124.135388 -210.274916)
		(width 0.14224)
		(layer "In6.Cu")
		(net "GMI_CPU1_G0_CPU0_G2_TX_DP<9>")
	)
	(segment
		(start 362.212636 -235.228892)
		(end 362.283502 -235.269786)
		(width 0.1143)
		(layer "In6.Cu")
		(net "GMI_CPU1_G0_CPU0_G2_TX_DP<9>")
	)
	(segment
		(start 109.280452 -229.437946)
		(end 109.277658 -229.436422)
		(width 0.1143)
		(layer "In6.Cu")
		(net "GMI_CPU1_G0_CPU0_G2_TX_DP<9>")
	)
	(segment
		(start 362.283502 -235.87837)
		(end 362.251752 -235.896658)
		(width 0.1143)
		(layer "In6.Cu")
		(net "GMI_CPU1_G0_CPU0_G2_TX_DP<9>")
	)
	(segment
		(start 107.365038 -240.11128)
		(end 107.403138 -240.088928)
		(width 0.1143)
		(layer "In6.Cu")
		(net "GMI_CPU1_G0_CPU0_G2_TX_DP<9>")
	)
	(segment
		(start 109.228382 -232.64749)
		(end 109.21238 -232.638346)
		(width 0.1143)
		(layer "In6.Cu")
		(net "GMI_CPU1_G0_CPU0_G2_TX_DP<9>")
	)
	(segment
		(start 109.21238 -230.410258)
		(end 109.278674 -230.37165)
		(width 0.1143)
		(layer "In6.Cu")
		(net "GMI_CPU1_G0_CPU0_G2_TX_DP<9>")
	)
	(segment
		(start 109.212126 -227.170488)
		(end 109.243622 -227.1522)
		(width 0.1143)
		(layer "In6.Cu")
		(net "GMI_CPU1_G0_CPU0_G2_TX_DP<9>")
	)
	(segment
		(start 364.130844 -238.491014)
		(end 364.13186 -238.491522)
		(width 0.1143)
		(layer "In6.Cu")
		(net "GMI_CPU1_G0_CPU0_G2_TX_DP<9>")
	)
	(segment
		(start 364.13186 -238.491522)
		(end 364.132622 -238.49203)
		(width 0.1143)
		(layer "In6.Cu")
		(net "GMI_CPU1_G0_CPU0_G2_TX_DP<9>")
	)
	(segment
		(start 364.092744 -240.088674)
		(end 364.130844 -240.111026)
		(width 0.1143)
		(layer "In6.Cu")
		(net "GMI_CPU1_G0_CPU0_G2_TX_DP<9>")
	)
	(segment
		(start 362.253784 -232.012744)
		(end 362.283502 -232.029762)
		(width 0.1143)
		(layer "In6.Cu")
		(net "GMI_CPU1_G0_CPU0_G2_TX_DP<9>")
	)
	(segment
		(start 364.132622 -239.136174)
		(end 364.13186 -239.136682)
		(width 0.1143)
		(layer "In6.Cu")
		(net "GMI_CPU1_G0_CPU0_G2_TX_DP<9>")
	)
	(segment
		(start 306.860702 -185.6105)
		(end 307.347366 -185.899806)
		(width 0.14224)
		(layer "In6.Cu")
		(net "GMI_CPU1_G0_CPU0_G2_TX_DP<9>")
	)
	(segment
		(start 106.862118 -240.940336)
		(end 106.899964 -240.918238)
		(width 0.1143)
		(layer "In6.Cu")
		(net "GMI_CPU1_G0_CPU0_G2_TX_DP<9>")
	)
	(segment
		(start 109.283246 -232.679494)
		(end 109.244384 -232.657142)
		(width 0.1143)
		(layer "In6.Cu")
		(net "GMI_CPU1_G0_CPU0_G2_TX_DP<9>")
	)
	(segment
		(start 117.087142 -215.65616)
		(end 122.55246 -211.171028)
		(width 0.14224)
		(layer "In6.Cu")
		(net "GMI_CPU1_G0_CPU0_G2_TX_DP<9>")
	)
	(segment
		(start 171.176696 -184.783222)
		(end 171.312078 -184.649364)
		(width 0.14224)
		(layer "In6.Cu")
		(net "GMI_CPU1_G0_CPU0_G2_TX_DP<9>")
	)
	(segment
		(start 362.218224 -229.436168)
		(end 362.21543 -229.437692)
		(width 0.1143)
		(layer "In6.Cu")
		(net "GMI_CPU1_G0_CPU0_G2_TX_DP<9>")
	)
	(segment
		(start 162.755326 -187.082938)
		(end 163.118292 -186.873388)
		(width 0.14224)
		(layer "In6.Cu")
		(net "GMI_CPU1_G0_CPU0_G2_TX_DP<9>")
	)
	(segment
		(start 164.126672 -186.135264)
		(end 164.126672 -186.135518)
		(width 0.14224)
		(layer "In6.Cu")
		(net "GMI_CPU1_G0_CPU0_G2_TX_DP<9>")
	)
	(segment
		(start 170.757342 -184.780936)
		(end 171.176696 -184.783222)
		(width 0.14224)
		(layer "In6.Cu")
		(net "GMI_CPU1_G0_CPU0_G2_TX_DP<9>")
	)
	(segment
		(start 107.36326 -239.136428)
		(end 107.332272 -239.118648)
		(width 0.1143)
		(layer "In6.Cu")
		(net "GMI_CPU1_G0_CPU0_G2_TX_DP<9>")
	)
	(segment
		(start 170.623484 -184.6453)
		(end 170.757342 -184.780936)
		(width 0.14224)
		(layer "In6.Cu")
		(net "GMI_CPU1_G0_CPU0_G2_TX_DP<9>")
	)
	(segment
		(start 362.252514 -232.011982)
		(end 362.253784 -232.012744)
		(width 0.1143)
		(layer "In6.Cu")
		(net "GMI_CPU1_G0_CPU0_G2_TX_DP<9>")
	)
	(segment
		(start 362.250228 -232.010712)
		(end 362.251752 -232.011474)
		(width 0.1143)
		(layer "In6.Cu")
		(net "GMI_CPU1_G0_CPU0_G2_TX_DP<9>")
	)
	(segment
		(start 359.151428 -222.053658)
		(end 359.491534 -222.874586)
		(width 0.1143)
		(layer "In6.Cu")
		(net "GMI_CPU1_G0_CPU0_G2_TX_DP<9>")
	)
	(segment
		(start 107.403138 -239.159796)
		(end 107.39628 -239.155732)
		(width 0.1143)
		(layer "In6.Cu")
		(net "GMI_CPU1_G0_CPU0_G2_TX_DP<9>")
	)
	(segment
		(start 109.21238 -233.650028)
		(end 109.283246 -233.609134)
		(width 0.1143)
		(layer "In6.Cu")
		(net "GMI_CPU1_G0_CPU0_G2_TX_DP<9>")
	)
	(segment
		(start 172.972222 -184.79389)
		(end 173.391576 -184.79643)
		(width 0.14224)
		(layer "In6.Cu")
		(net "GMI_CPU1_G0_CPU0_G2_TX_DP<9>")
	)
	(segment
		(start 124.48413 -210.041744)
		(end 124.521214 -209.855054)
		(width 0.14224)
		(layer "In6.Cu")
		(net "GMI_CPU1_G0_CPU0_G2_TX_DP<9>")
	)
	(segment
		(start 108.304076 -236.871764)
		(end 108.312458 -236.866938)
		(width 0.1143)
		(layer "In6.Cu")
		(net "GMI_CPU1_G0_CPU0_G2_TX_DP<9>")
	)
	(segment
		(start 171.864782 -184.787286)
		(end 172.284136 -184.789826)
		(width 0.14224)
		(layer "In6.Cu")
		(net "GMI_CPU1_G0_CPU0_G2_TX_DP<9>")
	)
	(segment
		(start 364.13186 -240.111534)
		(end 364.132622 -240.111788)
		(width 0.1143)
		(layer "In6.Cu")
		(net "GMI_CPU1_G0_CPU0_G2_TX_DP<9>")
	)
	(segment
		(start 109.995716 -225.87966)
		(end 110.001812 -225.737928)
		(width 0.1143)
		(layer "In6.Cu")
		(net "GMI_CPU1_G0_CPU0_G2_TX_DP<9>")
	)
	(segment
		(start 362.251752 -227.796852)
		(end 362.21543 -227.817934)
		(width 0.1143)
		(layer "In6.Cu")
		(net "GMI_CPU1_G0_CPU0_G2_TX_DP<9>")
	)
	(segment
		(start 362.212636 -234.299252)
		(end 362.18495 -234.319318)
		(width 0.1143)
		(layer "In6.Cu")
		(net "GMI_CPU1_G0_CPU0_G2_TX_DP<9>")
	)
	(segment
		(start 109.228382 -234.267502)
		(end 109.21238 -234.258358)
		(width 0.1143)
		(layer "In6.Cu")
		(net "GMI_CPU1_G0_CPU0_G2_TX_DP<9>")
	)
	(segment
		(start 107.39628 -239.155732)
		(end 107.395518 -239.155224)
		(width 0.1143)
		(layer "In6.Cu")
		(net "GMI_CPU1_G0_CPU0_G2_TX_DP<9>")
	)
	(segment
		(start 362.283502 -227.778564)
		(end 362.251752 -227.796852)
		(width 0.1143)
		(layer "In6.Cu")
		(net "GMI_CPU1_G0_CPU0_G2_TX_DP<9>")
	)
	(segment
		(start 364.132622 -238.49203)
		(end 364.16361 -238.50981)
		(width 0.1143)
		(layer "In6.Cu")
		(net "GMI_CPU1_G0_CPU0_G2_TX_DP<9>")
	)
	(segment
		(start 107.332272 -238.510064)
		(end 107.36326 -238.492284)
		(width 0.1143)
		(layer "In6.Cu")
		(net "GMI_CPU1_G0_CPU0_G2_TX_DP<9>")
	)
	(segment
		(start 162.57143 -187.033662)
		(end 162.755326 -187.082938)
		(width 0.14224)
		(layer "In6.Cu")
		(net "GMI_CPU1_G0_CPU0_G2_TX_DP<9>")
	)
	(segment
		(start 112.390174 -221.203012)
		(end 112.390174 -221.174564)
		(width 0.1143)
		(layer "In6.Cu")
		(net "GMI_CPU1_G0_CPU0_G2_TX_DP<9>")
	)
	(segment
		(start 107.365038 -238.491268)
		(end 107.403138 -238.468916)
		(width 0.1143)
		(layer "In6.Cu")
		(net "GMI_CPU1_G0_CPU0_G2_TX_DP<9>")
	)
	(segment
		(start 122.55246 -211.171028)
		(end 122.901456 -210.937602)
		(width 0.14224)
		(layer "In6.Cu")
		(net "GMI_CPU1_G0_CPU0_G2_TX_DP<9>")
	)
	(segment
		(start 112.390174 -220.872812)
		(end 112.757458 -219.98559)
		(width 0.14224)
		(layer "In6.Cu")
		(net "GMI_CPU1_G0_CPU0_G2_TX_DP<9>")
	)
	(segment
		(start 362.25226 -227.151946)
		(end 362.283756 -227.170234)
		(width 0.1143)
		(layer "In6.Cu")
		(net "GMI_CPU1_G0_CPU0_G2_TX_DP<9>")
	)
	(segment
		(start 169.410888 -184.772808)
		(end 169.830242 -184.775094)
		(width 0.14224)
		(layer "In6.Cu")
		(net "GMI_CPU1_G0_CPU0_G2_TX_DP<9>")
	)
	(segment
		(start 173.391576 -184.79643)
		(end 173.526958 -184.662572)
		(width 0.14224)
		(layer "In6.Cu")
		(net "GMI_CPU1_G0_CPU0_G2_TX_DP<9>")
	)
	(segment
		(start 362.21543 -231.990392)
		(end 362.250228 -232.010712)
		(width 0.1143)
		(layer "In6.Cu")
		(net "GMI_CPU1_G0_CPU0_G2_TX_DP<9>")
	)
	(segment
		(start 112.390174 -221.174564)
		(end 112.390174 -220.872812)
		(width 0.14224)
		(layer "In6.Cu")
		(net "GMI_CPU1_G0_CPU0_G2_TX_DP<9>")
	)
	(segment
		(start 364.100364 -239.15497)
		(end 364.099602 -239.155478)
		(width 0.1143)
		(layer "In6.Cu")
		(net "GMI_CPU1_G0_CPU0_G2_TX_DP<9>")
	)
	(segment
		(start 161.272728 -187.78347)
		(end 162.57143 -187.033662)
		(width 0.14224)
		(layer "In6.Cu")
		(net "GMI_CPU1_G0_CPU0_G2_TX_DP<9>")
	)
	(segment
		(start 362.283502 -232.638346)
		(end 362.283502 -232.638092)
		(width 0.1143)
		(layer "In6.Cu")
		(net "GMI_CPU1_G0_CPU0_G2_TX_DP<9>")
	)
	(segment
		(start 362.251752 -235.896658)
		(end 362.21543 -235.91774)
		(width 0.1143)
		(layer "In6.Cu")
		(net "GMI_CPU1_G0_CPU0_G2_TX_DP<9>")
	)
	(segment
		(start 169.27703 -184.637172)
		(end 169.410888 -184.772808)
		(width 0.14224)
		(layer "In6.Cu")
		(net "GMI_CPU1_G0_CPU0_G2_TX_DP<9>")
	)
	(segment
		(start 124.135388 -210.274916)
		(end 124.48413 -210.041744)
		(width 0.14224)
		(layer "In6.Cu")
		(net "GMI_CPU1_G0_CPU0_G2_TX_DP<9>")
	)
	(segment
		(start 109.710982 -226.343464)
		(end 109.751368 -226.32035)
		(width 0.1143)
		(layer "In6.Cu")
		(net "GMI_CPU1_G0_CPU0_G2_TX_DP<9>")
	)
	(segment
		(start 109.24413 -231.036876)
		(end 109.210602 -231.017318)
		(width 0.1143)
		(layer "In6.Cu")
		(net "GMI_CPU1_G0_CPU0_G2_TX_DP<9>")
	)
	(segment
		(start 109.24413 -236.871764)
		(end 109.280452 -236.850682)
		(width 0.1143)
		(layer "In6.Cu")
		(net "GMI_CPU1_G0_CPU0_G2_TX_DP<9>")
	)
	(arc
		(start 111.872268 -223.113092)
		(mid 112.223441 -222.424854)
		(end 112.344454 -221.661736)
		(width 0.1143)
		(layer "In6.Cu")
		(net "GMI_CPU1_G0_CPU0_G2_TX_DP<9>")
	)
	(arc
		(start 109.294676 -236.840776)
		(mid 109.522059 -236.384338)
		(end 109.294676 -235.9279)
		(width 0.1143)
		(layer "In6.Cu")
		(net "GMI_CPU1_G0_CPU0_G2_TX_DP<9>")
	)
	(arc
		(start 108.11637 -237.194344)
		(mid 108.157625 -237.023373)
		(end 108.272326 -236.890052)
		(width 0.1143)
		(layer "In6.Cu")
		(net "GMI_CPU1_G0_CPU0_G2_TX_DP<9>")
	)
	(arc
		(start 362.21543 -231.057704)
		(mid 362.208664 -231.062481)
		(end 362.201968 -231.067356)
		(width 0.1143)
		(layer "In6.Cu")
		(net "GMI_CPU1_G0_CPU0_G2_TX_DP<9>")
	)
	(arc
		(start 109.21238 -234.258612)
		(mid 109.056452 -233.95432)
		(end 109.21238 -233.650028)
		(width 0.1143)
		(layer "In6.Cu")
		(net "GMI_CPU1_G0_CPU0_G2_TX_DP<9>")
	)
	(arc
		(start 362.201206 -228.740716)
		(mid 362.208279 -228.745725)
		(end 362.21543 -228.750622)
		(width 0.1143)
		(layer "In6.Cu")
		(net "GMI_CPU1_G0_CPU0_G2_TX_DP<9>")
	)
	(arc
		(start 109.056424 -229.094538)
		(mid 109.097679 -228.923567)
		(end 109.21238 -228.790246)
		(width 0.1143)
		(layer "In6.Cu")
		(net "GMI_CPU1_G0_CPU0_G2_TX_DP<9>")
	)
	(arc
		(start 109.294676 -227.828094)
		(mid 109.287602 -227.823087)
		(end 109.280452 -227.818188)
		(width 0.1143)
		(layer "In6.Cu")
		(net "GMI_CPU1_G0_CPU0_G2_TX_DP<9>")
	)
	(arc
		(start 361.969558 -231.537764)
		(mid 362.039878 -231.770228)
		(end 362.183934 -231.965754)
		(width 0.1143)
		(layer "In6.Cu")
		(net "GMI_CPU1_G0_CPU0_G2_TX_DP<9>")
	)
	(arc
		(start 361.785916 -226.343718)
		(mid 361.920388 -226.479556)
		(end 361.969558 -226.664266)
		(width 0.1143)
		(layer "In6.Cu")
		(net "GMI_CPU1_G0_CPU0_G2_TX_DP<9>")
	)
	(arc
		(start 362.201206 -227.82784)
		(mid 361.973823 -228.284278)
		(end 362.201206 -228.740716)
		(width 0.1143)
		(layer "In6.Cu")
		(net "GMI_CPU1_G0_CPU0_G2_TX_DP<9>")
	)
	(arc
		(start 109.293914 -231.06761)
		(mid 109.287219 -231.062734)
		(end 109.280452 -231.057958)
		(width 0.1143)
		(layer "In6.Cu")
		(net "GMI_CPU1_G0_CPU0_G2_TX_DP<9>")
	)
	(arc
		(start 362.283502 -228.789992)
		(mid 362.398178 -228.923326)
		(end 362.439458 -229.094284)
		(width 0.1143)
		(layer "In6.Cu")
		(net "GMI_CPU1_G0_CPU0_G2_TX_DP<9>")
	)
	(arc
		(start 361.258358 -225.272854)
		(mid 361.395828 -225.538603)
		(end 361.491784 -225.822002)
		(width 0.1143)
		(layer "In6.Cu")
		(net "GMI_CPU1_G0_CPU0_G2_TX_DP<9>")
	)
	(arc
		(start 109.21238 -227.778818)
		(mid 109.056452 -227.474703)
		(end 109.212126 -227.170488)
		(width 0.1143)
		(layer "In6.Cu")
		(net "GMI_CPU1_G0_CPU0_G2_TX_DP<9>")
	)
	(arc
		(start 109.311948 -231.966008)
		(mid 109.455989 -231.770474)
		(end 109.526324 -231.538018)
		(width 0.1143)
		(layer "In6.Cu")
		(net "GMI_CPU1_G0_CPU0_G2_TX_DP<9>")
	)
	(arc
		(start 362.283502 -230.410004)
		(mid 362.398178 -230.543338)
		(end 362.439458 -230.714296)
		(width 0.1143)
		(layer "In6.Cu")
		(net "GMI_CPU1_G0_CPU0_G2_TX_DP<9>")
	)
	(arc
		(start 109.526324 -231.538018)
		(mid 109.467988 -231.274245)
		(end 109.293914 -231.06761)
		(width 0.1143)
		(layer "In6.Cu")
		(net "GMI_CPU1_G0_CPU0_G2_TX_DP<9>")
	)
	(arc
		(start 109.751368 -226.32035)
		(mid 109.925227 -226.128951)
		(end 109.995716 -225.880168)
		(width 0.1143)
		(layer "In6.Cu")
		(net "GMI_CPU1_G0_CPU0_G2_TX_DP<9>")
	)
	(arc
		(start 364.633764 -240.940082)
		(mid 364.730691 -241.042877)
		(end 364.782608 -241.17427)
		(width 0.1143)
		(layer "In6.Cu")
		(net "GMI_CPU1_G0_CPU0_G2_TX_DP<9>")
	)
	(arc
		(start 363.379512 -237.19409)
		(mid 363.444027 -237.456309)
		(end 363.622844 -237.658656)
		(width 0.1143)
		(layer "In6.Cu")
		(net "GMI_CPU1_G0_CPU0_G2_TX_DP<9>")
	)
	(arc
		(start 363.849412 -238.004096)
		(mid 363.913927 -238.266315)
		(end 364.092744 -238.468662)
		(width 0.1143)
		(layer "In6.Cu")
		(net "GMI_CPU1_G0_CPU0_G2_TX_DP<9>")
	)
	(arc
		(start 109.210602 -231.017318)
		(mid 109.097195 -230.884429)
		(end 109.056424 -230.71455)
		(width 0.1143)
		(layer "In6.Cu")
		(net "GMI_CPU1_G0_CPU0_G2_TX_DP<9>")
	)
	(arc
		(start 109.294676 -228.74097)
		(mid 109.522059 -228.284532)
		(end 109.294676 -227.828094)
		(width 0.1143)
		(layer "In6.Cu")
		(net "GMI_CPU1_G0_CPU0_G2_TX_DP<9>")
	)
	(arc
		(start 110.001812 -225.737928)
		(mid 110.01262 -225.681955)
		(end 110.03915 -225.631502)
		(width 0.1143)
		(layer "In6.Cu")
		(net "GMI_CPU1_G0_CPU0_G2_TX_DP<9>")
	)
	(arc
		(start 109.294676 -235.9279)
		(mid 109.287602 -235.922893)
		(end 109.280452 -235.917994)
		(width 0.1143)
		(layer "In6.Cu")
		(net "GMI_CPU1_G0_CPU0_G2_TX_DP<9>")
	)
	(arc
		(start 109.21238 -235.878624)
		(mid 109.056452 -235.574332)
		(end 109.21238 -235.27004)
		(width 0.1143)
		(layer "In6.Cu")
		(net "GMI_CPU1_G0_CPU0_G2_TX_DP<9>")
	)
	(arc
		(start 109.278674 -230.37165)
		(mid 109.45029 -230.161739)
		(end 109.526324 -229.901496)
		(width 0.1143)
		(layer "In6.Cu")
		(net "GMI_CPU1_G0_CPU0_G2_TX_DP<9>")
	)
	(arc
		(start 362.201206 -236.840522)
		(mid 362.208279 -236.845531)
		(end 362.21543 -236.850428)
		(width 0.1143)
		(layer "In6.Cu")
		(net "GMI_CPU1_G0_CPU0_G2_TX_DP<9>")
	)
	(arc
		(start 362.21543 -235.91774)
		(mid 362.20828 -235.922638)
		(end 362.201206 -235.927646)
		(width 0.1143)
		(layer "In6.Cu")
		(net "GMI_CPU1_G0_CPU0_G2_TX_DP<9>")
	)
	(arc
		(start 107.18165 -240.427764)
		(mid 107.23029 -240.245648)
		(end 107.36326 -240.112042)
		(width 0.1143)
		(layer "In6.Cu")
		(net "GMI_CPU1_G0_CPU0_G2_TX_DP<9>")
	)
	(arc
		(start 361.491784 -225.822002)
		(mid 361.497489 -225.850739)
		(end 361.500166 -225.879914)
		(width 0.1143)
		(layer "In6.Cu")
		(net "GMI_CPU1_G0_CPU0_G2_TX_DP<9>")
	)
	(arc
		(start 109.280452 -228.750876)
		(mid 109.287601 -228.745976)
		(end 109.294676 -228.74097)
		(width 0.1143)
		(layer "In6.Cu")
		(net "GMI_CPU1_G0_CPU0_G2_TX_DP<9>")
	)
	(arc
		(start 362.18495 -232.699306)
		(mid 361.95695 -233.14406)
		(end 362.18495 -233.588814)
		(width 0.1143)
		(layer "In6.Cu")
		(net "GMI_CPU1_G0_CPU0_G2_TX_DP<9>")
	)
	(arc
		(start 107.332272 -239.118648)
		(mid 107.181887 -238.814356)
		(end 107.332272 -238.510064)
		(width 0.1143)
		(layer "In6.Cu")
		(net "GMI_CPU1_G0_CPU0_G2_TX_DP<9>")
	)
	(arc
		(start 107.403138 -238.468916)
		(mid 107.581951 -238.266566)
		(end 107.64647 -238.00435)
		(width 0.1143)
		(layer "In6.Cu")
		(net "GMI_CPU1_G0_CPU0_G2_TX_DP<9>")
	)
	(arc
		(start 109.526324 -226.66452)
		(mid 109.575485 -226.479804)
		(end 109.709966 -226.343972)
		(width 0.1143)
		(layer "In6.Cu")
		(net "GMI_CPU1_G0_CPU0_G2_TX_DP<9>")
	)
	(arc
		(start 107.64647 -238.00435)
		(mid 107.688019 -237.832928)
		(end 107.803442 -237.69955)
		(width 0.1143)
		(layer "In6.Cu")
		(net "GMI_CPU1_G0_CPU0_G2_TX_DP<9>")
	)
	(arc
		(start 106.899964 -240.918238)
		(mid 107.106166 -240.712442)
		(end 107.18165 -240.431066)
		(width 0.1143)
		(layer "In6.Cu")
		(net "GMI_CPU1_G0_CPU0_G2_TX_DP<9>")
	)
	(arc
		(start 362.201968 -231.067356)
		(mid 362.027754 -231.273922)
		(end 361.969558 -231.537764)
		(width 0.1143)
		(layer "In6.Cu")
		(net "GMI_CPU1_G0_CPU0_G2_TX_DP<9>")
	)
	(arc
		(start 109.310932 -235.20908)
		(mid 109.538932 -234.764326)
		(end 109.310932 -234.319572)
		(width 0.1143)
		(layer "In6.Cu")
		(net "GMI_CPU1_G0_CPU0_G2_TX_DP<9>")
	)
	(arc
		(start 362.817664 -236.87151)
		(mid 362.999915 -236.82116)
		(end 363.183424 -236.866684)
		(width 0.1143)
		(layer "In6.Cu")
		(net "GMI_CPU1_G0_CPU0_G2_TX_DP<9>")
	)
	(arc
		(start 109.244638 -227.151438)
		(mid 109.45086 -226.945794)
		(end 109.526324 -226.66452)
		(width 0.1143)
		(layer "In6.Cu")
		(net "GMI_CPU1_G0_CPU0_G2_TX_DP<9>")
	)
	(arc
		(start 108.678218 -236.871764)
		(mid 108.961174 -236.947941)
		(end 109.24413 -236.871764)
		(width 0.1143)
		(layer "In6.Cu")
		(net "GMI_CPU1_G0_CPU0_G2_TX_DP<9>")
	)
	(arc
		(start 363.223556 -236.889798)
		(mid 363.338232 -237.023132)
		(end 363.379512 -237.19409)
		(width 0.1143)
		(layer "In6.Cu")
		(net "GMI_CPU1_G0_CPU0_G2_TX_DP<9>")
	)
	(arc
		(start 107.403138 -240.088928)
		(mid 107.646465 -239.624362)
		(end 107.403138 -239.159796)
		(width 0.1143)
		(layer "In6.Cu")
		(net "GMI_CPU1_G0_CPU0_G2_TX_DP<9>")
	)
	(arc
		(start 109.21238 -232.6386)
		(mid 109.056452 -232.334308)
		(end 109.21238 -232.030016)
		(width 0.1143)
		(layer "In6.Cu")
		(net "GMI_CPU1_G0_CPU0_G2_TX_DP<9>")
	)
	(arc
		(start 361.969558 -229.901242)
		(mid 362.045648 -230.161456)
		(end 362.217208 -230.371396)
		(width 0.1143)
		(layer "In6.Cu")
		(net "GMI_CPU1_G0_CPU0_G2_TX_DP<9>")
	)
	(arc
		(start 362.439458 -229.094284)
		(mid 362.398696 -229.264168)
		(end 362.28528 -229.397052)
		(width 0.1143)
		(layer "In6.Cu")
		(net "GMI_CPU1_G0_CPU0_G2_TX_DP<9>")
	)
	(arc
		(start 109.526324 -229.901496)
		(mid 109.460422 -229.639487)
		(end 109.280452 -229.437946)
		(width 0.1143)
		(layer "In6.Cu")
		(net "GMI_CPU1_G0_CPU0_G2_TX_DP<9>")
	)
	(arc
		(start 106.713274 -241.174524)
		(mid 106.765228 -241.043155)
		(end 106.862118 -240.940336)
		(width 0.1143)
		(layer "In6.Cu")
		(net "GMI_CPU1_G0_CPU0_G2_TX_DP<9>")
	)
	(arc
		(start 362.283502 -235.269786)
		(mid 362.43943 -235.574078)
		(end 362.283502 -235.87837)
		(width 0.1143)
		(layer "In6.Cu")
		(net "GMI_CPU1_G0_CPU0_G2_TX_DP<9>")
	)
	(arc
		(start 364.314232 -240.430812)
		(mid 364.389724 -240.712183)
		(end 364.595918 -240.917984)
		(width 0.1143)
		(layer "In6.Cu")
		(net "GMI_CPU1_G0_CPU0_G2_TX_DP<9>")
	)
	(arc
		(start 362.183934 -231.965754)
		(mid 362.199463 -231.978353)
		(end 362.21543 -231.990392)
		(width 0.1143)
		(layer "In6.Cu")
		(net "GMI_CPU1_G0_CPU0_G2_TX_DP<9>")
	)
	(arc
		(start 362.251752 -236.87151)
		(mid 362.534708 -236.947687)
		(end 362.817664 -236.87151)
		(width 0.1143)
		(layer "In6.Cu")
		(net "GMI_CPU1_G0_CPU0_G2_TX_DP<9>")
	)
	(arc
		(start 362.283756 -227.170234)
		(mid 362.439372 -227.474449)
		(end 362.283502 -227.778564)
		(width 0.1143)
		(layer "In6.Cu")
		(net "GMI_CPU1_G0_CPU0_G2_TX_DP<9>")
	)
	(arc
		(start 362.283502 -232.029762)
		(mid 362.43943 -232.334054)
		(end 362.283502 -232.638346)
		(width 0.1143)
		(layer "In6.Cu")
		(net "GMI_CPU1_G0_CPU0_G2_TX_DP<9>")
	)
	(arc
		(start 362.439458 -230.714296)
		(mid 362.398696 -230.88418)
		(end 362.28528 -231.017064)
		(width 0.1143)
		(layer "In6.Cu")
		(net "GMI_CPU1_G0_CPU0_G2_TX_DP<9>")
	)
	(arc
		(start 364.16361 -238.50981)
		(mid 364.313995 -238.814102)
		(end 364.16361 -239.118394)
		(width 0.1143)
		(layer "In6.Cu")
		(net "GMI_CPU1_G0_CPU0_G2_TX_DP<9>")
	)
	(arc
		(start 361.500166 -225.879914)
		(mid 361.57051 -226.128456)
		(end 361.744006 -226.319842)
		(width 0.1143)
		(layer "In6.Cu")
		(net "GMI_CPU1_G0_CPU0_G2_TX_DP<9>")
	)
	(arc
		(start 109.280452 -236.850682)
		(mid 109.287601 -236.845782)
		(end 109.294676 -236.840776)
		(width 0.1143)
		(layer "In6.Cu")
		(net "GMI_CPU1_G0_CPU0_G2_TX_DP<9>")
	)
	(arc
		(start 109.280452 -231.990646)
		(mid 109.296417 -231.978605)
		(end 109.311948 -231.966008)
		(width 0.1143)
		(layer "In6.Cu")
		(net "GMI_CPU1_G0_CPU0_G2_TX_DP<9>")
	)
	(arc
		(start 362.21543 -229.437692)
		(mid 362.035445 -229.639195)
		(end 361.969558 -229.901242)
		(width 0.1143)
		(layer "In6.Cu")
		(net "GMI_CPU1_G0_CPU0_G2_TX_DP<9>")
	)
	(arc
		(start 109.210602 -229.397306)
		(mid 109.097195 -229.264417)
		(end 109.056424 -229.094538)
		(width 0.1143)
		(layer "In6.Cu")
		(net "GMI_CPU1_G0_CPU0_G2_TX_DP<9>")
	)
	(arc
		(start 362.21543 -227.817934)
		(mid 362.20828 -227.822832)
		(end 362.201206 -227.82784)
		(width 0.1143)
		(layer "In6.Cu")
		(net "GMI_CPU1_G0_CPU0_G2_TX_DP<9>")
	)
	(arc
		(start 362.18495 -234.319318)
		(mid 361.95695 -234.764072)
		(end 362.18495 -235.208826)
		(width 0.1143)
		(layer "In6.Cu")
		(net "GMI_CPU1_G0_CPU0_G2_TX_DP<9>")
	)
	(arc
		(start 109.310932 -233.589068)
		(mid 109.538932 -233.144314)
		(end 109.310932 -232.69956)
		(width 0.1143)
		(layer "In6.Cu")
		(net "GMI_CPU1_G0_CPU0_G2_TX_DP<9>")
	)
	(arc
		(start 362.283502 -233.649774)
		(mid 362.43943 -233.954066)
		(end 362.283502 -234.258358)
		(width 0.1143)
		(layer "In6.Cu")
		(net "GMI_CPU1_G0_CPU0_G2_TX_DP<9>")
	)
	(arc
		(start 109.056424 -230.71455)
		(mid 109.097679 -230.543579)
		(end 109.21238 -230.410258)
		(width 0.1143)
		(layer "In6.Cu")
		(net "GMI_CPU1_G0_CPU0_G2_TX_DP<9>")
	)
	(arc
		(start 107.873038 -237.65891)
		(mid 108.051851 -237.45656)
		(end 108.11637 -237.194344)
		(width 0.1143)
		(layer "In6.Cu")
		(net "GMI_CPU1_G0_CPU0_G2_TX_DP<9>")
	)
	(arc
		(start 364.132622 -240.111788)
		(mid 364.265586 -240.245397)
		(end 364.314232 -240.42751)
		(width 0.1143)
		(layer "In6.Cu")
		(net "GMI_CPU1_G0_CPU0_G2_TX_DP<9>")
	)
	(arc
		(start 363.69244 -237.699296)
		(mid 363.807867 -237.832672)
		(end 363.849412 -238.004096)
		(width 0.1143)
		(layer "In6.Cu")
		(net "GMI_CPU1_G0_CPU0_G2_TX_DP<9>")
	)
	(arc
		(start 361.969558 -226.664266)
		(mid 362.04506 -226.945518)
		(end 362.251244 -227.151184)
		(width 0.1143)
		(layer "In6.Cu")
		(net "GMI_CPU1_G0_CPU0_G2_TX_DP<9>")
	)
	(arc
		(start 362.201206 -235.927646)
		(mid 361.973823 -236.384084)
		(end 362.201206 -236.840522)
		(width 0.1143)
		(layer "In6.Cu")
		(net "GMI_CPU1_G0_CPU0_G2_TX_DP<9>")
	)
	(arc
		(start 108.312458 -236.866938)
		(mid 108.495966 -236.821444)
		(end 108.678218 -236.871764)
		(width 0.1143)
		(layer "In6.Cu")
		(net "GMI_CPU1_G0_CPU0_G2_TX_DP<9>")
	)
	(arc
		(start 364.092744 -239.159542)
		(mid 363.849417 -239.624108)
		(end 364.092744 -240.088674)
		(width 0.1143)
		(layer "In6.Cu")
		(net "GMI_CPU1_G0_CPU0_G2_TX_DP<9>")
	)
	(segment
		(start 104.72801 -243.130324)
		(end 104.261158 -242.864386)
		(width 0.12954)
		(layer "F.Cu")
		(net "GMI_CPU1_G0_CPU0_G2_TX_DP<8>")
	)
	(segment
		(start 366.767872 -243.13007)
		(end 367.234724 -242.864132)
		(width 0.12954)
		(layer "F.Cu")
		(net "GMI_CPU1_G0_CPU0_G2_TX_DP<8>")
	)
	(segment
		(start 105.956608 -236.060234)
		(end 105.955084 -236.06125)
		(width 0.1143)
		(layer "In6.Cu")
		(net "GMI_CPU1_G0_CPU0_G2_TX_DP<8>")
	)
	(segment
		(start 364.634018 -226.360482)
		(end 364.589568 -226.33432)
		(width 0.1143)
		(layer "In6.Cu")
		(net "GMI_CPU1_G0_CPU0_G2_TX_DP<8>")
	)
	(segment
		(start 106.423968 -234.2769)
		(end 106.463084 -234.29976)
		(width 0.1143)
		(layer "In6.Cu")
		(net "GMI_CPU1_G0_CPU0_G2_TX_DP<8>")
	)
	(segment
		(start 107.870244 -224.7011)
		(end 107.803696 -224.739708)
		(width 0.1143)
		(layer "In6.Cu")
		(net "GMI_CPU1_G0_CPU0_G2_TX_DP<8>")
	)
	(segment
		(start 105.05313 -239.278922)
		(end 105.01503 -239.301274)
		(width 0.1143)
		(layer "In6.Cu")
		(net "GMI_CPU1_G0_CPU0_G2_TX_DP<8>")
	)
	(segment
		(start 106.423968 -227.797106)
		(end 106.463084 -227.819966)
		(width 0.1143)
		(layer "In6.Cu")
		(net "GMI_CPU1_G0_CPU0_G2_TX_DP<8>")
	)
	(segment
		(start 104.982264 -237.700058)
		(end 104.962452 -237.714282)
		(width 0.1143)
		(layer "In6.Cu")
		(net "GMI_CPU1_G0_CPU0_G2_TX_DP<8>")
	)
	(segment
		(start 105.01503 -239.301274)
		(end 105.014014 -239.301782)
		(width 0.1143)
		(layer "In6.Cu")
		(net "GMI_CPU1_G0_CPU0_G2_TX_DP<8>")
	)
	(segment
		(start 362.90885 -223.424242)
		(end 362.908596 -223.424242)
		(width 0.1143)
		(layer "In6.Cu")
		(net "GMI_CPU1_G0_CPU0_G2_TX_DP<8>")
	)
	(segment
		(start 104.609138 -241.690398)
		(end 104.583484 -241.709194)
		(width 0.1143)
		(layer "In6.Cu")
		(net "GMI_CPU1_G0_CPU0_G2_TX_DP<8>")
	)
	(segment
		(start 302.895 -182.593488)
		(end 167.826436 -181.806342)
		(width 0.14224)
		(layer "In6.Cu")
		(net "GMI_CPU1_G0_CPU0_G2_TX_DP<8>")
	)
	(segment
		(start 106.463084 -235.228892)
		(end 106.423968 -235.251752)
		(width 0.1143)
		(layer "In6.Cu")
		(net "GMI_CPU1_G0_CPU0_G2_TX_DP<8>")
	)
	(segment
		(start 366.983518 -241.749834)
		(end 366.912398 -241.70894)
		(width 0.1143)
		(layer "In6.Cu")
		(net "GMI_CPU1_G0_CPU0_G2_TX_DP<8>")
	)
	(segment
		(start 106.393488 -227.779326)
		(end 106.423968 -227.797106)
		(width 0.1143)
		(layer "In6.Cu")
		(net "GMI_CPU1_G0_CPU0_G2_TX_DP<8>")
	)
	(segment
		(start 365.071914 -229.41661)
		(end 365.104426 -229.397814)
		(width 0.1143)
		(layer "In6.Cu")
		(net "GMI_CPU1_G0_CPU0_G2_TX_DP<8>")
	)
	(segment
		(start 119.47398 -209.949288)
		(end 119.285258 -209.92465)
		(width 0.14224)
		(layer "In6.Cu")
		(net "GMI_CPU1_G0_CPU0_G2_TX_DP<8>")
	)
	(segment
		(start 123.396502 -206.769716)
		(end 123.37161 -206.958438)
		(width 0.14224)
		(layer "In6.Cu")
		(net "GMI_CPU1_G0_CPU0_G2_TX_DP<8>")
	)
	(segment
		(start 106.423968 -231.036876)
		(end 106.463084 -231.059736)
		(width 0.1143)
		(layer "In6.Cu")
		(net "GMI_CPU1_G0_CPU0_G2_TX_DP<8>")
	)
	(segment
		(start 105.953306 -236.062266)
		(end 105.922318 -236.080046)
		(width 0.1143)
		(layer "In6.Cu")
		(net "GMI_CPU1_G0_CPU0_G2_TX_DP<8>")
	)
	(segment
		(start 366.513618 -238.308388)
		(end 366.53343 -238.294164)
		(width 0.1143)
		(layer "In6.Cu")
		(net "GMI_CPU1_G0_CPU0_G2_TX_DP<8>")
	)
	(segment
		(start 365.539274 -236.05998)
		(end 365.502698 -236.038644)
		(width 0.1143)
		(layer "In6.Cu")
		(net "GMI_CPU1_G0_CPU0_G2_TX_DP<8>")
	)
	(segment
		(start 366.484662 -239.303306)
		(end 366.48263 -239.302036)
		(width 0.1143)
		(layer "In6.Cu")
		(net "GMI_CPU1_G0_CPU0_G2_TX_DP<8>")
	)
	(segment
		(start 121.61393 -208.307178)
		(end 121.28119 -208.562702)
		(width 0.14224)
		(layer "In6.Cu")
		(net "GMI_CPU1_G0_CPU0_G2_TX_DP<8>")
	)
	(segment
		(start 109.52861 -221.404942)
		(end 109.526578 -221.406974)
		(width 0.1143)
		(layer "In6.Cu")
		(net "GMI_CPU1_G0_CPU0_G2_TX_DP<8>")
	)
	(segment
		(start 117.124734 -211.75218)
		(end 116.791994 -212.00745)
		(width 0.14224)
		(layer "In6.Cu")
		(net "GMI_CPU1_G0_CPU0_G2_TX_DP<8>")
	)
	(segment
		(start 366.480852 -238.327184)
		(end 366.481868 -238.326676)
		(width 0.1143)
		(layer "In6.Cu")
		(net "GMI_CPU1_G0_CPU0_G2_TX_DP<8>")
	)
	(segment
		(start 164.440108 -182.703724)
		(end 125.326394 -205.288896)
		(width 0.14224)
		(layer "In6.Cu")
		(net "GMI_CPU1_G0_CPU0_G2_TX_DP<8>")
	)
	(segment
		(start 106.393488 -232.639108)
		(end 106.423968 -232.656888)
		(width 0.1143)
		(layer "In6.Cu")
		(net "GMI_CPU1_G0_CPU0_G2_TX_DP<8>")
	)
	(segment
		(start 104.567228 -240.09731)
		(end 104.56545 -240.099088)
		(width 0.1143)
		(layer "In6.Cu")
		(net "GMI_CPU1_G0_CPU0_G2_TX_DP<8>")
	)
	(segment
		(start 365.032798 -229.43947)
		(end 365.071914 -229.41661)
		(width 0.1143)
		(layer "In6.Cu")
		(net "GMI_CPU1_G0_CPU0_G2_TX_DP<8>")
	)
	(segment
		(start 120.759982 -208.792826)
		(end 120.73509 -208.981548)
		(width 0.14224)
		(layer "In6.Cu")
		(net "GMI_CPU1_G0_CPU0_G2_TX_DP<8>")
	)
	(segment
		(start 107.363768 -225.532188)
		(end 107.363514 -225.532188)
		(width 0.1143)
		(layer "In6.Cu")
		(net "GMI_CPU1_G0_CPU0_G2_TX_DP<8>")
	)
	(segment
		(start 365.542576 -236.062012)
		(end 365.541814 -236.061504)
		(width 0.1143)
		(layer "In6.Cu")
		(net "GMI_CPU1_G0_CPU0_G2_TX_DP<8>")
	)
	(segment
		(start 121.971308 -207.86344)
		(end 121.638822 -208.118456)
		(width 0.14224)
		(layer "In6.Cu")
		(net "GMI_CPU1_G0_CPU0_G2_TX_DP<8>")
	)
	(segment
		(start 366.479074 -237.679992)
		(end 366.478058 -237.679484)
		(width 0.1143)
		(layer "In6.Cu")
		(net "GMI_CPU1_G0_CPU0_G2_TX_DP<8>")
	)
	(segment
		(start 366.442752 -238.349536)
		(end 366.480852 -238.327184)
		(width 0.1143)
		(layer "In6.Cu")
		(net "GMI_CPU1_G0_CPU0_G2_TX_DP<8>")
	)
	(segment
		(start 106.423968 -233.63174)
		(end 106.393488 -233.64952)
		(width 0.1143)
		(layer "In6.Cu")
		(net "GMI_CPU1_G0_CPU0_G2_TX_DP<8>")
	)
	(segment
		(start 365.032798 -232.679494)
		(end 365.102394 -232.638854)
		(width 0.1143)
		(layer "In6.Cu")
		(net "GMI_CPU1_G0_CPU0_G2_TX_DP<8>")
	)
	(segment
		(start 106.423968 -235.251752)
		(end 106.393488 -235.269532)
		(width 0.1143)
		(layer "In6.Cu")
		(net "GMI_CPU1_G0_CPU0_G2_TX_DP<8>")
	)
	(segment
		(start 106.460544 -230.370634)
		(end 106.393488 -230.40975)
		(width 0.1143)
		(layer "In6.Cu")
		(net "GMI_CPU1_G0_CPU0_G2_TX_DP<8>")
	)
	(segment
		(start 120.40235 -209.237072)
		(end 120.213628 -209.21218)
		(width 0.14224)
		(layer "In6.Cu")
		(net "GMI_CPU1_G0_CPU0_G2_TX_DP<8>")
	)
	(segment
		(start 362.721398 -223.101662)
		(end 362.685076 -223.08058)
		(width 0.1143)
		(layer "In6.Cu")
		(net "GMI_CPU1_G0_CPU0_G2_TX_DP<8>")
	)
	(segment
		(start 362.750862 -223.11868)
		(end 362.721398 -223.101662)
		(width 0.1143)
		(layer "In6.Cu")
		(net "GMI_CPU1_G0_CPU0_G2_TX_DP<8>")
	)
	(segment
		(start 118.88216 -210.40344)
		(end 118.54942 -210.658964)
		(width 0.14224)
		(layer "In6.Cu")
		(net "GMI_CPU1_G0_CPU0_G2_TX_DP<8>")
	)
	(segment
		(start 105.52303 -236.848904)
		(end 105.483914 -236.871764)
		(width 0.1143)
		(layer "In6.Cu")
		(net "GMI_CPU1_G0_CPU0_G2_TX_DP<8>")
	)
	(segment
		(start 106.423968 -228.771958)
		(end 106.393488 -228.789738)
		(width 0.1143)
		(layer "In6.Cu")
		(net "GMI_CPU1_G0_CPU0_G2_TX_DP<8>")
	)
	(segment
		(start 118.360698 -210.634072)
		(end 118.028212 -210.889088)
		(width 0.14224)
		(layer "In6.Cu")
		(net "GMI_CPU1_G0_CPU0_G2_TX_DP<8>")
	)
	(segment
		(start 119.831612 -209.505296)
		(end 119.80672 -209.694018)
		(width 0.14224)
		(layer "In6.Cu")
		(net "GMI_CPU1_G0_CPU0_G2_TX_DP<8>")
	)
	(segment
		(start 103.963216 -242.864386)
		(end 104.261158 -242.864386)
		(width 0.1143)
		(layer "In6.Cu")
		(net "GMI_CPU1_G0_CPU0_G2_TX_DP<8>")
	)
	(segment
		(start 358.331516 -215.560402)
		(end 354.19411 -212.268054)
		(width 0.14224)
		(layer "In6.Cu")
		(net "GMI_CPU1_G0_CPU0_G2_TX_DP<8>")
	)
	(segment
		(start 366.912398 -240.7793)
		(end 366.952276 -240.756694)
		(width 0.1143)
		(layer "In6.Cu")
		(net "GMI_CPU1_G0_CPU0_G2_TX_DP<8>")
	)
	(segment
		(start 104.982264 -238.308642)
		(end 105.013252 -238.326422)
		(width 0.1143)
		(layer "In6.Cu")
		(net "GMI_CPU1_G0_CPU0_G2_TX_DP<8>")
	)
	(segment
		(start 365.032798 -231.059482)
		(end 365.071914 -231.036622)
		(width 0.1143)
		(layer "In6.Cu")
		(net "GMI_CPU1_G0_CPU0_G2_TX_DP<8>")
	)
	(segment
		(start 105.483914 -236.871764)
		(end 105.453434 -236.889544)
		(width 0.1143)
		(layer "In6.Cu")
		(net "GMI_CPU1_G0_CPU0_G2_TX_DP<8>")
	)
	(segment
		(start 364.132114 -225.531934)
		(end 364.094268 -225.51009)
		(width 0.1143)
		(layer "In6.Cu")
		(net "GMI_CPU1_G0_CPU0_G2_TX_DP<8>")
	)
	(segment
		(start 109.24413 -222.29191)
		(end 109.21238 -222.310198)
		(width 0.1143)
		(layer "In6.Cu")
		(net "GMI_CPU1_G0_CPU0_G2_TX_DP<8>")
	)
	(segment
		(start 361.967272 -221.153228)
		(end 361.921552 -221.107508)
		(width 0.1143)
		(layer "In6.Cu")
		(net "GMI_CPU1_G0_CPU0_G2_TX_DP<8>")
	)
	(segment
		(start 123.37161 -206.958438)
		(end 123.03887 -207.213962)
		(width 0.14224)
		(layer "In6.Cu")
		(net "GMI_CPU1_G0_CPU0_G2_TX_DP<8>")
	)
	(segment
		(start 361.921552 -221.09303)
		(end 361.921552 -220.18752)
		(width 0.14224)
		(layer "In6.Cu")
		(net "GMI_CPU1_G0_CPU0_G2_TX_DP<8>")
	)
	(segment
		(start 109.52861 -221.139004)
		(end 109.52861 -221.404942)
		(width 0.1143)
		(layer "In6.Cu")
		(net "GMI_CPU1_G0_CPU0_G2_TX_DP<8>")
	)
	(segment
		(start 364.132368 -225.531934)
		(end 364.132114 -225.531934)
		(width 0.1143)
		(layer "In6.Cu")
		(net "GMI_CPU1_G0_CPU0_G2_TX_DP<8>")
	)
	(segment
		(start 118.003574 -211.07781)
		(end 117.670834 -211.333334)
		(width 0.14224)
		(layer "In6.Cu")
		(net "GMI_CPU1_G0_CPU0_G2_TX_DP<8>")
	)
	(segment
		(start 366.478058 -237.679484)
		(end 366.442752 -237.658656)
		(width 0.1143)
		(layer "In6.Cu")
		(net "GMI_CPU1_G0_CPU0_G2_TX_DP<8>")
	)
	(segment
		(start 361.969304 -221.80423)
		(end 361.969304 -221.40672)
		(width 0.1143)
		(layer "In6.Cu")
		(net "GMI_CPU1_G0_CPU0_G2_TX_DP<8>")
	)
	(segment
		(start 105.955084 -236.06125)
		(end 105.954068 -236.061758)
		(width 0.1143)
		(layer "In6.Cu")
		(net "GMI_CPU1_G0_CPU0_G2_TX_DP<8>")
	)
	(segment
		(start 361.46867 -218.697048)
		(end 358.331516 -215.560402)
		(width 0.14224)
		(layer "In6.Cu")
		(net "GMI_CPU1_G0_CPU0_G2_TX_DP<8>")
	)
	(segment
		(start 107.402122 -225.51009)
		(end 107.401614 -225.510344)
		(width 0.1143)
		(layer "In6.Cu")
		(net "GMI_CPU1_G0_CPU0_G2_TX_DP<8>")
	)
	(segment
		(start 120.73509 -208.981548)
		(end 120.40235 -209.237072)
		(width 0.14224)
		(layer "In6.Cu")
		(net "GMI_CPU1_G0_CPU0_G2_TX_DP<8>")
	)
	(segment
		(start 105.05313 -237.65891)
		(end 105.020618 -237.678214)
		(width 0.1143)
		(layer "In6.Cu")
		(net "GMI_CPU1_G0_CPU0_G2_TX_DP<8>")
	)
	(segment
		(start 106.391456 -231.01808)
		(end 106.423968 -231.036876)
		(width 0.1143)
		(layer "In6.Cu")
		(net "GMI_CPU1_G0_CPU0_G2_TX_DP<8>")
	)
	(segment
		(start 122.16003 -207.888332)
		(end 121.971308 -207.86344)
		(width 0.14224)
		(layer "In6.Cu")
		(net "GMI_CPU1_G0_CPU0_G2_TX_DP<8>")
	)
	(segment
		(start 107.401614 -225.510344)
		(end 107.363768 -225.532188)
		(width 0.1143)
		(layer "In6.Cu")
		(net "GMI_CPU1_G0_CPU0_G2_TX_DP<8>")
	)
	(segment
		(start 107.871768 -224.700338)
		(end 107.870244 -224.7011)
		(width 0.1143)
		(layer "In6.Cu")
		(net "GMI_CPU1_G0_CPU0_G2_TX_DP<8>")
	)
	(segment
		(start 106.393488 -234.25912)
		(end 106.423968 -234.2769)
		(width 0.1143)
		(layer "In6.Cu")
		(net "GMI_CPU1_G0_CPU0_G2_TX_DP<8>")
	)
	(segment
		(start 105.013252 -239.30229)
		(end 105.01122 -239.30356)
		(width 0.1143)
		(layer "In6.Cu")
		(net "GMI_CPU1_G0_CPU0_G2_TX_DP<8>")
	)
	(segment
		(start 109.57433 -221.093284)
		(end 109.52861 -221.139004)
		(width 0.1143)
		(layer "In6.Cu")
		(net "GMI_CPU1_G0_CPU0_G2_TX_DP<8>")
	)
	(segment
		(start 306.517548 -182.593488)
		(end 302.895 -182.593488)
		(width 0.14224)
		(layer "In6.Cu")
		(net "GMI_CPU1_G0_CPU0_G2_TX_DP<8>")
	)
	(segment
		(start 110.532418 -217.959178)
		(end 109.57433 -220.272102)
		(width 0.14224)
		(layer "In6.Cu")
		(net "GMI_CPU1_G0_CPU0_G2_TX_DP<8>")
	)
	(segment
		(start 106.463084 -227.129086)
		(end 106.423968 -227.151946)
		(width 0.1143)
		(layer "In6.Cu")
		(net "GMI_CPU1_G0_CPU0_G2_TX_DP<8>")
	)
	(segment
		(start 104.56545 -240.099088)
		(end 104.51211 -240.13033)
		(width 0.1143)
		(layer "In6.Cu")
		(net "GMI_CPU1_G0_CPU0_G2_TX_DP<8>")
	)
	(segment
		(start 120.213628 -209.21218)
		(end 119.831612 -209.505296)
		(width 0.14224)
		(layer "In6.Cu")
		(net "GMI_CPU1_G0_CPU0_G2_TX_DP<8>")
	)
	(segment
		(start 106.463084 -233.60888)
		(end 106.423968 -233.63174)
		(width 0.1143)
		(layer "In6.Cu")
		(net "GMI_CPU1_G0_CPU0_G2_TX_DP<8>")
	)
	(segment
		(start 365.071914 -231.036622)
		(end 365.104426 -231.017826)
		(width 0.1143)
		(layer "In6.Cu")
		(net "GMI_CPU1_G0_CPU0_G2_TX_DP<8>")
	)
	(segment
		(start 116.197634 -212.293962)
		(end 110.532418 -217.959178)
		(width 0.14224)
		(layer "In6.Cu")
		(net "GMI_CPU1_G0_CPU0_G2_TX_DP<8>")
	)
	(segment
		(start 365.573564 -236.079792)
		(end 365.543846 -236.062774)
		(width 0.1143)
		(layer "In6.Cu")
		(net "GMI_CPU1_G0_CPU0_G2_TX_DP<8>")
	)
	(segment
		(start 104.583484 -240.779554)
		(end 104.609138 -240.79835)
		(width 0.1143)
		(layer "In6.Cu")
		(net "GMI_CPU1_G0_CPU0_G2_TX_DP<8>")
	)
	(segment
		(start 104.113076 -242.518946)
		(end 104.07396 -242.541806)
		(width 0.1143)
		(layer "In6.Cu")
		(net "GMI_CPU1_G0_CPU0_G2_TX_DP<8>")
	)
	(segment
		(start 367.532666 -242.864132)
		(end 367.602516 -242.794282)
		(width 0.1143)
		(layer "In6.Cu")
		(net "GMI_CPU1_G0_CPU0_G2_TX_DP<8>")
	)
	(segment
		(start 362.251752 -222.291656)
		(end 362.212636 -222.268796)
		(width 0.1143)
		(layer "In6.Cu")
		(net "GMI_CPU1_G0_CPU0_G2_TX_DP<8>")
	)
	(segment
		(start 366.481868 -237.681516)
		(end 366.480852 -237.681008)
		(width 0.1143)
		(layer "In6.Cu")
		(net "GMI_CPU1_G0_CPU0_G2_TX_DP<8>")
	)
	(segment
		(start 122.517662 -207.444086)
		(end 122.49277 -207.632808)
		(width 0.14224)
		(layer "In6.Cu")
		(net "GMI_CPU1_G0_CPU0_G2_TX_DP<8>")
	)
	(segment
		(start 105.014014 -238.32693)
		(end 105.05313 -238.34979)
		(width 0.1143)
		(layer "In6.Cu")
		(net "GMI_CPU1_G0_CPU0_G2_TX_DP<8>")
	)
	(segment
		(start 363.219238 -223.928178)
		(end 363.149134 -223.886776)
		(width 0.1143)
		(layer "In6.Cu")
		(net "GMI_CPU1_G0_CPU0_G2_TX_DP<8>")
	)
	(segment
		(start 363.379258 -224.234248)
		(end 363.379258 -224.232724)
		(width 0.1143)
		(layer "In6.Cu")
		(net "GMI_CPU1_G0_CPU0_G2_TX_DP<8>")
	)
	(segment
		(start 366.48263 -238.326168)
		(end 366.513618 -238.308388)
		(width 0.1143)
		(layer "In6.Cu")
		(net "GMI_CPU1_G0_CPU0_G2_TX_DP<8>")
	)
	(segment
		(start 106.463084 -231.988868)
		(end 106.423968 -232.011728)
		(width 0.1143)
		(layer "In6.Cu")
		(net "GMI_CPU1_G0_CPU0_G2_TX_DP<8>")
	)
	(segment
		(start 366.042448 -236.88929)
		(end 365.972852 -236.84865)
		(width 0.1143)
		(layer "In6.Cu")
		(net "GMI_CPU1_G0_CPU0_G2_TX_DP<8>")
	)
	(segment
		(start 105.013252 -237.682278)
		(end 104.982264 -237.700058)
		(width 0.1143)
		(layer "In6.Cu")
		(net "GMI_CPU1_G0_CPU0_G2_TX_DP<8>")
	)
	(segment
		(start 109.57433 -220.272102)
		(end 109.57433 -221.064836)
		(width 0.14224)
		(layer "In6.Cu")
		(net "GMI_CPU1_G0_CPU0_G2_TX_DP<8>")
	)
	(segment
		(start 122.49277 -207.632808)
		(end 122.16003 -207.888332)
		(width 0.14224)
		(layer "In6.Cu")
		(net "GMI_CPU1_G0_CPU0_G2_TX_DP<8>")
	)
	(segment
		(start 122.850148 -207.18907)
		(end 122.517662 -207.444086)
		(width 0.14224)
		(layer "In6.Cu")
		(net "GMI_CPU1_G0_CPU0_G2_TX_DP<8>")
	)
	(segment
		(start 361.969304 -221.40672)
		(end 361.967272 -221.404688)
		(width 0.1143)
		(layer "In6.Cu")
		(net "GMI_CPU1_G0_CPU0_G2_TX_DP<8>")
	)
	(segment
		(start 365.541814 -236.061504)
		(end 365.540798 -236.060996)
		(width 0.1143)
		(layer "In6.Cu")
		(net "GMI_CPU1_G0_CPU0_G2_TX_DP<8>")
	)
	(segment
		(start 108.346748 -223.88703)
		(end 108.276644 -223.928432)
		(width 0.1143)
		(layer "In6.Cu")
		(net "GMI_CPU1_G0_CPU0_G2_TX_DP<8>")
	)
	(segment
		(start 366.886744 -240.798096)
		(end 366.912398 -240.7793)
		(width 0.1143)
		(layer "In6.Cu")
		(net "GMI_CPU1_G0_CPU0_G2_TX_DP<8>")
	)
	(segment
		(start 105.016808 -237.680246)
		(end 105.01503 -237.681262)
		(width 0.1143)
		(layer "In6.Cu")
		(net "GMI_CPU1_G0_CPU0_G2_TX_DP<8>")
	)
	(segment
		(start 108.774484 -223.101916)
		(end 108.74502 -223.118934)
		(width 0.1143)
		(layer "In6.Cu")
		(net "GMI_CPU1_G0_CPU0_G2_TX_DP<8>")
	)
	(segment
		(start 106.423968 -229.416864)
		(end 106.463084 -229.439724)
		(width 0.1143)
		(layer "In6.Cu")
		(net "GMI_CPU1_G0_CPU0_G2_TX_DP<8>")
	)
	(segment
		(start 103.893366 -242.794536)
		(end 103.963216 -242.864386)
		(width 0.1143)
		(layer "In6.Cu")
		(net "GMI_CPU1_G0_CPU0_G2_TX_DP<8>")
	)
	(segment
		(start 123.03887 -207.213962)
		(end 122.850148 -207.18907)
		(width 0.14224)
		(layer "In6.Cu")
		(net "GMI_CPU1_G0_CPU0_G2_TX_DP<8>")
	)
	(segment
		(start 105.014014 -239.301782)
		(end 105.013252 -239.30229)
		(width 0.1143)
		(layer "In6.Cu")
		(net "GMI_CPU1_G0_CPU0_G2_TX_DP<8>")
	)
	(segment
		(start 366.481868 -238.326676)
		(end 366.48263 -238.326168)
		(width 0.1143)
		(layer "In6.Cu")
		(net "GMI_CPU1_G0_CPU0_G2_TX_DP<8>")
	)
	(segment
		(start 104.07396 -242.541806)
		(end 104.04348 -242.559586)
		(width 0.1143)
		(layer "In6.Cu")
		(net "GMI_CPU1_G0_CPU0_G2_TX_DP<8>")
	)
	(segment
		(start 105.01122 -239.30356)
		(end 105.009696 -239.304068)
		(width 0.1143)
		(layer "In6.Cu")
		(net "GMI_CPU1_G0_CPU0_G2_TX_DP<8>")
	)
	(segment
		(start 363.625638 -224.700846)
		(end 363.624114 -224.700084)
		(width 0.1143)
		(layer "In6.Cu")
		(net "GMI_CPU1_G0_CPU0_G2_TX_DP<8>")
	)
	(segment
		(start 365.102394 -228.789484)
		(end 365.032798 -228.748844)
		(width 0.1143)
		(layer "In6.Cu")
		(net "GMI_CPU1_G0_CPU0_G2_TX_DP<8>")
	)
	(segment
		(start 118.54942 -210.658964)
		(end 118.360698 -210.634072)
		(width 0.14224)
		(layer "In6.Cu")
		(net "GMI_CPU1_G0_CPU0_G2_TX_DP<8>")
	)
	(segment
		(start 121.092468 -208.53781)
		(end 120.759982 -208.792826)
		(width 0.14224)
		(layer "In6.Cu")
		(net "GMI_CPU1_G0_CPU0_G2_TX_DP<8>")
	)
	(segment
		(start 119.285258 -209.92465)
		(end 118.907052 -210.214718)
		(width 0.14224)
		(layer "In6.Cu")
		(net "GMI_CPU1_G0_CPU0_G2_TX_DP<8>")
	)
	(segment
		(start 366.930432 -240.098834)
		(end 366.928654 -240.097056)
		(width 0.1143)
		(layer "In6.Cu")
		(net "GMI_CPU1_G0_CPU0_G2_TX_DP<8>")
	)
	(segment
		(start 109.57433 -221.064836)
		(end 109.57433 -221.093284)
		(width 0.1143)
		(layer "In6.Cu")
		(net "GMI_CPU1_G0_CPU0_G2_TX_DP<8>")
	)
	(segment
		(start 366.480852 -239.30102)
		(end 366.442752 -239.278668)
		(width 0.1143)
		(layer "In6.Cu")
		(net "GMI_CPU1_G0_CPU0_G2_TX_DP<8>")
	)
	(segment
		(start 104.512364 -240.738406)
		(end 104.543606 -240.756948)
		(width 0.1143)
		(layer "In6.Cu")
		(net "GMI_CPU1_G0_CPU0_G2_TX_DP<8>")
	)
	(segment
		(start 365.032798 -234.299506)
		(end 365.102394 -234.258866)
		(width 0.1143)
		(layer "In6.Cu")
		(net "GMI_CPU1_G0_CPU0_G2_TX_DP<8>")
	)
	(segment
		(start 314.35421 -186.806078)
		(end 307.900832 -182.973726)
		(width 0.14224)
		(layer "In6.Cu")
		(net "GMI_CPU1_G0_CPU0_G2_TX_DP<8>")
	)
	(segment
		(start 167.826436 -181.806342)
		(end 164.440108 -182.703724)
		(width 0.14224)
		(layer "In6.Cu")
		(net "GMI_CPU1_G0_CPU0_G2_TX_DP<8>")
	)
	(segment
		(start 365.102394 -233.649266)
		(end 365.032798 -233.608626)
		(width 0.1143)
		(layer "In6.Cu")
		(net "GMI_CPU1_G0_CPU0_G2_TX_DP<8>")
	)
	(segment
		(start 365.102394 -227.169472)
		(end 365.032798 -227.128832)
		(width 0.1143)
		(layer "In6.Cu")
		(net "GMI_CPU1_G0_CPU0_G2_TX_DP<8>")
	)
	(segment
		(start 118.907052 -210.214718)
		(end 118.88216 -210.40344)
		(width 0.14224)
		(layer "In6.Cu")
		(net "GMI_CPU1_G0_CPU0_G2_TX_DP<8>")
	)
	(segment
		(start 366.480852 -237.681008)
		(end 366.479074 -237.679992)
		(width 0.1143)
		(layer "In6.Cu")
		(net "GMI_CPU1_G0_CPU0_G2_TX_DP<8>")
	)
	(segment
		(start 105.01503 -237.681262)
		(end 105.014014 -237.68177)
		(width 0.1143)
		(layer "In6.Cu")
		(net "GMI_CPU1_G0_CPU0_G2_TX_DP<8>")
	)
	(segment
		(start 365.102394 -232.029254)
		(end 365.032798 -231.988614)
		(width 0.1143)
		(layer "In6.Cu")
		(net "GMI_CPU1_G0_CPU0_G2_TX_DP<8>")
	)
	(segment
		(start 105.993184 -236.038898)
		(end 105.956608 -236.060234)
		(width 0.1143)
		(layer "In6.Cu")
		(net "GMI_CPU1_G0_CPU0_G2_TX_DP<8>")
	)
	(segment
		(start 109.526578 -221.406974)
		(end 109.526578 -221.804484)
		(width 0.1143)
		(layer "In6.Cu")
		(net "GMI_CPU1_G0_CPU0_G2_TX_DP<8>")
	)
	(segment
		(start 108.116624 -224.232978)
		(end 108.116624 -224.234502)
		(width 0.1143)
		(layer "In6.Cu")
		(net "GMI_CPU1_G0_CPU0_G2_TX_DP<8>")
	)
	(segment
		(start 366.486186 -239.303814)
		(end 366.484662 -239.303306)
		(width 0.1143)
		(layer "In6.Cu")
		(net "GMI_CPU1_G0_CPU0_G2_TX_DP<8>")
	)
	(segment
		(start 366.952276 -240.756694)
		(end 366.983518 -240.738152)
		(width 0.1143)
		(layer "In6.Cu")
		(net "GMI_CPU1_G0_CPU0_G2_TX_DP<8>")
	)
	(segment
		(start 105.020618 -237.678214)
		(end 105.017824 -237.679738)
		(width 0.1143)
		(layer "In6.Cu")
		(net "GMI_CPU1_G0_CPU0_G2_TX_DP<8>")
	)
	(segment
		(start 121.28119 -208.562702)
		(end 121.092468 -208.53781)
		(width 0.14224)
		(layer "In6.Cu")
		(net "GMI_CPU1_G0_CPU0_G2_TX_DP<8>")
	)
	(segment
		(start 105.013252 -238.326422)
		(end 105.014014 -238.32693)
		(width 0.1143)
		(layer "In6.Cu")
		(net "GMI_CPU1_G0_CPU0_G2_TX_DP<8>")
	)
	(segment
		(start 366.48263 -239.302036)
		(end 366.481868 -239.301528)
		(width 0.1143)
		(layer "In6.Cu")
		(net "GMI_CPU1_G0_CPU0_G2_TX_DP<8>")
	)
	(segment
		(start 117.149626 -211.563458)
		(end 117.124734 -211.75218)
		(width 0.14224)
		(layer "In6.Cu")
		(net "GMI_CPU1_G0_CPU0_G2_TX_DP<8>")
	)
	(segment
		(start 362.283502 -222.309944)
		(end 362.251752 -222.291656)
		(width 0.1143)
		(layer "In6.Cu")
		(net "GMI_CPU1_G0_CPU0_G2_TX_DP<8>")
	)
	(segment
		(start 367.452402 -242.559332)
		(end 367.382806 -242.518692)
		(width 0.1143)
		(layer "In6.Cu")
		(net "GMI_CPU1_G0_CPU0_G2_TX_DP<8>")
	)
	(segment
		(start 361.921552 -221.107508)
		(end 361.921552 -221.09303)
		(width 0.1143)
		(layer "In6.Cu")
		(net "GMI_CPU1_G0_CPU0_G2_TX_DP<8>")
	)
	(segment
		(start 116.791994 -212.00745)
		(end 116.603272 -211.982558)
		(width 0.14224)
		(layer "In6.Cu")
		(net "GMI_CPU1_G0_CPU0_G2_TX_DP<8>")
	)
	(segment
		(start 365.102394 -235.269278)
		(end 365.032798 -235.228638)
		(width 0.1143)
		(layer "In6.Cu")
		(net "GMI_CPU1_G0_CPU0_G2_TX_DP<8>")
	)
	(segment
		(start 104.543606 -240.756948)
		(end 104.583484 -240.779554)
		(width 0.1143)
		(layer "In6.Cu")
		(net "GMI_CPU1_G0_CPU0_G2_TX_DP<8>")
	)
	(segment
		(start 109.283246 -222.26905)
		(end 109.24413 -222.29191)
		(width 0.1143)
		(layer "In6.Cu")
		(net "GMI_CPU1_G0_CPU0_G2_TX_DP<8>")
	)
	(segment
		(start 104.583484 -241.709194)
		(end 104.512364 -241.750088)
		(width 0.1143)
		(layer "In6.Cu")
		(net "GMI_CPU1_G0_CPU0_G2_TX_DP<8>")
	)
	(segment
		(start 106.423968 -227.151946)
		(end 106.393488 -227.169726)
		(width 0.1143)
		(layer "In6.Cu")
		(net "GMI_CPU1_G0_CPU0_G2_TX_DP<8>")
	)
	(segment
		(start 117.670834 -211.333334)
		(end 117.481858 -211.308442)
		(width 0.14224)
		(layer "In6.Cu")
		(net "GMI_CPU1_G0_CPU0_G2_TX_DP<8>")
	)
	(segment
		(start 106.906314 -226.334574)
		(end 106.861864 -226.360736)
		(width 0.1143)
		(layer "In6.Cu")
		(net "GMI_CPU1_G0_CPU0_G2_TX_DP<8>")
	)
	(segment
		(start 365.102394 -230.409496)
		(end 365.035338 -230.37038)
		(width 0.1143)
		(layer "In6.Cu")
		(net "GMI_CPU1_G0_CPU0_G2_TX_DP<8>")
	)
	(segment
		(start 116.603272 -211.982558)
		(end 116.197634 -212.293962)
		(width 0.14224)
		(layer "In6.Cu")
		(net "GMI_CPU1_G0_CPU0_G2_TX_DP<8>")
	)
	(segment
		(start 366.983772 -240.130076)
		(end 366.930432 -240.098834)
		(width 0.1143)
		(layer "In6.Cu")
		(net "GMI_CPU1_G0_CPU0_G2_TX_DP<8>")
	)
	(segment
		(start 365.540798 -236.060996)
		(end 365.539274 -236.05998)
		(width 0.1143)
		(layer "In6.Cu")
		(net "GMI_CPU1_G0_CPU0_G2_TX_DP<8>")
	)
	(segment
		(start 117.481858 -211.308442)
		(end 117.149626 -211.563458)
		(width 0.14224)
		(layer "In6.Cu")
		(net "GMI_CPU1_G0_CPU0_G2_TX_DP<8>")
	)
	(segment
		(start 315.618876 -188.141356)
		(end 314.35421 -186.806078)
		(width 0.14224)
		(layer "In6.Cu")
		(net "GMI_CPU1_G0_CPU0_G2_TX_DP<8>")
	)
	(segment
		(start 105.017824 -237.679738)
		(end 105.016808 -237.680246)
		(width 0.1143)
		(layer "In6.Cu")
		(net "GMI_CPU1_G0_CPU0_G2_TX_DP<8>")
	)
	(segment
		(start 361.921552 -220.18752)
		(end 361.46867 -218.697048)
		(width 0.14224)
		(layer "In6.Cu")
		(net "GMI_CPU1_G0_CPU0_G2_TX_DP<8>")
	)
	(segment
		(start 365.032798 -227.819712)
		(end 365.102394 -227.779072)
		(width 0.1143)
		(layer "In6.Cu")
		(net "GMI_CPU1_G0_CPU0_G2_TX_DP<8>")
	)
	(segment
		(start 121.638822 -208.118456)
		(end 121.61393 -208.307178)
		(width 0.14224)
		(layer "In6.Cu")
		(net "GMI_CPU1_G0_CPU0_G2_TX_DP<8>")
	)
	(segment
		(start 366.53343 -237.714028)
		(end 366.513618 -237.699804)
		(width 0.1143)
		(layer "In6.Cu")
		(net "GMI_CPU1_G0_CPU0_G2_TX_DP<8>")
	)
	(segment
		(start 367.234724 -242.864132)
		(end 367.532666 -242.864132)
		(width 0.1143)
		(layer "In6.Cu")
		(net "GMI_CPU1_G0_CPU0_G2_TX_DP<8>")
	)
	(segment
		(start 105.954068 -236.061758)
		(end 105.953306 -236.062266)
		(width 0.1143)
		(layer "In6.Cu")
		(net "GMI_CPU1_G0_CPU0_G2_TX_DP<8>")
	)
	(segment
		(start 106.463084 -228.749098)
		(end 106.423968 -228.771958)
		(width 0.1143)
		(layer "In6.Cu")
		(net "GMI_CPU1_G0_CPU0_G2_TX_DP<8>")
	)
	(segment
		(start 125.326394 -205.288896)
		(end 123.396502 -206.769716)
		(width 0.14224)
		(layer "In6.Cu")
		(net "GMI_CPU1_G0_CPU0_G2_TX_DP<8>")
	)
	(segment
		(start 106.391456 -229.398068)
		(end 106.423968 -229.416864)
		(width 0.1143)
		(layer "In6.Cu")
		(net "GMI_CPU1_G0_CPU0_G2_TX_DP<8>")
	)
	(segment
		(start 366.481868 -239.301528)
		(end 366.480852 -239.30102)
		(width 0.1143)
		(layer "In6.Cu")
		(net "GMI_CPU1_G0_CPU0_G2_TX_DP<8>")
	)
	(segment
		(start 361.967272 -221.404688)
		(end 361.967272 -221.153228)
		(width 0.1143)
		(layer "In6.Cu")
		(net "GMI_CPU1_G0_CPU0_G2_TX_DP<8>")
	)
	(segment
		(start 307.900832 -182.973726)
		(end 306.517548 -182.593488)
		(width 0.14224)
		(layer "In6.Cu")
		(net "GMI_CPU1_G0_CPU0_G2_TX_DP<8>")
	)
	(segment
		(start 363.692186 -224.739454)
		(end 363.625638 -224.700846)
		(width 0.1143)
		(layer "In6.Cu")
		(net "GMI_CPU1_G0_CPU0_G2_TX_DP<8>")
	)
	(segment
		(start 366.912398 -241.70894)
		(end 366.886744 -241.690144)
		(width 0.1143)
		(layer "In6.Cu")
		(net "GMI_CPU1_G0_CPU0_G2_TX_DP<8>")
	)
	(segment
		(start 365.543846 -236.062774)
		(end 365.542576 -236.062012)
		(width 0.1143)
		(layer "In6.Cu")
		(net "GMI_CPU1_G0_CPU0_G2_TX_DP<8>")
	)
	(segment
		(start 108.587286 -223.424496)
		(end 108.587032 -223.424496)
		(width 0.1143)
		(layer "In6.Cu")
		(net "GMI_CPU1_G0_CPU0_G2_TX_DP<8>")
	)
	(segment
		(start 119.80672 -209.694018)
		(end 119.47398 -209.949288)
		(width 0.14224)
		(layer "In6.Cu")
		(net "GMI_CPU1_G0_CPU0_G2_TX_DP<8>")
	)
	(segment
		(start 366.513618 -237.699804)
		(end 366.48263 -237.682024)
		(width 0.1143)
		(layer "In6.Cu")
		(net "GMI_CPU1_G0_CPU0_G2_TX_DP<8>")
	)
	(segment
		(start 118.028212 -210.889088)
		(end 118.003574 -211.07781)
		(width 0.14224)
		(layer "In6.Cu")
		(net "GMI_CPU1_G0_CPU0_G2_TX_DP<8>")
	)
	(segment
		(start 108.810806 -223.080834)
		(end 108.774484 -223.101916)
		(width 0.1143)
		(layer "In6.Cu")
		(net "GMI_CPU1_G0_CPU0_G2_TX_DP<8>")
	)
	(segment
		(start 106.423968 -232.656888)
		(end 106.463084 -232.679748)
		(width 0.1143)
		(layer "In6.Cu")
		(net "GMI_CPU1_G0_CPU0_G2_TX_DP<8>")
	)
	(segment
		(start 106.423968 -232.011728)
		(end 106.393488 -232.029508)
		(width 0.1143)
		(layer "In6.Cu")
		(net "GMI_CPU1_G0_CPU0_G2_TX_DP<8>")
	)
	(segment
		(start 107.189016 -225.834194)
		(end 107.189016 -225.844862)
		(width 0.1143)
		(layer "In6.Cu")
		(net "GMI_CPU1_G0_CPU0_G2_TX_DP<8>")
	)
	(segment
		(start 366.48263 -237.682024)
		(end 366.481868 -237.681516)
		(width 0.1143)
		(layer "In6.Cu")
		(net "GMI_CPU1_G0_CPU0_G2_TX_DP<8>")
	)
	(segment
		(start 364.306866 -225.844608)
		(end 364.306866 -225.83394)
		(width 0.1143)
		(layer "In6.Cu")
		(net "GMI_CPU1_G0_CPU0_G2_TX_DP<8>")
	)
	(segment
		(start 354.19411 -212.268054)
		(end 315.618876 -188.141356)
		(width 0.14224)
		(layer "In6.Cu")
		(net "GMI_CPU1_G0_CPU0_G2_TX_DP<8>")
	)
	(segment
		(start 105.014014 -237.68177)
		(end 105.013252 -237.682278)
		(width 0.1143)
		(layer "In6.Cu")
		(net "GMI_CPU1_G0_CPU0_G2_TX_DP<8>")
	)
	(segment
		(start 364.094268 -225.51009)
		(end 364.09376 -225.509836)
		(width 0.1143)
		(layer "In6.Cu")
		(net "GMI_CPU1_G0_CPU0_G2_TX_DP<8>")
	)
	(segment
		(start 104.962452 -238.294418)
		(end 104.982264 -238.308642)
		(width 0.1143)
		(layer "In6.Cu")
		(net "GMI_CPU1_G0_CPU0_G2_TX_DP<8>")
	)
	(arc
		(start 106.706416 -226.66452)
		(mid 106.641901 -226.926739)
		(end 106.463084 -227.129086)
		(width 0.1143)
		(layer "In6.Cu")
		(net "GMI_CPU1_G0_CPU0_G2_TX_DP<8>")
	)
	(arc
		(start 364.09376 -225.509836)
		(mid 363.914031 -225.307216)
		(end 363.849158 -225.044254)
		(width 0.1143)
		(layer "In6.Cu")
		(net "GMI_CPU1_G0_CPU0_G2_TX_DP<8>")
	)
	(arc
		(start 106.463084 -227.819966)
		(mid 106.706411 -228.284532)
		(end 106.463084 -228.749098)
		(width 0.1143)
		(layer "In6.Cu")
		(net "GMI_CPU1_G0_CPU0_G2_TX_DP<8>")
	)
	(arc
		(start 365.502698 -236.038644)
		(mid 365.323885 -235.836294)
		(end 365.259366 -235.574078)
		(width 0.1143)
		(layer "In6.Cu")
		(net "GMI_CPU1_G0_CPU0_G2_TX_DP<8>")
	)
	(arc
		(start 109.526578 -221.804484)
		(mid 109.462063 -222.066703)
		(end 109.283246 -222.26905)
		(width 0.1143)
		(layer "In6.Cu")
		(net "GMI_CPU1_G0_CPU0_G2_TX_DP<8>")
	)
	(arc
		(start 106.463084 -234.29976)
		(mid 106.706411 -234.764326)
		(end 106.463084 -235.228892)
		(width 0.1143)
		(layer "In6.Cu")
		(net "GMI_CPU1_G0_CPU0_G2_TX_DP<8>")
	)
	(arc
		(start 365.259366 -235.574078)
		(mid 365.217817 -235.402656)
		(end 365.102394 -235.269278)
		(width 0.1143)
		(layer "In6.Cu")
		(net "GMI_CPU1_G0_CPU0_G2_TX_DP<8>")
	)
	(arc
		(start 366.442752 -237.658656)
		(mid 366.263939 -237.456306)
		(end 366.19942 -237.19409)
		(width 0.1143)
		(layer "In6.Cu")
		(net "GMI_CPU1_G0_CPU0_G2_TX_DP<8>")
	)
	(arc
		(start 106.236516 -229.094538)
		(mid 106.277482 -229.264944)
		(end 106.391456 -229.398068)
		(width 0.1143)
		(layer "In6.Cu")
		(net "GMI_CPU1_G0_CPU0_G2_TX_DP<8>")
	)
	(arc
		(start 365.972852 -236.84865)
		(mid 365.794039 -236.6463)
		(end 365.72952 -236.384084)
		(width 0.1143)
		(layer "In6.Cu")
		(net "GMI_CPU1_G0_CPU0_G2_TX_DP<8>")
	)
	(arc
		(start 366.928654 -240.097056)
		(mid 366.739667 -239.893803)
		(end 366.671098 -239.62487)
		(width 0.1143)
		(layer "In6.Cu")
		(net "GMI_CPU1_G0_CPU0_G2_TX_DP<8>")
	)
	(arc
		(start 106.393488 -227.169726)
		(mid 106.236511 -227.474526)
		(end 106.393488 -227.779326)
		(width 0.1143)
		(layer "In6.Cu")
		(net "GMI_CPU1_G0_CPU0_G2_TX_DP<8>")
	)
	(arc
		(start 365.72952 -236.384084)
		(mid 365.688265 -236.213113)
		(end 365.573564 -236.079792)
		(width 0.1143)
		(layer "In6.Cu")
		(net "GMI_CPU1_G0_CPU0_G2_TX_DP<8>")
	)
	(arc
		(start 365.035338 -230.37038)
		(mid 364.854686 -230.167635)
		(end 364.789466 -229.904036)
		(width 0.1143)
		(layer "In6.Cu")
		(net "GMI_CPU1_G0_CPU0_G2_TX_DP<8>")
	)
	(arc
		(start 365.032798 -235.228638)
		(mid 364.789471 -234.764072)
		(end 365.032798 -234.299506)
		(width 0.1143)
		(layer "In6.Cu")
		(net "GMI_CPU1_G0_CPU0_G2_TX_DP<8>")
	)
	(arc
		(start 104.609138 -240.79835)
		(mid 104.837746 -241.244374)
		(end 104.609138 -241.690398)
		(width 0.1143)
		(layer "In6.Cu")
		(net "GMI_CPU1_G0_CPU0_G2_TX_DP<8>")
	)
	(arc
		(start 365.032798 -231.988614)
		(mid 364.789471 -231.524048)
		(end 365.032798 -231.059482)
		(width 0.1143)
		(layer "In6.Cu")
		(net "GMI_CPU1_G0_CPU0_G2_TX_DP<8>")
	)
	(arc
		(start 105.766362 -236.384338)
		(mid 105.701847 -236.646557)
		(end 105.52303 -236.848904)
		(width 0.1143)
		(layer "In6.Cu")
		(net "GMI_CPU1_G0_CPU0_G2_TX_DP<8>")
	)
	(arc
		(start 107.646724 -225.044508)
		(mid 107.581852 -225.307471)
		(end 107.402122 -225.51009)
		(width 0.1143)
		(layer "In6.Cu")
		(net "GMI_CPU1_G0_CPU0_G2_TX_DP<8>")
	)
	(arc
		(start 106.236516 -235.574332)
		(mid 106.172001 -235.836551)
		(end 105.993184 -236.038898)
		(width 0.1143)
		(layer "In6.Cu")
		(net "GMI_CPU1_G0_CPU0_G2_TX_DP<8>")
	)
	(arc
		(start 365.259366 -230.714296)
		(mid 365.217817 -230.542874)
		(end 365.102394 -230.409496)
		(width 0.1143)
		(layer "In6.Cu")
		(net "GMI_CPU1_G0_CPU0_G2_TX_DP<8>")
	)
	(arc
		(start 366.983518 -240.738152)
		(mid 367.139451 -240.434217)
		(end 366.983772 -240.130076)
		(width 0.1143)
		(layer "In6.Cu")
		(net "GMI_CPU1_G0_CPU0_G2_TX_DP<8>")
	)
	(arc
		(start 106.393488 -233.64952)
		(mid 106.236511 -233.95432)
		(end 106.393488 -234.25912)
		(width 0.1143)
		(layer "In6.Cu")
		(net "GMI_CPU1_G0_CPU0_G2_TX_DP<8>")
	)
	(arc
		(start 367.139474 -242.054126)
		(mid 367.098219 -241.883155)
		(end 366.983518 -241.749834)
		(width 0.1143)
		(layer "In6.Cu")
		(net "GMI_CPU1_G0_CPU0_G2_TX_DP<8>")
	)
	(arc
		(start 107.803696 -224.739708)
		(mid 107.688269 -224.873084)
		(end 107.646724 -225.044508)
		(width 0.1143)
		(layer "In6.Cu")
		(net "GMI_CPU1_G0_CPU0_G2_TX_DP<8>")
	)
	(arc
		(start 104.962452 -237.714282)
		(mid 104.813738 -238.00435)
		(end 104.962452 -238.294418)
		(width 0.1143)
		(layer "In6.Cu")
		(net "GMI_CPU1_G0_CPU0_G2_TX_DP<8>")
	)
	(arc
		(start 105.922318 -236.080046)
		(mid 105.807642 -236.21338)
		(end 105.766362 -236.384338)
		(width 0.1143)
		(layer "In6.Cu")
		(net "GMI_CPU1_G0_CPU0_G2_TX_DP<8>")
	)
	(arc
		(start 365.032798 -228.748844)
		(mid 364.789471 -228.284278)
		(end 365.032798 -227.819712)
		(width 0.1143)
		(layer "In6.Cu")
		(net "GMI_CPU1_G0_CPU0_G2_TX_DP<8>")
	)
	(arc
		(start 105.009696 -239.304068)
		(mid 104.874289 -239.439865)
		(end 104.824784 -239.625124)
		(width 0.1143)
		(layer "In6.Cu")
		(net "GMI_CPU1_G0_CPU0_G2_TX_DP<8>")
	)
	(arc
		(start 106.393488 -235.269532)
		(mid 106.278061 -235.402908)
		(end 106.236516 -235.574332)
		(width 0.1143)
		(layer "In6.Cu")
		(net "GMI_CPU1_G0_CPU0_G2_TX_DP<8>")
	)
	(arc
		(start 104.04348 -242.559586)
		(mid 103.945715 -242.662562)
		(end 103.893366 -242.794536)
		(width 0.1143)
		(layer "In6.Cu")
		(net "GMI_CPU1_G0_CPU0_G2_TX_DP<8>")
	)
	(arc
		(start 365.102394 -234.258866)
		(mid 365.259371 -233.954066)
		(end 365.102394 -233.649266)
		(width 0.1143)
		(layer "In6.Cu")
		(net "GMI_CPU1_G0_CPU0_G2_TX_DP<8>")
	)
	(arc
		(start 367.382806 -242.518692)
		(mid 367.203993 -242.316342)
		(end 367.139474 -242.054126)
		(width 0.1143)
		(layer "In6.Cu")
		(net "GMI_CPU1_G0_CPU0_G2_TX_DP<8>")
	)
	(arc
		(start 106.236516 -230.71455)
		(mid 106.277482 -230.884956)
		(end 106.391456 -231.01808)
		(width 0.1143)
		(layer "In6.Cu")
		(net "GMI_CPU1_G0_CPU0_G2_TX_DP<8>")
	)
	(arc
		(start 366.671098 -239.62487)
		(mid 366.621558 -239.439631)
		(end 366.486186 -239.303814)
		(width 0.1143)
		(layer "In6.Cu")
		(net "GMI_CPU1_G0_CPU0_G2_TX_DP<8>")
	)
	(arc
		(start 363.624114 -224.700084)
		(mid 363.44417 -224.497403)
		(end 363.379258 -224.234248)
		(width 0.1143)
		(layer "In6.Cu")
		(net "GMI_CPU1_G0_CPU0_G2_TX_DP<8>")
	)
	(arc
		(start 363.149134 -223.886776)
		(mid 362.97253 -223.684845)
		(end 362.90885 -223.424242)
		(width 0.1143)
		(layer "In6.Cu")
		(net "GMI_CPU1_G0_CPU0_G2_TX_DP<8>")
	)
	(arc
		(start 364.789466 -229.904036)
		(mid 364.853981 -229.641817)
		(end 365.032798 -229.43947)
		(width 0.1143)
		(layer "In6.Cu")
		(net "GMI_CPU1_G0_CPU0_G2_TX_DP<8>")
	)
	(arc
		(start 106.393488 -232.029508)
		(mid 106.236511 -232.334308)
		(end 106.393488 -232.639108)
		(width 0.1143)
		(layer "In6.Cu")
		(net "GMI_CPU1_G0_CPU0_G2_TX_DP<8>")
	)
	(arc
		(start 366.886744 -241.690144)
		(mid 366.658136 -241.24412)
		(end 366.886744 -240.798096)
		(width 0.1143)
		(layer "In6.Cu")
		(net "GMI_CPU1_G0_CPU0_G2_TX_DP<8>")
	)
	(arc
		(start 363.849158 -225.044254)
		(mid 363.807609 -224.872832)
		(end 363.692186 -224.739454)
		(width 0.1143)
		(layer "In6.Cu")
		(net "GMI_CPU1_G0_CPU0_G2_TX_DP<8>")
	)
	(arc
		(start 365.259366 -229.094284)
		(mid 365.217817 -228.922862)
		(end 365.102394 -228.789484)
		(width 0.1143)
		(layer "In6.Cu")
		(net "GMI_CPU1_G0_CPU0_G2_TX_DP<8>")
	)
	(arc
		(start 108.587032 -223.424496)
		(mid 108.523384 -223.685116)
		(end 108.346748 -223.88703)
		(width 0.1143)
		(layer "In6.Cu")
		(net "GMI_CPU1_G0_CPU0_G2_TX_DP<8>")
	)
	(arc
		(start 108.116624 -224.234502)
		(mid 108.051743 -224.497673)
		(end 107.871768 -224.700338)
		(width 0.1143)
		(layer "In6.Cu")
		(net "GMI_CPU1_G0_CPU0_G2_TX_DP<8>")
	)
	(arc
		(start 366.19942 -237.19409)
		(mid 366.157871 -237.022668)
		(end 366.042448 -236.88929)
		(width 0.1143)
		(layer "In6.Cu")
		(net "GMI_CPU1_G0_CPU0_G2_TX_DP<8>")
	)
	(arc
		(start 109.056424 -222.61449)
		(mid 108.991257 -222.878014)
		(end 108.810806 -223.080834)
		(width 0.1143)
		(layer "In6.Cu")
		(net "GMI_CPU1_G0_CPU0_G2_TX_DP<8>")
	)
	(arc
		(start 364.306866 -225.83394)
		(mid 364.260097 -225.659556)
		(end 364.132368 -225.531934)
		(width 0.1143)
		(layer "In6.Cu")
		(net "GMI_CPU1_G0_CPU0_G2_TX_DP<8>")
	)
	(arc
		(start 364.789466 -226.664266)
		(mid 364.748354 -226.493634)
		(end 364.634018 -226.360482)
		(width 0.1143)
		(layer "In6.Cu")
		(net "GMI_CPU1_G0_CPU0_G2_TX_DP<8>")
	)
	(arc
		(start 105.296462 -237.194344)
		(mid 105.231947 -237.456563)
		(end 105.05313 -237.65891)
		(width 0.1143)
		(layer "In6.Cu")
		(net "GMI_CPU1_G0_CPU0_G2_TX_DP<8>")
	)
	(arc
		(start 106.393488 -228.789738)
		(mid 106.278061 -228.923114)
		(end 106.236516 -229.094538)
		(width 0.1143)
		(layer "In6.Cu")
		(net "GMI_CPU1_G0_CPU0_G2_TX_DP<8>")
	)
	(arc
		(start 365.032798 -227.128832)
		(mid 364.853985 -226.926482)
		(end 364.789466 -226.664266)
		(width 0.1143)
		(layer "In6.Cu")
		(net "GMI_CPU1_G0_CPU0_G2_TX_DP<8>")
	)
	(arc
		(start 106.463084 -232.679748)
		(mid 106.706411 -233.144314)
		(end 106.463084 -233.60888)
		(width 0.1143)
		(layer "In6.Cu")
		(net "GMI_CPU1_G0_CPU0_G2_TX_DP<8>")
	)
	(arc
		(start 104.51211 -240.13033)
		(mid 104.356283 -240.434471)
		(end 104.512364 -240.738406)
		(width 0.1143)
		(layer "In6.Cu")
		(net "GMI_CPU1_G0_CPU0_G2_TX_DP<8>")
	)
	(arc
		(start 366.53343 -238.294164)
		(mid 366.682144 -238.004096)
		(end 366.53343 -237.714028)
		(width 0.1143)
		(layer "In6.Cu")
		(net "GMI_CPU1_G0_CPU0_G2_TX_DP<8>")
	)
	(arc
		(start 363.379258 -224.232724)
		(mid 363.336692 -224.060788)
		(end 363.219238 -223.928178)
		(width 0.1143)
		(layer "In6.Cu")
		(net "GMI_CPU1_G0_CPU0_G2_TX_DP<8>")
	)
	(arc
		(start 105.05313 -238.34979)
		(mid 105.296457 -238.814356)
		(end 105.05313 -239.278922)
		(width 0.1143)
		(layer "In6.Cu")
		(net "GMI_CPU1_G0_CPU0_G2_TX_DP<8>")
	)
	(arc
		(start 108.276644 -223.928432)
		(mid 108.159116 -224.061003)
		(end 108.116624 -224.232978)
		(width 0.1143)
		(layer "In6.Cu")
		(net "GMI_CPU1_G0_CPU0_G2_TX_DP<8>")
	)
	(arc
		(start 365.102394 -227.779072)
		(mid 365.259371 -227.474272)
		(end 365.102394 -227.169472)
		(width 0.1143)
		(layer "In6.Cu")
		(net "GMI_CPU1_G0_CPU0_G2_TX_DP<8>")
	)
	(arc
		(start 109.21238 -222.310198)
		(mid 109.097704 -222.443532)
		(end 109.056424 -222.61449)
		(width 0.1143)
		(layer "In6.Cu")
		(net "GMI_CPU1_G0_CPU0_G2_TX_DP<8>")
	)
	(arc
		(start 106.393488 -230.40975)
		(mid 106.278061 -230.543126)
		(end 106.236516 -230.71455)
		(width 0.1143)
		(layer "In6.Cu")
		(net "GMI_CPU1_G0_CPU0_G2_TX_DP<8>")
	)
	(arc
		(start 104.356408 -242.05438)
		(mid 104.291893 -242.316599)
		(end 104.113076 -242.518946)
		(width 0.1143)
		(layer "In6.Cu")
		(net "GMI_CPU1_G0_CPU0_G2_TX_DP<8>")
	)
	(arc
		(start 106.861864 -226.360736)
		(mid 106.747562 -226.493906)
		(end 106.706416 -226.66452)
		(width 0.1143)
		(layer "In6.Cu")
		(net "GMI_CPU1_G0_CPU0_G2_TX_DP<8>")
	)
	(arc
		(start 367.602516 -242.794282)
		(mid 367.550099 -242.662351)
		(end 367.452402 -242.559332)
		(width 0.1143)
		(layer "In6.Cu")
		(net "GMI_CPU1_G0_CPU0_G2_TX_DP<8>")
	)
	(arc
		(start 106.463084 -229.439724)
		(mid 106.641897 -229.642074)
		(end 106.706416 -229.90429)
		(width 0.1143)
		(layer "In6.Cu")
		(net "GMI_CPU1_G0_CPU0_G2_TX_DP<8>")
	)
	(arc
		(start 365.032798 -233.608626)
		(mid 364.789471 -233.14406)
		(end 365.032798 -232.679494)
		(width 0.1143)
		(layer "In6.Cu")
		(net "GMI_CPU1_G0_CPU0_G2_TX_DP<8>")
	)
	(arc
		(start 106.706416 -229.90429)
		(mid 106.64118 -230.167881)
		(end 106.460544 -230.370634)
		(width 0.1143)
		(layer "In6.Cu")
		(net "GMI_CPU1_G0_CPU0_G2_TX_DP<8>")
	)
	(arc
		(start 107.363514 -225.532188)
		(mid 107.23574 -225.659784)
		(end 107.189016 -225.834194)
		(width 0.1143)
		(layer "In6.Cu")
		(net "GMI_CPU1_G0_CPU0_G2_TX_DP<8>")
	)
	(arc
		(start 362.685076 -223.08058)
		(mid 362.50458 -222.877784)
		(end 362.439458 -222.614236)
		(width 0.1143)
		(layer "In6.Cu")
		(net "GMI_CPU1_G0_CPU0_G2_TX_DP<8>")
	)
	(arc
		(start 362.908596 -223.424242)
		(mid 362.866842 -223.252299)
		(end 362.750862 -223.11868)
		(width 0.1143)
		(layer "In6.Cu")
		(net "GMI_CPU1_G0_CPU0_G2_TX_DP<8>")
	)
	(arc
		(start 365.104426 -231.017826)
		(mid 365.218355 -230.884679)
		(end 365.259366 -230.714296)
		(width 0.1143)
		(layer "In6.Cu")
		(net "GMI_CPU1_G0_CPU0_G2_TX_DP<8>")
	)
	(arc
		(start 362.439458 -222.614236)
		(mid 362.398203 -222.443265)
		(end 362.283502 -222.309944)
		(width 0.1143)
		(layer "In6.Cu")
		(net "GMI_CPU1_G0_CPU0_G2_TX_DP<8>")
	)
	(arc
		(start 104.824784 -239.625124)
		(mid 104.756207 -239.894052)
		(end 104.567228 -240.09731)
		(width 0.1143)
		(layer "In6.Cu")
		(net "GMI_CPU1_G0_CPU0_G2_TX_DP<8>")
	)
	(arc
		(start 362.212636 -222.268796)
		(mid 362.033823 -222.066446)
		(end 361.969304 -221.80423)
		(width 0.1143)
		(layer "In6.Cu")
		(net "GMI_CPU1_G0_CPU0_G2_TX_DP<8>")
	)
	(arc
		(start 104.512364 -241.750088)
		(mid 104.397688 -241.883422)
		(end 104.356408 -242.05438)
		(width 0.1143)
		(layer "In6.Cu")
		(net "GMI_CPU1_G0_CPU0_G2_TX_DP<8>")
	)
	(arc
		(start 106.463084 -231.059736)
		(mid 106.706411 -231.524302)
		(end 106.463084 -231.988868)
		(width 0.1143)
		(layer "In6.Cu")
		(net "GMI_CPU1_G0_CPU0_G2_TX_DP<8>")
	)
	(arc
		(start 366.442752 -239.278668)
		(mid 366.199425 -238.814102)
		(end 366.442752 -238.349536)
		(width 0.1143)
		(layer "In6.Cu")
		(net "GMI_CPU1_G0_CPU0_G2_TX_DP<8>")
	)
	(arc
		(start 105.453434 -236.889544)
		(mid 105.338007 -237.02292)
		(end 105.296462 -237.194344)
		(width 0.1143)
		(layer "In6.Cu")
		(net "GMI_CPU1_G0_CPU0_G2_TX_DP<8>")
	)
	(arc
		(start 364.589568 -226.33432)
		(mid 364.38258 -226.127348)
		(end 364.306866 -225.844608)
		(width 0.1143)
		(layer "In6.Cu")
		(net "GMI_CPU1_G0_CPU0_G2_TX_DP<8>")
	)
	(arc
		(start 365.104426 -229.397814)
		(mid 365.218355 -229.264667)
		(end 365.259366 -229.094284)
		(width 0.1143)
		(layer "In6.Cu")
		(net "GMI_CPU1_G0_CPU0_G2_TX_DP<8>")
	)
	(arc
		(start 108.74502 -223.118934)
		(mid 108.629067 -223.252567)
		(end 108.587286 -223.424496)
		(width 0.1143)
		(layer "In6.Cu")
		(net "GMI_CPU1_G0_CPU0_G2_TX_DP<8>")
	)
	(arc
		(start 107.189016 -225.844862)
		(mid 107.113259 -226.127577)
		(end 106.906314 -226.334574)
		(width 0.1143)
		(layer "In6.Cu")
		(net "GMI_CPU1_G0_CPU0_G2_TX_DP<8>")
	)
	(arc
		(start 365.102394 -232.638854)
		(mid 365.259371 -232.334054)
		(end 365.102394 -232.029254)
		(width 0.1143)
		(layer "In6.Cu")
		(net "GMI_CPU1_G0_CPU0_G2_TX_DP<8>")
	)
	(segment
		(start 104.72801 -239.8903)
		(end 104.261158 -239.624362)
		(width 0.12954)
		(layer "F.Cu")
		(net "GMI_CPU1_G0_CPU0_G2_TX_DP<7>")
	)
	(segment
		(start 366.767872 -239.890046)
		(end 367.234724 -239.624108)
		(width 0.12954)
		(layer "F.Cu")
		(net "GMI_CPU1_G0_CPU0_G2_TX_DP<7>")
	)
	(segment
		(start 105.01503 -236.06125)
		(end 105.014014 -236.061758)
		(width 0.1143)
		(layer "In6.Cu")
		(net "GMI_CPU1_G0_CPU0_G2_TX_DP<7>")
	)
	(segment
		(start 363.189266 -222.290132)
		(end 363.15269 -222.268796)
		(width 0.1143)
		(layer "In6.Cu")
		(net "GMI_CPU1_G0_CPU0_G2_TX_DP<7>")
	)
	(segment
		(start 105.52303 -233.60888)
		(end 105.483914 -233.63174)
		(width 0.1143)
		(layer "In6.Cu")
		(net "GMI_CPU1_G0_CPU0_G2_TX_DP<7>")
	)
	(segment
		(start 118.54942 -209.30743)
		(end 118.367556 -209.283554)
		(width 0.14224)
		(layer "In6.Cu")
		(net "GMI_CPU1_G0_CPU0_G2_TX_DP<7>")
	)
	(segment
		(start 366.95253 -236.872018)
		(end 366.951768 -236.87151)
		(width 0.1143)
		(layer "In6.Cu")
		(net "GMI_CPU1_G0_CPU0_G2_TX_DP<7>")
	)
	(segment
		(start 363.223556 -222.309944)
		(end 363.191806 -222.291656)
		(width 0.1143)
		(layer "In6.Cu")
		(net "GMI_CPU1_G0_CPU0_G2_TX_DP<7>")
	)
	(segment
		(start 105.014014 -236.061758)
		(end 105.013252 -236.062266)
		(width 0.1143)
		(layer "In6.Cu")
		(net "GMI_CPU1_G0_CPU0_G2_TX_DP<7>")
	)
	(segment
		(start 366.042448 -228.789484)
		(end 365.972852 -228.748844)
		(width 0.1143)
		(layer "In6.Cu")
		(net "GMI_CPU1_G0_CPU0_G2_TX_DP<7>")
	)
	(segment
		(start 366.951768 -236.87151)
		(end 366.95126 -236.871002)
		(width 0.1143)
		(layer "In6.Cu")
		(net "GMI_CPU1_G0_CPU0_G2_TX_DP<7>")
	)
	(segment
		(start 108.304076 -222.29191)
		(end 108.272326 -222.310198)
		(width 0.1143)
		(layer "In6.Cu")
		(net "GMI_CPU1_G0_CPU0_G2_TX_DP<7>")
	)
	(segment
		(start 366.042448 -227.169472)
		(end 365.972852 -227.128832)
		(width 0.1143)
		(layer "In6.Cu")
		(net "GMI_CPU1_G0_CPU0_G2_TX_DP<7>")
	)
	(segment
		(start 363.191806 -222.291656)
		(end 363.19079 -222.291148)
		(width 0.1143)
		(layer "In6.Cu")
		(net "GMI_CPU1_G0_CPU0_G2_TX_DP<7>")
	)
	(segment
		(start 121.494296 -207.047592)
		(end 121.161556 -207.303116)
		(width 0.14224)
		(layer "In6.Cu")
		(net "GMI_CPU1_G0_CPU0_G2_TX_DP<7>")
	)
	(segment
		(start 109.725968 -217.383106)
		(end 108.631228 -220.025976)
		(width 0.14224)
		(layer "In6.Cu")
		(net "GMI_CPU1_G0_CPU0_G2_TX_DP<7>")
	)
	(segment
		(start 118.035324 -209.53857)
		(end 118.011448 -209.72018)
		(width 0.14224)
		(layer "In6.Cu")
		(net "GMI_CPU1_G0_CPU0_G2_TX_DP<7>")
	)
	(segment
		(start 105.483914 -231.036876)
		(end 105.520998 -231.058212)
		(width 0.1143)
		(layer "In6.Cu")
		(net "GMI_CPU1_G0_CPU0_G2_TX_DP<7>")
	)
	(segment
		(start 362.864654 -219.603066)
		(end 362.276644 -218.18346)
		(width 0.14224)
		(layer "In6.Cu")
		(net "GMI_CPU1_G0_CPU0_G2_TX_DP<7>")
	)
	(segment
		(start 108.585508 -221.246954)
		(end 108.586524 -221.24797)
		(width 0.1143)
		(layer "In6.Cu")
		(net "GMI_CPU1_G0_CPU0_G2_TX_DP<7>")
	)
	(segment
		(start 354.636324 -211.398612)
		(end 315.992764 -187.097924)
		(width 0.14224)
		(layer "In6.Cu")
		(net "GMI_CPU1_G0_CPU0_G2_TX_DP<7>")
	)
	(segment
		(start 367.452402 -237.699296)
		(end 367.382806 -237.658656)
		(width 0.1143)
		(layer "In6.Cu")
		(net "GMI_CPU1_G0_CPU0_G2_TX_DP<7>")
	)
	(segment
		(start 366.479328 -236.05998)
		(end 366.442752 -236.038644)
		(width 0.1143)
		(layer "In6.Cu")
		(net "GMI_CPU1_G0_CPU0_G2_TX_DP<7>")
	)
	(segment
		(start 117.678708 -209.97545)
		(end 117.497098 -209.951574)
		(width 0.14224)
		(layer "In6.Cu")
		(net "GMI_CPU1_G0_CPU0_G2_TX_DP<7>")
	)
	(segment
		(start 105.955084 -226.341432)
		(end 105.954068 -226.34194)
		(width 0.1143)
		(layer "In6.Cu")
		(net "GMI_CPU1_G0_CPU0_G2_TX_DP<7>")
	)
	(segment
		(start 106.423206 -225.535998)
		(end 106.421174 -225.537268)
		(width 0.1143)
		(layer "In6.Cu")
		(net "GMI_CPU1_G0_CPU0_G2_TX_DP<7>")
	)
	(segment
		(start 121.161556 -207.303116)
		(end 120.979692 -207.27924)
		(width 0.14224)
		(layer "In6.Cu")
		(net "GMI_CPU1_G0_CPU0_G2_TX_DP<7>")
	)
	(segment
		(start 107.870752 -223.080834)
		(end 107.83443 -223.101916)
		(width 0.1143)
		(layer "In6.Cu")
		(net "GMI_CPU1_G0_CPU0_G2_TX_DP<7>")
	)
	(segment
		(start 105.013252 -236.062266)
		(end 104.98328 -236.079538)
		(width 0.1143)
		(layer "In6.Cu")
		(net "GMI_CPU1_G0_CPU0_G2_TX_DP<7>")
	)
	(segment
		(start 122.90298 -205.966568)
		(end 122.72137 -205.942692)
		(width 0.14224)
		(layer "In6.Cu")
		(net "GMI_CPU1_G0_CPU0_G2_TX_DP<7>")
	)
	(segment
		(start 363.19079 -222.291148)
		(end 363.189266 -222.290132)
		(width 0.1143)
		(layer "In6.Cu")
		(net "GMI_CPU1_G0_CPU0_G2_TX_DP<7>")
	)
	(segment
		(start 108.631228 -220.025976)
		(end 108.631228 -221.064836)
		(width 0.14224)
		(layer "In6.Cu")
		(net "GMI_CPU1_G0_CPU0_G2_TX_DP<7>")
	)
	(segment
		(start 123.259596 -205.529688)
		(end 123.23572 -205.711298)
		(width 0.14224)
		(layer "In6.Cu")
		(net "GMI_CPU1_G0_CPU0_G2_TX_DP<7>")
	)
	(segment
		(start 122.365008 -206.379572)
		(end 122.032268 -206.634842)
		(width 0.14224)
		(layer "In6.Cu")
		(net "GMI_CPU1_G0_CPU0_G2_TX_DP<7>")
	)
	(segment
		(start 362.864654 -221.081346)
		(end 362.864654 -219.603066)
		(width 0.14224)
		(layer "In6.Cu")
		(net "GMI_CPU1_G0_CPU0_G2_TX_DP<7>")
	)
	(segment
		(start 358.85755 -214.765636)
		(end 354.636324 -211.398612)
		(width 0.14224)
		(layer "In6.Cu")
		(net "GMI_CPU1_G0_CPU0_G2_TX_DP<7>")
	)
	(segment
		(start 104.543352 -236.872272)
		(end 104.512364 -236.890052)
		(width 0.1143)
		(layer "In6.Cu")
		(net "GMI_CPU1_G0_CPU0_G2_TX_DP<7>")
	)
	(segment
		(start 105.953306 -226.342448)
		(end 105.922318 -226.360228)
		(width 0.1143)
		(layer "In6.Cu")
		(net "GMI_CPU1_G0_CPU0_G2_TX_DP<7>")
	)
	(segment
		(start 365.972852 -229.43947)
		(end 366.011968 -229.41661)
		(width 0.1143)
		(layer "In6.Cu")
		(net "GMI_CPU1_G0_CPU0_G2_TX_DP<7>")
	)
	(segment
		(start 104.113076 -239.278922)
		(end 104.07396 -239.301782)
		(width 0.1143)
		(layer "In6.Cu")
		(net "GMI_CPU1_G0_CPU0_G2_TX_DP<7>")
	)
	(segment
		(start 363.661452 -223.101662)
		(end 363.62513 -223.08058)
		(width 0.1143)
		(layer "In6.Cu")
		(net "GMI_CPU1_G0_CPU0_G2_TX_DP<7>")
	)
	(segment
		(start 105.483914 -233.63174)
		(end 105.453434 -233.64952)
		(width 0.1143)
		(layer "In6.Cu")
		(net "GMI_CPU1_G0_CPU0_G2_TX_DP<7>")
	)
	(segment
		(start 106.895138 -224.72142)
		(end 106.890058 -224.724214)
		(width 0.1143)
		(layer "In6.Cu")
		(net "GMI_CPU1_G0_CPU0_G2_TX_DP<7>")
	)
	(segment
		(start 365.076486 -225.537776)
		(end 365.074708 -225.537014)
		(width 0.1143)
		(layer "In6.Cu")
		(net "GMI_CPU1_G0_CPU0_G2_TX_DP<7>")
	)
	(segment
		(start 105.451402 -229.398068)
		(end 105.483914 -229.416864)
		(width 0.1143)
		(layer "In6.Cu")
		(net "GMI_CPU1_G0_CPU0_G2_TX_DP<7>")
	)
	(segment
		(start 105.954068 -226.34194)
		(end 105.953306 -226.342448)
		(width 0.1143)
		(layer "In6.Cu")
		(net "GMI_CPU1_G0_CPU0_G2_TX_DP<7>")
	)
	(segment
		(start 108.586524 -221.24797)
		(end 108.586524 -221.804484)
		(width 0.1143)
		(layer "In6.Cu")
		(net "GMI_CPU1_G0_CPU0_G2_TX_DP<7>")
	)
	(segment
		(start 108.306616 -222.290386)
		(end 108.305092 -222.291402)
		(width 0.1143)
		(layer "In6.Cu")
		(net "GMI_CPU1_G0_CPU0_G2_TX_DP<7>")
	)
	(segment
		(start 366.042448 -232.029254)
		(end 365.972852 -231.988614)
		(width 0.1143)
		(layer "In6.Cu")
		(net "GMI_CPU1_G0_CPU0_G2_TX_DP<7>")
	)
	(segment
		(start 104.07396 -237.68177)
		(end 104.04348 -237.69955)
		(width 0.1143)
		(layer "In6.Cu")
		(net "GMI_CPU1_G0_CPU0_G2_TX_DP<7>")
	)
	(segment
		(start 105.957624 -226.339908)
		(end 105.956608 -226.340416)
		(width 0.1143)
		(layer "In6.Cu")
		(net "GMI_CPU1_G0_CPU0_G2_TX_DP<7>")
	)
	(segment
		(start 123.23572 -205.711298)
		(end 122.90298 -205.966568)
		(width 0.14224)
		(layer "In6.Cu")
		(net "GMI_CPU1_G0_CPU0_G2_TX_DP<7>")
	)
	(segment
		(start 366.983518 -236.889798)
		(end 366.9538 -236.87278)
		(width 0.1143)
		(layer "In6.Cu")
		(net "GMI_CPU1_G0_CPU0_G2_TX_DP<7>")
	)
	(segment
		(start 105.52303 -235.228892)
		(end 105.483914 -235.251752)
		(width 0.1143)
		(layer "In6.Cu")
		(net "GMI_CPU1_G0_CPU0_G2_TX_DP<7>")
	)
	(segment
		(start 366.042448 -230.409496)
		(end 365.975392 -230.37038)
		(width 0.1143)
		(layer "In6.Cu")
		(net "GMI_CPU1_G0_CPU0_G2_TX_DP<7>")
	)
	(segment
		(start 105.483914 -227.797106)
		(end 105.52303 -227.819966)
		(width 0.1143)
		(layer "In6.Cu")
		(net "GMI_CPU1_G0_CPU0_G2_TX_DP<7>")
	)
	(segment
		(start 365.538258 -226.339654)
		(end 365.502698 -226.318826)
		(width 0.1143)
		(layer "In6.Cu")
		(net "GMI_CPU1_G0_CPU0_G2_TX_DP<7>")
	)
	(segment
		(start 105.520998 -231.058212)
		(end 105.52303 -231.059736)
		(width 0.1143)
		(layer "In6.Cu")
		(net "GMI_CPU1_G0_CPU0_G2_TX_DP<7>")
	)
	(segment
		(start 121.850404 -206.610966)
		(end 121.518172 -206.865982)
		(width 0.14224)
		(layer "In6.Cu")
		(net "GMI_CPU1_G0_CPU0_G2_TX_DP<7>")
	)
	(segment
		(start 366.48263 -236.062012)
		(end 366.481868 -236.061504)
		(width 0.1143)
		(layer "In6.Cu")
		(net "GMI_CPU1_G0_CPU0_G2_TX_DP<7>")
	)
	(segment
		(start 116.626386 -210.619594)
		(end 116.03736 -211.071714)
		(width 0.14224)
		(layer "In6.Cu")
		(net "GMI_CPU1_G0_CPU0_G2_TX_DP<7>")
	)
	(segment
		(start 366.042448 -235.269278)
		(end 365.972852 -235.228638)
		(width 0.1143)
		(layer "In6.Cu")
		(net "GMI_CPU1_G0_CPU0_G2_TX_DP<7>")
	)
	(segment
		(start 118.88216 -209.05216)
		(end 118.54942 -209.30743)
		(width 0.14224)
		(layer "In6.Cu")
		(net "GMI_CPU1_G0_CPU0_G2_TX_DP<7>")
	)
	(segment
		(start 364.600744 -224.721166)
		(end 364.56112 -224.698052)
		(width 0.1143)
		(layer "In6.Cu")
		(net "GMI_CPU1_G0_CPU0_G2_TX_DP<7>")
	)
	(segment
		(start 366.481868 -236.061504)
		(end 366.480852 -236.060996)
		(width 0.1143)
		(layer "In6.Cu")
		(net "GMI_CPU1_G0_CPU0_G2_TX_DP<7>")
	)
	(segment
		(start 106.890058 -224.724214)
		(end 106.883454 -224.728278)
		(width 0.1143)
		(layer "In6.Cu")
		(net "GMI_CPU1_G0_CPU0_G2_TX_DP<7>")
	)
	(segment
		(start 365.074708 -225.537014)
		(end 365.072676 -225.535744)
		(width 0.1143)
		(layer "In6.Cu")
		(net "GMI_CPU1_G0_CPU0_G2_TX_DP<7>")
	)
	(segment
		(start 107.83443 -223.101916)
		(end 107.804966 -223.118934)
		(width 0.1143)
		(layer "In6.Cu")
		(net "GMI_CPU1_G0_CPU0_G2_TX_DP<7>")
	)
	(segment
		(start 108.631228 -221.064836)
		(end 108.631228 -221.093284)
		(width 0.1143)
		(layer "In6.Cu")
		(net "GMI_CPU1_G0_CPU0_G2_TX_DP<7>")
	)
	(segment
		(start 104.07396 -238.32693)
		(end 104.113076 -238.34979)
		(width 0.1143)
		(layer "In6.Cu")
		(net "GMI_CPU1_G0_CPU0_G2_TX_DP<7>")
	)
	(segment
		(start 105.483914 -232.011728)
		(end 105.453434 -232.029508)
		(width 0.1143)
		(layer "In6.Cu")
		(net "GMI_CPU1_G0_CPU0_G2_TX_DP<7>")
	)
	(segment
		(start 367.234724 -239.624108)
		(end 367.532666 -239.624108)
		(width 0.1143)
		(layer "In6.Cu")
		(net "GMI_CPU1_G0_CPU0_G2_TX_DP<7>")
	)
	(segment
		(start 105.483914 -227.151946)
		(end 105.453434 -227.169726)
		(width 0.1143)
		(layer "In6.Cu")
		(net "GMI_CPU1_G0_CPU0_G2_TX_DP<7>")
	)
	(segment
		(start 365.540798 -226.341178)
		(end 365.539274 -226.340162)
		(width 0.1143)
		(layer "In6.Cu")
		(net "GMI_CPU1_G0_CPU0_G2_TX_DP<7>")
	)
	(segment
		(start 362.864654 -221.09303)
		(end 362.864654 -221.081346)
		(width 0.1143)
		(layer "In6.Cu")
		(net "GMI_CPU1_G0_CPU0_G2_TX_DP<7>")
	)
	(segment
		(start 104.04348 -238.30915)
		(end 104.07396 -238.32693)
		(width 0.1143)
		(layer "In6.Cu")
		(net "GMI_CPU1_G0_CPU0_G2_TX_DP<7>")
	)
	(segment
		(start 107.364784 -223.911922)
		(end 107.331002 -223.93148)
		(width 0.1143)
		(layer "In6.Cu")
		(net "GMI_CPU1_G0_CPU0_G2_TX_DP<7>")
	)
	(segment
		(start 120.10898 -207.94726)
		(end 119.776748 -208.202276)
		(width 0.14224)
		(layer "In6.Cu")
		(net "GMI_CPU1_G0_CPU0_G2_TX_DP<7>")
	)
	(segment
		(start 120.290844 -207.971136)
		(end 120.10898 -207.94726)
		(width 0.14224)
		(layer "In6.Cu")
		(net "GMI_CPU1_G0_CPU0_G2_TX_DP<7>")
	)
	(segment
		(start 117.497098 -209.951574)
		(end 117.164612 -210.20659)
		(width 0.14224)
		(layer "In6.Cu")
		(net "GMI_CPU1_G0_CPU0_G2_TX_DP<7>")
	)
	(segment
		(start 365.972852 -231.059482)
		(end 365.974884 -231.057958)
		(width 0.1143)
		(layer "In6.Cu")
		(net "GMI_CPU1_G0_CPU0_G2_TX_DP<7>")
	)
	(segment
		(start 366.512602 -236.079284)
		(end 366.48263 -236.062012)
		(width 0.1143)
		(layer "In6.Cu")
		(net "GMI_CPU1_G0_CPU0_G2_TX_DP<7>")
	)
	(segment
		(start 103.893366 -239.554512)
		(end 103.963216 -239.624362)
		(width 0.1143)
		(layer "In6.Cu")
		(net "GMI_CPU1_G0_CPU0_G2_TX_DP<7>")
	)
	(segment
		(start 308.275482 -182.108348)
		(end 306.64023 -181.659276)
		(width 0.14224)
		(layer "In6.Cu")
		(net "GMI_CPU1_G0_CPU0_G2_TX_DP<7>")
	)
	(segment
		(start 122.388884 -206.197708)
		(end 122.365008 -206.379572)
		(width 0.14224)
		(layer "In6.Cu")
		(net "GMI_CPU1_G0_CPU0_G2_TX_DP<7>")
	)
	(segment
		(start 122.72137 -205.942692)
		(end 122.388884 -206.197708)
		(width 0.14224)
		(layer "In6.Cu")
		(net "GMI_CPU1_G0_CPU0_G2_TX_DP<7>")
	)
	(segment
		(start 118.367556 -209.283554)
		(end 118.035324 -209.53857)
		(width 0.14224)
		(layer "In6.Cu")
		(net "GMI_CPU1_G0_CPU0_G2_TX_DP<7>")
	)
	(segment
		(start 315.109098 -186.166506)
		(end 308.275482 -182.108348)
		(width 0.14224)
		(layer "In6.Cu")
		(net "GMI_CPU1_G0_CPU0_G2_TX_DP<7>")
	)
	(segment
		(start 362.909358 -221.80423)
		(end 362.909358 -221.247716)
		(width 0.1143)
		(layer "In6.Cu")
		(net "GMI_CPU1_G0_CPU0_G2_TX_DP<7>")
	)
	(segment
		(start 164.088572 -181.820566)
		(end 123.960128 -204.99197)
		(width 0.14224)
		(layer "In6.Cu")
		(net "GMI_CPU1_G0_CPU0_G2_TX_DP<7>")
	)
	(segment
		(start 105.483914 -234.2769)
		(end 105.52303 -234.29976)
		(width 0.1143)
		(layer "In6.Cu")
		(net "GMI_CPU1_G0_CPU0_G2_TX_DP<7>")
	)
	(segment
		(start 367.532666 -239.624108)
		(end 367.602516 -239.554258)
		(width 0.1143)
		(layer "In6.Cu")
		(net "GMI_CPU1_G0_CPU0_G2_TX_DP<7>")
	)
	(segment
		(start 117.164612 -210.20659)
		(end 117.140736 -210.3882)
		(width 0.14224)
		(layer "In6.Cu")
		(net "GMI_CPU1_G0_CPU0_G2_TX_DP<7>")
	)
	(segment
		(start 366.042448 -233.649266)
		(end 365.972852 -233.608626)
		(width 0.1143)
		(layer "In6.Cu")
		(net "GMI_CPU1_G0_CPU0_G2_TX_DP<7>")
	)
	(segment
		(start 119.776748 -208.202276)
		(end 119.752872 -208.38414)
		(width 0.14224)
		(layer "In6.Cu")
		(net "GMI_CPU1_G0_CPU0_G2_TX_DP<7>")
	)
	(segment
		(start 362.910374 -221.2467)
		(end 362.910374 -221.13875)
		(width 0.1143)
		(layer "In6.Cu")
		(net "GMI_CPU1_G0_CPU0_G2_TX_DP<7>")
	)
	(segment
		(start 302.898048 -181.659276)
		(end 167.673782 -180.87086)
		(width 0.14224)
		(layer "In6.Cu")
		(net "GMI_CPU1_G0_CPU0_G2_TX_DP<7>")
	)
	(segment
		(start 105.52303 -228.749098)
		(end 105.483914 -228.771958)
		(width 0.1143)
		(layer "In6.Cu")
		(net "GMI_CPU1_G0_CPU0_G2_TX_DP<7>")
	)
	(segment
		(start 120.64746 -207.534256)
		(end 120.623584 -207.715866)
		(width 0.14224)
		(layer "In6.Cu")
		(net "GMI_CPU1_G0_CPU0_G2_TX_DP<7>")
	)
	(segment
		(start 116.807996 -210.64347)
		(end 116.626386 -210.619594)
		(width 0.14224)
		(layer "In6.Cu")
		(net "GMI_CPU1_G0_CPU0_G2_TX_DP<7>")
	)
	(segment
		(start 364.612428 -224.728024)
		(end 364.605824 -224.72396)
		(width 0.1143)
		(layer "In6.Cu")
		(net "GMI_CPU1_G0_CPU0_G2_TX_DP<7>")
	)
	(segment
		(start 365.542576 -226.342194)
		(end 365.541814 -226.341686)
		(width 0.1143)
		(layer "In6.Cu")
		(net "GMI_CPU1_G0_CPU0_G2_TX_DP<7>")
	)
	(segment
		(start 365.573564 -226.359974)
		(end 365.543846 -226.342956)
		(width 0.1143)
		(layer "In6.Cu")
		(net "GMI_CPU1_G0_CPU0_G2_TX_DP<7>")
	)
	(segment
		(start 366.480852 -236.060996)
		(end 366.479328 -236.05998)
		(width 0.1143)
		(layer "In6.Cu")
		(net "GMI_CPU1_G0_CPU0_G2_TX_DP<7>")
	)
	(segment
		(start 363.690916 -223.11868)
		(end 363.661452 -223.101662)
		(width 0.1143)
		(layer "In6.Cu")
		(net "GMI_CPU1_G0_CPU0_G2_TX_DP<7>")
	)
	(segment
		(start 367.452402 -239.319308)
		(end 367.382806 -239.278668)
		(width 0.1143)
		(layer "In6.Cu")
		(net "GMI_CPU1_G0_CPU0_G2_TX_DP<7>")
	)
	(segment
		(start 119.420132 -208.63941)
		(end 119.238268 -208.615534)
		(width 0.14224)
		(layer "In6.Cu")
		(net "GMI_CPU1_G0_CPU0_G2_TX_DP<7>")
	)
	(segment
		(start 366.9538 -236.87278)
		(end 366.95253 -236.872018)
		(width 0.1143)
		(layer "In6.Cu")
		(net "GMI_CPU1_G0_CPU0_G2_TX_DP<7>")
	)
	(segment
		(start 106.421174 -225.537268)
		(end 106.419396 -225.53803)
		(width 0.1143)
		(layer "In6.Cu")
		(net "GMI_CPU1_G0_CPU0_G2_TX_DP<7>")
	)
	(segment
		(start 365.543846 -226.342956)
		(end 365.542576 -226.342194)
		(width 0.1143)
		(layer "In6.Cu")
		(net "GMI_CPU1_G0_CPU0_G2_TX_DP<7>")
	)
	(segment
		(start 105.05313 -236.038898)
		(end 105.016554 -236.060234)
		(width 0.1143)
		(layer "In6.Cu")
		(net "GMI_CPU1_G0_CPU0_G2_TX_DP<7>")
	)
	(segment
		(start 364.131098 -223.911668)
		(end 364.091982 -223.888808)
		(width 0.1143)
		(layer "In6.Cu")
		(net "GMI_CPU1_G0_CPU0_G2_TX_DP<7>")
	)
	(segment
		(start 105.52303 -231.988868)
		(end 105.483914 -232.011728)
		(width 0.1143)
		(layer "In6.Cu")
		(net "GMI_CPU1_G0_CPU0_G2_TX_DP<7>")
	)
	(segment
		(start 105.52303 -227.129086)
		(end 105.483914 -227.151946)
		(width 0.1143)
		(layer "In6.Cu")
		(net "GMI_CPU1_G0_CPU0_G2_TX_DP<7>")
	)
	(segment
		(start 120.979692 -207.27924)
		(end 120.64746 -207.534256)
		(width 0.14224)
		(layer "In6.Cu")
		(net "GMI_CPU1_G0_CPU0_G2_TX_DP<7>")
	)
	(segment
		(start 367.382806 -238.349536)
		(end 367.452402 -238.308896)
		(width 0.1143)
		(layer "In6.Cu")
		(net "GMI_CPU1_G0_CPU0_G2_TX_DP<7>")
	)
	(segment
		(start 105.483914 -235.251752)
		(end 105.453434 -235.269532)
		(width 0.1143)
		(layer "In6.Cu")
		(net "GMI_CPU1_G0_CPU0_G2_TX_DP<7>")
	)
	(segment
		(start 364.605824 -224.72396)
		(end 364.600744 -224.721166)
		(width 0.1143)
		(layer "In6.Cu")
		(net "GMI_CPU1_G0_CPU0_G2_TX_DP<7>")
	)
	(segment
		(start 121.518172 -206.865982)
		(end 121.494296 -207.047592)
		(width 0.14224)
		(layer "In6.Cu")
		(net "GMI_CPU1_G0_CPU0_G2_TX_DP<7>")
	)
	(segment
		(start 362.909358 -221.247716)
		(end 362.910374 -221.2467)
		(width 0.1143)
		(layer "In6.Cu")
		(net "GMI_CPU1_G0_CPU0_G2_TX_DP<7>")
	)
	(segment
		(start 119.752872 -208.38414)
		(end 119.420132 -208.63941)
		(width 0.14224)
		(layer "In6.Cu")
		(net "GMI_CPU1_G0_CPU0_G2_TX_DP<7>")
	)
	(segment
		(start 306.64023 -181.659276)
		(end 302.898048 -181.659276)
		(width 0.14224)
		(layer "In6.Cu")
		(net "GMI_CPU1_G0_CPU0_G2_TX_DP<7>")
	)
	(segment
		(start 118.011448 -209.72018)
		(end 117.678708 -209.97545)
		(width 0.14224)
		(layer "In6.Cu")
		(net "GMI_CPU1_G0_CPU0_G2_TX_DP<7>")
	)
	(segment
		(start 105.453434 -227.779326)
		(end 105.483914 -227.797106)
		(width 0.1143)
		(layer "In6.Cu")
		(net "GMI_CPU1_G0_CPU0_G2_TX_DP<7>")
	)
	(segment
		(start 105.453434 -234.25912)
		(end 105.483914 -234.2769)
		(width 0.1143)
		(layer "In6.Cu")
		(net "GMI_CPU1_G0_CPU0_G2_TX_DP<7>")
	)
	(segment
		(start 365.974884 -231.057958)
		(end 366.011968 -231.036622)
		(width 0.1143)
		(layer "In6.Cu")
		(net "GMI_CPU1_G0_CPU0_G2_TX_DP<7>")
	)
	(segment
		(start 105.52049 -230.370634)
		(end 105.453434 -230.40975)
		(width 0.1143)
		(layer "In6.Cu")
		(net "GMI_CPU1_G0_CPU0_G2_TX_DP<7>")
	)
	(segment
		(start 104.544622 -236.871256)
		(end 104.544114 -236.871764)
		(width 0.1143)
		(layer "In6.Cu")
		(net "GMI_CPU1_G0_CPU0_G2_TX_DP<7>")
	)
	(segment
		(start 119.238268 -208.615534)
		(end 118.906036 -208.87055)
		(width 0.14224)
		(layer "In6.Cu")
		(net "GMI_CPU1_G0_CPU0_G2_TX_DP<7>")
	)
	(segment
		(start 103.963216 -239.624362)
		(end 104.261158 -239.624362)
		(width 0.1143)
		(layer "In6.Cu")
		(net "GMI_CPU1_G0_CPU0_G2_TX_DP<7>")
	)
	(segment
		(start 108.343192 -222.26905)
		(end 108.306616 -222.290386)
		(width 0.1143)
		(layer "In6.Cu")
		(net "GMI_CPU1_G0_CPU0_G2_TX_DP<7>")
	)
	(segment
		(start 364.16488 -223.931226)
		(end 364.131098 -223.911668)
		(width 0.1143)
		(layer "In6.Cu")
		(net "GMI_CPU1_G0_CPU0_G2_TX_DP<7>")
	)
	(segment
		(start 105.483914 -229.416864)
		(end 105.52303 -229.439724)
		(width 0.1143)
		(layer "In6.Cu")
		(net "GMI_CPU1_G0_CPU0_G2_TX_DP<7>")
	)
	(segment
		(start 365.972852 -232.679494)
		(end 366.042448 -232.638854)
		(width 0.1143)
		(layer "In6.Cu")
		(net "GMI_CPU1_G0_CPU0_G2_TX_DP<7>")
	)
	(segment
		(start 362.276644 -218.18346)
		(end 358.85755 -214.765636)
		(width 0.14224)
		(layer "In6.Cu")
		(net "GMI_CPU1_G0_CPU0_G2_TX_DP<7>")
	)
	(segment
		(start 167.673782 -180.87086)
		(end 164.088572 -181.820566)
		(width 0.14224)
		(layer "In6.Cu")
		(net "GMI_CPU1_G0_CPU0_G2_TX_DP<7>")
	)
	(segment
		(start 123.960128 -204.99197)
		(end 123.259596 -205.529688)
		(width 0.14224)
		(layer "In6.Cu")
		(net "GMI_CPU1_G0_CPU0_G2_TX_DP<7>")
	)
	(segment
		(start 116.03736 -211.071714)
		(end 109.725968 -217.383106)
		(width 0.14224)
		(layer "In6.Cu")
		(net "GMI_CPU1_G0_CPU0_G2_TX_DP<7>")
	)
	(segment
		(start 104.07396 -239.301782)
		(end 104.04348 -239.319562)
		(width 0.1143)
		(layer "In6.Cu")
		(net "GMI_CPU1_G0_CPU0_G2_TX_DP<7>")
	)
	(segment
		(start 104.544114 -236.871764)
		(end 104.543352 -236.872272)
		(width 0.1143)
		(layer "In6.Cu")
		(net "GMI_CPU1_G0_CPU0_G2_TX_DP<7>")
	)
	(segment
		(start 366.011968 -231.036622)
		(end 366.04448 -231.017826)
		(width 0.1143)
		(layer "In6.Cu")
		(net "GMI_CPU1_G0_CPU0_G2_TX_DP<7>")
	)
	(segment
		(start 117.140736 -210.3882)
		(end 116.807996 -210.64347)
		(width 0.14224)
		(layer "In6.Cu")
		(net "GMI_CPU1_G0_CPU0_G2_TX_DP<7>")
	)
	(segment
		(start 365.972852 -227.819712)
		(end 366.042448 -227.779072)
		(width 0.1143)
		(layer "In6.Cu")
		(net "GMI_CPU1_G0_CPU0_G2_TX_DP<7>")
	)
	(segment
		(start 315.992764 -187.097924)
		(end 315.109098 -186.166506)
		(width 0.14224)
		(layer "In6.Cu")
		(net "GMI_CPU1_G0_CPU0_G2_TX_DP<7>")
	)
	(segment
		(start 365.972852 -234.299506)
		(end 366.042448 -234.258866)
		(width 0.1143)
		(layer "In6.Cu")
		(net "GMI_CPU1_G0_CPU0_G2_TX_DP<7>")
	)
	(segment
		(start 108.585508 -221.139004)
		(end 108.585508 -221.246954)
		(width 0.1143)
		(layer "In6.Cu")
		(net "GMI_CPU1_G0_CPU0_G2_TX_DP<7>")
	)
	(segment
		(start 108.305092 -222.291402)
		(end 108.304076 -222.29191)
		(width 0.1143)
		(layer "In6.Cu")
		(net "GMI_CPU1_G0_CPU0_G2_TX_DP<7>")
	)
	(segment
		(start 108.631228 -221.093284)
		(end 108.585508 -221.139004)
		(width 0.1143)
		(layer "In6.Cu")
		(net "GMI_CPU1_G0_CPU0_G2_TX_DP<7>")
	)
	(segment
		(start 105.993184 -226.31908)
		(end 105.957624 -226.339908)
		(width 0.1143)
		(layer "In6.Cu")
		(net "GMI_CPU1_G0_CPU0_G2_TX_DP<7>")
	)
	(segment
		(start 105.956608 -226.340416)
		(end 105.955084 -226.341432)
		(width 0.1143)
		(layer "In6.Cu")
		(net "GMI_CPU1_G0_CPU0_G2_TX_DP<7>")
	)
	(segment
		(start 365.541814 -226.341686)
		(end 365.540798 -226.341178)
		(width 0.1143)
		(layer "In6.Cu")
		(net "GMI_CPU1_G0_CPU0_G2_TX_DP<7>")
	)
	(segment
		(start 105.451402 -231.01808)
		(end 105.483914 -231.036876)
		(width 0.1143)
		(layer "In6.Cu")
		(net "GMI_CPU1_G0_CPU0_G2_TX_DP<7>")
	)
	(segment
		(start 122.032268 -206.634842)
		(end 121.850404 -206.610966)
		(width 0.14224)
		(layer "In6.Cu")
		(net "GMI_CPU1_G0_CPU0_G2_TX_DP<7>")
	)
	(segment
		(start 105.483914 -228.771958)
		(end 105.453434 -228.789738)
		(width 0.1143)
		(layer "In6.Cu")
		(net "GMI_CPU1_G0_CPU0_G2_TX_DP<7>")
	)
	(segment
		(start 107.4039 -223.889062)
		(end 107.364784 -223.911922)
		(width 0.1143)
		(layer "In6.Cu")
		(net "GMI_CPU1_G0_CPU0_G2_TX_DP<7>")
	)
	(segment
		(start 106.934762 -224.698306)
		(end 106.895138 -224.72142)
		(width 0.1143)
		(layer "In6.Cu")
		(net "GMI_CPU1_G0_CPU0_G2_TX_DP<7>")
	)
	(segment
		(start 104.113076 -237.65891)
		(end 104.07396 -237.68177)
		(width 0.1143)
		(layer "In6.Cu")
		(net "GMI_CPU1_G0_CPU0_G2_TX_DP<7>")
	)
	(segment
		(start 120.623584 -207.715866)
		(end 120.290844 -207.971136)
		(width 0.14224)
		(layer "In6.Cu")
		(net "GMI_CPU1_G0_CPU0_G2_TX_DP<7>")
	)
	(segment
		(start 105.453434 -232.639108)
		(end 105.483914 -232.656888)
		(width 0.1143)
		(layer "In6.Cu")
		(net "GMI_CPU1_G0_CPU0_G2_TX_DP<7>")
	)
	(segment
		(start 362.910374 -221.13875)
		(end 362.864654 -221.09303)
		(width 0.1143)
		(layer "In6.Cu")
		(net "GMI_CPU1_G0_CPU0_G2_TX_DP<7>")
	)
	(segment
		(start 365.539274 -226.340162)
		(end 365.538258 -226.339654)
		(width 0.1143)
		(layer "In6.Cu")
		(net "GMI_CPU1_G0_CPU0_G2_TX_DP<7>")
	)
	(segment
		(start 105.483914 -232.656888)
		(end 105.52303 -232.679748)
		(width 0.1143)
		(layer "In6.Cu")
		(net "GMI_CPU1_G0_CPU0_G2_TX_DP<7>")
	)
	(segment
		(start 366.011968 -229.41661)
		(end 366.04448 -229.397814)
		(width 0.1143)
		(layer "In6.Cu")
		(net "GMI_CPU1_G0_CPU0_G2_TX_DP<7>")
	)
	(segment
		(start 105.016554 -236.060234)
		(end 105.01503 -236.06125)
		(width 0.1143)
		(layer "In6.Cu")
		(net "GMI_CPU1_G0_CPU0_G2_TX_DP<7>")
	)
	(segment
		(start 118.906036 -208.87055)
		(end 118.88216 -209.05216)
		(width 0.14224)
		(layer "In6.Cu")
		(net "GMI_CPU1_G0_CPU0_G2_TX_DP<7>")
	)
	(arc
		(start 364.091982 -223.888808)
		(mid 363.913169 -223.686458)
		(end 363.84865 -223.424242)
		(width 0.1143)
		(layer "In6.Cu")
		(net "GMI_CPU1_G0_CPU0_G2_TX_DP<7>")
	)
	(arc
		(start 105.453434 -233.64952)
		(mid 105.296457 -233.95432)
		(end 105.453434 -234.25912)
		(width 0.1143)
		(layer "In6.Cu")
		(net "GMI_CPU1_G0_CPU0_G2_TX_DP<7>")
	)
	(arc
		(start 104.04348 -237.69955)
		(mid 103.886503 -238.00435)
		(end 104.04348 -238.30915)
		(width 0.1143)
		(layer "In6.Cu")
		(net "GMI_CPU1_G0_CPU0_G2_TX_DP<7>")
	)
	(arc
		(start 367.382806 -239.278668)
		(mid 367.139479 -238.814102)
		(end 367.382806 -238.349536)
		(width 0.1143)
		(layer "In6.Cu")
		(net "GMI_CPU1_G0_CPU0_G2_TX_DP<7>")
	)
	(arc
		(start 108.11637 -222.61449)
		(mid 108.051203 -222.878014)
		(end 107.870752 -223.080834)
		(width 0.1143)
		(layer "In6.Cu")
		(net "GMI_CPU1_G0_CPU0_G2_TX_DP<7>")
	)
	(arc
		(start 105.296462 -230.71455)
		(mid 105.337428 -230.884956)
		(end 105.451402 -231.01808)
		(width 0.1143)
		(layer "In6.Cu")
		(net "GMI_CPU1_G0_CPU0_G2_TX_DP<7>")
	)
	(arc
		(start 105.922318 -226.360228)
		(mid 105.807642 -226.493562)
		(end 105.766362 -226.66452)
		(width 0.1143)
		(layer "In6.Cu")
		(net "GMI_CPU1_G0_CPU0_G2_TX_DP<7>")
	)
	(arc
		(start 105.52303 -227.819966)
		(mid 105.766357 -228.284532)
		(end 105.52303 -228.749098)
		(width 0.1143)
		(layer "In6.Cu")
		(net "GMI_CPU1_G0_CPU0_G2_TX_DP<7>")
	)
	(arc
		(start 106.419396 -225.53803)
		(mid 106.285511 -225.671748)
		(end 106.236516 -225.854514)
		(width 0.1143)
		(layer "In6.Cu")
		(net "GMI_CPU1_G0_CPU0_G2_TX_DP<7>")
	)
	(arc
		(start 105.453434 -227.169726)
		(mid 105.296457 -227.474526)
		(end 105.453434 -227.779326)
		(width 0.1143)
		(layer "In6.Cu")
		(net "GMI_CPU1_G0_CPU0_G2_TX_DP<7>")
	)
	(arc
		(start 105.52303 -232.679748)
		(mid 105.766357 -233.144314)
		(end 105.52303 -233.60888)
		(width 0.1143)
		(layer "In6.Cu")
		(net "GMI_CPU1_G0_CPU0_G2_TX_DP<7>")
	)
	(arc
		(start 105.766362 -229.90429)
		(mid 105.701126 -230.167881)
		(end 105.52049 -230.370634)
		(width 0.1143)
		(layer "In6.Cu")
		(net "GMI_CPU1_G0_CPU0_G2_TX_DP<7>")
	)
	(arc
		(start 105.296462 -229.094538)
		(mid 105.337428 -229.264944)
		(end 105.451402 -229.398068)
		(width 0.1143)
		(layer "In6.Cu")
		(net "GMI_CPU1_G0_CPU0_G2_TX_DP<7>")
	)
	(arc
		(start 365.502698 -226.318826)
		(mid 365.323885 -226.116476)
		(end 365.259366 -225.85426)
		(width 0.1143)
		(layer "In6.Cu")
		(net "GMI_CPU1_G0_CPU0_G2_TX_DP<7>")
	)
	(arc
		(start 106.236516 -225.854514)
		(mid 106.172001 -226.116733)
		(end 105.993184 -226.31908)
		(width 0.1143)
		(layer "In6.Cu")
		(net "GMI_CPU1_G0_CPU0_G2_TX_DP<7>")
	)
	(arc
		(start 366.669574 -236.384084)
		(mid 366.628025 -236.212662)
		(end 366.512602 -236.079284)
		(width 0.1143)
		(layer "In6.Cu")
		(net "GMI_CPU1_G0_CPU0_G2_TX_DP<7>")
	)
	(arc
		(start 366.04448 -231.017826)
		(mid 366.158409 -230.884679)
		(end 366.19942 -230.714296)
		(width 0.1143)
		(layer "In6.Cu")
		(net "GMI_CPU1_G0_CPU0_G2_TX_DP<7>")
	)
	(arc
		(start 364.788958 -225.044254)
		(mid 364.741771 -224.863215)
		(end 364.612428 -224.728024)
		(width 0.1143)
		(layer "In6.Cu")
		(net "GMI_CPU1_G0_CPU0_G2_TX_DP<7>")
	)
	(arc
		(start 366.442752 -236.038644)
		(mid 366.263939 -235.836294)
		(end 366.19942 -235.574078)
		(width 0.1143)
		(layer "In6.Cu")
		(net "GMI_CPU1_G0_CPU0_G2_TX_DP<7>")
	)
	(arc
		(start 365.972852 -228.748844)
		(mid 365.729525 -228.284278)
		(end 365.972852 -227.819712)
		(width 0.1143)
		(layer "In6.Cu")
		(net "GMI_CPU1_G0_CPU0_G2_TX_DP<7>")
	)
	(arc
		(start 363.379512 -222.614236)
		(mid 363.338257 -222.443265)
		(end 363.223556 -222.309944)
		(width 0.1143)
		(layer "In6.Cu")
		(net "GMI_CPU1_G0_CPU0_G2_TX_DP<7>")
	)
	(arc
		(start 365.972852 -235.228638)
		(mid 365.729525 -234.764072)
		(end 365.972852 -234.299506)
		(width 0.1143)
		(layer "In6.Cu")
		(net "GMI_CPU1_G0_CPU0_G2_TX_DP<7>")
	)
	(arc
		(start 365.072676 -225.535744)
		(mid 364.865022 -225.32799)
		(end 364.788958 -225.044254)
		(width 0.1143)
		(layer "In6.Cu")
		(net "GMI_CPU1_G0_CPU0_G2_TX_DP<7>")
	)
	(arc
		(start 104.512364 -236.890052)
		(mid 104.397688 -237.023386)
		(end 104.356408 -237.194344)
		(width 0.1143)
		(layer "In6.Cu")
		(net "GMI_CPU1_G0_CPU0_G2_TX_DP<7>")
	)
	(arc
		(start 105.52303 -231.059736)
		(mid 105.766357 -231.524302)
		(end 105.52303 -231.988868)
		(width 0.1143)
		(layer "In6.Cu")
		(net "GMI_CPU1_G0_CPU0_G2_TX_DP<7>")
	)
	(arc
		(start 367.139474 -237.19409)
		(mid 367.098219 -237.023119)
		(end 366.983518 -236.889798)
		(width 0.1143)
		(layer "In6.Cu")
		(net "GMI_CPU1_G0_CPU0_G2_TX_DP<7>")
	)
	(arc
		(start 367.382806 -237.658656)
		(mid 367.203993 -237.456306)
		(end 367.139474 -237.19409)
		(width 0.1143)
		(layer "In6.Cu")
		(net "GMI_CPU1_G0_CPU0_G2_TX_DP<7>")
	)
	(arc
		(start 366.042448 -232.638854)
		(mid 366.199425 -232.334054)
		(end 366.042448 -232.029254)
		(width 0.1143)
		(layer "In6.Cu")
		(net "GMI_CPU1_G0_CPU0_G2_TX_DP<7>")
	)
	(arc
		(start 105.52303 -234.29976)
		(mid 105.766357 -234.764326)
		(end 105.52303 -235.228892)
		(width 0.1143)
		(layer "In6.Cu")
		(net "GMI_CPU1_G0_CPU0_G2_TX_DP<7>")
	)
	(arc
		(start 105.453434 -228.789738)
		(mid 105.338007 -228.923114)
		(end 105.296462 -229.094538)
		(width 0.1143)
		(layer "In6.Cu")
		(net "GMI_CPU1_G0_CPU0_G2_TX_DP<7>")
	)
	(arc
		(start 107.804966 -223.118934)
		(mid 107.689013 -223.252567)
		(end 107.647232 -223.424496)
		(width 0.1143)
		(layer "In6.Cu")
		(net "GMI_CPU1_G0_CPU0_G2_TX_DP<7>")
	)
	(arc
		(start 108.272326 -222.310198)
		(mid 108.15765 -222.443532)
		(end 108.11637 -222.61449)
		(width 0.1143)
		(layer "In6.Cu")
		(net "GMI_CPU1_G0_CPU0_G2_TX_DP<7>")
	)
	(arc
		(start 365.972852 -233.608626)
		(mid 365.729525 -233.14406)
		(end 365.972852 -232.679494)
		(width 0.1143)
		(layer "In6.Cu")
		(net "GMI_CPU1_G0_CPU0_G2_TX_DP<7>")
	)
	(arc
		(start 366.042448 -234.258866)
		(mid 366.199425 -233.954066)
		(end 366.042448 -233.649266)
		(width 0.1143)
		(layer "In6.Cu")
		(net "GMI_CPU1_G0_CPU0_G2_TX_DP<7>")
	)
	(arc
		(start 366.042448 -227.779072)
		(mid 366.199425 -227.474272)
		(end 366.042448 -227.169472)
		(width 0.1143)
		(layer "In6.Cu")
		(net "GMI_CPU1_G0_CPU0_G2_TX_DP<7>")
	)
	(arc
		(start 106.706924 -225.044508)
		(mid 106.630913 -225.328274)
		(end 106.423206 -225.535998)
		(width 0.1143)
		(layer "In6.Cu")
		(net "GMI_CPU1_G0_CPU0_G2_TX_DP<7>")
	)
	(arc
		(start 367.452402 -238.308896)
		(mid 367.609379 -238.004096)
		(end 367.452402 -237.699296)
		(width 0.1143)
		(layer "In6.Cu")
		(net "GMI_CPU1_G0_CPU0_G2_TX_DP<7>")
	)
	(arc
		(start 107.176824 -224.234502)
		(mid 107.112671 -224.496091)
		(end 106.934762 -224.698306)
		(width 0.1143)
		(layer "In6.Cu")
		(net "GMI_CPU1_G0_CPU0_G2_TX_DP<7>")
	)
	(arc
		(start 365.972852 -231.988614)
		(mid 365.729525 -231.524048)
		(end 365.972852 -231.059482)
		(width 0.1143)
		(layer "In6.Cu")
		(net "GMI_CPU1_G0_CPU0_G2_TX_DP<7>")
	)
	(arc
		(start 366.19942 -230.714296)
		(mid 366.157871 -230.542874)
		(end 366.042448 -230.409496)
		(width 0.1143)
		(layer "In6.Cu")
		(net "GMI_CPU1_G0_CPU0_G2_TX_DP<7>")
	)
	(arc
		(start 105.453434 -232.029508)
		(mid 105.296457 -232.334308)
		(end 105.453434 -232.639108)
		(width 0.1143)
		(layer "In6.Cu")
		(net "GMI_CPU1_G0_CPU0_G2_TX_DP<7>")
	)
	(arc
		(start 364.56112 -224.698052)
		(mid 364.383225 -224.49583)
		(end 364.319058 -224.234248)
		(width 0.1143)
		(layer "In6.Cu")
		(net "GMI_CPU1_G0_CPU0_G2_TX_DP<7>")
	)
	(arc
		(start 365.972852 -227.128832)
		(mid 365.794039 -226.926482)
		(end 365.72952 -226.664266)
		(width 0.1143)
		(layer "In6.Cu")
		(net "GMI_CPU1_G0_CPU0_G2_TX_DP<7>")
	)
	(arc
		(start 104.356408 -237.194344)
		(mid 104.291893 -237.456563)
		(end 104.113076 -237.65891)
		(width 0.1143)
		(layer "In6.Cu")
		(net "GMI_CPU1_G0_CPU0_G2_TX_DP<7>")
	)
	(arc
		(start 105.296462 -235.574332)
		(mid 105.231947 -235.836551)
		(end 105.05313 -236.038898)
		(width 0.1143)
		(layer "In6.Cu")
		(net "GMI_CPU1_G0_CPU0_G2_TX_DP<7>")
	)
	(arc
		(start 104.04348 -239.319562)
		(mid 103.945715 -239.422538)
		(end 103.893366 -239.554512)
		(width 0.1143)
		(layer "In6.Cu")
		(net "GMI_CPU1_G0_CPU0_G2_TX_DP<7>")
	)
	(arc
		(start 365.72952 -226.664266)
		(mid 365.688265 -226.493295)
		(end 365.573564 -226.359974)
		(width 0.1143)
		(layer "In6.Cu")
		(net "GMI_CPU1_G0_CPU0_G2_TX_DP<7>")
	)
	(arc
		(start 104.113076 -238.34979)
		(mid 104.356403 -238.814356)
		(end 104.113076 -239.278922)
		(width 0.1143)
		(layer "In6.Cu")
		(net "GMI_CPU1_G0_CPU0_G2_TX_DP<7>")
	)
	(arc
		(start 366.19942 -229.094284)
		(mid 366.157871 -228.922862)
		(end 366.042448 -228.789484)
		(width 0.1143)
		(layer "In6.Cu")
		(net "GMI_CPU1_G0_CPU0_G2_TX_DP<7>")
	)
	(arc
		(start 367.602516 -239.554258)
		(mid 367.550099 -239.422327)
		(end 367.452402 -239.319308)
		(width 0.1143)
		(layer "In6.Cu")
		(net "GMI_CPU1_G0_CPU0_G2_TX_DP<7>")
	)
	(arc
		(start 105.52303 -229.439724)
		(mid 105.701843 -229.642074)
		(end 105.766362 -229.90429)
		(width 0.1143)
		(layer "In6.Cu")
		(net "GMI_CPU1_G0_CPU0_G2_TX_DP<7>")
	)
	(arc
		(start 365.259366 -225.85426)
		(mid 365.210356 -225.671503)
		(end 365.076486 -225.537776)
		(width 0.1143)
		(layer "In6.Cu")
		(net "GMI_CPU1_G0_CPU0_G2_TX_DP<7>")
	)
	(arc
		(start 363.15269 -222.268796)
		(mid 362.973877 -222.066446)
		(end 362.909358 -221.80423)
		(width 0.1143)
		(layer "In6.Cu")
		(net "GMI_CPU1_G0_CPU0_G2_TX_DP<7>")
	)
	(arc
		(start 107.647232 -223.424496)
		(mid 107.582717 -223.686715)
		(end 107.4039 -223.889062)
		(width 0.1143)
		(layer "In6.Cu")
		(net "GMI_CPU1_G0_CPU0_G2_TX_DP<7>")
	)
	(arc
		(start 366.04448 -229.397814)
		(mid 366.158409 -229.264667)
		(end 366.19942 -229.094284)
		(width 0.1143)
		(layer "In6.Cu")
		(net "GMI_CPU1_G0_CPU0_G2_TX_DP<7>")
	)
	(arc
		(start 107.331002 -223.93148)
		(mid 107.217595 -224.06451)
		(end 107.176824 -224.234502)
		(width 0.1143)
		(layer "In6.Cu")
		(net "GMI_CPU1_G0_CPU0_G2_TX_DP<7>")
	)
	(arc
		(start 105.453434 -230.40975)
		(mid 105.338007 -230.543126)
		(end 105.296462 -230.71455)
		(width 0.1143)
		(layer "In6.Cu")
		(net "GMI_CPU1_G0_CPU0_G2_TX_DP<7>")
	)
	(arc
		(start 104.98328 -236.079538)
		(mid 104.867853 -236.212914)
		(end 104.826308 -236.384338)
		(width 0.1143)
		(layer "In6.Cu")
		(net "GMI_CPU1_G0_CPU0_G2_TX_DP<7>")
	)
	(arc
		(start 105.766362 -226.66452)
		(mid 105.701847 -226.926739)
		(end 105.52303 -227.129086)
		(width 0.1143)
		(layer "In6.Cu")
		(net "GMI_CPU1_G0_CPU0_G2_TX_DP<7>")
	)
	(arc
		(start 106.883454 -224.728278)
		(mid 106.754067 -224.863445)
		(end 106.706924 -225.044508)
		(width 0.1143)
		(layer "In6.Cu")
		(net "GMI_CPU1_G0_CPU0_G2_TX_DP<7>")
	)
	(arc
		(start 363.62513 -223.08058)
		(mid 363.444634 -222.877784)
		(end 363.379512 -222.614236)
		(width 0.1143)
		(layer "In6.Cu")
		(net "GMI_CPU1_G0_CPU0_G2_TX_DP<7>")
	)
	(arc
		(start 105.453434 -235.269532)
		(mid 105.338007 -235.402908)
		(end 105.296462 -235.574332)
		(width 0.1143)
		(layer "In6.Cu")
		(net "GMI_CPU1_G0_CPU0_G2_TX_DP<7>")
	)
	(arc
		(start 104.826308 -236.384338)
		(mid 104.750806 -236.66559)
		(end 104.544622 -236.871256)
		(width 0.1143)
		(layer "In6.Cu")
		(net "GMI_CPU1_G0_CPU0_G2_TX_DP<7>")
	)
	(arc
		(start 363.84865 -223.424242)
		(mid 363.806896 -223.252299)
		(end 363.690916 -223.11868)
		(width 0.1143)
		(layer "In6.Cu")
		(net "GMI_CPU1_G0_CPU0_G2_TX_DP<7>")
	)
	(arc
		(start 365.72952 -229.904036)
		(mid 365.794035 -229.641817)
		(end 365.972852 -229.43947)
		(width 0.1143)
		(layer "In6.Cu")
		(net "GMI_CPU1_G0_CPU0_G2_TX_DP<7>")
	)
	(arc
		(start 364.319058 -224.234248)
		(mid 364.2783 -224.06425)
		(end 364.16488 -223.931226)
		(width 0.1143)
		(layer "In6.Cu")
		(net "GMI_CPU1_G0_CPU0_G2_TX_DP<7>")
	)
	(arc
		(start 108.586524 -221.804484)
		(mid 108.522009 -222.066703)
		(end 108.343192 -222.26905)
		(width 0.1143)
		(layer "In6.Cu")
		(net "GMI_CPU1_G0_CPU0_G2_TX_DP<7>")
	)
	(arc
		(start 366.95126 -236.871002)
		(mid 366.745038 -236.665358)
		(end 366.669574 -236.384084)
		(width 0.1143)
		(layer "In6.Cu")
		(net "GMI_CPU1_G0_CPU0_G2_TX_DP<7>")
	)
	(arc
		(start 366.19942 -235.574078)
		(mid 366.157871 -235.402656)
		(end 366.042448 -235.269278)
		(width 0.1143)
		(layer "In6.Cu")
		(net "GMI_CPU1_G0_CPU0_G2_TX_DP<7>")
	)
	(arc
		(start 365.975392 -230.37038)
		(mid 365.79474 -230.167635)
		(end 365.72952 -229.904036)
		(width 0.1143)
		(layer "In6.Cu")
		(net "GMI_CPU1_G0_CPU0_G2_TX_DP<7>")
	)
	(segment
		(start 366.767872 -241.510058)
		(end 367.234724 -241.24412)
		(width 0.12954)
		(layer "F.Cu")
		(net "GMI_CPU1_G0_CPU0_G2_TX_DP<6>")
	)
	(segment
		(start 104.72801 -241.510312)
		(end 104.261158 -241.244374)
		(width 0.12954)
		(layer "F.Cu")
		(net "GMI_CPU1_G0_CPU0_G2_TX_DP<6>")
	)
	(segment
		(start 366.877346 -230.336852)
		(end 366.915192 -230.369872)
		(width 0.1143)
		(layer "In6.Cu")
		(net "GMI_CPU1_G0_CPU0_G2_TX_DP<6>")
	)
	(segment
		(start 366.480852 -226.341178)
		(end 366.481868 -226.341686)
		(width 0.1143)
		(layer "In6.Cu")
		(net "GMI_CPU1_G0_CPU0_G2_TX_DP<6>")
	)
	(segment
		(start 115.937284 -209.785712)
		(end 116.118894 -209.809588)
		(width 0.14224)
		(layer "In6.Cu")
		(net "GMI_CPU1_G0_CPU0_G2_TX_DP<6>")
	)
	(segment
		(start 118.73103 -207.805274)
		(end 119.06377 -207.550004)
		(width 0.14224)
		(layer "In6.Cu")
		(net "GMI_CPU1_G0_CPU0_G2_TX_DP<6>")
	)
	(segment
		(start 104.611932 -231.966008)
		(end 104.648 -231.931464)
		(width 0.1143)
		(layer "In6.Cu")
		(net "GMI_CPU1_G0_CPU0_G2_TX_DP<6>")
	)
	(segment
		(start 104.582976 -227.129086)
		(end 104.628442 -227.089462)
		(width 0.1143)
		(layer "In6.Cu")
		(net "GMI_CPU1_G0_CPU0_G2_TX_DP<6>")
	)
	(segment
		(start 118.216934 -208.036414)
		(end 118.549166 -207.781398)
		(width 0.14224)
		(layer "In6.Cu")
		(net "GMI_CPU1_G0_CPU0_G2_TX_DP<6>")
	)
	(segment
		(start 116.807742 -209.117692)
		(end 116.989606 -209.141568)
		(width 0.14224)
		(layer "In6.Cu")
		(net "GMI_CPU1_G0_CPU0_G2_TX_DP<6>")
	)
	(segment
		(start 104.583484 -232.679494)
		(end 104.544368 -232.657142)
		(width 0.1143)
		(layer "In6.Cu")
		(net "GMI_CPU1_G0_CPU0_G2_TX_DP<6>")
	)
	(segment
		(start 366.876584 -231.958642)
		(end 366.876584 -231.958388)
		(width 0.1143)
		(layer "In6.Cu")
		(net "GMI_CPU1_G0_CPU0_G2_TX_DP<6>")
	)
	(segment
		(start 367.891822 -236.87151)
		(end 367.892584 -236.872018)
		(width 0.1143)
		(layer "In6.Cu")
		(net "GMI_CPU1_G0_CPU0_G2_TX_DP<6>")
	)
	(segment
		(start 103.60406 -240.756948)
		(end 103.603298 -240.75644)
		(width 0.1143)
		(layer "In6.Cu")
		(net "GMI_CPU1_G0_CPU0_G2_TX_DP<6>")
	)
	(segment
		(start 105.014014 -226.34194)
		(end 105.01503 -226.341432)
		(width 0.1143)
		(layer "In6.Cu")
		(net "GMI_CPU1_G0_CPU0_G2_TX_DP<6>")
	)
	(segment
		(start 116.989606 -209.141568)
		(end 117.322346 -208.886298)
		(width 0.14224)
		(layer "In6.Cu")
		(net "GMI_CPU1_G0_CPU0_G2_TX_DP<6>")
	)
	(segment
		(start 104.58323 -234.299506)
		(end 104.512364 -234.258358)
		(width 0.1143)
		(layer "In6.Cu")
		(net "GMI_CPU1_G0_CPU0_G2_TX_DP<6>")
	)
	(segment
		(start 105.483914 -225.531934)
		(end 105.520236 -225.510852)
		(width 0.1143)
		(layer "In6.Cu")
		(net "GMI_CPU1_G0_CPU0_G2_TX_DP<6>")
	)
	(segment
		(start 103.6066 -236.87024)
		(end 103.643176 -236.848904)
		(width 0.1143)
		(layer "In6.Cu")
		(net "GMI_CPU1_G0_CPU0_G2_TX_DP<6>")
	)
	(segment
		(start 104.512364 -227.778564)
		(end 104.512364 -227.778818)
		(width 0.1143)
		(layer "In6.Cu")
		(net "GMI_CPU1_G0_CPU0_G2_TX_DP<6>")
	)
	(segment
		(start 366.673384 -226.699826)
		(end 366.679226 -226.740974)
		(width 0.1143)
		(layer "In6.Cu")
		(net "GMI_CPU1_G0_CPU0_G2_TX_DP<6>")
	)
	(segment
		(start 119.419878 -207.113124)
		(end 119.601742 -207.137)
		(width 0.14224)
		(layer "In6.Cu")
		(net "GMI_CPU1_G0_CPU0_G2_TX_DP<6>")
	)
	(segment
		(start 366.9538 -232.012744)
		(end 366.983518 -232.029762)
		(width 0.1143)
		(layer "In6.Cu")
		(net "GMI_CPU1_G0_CPU0_G2_TX_DP<6>")
	)
	(segment
		(start 366.951514 -232.656888)
		(end 366.912398 -232.67924)
		(width 0.1143)
		(layer "In6.Cu")
		(net "GMI_CPU1_G0_CPU0_G2_TX_DP<6>")
	)
	(segment
		(start 367.893854 -236.87278)
		(end 367.923572 -236.889798)
		(width 0.1143)
		(layer "In6.Cu")
		(net "GMI_CPU1_G0_CPU0_G2_TX_DP<6>")
	)
	(segment
		(start 366.985296 -231.017064)
		(end 366.982502 -231.019096)
		(width 0.1143)
		(layer "In6.Cu")
		(net "GMI_CPU1_G0_CPU0_G2_TX_DP<6>")
	)
	(segment
		(start 104.544114 -231.036876)
		(end 104.510586 -231.017318)
		(width 0.1143)
		(layer "In6.Cu")
		(net "GMI_CPU1_G0_CPU0_G2_TX_DP<6>")
	)
	(segment
		(start 103.635556 -240.775236)
		(end 103.60406 -240.756948)
		(width 0.1143)
		(layer "In6.Cu")
		(net "GMI_CPU1_G0_CPU0_G2_TX_DP<6>")
	)
	(segment
		(start 366.868202 -227.08997)
		(end 366.912906 -227.129086)
		(width 0.1143)
		(layer "In6.Cu")
		(net "GMI_CPU1_G0_CPU0_G2_TX_DP<6>")
	)
	(segment
		(start 109.032548 -216.612724)
		(end 115.604798 -210.040728)
		(width 0.14224)
		(layer "In6.Cu")
		(net "GMI_CPU1_G0_CPU0_G2_TX_DP<6>")
	)
	(segment
		(start 121.343166 -205.800706)
		(end 121.675906 -205.545436)
		(width 0.14224)
		(layer "In6.Cu")
		(net "GMI_CPU1_G0_CPU0_G2_TX_DP<6>")
	)
	(segment
		(start 366.885474 -228.72954)
		(end 366.912398 -228.748844)
		(width 0.1143)
		(layer "In6.Cu")
		(net "GMI_CPU1_G0_CPU0_G2_TX_DP<6>")
	)
	(segment
		(start 366.442752 -226.318826)
		(end 366.480852 -226.341178)
		(width 0.1143)
		(layer "In6.Cu")
		(net "GMI_CPU1_G0_CPU0_G2_TX_DP<6>")
	)
	(segment
		(start 366.983518 -234.258104)
		(end 366.912652 -234.299252)
		(width 0.1143)
		(layer "In6.Cu")
		(net "GMI_CPU1_G0_CPU0_G2_TX_DP<6>")
	)
	(segment
		(start 319.367154 -188.0743)
		(end 355.063298 -210.536536)
		(width 0.14224)
		(layer "In6.Cu")
		(net "GMI_CPU1_G0_CPU0_G2_TX_DP<6>")
	)
	(segment
		(start 366.836706 -231.918764)
		(end 366.876584 -231.958642)
		(width 0.1143)
		(layer "In6.Cu")
		(net "GMI_CPU1_G0_CPU0_G2_TX_DP<6>")
	)
	(segment
		(start 107.645708 -221.246954)
		(end 107.645708 -221.139004)
		(width 0.1143)
		(layer "In6.Cu")
		(net "GMI_CPU1_G0_CPU0_G2_TX_DP<6>")
	)
	(segment
		(start 104.610408 -227.83927)
		(end 104.583484 -227.819966)
		(width 0.1143)
		(layer "In6.Cu")
		(net "GMI_CPU1_G0_CPU0_G2_TX_DP<6>")
	)
	(segment
		(start 302.901096 -180.711348)
		(end 306.717192 -180.711348)
		(width 0.14224)
		(layer "In6.Cu")
		(net "GMI_CPU1_G0_CPU0_G2_TX_DP<6>")
	)
	(segment
		(start 107.33024 -222.311468)
		(end 107.403138 -222.26905)
		(width 0.1143)
		(layer "In6.Cu")
		(net "GMI_CPU1_G0_CPU0_G2_TX_DP<6>")
	)
	(segment
		(start 366.912398 -228.748844)
		(end 366.983518 -228.789992)
		(width 0.1143)
		(layer "In6.Cu")
		(net "GMI_CPU1_G0_CPU0_G2_TX_DP<6>")
	)
	(segment
		(start 104.543352 -232.012236)
		(end 104.544114 -232.011728)
		(width 0.1143)
		(layer "In6.Cu")
		(net "GMI_CPU1_G0_CPU0_G2_TX_DP<6>")
	)
	(segment
		(start 120.29059 -206.445104)
		(end 120.472454 -206.46898)
		(width 0.14224)
		(layer "In6.Cu")
		(net "GMI_CPU1_G0_CPU0_G2_TX_DP<6>")
	)
	(segment
		(start 365.50219 -224.69856)
		(end 365.542322 -224.721674)
		(width 0.1143)
		(layer "In6.Cu")
		(net "GMI_CPU1_G0_CPU0_G2_TX_DP<6>")
	)
	(segment
		(start 366.983518 -227.778564)
		(end 366.983518 -227.77831)
		(width 0.1143)
		(layer "In6.Cu")
		(net "GMI_CPU1_G0_CPU0_G2_TX_DP<6>")
	)
	(segment
		(start 366.876584 -231.958388)
		(end 366.890554 -231.972358)
		(width 0.1143)
		(layer "In6.Cu")
		(net "GMI_CPU1_G0_CPU0_G2_TX_DP<6>")
	)
	(segment
		(start 366.912652 -235.228892)
		(end 366.983518 -235.269786)
		(width 0.1143)
		(layer "In6.Cu")
		(net "GMI_CPU1_G0_CPU0_G2_TX_DP<6>")
	)
	(segment
		(start 366.48263 -226.342194)
		(end 366.513618 -226.359974)
		(width 0.1143)
		(layer "In6.Cu")
		(net "GMI_CPU1_G0_CPU0_G2_TX_DP<6>")
	)
	(segment
		(start 104.610916 -234.319572)
		(end 104.58323 -234.299506)
		(width 0.1143)
		(layer "In6.Cu")
		(net "GMI_CPU1_G0_CPU0_G2_TX_DP<6>")
	)
	(segment
		(start 367.890806 -240.757202)
		(end 367.889282 -240.758218)
		(width 0.1143)
		(layer "In6.Cu")
		(net "GMI_CPU1_G0_CPU0_G2_TX_DP<6>")
	)
	(segment
		(start 103.605076 -236.871256)
		(end 103.6066 -236.87024)
		(width 0.1143)
		(layer "In6.Cu")
		(net "GMI_CPU1_G0_CPU0_G2_TX_DP<6>")
	)
	(segment
		(start 104.511856 -230.410512)
		(end 104.58069 -230.370126)
		(width 0.1143)
		(layer "In6.Cu")
		(net "GMI_CPU1_G0_CPU0_G2_TX_DP<6>")
	)
	(segment
		(start 306.717192 -180.711348)
		(end 308.636162 -181.238144)
		(width 0.14224)
		(layer "In6.Cu")
		(net "GMI_CPU1_G0_CPU0_G2_TX_DP<6>")
	)
	(segment
		(start 308.636162 -181.238144)
		(end 316.247018 -185.75782)
		(width 0.14224)
		(layer "In6.Cu")
		(net "GMI_CPU1_G0_CPU0_G2_TX_DP<6>")
	)
	(segment
		(start 104.356408 -230.71455)
		(end 104.356154 -230.714296)
		(width 0.1143)
		(layer "In6.Cu")
		(net "GMI_CPU1_G0_CPU0_G2_TX_DP<6>")
	)
	(segment
		(start 104.593898 -229.447598)
		(end 104.580436 -229.437946)
		(width 0.1143)
		(layer "In6.Cu")
		(net "GMI_CPU1_G0_CPU0_G2_TX_DP<6>")
	)
	(segment
		(start 316.247018 -185.75782)
		(end 316.29223 -185.93562)
		(width 0.14224)
		(layer "In6.Cu")
		(net "GMI_CPU1_G0_CPU0_G2_TX_DP<6>")
	)
	(segment
		(start 103.602028 -240.755678)
		(end 103.57231 -240.73866)
		(width 0.1143)
		(layer "In6.Cu")
		(net "GMI_CPU1_G0_CPU0_G2_TX_DP<6>")
	)
	(segment
		(start 103.603298 -236.872272)
		(end 103.60406 -236.871764)
		(width 0.1143)
		(layer "In6.Cu")
		(net "GMI_CPU1_G0_CPU0_G2_TX_DP<6>")
	)
	(segment
		(start 104.528366 -227.787708)
		(end 104.512364 -227.778564)
		(width 0.1143)
		(layer "In6.Cu")
		(net "GMI_CPU1_G0_CPU0_G2_TX_DP<6>")
	)
	(segment
		(start 317.190628 -186.318144)
		(end 319.367154 -188.0743)
		(width 0.14224)
		(layer "In6.Cu")
		(net "GMI_CPU1_G0_CPU0_G2_TX_DP<6>")
	)
	(segment
		(start 367.852706 -236.84865)
		(end 367.889282 -236.869986)
		(width 0.1143)
		(layer "In6.Cu")
		(net "GMI_CPU1_G0_CPU0_G2_TX_DP<6>")
	)
	(segment
		(start 104.58323 -235.229146)
		(end 104.610916 -235.20908)
		(width 0.1143)
		(layer "In6.Cu")
		(net "GMI_CPU1_G0_CPU0_G2_TX_DP<6>")
	)
	(segment
		(start 366.912398 -232.67924)
		(end 366.886744 -232.698036)
		(width 0.1143)
		(layer "In6.Cu")
		(net "GMI_CPU1_G0_CPU0_G2_TX_DP<6>")
	)
	(segment
		(start 105.453434 -225.549714)
		(end 105.483914 -225.531934)
		(width 0.1143)
		(layer "In6.Cu")
		(net "GMI_CPU1_G0_CPU0_G2_TX_DP<6>")
	)
	(segment
		(start 104.512364 -228.790246)
		(end 104.583484 -228.749098)
		(width 0.1143)
		(layer "In6.Cu")
		(net "GMI_CPU1_G0_CPU0_G2_TX_DP<6>")
	)
	(segment
		(start 367.892584 -240.756186)
		(end 367.891822 -240.756694)
		(width 0.1143)
		(layer "In6.Cu")
		(net "GMI_CPU1_G0_CPU0_G2_TX_DP<6>")
	)
	(segment
		(start 117.346222 -208.704688)
		(end 117.678454 -208.449672)
		(width 0.14224)
		(layer "In6.Cu")
		(net "GMI_CPU1_G0_CPU0_G2_TX_DP<6>")
	)
	(segment
		(start 107.691428 -219.850716)
		(end 109.032548 -216.612724)
		(width 0.14224)
		(layer "In6.Cu")
		(net "GMI_CPU1_G0_CPU0_G2_TX_DP<6>")
	)
	(segment
		(start 367.923572 -240.738406)
		(end 367.893854 -240.755424)
		(width 0.1143)
		(layer "In6.Cu")
		(net "GMI_CPU1_G0_CPU0_G2_TX_DP<6>")
	)
	(segment
		(start 364.092744 -222.268796)
		(end 364.165642 -222.311214)
		(width 0.1143)
		(layer "In6.Cu")
		(net "GMI_CPU1_G0_CPU0_G2_TX_DP<6>")
	)
	(segment
		(start 104.609138 -232.69829)
		(end 104.583484 -232.679494)
		(width 0.1143)
		(layer "In6.Cu")
		(net "GMI_CPU1_G0_CPU0_G2_TX_DP<6>")
	)
	(segment
		(start 355.063298 -210.536536)
		(end 359.49636 -214.07374)
		(width 0.14224)
		(layer "In6.Cu")
		(net "GMI_CPU1_G0_CPU0_G2_TX_DP<6>")
	)
	(segment
		(start 107.691428 -221.064836)
		(end 107.691428 -219.850716)
		(width 0.14224)
		(layer "In6.Cu")
		(net "GMI_CPU1_G0_CPU0_G2_TX_DP<6>")
	)
	(segment
		(start 103.133906 -238.32693)
		(end 103.103426 -238.30915)
		(width 0.1143)
		(layer "In6.Cu")
		(net "GMI_CPU1_G0_CPU0_G2_TX_DP<6>")
	)
	(segment
		(start 103.60406 -236.871764)
		(end 103.605076 -236.871256)
		(width 0.1143)
		(layer "In6.Cu")
		(net "GMI_CPU1_G0_CPU0_G2_TX_DP<6>")
	)
	(segment
		(start 103.133906 -239.301782)
		(end 103.173022 -239.278922)
		(width 0.1143)
		(layer "In6.Cu")
		(net "GMI_CPU1_G0_CPU0_G2_TX_DP<6>")
	)
	(segment
		(start 120.805194 -206.213456)
		(end 120.82907 -206.031846)
		(width 0.14224)
		(layer "In6.Cu")
		(net "GMI_CPU1_G0_CPU0_G2_TX_DP<6>")
	)
	(segment
		(start 104.820212 -229.963472)
		(end 104.826308 -229.902512)
		(width 0.1143)
		(layer "In6.Cu")
		(net "GMI_CPU1_G0_CPU0_G2_TX_DP<6>")
	)
	(segment
		(start 117.860318 -208.473548)
		(end 118.193058 -208.218278)
		(width 0.14224)
		(layer "In6.Cu")
		(net "GMI_CPU1_G0_CPU0_G2_TX_DP<6>")
	)
	(segment
		(start 316.830456 -186.104276)
		(end 317.190628 -186.318144)
		(width 0.14224)
		(layer "In6.Cu")
		(net "GMI_CPU1_G0_CPU0_G2_TX_DP<6>")
	)
	(segment
		(start 363.804454 -219.355924)
		(end 363.804454 -221.081346)
		(width 0.14224)
		(layer "In6.Cu")
		(net "GMI_CPU1_G0_CPU0_G2_TX_DP<6>")
	)
	(segment
		(start 363.849412 -221.247462)
		(end 363.849412 -221.80423)
		(width 0.1143)
		(layer "In6.Cu")
		(net "GMI_CPU1_G0_CPU0_G2_TX_DP<6>")
	)
	(segment
		(start 103.963216 -241.244374)
		(end 103.880412 -241.16157)
		(width 0.1143)
		(layer "In6.Cu")
		(net "GMI_CPU1_G0_CPU0_G2_TX_DP<6>")
	)
	(segment
		(start 364.165642 -222.311214)
		(end 364.202218 -222.337884)
		(width 0.1143)
		(layer "In6.Cu")
		(net "GMI_CPU1_G0_CPU0_G2_TX_DP<6>")
	)
	(segment
		(start 104.816656 -226.74199)
		(end 104.822752 -226.699572)
		(width 0.1143)
		(layer "In6.Cu")
		(net "GMI_CPU1_G0_CPU0_G2_TX_DP<6>")
	)
	(segment
		(start 103.643176 -240.779808)
		(end 103.636318 -240.775744)
		(width 0.1143)
		(layer "In6.Cu")
		(net "GMI_CPU1_G0_CPU0_G2_TX_DP<6>")
	)
	(segment
		(start 104.544368 -227.79736)
		(end 104.528366 -227.787708)
		(width 0.1143)
		(layer "In6.Cu")
		(net "GMI_CPU1_G0_CPU0_G2_TX_DP<6>")
	)
	(segment
		(start 366.983518 -232.638346)
		(end 366.983518 -232.638092)
		(width 0.1143)
		(layer "In6.Cu")
		(net "GMI_CPU1_G0_CPU0_G2_TX_DP<6>")
	)
	(segment
		(start 117.322346 -208.886298)
		(end 117.346222 -208.704688)
		(width 0.14224)
		(layer "In6.Cu")
		(net "GMI_CPU1_G0_CPU0_G2_TX_DP<6>")
	)
	(segment
		(start 120.472454 -206.46898)
		(end 120.805194 -206.213456)
		(width 0.14224)
		(layer "In6.Cu")
		(net "GMI_CPU1_G0_CPU0_G2_TX_DP<6>")
	)
	(segment
		(start 104.982264 -226.360228)
		(end 105.013252 -226.342448)
		(width 0.1143)
		(layer "In6.Cu")
		(net "GMI_CPU1_G0_CPU0_G2_TX_DP<6>")
	)
	(segment
		(start 119.06377 -207.550004)
		(end 119.087646 -207.36814)
		(width 0.14224)
		(layer "In6.Cu")
		(net "GMI_CPU1_G0_CPU0_G2_TX_DP<6>")
	)
	(segment
		(start 104.512364 -232.638346)
		(end 104.512364 -232.6386)
		(width 0.1143)
		(layer "In6.Cu")
		(net "GMI_CPU1_G0_CPU0_G2_TX_DP<6>")
	)
	(segment
		(start 121.699782 -205.363572)
		(end 122.498866 -204.750416)
		(width 0.14224)
		(layer "In6.Cu")
		(net "GMI_CPU1_G0_CPU0_G2_TX_DP<6>")
	)
	(segment
		(start 367.382806 -236.038644)
		(end 367.452402 -236.079284)
		(width 0.1143)
		(layer "In6.Cu")
		(net "GMI_CPU1_G0_CPU0_G2_TX_DP<6>")
	)
	(segment
		(start 366.912398 -227.819712)
		(end 366.885474 -227.839016)
		(width 0.1143)
		(layer "In6.Cu")
		(net "GMI_CPU1_G0_CPU0_G2_TX_DP<6>")
	)
	(segment
		(start 366.912398 -233.60888)
		(end 366.983518 -233.649774)
		(width 0.1143)
		(layer "In6.Cu")
		(net "GMI_CPU1_G0_CPU0_G2_TX_DP<6>")
	)
	(segment
		(start 115.604798 -210.040728)
		(end 115.937284 -209.785712)
		(width 0.14224)
		(layer "In6.Cu")
		(net "GMI_CPU1_G0_CPU0_G2_TX_DP<6>")
	)
	(segment
		(start 105.922064 -224.740216)
		(end 105.95356 -224.721928)
		(width 0.1143)
		(layer "In6.Cu")
		(net "GMI_CPU1_G0_CPU0_G2_TX_DP<6>")
	)
	(segment
		(start 121.161302 -205.77683)
		(end 121.343166 -205.800706)
		(width 0.14224)
		(layer "In6.Cu")
		(net "GMI_CPU1_G0_CPU0_G2_TX_DP<6>")
	)
	(segment
		(start 103.173022 -238.34979)
		(end 103.133906 -238.32693)
		(width 0.1143)
		(layer "In6.Cu")
		(net "GMI_CPU1_G0_CPU0_G2_TX_DP<6>")
	)
	(segment
		(start 104.261158 -241.244374)
		(end 103.963216 -241.244374)
		(width 0.1143)
		(layer "In6.Cu")
		(net "GMI_CPU1_G0_CPU0_G2_TX_DP<6>")
	)
	(segment
		(start 363.115352 -217.692478)
		(end 363.804454 -219.355924)
		(width 0.14224)
		(layer "In6.Cu")
		(net "GMI_CPU1_G0_CPU0_G2_TX_DP<6>")
	)
	(segment
		(start 104.580436 -229.437946)
		(end 104.577642 -229.436422)
		(width 0.1143)
		(layer "In6.Cu")
		(net "GMI_CPU1_G0_CPU0_G2_TX_DP<6>")
	)
	(segment
		(start 122.498866 -204.750416)
		(end 163.725352 -180.945028)
		(width 0.14224)
		(layer "In6.Cu")
		(net "GMI_CPU1_G0_CPU0_G2_TX_DP<6>")
	)
	(segment
		(start 107.176062 -222.61449)
		(end 107.176062 -222.569532)
		(width 0.1143)
		(layer "In6.Cu")
		(net "GMI_CPU1_G0_CPU0_G2_TX_DP<6>")
	)
	(segment
		(start 105.013252 -226.342448)
		(end 105.014014 -226.34194)
		(width 0.1143)
		(layer "In6.Cu")
		(net "GMI_CPU1_G0_CPU0_G2_TX_DP<6>")
	)
	(segment
		(start 367.892584 -236.872018)
		(end 367.893854 -236.87278)
		(width 0.1143)
		(layer "In6.Cu")
		(net "GMI_CPU1_G0_CPU0_G2_TX_DP<6>")
	)
	(segment
		(start 366.95253 -232.011982)
		(end 366.9538 -232.012744)
		(width 0.1143)
		(layer "In6.Cu")
		(net "GMI_CPU1_G0_CPU0_G2_TX_DP<6>")
	)
	(segment
		(start 105.95356 -224.721928)
		(end 105.993692 -224.698814)
		(width 0.1143)
		(layer "In6.Cu")
		(net "GMI_CPU1_G0_CPU0_G2_TX_DP<6>")
	)
	(segment
		(start 367.891822 -240.756694)
		(end 367.890806 -240.757202)
		(width 0.1143)
		(layer "In6.Cu")
		(net "GMI_CPU1_G0_CPU0_G2_TX_DP<6>")
	)
	(segment
		(start 167.586152 -179.922424)
		(end 167.586152 -179.92217)
		(width 0.14224)
		(layer "In6.Cu")
		(net "GMI_CPU1_G0_CPU0_G2_TX_DP<6>")
	)
	(segment
		(start 364.563152 -223.078802)
		(end 364.634018 -223.11995)
		(width 0.1143)
		(layer "In6.Cu")
		(net "GMI_CPU1_G0_CPU0_G2_TX_DP<6>")
	)
	(segment
		(start 366.951768 -232.011474)
		(end 366.95253 -232.011982)
		(width 0.1143)
		(layer "In6.Cu")
		(net "GMI_CPU1_G0_CPU0_G2_TX_DP<6>")
	)
	(segment
		(start 163.725352 -180.945028)
		(end 167.586152 -179.922424)
		(width 0.14224)
		(layer "In6.Cu")
		(net "GMI_CPU1_G0_CPU0_G2_TX_DP<6>")
	)
	(segment
		(start 366.912652 -234.299252)
		(end 366.884966 -234.319318)
		(width 0.1143)
		(layer "In6.Cu")
		(net "GMI_CPU1_G0_CPU0_G2_TX_DP<6>")
	)
	(segment
		(start 104.07396 -236.061758)
		(end 104.113076 -236.038898)
		(width 0.1143)
		(layer "In6.Cu")
		(net "GMI_CPU1_G0_CPU0_G2_TX_DP<6>")
	)
	(segment
		(start 364.31982 -222.569278)
		(end 364.31982 -222.614236)
		(width 0.1143)
		(layer "In6.Cu")
		(net "GMI_CPU1_G0_CPU0_G2_TX_DP<6>")
	)
	(segment
		(start 366.912906 -227.129086)
		(end 366.983772 -227.170234)
		(width 0.1143)
		(layer "In6.Cu")
		(net "GMI_CPU1_G0_CPU0_G2_TX_DP<6>")
	)
	(segment
		(start 366.982502 -231.019096)
		(end 366.910366 -231.061006)
		(width 0.1143)
		(layer "In6.Cu")
		(net "GMI_CPU1_G0_CPU0_G2_TX_DP<6>")
	)
	(segment
		(start 104.544114 -232.011728)
		(end 104.545638 -232.010966)
		(width 0.1143)
		(layer "In6.Cu")
		(net "GMI_CPU1_G0_CPU0_G2_TX_DP<6>")
	)
	(segment
		(start 316.65291 -186.149488)
		(end 316.830456 -186.104276)
		(width 0.14224)
		(layer "In6.Cu")
		(net "GMI_CPU1_G0_CPU0_G2_TX_DP<6>")
	)
	(segment
		(start 107.691428 -221.093284)
		(end 107.691428 -221.064836)
		(width 0.1143)
		(layer "In6.Cu")
		(net "GMI_CPU1_G0_CPU0_G2_TX_DP<6>")
	)
	(segment
		(start 103.103426 -237.69955)
		(end 103.133906 -237.68177)
		(width 0.1143)
		(layer "In6.Cu")
		(net "GMI_CPU1_G0_CPU0_G2_TX_DP<6>")
	)
	(segment
		(start 366.985296 -229.397052)
		(end 366.952022 -229.416356)
		(width 0.1143)
		(layer "In6.Cu")
		(net "GMI_CPU1_G0_CPU0_G2_TX_DP<6>")
	)
	(segment
		(start 103.57231 -236.890052)
		(end 103.603298 -236.872272)
		(width 0.1143)
		(layer "In6.Cu")
		(net "GMI_CPU1_G0_CPU0_G2_TX_DP<6>")
	)
	(segment
		(start 107.64647 -221.247716)
		(end 107.645708 -221.246954)
		(width 0.1143)
		(layer "In6.Cu")
		(net "GMI_CPU1_G0_CPU0_G2_TX_DP<6>")
	)
	(segment
		(start 363.850174 -221.13875)
		(end 363.850174 -221.2467)
		(width 0.1143)
		(layer "In6.Cu")
		(net "GMI_CPU1_G0_CPU0_G2_TX_DP<6>")
	)
	(segment
		(start 104.51211 -227.170488)
		(end 104.582976 -227.129086)
		(width 0.1143)
		(layer "In6.Cu")
		(net "GMI_CPU1_G0_CPU0_G2_TX_DP<6>")
	)
	(segment
		(start 366.983518 -227.77831)
		(end 366.967516 -227.787454)
		(width 0.1143)
		(layer "In6.Cu")
		(net "GMI_CPU1_G0_CPU0_G2_TX_DP<6>")
	)
	(segment
		(start 366.950244 -232.010712)
		(end 366.951768 -232.011474)
		(width 0.1143)
		(layer "In6.Cu")
		(net "GMI_CPU1_G0_CPU0_G2_TX_DP<6>")
	)
	(segment
		(start 366.915446 -231.990392)
		(end 366.950244 -232.010712)
		(width 0.1143)
		(layer "In6.Cu")
		(net "GMI_CPU1_G0_CPU0_G2_TX_DP<6>")
	)
	(segment
		(start 366.890554 -231.972358)
		(end 366.892078 -231.972358)
		(width 0.1143)
		(layer "In6.Cu")
		(net "GMI_CPU1_G0_CPU0_G2_TX_DP<6>")
	)
	(segment
		(start 117.678454 -208.449672)
		(end 117.860318 -208.473548)
		(width 0.14224)
		(layer "In6.Cu")
		(net "GMI_CPU1_G0_CPU0_G2_TX_DP<6>")
	)
	(segment
		(start 103.133906 -239.946942)
		(end 103.103426 -239.929162)
		(width 0.1143)
		(layer "In6.Cu")
		(net "GMI_CPU1_G0_CPU0_G2_TX_DP<6>")
	)
	(segment
		(start 367.893854 -240.755424)
		(end 367.892584 -240.756186)
		(width 0.1143)
		(layer "In6.Cu")
		(net "GMI_CPU1_G0_CPU0_G2_TX_DP<6>")
	)
	(segment
		(start 121.675906 -205.545436)
		(end 121.699782 -205.363572)
		(width 0.14224)
		(layer "In6.Cu")
		(net "GMI_CPU1_G0_CPU0_G2_TX_DP<6>")
	)
	(segment
		(start 107.645708 -221.139004)
		(end 107.691428 -221.093284)
		(width 0.1143)
		(layer "In6.Cu")
		(net "GMI_CPU1_G0_CPU0_G2_TX_DP<6>")
	)
	(segment
		(start 363.850174 -221.2467)
		(end 363.849412 -221.247462)
		(width 0.1143)
		(layer "In6.Cu")
		(net "GMI_CPU1_G0_CPU0_G2_TX_DP<6>")
	)
	(segment
		(start 366.886744 -233.590084)
		(end 366.912398 -233.60888)
		(width 0.1143)
		(layer "In6.Cu")
		(net "GMI_CPU1_G0_CPU0_G2_TX_DP<6>")
	)
	(segment
		(start 366.967516 -232.647236)
		(end 366.951514 -232.656888)
		(width 0.1143)
		(layer "In6.Cu")
		(net "GMI_CPU1_G0_CPU0_G2_TX_DP<6>")
	)
	(segment
		(start 104.583484 -228.749098)
		(end 104.610408 -228.729794)
		(width 0.1143)
		(layer "In6.Cu")
		(net "GMI_CPU1_G0_CPU0_G2_TX_DP<6>")
	)
	(segment
		(start 104.820212 -231.587548)
		(end 104.826308 -231.538018)
		(width 0.1143)
		(layer "In6.Cu")
		(net "GMI_CPU1_G0_CPU0_G2_TX_DP<6>")
	)
	(segment
		(start 366.669574 -231.53878)
		(end 366.678464 -231.60101)
		(width 0.1143)
		(layer "In6.Cu")
		(net "GMI_CPU1_G0_CPU0_G2_TX_DP<6>")
	)
	(segment
		(start 366.481868 -226.341686)
		(end 366.48263 -226.342194)
		(width 0.1143)
		(layer "In6.Cu")
		(net "GMI_CPU1_G0_CPU0_G2_TX_DP<6>")
	)
	(segment
		(start 103.103426 -239.319562)
		(end 103.133906 -239.301782)
		(width 0.1143)
		(layer "In6.Cu")
		(net "GMI_CPU1_G0_CPU0_G2_TX_DP<6>")
	)
	(segment
		(start 107.64647 -221.804484)
		(end 107.64647 -221.247716)
		(width 0.1143)
		(layer "In6.Cu")
		(net "GMI_CPU1_G0_CPU0_G2_TX_DP<6>")
	)
	(segment
		(start 366.884966 -235.208826)
		(end 366.912652 -235.228892)
		(width 0.1143)
		(layer "In6.Cu")
		(net "GMI_CPU1_G0_CPU0_G2_TX_DP<6>")
	)
	(segment
		(start 120.82907 -206.031846)
		(end 121.161302 -205.77683)
		(width 0.14224)
		(layer "In6.Cu")
		(net "GMI_CPU1_G0_CPU0_G2_TX_DP<6>")
	)
	(segment
		(start 104.512364 -235.27004)
		(end 104.58323 -235.229146)
		(width 0.1143)
		(layer "In6.Cu")
		(net "GMI_CPU1_G0_CPU0_G2_TX_DP<6>")
	)
	(segment
		(start 119.934482 -206.88173)
		(end 119.958358 -206.70012)
		(width 0.14224)
		(layer "In6.Cu")
		(net "GMI_CPU1_G0_CPU0_G2_TX_DP<6>")
	)
	(segment
		(start 106.861864 -223.120204)
		(end 106.93273 -223.079056)
		(width 0.1143)
		(layer "In6.Cu")
		(net "GMI_CPU1_G0_CPU0_G2_TX_DP<6>")
	)
	(segment
		(start 107.293664 -222.338138)
		(end 107.33024 -222.311468)
		(width 0.1143)
		(layer "In6.Cu")
		(net "GMI_CPU1_G0_CPU0_G2_TX_DP<6>")
	)
	(segment
		(start 104.545638 -232.010966)
		(end 104.580436 -231.990646)
		(width 0.1143)
		(layer "In6.Cu")
		(net "GMI_CPU1_G0_CPU0_G2_TX_DP<6>")
	)
	(segment
		(start 104.583484 -227.819966)
		(end 104.544368 -227.79736)
		(width 0.1143)
		(layer "In6.Cu")
		(net "GMI_CPU1_G0_CPU0_G2_TX_DP<6>")
	)
	(segment
		(start 363.804454 -221.081346)
		(end 363.804454 -221.09303)
		(width 0.1143)
		(layer "In6.Cu")
		(net "GMI_CPU1_G0_CPU0_G2_TX_DP<6>")
	)
	(segment
		(start 368.32286 -239.278668)
		(end 368.392456 -239.319308)
		(width 0.1143)
		(layer "In6.Cu")
		(net "GMI_CPU1_G0_CPU0_G2_TX_DP<6>")
	)
	(segment
		(start 116.451634 -209.554318)
		(end 116.47551 -209.372708)
		(width 0.14224)
		(layer "In6.Cu")
		(net "GMI_CPU1_G0_CPU0_G2_TX_DP<6>")
	)
	(segment
		(start 104.512364 -232.030016)
		(end 104.543352 -232.012236)
		(width 0.1143)
		(layer "In6.Cu")
		(net "GMI_CPU1_G0_CPU0_G2_TX_DP<6>")
	)
	(segment
		(start 366.967516 -227.787454)
		(end 366.951514 -227.797106)
		(width 0.1143)
		(layer "In6.Cu")
		(net "GMI_CPU1_G0_CPU0_G2_TX_DP<6>")
	)
	(segment
		(start 104.577642 -229.436422)
		(end 104.510586 -229.397306)
		(width 0.1143)
		(layer "In6.Cu")
		(net "GMI_CPU1_G0_CPU0_G2_TX_DP<6>")
	)
	(segment
		(start 365.975646 -225.510598)
		(end 366.011968 -225.53168)
		(width 0.1143)
		(layer "In6.Cu")
		(net "GMI_CPU1_G0_CPU0_G2_TX_DP<6>")
	)
	(segment
		(start 367.61547 -241.161316)
		(end 367.532666 -241.24412)
		(width 0.1143)
		(layer "In6.Cu")
		(net "GMI_CPU1_G0_CPU0_G2_TX_DP<6>")
	)
	(segment
		(start 119.087646 -207.36814)
		(end 119.419878 -207.113124)
		(width 0.14224)
		(layer "In6.Cu")
		(net "GMI_CPU1_G0_CPU0_G2_TX_DP<6>")
	)
	(segment
		(start 104.58069 -230.370126)
		(end 104.631998 -230.325676)
		(width 0.1143)
		(layer "In6.Cu")
		(net "GMI_CPU1_G0_CPU0_G2_TX_DP<6>")
	)
	(segment
		(start 366.011968 -225.53168)
		(end 366.042448 -225.54946)
		(width 0.1143)
		(layer "In6.Cu")
		(net "GMI_CPU1_G0_CPU0_G2_TX_DP<6>")
	)
	(segment
		(start 104.512364 -233.650028)
		(end 104.583484 -233.609134)
		(width 0.1143)
		(layer "In6.Cu")
		(net "GMI_CPU1_G0_CPU0_G2_TX_DP<6>")
	)
	(segment
		(start 116.47551 -209.372708)
		(end 116.807742 -209.117692)
		(width 0.14224)
		(layer "In6.Cu")
		(net "GMI_CPU1_G0_CPU0_G2_TX_DP<6>")
	)
	(segment
		(start 104.04348 -236.079538)
		(end 104.07396 -236.061758)
		(width 0.1143)
		(layer "In6.Cu")
		(net "GMI_CPU1_G0_CPU0_G2_TX_DP<6>")
	)
	(segment
		(start 104.826308 -226.655122)
		(end 104.826308 -226.654868)
		(width 0.1143)
		(layer "In6.Cu")
		(net "GMI_CPU1_G0_CPU0_G2_TX_DP<6>")
	)
	(segment
		(start 366.951514 -227.797106)
		(end 366.912398 -227.819712)
		(width 0.1143)
		(layer "In6.Cu")
		(net "GMI_CPU1_G0_CPU0_G2_TX_DP<6>")
	)
	(segment
		(start 118.193058 -208.218278)
		(end 118.216934 -208.036414)
		(width 0.14224)
		(layer "In6.Cu")
		(net "GMI_CPU1_G0_CPU0_G2_TX_DP<6>")
	)
	(segment
		(start 366.952022 -229.416356)
		(end 366.910874 -229.44074)
		(width 0.1143)
		(layer "In6.Cu")
		(net "GMI_CPU1_G0_CPU0_G2_TX_DP<6>")
	)
	(segment
		(start 103.603298 -240.75644)
		(end 103.602028 -240.755678)
		(width 0.1143)
		(layer "In6.Cu")
		(net "GMI_CPU1_G0_CPU0_G2_TX_DP<6>")
	)
	(segment
		(start 367.889282 -240.758218)
		(end 367.852706 -240.779554)
		(width 0.1143)
		(layer "In6.Cu")
		(net "GMI_CPU1_G0_CPU0_G2_TX_DP<6>")
	)
	(segment
		(start 104.544368 -232.657142)
		(end 104.528366 -232.64749)
		(width 0.1143)
		(layer "In6.Cu")
		(net "GMI_CPU1_G0_CPU0_G2_TX_DP<6>")
	)
	(segment
		(start 119.958358 -206.70012)
		(end 120.29059 -206.445104)
		(width 0.14224)
		(layer "In6.Cu")
		(net "GMI_CPU1_G0_CPU0_G2_TX_DP<6>")
	)
	(segment
		(start 366.915192 -230.369872)
		(end 366.983518 -230.410004)
		(width 0.1143)
		(layer "In6.Cu")
		(net "GMI_CPU1_G0_CPU0_G2_TX_DP<6>")
	)
	(segment
		(start 167.586152 -179.92217)
		(end 302.901096 -180.711348)
		(width 0.14224)
		(layer "In6.Cu")
		(net "GMI_CPU1_G0_CPU0_G2_TX_DP<6>")
	)
	(segment
		(start 367.890806 -236.871002)
		(end 367.891822 -236.87151)
		(width 0.1143)
		(layer "In6.Cu")
		(net "GMI_CPU1_G0_CPU0_G2_TX_DP<6>")
	)
	(segment
		(start 105.01503 -226.341432)
		(end 105.05313 -226.31908)
		(width 0.1143)
		(layer "In6.Cu")
		(net "GMI_CPU1_G0_CPU0_G2_TX_DP<6>")
	)
	(segment
		(start 104.580436 -231.057958)
		(end 104.544114 -231.036876)
		(width 0.1143)
		(layer "In6.Cu")
		(net "GMI_CPU1_G0_CPU0_G2_TX_DP<6>")
	)
	(segment
		(start 367.889282 -236.869986)
		(end 367.890806 -236.871002)
		(width 0.1143)
		(layer "In6.Cu")
		(net "GMI_CPU1_G0_CPU0_G2_TX_DP<6>")
	)
	(segment
		(start 366.983518 -232.638092)
		(end 366.967516 -232.647236)
		(width 0.1143)
		(layer "In6.Cu")
		(net "GMI_CPU1_G0_CPU0_G2_TX_DP<6>")
	)
	(segment
		(start 104.583484 -233.609134)
		(end 104.609138 -233.590338)
		(width 0.1143)
		(layer "In6.Cu")
		(net "GMI_CPU1_G0_CPU0_G2_TX_DP<6>")
	)
	(segment
		(start 103.636318 -240.775744)
		(end 103.635556 -240.775236)
		(width 0.1143)
		(layer "In6.Cu")
		(net "GMI_CPU1_G0_CPU0_G2_TX_DP<6>")
	)
	(segment
		(start 367.532666 -241.24412)
		(end 367.234724 -241.24412)
		(width 0.1143)
		(layer "In6.Cu")
		(net "GMI_CPU1_G0_CPU0_G2_TX_DP<6>")
	)
	(segment
		(start 368.392456 -239.928908)
		(end 368.32286 -239.969548)
		(width 0.1143)
		(layer "In6.Cu")
		(net "GMI_CPU1_G0_CPU0_G2_TX_DP<6>")
	)
	(segment
		(start 119.601742 -207.137)
		(end 119.934482 -206.88173)
		(width 0.14224)
		(layer "In6.Cu")
		(net "GMI_CPU1_G0_CPU0_G2_TX_DP<6>")
	)
	(segment
		(start 368.32286 -237.658656)
		(end 368.392456 -237.699296)
		(width 0.1143)
		(layer "In6.Cu")
		(net "GMI_CPU1_G0_CPU0_G2_TX_DP<6>")
	)
	(segment
		(start 359.49636 -214.07374)
		(end 363.115352 -217.692478)
		(width 0.14224)
		(layer "In6.Cu")
		(net "GMI_CPU1_G0_CPU0_G2_TX_DP<6>")
	)
	(segment
		(start 365.542322 -224.721674)
		(end 365.573818 -224.739962)
		(width 0.1143)
		(layer "In6.Cu")
		(net "GMI_CPU1_G0_CPU0_G2_TX_DP<6>")
	)
	(segment
		(start 116.118894 -209.809588)
		(end 116.451634 -209.554318)
		(width 0.14224)
		(layer "In6.Cu")
		(net "GMI_CPU1_G0_CPU0_G2_TX_DP<6>")
	)
	(segment
		(start 363.804454 -221.09303)
		(end 363.850174 -221.13875)
		(width 0.1143)
		(layer "In6.Cu")
		(net "GMI_CPU1_G0_CPU0_G2_TX_DP<6>")
	)
	(segment
		(start 368.392456 -238.308896)
		(end 368.32286 -238.349536)
		(width 0.1143)
		(layer "In6.Cu")
		(net "GMI_CPU1_G0_CPU0_G2_TX_DP<6>")
	)
	(segment
		(start 104.528366 -232.64749)
		(end 104.512364 -232.638346)
		(width 0.1143)
		(layer "In6.Cu")
		(net "GMI_CPU1_G0_CPU0_G2_TX_DP<6>")
	)
	(segment
		(start 118.549166 -207.781398)
		(end 118.73103 -207.805274)
		(width 0.14224)
		(layer "In6.Cu")
		(net "GMI_CPU1_G0_CPU0_G2_TX_DP<6>")
	)
	(segment
		(start 103.173022 -239.969802)
		(end 103.133906 -239.946942)
		(width 0.1143)
		(layer "In6.Cu")
		(net "GMI_CPU1_G0_CPU0_G2_TX_DP<6>")
	)
	(segment
		(start 316.29223 -185.93562)
		(end 316.65291 -186.149488)
		(width 0.14224)
		(layer "In6.Cu")
		(net "GMI_CPU1_G0_CPU0_G2_TX_DP<6>")
	)
	(segment
		(start 103.133906 -237.68177)
		(end 103.173022 -237.65891)
		(width 0.1143)
		(layer "In6.Cu")
		(net "GMI_CPU1_G0_CPU0_G2_TX_DP<6>")
	)
	(segment
		(start 366.669574 -229.902258)
		(end 366.673892 -229.945692)
		(width 0.1143)
		(layer "In6.Cu")
		(net "GMI_CPU1_G0_CPU0_G2_TX_DP<6>")
	)
	(arc
		(start 106.021632 -224.676462)
		(mid 106.154165 -224.503297)
		(end 106.228388 -224.298256)
		(width 0.1143)
		(layer "In6.Cu")
		(net "GMI_CPU1_G0_CPU0_G2_TX_DP<6>")
	)
	(arc
		(start 104.593898 -231.06761)
		(mid 104.587203 -231.062734)
		(end 104.580436 -231.057958)
		(width 0.1143)
		(layer "In6.Cu")
		(net "GMI_CPU1_G0_CPU0_G2_TX_DP<6>")
	)
	(arc
		(start 106.393742 -223.929448)
		(mid 106.417156 -223.913042)
		(end 106.441748 -223.89846)
		(width 0.1143)
		(layer "In6.Cu")
		(net "GMI_CPU1_G0_CPU0_G2_TX_DP<6>")
	)
	(arc
		(start 366.892078 -231.972358)
		(mid 366.903644 -231.981527)
		(end 366.915446 -231.990392)
		(width 0.1143)
		(layer "In6.Cu")
		(net "GMI_CPU1_G0_CPU0_G2_TX_DP<6>")
	)
	(arc
		(start 366.673892 -229.945692)
		(mid 366.738329 -230.160666)
		(end 366.877346 -230.336852)
		(width 0.1143)
		(layer "In6.Cu")
		(net "GMI_CPU1_G0_CPU0_G2_TX_DP<6>")
	)
	(arc
		(start 106.512868 -223.849692)
		(mid 106.655364 -223.657971)
		(end 106.705908 -223.424496)
		(width 0.1143)
		(layer "In6.Cu")
		(net "GMI_CPU1_G0_CPU0_G2_TX_DP<6>")
	)
	(arc
		(start 367.139474 -230.714296)
		(mid 367.098712 -230.88418)
		(end 366.985296 -231.017064)
		(width 0.1143)
		(layer "In6.Cu")
		(net "GMI_CPU1_G0_CPU0_G2_TX_DP<6>")
	)
	(arc
		(start 104.609138 -233.590338)
		(mid 104.837746 -233.144314)
		(end 104.609138 -232.69829)
		(width 0.1143)
		(layer "In6.Cu")
		(net "GMI_CPU1_G0_CPU0_G2_TX_DP<6>")
	)
	(arc
		(start 365.25962 -224.223072)
		(mid 365.261992 -224.260702)
		(end 365.267494 -224.298002)
		(width 0.1143)
		(layer "In6.Cu")
		(net "GMI_CPU1_G0_CPU0_G2_TX_DP<6>")
	)
	(arc
		(start 107.403138 -222.26905)
		(mid 107.581951 -222.0667)
		(end 107.64647 -221.804484)
		(width 0.1143)
		(layer "In6.Cu")
		(net "GMI_CPU1_G0_CPU0_G2_TX_DP<6>")
	)
	(arc
		(start 367.923572 -236.889798)
		(mid 368.038248 -237.023132)
		(end 368.079528 -237.19409)
		(width 0.1143)
		(layer "In6.Cu")
		(net "GMI_CPU1_G0_CPU0_G2_TX_DP<6>")
	)
	(arc
		(start 103.173022 -239.278922)
		(mid 103.416349 -238.814356)
		(end 103.173022 -238.34979)
		(width 0.1143)
		(layer "In6.Cu")
		(net "GMI_CPU1_G0_CPU0_G2_TX_DP<6>")
	)
	(arc
		(start 103.643176 -236.848904)
		(mid 103.821989 -236.646554)
		(end 103.886508 -236.384338)
		(width 0.1143)
		(layer "In6.Cu")
		(net "GMI_CPU1_G0_CPU0_G2_TX_DP<6>")
	)
	(arc
		(start 105.05313 -226.31908)
		(mid 105.231943 -226.11673)
		(end 105.296462 -225.854514)
		(width 0.1143)
		(layer "In6.Cu")
		(net "GMI_CPU1_G0_CPU0_G2_TX_DP<6>")
	)
	(arc
		(start 104.822752 -226.699572)
		(mid 104.825096 -226.677392)
		(end 104.826308 -226.655122)
		(width 0.1143)
		(layer "In6.Cu")
		(net "GMI_CPU1_G0_CPU0_G2_TX_DP<6>")
	)
	(arc
		(start 106.228388 -224.298256)
		(mid 106.233881 -224.260955)
		(end 106.236262 -224.223326)
		(width 0.1143)
		(layer "In6.Cu")
		(net "GMI_CPU1_G0_CPU0_G2_TX_DP<6>")
	)
	(arc
		(start 104.631998 -230.325676)
		(mid 104.76067 -230.162537)
		(end 104.820212 -229.963472)
		(width 0.1143)
		(layer "In6.Cu")
		(net "GMI_CPU1_G0_CPU0_G2_TX_DP<6>")
	)
	(arc
		(start 365.267494 -224.298002)
		(mid 365.341715 -224.503044)
		(end 365.47425 -224.676208)
		(width 0.1143)
		(layer "In6.Cu")
		(net "GMI_CPU1_G0_CPU0_G2_TX_DP<6>")
	)
	(arc
		(start 366.983518 -230.410004)
		(mid 367.098194 -230.543338)
		(end 367.139474 -230.714296)
		(width 0.1143)
		(layer "In6.Cu")
		(net "GMI_CPU1_G0_CPU0_G2_TX_DP<6>")
	)
	(arc
		(start 368.392456 -237.699296)
		(mid 368.549433 -238.004096)
		(end 368.392456 -238.308896)
		(width 0.1143)
		(layer "In6.Cu")
		(net "GMI_CPU1_G0_CPU0_G2_TX_DP<6>")
	)
	(arc
		(start 367.452402 -236.079284)
		(mid 367.567829 -236.21266)
		(end 367.609374 -236.384084)
		(width 0.1143)
		(layer "In6.Cu")
		(net "GMI_CPU1_G0_CPU0_G2_TX_DP<6>")
	)
	(arc
		(start 368.32286 -239.969548)
		(mid 368.144047 -240.171898)
		(end 368.079528 -240.434114)
		(width 0.1143)
		(layer "In6.Cu")
		(net "GMI_CPU1_G0_CPU0_G2_TX_DP<6>")
	)
	(arc
		(start 367.61928 -241.138456)
		(mid 367.617257 -241.149866)
		(end 367.61547 -241.161316)
		(width 0.1143)
		(layer "In6.Cu")
		(net "GMI_CPU1_G0_CPU0_G2_TX_DP<6>")
	)
	(arc
		(start 367.139474 -235.574078)
		(mid 367.203989 -235.836297)
		(end 367.382806 -236.038644)
		(width 0.1143)
		(layer "In6.Cu")
		(net "GMI_CPU1_G0_CPU0_G2_TX_DP<6>")
	)
	(arc
		(start 106.705908 -223.424496)
		(mid 106.749534 -223.25475)
		(end 106.861864 -223.120204)
		(width 0.1143)
		(layer "In6.Cu")
		(net "GMI_CPU1_G0_CPU0_G2_TX_DP<6>")
	)
	(arc
		(start 107.176062 -222.569532)
		(mid 107.207145 -222.439744)
		(end 107.293664 -222.338138)
		(width 0.1143)
		(layer "In6.Cu")
		(net "GMI_CPU1_G0_CPU0_G2_TX_DP<6>")
	)
	(arc
		(start 364.634018 -223.11995)
		(mid 364.746391 -223.254474)
		(end 364.789974 -223.424242)
		(width 0.1143)
		(layer "In6.Cu")
		(net "GMI_CPU1_G0_CPU0_G2_TX_DP<6>")
	)
	(arc
		(start 366.886744 -232.698036)
		(mid 366.658136 -233.14406)
		(end 366.886744 -233.590084)
		(width 0.1143)
		(layer "In6.Cu")
		(net "GMI_CPU1_G0_CPU0_G2_TX_DP<6>")
	)
	(arc
		(start 367.609374 -236.384084)
		(mid 367.673889 -236.646303)
		(end 367.852706 -236.84865)
		(width 0.1143)
		(layer "In6.Cu")
		(net "GMI_CPU1_G0_CPU0_G2_TX_DP<6>")
	)
	(arc
		(start 103.886508 -236.384338)
		(mid 103.928057 -236.212916)
		(end 104.04348 -236.079538)
		(width 0.1143)
		(layer "In6.Cu")
		(net "GMI_CPU1_G0_CPU0_G2_TX_DP<6>")
	)
	(arc
		(start 365.054134 -223.898206)
		(mid 365.078732 -223.912779)
		(end 365.10214 -223.929194)
		(width 0.1143)
		(layer "In6.Cu")
		(net "GMI_CPU1_G0_CPU0_G2_TX_DP<6>")
	)
	(arc
		(start 368.079528 -240.434114)
		(mid 368.038273 -240.605085)
		(end 367.923572 -240.738406)
		(width 0.1143)
		(layer "In6.Cu")
		(net "GMI_CPU1_G0_CPU0_G2_TX_DP<6>")
	)
	(arc
		(start 105.520236 -225.510852)
		(mid 105.700888 -225.308107)
		(end 105.766108 -225.044508)
		(width 0.1143)
		(layer "In6.Cu")
		(net "GMI_CPU1_G0_CPU0_G2_TX_DP<6>")
	)
	(arc
		(start 104.376728 -234.075986)
		(mid 104.374107 -233.840577)
		(end 104.512364 -233.650028)
		(width 0.1143)
		(layer "In6.Cu")
		(net "GMI_CPU1_G0_CPU0_G2_TX_DP<6>")
	)
	(arc
		(start 103.880412 -241.16157)
		(mid 103.878624 -241.150121)
		(end 103.876602 -241.13871)
		(width 0.1143)
		(layer "In6.Cu")
		(net "GMI_CPU1_G0_CPU0_G2_TX_DP<6>")
	)
	(arc
		(start 366.983518 -232.029762)
		(mid 367.139446 -232.334054)
		(end 366.983518 -232.638346)
		(width 0.1143)
		(layer "In6.Cu")
		(net "GMI_CPU1_G0_CPU0_G2_TX_DP<6>")
	)
	(arc
		(start 366.513618 -226.359974)
		(mid 366.626199 -226.489116)
		(end 366.669574 -226.654868)
		(width 0.1143)
		(layer "In6.Cu")
		(net "GMI_CPU1_G0_CPU0_G2_TX_DP<6>")
	)
	(arc
		(start 103.876602 -241.13871)
		(mid 103.795169 -240.936312)
		(end 103.643176 -240.779808)
		(width 0.1143)
		(layer "In6.Cu")
		(net "GMI_CPU1_G0_CPU0_G2_TX_DP<6>")
	)
	(arc
		(start 365.10214 -223.929194)
		(mid 365.215373 -224.057655)
		(end 365.25962 -224.223072)
		(width 0.1143)
		(layer "In6.Cu")
		(net "GMI_CPU1_G0_CPU0_G2_TX_DP<6>")
	)
	(arc
		(start 104.356408 -235.574332)
		(mid 104.397663 -235.403361)
		(end 104.512364 -235.27004)
		(width 0.1143)
		(layer "In6.Cu")
		(net "GMI_CPU1_G0_CPU0_G2_TX_DP<6>")
	)
	(arc
		(start 368.32286 -238.349536)
		(mid 368.079533 -238.814102)
		(end 368.32286 -239.278668)
		(width 0.1143)
		(layer "In6.Cu")
		(net "GMI_CPU1_G0_CPU0_G2_TX_DP<6>")
	)
	(arc
		(start 366.910366 -231.061006)
		(mid 366.72989 -231.269599)
		(end 366.669574 -231.53878)
		(width 0.1143)
		(layer "In6.Cu")
		(net "GMI_CPU1_G0_CPU0_G2_TX_DP<6>")
	)
	(arc
		(start 365.729774 -225.044254)
		(mid 365.79501 -225.307845)
		(end 365.975646 -225.510598)
		(width 0.1143)
		(layer "In6.Cu")
		(net "GMI_CPU1_G0_CPU0_G2_TX_DP<6>")
	)
	(arc
		(start 364.789974 -223.424242)
		(mid 364.840487 -223.657732)
		(end 364.983014 -223.849438)
		(width 0.1143)
		(layer "In6.Cu")
		(net "GMI_CPU1_G0_CPU0_G2_TX_DP<6>")
	)
	(arc
		(start 366.983518 -235.269786)
		(mid 367.098194 -235.40312)
		(end 367.139474 -235.574078)
		(width 0.1143)
		(layer "In6.Cu")
		(net "GMI_CPU1_G0_CPU0_G2_TX_DP<6>")
	)
	(arc
		(start 365.573818 -224.739962)
		(mid 365.688494 -224.873296)
		(end 365.729774 -225.044254)
		(width 0.1143)
		(layer "In6.Cu")
		(net "GMI_CPU1_G0_CPU0_G2_TX_DP<6>")
	)
	(arc
		(start 363.849412 -221.80423)
		(mid 363.913927 -222.066449)
		(end 364.092744 -222.268796)
		(width 0.1143)
		(layer "In6.Cu")
		(net "GMI_CPU1_G0_CPU0_G2_TX_DP<6>")
	)
	(arc
		(start 366.910874 -229.44074)
		(mid 366.769281 -229.58328)
		(end 366.686592 -229.766368)
		(width 0.1143)
		(layer "In6.Cu")
		(net "GMI_CPU1_G0_CPU0_G2_TX_DP<6>")
	)
	(arc
		(start 365.47425 -224.676208)
		(mid 365.48804 -224.687609)
		(end 365.50219 -224.69856)
		(width 0.1143)
		(layer "In6.Cu")
		(net "GMI_CPU1_G0_CPU0_G2_TX_DP<6>")
	)
	(arc
		(start 104.826308 -226.654868)
		(mid 104.869701 -226.489236)
		(end 104.982264 -226.360228)
		(width 0.1143)
		(layer "In6.Cu")
		(net "GMI_CPU1_G0_CPU0_G2_TX_DP<6>")
	)
	(arc
		(start 367.852706 -240.779554)
		(mid 367.700719 -240.936062)
		(end 367.61928 -241.138456)
		(width 0.1143)
		(layer "In6.Cu")
		(net "GMI_CPU1_G0_CPU0_G2_TX_DP<6>")
	)
	(arc
		(start 103.416354 -237.194344)
		(mid 103.457609 -237.023373)
		(end 103.57231 -236.890052)
		(width 0.1143)
		(layer "In6.Cu")
		(net "GMI_CPU1_G0_CPU0_G2_TX_DP<6>")
	)
	(arc
		(start 366.679226 -226.740974)
		(mid 366.742408 -226.932431)
		(end 366.868202 -227.08997)
		(width 0.1143)
		(layer "In6.Cu")
		(net "GMI_CPU1_G0_CPU0_G2_TX_DP<6>")
	)
	(arc
		(start 104.610916 -235.20908)
		(mid 104.838916 -234.764326)
		(end 104.610916 -234.319572)
		(width 0.1143)
		(layer "In6.Cu")
		(net "GMI_CPU1_G0_CPU0_G2_TX_DP<6>")
	)
	(arc
		(start 104.826308 -231.538018)
		(mid 104.767972 -231.274245)
		(end 104.593898 -231.06761)
		(width 0.1143)
		(layer "In6.Cu")
		(net "GMI_CPU1_G0_CPU0_G2_TX_DP<6>")
	)
	(arc
		(start 366.983518 -228.789992)
		(mid 367.098194 -228.923326)
		(end 367.139474 -229.094284)
		(width 0.1143)
		(layer "In6.Cu")
		(net "GMI_CPU1_G0_CPU0_G2_TX_DP<6>")
	)
	(arc
		(start 104.580436 -231.990646)
		(mid 104.596401 -231.978605)
		(end 104.611932 -231.966008)
		(width 0.1143)
		(layer "In6.Cu")
		(net "GMI_CPU1_G0_CPU0_G2_TX_DP<6>")
	)
	(arc
		(start 106.441748 -223.89846)
		(mid 106.478708 -223.876117)
		(end 106.512868 -223.849692)
		(width 0.1143)
		(layer "In6.Cu")
		(net "GMI_CPU1_G0_CPU0_G2_TX_DP<6>")
	)
	(arc
		(start 104.648 -231.931464)
		(mid 104.76373 -231.774339)
		(end 104.820212 -231.587548)
		(width 0.1143)
		(layer "In6.Cu")
		(net "GMI_CPU1_G0_CPU0_G2_TX_DP<6>")
	)
	(arc
		(start 366.678464 -231.60101)
		(mid 366.731716 -231.772763)
		(end 366.836706 -231.918764)
		(width 0.1143)
		(layer "In6.Cu")
		(net "GMI_CPU1_G0_CPU0_G2_TX_DP<6>")
	)
	(arc
		(start 366.983518 -233.649774)
		(mid 367.121774 -233.840324)
		(end 367.119154 -234.075732)
		(width 0.1143)
		(layer "In6.Cu")
		(net "GMI_CPU1_G0_CPU0_G2_TX_DP<6>")
	)
	(arc
		(start 104.510586 -231.017318)
		(mid 104.397179 -230.884429)
		(end 104.356408 -230.71455)
		(width 0.1143)
		(layer "In6.Cu")
		(net "GMI_CPU1_G0_CPU0_G2_TX_DP<6>")
	)
	(arc
		(start 105.993692 -224.698814)
		(mid 106.007836 -224.687856)
		(end 106.021632 -224.676462)
		(width 0.1143)
		(layer "In6.Cu")
		(net "GMI_CPU1_G0_CPU0_G2_TX_DP<6>")
	)
	(arc
		(start 103.57231 -240.73866)
		(mid 103.457634 -240.605326)
		(end 103.416354 -240.434368)
		(width 0.1143)
		(layer "In6.Cu")
		(net "GMI_CPU1_G0_CPU0_G2_TX_DP<6>")
	)
	(arc
		(start 106.93273 -223.079056)
		(mid 107.111543 -222.876706)
		(end 107.176062 -222.61449)
		(width 0.1143)
		(layer "In6.Cu")
		(net "GMI_CPU1_G0_CPU0_G2_TX_DP<6>")
	)
	(arc
		(start 366.686592 -229.766368)
		(mid 366.673944 -229.833795)
		(end 366.669574 -229.902258)
		(width 0.1143)
		(layer "In6.Cu")
		(net "GMI_CPU1_G0_CPU0_G2_TX_DP<6>")
	)
	(arc
		(start 103.103426 -238.30915)
		(mid 102.946449 -238.00435)
		(end 103.103426 -237.69955)
		(width 0.1143)
		(layer "In6.Cu")
		(net "GMI_CPU1_G0_CPU0_G2_TX_DP<6>")
	)
	(arc
		(start 104.356408 -229.094538)
		(mid 104.397663 -228.923567)
		(end 104.512364 -228.790246)
		(width 0.1143)
		(layer "In6.Cu")
		(net "GMI_CPU1_G0_CPU0_G2_TX_DP<6>")
	)
	(arc
		(start 366.669574 -226.654868)
		(mid 366.670894 -226.677397)
		(end 366.673384 -226.699826)
		(width 0.1143)
		(layer "In6.Cu")
		(net "GMI_CPU1_G0_CPU0_G2_TX_DP<6>")
	)
	(arc
		(start 367.139474 -229.094284)
		(mid 367.098712 -229.264168)
		(end 366.985296 -229.397052)
		(width 0.1143)
		(layer "In6.Cu")
		(net "GMI_CPU1_G0_CPU0_G2_TX_DP<6>")
	)
	(arc
		(start 103.416354 -240.434368)
		(mid 103.351839 -240.172149)
		(end 103.173022 -239.969802)
		(width 0.1143)
		(layer "In6.Cu")
		(net "GMI_CPU1_G0_CPU0_G2_TX_DP<6>")
	)
	(arc
		(start 366.884966 -234.319318)
		(mid 366.656966 -234.764072)
		(end 366.884966 -235.208826)
		(width 0.1143)
		(layer "In6.Cu")
		(net "GMI_CPU1_G0_CPU0_G2_TX_DP<6>")
	)
	(arc
		(start 103.103426 -239.929162)
		(mid 102.946449 -239.624362)
		(end 103.103426 -239.319562)
		(width 0.1143)
		(layer "In6.Cu")
		(net "GMI_CPU1_G0_CPU0_G2_TX_DP<6>")
	)
	(arc
		(start 105.296462 -225.854514)
		(mid 105.338011 -225.683092)
		(end 105.453434 -225.549714)
		(width 0.1143)
		(layer "In6.Cu")
		(net "GMI_CPU1_G0_CPU0_G2_TX_DP<6>")
	)
	(arc
		(start 368.079528 -237.19409)
		(mid 368.144043 -237.456309)
		(end 368.32286 -237.658656)
		(width 0.1143)
		(layer "In6.Cu")
		(net "GMI_CPU1_G0_CPU0_G2_TX_DP<6>")
	)
	(arc
		(start 364.983014 -223.849438)
		(mid 365.01718 -223.875855)
		(end 365.054134 -223.898206)
		(width 0.1143)
		(layer "In6.Cu")
		(net "GMI_CPU1_G0_CPU0_G2_TX_DP<6>")
	)
	(arc
		(start 104.113076 -236.038898)
		(mid 104.291889 -235.836548)
		(end 104.356408 -235.574332)
		(width 0.1143)
		(layer "In6.Cu")
		(net "GMI_CPU1_G0_CPU0_G2_TX_DP<6>")
	)
	(arc
		(start 368.392456 -239.319308)
		(mid 368.549433 -239.624108)
		(end 368.392456 -239.928908)
		(width 0.1143)
		(layer "In6.Cu")
		(net "GMI_CPU1_G0_CPU0_G2_TX_DP<6>")
	)
	(arc
		(start 103.173022 -237.65891)
		(mid 103.351835 -237.45656)
		(end 103.416354 -237.194344)
		(width 0.1143)
		(layer "In6.Cu")
		(net "GMI_CPU1_G0_CPU0_G2_TX_DP<6>")
	)
	(arc
		(start 366.19942 -225.85426)
		(mid 366.263935 -226.116479)
		(end 366.442752 -226.318826)
		(width 0.1143)
		(layer "In6.Cu")
		(net "GMI_CPU1_G0_CPU0_G2_TX_DP<6>")
	)
	(arc
		(start 364.202218 -222.337884)
		(mid 364.288714 -222.439502)
		(end 364.31982 -222.569278)
		(width 0.1143)
		(layer "In6.Cu")
		(net "GMI_CPU1_G0_CPU0_G2_TX_DP<6>")
	)
	(arc
		(start 104.610408 -228.729794)
		(mid 104.83882 -228.284532)
		(end 104.610408 -227.83927)
		(width 0.1143)
		(layer "In6.Cu")
		(net "GMI_CPU1_G0_CPU0_G2_TX_DP<6>")
	)
	(arc
		(start 104.512364 -234.258358)
		(mid 104.430383 -234.177708)
		(end 104.376728 -234.075986)
		(width 0.1143)
		(layer "In6.Cu")
		(net "GMI_CPU1_G0_CPU0_G2_TX_DP<6>")
	)
	(arc
		(start 104.512364 -232.6386)
		(mid 104.356436 -232.334308)
		(end 104.512364 -232.030016)
		(width 0.1143)
		(layer "In6.Cu")
		(net "GMI_CPU1_G0_CPU0_G2_TX_DP<6>")
	)
	(arc
		(start 364.31982 -222.614236)
		(mid 364.384335 -222.876455)
		(end 364.563152 -223.078802)
		(width 0.1143)
		(layer "In6.Cu")
		(net "GMI_CPU1_G0_CPU0_G2_TX_DP<6>")
	)
	(arc
		(start 366.983772 -227.170234)
		(mid 367.139388 -227.474449)
		(end 366.983518 -227.778564)
		(width 0.1143)
		(layer "In6.Cu")
		(net "GMI_CPU1_G0_CPU0_G2_TX_DP<6>")
	)
	(arc
		(start 104.512364 -227.778818)
		(mid 104.356436 -227.474703)
		(end 104.51211 -227.170488)
		(width 0.1143)
		(layer "In6.Cu")
		(net "GMI_CPU1_G0_CPU0_G2_TX_DP<6>")
	)
	(arc
		(start 104.826308 -229.902512)
		(mid 104.764461 -229.647284)
		(end 104.593898 -229.447598)
		(width 0.1143)
		(layer "In6.Cu")
		(net "GMI_CPU1_G0_CPU0_G2_TX_DP<6>")
	)
	(arc
		(start 105.766108 -225.044508)
		(mid 105.807363 -224.873537)
		(end 105.922064 -224.740216)
		(width 0.1143)
		(layer "In6.Cu")
		(net "GMI_CPU1_G0_CPU0_G2_TX_DP<6>")
	)
	(arc
		(start 104.510586 -229.397306)
		(mid 104.397179 -229.264417)
		(end 104.356408 -229.094538)
		(width 0.1143)
		(layer "In6.Cu")
		(net "GMI_CPU1_G0_CPU0_G2_TX_DP<6>")
	)
	(arc
		(start 366.885474 -227.839016)
		(mid 366.657062 -228.284278)
		(end 366.885474 -228.72954)
		(width 0.1143)
		(layer "In6.Cu")
		(net "GMI_CPU1_G0_CPU0_G2_TX_DP<6>")
	)
	(arc
		(start 367.119154 -234.075732)
		(mid 367.065518 -234.177468)
		(end 366.983518 -234.258104)
		(width 0.1143)
		(layer "In6.Cu")
		(net "GMI_CPU1_G0_CPU0_G2_TX_DP<6>")
	)
	(arc
		(start 104.356154 -230.714296)
		(mid 104.397477 -230.543698)
		(end 104.511856 -230.410512)
		(width 0.1143)
		(layer "In6.Cu")
		(net "GMI_CPU1_G0_CPU0_G2_TX_DP<6>")
	)
	(arc
		(start 104.628442 -227.089462)
		(mid 104.753718 -226.932611)
		(end 104.816656 -226.74199)
		(width 0.1143)
		(layer "In6.Cu")
		(net "GMI_CPU1_G0_CPU0_G2_TX_DP<6>")
	)
	(arc
		(start 366.042448 -225.54946)
		(mid 366.157875 -225.682836)
		(end 366.19942 -225.85426)
		(width 0.1143)
		(layer "In6.Cu")
		(net "GMI_CPU1_G0_CPU0_G2_TX_DP<6>")
	)
	(arc
		(start 106.236262 -224.223326)
		(mid 106.280546 -224.057929)
		(end 106.393742 -223.929448)
		(width 0.1143)
		(layer "In6.Cu")
		(net "GMI_CPU1_G0_CPU0_G2_TX_DP<6>")
	)
	(segment
		(start 101.907848 -243.130324)
		(end 101.440996 -242.864386)
		(width 0.12954)
		(layer "F.Cu")
		(net "GMI_CPU1_G0_CPU0_G2_TX_DP<5>")
	)
	(segment
		(start 369.588034 -243.13007)
		(end 370.054886 -242.864132)
		(width 0.12954)
		(layer "F.Cu")
		(net "GMI_CPU1_G0_CPU0_G2_TX_DP<5>")
	)
	(segment
		(start 367.890806 -227.151184)
		(end 367.891822 -227.151692)
		(width 0.1143)
		(layer "In6.Cu")
		(net "GMI_CPU1_G0_CPU0_G2_TX_DP<5>")
	)
	(segment
		(start 369.301776 -239.946688)
		(end 369.265454 -239.96777)
		(width 0.1143)
		(layer "In6.Cu")
		(net "GMI_CPU1_G0_CPU0_G2_TX_DP<5>")
	)
	(segment
		(start 366.479328 -224.72015)
		(end 366.480852 -224.721166)
		(width 0.1143)
		(layer "In6.Cu")
		(net "GMI_CPU1_G0_CPU0_G2_TX_DP<5>")
	)
	(segment
		(start 101.256592 -242.540282)
		(end 101.293168 -242.518946)
		(width 0.1143)
		(layer "In6.Cu")
		(net "GMI_CPU1_G0_CPU0_G2_TX_DP<5>")
	)
	(segment
		(start 104.545638 -225.531172)
		(end 104.580436 -225.510852)
		(width 0.1143)
		(layer "In6.Cu")
		(net "GMI_CPU1_G0_CPU0_G2_TX_DP<5>")
	)
	(segment
		(start 367.889282 -227.150168)
		(end 367.890806 -227.151184)
		(width 0.1143)
		(layer "In6.Cu")
		(net "GMI_CPU1_G0_CPU0_G2_TX_DP<5>")
	)
	(segment
		(start 105.924858 -223.118934)
		(end 105.98785 -223.082358)
		(width 0.1143)
		(layer "In6.Cu")
		(net "GMI_CPU1_G0_CPU0_G2_TX_DP<5>")
	)
	(segment
		(start 117.65788 -207.2767)
		(end 117.681756 -207.094836)
		(width 0.14224)
		(layer "In6.Cu")
		(net "GMI_CPU1_G0_CPU0_G2_TX_DP<5>")
	)
	(segment
		(start 103.60406 -232.656888)
		(end 103.603298 -232.65638)
		(width 0.1143)
		(layer "In6.Cu")
		(net "GMI_CPU1_G0_CPU0_G2_TX_DP<5>")
	)
	(segment
		(start 369.265454 -240.900458)
		(end 369.301776 -240.92154)
		(width 0.1143)
		(layer "In6.Cu")
		(net "GMI_CPU1_G0_CPU0_G2_TX_DP<5>")
	)
	(segment
		(start 104.98328 -224.739708)
		(end 105.013252 -224.722436)
		(width 0.1143)
		(layer "In6.Cu")
		(net "GMI_CPU1_G0_CPU0_G2_TX_DP<5>")
	)
	(segment
		(start 105.484422 -223.911922)
		(end 105.524808 -223.8883)
		(width 0.1143)
		(layer "In6.Cu")
		(net "GMI_CPU1_G0_CPU0_G2_TX_DP<5>")
	)
	(segment
		(start 367.852706 -231.988614)
		(end 367.889282 -232.00995)
		(width 0.1143)
		(layer "In6.Cu")
		(net "GMI_CPU1_G0_CPU0_G2_TX_DP<5>")
	)
	(segment
		(start 119.066564 -206.195676)
		(end 119.399304 -205.940406)
		(width 0.14224)
		(layer "In6.Cu")
		(net "GMI_CPU1_G0_CPU0_G2_TX_DP<5>")
	)
	(segment
		(start 102.162356 -239.32007)
		(end 102.194106 -239.301782)
		(width 0.1143)
		(layer "In6.Cu")
		(net "GMI_CPU1_G0_CPU0_G2_TX_DP<5>")
	)
	(segment
		(start 116.811044 -207.76311)
		(end 117.143276 -207.508094)
		(width 0.14224)
		(layer "In6.Cu")
		(net "GMI_CPU1_G0_CPU0_G2_TX_DP<5>")
	)
	(segment
		(start 121.095008 -204.475588)
		(end 163.347146 -180.078126)
		(width 0.14224)
		(layer "In6.Cu")
		(net "GMI_CPU1_G0_CPU0_G2_TX_DP<5>")
	)
	(segment
		(start 104.544114 -225.531934)
		(end 104.545638 -225.531172)
		(width 0.1143)
		(layer "In6.Cu")
		(net "GMI_CPU1_G0_CPU0_G2_TX_DP<5>")
	)
	(segment
		(start 367.890806 -233.630978)
		(end 367.891822 -233.631486)
		(width 0.1143)
		(layer "In6.Cu")
		(net "GMI_CPU1_G0_CPU0_G2_TX_DP<5>")
	)
	(segment
		(start 357.71582 -211.450936)
		(end 360.06913 -213.327742)
		(width 0.14224)
		(layer "In6.Cu")
		(net "GMI_CPU1_G0_CPU0_G2_TX_DP<5>")
	)
	(segment
		(start 369.333526 -239.9284)
		(end 369.301776 -239.946688)
		(width 0.1143)
		(layer "In6.Cu")
		(net "GMI_CPU1_G0_CPU0_G2_TX_DP<5>")
	)
	(segment
		(start 106.705908 -221.246954)
		(end 106.705908 -221.139004)
		(width 0.1143)
		(layer "In6.Cu")
		(net "GMI_CPU1_G0_CPU0_G2_TX_DP<5>")
	)
	(segment
		(start 103.60406 -233.63174)
		(end 103.605076 -233.631232)
		(width 0.1143)
		(layer "In6.Cu")
		(net "GMI_CPU1_G0_CPU0_G2_TX_DP<5>")
	)
	(segment
		(start 367.923572 -232.638346)
		(end 367.893854 -232.655364)
		(width 0.1143)
		(layer "In6.Cu")
		(net "GMI_CPU1_G0_CPU0_G2_TX_DP<5>")
	)
	(segment
		(start 104.543352 -225.532442)
		(end 104.544114 -225.531934)
		(width 0.1143)
		(layer "In6.Cu")
		(net "GMI_CPU1_G0_CPU0_G2_TX_DP<5>")
	)
	(segment
		(start 105.451656 -223.930972)
		(end 105.484422 -223.911922)
		(width 0.1143)
		(layer "In6.Cu")
		(net "GMI_CPU1_G0_CPU0_G2_TX_DP<5>")
	)
	(segment
		(start 364.744762 -221.081346)
		(end 364.744762 -221.09303)
		(width 0.1143)
		(layer "In6.Cu")
		(net "GMI_CPU1_G0_CPU0_G2_TX_DP<5>")
	)
	(segment
		(start 102.64775 -236.881162)
		(end 102.660958 -236.873542)
		(width 0.1143)
		(layer "In6.Cu")
		(net "GMI_CPU1_G0_CPU0_G2_TX_DP<5>")
	)
	(segment
		(start 117.681756 -207.094836)
		(end 118.014242 -206.83982)
		(width 0.14224)
		(layer "In6.Cu")
		(net "GMI_CPU1_G0_CPU0_G2_TX_DP<5>")
	)
	(segment
		(start 103.133906 -236.061758)
		(end 103.173022 -236.038898)
		(width 0.1143)
		(layer "In6.Cu")
		(net "GMI_CPU1_G0_CPU0_G2_TX_DP<5>")
	)
	(segment
		(start 367.92535 -229.397052)
		(end 367.852706 -229.43947)
		(width 0.1143)
		(layer "In6.Cu")
		(net "GMI_CPU1_G0_CPU0_G2_TX_DP<5>")
	)
	(segment
		(start 368.834162 -236.87278)
		(end 368.834924 -236.873288)
		(width 0.1143)
		(layer "In6.Cu")
		(net "GMI_CPU1_G0_CPU0_G2_TX_DP<5>")
	)
	(segment
		(start 116.272564 -208.176368)
		(end 116.454428 -208.200244)
		(width 0.14224)
		(layer "In6.Cu")
		(net "GMI_CPU1_G0_CPU0_G2_TX_DP<5>")
	)
	(segment
		(start 102.194106 -239.946942)
		(end 102.162356 -239.928654)
		(width 0.1143)
		(layer "In6.Cu")
		(net "GMI_CPU1_G0_CPU0_G2_TX_DP<5>")
	)
	(segment
		(start 118.195852 -206.863696)
		(end 118.528592 -206.608426)
		(width 0.14224)
		(layer "In6.Cu")
		(net "GMI_CPU1_G0_CPU0_G2_TX_DP<5>")
	)
	(segment
		(start 370.202714 -242.518692)
		(end 370.23929 -242.540028)
		(width 0.1143)
		(layer "In6.Cu")
		(net "GMI_CPU1_G0_CPU0_G2_TX_DP<5>")
	)
	(segment
		(start 103.6066 -233.630216)
		(end 103.643176 -233.60888)
		(width 0.1143)
		(layer "In6.Cu")
		(net "GMI_CPU1_G0_CPU0_G2_TX_DP<5>")
	)
	(segment
		(start 367.852706 -235.228638)
		(end 367.889282 -235.249974)
		(width 0.1143)
		(layer "In6.Cu")
		(net "GMI_CPU1_G0_CPU0_G2_TX_DP<5>")
	)
	(segment
		(start 306.824888 -179.774088)
		(end 309.00497 -180.372512)
		(width 0.14224)
		(layer "In6.Cu")
		(net "GMI_CPU1_G0_CPU0_G2_TX_DP<5>")
	)
	(segment
		(start 103.60406 -227.151946)
		(end 103.605076 -227.151438)
		(width 0.1143)
		(layer "In6.Cu")
		(net "GMI_CPU1_G0_CPU0_G2_TX_DP<5>")
	)
	(segment
		(start 102.194106 -239.301782)
		(end 102.230428 -239.2807)
		(width 0.1143)
		(layer "In6.Cu")
		(net "GMI_CPU1_G0_CPU0_G2_TX_DP<5>")
	)
	(segment
		(start 115.583716 -208.868264)
		(end 115.916456 -208.612994)
		(width 0.14224)
		(layer "In6.Cu")
		(net "GMI_CPU1_G0_CPU0_G2_TX_DP<5>")
	)
	(segment
		(start 355.362002 -209.573622)
		(end 357.715566 -211.450682)
		(width 0.14224)
		(layer "In6.Cu")
		(net "GMI_CPU1_G0_CPU0_G2_TX_DP<5>")
	)
	(segment
		(start 116.454428 -208.200244)
		(end 116.787168 -207.944974)
		(width 0.14224)
		(layer "In6.Cu")
		(net "GMI_CPU1_G0_CPU0_G2_TX_DP<5>")
	)
	(segment
		(start 105.013252 -224.722436)
		(end 105.014014 -224.721928)
		(width 0.1143)
		(layer "In6.Cu")
		(net "GMI_CPU1_G0_CPU0_G2_TX_DP<5>")
	)
	(segment
		(start 369.333526 -238.308388)
		(end 369.301776 -238.326676)
		(width 0.1143)
		(layer "In6.Cu")
		(net "GMI_CPU1_G0_CPU0_G2_TX_DP<5>")
	)
	(segment
		(start 102.634288 -236.889036)
		(end 102.64775 -236.881162)
		(width 0.1143)
		(layer "In6.Cu")
		(net "GMI_CPU1_G0_CPU0_G2_TX_DP<5>")
	)
	(segment
		(start 102.230428 -238.348012)
		(end 102.194106 -238.32693)
		(width 0.1143)
		(layer "In6.Cu")
		(net "GMI_CPU1_G0_CPU0_G2_TX_DP<5>")
	)
	(segment
		(start 103.605076 -232.657396)
		(end 103.60406 -232.656888)
		(width 0.1143)
		(layer "In6.Cu")
		(net "GMI_CPU1_G0_CPU0_G2_TX_DP<5>")
	)
	(segment
		(start 103.605076 -232.01122)
		(end 103.6066 -232.010204)
		(width 0.1143)
		(layer "In6.Cu")
		(net "GMI_CPU1_G0_CPU0_G2_TX_DP<5>")
	)
	(segment
		(start 368.832638 -236.872018)
		(end 368.834162 -236.87278)
		(width 0.1143)
		(layer "In6.Cu")
		(net "GMI_CPU1_G0_CPU0_G2_TX_DP<5>")
	)
	(segment
		(start 120.293892 -205.090522)
		(end 121.095008 -204.475588)
		(width 0.14224)
		(layer "In6.Cu")
		(net "GMI_CPU1_G0_CPU0_G2_TX_DP<5>")
	)
	(segment
		(start 107.613704 -217.262964)
		(end 108.114084 -216.054686)
		(width 0.14224)
		(layer "In6.Cu")
		(net "GMI_CPU1_G0_CPU0_G2_TX_DP<5>")
	)
	(segment
		(start 103.60406 -232.011728)
		(end 103.605076 -232.01122)
		(width 0.1143)
		(layer "In6.Cu")
		(net "GMI_CPU1_G0_CPU0_G2_TX_DP<5>")
	)
	(segment
		(start 103.636318 -227.815902)
		(end 103.635556 -227.815394)
		(width 0.1143)
		(layer "In6.Cu")
		(net "GMI_CPU1_G0_CPU0_G2_TX_DP<5>")
	)
	(segment
		(start 367.893854 -232.012744)
		(end 367.923572 -232.029762)
		(width 0.1143)
		(layer "In6.Cu")
		(net "GMI_CPU1_G0_CPU0_G2_TX_DP<5>")
	)
	(segment
		(start 367.891822 -227.796852)
		(end 367.890806 -227.79736)
		(width 0.1143)
		(layer "In6.Cu")
		(net "GMI_CPU1_G0_CPU0_G2_TX_DP<5>")
	)
	(segment
		(start 366.9538 -225.53295)
		(end 366.983518 -225.549968)
		(width 0.1143)
		(layer "In6.Cu")
		(net "GMI_CPU1_G0_CPU0_G2_TX_DP<5>")
	)
	(segment
		(start 106.751628 -219.344494)
		(end 106.934 -218.904058)
		(width 0.14224)
		(layer "In6.Cu")
		(net "GMI_CPU1_G0_CPU0_G2_TX_DP<5>")
	)
	(segment
		(start 107.193842 -218.276932)
		(end 107.354116 -217.889836)
		(width 0.14224)
		(layer "In6.Cu")
		(net "GMI_CPU1_G0_CPU0_G2_TX_DP<5>")
	)
	(segment
		(start 370.352828 -242.864132)
		(end 370.054886 -242.864132)
		(width 0.1143)
		(layer "In6.Cu")
		(net "GMI_CPU1_G0_CPU0_G2_TX_DP<5>")
	)
	(segment
		(start 102.233476 -237.659164)
		(end 102.350316 -237.574836)
		(width 0.1143)
		(layer "In6.Cu")
		(net "GMI_CPU1_G0_CPU0_G2_TX_DP<5>")
	)
	(segment
		(start 105.016554 -224.720404)
		(end 105.05313 -224.699068)
		(width 0.1143)
		(layer "In6.Cu")
		(net "GMI_CPU1_G0_CPU0_G2_TX_DP<5>")
	)
	(segment
		(start 367.852706 -233.608626)
		(end 367.889282 -233.629962)
		(width 0.1143)
		(layer "In6.Cu")
		(net "GMI_CPU1_G0_CPU0_G2_TX_DP<5>")
	)
	(segment
		(start 106.751628 -221.093284)
		(end 106.751628 -221.064836)
		(width 0.1143)
		(layer "In6.Cu")
		(net "GMI_CPU1_G0_CPU0_G2_TX_DP<5>")
	)
	(segment
		(start 368.829336 -236.869986)
		(end 368.83086 -236.871002)
		(width 0.1143)
		(layer "In6.Cu")
		(net "GMI_CPU1_G0_CPU0_G2_TX_DP<5>")
	)
	(segment
		(start 102.194106 -240.921794)
		(end 102.230428 -240.900712)
		(width 0.1143)
		(layer "In6.Cu")
		(net "GMI_CPU1_G0_CPU0_G2_TX_DP<5>")
	)
	(segment
		(start 103.60406 -234.2769)
		(end 103.603298 -234.276392)
		(width 0.1143)
		(layer "In6.Cu")
		(net "GMI_CPU1_G0_CPU0_G2_TX_DP<5>")
	)
	(segment
		(start 103.60406 -231.036876)
		(end 103.570532 -231.017318)
		(width 0.1143)
		(layer "In6.Cu")
		(net "GMI_CPU1_G0_CPU0_G2_TX_DP<5>")
	)
	(segment
		(start 367.891822 -235.251498)
		(end 367.923572 -235.269786)
		(width 0.1143)
		(layer "In6.Cu")
		(net "GMI_CPU1_G0_CPU0_G2_TX_DP<5>")
	)
	(segment
		(start 163.347146 -180.078126)
		(end 165.412166 -179.53101)
		(width 0.14224)
		(layer "In6.Cu")
		(net "GMI_CPU1_G0_CPU0_G2_TX_DP<5>")
	)
	(segment
		(start 364.744762 -219.122752)
		(end 364.744762 -221.081346)
		(width 0.14224)
		(layer "In6.Cu")
		(net "GMI_CPU1_G0_CPU0_G2_TX_DP<5>")
	)
	(segment
		(start 102.66172 -236.873034)
		(end 102.663244 -236.872272)
		(width 0.1143)
		(layer "In6.Cu")
		(net "GMI_CPU1_G0_CPU0_G2_TX_DP<5>")
	)
	(segment
		(start 115.916456 -208.612994)
		(end 115.940332 -208.431384)
		(width 0.14224)
		(layer "In6.Cu")
		(net "GMI_CPU1_G0_CPU0_G2_TX_DP<5>")
	)
	(segment
		(start 101.222302 -242.560094)
		(end 101.25329 -242.542314)
		(width 0.1143)
		(layer "In6.Cu")
		(net "GMI_CPU1_G0_CPU0_G2_TX_DP<5>")
	)
	(segment
		(start 369.301776 -239.301528)
		(end 369.333526 -239.319816)
		(width 0.1143)
		(layer "In6.Cu")
		(net "GMI_CPU1_G0_CPU0_G2_TX_DP<5>")
	)
	(segment
		(start 366.480852 -224.721166)
		(end 366.481868 -224.721674)
		(width 0.1143)
		(layer "In6.Cu")
		(net "GMI_CPU1_G0_CPU0_G2_TX_DP<5>")
	)
	(segment
		(start 106.751628 -221.064836)
		(end 106.751628 -219.344494)
		(width 0.14224)
		(layer "In6.Cu")
		(net "GMI_CPU1_G0_CPU0_G2_TX_DP<5>")
	)
	(segment
		(start 366.915446 -225.510598)
		(end 366.950244 -225.530918)
		(width 0.1143)
		(layer "In6.Cu")
		(net "GMI_CPU1_G0_CPU0_G2_TX_DP<5>")
	)
	(segment
		(start 107.354116 -217.889836)
		(end 107.523534 -217.819732)
		(width 0.14224)
		(layer "In6.Cu")
		(net "GMI_CPU1_G0_CPU0_G2_TX_DP<5>")
	)
	(segment
		(start 367.893854 -228.772974)
		(end 367.923572 -228.789992)
		(width 0.1143)
		(layer "In6.Cu")
		(net "GMI_CPU1_G0_CPU0_G2_TX_DP<5>")
	)
	(segment
		(start 103.6066 -232.010204)
		(end 103.643176 -231.988868)
		(width 0.1143)
		(layer "In6.Cu")
		(net "GMI_CPU1_G0_CPU0_G2_TX_DP<5>")
	)
	(segment
		(start 117.32514 -207.53197)
		(end 117.65788 -207.2767)
		(width 0.14224)
		(layer "In6.Cu")
		(net "GMI_CPU1_G0_CPU0_G2_TX_DP<5>")
	)
	(segment
		(start 367.889282 -232.00995)
		(end 367.890806 -232.010966)
		(width 0.1143)
		(layer "In6.Cu")
		(net "GMI_CPU1_G0_CPU0_G2_TX_DP<5>")
	)
	(segment
		(start 103.60406 -235.251752)
		(end 103.605076 -235.251244)
		(width 0.1143)
		(layer "In6.Cu")
		(net "GMI_CPU1_G0_CPU0_G2_TX_DP<5>")
	)
	(segment
		(start 103.636318 -234.295696)
		(end 103.635556 -234.295188)
		(width 0.1143)
		(layer "In6.Cu")
		(net "GMI_CPU1_G0_CPU0_G2_TX_DP<5>")
	)
	(segment
		(start 302.904144 -179.774088)
		(end 306.824888 -179.774088)
		(width 0.14224)
		(layer "In6.Cu")
		(net "GMI_CPU1_G0_CPU0_G2_TX_DP<5>")
	)
	(segment
		(start 367.891822 -227.151692)
		(end 367.892584 -227.1522)
		(width 0.1143)
		(layer "In6.Cu")
		(net "GMI_CPU1_G0_CPU0_G2_TX_DP<5>")
	)
	(segment
		(start 367.893854 -227.795582)
		(end 367.892584 -227.796344)
		(width 0.1143)
		(layer "In6.Cu")
		(net "GMI_CPU1_G0_CPU0_G2_TX_DP<5>")
	)
	(segment
		(start 366.950244 -225.530918)
		(end 366.951768 -225.53168)
		(width 0.1143)
		(layer "In6.Cu")
		(net "GMI_CPU1_G0_CPU0_G2_TX_DP<5>")
	)
	(segment
		(start 119.42318 -205.758542)
		(end 119.755412 -205.503526)
		(width 0.14224)
		(layer "In6.Cu")
		(net "GMI_CPU1_G0_CPU0_G2_TX_DP<5>")
	)
	(segment
		(start 103.57231 -230.410258)
		(end 103.60406 -230.39197)
		(width 0.1143)
		(layer "In6.Cu")
		(net "GMI_CPU1_G0_CPU0_G2_TX_DP<5>")
	)
	(segment
		(start 107.263946 -218.44635)
		(end 107.193842 -218.276932)
		(width 0.14224)
		(layer "In6.Cu")
		(net "GMI_CPU1_G0_CPU0_G2_TX_DP<5>")
	)
	(segment
		(start 367.892584 -232.656126)
		(end 367.891822 -232.656634)
		(width 0.1143)
		(layer "In6.Cu")
		(net "GMI_CPU1_G0_CPU0_G2_TX_DP<5>")
	)
	(segment
		(start 103.603298 -228.772466)
		(end 103.60406 -228.771958)
		(width 0.1143)
		(layer "In6.Cu")
		(net "GMI_CPU1_G0_CPU0_G2_TX_DP<5>")
	)
	(segment
		(start 368.848132 -236.880908)
		(end 368.861594 -236.888782)
		(width 0.1143)
		(layer "In6.Cu")
		(net "GMI_CPU1_G0_CPU0_G2_TX_DP<5>")
	)
	(segment
		(start 115.06962 -209.099404)
		(end 115.401852 -208.844388)
		(width 0.14224)
		(layer "In6.Cu")
		(net "GMI_CPU1_G0_CPU0_G2_TX_DP<5>")
	)
	(segment
		(start 103.603298 -232.012236)
		(end 103.60406 -232.011728)
		(width 0.1143)
		(layer "In6.Cu")
		(net "GMI_CPU1_G0_CPU0_G2_TX_DP<5>")
	)
	(segment
		(start 367.855246 -230.37038)
		(end 367.891822 -230.391716)
		(width 0.1143)
		(layer "In6.Cu")
		(net "GMI_CPU1_G0_CPU0_G2_TX_DP<5>")
	)
	(segment
		(start 102.666546 -236.87024)
		(end 102.703122 -236.848904)
		(width 0.1143)
		(layer "In6.Cu")
		(net "GMI_CPU1_G0_CPU0_G2_TX_DP<5>")
	)
	(segment
		(start 118.552468 -206.426816)
		(end 118.8847 -206.1718)
		(width 0.14224)
		(layer "In6.Cu")
		(net "GMI_CPU1_G0_CPU0_G2_TX_DP<5>")
	)
	(segment
		(start 370.243862 -242.542822)
		(end 370.27358 -242.55984)
		(width 0.1143)
		(layer "In6.Cu")
		(net "GMI_CPU1_G0_CPU0_G2_TX_DP<5>")
	)
	(segment
		(start 367.889282 -235.249974)
		(end 367.890806 -235.25099)
		(width 0.1143)
		(layer "In6.Cu")
		(net "GMI_CPU1_G0_CPU0_G2_TX_DP<5>")
	)
	(segment
		(start 103.602028 -234.27563)
		(end 103.57231 -234.258612)
		(width 0.1143)
		(layer "In6.Cu")
		(net "GMI_CPU1_G0_CPU0_G2_TX_DP<5>")
	)
	(segment
		(start 105.014014 -224.721928)
		(end 105.01503 -224.72142)
		(width 0.1143)
		(layer "In6.Cu")
		(net "GMI_CPU1_G0_CPU0_G2_TX_DP<5>")
	)
	(segment
		(start 120.270016 -205.272132)
		(end 120.293892 -205.090522)
		(width 0.14224)
		(layer "In6.Cu")
		(net "GMI_CPU1_G0_CPU0_G2_TX_DP<5>")
	)
	(segment
		(start 103.605076 -235.251244)
		(end 103.6066 -235.250228)
		(width 0.1143)
		(layer "In6.Cu")
		(net "GMI_CPU1_G0_CPU0_G2_TX_DP<5>")
	)
	(segment
		(start 103.60406 -228.771958)
		(end 103.605076 -228.77145)
		(width 0.1143)
		(layer "In6.Cu")
		(net "GMI_CPU1_G0_CPU0_G2_TX_DP<5>")
	)
	(segment
		(start 318.01943 -185.725816)
		(end 319.892172 -187.281312)
		(width 0.14224)
		(layer "In6.Cu")
		(net "GMI_CPU1_G0_CPU0_G2_TX_DP<5>")
	)
	(segment
		(start 367.892584 -227.1522)
		(end 367.893854 -227.152962)
		(width 0.1143)
		(layer "In6.Cu")
		(net "GMI_CPU1_G0_CPU0_G2_TX_DP<5>")
	)
	(segment
		(start 103.643176 -234.29976)
		(end 103.636318 -234.295696)
		(width 0.1143)
		(layer "In6.Cu")
		(net "GMI_CPU1_G0_CPU0_G2_TX_DP<5>")
	)
	(segment
		(start 103.643176 -232.679748)
		(end 103.605076 -232.657396)
		(width 0.1143)
		(layer "In6.Cu")
		(net "GMI_CPU1_G0_CPU0_G2_TX_DP<5>")
	)
	(segment
		(start 369.262406 -237.65891)
		(end 369.333526 -237.699804)
		(width 0.1143)
		(layer "In6.Cu")
		(net "GMI_CPU1_G0_CPU0_G2_TX_DP<5>")
	)
	(segment
		(start 369.301776 -238.326676)
		(end 369.265454 -238.347758)
		(width 0.1143)
		(layer "In6.Cu")
		(net "GMI_CPU1_G0_CPU0_G2_TX_DP<5>")
	)
	(segment
		(start 367.890806 -232.657142)
		(end 367.852706 -232.679494)
		(width 0.1143)
		(layer "In6.Cu")
		(net "GMI_CPU1_G0_CPU0_G2_TX_DP<5>")
	)
	(segment
		(start 115.940332 -208.431384)
		(end 116.272564 -208.176368)
		(width 0.14224)
		(layer "In6.Cu")
		(net "GMI_CPU1_G0_CPU0_G2_TX_DP<5>")
	)
	(segment
		(start 309.00497 -180.372512)
		(end 318.01943 -185.725816)
		(width 0.14224)
		(layer "In6.Cu")
		(net "GMI_CPU1_G0_CPU0_G2_TX_DP<5>")
	)
	(segment
		(start 367.893854 -227.152962)
		(end 367.923572 -227.16998)
		(width 0.1143)
		(layer "In6.Cu")
		(net "GMI_CPU1_G0_CPU0_G2_TX_DP<5>")
	)
	(segment
		(start 367.923572 -234.258358)
		(end 367.893854 -234.275376)
		(width 0.1143)
		(layer "In6.Cu")
		(net "GMI_CPU1_G0_CPU0_G2_TX_DP<5>")
	)
	(segment
		(start 367.891822 -232.011474)
		(end 367.892584 -232.011982)
		(width 0.1143)
		(layer "In6.Cu")
		(net "GMI_CPU1_G0_CPU0_G2_TX_DP<5>")
	)
	(segment
		(start 367.893854 -233.632756)
		(end 367.923572 -233.649774)
		(width 0.1143)
		(layer "In6.Cu")
		(net "GMI_CPU1_G0_CPU0_G2_TX_DP<5>")
	)
	(segment
		(start 365.971074 -223.888046)
		(end 366.01146 -223.911668)
		(width 0.1143)
		(layer "In6.Cu")
		(net "GMI_CPU1_G0_CPU0_G2_TX_DP<5>")
	)
	(segment
		(start 102.162356 -237.700058)
		(end 102.233476 -237.659164)
		(width 0.1143)
		(layer "In6.Cu")
		(net "GMI_CPU1_G0_CPU0_G2_TX_DP<5>")
	)
	(segment
		(start 367.889282 -227.798376)
		(end 367.852706 -227.819712)
		(width 0.1143)
		(layer "In6.Cu")
		(net "GMI_CPU1_G0_CPU0_G2_TX_DP<5>")
	)
	(segment
		(start 103.603298 -234.276392)
		(end 103.602028 -234.27563)
		(width 0.1143)
		(layer "In6.Cu")
		(net "GMI_CPU1_G0_CPU0_G2_TX_DP<5>")
	)
	(segment
		(start 102.665022 -236.871256)
		(end 102.666546 -236.87024)
		(width 0.1143)
		(layer "In6.Cu")
		(net "GMI_CPU1_G0_CPU0_G2_TX_DP<5>")
	)
	(segment
		(start 106.447082 -222.27921)
		(end 106.452924 -222.276416)
		(width 0.1143)
		(layer "In6.Cu")
		(net "GMI_CPU1_G0_CPU0_G2_TX_DP<5>")
	)
	(segment
		(start 104.512364 -225.550222)
		(end 104.543352 -225.532442)
		(width 0.1143)
		(layer "In6.Cu")
		(net "GMI_CPU1_G0_CPU0_G2_TX_DP<5>")
	)
	(segment
		(start 165.412166 -179.53101)
		(end 167.476932 -178.984148)
		(width 0.14224)
		(layer "In6.Cu")
		(net "GMI_CPU1_G0_CPU0_G2_TX_DP<5>")
	)
	(segment
		(start 104.04348 -226.35972)
		(end 104.07396 -226.34194)
		(width 0.1143)
		(layer "In6.Cu")
		(net "GMI_CPU1_G0_CPU0_G2_TX_DP<5>")
	)
	(segment
		(start 103.57231 -232.030016)
		(end 103.603298 -232.012236)
		(width 0.1143)
		(layer "In6.Cu")
		(net "GMI_CPU1_G0_CPU0_G2_TX_DP<5>")
	)
	(segment
		(start 369.732814 -241.708686)
		(end 369.80241 -241.749326)
		(width 0.1143)
		(layer "In6.Cu")
		(net "GMI_CPU1_G0_CPU0_G2_TX_DP<5>")
	)
	(segment
		(start 368.83086 -236.871002)
		(end 368.831876 -236.87151)
		(width 0.1143)
		(layer "In6.Cu")
		(net "GMI_CPU1_G0_CPU0_G2_TX_DP<5>")
	)
	(segment
		(start 367.92535 -231.017064)
		(end 367.852706 -231.059482)
		(width 0.1143)
		(layer "In6.Cu")
		(net "GMI_CPU1_G0_CPU0_G2_TX_DP<5>")
	)
	(segment
		(start 103.635556 -227.815394)
		(end 103.60406 -227.797106)
		(width 0.1143)
		(layer "In6.Cu")
		(net "GMI_CPU1_G0_CPU0_G2_TX_DP<5>")
	)
	(segment
		(start 103.605076 -233.631232)
		(end 103.6066 -233.630216)
		(width 0.1143)
		(layer "In6.Cu")
		(net "GMI_CPU1_G0_CPU0_G2_TX_DP<5>")
	)
	(segment
		(start 106.270044 -222.592646)
		(end 106.270044 -222.591122)
		(width 0.1143)
		(layer "In6.Cu")
		(net "GMI_CPU1_G0_CPU0_G2_TX_DP<5>")
	)
	(segment
		(start 167.476932 -178.984148)
		(end 302.904144 -179.774088)
		(width 0.14224)
		(layer "In6.Cu")
		(net "GMI_CPU1_G0_CPU0_G2_TX_DP<5>")
	)
	(segment
		(start 367.923572 -227.778564)
		(end 367.893854 -227.795582)
		(width 0.1143)
		(layer "In6.Cu")
		(net "GMI_CPU1_G0_CPU0_G2_TX_DP<5>")
	)
	(segment
		(start 103.605076 -227.151438)
		(end 103.6066 -227.150422)
		(width 0.1143)
		(layer "In6.Cu")
		(net "GMI_CPU1_G0_CPU0_G2_TX_DP<5>")
	)
	(segment
		(start 367.891822 -230.391716)
		(end 367.923572 -230.410004)
		(width 0.1143)
		(layer "In6.Cu")
		(net "GMI_CPU1_G0_CPU0_G2_TX_DP<5>")
	)
	(segment
		(start 101.723952 -241.7318)
		(end 101.763068 -241.70894)
		(width 0.1143)
		(layer "In6.Cu")
		(net "GMI_CPU1_G0_CPU0_G2_TX_DP<5>")
	)
	(segment
		(start 368.79276 -236.84865)
		(end 368.829336 -236.869986)
		(width 0.1143)
		(layer "In6.Cu")
		(net "GMI_CPU1_G0_CPU0_G2_TX_DP<5>")
	)
	(segment
		(start 368.834924 -236.873288)
		(end 368.848132 -236.880908)
		(width 0.1143)
		(layer "In6.Cu")
		(net "GMI_CPU1_G0_CPU0_G2_TX_DP<5>")
	)
	(segment
		(start 103.603298 -227.152454)
		(end 103.60406 -227.151946)
		(width 0.1143)
		(layer "In6.Cu")
		(net "GMI_CPU1_G0_CPU0_G2_TX_DP<5>")
	)
	(segment
		(start 366.48263 -224.722182)
		(end 366.512602 -224.739454)
		(width 0.1143)
		(layer "In6.Cu")
		(net "GMI_CPU1_G0_CPU0_G2_TX_DP<5>")
	)
	(segment
		(start 107.523534 -217.819732)
		(end 107.683808 -217.432382)
		(width 0.14224)
		(layer "In6.Cu")
		(net "GMI_CPU1_G0_CPU0_G2_TX_DP<5>")
	)
	(segment
		(start 107.103418 -218.8337)
		(end 107.263946 -218.44635)
		(width 0.14224)
		(layer "In6.Cu")
		(net "GMI_CPU1_G0_CPU0_G2_TX_DP<5>")
	)
	(segment
		(start 102.660958 -236.873542)
		(end 102.66172 -236.873034)
		(width 0.1143)
		(layer "In6.Cu")
		(net "GMI_CPU1_G0_CPU0_G2_TX_DP<5>")
	)
	(segment
		(start 103.603298 -227.796598)
		(end 103.602028 -227.795836)
		(width 0.1143)
		(layer "In6.Cu")
		(net "GMI_CPU1_G0_CPU0_G2_TX_DP<5>")
	)
	(segment
		(start 103.603298 -232.65638)
		(end 103.602028 -232.655618)
		(width 0.1143)
		(layer "In6.Cu")
		(net "GMI_CPU1_G0_CPU0_G2_TX_DP<5>")
	)
	(segment
		(start 102.664006 -236.871764)
		(end 102.665022 -236.871256)
		(width 0.1143)
		(layer "In6.Cu")
		(net "GMI_CPU1_G0_CPU0_G2_TX_DP<5>")
	)
	(segment
		(start 370.242592 -242.54206)
		(end 370.243862 -242.542822)
		(width 0.1143)
		(layer "In6.Cu")
		(net "GMI_CPU1_G0_CPU0_G2_TX_DP<5>")
	)
	(segment
		(start 368.831876 -236.87151)
		(end 368.832638 -236.872018)
		(width 0.1143)
		(layer "In6.Cu")
		(net "GMI_CPU1_G0_CPU0_G2_TX_DP<5>")
	)
	(segment
		(start 367.890806 -232.010966)
		(end 367.891822 -232.011474)
		(width 0.1143)
		(layer "In6.Cu")
		(net "GMI_CPU1_G0_CPU0_G2_TX_DP<5>")
	)
	(segment
		(start 367.891822 -232.656634)
		(end 367.890806 -232.657142)
		(width 0.1143)
		(layer "In6.Cu")
		(net "GMI_CPU1_G0_CPU0_G2_TX_DP<5>")
	)
	(segment
		(start 103.60406 -230.39197)
		(end 103.640636 -230.370634)
		(width 0.1143)
		(layer "In6.Cu")
		(net "GMI_CPU1_G0_CPU0_G2_TX_DP<5>")
	)
	(segment
		(start 370.24183 -242.541552)
		(end 370.242592 -242.54206)
		(width 0.1143)
		(layer "In6.Cu")
		(net "GMI_CPU1_G0_CPU0_G2_TX_DP<5>")
	)
	(segment
		(start 370.240814 -242.541044)
		(end 370.24183 -242.541552)
		(width 0.1143)
		(layer "In6.Cu")
		(net "GMI_CPU1_G0_CPU0_G2_TX_DP<5>")
	)
	(segment
		(start 118.014242 -206.83982)
		(end 118.195852 -206.863696)
		(width 0.14224)
		(layer "In6.Cu")
		(net "GMI_CPU1_G0_CPU0_G2_TX_DP<5>")
	)
	(segment
		(start 367.382806 -226.318826)
		(end 367.452402 -226.359466)
		(width 0.1143)
		(layer "In6.Cu")
		(net "GMI_CPU1_G0_CPU0_G2_TX_DP<5>")
	)
	(segment
		(start 106.706924 -221.24797)
		(end 106.705908 -221.246954)
		(width 0.1143)
		(layer "In6.Cu")
		(net "GMI_CPU1_G0_CPU0_G2_TX_DP<5>")
	)
	(segment
		(start 363.953044 -217.211656)
		(end 364.744762 -219.122752)
		(width 0.14224)
		(layer "In6.Cu")
		(net "GMI_CPU1_G0_CPU0_G2_TX_DP<5>")
	)
	(segment
		(start 367.892584 -234.276138)
		(end 367.891822 -234.276646)
		(width 0.1143)
		(layer "In6.Cu")
		(net "GMI_CPU1_G0_CPU0_G2_TX_DP<5>")
	)
	(segment
		(start 101.255068 -242.541298)
		(end 101.256592 -242.540282)
		(width 0.1143)
		(layer "In6.Cu")
		(net "GMI_CPU1_G0_CPU0_G2_TX_DP<5>")
	)
	(segment
		(start 364.790482 -221.13875)
		(end 364.790482 -221.2467)
		(width 0.1143)
		(layer "In6.Cu")
		(net "GMI_CPU1_G0_CPU0_G2_TX_DP<5>")
	)
	(segment
		(start 103.57231 -235.27004)
		(end 103.60406 -235.251752)
		(width 0.1143)
		(layer "In6.Cu")
		(net "GMI_CPU1_G0_CPU0_G2_TX_DP<5>")
	)
	(segment
		(start 115.401852 -208.844388)
		(end 115.583716 -208.868264)
		(width 0.14224)
		(layer "In6.Cu")
		(net "GMI_CPU1_G0_CPU0_G2_TX_DP<5>")
	)
	(segment
		(start 103.605076 -228.77145)
		(end 103.6066 -228.770434)
		(width 0.1143)
		(layer "In6.Cu")
		(net "GMI_CPU1_G0_CPU0_G2_TX_DP<5>")
	)
	(segment
		(start 103.60406 -227.797106)
		(end 103.603298 -227.796598)
		(width 0.1143)
		(layer "In6.Cu")
		(net "GMI_CPU1_G0_CPU0_G2_TX_DP<5>")
	)
	(segment
		(start 370.23929 -242.540028)
		(end 370.240814 -242.541044)
		(width 0.1143)
		(layer "In6.Cu")
		(net "GMI_CPU1_G0_CPU0_G2_TX_DP<5>")
	)
	(segment
		(start 104.07396 -226.34194)
		(end 104.113076 -226.31908)
		(width 0.1143)
		(layer "In6.Cu")
		(net "GMI_CPU1_G0_CPU0_G2_TX_DP<5>")
	)
	(segment
		(start 102.194106 -238.32693)
		(end 102.162356 -238.308642)
		(width 0.1143)
		(layer "In6.Cu")
		(net "GMI_CPU1_G0_CPU0_G2_TX_DP<5>")
	)
	(segment
		(start 367.889282 -228.77018)
		(end 367.890806 -228.771196)
		(width 0.1143)
		(layer "In6.Cu")
		(net "GMI_CPU1_G0_CPU0_G2_TX_DP<5>")
	)
	(segment
		(start 103.57231 -233.650028)
		(end 103.603298 -233.632248)
		(width 0.1143)
		(layer "In6.Cu")
		(net "GMI_CPU1_G0_CPU0_G2_TX_DP<5>")
	)
	(segment
		(start 366.95253 -225.532188)
		(end 366.9538 -225.53295)
		(width 0.1143)
		(layer "In6.Cu")
		(net "GMI_CPU1_G0_CPU0_G2_TX_DP<5>")
	)
	(segment
		(start 364.744762 -221.09303)
		(end 364.790482 -221.13875)
		(width 0.1143)
		(layer "In6.Cu")
		(net "GMI_CPU1_G0_CPU0_G2_TX_DP<5>")
	)
	(segment
		(start 106.705908 -221.139004)
		(end 106.751628 -221.093284)
		(width 0.1143)
		(layer "In6.Cu")
		(net "GMI_CPU1_G0_CPU0_G2_TX_DP<5>")
	)
	(segment
		(start 116.787168 -207.944974)
		(end 116.811044 -207.76311)
		(width 0.14224)
		(layer "In6.Cu")
		(net "GMI_CPU1_G0_CPU0_G2_TX_DP<5>")
	)
	(segment
		(start 369.019582 -237.19409)
		(end 369.019582 -237.328202)
		(width 0.1143)
		(layer "In6.Cu")
		(net "GMI_CPU1_G0_CPU0_G2_TX_DP<5>")
	)
	(segment
		(start 369.301776 -240.92154)
		(end 369.333526 -240.939828)
		(width 0.1143)
		(layer "In6.Cu")
		(net "GMI_CPU1_G0_CPU0_G2_TX_DP<5>")
	)
	(segment
		(start 103.643176 -229.439724)
		(end 103.60406 -229.416864)
		(width 0.1143)
		(layer "In6.Cu")
		(net "GMI_CPU1_G0_CPU0_G2_TX_DP<5>")
	)
	(segment
		(start 101.440996 -242.864386)
		(end 101.143054 -242.864386)
		(width 0.1143)
		(layer "In6.Cu")
		(net "GMI_CPU1_G0_CPU0_G2_TX_DP<5>")
	)
	(segment
		(start 365.071914 -222.291656)
		(end 365.102394 -222.309436)
		(width 0.1143)
		(layer "In6.Cu")
		(net "GMI_CPU1_G0_CPU0_G2_TX_DP<5>")
	)
	(segment
		(start 103.643176 -231.059736)
		(end 103.60406 -231.036876)
		(width 0.1143)
		(layer "In6.Cu")
		(net "GMI_CPU1_G0_CPU0_G2_TX_DP<5>")
	)
	(segment
		(start 103.103426 -236.079538)
		(end 103.133906 -236.061758)
		(width 0.1143)
		(layer "In6.Cu")
		(net "GMI_CPU1_G0_CPU0_G2_TX_DP<5>")
	)
	(segment
		(start 367.892584 -232.011982)
		(end 367.893854 -232.012744)
		(width 0.1143)
		(layer "In6.Cu")
		(net "GMI_CPU1_G0_CPU0_G2_TX_DP<5>")
	)
	(segment
		(start 366.951768 -225.53168)
		(end 366.95253 -225.532188)
		(width 0.1143)
		(layer "In6.Cu")
		(net "GMI_CPU1_G0_CPU0_G2_TX_DP<5>")
	)
	(segment
		(start 106.934 -218.903804)
		(end 107.103418 -218.8337)
		(width 0.14224)
		(layer "In6.Cu")
		(net "GMI_CPU1_G0_CPU0_G2_TX_DP<5>")
	)
	(segment
		(start 367.892584 -227.796344)
		(end 367.891822 -227.796852)
		(width 0.1143)
		(layer "In6.Cu")
		(net "GMI_CPU1_G0_CPU0_G2_TX_DP<5>")
	)
	(segment
		(start 102.663244 -236.872272)
		(end 102.664006 -236.871764)
		(width 0.1143)
		(layer "In6.Cu")
		(net "GMI_CPU1_G0_CPU0_G2_TX_DP<5>")
	)
	(segment
		(start 103.635556 -234.295188)
		(end 103.60406 -234.2769)
		(width 0.1143)
		(layer "In6.Cu")
		(net "GMI_CPU1_G0_CPU0_G2_TX_DP<5>")
	)
	(segment
		(start 367.889282 -233.629962)
		(end 367.890806 -233.630978)
		(width 0.1143)
		(layer "In6.Cu")
		(net "GMI_CPU1_G0_CPU0_G2_TX_DP<5>")
	)
	(segment
		(start 367.890806 -227.79736)
		(end 367.889282 -227.798376)
		(width 0.1143)
		(layer "In6.Cu")
		(net "GMI_CPU1_G0_CPU0_G2_TX_DP<5>")
	)
	(segment
		(start 103.60406 -229.416864)
		(end 103.570532 -229.397306)
		(width 0.1143)
		(layer "In6.Cu")
		(net "GMI_CPU1_G0_CPU0_G2_TX_DP<5>")
	)
	(segment
		(start 103.6066 -235.250228)
		(end 103.643176 -235.228892)
		(width 0.1143)
		(layer "In6.Cu")
		(net "GMI_CPU1_G0_CPU0_G2_TX_DP<5>")
	)
	(segment
		(start 102.162356 -240.940082)
		(end 102.194106 -240.921794)
		(width 0.1143)
		(layer "In6.Cu")
		(net "GMI_CPU1_G0_CPU0_G2_TX_DP<5>")
	)
	(segment
		(start 370.422678 -242.794282)
		(end 370.352828 -242.864132)
		(width 0.1143)
		(layer "In6.Cu")
		(net "GMI_CPU1_G0_CPU0_G2_TX_DP<5>")
	)
	(segment
		(start 105.01503 -224.72142)
		(end 105.016554 -224.720404)
		(width 0.1143)
		(layer "In6.Cu")
		(net "GMI_CPU1_G0_CPU0_G2_TX_DP<5>")
	)
	(segment
		(start 106.706924 -221.804484)
		(end 106.706924 -221.24797)
		(width 0.1143)
		(layer "In6.Cu")
		(net "GMI_CPU1_G0_CPU0_G2_TX_DP<5>")
	)
	(segment
		(start 101.693472 -241.74958)
		(end 101.723952 -241.7318)
		(width 0.1143)
		(layer "In6.Cu")
		(net "GMI_CPU1_G0_CPU0_G2_TX_DP<5>")
	)
	(segment
		(start 103.57231 -227.170234)
		(end 103.603298 -227.152454)
		(width 0.1143)
		(layer "In6.Cu")
		(net "GMI_CPU1_G0_CPU0_G2_TX_DP<5>")
	)
	(segment
		(start 367.893854 -232.655364)
		(end 367.892584 -232.656126)
		(width 0.1143)
		(layer "In6.Cu")
		(net "GMI_CPU1_G0_CPU0_G2_TX_DP<5>")
	)
	(segment
		(start 103.643176 -227.819966)
		(end 103.636318 -227.815902)
		(width 0.1143)
		(layer "In6.Cu")
		(net "GMI_CPU1_G0_CPU0_G2_TX_DP<5>")
	)
	(segment
		(start 118.528592 -206.608426)
		(end 118.552468 -206.426816)
		(width 0.14224)
		(layer "In6.Cu")
		(net "GMI_CPU1_G0_CPU0_G2_TX_DP<5>")
	)
	(segment
		(start 117.143276 -207.508094)
		(end 117.32514 -207.53197)
		(width 0.14224)
		(layer "In6.Cu")
		(net "GMI_CPU1_G0_CPU0_G2_TX_DP<5>")
	)
	(segment
		(start 367.889282 -234.27817)
		(end 367.852706 -234.299506)
		(width 0.1143)
		(layer "In6.Cu")
		(net "GMI_CPU1_G0_CPU0_G2_TX_DP<5>")
	)
	(segment
		(start 103.602028 -232.655618)
		(end 103.57231 -232.6386)
		(width 0.1143)
		(layer "In6.Cu")
		(net "GMI_CPU1_G0_CPU0_G2_TX_DP<5>")
	)
	(segment
		(start 364.789466 -221.247716)
		(end 364.789466 -221.80423)
		(width 0.1143)
		(layer "In6.Cu")
		(net "GMI_CPU1_G0_CPU0_G2_TX_DP<5>")
	)
	(segment
		(start 107.683808 -217.432382)
		(end 107.613704 -217.262964)
		(width 0.14224)
		(layer "In6.Cu")
		(net "GMI_CPU1_G0_CPU0_G2_TX_DP<5>")
	)
	(segment
		(start 366.481868 -224.721674)
		(end 366.48263 -224.722182)
		(width 0.1143)
		(layer "In6.Cu")
		(net "GMI_CPU1_G0_CPU0_G2_TX_DP<5>")
	)
	(segment
		(start 319.892172 -187.281312)
		(end 355.362002 -209.573622)
		(width 0.14224)
		(layer "In6.Cu")
		(net "GMI_CPU1_G0_CPU0_G2_TX_DP<5>")
	)
	(segment
		(start 367.892584 -233.631994)
		(end 367.893854 -233.632756)
		(width 0.1143)
		(layer "In6.Cu")
		(net "GMI_CPU1_G0_CPU0_G2_TX_DP<5>")
	)
	(segment
		(start 367.890806 -234.277154)
		(end 367.889282 -234.27817)
		(width 0.1143)
		(layer "In6.Cu")
		(net "GMI_CPU1_G0_CPU0_G2_TX_DP<5>")
	)
	(segment
		(start 366.01146 -223.911668)
		(end 366.044226 -223.930718)
		(width 0.1143)
		(layer "In6.Cu")
		(net "GMI_CPU1_G0_CPU0_G2_TX_DP<5>")
	)
	(segment
		(start 119.937276 -205.527402)
		(end 120.270016 -205.272132)
		(width 0.14224)
		(layer "In6.Cu")
		(net "GMI_CPU1_G0_CPU0_G2_TX_DP<5>")
	)
	(segment
		(start 369.145566 -237.574582)
		(end 369.262406 -237.65891)
		(width 0.1143)
		(layer "In6.Cu")
		(net "GMI_CPU1_G0_CPU0_G2_TX_DP<5>")
	)
	(segment
		(start 365.502698 -223.078802)
		(end 365.541814 -223.101662)
		(width 0.1143)
		(layer "In6.Cu")
		(net "GMI_CPU1_G0_CPU0_G2_TX_DP<5>")
	)
	(segment
		(start 367.890806 -235.25099)
		(end 367.891822 -235.251498)
		(width 0.1143)
		(layer "In6.Cu")
		(net "GMI_CPU1_G0_CPU0_G2_TX_DP<5>")
	)
	(segment
		(start 103.6066 -227.150422)
		(end 103.643176 -227.129086)
		(width 0.1143)
		(layer "In6.Cu")
		(net "GMI_CPU1_G0_CPU0_G2_TX_DP<5>")
	)
	(segment
		(start 367.892584 -228.772212)
		(end 367.893854 -228.772974)
		(width 0.1143)
		(layer "In6.Cu")
		(net "GMI_CPU1_G0_CPU0_G2_TX_DP<5>")
	)
	(segment
		(start 364.790482 -221.2467)
		(end 364.789466 -221.247716)
		(width 0.1143)
		(layer "In6.Cu")
		(net "GMI_CPU1_G0_CPU0_G2_TX_DP<5>")
	)
	(segment
		(start 119.755412 -205.503526)
		(end 119.937276 -205.527402)
		(width 0.14224)
		(layer "In6.Cu")
		(net "GMI_CPU1_G0_CPU0_G2_TX_DP<5>")
	)
	(segment
		(start 367.891822 -234.276646)
		(end 367.890806 -234.277154)
		(width 0.1143)
		(layer "In6.Cu")
		(net "GMI_CPU1_G0_CPU0_G2_TX_DP<5>")
	)
	(segment
		(start 106.934 -218.904058)
		(end 106.934 -218.903804)
		(width 0.14224)
		(layer "In6.Cu")
		(net "GMI_CPU1_G0_CPU0_G2_TX_DP<5>")
	)
	(segment
		(start 367.852706 -227.128832)
		(end 367.889282 -227.150168)
		(width 0.1143)
		(layer "In6.Cu")
		(net "GMI_CPU1_G0_CPU0_G2_TX_DP<5>")
	)
	(segment
		(start 103.603298 -233.632248)
		(end 103.60406 -233.63174)
		(width 0.1143)
		(layer "In6.Cu")
		(net "GMI_CPU1_G0_CPU0_G2_TX_DP<5>")
	)
	(segment
		(start 108.114084 -216.054686)
		(end 115.06962 -209.099404)
		(width 0.14224)
		(layer "In6.Cu")
		(net "GMI_CPU1_G0_CPU0_G2_TX_DP<5>")
	)
	(segment
		(start 367.893854 -234.275376)
		(end 367.892584 -234.276138)
		(width 0.1143)
		(layer "In6.Cu")
		(net "GMI_CPU1_G0_CPU0_G2_TX_DP<5>")
	)
	(segment
		(start 369.265454 -239.280446)
		(end 369.301776 -239.301528)
		(width 0.1143)
		(layer "In6.Cu")
		(net "GMI_CPU1_G0_CPU0_G2_TX_DP<5>")
	)
	(segment
		(start 101.254052 -242.541806)
		(end 101.255068 -242.541298)
		(width 0.1143)
		(layer "In6.Cu")
		(net "GMI_CPU1_G0_CPU0_G2_TX_DP<5>")
	)
	(segment
		(start 101.143054 -242.864386)
		(end 101.073204 -242.794536)
		(width 0.1143)
		(layer "In6.Cu")
		(net "GMI_CPU1_G0_CPU0_G2_TX_DP<5>")
	)
	(segment
		(start 102.4763 -237.328456)
		(end 102.4763 -237.194344)
		(width 0.1143)
		(layer "In6.Cu")
		(net "GMI_CPU1_G0_CPU0_G2_TX_DP<5>")
	)
	(segment
		(start 103.602028 -227.795836)
		(end 103.57231 -227.778818)
		(width 0.1143)
		(layer "In6.Cu")
		(net "GMI_CPU1_G0_CPU0_G2_TX_DP<5>")
	)
	(segment
		(start 367.890806 -228.771196)
		(end 367.891822 -228.771704)
		(width 0.1143)
		(layer "In6.Cu")
		(net "GMI_CPU1_G0_CPU0_G2_TX_DP<5>")
	)
	(segment
		(start 119.399304 -205.940406)
		(end 119.42318 -205.758542)
		(width 0.14224)
		(layer "In6.Cu")
		(net "GMI_CPU1_G0_CPU0_G2_TX_DP<5>")
	)
	(segment
		(start 365.541814 -223.101662)
		(end 365.571024 -223.11868)
		(width 0.1143)
		(layer "In6.Cu")
		(net "GMI_CPU1_G0_CPU0_G2_TX_DP<5>")
	)
	(segment
		(start 367.891822 -228.771704)
		(end 367.892584 -228.772212)
		(width 0.1143)
		(layer "In6.Cu")
		(net "GMI_CPU1_G0_CPU0_G2_TX_DP<5>")
	)
	(segment
		(start 101.25329 -242.542314)
		(end 101.254052 -242.541806)
		(width 0.1143)
		(layer "In6.Cu")
		(net "GMI_CPU1_G0_CPU0_G2_TX_DP<5>")
	)
	(segment
		(start 360.06913 -213.327742)
		(end 363.953044 -217.211656)
		(width 0.14224)
		(layer "In6.Cu")
		(net "GMI_CPU1_G0_CPU0_G2_TX_DP<5>")
	)
	(segment
		(start 357.715566 -211.450682)
		(end 357.71582 -211.450936)
		(width 0.14224)
		(layer "In6.Cu")
		(net "GMI_CPU1_G0_CPU0_G2_TX_DP<5>")
	)
	(segment
		(start 367.852706 -228.748844)
		(end 367.889282 -228.77018)
		(width 0.1143)
		(layer "In6.Cu")
		(net "GMI_CPU1_G0_CPU0_G2_TX_DP<5>")
	)
	(segment
		(start 103.57231 -228.790246)
		(end 103.603298 -228.772466)
		(width 0.1143)
		(layer "In6.Cu")
		(net "GMI_CPU1_G0_CPU0_G2_TX_DP<5>")
	)
	(segment
		(start 365.032798 -222.268796)
		(end 365.071914 -222.291656)
		(width 0.1143)
		(layer "In6.Cu")
		(net "GMI_CPU1_G0_CPU0_G2_TX_DP<5>")
	)
	(segment
		(start 102.230428 -239.968024)
		(end 102.194106 -239.946942)
		(width 0.1143)
		(layer "In6.Cu")
		(net "GMI_CPU1_G0_CPU0_G2_TX_DP<5>")
	)
	(segment
		(start 368.32286 -236.038644)
		(end 368.392456 -236.079284)
		(width 0.1143)
		(layer "In6.Cu")
		(net "GMI_CPU1_G0_CPU0_G2_TX_DP<5>")
	)
	(segment
		(start 118.8847 -206.1718)
		(end 119.066564 -206.195676)
		(width 0.14224)
		(layer "In6.Cu")
		(net "GMI_CPU1_G0_CPU0_G2_TX_DP<5>")
	)
	(segment
		(start 366.442752 -224.698814)
		(end 366.479328 -224.72015)
		(width 0.1143)
		(layer "In6.Cu")
		(net "GMI_CPU1_G0_CPU0_G2_TX_DP<5>")
	)
	(segment
		(start 103.6066 -228.770434)
		(end 103.643176 -228.749098)
		(width 0.1143)
		(layer "In6.Cu")
		(net "GMI_CPU1_G0_CPU0_G2_TX_DP<5>")
	)
	(segment
		(start 367.891822 -233.631486)
		(end 367.892584 -233.631994)
		(width 0.1143)
		(layer "In6.Cu")
		(net "GMI_CPU1_G0_CPU0_G2_TX_DP<5>")
	)
	(arc
		(start 366.88395 -225.48596)
		(mid 366.899482 -225.498555)
		(end 366.915446 -225.510598)
		(width 0.1143)
		(layer "In6.Cu")
		(net "GMI_CPU1_G0_CPU0_G2_TX_DP<5>")
	)
	(arc
		(start 369.489482 -241.24412)
		(mid 369.553997 -241.506339)
		(end 369.732814 -241.708686)
		(width 0.1143)
		(layer "In6.Cu")
		(net "GMI_CPU1_G0_CPU0_G2_TX_DP<5>")
	)
	(arc
		(start 102.4763 -237.194344)
		(mid 102.518179 -237.022475)
		(end 102.634288 -236.889036)
		(width 0.1143)
		(layer "In6.Cu")
		(net "GMI_CPU1_G0_CPU0_G2_TX_DP<5>")
	)
	(arc
		(start 103.886508 -226.66452)
		(mid 103.928057 -226.493098)
		(end 104.04348 -226.35972)
		(width 0.1143)
		(layer "In6.Cu")
		(net "GMI_CPU1_G0_CPU0_G2_TX_DP<5>")
	)
	(arc
		(start 105.767124 -223.424496)
		(mid 105.808878 -223.252553)
		(end 105.924858 -223.118934)
		(width 0.1143)
		(layer "In6.Cu")
		(net "GMI_CPU1_G0_CPU0_G2_TX_DP<5>")
	)
	(arc
		(start 365.571024 -223.11868)
		(mid 365.686977 -223.252313)
		(end 365.728758 -223.424242)
		(width 0.1143)
		(layer "In6.Cu")
		(net "GMI_CPU1_G0_CPU0_G2_TX_DP<5>")
	)
	(arc
		(start 366.19942 -224.234248)
		(mid 366.263935 -224.496467)
		(end 366.442752 -224.698814)
		(width 0.1143)
		(layer "In6.Cu")
		(net "GMI_CPU1_G0_CPU0_G2_TX_DP<5>")
	)
	(arc
		(start 369.333526 -237.699804)
		(mid 369.489454 -238.004096)
		(end 369.333526 -238.308388)
		(width 0.1143)
		(layer "In6.Cu")
		(net "GMI_CPU1_G0_CPU0_G2_TX_DP<5>")
	)
	(arc
		(start 101.763068 -241.70894)
		(mid 101.941881 -241.50659)
		(end 102.0064 -241.244374)
		(width 0.1143)
		(layer "In6.Cu")
		(net "GMI_CPU1_G0_CPU0_G2_TX_DP<5>")
	)
	(arc
		(start 365.102394 -222.309436)
		(mid 365.217821 -222.442812)
		(end 365.259366 -222.614236)
		(width 0.1143)
		(layer "In6.Cu")
		(net "GMI_CPU1_G0_CPU0_G2_TX_DP<5>")
	)
	(arc
		(start 369.333526 -240.939828)
		(mid 369.448202 -241.073162)
		(end 369.489482 -241.24412)
		(width 0.1143)
		(layer "In6.Cu")
		(net "GMI_CPU1_G0_CPU0_G2_TX_DP<5>")
	)
	(arc
		(start 366.669574 -225.033078)
		(mid 366.671953 -225.070581)
		(end 366.677448 -225.107754)
		(width 0.1143)
		(layer "In6.Cu")
		(net "GMI_CPU1_G0_CPU0_G2_TX_DP<5>")
	)
	(arc
		(start 105.05313 -224.699068)
		(mid 105.231943 -224.496718)
		(end 105.296462 -224.234502)
		(width 0.1143)
		(layer "In6.Cu")
		(net "GMI_CPU1_G0_CPU0_G2_TX_DP<5>")
	)
	(arc
		(start 105.98785 -223.082358)
		(mid 106.194483 -222.875259)
		(end 106.270044 -222.592646)
		(width 0.1143)
		(layer "In6.Cu")
		(net "GMI_CPU1_G0_CPU0_G2_TX_DP<5>")
	)
	(arc
		(start 369.25123 -239.977676)
		(mid 369.023847 -240.434114)
		(end 369.25123 -240.890552)
		(width 0.1143)
		(layer "In6.Cu")
		(net "GMI_CPU1_G0_CPU0_G2_TX_DP<5>")
	)
	(arc
		(start 104.356408 -225.854514)
		(mid 104.397663 -225.683543)
		(end 104.512364 -225.550222)
		(width 0.1143)
		(layer "In6.Cu")
		(net "GMI_CPU1_G0_CPU0_G2_TX_DP<5>")
	)
	(arc
		(start 102.162356 -239.928654)
		(mid 102.006428 -239.624362)
		(end 102.162356 -239.32007)
		(width 0.1143)
		(layer "In6.Cu")
		(net "GMI_CPU1_G0_CPU0_G2_TX_DP<5>")
	)
	(arc
		(start 103.57231 -227.778818)
		(mid 103.416382 -227.474526)
		(end 103.57231 -227.170234)
		(width 0.1143)
		(layer "In6.Cu")
		(net "GMI_CPU1_G0_CPU0_G2_TX_DP<5>")
	)
	(arc
		(start 102.244652 -239.270794)
		(mid 102.472035 -238.814356)
		(end 102.244652 -238.357918)
		(width 0.1143)
		(layer "In6.Cu")
		(net "GMI_CPU1_G0_CPU0_G2_TX_DP<5>")
	)
	(arc
		(start 367.923572 -232.029762)
		(mid 368.0795 -232.334054)
		(end 367.923572 -232.638346)
		(width 0.1143)
		(layer "In6.Cu")
		(net "GMI_CPU1_G0_CPU0_G2_TX_DP<5>")
	)
	(arc
		(start 103.886508 -229.90429)
		(mid 103.821993 -229.642071)
		(end 103.643176 -229.439724)
		(width 0.1143)
		(layer "In6.Cu")
		(net "GMI_CPU1_G0_CPU0_G2_TX_DP<5>")
	)
	(arc
		(start 369.80241 -241.749326)
		(mid 369.917837 -241.882702)
		(end 369.959382 -242.054126)
		(width 0.1143)
		(layer "In6.Cu")
		(net "GMI_CPU1_G0_CPU0_G2_TX_DP<5>")
	)
	(arc
		(start 103.173022 -236.038898)
		(mid 103.351835 -235.836548)
		(end 103.416354 -235.574332)
		(width 0.1143)
		(layer "In6.Cu")
		(net "GMI_CPU1_G0_CPU0_G2_TX_DP<5>")
	)
	(arc
		(start 103.57231 -234.258612)
		(mid 103.416382 -233.95432)
		(end 103.57231 -233.650028)
		(width 0.1143)
		(layer "In6.Cu")
		(net "GMI_CPU1_G0_CPU0_G2_TX_DP<5>")
	)
	(arc
		(start 104.826308 -225.033332)
		(mid 104.870372 -224.868109)
		(end 104.98328 -224.739708)
		(width 0.1143)
		(layer "In6.Cu")
		(net "GMI_CPU1_G0_CPU0_G2_TX_DP<5>")
	)
	(arc
		(start 368.392456 -236.079284)
		(mid 368.507883 -236.21266)
		(end 368.549428 -236.384084)
		(width 0.1143)
		(layer "In6.Cu")
		(net "GMI_CPU1_G0_CPU0_G2_TX_DP<5>")
	)
	(arc
		(start 369.25123 -238.357664)
		(mid 369.023847 -238.814102)
		(end 369.25123 -239.27054)
		(width 0.1143)
		(layer "In6.Cu")
		(net "GMI_CPU1_G0_CPU0_G2_TX_DP<5>")
	)
	(arc
		(start 103.57231 -232.6386)
		(mid 103.416382 -232.334308)
		(end 103.57231 -232.030016)
		(width 0.1143)
		(layer "In6.Cu")
		(net "GMI_CPU1_G0_CPU0_G2_TX_DP<5>")
	)
	(arc
		(start 367.923572 -227.16998)
		(mid 368.0795 -227.474272)
		(end 367.923572 -227.778564)
		(width 0.1143)
		(layer "In6.Cu")
		(net "GMI_CPU1_G0_CPU0_G2_TX_DP<5>")
	)
	(arc
		(start 366.983518 -225.549968)
		(mid 367.098194 -225.683302)
		(end 367.139474 -225.85426)
		(width 0.1143)
		(layer "In6.Cu")
		(net "GMI_CPU1_G0_CPU0_G2_TX_DP<5>")
	)
	(arc
		(start 103.643176 -227.129086)
		(mid 103.821989 -226.926736)
		(end 103.886508 -226.66452)
		(width 0.1143)
		(layer "In6.Cu")
		(net "GMI_CPU1_G0_CPU0_G2_TX_DP<5>")
	)
	(arc
		(start 103.643176 -228.749098)
		(mid 103.886503 -228.284532)
		(end 103.643176 -227.819966)
		(width 0.1143)
		(layer "In6.Cu")
		(net "GMI_CPU1_G0_CPU0_G2_TX_DP<5>")
	)
	(arc
		(start 103.570532 -231.017318)
		(mid 103.457125 -230.884429)
		(end 103.416354 -230.71455)
		(width 0.1143)
		(layer "In6.Cu")
		(net "GMI_CPU1_G0_CPU0_G2_TX_DP<5>")
	)
	(arc
		(start 102.244652 -239.97793)
		(mid 102.237578 -239.972923)
		(end 102.230428 -239.968024)
		(width 0.1143)
		(layer "In6.Cu")
		(net "GMI_CPU1_G0_CPU0_G2_TX_DP<5>")
	)
	(arc
		(start 367.852706 -234.299506)
		(mid 367.609379 -234.764072)
		(end 367.852706 -235.228638)
		(width 0.1143)
		(layer "In6.Cu")
		(net "GMI_CPU1_G0_CPU0_G2_TX_DP<5>")
	)
	(arc
		(start 103.416354 -235.574332)
		(mid 103.457609 -235.403361)
		(end 103.57231 -235.27004)
		(width 0.1143)
		(layer "In6.Cu")
		(net "GMI_CPU1_G0_CPU0_G2_TX_DP<5>")
	)
	(arc
		(start 102.244652 -240.890806)
		(mid 102.472035 -240.434368)
		(end 102.244652 -239.97793)
		(width 0.1143)
		(layer "In6.Cu")
		(net "GMI_CPU1_G0_CPU0_G2_TX_DP<5>")
	)
	(arc
		(start 105.524808 -223.8883)
		(mid 105.702873 -223.686123)
		(end 105.767124 -223.424496)
		(width 0.1143)
		(layer "In6.Cu")
		(net "GMI_CPU1_G0_CPU0_G2_TX_DP<5>")
	)
	(arc
		(start 366.677448 -225.107754)
		(mid 366.751566 -225.31276)
		(end 366.88395 -225.48596)
		(width 0.1143)
		(layer "In6.Cu")
		(net "GMI_CPU1_G0_CPU0_G2_TX_DP<5>")
	)
	(arc
		(start 105.296462 -224.234502)
		(mid 105.337512 -224.064052)
		(end 105.451656 -223.930972)
		(width 0.1143)
		(layer "In6.Cu")
		(net "GMI_CPU1_G0_CPU0_G2_TX_DP<5>")
	)
	(arc
		(start 367.923572 -235.269786)
		(mid 368.038248 -235.40312)
		(end 368.079528 -235.574078)
		(width 0.1143)
		(layer "In6.Cu")
		(net "GMI_CPU1_G0_CPU0_G2_TX_DP<5>")
	)
	(arc
		(start 103.643176 -231.988868)
		(mid 103.886503 -231.524302)
		(end 103.643176 -231.059736)
		(width 0.1143)
		(layer "In6.Cu")
		(net "GMI_CPU1_G0_CPU0_G2_TX_DP<5>")
	)
	(arc
		(start 101.5365 -242.05438)
		(mid 101.578049 -241.882958)
		(end 101.693472 -241.74958)
		(width 0.1143)
		(layer "In6.Cu")
		(net "GMI_CPU1_G0_CPU0_G2_TX_DP<5>")
	)
	(arc
		(start 368.861594 -236.888782)
		(mid 368.977641 -237.022253)
		(end 369.019582 -237.19409)
		(width 0.1143)
		(layer "In6.Cu")
		(net "GMI_CPU1_G0_CPU0_G2_TX_DP<5>")
	)
	(arc
		(start 104.818434 -225.108008)
		(mid 104.823913 -225.070833)
		(end 104.826308 -225.033332)
		(width 0.1143)
		(layer "In6.Cu")
		(net "GMI_CPU1_G0_CPU0_G2_TX_DP<5>")
	)
	(arc
		(start 369.019582 -237.328202)
		(mid 369.052841 -237.466602)
		(end 369.145566 -237.574582)
		(width 0.1143)
		(layer "In6.Cu")
		(net "GMI_CPU1_G0_CPU0_G2_TX_DP<5>")
	)
	(arc
		(start 102.244652 -238.357918)
		(mid 102.237578 -238.352911)
		(end 102.230428 -238.348012)
		(width 0.1143)
		(layer "In6.Cu")
		(net "GMI_CPU1_G0_CPU0_G2_TX_DP<5>")
	)
	(arc
		(start 369.959382 -242.054126)
		(mid 370.023897 -242.316345)
		(end 370.202714 -242.518692)
		(width 0.1143)
		(layer "In6.Cu")
		(net "GMI_CPU1_G0_CPU0_G2_TX_DP<5>")
	)
	(arc
		(start 367.852706 -227.819712)
		(mid 367.609379 -228.284278)
		(end 367.852706 -228.748844)
		(width 0.1143)
		(layer "In6.Cu")
		(net "GMI_CPU1_G0_CPU0_G2_TX_DP<5>")
	)
	(arc
		(start 366.512602 -224.739454)
		(mid 366.625449 -224.867887)
		(end 366.669574 -225.033078)
		(width 0.1143)
		(layer "In6.Cu")
		(net "GMI_CPU1_G0_CPU0_G2_TX_DP<5>")
	)
	(arc
		(start 367.923572 -230.410004)
		(mid 368.038248 -230.543338)
		(end 368.079528 -230.714296)
		(width 0.1143)
		(layer "In6.Cu")
		(net "GMI_CPU1_G0_CPU0_G2_TX_DP<5>")
	)
	(arc
		(start 369.333526 -239.319816)
		(mid 369.489454 -239.624108)
		(end 369.333526 -239.9284)
		(width 0.1143)
		(layer "In6.Cu")
		(net "GMI_CPU1_G0_CPU0_G2_TX_DP<5>")
	)
	(arc
		(start 101.073204 -242.794536)
		(mid 101.125253 -242.663017)
		(end 101.222302 -242.560094)
		(width 0.1143)
		(layer "In6.Cu")
		(net "GMI_CPU1_G0_CPU0_G2_TX_DP<5>")
	)
	(arc
		(start 104.611932 -225.486214)
		(mid 104.74435 -225.313033)
		(end 104.818434 -225.108008)
		(width 0.1143)
		(layer "In6.Cu")
		(net "GMI_CPU1_G0_CPU0_G2_TX_DP<5>")
	)
	(arc
		(start 367.609374 -226.664266)
		(mid 367.673889 -226.926485)
		(end 367.852706 -227.128832)
		(width 0.1143)
		(layer "In6.Cu")
		(net "GMI_CPU1_G0_CPU0_G2_TX_DP<5>")
	)
	(arc
		(start 367.923572 -233.649774)
		(mid 368.0795 -233.954066)
		(end 367.923572 -234.258358)
		(width 0.1143)
		(layer "In6.Cu")
		(net "GMI_CPU1_G0_CPU0_G2_TX_DP<5>")
	)
	(arc
		(start 368.079528 -229.094284)
		(mid 368.038766 -229.264168)
		(end 367.92535 -229.397052)
		(width 0.1143)
		(layer "In6.Cu")
		(net "GMI_CPU1_G0_CPU0_G2_TX_DP<5>")
	)
	(arc
		(start 103.570532 -229.397306)
		(mid 103.457125 -229.264417)
		(end 103.416354 -229.094538)
		(width 0.1143)
		(layer "In6.Cu")
		(net "GMI_CPU1_G0_CPU0_G2_TX_DP<5>")
	)
	(arc
		(start 365.259366 -222.614236)
		(mid 365.323881 -222.876455)
		(end 365.502698 -223.078802)
		(width 0.1143)
		(layer "In6.Cu")
		(net "GMI_CPU1_G0_CPU0_G2_TX_DP<5>")
	)
	(arc
		(start 368.549428 -236.384084)
		(mid 368.613943 -236.646303)
		(end 368.79276 -236.84865)
		(width 0.1143)
		(layer "In6.Cu")
		(net "GMI_CPU1_G0_CPU0_G2_TX_DP<5>")
	)
	(arc
		(start 103.643176 -233.60888)
		(mid 103.886503 -233.144314)
		(end 103.643176 -232.679748)
		(width 0.1143)
		(layer "In6.Cu")
		(net "GMI_CPU1_G0_CPU0_G2_TX_DP<5>")
	)
	(arc
		(start 104.113076 -226.31908)
		(mid 104.291889 -226.11673)
		(end 104.356408 -225.854514)
		(width 0.1143)
		(layer "In6.Cu")
		(net "GMI_CPU1_G0_CPU0_G2_TX_DP<5>")
	)
	(arc
		(start 102.162356 -238.308642)
		(mid 102.006428 -238.00435)
		(end 102.162356 -237.700058)
		(width 0.1143)
		(layer "In6.Cu")
		(net "GMI_CPU1_G0_CPU0_G2_TX_DP<5>")
	)
	(arc
		(start 366.044226 -223.930718)
		(mid 366.158379 -224.063794)
		(end 366.19942 -224.234248)
		(width 0.1143)
		(layer "In6.Cu")
		(net "GMI_CPU1_G0_CPU0_G2_TX_DP<5>")
	)
	(arc
		(start 369.265454 -238.347758)
		(mid 369.258304 -238.352656)
		(end 369.25123 -238.357664)
		(width 0.1143)
		(layer "In6.Cu")
		(net "GMI_CPU1_G0_CPU0_G2_TX_DP<5>")
	)
	(arc
		(start 106.452924 -222.276416)
		(mid 106.639465 -222.072492)
		(end 106.706924 -221.804484)
		(width 0.1143)
		(layer "In6.Cu")
		(net "GMI_CPU1_G0_CPU0_G2_TX_DP<5>")
	)
	(arc
		(start 367.852706 -231.059482)
		(mid 367.609379 -231.524048)
		(end 367.852706 -231.988614)
		(width 0.1143)
		(layer "In6.Cu")
		(net "GMI_CPU1_G0_CPU0_G2_TX_DP<5>")
	)
	(arc
		(start 106.270044 -222.591122)
		(mid 106.317447 -222.41183)
		(end 106.447082 -222.27921)
		(width 0.1143)
		(layer "In6.Cu")
		(net "GMI_CPU1_G0_CPU0_G2_TX_DP<5>")
	)
	(arc
		(start 102.350316 -237.574836)
		(mid 102.442997 -237.466834)
		(end 102.4763 -237.328456)
		(width 0.1143)
		(layer "In6.Cu")
		(net "GMI_CPU1_G0_CPU0_G2_TX_DP<5>")
	)
	(arc
		(start 368.079528 -230.714296)
		(mid 368.038766 -230.88418)
		(end 367.92535 -231.017064)
		(width 0.1143)
		(layer "In6.Cu")
		(net "GMI_CPU1_G0_CPU0_G2_TX_DP<5>")
	)
	(arc
		(start 369.25123 -239.27054)
		(mid 369.258303 -239.275549)
		(end 369.265454 -239.280446)
		(width 0.1143)
		(layer "In6.Cu")
		(net "GMI_CPU1_G0_CPU0_G2_TX_DP<5>")
	)
	(arc
		(start 367.139474 -225.85426)
		(mid 367.203989 -226.116479)
		(end 367.382806 -226.318826)
		(width 0.1143)
		(layer "In6.Cu")
		(net "GMI_CPU1_G0_CPU0_G2_TX_DP<5>")
	)
	(arc
		(start 102.0064 -241.244374)
		(mid 102.047655 -241.073403)
		(end 102.162356 -240.940082)
		(width 0.1143)
		(layer "In6.Cu")
		(net "GMI_CPU1_G0_CPU0_G2_TX_DP<5>")
	)
	(arc
		(start 104.580436 -225.510852)
		(mid 104.596405 -225.498815)
		(end 104.611932 -225.486214)
		(width 0.1143)
		(layer "In6.Cu")
		(net "GMI_CPU1_G0_CPU0_G2_TX_DP<5>")
	)
	(arc
		(start 367.923572 -228.789992)
		(mid 368.038248 -228.923326)
		(end 368.079528 -229.094284)
		(width 0.1143)
		(layer "In6.Cu")
		(net "GMI_CPU1_G0_CPU0_G2_TX_DP<5>")
	)
	(arc
		(start 103.643176 -235.228892)
		(mid 103.886503 -234.764326)
		(end 103.643176 -234.29976)
		(width 0.1143)
		(layer "In6.Cu")
		(net "GMI_CPU1_G0_CPU0_G2_TX_DP<5>")
	)
	(arc
		(start 102.230428 -239.2807)
		(mid 102.237577 -239.2758)
		(end 102.244652 -239.270794)
		(width 0.1143)
		(layer "In6.Cu")
		(net "GMI_CPU1_G0_CPU0_G2_TX_DP<5>")
	)
	(arc
		(start 367.852706 -232.679494)
		(mid 367.609379 -233.14406)
		(end 367.852706 -233.608626)
		(width 0.1143)
		(layer "In6.Cu")
		(net "GMI_CPU1_G0_CPU0_G2_TX_DP<5>")
	)
	(arc
		(start 102.946454 -236.384338)
		(mid 102.988003 -236.212916)
		(end 103.103426 -236.079538)
		(width 0.1143)
		(layer "In6.Cu")
		(net "GMI_CPU1_G0_CPU0_G2_TX_DP<5>")
	)
	(arc
		(start 365.728758 -223.424242)
		(mid 365.793051 -223.685847)
		(end 365.971074 -223.888046)
		(width 0.1143)
		(layer "In6.Cu")
		(net "GMI_CPU1_G0_CPU0_G2_TX_DP<5>")
	)
	(arc
		(start 369.25123 -240.890552)
		(mid 369.258303 -240.895561)
		(end 369.265454 -240.900458)
		(width 0.1143)
		(layer "In6.Cu")
		(net "GMI_CPU1_G0_CPU0_G2_TX_DP<5>")
	)
	(arc
		(start 103.416354 -230.71455)
		(mid 103.457609 -230.543579)
		(end 103.57231 -230.410258)
		(width 0.1143)
		(layer "In6.Cu")
		(net "GMI_CPU1_G0_CPU0_G2_TX_DP<5>")
	)
	(arc
		(start 101.293168 -242.518946)
		(mid 101.471981 -242.316596)
		(end 101.5365 -242.05438)
		(width 0.1143)
		(layer "In6.Cu")
		(net "GMI_CPU1_G0_CPU0_G2_TX_DP<5>")
	)
	(arc
		(start 102.230428 -240.900712)
		(mid 102.237577 -240.895812)
		(end 102.244652 -240.890806)
		(width 0.1143)
		(layer "In6.Cu")
		(net "GMI_CPU1_G0_CPU0_G2_TX_DP<5>")
	)
	(arc
		(start 367.852706 -229.43947)
		(mid 367.673893 -229.64182)
		(end 367.609374 -229.904036)
		(width 0.1143)
		(layer "In6.Cu")
		(net "GMI_CPU1_G0_CPU0_G2_TX_DP<5>")
	)
	(arc
		(start 369.265454 -239.96777)
		(mid 369.258304 -239.972668)
		(end 369.25123 -239.977676)
		(width 0.1143)
		(layer "In6.Cu")
		(net "GMI_CPU1_G0_CPU0_G2_TX_DP<5>")
	)
	(arc
		(start 103.416354 -229.094538)
		(mid 103.457609 -228.923567)
		(end 103.57231 -228.790246)
		(width 0.1143)
		(layer "In6.Cu")
		(net "GMI_CPU1_G0_CPU0_G2_TX_DP<5>")
	)
	(arc
		(start 367.452402 -226.359466)
		(mid 367.567829 -226.492842)
		(end 367.609374 -226.664266)
		(width 0.1143)
		(layer "In6.Cu")
		(net "GMI_CPU1_G0_CPU0_G2_TX_DP<5>")
	)
	(arc
		(start 102.703122 -236.848904)
		(mid 102.881935 -236.646554)
		(end 102.946454 -236.384338)
		(width 0.1143)
		(layer "In6.Cu")
		(net "GMI_CPU1_G0_CPU0_G2_TX_DP<5>")
	)
	(arc
		(start 103.640636 -230.370634)
		(mid 103.821288 -230.167889)
		(end 103.886508 -229.90429)
		(width 0.1143)
		(layer "In6.Cu")
		(net "GMI_CPU1_G0_CPU0_G2_TX_DP<5>")
	)
	(arc
		(start 368.079528 -235.574078)
		(mid 368.144043 -235.836297)
		(end 368.32286 -236.038644)
		(width 0.1143)
		(layer "In6.Cu")
		(net "GMI_CPU1_G0_CPU0_G2_TX_DP<5>")
	)
	(arc
		(start 370.27358 -242.55984)
		(mid 370.370715 -242.662709)
		(end 370.422678 -242.794282)
		(width 0.1143)
		(layer "In6.Cu")
		(net "GMI_CPU1_G0_CPU0_G2_TX_DP<5>")
	)
	(arc
		(start 367.609374 -229.904036)
		(mid 367.67461 -230.167627)
		(end 367.855246 -230.37038)
		(width 0.1143)
		(layer "In6.Cu")
		(net "GMI_CPU1_G0_CPU0_G2_TX_DP<5>")
	)
	(arc
		(start 364.789466 -221.80423)
		(mid 364.853981 -222.066449)
		(end 365.032798 -222.268796)
		(width 0.1143)
		(layer "In6.Cu")
		(net "GMI_CPU1_G0_CPU0_G2_TX_DP<5>")
	)
	(segment
		(start 101.907848 -239.8903)
		(end 101.440996 -239.624362)
		(width 0.12954)
		(layer "F.Cu")
		(net "GMI_CPU1_G0_CPU0_G2_TX_DP<4>")
	)
	(segment
		(start 369.588034 -239.890046)
		(end 370.054886 -239.624108)
		(width 0.12954)
		(layer "F.Cu")
		(net "GMI_CPU1_G0_CPU0_G2_TX_DP<4>")
	)
	(segment
		(start 309.427372 -179.521612)
		(end 319.2653 -185.36412)
		(width 0.14224)
		(layer "In6.Cu")
		(net "GMI_CPU1_G0_CPU0_G2_TX_DP<4>")
	)
	(segment
		(start 105.01376 -223.101916)
		(end 105.054146 -223.078294)
		(width 0.1143)
		(layer "In6.Cu")
		(net "GMI_CPU1_G0_CPU0_G2_TX_DP<4>")
	)
	(segment
		(start 104.04348 -224.739708)
		(end 104.07396 -224.721928)
		(width 0.1143)
		(layer "In6.Cu")
		(net "GMI_CPU1_G0_CPU0_G2_TX_DP<4>")
	)
	(segment
		(start 367.889282 -225.530156)
		(end 367.890806 -225.531172)
		(width 0.1143)
		(layer "In6.Cu")
		(net "GMI_CPU1_G0_CPU0_G2_TX_DP<4>")
	)
	(segment
		(start 102.664006 -235.251752)
		(end 102.665022 -235.251244)
		(width 0.1143)
		(layer "In6.Cu")
		(net "GMI_CPU1_G0_CPU0_G2_TX_DP<4>")
	)
	(segment
		(start 105.766362 -221.804484)
		(end 105.766362 -221.247462)
		(width 0.1143)
		(layer "In6.Cu")
		(net "GMI_CPU1_G0_CPU0_G2_TX_DP<4>")
	)
	(segment
		(start 102.666546 -235.250228)
		(end 102.703122 -235.228892)
		(width 0.1143)
		(layer "In6.Cu")
		(net "GMI_CPU1_G0_CPU0_G2_TX_DP<4>")
	)
	(segment
		(start 368.865404 -231.017064)
		(end 368.79276 -231.059482)
		(width 0.1143)
		(layer "In6.Cu")
		(net "GMI_CPU1_G0_CPU0_G2_TX_DP<4>")
	)
	(segment
		(start 368.815874 -230.382318)
		(end 368.863626 -230.410004)
		(width 0.1143)
		(layer "In6.Cu")
		(net "GMI_CPU1_G0_CPU0_G2_TX_DP<4>")
	)
	(segment
		(start 101.24821 -238.323628)
		(end 101.247448 -238.32312)
		(width 0.1143)
		(layer "In6.Cu")
		(net "GMI_CPU1_G0_CPU0_G2_TX_DP<4>")
	)
	(segment
		(start 368.829336 -232.658158)
		(end 368.79276 -232.679494)
		(width 0.1143)
		(layer "In6.Cu")
		(net "GMI_CPU1_G0_CPU0_G2_TX_DP<4>")
	)
	(segment
		(start 102.666546 -227.150422)
		(end 102.703122 -227.129086)
		(width 0.1143)
		(layer "In6.Cu")
		(net "GMI_CPU1_G0_CPU0_G2_TX_DP<4>")
	)
	(segment
		(start 370.24183 -238.326676)
		(end 370.240814 -238.327184)
		(width 0.1143)
		(layer "In6.Cu")
		(net "GMI_CPU1_G0_CPU0_G2_TX_DP<4>")
	)
	(segment
		(start 368.832638 -227.796344)
		(end 368.831876 -227.796852)
		(width 0.1143)
		(layer "In6.Cu")
		(net "GMI_CPU1_G0_CPU0_G2_TX_DP<4>")
	)
	(segment
		(start 364.76686 -216.700862)
		(end 365.684308 -218.915742)
		(width 0.14224)
		(layer "In6.Cu")
		(net "GMI_CPU1_G0_CPU0_G2_TX_DP<4>")
	)
	(segment
		(start 370.23929 -239.300004)
		(end 370.240814 -239.30102)
		(width 0.1143)
		(layer "In6.Cu")
		(net "GMI_CPU1_G0_CPU0_G2_TX_DP<4>")
	)
	(segment
		(start 370.422678 -239.554258)
		(end 370.352828 -239.624108)
		(width 0.1143)
		(layer "In6.Cu")
		(net "GMI_CPU1_G0_CPU0_G2_TX_DP<4>")
	)
	(segment
		(start 368.79276 -235.228638)
		(end 368.829336 -235.249974)
		(width 0.1143)
		(layer "In6.Cu")
		(net "GMI_CPU1_G0_CPU0_G2_TX_DP<4>")
	)
	(segment
		(start 368.829336 -235.249974)
		(end 368.83086 -235.25099)
		(width 0.1143)
		(layer "In6.Cu")
		(net "GMI_CPU1_G0_CPU0_G2_TX_DP<4>")
	)
	(segment
		(start 102.703122 -229.439724)
		(end 102.697026 -229.436168)
		(width 0.1143)
		(layer "In6.Cu")
		(net "GMI_CPU1_G0_CPU0_G2_TX_DP<4>")
	)
	(segment
		(start 368.831876 -232.011474)
		(end 368.832638 -232.011982)
		(width 0.1143)
		(layer "In6.Cu")
		(net "GMI_CPU1_G0_CPU0_G2_TX_DP<4>")
	)
	(segment
		(start 101.249734 -238.32439)
		(end 101.24821 -238.323628)
		(width 0.1143)
		(layer "In6.Cu")
		(net "GMI_CPU1_G0_CPU0_G2_TX_DP<4>")
	)
	(segment
		(start 235.115608 -178.43627)
		(end 235.115608 -178.436524)
		(width 0.14224)
		(layer "In6.Cu")
		(net "GMI_CPU1_G0_CPU0_G2_TX_DP<4>")
	)
	(segment
		(start 105.452164 -222.310706)
		(end 105.52303 -222.26905)
		(width 0.1143)
		(layer "In6.Cu")
		(net "GMI_CPU1_G0_CPU0_G2_TX_DP<4>")
	)
	(segment
		(start 101.693472 -236.889544)
		(end 101.723952 -236.871764)
		(width 0.1143)
		(layer "In6.Cu")
		(net "GMI_CPU1_G0_CPU0_G2_TX_DP<4>")
	)
	(segment
		(start 118.305326 -205.4352)
		(end 118.638066 -205.17993)
		(width 0.14224)
		(layer "In6.Cu")
		(net "GMI_CPU1_G0_CPU0_G2_TX_DP<4>")
	)
	(segment
		(start 368.832638 -233.631994)
		(end 368.863626 -233.649774)
		(width 0.1143)
		(layer "In6.Cu")
		(net "GMI_CPU1_G0_CPU0_G2_TX_DP<4>")
	)
	(segment
		(start 102.162356 -236.080046)
		(end 102.230936 -236.040676)
		(width 0.1143)
		(layer "In6.Cu")
		(net "GMI_CPU1_G0_CPU0_G2_TX_DP<4>")
	)
	(segment
		(start 102.703122 -234.29976)
		(end 102.696264 -234.295696)
		(width 0.1143)
		(layer "In6.Cu")
		(net "GMI_CPU1_G0_CPU0_G2_TX_DP<4>")
	)
	(segment
		(start 368.83086 -232.657142)
		(end 368.829336 -232.658158)
		(width 0.1143)
		(layer "In6.Cu")
		(net "GMI_CPU1_G0_CPU0_G2_TX_DP<4>")
	)
	(segment
		(start 365.684308 -221.081346)
		(end 365.684308 -221.09303)
		(width 0.1143)
		(layer "In6.Cu")
		(net "GMI_CPU1_G0_CPU0_G2_TX_DP<4>")
	)
	(segment
		(start 105.971848 -218.43238)
		(end 106.141266 -218.362276)
		(width 0.14224)
		(layer "In6.Cu")
		(net "GMI_CPU1_G0_CPU0_G2_TX_DP<4>")
	)
	(segment
		(start 102.695502 -234.295188)
		(end 102.664006 -234.2769)
		(width 0.1143)
		(layer "In6.Cu")
		(net "GMI_CPU1_G0_CPU0_G2_TX_DP<4>")
	)
	(segment
		(start 102.697026 -229.436168)
		(end 102.697026 -229.436422)
		(width 0.1143)
		(layer "In6.Cu")
		(net "GMI_CPU1_G0_CPU0_G2_TX_DP<4>")
	)
	(segment
		(start 365.72952 -221.247208)
		(end 365.72952 -221.80423)
		(width 0.1143)
		(layer "In6.Cu")
		(net "GMI_CPU1_G0_CPU0_G2_TX_DP<4>")
	)
	(segment
		(start 370.24183 -239.301528)
		(end 370.242592 -239.302036)
		(width 0.1143)
		(layer "In6.Cu")
		(net "GMI_CPU1_G0_CPU0_G2_TX_DP<4>")
	)
	(segment
		(start 370.245386 -238.324644)
		(end 370.242592 -238.326168)
		(width 0.1143)
		(layer "In6.Cu")
		(net "GMI_CPU1_G0_CPU0_G2_TX_DP<4>")
	)
	(segment
		(start 365.684308 -221.09303)
		(end 365.730028 -221.13875)
		(width 0.1143)
		(layer "In6.Cu")
		(net "GMI_CPU1_G0_CPU0_G2_TX_DP<4>")
	)
	(segment
		(start 368.831876 -233.631486)
		(end 368.832638 -233.631994)
		(width 0.1143)
		(layer "In6.Cu")
		(net "GMI_CPU1_G0_CPU0_G2_TX_DP<4>")
	)
	(segment
		(start 102.61981 -230.419148)
		(end 102.632256 -230.410258)
		(width 0.1143)
		(layer "In6.Cu")
		(net "GMI_CPU1_G0_CPU0_G2_TX_DP<4>")
	)
	(segment
		(start 367.893854 -225.53295)
		(end 367.923572 -225.549968)
		(width 0.1143)
		(layer "In6.Cu")
		(net "GMI_CPU1_G0_CPU0_G2_TX_DP<4>")
	)
	(segment
		(start 101.25329 -237.682278)
		(end 101.254052 -237.68177)
		(width 0.1143)
		(layer "In6.Cu")
		(net "GMI_CPU1_G0_CPU0_G2_TX_DP<4>")
	)
	(segment
		(start 368.83213 -229.416864)
		(end 368.798856 -229.436168)
		(width 0.1143)
		(layer "In6.Cu")
		(net "GMI_CPU1_G0_CPU0_G2_TX_DP<4>")
	)
	(segment
		(start 101.222302 -239.32007)
		(end 101.25329 -239.30229)
		(width 0.1143)
		(layer "In6.Cu")
		(net "GMI_CPU1_G0_CPU0_G2_TX_DP<4>")
	)
	(segment
		(start 102.665022 -235.251244)
		(end 102.666546 -235.250228)
		(width 0.1143)
		(layer "In6.Cu")
		(net "GMI_CPU1_G0_CPU0_G2_TX_DP<4>")
	)
	(segment
		(start 368.829336 -227.150168)
		(end 368.83086 -227.151184)
		(width 0.1143)
		(layer "In6.Cu")
		(net "GMI_CPU1_G0_CPU0_G2_TX_DP<4>")
	)
	(segment
		(start 370.243862 -237.682786)
		(end 370.27358 -237.699804)
		(width 0.1143)
		(layer "In6.Cu")
		(net "GMI_CPU1_G0_CPU0_G2_TX_DP<4>")
	)
	(segment
		(start 103.57231 -225.550222)
		(end 103.603298 -225.532442)
		(width 0.1143)
		(layer "In6.Cu")
		(net "GMI_CPU1_G0_CPU0_G2_TX_DP<4>")
	)
	(segment
		(start 102.663244 -233.632248)
		(end 102.664006 -233.63174)
		(width 0.1143)
		(layer "In6.Cu")
		(net "GMI_CPU1_G0_CPU0_G2_TX_DP<4>")
	)
	(segment
		(start 116.02593 -207.184244)
		(end 116.049806 -207.002634)
		(width 0.14224)
		(layer "In6.Cu")
		(net "GMI_CPU1_G0_CPU0_G2_TX_DP<4>")
	)
	(segment
		(start 370.242592 -238.326168)
		(end 370.24183 -238.326676)
		(width 0.1143)
		(layer "In6.Cu")
		(net "GMI_CPU1_G0_CPU0_G2_TX_DP<4>")
	)
	(segment
		(start 368.829336 -232.00995)
		(end 368.83086 -232.010966)
		(width 0.1143)
		(layer "In6.Cu")
		(net "GMI_CPU1_G0_CPU0_G2_TX_DP<4>")
	)
	(segment
		(start 368.863626 -230.410004)
		(end 368.876072 -230.418894)
		(width 0.1143)
		(layer "In6.Cu")
		(net "GMI_CPU1_G0_CPU0_G2_TX_DP<4>")
	)
	(segment
		(start 102.664006 -227.151946)
		(end 102.665022 -227.151438)
		(width 0.1143)
		(layer "In6.Cu")
		(net "GMI_CPU1_G0_CPU0_G2_TX_DP<4>")
	)
	(segment
		(start 368.863626 -232.638346)
		(end 368.832638 -232.656126)
		(width 0.1143)
		(layer "In6.Cu")
		(net "GMI_CPU1_G0_CPU0_G2_TX_DP<4>")
	)
	(segment
		(start 115.51158 -207.415638)
		(end 115.69319 -207.439514)
		(width 0.14224)
		(layer "In6.Cu")
		(net "GMI_CPU1_G0_CPU0_G2_TX_DP<4>")
	)
	(segment
		(start 101.222302 -237.700058)
		(end 101.25329 -237.682278)
		(width 0.1143)
		(layer "In6.Cu")
		(net "GMI_CPU1_G0_CPU0_G2_TX_DP<4>")
	)
	(segment
		(start 104.51338 -223.929702)
		(end 104.54386 -223.911922)
		(width 0.1143)
		(layer "In6.Cu")
		(net "GMI_CPU1_G0_CPU0_G2_TX_DP<4>")
	)
	(segment
		(start 319.310766 -185.54192)
		(end 319.671192 -185.756042)
		(width 0.14224)
		(layer "In6.Cu")
		(net "GMI_CPU1_G0_CPU0_G2_TX_DP<4>")
	)
	(segment
		(start 118.123462 -205.411324)
		(end 118.305326 -205.4352)
		(width 0.14224)
		(layer "In6.Cu")
		(net "GMI_CPU1_G0_CPU0_G2_TX_DP<4>")
	)
	(segment
		(start 101.254052 -237.68177)
		(end 101.255068 -237.681262)
		(width 0.1143)
		(layer "In6.Cu")
		(net "GMI_CPU1_G0_CPU0_G2_TX_DP<4>")
	)
	(segment
		(start 105.971848 -218.432634)
		(end 105.971848 -218.43238)
		(width 0.14224)
		(layer "In6.Cu")
		(net "GMI_CPU1_G0_CPU0_G2_TX_DP<4>")
	)
	(segment
		(start 117.767354 -205.848204)
		(end 117.79123 -205.66634)
		(width 0.14224)
		(layer "In6.Cu")
		(net "GMI_CPU1_G0_CPU0_G2_TX_DP<4>")
	)
	(segment
		(start 365.972852 -222.268796)
		(end 366.043718 -222.310452)
		(width 0.1143)
		(layer "In6.Cu")
		(net "GMI_CPU1_G0_CPU0_G2_TX_DP<4>")
	)
	(segment
		(start 102.664006 -232.656888)
		(end 102.663244 -232.65638)
		(width 0.1143)
		(layer "In6.Cu")
		(net "GMI_CPU1_G0_CPU0_G2_TX_DP<4>")
	)
	(segment
		(start 101.247448 -238.32312)
		(end 101.246432 -238.322612)
		(width 0.1143)
		(layer "In6.Cu")
		(net "GMI_CPU1_G0_CPU0_G2_TX_DP<4>")
	)
	(segment
		(start 102.665022 -228.77145)
		(end 102.666546 -228.770434)
		(width 0.1143)
		(layer "In6.Cu")
		(net "GMI_CPU1_G0_CPU0_G2_TX_DP<4>")
	)
	(segment
		(start 102.665022 -232.01122)
		(end 102.666546 -232.010204)
		(width 0.1143)
		(layer "In6.Cu")
		(net "GMI_CPU1_G0_CPU0_G2_TX_DP<4>")
	)
	(segment
		(start 370.24945 -238.322358)
		(end 370.248434 -238.322866)
		(width 0.1143)
		(layer "In6.Cu")
		(net "GMI_CPU1_G0_CPU0_G2_TX_DP<4>")
	)
	(segment
		(start 368.831876 -228.771704)
		(end 368.832384 -228.771704)
		(width 0.1143)
		(layer "In6.Cu")
		(net "GMI_CPU1_G0_CPU0_G2_TX_DP<4>")
	)
	(segment
		(start 117.25275 -206.079598)
		(end 117.434614 -206.103474)
		(width 0.14224)
		(layer "In6.Cu")
		(net "GMI_CPU1_G0_CPU0_G2_TX_DP<4>")
	)
	(segment
		(start 106.651552 -216.79154)
		(end 107.08259 -215.750902)
		(width 0.14224)
		(layer "In6.Cu")
		(net "GMI_CPU1_G0_CPU0_G2_TX_DP<4>")
	)
	(segment
		(start 368.829336 -233.629962)
		(end 368.83086 -233.630978)
		(width 0.1143)
		(layer "In6.Cu")
		(net "GMI_CPU1_G0_CPU0_G2_TX_DP<4>")
	)
	(segment
		(start 368.831876 -232.656634)
		(end 368.83086 -232.657142)
		(width 0.1143)
		(layer "In6.Cu")
		(net "GMI_CPU1_G0_CPU0_G2_TX_DP<4>")
	)
	(segment
		(start 102.665022 -227.151438)
		(end 102.666546 -227.150422)
		(width 0.1143)
		(layer "In6.Cu")
		(net "GMI_CPU1_G0_CPU0_G2_TX_DP<4>")
	)
	(segment
		(start 103.103426 -226.35972)
		(end 103.133906 -226.34194)
		(width 0.1143)
		(layer "In6.Cu")
		(net "GMI_CPU1_G0_CPU0_G2_TX_DP<4>")
	)
	(segment
		(start 302.907192 -178.831748)
		(end 306.914042 -178.831748)
		(width 0.14224)
		(layer "In6.Cu")
		(net "GMI_CPU1_G0_CPU0_G2_TX_DP<4>")
	)
	(segment
		(start 370.352828 -239.624108)
		(end 370.054886 -239.624108)
		(width 0.1143)
		(layer "In6.Cu")
		(net "GMI_CPU1_G0_CPU0_G2_TX_DP<4>")
	)
	(segment
		(start 367.891822 -225.53168)
		(end 367.892584 -225.532188)
		(width 0.1143)
		(layer "In6.Cu")
		(net "GMI_CPU1_G0_CPU0_G2_TX_DP<4>")
	)
	(segment
		(start 106.561382 -217.348308)
		(end 106.72191 -216.960958)
		(width 0.14224)
		(layer "In6.Cu")
		(net "GMI_CPU1_G0_CPU0_G2_TX_DP<4>")
	)
	(segment
		(start 368.831876 -227.151692)
		(end 368.832638 -227.1522)
		(width 0.1143)
		(layer "In6.Cu")
		(net "GMI_CPU1_G0_CPU0_G2_TX_DP<4>")
	)
	(segment
		(start 118.638066 -205.17993)
		(end 118.661942 -204.998066)
		(width 0.14224)
		(layer "In6.Cu")
		(net "GMI_CPU1_G0_CPU0_G2_TX_DP<4>")
	)
	(segment
		(start 116.896642 -206.516224)
		(end 116.920518 -206.334614)
		(width 0.14224)
		(layer "In6.Cu")
		(net "GMI_CPU1_G0_CPU0_G2_TX_DP<4>")
	)
	(segment
		(start 367.382806 -224.698814)
		(end 367.452402 -224.739454)
		(width 0.1143)
		(layer "In6.Cu")
		(net "GMI_CPU1_G0_CPU0_G2_TX_DP<4>")
	)
	(segment
		(start 367.892584 -225.532188)
		(end 367.893854 -225.53295)
		(width 0.1143)
		(layer "In6.Cu")
		(net "GMI_CPU1_G0_CPU0_G2_TX_DP<4>")
	)
	(segment
		(start 102.632256 -233.650028)
		(end 102.663244 -233.632248)
		(width 0.1143)
		(layer "In6.Cu")
		(net "GMI_CPU1_G0_CPU0_G2_TX_DP<4>")
	)
	(segment
		(start 102.663244 -234.276392)
		(end 102.632256 -234.258612)
		(width 0.1143)
		(layer "In6.Cu")
		(net "GMI_CPU1_G0_CPU0_G2_TX_DP<4>")
	)
	(segment
		(start 319.2653 -185.36412)
		(end 319.310766 -185.54192)
		(width 0.14224)
		(layer "In6.Cu")
		(net "GMI_CPU1_G0_CPU0_G2_TX_DP<4>")
	)
	(segment
		(start 368.832638 -232.011982)
		(end 368.863626 -232.029762)
		(width 0.1143)
		(layer "In6.Cu")
		(net "GMI_CPU1_G0_CPU0_G2_TX_DP<4>")
	)
	(segment
		(start 368.83086 -228.771196)
		(end 368.831876 -228.771704)
		(width 0.1143)
		(layer "In6.Cu")
		(net "GMI_CPU1_G0_CPU0_G2_TX_DP<4>")
	)
	(segment
		(start 106.141266 -218.362276)
		(end 106.301794 -217.974926)
		(width 0.14224)
		(layer "In6.Cu")
		(net "GMI_CPU1_G0_CPU0_G2_TX_DP<4>")
	)
	(segment
		(start 319.848738 -185.71083)
		(end 320.313558 -185.986928)
		(width 0.14224)
		(layer "In6.Cu")
		(net "GMI_CPU1_G0_CPU0_G2_TX_DP<4>")
	)
	(segment
		(start 101.255068 -237.681262)
		(end 101.256592 -237.680246)
		(width 0.1143)
		(layer "In6.Cu")
		(net "GMI_CPU1_G0_CPU0_G2_TX_DP<4>")
	)
	(segment
		(start 365.730028 -221.2467)
		(end 365.72952 -221.247208)
		(width 0.1143)
		(layer "In6.Cu")
		(net "GMI_CPU1_G0_CPU0_G2_TX_DP<4>")
	)
	(segment
		(start 368.863626 -234.258358)
		(end 368.832638 -234.276138)
		(width 0.1143)
		(layer "In6.Cu")
		(net "GMI_CPU1_G0_CPU0_G2_TX_DP<4>")
	)
	(segment
		(start 102.697026 -229.436422)
		(end 102.663752 -229.417118)
		(width 0.1143)
		(layer "In6.Cu")
		(net "GMI_CPU1_G0_CPU0_G2_TX_DP<4>")
	)
	(segment
		(start 101.254052 -238.32693)
		(end 101.25329 -238.326422)
		(width 0.1143)
		(layer "In6.Cu")
		(net "GMI_CPU1_G0_CPU0_G2_TX_DP<4>")
	)
	(segment
		(start 235.115608 -178.436524)
		(end 302.907192 -178.831748)
		(width 0.14224)
		(layer "In6.Cu")
		(net "GMI_CPU1_G0_CPU0_G2_TX_DP<4>")
	)
	(segment
		(start 370.248434 -238.322866)
		(end 370.247672 -238.323374)
		(width 0.1143)
		(layer "In6.Cu")
		(net "GMI_CPU1_G0_CPU0_G2_TX_DP<4>")
	)
	(segment
		(start 103.60406 -225.531934)
		(end 103.605076 -225.531426)
		(width 0.1143)
		(layer "In6.Cu")
		(net "GMI_CPU1_G0_CPU0_G2_TX_DP<4>")
	)
	(segment
		(start 103.605076 -225.531426)
		(end 103.6066 -225.53041)
		(width 0.1143)
		(layer "In6.Cu")
		(net "GMI_CPU1_G0_CPU0_G2_TX_DP<4>")
	)
	(segment
		(start 101.256592 -237.680246)
		(end 101.293168 -237.65891)
		(width 0.1143)
		(layer "In6.Cu")
		(net "GMI_CPU1_G0_CPU0_G2_TX_DP<4>")
	)
	(segment
		(start 105.811574 -221.064836)
		(end 105.811574 -218.81973)
		(width 0.14224)
		(layer "In6.Cu")
		(net "GMI_CPU1_G0_CPU0_G2_TX_DP<4>")
	)
	(segment
		(start 105.811574 -221.093284)
		(end 105.811574 -221.064836)
		(width 0.1143)
		(layer "In6.Cu")
		(net "GMI_CPU1_G0_CPU0_G2_TX_DP<4>")
	)
	(segment
		(start 102.666546 -233.630216)
		(end 102.703122 -233.60888)
		(width 0.1143)
		(layer "In6.Cu")
		(net "GMI_CPU1_G0_CPU0_G2_TX_DP<4>")
	)
	(segment
		(start 101.293168 -238.34979)
		(end 101.28631 -238.345726)
		(width 0.1143)
		(layer "In6.Cu")
		(net "GMI_CPU1_G0_CPU0_G2_TX_DP<4>")
	)
	(segment
		(start 103.603298 -225.532442)
		(end 103.60406 -225.531934)
		(width 0.1143)
		(layer "In6.Cu")
		(net "GMI_CPU1_G0_CPU0_G2_TX_DP<4>")
	)
	(segment
		(start 102.696264 -232.675684)
		(end 102.695502 -232.675176)
		(width 0.1143)
		(layer "In6.Cu")
		(net "GMI_CPU1_G0_CPU0_G2_TX_DP<4>")
	)
	(segment
		(start 370.240814 -237.681008)
		(end 370.24183 -237.681516)
		(width 0.1143)
		(layer "In6.Cu")
		(net "GMI_CPU1_G0_CPU0_G2_TX_DP<4>")
	)
	(segment
		(start 101.250496 -238.324898)
		(end 101.249734 -238.32439)
		(width 0.1143)
		(layer "In6.Cu")
		(net "GMI_CPU1_G0_CPU0_G2_TX_DP<4>")
	)
	(segment
		(start 102.664006 -234.2769)
		(end 102.663244 -234.276392)
		(width 0.1143)
		(layer "In6.Cu")
		(net "GMI_CPU1_G0_CPU0_G2_TX_DP<4>")
	)
	(segment
		(start 102.4763 -230.71455)
		(end 102.4763 -230.69931)
		(width 0.1143)
		(layer "In6.Cu")
		(net "GMI_CPU1_G0_CPU0_G2_TX_DP<4>")
	)
	(segment
		(start 370.242592 -239.302036)
		(end 370.243862 -239.302798)
		(width 0.1143)
		(layer "In6.Cu")
		(net "GMI_CPU1_G0_CPU0_G2_TX_DP<4>")
	)
	(segment
		(start 366.917224 -223.891348)
		(end 366.982502 -223.929448)
		(width 0.1143)
		(layer "In6.Cu")
		(net "GMI_CPU1_G0_CPU0_G2_TX_DP<4>")
	)
	(segment
		(start 368.829336 -227.798376)
		(end 368.79276 -227.819712)
		(width 0.1143)
		(layer "In6.Cu")
		(net "GMI_CPU1_G0_CPU0_G2_TX_DP<4>")
	)
	(segment
		(start 102.477824 -235.61294)
		(end 102.477824 -235.574332)
		(width 0.1143)
		(layer "In6.Cu")
		(net "GMI_CPU1_G0_CPU0_G2_TX_DP<4>")
	)
	(segment
		(start 101.440996 -239.624362)
		(end 101.143054 -239.624362)
		(width 0.1143)
		(layer "In6.Cu")
		(net "GMI_CPU1_G0_CPU0_G2_TX_DP<4>")
	)
	(segment
		(start 105.811574 -218.81973)
		(end 105.971848 -218.432634)
		(width 0.14224)
		(layer "In6.Cu")
		(net "GMI_CPU1_G0_CPU0_G2_TX_DP<4>")
	)
	(segment
		(start 102.663244 -227.152454)
		(end 102.664006 -227.151946)
		(width 0.1143)
		(layer "In6.Cu")
		(net "GMI_CPU1_G0_CPU0_G2_TX_DP<4>")
	)
	(segment
		(start 365.730028 -221.13875)
		(end 365.730028 -221.2467)
		(width 0.1143)
		(layer "In6.Cu")
		(net "GMI_CPU1_G0_CPU0_G2_TX_DP<4>")
	)
	(segment
		(start 368.83086 -235.25099)
		(end 368.831876 -235.251498)
		(width 0.1143)
		(layer "In6.Cu")
		(net "GMI_CPU1_G0_CPU0_G2_TX_DP<4>")
	)
	(segment
		(start 370.240814 -238.327184)
		(end 370.23929 -238.3282)
		(width 0.1143)
		(layer "In6.Cu")
		(net "GMI_CPU1_G0_CPU0_G2_TX_DP<4>")
	)
	(segment
		(start 116.920518 -206.334614)
		(end 117.25275 -206.079598)
		(width 0.14224)
		(layer "In6.Cu")
		(net "GMI_CPU1_G0_CPU0_G2_TX_DP<4>")
	)
	(segment
		(start 102.632256 -227.170234)
		(end 102.663244 -227.152454)
		(width 0.1143)
		(layer "In6.Cu")
		(net "GMI_CPU1_G0_CPU0_G2_TX_DP<4>")
	)
	(segment
		(start 369.019582 -230.699056)
		(end 369.019582 -230.714296)
		(width 0.1143)
		(layer "In6.Cu")
		(net "GMI_CPU1_G0_CPU0_G2_TX_DP<4>")
	)
	(segment
		(start 119.732806 -204.176376)
		(end 163.021772 -179.179728)
		(width 0.14224)
		(layer "In6.Cu")
		(net "GMI_CPU1_G0_CPU0_G2_TX_DP<4>")
	)
	(segment
		(start 104.980994 -223.120966)
		(end 105.01376 -223.101916)
		(width 0.1143)
		(layer "In6.Cu")
		(net "GMI_CPU1_G0_CPU0_G2_TX_DP<4>")
	)
	(segment
		(start 102.666546 -232.010204)
		(end 102.703122 -231.988868)
		(width 0.1143)
		(layer "In6.Cu")
		(net "GMI_CPU1_G0_CPU0_G2_TX_DP<4>")
	)
	(segment
		(start 115.108482 -207.72501)
		(end 115.51158 -207.415638)
		(width 0.14224)
		(layer "In6.Cu")
		(net "GMI_CPU1_G0_CPU0_G2_TX_DP<4>")
	)
	(segment
		(start 366.482122 -223.101662)
		(end 366.514888 -223.120712)
		(width 0.1143)
		(layer "In6.Cu")
		(net "GMI_CPU1_G0_CPU0_G2_TX_DP<4>")
	)
	(segment
		(start 368.79276 -233.608626)
		(end 368.829336 -233.629962)
		(width 0.1143)
		(layer "In6.Cu")
		(net "GMI_CPU1_G0_CPU0_G2_TX_DP<4>")
	)
	(segment
		(start 163.021772 -179.179728)
		(end 167.323262 -178.040538)
		(width 0.14224)
		(layer "In6.Cu")
		(net "GMI_CPU1_G0_CPU0_G2_TX_DP<4>")
	)
	(segment
		(start 101.28631 -238.345726)
		(end 101.285548 -238.345218)
		(width 0.1143)
		(layer "In6.Cu")
		(net "GMI_CPU1_G0_CPU0_G2_TX_DP<4>")
	)
	(segment
		(start 102.663498 -235.251752)
		(end 102.664006 -235.251752)
		(width 0.1143)
		(layer "In6.Cu")
		(net "GMI_CPU1_G0_CPU0_G2_TX_DP<4>")
	)
	(segment
		(start 102.664006 -227.797106)
		(end 102.663244 -227.796598)
		(width 0.1143)
		(layer "In6.Cu")
		(net "GMI_CPU1_G0_CPU0_G2_TX_DP<4>")
	)
	(segment
		(start 105.765854 -221.139004)
		(end 105.811574 -221.093284)
		(width 0.1143)
		(layer "In6.Cu")
		(net "GMI_CPU1_G0_CPU0_G2_TX_DP<4>")
	)
	(segment
		(start 368.831876 -234.276646)
		(end 368.83086 -234.277154)
		(width 0.1143)
		(layer "In6.Cu")
		(net "GMI_CPU1_G0_CPU0_G2_TX_DP<4>")
	)
	(segment
		(start 368.832638 -234.276138)
		(end 368.831876 -234.276646)
		(width 0.1143)
		(layer "In6.Cu")
		(net "GMI_CPU1_G0_CPU0_G2_TX_DP<4>")
	)
	(segment
		(start 368.831876 -235.251498)
		(end 368.832384 -235.251498)
		(width 0.1143)
		(layer "In6.Cu")
		(net "GMI_CPU1_G0_CPU0_G2_TX_DP<4>")
	)
	(segment
		(start 368.832638 -232.656126)
		(end 368.831876 -232.656634)
		(width 0.1143)
		(layer "In6.Cu")
		(net "GMI_CPU1_G0_CPU0_G2_TX_DP<4>")
	)
	(segment
		(start 320.631058 -186.260232)
		(end 320.644774 -186.442858)
		(width 0.14224)
		(layer "In6.Cu")
		(net "GMI_CPU1_G0_CPU0_G2_TX_DP<4>")
	)
	(segment
		(start 101.25329 -238.326422)
		(end 101.250496 -238.324898)
		(width 0.1143)
		(layer "In6.Cu")
		(net "GMI_CPU1_G0_CPU0_G2_TX_DP<4>")
	)
	(segment
		(start 101.255068 -239.301274)
		(end 101.256592 -239.300258)
		(width 0.1143)
		(layer "In6.Cu")
		(net "GMI_CPU1_G0_CPU0_G2_TX_DP<4>")
	)
	(segment
		(start 368.832638 -227.1522)
		(end 368.863626 -227.16998)
		(width 0.1143)
		(layer "In6.Cu")
		(net "GMI_CPU1_G0_CPU0_G2_TX_DP<4>")
	)
	(segment
		(start 101.256592 -239.300258)
		(end 101.293168 -239.278922)
		(width 0.1143)
		(layer "In6.Cu")
		(net "GMI_CPU1_G0_CPU0_G2_TX_DP<4>")
	)
	(segment
		(start 368.83086 -232.010966)
		(end 368.831876 -232.011474)
		(width 0.1143)
		(layer "In6.Cu")
		(net "GMI_CPU1_G0_CPU0_G2_TX_DP<4>")
	)
	(segment
		(start 117.434614 -206.103474)
		(end 117.767354 -205.848204)
		(width 0.14224)
		(layer "In6.Cu")
		(net "GMI_CPU1_G0_CPU0_G2_TX_DP<4>")
	)
	(segment
		(start 368.83086 -227.79736)
		(end 368.829336 -227.798376)
		(width 0.1143)
		(layer "In6.Cu")
		(net "GMI_CPU1_G0_CPU0_G2_TX_DP<4>")
	)
	(segment
		(start 368.831876 -227.796852)
		(end 368.83086 -227.79736)
		(width 0.1143)
		(layer "In6.Cu")
		(net "GMI_CPU1_G0_CPU0_G2_TX_DP<4>")
	)
	(segment
		(start 368.79276 -227.128832)
		(end 368.829336 -227.150168)
		(width 0.1143)
		(layer "In6.Cu")
		(net "GMI_CPU1_G0_CPU0_G2_TX_DP<4>")
	)
	(segment
		(start 104.07396 -224.721928)
		(end 104.113076 -224.699068)
		(width 0.1143)
		(layer "In6.Cu")
		(net "GMI_CPU1_G0_CPU0_G2_TX_DP<4>")
	)
	(segment
		(start 102.663244 -227.796598)
		(end 102.632256 -227.778818)
		(width 0.1143)
		(layer "In6.Cu")
		(net "GMI_CPU1_G0_CPU0_G2_TX_DP<4>")
	)
	(segment
		(start 370.247672 -238.323374)
		(end 370.246148 -238.324136)
		(width 0.1143)
		(layer "In6.Cu")
		(net "GMI_CPU1_G0_CPU0_G2_TX_DP<4>")
	)
	(segment
		(start 103.133906 -226.34194)
		(end 103.173022 -226.31908)
		(width 0.1143)
		(layer "In6.Cu")
		(net "GMI_CPU1_G0_CPU0_G2_TX_DP<4>")
	)
	(segment
		(start 102.695502 -227.815394)
		(end 102.664006 -227.797106)
		(width 0.1143)
		(layer "In6.Cu")
		(net "GMI_CPU1_G0_CPU0_G2_TX_DP<4>")
	)
	(segment
		(start 102.695502 -230.373682)
		(end 102.700582 -230.370634)
		(width 0.1143)
		(layer "In6.Cu")
		(net "GMI_CPU1_G0_CPU0_G2_TX_DP<4>")
	)
	(segment
		(start 365.684308 -218.915742)
		(end 365.684308 -221.081346)
		(width 0.14224)
		(layer "In6.Cu")
		(net "GMI_CPU1_G0_CPU0_G2_TX_DP<4>")
	)
	(segment
		(start 102.696264 -227.815902)
		(end 102.695502 -227.815394)
		(width 0.1143)
		(layer "In6.Cu")
		(net "GMI_CPU1_G0_CPU0_G2_TX_DP<4>")
	)
	(segment
		(start 370.23929 -238.3282)
		(end 370.202714 -238.349536)
		(width 0.1143)
		(layer "In6.Cu")
		(net "GMI_CPU1_G0_CPU0_G2_TX_DP<4>")
	)
	(segment
		(start 102.664006 -232.011728)
		(end 102.665022 -232.01122)
		(width 0.1143)
		(layer "In6.Cu")
		(net "GMI_CPU1_G0_CPU0_G2_TX_DP<4>")
	)
	(segment
		(start 369.264946 -236.040422)
		(end 369.333526 -236.079792)
		(width 0.1143)
		(layer "In6.Cu")
		(net "GMI_CPU1_G0_CPU0_G2_TX_DP<4>")
	)
	(segment
		(start 106.23169 -217.805508)
		(end 106.391964 -217.418412)
		(width 0.14224)
		(layer "In6.Cu")
		(net "GMI_CPU1_G0_CPU0_G2_TX_DP<4>")
	)
	(segment
		(start 368.83086 -234.277154)
		(end 368.829336 -234.27817)
		(width 0.1143)
		(layer "In6.Cu")
		(net "GMI_CPU1_G0_CPU0_G2_TX_DP<4>")
	)
	(segment
		(start 106.72191 -216.960958)
		(end 106.651552 -216.79154)
		(width 0.14224)
		(layer "In6.Cu")
		(net "GMI_CPU1_G0_CPU0_G2_TX_DP<4>")
	)
	(segment
		(start 115.69319 -207.439514)
		(end 116.02593 -207.184244)
		(width 0.14224)
		(layer "In6.Cu")
		(net "GMI_CPU1_G0_CPU0_G2_TX_DP<4>")
	)
	(segment
		(start 370.27358 -238.308388)
		(end 370.24945 -238.322358)
		(width 0.1143)
		(layer "In6.Cu")
		(net "GMI_CPU1_G0_CPU0_G2_TX_DP<4>")
	)
	(segment
		(start 368.798856 -229.435914)
		(end 368.79276 -229.43947)
		(width 0.1143)
		(layer "In6.Cu")
		(net "GMI_CPU1_G0_CPU0_G2_TX_DP<4>")
	)
	(segment
		(start 102.632256 -230.410258)
		(end 102.680008 -230.382572)
		(width 0.1143)
		(layer "In6.Cu")
		(net "GMI_CPU1_G0_CPU0_G2_TX_DP<4>")
	)
	(segment
		(start 368.79276 -228.748844)
		(end 368.829336 -228.77018)
		(width 0.1143)
		(layer "In6.Cu")
		(net "GMI_CPU1_G0_CPU0_G2_TX_DP<4>")
	)
	(segment
		(start 117.79123 -205.66634)
		(end 118.123462 -205.411324)
		(width 0.14224)
		(layer "In6.Cu")
		(net "GMI_CPU1_G0_CPU0_G2_TX_DP<4>")
	)
	(segment
		(start 368.32286 -226.318826)
		(end 368.392456 -226.359466)
		(width 0.1143)
		(layer "In6.Cu")
		(net "GMI_CPU1_G0_CPU0_G2_TX_DP<4>")
	)
	(segment
		(start 370.240814 -239.30102)
		(end 370.24183 -239.301528)
		(width 0.1143)
		(layer "In6.Cu")
		(net "GMI_CPU1_G0_CPU0_G2_TX_DP<4>")
	)
	(segment
		(start 368.83086 -227.151184)
		(end 368.831876 -227.151692)
		(width 0.1143)
		(layer "In6.Cu")
		(net "GMI_CPU1_G0_CPU0_G2_TX_DP<4>")
	)
	(segment
		(start 368.829336 -234.27817)
		(end 368.79276 -234.299506)
		(width 0.1143)
		(layer "In6.Cu")
		(net "GMI_CPU1_G0_CPU0_G2_TX_DP<4>")
	)
	(segment
		(start 102.666546 -228.770434)
		(end 102.703122 -228.749098)
		(width 0.1143)
		(layer "In6.Cu")
		(net "GMI_CPU1_G0_CPU0_G2_TX_DP<4>")
	)
	(segment
		(start 369.018058 -235.574078)
		(end 369.018058 -235.612686)
		(width 0.1143)
		(layer "In6.Cu")
		(net "GMI_CPU1_G0_CPU0_G2_TX_DP<4>")
	)
	(segment
		(start 101.723952 -236.871764)
		(end 101.763068 -236.848904)
		(width 0.1143)
		(layer "In6.Cu")
		(net "GMI_CPU1_G0_CPU0_G2_TX_DP<4>")
	)
	(segment
		(start 368.7953 -230.37038)
		(end 368.80038 -230.373428)
		(width 0.1143)
		(layer "In6.Cu")
		(net "GMI_CPU1_G0_CPU0_G2_TX_DP<4>")
	)
	(segment
		(start 367.890806 -225.531172)
		(end 367.891822 -225.53168)
		(width 0.1143)
		(layer "In6.Cu")
		(net "GMI_CPU1_G0_CPU0_G2_TX_DP<4>")
	)
	(segment
		(start 118.661942 -204.998066)
		(end 119.732806 -204.176376)
		(width 0.14224)
		(layer "In6.Cu")
		(net "GMI_CPU1_G0_CPU0_G2_TX_DP<4>")
	)
	(segment
		(start 355.953568 -208.832196)
		(end 360.618278 -212.55228)
		(width 0.14224)
		(layer "In6.Cu")
		(net "GMI_CPU1_G0_CPU0_G2_TX_DP<4>")
	)
	(segment
		(start 105.765854 -221.246954)
		(end 105.765854 -221.139004)
		(width 0.1143)
		(layer "In6.Cu")
		(net "GMI_CPU1_G0_CPU0_G2_TX_DP<4>")
	)
	(segment
		(start 105.766362 -221.247462)
		(end 105.765854 -221.246954)
		(width 0.1143)
		(layer "In6.Cu")
		(net "GMI_CPU1_G0_CPU0_G2_TX_DP<4>")
	)
	(segment
		(start 370.23929 -237.679992)
		(end 370.240814 -237.681008)
		(width 0.1143)
		(layer "In6.Cu")
		(net "GMI_CPU1_G0_CPU0_G2_TX_DP<4>")
	)
	(segment
		(start 366.441736 -223.07804)
		(end 366.482122 -223.101662)
		(width 0.1143)
		(layer "In6.Cu")
		(net "GMI_CPU1_G0_CPU0_G2_TX_DP<4>")
	)
	(segment
		(start 102.664006 -233.63174)
		(end 102.665022 -233.631232)
		(width 0.1143)
		(layer "In6.Cu")
		(net "GMI_CPU1_G0_CPU0_G2_TX_DP<4>")
	)
	(segment
		(start 321.145408 -186.7027)
		(end 322.23583 -187.64123)
		(width 0.14224)
		(layer "In6.Cu")
		(net "GMI_CPU1_G0_CPU0_G2_TX_DP<4>")
	)
	(segment
		(start 320.313558 -185.986928)
		(end 320.631058 -186.260232)
		(width 0.14224)
		(layer "In6.Cu")
		(net "GMI_CPU1_G0_CPU0_G2_TX_DP<4>")
	)
	(segment
		(start 106.391964 -217.418412)
		(end 106.561382 -217.348308)
		(width 0.14224)
		(layer "In6.Cu")
		(net "GMI_CPU1_G0_CPU0_G2_TX_DP<4>")
	)
	(segment
		(start 102.680008 -230.382572)
		(end 102.68077 -230.382064)
		(width 0.1143)
		(layer "In6.Cu")
		(net "GMI_CPU1_G0_CPU0_G2_TX_DP<4>")
	)
	(segment
		(start 116.563902 -206.771494)
		(end 116.896642 -206.516224)
		(width 0.14224)
		(layer "In6.Cu")
		(net "GMI_CPU1_G0_CPU0_G2_TX_DP<4>")
	)
	(segment
		(start 368.80038 -230.373428)
		(end 368.815112 -230.38181)
		(width 0.1143)
		(layer "In6.Cu")
		(net "GMI_CPU1_G0_CPU0_G2_TX_DP<4>")
	)
	(segment
		(start 101.254052 -239.301782)
		(end 101.255068 -239.301274)
		(width 0.1143)
		(layer "In6.Cu")
		(net "GMI_CPU1_G0_CPU0_G2_TX_DP<4>")
	)
	(segment
		(start 107.08259 -215.750902)
		(end 115.108482 -207.72501)
		(width 0.14224)
		(layer "In6.Cu")
		(net "GMI_CPU1_G0_CPU0_G2_TX_DP<4>")
	)
	(segment
		(start 368.815112 -230.38181)
		(end 368.815874 -230.382318)
		(width 0.1143)
		(layer "In6.Cu")
		(net "GMI_CPU1_G0_CPU0_G2_TX_DP<4>")
	)
	(segment
		(start 368.83086 -233.630978)
		(end 368.831876 -233.631486)
		(width 0.1143)
		(layer "In6.Cu")
		(net "GMI_CPU1_G0_CPU0_G2_TX_DP<4>")
	)
	(segment
		(start 368.863626 -227.778564)
		(end 368.832638 -227.796344)
		(width 0.1143)
		(layer "In6.Cu")
		(net "GMI_CPU1_G0_CPU0_G2_TX_DP<4>")
	)
	(segment
		(start 360.618278 -212.55228)
		(end 364.76686 -216.700862)
		(width 0.14224)
		(layer "In6.Cu")
		(net "GMI_CPU1_G0_CPU0_G2_TX_DP<4>")
	)
	(segment
		(start 104.54386 -223.911922)
		(end 104.578658 -223.891602)
		(width 0.1143)
		(layer "In6.Cu")
		(net "GMI_CPU1_G0_CPU0_G2_TX_DP<4>")
	)
	(segment
		(start 368.79276 -231.988614)
		(end 368.829336 -232.00995)
		(width 0.1143)
		(layer "In6.Cu")
		(net "GMI_CPU1_G0_CPU0_G2_TX_DP<4>")
	)
	(segment
		(start 370.243862 -239.302798)
		(end 370.27358 -239.319816)
		(width 0.1143)
		(layer "In6.Cu")
		(net "GMI_CPU1_G0_CPU0_G2_TX_DP<4>")
	)
	(segment
		(start 322.23583 -187.64123)
		(end 355.953568 -208.832196)
		(width 0.14224)
		(layer "In6.Cu")
		(net "GMI_CPU1_G0_CPU0_G2_TX_DP<4>")
	)
	(segment
		(start 102.68077 -230.382064)
		(end 102.695502 -230.373682)
		(width 0.1143)
		(layer "In6.Cu")
		(net "GMI_CPU1_G0_CPU0_G2_TX_DP<4>")
	)
	(segment
		(start 102.632256 -232.030016)
		(end 102.663244 -232.012236)
		(width 0.1143)
		(layer "In6.Cu")
		(net "GMI_CPU1_G0_CPU0_G2_TX_DP<4>")
	)
	(segment
		(start 370.202714 -239.278668)
		(end 370.23929 -239.300004)
		(width 0.1143)
		(layer "In6.Cu")
		(net "GMI_CPU1_G0_CPU0_G2_TX_DP<4>")
	)
	(segment
		(start 368.829336 -228.77018)
		(end 368.83086 -228.771196)
		(width 0.1143)
		(layer "In6.Cu")
		(net "GMI_CPU1_G0_CPU0_G2_TX_DP<4>")
	)
	(segment
		(start 370.24183 -237.681516)
		(end 370.242592 -237.682024)
		(width 0.1143)
		(layer "In6.Cu")
		(net "GMI_CPU1_G0_CPU0_G2_TX_DP<4>")
	)
	(segment
		(start 370.242592 -237.682024)
		(end 370.243862 -237.682786)
		(width 0.1143)
		(layer "In6.Cu")
		(net "GMI_CPU1_G0_CPU0_G2_TX_DP<4>")
	)
	(segment
		(start 101.246432 -238.322612)
		(end 101.222302 -238.308642)
		(width 0.1143)
		(layer "In6.Cu")
		(net "GMI_CPU1_G0_CPU0_G2_TX_DP<4>")
	)
	(segment
		(start 167.323262 -178.040538)
		(end 235.115608 -178.43627)
		(width 0.14224)
		(layer "In6.Cu")
		(net "GMI_CPU1_G0_CPU0_G2_TX_DP<4>")
	)
	(segment
		(start 102.703122 -227.819966)
		(end 102.696264 -227.815902)
		(width 0.1143)
		(layer "In6.Cu")
		(net "GMI_CPU1_G0_CPU0_G2_TX_DP<4>")
	)
	(segment
		(start 101.285548 -238.345218)
		(end 101.254052 -238.32693)
		(width 0.1143)
		(layer "In6.Cu")
		(net "GMI_CPU1_G0_CPU0_G2_TX_DP<4>")
	)
	(segment
		(start 106.301794 -217.974926)
		(end 106.23169 -217.805508)
		(width 0.14224)
		(layer "In6.Cu")
		(net "GMI_CPU1_G0_CPU0_G2_TX_DP<4>")
	)
	(segment
		(start 102.664006 -228.771958)
		(end 102.665022 -228.77145)
		(width 0.1143)
		(layer "In6.Cu")
		(net "GMI_CPU1_G0_CPU0_G2_TX_DP<4>")
	)
	(segment
		(start 116.382038 -206.747618)
		(end 116.563902 -206.771494)
		(width 0.14224)
		(layer "In6.Cu")
		(net "GMI_CPU1_G0_CPU0_G2_TX_DP<4>")
	)
	(segment
		(start 370.246148 -238.324136)
		(end 370.245386 -238.324644)
		(width 0.1143)
		(layer "In6.Cu")
		(net "GMI_CPU1_G0_CPU0_G2_TX_DP<4>")
	)
	(segment
		(start 101.25329 -239.30229)
		(end 101.254052 -239.301782)
		(width 0.1143)
		(layer "In6.Cu")
		(net "GMI_CPU1_G0_CPU0_G2_TX_DP<4>")
	)
	(segment
		(start 101.143054 -239.624362)
		(end 101.073204 -239.554512)
		(width 0.1143)
		(layer "In6.Cu")
		(net "GMI_CPU1_G0_CPU0_G2_TX_DP<4>")
	)
	(segment
		(start 103.6066 -225.53041)
		(end 103.643176 -225.509074)
		(width 0.1143)
		(layer "In6.Cu")
		(net "GMI_CPU1_G0_CPU0_G2_TX_DP<4>")
	)
	(segment
		(start 369.732814 -236.84865)
		(end 369.80241 -236.88929)
		(width 0.1143)
		(layer "In6.Cu")
		(net "GMI_CPU1_G0_CPU0_G2_TX_DP<4>")
	)
	(segment
		(start 102.703122 -231.059736)
		(end 102.630478 -231.017318)
		(width 0.1143)
		(layer "In6.Cu")
		(net "GMI_CPU1_G0_CPU0_G2_TX_DP<4>")
	)
	(segment
		(start 319.671192 -185.756042)
		(end 319.848738 -185.71083)
		(width 0.14224)
		(layer "In6.Cu")
		(net "GMI_CPU1_G0_CPU0_G2_TX_DP<4>")
	)
	(segment
		(start 306.914042 -178.831748)
		(end 309.427372 -179.521612)
		(width 0.14224)
		(layer "In6.Cu")
		(net "GMI_CPU1_G0_CPU0_G2_TX_DP<4>")
	)
	(segment
		(start 102.663498 -228.771958)
		(end 102.664006 -228.771958)
		(width 0.1143)
		(layer "In6.Cu")
		(net "GMI_CPU1_G0_CPU0_G2_TX_DP<4>")
	)
	(segment
		(start 320.644774 -186.442858)
		(end 320.962782 -186.716416)
		(width 0.14224)
		(layer "In6.Cu")
		(net "GMI_CPU1_G0_CPU0_G2_TX_DP<4>")
	)
	(segment
		(start 102.696264 -234.295696)
		(end 102.695502 -234.295188)
		(width 0.1143)
		(layer "In6.Cu")
		(net "GMI_CPU1_G0_CPU0_G2_TX_DP<4>")
	)
	(segment
		(start 370.202714 -237.658656)
		(end 370.23929 -237.679992)
		(width 0.1143)
		(layer "In6.Cu")
		(net "GMI_CPU1_G0_CPU0_G2_TX_DP<4>")
	)
	(segment
		(start 116.049806 -207.002634)
		(end 116.382038 -206.747618)
		(width 0.14224)
		(layer "In6.Cu")
		(net "GMI_CPU1_G0_CPU0_G2_TX_DP<4>")
	)
	(segment
		(start 367.852706 -225.50882)
		(end 367.889282 -225.530156)
		(width 0.1143)
		(layer "In6.Cu")
		(net "GMI_CPU1_G0_CPU0_G2_TX_DP<4>")
	)
	(segment
		(start 102.663244 -232.65638)
		(end 102.632256 -232.6386)
		(width 0.1143)
		(layer "In6.Cu")
		(net "GMI_CPU1_G0_CPU0_G2_TX_DP<4>")
	)
	(segment
		(start 368.798856 -229.436168)
		(end 368.798856 -229.435914)
		(width 0.1143)
		(layer "In6.Cu")
		(net "GMI_CPU1_G0_CPU0_G2_TX_DP<4>")
	)
	(segment
		(start 102.703122 -232.679748)
		(end 102.696264 -232.675684)
		(width 0.1143)
		(layer "In6.Cu")
		(net "GMI_CPU1_G0_CPU0_G2_TX_DP<4>")
	)
	(segment
		(start 102.695502 -232.675176)
		(end 102.664006 -232.656888)
		(width 0.1143)
		(layer "In6.Cu")
		(net "GMI_CPU1_G0_CPU0_G2_TX_DP<4>")
	)
	(segment
		(start 102.663244 -232.012236)
		(end 102.664006 -232.011728)
		(width 0.1143)
		(layer "In6.Cu")
		(net "GMI_CPU1_G0_CPU0_G2_TX_DP<4>")
	)
	(segment
		(start 102.665022 -233.631232)
		(end 102.666546 -233.630216)
		(width 0.1143)
		(layer "In6.Cu")
		(net "GMI_CPU1_G0_CPU0_G2_TX_DP<4>")
	)
	(segment
		(start 320.962782 -186.716416)
		(end 321.145408 -186.7027)
		(width 0.14224)
		(layer "In6.Cu")
		(net "GMI_CPU1_G0_CPU0_G2_TX_DP<4>")
	)
	(arc
		(start 101.293168 -239.278922)
		(mid 101.536495 -238.814356)
		(end 101.293168 -238.34979)
		(width 0.1143)
		(layer "In6.Cu")
		(net "GMI_CPU1_G0_CPU0_G2_TX_DP<4>")
	)
	(arc
		(start 105.766362 -221.807278)
		(mid 105.766363 -221.805881)
		(end 105.766362 -221.804484)
		(width 0.1143)
		(layer "In6.Cu")
		(net "GMI_CPU1_G0_CPU0_G2_TX_DP<4>")
	)
	(arc
		(start 104.578658 -223.891602)
		(mid 104.760237 -223.688735)
		(end 104.8258 -223.424496)
		(width 0.1143)
		(layer "In6.Cu")
		(net "GMI_CPU1_G0_CPU0_G2_TX_DP<4>")
	)
	(arc
		(start 102.700582 -230.370634)
		(mid 102.881234 -230.167889)
		(end 102.946454 -229.90429)
		(width 0.1143)
		(layer "In6.Cu")
		(net "GMI_CPU1_G0_CPU0_G2_TX_DP<4>")
	)
	(arc
		(start 368.832384 -235.251498)
		(mid 368.968299 -235.387987)
		(end 369.018058 -235.574078)
		(width 0.1143)
		(layer "In6.Cu")
		(net "GMI_CPU1_G0_CPU0_G2_TX_DP<4>")
	)
	(arc
		(start 101.222302 -238.308642)
		(mid 101.066374 -238.00435)
		(end 101.222302 -237.700058)
		(width 0.1143)
		(layer "In6.Cu")
		(net "GMI_CPU1_G0_CPU0_G2_TX_DP<4>")
	)
	(arc
		(start 369.333526 -236.079792)
		(mid 369.448202 -236.213126)
		(end 369.489482 -236.384084)
		(width 0.1143)
		(layer "In6.Cu")
		(net "GMI_CPU1_G0_CPU0_G2_TX_DP<4>")
	)
	(arc
		(start 368.79276 -232.679494)
		(mid 368.549433 -233.14406)
		(end 368.79276 -233.608626)
		(width 0.1143)
		(layer "In6.Cu")
		(net "GMI_CPU1_G0_CPU0_G2_TX_DP<4>")
	)
	(arc
		(start 102.703122 -231.988868)
		(mid 102.946449 -231.524302)
		(end 102.703122 -231.059736)
		(width 0.1143)
		(layer "In6.Cu")
		(net "GMI_CPU1_G0_CPU0_G2_TX_DP<4>")
	)
	(arc
		(start 368.392456 -226.359466)
		(mid 368.507883 -226.492842)
		(end 368.549428 -226.664266)
		(width 0.1143)
		(layer "In6.Cu")
		(net "GMI_CPU1_G0_CPU0_G2_TX_DP<4>")
	)
	(arc
		(start 367.139474 -224.234248)
		(mid 367.203989 -224.496467)
		(end 367.382806 -224.698814)
		(width 0.1143)
		(layer "In6.Cu")
		(net "GMI_CPU1_G0_CPU0_G2_TX_DP<4>")
	)
	(arc
		(start 102.632256 -227.778818)
		(mid 102.481871 -227.474526)
		(end 102.632256 -227.170234)
		(width 0.1143)
		(layer "In6.Cu")
		(net "GMI_CPU1_G0_CPU0_G2_TX_DP<4>")
	)
	(arc
		(start 366.670082 -223.424242)
		(mid 366.735683 -223.688461)
		(end 366.917224 -223.891348)
		(width 0.1143)
		(layer "In6.Cu")
		(net "GMI_CPU1_G0_CPU0_G2_TX_DP<4>")
	)
	(arc
		(start 103.416354 -225.854514)
		(mid 103.457609 -225.683543)
		(end 103.57231 -225.550222)
		(width 0.1143)
		(layer "In6.Cu")
		(net "GMI_CPU1_G0_CPU0_G2_TX_DP<4>")
	)
	(arc
		(start 102.703122 -228.749098)
		(mid 102.946449 -228.284532)
		(end 102.703122 -227.819966)
		(width 0.1143)
		(layer "In6.Cu")
		(net "GMI_CPU1_G0_CPU0_G2_TX_DP<4>")
	)
	(arc
		(start 102.703122 -233.60888)
		(mid 102.946449 -233.144314)
		(end 102.703122 -232.679748)
		(width 0.1143)
		(layer "In6.Cu")
		(net "GMI_CPU1_G0_CPU0_G2_TX_DP<4>")
	)
	(arc
		(start 102.946454 -229.90429)
		(mid 102.881939 -229.642071)
		(end 102.703122 -229.439724)
		(width 0.1143)
		(layer "In6.Cu")
		(net "GMI_CPU1_G0_CPU0_G2_TX_DP<4>")
	)
	(arc
		(start 370.202714 -238.349536)
		(mid 369.959387 -238.814102)
		(end 370.202714 -239.278668)
		(width 0.1143)
		(layer "In6.Cu")
		(net "GMI_CPU1_G0_CPU0_G2_TX_DP<4>")
	)
	(arc
		(start 365.72952 -221.80423)
		(mid 365.729518 -221.805627)
		(end 365.72952 -221.807024)
		(width 0.1143)
		(layer "In6.Cu")
		(net "GMI_CPU1_G0_CPU0_G2_TX_DP<4>")
	)
	(arc
		(start 369.959382 -237.19409)
		(mid 370.023897 -237.456309)
		(end 370.202714 -237.658656)
		(width 0.1143)
		(layer "In6.Cu")
		(net "GMI_CPU1_G0_CPU0_G2_TX_DP<4>")
	)
	(arc
		(start 105.296208 -222.61449)
		(mid 105.337525 -222.443774)
		(end 105.452164 -222.310706)
		(width 0.1143)
		(layer "In6.Cu")
		(net "GMI_CPU1_G0_CPU0_G2_TX_DP<4>")
	)
	(arc
		(start 368.832384 -228.771704)
		(mid 369.018022 -229.094394)
		(end 368.83213 -229.416864)
		(width 0.1143)
		(layer "In6.Cu")
		(net "GMI_CPU1_G0_CPU0_G2_TX_DP<4>")
	)
	(arc
		(start 104.8258 -223.424496)
		(mid 104.86685 -223.254046)
		(end 104.980994 -223.120966)
		(width 0.1143)
		(layer "In6.Cu")
		(net "GMI_CPU1_G0_CPU0_G2_TX_DP<4>")
	)
	(arc
		(start 102.477824 -235.574332)
		(mid 102.527552 -235.388223)
		(end 102.663498 -235.251752)
		(width 0.1143)
		(layer "In6.Cu")
		(net "GMI_CPU1_G0_CPU0_G2_TX_DP<4>")
	)
	(arc
		(start 102.4763 -230.69931)
		(mid 102.514268 -230.541924)
		(end 102.61981 -230.419148)
		(width 0.1143)
		(layer "In6.Cu")
		(net "GMI_CPU1_G0_CPU0_G2_TX_DP<4>")
	)
	(arc
		(start 102.630478 -231.017318)
		(mid 102.517071 -230.884429)
		(end 102.4763 -230.71455)
		(width 0.1143)
		(layer "In6.Cu")
		(net "GMI_CPU1_G0_CPU0_G2_TX_DP<4>")
	)
	(arc
		(start 105.52303 -222.26905)
		(mid 105.529026 -222.264897)
		(end 105.534968 -222.260668)
		(width 0.1143)
		(layer "In6.Cu")
		(net "GMI_CPU1_G0_CPU0_G2_TX_DP<4>")
	)
	(arc
		(start 366.199674 -222.614236)
		(mid 366.263846 -222.8758)
		(end 366.441736 -223.07804)
		(width 0.1143)
		(layer "In6.Cu")
		(net "GMI_CPU1_G0_CPU0_G2_TX_DP<4>")
	)
	(arc
		(start 102.703122 -227.129086)
		(mid 102.881935 -226.926736)
		(end 102.946454 -226.66452)
		(width 0.1143)
		(layer "In6.Cu")
		(net "GMI_CPU1_G0_CPU0_G2_TX_DP<4>")
	)
	(arc
		(start 365.72952 -221.807024)
		(mid 365.792483 -222.060648)
		(end 365.960914 -222.260414)
		(width 0.1143)
		(layer "In6.Cu")
		(net "GMI_CPU1_G0_CPU0_G2_TX_DP<4>")
	)
	(arc
		(start 368.79276 -234.299506)
		(mid 368.549433 -234.764072)
		(end 368.79276 -235.228638)
		(width 0.1143)
		(layer "In6.Cu")
		(net "GMI_CPU1_G0_CPU0_G2_TX_DP<4>")
	)
	(arc
		(start 368.876072 -230.418894)
		(mid 368.981628 -230.541663)
		(end 369.019582 -230.699056)
		(width 0.1143)
		(layer "In6.Cu")
		(net "GMI_CPU1_G0_CPU0_G2_TX_DP<4>")
	)
	(arc
		(start 369.019582 -230.714296)
		(mid 368.97882 -230.88418)
		(end 368.865404 -231.017064)
		(width 0.1143)
		(layer "In6.Cu")
		(net "GMI_CPU1_G0_CPU0_G2_TX_DP<4>")
	)
	(arc
		(start 369.80241 -236.88929)
		(mid 369.917837 -237.022666)
		(end 369.959382 -237.19409)
		(width 0.1143)
		(layer "In6.Cu")
		(net "GMI_CPU1_G0_CPU0_G2_TX_DP<4>")
	)
	(arc
		(start 366.043718 -222.310452)
		(mid 366.158337 -222.44353)
		(end 366.199674 -222.614236)
		(width 0.1143)
		(layer "In6.Cu")
		(net "GMI_CPU1_G0_CPU0_G2_TX_DP<4>")
	)
	(arc
		(start 103.886508 -225.044508)
		(mid 103.928057 -224.873086)
		(end 104.04348 -224.739708)
		(width 0.1143)
		(layer "In6.Cu")
		(net "GMI_CPU1_G0_CPU0_G2_TX_DP<4>")
	)
	(arc
		(start 368.863626 -227.16998)
		(mid 369.014011 -227.474272)
		(end 368.863626 -227.778564)
		(width 0.1143)
		(layer "In6.Cu")
		(net "GMI_CPU1_G0_CPU0_G2_TX_DP<4>")
	)
	(arc
		(start 367.609374 -225.044254)
		(mid 367.673889 -225.306473)
		(end 367.852706 -225.50882)
		(width 0.1143)
		(layer "In6.Cu")
		(net "GMI_CPU1_G0_CPU0_G2_TX_DP<4>")
	)
	(arc
		(start 368.863626 -233.649774)
		(mid 369.014011 -233.954066)
		(end 368.863626 -234.258358)
		(width 0.1143)
		(layer "In6.Cu")
		(net "GMI_CPU1_G0_CPU0_G2_TX_DP<4>")
	)
	(arc
		(start 102.946454 -226.66452)
		(mid 102.988003 -226.493098)
		(end 103.103426 -226.35972)
		(width 0.1143)
		(layer "In6.Cu")
		(net "GMI_CPU1_G0_CPU0_G2_TX_DP<4>")
	)
	(arc
		(start 367.452402 -224.739454)
		(mid 367.567829 -224.87283)
		(end 367.609374 -225.044254)
		(width 0.1143)
		(layer "In6.Cu")
		(net "GMI_CPU1_G0_CPU0_G2_TX_DP<4>")
	)
	(arc
		(start 102.0064 -236.384338)
		(mid 102.047655 -236.213367)
		(end 102.162356 -236.080046)
		(width 0.1143)
		(layer "In6.Cu")
		(net "GMI_CPU1_G0_CPU0_G2_TX_DP<4>")
	)
	(arc
		(start 102.632256 -232.6386)
		(mid 102.481871 -232.334308)
		(end 102.632256 -232.030016)
		(width 0.1143)
		(layer "In6.Cu")
		(net "GMI_CPU1_G0_CPU0_G2_TX_DP<4>")
	)
	(arc
		(start 103.643176 -225.509074)
		(mid 103.821989 -225.306724)
		(end 103.886508 -225.044508)
		(width 0.1143)
		(layer "In6.Cu")
		(net "GMI_CPU1_G0_CPU0_G2_TX_DP<4>")
	)
	(arc
		(start 368.863626 -232.029762)
		(mid 369.014011 -232.334054)
		(end 368.863626 -232.638346)
		(width 0.1143)
		(layer "In6.Cu")
		(net "GMI_CPU1_G0_CPU0_G2_TX_DP<4>")
	)
	(arc
		(start 101.073204 -239.554512)
		(mid 101.125253 -239.422993)
		(end 101.222302 -239.32007)
		(width 0.1143)
		(layer "In6.Cu")
		(net "GMI_CPU1_G0_CPU0_G2_TX_DP<4>")
	)
	(arc
		(start 368.549428 -226.664266)
		(mid 368.613943 -226.926485)
		(end 368.79276 -227.128832)
		(width 0.1143)
		(layer "In6.Cu")
		(net "GMI_CPU1_G0_CPU0_G2_TX_DP<4>")
	)
	(arc
		(start 105.054146 -223.078294)
		(mid 105.232119 -222.876097)
		(end 105.296208 -222.61449)
		(width 0.1143)
		(layer "In6.Cu")
		(net "GMI_CPU1_G0_CPU0_G2_TX_DP<4>")
	)
	(arc
		(start 101.763068 -236.848904)
		(mid 101.941881 -236.646554)
		(end 102.0064 -236.384338)
		(width 0.1143)
		(layer "In6.Cu")
		(net "GMI_CPU1_G0_CPU0_G2_TX_DP<4>")
	)
	(arc
		(start 101.5365 -237.194344)
		(mid 101.578049 -237.022922)
		(end 101.693472 -236.889544)
		(width 0.1143)
		(layer "In6.Cu")
		(net "GMI_CPU1_G0_CPU0_G2_TX_DP<4>")
	)
	(arc
		(start 103.173022 -226.31908)
		(mid 103.351835 -226.11673)
		(end 103.416354 -225.854514)
		(width 0.1143)
		(layer "In6.Cu")
		(net "GMI_CPU1_G0_CPU0_G2_TX_DP<4>")
	)
	(arc
		(start 368.79276 -229.43947)
		(mid 368.613947 -229.64182)
		(end 368.549428 -229.904036)
		(width 0.1143)
		(layer "In6.Cu")
		(net "GMI_CPU1_G0_CPU0_G2_TX_DP<4>")
	)
	(arc
		(start 102.230936 -236.040676)
		(mid 102.411735 -235.859912)
		(end 102.477824 -235.61294)
		(width 0.1143)
		(layer "In6.Cu")
		(net "GMI_CPU1_G0_CPU0_G2_TX_DP<4>")
	)
	(arc
		(start 368.079528 -225.85426)
		(mid 368.144043 -226.116479)
		(end 368.32286 -226.318826)
		(width 0.1143)
		(layer "In6.Cu")
		(net "GMI_CPU1_G0_CPU0_G2_TX_DP<4>")
	)
	(arc
		(start 369.489482 -236.384084)
		(mid 369.553997 -236.646303)
		(end 369.732814 -236.84865)
		(width 0.1143)
		(layer "In6.Cu")
		(net "GMI_CPU1_G0_CPU0_G2_TX_DP<4>")
	)
	(arc
		(start 367.923572 -225.549968)
		(mid 368.038248 -225.683302)
		(end 368.079528 -225.85426)
		(width 0.1143)
		(layer "In6.Cu")
		(net "GMI_CPU1_G0_CPU0_G2_TX_DP<4>")
	)
	(arc
		(start 365.960914 -222.260414)
		(mid 365.966856 -222.264644)
		(end 365.972852 -222.268796)
		(width 0.1143)
		(layer "In6.Cu")
		(net "GMI_CPU1_G0_CPU0_G2_TX_DP<4>")
	)
	(arc
		(start 101.293168 -237.65891)
		(mid 101.471981 -237.45656)
		(end 101.5365 -237.194344)
		(width 0.1143)
		(layer "In6.Cu")
		(net "GMI_CPU1_G0_CPU0_G2_TX_DP<4>")
	)
	(arc
		(start 366.514888 -223.120712)
		(mid 366.629041 -223.253788)
		(end 366.670082 -223.424242)
		(width 0.1143)
		(layer "In6.Cu")
		(net "GMI_CPU1_G0_CPU0_G2_TX_DP<4>")
	)
	(arc
		(start 368.79276 -231.059482)
		(mid 368.549433 -231.524048)
		(end 368.79276 -231.988614)
		(width 0.1143)
		(layer "In6.Cu")
		(net "GMI_CPU1_G0_CPU0_G2_TX_DP<4>")
	)
	(arc
		(start 366.982502 -223.929448)
		(mid 367.097929 -224.062824)
		(end 367.139474 -224.234248)
		(width 0.1143)
		(layer "In6.Cu")
		(net "GMI_CPU1_G0_CPU0_G2_TX_DP<4>")
	)
	(arc
		(start 368.549428 -229.904036)
		(mid 368.614664 -230.167627)
		(end 368.7953 -230.37038)
		(width 0.1143)
		(layer "In6.Cu")
		(net "GMI_CPU1_G0_CPU0_G2_TX_DP<4>")
	)
	(arc
		(start 105.534968 -222.260668)
		(mid 105.703297 -222.060849)
		(end 105.766362 -221.807278)
		(width 0.1143)
		(layer "In6.Cu")
		(net "GMI_CPU1_G0_CPU0_G2_TX_DP<4>")
	)
	(arc
		(start 369.018058 -235.612686)
		(mid 369.084151 -235.859656)
		(end 369.264946 -236.040422)
		(width 0.1143)
		(layer "In6.Cu")
		(net "GMI_CPU1_G0_CPU0_G2_TX_DP<4>")
	)
	(arc
		(start 104.356408 -224.234502)
		(mid 104.397957 -224.06308)
		(end 104.51338 -223.929702)
		(width 0.1143)
		(layer "In6.Cu")
		(net "GMI_CPU1_G0_CPU0_G2_TX_DP<4>")
	)
	(arc
		(start 370.27358 -237.699804)
		(mid 370.429508 -238.004096)
		(end 370.27358 -238.308388)
		(width 0.1143)
		(layer "In6.Cu")
		(net "GMI_CPU1_G0_CPU0_G2_TX_DP<4>")
	)
	(arc
		(start 104.113076 -224.699068)
		(mid 104.291889 -224.496718)
		(end 104.356408 -224.234502)
		(width 0.1143)
		(layer "In6.Cu")
		(net "GMI_CPU1_G0_CPU0_G2_TX_DP<4>")
	)
	(arc
		(start 102.663752 -229.417118)
		(mid 102.477988 -229.094648)
		(end 102.663498 -228.771958)
		(width 0.1143)
		(layer "In6.Cu")
		(net "GMI_CPU1_G0_CPU0_G2_TX_DP<4>")
	)
	(arc
		(start 102.703122 -235.228892)
		(mid 102.946449 -234.764326)
		(end 102.703122 -234.29976)
		(width 0.1143)
		(layer "In6.Cu")
		(net "GMI_CPU1_G0_CPU0_G2_TX_DP<4>")
	)
	(arc
		(start 102.632256 -234.258612)
		(mid 102.481871 -233.95432)
		(end 102.632256 -233.650028)
		(width 0.1143)
		(layer "In6.Cu")
		(net "GMI_CPU1_G0_CPU0_G2_TX_DP<4>")
	)
	(arc
		(start 370.27358 -239.319816)
		(mid 370.370715 -239.422685)
		(end 370.422678 -239.554258)
		(width 0.1143)
		(layer "In6.Cu")
		(net "GMI_CPU1_G0_CPU0_G2_TX_DP<4>")
	)
	(arc
		(start 368.79276 -227.819712)
		(mid 368.549433 -228.284278)
		(end 368.79276 -228.748844)
		(width 0.1143)
		(layer "In6.Cu")
		(net "GMI_CPU1_G0_CPU0_G2_TX_DP<4>")
	)
	(segment
		(start 101.907848 -241.510312)
		(end 101.440996 -241.244374)
		(width 0.12954)
		(layer "F.Cu")
		(net "GMI_CPU1_G0_CPU0_G2_TX_DP<3>")
	)
	(segment
		(start 369.588034 -241.510058)
		(end 370.054886 -241.24412)
		(width 0.12954)
		(layer "F.Cu")
		(net "GMI_CPU1_G0_CPU0_G2_TX_DP<3>")
	)
	(segment
		(start 117.910356 -204.231494)
		(end 118.37543 -203.874624)
		(width 0.14224)
		(layer "In6.Cu")
		(net "GMI_CPU1_G0_CPU0_G2_TX_DP<3>")
	)
	(segment
		(start 100.319586 -239.29848)
		(end 100.353114 -239.278922)
		(width 0.1143)
		(layer "In6.Cu")
		(net "GMI_CPU1_G0_CPU0_G2_TX_DP<3>")
	)
	(segment
		(start 323.5071 -186.798204)
		(end 323.821806 -187.074556)
		(width 0.14224)
		(layer "In6.Cu")
		(net "GMI_CPU1_G0_CPU0_G2_TX_DP<3>")
	)
	(segment
		(start 371.181884 -238.326676)
		(end 371.180868 -238.327184)
		(width 0.1143)
		(layer "In6.Cu")
		(net "GMI_CPU1_G0_CPU0_G2_TX_DP<3>")
	)
	(segment
		(start 100.313236 -238.326422)
		(end 100.282248 -238.308642)
		(width 0.1143)
		(layer "In6.Cu")
		(net "GMI_CPU1_G0_CPU0_G2_TX_DP<3>")
	)
	(segment
		(start 323.833744 -187.257436)
		(end 324.148958 -187.534296)
		(width 0.14224)
		(layer "In6.Cu")
		(net "GMI_CPU1_G0_CPU0_G2_TX_DP<3>")
	)
	(segment
		(start 103.103426 -224.739708)
		(end 103.133906 -224.721928)
		(width 0.1143)
		(layer "In6.Cu")
		(net "GMI_CPU1_G0_CPU0_G2_TX_DP<3>")
	)
	(segment
		(start 322.603368 -186.412632)
		(end 322.964048 -186.6265)
		(width 0.14224)
		(layer "In6.Cu")
		(net "GMI_CPU1_G0_CPU0_G2_TX_DP<3>")
	)
	(segment
		(start 370.202714 -236.038644)
		(end 370.23929 -236.05998)
		(width 0.1143)
		(layer "In6.Cu")
		(net "GMI_CPU1_G0_CPU0_G2_TX_DP<3>")
	)
	(segment
		(start 101.254052 -236.061758)
		(end 101.255068 -236.06125)
		(width 0.1143)
		(layer "In6.Cu")
		(net "GMI_CPU1_G0_CPU0_G2_TX_DP<3>")
	)
	(segment
		(start 369.77193 -231.036622)
		(end 369.732814 -231.059482)
		(width 0.1143)
		(layer "In6.Cu")
		(net "GMI_CPU1_G0_CPU0_G2_TX_DP<3>")
	)
	(segment
		(start 101.222302 -236.080046)
		(end 101.25329 -236.062266)
		(width 0.1143)
		(layer "In6.Cu")
		(net "GMI_CPU1_G0_CPU0_G2_TX_DP<3>")
	)
	(segment
		(start 100.783898 -240.756948)
		(end 100.753418 -240.739168)
		(width 0.1143)
		(layer "In6.Cu")
		(net "GMI_CPU1_G0_CPU0_G2_TX_DP<3>")
	)
	(segment
		(start 101.693472 -235.269532)
		(end 101.723952 -235.251752)
		(width 0.1143)
		(layer "In6.Cu")
		(net "GMI_CPU1_G0_CPU0_G2_TX_DP<3>")
	)
	(segment
		(start 105.669334 -216.714578)
		(end 105.829862 -216.327228)
		(width 0.14224)
		(layer "In6.Cu")
		(net "GMI_CPU1_G0_CPU0_G2_TX_DP<3>")
	)
	(segment
		(start 101.25329 -236.062266)
		(end 101.254052 -236.061758)
		(width 0.1143)
		(layer "In6.Cu")
		(net "GMI_CPU1_G0_CPU0_G2_TX_DP<3>")
	)
	(segment
		(start 162.80003 -178.222402)
		(end 167.029892 -177.101754)
		(width 0.14224)
		(layer "In6.Cu")
		(net "GMI_CPU1_G0_CPU0_G2_TX_DP<3>")
	)
	(segment
		(start 369.732814 -227.128832)
		(end 369.80241 -227.169472)
		(width 0.1143)
		(layer "In6.Cu")
		(net "GMI_CPU1_G0_CPU0_G2_TX_DP<3>")
	)
	(segment
		(start 100.823014 -240.779808)
		(end 100.783898 -240.756948)
		(width 0.1143)
		(layer "In6.Cu")
		(net "GMI_CPU1_G0_CPU0_G2_TX_DP<3>")
	)
	(segment
		(start 371.142768 -239.278668)
		(end 371.180868 -239.30102)
		(width 0.1143)
		(layer "In6.Cu")
		(net "GMI_CPU1_G0_CPU0_G2_TX_DP<3>")
	)
	(segment
		(start 234.970066 -177.498502)
		(end 302.91024 -177.894996)
		(width 0.14224)
		(layer "In6.Cu")
		(net "GMI_CPU1_G0_CPU0_G2_TX_DP<3>")
	)
	(segment
		(start 370.352828 -241.24412)
		(end 370.054886 -241.24412)
		(width 0.1143)
		(layer "In6.Cu")
		(net "GMI_CPU1_G0_CPU0_G2_TX_DP<3>")
	)
	(segment
		(start 366.669828 -221.2467)
		(end 366.669574 -221.246954)
		(width 0.1143)
		(layer "In6.Cu")
		(net "GMI_CPU1_G0_CPU0_G2_TX_DP<3>")
	)
	(segment
		(start 101.723952 -231.036876)
		(end 101.69144 -231.01808)
		(width 0.1143)
		(layer "In6.Cu")
		(net "GMI_CPU1_G0_CPU0_G2_TX_DP<3>")
	)
	(segment
		(start 101.723952 -228.771958)
		(end 101.763068 -228.749098)
		(width 0.1143)
		(layer "In6.Cu")
		(net "GMI_CPU1_G0_CPU0_G2_TX_DP<3>")
	)
	(segment
		(start 117.015768 -205.081378)
		(end 117.039644 -204.899514)
		(width 0.14224)
		(layer "In6.Cu")
		(net "GMI_CPU1_G0_CPU0_G2_TX_DP<3>")
	)
	(segment
		(start 371.180868 -239.30102)
		(end 371.181884 -239.301528)
		(width 0.1143)
		(layer "In6.Cu")
		(net "GMI_CPU1_G0_CPU0_G2_TX_DP<3>")
	)
	(segment
		(start 366.915446 -222.270574)
		(end 366.951768 -222.291656)
		(width 0.1143)
		(layer "In6.Cu")
		(net "GMI_CPU1_G0_CPU0_G2_TX_DP<3>")
	)
	(segment
		(start 101.723952 -232.656888)
		(end 101.693472 -232.639108)
		(width 0.1143)
		(layer "In6.Cu")
		(net "GMI_CPU1_G0_CPU0_G2_TX_DP<3>")
	)
	(segment
		(start 322.558156 -186.234832)
		(end 322.603368 -186.412632)
		(width 0.14224)
		(layer "In6.Cu")
		(net "GMI_CPU1_G0_CPU0_G2_TX_DP<3>")
	)
	(segment
		(start 371.179344 -238.3282)
		(end 371.142768 -238.349536)
		(width 0.1143)
		(layer "In6.Cu")
		(net "GMI_CPU1_G0_CPU0_G2_TX_DP<3>")
	)
	(segment
		(start 101.763068 -229.439724)
		(end 101.723952 -229.416864)
		(width 0.1143)
		(layer "In6.Cu")
		(net "GMI_CPU1_G0_CPU0_G2_TX_DP<3>")
	)
	(segment
		(start 116.683028 -205.336648)
		(end 117.015768 -205.081378)
		(width 0.14224)
		(layer "In6.Cu")
		(net "GMI_CPU1_G0_CPU0_G2_TX_DP<3>")
	)
	(segment
		(start 104.871774 -221.064836)
		(end 104.871774 -218.301316)
		(width 0.14224)
		(layer "In6.Cu")
		(net "GMI_CPU1_G0_CPU0_G2_TX_DP<3>")
	)
	(segment
		(start 100.282248 -239.32007)
		(end 100.313236 -239.30229)
		(width 0.1143)
		(layer "In6.Cu")
		(net "GMI_CPU1_G0_CPU0_G2_TX_DP<3>")
	)
	(segment
		(start 100.313998 -238.32693)
		(end 100.313236 -238.326422)
		(width 0.1143)
		(layer "In6.Cu")
		(net "GMI_CPU1_G0_CPU0_G2_TX_DP<3>")
	)
	(segment
		(start 105.759758 -216.15781)
		(end 106.055922 -215.442292)
		(width 0.14224)
		(layer "In6.Cu")
		(net "GMI_CPU1_G0_CPU0_G2_TX_DP<3>")
	)
	(segment
		(start 371.182646 -237.682024)
		(end 371.213634 -237.699804)
		(width 0.1143)
		(layer "In6.Cu")
		(net "GMI_CPU1_G0_CPU0_G2_TX_DP<3>")
	)
	(segment
		(start 101.693472 -233.64952)
		(end 101.723952 -233.63174)
		(width 0.1143)
		(layer "In6.Cu")
		(net "GMI_CPU1_G0_CPU0_G2_TX_DP<3>")
	)
	(segment
		(start 100.353114 -238.34979)
		(end 100.346256 -238.345726)
		(width 0.1143)
		(layer "In6.Cu")
		(net "GMI_CPU1_G0_CPU0_G2_TX_DP<3>")
	)
	(segment
		(start 368.79276 -225.50882)
		(end 368.83086 -225.531172)
		(width 0.1143)
		(layer "In6.Cu")
		(net "GMI_CPU1_G0_CPU0_G2_TX_DP<3>")
	)
	(segment
		(start 366.624108 -221.081346)
		(end 366.624108 -221.09303)
		(width 0.1143)
		(layer "In6.Cu")
		(net "GMI_CPU1_G0_CPU0_G2_TX_DP<3>")
	)
	(segment
		(start 368.83086 -225.531172)
		(end 368.831876 -225.53168)
		(width 0.1143)
		(layer "In6.Cu")
		(net "GMI_CPU1_G0_CPU0_G2_TX_DP<3>")
	)
	(segment
		(start 369.80241 -234.258866)
		(end 369.732814 -234.299506)
		(width 0.1143)
		(layer "In6.Cu")
		(net "GMI_CPU1_G0_CPU0_G2_TX_DP<3>")
	)
	(segment
		(start 371.180868 -238.327184)
		(end 371.179344 -238.3282)
		(width 0.1143)
		(layer "In6.Cu")
		(net "GMI_CPU1_G0_CPU0_G2_TX_DP<3>")
	)
	(segment
		(start 371.180868 -237.681008)
		(end 371.181884 -237.681516)
		(width 0.1143)
		(layer "In6.Cu")
		(net "GMI_CPU1_G0_CPU0_G2_TX_DP<3>")
	)
	(segment
		(start 101.723952 -227.797106)
		(end 101.693472 -227.779326)
		(width 0.1143)
		(layer "In6.Cu")
		(net "GMI_CPU1_G0_CPU0_G2_TX_DP<3>")
	)
	(segment
		(start 366.669828 -221.13875)
		(end 366.669828 -221.2467)
		(width 0.1143)
		(layer "In6.Cu")
		(net "GMI_CPU1_G0_CPU0_G2_TX_DP<3>")
	)
	(segment
		(start 115.630706 -205.980792)
		(end 115.812316 -206.004668)
		(width 0.14224)
		(layer "In6.Cu")
		(net "GMI_CPU1_G0_CPU0_G2_TX_DP<3>")
	)
	(segment
		(start 100.346256 -238.345726)
		(end 100.345494 -238.345218)
		(width 0.1143)
		(layer "In6.Cu")
		(net "GMI_CPU1_G0_CPU0_G2_TX_DP<3>")
	)
	(segment
		(start 103.133906 -224.721928)
		(end 103.173022 -224.699068)
		(width 0.1143)
		(layer "In6.Cu")
		(net "GMI_CPU1_G0_CPU0_G2_TX_DP<3>")
	)
	(segment
		(start 371.213634 -239.319816)
		(end 371.233446 -239.33404)
		(width 0.1143)
		(layer "In6.Cu")
		(net "GMI_CPU1_G0_CPU0_G2_TX_DP<3>")
	)
	(segment
		(start 323.821806 -187.074556)
		(end 323.833744 -187.257436)
		(width 0.14224)
		(layer "In6.Cu")
		(net "GMI_CPU1_G0_CPU0_G2_TX_DP<3>")
	)
	(segment
		(start 234.97032 -177.498502)
		(end 234.970066 -177.498502)
		(width 0.14224)
		(layer "In6.Cu")
		(net "GMI_CPU1_G0_CPU0_G2_TX_DP<3>")
	)
	(segment
		(start 105.0798 -217.798904)
		(end 105.0798 -217.79865)
		(width 0.14224)
		(layer "In6.Cu")
		(net "GMI_CPU1_G0_CPU0_G2_TX_DP<3>")
	)
	(segment
		(start 369.732814 -228.748844)
		(end 369.80241 -228.789484)
		(width 0.1143)
		(layer "In6.Cu")
		(net "GMI_CPU1_G0_CPU0_G2_TX_DP<3>")
	)
	(segment
		(start 356.372668 -207.965548)
		(end 361.20451 -211.81949)
		(width 0.14224)
		(layer "In6.Cu")
		(net "GMI_CPU1_G0_CPU0_G2_TX_DP<3>")
	)
	(segment
		(start 321.660012 -185.852308)
		(end 322.020438 -186.066176)
		(width 0.14224)
		(layer "In6.Cu")
		(net "GMI_CPU1_G0_CPU0_G2_TX_DP<3>")
	)
	(segment
		(start 101.723952 -229.416864)
		(end 101.69144 -229.398068)
		(width 0.1143)
		(layer "In6.Cu")
		(net "GMI_CPU1_G0_CPU0_G2_TX_DP<3>")
	)
	(segment
		(start 322.964048 -186.6265)
		(end 323.141594 -186.581288)
		(width 0.14224)
		(layer "In6.Cu")
		(net "GMI_CPU1_G0_CPU0_G2_TX_DP<3>")
	)
	(segment
		(start 102.0064 -226.66452)
		(end 102.006146 -226.66452)
		(width 0.1143)
		(layer "In6.Cu")
		(net "GMI_CPU1_G0_CPU0_G2_TX_DP<3>")
	)
	(segment
		(start 367.387632 -223.082358)
		(end 367.45672 -223.12249)
		(width 0.1143)
		(layer "In6.Cu")
		(net "GMI_CPU1_G0_CPU0_G2_TX_DP<3>")
	)
	(segment
		(start 100.313236 -237.682278)
		(end 100.313998 -237.68177)
		(width 0.1143)
		(layer "In6.Cu")
		(net "GMI_CPU1_G0_CPU0_G2_TX_DP<3>")
	)
	(segment
		(start 104.826054 -221.139004)
		(end 104.871774 -221.093284)
		(width 0.1143)
		(layer "In6.Cu")
		(net "GMI_CPU1_G0_CPU0_G2_TX_DP<3>")
	)
	(segment
		(start 366.951768 -222.291656)
		(end 366.978692 -222.30715)
		(width 0.1143)
		(layer "In6.Cu")
		(net "GMI_CPU1_G0_CPU0_G2_TX_DP<3>")
	)
	(segment
		(start 102.661212 -225.533712)
		(end 102.663244 -225.532442)
		(width 0.1143)
		(layer "In6.Cu")
		(net "GMI_CPU1_G0_CPU0_G2_TX_DP<3>")
	)
	(segment
		(start 369.732814 -233.608626)
		(end 369.80241 -233.649266)
		(width 0.1143)
		(layer "In6.Cu")
		(net "GMI_CPU1_G0_CPU0_G2_TX_DP<3>")
	)
	(segment
		(start 100.313236 -239.946434)
		(end 100.282248 -239.928654)
		(width 0.1143)
		(layer "In6.Cu")
		(net "GMI_CPU1_G0_CPU0_G2_TX_DP<3>")
	)
	(segment
		(start 101.763068 -232.679748)
		(end 101.723952 -232.656888)
		(width 0.1143)
		(layer "In6.Cu")
		(net "GMI_CPU1_G0_CPU0_G2_TX_DP<3>")
	)
	(segment
		(start 100.353114 -239.969802)
		(end 100.346256 -239.965738)
		(width 0.1143)
		(layer "In6.Cu")
		(net "GMI_CPU1_G0_CPU0_G2_TX_DP<3>")
	)
	(segment
		(start 102.162102 -226.360482)
		(end 102.19055 -226.343718)
		(width 0.1143)
		(layer "In6.Cu")
		(net "GMI_CPU1_G0_CPU0_G2_TX_DP<3>")
	)
	(segment
		(start 100.346256 -239.965738)
		(end 100.345494 -239.96523)
		(width 0.1143)
		(layer "In6.Cu")
		(net "GMI_CPU1_G0_CPU0_G2_TX_DP<3>")
	)
	(segment
		(start 103.57231 -223.93021)
		(end 103.60406 -223.911922)
		(width 0.1143)
		(layer "In6.Cu")
		(net "GMI_CPU1_G0_CPU0_G2_TX_DP<3>")
	)
	(segment
		(start 101.693472 -227.169726)
		(end 101.723952 -227.151946)
		(width 0.1143)
		(layer "In6.Cu")
		(net "GMI_CPU1_G0_CPU0_G2_TX_DP<3>")
	)
	(segment
		(start 104.51719 -222.307404)
		(end 104.544114 -222.29191)
		(width 0.1143)
		(layer "In6.Cu")
		(net "GMI_CPU1_G0_CPU0_G2_TX_DP<3>")
	)
	(segment
		(start 115.812316 -206.004668)
		(end 116.145056 -205.749398)
		(width 0.14224)
		(layer "In6.Cu")
		(net "GMI_CPU1_G0_CPU0_G2_TX_DP<3>")
	)
	(segment
		(start 167.029892 -177.101754)
		(end 234.97032 -177.498502)
		(width 0.14224)
		(layer "In6.Cu")
		(net "GMI_CPU1_G0_CPU0_G2_TX_DP<3>")
	)
	(segment
		(start 366.624108 -218.637104)
		(end 366.624108 -221.081346)
		(width 0.14224)
		(layer "In6.Cu")
		(net "GMI_CPU1_G0_CPU0_G2_TX_DP<3>")
	)
	(segment
		(start 102.665022 -225.531426)
		(end 102.703122 -225.509074)
		(width 0.1143)
		(layer "In6.Cu")
		(net "GMI_CPU1_G0_CPU0_G2_TX_DP<3>")
	)
	(segment
		(start 369.735354 -230.37038)
		(end 369.80241 -230.409496)
		(width 0.1143)
		(layer "In6.Cu")
		(net "GMI_CPU1_G0_CPU0_G2_TX_DP<3>")
	)
	(segment
		(start 101.723952 -235.251752)
		(end 101.763068 -235.228892)
		(width 0.1143)
		(layer "In6.Cu")
		(net "GMI_CPU1_G0_CPU0_G2_TX_DP<3>")
	)
	(segment
		(start 370.242592 -236.062012)
		(end 370.243862 -236.062774)
		(width 0.1143)
		(layer "In6.Cu")
		(net "GMI_CPU1_G0_CPU0_G2_TX_DP<3>")
	)
	(segment
		(start 368.831876 -225.53168)
		(end 368.832638 -225.532188)
		(width 0.1143)
		(layer "In6.Cu")
		(net "GMI_CPU1_G0_CPU0_G2_TX_DP<3>")
	)
	(segment
		(start 102.664006 -225.531934)
		(end 102.665022 -225.531426)
		(width 0.1143)
		(layer "In6.Cu")
		(net "GMI_CPU1_G0_CPU0_G2_TX_DP<3>")
	)
	(segment
		(start 369.732814 -231.988614)
		(end 369.80241 -232.029254)
		(width 0.1143)
		(layer "In6.Cu")
		(net "GMI_CPU1_G0_CPU0_G2_TX_DP<3>")
	)
	(segment
		(start 322.197984 -186.020964)
		(end 322.558156 -186.234832)
		(width 0.14224)
		(layer "In6.Cu")
		(net "GMI_CPU1_G0_CPU0_G2_TX_DP<3>")
	)
	(segment
		(start 361.20451 -211.81949)
		(end 365.63554 -216.25052)
		(width 0.14224)
		(layer "In6.Cu")
		(net "GMI_CPU1_G0_CPU0_G2_TX_DP<3>")
	)
	(segment
		(start 100.313998 -239.301782)
		(end 100.315014 -239.301274)
		(width 0.1143)
		(layer "In6.Cu")
		(net "GMI_CPU1_G0_CPU0_G2_TX_DP<3>")
	)
	(segment
		(start 101.440996 -241.244374)
		(end 101.143054 -241.244374)
		(width 0.1143)
		(layer "In6.Cu")
		(net "GMI_CPU1_G0_CPU0_G2_TX_DP<3>")
	)
	(segment
		(start 100.282248 -239.928654)
		(end 100.262436 -239.91443)
		(width 0.1143)
		(layer "In6.Cu")
		(net "GMI_CPU1_G0_CPU0_G2_TX_DP<3>")
	)
	(segment
		(start 368.832638 -225.532188)
		(end 368.83467 -225.533458)
		(width 0.1143)
		(layer "In6.Cu")
		(net "GMI_CPU1_G0_CPU0_G2_TX_DP<3>")
	)
	(segment
		(start 101.763068 -227.819966)
		(end 101.723952 -227.797106)
		(width 0.1143)
		(layer "In6.Cu")
		(net "GMI_CPU1_G0_CPU0_G2_TX_DP<3>")
	)
	(segment
		(start 103.60406 -223.911922)
		(end 103.64597 -223.887538)
		(width 0.1143)
		(layer "In6.Cu")
		(net "GMI_CPU1_G0_CPU0_G2_TX_DP<3>")
	)
	(segment
		(start 116.168932 -205.567788)
		(end 116.501164 -205.312772)
		(width 0.14224)
		(layer "In6.Cu")
		(net "GMI_CPU1_G0_CPU0_G2_TX_DP<3>")
	)
	(segment
		(start 367.849912 -223.887284)
		(end 367.891822 -223.911668)
		(width 0.1143)
		(layer "In6.Cu")
		(net "GMI_CPU1_G0_CPU0_G2_TX_DP<3>")
	)
	(segment
		(start 101.255068 -236.06125)
		(end 101.256592 -236.060234)
		(width 0.1143)
		(layer "In6.Cu")
		(net "GMI_CPU1_G0_CPU0_G2_TX_DP<3>")
	)
	(segment
		(start 302.91024 -177.894996)
		(end 307.03012 -177.894996)
		(width 0.14224)
		(layer "In6.Cu")
		(net "GMI_CPU1_G0_CPU0_G2_TX_DP<3>")
	)
	(segment
		(start 100.345494 -238.345218)
		(end 100.313998 -238.32693)
		(width 0.1143)
		(layer "In6.Cu")
		(net "GMI_CPU1_G0_CPU0_G2_TX_DP<3>")
	)
	(segment
		(start 371.181884 -237.681516)
		(end 371.182646 -237.682024)
		(width 0.1143)
		(layer "In6.Cu")
		(net "GMI_CPU1_G0_CPU0_G2_TX_DP<3>")
	)
	(segment
		(start 324.148958 -187.534296)
		(end 324.331838 -187.522358)
		(width 0.14224)
		(layer "In6.Cu")
		(net "GMI_CPU1_G0_CPU0_G2_TX_DP<3>")
	)
	(segment
		(start 100.315014 -237.681262)
		(end 100.353114 -237.65891)
		(width 0.1143)
		(layer "In6.Cu")
		(net "GMI_CPU1_G0_CPU0_G2_TX_DP<3>")
	)
	(segment
		(start 370.240814 -236.060996)
		(end 370.24183 -236.061504)
		(width 0.1143)
		(layer "In6.Cu")
		(net "GMI_CPU1_G0_CPU0_G2_TX_DP<3>")
	)
	(segment
		(start 365.63554 -216.25052)
		(end 366.624108 -218.637104)
		(width 0.14224)
		(layer "In6.Cu")
		(net "GMI_CPU1_G0_CPU0_G2_TX_DP<3>")
	)
	(segment
		(start 324.331838 -187.522358)
		(end 325.541894 -188.585094)
		(width 0.14224)
		(layer "In6.Cu")
		(net "GMI_CPU1_G0_CPU0_G2_TX_DP<3>")
	)
	(segment
		(start 101.693472 -230.40975)
		(end 101.760528 -230.370634)
		(width 0.1143)
		(layer "In6.Cu")
		(net "GMI_CPU1_G0_CPU0_G2_TX_DP<3>")
	)
	(segment
		(start 371.233446 -239.914176)
		(end 371.213634 -239.9284)
		(width 0.1143)
		(layer "In6.Cu")
		(net "GMI_CPU1_G0_CPU0_G2_TX_DP<3>")
	)
	(segment
		(start 370.742464 -240.738914)
		(end 370.672868 -240.779554)
		(width 0.1143)
		(layer "In6.Cu")
		(net "GMI_CPU1_G0_CPU0_G2_TX_DP<3>")
	)
	(segment
		(start 100.282248 -237.700058)
		(end 100.313236 -237.682278)
		(width 0.1143)
		(layer "In6.Cu")
		(net "GMI_CPU1_G0_CPU0_G2_TX_DP<3>")
	)
	(segment
		(start 367.891822 -223.911668)
		(end 367.923572 -223.929956)
		(width 0.1143)
		(layer "In6.Cu")
		(net "GMI_CPU1_G0_CPU0_G2_TX_DP<3>")
	)
	(segment
		(start 371.213634 -238.308388)
		(end 371.182646 -238.326168)
		(width 0.1143)
		(layer "In6.Cu")
		(net "GMI_CPU1_G0_CPU0_G2_TX_DP<3>")
	)
	(segment
		(start 371.213634 -239.9284)
		(end 371.182646 -239.94618)
		(width 0.1143)
		(layer "In6.Cu")
		(net "GMI_CPU1_G0_CPU0_G2_TX_DP<3>")
	)
	(segment
		(start 102.663244 -225.532442)
		(end 102.664006 -225.531934)
		(width 0.1143)
		(layer "In6.Cu")
		(net "GMI_CPU1_G0_CPU0_G2_TX_DP<3>")
	)
	(segment
		(start 371.182646 -239.94618)
		(end 371.181884 -239.946688)
		(width 0.1143)
		(layer "In6.Cu")
		(net "GMI_CPU1_G0_CPU0_G2_TX_DP<3>")
	)
	(segment
		(start 105.829862 -216.327228)
		(end 105.759758 -216.15781)
		(width 0.14224)
		(layer "In6.Cu")
		(net "GMI_CPU1_G0_CPU0_G2_TX_DP<3>")
	)
	(segment
		(start 115.14455 -206.353664)
		(end 115.630706 -205.980792)
		(width 0.14224)
		(layer "In6.Cu")
		(net "GMI_CPU1_G0_CPU0_G2_TX_DP<3>")
	)
	(segment
		(start 368.83467 -225.533458)
		(end 368.836194 -225.533966)
		(width 0.1143)
		(layer "In6.Cu")
		(net "GMI_CPU1_G0_CPU0_G2_TX_DP<3>")
	)
	(segment
		(start 101.693472 -228.789738)
		(end 101.723952 -228.771958)
		(width 0.1143)
		(layer "In6.Cu")
		(net "GMI_CPU1_G0_CPU0_G2_TX_DP<3>")
	)
	(segment
		(start 369.489736 -226.664266)
		(end 369.489482 -226.664266)
		(width 0.1143)
		(layer "In6.Cu")
		(net "GMI_CPU1_G0_CPU0_G2_TX_DP<3>")
	)
	(segment
		(start 371.182646 -239.302036)
		(end 371.213634 -239.319816)
		(width 0.1143)
		(layer "In6.Cu")
		(net "GMI_CPU1_G0_CPU0_G2_TX_DP<3>")
	)
	(segment
		(start 370.24183 -236.061504)
		(end 370.242592 -236.062012)
		(width 0.1143)
		(layer "In6.Cu")
		(net "GMI_CPU1_G0_CPU0_G2_TX_DP<3>")
	)
	(segment
		(start 371.182646 -238.326168)
		(end 371.181884 -238.326676)
		(width 0.1143)
		(layer "In6.Cu")
		(net "GMI_CPU1_G0_CPU0_G2_TX_DP<3>")
	)
	(segment
		(start 371.179344 -239.948212)
		(end 371.142768 -239.969548)
		(width 0.1143)
		(layer "In6.Cu")
		(net "GMI_CPU1_G0_CPU0_G2_TX_DP<3>")
	)
	(segment
		(start 100.262436 -239.334294)
		(end 100.282248 -239.32007)
		(width 0.1143)
		(layer "In6.Cu")
		(net "GMI_CPU1_G0_CPU0_G2_TX_DP<3>")
	)
	(segment
		(start 323.141594 -186.581288)
		(end 323.5071 -186.798204)
		(width 0.14224)
		(layer "In6.Cu")
		(net "GMI_CPU1_G0_CPU0_G2_TX_DP<3>")
	)
	(segment
		(start 369.80241 -232.638854)
		(end 369.732814 -232.679494)
		(width 0.1143)
		(layer "In6.Cu")
		(net "GMI_CPU1_G0_CPU0_G2_TX_DP<3>")
	)
	(segment
		(start 368.32286 -224.698814)
		(end 368.392456 -224.739454)
		(width 0.1143)
		(layer "In6.Cu")
		(net "GMI_CPU1_G0_CPU0_G2_TX_DP<3>")
	)
	(segment
		(start 100.753418 -236.889544)
		(end 100.783898 -236.871764)
		(width 0.1143)
		(layer "In6.Cu")
		(net "GMI_CPU1_G0_CPU0_G2_TX_DP<3>")
	)
	(segment
		(start 369.804442 -229.397814)
		(end 369.77193 -229.41661)
		(width 0.1143)
		(layer "In6.Cu")
		(net "GMI_CPU1_G0_CPU0_G2_TX_DP<3>")
	)
	(segment
		(start 105.0798 -217.79865)
		(end 105.249218 -217.728546)
		(width 0.14224)
		(layer "In6.Cu")
		(net "GMI_CPU1_G0_CPU0_G2_TX_DP<3>")
	)
	(segment
		(start 104.871774 -218.301316)
		(end 105.0798 -217.798904)
		(width 0.14224)
		(layer "In6.Cu")
		(net "GMI_CPU1_G0_CPU0_G2_TX_DP<3>")
	)
	(segment
		(start 371.181884 -239.946688)
		(end 371.180868 -239.947196)
		(width 0.1143)
		(layer "In6.Cu")
		(net "GMI_CPU1_G0_CPU0_G2_TX_DP<3>")
	)
	(segment
		(start 371.142768 -237.658656)
		(end 371.180868 -237.681008)
		(width 0.1143)
		(layer "In6.Cu")
		(net "GMI_CPU1_G0_CPU0_G2_TX_DP<3>")
	)
	(segment
		(start 325.541894 -188.585094)
		(end 356.372668 -207.965548)
		(width 0.14224)
		(layer "In6.Cu")
		(net "GMI_CPU1_G0_CPU0_G2_TX_DP<3>")
	)
	(segment
		(start 104.074976 -223.101916)
		(end 104.10825 -223.082612)
		(width 0.1143)
		(layer "In6.Cu")
		(net "GMI_CPU1_G0_CPU0_G2_TX_DP<3>")
	)
	(segment
		(start 104.826054 -221.246954)
		(end 104.826054 -221.139004)
		(width 0.1143)
		(layer "In6.Cu")
		(net "GMI_CPU1_G0_CPU0_G2_TX_DP<3>")
	)
	(segment
		(start 101.723952 -233.63174)
		(end 101.763068 -233.60888)
		(width 0.1143)
		(layer "In6.Cu")
		(net "GMI_CPU1_G0_CPU0_G2_TX_DP<3>")
	)
	(segment
		(start 101.723952 -232.011728)
		(end 101.763068 -231.988868)
		(width 0.1143)
		(layer "In6.Cu")
		(net "GMI_CPU1_G0_CPU0_G2_TX_DP<3>")
	)
	(segment
		(start 100.783898 -236.871764)
		(end 100.823014 -236.848904)
		(width 0.1143)
		(layer "In6.Cu")
		(net "GMI_CPU1_G0_CPU0_G2_TX_DP<3>")
	)
	(segment
		(start 369.732814 -235.228638)
		(end 369.80241 -235.269278)
		(width 0.1143)
		(layer "In6.Cu")
		(net "GMI_CPU1_G0_CPU0_G2_TX_DP<3>")
	)
	(segment
		(start 116.145056 -205.749398)
		(end 116.168932 -205.567788)
		(width 0.14224)
		(layer "In6.Cu")
		(net "GMI_CPU1_G0_CPU0_G2_TX_DP<3>")
	)
	(segment
		(start 104.826308 -221.804484)
		(end 104.826308 -221.247208)
		(width 0.1143)
		(layer "In6.Cu")
		(net "GMI_CPU1_G0_CPU0_G2_TX_DP<3>")
	)
	(segment
		(start 100.313998 -237.68177)
		(end 100.315014 -237.681262)
		(width 0.1143)
		(layer "In6.Cu")
		(net "GMI_CPU1_G0_CPU0_G2_TX_DP<3>")
	)
	(segment
		(start 101.723952 -234.2769)
		(end 101.693472 -234.25912)
		(width 0.1143)
		(layer "In6.Cu")
		(net "GMI_CPU1_G0_CPU0_G2_TX_DP<3>")
	)
	(segment
		(start 116.501164 -205.312772)
		(end 116.683028 -205.336648)
		(width 0.14224)
		(layer "In6.Cu")
		(net "GMI_CPU1_G0_CPU0_G2_TX_DP<3>")
	)
	(segment
		(start 371.181884 -239.301528)
		(end 371.182646 -239.302036)
		(width 0.1143)
		(layer "In6.Cu")
		(net "GMI_CPU1_G0_CPU0_G2_TX_DP<3>")
	)
	(segment
		(start 370.672868 -236.84865)
		(end 370.742464 -236.88929)
		(width 0.1143)
		(layer "In6.Cu")
		(net "GMI_CPU1_G0_CPU0_G2_TX_DP<3>")
	)
	(segment
		(start 104.871774 -221.093284)
		(end 104.871774 -221.064836)
		(width 0.1143)
		(layer "In6.Cu")
		(net "GMI_CPU1_G0_CPU0_G2_TX_DP<3>")
	)
	(segment
		(start 101.723952 -227.151946)
		(end 101.763068 -227.129086)
		(width 0.1143)
		(layer "In6.Cu")
		(net "GMI_CPU1_G0_CPU0_G2_TX_DP<3>")
	)
	(segment
		(start 307.03012 -177.894996)
		(end 309.790084 -178.652678)
		(width 0.14224)
		(layer "In6.Cu")
		(net "GMI_CPU1_G0_CPU0_G2_TX_DP<3>")
	)
	(segment
		(start 322.020438 -186.066176)
		(end 322.197984 -186.020964)
		(width 0.14224)
		(layer "In6.Cu")
		(net "GMI_CPU1_G0_CPU0_G2_TX_DP<3>")
	)
	(segment
		(start 118.37543 -203.874624)
		(end 162.80003 -178.222402)
		(width 0.14224)
		(layer "In6.Cu")
		(net "GMI_CPU1_G0_CPU0_G2_TX_DP<3>")
	)
	(segment
		(start 105.409746 -217.341196)
		(end 105.339642 -217.171778)
		(width 0.14224)
		(layer "In6.Cu")
		(net "GMI_CPU1_G0_CPU0_G2_TX_DP<3>")
	)
	(segment
		(start 117.55374 -204.668374)
		(end 117.88648 -204.413104)
		(width 0.14224)
		(layer "In6.Cu")
		(net "GMI_CPU1_G0_CPU0_G2_TX_DP<3>")
	)
	(segment
		(start 309.790084 -178.652678)
		(end 321.6148 -185.674508)
		(width 0.14224)
		(layer "In6.Cu")
		(net "GMI_CPU1_G0_CPU0_G2_TX_DP<3>")
	)
	(segment
		(start 101.763068 -231.059736)
		(end 101.723952 -231.036876)
		(width 0.1143)
		(layer "In6.Cu")
		(net "GMI_CPU1_G0_CPU0_G2_TX_DP<3>")
	)
	(segment
		(start 104.826308 -221.247208)
		(end 104.826054 -221.246954)
		(width 0.1143)
		(layer "In6.Cu")
		(net "GMI_CPU1_G0_CPU0_G2_TX_DP<3>")
	)
	(segment
		(start 321.6148 -185.674508)
		(end 321.660012 -185.852308)
		(width 0.14224)
		(layer "In6.Cu")
		(net "GMI_CPU1_G0_CPU0_G2_TX_DP<3>")
	)
	(segment
		(start 104.544114 -222.29191)
		(end 104.580436 -222.270828)
		(width 0.1143)
		(layer "In6.Cu")
		(net "GMI_CPU1_G0_CPU0_G2_TX_DP<3>")
	)
	(segment
		(start 370.435632 -241.161316)
		(end 370.352828 -241.24412)
		(width 0.1143)
		(layer "In6.Cu")
		(net "GMI_CPU1_G0_CPU0_G2_TX_DP<3>")
	)
	(segment
		(start 366.624108 -221.09303)
		(end 366.669828 -221.13875)
		(width 0.1143)
		(layer "In6.Cu")
		(net "GMI_CPU1_G0_CPU0_G2_TX_DP<3>")
	)
	(segment
		(start 100.315014 -239.301274)
		(end 100.319586 -239.29848)
		(width 0.1143)
		(layer "In6.Cu")
		(net "GMI_CPU1_G0_CPU0_G2_TX_DP<3>")
	)
	(segment
		(start 370.243862 -236.062774)
		(end 370.27358 -236.079792)
		(width 0.1143)
		(layer "In6.Cu")
		(net "GMI_CPU1_G0_CPU0_G2_TX_DP<3>")
	)
	(segment
		(start 101.256592 -236.060234)
		(end 101.293168 -236.038898)
		(width 0.1143)
		(layer "In6.Cu")
		(net "GMI_CPU1_G0_CPU0_G2_TX_DP<3>")
	)
	(segment
		(start 369.80241 -227.779072)
		(end 369.732814 -227.819712)
		(width 0.1143)
		(layer "In6.Cu")
		(net "GMI_CPU1_G0_CPU0_G2_TX_DP<3>")
	)
	(segment
		(start 366.669574 -221.246954)
		(end 366.669574 -221.80423)
		(width 0.1143)
		(layer "In6.Cu")
		(net "GMI_CPU1_G0_CPU0_G2_TX_DP<3>")
	)
	(segment
		(start 101.143054 -241.244374)
		(end 101.06025 -241.16157)
		(width 0.1143)
		(layer "In6.Cu")
		(net "GMI_CPU1_G0_CPU0_G2_TX_DP<3>")
	)
	(segment
		(start 117.88648 -204.413104)
		(end 117.910356 -204.231494)
		(width 0.14224)
		(layer "In6.Cu")
		(net "GMI_CPU1_G0_CPU0_G2_TX_DP<3>")
	)
	(segment
		(start 106.055922 -215.442292)
		(end 115.14455 -206.353664)
		(width 0.14224)
		(layer "In6.Cu")
		(net "GMI_CPU1_G0_CPU0_G2_TX_DP<3>")
	)
	(segment
		(start 102.659688 -225.53422)
		(end 102.661212 -225.533712)
		(width 0.1143)
		(layer "In6.Cu")
		(net "GMI_CPU1_G0_CPU0_G2_TX_DP<3>")
	)
	(segment
		(start 370.23929 -236.05998)
		(end 370.240814 -236.060996)
		(width 0.1143)
		(layer "In6.Cu")
		(net "GMI_CPU1_G0_CPU0_G2_TX_DP<3>")
	)
	(segment
		(start 117.039644 -204.899514)
		(end 117.37213 -204.644498)
		(width 0.14224)
		(layer "In6.Cu")
		(net "GMI_CPU1_G0_CPU0_G2_TX_DP<3>")
	)
	(segment
		(start 105.339642 -217.171778)
		(end 105.499916 -216.784682)
		(width 0.14224)
		(layer "In6.Cu")
		(net "GMI_CPU1_G0_CPU0_G2_TX_DP<3>")
	)
	(segment
		(start 100.313998 -239.946942)
		(end 100.313236 -239.946434)
		(width 0.1143)
		(layer "In6.Cu")
		(net "GMI_CPU1_G0_CPU0_G2_TX_DP<3>")
	)
	(segment
		(start 101.763068 -234.29976)
		(end 101.723952 -234.2769)
		(width 0.1143)
		(layer "In6.Cu")
		(net "GMI_CPU1_G0_CPU0_G2_TX_DP<3>")
	)
	(segment
		(start 100.345494 -239.96523)
		(end 100.313998 -239.946942)
		(width 0.1143)
		(layer "In6.Cu")
		(net "GMI_CPU1_G0_CPU0_G2_TX_DP<3>")
	)
	(segment
		(start 104.039162 -223.122744)
		(end 104.074976 -223.101916)
		(width 0.1143)
		(layer "In6.Cu")
		(net "GMI_CPU1_G0_CPU0_G2_TX_DP<3>")
	)
	(segment
		(start 371.180868 -239.947196)
		(end 371.179344 -239.948212)
		(width 0.1143)
		(layer "In6.Cu")
		(net "GMI_CPU1_G0_CPU0_G2_TX_DP<3>")
	)
	(segment
		(start 105.249218 -217.728546)
		(end 105.409746 -217.341196)
		(width 0.14224)
		(layer "In6.Cu")
		(net "GMI_CPU1_G0_CPU0_G2_TX_DP<3>")
	)
	(segment
		(start 369.305332 -226.343464)
		(end 369.33378 -226.360228)
		(width 0.1143)
		(layer "In6.Cu")
		(net "GMI_CPU1_G0_CPU0_G2_TX_DP<3>")
	)
	(segment
		(start 369.804442 -231.017826)
		(end 369.77193 -231.036622)
		(width 0.1143)
		(layer "In6.Cu")
		(net "GMI_CPU1_G0_CPU0_G2_TX_DP<3>")
	)
	(segment
		(start 117.37213 -204.644498)
		(end 117.55374 -204.668374)
		(width 0.14224)
		(layer "In6.Cu")
		(net "GMI_CPU1_G0_CPU0_G2_TX_DP<3>")
	)
	(segment
		(start 101.693472 -232.029508)
		(end 101.723952 -232.011728)
		(width 0.1143)
		(layer "In6.Cu")
		(net "GMI_CPU1_G0_CPU0_G2_TX_DP<3>")
	)
	(segment
		(start 369.77193 -229.41661)
		(end 369.732814 -229.43947)
		(width 0.1143)
		(layer "In6.Cu")
		(net "GMI_CPU1_G0_CPU0_G2_TX_DP<3>")
	)
	(segment
		(start 105.499916 -216.784682)
		(end 105.669334 -216.714578)
		(width 0.14224)
		(layer "In6.Cu")
		(net "GMI_CPU1_G0_CPU0_G2_TX_DP<3>")
	)
	(segment
		(start 100.313236 -239.30229)
		(end 100.313998 -239.301782)
		(width 0.1143)
		(layer "In6.Cu")
		(net "GMI_CPU1_G0_CPU0_G2_TX_DP<3>")
	)
	(arc
		(start 367.138966 -222.614236)
		(mid 367.204996 -222.879264)
		(end 367.387632 -223.082358)
		(width 0.1143)
		(layer "In6.Cu")
		(net "GMI_CPU1_G0_CPU0_G2_TX_DP<3>")
	)
	(arc
		(start 101.693472 -227.779326)
		(mid 101.536495 -227.474526)
		(end 101.693472 -227.169726)
		(width 0.1143)
		(layer "In6.Cu")
		(net "GMI_CPU1_G0_CPU0_G2_TX_DP<3>")
	)
	(arc
		(start 366.669574 -221.80423)
		(mid 366.669564 -221.807532)
		(end 366.669574 -221.810834)
		(width 0.1143)
		(layer "In6.Cu")
		(net "GMI_CPU1_G0_CPU0_G2_TX_DP<3>")
	)
	(arc
		(start 371.213634 -237.699804)
		(mid 371.362731 -238.004096)
		(end 371.213634 -238.308388)
		(width 0.1143)
		(layer "In6.Cu")
		(net "GMI_CPU1_G0_CPU0_G2_TX_DP<3>")
	)
	(arc
		(start 370.742464 -236.88929)
		(mid 370.857891 -237.022666)
		(end 370.899436 -237.19409)
		(width 0.1143)
		(layer "In6.Cu")
		(net "GMI_CPU1_G0_CPU0_G2_TX_DP<3>")
	)
	(arc
		(start 100.753418 -240.739168)
		(mid 100.637991 -240.605792)
		(end 100.596446 -240.434368)
		(width 0.1143)
		(layer "In6.Cu")
		(net "GMI_CPU1_G0_CPU0_G2_TX_DP<3>")
	)
	(arc
		(start 100.596446 -240.434368)
		(mid 100.531931 -240.172149)
		(end 100.353114 -239.969802)
		(width 0.1143)
		(layer "In6.Cu")
		(net "GMI_CPU1_G0_CPU0_G2_TX_DP<3>")
	)
	(arc
		(start 371.142768 -239.969548)
		(mid 370.963955 -240.171898)
		(end 370.899436 -240.434114)
		(width 0.1143)
		(layer "In6.Cu")
		(net "GMI_CPU1_G0_CPU0_G2_TX_DP<3>")
	)
	(arc
		(start 101.293168 -236.038898)
		(mid 101.471981 -235.836548)
		(end 101.5365 -235.574332)
		(width 0.1143)
		(layer "In6.Cu")
		(net "GMI_CPU1_G0_CPU0_G2_TX_DP<3>")
	)
	(arc
		(start 100.596446 -237.194344)
		(mid 100.637995 -237.022922)
		(end 100.753418 -236.889544)
		(width 0.1143)
		(layer "In6.Cu")
		(net "GMI_CPU1_G0_CPU0_G2_TX_DP<3>")
	)
	(arc
		(start 369.959382 -230.714296)
		(mid 369.918416 -230.884702)
		(end 369.804442 -231.017826)
		(width 0.1143)
		(layer "In6.Cu")
		(net "GMI_CPU1_G0_CPU0_G2_TX_DP<3>")
	)
	(arc
		(start 369.959382 -235.574078)
		(mid 370.023897 -235.836297)
		(end 370.202714 -236.038644)
		(width 0.1143)
		(layer "In6.Cu")
		(net "GMI_CPU1_G0_CPU0_G2_TX_DP<3>")
	)
	(arc
		(start 369.80241 -232.029254)
		(mid 369.959387 -232.334054)
		(end 369.80241 -232.638854)
		(width 0.1143)
		(layer "In6.Cu")
		(net "GMI_CPU1_G0_CPU0_G2_TX_DP<3>")
	)
	(arc
		(start 368.836194 -225.533966)
		(mid 368.970687 -225.668923)
		(end 369.019836 -225.85299)
		(width 0.1143)
		(layer "In6.Cu")
		(net "GMI_CPU1_G0_CPU0_G2_TX_DP<3>")
	)
	(arc
		(start 369.019836 -225.85299)
		(mid 369.096401 -226.136757)
		(end 369.305332 -226.343464)
		(width 0.1143)
		(layer "In6.Cu")
		(net "GMI_CPU1_G0_CPU0_G2_TX_DP<3>")
	)
	(arc
		(start 367.923572 -223.929956)
		(mid 368.038248 -224.06329)
		(end 368.079528 -224.234248)
		(width 0.1143)
		(layer "In6.Cu")
		(net "GMI_CPU1_G0_CPU0_G2_TX_DP<3>")
	)
	(arc
		(start 369.489482 -229.904036)
		(mid 369.554718 -230.167627)
		(end 369.735354 -230.37038)
		(width 0.1143)
		(layer "In6.Cu")
		(net "GMI_CPU1_G0_CPU0_G2_TX_DP<3>")
	)
	(arc
		(start 369.33378 -226.360228)
		(mid 369.448456 -226.493419)
		(end 369.489736 -226.664266)
		(width 0.1143)
		(layer "In6.Cu")
		(net "GMI_CPU1_G0_CPU0_G2_TX_DP<3>")
	)
	(arc
		(start 103.173022 -224.699068)
		(mid 103.351835 -224.496718)
		(end 103.416354 -224.234502)
		(width 0.1143)
		(layer "In6.Cu")
		(net "GMI_CPU1_G0_CPU0_G2_TX_DP<3>")
	)
	(arc
		(start 103.416354 -224.234502)
		(mid 103.457609 -224.063531)
		(end 103.57231 -223.93021)
		(width 0.1143)
		(layer "In6.Cu")
		(net "GMI_CPU1_G0_CPU0_G2_TX_DP<3>")
	)
	(arc
		(start 101.69144 -229.398068)
		(mid 101.577511 -229.264921)
		(end 101.5365 -229.094538)
		(width 0.1143)
		(layer "In6.Cu")
		(net "GMI_CPU1_G0_CPU0_G2_TX_DP<3>")
	)
	(arc
		(start 100.282248 -238.308642)
		(mid 100.133151 -238.00435)
		(end 100.282248 -237.700058)
		(width 0.1143)
		(layer "In6.Cu")
		(net "GMI_CPU1_G0_CPU0_G2_TX_DP<3>")
	)
	(arc
		(start 368.392456 -224.739454)
		(mid 368.507883 -224.87283)
		(end 368.549428 -225.044254)
		(width 0.1143)
		(layer "In6.Cu")
		(net "GMI_CPU1_G0_CPU0_G2_TX_DP<3>")
	)
	(arc
		(start 101.763068 -233.60888)
		(mid 102.006395 -233.144314)
		(end 101.763068 -232.679748)
		(width 0.1143)
		(layer "In6.Cu")
		(net "GMI_CPU1_G0_CPU0_G2_TX_DP<3>")
	)
	(arc
		(start 104.580436 -222.270828)
		(mid 104.588614 -222.265185)
		(end 104.596692 -222.259398)
		(width 0.1143)
		(layer "In6.Cu")
		(net "GMI_CPU1_G0_CPU0_G2_TX_DP<3>")
	)
	(arc
		(start 100.823014 -236.848904)
		(mid 101.001827 -236.646554)
		(end 101.066346 -236.384338)
		(width 0.1143)
		(layer "In6.Cu")
		(net "GMI_CPU1_G0_CPU0_G2_TX_DP<3>")
	)
	(arc
		(start 102.703122 -225.509074)
		(mid 102.881935 -225.306724)
		(end 102.946454 -225.044508)
		(width 0.1143)
		(layer "In6.Cu")
		(net "GMI_CPU1_G0_CPU0_G2_TX_DP<3>")
	)
	(arc
		(start 103.64597 -223.887538)
		(mid 103.822952 -223.685446)
		(end 103.886762 -223.424496)
		(width 0.1143)
		(layer "In6.Cu")
		(net "GMI_CPU1_G0_CPU0_G2_TX_DP<3>")
	)
	(arc
		(start 101.693472 -232.639108)
		(mid 101.536495 -232.334308)
		(end 101.693472 -232.029508)
		(width 0.1143)
		(layer "In6.Cu")
		(net "GMI_CPU1_G0_CPU0_G2_TX_DP<3>")
	)
	(arc
		(start 101.763068 -227.129086)
		(mid 101.941881 -226.926736)
		(end 102.0064 -226.66452)
		(width 0.1143)
		(layer "In6.Cu")
		(net "GMI_CPU1_G0_CPU0_G2_TX_DP<3>")
	)
	(arc
		(start 102.476046 -225.853244)
		(mid 102.525246 -225.669207)
		(end 102.659688 -225.53422)
		(width 0.1143)
		(layer "In6.Cu")
		(net "GMI_CPU1_G0_CPU0_G2_TX_DP<3>")
	)
	(arc
		(start 370.899436 -237.19409)
		(mid 370.963951 -237.456309)
		(end 371.142768 -237.658656)
		(width 0.1143)
		(layer "In6.Cu")
		(net "GMI_CPU1_G0_CPU0_G2_TX_DP<3>")
	)
	(arc
		(start 101.763068 -235.228892)
		(mid 102.006395 -234.764326)
		(end 101.763068 -234.29976)
		(width 0.1143)
		(layer "In6.Cu")
		(net "GMI_CPU1_G0_CPU0_G2_TX_DP<3>")
	)
	(arc
		(start 101.693472 -234.25912)
		(mid 101.536495 -233.95432)
		(end 101.693472 -233.64952)
		(width 0.1143)
		(layer "In6.Cu")
		(net "GMI_CPU1_G0_CPU0_G2_TX_DP<3>")
	)
	(arc
		(start 369.80241 -235.269278)
		(mid 369.917837 -235.402654)
		(end 369.959382 -235.574078)
		(width 0.1143)
		(layer "In6.Cu")
		(net "GMI_CPU1_G0_CPU0_G2_TX_DP<3>")
	)
	(arc
		(start 368.549428 -225.044254)
		(mid 368.613943 -225.306473)
		(end 368.79276 -225.50882)
		(width 0.1143)
		(layer "In6.Cu")
		(net "GMI_CPU1_G0_CPU0_G2_TX_DP<3>")
	)
	(arc
		(start 103.886762 -223.424496)
		(mid 103.927026 -223.255472)
		(end 104.039162 -223.122744)
		(width 0.1143)
		(layer "In6.Cu")
		(net "GMI_CPU1_G0_CPU0_G2_TX_DP<3>")
	)
	(arc
		(start 366.669574 -221.810834)
		(mid 366.734446 -222.060576)
		(end 366.89919 -222.259144)
		(width 0.1143)
		(layer "In6.Cu")
		(net "GMI_CPU1_G0_CPU0_G2_TX_DP<3>")
	)
	(arc
		(start 104.356916 -222.61449)
		(mid 104.399389 -222.441286)
		(end 104.51719 -222.307404)
		(width 0.1143)
		(layer "In6.Cu")
		(net "GMI_CPU1_G0_CPU0_G2_TX_DP<3>")
	)
	(arc
		(start 368.079528 -224.234248)
		(mid 368.144043 -224.496467)
		(end 368.32286 -224.698814)
		(width 0.1143)
		(layer "In6.Cu")
		(net "GMI_CPU1_G0_CPU0_G2_TX_DP<3>")
	)
	(arc
		(start 371.142768 -238.349536)
		(mid 370.899441 -238.814102)
		(end 371.142768 -239.278668)
		(width 0.1143)
		(layer "In6.Cu")
		(net "GMI_CPU1_G0_CPU0_G2_TX_DP<3>")
	)
	(arc
		(start 100.353114 -237.65891)
		(mid 100.531927 -237.45656)
		(end 100.596446 -237.194344)
		(width 0.1143)
		(layer "In6.Cu")
		(net "GMI_CPU1_G0_CPU0_G2_TX_DP<3>")
	)
	(arc
		(start 367.60912 -223.424242)
		(mid 367.672912 -223.685201)
		(end 367.849912 -223.887284)
		(width 0.1143)
		(layer "In6.Cu")
		(net "GMI_CPU1_G0_CPU0_G2_TX_DP<3>")
	)
	(arc
		(start 104.826308 -221.811088)
		(mid 104.826318 -221.807786)
		(end 104.826308 -221.804484)
		(width 0.1143)
		(layer "In6.Cu")
		(net "GMI_CPU1_G0_CPU0_G2_TX_DP<3>")
	)
	(arc
		(start 101.066346 -236.384338)
		(mid 101.107601 -236.213367)
		(end 101.222302 -236.080046)
		(width 0.1143)
		(layer "In6.Cu")
		(net "GMI_CPU1_G0_CPU0_G2_TX_DP<3>")
	)
	(arc
		(start 100.353114 -239.278922)
		(mid 100.596441 -238.814356)
		(end 100.353114 -238.34979)
		(width 0.1143)
		(layer "In6.Cu")
		(net "GMI_CPU1_G0_CPU0_G2_TX_DP<3>")
	)
	(arc
		(start 101.760528 -230.370634)
		(mid 101.94118 -230.167889)
		(end 102.0064 -229.90429)
		(width 0.1143)
		(layer "In6.Cu")
		(net "GMI_CPU1_G0_CPU0_G2_TX_DP<3>")
	)
	(arc
		(start 100.262436 -239.91443)
		(mid 100.113722 -239.624362)
		(end 100.262436 -239.334294)
		(width 0.1143)
		(layer "In6.Cu")
		(net "GMI_CPU1_G0_CPU0_G2_TX_DP<3>")
	)
	(arc
		(start 102.946454 -225.044508)
		(mid 102.988003 -224.873086)
		(end 103.103426 -224.739708)
		(width 0.1143)
		(layer "In6.Cu")
		(net "GMI_CPU1_G0_CPU0_G2_TX_DP<3>")
	)
	(arc
		(start 101.5365 -229.094538)
		(mid 101.578049 -228.923116)
		(end 101.693472 -228.789738)
		(width 0.1143)
		(layer "In6.Cu")
		(net "GMI_CPU1_G0_CPU0_G2_TX_DP<3>")
	)
	(arc
		(start 369.732814 -227.819712)
		(mid 369.489487 -228.284278)
		(end 369.732814 -228.748844)
		(width 0.1143)
		(layer "In6.Cu")
		(net "GMI_CPU1_G0_CPU0_G2_TX_DP<3>")
	)
	(arc
		(start 370.439442 -241.138456)
		(mid 370.437419 -241.149866)
		(end 370.435632 -241.161316)
		(width 0.1143)
		(layer "In6.Cu")
		(net "GMI_CPU1_G0_CPU0_G2_TX_DP<3>")
	)
	(arc
		(start 101.5365 -235.574332)
		(mid 101.578049 -235.40291)
		(end 101.693472 -235.269532)
		(width 0.1143)
		(layer "In6.Cu")
		(net "GMI_CPU1_G0_CPU0_G2_TX_DP<3>")
	)
	(arc
		(start 367.45672 -223.12249)
		(mid 367.568867 -223.255213)
		(end 367.60912 -223.424242)
		(width 0.1143)
		(layer "In6.Cu")
		(net "GMI_CPU1_G0_CPU0_G2_TX_DP<3>")
	)
	(arc
		(start 370.27358 -236.079792)
		(mid 370.388256 -236.213126)
		(end 370.429536 -236.384084)
		(width 0.1143)
		(layer "In6.Cu")
		(net "GMI_CPU1_G0_CPU0_G2_TX_DP<3>")
	)
	(arc
		(start 369.732814 -229.43947)
		(mid 369.554001 -229.64182)
		(end 369.489482 -229.904036)
		(width 0.1143)
		(layer "In6.Cu")
		(net "GMI_CPU1_G0_CPU0_G2_TX_DP<3>")
	)
	(arc
		(start 101.69144 -231.01808)
		(mid 101.577511 -230.884933)
		(end 101.5365 -230.71455)
		(width 0.1143)
		(layer "In6.Cu")
		(net "GMI_CPU1_G0_CPU0_G2_TX_DP<3>")
	)
	(arc
		(start 369.489482 -226.664266)
		(mid 369.553997 -226.926485)
		(end 369.732814 -227.128832)
		(width 0.1143)
		(layer "In6.Cu")
		(net "GMI_CPU1_G0_CPU0_G2_TX_DP<3>")
	)
	(arc
		(start 101.763068 -231.988868)
		(mid 102.006395 -231.524302)
		(end 101.763068 -231.059736)
		(width 0.1143)
		(layer "In6.Cu")
		(net "GMI_CPU1_G0_CPU0_G2_TX_DP<3>")
	)
	(arc
		(start 366.89919 -222.259144)
		(mid 366.907268 -222.26493)
		(end 366.915446 -222.270574)
		(width 0.1143)
		(layer "In6.Cu")
		(net "GMI_CPU1_G0_CPU0_G2_TX_DP<3>")
	)
	(arc
		(start 369.959382 -229.094284)
		(mid 369.918416 -229.26469)
		(end 369.804442 -229.397814)
		(width 0.1143)
		(layer "In6.Cu")
		(net "GMI_CPU1_G0_CPU0_G2_TX_DP<3>")
	)
	(arc
		(start 370.672868 -240.779554)
		(mid 370.520881 -240.936062)
		(end 370.439442 -241.138456)
		(width 0.1143)
		(layer "In6.Cu")
		(net "GMI_CPU1_G0_CPU0_G2_TX_DP<3>")
	)
	(arc
		(start 366.978692 -222.30715)
		(mid 367.096466 -222.441045)
		(end 367.138966 -222.614236)
		(width 0.1143)
		(layer "In6.Cu")
		(net "GMI_CPU1_G0_CPU0_G2_TX_DP<3>")
	)
	(arc
		(start 102.0064 -229.90429)
		(mid 101.941885 -229.642071)
		(end 101.763068 -229.439724)
		(width 0.1143)
		(layer "In6.Cu")
		(net "GMI_CPU1_G0_CPU0_G2_TX_DP<3>")
	)
	(arc
		(start 369.80241 -233.649266)
		(mid 369.959387 -233.954066)
		(end 369.80241 -234.258866)
		(width 0.1143)
		(layer "In6.Cu")
		(net "GMI_CPU1_G0_CPU0_G2_TX_DP<3>")
	)
	(arc
		(start 102.006146 -226.66452)
		(mid 102.047405 -226.493663)
		(end 102.162102 -226.360482)
		(width 0.1143)
		(layer "In6.Cu")
		(net "GMI_CPU1_G0_CPU0_G2_TX_DP<3>")
	)
	(arc
		(start 102.19055 -226.343718)
		(mid 102.399448 -226.136992)
		(end 102.476046 -225.853244)
		(width 0.1143)
		(layer "In6.Cu")
		(net "GMI_CPU1_G0_CPU0_G2_TX_DP<3>")
	)
	(arc
		(start 369.732814 -234.299506)
		(mid 369.489487 -234.764072)
		(end 369.732814 -235.228638)
		(width 0.1143)
		(layer "In6.Cu")
		(net "GMI_CPU1_G0_CPU0_G2_TX_DP<3>")
	)
	(arc
		(start 370.899436 -240.434114)
		(mid 370.857887 -240.605536)
		(end 370.742464 -240.738914)
		(width 0.1143)
		(layer "In6.Cu")
		(net "GMI_CPU1_G0_CPU0_G2_TX_DP<3>")
	)
	(arc
		(start 371.233446 -239.33404)
		(mid 371.38216 -239.624108)
		(end 371.233446 -239.914176)
		(width 0.1143)
		(layer "In6.Cu")
		(net "GMI_CPU1_G0_CPU0_G2_TX_DP<3>")
	)
	(arc
		(start 369.80241 -227.169472)
		(mid 369.959387 -227.474272)
		(end 369.80241 -227.779072)
		(width 0.1143)
		(layer "In6.Cu")
		(net "GMI_CPU1_G0_CPU0_G2_TX_DP<3>")
	)
	(arc
		(start 369.732814 -232.679494)
		(mid 369.489487 -233.14406)
		(end 369.732814 -233.608626)
		(width 0.1143)
		(layer "In6.Cu")
		(net "GMI_CPU1_G0_CPU0_G2_TX_DP<3>")
	)
	(arc
		(start 370.429536 -236.384084)
		(mid 370.494051 -236.646303)
		(end 370.672868 -236.84865)
		(width 0.1143)
		(layer "In6.Cu")
		(net "GMI_CPU1_G0_CPU0_G2_TX_DP<3>")
	)
	(arc
		(start 101.763068 -228.749098)
		(mid 102.006395 -228.284532)
		(end 101.763068 -227.819966)
		(width 0.1143)
		(layer "In6.Cu")
		(net "GMI_CPU1_G0_CPU0_G2_TX_DP<3>")
	)
	(arc
		(start 101.5365 -230.71455)
		(mid 101.578049 -230.543128)
		(end 101.693472 -230.40975)
		(width 0.1143)
		(layer "In6.Cu")
		(net "GMI_CPU1_G0_CPU0_G2_TX_DP<3>")
	)
	(arc
		(start 369.732814 -231.059482)
		(mid 369.489487 -231.524048)
		(end 369.732814 -231.988614)
		(width 0.1143)
		(layer "In6.Cu")
		(net "GMI_CPU1_G0_CPU0_G2_TX_DP<3>")
	)
	(arc
		(start 104.10825 -223.082612)
		(mid 104.290912 -222.879531)
		(end 104.356916 -222.61449)
		(width 0.1143)
		(layer "In6.Cu")
		(net "GMI_CPU1_G0_CPU0_G2_TX_DP<3>")
	)
	(arc
		(start 104.596692 -222.259398)
		(mid 104.761359 -222.060791)
		(end 104.826308 -221.811088)
		(width 0.1143)
		(layer "In6.Cu")
		(net "GMI_CPU1_G0_CPU0_G2_TX_DP<3>")
	)
	(arc
		(start 369.80241 -228.789484)
		(mid 369.917837 -228.92286)
		(end 369.959382 -229.094284)
		(width 0.1143)
		(layer "In6.Cu")
		(net "GMI_CPU1_G0_CPU0_G2_TX_DP<3>")
	)
	(arc
		(start 369.80241 -230.409496)
		(mid 369.917837 -230.542872)
		(end 369.959382 -230.714296)
		(width 0.1143)
		(layer "In6.Cu")
		(net "GMI_CPU1_G0_CPU0_G2_TX_DP<3>")
	)
	(arc
		(start 101.06025 -241.16157)
		(mid 101.058462 -241.150121)
		(end 101.05644 -241.13871)
		(width 0.1143)
		(layer "In6.Cu")
		(net "GMI_CPU1_G0_CPU0_G2_TX_DP<3>")
	)
	(arc
		(start 101.05644 -241.13871)
		(mid 100.975007 -240.936312)
		(end 100.823014 -240.779808)
		(width 0.1143)
		(layer "In6.Cu")
		(net "GMI_CPU1_G0_CPU0_G2_TX_DP<3>")
	)
	(segment
		(start 372.407942 -243.13007)
		(end 372.874794 -242.864132)
		(width 0.12954)
		(layer "F.Cu")
		(net "GMI_CPU1_G0_CPU0_G2_TX_DP<2>")
	)
	(segment
		(start 99.08794 -243.130324)
		(end 98.621088 -242.864386)
		(width 0.12954)
		(layer "F.Cu")
		(net "GMI_CPU1_G0_CPU0_G2_TX_DP<2>")
	)
	(segment
		(start 102.48138 -224.228406)
		(end 102.48138 -224.303844)
		(width 0.1143)
		(layer "In6.Cu")
		(net "GMI_CPU1_G0_CPU0_G2_TX_DP<2>")
	)
	(segment
		(start 372.623588 -240.129822)
		(end 372.59387 -240.112804)
		(width 0.1143)
		(layer "In6.Cu")
		(net "GMI_CPU1_G0_CPU0_G2_TX_DP<2>")
	)
	(segment
		(start 370.711984 -231.036622)
		(end 370.744496 -231.017826)
		(width 0.1143)
		(layer "In6.Cu")
		(net "GMI_CPU1_G0_CPU0_G2_TX_DP<2>")
	)
	(segment
		(start 372.599458 -240.752376)
		(end 372.623588 -240.738406)
		(width 0.1143)
		(layer "In6.Cu")
		(net "GMI_CPU1_G0_CPU0_G2_TX_DP<2>")
	)
	(segment
		(start 327.49236 -188.055504)
		(end 327.132188 -187.841636)
		(width 0.14224)
		(layer "In6.Cu")
		(net "GMI_CPU1_G0_CPU0_G2_TX_DP<2>")
	)
	(segment
		(start 372.591838 -240.111534)
		(end 372.590822 -240.111026)
		(width 0.1143)
		(layer "In6.Cu")
		(net "GMI_CPU1_G0_CPU0_G2_TX_DP<2>")
	)
	(segment
		(start 367.608866 -221.80423)
		(end 367.608866 -221.247208)
		(width 0.1143)
		(layer "In6.Cu")
		(net "GMI_CPU1_G0_CPU0_G2_TX_DP<2>")
	)
	(segment
		(start 100.823014 -235.228892)
		(end 100.783898 -235.251752)
		(width 0.1143)
		(layer "In6.Cu")
		(net "GMI_CPU1_G0_CPU0_G2_TX_DP<2>")
	)
	(segment
		(start 356.785164 -207.101948)
		(end 331.13218 -190.981076)
		(width 0.14224)
		(layer "In6.Cu")
		(net "GMI_CPU1_G0_CPU0_G2_TX_DP<2>")
	)
	(segment
		(start 370.242592 -226.342194)
		(end 370.24183 -226.341686)
		(width 0.1143)
		(layer "In6.Cu")
		(net "GMI_CPU1_G0_CPU0_G2_TX_DP<2>")
	)
	(segment
		(start 98.90506 -241.731292)
		(end 98.904044 -241.7318)
		(width 0.1143)
		(layer "In6.Cu")
		(net "GMI_CPU1_G0_CPU0_G2_TX_DP<2>")
	)
	(segment
		(start 100.313236 -236.062266)
		(end 100.311204 -236.063536)
		(width 0.1143)
		(layer "In6.Cu")
		(net "GMI_CPU1_G0_CPU0_G2_TX_DP<2>")
	)
	(segment
		(start 371.656102 -236.87405)
		(end 371.655086 -236.873542)
		(width 0.1143)
		(layer "In6.Cu")
		(net "GMI_CPU1_G0_CPU0_G2_TX_DP<2>")
	)
	(segment
		(start 370.24183 -226.341686)
		(end 370.240814 -226.341178)
		(width 0.1143)
		(layer "In6.Cu")
		(net "GMI_CPU1_G0_CPU0_G2_TX_DP<2>")
	)
	(segment
		(start 373.092472 -242.559332)
		(end 373.022876 -242.518692)
		(width 0.1143)
		(layer "In6.Cu")
		(net "GMI_CPU1_G0_CPU0_G2_TX_DP<2>")
	)
	(segment
		(start 370.672868 -229.43947)
		(end 370.711984 -229.41661)
		(width 0.1143)
		(layer "In6.Cu")
		(net "GMI_CPU1_G0_CPU0_G2_TX_DP<2>")
	)
	(segment
		(start 99.373944 -237.68177)
		(end 99.343464 -237.69955)
		(width 0.1143)
		(layer "In6.Cu")
		(net "GMI_CPU1_G0_CPU0_G2_TX_DP<2>")
	)
	(segment
		(start 100.751386 -231.01808)
		(end 100.783898 -231.036876)
		(width 0.1143)
		(layer "In6.Cu")
		(net "GMI_CPU1_G0_CPU0_G2_TX_DP<2>")
	)
	(segment
		(start 99.343464 -238.30915)
		(end 99.373944 -238.32693)
		(width 0.1143)
		(layer "In6.Cu")
		(net "GMI_CPU1_G0_CPU0_G2_TX_DP<2>")
	)
	(segment
		(start 100.311204 -236.063536)
		(end 100.30968 -236.064044)
		(width 0.1143)
		(layer "In6.Cu")
		(net "GMI_CPU1_G0_CPU0_G2_TX_DP<2>")
	)
	(segment
		(start 98.43389 -242.541806)
		(end 98.40341 -242.559586)
		(width 0.1143)
		(layer "In6.Cu")
		(net "GMI_CPU1_G0_CPU0_G2_TX_DP<2>")
	)
	(segment
		(start 101.293168 -226.31908)
		(end 101.256592 -226.340416)
		(width 0.1143)
		(layer "In6.Cu")
		(net "GMI_CPU1_G0_CPU0_G2_TX_DP<2>")
	)
	(segment
		(start 101.723952 -225.531934)
		(end 101.693472 -225.549714)
		(width 0.1143)
		(layer "In6.Cu")
		(net "GMI_CPU1_G0_CPU0_G2_TX_DP<2>")
	)
	(segment
		(start 361.831128 -211.12607)
		(end 356.785164 -207.101948)
		(width 0.14224)
		(layer "In6.Cu")
		(net "GMI_CPU1_G0_CPU0_G2_TX_DP<2>")
	)
	(segment
		(start 371.180868 -236.060996)
		(end 371.142768 -236.038644)
		(width 0.1143)
		(layer "In6.Cu")
		(net "GMI_CPU1_G0_CPU0_G2_TX_DP<2>")
	)
	(segment
		(start 329.665838 -189.67958)
		(end 329.352656 -189.40145)
		(width 0.14224)
		(layer "In6.Cu")
		(net "GMI_CPU1_G0_CPU0_G2_TX_DP<2>")
	)
	(segment
		(start 372.589298 -240.11001)
		(end 372.552722 -240.088674)
		(width 0.1143)
		(layer "In6.Cu")
		(net "GMI_CPU1_G0_CPU0_G2_TX_DP<2>")
	)
	(segment
		(start 101.25329 -226.342448)
		(end 101.222302 -226.360228)
		(width 0.1143)
		(layer "In6.Cu")
		(net "GMI_CPU1_G0_CPU0_G2_TX_DP<2>")
	)
	(segment
		(start 367.563654 -221.081346)
		(end 367.563654 -218.45524)
		(width 0.14224)
		(layer "In6.Cu")
		(net "GMI_CPU1_G0_CPU0_G2_TX_DP<2>")
	)
	(segment
		(start 103.131112 -223.10598)
		(end 103.129588 -223.106996)
		(width 0.1143)
		(layer "In6.Cu")
		(net "GMI_CPU1_G0_CPU0_G2_TX_DP<2>")
	)
	(segment
		(start 98.473006 -242.518946)
		(end 98.43389 -242.541806)
		(width 0.1143)
		(layer "In6.Cu")
		(net "GMI_CPU1_G0_CPU0_G2_TX_DP<2>")
	)
	(segment
		(start 368.367818 -223.107504)
		(end 368.366294 -223.106742)
		(width 0.1143)
		(layer "In6.Cu")
		(net "GMI_CPU1_G0_CPU0_G2_TX_DP<2>")
	)
	(segment
		(start 372.595394 -240.754662)
		(end 372.596156 -240.754154)
		(width 0.1143)
		(layer "In6.Cu")
		(net "GMI_CPU1_G0_CPU0_G2_TX_DP<2>")
	)
	(segment
		(start 100.753418 -227.779326)
		(end 100.783898 -227.797106)
		(width 0.1143)
		(layer "In6.Cu")
		(net "GMI_CPU1_G0_CPU0_G2_TX_DP<2>")
	)
	(segment
		(start 101.256592 -226.340416)
		(end 101.255068 -226.341432)
		(width 0.1143)
		(layer "In6.Cu")
		(net "GMI_CPU1_G0_CPU0_G2_TX_DP<2>")
	)
	(segment
		(start 100.783898 -227.151946)
		(end 100.753418 -227.169726)
		(width 0.1143)
		(layer "In6.Cu")
		(net "GMI_CPU1_G0_CPU0_G2_TX_DP<2>")
	)
	(segment
		(start 104.419908 -216.614756)
		(end 104.490012 -216.784174)
		(width 0.14224)
		(layer "In6.Cu")
		(net "GMI_CPU1_G0_CPU0_G2_TX_DP<2>")
	)
	(segment
		(start 372.623588 -241.749834)
		(end 372.59387 -241.732816)
		(width 0.1143)
		(layer "In6.Cu")
		(net "GMI_CPU1_G0_CPU0_G2_TX_DP<2>")
	)
	(segment
		(start 98.906584 -240.758472)
		(end 98.94316 -240.779808)
		(width 0.1143)
		(layer "In6.Cu")
		(net "GMI_CPU1_G0_CPU0_G2_TX_DP<2>")
	)
	(segment
		(start 100.315014 -236.06125)
		(end 100.313998 -236.061758)
		(width 0.1143)
		(layer "In6.Cu")
		(net "GMI_CPU1_G0_CPU0_G2_TX_DP<2>")
	)
	(segment
		(start 310.226456 -177.802286)
		(end 307.140102 -176.955196)
		(width 0.14224)
		(layer "In6.Cu")
		(net "GMI_CPU1_G0_CPU0_G2_TX_DP<2>")
	)
	(segment
		(start 104.7496 -216.157556)
		(end 104.580182 -216.22766)
		(width 0.14224)
		(layer "In6.Cu")
		(net "GMI_CPU1_G0_CPU0_G2_TX_DP<2>")
	)
	(segment
		(start 370.742464 -230.409496)
		(end 370.675408 -230.37038)
		(width 0.1143)
		(layer "In6.Cu")
		(net "GMI_CPU1_G0_CPU0_G2_TX_DP<2>")
	)
	(segment
		(start 370.742464 -232.029254)
		(end 370.672868 -231.988614)
		(width 0.1143)
		(layer "In6.Cu")
		(net "GMI_CPU1_G0_CPU0_G2_TX_DP<2>")
	)
	(segment
		(start 325.650352 -187.112656)
		(end 325.60514 -186.934856)
		(width 0.14224)
		(layer "In6.Cu")
		(net "GMI_CPU1_G0_CPU0_G2_TX_DP<2>")
	)
	(segment
		(start 100.783898 -229.416864)
		(end 100.823014 -229.439724)
		(width 0.1143)
		(layer "In6.Cu")
		(net "GMI_CPU1_G0_CPU0_G2_TX_DP<2>")
	)
	(segment
		(start 98.903282 -240.75644)
		(end 98.904044 -240.756948)
		(width 0.1143)
		(layer "In6.Cu")
		(net "GMI_CPU1_G0_CPU0_G2_TX_DP<2>")
	)
	(segment
		(start 103.886508 -221.246954)
		(end 103.887016 -221.247462)
		(width 0.1143)
		(layer "In6.Cu")
		(net "GMI_CPU1_G0_CPU0_G2_TX_DP<2>")
	)
	(segment
		(start 372.59387 -241.732816)
		(end 372.5926 -241.732054)
		(width 0.1143)
		(layer "In6.Cu")
		(net "GMI_CPU1_G0_CPU0_G2_TX_DP<2>")
	)
	(segment
		(start 162.445954 -177.340768)
		(end 117.841776 -203.09713)
		(width 0.14224)
		(layer "In6.Cu")
		(net "GMI_CPU1_G0_CPU0_G2_TX_DP<2>")
	)
	(segment
		(start 370.672868 -234.299506)
		(end 370.742464 -234.258866)
		(width 0.1143)
		(layer "In6.Cu")
		(net "GMI_CPU1_G0_CPU0_G2_TX_DP<2>")
	)
	(segment
		(start 372.152418 -239.319308)
		(end 372.082822 -239.278668)
		(width 0.1143)
		(layer "In6.Cu")
		(net "GMI_CPU1_G0_CPU0_G2_TX_DP<2>")
	)
	(segment
		(start 371.186202 -236.06379)
		(end 371.184678 -236.063282)
		(width 0.1143)
		(layer "In6.Cu")
		(net "GMI_CPU1_G0_CPU0_G2_TX_DP<2>")
	)
	(segment
		(start 102.70236 -223.88957)
		(end 102.663244 -223.912176)
		(width 0.1143)
		(layer "In6.Cu")
		(net "GMI_CPU1_G0_CPU0_G2_TX_DP<2>")
	)
	(segment
		(start 372.589298 -240.758218)
		(end 372.590822 -240.757202)
		(width 0.1143)
		(layer "In6.Cu")
		(net "GMI_CPU1_G0_CPU0_G2_TX_DP<2>")
	)
	(segment
		(start 307.140102 -176.955196)
		(end 302.913288 -176.955196)
		(width 0.14224)
		(layer "In6.Cu")
		(net "GMI_CPU1_G0_CPU0_G2_TX_DP<2>")
	)
	(segment
		(start 324.661784 -186.374278)
		(end 310.226456 -177.802286)
		(width 0.14224)
		(layer "In6.Cu")
		(net "GMI_CPU1_G0_CPU0_G2_TX_DP<2>")
	)
	(segment
		(start 99.656138 -237.194344)
		(end 99.656392 -237.194344)
		(width 0.1143)
		(layer "In6.Cu")
		(net "GMI_CPU1_G0_CPU0_G2_TX_DP<2>")
	)
	(segment
		(start 367.609374 -221.13875)
		(end 367.563654 -221.09303)
		(width 0.1143)
		(layer "In6.Cu")
		(net "GMI_CPU1_G0_CPU0_G2_TX_DP<2>")
	)
	(segment
		(start 367.563654 -218.45524)
		(end 366.434624 -215.729566)
		(width 0.14224)
		(layer "In6.Cu")
		(net "GMI_CPU1_G0_CPU0_G2_TX_DP<2>")
	)
	(segment
		(start 100.783898 -228.771958)
		(end 100.753418 -228.789738)
		(width 0.1143)
		(layer "In6.Cu")
		(net "GMI_CPU1_G0_CPU0_G2_TX_DP<2>")
	)
	(segment
		(start 366.434624 -215.729566)
		(end 361.831128 -211.12607)
		(width 0.14224)
		(layer "In6.Cu")
		(net "GMI_CPU1_G0_CPU0_G2_TX_DP<2>")
	)
	(segment
		(start 99.840796 -236.873796)
		(end 99.83978 -236.874304)
		(width 0.1143)
		(layer "In6.Cu")
		(net "GMI_CPU1_G0_CPU0_G2_TX_DP<2>")
	)
	(segment
		(start 372.590822 -241.731038)
		(end 372.589298 -241.730022)
		(width 0.1143)
		(layer "In6.Cu")
		(net "GMI_CPU1_G0_CPU0_G2_TX_DP<2>")
	)
	(segment
		(start 324.706996 -186.552078)
		(end 324.661784 -186.374278)
		(width 0.14224)
		(layer "In6.Cu")
		(net "GMI_CPU1_G0_CPU0_G2_TX_DP<2>")
	)
	(segment
		(start 98.906584 -240.110264)
		(end 98.90506 -240.11128)
		(width 0.1143)
		(layer "In6.Cu")
		(net "GMI_CPU1_G0_CPU0_G2_TX_DP<2>")
	)
	(segment
		(start 372.5926 -241.732054)
		(end 372.591838 -241.731546)
		(width 0.1143)
		(layer "In6.Cu")
		(net "GMI_CPU1_G0_CPU0_G2_TX_DP<2>")
	)
	(segment
		(start 326.593962 -187.67298)
		(end 326.54875 -187.49518)
		(width 0.14224)
		(layer "In6.Cu")
		(net "GMI_CPU1_G0_CPU0_G2_TX_DP<2>")
	)
	(segment
		(start 100.823014 -228.749098)
		(end 100.783898 -228.771958)
		(width 0.1143)
		(layer "In6.Cu")
		(net "GMI_CPU1_G0_CPU0_G2_TX_DP<2>")
	)
	(segment
		(start 372.597172 -240.753646)
		(end 372.597934 -240.753138)
		(width 0.1143)
		(layer "In6.Cu")
		(net "GMI_CPU1_G0_CPU0_G2_TX_DP<2>")
	)
	(segment
		(start 372.591838 -241.731546)
		(end 372.590822 -241.731038)
		(width 0.1143)
		(layer "In6.Cu")
		(net "GMI_CPU1_G0_CPU0_G2_TX_DP<2>")
	)
	(segment
		(start 98.872294 -240.73866)
		(end 98.895408 -240.752122)
		(width 0.1143)
		(layer "In6.Cu")
		(net "GMI_CPU1_G0_CPU0_G2_TX_DP<2>")
	)
	(segment
		(start 100.353114 -236.038898)
		(end 100.315014 -236.06125)
		(width 0.1143)
		(layer "In6.Cu")
		(net "GMI_CPU1_G0_CPU0_G2_TX_DP<2>")
	)
	(segment
		(start 331.13218 -190.981076)
		(end 330.17333 -190.129922)
		(width 0.14224)
		(layer "In6.Cu")
		(net "GMI_CPU1_G0_CPU0_G2_TX_DP<2>")
	)
	(segment
		(start 370.672868 -227.819712)
		(end 370.742464 -227.779072)
		(width 0.1143)
		(layer "In6.Cu")
		(net "GMI_CPU1_G0_CPU0_G2_TX_DP<2>")
	)
	(segment
		(start 371.683788 -236.890052)
		(end 371.656864 -236.874558)
		(width 0.1143)
		(layer "In6.Cu")
		(net "GMI_CPU1_G0_CPU0_G2_TX_DP<2>")
	)
	(segment
		(start 329.169776 -189.412118)
		(end 328.856086 -189.133734)
		(width 0.14224)
		(layer "In6.Cu")
		(net "GMI_CPU1_G0_CPU0_G2_TX_DP<2>")
	)
	(segment
		(start 370.742464 -235.269278)
		(end 370.672868 -235.228638)
		(width 0.1143)
		(layer "In6.Cu")
		(net "GMI_CPU1_G0_CPU0_G2_TX_DP<2>")
	)
	(segment
		(start 103.129588 -223.106996)
		(end 103.128064 -223.107758)
		(width 0.1143)
		(layer "In6.Cu")
		(net "GMI_CPU1_G0_CPU0_G2_TX_DP<2>")
	)
	(segment
		(start 103.932228 -217.7923)
		(end 103.932228 -221.064836)
		(width 0.14224)
		(layer "In6.Cu")
		(net "GMI_CPU1_G0_CPU0_G2_TX_DP<2>")
	)
	(segment
		(start 98.90506 -240.11128)
		(end 98.904044 -240.111788)
		(width 0.1143)
		(layer "In6.Cu")
		(net "GMI_CPU1_G0_CPU0_G2_TX_DP<2>")
	)
	(segment
		(start 100.751386 -229.398068)
		(end 100.783898 -229.416864)
		(width 0.1143)
		(layer "In6.Cu")
		(net "GMI_CPU1_G0_CPU0_G2_TX_DP<2>")
	)
	(segment
		(start 370.23929 -226.340162)
		(end 370.202714 -226.318826)
		(width 0.1143)
		(layer "In6.Cu")
		(net "GMI_CPU1_G0_CPU0_G2_TX_DP<2>")
	)
	(segment
		(start 372.152418 -237.699296)
		(end 372.082822 -237.658656)
		(width 0.1143)
		(layer "In6.Cu")
		(net "GMI_CPU1_G0_CPU0_G2_TX_DP<2>")
	)
	(segment
		(start 104.490012 -216.784174)
		(end 104.329484 -217.171524)
		(width 0.14224)
		(layer "In6.Cu")
		(net "GMI_CPU1_G0_CPU0_G2_TX_DP<2>")
	)
	(segment
		(start 372.59387 -240.112804)
		(end 372.5926 -240.112042)
		(width 0.1143)
		(layer "In6.Cu")
		(net "GMI_CPU1_G0_CPU0_G2_TX_DP<2>")
	)
	(segment
		(start 328.845164 -188.950854)
		(end 328.531982 -188.672724)
		(width 0.14224)
		(layer "In6.Cu")
		(net "GMI_CPU1_G0_CPU0_G2_TX_DP<2>")
	)
	(segment
		(start 372.082822 -238.349536)
		(end 372.152418 -238.308896)
		(width 0.1143)
		(layer "In6.Cu")
		(net "GMI_CPU1_G0_CPU0_G2_TX_DP<2>")
	)
	(segment
		(start 372.591838 -240.756694)
		(end 372.5926 -240.756186)
		(width 0.1143)
		(layer "In6.Cu")
		(net "GMI_CPU1_G0_CPU0_G2_TX_DP<2>")
	)
	(segment
		(start 329.99045 -190.140844)
		(end 329.67676 -189.86246)
		(width 0.14224)
		(layer "In6.Cu")
		(net "GMI_CPU1_G0_CPU0_G2_TX_DP<2>")
	)
	(segment
		(start 369.333526 -224.739962)
		(end 369.232942 -224.681796)
		(width 0.1143)
		(layer "In6.Cu")
		(net "GMI_CPU1_G0_CPU0_G2_TX_DP<2>")
	)
	(segment
		(start 369.80241 -225.54946)
		(end 369.732814 -225.50882)
		(width 0.1143)
		(layer "In6.Cu")
		(net "GMI_CPU1_G0_CPU0_G2_TX_DP<2>")
	)
	(segment
		(start 99.41306 -237.65891)
		(end 99.373944 -237.68177)
		(width 0.1143)
		(layer "In6.Cu")
		(net "GMI_CPU1_G0_CPU0_G2_TX_DP<2>")
	)
	(segment
		(start 99.41306 -239.278922)
		(end 99.373944 -239.301782)
		(width 0.1143)
		(layer "In6.Cu")
		(net "GMI_CPU1_G0_CPU0_G2_TX_DP<2>")
	)
	(segment
		(start 326.188578 -187.281312)
		(end 326.011032 -187.326524)
		(width 0.14224)
		(layer "In6.Cu")
		(net "GMI_CPU1_G0_CPU0_G2_TX_DP<2>")
	)
	(segment
		(start 367.609374 -221.2467)
		(end 367.609374 -221.13875)
		(width 0.1143)
		(layer "In6.Cu")
		(net "GMI_CPU1_G0_CPU0_G2_TX_DP<2>")
	)
	(segment
		(start 100.783898 -235.251752)
		(end 100.753418 -235.269532)
		(width 0.1143)
		(layer "In6.Cu")
		(net "GMI_CPU1_G0_CPU0_G2_TX_DP<2>")
	)
	(segment
		(start 99.839018 -236.874812)
		(end 99.812094 -236.890306)
		(width 0.1143)
		(layer "In6.Cu")
		(net "GMI_CPU1_G0_CPU0_G2_TX_DP<2>")
	)
	(segment
		(start 370.711984 -229.41661)
		(end 370.744496 -229.397814)
		(width 0.1143)
		(layer "In6.Cu")
		(net "GMI_CPU1_G0_CPU0_G2_TX_DP<2>")
	)
	(segment
		(start 100.783898 -234.2769)
		(end 100.823014 -234.29976)
		(width 0.1143)
		(layer "In6.Cu")
		(net "GMI_CPU1_G0_CPU0_G2_TX_DP<2>")
	)
	(segment
		(start 325.60514 -186.934856)
		(end 325.244968 -186.720988)
		(width 0.14224)
		(layer "In6.Cu")
		(net "GMI_CPU1_G0_CPU0_G2_TX_DP<2>")
	)
	(segment
		(start 372.5926 -240.756186)
		(end 372.59387 -240.755424)
		(width 0.1143)
		(layer "In6.Cu")
		(net "GMI_CPU1_G0_CPU0_G2_TX_DP<2>")
	)
	(segment
		(start 368.832638 -223.911922)
		(end 368.793522 -223.889316)
		(width 0.1143)
		(layer "In6.Cu")
		(net "GMI_CPU1_G0_CPU0_G2_TX_DP<2>")
	)
	(segment
		(start 100.823014 -231.988868)
		(end 100.783898 -232.011728)
		(width 0.1143)
		(layer "In6.Cu")
		(net "GMI_CPU1_G0_CPU0_G2_TX_DP<2>")
	)
	(segment
		(start 101.255068 -226.341432)
		(end 101.254052 -226.34194)
		(width 0.1143)
		(layer "In6.Cu")
		(net "GMI_CPU1_G0_CPU0_G2_TX_DP<2>")
	)
	(segment
		(start 98.906584 -241.730276)
		(end 98.90506 -241.731292)
		(width 0.1143)
		(layer "In6.Cu")
		(net "GMI_CPU1_G0_CPU0_G2_TX_DP<2>")
	)
	(segment
		(start 325.067422 -186.7662)
		(end 324.706996 -186.552078)
		(width 0.14224)
		(layer "In6.Cu")
		(net "GMI_CPU1_G0_CPU0_G2_TX_DP<2>")
	)
	(segment
		(start 100.823014 -227.129086)
		(end 100.783898 -227.151946)
		(width 0.1143)
		(layer "In6.Cu")
		(net "GMI_CPU1_G0_CPU0_G2_TX_DP<2>")
	)
	(segment
		(start 103.932228 -221.093284)
		(end 103.886508 -221.139004)
		(width 0.1143)
		(layer "In6.Cu")
		(net "GMI_CPU1_G0_CPU0_G2_TX_DP<2>")
	)
	(segment
		(start 103.63835 -222.272606)
		(end 103.568754 -222.312738)
		(width 0.1143)
		(layer "In6.Cu")
		(net "GMI_CPU1_G0_CPU0_G2_TX_DP<2>")
	)
	(segment
		(start 100.783898 -233.63174)
		(end 100.753418 -233.64952)
		(width 0.1143)
		(layer "In6.Cu")
		(net "GMI_CPU1_G0_CPU0_G2_TX_DP<2>")
	)
	(segment
		(start 326.954642 -187.886848)
		(end 326.593962 -187.67298)
		(width 0.14224)
		(layer "In6.Cu")
		(net "GMI_CPU1_G0_CPU0_G2_TX_DP<2>")
	)
	(segment
		(start 100.823014 -233.60888)
		(end 100.783898 -233.63174)
		(width 0.1143)
		(layer "In6.Cu")
		(net "GMI_CPU1_G0_CPU0_G2_TX_DP<2>")
	)
	(segment
		(start 100.783898 -232.011728)
		(end 100.753418 -232.029508)
		(width 0.1143)
		(layer "In6.Cu")
		(net "GMI_CPU1_G0_CPU0_G2_TX_DP<2>")
	)
	(segment
		(start 370.742464 -227.169472)
		(end 370.672868 -227.128832)
		(width 0.1143)
		(layer "In6.Cu")
		(net "GMI_CPU1_G0_CPU0_G2_TX_DP<2>")
	)
	(segment
		(start 98.94316 -240.088928)
		(end 98.906584 -240.110264)
		(width 0.1143)
		(layer "In6.Cu")
		(net "GMI_CPU1_G0_CPU0_G2_TX_DP<2>")
	)
	(segment
		(start 103.887016 -221.247462)
		(end 103.887016 -221.804484)
		(width 0.1143)
		(layer "In6.Cu")
		(net "GMI_CPU1_G0_CPU0_G2_TX_DP<2>")
	)
	(segment
		(start 98.89871 -240.7539)
		(end 98.899726 -240.754408)
		(width 0.1143)
		(layer "In6.Cu")
		(net "GMI_CPU1_G0_CPU0_G2_TX_DP<2>")
	)
	(segment
		(start 370.742464 -228.789484)
		(end 370.672868 -228.748844)
		(width 0.1143)
		(layer "In6.Cu")
		(net "GMI_CPU1_G0_CPU0_G2_TX_DP<2>")
	)
	(segment
		(start 372.590822 -240.757202)
		(end 372.591838 -240.756694)
		(width 0.1143)
		(layer "In6.Cu")
		(net "GMI_CPU1_G0_CPU0_G2_TX_DP<2>")
	)
	(segment
		(start 101.254052 -226.34194)
		(end 101.25329 -226.342448)
		(width 0.1143)
		(layer "In6.Cu")
		(net "GMI_CPU1_G0_CPU0_G2_TX_DP<2>")
	)
	(segment
		(start 327.132188 -187.841636)
		(end 326.954642 -187.886848)
		(width 0.14224)
		(layer "In6.Cu")
		(net "GMI_CPU1_G0_CPU0_G2_TX_DP<2>")
	)
	(segment
		(start 114.498882 -205.662276)
		(end 105.037382 -215.123776)
		(width 0.14224)
		(layer "In6.Cu")
		(net "GMI_CPU1_G0_CPU0_G2_TX_DP<2>")
	)
	(segment
		(start 330.17333 -190.129922)
		(end 329.99045 -190.140844)
		(width 0.14224)
		(layer "In6.Cu")
		(net "GMI_CPU1_G0_CPU0_G2_TX_DP<2>")
	)
	(segment
		(start 326.011032 -187.326524)
		(end 325.650352 -187.112656)
		(width 0.14224)
		(layer "In6.Cu")
		(net "GMI_CPU1_G0_CPU0_G2_TX_DP<2>")
	)
	(segment
		(start 370.243862 -226.342956)
		(end 370.242592 -226.342194)
		(width 0.1143)
		(layer "In6.Cu")
		(net "GMI_CPU1_G0_CPU0_G2_TX_DP<2>")
	)
	(segment
		(start 98.897948 -240.753392)
		(end 98.89871 -240.7539)
		(width 0.1143)
		(layer "In6.Cu")
		(net "GMI_CPU1_G0_CPU0_G2_TX_DP<2>")
	)
	(segment
		(start 370.672868 -231.059482)
		(end 370.711984 -231.036622)
		(width 0.1143)
		(layer "In6.Cu")
		(net "GMI_CPU1_G0_CPU0_G2_TX_DP<2>")
	)
	(segment
		(start 371.83949 -237.19409)
		(end 371.839744 -237.19409)
		(width 0.1143)
		(layer "In6.Cu")
		(net "GMI_CPU1_G0_CPU0_G2_TX_DP<2>")
	)
	(segment
		(start 371.184678 -236.063282)
		(end 371.182646 -236.062012)
		(width 0.1143)
		(layer "In6.Cu")
		(net "GMI_CPU1_G0_CPU0_G2_TX_DP<2>")
	)
	(segment
		(start 104.580182 -216.22766)
		(end 104.419908 -216.614756)
		(width 0.14224)
		(layer "In6.Cu")
		(net "GMI_CPU1_G0_CPU0_G2_TX_DP<2>")
	)
	(segment
		(start 99.83978 -236.874304)
		(end 99.839018 -236.874812)
		(width 0.1143)
		(layer "In6.Cu")
		(net "GMI_CPU1_G0_CPU0_G2_TX_DP<2>")
	)
	(segment
		(start 100.753418 -232.639108)
		(end 100.783898 -232.656888)
		(width 0.1143)
		(layer "In6.Cu")
		(net "GMI_CPU1_G0_CPU0_G2_TX_DP<2>")
	)
	(segment
		(start 100.783898 -232.656888)
		(end 100.823014 -232.679748)
		(width 0.1143)
		(layer "In6.Cu")
		(net "GMI_CPU1_G0_CPU0_G2_TX_DP<2>")
	)
	(segment
		(start 98.904044 -240.756948)
		(end 98.90506 -240.757456)
		(width 0.1143)
		(layer "In6.Cu")
		(net "GMI_CPU1_G0_CPU0_G2_TX_DP<2>")
	)
	(segment
		(start 98.94316 -241.70894)
		(end 98.906584 -241.730276)
		(width 0.1143)
		(layer "In6.Cu")
		(net "GMI_CPU1_G0_CPU0_G2_TX_DP<2>")
	)
	(segment
		(start 100.753418 -234.25912)
		(end 100.783898 -234.2769)
		(width 0.1143)
		(layer "In6.Cu")
		(net "GMI_CPU1_G0_CPU0_G2_TX_DP<2>")
	)
	(segment
		(start 98.903282 -240.112296)
		(end 98.872294 -240.130076)
		(width 0.1143)
		(layer "In6.Cu")
		(net "GMI_CPU1_G0_CPU0_G2_TX_DP<2>")
	)
	(segment
		(start 98.902012 -240.755678)
		(end 98.903282 -240.75644)
		(width 0.1143)
		(layer "In6.Cu")
		(net "GMI_CPU1_G0_CPU0_G2_TX_DP<2>")
	)
	(segment
		(start 98.903282 -241.732308)
		(end 98.872294 -241.750088)
		(width 0.1143)
		(layer "In6.Cu")
		(net "GMI_CPU1_G0_CPU0_G2_TX_DP<2>")
	)
	(segment
		(start 104.909874 -215.770206)
		(end 104.7496 -216.157556)
		(width 0.14224)
		(layer "In6.Cu")
		(net "GMI_CPU1_G0_CPU0_G2_TX_DP<2>")
	)
	(segment
		(start 98.904044 -240.111788)
		(end 98.903282 -240.112296)
		(width 0.1143)
		(layer "In6.Cu")
		(net "GMI_CPU1_G0_CPU0_G2_TX_DP<2>")
	)
	(segment
		(start 371.182646 -236.062012)
		(end 371.181884 -236.061504)
		(width 0.1143)
		(layer "In6.Cu")
		(net "GMI_CPU1_G0_CPU0_G2_TX_DP<2>")
	)
	(segment
		(start 367.608866 -221.247208)
		(end 367.609374 -221.2467)
		(width 0.1143)
		(layer "In6.Cu")
		(net "GMI_CPU1_G0_CPU0_G2_TX_DP<2>")
	)
	(segment
		(start 104.160066 -217.241882)
		(end 103.932228 -217.7923)
		(width 0.14224)
		(layer "In6.Cu")
		(net "GMI_CPU1_G0_CPU0_G2_TX_DP<2>")
	)
	(segment
		(start 98.904044 -241.7318)
		(end 98.903282 -241.732308)
		(width 0.1143)
		(layer "In6.Cu")
		(net "GMI_CPU1_G0_CPU0_G2_TX_DP<2>")
	)
	(segment
		(start 117.841776 -203.09713)
		(end 114.498882 -205.662276)
		(width 0.14224)
		(layer "In6.Cu")
		(net "GMI_CPU1_G0_CPU0_G2_TX_DP<2>")
	)
	(segment
		(start 98.323146 -242.864386)
		(end 98.621088 -242.864386)
		(width 0.1143)
		(layer "In6.Cu")
		(net "GMI_CPU1_G0_CPU0_G2_TX_DP<2>")
	)
	(segment
		(start 328.856086 -189.133734)
		(end 328.845164 -188.950854)
		(width 0.14224)
		(layer "In6.Cu")
		(net "GMI_CPU1_G0_CPU0_G2_TX_DP<2>")
	)
	(segment
		(start 101.763068 -225.509074)
		(end 101.723952 -225.531934)
		(width 0.1143)
		(layer "In6.Cu")
		(net "GMI_CPU1_G0_CPU0_G2_TX_DP<2>")
	)
	(segment
		(start 326.54875 -187.49518)
		(end 326.188578 -187.281312)
		(width 0.14224)
		(layer "In6.Cu")
		(net "GMI_CPU1_G0_CPU0_G2_TX_DP<2>")
	)
	(segment
		(start 370.742464 -233.649266)
		(end 370.672868 -233.608626)
		(width 0.1143)
		(layer "In6.Cu")
		(net "GMI_CPU1_G0_CPU0_G2_TX_DP<2>")
	)
	(segment
		(start 166.90086 -176.160684)
		(end 162.445954 -177.340768)
		(width 0.14224)
		(layer "In6.Cu")
		(net "GMI_CPU1_G0_CPU0_G2_TX_DP<2>")
	)
	(segment
		(start 103.886508 -221.139004)
		(end 103.886508 -221.246954)
		(width 0.1143)
		(layer "In6.Cu")
		(net "GMI_CPU1_G0_CPU0_G2_TX_DP<2>")
	)
	(segment
		(start 99.373944 -239.301782)
		(end 99.343464 -239.319562)
		(width 0.1143)
		(layer "In6.Cu")
		(net "GMI_CPU1_G0_CPU0_G2_TX_DP<2>")
	)
	(segment
		(start 329.67676 -189.86246)
		(end 329.665838 -189.67958)
		(width 0.14224)
		(layer "In6.Cu")
		(net "GMI_CPU1_G0_CPU0_G2_TX_DP<2>")
	)
	(segment
		(start 372.59387 -240.755424)
		(end 372.595394 -240.754662)
		(width 0.1143)
		(layer "In6.Cu")
		(net "GMI_CPU1_G0_CPU0_G2_TX_DP<2>")
	)
	(segment
		(start 371.181884 -236.061504)
		(end 371.180868 -236.060996)
		(width 0.1143)
		(layer "In6.Cu")
		(net "GMI_CPU1_G0_CPU0_G2_TX_DP<2>")
	)
	(segment
		(start 100.313998 -236.061758)
		(end 100.313236 -236.062266)
		(width 0.1143)
		(layer "In6.Cu")
		(net "GMI_CPU1_G0_CPU0_G2_TX_DP<2>")
	)
	(segment
		(start 369.014502 -224.30359)
		(end 369.014502 -224.228152)
		(width 0.1143)
		(layer "In6.Cu")
		(net "GMI_CPU1_G0_CPU0_G2_TX_DP<2>")
	)
	(segment
		(start 100.820474 -230.370634)
		(end 100.753418 -230.40975)
		(width 0.1143)
		(layer "In6.Cu")
		(net "GMI_CPU1_G0_CPU0_G2_TX_DP<2>")
	)
	(segment
		(start 98.900488 -240.754916)
		(end 98.902012 -240.755678)
		(width 0.1143)
		(layer "In6.Cu")
		(net "GMI_CPU1_G0_CPU0_G2_TX_DP<2>")
	)
	(segment
		(start 368.36477 -223.105726)
		(end 368.359182 -223.102424)
		(width 0.1143)
		(layer "In6.Cu")
		(net "GMI_CPU1_G0_CPU0_G2_TX_DP<2>")
	)
	(segment
		(start 372.874794 -242.864132)
		(end 373.172736 -242.864132)
		(width 0.1143)
		(layer "In6.Cu")
		(net "GMI_CPU1_G0_CPU0_G2_TX_DP<2>")
	)
	(segment
		(start 372.5926 -240.112042)
		(end 372.591838 -240.111534)
		(width 0.1143)
		(layer "In6.Cu")
		(net "GMI_CPU1_G0_CPU0_G2_TX_DP<2>")
	)
	(segment
		(start 325.244968 -186.720988)
		(end 325.067422 -186.7662)
		(width 0.14224)
		(layer "In6.Cu")
		(net "GMI_CPU1_G0_CPU0_G2_TX_DP<2>")
	)
	(segment
		(start 100.783898 -227.797106)
		(end 100.823014 -227.819966)
		(width 0.1143)
		(layer "In6.Cu")
		(net "GMI_CPU1_G0_CPU0_G2_TX_DP<2>")
	)
	(segment
		(start 368.366294 -223.106742)
		(end 368.36477 -223.105726)
		(width 0.1143)
		(layer "In6.Cu")
		(net "GMI_CPU1_G0_CPU0_G2_TX_DP<2>")
	)
	(segment
		(start 371.656864 -236.874558)
		(end 371.656102 -236.87405)
		(width 0.1143)
		(layer "In6.Cu")
		(net "GMI_CPU1_G0_CPU0_G2_TX_DP<2>")
	)
	(segment
		(start 102.26294 -224.68205)
		(end 102.162356 -224.740216)
		(width 0.1143)
		(layer "In6.Cu")
		(net "GMI_CPU1_G0_CPU0_G2_TX_DP<2>")
	)
	(segment
		(start 327.898252 -188.447172)
		(end 327.537572 -188.233304)
		(width 0.14224)
		(layer "In6.Cu")
		(net "GMI_CPU1_G0_CPU0_G2_TX_DP<2>")
	)
	(segment
		(start 103.932228 -221.064836)
		(end 103.932228 -221.093284)
		(width 0.1143)
		(layer "In6.Cu")
		(net "GMI_CPU1_G0_CPU0_G2_TX_DP<2>")
	)
	(segment
		(start 367.927128 -222.312484)
		(end 367.857532 -222.272352)
		(width 0.1143)
		(layer "In6.Cu")
		(net "GMI_CPU1_G0_CPU0_G2_TX_DP<2>")
	)
	(segment
		(start 328.075798 -188.40196)
		(end 327.898252 -188.447172)
		(width 0.14224)
		(layer "In6.Cu")
		(net "GMI_CPU1_G0_CPU0_G2_TX_DP<2>")
	)
	(segment
		(start 329.352656 -189.40145)
		(end 329.169776 -189.412118)
		(width 0.14224)
		(layer "In6.Cu")
		(net "GMI_CPU1_G0_CPU0_G2_TX_DP<2>")
	)
	(segment
		(start 104.83977 -215.600788)
		(end 104.909874 -215.770206)
		(width 0.14224)
		(layer "In6.Cu")
		(net "GMI_CPU1_G0_CPU0_G2_TX_DP<2>")
	)
	(segment
		(start 103.1367 -223.102678)
		(end 103.131112 -223.10598)
		(width 0.1143)
		(layer "In6.Cu")
		(net "GMI_CPU1_G0_CPU0_G2_TX_DP<2>")
	)
	(segment
		(start 372.552722 -240.779554)
		(end 372.589298 -240.758218)
		(width 0.1143)
		(layer "In6.Cu")
		(net "GMI_CPU1_G0_CPU0_G2_TX_DP<2>")
	)
	(segment
		(start 327.537572 -188.233304)
		(end 327.49236 -188.055504)
		(width 0.14224)
		(layer "In6.Cu")
		(net "GMI_CPU1_G0_CPU0_G2_TX_DP<2>")
	)
	(segment
		(start 373.172736 -242.864132)
		(end 373.242586 -242.794282)
		(width 0.1143)
		(layer "In6.Cu")
		(net "GMI_CPU1_G0_CPU0_G2_TX_DP<2>")
	)
	(segment
		(start 302.913288 -176.955196)
		(end 166.90086 -176.160684)
		(width 0.14224)
		(layer "In6.Cu")
		(net "GMI_CPU1_G0_CPU0_G2_TX_DP<2>")
	)
	(segment
		(start 98.253296 -242.794536)
		(end 98.323146 -242.864386)
		(width 0.1143)
		(layer "In6.Cu")
		(net "GMI_CPU1_G0_CPU0_G2_TX_DP<2>")
	)
	(segment
		(start 104.160066 -217.241628)
		(end 104.160066 -217.241882)
		(width 0.14224)
		(layer "In6.Cu")
		(net "GMI_CPU1_G0_CPU0_G2_TX_DP<2>")
	)
	(segment
		(start 370.240814 -226.341178)
		(end 370.23929 -226.340162)
		(width 0.1143)
		(layer "In6.Cu")
		(net "GMI_CPU1_G0_CPU0_G2_TX_DP<2>")
	)
	(segment
		(start 367.563654 -221.09303)
		(end 367.563654 -221.081346)
		(width 0.1143)
		(layer "In6.Cu")
		(net "GMI_CPU1_G0_CPU0_G2_TX_DP<2>")
	)
	(segment
		(start 104.329484 -217.171524)
		(end 104.160066 -217.241628)
		(width 0.14224)
		(layer "In6.Cu")
		(net "GMI_CPU1_G0_CPU0_G2_TX_DP<2>")
	)
	(segment
		(start 100.783898 -231.036876)
		(end 100.823014 -231.059736)
		(width 0.1143)
		(layer "In6.Cu")
		(net "GMI_CPU1_G0_CPU0_G2_TX_DP<2>")
	)
	(segment
		(start 98.899726 -240.754408)
		(end 98.900488 -240.754916)
		(width 0.1143)
		(layer "In6.Cu")
		(net "GMI_CPU1_G0_CPU0_G2_TX_DP<2>")
	)
	(segment
		(start 105.037382 -215.123776)
		(end 104.83977 -215.600788)
		(width 0.14224)
		(layer "In6.Cu")
		(net "GMI_CPU1_G0_CPU0_G2_TX_DP<2>")
	)
	(segment
		(start 328.531982 -188.672724)
		(end 328.075798 -188.40196)
		(width 0.14224)
		(layer "In6.Cu")
		(net "GMI_CPU1_G0_CPU0_G2_TX_DP<2>")
	)
	(segment
		(start 98.895408 -240.752122)
		(end 98.897948 -240.753392)
		(width 0.1143)
		(layer "In6.Cu")
		(net "GMI_CPU1_G0_CPU0_G2_TX_DP<2>")
	)
	(segment
		(start 98.90506 -240.757456)
		(end 98.906584 -240.758472)
		(width 0.1143)
		(layer "In6.Cu")
		(net "GMI_CPU1_G0_CPU0_G2_TX_DP<2>")
	)
	(segment
		(start 370.27358 -226.359974)
		(end 370.243862 -226.342956)
		(width 0.1143)
		(layer "In6.Cu")
		(net "GMI_CPU1_G0_CPU0_G2_TX_DP<2>")
	)
	(segment
		(start 370.672868 -232.679494)
		(end 370.742464 -232.638854)
		(width 0.1143)
		(layer "In6.Cu")
		(net "GMI_CPU1_G0_CPU0_G2_TX_DP<2>")
	)
	(segment
		(start 99.373944 -238.32693)
		(end 99.41306 -238.34979)
		(width 0.1143)
		(layer "In6.Cu")
		(net "GMI_CPU1_G0_CPU0_G2_TX_DP<2>")
	)
	(segment
		(start 372.590822 -240.111026)
		(end 372.589298 -240.11001)
		(width 0.1143)
		(layer "In6.Cu")
		(net "GMI_CPU1_G0_CPU0_G2_TX_DP<2>")
	)
	(segment
		(start 372.597934 -240.753138)
		(end 372.599458 -240.752376)
		(width 0.1143)
		(layer "In6.Cu")
		(net "GMI_CPU1_G0_CPU0_G2_TX_DP<2>")
	)
	(segment
		(start 372.596156 -240.754154)
		(end 372.597172 -240.753646)
		(width 0.1143)
		(layer "In6.Cu")
		(net "GMI_CPU1_G0_CPU0_G2_TX_DP<2>")
	)
	(segment
		(start 372.589298 -241.730022)
		(end 372.552722 -241.708686)
		(width 0.1143)
		(layer "In6.Cu")
		(net "GMI_CPU1_G0_CPU0_G2_TX_DP<2>")
	)
	(arc
		(start 100.753418 -232.029508)
		(mid 100.596441 -232.334308)
		(end 100.753418 -232.639108)
		(width 0.1143)
		(layer "In6.Cu")
		(net "GMI_CPU1_G0_CPU0_G2_TX_DP<2>")
	)
	(arc
		(start 371.371876 -236.38637)
		(mid 371.322148 -236.200261)
		(end 371.186202 -236.06379)
		(width 0.1143)
		(layer "In6.Cu")
		(net "GMI_CPU1_G0_CPU0_G2_TX_DP<2>")
	)
	(arc
		(start 101.693472 -225.549714)
		(mid 101.578045 -225.68309)
		(end 101.5365 -225.854514)
		(width 0.1143)
		(layer "In6.Cu")
		(net "GMI_CPU1_G0_CPU0_G2_TX_DP<2>")
	)
	(arc
		(start 371.839744 -237.19409)
		(mid 371.798485 -237.023233)
		(end 371.683788 -236.890052)
		(width 0.1143)
		(layer "In6.Cu")
		(net "GMI_CPU1_G0_CPU0_G2_TX_DP<2>")
	)
	(arc
		(start 102.48138 -224.303844)
		(mid 102.422846 -224.522221)
		(end 102.26294 -224.68205)
		(width 0.1143)
		(layer "In6.Cu")
		(net "GMI_CPU1_G0_CPU0_G2_TX_DP<2>")
	)
	(arc
		(start 99.656392 -237.194344)
		(mid 99.591877 -237.456563)
		(end 99.41306 -237.65891)
		(width 0.1143)
		(layer "In6.Cu")
		(net "GMI_CPU1_G0_CPU0_G2_TX_DP<2>")
	)
	(arc
		(start 371.142768 -236.038644)
		(mid 370.963955 -235.836294)
		(end 370.899436 -235.574078)
		(width 0.1143)
		(layer "In6.Cu")
		(net "GMI_CPU1_G0_CPU0_G2_TX_DP<2>")
	)
	(arc
		(start 368.359182 -223.102424)
		(mid 368.154208 -222.895608)
		(end 368.079274 -222.614236)
		(width 0.1143)
		(layer "In6.Cu")
		(net "GMI_CPU1_G0_CPU0_G2_TX_DP<2>")
	)
	(arc
		(start 98.872294 -240.130076)
		(mid 98.716366 -240.434368)
		(end 98.872294 -240.73866)
		(width 0.1143)
		(layer "In6.Cu")
		(net "GMI_CPU1_G0_CPU0_G2_TX_DP<2>")
	)
	(arc
		(start 370.742464 -232.638854)
		(mid 370.899441 -232.334054)
		(end 370.742464 -232.029254)
		(width 0.1143)
		(layer "In6.Cu")
		(net "GMI_CPU1_G0_CPU0_G2_TX_DP<2>")
	)
	(arc
		(start 369.732814 -225.50882)
		(mid 369.554001 -225.30647)
		(end 369.489482 -225.044254)
		(width 0.1143)
		(layer "In6.Cu")
		(net "GMI_CPU1_G0_CPU0_G2_TX_DP<2>")
	)
	(arc
		(start 99.812094 -236.890306)
		(mid 99.697418 -237.023497)
		(end 99.656138 -237.194344)
		(width 0.1143)
		(layer "In6.Cu")
		(net "GMI_CPU1_G0_CPU0_G2_TX_DP<2>")
	)
	(arc
		(start 370.672868 -235.228638)
		(mid 370.429541 -234.764072)
		(end 370.672868 -234.299506)
		(width 0.1143)
		(layer "In6.Cu")
		(net "GMI_CPU1_G0_CPU0_G2_TX_DP<2>")
	)
	(arc
		(start 372.082822 -239.278668)
		(mid 371.839495 -238.814102)
		(end 372.082822 -238.349536)
		(width 0.1143)
		(layer "In6.Cu")
		(net "GMI_CPU1_G0_CPU0_G2_TX_DP<2>")
	)
	(arc
		(start 101.222302 -226.360228)
		(mid 101.107626 -226.493562)
		(end 101.066346 -226.66452)
		(width 0.1143)
		(layer "In6.Cu")
		(net "GMI_CPU1_G0_CPU0_G2_TX_DP<2>")
	)
	(arc
		(start 371.655086 -236.873542)
		(mid 371.447725 -236.668174)
		(end 371.371876 -236.38637)
		(width 0.1143)
		(layer "In6.Cu")
		(net "GMI_CPU1_G0_CPU0_G2_TX_DP<2>")
	)
	(arc
		(start 368.793522 -223.889316)
		(mid 368.614329 -223.686806)
		(end 368.549682 -223.424242)
		(width 0.1143)
		(layer "In6.Cu")
		(net "GMI_CPU1_G0_CPU0_G2_TX_DP<2>")
	)
	(arc
		(start 373.242586 -242.794282)
		(mid 373.190169 -242.662351)
		(end 373.092472 -242.559332)
		(width 0.1143)
		(layer "In6.Cu")
		(net "GMI_CPU1_G0_CPU0_G2_TX_DP<2>")
	)
	(arc
		(start 100.596446 -235.574332)
		(mid 100.531931 -235.836551)
		(end 100.353114 -236.038898)
		(width 0.1143)
		(layer "In6.Cu")
		(net "GMI_CPU1_G0_CPU0_G2_TX_DP<2>")
	)
	(arc
		(start 100.823014 -231.059736)
		(mid 101.066341 -231.524302)
		(end 100.823014 -231.988868)
		(width 0.1143)
		(layer "In6.Cu")
		(net "GMI_CPU1_G0_CPU0_G2_TX_DP<2>")
	)
	(arc
		(start 102.9462 -223.424496)
		(mid 102.881541 -223.687053)
		(end 102.70236 -223.88957)
		(width 0.1143)
		(layer "In6.Cu")
		(net "GMI_CPU1_G0_CPU0_G2_TX_DP<2>")
	)
	(arc
		(start 372.082822 -237.658656)
		(mid 371.904009 -237.456306)
		(end 371.83949 -237.19409)
		(width 0.1143)
		(layer "In6.Cu")
		(net "GMI_CPU1_G0_CPU0_G2_TX_DP<2>")
	)
	(arc
		(start 370.742464 -227.779072)
		(mid 370.899441 -227.474272)
		(end 370.742464 -227.169472)
		(width 0.1143)
		(layer "In6.Cu")
		(net "GMI_CPU1_G0_CPU0_G2_TX_DP<2>")
	)
	(arc
		(start 370.672868 -228.748844)
		(mid 370.429541 -228.284278)
		(end 370.672868 -227.819712)
		(width 0.1143)
		(layer "In6.Cu")
		(net "GMI_CPU1_G0_CPU0_G2_TX_DP<2>")
	)
	(arc
		(start 368.549682 -223.424242)
		(mid 368.500985 -223.241621)
		(end 368.367818 -223.107504)
		(width 0.1143)
		(layer "In6.Cu")
		(net "GMI_CPU1_G0_CPU0_G2_TX_DP<2>")
	)
	(arc
		(start 103.887016 -221.804484)
		(mid 103.820986 -222.069512)
		(end 103.63835 -222.272606)
		(width 0.1143)
		(layer "In6.Cu")
		(net "GMI_CPU1_G0_CPU0_G2_TX_DP<2>")
	)
	(arc
		(start 103.568754 -222.312738)
		(mid 103.456827 -222.44553)
		(end 103.416608 -222.61449)
		(width 0.1143)
		(layer "In6.Cu")
		(net "GMI_CPU1_G0_CPU0_G2_TX_DP<2>")
	)
	(arc
		(start 101.066346 -229.90429)
		(mid 101.00111 -230.167881)
		(end 100.820474 -230.370634)
		(width 0.1143)
		(layer "In6.Cu")
		(net "GMI_CPU1_G0_CPU0_G2_TX_DP<2>")
	)
	(arc
		(start 370.744496 -229.397814)
		(mid 370.858425 -229.264667)
		(end 370.899436 -229.094284)
		(width 0.1143)
		(layer "In6.Cu")
		(net "GMI_CPU1_G0_CPU0_G2_TX_DP<2>")
	)
	(arc
		(start 100.823014 -229.439724)
		(mid 101.001827 -229.642074)
		(end 101.066346 -229.90429)
		(width 0.1143)
		(layer "In6.Cu")
		(net "GMI_CPU1_G0_CPU0_G2_TX_DP<2>")
	)
	(arc
		(start 102.663244 -223.912176)
		(mid 102.530051 -224.045995)
		(end 102.48138 -224.228406)
		(width 0.1143)
		(layer "In6.Cu")
		(net "GMI_CPU1_G0_CPU0_G2_TX_DP<2>")
	)
	(arc
		(start 372.779544 -242.054126)
		(mid 372.738289 -241.883155)
		(end 372.623588 -241.749834)
		(width 0.1143)
		(layer "In6.Cu")
		(net "GMI_CPU1_G0_CPU0_G2_TX_DP<2>")
	)
	(arc
		(start 370.429536 -229.904036)
		(mid 370.494051 -229.641817)
		(end 370.672868 -229.43947)
		(width 0.1143)
		(layer "In6.Cu")
		(net "GMI_CPU1_G0_CPU0_G2_TX_DP<2>")
	)
	(arc
		(start 103.416608 -222.61449)
		(mid 103.341665 -222.895857)
		(end 103.1367 -223.102678)
		(width 0.1143)
		(layer "In6.Cu")
		(net "GMI_CPU1_G0_CPU0_G2_TX_DP<2>")
	)
	(arc
		(start 372.30939 -239.624108)
		(mid 372.267841 -239.452686)
		(end 372.152418 -239.319308)
		(width 0.1143)
		(layer "In6.Cu")
		(net "GMI_CPU1_G0_CPU0_G2_TX_DP<2>")
	)
	(arc
		(start 100.596446 -230.71455)
		(mid 100.637412 -230.884956)
		(end 100.751386 -231.01808)
		(width 0.1143)
		(layer "In6.Cu")
		(net "GMI_CPU1_G0_CPU0_G2_TX_DP<2>")
	)
	(arc
		(start 370.672868 -227.128832)
		(mid 370.494055 -226.926482)
		(end 370.429536 -226.664266)
		(width 0.1143)
		(layer "In6.Cu")
		(net "GMI_CPU1_G0_CPU0_G2_TX_DP<2>")
	)
	(arc
		(start 369.232942 -224.681796)
		(mid 369.073033 -224.521969)
		(end 369.014502 -224.30359)
		(width 0.1143)
		(layer "In6.Cu")
		(net "GMI_CPU1_G0_CPU0_G2_TX_DP<2>")
	)
	(arc
		(start 100.753418 -227.169726)
		(mid 100.596441 -227.474526)
		(end 100.753418 -227.779326)
		(width 0.1143)
		(layer "In6.Cu")
		(net "GMI_CPU1_G0_CPU0_G2_TX_DP<2>")
	)
	(arc
		(start 372.552722 -241.708686)
		(mid 372.309395 -241.24412)
		(end 372.552722 -240.779554)
		(width 0.1143)
		(layer "In6.Cu")
		(net "GMI_CPU1_G0_CPU0_G2_TX_DP<2>")
	)
	(arc
		(start 100.823014 -227.819966)
		(mid 101.066341 -228.284532)
		(end 100.823014 -228.749098)
		(width 0.1143)
		(layer "In6.Cu")
		(net "GMI_CPU1_G0_CPU0_G2_TX_DP<2>")
	)
	(arc
		(start 98.40341 -242.559586)
		(mid 98.305645 -242.662562)
		(end 98.253296 -242.794536)
		(width 0.1143)
		(layer "In6.Cu")
		(net "GMI_CPU1_G0_CPU0_G2_TX_DP<2>")
	)
	(arc
		(start 370.675408 -230.37038)
		(mid 370.494756 -230.167635)
		(end 370.429536 -229.904036)
		(width 0.1143)
		(layer "In6.Cu")
		(net "GMI_CPU1_G0_CPU0_G2_TX_DP<2>")
	)
	(arc
		(start 100.30968 -236.064044)
		(mid 100.173765 -236.200533)
		(end 100.124006 -236.386624)
		(width 0.1143)
		(layer "In6.Cu")
		(net "GMI_CPU1_G0_CPU0_G2_TX_DP<2>")
	)
	(arc
		(start 370.744496 -231.017826)
		(mid 370.858425 -230.884679)
		(end 370.899436 -230.714296)
		(width 0.1143)
		(layer "In6.Cu")
		(net "GMI_CPU1_G0_CPU0_G2_TX_DP<2>")
	)
	(arc
		(start 370.202714 -226.318826)
		(mid 370.023901 -226.116476)
		(end 369.959382 -225.85426)
		(width 0.1143)
		(layer "In6.Cu")
		(net "GMI_CPU1_G0_CPU0_G2_TX_DP<2>")
	)
	(arc
		(start 369.959382 -225.85426)
		(mid 369.917833 -225.682838)
		(end 369.80241 -225.54946)
		(width 0.1143)
		(layer "In6.Cu")
		(net "GMI_CPU1_G0_CPU0_G2_TX_DP<2>")
	)
	(arc
		(start 99.343464 -239.319562)
		(mid 99.228037 -239.452938)
		(end 99.186492 -239.624362)
		(width 0.1143)
		(layer "In6.Cu")
		(net "GMI_CPU1_G0_CPU0_G2_TX_DP<2>")
	)
	(arc
		(start 101.066346 -226.66452)
		(mid 101.001831 -226.926739)
		(end 100.823014 -227.129086)
		(width 0.1143)
		(layer "In6.Cu")
		(net "GMI_CPU1_G0_CPU0_G2_TX_DP<2>")
	)
	(arc
		(start 372.152418 -238.308896)
		(mid 372.309395 -238.004096)
		(end 372.152418 -237.699296)
		(width 0.1143)
		(layer "In6.Cu")
		(net "GMI_CPU1_G0_CPU0_G2_TX_DP<2>")
	)
	(arc
		(start 368.079274 -222.614236)
		(mid 368.039094 -222.445257)
		(end 367.927128 -222.312484)
		(width 0.1143)
		(layer "In6.Cu")
		(net "GMI_CPU1_G0_CPU0_G2_TX_DP<2>")
	)
	(arc
		(start 100.753418 -235.269532)
		(mid 100.637991 -235.402908)
		(end 100.596446 -235.574332)
		(width 0.1143)
		(layer "In6.Cu")
		(net "GMI_CPU1_G0_CPU0_G2_TX_DP<2>")
	)
	(arc
		(start 100.753418 -228.789738)
		(mid 100.637991 -228.923114)
		(end 100.596446 -229.094538)
		(width 0.1143)
		(layer "In6.Cu")
		(net "GMI_CPU1_G0_CPU0_G2_TX_DP<2>")
	)
	(arc
		(start 100.823014 -232.679748)
		(mid 101.066341 -233.144314)
		(end 100.823014 -233.60888)
		(width 0.1143)
		(layer "In6.Cu")
		(net "GMI_CPU1_G0_CPU0_G2_TX_DP<2>")
	)
	(arc
		(start 99.41306 -238.34979)
		(mid 99.656387 -238.814356)
		(end 99.41306 -239.278922)
		(width 0.1143)
		(layer "In6.Cu")
		(net "GMI_CPU1_G0_CPU0_G2_TX_DP<2>")
	)
	(arc
		(start 372.552722 -240.088674)
		(mid 372.373909 -239.886324)
		(end 372.30939 -239.624108)
		(width 0.1143)
		(layer "In6.Cu")
		(net "GMI_CPU1_G0_CPU0_G2_TX_DP<2>")
	)
	(arc
		(start 102.162356 -224.740216)
		(mid 102.04768 -224.87355)
		(end 102.0064 -225.044508)
		(width 0.1143)
		(layer "In6.Cu")
		(net "GMI_CPU1_G0_CPU0_G2_TX_DP<2>")
	)
	(arc
		(start 100.823014 -234.29976)
		(mid 101.066341 -234.764326)
		(end 100.823014 -235.228892)
		(width 0.1143)
		(layer "In6.Cu")
		(net "GMI_CPU1_G0_CPU0_G2_TX_DP<2>")
	)
	(arc
		(start 372.623588 -240.738406)
		(mid 372.779516 -240.434114)
		(end 372.623588 -240.129822)
		(width 0.1143)
		(layer "In6.Cu")
		(net "GMI_CPU1_G0_CPU0_G2_TX_DP<2>")
	)
	(arc
		(start 100.124006 -236.386624)
		(mid 100.048109 -236.6684)
		(end 99.840796 -236.873796)
		(width 0.1143)
		(layer "In6.Cu")
		(net "GMI_CPU1_G0_CPU0_G2_TX_DP<2>")
	)
	(arc
		(start 100.596446 -229.094538)
		(mid 100.637412 -229.264944)
		(end 100.751386 -229.398068)
		(width 0.1143)
		(layer "In6.Cu")
		(net "GMI_CPU1_G0_CPU0_G2_TX_DP<2>")
	)
	(arc
		(start 370.899436 -229.094284)
		(mid 370.857887 -228.922862)
		(end 370.742464 -228.789484)
		(width 0.1143)
		(layer "In6.Cu")
		(net "GMI_CPU1_G0_CPU0_G2_TX_DP<2>")
	)
	(arc
		(start 370.899436 -235.574078)
		(mid 370.857887 -235.402656)
		(end 370.742464 -235.269278)
		(width 0.1143)
		(layer "In6.Cu")
		(net "GMI_CPU1_G0_CPU0_G2_TX_DP<2>")
	)
	(arc
		(start 370.672868 -233.608626)
		(mid 370.429541 -233.14406)
		(end 370.672868 -232.679494)
		(width 0.1143)
		(layer "In6.Cu")
		(net "GMI_CPU1_G0_CPU0_G2_TX_DP<2>")
	)
	(arc
		(start 369.014502 -224.228152)
		(mid 368.965785 -224.045767)
		(end 368.832638 -223.911922)
		(width 0.1143)
		(layer "In6.Cu")
		(net "GMI_CPU1_G0_CPU0_G2_TX_DP<2>")
	)
	(arc
		(start 98.94316 -240.779808)
		(mid 99.186487 -241.244374)
		(end 98.94316 -241.70894)
		(width 0.1143)
		(layer "In6.Cu")
		(net "GMI_CPU1_G0_CPU0_G2_TX_DP<2>")
	)
	(arc
		(start 101.5365 -225.854514)
		(mid 101.471985 -226.116733)
		(end 101.293168 -226.31908)
		(width 0.1143)
		(layer "In6.Cu")
		(net "GMI_CPU1_G0_CPU0_G2_TX_DP<2>")
	)
	(arc
		(start 367.857532 -222.272352)
		(mid 367.67487 -222.069271)
		(end 367.608866 -221.80423)
		(width 0.1143)
		(layer "In6.Cu")
		(net "GMI_CPU1_G0_CPU0_G2_TX_DP<2>")
	)
	(arc
		(start 100.753418 -233.64952)
		(mid 100.596441 -233.95432)
		(end 100.753418 -234.25912)
		(width 0.1143)
		(layer "In6.Cu")
		(net "GMI_CPU1_G0_CPU0_G2_TX_DP<2>")
	)
	(arc
		(start 102.0064 -225.044508)
		(mid 101.941885 -225.306727)
		(end 101.763068 -225.509074)
		(width 0.1143)
		(layer "In6.Cu")
		(net "GMI_CPU1_G0_CPU0_G2_TX_DP<2>")
	)
	(arc
		(start 103.128064 -223.107758)
		(mid 102.994908 -223.241881)
		(end 102.9462 -223.424496)
		(width 0.1143)
		(layer "In6.Cu")
		(net "GMI_CPU1_G0_CPU0_G2_TX_DP<2>")
	)
	(arc
		(start 369.489482 -225.044254)
		(mid 369.448227 -224.873283)
		(end 369.333526 -224.739962)
		(width 0.1143)
		(layer "In6.Cu")
		(net "GMI_CPU1_G0_CPU0_G2_TX_DP<2>")
	)
	(arc
		(start 370.672868 -231.988614)
		(mid 370.429541 -231.524048)
		(end 370.672868 -231.059482)
		(width 0.1143)
		(layer "In6.Cu")
		(net "GMI_CPU1_G0_CPU0_G2_TX_DP<2>")
	)
	(arc
		(start 98.872294 -241.750088)
		(mid 98.757618 -241.883422)
		(end 98.716338 -242.05438)
		(width 0.1143)
		(layer "In6.Cu")
		(net "GMI_CPU1_G0_CPU0_G2_TX_DP<2>")
	)
	(arc
		(start 99.343464 -237.69955)
		(mid 99.186487 -238.00435)
		(end 99.343464 -238.30915)
		(width 0.1143)
		(layer "In6.Cu")
		(net "GMI_CPU1_G0_CPU0_G2_TX_DP<2>")
	)
	(arc
		(start 370.742464 -234.258866)
		(mid 370.899441 -233.954066)
		(end 370.742464 -233.649266)
		(width 0.1143)
		(layer "In6.Cu")
		(net "GMI_CPU1_G0_CPU0_G2_TX_DP<2>")
	)
	(arc
		(start 100.753418 -230.40975)
		(mid 100.637991 -230.543126)
		(end 100.596446 -230.71455)
		(width 0.1143)
		(layer "In6.Cu")
		(net "GMI_CPU1_G0_CPU0_G2_TX_DP<2>")
	)
	(arc
		(start 99.186492 -239.624362)
		(mid 99.121977 -239.886581)
		(end 98.94316 -240.088928)
		(width 0.1143)
		(layer "In6.Cu")
		(net "GMI_CPU1_G0_CPU0_G2_TX_DP<2>")
	)
	(arc
		(start 370.899436 -230.714296)
		(mid 370.857887 -230.542874)
		(end 370.742464 -230.409496)
		(width 0.1143)
		(layer "In6.Cu")
		(net "GMI_CPU1_G0_CPU0_G2_TX_DP<2>")
	)
	(arc
		(start 370.429536 -226.664266)
		(mid 370.388281 -226.493295)
		(end 370.27358 -226.359974)
		(width 0.1143)
		(layer "In6.Cu")
		(net "GMI_CPU1_G0_CPU0_G2_TX_DP<2>")
	)
	(arc
		(start 98.716338 -242.05438)
		(mid 98.651823 -242.316599)
		(end 98.473006 -242.518946)
		(width 0.1143)
		(layer "In6.Cu")
		(net "GMI_CPU1_G0_CPU0_G2_TX_DP<2>")
	)
	(arc
		(start 373.022876 -242.518692)
		(mid 372.844063 -242.316342)
		(end 372.779544 -242.054126)
		(width 0.1143)
		(layer "In6.Cu")
		(net "GMI_CPU1_G0_CPU0_G2_TX_DP<2>")
	)
	(segment
		(start 99.08794 -239.8903)
		(end 98.621088 -239.624362)
		(width 0.12954)
		(layer "F.Cu")
		(net "GMI_CPU1_G0_CPU0_G2_TX_DP<1>")
	)
	(segment
		(start 372.407942 -239.890046)
		(end 372.874794 -239.624108)
		(width 0.12954)
		(layer "F.Cu")
		(net "GMI_CPU1_G0_CPU0_G2_TX_DP<1>")
	)
	(segment
		(start 101.256592 -224.720404)
		(end 101.255068 -224.72142)
		(width 0.1143)
		(layer "In6.Cu")
		(net "GMI_CPU1_G0_CPU0_G2_TX_DP<1>")
	)
	(segment
		(start 367.253774 -215.20023)
		(end 362.556552 -210.502754)
		(width 0.14224)
		(layer "In6.Cu")
		(net "GMI_CPU1_G0_CPU0_G2_TX_DP<1>")
	)
	(segment
		(start 100.313236 -226.342448)
		(end 100.310696 -226.343972)
		(width 0.1143)
		(layer "In6.Cu")
		(net "GMI_CPU1_G0_CPU0_G2_TX_DP<1>")
	)
	(segment
		(start 99.373944 -236.061758)
		(end 99.343464 -236.079538)
		(width 0.1143)
		(layer "In6.Cu")
		(net "GMI_CPU1_G0_CPU0_G2_TX_DP<1>")
	)
	(segment
		(start 368.859308 -222.31985)
		(end 368.790728 -222.280226)
		(width 0.1143)
		(layer "In6.Cu")
		(net "GMI_CPU1_G0_CPU0_G2_TX_DP<1>")
	)
	(segment
		(start 368.504216 -221.107508)
		(end 368.504216 -221.09303)
		(width 0.1143)
		(layer "In6.Cu")
		(net "GMI_CPU1_G0_CPU0_G2_TX_DP<1>")
	)
	(segment
		(start 99.910392 -233.593386)
		(end 99.812348 -233.650028)
		(width 0.1143)
		(layer "In6.Cu")
		(net "GMI_CPU1_G0_CPU0_G2_TX_DP<1>")
	)
	(segment
		(start 99.844098 -234.2769)
		(end 99.88042 -234.297982)
		(width 0.1143)
		(layer "In6.Cu")
		(net "GMI_CPU1_G0_CPU0_G2_TX_DP<1>")
	)
	(segment
		(start 98.904044 -236.871764)
		(end 98.903282 -236.872272)
		(width 0.1143)
		(layer "In6.Cu")
		(net "GMI_CPU1_G0_CPU0_G2_TX_DP<1>")
	)
	(segment
		(start 99.877626 -229.436422)
		(end 99.88042 -229.437946)
		(width 0.1143)
		(layer "In6.Cu")
		(net "GMI_CPU1_G0_CPU0_G2_TX_DP<1>")
	)
	(segment
		(start 371.683534 -232.638092)
		(end 371.683534 -232.638346)
		(width 0.1143)
		(layer "In6.Cu")
		(net "GMI_CPU1_G0_CPU0_G2_TX_DP<1>")
	)
	(segment
		(start 98.473006 -237.65891)
		(end 98.43389 -237.68177)
		(width 0.1143)
		(layer "In6.Cu")
		(net "GMI_CPU1_G0_CPU0_G2_TX_DP<1>")
	)
	(segment
		(start 331.605636 -190.147448)
		(end 329.19162 -187.948316)
		(width 0.14224)
		(layer "In6.Cu")
		(net "GMI_CPU1_G0_CPU0_G2_TX_DP<1>")
	)
	(segment
		(start 99.812348 -227.778818)
		(end 99.840542 -227.795074)
		(width 0.1143)
		(layer "In6.Cu")
		(net "GMI_CPU1_G0_CPU0_G2_TX_DP<1>")
	)
	(segment
		(start 113.13287 -205.505812)
		(end 111.261144 -207.377538)
		(width 0.14224)
		(layer "In6.Cu")
		(net "GMI_CPU1_G0_CPU0_G2_TX_DP<1>")
	)
	(segment
		(start 368.504216 -218.223846)
		(end 367.253774 -215.20023)
		(width 0.14224)
		(layer "In6.Cu")
		(net "GMI_CPU1_G0_CPU0_G2_TX_DP<1>")
	)
	(segment
		(start 99.91979 -233.584242)
		(end 99.910392 -233.593386)
		(width 0.1143)
		(layer "In6.Cu")
		(net "GMI_CPU1_G0_CPU0_G2_TX_DP<1>")
	)
	(segment
		(start 109.991144 -208.647538)
		(end 109.69498 -208.943702)
		(width 0.14224)
		(layer "In6.Cu")
		(net "GMI_CPU1_G0_CPU0_G2_TX_DP<1>")
	)
	(segment
		(start 371.651784 -234.276646)
		(end 371.683534 -234.258358)
		(width 0.1143)
		(layer "In6.Cu")
		(net "GMI_CPU1_G0_CPU0_G2_TX_DP<1>")
	)
	(segment
		(start 371.651784 -228.771704)
		(end 371.651276 -228.771704)
		(width 0.1143)
		(layer "In6.Cu")
		(net "GMI_CPU1_G0_CPU0_G2_TX_DP<1>")
	)
	(segment
		(start 371.615462 -229.437692)
		(end 371.618256 -229.436168)
		(width 0.1143)
		(layer "In6.Cu")
		(net "GMI_CPU1_G0_CPU0_G2_TX_DP<1>")
	)
	(segment
		(start 100.353114 -226.31908)
		(end 100.315014 -226.341432)
		(width 0.1143)
		(layer "In6.Cu")
		(net "GMI_CPU1_G0_CPU0_G2_TX_DP<1>")
	)
	(segment
		(start 99.41306 -236.038898)
		(end 99.373944 -236.061758)
		(width 0.1143)
		(layer "In6.Cu")
		(net "GMI_CPU1_G0_CPU0_G2_TX_DP<1>")
	)
	(segment
		(start 98.90506 -236.871256)
		(end 98.904044 -236.871764)
		(width 0.1143)
		(layer "In6.Cu")
		(net "GMI_CPU1_G0_CPU0_G2_TX_DP<1>")
	)
	(segment
		(start 98.323146 -239.624362)
		(end 98.621088 -239.624362)
		(width 0.1143)
		(layer "In6.Cu")
		(net "GMI_CPU1_G0_CPU0_G2_TX_DP<1>")
	)
	(segment
		(start 371.654324 -228.773228)
		(end 371.653562 -228.77272)
		(width 0.1143)
		(layer "In6.Cu")
		(net "GMI_CPU1_G0_CPU0_G2_TX_DP<1>")
	)
	(segment
		(start 99.843336 -228.772466)
		(end 99.812348 -228.790246)
		(width 0.1143)
		(layer "In6.Cu")
		(net "GMI_CPU1_G0_CPU0_G2_TX_DP<1>")
	)
	(segment
		(start 98.43389 -237.68177)
		(end 98.40341 -237.69955)
		(width 0.1143)
		(layer "In6.Cu")
		(net "GMI_CPU1_G0_CPU0_G2_TX_DP<1>")
	)
	(segment
		(start 99.81565 -232.640378)
		(end 99.90582 -232.705148)
		(width 0.1143)
		(layer "In6.Cu")
		(net "GMI_CPU1_G0_CPU0_G2_TX_DP<1>")
	)
	(segment
		(start 108.911898 -209.91703)
		(end 108.61548 -210.213702)
		(width 0.14224)
		(layer "In6.Cu")
		(net "GMI_CPU1_G0_CPU0_G2_TX_DP<1>")
	)
	(segment
		(start 107.049316 -211.779866)
		(end 106.858816 -211.779866)
		(width 0.14224)
		(layer "In6.Cu")
		(net "GMI_CPU1_G0_CPU0_G2_TX_DP<1>")
	)
	(segment
		(start 109.69498 -208.943702)
		(end 109.69498 -209.133948)
		(width 0.14224)
		(layer "In6.Cu")
		(net "GMI_CPU1_G0_CPU0_G2_TX_DP<1>")
	)
	(segment
		(start 371.651276 -227.796852)
		(end 371.651784 -227.796852)
		(width 0.1143)
		(layer "In6.Cu")
		(net "GMI_CPU1_G0_CPU0_G2_TX_DP<1>")
	)
	(segment
		(start 371.68201 -233.649012)
		(end 371.612922 -233.60888)
		(width 0.1143)
		(layer "In6.Cu")
		(net "GMI_CPU1_G0_CPU0_G2_TX_DP<1>")
	)
	(segment
		(start 98.473006 -239.278922)
		(end 98.43389 -239.301782)
		(width 0.1143)
		(layer "In6.Cu")
		(net "GMI_CPU1_G0_CPU0_G2_TX_DP<1>")
	)
	(segment
		(start 373.092472 -237.699296)
		(end 373.022876 -237.658656)
		(width 0.1143)
		(layer "In6.Cu")
		(net "GMI_CPU1_G0_CPU0_G2_TX_DP<1>")
	)
	(segment
		(start 371.654324 -227.795328)
		(end 371.65534 -227.79482)
		(width 0.1143)
		(layer "In6.Cu")
		(net "GMI_CPU1_G0_CPU0_G2_TX_DP<1>")
	)
	(segment
		(start 100.313998 -226.34194)
		(end 100.313236 -226.342448)
		(width 0.1143)
		(layer "In6.Cu")
		(net "GMI_CPU1_G0_CPU0_G2_TX_DP<1>")
	)
	(segment
		(start 98.903282 -236.872272)
		(end 98.872294 -236.890052)
		(width 0.1143)
		(layer "In6.Cu")
		(net "GMI_CPU1_G0_CPU0_G2_TX_DP<1>")
	)
	(segment
		(start 166.757096 -175.226726)
		(end 162.080448 -176.465484)
		(width 0.14224)
		(layer "In6.Cu")
		(net "GMI_CPU1_G0_CPU0_G2_TX_DP<1>")
	)
	(segment
		(start 99.844098 -232.011728)
		(end 99.812348 -232.030016)
		(width 0.1143)
		(layer "In6.Cu")
		(net "GMI_CPU1_G0_CPU0_G2_TX_DP<1>")
	)
	(segment
		(start 371.651784 -235.251498)
		(end 371.615462 -235.230416)
		(width 0.1143)
		(layer "In6.Cu")
		(net "GMI_CPU1_G0_CPU0_G2_TX_DP<1>")
	)
	(segment
		(start 98.43389 -239.301782)
		(end 98.40341 -239.319562)
		(width 0.1143)
		(layer "In6.Cu")
		(net "GMI_CPU1_G0_CPU0_G2_TX_DP<1>")
	)
	(segment
		(start 100.315014 -226.341432)
		(end 100.313998 -226.34194)
		(width 0.1143)
		(layer "In6.Cu")
		(net "GMI_CPU1_G0_CPU0_G2_TX_DP<1>")
	)
	(segment
		(start 101.723952 -223.911922)
		(end 101.693472 -223.929702)
		(width 0.1143)
		(layer "In6.Cu")
		(net "GMI_CPU1_G0_CPU0_G2_TX_DP<1>")
	)
	(segment
		(start 372.591838 -236.87151)
		(end 372.590822 -236.871002)
		(width 0.1143)
		(layer "In6.Cu")
		(net "GMI_CPU1_G0_CPU0_G2_TX_DP<1>")
	)
	(segment
		(start 368.504216 -221.09303)
		(end 368.504216 -218.223846)
		(width 0.14224)
		(layer "In6.Cu")
		(net "GMI_CPU1_G0_CPU0_G2_TX_DP<1>")
	)
	(segment
		(start 99.88042 -235.23067)
		(end 99.844098 -235.251752)
		(width 0.1143)
		(layer "In6.Cu")
		(net "GMI_CPU1_G0_CPU0_G2_TX_DP<1>")
	)
	(segment
		(start 99.812856 -232.6386)
		(end 99.81565 -232.640378)
		(width 0.1143)
		(layer "In6.Cu")
		(net "GMI_CPU1_G0_CPU0_G2_TX_DP<1>")
	)
	(segment
		(start 99.878642 -230.37165)
		(end 99.812348 -230.410258)
		(width 0.1143)
		(layer "In6.Cu")
		(net "GMI_CPU1_G0_CPU0_G2_TX_DP<1>")
	)
	(segment
		(start 99.843336 -231.036368)
		(end 99.844098 -231.036876)
		(width 0.1143)
		(layer "In6.Cu")
		(net "GMI_CPU1_G0_CPU0_G2_TX_DP<1>")
	)
	(segment
		(start 105.77957 -212.859112)
		(end 105.77957 -213.049358)
		(width 0.14224)
		(layer "In6.Cu")
		(net "GMI_CPU1_G0_CPU0_G2_TX_DP<1>")
	)
	(segment
		(start 370.23929 -224.72015)
		(end 370.202714 -224.698814)
		(width 0.1143)
		(layer "In6.Cu")
		(net "GMI_CPU1_G0_CPU0_G2_TX_DP<1>")
	)
	(segment
		(start 99.844098 -235.251752)
		(end 99.812348 -235.27004)
		(width 0.1143)
		(layer "In6.Cu")
		(net "GMI_CPU1_G0_CPU0_G2_TX_DP<1>")
	)
	(segment
		(start 370.242592 -224.722182)
		(end 370.24183 -224.721674)
		(width 0.1143)
		(layer "In6.Cu")
		(net "GMI_CPU1_G0_CPU0_G2_TX_DP<1>")
	)
	(segment
		(start 102.991666 -221.064836)
		(end 102.991666 -221.093284)
		(width 0.1143)
		(layer "In6.Cu")
		(net "GMI_CPU1_G0_CPU0_G2_TX_DP<1>")
	)
	(segment
		(start 371.672866 -227.163884)
		(end 371.651784 -227.151692)
		(width 0.1143)
		(layer "In6.Cu")
		(net "GMI_CPU1_G0_CPU0_G2_TX_DP<1>")
	)
	(segment
		(start 105.292652 -213.34603)
		(end 104.646984 -213.991698)
		(width 0.14224)
		(layer "In6.Cu")
		(net "GMI_CPU1_G0_CPU0_G2_TX_DP<1>")
	)
	(segment
		(start 99.823016 -227.164138)
		(end 99.822254 -227.164646)
		(width 0.1143)
		(layer "In6.Cu")
		(net "GMI_CPU1_G0_CPU0_G2_TX_DP<1>")
	)
	(segment
		(start 99.843336 -227.796598)
		(end 99.844098 -227.797106)
		(width 0.1143)
		(layer "In6.Cu")
		(net "GMI_CPU1_G0_CPU0_G2_TX_DP<1>")
	)
	(segment
		(start 370.27358 -224.739962)
		(end 370.243862 -224.722944)
		(width 0.1143)
		(layer "In6.Cu")
		(net "GMI_CPU1_G0_CPU0_G2_TX_DP<1>")
	)
	(segment
		(start 371.683534 -228.789992)
		(end 371.655594 -228.77399)
		(width 0.1143)
		(layer "In6.Cu")
		(net "GMI_CPU1_G0_CPU0_G2_TX_DP<1>")
	)
	(segment
		(start 371.615462 -234.297728)
		(end 371.651784 -234.276646)
		(width 0.1143)
		(layer "In6.Cu")
		(net "GMI_CPU1_G0_CPU0_G2_TX_DP<1>")
	)
	(segment
		(start 371.652546 -228.772212)
		(end 371.651784 -228.771704)
		(width 0.1143)
		(layer "In6.Cu")
		(net "GMI_CPU1_G0_CPU0_G2_TX_DP<1>")
	)
	(segment
		(start 101.255068 -224.72142)
		(end 101.254052 -224.721928)
		(width 0.1143)
		(layer "In6.Cu")
		(net "GMI_CPU1_G0_CPU0_G2_TX_DP<1>")
	)
	(segment
		(start 371.683534 -233.649774)
		(end 371.68201 -233.649012)
		(width 0.1143)
		(layer "In6.Cu")
		(net "GMI_CPU1_G0_CPU0_G2_TX_DP<1>")
	)
	(segment
		(start 107.345734 -211.483194)
		(end 107.049316 -211.779866)
		(width 0.14224)
		(layer "In6.Cu")
		(net "GMI_CPU1_G0_CPU0_G2_TX_DP<1>")
	)
	(segment
		(start 371.612922 -233.60888)
		(end 371.59438 -233.595672)
		(width 0.1143)
		(layer "In6.Cu")
		(net "GMI_CPU1_G0_CPU0_G2_TX_DP<1>")
	)
	(segment
		(start 370.742464 -225.54946)
		(end 370.672868 -225.50882)
		(width 0.1143)
		(layer "In6.Cu")
		(net "GMI_CPU1_G0_CPU0_G2_TX_DP<1>")
	)
	(segment
		(start 109.69498 -209.133948)
		(end 109.398562 -209.43062)
		(width 0.14224)
		(layer "In6.Cu")
		(net "GMI_CPU1_G0_CPU0_G2_TX_DP<1>")
	)
	(segment
		(start 371.652546 -231.036114)
		(end 371.685312 -231.017064)
		(width 0.1143)
		(layer "In6.Cu")
		(net "GMI_CPU1_G0_CPU0_G2_TX_DP<1>")
	)
	(segment
		(start 372.5926 -236.872018)
		(end 372.591838 -236.87151)
		(width 0.1143)
		(layer "In6.Cu")
		(net "GMI_CPU1_G0_CPU0_G2_TX_DP<1>")
	)
	(segment
		(start 100.823014 -225.509074)
		(end 100.783898 -225.531934)
		(width 0.1143)
		(layer "In6.Cu")
		(net "GMI_CPU1_G0_CPU0_G2_TX_DP<1>")
	)
	(segment
		(start 99.81057 -231.017318)
		(end 99.843336 -231.036368)
		(width 0.1143)
		(layer "In6.Cu")
		(net "GMI_CPU1_G0_CPU0_G2_TX_DP<1>")
	)
	(segment
		(start 371.65534 -227.79482)
		(end 371.683534 -227.778564)
		(width 0.1143)
		(layer "In6.Cu")
		(net "GMI_CPU1_G0_CPU0_G2_TX_DP<1>")
	)
	(segment
		(start 371.180868 -226.341178)
		(end 371.142768 -226.318826)
		(width 0.1143)
		(layer "In6.Cu")
		(net "GMI_CPU1_G0_CPU0_G2_TX_DP<1>")
	)
	(segment
		(start 268.884654 -175.82388)
		(end 268.8844 -175.82388)
		(width 0.14224)
		(layer "In6.Cu")
		(net "GMI_CPU1_G0_CPU0_G2_TX_DP<1>")
	)
	(segment
		(start 372.590822 -236.871002)
		(end 372.589298 -236.869986)
		(width 0.1143)
		(layer "In6.Cu")
		(net "GMI_CPU1_G0_CPU0_G2_TX_DP<1>")
	)
	(segment
		(start 373.022876 -238.349536)
		(end 373.092472 -238.308896)
		(width 0.1143)
		(layer "In6.Cu")
		(net "GMI_CPU1_G0_CPU0_G2_TX_DP<1>")
	)
	(segment
		(start 302.916336 -176.022762)
		(end 268.884654 -175.82388)
		(width 0.14224)
		(layer "In6.Cu")
		(net "GMI_CPU1_G0_CPU0_G2_TX_DP<1>")
	)
	(segment
		(start 99.844098 -227.151946)
		(end 99.823016 -227.164138)
		(width 0.1143)
		(layer "In6.Cu")
		(net "GMI_CPU1_G0_CPU0_G2_TX_DP<1>")
	)
	(segment
		(start 371.651784 -227.151692)
		(end 371.65153 -227.151438)
		(width 0.1143)
		(layer "In6.Cu")
		(net "GMI_CPU1_G0_CPU0_G2_TX_DP<1>")
	)
	(segment
		(start 99.812348 -234.258612)
		(end 99.844098 -234.2769)
		(width 0.1143)
		(layer "In6.Cu")
		(net "GMI_CPU1_G0_CPU0_G2_TX_DP<1>")
	)
	(segment
		(start 373.172736 -239.624108)
		(end 373.242586 -239.554258)
		(width 0.1143)
		(layer "In6.Cu")
		(net "GMI_CPU1_G0_CPU0_G2_TX_DP<1>")
	)
	(segment
		(start 371.618256 -229.436168)
		(end 371.685312 -229.397052)
		(width 0.1143)
		(layer "In6.Cu")
		(net "GMI_CPU1_G0_CPU0_G2_TX_DP<1>")
	)
	(segment
		(start 371.683534 -232.029762)
		(end 371.651784 -232.011474)
		(width 0.1143)
		(layer "In6.Cu")
		(net "GMI_CPU1_G0_CPU0_G2_TX_DP<1>")
	)
	(segment
		(start 99.81057 -229.397306)
		(end 99.877626 -229.436422)
		(width 0.1143)
		(layer "In6.Cu")
		(net "GMI_CPU1_G0_CPU0_G2_TX_DP<1>")
	)
	(segment
		(start 369.334034 -223.120458)
		(end 369.287806 -223.093788)
		(width 0.1143)
		(layer "In6.Cu")
		(net "GMI_CPU1_G0_CPU0_G2_TX_DP<1>")
	)
	(segment
		(start 111.261144 -207.567784)
		(end 110.964726 -207.864456)
		(width 0.14224)
		(layer "In6.Cu")
		(net "GMI_CPU1_G0_CPU0_G2_TX_DP<1>")
	)
	(segment
		(start 107.832398 -210.996784)
		(end 107.641898 -210.996784)
		(width 0.14224)
		(layer "In6.Cu")
		(net "GMI_CPU1_G0_CPU0_G2_TX_DP<1>")
	)
	(segment
		(start 107.345734 -211.292948)
		(end 107.345734 -211.483194)
		(width 0.14224)
		(layer "In6.Cu")
		(net "GMI_CPU1_G0_CPU0_G2_TX_DP<1>")
	)
	(segment
		(start 102.9462 -221.247208)
		(end 102.9462 -221.820486)
		(width 0.1143)
		(layer "In6.Cu")
		(net "GMI_CPU1_G0_CPU0_G2_TX_DP<1>")
	)
	(segment
		(start 105.77957 -213.049358)
		(end 105.482898 -213.34603)
		(width 0.14224)
		(layer "In6.Cu")
		(net "GMI_CPU1_G0_CPU0_G2_TX_DP<1>")
	)
	(segment
		(start 108.42498 -210.213702)
		(end 108.128816 -210.509866)
		(width 0.14224)
		(layer "In6.Cu")
		(net "GMI_CPU1_G0_CPU0_G2_TX_DP<1>")
	)
	(segment
		(start 371.59438 -232.692448)
		(end 371.614192 -232.678478)
		(width 0.1143)
		(layer "In6.Cu")
		(net "GMI_CPU1_G0_CPU0_G2_TX_DP<1>")
	)
	(segment
		(start 110.181644 -208.647538)
		(end 109.991144 -208.647538)
		(width 0.14224)
		(layer "In6.Cu")
		(net "GMI_CPU1_G0_CPU0_G2_TX_DP<1>")
	)
	(segment
		(start 371.651784 -227.796852)
		(end 371.652546 -227.796344)
		(width 0.1143)
		(layer "In6.Cu")
		(net "GMI_CPU1_G0_CPU0_G2_TX_DP<1>")
	)
	(segment
		(start 371.653562 -228.77272)
		(end 371.652546 -228.772212)
		(width 0.1143)
		(layer "In6.Cu")
		(net "GMI_CPU1_G0_CPU0_G2_TX_DP<1>")
	)
	(segment
		(start 371.651784 -231.036622)
		(end 371.652546 -231.036114)
		(width 0.1143)
		(layer "In6.Cu")
		(net "GMI_CPU1_G0_CPU0_G2_TX_DP<1>")
	)
	(segment
		(start 101.254052 -224.721928)
		(end 101.25329 -224.722436)
		(width 0.1143)
		(layer "In6.Cu")
		(net "GMI_CPU1_G0_CPU0_G2_TX_DP<1>")
	)
	(segment
		(start 372.623588 -236.889798)
		(end 372.59387 -236.87278)
		(width 0.1143)
		(layer "In6.Cu")
		(net "GMI_CPU1_G0_CPU0_G2_TX_DP<1>")
	)
	(segment
		(start 371.683534 -230.410004)
		(end 371.61724 -230.371396)
		(width 0.1143)
		(layer "In6.Cu")
		(net "GMI_CPU1_G0_CPU0_G2_TX_DP<1>")
	)
	(segment
		(start 110.964726 -207.864456)
		(end 110.774226 -207.864456)
		(width 0.14224)
		(layer "In6.Cu")
		(net "GMI_CPU1_G0_CPU0_G2_TX_DP<1>")
	)
	(segment
		(start 370.240814 -224.721166)
		(end 370.23929 -224.72015)
		(width 0.1143)
		(layer "In6.Cu")
		(net "GMI_CPU1_G0_CPU0_G2_TX_DP<1>")
	)
	(segment
		(start 109.208062 -209.43062)
		(end 108.911898 -209.726784)
		(width 0.14224)
		(layer "In6.Cu")
		(net "GMI_CPU1_G0_CPU0_G2_TX_DP<1>")
	)
	(segment
		(start 102.991666 -217.602308)
		(end 102.991666 -221.064836)
		(width 0.14224)
		(layer "In6.Cu")
		(net "GMI_CPU1_G0_CPU0_G2_TX_DP<1>")
	)
	(segment
		(start 99.844606 -228.771958)
		(end 99.844098 -228.771958)
		(width 0.1143)
		(layer "In6.Cu")
		(net "GMI_CPU1_G0_CPU0_G2_TX_DP<1>")
	)
	(segment
		(start 102.945946 -221.139004)
		(end 102.945946 -221.246954)
		(width 0.1143)
		(layer "In6.Cu")
		(net "GMI_CPU1_G0_CPU0_G2_TX_DP<1>")
	)
	(segment
		(start 362.556552 -210.502754)
		(end 357.055928 -206.118714)
		(width 0.14224)
		(layer "In6.Cu")
		(net "GMI_CPU1_G0_CPU0_G2_TX_DP<1>")
	)
	(segment
		(start 372.589298 -236.869986)
		(end 372.552722 -236.84865)
		(width 0.1143)
		(layer "In6.Cu")
		(net "GMI_CPU1_G0_CPU0_G2_TX_DP<1>")
	)
	(segment
		(start 99.812348 -232.6386)
		(end 99.812856 -232.6386)
		(width 0.1143)
		(layer "In6.Cu")
		(net "GMI_CPU1_G0_CPU0_G2_TX_DP<1>")
	)
	(segment
		(start 371.181884 -226.341686)
		(end 371.180868 -226.341178)
		(width 0.1143)
		(layer "In6.Cu")
		(net "GMI_CPU1_G0_CPU0_G2_TX_DP<1>")
	)
	(segment
		(start 373.092472 -239.319308)
		(end 373.022876 -239.278668)
		(width 0.1143)
		(layer "In6.Cu")
		(net "GMI_CPU1_G0_CPU0_G2_TX_DP<1>")
	)
	(segment
		(start 371.683534 -235.269786)
		(end 371.651784 -235.251498)
		(width 0.1143)
		(layer "In6.Cu")
		(net "GMI_CPU1_G0_CPU0_G2_TX_DP<1>")
	)
	(segment
		(start 369.80241 -223.929448)
		(end 369.732814 -223.888808)
		(width 0.1143)
		(layer "In6.Cu")
		(net "GMI_CPU1_G0_CPU0_G2_TX_DP<1>")
	)
	(segment
		(start 99.840542 -227.795074)
		(end 99.841558 -227.795582)
		(width 0.1143)
		(layer "In6.Cu")
		(net "GMI_CPU1_G0_CPU0_G2_TX_DP<1>")
	)
	(segment
		(start 108.128816 -210.509866)
		(end 108.128816 -210.700112)
		(width 0.14224)
		(layer "In6.Cu")
		(net "GMI_CPU1_G0_CPU0_G2_TX_DP<1>")
	)
	(segment
		(start 106.266234 -212.562948)
		(end 106.075734 -212.562948)
		(width 0.14224)
		(layer "In6.Cu")
		(net "GMI_CPU1_G0_CPU0_G2_TX_DP<1>")
	)
	(segment
		(start 99.844098 -228.771958)
		(end 99.843336 -228.772466)
		(width 0.1143)
		(layer "In6.Cu")
		(net "GMI_CPU1_G0_CPU0_G2_TX_DP<1>")
	)
	(segment
		(start 98.43389 -238.32693)
		(end 98.473006 -238.34979)
		(width 0.1143)
		(layer "In6.Cu")
		(net "GMI_CPU1_G0_CPU0_G2_TX_DP<1>")
	)
	(segment
		(start 372.59387 -236.87278)
		(end 372.5926 -236.872018)
		(width 0.1143)
		(layer "In6.Cu")
		(net "GMI_CPU1_G0_CPU0_G2_TX_DP<1>")
	)
	(segment
		(start 107.641898 -210.996784)
		(end 107.345734 -211.292948)
		(width 0.14224)
		(layer "In6.Cu")
		(net "GMI_CPU1_G0_CPU0_G2_TX_DP<1>")
	)
	(segment
		(start 368.549936 -221.2467)
		(end 368.549936 -221.153228)
		(width 0.1143)
		(layer "In6.Cu")
		(net "GMI_CPU1_G0_CPU0_G2_TX_DP<1>")
	)
	(segment
		(start 102.991666 -221.093284)
		(end 102.945946 -221.139004)
		(width 0.1143)
		(layer "In6.Cu")
		(net "GMI_CPU1_G0_CPU0_G2_TX_DP<1>")
	)
	(segment
		(start 104.226614 -214.62111)
		(end 102.991666 -217.602308)
		(width 0.14224)
		(layer "In6.Cu")
		(net "GMI_CPU1_G0_CPU0_G2_TX_DP<1>")
	)
	(segment
		(start 368.549936 -221.153228)
		(end 368.504216 -221.107508)
		(width 0.1143)
		(layer "In6.Cu")
		(net "GMI_CPU1_G0_CPU0_G2_TX_DP<1>")
	)
	(segment
		(start 106.562652 -212.07603)
		(end 106.562652 -212.266276)
		(width 0.14224)
		(layer "In6.Cu")
		(net "GMI_CPU1_G0_CPU0_G2_TX_DP<1>")
	)
	(segment
		(start 102.705154 -222.28048)
		(end 102.636574 -222.320104)
		(width 0.1143)
		(layer "In6.Cu")
		(net "GMI_CPU1_G0_CPU0_G2_TX_DP<1>")
	)
	(segment
		(start 162.080448 -176.465484)
		(end 117.214396 -202.373738)
		(width 0.14224)
		(layer "In6.Cu")
		(net "GMI_CPU1_G0_CPU0_G2_TX_DP<1>")
	)
	(segment
		(start 101.25329 -224.722436)
		(end 101.222302 -224.740216)
		(width 0.1143)
		(layer "In6.Cu")
		(net "GMI_CPU1_G0_CPU0_G2_TX_DP<1>")
	)
	(segment
		(start 371.614192 -232.678478)
		(end 371.683534 -232.638092)
		(width 0.1143)
		(layer "In6.Cu")
		(net "GMI_CPU1_G0_CPU0_G2_TX_DP<1>")
	)
	(segment
		(start 371.683534 -227.16998)
		(end 371.673628 -227.164392)
		(width 0.1143)
		(layer "In6.Cu")
		(net "GMI_CPU1_G0_CPU0_G2_TX_DP<1>")
	)
	(segment
		(start 109.398562 -209.43062)
		(end 109.208062 -209.43062)
		(width 0.14224)
		(layer "In6.Cu")
		(net "GMI_CPU1_G0_CPU0_G2_TX_DP<1>")
	)
	(segment
		(start 106.075734 -212.562948)
		(end 105.77957 -212.859112)
		(width 0.14224)
		(layer "In6.Cu")
		(net "GMI_CPU1_G0_CPU0_G2_TX_DP<1>")
	)
	(segment
		(start 371.185186 -226.343718)
		(end 371.182646 -226.342194)
		(width 0.1143)
		(layer "In6.Cu")
		(net "GMI_CPU1_G0_CPU0_G2_TX_DP<1>")
	)
	(segment
		(start 98.906584 -236.87024)
		(end 98.90506 -236.871256)
		(width 0.1143)
		(layer "In6.Cu")
		(net "GMI_CPU1_G0_CPU0_G2_TX_DP<1>")
	)
	(segment
		(start 372.152418 -236.079284)
		(end 372.082822 -236.038644)
		(width 0.1143)
		(layer "In6.Cu")
		(net "GMI_CPU1_G0_CPU0_G2_TX_DP<1>")
	)
	(segment
		(start 99.844352 -227.151692)
		(end 99.844098 -227.151946)
		(width 0.1143)
		(layer "In6.Cu")
		(net "GMI_CPU1_G0_CPU0_G2_TX_DP<1>")
	)
	(segment
		(start 104.646984 -213.991698)
		(end 104.226614 -214.62111)
		(width 0.14224)
		(layer "In6.Cu")
		(net "GMI_CPU1_G0_CPU0_G2_TX_DP<1>")
	)
	(segment
		(start 100.783898 -225.531934)
		(end 100.753418 -225.549714)
		(width 0.1143)
		(layer "In6.Cu")
		(net "GMI_CPU1_G0_CPU0_G2_TX_DP<1>")
	)
	(segment
		(start 98.94316 -236.848904)
		(end 98.906584 -236.87024)
		(width 0.1143)
		(layer "In6.Cu")
		(net "GMI_CPU1_G0_CPU0_G2_TX_DP<1>")
	)
	(segment
		(start 98.253296 -239.554512)
		(end 98.323146 -239.624362)
		(width 0.1143)
		(layer "In6.Cu")
		(net "GMI_CPU1_G0_CPU0_G2_TX_DP<1>")
	)
	(segment
		(start 368.549682 -221.820232)
		(end 368.549682 -221.246954)
		(width 0.1143)
		(layer "In6.Cu")
		(net "GMI_CPU1_G0_CPU0_G2_TX_DP<1>")
	)
	(segment
		(start 371.655594 -228.77399)
		(end 371.654324 -228.773228)
		(width 0.1143)
		(layer "In6.Cu")
		(net "GMI_CPU1_G0_CPU0_G2_TX_DP<1>")
	)
	(segment
		(start 357.055928 -206.118714)
		(end 331.605636 -190.147448)
		(width 0.14224)
		(layer "In6.Cu")
		(net "GMI_CPU1_G0_CPU0_G2_TX_DP<1>")
	)
	(segment
		(start 111.261144 -207.377538)
		(end 111.261144 -207.567784)
		(width 0.14224)
		(layer "In6.Cu")
		(net "GMI_CPU1_G0_CPU0_G2_TX_DP<1>")
	)
	(segment
		(start 329.19162 -187.948316)
		(end 310.687212 -176.960022)
		(width 0.14224)
		(layer "In6.Cu")
		(net "GMI_CPU1_G0_CPU0_G2_TX_DP<1>")
	)
	(segment
		(start 268.8844 -175.82388)
		(end 166.757096 -175.226726)
		(width 0.14224)
		(layer "In6.Cu")
		(net "GMI_CPU1_G0_CPU0_G2_TX_DP<1>")
	)
	(segment
		(start 98.40341 -238.30915)
		(end 98.43389 -238.32693)
		(width 0.1143)
		(layer "In6.Cu")
		(net "GMI_CPU1_G0_CPU0_G2_TX_DP<1>")
	)
	(segment
		(start 110.774226 -207.864456)
		(end 110.478062 -208.16062)
		(width 0.14224)
		(layer "In6.Cu")
		(net "GMI_CPU1_G0_CPU0_G2_TX_DP<1>")
	)
	(segment
		(start 110.478062 -208.350866)
		(end 110.181644 -208.647538)
		(width 0.14224)
		(layer "In6.Cu")
		(net "GMI_CPU1_G0_CPU0_G2_TX_DP<1>")
	)
	(segment
		(start 370.24183 -224.721674)
		(end 370.240814 -224.721166)
		(width 0.1143)
		(layer "In6.Cu")
		(net "GMI_CPU1_G0_CPU0_G2_TX_DP<1>")
	)
	(segment
		(start 307.273198 -176.022762)
		(end 302.916336 -176.022762)
		(width 0.14224)
		(layer "In6.Cu")
		(net "GMI_CPU1_G0_CPU0_G2_TX_DP<1>")
	)
	(segment
		(start 108.911898 -209.726784)
		(end 108.911898 -209.91703)
		(width 0.14224)
		(layer "In6.Cu")
		(net "GMI_CPU1_G0_CPU0_G2_TX_DP<1>")
	)
	(segment
		(start 108.128816 -210.700112)
		(end 107.832398 -210.996784)
		(width 0.14224)
		(layer "In6.Cu")
		(net "GMI_CPU1_G0_CPU0_G2_TX_DP<1>")
	)
	(segment
		(start 117.214396 -202.373738)
		(end 113.13287 -205.505812)
		(width 0.14224)
		(layer "In6.Cu")
		(net "GMI_CPU1_G0_CPU0_G2_TX_DP<1>")
	)
	(segment
		(start 108.61548 -210.213702)
		(end 108.42498 -210.213702)
		(width 0.14224)
		(layer "In6.Cu")
		(net "GMI_CPU1_G0_CPU0_G2_TX_DP<1>")
	)
	(segment
		(start 99.844098 -227.797106)
		(end 99.844606 -227.797106)
		(width 0.1143)
		(layer "In6.Cu")
		(net "GMI_CPU1_G0_CPU0_G2_TX_DP<1>")
	)
	(segment
		(start 105.482898 -213.34603)
		(end 105.292652 -213.34603)
		(width 0.14224)
		(layer "In6.Cu")
		(net "GMI_CPU1_G0_CPU0_G2_TX_DP<1>")
	)
	(segment
		(start 371.182646 -226.342194)
		(end 371.181884 -226.341686)
		(width 0.1143)
		(layer "In6.Cu")
		(net "GMI_CPU1_G0_CPU0_G2_TX_DP<1>")
	)
	(segment
		(start 99.84232 -227.79609)
		(end 99.843336 -227.796598)
		(width 0.1143)
		(layer "In6.Cu")
		(net "GMI_CPU1_G0_CPU0_G2_TX_DP<1>")
	)
	(segment
		(start 368.549682 -221.246954)
		(end 368.549936 -221.2467)
		(width 0.1143)
		(layer "In6.Cu")
		(net "GMI_CPU1_G0_CPU0_G2_TX_DP<1>")
	)
	(segment
		(start 372.874794 -239.624108)
		(end 373.172736 -239.624108)
		(width 0.1143)
		(layer "In6.Cu")
		(net "GMI_CPU1_G0_CPU0_G2_TX_DP<1>")
	)
	(segment
		(start 371.652546 -227.796344)
		(end 371.653562 -227.795836)
		(width 0.1143)
		(layer "In6.Cu")
		(net "GMI_CPU1_G0_CPU0_G2_TX_DP<1>")
	)
	(segment
		(start 371.653562 -227.795836)
		(end 371.654324 -227.795328)
		(width 0.1143)
		(layer "In6.Cu")
		(net "GMI_CPU1_G0_CPU0_G2_TX_DP<1>")
	)
	(segment
		(start 102.208076 -223.094042)
		(end 102.161848 -223.120712)
		(width 0.1143)
		(layer "In6.Cu")
		(net "GMI_CPU1_G0_CPU0_G2_TX_DP<1>")
	)
	(segment
		(start 99.841558 -227.795582)
		(end 99.84232 -227.79609)
		(width 0.1143)
		(layer "In6.Cu")
		(net "GMI_CPU1_G0_CPU0_G2_TX_DP<1>")
	)
	(segment
		(start 102.945946 -221.246954)
		(end 102.9462 -221.247208)
		(width 0.1143)
		(layer "In6.Cu")
		(net "GMI_CPU1_G0_CPU0_G2_TX_DP<1>")
	)
	(segment
		(start 310.687212 -176.960022)
		(end 307.273198 -176.022762)
		(width 0.14224)
		(layer "In6.Cu")
		(net "GMI_CPU1_G0_CPU0_G2_TX_DP<1>")
	)
	(segment
		(start 101.763068 -223.889062)
		(end 101.723952 -223.911922)
		(width 0.1143)
		(layer "In6.Cu")
		(net "GMI_CPU1_G0_CPU0_G2_TX_DP<1>")
	)
	(segment
		(start 371.673628 -227.164392)
		(end 371.672866 -227.163884)
		(width 0.1143)
		(layer "In6.Cu")
		(net "GMI_CPU1_G0_CPU0_G2_TX_DP<1>")
	)
	(segment
		(start 99.822254 -227.164646)
		(end 99.812348 -227.170234)
		(width 0.1143)
		(layer "In6.Cu")
		(net "GMI_CPU1_G0_CPU0_G2_TX_DP<1>")
	)
	(segment
		(start 110.478062 -208.16062)
		(end 110.478062 -208.350866)
		(width 0.14224)
		(layer "In6.Cu")
		(net "GMI_CPU1_G0_CPU0_G2_TX_DP<1>")
	)
	(segment
		(start 101.293168 -224.699068)
		(end 101.256592 -224.720404)
		(width 0.1143)
		(layer "In6.Cu")
		(net "GMI_CPU1_G0_CPU0_G2_TX_DP<1>")
	)
	(segment
		(start 106.858816 -211.779866)
		(end 106.562652 -212.07603)
		(width 0.14224)
		(layer "In6.Cu")
		(net "GMI_CPU1_G0_CPU0_G2_TX_DP<1>")
	)
	(segment
		(start 106.562652 -212.266276)
		(end 106.266234 -212.562948)
		(width 0.14224)
		(layer "In6.Cu")
		(net "GMI_CPU1_G0_CPU0_G2_TX_DP<1>")
	)
	(segment
		(start 370.243862 -224.722944)
		(end 370.242592 -224.722182)
		(width 0.1143)
		(layer "In6.Cu")
		(net "GMI_CPU1_G0_CPU0_G2_TX_DP<1>")
	)
	(arc
		(start 370.899436 -225.85426)
		(mid 370.857887 -225.682838)
		(end 370.742464 -225.54946)
		(width 0.1143)
		(layer "In6.Cu")
		(net "GMI_CPU1_G0_CPU0_G2_TX_DP<1>")
	)
	(arc
		(start 102.636574 -222.320104)
		(mid 102.520619 -222.453594)
		(end 102.47884 -222.625412)
		(width 0.1143)
		(layer "In6.Cu")
		(net "GMI_CPU1_G0_CPU0_G2_TX_DP<1>")
	)
	(arc
		(start 370.672868 -225.50882)
		(mid 370.494055 -225.30647)
		(end 370.429536 -225.044254)
		(width 0.1143)
		(layer "In6.Cu")
		(net "GMI_CPU1_G0_CPU0_G2_TX_DP<1>")
	)
	(arc
		(start 373.242586 -239.554258)
		(mid 373.190169 -239.422327)
		(end 373.092472 -239.319308)
		(width 0.1143)
		(layer "In6.Cu")
		(net "GMI_CPU1_G0_CPU0_G2_TX_DP<1>")
	)
	(arc
		(start 99.812348 -228.790246)
		(mid 99.697672 -228.92358)
		(end 99.656392 -229.094538)
		(width 0.1143)
		(layer "In6.Cu")
		(net "GMI_CPU1_G0_CPU0_G2_TX_DP<1>")
	)
	(arc
		(start 373.092472 -238.308896)
		(mid 373.249449 -238.004096)
		(end 373.092472 -237.699296)
		(width 0.1143)
		(layer "In6.Cu")
		(net "GMI_CPU1_G0_CPU0_G2_TX_DP<1>")
	)
	(arc
		(start 371.615462 -235.230416)
		(mid 371.608313 -235.225516)
		(end 371.601238 -235.22051)
		(width 0.1143)
		(layer "In6.Cu")
		(net "GMI_CPU1_G0_CPU0_G2_TX_DP<1>")
	)
	(arc
		(start 99.656392 -230.71455)
		(mid 99.697154 -230.884434)
		(end 99.81057 -231.017318)
		(width 0.1143)
		(layer "In6.Cu")
		(net "GMI_CPU1_G0_CPU0_G2_TX_DP<1>")
	)
	(arc
		(start 372.30939 -236.384084)
		(mid 372.267841 -236.212662)
		(end 372.152418 -236.079284)
		(width 0.1143)
		(layer "In6.Cu")
		(net "GMI_CPU1_G0_CPU0_G2_TX_DP<1>")
	)
	(arc
		(start 99.812348 -227.170234)
		(mid 99.65642 -227.474526)
		(end 99.812348 -227.778818)
		(width 0.1143)
		(layer "In6.Cu")
		(net "GMI_CPU1_G0_CPU0_G2_TX_DP<1>")
	)
	(arc
		(start 98.473006 -238.34979)
		(mid 98.716333 -238.814356)
		(end 98.473006 -239.278922)
		(width 0.1143)
		(layer "In6.Cu")
		(net "GMI_CPU1_G0_CPU0_G2_TX_DP<1>")
	)
	(arc
		(start 99.844606 -227.797106)
		(mid 100.125253 -228.284532)
		(end 99.844606 -228.771958)
		(width 0.1143)
		(layer "In6.Cu")
		(net "GMI_CPU1_G0_CPU0_G2_TX_DP<1>")
	)
	(arc
		(start 371.683534 -234.258358)
		(mid 371.839462 -233.954066)
		(end 371.683534 -233.649774)
		(width 0.1143)
		(layer "In6.Cu")
		(net "GMI_CPU1_G0_CPU0_G2_TX_DP<1>")
	)
	(arc
		(start 99.894644 -235.220764)
		(mid 99.887571 -235.225773)
		(end 99.88042 -235.23067)
		(width 0.1143)
		(layer "In6.Cu")
		(net "GMI_CPU1_G0_CPU0_G2_TX_DP<1>")
	)
	(arc
		(start 373.022876 -239.278668)
		(mid 372.779549 -238.814102)
		(end 373.022876 -238.349536)
		(width 0.1143)
		(layer "In6.Cu")
		(net "GMI_CPU1_G0_CPU0_G2_TX_DP<1>")
	)
	(arc
		(start 371.683534 -232.638346)
		(mid 371.839462 -232.334054)
		(end 371.683534 -232.029762)
		(width 0.1143)
		(layer "In6.Cu")
		(net "GMI_CPU1_G0_CPU0_G2_TX_DP<1>")
	)
	(arc
		(start 371.59438 -233.595672)
		(mid 371.362609 -233.14406)
		(end 371.59438 -232.692448)
		(width 0.1143)
		(layer "In6.Cu")
		(net "GMI_CPU1_G0_CPU0_G2_TX_DP<1>")
	)
	(arc
		(start 372.082822 -236.038644)
		(mid 371.904009 -235.836294)
		(end 371.83949 -235.574078)
		(width 0.1143)
		(layer "In6.Cu")
		(net "GMI_CPU1_G0_CPU0_G2_TX_DP<1>")
	)
	(arc
		(start 371.371622 -226.665536)
		(mid 371.321657 -226.47956)
		(end 371.185186 -226.343718)
		(width 0.1143)
		(layer "In6.Cu")
		(net "GMI_CPU1_G0_CPU0_G2_TX_DP<1>")
	)
	(arc
		(start 99.812348 -233.650028)
		(mid 99.65642 -233.95432)
		(end 99.812348 -234.258612)
		(width 0.1143)
		(layer "In6.Cu")
		(net "GMI_CPU1_G0_CPU0_G2_TX_DP<1>")
	)
	(arc
		(start 373.022876 -237.658656)
		(mid 372.844063 -237.456306)
		(end 372.779544 -237.19409)
		(width 0.1143)
		(layer "In6.Cu")
		(net "GMI_CPU1_G0_CPU0_G2_TX_DP<1>")
	)
	(arc
		(start 369.489482 -223.424242)
		(mid 369.44837 -223.25361)
		(end 369.334034 -223.120458)
		(width 0.1143)
		(layer "In6.Cu")
		(net "GMI_CPU1_G0_CPU0_G2_TX_DP<1>")
	)
	(arc
		(start 371.601238 -234.307634)
		(mid 371.608312 -234.302627)
		(end 371.615462 -234.297728)
		(width 0.1143)
		(layer "In6.Cu")
		(net "GMI_CPU1_G0_CPU0_G2_TX_DP<1>")
	)
	(arc
		(start 98.40341 -237.69955)
		(mid 98.246433 -238.00435)
		(end 98.40341 -238.30915)
		(width 0.1143)
		(layer "In6.Cu")
		(net "GMI_CPU1_G0_CPU0_G2_TX_DP<1>")
	)
	(arc
		(start 98.40341 -239.319562)
		(mid 98.305645 -239.422538)
		(end 98.253296 -239.554512)
		(width 0.1143)
		(layer "In6.Cu")
		(net "GMI_CPU1_G0_CPU0_G2_TX_DP<1>")
	)
	(arc
		(start 371.83949 -230.714296)
		(mid 371.798235 -230.543325)
		(end 371.683534 -230.410004)
		(width 0.1143)
		(layer "In6.Cu")
		(net "GMI_CPU1_G0_CPU0_G2_TX_DP<1>")
	)
	(arc
		(start 371.142768 -226.318826)
		(mid 370.963955 -226.116476)
		(end 370.899436 -225.85426)
		(width 0.1143)
		(layer "In6.Cu")
		(net "GMI_CPU1_G0_CPU0_G2_TX_DP<1>")
	)
	(arc
		(start 371.685312 -229.397052)
		(mid 371.798719 -229.264163)
		(end 371.83949 -229.094284)
		(width 0.1143)
		(layer "In6.Cu")
		(net "GMI_CPU1_G0_CPU0_G2_TX_DP<1>")
	)
	(arc
		(start 99.656392 -229.094538)
		(mid 99.697154 -229.264422)
		(end 99.81057 -229.397306)
		(width 0.1143)
		(layer "In6.Cu")
		(net "GMI_CPU1_G0_CPU0_G2_TX_DP<1>")
	)
	(arc
		(start 101.066346 -225.044508)
		(mid 101.001831 -225.306727)
		(end 100.823014 -225.509074)
		(width 0.1143)
		(layer "In6.Cu")
		(net "GMI_CPU1_G0_CPU0_G2_TX_DP<1>")
	)
	(arc
		(start 371.36959 -229.901242)
		(mid 371.4354 -229.639155)
		(end 371.615462 -229.437692)
		(width 0.1143)
		(layer "In6.Cu")
		(net "GMI_CPU1_G0_CPU0_G2_TX_DP<1>")
	)
	(arc
		(start 100.310696 -226.343972)
		(mid 100.174278 -226.479845)
		(end 100.12426 -226.66579)
		(width 0.1143)
		(layer "In6.Cu")
		(net "GMI_CPU1_G0_CPU0_G2_TX_DP<1>")
	)
	(arc
		(start 371.83949 -229.094284)
		(mid 371.798235 -228.923313)
		(end 371.683534 -228.789992)
		(width 0.1143)
		(layer "In6.Cu")
		(net "GMI_CPU1_G0_CPU0_G2_TX_DP<1>")
	)
	(arc
		(start 99.88042 -234.297982)
		(mid 99.88757 -234.30288)
		(end 99.894644 -234.307888)
		(width 0.1143)
		(layer "In6.Cu")
		(net "GMI_CPU1_G0_CPU0_G2_TX_DP<1>")
	)
	(arc
		(start 100.126292 -229.901496)
		(mid 100.050202 -230.16171)
		(end 99.878642 -230.37165)
		(width 0.1143)
		(layer "In6.Cu")
		(net "GMI_CPU1_G0_CPU0_G2_TX_DP<1>")
	)
	(arc
		(start 100.596446 -225.854514)
		(mid 100.531931 -226.116733)
		(end 100.353114 -226.31908)
		(width 0.1143)
		(layer "In6.Cu")
		(net "GMI_CPU1_G0_CPU0_G2_TX_DP<1>")
	)
	(arc
		(start 369.732814 -223.888808)
		(mid 369.554001 -223.686458)
		(end 369.489482 -223.424242)
		(width 0.1143)
		(layer "In6.Cu")
		(net "GMI_CPU1_G0_CPU0_G2_TX_DP<1>")
	)
	(arc
		(start 99.343464 -236.079538)
		(mid 99.228037 -236.212914)
		(end 99.186492 -236.384338)
		(width 0.1143)
		(layer "In6.Cu")
		(net "GMI_CPU1_G0_CPU0_G2_TX_DP<1>")
	)
	(arc
		(start 101.222302 -224.740216)
		(mid 101.107626 -224.87355)
		(end 101.066346 -225.044508)
		(width 0.1143)
		(layer "In6.Cu")
		(net "GMI_CPU1_G0_CPU0_G2_TX_DP<1>")
	)
	(arc
		(start 99.894644 -234.307888)
		(mid 100.122128 -234.764326)
		(end 99.894644 -235.220764)
		(width 0.1143)
		(layer "In6.Cu")
		(net "GMI_CPU1_G0_CPU0_G2_TX_DP<1>")
	)
	(arc
		(start 102.161848 -223.120712)
		(mid 102.047546 -223.253882)
		(end 102.0064 -223.424496)
		(width 0.1143)
		(layer "In6.Cu")
		(net "GMI_CPU1_G0_CPU0_G2_TX_DP<1>")
	)
	(arc
		(start 98.716338 -237.194344)
		(mid 98.651823 -237.456563)
		(end 98.473006 -237.65891)
		(width 0.1143)
		(layer "In6.Cu")
		(net "GMI_CPU1_G0_CPU0_G2_TX_DP<1>")
	)
	(arc
		(start 99.186492 -236.384338)
		(mid 99.121977 -236.646557)
		(end 98.94316 -236.848904)
		(width 0.1143)
		(layer "In6.Cu")
		(net "GMI_CPU1_G0_CPU0_G2_TX_DP<1>")
	)
	(arc
		(start 371.65153 -227.151438)
		(mid 371.446566 -226.945928)
		(end 371.371622 -226.665536)
		(width 0.1143)
		(layer "In6.Cu")
		(net "GMI_CPU1_G0_CPU0_G2_TX_DP<1>")
	)
	(arc
		(start 369.017042 -222.625158)
		(mid 368.975283 -222.453329)
		(end 368.859308 -222.31985)
		(width 0.1143)
		(layer "In6.Cu")
		(net "GMI_CPU1_G0_CPU0_G2_TX_DP<1>")
	)
	(arc
		(start 99.812348 -235.27004)
		(mid 99.697672 -235.403374)
		(end 99.656392 -235.574332)
		(width 0.1143)
		(layer "In6.Cu")
		(net "GMI_CPU1_G0_CPU0_G2_TX_DP<1>")
	)
	(arc
		(start 371.683534 -227.778564)
		(mid 371.839462 -227.474272)
		(end 371.683534 -227.16998)
		(width 0.1143)
		(layer "In6.Cu")
		(net "GMI_CPU1_G0_CPU0_G2_TX_DP<1>")
	)
	(arc
		(start 368.790728 -222.280226)
		(mid 368.613572 -222.079912)
		(end 368.549682 -221.820232)
		(width 0.1143)
		(layer "In6.Cu")
		(net "GMI_CPU1_G0_CPU0_G2_TX_DP<1>")
	)
	(arc
		(start 99.88042 -229.437946)
		(mid 100.060405 -229.639449)
		(end 100.126292 -229.901496)
		(width 0.1143)
		(layer "In6.Cu")
		(net "GMI_CPU1_G0_CPU0_G2_TX_DP<1>")
	)
	(arc
		(start 98.872294 -236.890052)
		(mid 98.757618 -237.023386)
		(end 98.716338 -237.194344)
		(width 0.1143)
		(layer "In6.Cu")
		(net "GMI_CPU1_G0_CPU0_G2_TX_DP<1>")
	)
	(arc
		(start 100.753418 -225.549714)
		(mid 100.637991 -225.68309)
		(end 100.596446 -225.854514)
		(width 0.1143)
		(layer "In6.Cu")
		(net "GMI_CPU1_G0_CPU0_G2_TX_DP<1>")
	)
	(arc
		(start 370.429536 -225.044254)
		(mid 370.388281 -224.873283)
		(end 370.27358 -224.739962)
		(width 0.1143)
		(layer "In6.Cu")
		(net "GMI_CPU1_G0_CPU0_G2_TX_DP<1>")
	)
	(arc
		(start 99.656392 -235.574332)
		(mid 99.591877 -235.836551)
		(end 99.41306 -236.038898)
		(width 0.1143)
		(layer "In6.Cu")
		(net "GMI_CPU1_G0_CPU0_G2_TX_DP<1>")
	)
	(arc
		(start 100.12426 -226.66579)
		(mid 100.04927 -226.946156)
		(end 99.844352 -227.151692)
		(width 0.1143)
		(layer "In6.Cu")
		(net "GMI_CPU1_G0_CPU0_G2_TX_DP<1>")
	)
	(arc
		(start 102.9462 -221.820486)
		(mid 102.882351 -222.080188)
		(end 102.705154 -222.28048)
		(width 0.1143)
		(layer "In6.Cu")
		(net "GMI_CPU1_G0_CPU0_G2_TX_DP<1>")
	)
	(arc
		(start 371.685312 -231.017064)
		(mid 371.798719 -230.884175)
		(end 371.83949 -230.714296)
		(width 0.1143)
		(layer "In6.Cu")
		(net "GMI_CPU1_G0_CPU0_G2_TX_DP<1>")
	)
	(arc
		(start 371.651784 -232.011474)
		(mid 371.371137 -231.524048)
		(end 371.651784 -231.036622)
		(width 0.1143)
		(layer "In6.Cu")
		(net "GMI_CPU1_G0_CPU0_G2_TX_DP<1>")
	)
	(arc
		(start 370.202714 -224.698814)
		(mid 370.023901 -224.496464)
		(end 369.959382 -224.234248)
		(width 0.1143)
		(layer "In6.Cu")
		(net "GMI_CPU1_G0_CPU0_G2_TX_DP<1>")
	)
	(arc
		(start 369.287806 -223.093788)
		(mid 369.089549 -222.895803)
		(end 369.017042 -222.625158)
		(width 0.1143)
		(layer "In6.Cu")
		(net "GMI_CPU1_G0_CPU0_G2_TX_DP<1>")
	)
	(arc
		(start 371.61724 -230.371396)
		(mid 371.445624 -230.161485)
		(end 371.36959 -229.901242)
		(width 0.1143)
		(layer "In6.Cu")
		(net "GMI_CPU1_G0_CPU0_G2_TX_DP<1>")
	)
	(arc
		(start 102.47884 -222.625412)
		(mid 102.406344 -222.896063)
		(end 102.208076 -223.094042)
		(width 0.1143)
		(layer "In6.Cu")
		(net "GMI_CPU1_G0_CPU0_G2_TX_DP<1>")
	)
	(arc
		(start 101.693472 -223.929702)
		(mid 101.578045 -224.063078)
		(end 101.5365 -224.234502)
		(width 0.1143)
		(layer "In6.Cu")
		(net "GMI_CPU1_G0_CPU0_G2_TX_DP<1>")
	)
	(arc
		(start 102.0064 -223.424496)
		(mid 101.941885 -223.686715)
		(end 101.763068 -223.889062)
		(width 0.1143)
		(layer "In6.Cu")
		(net "GMI_CPU1_G0_CPU0_G2_TX_DP<1>")
	)
	(arc
		(start 371.83949 -235.574078)
		(mid 371.798235 -235.403107)
		(end 371.683534 -235.269786)
		(width 0.1143)
		(layer "In6.Cu")
		(net "GMI_CPU1_G0_CPU0_G2_TX_DP<1>")
	)
	(arc
		(start 371.651276 -228.771704)
		(mid 371.370629 -228.284278)
		(end 371.651276 -227.796852)
		(width 0.1143)
		(layer "In6.Cu")
		(net "GMI_CPU1_G0_CPU0_G2_TX_DP<1>")
	)
	(arc
		(start 99.844098 -231.036876)
		(mid 100.124745 -231.524302)
		(end 99.844098 -232.011728)
		(width 0.1143)
		(layer "In6.Cu")
		(net "GMI_CPU1_G0_CPU0_G2_TX_DP<1>")
	)
	(arc
		(start 101.5365 -224.234502)
		(mid 101.471985 -224.496721)
		(end 101.293168 -224.699068)
		(width 0.1143)
		(layer "In6.Cu")
		(net "GMI_CPU1_G0_CPU0_G2_TX_DP<1>")
	)
	(arc
		(start 99.812348 -232.030016)
		(mid 99.65642 -232.334308)
		(end 99.812348 -232.6386)
		(width 0.1143)
		(layer "In6.Cu")
		(net "GMI_CPU1_G0_CPU0_G2_TX_DP<1>")
	)
	(arc
		(start 369.959382 -224.234248)
		(mid 369.917833 -224.062826)
		(end 369.80241 -223.929448)
		(width 0.1143)
		(layer "In6.Cu")
		(net "GMI_CPU1_G0_CPU0_G2_TX_DP<1>")
	)
	(arc
		(start 372.552722 -236.84865)
		(mid 372.373909 -236.6463)
		(end 372.30939 -236.384084)
		(width 0.1143)
		(layer "In6.Cu")
		(net "GMI_CPU1_G0_CPU0_G2_TX_DP<1>")
	)
	(arc
		(start 372.779544 -237.19409)
		(mid 372.738289 -237.023119)
		(end 372.623588 -236.889798)
		(width 0.1143)
		(layer "In6.Cu")
		(net "GMI_CPU1_G0_CPU0_G2_TX_DP<1>")
	)
	(arc
		(start 371.601238 -235.22051)
		(mid 371.373754 -234.764072)
		(end 371.601238 -234.307634)
		(width 0.1143)
		(layer "In6.Cu")
		(net "GMI_CPU1_G0_CPU0_G2_TX_DP<1>")
	)
	(arc
		(start 99.812348 -230.410258)
		(mid 99.697672 -230.543592)
		(end 99.656392 -230.71455)
		(width 0.1143)
		(layer "In6.Cu")
		(net "GMI_CPU1_G0_CPU0_G2_TX_DP<1>")
	)
	(arc
		(start 99.90582 -232.705148)
		(mid 100.13375 -233.14119)
		(end 99.91979 -233.584242)
		(width 0.1143)
		(layer "In6.Cu")
		(net "GMI_CPU1_G0_CPU0_G2_TX_DP<1>")
	)
	(segment
		(start 361.597956 -242.320064)
		(end 362.064808 -242.054126)
		(width 0.12954)
		(layer "F.Cu")
		(net "GMI_CPU1_G0_CPU0_G2_TX_DP<15>")
	)
	(segment
		(start 109.897926 -242.320318)
		(end 109.431074 -242.05438)
		(width 0.12954)
		(layer "F.Cu")
		(net "GMI_CPU1_G0_CPU0_G2_TX_DP<15>")
	)
	(segment
		(start 116.760244 -222.290386)
		(end 116.79682 -222.26905)
		(width 0.1143)
		(layer "In6.Cu")
		(net "GMI_CPU1_G0_CPU0_G2_TX_DP<15>")
	)
	(segment
		(start 345.613228 -214.973408)
		(end 345.656154 -215.159082)
		(width 0.14224)
		(layer "In6.Cu")
		(net "GMI_CPU1_G0_CPU0_G2_TX_DP<15>")
	)
	(segment
		(start 116.748052 -222.297244)
		(end 116.756434 -222.292418)
		(width 0.1143)
		(layer "In6.Cu")
		(net "GMI_CPU1_G0_CPU0_G2_TX_DP<15>")
	)
	(segment
		(start 346.011754 -215.381332)
		(end 346.197174 -215.33866)
		(width 0.14224)
		(layer "In6.Cu")
		(net "GMI_CPU1_G0_CPU0_G2_TX_DP<15>")
	)
	(segment
		(start 357.654098 -226.341686)
		(end 357.66248 -226.33686)
		(width 0.1143)
		(layer "In6.Cu")
		(net "GMI_CPU1_G0_CPU0_G2_TX_DP<15>")
	)
	(segment
		(start 356.15245 -224.724214)
		(end 356.153466 -224.724722)
		(width 0.1143)
		(layer "In6.Cu")
		(net "GMI_CPU1_G0_CPU0_G2_TX_DP<15>")
	)
	(segment
		(start 119.350028 -218.688412)
		(end 124.704094 -214.500206)
		(width 0.14224)
		(layer "In6.Cu")
		(net "GMI_CPU1_G0_CPU0_G2_TX_DP<15>")
	)
	(segment
		(start 353.922838 -220.586554)
		(end 354.264976 -220.828362)
		(width 0.14224)
		(layer "In6.Cu")
		(net "GMI_CPU1_G0_CPU0_G2_TX_DP<15>")
	)
	(segment
		(start 354.409756 -221.202758)
		(end 354.455476 -221.248478)
		(width 0.1143)
		(layer "In6.Cu")
		(net "GMI_CPU1_G0_CPU0_G2_TX_DP<15>")
	)
	(segment
		(start 109.431074 -242.05438)
		(end 109.133132 -242.05438)
		(width 0.1143)
		(layer "In6.Cu")
		(net "GMI_CPU1_G0_CPU0_G2_TX_DP<15>")
	)
	(segment
		(start 114.877596 -225.531934)
		(end 114.916712 -225.509074)
		(width 0.1143)
		(layer "In6.Cu")
		(net "GMI_CPU1_G0_CPU0_G2_TX_DP<15>")
	)
	(segment
		(start 352.830638 -219.979494)
		(end 353.018344 -219.947236)
		(width 0.14224)
		(layer "In6.Cu")
		(net "GMI_CPU1_G0_CPU0_G2_TX_DP<15>")
	)
	(segment
		(start 115.35029 -224.720404)
		(end 115.386866 -224.699068)
		(width 0.1143)
		(layer "In6.Cu")
		(net "GMI_CPU1_G0_CPU0_G2_TX_DP<15>")
	)
	(segment
		(start 231.94772 -200.883012)
		(end 236.351064 -201.65949)
		(width 0.14224)
		(layer "In6.Cu")
		(net "GMI_CPU1_G0_CPU0_G2_TX_DP<15>")
	)
	(segment
		(start 356.153466 -224.724722)
		(end 356.154228 -224.72523)
		(width 0.1143)
		(layer "In6.Cu")
		(net "GMI_CPU1_G0_CPU0_G2_TX_DP<15>")
	)
	(segment
		(start 113.455704 -226.34829)
		(end 113.467642 -226.34194)
		(width 0.1143)
		(layer "In6.Cu")
		(net "GMI_CPU1_G0_CPU0_G2_TX_DP<15>")
	)
	(segment
		(start 354.737162 -222.291148)
		(end 354.738178 -222.291656)
		(width 0.1143)
		(layer "In6.Cu")
		(net "GMI_CPU1_G0_CPU0_G2_TX_DP<15>")
	)
	(segment
		(start 346.556076 -215.562942)
		(end 346.599002 -215.748616)
		(width 0.14224)
		(layer "In6.Cu")
		(net "GMI_CPU1_G0_CPU0_G2_TX_DP<15>")
	)
	(segment
		(start 348.443804 -216.743026)
		(end 348.807278 -216.970102)
		(width 0.14224)
		(layer "In6.Cu")
		(net "GMI_CPU1_G0_CPU0_G2_TX_DP<15>")
	)
	(segment
		(start 116.757704 -222.29191)
		(end 116.75872 -222.291402)
		(width 0.1143)
		(layer "In6.Cu")
		(net "GMI_CPU1_G0_CPU0_G2_TX_DP<15>")
	)
	(segment
		(start 124.704094 -214.500206)
		(end 163.037774 -191.401954)
		(width 0.14224)
		(layer "In6.Cu")
		(net "GMI_CPU1_G0_CPU0_G2_TX_DP<15>")
	)
	(segment
		(start 307.792882 -191.33185)
		(end 345.613228 -214.973408)
		(width 0.14224)
		(layer "In6.Cu")
		(net "GMI_CPU1_G0_CPU0_G2_TX_DP<15>")
	)
	(segment
		(start 347.859858 -216.377774)
		(end 347.90253 -216.563448)
		(width 0.14224)
		(layer "In6.Cu")
		(net "GMI_CPU1_G0_CPU0_G2_TX_DP<15>")
	)
	(segment
		(start 117.040152 -221.62516)
		(end 117.040406 -221.624906)
		(width 0.1143)
		(layer "In6.Cu")
		(net "GMI_CPU1_G0_CPU0_G2_TX_DP<15>")
	)
	(segment
		(start 115.342416 -224.724976)
		(end 115.343432 -224.724468)
		(width 0.1143)
		(layer "In6.Cu")
		(net "GMI_CPU1_G0_CPU0_G2_TX_DP<15>")
	)
	(segment
		(start 110.2995 -241.642646)
		(end 111.398558 -240.543588)
		(width 0.1143)
		(layer "In6.Cu")
		(net "GMI_CPU1_G0_CPU0_G2_TX_DP<15>")
	)
	(segment
		(start 360.391202 -240.837212)
		(end 361.196382 -241.642392)
		(width 0.1143)
		(layer "In6.Cu")
		(net "GMI_CPU1_G0_CPU0_G2_TX_DP<15>")
	)
	(segment
		(start 116.100098 -223.424496)
		(end 116.099844 -223.424496)
		(width 0.1143)
		(layer "In6.Cu")
		(net "GMI_CPU1_G0_CPU0_G2_TX_DP<15>")
	)
	(segment
		(start 240.275872 -200.96734)
		(end 251.791724 -192.903094)
		(width 0.14224)
		(layer "In6.Cu")
		(net "GMI_CPU1_G0_CPU0_G2_TX_DP<15>")
	)
	(segment
		(start 117.040406 -221.624906)
		(end 117.040406 -221.248732)
		(width 0.1143)
		(layer "In6.Cu")
		(net "GMI_CPU1_G0_CPU0_G2_TX_DP<15>")
	)
	(segment
		(start 117.040152 -221.804484)
		(end 117.040152 -221.62516)
		(width 0.1143)
		(layer "In6.Cu")
		(net "GMI_CPU1_G0_CPU0_G2_TX_DP<15>")
	)
	(segment
		(start 355.639116 -223.888808)
		(end 355.708712 -223.929448)
		(width 0.1143)
		(layer "In6.Cu")
		(net "GMI_CPU1_G0_CPU0_G2_TX_DP<15>")
	)
	(segment
		(start 356.109016 -224.698814)
		(end 356.145592 -224.72015)
		(width 0.1143)
		(layer "In6.Cu")
		(net "GMI_CPU1_G0_CPU0_G2_TX_DP<15>")
	)
	(segment
		(start 163.037774 -191.401954)
		(end 207.088232 -191.215518)
		(width 0.14224)
		(layer "In6.Cu")
		(net "GMI_CPU1_G0_CPU0_G2_TX_DP<15>")
	)
	(segment
		(start 115.341654 -224.725484)
		(end 115.342416 -224.724976)
		(width 0.1143)
		(layer "In6.Cu")
		(net "GMI_CPU1_G0_CPU0_G2_TX_DP<15>")
	)
	(segment
		(start 350.304862 -218.029028)
		(end 350.647 -218.270836)
		(width 0.14224)
		(layer "In6.Cu")
		(net "GMI_CPU1_G0_CPU0_G2_TX_DP<15>")
	)
	(segment
		(start 353.018344 -219.947236)
		(end 353.360482 -220.189044)
		(width 0.14224)
		(layer "In6.Cu")
		(net "GMI_CPU1_G0_CPU0_G2_TX_DP<15>")
	)
	(segment
		(start 114.407696 -226.34194)
		(end 114.408712 -226.341432)
		(width 0.1143)
		(layer "In6.Cu")
		(net "GMI_CPU1_G0_CPU0_G2_TX_DP<15>")
	)
	(segment
		(start 354.264976 -220.828362)
		(end 354.409756 -220.973142)
		(width 0.14224)
		(layer "In6.Cu")
		(net "GMI_CPU1_G0_CPU0_G2_TX_DP<15>")
	)
	(segment
		(start 361.311444 -241.731292)
		(end 361.311952 -241.731546)
		(width 0.1143)
		(layer "In6.Cu")
		(net "GMI_CPU1_G0_CPU0_G2_TX_DP<15>")
	)
	(segment
		(start 349.742506 -217.631264)
		(end 349.774764 -217.81897)
		(width 0.14224)
		(layer "In6.Cu")
		(net "GMI_CPU1_G0_CPU0_G2_TX_DP<15>")
	)
	(segment
		(start 356.156768 -224.7265)
		(end 356.179882 -224.739962)
		(width 0.1143)
		(layer "In6.Cu")
		(net "GMI_CPU1_G0_CPU0_G2_TX_DP<15>")
	)
	(segment
		(start 348.807278 -216.970102)
		(end 349.742506 -217.631264)
		(width 0.14224)
		(layer "In6.Cu")
		(net "GMI_CPU1_G0_CPU0_G2_TX_DP<15>")
	)
	(segment
		(start 354.409756 -220.973142)
		(end 354.409756 -221.17431)
		(width 0.14224)
		(layer "In6.Cu")
		(net "GMI_CPU1_G0_CPU0_G2_TX_DP<15>")
	)
	(segment
		(start 354.738178 -222.291656)
		(end 354.739448 -222.292164)
		(width 0.1143)
		(layer "In6.Cu")
		(net "GMI_CPU1_G0_CPU0_G2_TX_DP<15>")
	)
	(segment
		(start 354.455476 -221.624652)
		(end 354.45573 -221.624906)
		(width 0.1143)
		(layer "In6.Cu")
		(net "GMI_CPU1_G0_CPU0_G2_TX_DP<15>")
	)
	(segment
		(start 358.723946 -227.890324)
		(end 358.723946 -236.812328)
		(width 0.1143)
		(layer "In6.Cu")
		(net "GMI_CPU1_G0_CPU0_G2_TX_DP<15>")
	)
	(segment
		(start 116.756434 -222.292418)
		(end 116.757704 -222.29191)
		(width 0.1143)
		(layer "In6.Cu")
		(net "GMI_CPU1_G0_CPU0_G2_TX_DP<15>")
	)
	(segment
		(start 116.2558 -223.120458)
		(end 116.28755 -223.101916)
		(width 0.1143)
		(layer "In6.Cu")
		(net "GMI_CPU1_G0_CPU0_G2_TX_DP<15>")
	)
	(segment
		(start 351.926144 -219.340176)
		(end 352.11385 -219.307918)
		(width 0.14224)
		(layer "In6.Cu")
		(net "GMI_CPU1_G0_CPU0_G2_TX_DP<15>")
	)
	(segment
		(start 116.56187 -222.626428)
		(end 116.56187 -222.621094)
		(width 0.1143)
		(layer "In6.Cu")
		(net "GMI_CPU1_G0_CPU0_G2_TX_DP<15>")
	)
	(segment
		(start 117.040406 -221.248732)
		(end 117.086126 -221.203012)
		(width 0.1143)
		(layer "In6.Cu")
		(net "GMI_CPU1_G0_CPU0_G2_TX_DP<15>")
	)
	(segment
		(start 354.699062 -222.268796)
		(end 354.735638 -222.290132)
		(width 0.1143)
		(layer "In6.Cu")
		(net "GMI_CPU1_G0_CPU0_G2_TX_DP<15>")
	)
	(segment
		(start 262.841486 -190.954914)
		(end 303.7332 -191.33185)
		(width 0.14224)
		(layer "In6.Cu")
		(net "GMI_CPU1_G0_CPU0_G2_TX_DP<15>")
	)
	(segment
		(start 115.348766 -224.72142)
		(end 115.35029 -224.720404)
		(width 0.1143)
		(layer "In6.Cu")
		(net "GMI_CPU1_G0_CPU0_G2_TX_DP<15>")
	)
	(segment
		(start 112.819434 -227.380546)
		(end 113.042446 -226.84232)
		(width 0.1143)
		(layer "In6.Cu")
		(net "GMI_CPU1_G0_CPU0_G2_TX_DP<15>")
	)
	(segment
		(start 115.81765 -223.911922)
		(end 115.856766 -223.889062)
		(width 0.1143)
		(layer "In6.Cu")
		(net "GMI_CPU1_G0_CPU0_G2_TX_DP<15>")
	)
	(segment
		(start 354.735638 -222.290132)
		(end 354.737162 -222.291148)
		(width 0.1143)
		(layer "In6.Cu")
		(net "GMI_CPU1_G0_CPU0_G2_TX_DP<15>")
	)
	(segment
		(start 346.599002 -215.748616)
		(end 346.954602 -215.970866)
		(width 0.14224)
		(layer "In6.Cu")
		(net "GMI_CPU1_G0_CPU0_G2_TX_DP<15>")
	)
	(segment
		(start 351.583752 -219.09786)
		(end 351.926144 -219.340176)
		(width 0.14224)
		(layer "In6.Cu")
		(net "GMI_CPU1_G0_CPU0_G2_TX_DP<15>")
	)
	(segment
		(start 356.148132 -224.721674)
		(end 356.148894 -224.722182)
		(width 0.1143)
		(layer "In6.Cu")
		(net "GMI_CPU1_G0_CPU0_G2_TX_DP<15>")
	)
	(segment
		(start 362.4326 -241.984276)
		(end 362.36275 -242.054126)
		(width 0.1143)
		(layer "In6.Cu")
		(net "GMI_CPU1_G0_CPU0_G2_TX_DP<15>")
	)
	(segment
		(start 358.104694 -226.400614)
		(end 358.107996 -226.403916)
		(width 0.1143)
		(layer "In6.Cu")
		(net "GMI_CPU1_G0_CPU0_G2_TX_DP<15>")
	)
	(segment
		(start 346.954602 -215.970866)
		(end 347.140022 -215.92794)
		(width 0.14224)
		(layer "In6.Cu")
		(net "GMI_CPU1_G0_CPU0_G2_TX_DP<15>")
	)
	(segment
		(start 356.148894 -224.722182)
		(end 356.151688 -224.723706)
		(width 0.1143)
		(layer "In6.Cu")
		(net "GMI_CPU1_G0_CPU0_G2_TX_DP<15>")
	)
	(segment
		(start 111.398558 -240.543588)
		(end 111.398558 -240.543334)
		(width 0.1143)
		(layer "In6.Cu")
		(net "GMI_CPU1_G0_CPU0_G2_TX_DP<15>")
	)
	(segment
		(start 109.133132 -242.05438)
		(end 109.063282 -241.98453)
		(width 0.1143)
		(layer "In6.Cu")
		(net "GMI_CPU1_G0_CPU0_G2_TX_DP<15>")
	)
	(segment
		(start 355.208332 -223.101662)
		(end 355.240082 -223.120204)
		(width 0.1143)
		(layer "In6.Cu")
		(net "GMI_CPU1_G0_CPU0_G2_TX_DP<15>")
	)
	(segment
		(start 357.08717 -226.341178)
		(end 357.088186 -226.341686)
		(width 0.1143)
		(layer "In6.Cu")
		(net "GMI_CPU1_G0_CPU0_G2_TX_DP<15>")
	)
	(segment
		(start 116.75872 -222.291402)
		(end 116.760244 -222.290386)
		(width 0.1143)
		(layer "In6.Cu")
		(net "GMI_CPU1_G0_CPU0_G2_TX_DP<15>")
	)
	(segment
		(start 114.408712 -226.341432)
		(end 114.446812 -226.31908)
		(width 0.1143)
		(layer "In6.Cu")
		(net "GMI_CPU1_G0_CPU0_G2_TX_DP<15>")
	)
	(segment
		(start 362.251752 -241.731546)
		(end 362.283502 -241.749834)
		(width 0.1143)
		(layer "In6.Cu")
		(net "GMI_CPU1_G0_CPU0_G2_TX_DP<15>")
	)
	(segment
		(start 362.36275 -242.054126)
		(end 362.064808 -242.054126)
		(width 0.1143)
		(layer "In6.Cu")
		(net "GMI_CPU1_G0_CPU0_G2_TX_DP<15>")
	)
	(segment
		(start 350.647 -218.270836)
		(end 350.679258 -218.458542)
		(width 0.14224)
		(layer "In6.Cu")
		(net "GMI_CPU1_G0_CPU0_G2_TX_DP<15>")
	)
	(segment
		(start 347.140022 -215.92794)
		(end 347.859858 -216.377774)
		(width 0.14224)
		(layer "In6.Cu")
		(net "GMI_CPU1_G0_CPU0_G2_TX_DP<15>")
	)
	(segment
		(start 352.455988 -219.549726)
		(end 352.488246 -219.737178)
		(width 0.14224)
		(layer "In6.Cu")
		(net "GMI_CPU1_G0_CPU0_G2_TX_DP<15>")
	)
	(segment
		(start 251.791724 -192.903094)
		(end 262.841486 -190.954914)
		(width 0.14224)
		(layer "In6.Cu")
		(net "GMI_CPU1_G0_CPU0_G2_TX_DP<15>")
	)
	(segment
		(start 346.197174 -215.33866)
		(end 346.556076 -215.562942)
		(width 0.14224)
		(layer "In6.Cu")
		(net "GMI_CPU1_G0_CPU0_G2_TX_DP<15>")
	)
	(segment
		(start 207.088232 -191.215518)
		(end 209.73542 -191.682624)
		(width 0.14224)
		(layer "In6.Cu")
		(net "GMI_CPU1_G0_CPU0_G2_TX_DP<15>")
	)
	(segment
		(start 355.396038 -223.424242)
		(end 355.395784 -223.424242)
		(width 0.1143)
		(layer "In6.Cu")
		(net "GMI_CPU1_G0_CPU0_G2_TX_DP<15>")
	)
	(segment
		(start 236.351064 -201.65949)
		(end 240.275872 -200.96734)
		(width 0.14224)
		(layer "In6.Cu")
		(net "GMI_CPU1_G0_CPU0_G2_TX_DP<15>")
	)
	(segment
		(start 352.11385 -219.307918)
		(end 352.455988 -219.549726)
		(width 0.14224)
		(layer "In6.Cu")
		(net "GMI_CPU1_G0_CPU0_G2_TX_DP<15>")
	)
	(segment
		(start 115.346988 -224.722436)
		(end 115.34775 -224.721928)
		(width 0.1143)
		(layer "In6.Cu")
		(net "GMI_CPU1_G0_CPU0_G2_TX_DP<15>")
	)
	(segment
		(start 113.042446 -226.84232)
		(end 113.0427 -226.841812)
		(width 0.1143)
		(layer "In6.Cu")
		(net "GMI_CPU1_G0_CPU0_G2_TX_DP<15>")
	)
	(segment
		(start 356.154228 -224.72523)
		(end 356.156768 -224.7265)
		(width 0.1143)
		(layer "In6.Cu")
		(net "GMI_CPU1_G0_CPU0_G2_TX_DP<15>")
	)
	(segment
		(start 349.774764 -217.81897)
		(end 350.117156 -218.061286)
		(width 0.14224)
		(layer "In6.Cu")
		(net "GMI_CPU1_G0_CPU0_G2_TX_DP<15>")
	)
	(segment
		(start 117.086126 -221.203012)
		(end 117.086126 -221.174564)
		(width 0.1143)
		(layer "In6.Cu")
		(net "GMI_CPU1_G0_CPU0_G2_TX_DP<15>")
	)
	(segment
		(start 353.360482 -220.189044)
		(end 353.39274 -220.376496)
		(width 0.14224)
		(layer "In6.Cu")
		(net "GMI_CPU1_G0_CPU0_G2_TX_DP<15>")
	)
	(segment
		(start 354.934012 -222.62084)
		(end 354.934012 -222.626174)
		(width 0.1143)
		(layer "In6.Cu")
		(net "GMI_CPU1_G0_CPU0_G2_TX_DP<15>")
	)
	(segment
		(start 357.04907 -226.318826)
		(end 357.08717 -226.341178)
		(width 0.1143)
		(layer "In6.Cu")
		(net "GMI_CPU1_G0_CPU0_G2_TX_DP<15>")
	)
	(segment
		(start 354.45573 -221.624906)
		(end 354.45573 -221.80423)
		(width 0.1143)
		(layer "In6.Cu")
		(net "GMI_CPU1_G0_CPU0_G2_TX_DP<15>")
	)
	(segment
		(start 351.021904 -218.700858)
		(end 351.209356 -218.6686)
		(width 0.14224)
		(layer "In6.Cu")
		(net "GMI_CPU1_G0_CPU0_G2_TX_DP<15>")
	)
	(segment
		(start 113.833402 -226.337114)
		(end 113.841784 -226.34194)
		(width 0.1143)
		(layer "In6.Cu")
		(net "GMI_CPU1_G0_CPU0_G2_TX_DP<15>")
	)
	(segment
		(start 353.39274 -220.376496)
		(end 353.735132 -220.618812)
		(width 0.14224)
		(layer "In6.Cu")
		(net "GMI_CPU1_G0_CPU0_G2_TX_DP<15>")
	)
	(segment
		(start 354.455476 -221.248478)
		(end 354.455476 -221.624652)
		(width 0.1143)
		(layer "In6.Cu")
		(net "GMI_CPU1_G0_CPU0_G2_TX_DP<15>")
	)
	(segment
		(start 356.147116 -224.721166)
		(end 356.148132 -224.721674)
		(width 0.1143)
		(layer "In6.Cu")
		(net "GMI_CPU1_G0_CPU0_G2_TX_DP<15>")
	)
	(segment
		(start 115.78717 -223.929702)
		(end 115.81765 -223.911922)
		(width 0.1143)
		(layer "In6.Cu")
		(net "GMI_CPU1_G0_CPU0_G2_TX_DP<15>")
	)
	(segment
		(start 112.797336 -237.06074)
		(end 112.797336 -227.491798)
		(width 0.1143)
		(layer "In6.Cu")
		(net "GMI_CPU1_G0_CPU0_G2_TX_DP<15>")
	)
	(segment
		(start 356.151688 -224.723706)
		(end 356.15245 -224.724214)
		(width 0.1143)
		(layer "In6.Cu")
		(net "GMI_CPU1_G0_CPU0_G2_TX_DP<15>")
	)
	(segment
		(start 348.25813 -216.785698)
		(end 348.443804 -216.743026)
		(width 0.14224)
		(layer "In6.Cu")
		(net "GMI_CPU1_G0_CPU0_G2_TX_DP<15>")
	)
	(segment
		(start 351.209356 -218.6686)
		(end 351.551494 -218.910408)
		(width 0.14224)
		(layer "In6.Cu")
		(net "GMI_CPU1_G0_CPU0_G2_TX_DP<15>")
	)
	(segment
		(start 354.739448 -222.292164)
		(end 354.74783 -222.29699)
		(width 0.1143)
		(layer "In6.Cu")
		(net "GMI_CPU1_G0_CPU0_G2_TX_DP<15>")
	)
	(segment
		(start 345.656154 -215.159082)
		(end 346.011754 -215.381332)
		(width 0.14224)
		(layer "In6.Cu")
		(net "GMI_CPU1_G0_CPU0_G2_TX_DP<15>")
	)
	(segment
		(start 351.551494 -218.910408)
		(end 351.583752 -219.09786)
		(width 0.14224)
		(layer "In6.Cu")
		(net "GMI_CPU1_G0_CPU0_G2_TX_DP<15>")
	)
	(segment
		(start 115.34775 -224.721928)
		(end 115.348766 -224.72142)
		(width 0.1143)
		(layer "In6.Cu")
		(net "GMI_CPU1_G0_CPU0_G2_TX_DP<15>")
	)
	(segment
		(start 115.344194 -224.72396)
		(end 115.346988 -224.722436)
		(width 0.1143)
		(layer "In6.Cu")
		(net "GMI_CPU1_G0_CPU0_G2_TX_DP<15>")
	)
	(segment
		(start 109.21238 -241.750088)
		(end 109.24413 -241.7318)
		(width 0.1143)
		(layer "In6.Cu")
		(net "GMI_CPU1_G0_CPU0_G2_TX_DP<15>")
	)
	(segment
		(start 117.086126 -221.174564)
		(end 117.086126 -220.952314)
		(width 0.14224)
		(layer "In6.Cu")
		(net "GMI_CPU1_G0_CPU0_G2_TX_DP<15>")
	)
	(segment
		(start 303.7332 -191.33185)
		(end 307.792882 -191.33185)
		(width 0.14224)
		(layer "In6.Cu")
		(net "GMI_CPU1_G0_CPU0_G2_TX_DP<15>")
	)
	(segment
		(start 356.145592 -224.72015)
		(end 356.147116 -224.721166)
		(width 0.1143)
		(layer "In6.Cu")
		(net "GMI_CPU1_G0_CPU0_G2_TX_DP<15>")
	)
	(segment
		(start 115.343432 -224.724468)
		(end 115.344194 -224.72396)
		(width 0.1143)
		(layer "In6.Cu")
		(net "GMI_CPU1_G0_CPU0_G2_TX_DP<15>")
	)
	(segment
		(start 353.735132 -220.618812)
		(end 353.922838 -220.586554)
		(width 0.14224)
		(layer "In6.Cu")
		(net "GMI_CPU1_G0_CPU0_G2_TX_DP<15>")
	)
	(segment
		(start 115.316 -224.740216)
		(end 115.341654 -224.725484)
		(width 0.1143)
		(layer "In6.Cu")
		(net "GMI_CPU1_G0_CPU0_G2_TX_DP<15>")
	)
	(segment
		(start 356.57917 -225.50882)
		(end 356.648766 -225.54946)
		(width 0.1143)
		(layer "In6.Cu")
		(net "GMI_CPU1_G0_CPU0_G2_TX_DP<15>")
	)
	(segment
		(start 354.409756 -221.17431)
		(end 354.409756 -221.202758)
		(width 0.1143)
		(layer "In6.Cu")
		(net "GMI_CPU1_G0_CPU0_G2_TX_DP<15>")
	)
	(segment
		(start 114.847116 -225.549714)
		(end 114.877596 -225.531934)
		(width 0.1143)
		(layer "In6.Cu")
		(net "GMI_CPU1_G0_CPU0_G2_TX_DP<15>")
	)
	(segment
		(start 352.488246 -219.737178)
		(end 352.830638 -219.979494)
		(width 0.14224)
		(layer "In6.Cu")
		(net "GMI_CPU1_G0_CPU0_G2_TX_DP<15>")
	)
	(segment
		(start 110.18393 -241.7318)
		(end 110.184438 -241.731546)
		(width 0.1143)
		(layer "In6.Cu")
		(net "GMI_CPU1_G0_CPU0_G2_TX_DP<15>")
	)
	(segment
		(start 350.679258 -218.458542)
		(end 351.021904 -218.700858)
		(width 0.14224)
		(layer "In6.Cu")
		(net "GMI_CPU1_G0_CPU0_G2_TX_DP<15>")
	)
	(segment
		(start 209.73542 -191.682624)
		(end 231.94772 -200.883012)
		(width 0.14224)
		(layer "In6.Cu")
		(net "GMI_CPU1_G0_CPU0_G2_TX_DP<15>")
	)
	(segment
		(start 117.086126 -220.952314)
		(end 119.350028 -218.688412)
		(width 0.14224)
		(layer "In6.Cu")
		(net "GMI_CPU1_G0_CPU0_G2_TX_DP<15>")
	)
	(segment
		(start 347.90253 -216.563448)
		(end 348.25813 -216.785698)
		(width 0.14224)
		(layer "In6.Cu")
		(net "GMI_CPU1_G0_CPU0_G2_TX_DP<15>")
	)
	(segment
		(start 350.117156 -218.061286)
		(end 350.304862 -218.029028)
		(width 0.14224)
		(layer "In6.Cu")
		(net "GMI_CPU1_G0_CPU0_G2_TX_DP<15>")
	)
	(arc
		(start 113.841784 -226.34194)
		(mid 114.12474 -226.418117)
		(end 114.407696 -226.34194)
		(width 0.1143)
		(layer "In6.Cu")
		(net "GMI_CPU1_G0_CPU0_G2_TX_DP<15>")
	)
	(arc
		(start 110.184438 -241.731546)
		(mid 110.244842 -241.690815)
		(end 110.2995 -241.642646)
		(width 0.1143)
		(layer "In6.Cu")
		(net "GMI_CPU1_G0_CPU0_G2_TX_DP<15>")
	)
	(arc
		(start 358.02824 -226.341686)
		(mid 358.068385 -226.368662)
		(end 358.104694 -226.400614)
		(width 0.1143)
		(layer "In6.Cu")
		(net "GMI_CPU1_G0_CPU0_G2_TX_DP<15>")
	)
	(arc
		(start 356.648766 -225.54946)
		(mid 356.764193 -225.682836)
		(end 356.805738 -225.85426)
		(width 0.1143)
		(layer "In6.Cu")
		(net "GMI_CPU1_G0_CPU0_G2_TX_DP<15>")
	)
	(arc
		(start 358.723946 -236.812328)
		(mid 359.157302 -238.990576)
		(end 360.391202 -240.837212)
		(width 0.1143)
		(layer "In6.Cu")
		(net "GMI_CPU1_G0_CPU0_G2_TX_DP<15>")
	)
	(arc
		(start 356.335838 -225.044254)
		(mid 356.400353 -225.306473)
		(end 356.57917 -225.50882)
		(width 0.1143)
		(layer "In6.Cu")
		(net "GMI_CPU1_G0_CPU0_G2_TX_DP<15>")
	)
	(arc
		(start 112.797336 -227.491798)
		(mid 112.802914 -227.435085)
		(end 112.819434 -227.380546)
		(width 0.1143)
		(layer "In6.Cu")
		(net "GMI_CPU1_G0_CPU0_G2_TX_DP<15>")
	)
	(arc
		(start 115.856766 -223.889062)
		(mid 116.035579 -223.686712)
		(end 116.100098 -223.424496)
		(width 0.1143)
		(layer "In6.Cu")
		(net "GMI_CPU1_G0_CPU0_G2_TX_DP<15>")
	)
	(arc
		(start 115.160044 -225.044508)
		(mid 115.201299 -224.873537)
		(end 115.316 -224.740216)
		(width 0.1143)
		(layer "In6.Cu")
		(net "GMI_CPU1_G0_CPU0_G2_TX_DP<15>")
	)
	(arc
		(start 111.398558 -240.543334)
		(mid 112.343568 -239.195415)
		(end 112.772444 -237.606078)
		(width 0.1143)
		(layer "In6.Cu")
		(net "GMI_CPU1_G0_CPU0_G2_TX_DP<15>")
	)
	(arc
		(start 114.446812 -226.31908)
		(mid 114.625625 -226.11673)
		(end 114.690144 -225.854514)
		(width 0.1143)
		(layer "In6.Cu")
		(net "GMI_CPU1_G0_CPU0_G2_TX_DP<15>")
	)
	(arc
		(start 358.107996 -226.403916)
		(mid 358.563835 -227.085843)
		(end 358.723946 -227.890324)
		(width 0.1143)
		(layer "In6.Cu")
		(net "GMI_CPU1_G0_CPU0_G2_TX_DP<15>")
	)
	(arc
		(start 356.805738 -225.85426)
		(mid 356.870253 -226.116479)
		(end 357.04907 -226.318826)
		(width 0.1143)
		(layer "In6.Cu")
		(net "GMI_CPU1_G0_CPU0_G2_TX_DP<15>")
	)
	(arc
		(start 113.0427 -226.841812)
		(mid 113.053325 -226.81489)
		(end 113.063274 -226.78771)
		(width 0.1143)
		(layer "In6.Cu")
		(net "GMI_CPU1_G0_CPU0_G2_TX_DP<15>")
	)
	(arc
		(start 357.088186 -226.341686)
		(mid 357.371142 -226.417863)
		(end 357.654098 -226.341686)
		(width 0.1143)
		(layer "In6.Cu")
		(net "GMI_CPU1_G0_CPU0_G2_TX_DP<15>")
	)
	(arc
		(start 354.934012 -222.626174)
		(mid 355.007518 -222.900634)
		(end 355.208332 -223.101662)
		(width 0.1143)
		(layer "In6.Cu")
		(net "GMI_CPU1_G0_CPU0_G2_TX_DP<15>")
	)
	(arc
		(start 116.79682 -222.26905)
		(mid 116.975633 -222.0667)
		(end 117.040152 -221.804484)
		(width 0.1143)
		(layer "In6.Cu")
		(net "GMI_CPU1_G0_CPU0_G2_TX_DP<15>")
	)
	(arc
		(start 362.283502 -241.749834)
		(mid 362.380637 -241.852703)
		(end 362.4326 -241.984276)
		(width 0.1143)
		(layer "In6.Cu")
		(net "GMI_CPU1_G0_CPU0_G2_TX_DP<15>")
	)
	(arc
		(start 114.916712 -225.509074)
		(mid 115.095525 -225.306724)
		(end 115.160044 -225.044508)
		(width 0.1143)
		(layer "In6.Cu")
		(net "GMI_CPU1_G0_CPU0_G2_TX_DP<15>")
	)
	(arc
		(start 356.179882 -224.739962)
		(mid 356.294558 -224.873296)
		(end 356.335838 -225.044254)
		(width 0.1143)
		(layer "In6.Cu")
		(net "GMI_CPU1_G0_CPU0_G2_TX_DP<15>")
	)
	(arc
		(start 354.74783 -222.29699)
		(mid 354.884183 -222.434051)
		(end 354.934012 -222.62084)
		(width 0.1143)
		(layer "In6.Cu")
		(net "GMI_CPU1_G0_CPU0_G2_TX_DP<15>")
	)
	(arc
		(start 114.690144 -225.854514)
		(mid 114.731693 -225.683092)
		(end 114.847116 -225.549714)
		(width 0.1143)
		(layer "In6.Cu")
		(net "GMI_CPU1_G0_CPU0_G2_TX_DP<15>")
	)
	(arc
		(start 112.772444 -237.606078)
		(mid 112.791116 -237.333693)
		(end 112.797336 -237.06074)
		(width 0.1143)
		(layer "In6.Cu")
		(net "GMI_CPU1_G0_CPU0_G2_TX_DP<15>")
	)
	(arc
		(start 113.467642 -226.34194)
		(mid 113.649893 -226.29159)
		(end 113.833402 -226.337114)
		(width 0.1143)
		(layer "In6.Cu")
		(net "GMI_CPU1_G0_CPU0_G2_TX_DP<15>")
	)
	(arc
		(start 116.56187 -222.621094)
		(mid 116.611741 -222.434329)
		(end 116.748052 -222.297244)
		(width 0.1143)
		(layer "In6.Cu")
		(net "GMI_CPU1_G0_CPU0_G2_TX_DP<15>")
	)
	(arc
		(start 116.28755 -223.101916)
		(mid 116.488408 -222.900913)
		(end 116.56187 -222.626428)
		(width 0.1143)
		(layer "In6.Cu")
		(net "GMI_CPU1_G0_CPU0_G2_TX_DP<15>")
	)
	(arc
		(start 355.865684 -224.234248)
		(mid 355.930199 -224.496467)
		(end 356.109016 -224.698814)
		(width 0.1143)
		(layer "In6.Cu")
		(net "GMI_CPU1_G0_CPU0_G2_TX_DP<15>")
	)
	(arc
		(start 109.063282 -241.98453)
		(mid 109.115331 -241.853011)
		(end 109.21238 -241.750088)
		(width 0.1143)
		(layer "In6.Cu")
		(net "GMI_CPU1_G0_CPU0_G2_TX_DP<15>")
	)
	(arc
		(start 355.395784 -223.424242)
		(mid 355.460299 -223.686461)
		(end 355.639116 -223.888808)
		(width 0.1143)
		(layer "In6.Cu")
		(net "GMI_CPU1_G0_CPU0_G2_TX_DP<15>")
	)
	(arc
		(start 109.618018 -241.7318)
		(mid 109.900974 -241.807977)
		(end 110.18393 -241.7318)
		(width 0.1143)
		(layer "In6.Cu")
		(net "GMI_CPU1_G0_CPU0_G2_TX_DP<15>")
	)
	(arc
		(start 361.877864 -241.731546)
		(mid 362.064808 -241.681291)
		(end 362.251752 -241.731546)
		(width 0.1143)
		(layer "In6.Cu")
		(net "GMI_CPU1_G0_CPU0_G2_TX_DP<15>")
	)
	(arc
		(start 354.45573 -221.80423)
		(mid 354.520245 -222.066449)
		(end 354.699062 -222.268796)
		(width 0.1143)
		(layer "In6.Cu")
		(net "GMI_CPU1_G0_CPU0_G2_TX_DP<15>")
	)
	(arc
		(start 361.196382 -241.642392)
		(mid 361.251029 -241.690576)
		(end 361.311444 -241.731292)
		(width 0.1143)
		(layer "In6.Cu")
		(net "GMI_CPU1_G0_CPU0_G2_TX_DP<15>")
	)
	(arc
		(start 357.66248 -226.33686)
		(mid 357.845988 -226.291366)
		(end 358.02824 -226.341686)
		(width 0.1143)
		(layer "In6.Cu")
		(net "GMI_CPU1_G0_CPU0_G2_TX_DP<15>")
	)
	(arc
		(start 115.386866 -224.699068)
		(mid 115.565679 -224.496718)
		(end 115.630198 -224.234502)
		(width 0.1143)
		(layer "In6.Cu")
		(net "GMI_CPU1_G0_CPU0_G2_TX_DP<15>")
	)
	(arc
		(start 355.708712 -223.929448)
		(mid 355.824139 -224.062824)
		(end 355.865684 -224.234248)
		(width 0.1143)
		(layer "In6.Cu")
		(net "GMI_CPU1_G0_CPU0_G2_TX_DP<15>")
	)
	(arc
		(start 361.311952 -241.731546)
		(mid 361.594908 -241.807723)
		(end 361.877864 -241.731546)
		(width 0.1143)
		(layer "In6.Cu")
		(net "GMI_CPU1_G0_CPU0_G2_TX_DP<15>")
	)
	(arc
		(start 115.630198 -224.234502)
		(mid 115.671747 -224.06308)
		(end 115.78717 -223.929702)
		(width 0.1143)
		(layer "In6.Cu")
		(net "GMI_CPU1_G0_CPU0_G2_TX_DP<15>")
	)
	(arc
		(start 116.099844 -223.424496)
		(mid 116.141103 -223.253639)
		(end 116.2558 -223.120458)
		(width 0.1143)
		(layer "In6.Cu")
		(net "GMI_CPU1_G0_CPU0_G2_TX_DP<15>")
	)
	(arc
		(start 355.240082 -223.120204)
		(mid 355.354758 -223.253395)
		(end 355.396038 -223.424242)
		(width 0.1143)
		(layer "In6.Cu")
		(net "GMI_CPU1_G0_CPU0_G2_TX_DP<15>")
	)
	(arc
		(start 109.24413 -241.7318)
		(mid 109.431074 -241.681545)
		(end 109.618018 -241.7318)
		(width 0.1143)
		(layer "In6.Cu")
		(net "GMI_CPU1_G0_CPU0_G2_TX_DP<15>")
	)
	(arc
		(start 113.063274 -226.78771)
		(mid 113.216581 -226.529684)
		(end 113.455704 -226.34829)
		(width 0.1143)
		(layer "In6.Cu")
		(net "GMI_CPU1_G0_CPU0_G2_TX_DP<15>")
	)
	(segment
		(start 361.597956 -240.700052)
		(end 362.064808 -240.434114)
		(width 0.12954)
		(layer "F.Cu")
		(net "GMI_CPU1_G0_CPU0_G2_TX_DP<14>")
	)
	(segment
		(start 109.897926 -240.700306)
		(end 109.431074 -240.434368)
		(width 0.12954)
		(layer "F.Cu")
		(net "GMI_CPU1_G0_CPU0_G2_TX_DP<14>")
	)
	(segment
		(start 353.075748 -218.627706)
		(end 354.631752 -219.865448)
		(width 0.14224)
		(layer "In6.Cu")
		(net "GMI_CPU1_G0_CPU0_G2_TX_DP<14>")
	)
	(segment
		(start 112.012984 -227.514658)
		(end 112.66424 -225.976688)
		(width 0.1143)
		(layer "In6.Cu")
		(net "GMI_CPU1_G0_CPU0_G2_TX_DP<14>")
	)
	(segment
		(start 357.04907 -224.698814)
		(end 357.08717 -224.721166)
		(width 0.1143)
		(layer "In6.Cu")
		(net "GMI_CPU1_G0_CPU0_G2_TX_DP<14>")
	)
	(segment
		(start 114.40541 -224.723198)
		(end 114.406172 -224.72269)
		(width 0.1143)
		(layer "In6.Cu")
		(net "GMI_CPU1_G0_CPU0_G2_TX_DP<14>")
	)
	(segment
		(start 216.342976 -193.410078)
		(end 216.730326 -193.570606)
		(width 0.14224)
		(layer "In6.Cu")
		(net "GMI_CPU1_G0_CPU0_G2_TX_DP<14>")
	)
	(segment
		(start 116.09959 -221.545912)
		(end 116.09959 -221.248732)
		(width 0.1143)
		(layer "In6.Cu")
		(net "GMI_CPU1_G0_CPU0_G2_TX_DP<14>")
	)
	(segment
		(start 115.346988 -223.102424)
		(end 115.34775 -223.101916)
		(width 0.1143)
		(layer "In6.Cu")
		(net "GMI_CPU1_G0_CPU0_G2_TX_DP<14>")
	)
	(segment
		(start 115.348766 -223.101408)
		(end 115.35029 -223.100392)
		(width 0.1143)
		(layer "In6.Cu")
		(net "GMI_CPU1_G0_CPU0_G2_TX_DP<14>")
	)
	(segment
		(start 227.740718 -197.984872)
		(end 227.813616 -198.161148)
		(width 0.14224)
		(layer "In6.Cu")
		(net "GMI_CPU1_G0_CPU0_G2_TX_DP<14>")
	)
	(segment
		(start 110.294674 -240.02619)
		(end 110.92688 -239.394238)
		(width 0.1143)
		(layer "In6.Cu")
		(net "GMI_CPU1_G0_CPU0_G2_TX_DP<14>")
	)
	(segment
		(start 112.997742 -225.531934)
		(end 113.006124 -225.527108)
		(width 0.1143)
		(layer "In6.Cu")
		(net "GMI_CPU1_G0_CPU0_G2_TX_DP<14>")
	)
	(segment
		(start 207.12811 -190.268352)
		(end 210.581494 -190.877444)
		(width 0.14224)
		(layer "In6.Cu")
		(net "GMI_CPU1_G0_CPU0_G2_TX_DP<14>")
	)
	(segment
		(start 228.20122 -198.321422)
		(end 228.376988 -198.248524)
		(width 0.14224)
		(layer "In6.Cu")
		(net "GMI_CPU1_G0_CPU0_G2_TX_DP<14>")
	)
	(segment
		(start 228.764084 -198.408798)
		(end 228.836982 -198.585074)
		(width 0.14224)
		(layer "In6.Cu")
		(net "GMI_CPU1_G0_CPU0_G2_TX_DP<14>")
	)
	(segment
		(start 308.159658 -190.391796)
		(end 351.136204 -217.256614)
		(width 0.14224)
		(layer "In6.Cu")
		(net "GMI_CPU1_G0_CPU0_G2_TX_DP<14>")
	)
	(segment
		(start 115.35029 -223.100392)
		(end 115.386866 -223.079056)
		(width 0.1143)
		(layer "In6.Cu")
		(net "GMI_CPU1_G0_CPU0_G2_TX_DP<14>")
	)
	(segment
		(start 356.153974 -223.104964)
		(end 356.154736 -223.105472)
		(width 0.1143)
		(layer "In6.Cu")
		(net "GMI_CPU1_G0_CPU0_G2_TX_DP<14>")
	)
	(segment
		(start 236.371892 -200.708768)
		(end 239.893602 -200.087738)
		(width 0.14224)
		(layer "In6.Cu")
		(net "GMI_CPU1_G0_CPU0_G2_TX_DP<14>")
	)
	(segment
		(start 112.66424 -225.976688)
		(end 112.66424 -225.976434)
		(width 0.1143)
		(layer "In6.Cu")
		(net "GMI_CPU1_G0_CPU0_G2_TX_DP<14>")
	)
	(segment
		(start 229.224586 -198.745348)
		(end 229.400354 -198.67245)
		(width 0.14224)
		(layer "In6.Cu")
		(net "GMI_CPU1_G0_CPU0_G2_TX_DP<14>")
	)
	(segment
		(start 359.537 -227.89896)
		(end 359.537 -236.78134)
		(width 0.1143)
		(layer "In6.Cu")
		(net "GMI_CPU1_G0_CPU0_G2_TX_DP<14>")
	)
	(segment
		(start 355.396292 -221.248478)
		(end 355.396292 -221.545658)
		(width 0.1143)
		(layer "In6.Cu")
		(net "GMI_CPU1_G0_CPU0_G2_TX_DP<14>")
	)
	(segment
		(start 114.847116 -223.929702)
		(end 114.877596 -223.911922)
		(width 0.1143)
		(layer "In6.Cu")
		(net "GMI_CPU1_G0_CPU0_G2_TX_DP<14>")
	)
	(segment
		(start 213.091522 -191.917574)
		(end 213.16442 -192.093342)
		(width 0.14224)
		(layer "In6.Cu")
		(net "GMI_CPU1_G0_CPU0_G2_TX_DP<14>")
	)
	(segment
		(start 109.21238 -240.130076)
		(end 109.24413 -240.111788)
		(width 0.1143)
		(layer "In6.Cu")
		(net "GMI_CPU1_G0_CPU0_G2_TX_DP<14>")
	)
	(segment
		(start 115.344194 -223.103948)
		(end 115.346988 -223.102424)
		(width 0.1143)
		(layer "In6.Cu")
		(net "GMI_CPU1_G0_CPU0_G2_TX_DP<14>")
	)
	(segment
		(start 229.400354 -198.67245)
		(end 229.78745 -198.832724)
		(width 0.14224)
		(layer "In6.Cu")
		(net "GMI_CPU1_G0_CPU0_G2_TX_DP<14>")
	)
	(segment
		(start 229.78745 -198.832724)
		(end 229.860348 -199.009)
		(width 0.14224)
		(layer "In6.Cu")
		(net "GMI_CPU1_G0_CPU0_G2_TX_DP<14>")
	)
	(segment
		(start 114.403632 -224.724214)
		(end 114.40541 -224.723198)
		(width 0.1143)
		(layer "In6.Cu")
		(net "GMI_CPU1_G0_CPU0_G2_TX_DP<14>")
	)
	(segment
		(start 111.984028 -237.210346)
		(end 111.984028 -227.657152)
		(width 0.1143)
		(layer "In6.Cu")
		(net "GMI_CPU1_G0_CPU0_G2_TX_DP<14>")
	)
	(segment
		(start 251.423424 -192.01384)
		(end 262.765794 -190.013844)
		(width 0.14224)
		(layer "In6.Cu")
		(net "GMI_CPU1_G0_CPU0_G2_TX_DP<14>")
	)
	(segment
		(start 355.396292 -221.545658)
		(end 355.395784 -221.546166)
		(width 0.1143)
		(layer "In6.Cu")
		(net "GMI_CPU1_G0_CPU0_G2_TX_DP<14>")
	)
	(segment
		(start 116.09959 -221.248732)
		(end 116.14531 -221.203012)
		(width 0.1143)
		(layer "In6.Cu")
		(net "GMI_CPU1_G0_CPU0_G2_TX_DP<14>")
	)
	(segment
		(start 116.100098 -221.54642)
		(end 116.09959 -221.545912)
		(width 0.1143)
		(layer "In6.Cu")
		(net "GMI_CPU1_G0_CPU0_G2_TX_DP<14>")
	)
	(segment
		(start 115.81765 -222.29191)
		(end 115.856766 -222.26905)
		(width 0.1143)
		(layer "In6.Cu")
		(net "GMI_CPU1_G0_CPU0_G2_TX_DP<14>")
	)
	(segment
		(start 358.574848 -225.590608)
		(end 358.585008 -225.600768)
		(width 0.1143)
		(layer "In6.Cu")
		(net "GMI_CPU1_G0_CPU0_G2_TX_DP<14>")
	)
	(segment
		(start 115.78717 -222.30969)
		(end 115.81765 -222.29191)
		(width 0.1143)
		(layer "In6.Cu")
		(net "GMI_CPU1_G0_CPU0_G2_TX_DP<14>")
	)
	(segment
		(start 116.100098 -221.804484)
		(end 116.100098 -221.54642)
		(width 0.1143)
		(layer "In6.Cu")
		(net "GMI_CPU1_G0_CPU0_G2_TX_DP<14>")
	)
	(segment
		(start 303.7332 -190.391796)
		(end 308.159658 -190.391796)
		(width 0.14224)
		(layer "In6.Cu")
		(net "GMI_CPU1_G0_CPU0_G2_TX_DP<14>")
	)
	(segment
		(start 262.765794 -190.013844)
		(end 303.7332 -190.391796)
		(width 0.14224)
		(layer "In6.Cu")
		(net "GMI_CPU1_G0_CPU0_G2_TX_DP<14>")
	)
	(segment
		(start 228.376988 -198.248524)
		(end 228.764084 -198.408798)
		(width 0.14224)
		(layer "In6.Cu")
		(net "GMI_CPU1_G0_CPU0_G2_TX_DP<14>")
	)
	(segment
		(start 143.464026 -202.099164)
		(end 143.46428 -202.099164)
		(width 0.14224)
		(layer "In6.Cu")
		(net "GMI_CPU1_G0_CPU0_G2_TX_DP<14>")
	)
	(segment
		(start 215.246712 -192.81013)
		(end 215.31961 -192.986152)
		(width 0.14224)
		(layer "In6.Cu")
		(net "GMI_CPU1_G0_CPU0_G2_TX_DP<14>")
	)
	(segment
		(start 229.860348 -199.009)
		(end 230.247952 -199.169274)
		(width 0.14224)
		(layer "In6.Cu")
		(net "GMI_CPU1_G0_CPU0_G2_TX_DP<14>")
	)
	(segment
		(start 357.08971 -224.722436)
		(end 357.090472 -224.722944)
		(width 0.1143)
		(layer "In6.Cu")
		(net "GMI_CPU1_G0_CPU0_G2_TX_DP<14>")
	)
	(segment
		(start 362.36275 -240.434114)
		(end 362.064808 -240.434114)
		(width 0.1143)
		(layer "In6.Cu")
		(net "GMI_CPU1_G0_CPU0_G2_TX_DP<14>")
	)
	(segment
		(start 356.148894 -223.10217)
		(end 356.151688 -223.103694)
		(width 0.1143)
		(layer "In6.Cu")
		(net "GMI_CPU1_G0_CPU0_G2_TX_DP<14>")
	)
	(segment
		(start 216.906348 -193.497708)
		(end 227.740718 -197.984872)
		(width 0.14224)
		(layer "In6.Cu")
		(net "GMI_CPU1_G0_CPU0_G2_TX_DP<14>")
	)
	(segment
		(start 360.935016 -239.759998)
		(end 361.219496 -240.044478)
		(width 0.1143)
		(layer "In6.Cu")
		(net "GMI_CPU1_G0_CPU0_G2_TX_DP<14>")
	)
	(segment
		(start 355.395784 -221.546166)
		(end 355.395784 -221.80423)
		(width 0.1143)
		(layer "In6.Cu")
		(net "GMI_CPU1_G0_CPU0_G2_TX_DP<14>")
	)
	(segment
		(start 124.141484 -213.742016)
		(end 143.464026 -202.099164)
		(width 0.14224)
		(layer "In6.Cu")
		(net "GMI_CPU1_G0_CPU0_G2_TX_DP<14>")
	)
	(segment
		(start 239.893602 -200.087738)
		(end 245.658386 -196.050662)
		(width 0.14224)
		(layer "In6.Cu")
		(net "GMI_CPU1_G0_CPU0_G2_TX_DP<14>")
	)
	(segment
		(start 143.46428 -202.099164)
		(end 162.786314 -190.456566)
		(width 0.14224)
		(layer "In6.Cu")
		(net "GMI_CPU1_G0_CPU0_G2_TX_DP<14>")
	)
	(segment
		(start 362.251752 -240.111534)
		(end 362.283502 -240.129822)
		(width 0.1143)
		(layer "In6.Cu")
		(net "GMI_CPU1_G0_CPU0_G2_TX_DP<14>")
	)
	(segment
		(start 228.836982 -198.585074)
		(end 229.224586 -198.745348)
		(width 0.14224)
		(layer "In6.Cu")
		(net "GMI_CPU1_G0_CPU0_G2_TX_DP<14>")
	)
	(segment
		(start 214.859616 -192.649856)
		(end 215.246712 -192.81013)
		(width 0.14224)
		(layer "In6.Cu")
		(net "GMI_CPU1_G0_CPU0_G2_TX_DP<14>")
	)
	(segment
		(start 356.148132 -223.101662)
		(end 356.148894 -223.10217)
		(width 0.1143)
		(layer "In6.Cu")
		(net "GMI_CPU1_G0_CPU0_G2_TX_DP<14>")
	)
	(segment
		(start 356.156006 -223.106234)
		(end 356.158546 -223.107504)
		(width 0.1143)
		(layer "In6.Cu")
		(net "GMI_CPU1_G0_CPU0_G2_TX_DP<14>")
	)
	(segment
		(start 114.877596 -223.911922)
		(end 114.916712 -223.889062)
		(width 0.1143)
		(layer "In6.Cu")
		(net "GMI_CPU1_G0_CPU0_G2_TX_DP<14>")
	)
	(segment
		(start 356.147116 -223.101154)
		(end 356.148132 -223.101662)
		(width 0.1143)
		(layer "In6.Cu")
		(net "GMI_CPU1_G0_CPU0_G2_TX_DP<14>")
	)
	(segment
		(start 114.408712 -224.72142)
		(end 114.446812 -224.699068)
		(width 0.1143)
		(layer "In6.Cu")
		(net "GMI_CPU1_G0_CPU0_G2_TX_DP<14>")
	)
	(segment
		(start 215.31961 -192.986152)
		(end 215.70696 -193.14668)
		(width 0.14224)
		(layer "In6.Cu")
		(net "GMI_CPU1_G0_CPU0_G2_TX_DP<14>")
	)
	(segment
		(start 355.350572 -220.584268)
		(end 355.350572 -221.17431)
		(width 0.14224)
		(layer "In6.Cu")
		(net "GMI_CPU1_G0_CPU0_G2_TX_DP<14>")
	)
	(segment
		(start 357.08717 -224.721166)
		(end 357.08971 -224.722436)
		(width 0.1143)
		(layer "In6.Cu")
		(net "GMI_CPU1_G0_CPU0_G2_TX_DP<14>")
	)
	(segment
		(start 109.431074 -240.434368)
		(end 109.133132 -240.434368)
		(width 0.1143)
		(layer "In6.Cu")
		(net "GMI_CPU1_G0_CPU0_G2_TX_DP<14>")
	)
	(segment
		(start 216.730326 -193.570606)
		(end 216.906348 -193.497708)
		(width 0.14224)
		(layer "In6.Cu")
		(net "GMI_CPU1_G0_CPU0_G2_TX_DP<14>")
	)
	(segment
		(start 245.658386 -196.050662)
		(end 245.65864 -196.050662)
		(width 0.14224)
		(layer "In6.Cu")
		(net "GMI_CPU1_G0_CPU0_G2_TX_DP<14>")
	)
	(segment
		(start 213.727792 -192.180972)
		(end 214.2236 -192.386204)
		(width 0.14224)
		(layer "In6.Cu")
		(net "GMI_CPU1_G0_CPU0_G2_TX_DP<14>")
	)
	(segment
		(start 356.109016 -223.078802)
		(end 356.145592 -223.100138)
		(width 0.1143)
		(layer "In6.Cu")
		(net "GMI_CPU1_G0_CPU0_G2_TX_DP<14>")
	)
	(segment
		(start 216.270078 -193.234056)
		(end 216.342976 -193.410078)
		(width 0.14224)
		(layer "In6.Cu")
		(net "GMI_CPU1_G0_CPU0_G2_TX_DP<14>")
	)
	(segment
		(start 230.247952 -199.169274)
		(end 230.42372 -199.096376)
		(width 0.14224)
		(layer "In6.Cu")
		(net "GMI_CPU1_G0_CPU0_G2_TX_DP<14>")
	)
	(segment
		(start 231.44226 -199.51827)
		(end 232.794302 -200.07834)
		(width 0.14224)
		(layer "In6.Cu")
		(net "GMI_CPU1_G0_CPU0_G2_TX_DP<14>")
	)
	(segment
		(start 109.133132 -240.434368)
		(end 109.063282 -240.364518)
		(width 0.1143)
		(layer "In6.Cu")
		(net "GMI_CPU1_G0_CPU0_G2_TX_DP<14>")
	)
	(segment
		(start 356.154736 -223.105472)
		(end 356.156006 -223.106234)
		(width 0.1143)
		(layer "In6.Cu")
		(net "GMI_CPU1_G0_CPU0_G2_TX_DP<14>")
	)
	(segment
		(start 355.639116 -222.268796)
		(end 355.708712 -222.309436)
		(width 0.1143)
		(layer "In6.Cu")
		(net "GMI_CPU1_G0_CPU0_G2_TX_DP<14>")
	)
	(segment
		(start 356.15245 -223.104202)
		(end 356.153974 -223.104964)
		(width 0.1143)
		(layer "In6.Cu")
		(net "GMI_CPU1_G0_CPU0_G2_TX_DP<14>")
	)
	(segment
		(start 357.09225 -224.72396)
		(end 357.093266 -224.724468)
		(width 0.1143)
		(layer "In6.Cu")
		(net "GMI_CPU1_G0_CPU0_G2_TX_DP<14>")
	)
	(segment
		(start 356.57917 -223.888808)
		(end 356.648766 -223.929448)
		(width 0.1143)
		(layer "In6.Cu")
		(net "GMI_CPU1_G0_CPU0_G2_TX_DP<14>")
	)
	(segment
		(start 355.350572 -221.17431)
		(end 355.350572 -221.202758)
		(width 0.1143)
		(layer "In6.Cu")
		(net "GMI_CPU1_G0_CPU0_G2_TX_DP<14>")
	)
	(segment
		(start 210.581494 -190.877444)
		(end 213.091522 -191.917574)
		(width 0.14224)
		(layer "In6.Cu")
		(net "GMI_CPU1_G0_CPU0_G2_TX_DP<14>")
	)
	(segment
		(start 230.42372 -199.096376)
		(end 230.815388 -199.258682)
		(width 0.14224)
		(layer "In6.Cu")
		(net "GMI_CPU1_G0_CPU0_G2_TX_DP<14>")
	)
	(segment
		(start 115.341146 -223.105726)
		(end 115.341908 -223.105218)
		(width 0.1143)
		(layer "In6.Cu")
		(net "GMI_CPU1_G0_CPU0_G2_TX_DP<14>")
	)
	(segment
		(start 362.4326 -240.364264)
		(end 362.36275 -240.434114)
		(width 0.1143)
		(layer "In6.Cu")
		(net "GMI_CPU1_G0_CPU0_G2_TX_DP<14>")
	)
	(segment
		(start 356.158546 -223.107504)
		(end 356.179882 -223.11995)
		(width 0.1143)
		(layer "In6.Cu")
		(net "GMI_CPU1_G0_CPU0_G2_TX_DP<14>")
	)
	(segment
		(start 114.402616 -224.724722)
		(end 114.403632 -224.724214)
		(width 0.1143)
		(layer "In6.Cu")
		(net "GMI_CPU1_G0_CPU0_G2_TX_DP<14>")
	)
	(segment
		(start 245.65864 -196.050662)
		(end 251.423424 -192.01384)
		(width 0.14224)
		(layer "In6.Cu")
		(net "GMI_CPU1_G0_CPU0_G2_TX_DP<14>")
	)
	(segment
		(start 116.14531 -221.203012)
		(end 116.14531 -221.174564)
		(width 0.1143)
		(layer "In6.Cu")
		(net "GMI_CPU1_G0_CPU0_G2_TX_DP<14>")
	)
	(segment
		(start 114.406172 -224.72269)
		(end 114.408712 -224.72142)
		(width 0.1143)
		(layer "In6.Cu")
		(net "GMI_CPU1_G0_CPU0_G2_TX_DP<14>")
	)
	(segment
		(start 215.70696 -193.14668)
		(end 215.882982 -193.073782)
		(width 0.14224)
		(layer "In6.Cu")
		(net "GMI_CPU1_G0_CPU0_G2_TX_DP<14>")
	)
	(segment
		(start 213.16442 -192.093342)
		(end 213.55177 -192.25387)
		(width 0.14224)
		(layer "In6.Cu")
		(net "GMI_CPU1_G0_CPU0_G2_TX_DP<14>")
	)
	(segment
		(start 231.276398 -199.587104)
		(end 231.44226 -199.51827)
		(width 0.14224)
		(layer "In6.Cu")
		(net "GMI_CPU1_G0_CPU0_G2_TX_DP<14>")
	)
	(segment
		(start 215.882982 -193.073782)
		(end 216.270078 -193.234056)
		(width 0.14224)
		(layer "In6.Cu")
		(net "GMI_CPU1_G0_CPU0_G2_TX_DP<14>")
	)
	(segment
		(start 162.786314 -190.456566)
		(end 207.12811 -190.268352)
		(width 0.14224)
		(layer "In6.Cu")
		(net "GMI_CPU1_G0_CPU0_G2_TX_DP<14>")
	)
	(segment
		(start 115.316 -223.120204)
		(end 115.341146 -223.105726)
		(width 0.1143)
		(layer "In6.Cu")
		(net "GMI_CPU1_G0_CPU0_G2_TX_DP<14>")
	)
	(segment
		(start 230.815388 -199.258682)
		(end 230.884222 -199.424798)
		(width 0.14224)
		(layer "In6.Cu")
		(net "GMI_CPU1_G0_CPU0_G2_TX_DP<14>")
	)
	(segment
		(start 356.145592 -223.100138)
		(end 356.147116 -223.101154)
		(width 0.1143)
		(layer "In6.Cu")
		(net "GMI_CPU1_G0_CPU0_G2_TX_DP<14>")
	)
	(segment
		(start 227.813616 -198.161148)
		(end 228.20122 -198.321422)
		(width 0.14224)
		(layer "In6.Cu")
		(net "GMI_CPU1_G0_CPU0_G2_TX_DP<14>")
	)
	(segment
		(start 213.55177 -192.25387)
		(end 213.727792 -192.180972)
		(width 0.14224)
		(layer "In6.Cu")
		(net "GMI_CPU1_G0_CPU0_G2_TX_DP<14>")
	)
	(segment
		(start 214.2236 -192.386204)
		(end 214.296244 -192.562226)
		(width 0.14224)
		(layer "In6.Cu")
		(net "GMI_CPU1_G0_CPU0_G2_TX_DP<14>")
	)
	(segment
		(start 360.935016 -239.760252)
		(end 360.935016 -239.759998)
		(width 0.1143)
		(layer "In6.Cu")
		(net "GMI_CPU1_G0_CPU0_G2_TX_DP<14>")
	)
	(segment
		(start 116.14531 -220.57233)
		(end 118.78691 -217.93073)
		(width 0.14224)
		(layer "In6.Cu")
		(net "GMI_CPU1_G0_CPU0_G2_TX_DP<14>")
	)
	(segment
		(start 354.631752 -219.865448)
		(end 355.350572 -220.584268)
		(width 0.14224)
		(layer "In6.Cu")
		(net "GMI_CPU1_G0_CPU0_G2_TX_DP<14>")
	)
	(segment
		(start 214.683848 -192.722754)
		(end 214.859616 -192.649856)
		(width 0.14224)
		(layer "In6.Cu")
		(net "GMI_CPU1_G0_CPU0_G2_TX_DP<14>")
	)
	(segment
		(start 116.14531 -221.174564)
		(end 116.14531 -220.57233)
		(width 0.14224)
		(layer "In6.Cu")
		(net "GMI_CPU1_G0_CPU0_G2_TX_DP<14>")
	)
	(segment
		(start 360.654854 -239.479836)
		(end 360.935016 -239.760252)
		(width 0.1143)
		(layer "In6.Cu")
		(net "GMI_CPU1_G0_CPU0_G2_TX_DP<14>")
	)
	(segment
		(start 357.090472 -224.722944)
		(end 357.09225 -224.72396)
		(width 0.1143)
		(layer "In6.Cu")
		(net "GMI_CPU1_G0_CPU0_G2_TX_DP<14>")
	)
	(segment
		(start 355.350572 -221.202758)
		(end 355.396292 -221.248478)
		(width 0.1143)
		(layer "In6.Cu")
		(net "GMI_CPU1_G0_CPU0_G2_TX_DP<14>")
	)
	(segment
		(start 358.489758 -225.526854)
		(end 358.49814 -225.53168)
		(width 0.1143)
		(layer "In6.Cu")
		(net "GMI_CPU1_G0_CPU0_G2_TX_DP<14>")
	)
	(segment
		(start 214.296244 -192.562226)
		(end 214.683848 -192.722754)
		(width 0.14224)
		(layer "In6.Cu")
		(net "GMI_CPU1_G0_CPU0_G2_TX_DP<14>")
	)
	(segment
		(start 115.341908 -223.105218)
		(end 115.343432 -223.104456)
		(width 0.1143)
		(layer "In6.Cu")
		(net "GMI_CPU1_G0_CPU0_G2_TX_DP<14>")
	)
	(segment
		(start 115.343432 -223.104456)
		(end 115.344194 -223.103948)
		(width 0.1143)
		(layer "In6.Cu")
		(net "GMI_CPU1_G0_CPU0_G2_TX_DP<14>")
	)
	(segment
		(start 232.794302 -200.07834)
		(end 236.371892 -200.708768)
		(width 0.14224)
		(layer "In6.Cu")
		(net "GMI_CPU1_G0_CPU0_G2_TX_DP<14>")
	)
	(segment
		(start 111.910622 -237.71479)
		(end 111.971836 -237.355888)
		(width 0.1143)
		(layer "In6.Cu")
		(net "GMI_CPU1_G0_CPU0_G2_TX_DP<14>")
	)
	(segment
		(start 351.136204 -217.256614)
		(end 353.075748 -218.627706)
		(width 0.14224)
		(layer "In6.Cu")
		(net "GMI_CPU1_G0_CPU0_G2_TX_DP<14>")
	)
	(segment
		(start 118.78691 -217.93073)
		(end 124.141484 -213.742016)
		(width 0.14224)
		(layer "In6.Cu")
		(net "GMI_CPU1_G0_CPU0_G2_TX_DP<14>")
	)
	(segment
		(start 356.151688 -223.103694)
		(end 356.15245 -223.104202)
		(width 0.1143)
		(layer "In6.Cu")
		(net "GMI_CPU1_G0_CPU0_G2_TX_DP<14>")
	)
	(segment
		(start 115.34775 -223.101916)
		(end 115.348766 -223.101408)
		(width 0.1143)
		(layer "In6.Cu")
		(net "GMI_CPU1_G0_CPU0_G2_TX_DP<14>")
	)
	(segment
		(start 230.884222 -199.424798)
		(end 231.276398 -199.587104)
		(width 0.14224)
		(layer "In6.Cu")
		(net "GMI_CPU1_G0_CPU0_G2_TX_DP<14>")
	)
	(arc
		(start 358.49814 -225.53168)
		(mid 358.507237 -225.537138)
		(end 358.516174 -225.542856)
		(width 0.1143)
		(layer "In6.Cu")
		(net "GMI_CPU1_G0_CPU0_G2_TX_DP<14>")
	)
	(arc
		(start 356.648766 -223.929448)
		(mid 356.764193 -224.062824)
		(end 356.805738 -224.234248)
		(width 0.1143)
		(layer "In6.Cu")
		(net "GMI_CPU1_G0_CPU0_G2_TX_DP<14>")
	)
	(arc
		(start 112.979708 -225.54311)
		(mid 112.988646 -225.537395)
		(end 112.997742 -225.531934)
		(width 0.1143)
		(layer "In6.Cu")
		(net "GMI_CPU1_G0_CPU0_G2_TX_DP<14>")
	)
	(arc
		(start 113.371884 -225.531934)
		(mid 113.65484 -225.608111)
		(end 113.937796 -225.531934)
		(width 0.1143)
		(layer "In6.Cu")
		(net "GMI_CPU1_G0_CPU0_G2_TX_DP<14>")
	)
	(arc
		(start 115.856766 -222.26905)
		(mid 116.035579 -222.0667)
		(end 116.100098 -221.804484)
		(width 0.1143)
		(layer "In6.Cu")
		(net "GMI_CPU1_G0_CPU0_G2_TX_DP<14>")
	)
	(arc
		(start 356.805738 -224.234248)
		(mid 356.870253 -224.496467)
		(end 357.04907 -224.698814)
		(width 0.1143)
		(layer "In6.Cu")
		(net "GMI_CPU1_G0_CPU0_G2_TX_DP<14>")
	)
	(arc
		(start 114.446812 -224.699068)
		(mid 114.625625 -224.496718)
		(end 114.690144 -224.234502)
		(width 0.1143)
		(layer "In6.Cu")
		(net "GMI_CPU1_G0_CPU0_G2_TX_DP<14>")
	)
	(arc
		(start 358.123998 -225.53168)
		(mid 358.306249 -225.48133)
		(end 358.489758 -225.526854)
		(width 0.1143)
		(layer "In6.Cu")
		(net "GMI_CPU1_G0_CPU0_G2_TX_DP<14>")
	)
	(arc
		(start 358.516174 -225.542856)
		(mid 358.546733 -225.565231)
		(end 358.574848 -225.590608)
		(width 0.1143)
		(layer "In6.Cu")
		(net "GMI_CPU1_G0_CPU0_G2_TX_DP<14>")
	)
	(arc
		(start 111.862362 -237.88878)
		(mid 111.890919 -237.803013)
		(end 111.910622 -237.71479)
		(width 0.1143)
		(layer "In6.Cu")
		(net "GMI_CPU1_G0_CPU0_G2_TX_DP<14>")
	)
	(arc
		(start 110.92688 -239.394238)
		(mid 111.463928 -238.684576)
		(end 111.862362 -237.88878)
		(width 0.1143)
		(layer "In6.Cu")
		(net "GMI_CPU1_G0_CPU0_G2_TX_DP<14>")
	)
	(arc
		(start 109.618018 -240.111788)
		(mid 109.883045 -240.187799)
		(end 110.152434 -240.12906)
		(width 0.1143)
		(layer "In6.Cu")
		(net "GMI_CPU1_G0_CPU0_G2_TX_DP<14>")
	)
	(arc
		(start 357.093266 -224.724468)
		(mid 357.226954 -224.859869)
		(end 357.275892 -225.043746)
		(width 0.1143)
		(layer "In6.Cu")
		(net "GMI_CPU1_G0_CPU0_G2_TX_DP<14>")
	)
	(arc
		(start 356.179882 -223.11995)
		(mid 356.294558 -223.253284)
		(end 356.335838 -223.424242)
		(width 0.1143)
		(layer "In6.Cu")
		(net "GMI_CPU1_G0_CPU0_G2_TX_DP<14>")
	)
	(arc
		(start 355.865684 -222.614236)
		(mid 355.930199 -222.876455)
		(end 356.109016 -223.078802)
		(width 0.1143)
		(layer "In6.Cu")
		(net "GMI_CPU1_G0_CPU0_G2_TX_DP<14>")
	)
	(arc
		(start 362.283502 -240.129822)
		(mid 362.380637 -240.232691)
		(end 362.4326 -240.364264)
		(width 0.1143)
		(layer "In6.Cu")
		(net "GMI_CPU1_G0_CPU0_G2_TX_DP<14>")
	)
	(arc
		(start 356.335838 -223.424242)
		(mid 356.400353 -223.686461)
		(end 356.57917 -223.888808)
		(width 0.1143)
		(layer "In6.Cu")
		(net "GMI_CPU1_G0_CPU0_G2_TX_DP<14>")
	)
	(arc
		(start 355.708712 -222.309436)
		(mid 355.824139 -222.442812)
		(end 355.865684 -222.614236)
		(width 0.1143)
		(layer "In6.Cu")
		(net "GMI_CPU1_G0_CPU0_G2_TX_DP<14>")
	)
	(arc
		(start 113.006124 -225.527108)
		(mid 113.189632 -225.481614)
		(end 113.371884 -225.531934)
		(width 0.1143)
		(layer "In6.Cu")
		(net "GMI_CPU1_G0_CPU0_G2_TX_DP<14>")
	)
	(arc
		(start 357.558086 -225.53168)
		(mid 357.841042 -225.607857)
		(end 358.123998 -225.53168)
		(width 0.1143)
		(layer "In6.Cu")
		(net "GMI_CPU1_G0_CPU0_G2_TX_DP<14>")
	)
	(arc
		(start 114.916712 -223.889062)
		(mid 115.095525 -223.686712)
		(end 115.160044 -223.424496)
		(width 0.1143)
		(layer "In6.Cu")
		(net "GMI_CPU1_G0_CPU0_G2_TX_DP<14>")
	)
	(arc
		(start 112.921034 -225.590862)
		(mid 112.949164 -225.565504)
		(end 112.979708 -225.54311)
		(width 0.1143)
		(layer "In6.Cu")
		(net "GMI_CPU1_G0_CPU0_G2_TX_DP<14>")
	)
	(arc
		(start 115.386866 -223.079056)
		(mid 115.565679 -222.876706)
		(end 115.630198 -222.61449)
		(width 0.1143)
		(layer "In6.Cu")
		(net "GMI_CPU1_G0_CPU0_G2_TX_DP<14>")
	)
	(arc
		(start 359.537 -236.78134)
		(mid 359.82757 -238.241754)
		(end 360.654854 -239.479836)
		(width 0.1143)
		(layer "In6.Cu")
		(net "GMI_CPU1_G0_CPU0_G2_TX_DP<14>")
	)
	(arc
		(start 115.160044 -223.424496)
		(mid 115.201299 -223.253525)
		(end 115.316 -223.120204)
		(width 0.1143)
		(layer "In6.Cu")
		(net "GMI_CPU1_G0_CPU0_G2_TX_DP<14>")
	)
	(arc
		(start 110.152434 -240.12906)
		(mid 110.227725 -240.083393)
		(end 110.294674 -240.02619)
		(width 0.1143)
		(layer "In6.Cu")
		(net "GMI_CPU1_G0_CPU0_G2_TX_DP<14>")
	)
	(arc
		(start 114.21999 -225.044)
		(mid 114.268931 -224.860125)
		(end 114.402616 -224.724722)
		(width 0.1143)
		(layer "In6.Cu")
		(net "GMI_CPU1_G0_CPU0_G2_TX_DP<14>")
	)
	(arc
		(start 109.24413 -240.111788)
		(mid 109.431074 -240.061533)
		(end 109.618018 -240.111788)
		(width 0.1143)
		(layer "In6.Cu")
		(net "GMI_CPU1_G0_CPU0_G2_TX_DP<14>")
	)
	(arc
		(start 111.971836 -237.355888)
		(mid 111.980997 -237.283374)
		(end 111.984028 -237.210346)
		(width 0.1143)
		(layer "In6.Cu")
		(net "GMI_CPU1_G0_CPU0_G2_TX_DP<14>")
	)
	(arc
		(start 112.66424 -225.976434)
		(mid 112.774198 -225.771366)
		(end 112.921034 -225.590862)
		(width 0.1143)
		(layer "In6.Cu")
		(net "GMI_CPU1_G0_CPU0_G2_TX_DP<14>")
	)
	(arc
		(start 361.219496 -240.044478)
		(mid 361.537802 -240.184808)
		(end 361.877864 -240.111534)
		(width 0.1143)
		(layer "In6.Cu")
		(net "GMI_CPU1_G0_CPU0_G2_TX_DP<14>")
	)
	(arc
		(start 109.063282 -240.364518)
		(mid 109.115331 -240.232999)
		(end 109.21238 -240.130076)
		(width 0.1143)
		(layer "In6.Cu")
		(net "GMI_CPU1_G0_CPU0_G2_TX_DP<14>")
	)
	(arc
		(start 358.585008 -225.600768)
		(mid 359.289602 -226.655173)
		(end 359.537 -227.89896)
		(width 0.1143)
		(layer "In6.Cu")
		(net "GMI_CPU1_G0_CPU0_G2_TX_DP<14>")
	)
	(arc
		(start 114.690144 -224.234502)
		(mid 114.731693 -224.06308)
		(end 114.847116 -223.929702)
		(width 0.1143)
		(layer "In6.Cu")
		(net "GMI_CPU1_G0_CPU0_G2_TX_DP<14>")
	)
	(arc
		(start 355.395784 -221.80423)
		(mid 355.460299 -222.066449)
		(end 355.639116 -222.268796)
		(width 0.1143)
		(layer "In6.Cu")
		(net "GMI_CPU1_G0_CPU0_G2_TX_DP<14>")
	)
	(arc
		(start 113.937796 -225.531934)
		(mid 114.144386 -225.325839)
		(end 114.21999 -225.044)
		(width 0.1143)
		(layer "In6.Cu")
		(net "GMI_CPU1_G0_CPU0_G2_TX_DP<14>")
	)
	(arc
		(start 361.877864 -240.111534)
		(mid 362.064808 -240.061279)
		(end 362.251752 -240.111534)
		(width 0.1143)
		(layer "In6.Cu")
		(net "GMI_CPU1_G0_CPU0_G2_TX_DP<14>")
	)
	(arc
		(start 357.275892 -225.043746)
		(mid 357.351527 -225.325567)
		(end 357.558086 -225.53168)
		(width 0.1143)
		(layer "In6.Cu")
		(net "GMI_CPU1_G0_CPU0_G2_TX_DP<14>")
	)
	(arc
		(start 111.984028 -227.657152)
		(mid 111.991376 -227.584458)
		(end 112.012984 -227.514658)
		(width 0.1143)
		(layer "In6.Cu")
		(net "GMI_CPU1_G0_CPU0_G2_TX_DP<14>")
	)
	(arc
		(start 115.630198 -222.61449)
		(mid 115.671747 -222.443068)
		(end 115.78717 -222.30969)
		(width 0.1143)
		(layer "In6.Cu")
		(net "GMI_CPU1_G0_CPU0_G2_TX_DP<14>")
	)
	(segment
		(start 361.597956 -239.08004)
		(end 362.064808 -238.814102)
		(width 0.12954)
		(layer "F.Cu")
		(net "GMI_CPU1_G0_CPU0_G2_TX_DP<13>")
	)
	(segment
		(start 109.897926 -239.080294)
		(end 109.431074 -238.814356)
		(width 0.12954)
		(layer "F.Cu")
		(net "GMI_CPU1_G0_CPU0_G2_TX_DP<13>")
	)
	(segment
		(start 233.761534 -199.293734)
		(end 236.278928 -199.737726)
		(width 0.14224)
		(layer "In6.Cu")
		(net "GMI_CPU1_G0_CPU0_G2_TX_DP<13>")
	)
	(segment
		(start 358.027224 -224.721166)
		(end 358.027986 -224.721674)
		(width 0.1143)
		(layer "In6.Cu")
		(net "GMI_CPU1_G0_CPU0_G2_TX_DP<13>")
	)
	(segment
		(start 113.93932 -223.91116)
		(end 113.974118 -223.89084)
		(width 0.1143)
		(layer "In6.Cu")
		(net "GMI_CPU1_G0_CPU0_G2_TX_DP<13>")
	)
	(segment
		(start 114.376962 -223.119696)
		(end 114.406934 -223.102424)
		(width 0.1143)
		(layer "In6.Cu")
		(net "GMI_CPU1_G0_CPU0_G2_TX_DP<13>")
	)
	(segment
		(start 115.205764 -220.192092)
		(end 118.174516 -217.22334)
		(width 0.14224)
		(layer "In6.Cu")
		(net "GMI_CPU1_G0_CPU0_G2_TX_DP<13>")
	)
	(segment
		(start 212.831426 -190.770002)
		(end 213.21903 -190.930276)
		(width 0.14224)
		(layer "In6.Cu")
		(net "GMI_CPU1_G0_CPU0_G2_TX_DP<13>")
	)
	(segment
		(start 357.08717 -223.101154)
		(end 357.088186 -223.101662)
		(width 0.1143)
		(layer "In6.Cu")
		(net "GMI_CPU1_G0_CPU0_G2_TX_DP<13>")
	)
	(segment
		(start 214.381842 -191.41186)
		(end 214.55761 -191.338962)
		(width 0.14224)
		(layer "In6.Cu")
		(net "GMI_CPU1_G0_CPU0_G2_TX_DP<13>")
	)
	(segment
		(start 231.9782 -198.555102)
		(end 233.761534 -199.293734)
		(width 0.14224)
		(layer "In6.Cu")
		(net "GMI_CPU1_G0_CPU0_G2_TX_DP<13>")
	)
	(segment
		(start 143.118332 -201.20991)
		(end 162.588448 -189.478158)
		(width 0.14224)
		(layer "In6.Cu")
		(net "GMI_CPU1_G0_CPU0_G2_TX_DP<13>")
	)
	(segment
		(start 115.160044 -221.248732)
		(end 115.205764 -221.203012)
		(width 0.1143)
		(layer "In6.Cu")
		(net "GMI_CPU1_G0_CPU0_G2_TX_DP<13>")
	)
	(segment
		(start 362.4326 -238.744252)
		(end 362.36275 -238.814102)
		(width 0.1143)
		(layer "In6.Cu")
		(net "GMI_CPU1_G0_CPU0_G2_TX_DP<13>")
	)
	(segment
		(start 356.290118 -221.17431)
		(end 356.290118 -221.202758)
		(width 0.1143)
		(layer "In6.Cu")
		(net "GMI_CPU1_G0_CPU0_G2_TX_DP<13>")
	)
	(segment
		(start 113.876328 -223.955864)
		(end 113.90884 -223.928686)
		(width 0.1143)
		(layer "In6.Cu")
		(net "GMI_CPU1_G0_CPU0_G2_TX_DP<13>")
	)
	(segment
		(start 211.549742 -190.092838)
		(end 212.758782 -190.593726)
		(width 0.14224)
		(layer "In6.Cu")
		(net "GMI_CPU1_G0_CPU0_G2_TX_DP<13>")
	)
	(segment
		(start 361.308904 -238.489744)
		(end 361.311952 -238.491522)
		(width 0.1143)
		(layer "In6.Cu")
		(net "GMI_CPU1_G0_CPU0_G2_TX_DP<13>")
	)
	(segment
		(start 357.088186 -223.101662)
		(end 357.088948 -223.10217)
		(width 0.1143)
		(layer "In6.Cu")
		(net "GMI_CPU1_G0_CPU0_G2_TX_DP<13>")
	)
	(segment
		(start 357.565706 -223.915986)
		(end 357.589836 -223.929956)
		(width 0.1143)
		(layer "In6.Cu")
		(net "GMI_CPU1_G0_CPU0_G2_TX_DP<13>")
	)
	(segment
		(start 123.647708 -212.941916)
		(end 143.118078 -201.210164)
		(width 0.14224)
		(layer "In6.Cu")
		(net "GMI_CPU1_G0_CPU0_G2_TX_DP<13>")
	)
	(segment
		(start 113.937796 -223.911922)
		(end 113.93932 -223.91116)
		(width 0.1143)
		(layer "In6.Cu")
		(net "GMI_CPU1_G0_CPU0_G2_TX_DP<13>")
	)
	(segment
		(start 112.389666 -225.06305)
		(end 112.390428 -225.062288)
		(width 0.1143)
		(layer "In6.Cu")
		(net "GMI_CPU1_G0_CPU0_G2_TX_DP<13>")
	)
	(segment
		(start 230.955088 -198.131176)
		(end 231.342184 -198.29145)
		(width 0.14224)
		(layer "In6.Cu")
		(net "GMI_CPU1_G0_CPU0_G2_TX_DP<13>")
	)
	(segment
		(start 114.410236 -223.100392)
		(end 114.446812 -223.079056)
		(width 0.1143)
		(layer "In6.Cu")
		(net "GMI_CPU1_G0_CPU0_G2_TX_DP<13>")
	)
	(segment
		(start 358.027986 -224.721674)
		(end 358.02824 -224.721674)
		(width 0.1143)
		(layer "In6.Cu")
		(net "GMI_CPU1_G0_CPU0_G2_TX_DP<13>")
	)
	(segment
		(start 359.267506 -225.225864)
		(end 359.500678 -225.493326)
		(width 0.1143)
		(layer "In6.Cu")
		(net "GMI_CPU1_G0_CPU0_G2_TX_DP<13>")
	)
	(segment
		(start 109.431074 -238.814356)
		(end 109.133132 -238.814356)
		(width 0.1143)
		(layer "In6.Cu")
		(net "GMI_CPU1_G0_CPU0_G2_TX_DP<13>")
	)
	(segment
		(start 213.21903 -190.930276)
		(end 213.394798 -190.857378)
		(width 0.14224)
		(layer "In6.Cu")
		(net "GMI_CPU1_G0_CPU0_G2_TX_DP<13>")
	)
	(segment
		(start 111.182912 -227.937314)
		(end 111.182912 -227.93706)
		(width 0.1143)
		(layer "In6.Cu")
		(net "GMI_CPU1_G0_CPU0_G2_TX_DP<13>")
	)
	(segment
		(start 114.408712 -223.101408)
		(end 114.410236 -223.100392)
		(width 0.1143)
		(layer "In6.Cu")
		(net "GMI_CPU1_G0_CPU0_G2_TX_DP<13>")
	)
	(segment
		(start 357.04907 -223.078802)
		(end 357.085646 -223.100138)
		(width 0.1143)
		(layer "In6.Cu")
		(net "GMI_CPU1_G0_CPU0_G2_TX_DP<13>")
	)
	(segment
		(start 262.689086 -189.07252)
		(end 303.7332 -189.451488)
		(width 0.14224)
		(layer "In6.Cu")
		(net "GMI_CPU1_G0_CPU0_G2_TX_DP<13>")
	)
	(segment
		(start 361.305602 -238.487966)
		(end 361.306364 -238.488474)
		(width 0.1143)
		(layer "In6.Cu")
		(net "GMI_CPU1_G0_CPU0_G2_TX_DP<13>")
	)
	(segment
		(start 206.994252 -189.28969)
		(end 211.549742 -190.092838)
		(width 0.14224)
		(layer "In6.Cu")
		(net "GMI_CPU1_G0_CPU0_G2_TX_DP<13>")
	)
	(segment
		(start 217.064336 -192.523364)
		(end 217.451686 -192.683638)
		(width 0.14224)
		(layer "In6.Cu")
		(net "GMI_CPU1_G0_CPU0_G2_TX_DP<13>")
	)
	(segment
		(start 112.390428 -225.062034)
		(end 112.412272 -225.03765)
		(width 0.1143)
		(layer "In6.Cu")
		(net "GMI_CPU1_G0_CPU0_G2_TX_DP<13>")
	)
	(segment
		(start 230.391716 -198.043546)
		(end 230.77932 -198.204074)
		(width 0.14224)
		(layer "In6.Cu")
		(net "GMI_CPU1_G0_CPU0_G2_TX_DP<13>")
	)
	(segment
		(start 112.526318 -224.929446)
		(end 112.601248 -224.870264)
		(width 0.1143)
		(layer "In6.Cu")
		(net "GMI_CPU1_G0_CPU0_G2_TX_DP<13>")
	)
	(segment
		(start 352.683318 -217.114628)
		(end 355.264974 -219.168726)
		(width 0.14224)
		(layer "In6.Cu")
		(net "GMI_CPU1_G0_CPU0_G2_TX_DP<13>")
	)
	(segment
		(start 231.802432 -198.628)
		(end 231.9782 -198.555102)
		(width 0.14224)
		(layer "In6.Cu")
		(net "GMI_CPU1_G0_CPU0_G2_TX_DP<13>")
	)
	(segment
		(start 229.295452 -197.443598)
		(end 229.36835 -197.61962)
		(width 0.14224)
		(layer "In6.Cu")
		(net "GMI_CPU1_G0_CPU0_G2_TX_DP<13>")
	)
	(segment
		(start 215.405208 -191.835786)
		(end 215.580976 -191.762888)
		(width 0.14224)
		(layer "In6.Cu")
		(net "GMI_CPU1_G0_CPU0_G2_TX_DP<13>")
	)
	(segment
		(start 114.847116 -222.30969)
		(end 114.877596 -222.29191)
		(width 0.1143)
		(layer "In6.Cu")
		(net "GMI_CPU1_G0_CPU0_G2_TX_DP<13>")
	)
	(segment
		(start 230.77932 -198.204074)
		(end 230.955088 -198.131176)
		(width 0.14224)
		(layer "In6.Cu")
		(net "GMI_CPU1_G0_CPU0_G2_TX_DP<13>")
	)
	(segment
		(start 216.991438 -192.347088)
		(end 217.064336 -192.523364)
		(width 0.14224)
		(layer "In6.Cu")
		(net "GMI_CPU1_G0_CPU0_G2_TX_DP<13>")
	)
	(segment
		(start 217.451686 -192.683638)
		(end 217.627708 -192.61074)
		(width 0.14224)
		(layer "In6.Cu")
		(net "GMI_CPU1_G0_CPU0_G2_TX_DP<13>")
	)
	(segment
		(start 216.04097 -192.099438)
		(end 216.428574 -192.259712)
		(width 0.14224)
		(layer "In6.Cu")
		(net "GMI_CPU1_G0_CPU0_G2_TX_DP<13>")
	)
	(segment
		(start 115.205764 -221.174564)
		(end 115.205764 -220.192092)
		(width 0.14224)
		(layer "In6.Cu")
		(net "GMI_CPU1_G0_CPU0_G2_TX_DP<13>")
	)
	(segment
		(start 239.587024 -199.154288)
		(end 251.05487 -191.124078)
		(width 0.14224)
		(layer "In6.Cu")
		(net "GMI_CPU1_G0_CPU0_G2_TX_DP<13>")
	)
	(segment
		(start 231.342184 -198.29145)
		(end 231.414828 -198.467726)
		(width 0.14224)
		(layer "In6.Cu")
		(net "GMI_CPU1_G0_CPU0_G2_TX_DP<13>")
	)
	(segment
		(start 356.290118 -221.202758)
		(end 356.335838 -221.248478)
		(width 0.1143)
		(layer "In6.Cu")
		(net "GMI_CPU1_G0_CPU0_G2_TX_DP<13>")
	)
	(segment
		(start 356.335838 -221.248478)
		(end 356.335838 -221.80423)
		(width 0.1143)
		(layer "In6.Cu")
		(net "GMI_CPU1_G0_CPU0_G2_TX_DP<13>")
	)
	(segment
		(start 251.05487 -191.124078)
		(end 262.689086 -189.07252)
		(width 0.14224)
		(layer "In6.Cu")
		(net "GMI_CPU1_G0_CPU0_G2_TX_DP<13>")
	)
	(segment
		(start 361.278678 -238.471964)
		(end 361.305602 -238.487966)
		(width 0.1143)
		(layer "In6.Cu")
		(net "GMI_CPU1_G0_CPU0_G2_TX_DP<13>")
	)
	(segment
		(start 113.933224 -223.914716)
		(end 113.933986 -223.914208)
		(width 0.1143)
		(layer "In6.Cu")
		(net "GMI_CPU1_G0_CPU0_G2_TX_DP<13>")
	)
	(segment
		(start 109.21238 -238.510064)
		(end 109.24413 -238.491776)
		(width 0.1143)
		(layer "In6.Cu")
		(net "GMI_CPU1_G0_CPU0_G2_TX_DP<13>")
	)
	(segment
		(start 113.933986 -223.914208)
		(end 113.937034 -223.91243)
		(width 0.1143)
		(layer "In6.Cu")
		(net "GMI_CPU1_G0_CPU0_G2_TX_DP<13>")
	)
	(segment
		(start 358.310942 -224.797874)
		(end 358.603042 -224.797874)
		(width 0.1143)
		(layer "In6.Cu")
		(net "GMI_CPU1_G0_CPU0_G2_TX_DP<13>")
	)
	(segment
		(start 143.118078 -201.20991)
		(end 143.118332 -201.20991)
		(width 0.14224)
		(layer "In6.Cu")
		(net "GMI_CPU1_G0_CPU0_G2_TX_DP<13>")
	)
	(segment
		(start 308.430168 -189.451488)
		(end 352.683318 -217.114628)
		(width 0.14224)
		(layer "In6.Cu")
		(net "GMI_CPU1_G0_CPU0_G2_TX_DP<13>")
	)
	(segment
		(start 214.944706 -191.499236)
		(end 215.017604 -191.675512)
		(width 0.14224)
		(layer "In6.Cu")
		(net "GMI_CPU1_G0_CPU0_G2_TX_DP<13>")
	)
	(segment
		(start 357.558086 -223.911668)
		(end 357.558848 -223.912176)
		(width 0.1143)
		(layer "In6.Cu")
		(net "GMI_CPU1_G0_CPU0_G2_TX_DP<13>")
	)
	(segment
		(start 115.205764 -221.203012)
		(end 115.205764 -221.174564)
		(width 0.1143)
		(layer "In6.Cu")
		(net "GMI_CPU1_G0_CPU0_G2_TX_DP<13>")
	)
	(segment
		(start 216.604342 -192.186814)
		(end 216.991438 -192.347088)
		(width 0.14224)
		(layer "In6.Cu")
		(net "GMI_CPU1_G0_CPU0_G2_TX_DP<13>")
	)
	(segment
		(start 229.755954 -197.780148)
		(end 229.931722 -197.70725)
		(width 0.14224)
		(layer "In6.Cu")
		(net "GMI_CPU1_G0_CPU0_G2_TX_DP<13>")
	)
	(segment
		(start 357.556562 -223.910906)
		(end 357.558086 -223.911668)
		(width 0.1143)
		(layer "In6.Cu")
		(net "GMI_CPU1_G0_CPU0_G2_TX_DP<13>")
	)
	(segment
		(start 358.815132 -224.85477)
		(end 358.92105 -224.915984)
		(width 0.1143)
		(layer "In6.Cu")
		(net "GMI_CPU1_G0_CPU0_G2_TX_DP<13>")
	)
	(segment
		(start 362.36275 -238.814102)
		(end 362.064808 -238.814102)
		(width 0.1143)
		(layer "In6.Cu")
		(net "GMI_CPU1_G0_CPU0_G2_TX_DP<13>")
	)
	(segment
		(start 229.36835 -197.61962)
		(end 229.755954 -197.780148)
		(width 0.14224)
		(layer "In6.Cu")
		(net "GMI_CPU1_G0_CPU0_G2_TX_DP<13>")
	)
	(segment
		(start 213.92134 -191.07531)
		(end 213.994238 -191.251586)
		(width 0.14224)
		(layer "In6.Cu")
		(net "GMI_CPU1_G0_CPU0_G2_TX_DP<13>")
	)
	(segment
		(start 143.118078 -201.210164)
		(end 143.118078 -201.20991)
		(width 0.14224)
		(layer "In6.Cu")
		(net "GMI_CPU1_G0_CPU0_G2_TX_DP<13>")
	)
	(segment
		(start 356.57917 -222.268796)
		(end 356.648766 -222.309436)
		(width 0.1143)
		(layer "In6.Cu")
		(net "GMI_CPU1_G0_CPU0_G2_TX_DP<13>")
	)
	(segment
		(start 357.563928 -223.91497)
		(end 357.56469 -223.915478)
		(width 0.1143)
		(layer "In6.Cu")
		(net "GMI_CPU1_G0_CPU0_G2_TX_DP<13>")
	)
	(segment
		(start 355.264974 -219.168726)
		(end 356.290118 -220.19387)
		(width 0.14224)
		(layer "In6.Cu")
		(net "GMI_CPU1_G0_CPU0_G2_TX_DP<13>")
	)
	(segment
		(start 111.170974 -236.992668)
		(end 111.170974 -228.051106)
		(width 0.1143)
		(layer "In6.Cu")
		(net "GMI_CPU1_G0_CPU0_G2_TX_DP<13>")
	)
	(segment
		(start 112.36833 -225.086926)
		(end 112.368584 -225.086672)
		(width 0.1143)
		(layer "In6.Cu")
		(net "GMI_CPU1_G0_CPU0_G2_TX_DP<13>")
	)
	(segment
		(start 361.306364 -238.488474)
		(end 361.308904 -238.489744)
		(width 0.1143)
		(layer "In6.Cu")
		(net "GMI_CPU1_G0_CPU0_G2_TX_DP<13>")
	)
	(segment
		(start 114.877596 -222.29191)
		(end 114.916712 -222.26905)
		(width 0.1143)
		(layer "In6.Cu")
		(net "GMI_CPU1_G0_CPU0_G2_TX_DP<13>")
	)
	(segment
		(start 162.588448 -189.478158)
		(end 206.994252 -189.28969)
		(width 0.14224)
		(layer "In6.Cu")
		(net "GMI_CPU1_G0_CPU0_G2_TX_DP<13>")
	)
	(segment
		(start 357.989124 -224.698814)
		(end 358.027224 -224.721166)
		(width 0.1143)
		(layer "In6.Cu")
		(net "GMI_CPU1_G0_CPU0_G2_TX_DP<13>")
	)
	(segment
		(start 360.8959 -238.089186)
		(end 361.278678 -238.471964)
		(width 0.1143)
		(layer "In6.Cu")
		(net "GMI_CPU1_G0_CPU0_G2_TX_DP<13>")
	)
	(segment
		(start 118.174516 -217.22334)
		(end 123.647708 -212.941916)
		(width 0.14224)
		(layer "In6.Cu")
		(net "GMI_CPU1_G0_CPU0_G2_TX_DP<13>")
	)
	(segment
		(start 216.428574 -192.259712)
		(end 216.604342 -192.186814)
		(width 0.14224)
		(layer "In6.Cu")
		(net "GMI_CPU1_G0_CPU0_G2_TX_DP<13>")
	)
	(segment
		(start 113.90884 -223.928686)
		(end 113.933224 -223.914716)
		(width 0.1143)
		(layer "In6.Cu")
		(net "GMI_CPU1_G0_CPU0_G2_TX_DP<13>")
	)
	(segment
		(start 217.627708 -192.61074)
		(end 229.295452 -197.443598)
		(width 0.14224)
		(layer "In6.Cu")
		(net "GMI_CPU1_G0_CPU0_G2_TX_DP<13>")
	)
	(segment
		(start 230.318818 -197.867524)
		(end 230.391716 -198.043546)
		(width 0.14224)
		(layer "In6.Cu")
		(net "GMI_CPU1_G0_CPU0_G2_TX_DP<13>")
	)
	(segment
		(start 110.263432 -238.42599)
		(end 110.911132 -237.77829)
		(width 0.1143)
		(layer "In6.Cu")
		(net "GMI_CPU1_G0_CPU0_G2_TX_DP<13>")
	)
	(segment
		(start 357.562404 -223.914208)
		(end 357.563928 -223.91497)
		(width 0.1143)
		(layer "In6.Cu")
		(net "GMI_CPU1_G0_CPU0_G2_TX_DP<13>")
	)
	(segment
		(start 357.561642 -223.9137)
		(end 357.562404 -223.914208)
		(width 0.1143)
		(layer "In6.Cu")
		(net "GMI_CPU1_G0_CPU0_G2_TX_DP<13>")
	)
	(segment
		(start 357.56469 -223.915478)
		(end 357.565706 -223.915986)
		(width 0.1143)
		(layer "In6.Cu")
		(net "GMI_CPU1_G0_CPU0_G2_TX_DP<13>")
	)
	(segment
		(start 303.7332 -189.451488)
		(end 308.430168 -189.451488)
		(width 0.14224)
		(layer "In6.Cu")
		(net "GMI_CPU1_G0_CPU0_G2_TX_DP<13>")
	)
	(segment
		(start 109.133132 -238.814356)
		(end 109.063282 -238.744506)
		(width 0.1143)
		(layer "In6.Cu")
		(net "GMI_CPU1_G0_CPU0_G2_TX_DP<13>")
	)
	(segment
		(start 115.160044 -221.804484)
		(end 115.160044 -221.248732)
		(width 0.1143)
		(layer "In6.Cu")
		(net "GMI_CPU1_G0_CPU0_G2_TX_DP<13>")
	)
	(segment
		(start 357.521764 -223.890586)
		(end 357.556562 -223.910906)
		(width 0.1143)
		(layer "In6.Cu")
		(net "GMI_CPU1_G0_CPU0_G2_TX_DP<13>")
	)
	(segment
		(start 114.407696 -223.101916)
		(end 114.408712 -223.101408)
		(width 0.1143)
		(layer "In6.Cu")
		(net "GMI_CPU1_G0_CPU0_G2_TX_DP<13>")
	)
	(segment
		(start 112.167162 -225.339402)
		(end 112.168432 -225.337116)
		(width 0.1143)
		(layer "In6.Cu")
		(net "GMI_CPU1_G0_CPU0_G2_TX_DP<13>")
	)
	(segment
		(start 112.802924 -224.797874)
		(end 113.183924 -224.797874)
		(width 0.1143)
		(layer "In6.Cu")
		(net "GMI_CPU1_G0_CPU0_G2_TX_DP<13>")
	)
	(segment
		(start 362.251752 -238.491522)
		(end 362.283502 -238.50981)
		(width 0.1143)
		(layer "In6.Cu")
		(net "GMI_CPU1_G0_CPU0_G2_TX_DP<13>")
	)
	(segment
		(start 212.758782 -190.593726)
		(end 212.831426 -190.770002)
		(width 0.14224)
		(layer "In6.Cu")
		(net "GMI_CPU1_G0_CPU0_G2_TX_DP<13>")
	)
	(segment
		(start 112.68202 -224.822766)
		(end 112.682274 -224.822512)
		(width 0.1143)
		(layer "In6.Cu")
		(net "GMI_CPU1_G0_CPU0_G2_TX_DP<13>")
	)
	(segment
		(start 215.968072 -191.923162)
		(end 216.04097 -192.099438)
		(width 0.14224)
		(layer "In6.Cu")
		(net "GMI_CPU1_G0_CPU0_G2_TX_DP<13>")
	)
	(segment
		(start 214.55761 -191.338962)
		(end 214.944706 -191.499236)
		(width 0.14224)
		(layer "In6.Cu")
		(net "GMI_CPU1_G0_CPU0_G2_TX_DP<13>")
	)
	(segment
		(start 356.290118 -220.19387)
		(end 356.290118 -221.17431)
		(width 0.14224)
		(layer "In6.Cu")
		(net "GMI_CPU1_G0_CPU0_G2_TX_DP<13>")
	)
	(segment
		(start 112.368584 -225.086672)
		(end 112.389666 -225.06305)
		(width 0.1143)
		(layer "In6.Cu")
		(net "GMI_CPU1_G0_CPU0_G2_TX_DP<13>")
	)
	(segment
		(start 215.580976 -191.762888)
		(end 215.968072 -191.923162)
		(width 0.14224)
		(layer "In6.Cu")
		(net "GMI_CPU1_G0_CPU0_G2_TX_DP<13>")
	)
	(segment
		(start 236.278928 -199.737726)
		(end 239.587024 -199.154288)
		(width 0.14224)
		(layer "In6.Cu")
		(net "GMI_CPU1_G0_CPU0_G2_TX_DP<13>")
	)
	(segment
		(start 231.414828 -198.467726)
		(end 231.802432 -198.628)
		(width 0.14224)
		(layer "In6.Cu")
		(net "GMI_CPU1_G0_CPU0_G2_TX_DP<13>")
	)
	(segment
		(start 360.350054 -228.109526)
		(end 360.350054 -236.771688)
		(width 0.1143)
		(layer "In6.Cu")
		(net "GMI_CPU1_G0_CPU0_G2_TX_DP<13>")
	)
	(segment
		(start 112.677194 -224.824544)
		(end 112.68202 -224.822766)
		(width 0.1143)
		(layer "In6.Cu")
		(net "GMI_CPU1_G0_CPU0_G2_TX_DP<13>")
	)
	(segment
		(start 112.390428 -225.062288)
		(end 112.390428 -225.062034)
		(width 0.1143)
		(layer "In6.Cu")
		(net "GMI_CPU1_G0_CPU0_G2_TX_DP<13>")
	)
	(segment
		(start 229.931722 -197.70725)
		(end 230.318818 -197.867524)
		(width 0.14224)
		(layer "In6.Cu")
		(net "GMI_CPU1_G0_CPU0_G2_TX_DP<13>")
	)
	(segment
		(start 357.558848 -223.912176)
		(end 357.561642 -223.9137)
		(width 0.1143)
		(layer "In6.Cu")
		(net "GMI_CPU1_G0_CPU0_G2_TX_DP<13>")
	)
	(segment
		(start 111.240316 -227.740718)
		(end 112.092232 -225.479102)
		(width 0.1143)
		(layer "In6.Cu")
		(net "GMI_CPU1_G0_CPU0_G2_TX_DP<13>")
	)
	(segment
		(start 114.406934 -223.102424)
		(end 114.407696 -223.101916)
		(width 0.1143)
		(layer "In6.Cu")
		(net "GMI_CPU1_G0_CPU0_G2_TX_DP<13>")
	)
	(segment
		(start 357.088948 -223.10217)
		(end 357.11892 -223.119442)
		(width 0.1143)
		(layer "In6.Cu")
		(net "GMI_CPU1_G0_CPU0_G2_TX_DP<13>")
	)
	(segment
		(start 113.937034 -223.91243)
		(end 113.937796 -223.911922)
		(width 0.1143)
		(layer "In6.Cu")
		(net "GMI_CPU1_G0_CPU0_G2_TX_DP<13>")
	)
	(segment
		(start 357.085646 -223.100138)
		(end 357.08717 -223.101154)
		(width 0.1143)
		(layer "In6.Cu")
		(net "GMI_CPU1_G0_CPU0_G2_TX_DP<13>")
	)
	(segment
		(start 213.994238 -191.251586)
		(end 214.381842 -191.41186)
		(width 0.14224)
		(layer "In6.Cu")
		(net "GMI_CPU1_G0_CPU0_G2_TX_DP<13>")
	)
	(segment
		(start 215.017604 -191.675512)
		(end 215.405208 -191.835786)
		(width 0.14224)
		(layer "In6.Cu")
		(net "GMI_CPU1_G0_CPU0_G2_TX_DP<13>")
	)
	(segment
		(start 213.394798 -190.857378)
		(end 213.92134 -191.07531)
		(width 0.14224)
		(layer "In6.Cu")
		(net "GMI_CPU1_G0_CPU0_G2_TX_DP<13>")
	)
	(arc
		(start 359.570782 -225.58375)
		(mid 360.150784 -226.787902)
		(end 360.350054 -228.109526)
		(width 0.1143)
		(layer "In6.Cu")
		(net "GMI_CPU1_G0_CPU0_G2_TX_DP<13>")
	)
	(arc
		(start 358.603042 -224.797874)
		(mid 358.712835 -224.812347)
		(end 358.815132 -224.85477)
		(width 0.1143)
		(layer "In6.Cu")
		(net "GMI_CPU1_G0_CPU0_G2_TX_DP<13>")
	)
	(arc
		(start 359.014014 -224.982786)
		(mid 359.102349 -225.061749)
		(end 359.188766 -225.142806)
		(width 0.1143)
		(layer "In6.Cu")
		(net "GMI_CPU1_G0_CPU0_G2_TX_DP<13>")
	)
	(arc
		(start 113.75009 -224.232724)
		(mid 113.783558 -224.080787)
		(end 113.876328 -223.955864)
		(width 0.1143)
		(layer "In6.Cu")
		(net "GMI_CPU1_G0_CPU0_G2_TX_DP<13>")
	)
	(arc
		(start 110.08741 -238.53648)
		(mid 110.181634 -238.491136)
		(end 110.263432 -238.42599)
		(width 0.1143)
		(layer "In6.Cu")
		(net "GMI_CPU1_G0_CPU0_G2_TX_DP<13>")
	)
	(arc
		(start 112.092232 -225.479102)
		(mid 112.125163 -225.40682)
		(end 112.167162 -225.339402)
		(width 0.1143)
		(layer "In6.Cu")
		(net "GMI_CPU1_G0_CPU0_G2_TX_DP<13>")
	)
	(arc
		(start 113.183924 -224.797874)
		(mid 113.184178 -224.797874)
		(end 113.184432 -224.797874)
		(width 0.1143)
		(layer "In6.Cu")
		(net "GMI_CPU1_G0_CPU0_G2_TX_DP<13>")
	)
	(arc
		(start 358.92105 -224.915984)
		(mid 358.969153 -224.947129)
		(end 359.014014 -224.982786)
		(width 0.1143)
		(layer "In6.Cu")
		(net "GMI_CPU1_G0_CPU0_G2_TX_DP<13>")
	)
	(arc
		(start 356.805738 -222.614236)
		(mid 356.870253 -222.876455)
		(end 357.04907 -223.078802)
		(width 0.1143)
		(layer "In6.Cu")
		(net "GMI_CPU1_G0_CPU0_G2_TX_DP<13>")
	)
	(arc
		(start 109.24413 -238.491776)
		(mid 109.431074 -238.441521)
		(end 109.618018 -238.491776)
		(width 0.1143)
		(layer "In6.Cu")
		(net "GMI_CPU1_G0_CPU0_G2_TX_DP<13>")
	)
	(arc
		(start 109.063282 -238.744506)
		(mid 109.115331 -238.612987)
		(end 109.21238 -238.510064)
		(width 0.1143)
		(layer "In6.Cu")
		(net "GMI_CPU1_G0_CPU0_G2_TX_DP<13>")
	)
	(arc
		(start 362.283502 -238.50981)
		(mid 362.380637 -238.612679)
		(end 362.4326 -238.744252)
		(width 0.1143)
		(layer "In6.Cu")
		(net "GMI_CPU1_G0_CPU0_G2_TX_DP<13>")
	)
	(arc
		(start 112.601248 -224.870264)
		(mid 112.637744 -224.844951)
		(end 112.677194 -224.824544)
		(width 0.1143)
		(layer "In6.Cu")
		(net "GMI_CPU1_G0_CPU0_G2_TX_DP<13>")
	)
	(arc
		(start 113.974118 -223.89084)
		(mid 113.990087 -223.878803)
		(end 114.005614 -223.866202)
		(width 0.1143)
		(layer "In6.Cu")
		(net "GMI_CPU1_G0_CPU0_G2_TX_DP<13>")
	)
	(arc
		(start 356.335838 -221.80423)
		(mid 356.400353 -222.066449)
		(end 356.57917 -222.268796)
		(width 0.1143)
		(layer "In6.Cu")
		(net "GMI_CPU1_G0_CPU0_G2_TX_DP<13>")
	)
	(arc
		(start 357.275892 -223.413066)
		(mid 357.278271 -223.450569)
		(end 357.283766 -223.487742)
		(width 0.1143)
		(layer "In6.Cu")
		(net "GMI_CPU1_G0_CPU0_G2_TX_DP<13>")
	)
	(arc
		(start 357.589836 -223.929956)
		(mid 357.704512 -224.06329)
		(end 357.745792 -224.234248)
		(width 0.1143)
		(layer "In6.Cu")
		(net "GMI_CPU1_G0_CPU0_G2_TX_DP<13>")
	)
	(arc
		(start 113.184432 -224.797874)
		(mid 113.583419 -224.631563)
		(end 113.75009 -224.232724)
		(width 0.1143)
		(layer "In6.Cu")
		(net "GMI_CPU1_G0_CPU0_G2_TX_DP<13>")
	)
	(arc
		(start 361.311952 -238.491522)
		(mid 361.594908 -238.567699)
		(end 361.877864 -238.491522)
		(width 0.1143)
		(layer "In6.Cu")
		(net "GMI_CPU1_G0_CPU0_G2_TX_DP<13>")
	)
	(arc
		(start 357.490268 -223.865948)
		(mid 357.5058 -223.878543)
		(end 357.521764 -223.890586)
		(width 0.1143)
		(layer "In6.Cu")
		(net "GMI_CPU1_G0_CPU0_G2_TX_DP<13>")
	)
	(arc
		(start 114.690144 -222.61449)
		(mid 114.731693 -222.443068)
		(end 114.847116 -222.30969)
		(width 0.1143)
		(layer "In6.Cu")
		(net "GMI_CPU1_G0_CPU0_G2_TX_DP<13>")
	)
	(arc
		(start 357.11892 -223.119442)
		(mid 357.231767 -223.247875)
		(end 357.275892 -223.413066)
		(width 0.1143)
		(layer "In6.Cu")
		(net "GMI_CPU1_G0_CPU0_G2_TX_DP<13>")
	)
	(arc
		(start 112.168432 -225.337116)
		(mid 112.264982 -225.209305)
		(end 112.36833 -225.086926)
		(width 0.1143)
		(layer "In6.Cu")
		(net "GMI_CPU1_G0_CPU0_G2_TX_DP<13>")
	)
	(arc
		(start 112.682274 -224.822512)
		(mid 112.74136 -224.804112)
		(end 112.802924 -224.797874)
		(width 0.1143)
		(layer "In6.Cu")
		(net "GMI_CPU1_G0_CPU0_G2_TX_DP<13>")
	)
	(arc
		(start 359.188766 -225.142806)
		(mid 359.229043 -225.183475)
		(end 359.267506 -225.225864)
		(width 0.1143)
		(layer "In6.Cu")
		(net "GMI_CPU1_G0_CPU0_G2_TX_DP<13>")
	)
	(arc
		(start 109.618018 -238.491776)
		(mid 109.847814 -238.565544)
		(end 110.08741 -238.53648)
		(width 0.1143)
		(layer "In6.Cu")
		(net "GMI_CPU1_G0_CPU0_G2_TX_DP<13>")
	)
	(arc
		(start 114.21999 -223.41332)
		(mid 114.264054 -223.248097)
		(end 114.376962 -223.119696)
		(width 0.1143)
		(layer "In6.Cu")
		(net "GMI_CPU1_G0_CPU0_G2_TX_DP<13>")
	)
	(arc
		(start 356.648766 -222.309436)
		(mid 356.764193 -222.442812)
		(end 356.805738 -222.614236)
		(width 0.1143)
		(layer "In6.Cu")
		(net "GMI_CPU1_G0_CPU0_G2_TX_DP<13>")
	)
	(arc
		(start 360.350054 -236.771688)
		(mid 360.491961 -237.484719)
		(end 360.8959 -238.089186)
		(width 0.1143)
		(layer "In6.Cu")
		(net "GMI_CPU1_G0_CPU0_G2_TX_DP<13>")
	)
	(arc
		(start 357.283766 -223.487742)
		(mid 357.357884 -223.692748)
		(end 357.490268 -223.865948)
		(width 0.1143)
		(layer "In6.Cu")
		(net "GMI_CPU1_G0_CPU0_G2_TX_DP<13>")
	)
	(arc
		(start 357.745792 -224.234248)
		(mid 357.810307 -224.496467)
		(end 357.989124 -224.698814)
		(width 0.1143)
		(layer "In6.Cu")
		(net "GMI_CPU1_G0_CPU0_G2_TX_DP<13>")
	)
	(arc
		(start 110.911132 -237.77829)
		(mid 111.018795 -237.641685)
		(end 111.09198 -237.483904)
		(width 0.1143)
		(layer "In6.Cu")
		(net "GMI_CPU1_G0_CPU0_G2_TX_DP<13>")
	)
	(arc
		(start 359.500678 -225.493326)
		(mid 359.537076 -225.537494)
		(end 359.570782 -225.58375)
		(width 0.1143)
		(layer "In6.Cu")
		(net "GMI_CPU1_G0_CPU0_G2_TX_DP<13>")
	)
	(arc
		(start 114.446812 -223.079056)
		(mid 114.625625 -222.876706)
		(end 114.690144 -222.61449)
		(width 0.1143)
		(layer "In6.Cu")
		(net "GMI_CPU1_G0_CPU0_G2_TX_DP<13>")
	)
	(arc
		(start 111.182912 -227.93706)
		(mid 111.207978 -227.837826)
		(end 111.240316 -227.740718)
		(width 0.1143)
		(layer "In6.Cu")
		(net "GMI_CPU1_G0_CPU0_G2_TX_DP<13>")
	)
	(arc
		(start 114.005614 -223.866202)
		(mid 114.138032 -223.693021)
		(end 114.212116 -223.487996)
		(width 0.1143)
		(layer "In6.Cu")
		(net "GMI_CPU1_G0_CPU0_G2_TX_DP<13>")
	)
	(arc
		(start 114.916712 -222.26905)
		(mid 115.095525 -222.0667)
		(end 115.160044 -221.804484)
		(width 0.1143)
		(layer "In6.Cu")
		(net "GMI_CPU1_G0_CPU0_G2_TX_DP<13>")
	)
	(arc
		(start 114.212116 -223.487996)
		(mid 114.217595 -223.450821)
		(end 114.21999 -223.41332)
		(width 0.1143)
		(layer "In6.Cu")
		(net "GMI_CPU1_G0_CPU0_G2_TX_DP<13>")
	)
	(arc
		(start 358.02824 -224.721674)
		(mid 358.164558 -224.778441)
		(end 358.310942 -224.797874)
		(width 0.1143)
		(layer "In6.Cu")
		(net "GMI_CPU1_G0_CPU0_G2_TX_DP<13>")
	)
	(arc
		(start 111.09198 -237.483904)
		(mid 111.151089 -237.24144)
		(end 111.170974 -236.992668)
		(width 0.1143)
		(layer "In6.Cu")
		(net "GMI_CPU1_G0_CPU0_G2_TX_DP<13>")
	)
	(arc
		(start 111.170974 -228.051106)
		(mid 111.173952 -227.993896)
		(end 111.182912 -227.937314)
		(width 0.1143)
		(layer "In6.Cu")
		(net "GMI_CPU1_G0_CPU0_G2_TX_DP<13>")
	)
	(arc
		(start 361.877864 -238.491522)
		(mid 362.064808 -238.441267)
		(end 362.251752 -238.491522)
		(width 0.1143)
		(layer "In6.Cu")
		(net "GMI_CPU1_G0_CPU0_G2_TX_DP<13>")
	)
	(arc
		(start 112.412272 -225.03765)
		(mid 112.466956 -224.981082)
		(end 112.526318 -224.929446)
		(width 0.1143)
		(layer "In6.Cu")
		(net "GMI_CPU1_G0_CPU0_G2_TX_DP<13>")
	)
	(segment
		(start 363.947964 -243.13007)
		(end 364.414816 -242.864132)
		(width 0.12954)
		(layer "F.Cu")
		(net "GMI_CPU1_G0_CPU0_G2_TX_DP<12>")
	)
	(segment
		(start 107.547918 -243.130324)
		(end 107.081066 -242.864386)
		(width 0.12954)
		(layer "F.Cu")
		(net "GMI_CPU1_G0_CPU0_G2_TX_DP<12>")
	)
	(segment
		(start 230.830374 -196.915278)
		(end 231.21747 -197.075552)
		(width 0.14224)
		(layer "In6.Cu")
		(net "GMI_CPU1_G0_CPU0_G2_TX_DP<12>")
	)
	(segment
		(start 108.304076 -238.491776)
		(end 108.305092 -238.491268)
		(width 0.1143)
		(layer "In6.Cu")
		(net "GMI_CPU1_G0_CPU0_G2_TX_DP<12>")
	)
	(segment
		(start 108.304076 -240.111788)
		(end 108.305092 -240.11128)
		(width 0.1143)
		(layer "In6.Cu")
		(net "GMI_CPU1_G0_CPU0_G2_TX_DP<12>")
	)
	(segment
		(start 108.308394 -240.109248)
		(end 108.312458 -240.106962)
		(width 0.1143)
		(layer "In6.Cu")
		(net "GMI_CPU1_G0_CPU0_G2_TX_DP<12>")
	)
	(segment
		(start 108.336334 -239.155732)
		(end 108.335572 -239.155224)
		(width 0.1143)
		(layer "In6.Cu")
		(net "GMI_CPU1_G0_CPU0_G2_TX_DP<12>")
	)
	(segment
		(start 108.314998 -240.105438)
		(end 108.343192 -240.088928)
		(width 0.1143)
		(layer "In6.Cu")
		(net "GMI_CPU1_G0_CPU0_G2_TX_DP<12>")
	)
	(segment
		(start 108.29544 -240.116868)
		(end 108.296202 -240.11636)
		(width 0.1143)
		(layer "In6.Cu")
		(net "GMI_CPU1_G0_CPU0_G2_TX_DP<12>")
	)
	(segment
		(start 110.15345 -228.789738)
		(end 110.18393 -228.771958)
		(width 0.1143)
		(layer "In6.Cu")
		(net "GMI_CPU1_G0_CPU0_G2_TX_DP<12>")
	)
	(segment
		(start 364.128304 -241.729514)
		(end 364.12932 -241.730022)
		(width 0.1143)
		(layer "In6.Cu")
		(net "GMI_CPU1_G0_CPU0_G2_TX_DP<12>")
	)
	(segment
		(start 213.120986 -189.7253)
		(end 213.296754 -189.652402)
		(width 0.14224)
		(layer "In6.Cu")
		(net "GMI_CPU1_G0_CPU0_G2_TX_DP<12>")
	)
	(segment
		(start 108.744258 -237.699042)
		(end 108.773976 -237.68177)
		(width 0.1143)
		(layer "In6.Cu")
		(net "GMI_CPU1_G0_CPU0_G2_TX_DP<12>")
	)
	(segment
		(start 361.780836 -237.681008)
		(end 361.781852 -237.681516)
		(width 0.1143)
		(layer "In6.Cu")
		(net "GMI_CPU1_G0_CPU0_G2_TX_DP<12>")
	)
	(segment
		(start 361.269534 -233.606848)
		(end 361.342432 -233.649266)
		(width 0.1143)
		(layer "In6.Cu")
		(net "GMI_CPU1_G0_CPU0_G2_TX_DP<12>")
	)
	(segment
		(start 361.742736 -237.658656)
		(end 361.779312 -237.679992)
		(width 0.1143)
		(layer "In6.Cu")
		(net "GMI_CPU1_G0_CPU0_G2_TX_DP<12>")
	)
	(segment
		(start 363.196124 -239.134142)
		(end 363.195362 -239.13465)
		(width 0.1143)
		(layer "In6.Cu")
		(net "GMI_CPU1_G0_CPU0_G2_TX_DP<12>")
	)
	(segment
		(start 361.342432 -232.638854)
		(end 361.342432 -232.6386)
		(width 0.1143)
		(layer "In6.Cu")
		(net "GMI_CPU1_G0_CPU0_G2_TX_DP<12>")
	)
	(segment
		(start 357.23068 -221.17431)
		(end 357.23068 -221.202758)
		(width 0.1143)
		(layer "In6.Cu")
		(net "GMI_CPU1_G0_CPU0_G2_TX_DP<12>")
	)
	(segment
		(start 363.19079 -238.491014)
		(end 363.191806 -238.491522)
		(width 0.1143)
		(layer "In6.Cu")
		(net "GMI_CPU1_G0_CPU0_G2_TX_DP<12>")
	)
	(segment
		(start 363.19841 -239.132872)
		(end 363.197648 -239.13338)
		(width 0.1143)
		(layer "In6.Cu")
		(net "GMI_CPU1_G0_CPU0_G2_TX_DP<12>")
	)
	(segment
		(start 108.303314 -240.112296)
		(end 108.304076 -240.111788)
		(width 0.1143)
		(layer "In6.Cu")
		(net "GMI_CPU1_G0_CPU0_G2_TX_DP<12>")
	)
	(segment
		(start 363.180884 -240.105184)
		(end 363.1819 -240.105692)
		(width 0.1143)
		(layer "In6.Cu")
		(net "GMI_CPU1_G0_CPU0_G2_TX_DP<12>")
	)
	(segment
		(start 364.12932 -241.730022)
		(end 364.130844 -241.731038)
		(width 0.1143)
		(layer "In6.Cu")
		(net "GMI_CPU1_G0_CPU0_G2_TX_DP<12>")
	)
	(segment
		(start 363.183424 -238.486696)
		(end 363.187488 -238.488982)
		(width 0.1143)
		(layer "In6.Cu")
		(net "GMI_CPU1_G0_CPU0_G2_TX_DP<12>")
	)
	(segment
		(start 363.192568 -239.136174)
		(end 363.191806 -239.136682)
		(width 0.1143)
		(layer "In6.Cu")
		(net "GMI_CPU1_G0_CPU0_G2_TX_DP<12>")
	)
	(segment
		(start 107.372404 -241.726974)
		(end 107.373928 -241.725958)
		(width 0.1143)
		(layer "In6.Cu")
		(net "GMI_CPU1_G0_CPU0_G2_TX_DP<12>")
	)
	(segment
		(start 231.21747 -197.075552)
		(end 231.290368 -197.251574)
		(width 0.14224)
		(layer "In6.Cu")
		(net "GMI_CPU1_G0_CPU0_G2_TX_DP<12>")
	)
	(segment
		(start 358.605836 -223.460056)
		(end 358.60609 -223.460056)
		(width 0.1143)
		(layer "In6.Cu")
		(net "GMI_CPU1_G0_CPU0_G2_TX_DP<12>")
	)
	(segment
		(start 108.297726 -240.115598)
		(end 108.302044 -240.113058)
		(width 0.1143)
		(layer "In6.Cu")
		(net "GMI_CPU1_G0_CPU0_G2_TX_DP<12>")
	)
	(segment
		(start 229.63124 -196.56425)
		(end 229.807008 -196.491352)
		(width 0.14224)
		(layer "In6.Cu")
		(net "GMI_CPU1_G0_CPU0_G2_TX_DP<12>")
	)
	(segment
		(start 355.844348 -218.420188)
		(end 357.23068 -219.80652)
		(width 0.14224)
		(layer "In6.Cu")
		(net "GMI_CPU1_G0_CPU0_G2_TX_DP<12>")
	)
	(segment
		(start 109.715046 -237.681262)
		(end 109.71657 -237.680246)
		(width 0.1143)
		(layer "In6.Cu")
		(net "GMI_CPU1_G0_CPU0_G2_TX_DP<12>")
	)
	(segment
		(start 114.21999 -221.62389)
		(end 114.219482 -221.623382)
		(width 0.1143)
		(layer "In6.Cu")
		(net "GMI_CPU1_G0_CPU0_G2_TX_DP<12>")
	)
	(segment
		(start 363.159548 -239.155478)
		(end 363.15269 -239.159542)
		(width 0.1143)
		(layer "In6.Cu")
		(net "GMI_CPU1_G0_CPU0_G2_TX_DP<12>")
	)
	(segment
		(start 110.226348 -232.681526)
		(end 110.15345 -232.638854)
		(width 0.1143)
		(layer "In6.Cu")
		(net "GMI_CPU1_G0_CPU0_G2_TX_DP<12>")
	)
	(segment
		(start 108.308394 -238.489236)
		(end 108.312458 -238.48695)
		(width 0.1143)
		(layer "In6.Cu")
		(net "GMI_CPU1_G0_CPU0_G2_TX_DP<12>")
	)
	(segment
		(start 108.296202 -239.132364)
		(end 108.293662 -239.131094)
		(width 0.1143)
		(layer "In6.Cu")
		(net "GMI_CPU1_G0_CPU0_G2_TX_DP<12>")
	)
	(segment
		(start 362.347764 -237.681516)
		(end 362.356146 -237.67669)
		(width 0.1143)
		(layer "In6.Cu")
		(net "GMI_CPU1_G0_CPU0_G2_TX_DP<12>")
	)
	(segment
		(start 110.223046 -229.439724)
		(end 110.221014 -229.4382)
		(width 0.1143)
		(layer "In6.Cu")
		(net "GMI_CPU1_G0_CPU0_G2_TX_DP<12>")
	)
	(segment
		(start 113.937542 -222.29191)
		(end 113.976658 -222.26905)
		(width 0.1143)
		(layer "In6.Cu")
		(net "GMI_CPU1_G0_CPU0_G2_TX_DP<12>")
	)
	(segment
		(start 107.365038 -241.731292)
		(end 107.366562 -241.730276)
		(width 0.1143)
		(layer "In6.Cu")
		(net "GMI_CPU1_G0_CPU0_G2_TX_DP<12>")
	)
	(segment
		(start 109.71657 -237.680246)
		(end 109.753146 -237.65891)
		(width 0.1143)
		(layer "In6.Cu")
		(net "GMI_CPU1_G0_CPU0_G2_TX_DP<12>")
	)
	(segment
		(start 110.18393 -236.871764)
		(end 110.220252 -236.850682)
		(width 0.1143)
		(layer "In6.Cu")
		(net "GMI_CPU1_G0_CPU0_G2_TX_DP<12>")
	)
	(segment
		(start 363.192568 -238.49203)
		(end 363.193838 -238.492792)
		(width 0.1143)
		(layer "In6.Cu")
		(net "GMI_CPU1_G0_CPU0_G2_TX_DP<12>")
	)
	(segment
		(start 214.19693 -190.17107)
		(end 214.372698 -190.098172)
		(width 0.14224)
		(layer "In6.Cu")
		(net "GMI_CPU1_G0_CPU0_G2_TX_DP<12>")
	)
	(segment
		(start 361.259628 -233.599482)
		(end 361.269534 -233.606848)
		(width 0.1143)
		(layer "In6.Cu")
		(net "GMI_CPU1_G0_CPU0_G2_TX_DP<12>")
	)
	(segment
		(start 214.832692 -190.434468)
		(end 215.220042 -190.594996)
		(width 0.14224)
		(layer "In6.Cu")
		(net "GMI_CPU1_G0_CPU0_G2_TX_DP<12>")
	)
	(segment
		(start 107.36326 -241.732308)
		(end 107.364022 -241.7318)
		(width 0.1143)
		(layer "In6.Cu")
		(net "GMI_CPU1_G0_CPU0_G2_TX_DP<12>")
	)
	(segment
		(start 213.296754 -189.652402)
		(end 213.736428 -189.83452)
		(width 0.14224)
		(layer "In6.Cu")
		(net "GMI_CPU1_G0_CPU0_G2_TX_DP<12>")
	)
	(segment
		(start 110.223046 -231.059736)
		(end 110.18393 -231.036876)
		(width 0.1143)
		(layer "In6.Cu")
		(net "GMI_CPU1_G0_CPU0_G2_TX_DP<12>")
	)
	(segment
		(start 114.265202 -221.174564)
		(end 114.265202 -219.813124)
		(width 0.14224)
		(layer "In6.Cu")
		(net "GMI_CPU1_G0_CPU0_G2_TX_DP<12>")
	)
	(segment
		(start 364.565438 -242.52047)
		(end 364.63351 -242.55984)
		(width 0.1143)
		(layer "In6.Cu")
		(net "GMI_CPU1_G0_CPU0_G2_TX_DP<12>")
	)
	(segment
		(start 112.078262 -224.24136)
		(end 112.07877 -224.240852)
		(width 0.1143)
		(layer "In6.Cu")
		(net "GMI_CPU1_G0_CPU0_G2_TX_DP<12>")
	)
	(segment
		(start 363.187488 -240.108994)
		(end 363.18825 -240.109502)
		(width 0.1143)
		(layer "In6.Cu")
		(net "GMI_CPU1_G0_CPU0_G2_TX_DP<12>")
	)
	(segment
		(start 234.259628 -198.335646)
		(end 234.646724 -198.49592)
		(width 0.14224)
		(layer "In6.Cu")
		(net "GMI_CPU1_G0_CPU0_G2_TX_DP<12>")
	)
	(segment
		(start 214.372698 -190.098172)
		(end 214.759794 -190.258446)
		(width 0.14224)
		(layer "In6.Cu")
		(net "GMI_CPU1_G0_CPU0_G2_TX_DP<12>")
	)
	(segment
		(start 360.54411 -225.870516)
		(end 360.54411 -225.87077)
		(width 0.1143)
		(layer "In6.Cu")
		(net "GMI_CPU1_G0_CPU0_G2_TX_DP<12>")
	)
	(segment
		(start 363.187488 -238.488982)
		(end 363.18825 -238.48949)
		(width 0.1143)
		(layer "In6.Cu")
		(net "GMI_CPU1_G0_CPU0_G2_TX_DP<12>")
	)
	(segment
		(start 232.240836 -197.499478)
		(end 232.313734 -197.6755)
		(width 0.14224)
		(layer "In6.Cu")
		(net "GMI_CPU1_G0_CPU0_G2_TX_DP<12>")
	)
	(segment
		(start 363.18825 -238.48949)
		(end 363.189266 -238.489998)
		(width 0.1143)
		(layer "In6.Cu")
		(net "GMI_CPU1_G0_CPU0_G2_TX_DP<12>")
	)
	(segment
		(start 357.989124 -223.078802)
		(end 358.466136 -223.355408)
		(width 0.1143)
		(layer "In6.Cu")
		(net "GMI_CPU1_G0_CPU0_G2_TX_DP<12>")
	)
	(segment
		(start 308.680866 -188.483748)
		(end 352.57105 -215.820498)
		(width 0.14224)
		(layer "In6.Cu")
		(net "GMI_CPU1_G0_CPU0_G2_TX_DP<12>")
	)
	(segment
		(start 123.15063 -212.143848)
		(end 142.73149 -200.345294)
		(width 0.14224)
		(layer "In6.Cu")
		(net "GMI_CPU1_G0_CPU0_G2_TX_DP<12>")
	)
	(segment
		(start 363.193838 -238.492792)
		(end 363.223556 -238.50981)
		(width 0.1143)
		(layer "In6.Cu")
		(net "GMI_CPU1_G0_CPU0_G2_TX_DP<12>")
	)
	(segment
		(start 108.303314 -238.492284)
		(end 108.304076 -238.491776)
		(width 0.1143)
		(layer "In6.Cu")
		(net "GMI_CPU1_G0_CPU0_G2_TX_DP<12>")
	)
	(segment
		(start 213.736428 -189.83452)
		(end 213.809326 -190.010542)
		(width 0.14224)
		(layer "In6.Cu")
		(net "GMI_CPU1_G0_CPU0_G2_TX_DP<12>")
	)
	(segment
		(start 361.342432 -234.258612)
		(end 361.269534 -234.301284)
		(width 0.1143)
		(layer "In6.Cu")
		(net "GMI_CPU1_G0_CPU0_G2_TX_DP<12>")
	)
	(segment
		(start 110.236254 -232.688892)
		(end 110.226348 -232.681526)
		(width 0.1143)
		(layer "In6.Cu")
		(net "GMI_CPU1_G0_CPU0_G2_TX_DP<12>")
	)
	(segment
		(start 111.619538 -224.826068)
		(end 111.619792 -224.82556)
		(width 0.1143)
		(layer "In6.Cu")
		(net "GMI_CPU1_G0_CPU0_G2_TX_DP<12>")
	)
	(segment
		(start 107.367578 -241.729768)
		(end 107.36834 -241.72926)
		(width 0.1143)
		(layer "In6.Cu")
		(net "GMI_CPU1_G0_CPU0_G2_TX_DP<12>")
	)
	(segment
		(start 357.23068 -219.80652)
		(end 357.23068 -221.17431)
		(width 0.14224)
		(layer "In6.Cu")
		(net "GMI_CPU1_G0_CPU0_G2_TX_DP<12>")
	)
	(segment
		(start 113.467896 -223.101662)
		(end 113.505234 -223.080072)
		(width 0.1143)
		(layer "In6.Cu")
		(net "GMI_CPU1_G0_CPU0_G2_TX_DP<12>")
	)
	(segment
		(start 363.191806 -240.111534)
		(end 363.192568 -240.112042)
		(width 0.1143)
		(layer "In6.Cu")
		(net "GMI_CPU1_G0_CPU0_G2_TX_DP<12>")
	)
	(segment
		(start 361.344464 -229.397814)
		(end 361.311952 -229.41661)
		(width 0.1143)
		(layer "In6.Cu")
		(net "GMI_CPU1_G0_CPU0_G2_TX_DP<12>")
	)
	(segment
		(start 107.803442 -240.939574)
		(end 107.833922 -240.921794)
		(width 0.1143)
		(layer "In6.Cu")
		(net "GMI_CPU1_G0_CPU0_G2_TX_DP<12>")
	)
	(segment
		(start 233.264202 -197.923404)
		(end 233.3371 -198.099426)
		(width 0.14224)
		(layer "In6.Cu")
		(net "GMI_CPU1_G0_CPU0_G2_TX_DP<12>")
	)
	(segment
		(start 108.306616 -240.110264)
		(end 108.307632 -240.109756)
		(width 0.1143)
		(layer "In6.Cu")
		(net "GMI_CPU1_G0_CPU0_G2_TX_DP<12>")
	)
	(segment
		(start 357.2764 -221.623128)
		(end 357.275892 -221.623636)
		(width 0.1143)
		(layer "In6.Cu")
		(net "GMI_CPU1_G0_CPU0_G2_TX_DP<12>")
	)
	(segment
		(start 363.15269 -238.468662)
		(end 363.180884 -238.485172)
		(width 0.1143)
		(layer "In6.Cu")
		(net "GMI_CPU1_G0_CPU0_G2_TX_DP<12>")
	)
	(segment
		(start 110.15345 -233.64952)
		(end 110.226348 -233.607102)
		(width 0.1143)
		(layer "In6.Cu")
		(net "GMI_CPU1_G0_CPU0_G2_TX_DP<12>")
	)
	(segment
		(start 214.759794 -190.258446)
		(end 214.832692 -190.434468)
		(width 0.14224)
		(layer "In6.Cu")
		(net "GMI_CPU1_G0_CPU0_G2_TX_DP<12>")
	)
	(segment
		(start 108.299758 -239.134396)
		(end 108.298234 -239.133634)
		(width 0.1143)
		(layer "In6.Cu")
		(net "GMI_CPU1_G0_CPU0_G2_TX_DP<12>")
	)
	(segment
		(start 361.311952 -236.87151)
		(end 361.342432 -236.88929)
		(width 0.1143)
		(layer "In6.Cu")
		(net "GMI_CPU1_G0_CPU0_G2_TX_DP<12>")
	)
	(segment
		(start 363.195362 -239.13465)
		(end 363.192568 -239.136174)
		(width 0.1143)
		(layer "In6.Cu")
		(net "GMI_CPU1_G0_CPU0_G2_TX_DP<12>")
	)
	(segment
		(start 108.306616 -238.490252)
		(end 108.307632 -238.489744)
		(width 0.1143)
		(layer "In6.Cu")
		(net "GMI_CPU1_G0_CPU0_G2_TX_DP<12>")
	)
	(segment
		(start 108.307632 -238.489744)
		(end 108.308394 -238.489236)
		(width 0.1143)
		(layer "In6.Cu")
		(net "GMI_CPU1_G0_CPU0_G2_TX_DP<12>")
	)
	(segment
		(start 361.269534 -234.301284)
		(end 361.259628 -234.30865)
		(width 0.1143)
		(layer "In6.Cu")
		(net "GMI_CPU1_G0_CPU0_G2_TX_DP<12>")
	)
	(segment
		(start 360.87177 -226.358704)
		(end 360.873548 -226.359974)
		(width 0.1143)
		(layer "In6.Cu")
		(net "GMI_CPU1_G0_CPU0_G2_TX_DP<12>")
	)
	(segment
		(start 364.092744 -241.708686)
		(end 364.128304 -241.729514)
		(width 0.1143)
		(layer "In6.Cu")
		(net "GMI_CPU1_G0_CPU0_G2_TX_DP<12>")
	)
	(segment
		(start 108.297472 -239.133126)
		(end 108.296202 -239.132364)
		(width 0.1143)
		(layer "In6.Cu")
		(net "GMI_CPU1_G0_CPU0_G2_TX_DP<12>")
	)
	(segment
		(start 360.829098 -226.334066)
		(end 360.87177 -226.358704)
		(width 0.1143)
		(layer "In6.Cu")
		(net "GMI_CPU1_G0_CPU0_G2_TX_DP<12>")
	)
	(segment
		(start 359.704894 -224.59061)
		(end 360.343958 -225.465386)
		(width 0.1143)
		(layer "In6.Cu")
		(net "GMI_CPU1_G0_CPU0_G2_TX_DP<12>")
	)
	(segment
		(start 212.660484 -189.389004)
		(end 212.733382 -189.565026)
		(width 0.14224)
		(layer "In6.Cu")
		(net "GMI_CPU1_G0_CPU0_G2_TX_DP<12>")
	)
	(segment
		(start 362.751624 -237.698788)
		(end 362.752386 -237.699296)
		(width 0.1143)
		(layer "In6.Cu")
		(net "GMI_CPU1_G0_CPU0_G2_TX_DP<12>")
	)
	(segment
		(start 108.307632 -240.109756)
		(end 108.308394 -240.109248)
		(width 0.1143)
		(layer "In6.Cu")
		(net "GMI_CPU1_G0_CPU0_G2_TX_DP<12>")
	)
	(segment
		(start 109.71403 -237.68177)
		(end 109.715046 -237.681262)
		(width 0.1143)
		(layer "In6.Cu")
		(net "GMI_CPU1_G0_CPU0_G2_TX_DP<12>")
	)
	(segment
		(start 360.39425 -225.543364)
		(end 360.453686 -225.647758)
		(width 0.1143)
		(layer "In6.Cu")
		(net "GMI_CPU1_G0_CPU0_G2_TX_DP<12>")
	)
	(segment
		(start 361.272836 -227.128832)
		(end 361.342432 -227.169472)
		(width 0.1143)
		(layer "In6.Cu")
		(net "GMI_CPU1_G0_CPU0_G2_TX_DP<12>")
	)
	(segment
		(start 110.226348 -233.607102)
		(end 110.236254 -233.599736)
		(width 0.1143)
		(layer "In6.Cu")
		(net "GMI_CPU1_G0_CPU0_G2_TX_DP<12>")
	)
	(segment
		(start 363.180884 -238.485172)
		(end 363.1819 -238.48568)
		(width 0.1143)
		(layer "In6.Cu")
		(net "GMI_CPU1_G0_CPU0_G2_TX_DP<12>")
	)
	(segment
		(start 108.305092 -240.11128)
		(end 108.306616 -240.110264)
		(width 0.1143)
		(layer "In6.Cu")
		(net "GMI_CPU1_G0_CPU0_G2_TX_DP<12>")
	)
	(segment
		(start 213.809326 -190.010542)
		(end 214.19693 -190.17107)
		(width 0.14224)
		(layer "In6.Cu")
		(net "GMI_CPU1_G0_CPU0_G2_TX_DP<12>")
	)
	(segment
		(start 363.192568 -240.112042)
		(end 363.193838 -240.112804)
		(width 0.1143)
		(layer "In6.Cu")
		(net "GMI_CPU1_G0_CPU0_G2_TX_DP<12>")
	)
	(segment
		(start 108.343192 -239.159796)
		(end 108.336334 -239.155732)
		(width 0.1143)
		(layer "In6.Cu")
		(net "GMI_CPU1_G0_CPU0_G2_TX_DP<12>")
	)
	(segment
		(start 262.760968 -188.105542)
		(end 303.70526 -188.483748)
		(width 0.14224)
		(layer "In6.Cu")
		(net "GMI_CPU1_G0_CPU0_G2_TX_DP<12>")
	)
	(segment
		(start 107.833922 -240.921794)
		(end 107.873038 -240.898934)
		(width 0.1143)
		(layer "In6.Cu")
		(net "GMI_CPU1_G0_CPU0_G2_TX_DP<12>")
	)
	(segment
		(start 234.259374 -198.3359)
		(end 234.259628 -198.335646)
		(width 0.14224)
		(layer "In6.Cu")
		(net "GMI_CPU1_G0_CPU0_G2_TX_DP<12>")
	)
	(segment
		(start 363.20222 -239.13084)
		(end 363.19968 -239.13211)
		(width 0.1143)
		(layer "In6.Cu")
		(net "GMI_CPU1_G0_CPU0_G2_TX_DP<12>")
	)
	(segment
		(start 212.733382 -189.565026)
		(end 213.120986 -189.7253)
		(width 0.14224)
		(layer "In6.Cu")
		(net "GMI_CPU1_G0_CPU0_G2_TX_DP<12>")
	)
	(segment
		(start 357.23068 -221.202758)
		(end 357.2764 -221.248478)
		(width 0.1143)
		(layer "In6.Cu")
		(net "GMI_CPU1_G0_CPU0_G2_TX_DP<12>")
	)
	(segment
		(start 108.312458 -238.48695)
		(end 108.313982 -238.485934)
		(width 0.1143)
		(layer "In6.Cu")
		(net "GMI_CPU1_G0_CPU0_G2_TX_DP<12>")
	)
	(segment
		(start 361.342432 -234.258866)
		(end 361.342432 -234.258612)
		(width 0.1143)
		(layer "In6.Cu")
		(net "GMI_CPU1_G0_CPU0_G2_TX_DP<12>")
	)
	(segment
		(start 114.21999 -221.804484)
		(end 114.21999 -221.62389)
		(width 0.1143)
		(layer "In6.Cu")
		(net "GMI_CPU1_G0_CPU0_G2_TX_DP<12>")
	)
	(segment
		(start 363.183424 -240.106708)
		(end 363.187488 -240.108994)
		(width 0.1143)
		(layer "In6.Cu")
		(net "GMI_CPU1_G0_CPU0_G2_TX_DP<12>")
	)
	(segment
		(start 361.272836 -231.988614)
		(end 361.343702 -232.03027)
		(width 0.1143)
		(layer "In6.Cu")
		(net "GMI_CPU1_G0_CPU0_G2_TX_DP<12>")
	)
	(segment
		(start 108.296202 -238.496348)
		(end 108.297726 -238.495586)
		(width 0.1143)
		(layer "In6.Cu")
		(net "GMI_CPU1_G0_CPU0_G2_TX_DP<12>")
	)
	(segment
		(start 110.223046 -227.819966)
		(end 110.18393 -227.797106)
		(width 0.1143)
		(layer "In6.Cu")
		(net "GMI_CPU1_G0_CPU0_G2_TX_DP<12>")
	)
	(segment
		(start 364.132368 -241.731546)
		(end 364.161578 -241.748818)
		(width 0.1143)
		(layer "In6.Cu")
		(net "GMI_CPU1_G0_CPU0_G2_TX_DP<12>")
	)
	(segment
		(start 362.721906 -237.681516)
		(end 362.751624 -237.698788)
		(width 0.1143)
		(layer "In6.Cu")
		(net "GMI_CPU1_G0_CPU0_G2_TX_DP<12>")
	)
	(segment
		(start 142.731744 -200.345294)
		(end 162.312096 -188.546994)
		(width 0.14224)
		(layer "In6.Cu")
		(net "GMI_CPU1_G0_CPU0_G2_TX_DP<12>")
	)
	(segment
		(start 110.18393 -231.036876)
		(end 110.151418 -231.01808)
		(width 0.1143)
		(layer "In6.Cu")
		(net "GMI_CPU1_G0_CPU0_G2_TX_DP<12>")
	)
	(segment
		(start 114.265202 -219.813124)
		(end 117.564662 -216.513664)
		(width 0.14224)
		(layer "In6.Cu")
		(net "GMI_CPU1_G0_CPU0_G2_TX_DP<12>")
	)
	(segment
		(start 357.275892 -221.623636)
		(end 357.275892 -221.80423)
		(width 0.1143)
		(layer "In6.Cu")
		(net "GMI_CPU1_G0_CPU0_G2_TX_DP<12>")
	)
	(segment
		(start 361.275376 -230.37038)
		(end 361.342432 -230.409496)
		(width 0.1143)
		(layer "In6.Cu")
		(net "GMI_CPU1_G0_CPU0_G2_TX_DP<12>")
	)
	(segment
		(start 250.68657 -190.234824)
		(end 262.760968 -188.105542)
		(width 0.14224)
		(layer "In6.Cu")
		(net "GMI_CPU1_G0_CPU0_G2_TX_DP<12>")
	)
	(segment
		(start 108.298234 -239.133634)
		(end 108.297472 -239.133126)
		(width 0.1143)
		(layer "In6.Cu")
		(net "GMI_CPU1_G0_CPU0_G2_TX_DP<12>")
	)
	(segment
		(start 108.30052 -239.134904)
		(end 108.299758 -239.134396)
		(width 0.1143)
		(layer "In6.Cu")
		(net "GMI_CPU1_G0_CPU0_G2_TX_DP<12>")
	)
	(segment
		(start 363.19079 -240.111026)
		(end 363.191806 -240.111534)
		(width 0.1143)
		(layer "In6.Cu")
		(net "GMI_CPU1_G0_CPU0_G2_TX_DP<12>")
	)
	(segment
		(start 108.296202 -240.11636)
		(end 108.297726 -240.115598)
		(width 0.1143)
		(layer "In6.Cu")
		(net "GMI_CPU1_G0_CPU0_G2_TX_DP<12>")
	)
	(segment
		(start 229.807008 -196.491352)
		(end 230.194104 -196.651626)
		(width 0.14224)
		(layer "In6.Cu")
		(net "GMI_CPU1_G0_CPU0_G2_TX_DP<12>")
	)
	(segment
		(start 363.18825 -240.109502)
		(end 363.189266 -240.11001)
		(width 0.1143)
		(layer "In6.Cu")
		(net "GMI_CPU1_G0_CPU0_G2_TX_DP<12>")
	)
	(segment
		(start 359.350564 -224.167954)
		(end 359.634028 -224.500948)
		(width 0.1143)
		(layer "In6.Cu")
		(net "GMI_CPU1_G0_CPU0_G2_TX_DP<12>")
	)
	(segment
		(start 361.27563 -236.850428)
		(end 361.311952 -236.87151)
		(width 0.1143)
		(layer "In6.Cu")
		(net "GMI_CPU1_G0_CPU0_G2_TX_DP<12>")
	)
	(segment
		(start 363.191806 -238.491522)
		(end 363.192568 -238.49203)
		(width 0.1143)
		(layer "In6.Cu")
		(net "GMI_CPU1_G0_CPU0_G2_TX_DP<12>")
	)
	(segment
		(start 108.313982 -240.105946)
		(end 108.314998 -240.105438)
		(width 0.1143)
		(layer "In6.Cu")
		(net "GMI_CPU1_G0_CPU0_G2_TX_DP<12>")
	)
	(segment
		(start 110.18393 -229.416864)
		(end 110.151418 -229.398068)
		(width 0.1143)
		(layer "In6.Cu")
		(net "GMI_CPU1_G0_CPU0_G2_TX_DP<12>")
	)
	(segment
		(start 110.15345 -230.40975)
		(end 110.220506 -230.370634)
		(width 0.1143)
		(layer "In6.Cu")
		(net "GMI_CPU1_G0_CPU0_G2_TX_DP<12>")
	)
	(segment
		(start 112.07877 -224.240852)
		(end 112.081564 -224.237296)
		(width 0.1143)
		(layer "In6.Cu")
		(net "GMI_CPU1_G0_CPU0_G2_TX_DP<12>")
	)
	(segment
		(start 108.313982 -238.485934)
		(end 108.314998 -238.485426)
		(width 0.1143)
		(layer "In6.Cu")
		(net "GMI_CPU1_G0_CPU0_G2_TX_DP<12>")
	)
	(segment
		(start 110.18393 -227.797106)
		(end 110.15345 -227.779326)
		(width 0.1143)
		(layer "In6.Cu")
		(net "GMI_CPU1_G0_CPU0_G2_TX_DP<12>")
	)
	(segment
		(start 215.220042 -190.594996)
		(end 215.396064 -190.522098)
		(width 0.14224)
		(layer "In6.Cu")
		(net "GMI_CPU1_G0_CPU0_G2_TX_DP<12>")
	)
	(segment
		(start 110.15345 -227.169726)
		(end 110.18393 -227.151946)
		(width 0.1143)
		(layer "In6.Cu")
		(net "GMI_CPU1_G0_CPU0_G2_TX_DP<12>")
	)
	(segment
		(start 110.236254 -234.308904)
		(end 110.226348 -234.301538)
		(width 0.1143)
		(layer "In6.Cu")
		(net "GMI_CPU1_G0_CPU0_G2_TX_DP<12>")
	)
	(segment
		(start 107.373928 -241.725958)
		(end 107.403138 -241.70894)
		(width 0.1143)
		(layer "In6.Cu")
		(net "GMI_CPU1_G0_CPU0_G2_TX_DP<12>")
	)
	(segment
		(start 110.466124 -236.384338)
		(end 110.466378 -236.384338)
		(width 0.1143)
		(layer "In6.Cu")
		(net "GMI_CPU1_G0_CPU0_G2_TX_DP<12>")
	)
	(segment
		(start 107.33532 -241.748564)
		(end 107.36326 -241.732054)
		(width 0.1143)
		(layer "In6.Cu")
		(net "GMI_CPU1_G0_CPU0_G2_TX_DP<12>")
	)
	(segment
		(start 232.877106 -197.76313)
		(end 233.264202 -197.923404)
		(width 0.14224)
		(layer "In6.Cu")
		(net "GMI_CPU1_G0_CPU0_G2_TX_DP<12>")
	)
	(segment
		(start 108.335572 -239.155224)
		(end 108.304076 -239.136936)
		(width 0.1143)
		(layer "In6.Cu")
		(net "GMI_CPU1_G0_CPU0_G2_TX_DP<12>")
	)
	(segment
		(start 358.60609 -223.460056)
		(end 359.27157 -224.085404)
		(width 0.1143)
		(layer "In6.Cu")
		(net "GMI_CPU1_G0_CPU0_G2_TX_DP<12>")
	)
	(segment
		(start 361.344464 -231.017826)
		(end 361.311952 -231.036622)
		(width 0.1143)
		(layer "In6.Cu")
		(net "GMI_CPU1_G0_CPU0_G2_TX_DP<12>")
	)
	(segment
		(start 110.226348 -234.301538)
		(end 110.15345 -234.258866)
		(width 0.1143)
		(layer "In6.Cu")
		(net "GMI_CPU1_G0_CPU0_G2_TX_DP<12>")
	)
	(segment
		(start 361.342432 -232.6386)
		(end 361.269534 -232.681272)
		(width 0.1143)
		(layer "In6.Cu")
		(net "GMI_CPU1_G0_CPU0_G2_TX_DP<12>")
	)
	(segment
		(start 357.519224 -222.268796)
		(end 357.58882 -222.309436)
		(width 0.1143)
		(layer "In6.Cu")
		(net "GMI_CPU1_G0_CPU0_G2_TX_DP<12>")
	)
	(segment
		(start 112.081564 -224.237296)
		(end 112.08258 -224.23628)
		(width 0.1143)
		(layer "In6.Cu")
		(net "GMI_CPU1_G0_CPU0_G2_TX_DP<12>")
	)
	(segment
		(start 108.743496 -237.69955)
		(end 108.744258 -237.699042)
		(width 0.1143)
		(layer "In6.Cu")
		(net "GMI_CPU1_G0_CPU0_G2_TX_DP<12>")
	)
	(segment
		(start 114.219482 -221.623382)
		(end 114.219482 -221.248732)
		(width 0.1143)
		(layer "In6.Cu")
		(net "GMI_CPU1_G0_CPU0_G2_TX_DP<12>")
	)
	(segment
		(start 352.57105 -215.820498)
		(end 355.844348 -218.420188)
		(width 0.14224)
		(layer "In6.Cu")
		(net "GMI_CPU1_G0_CPU0_G2_TX_DP<12>")
	)
	(segment
		(start 108.272326 -238.510064)
		(end 108.29544 -238.496856)
		(width 0.1143)
		(layer "In6.Cu")
		(net "GMI_CPU1_G0_CPU0_G2_TX_DP<12>")
	)
	(segment
		(start 107.364022 -241.7318)
		(end 107.365038 -241.731292)
		(width 0.1143)
		(layer "In6.Cu")
		(net "GMI_CPU1_G0_CPU0_G2_TX_DP<12>")
	)
	(segment
		(start 230.194104 -196.651626)
		(end 230.267002 -196.827648)
		(width 0.14224)
		(layer "In6.Cu")
		(net "GMI_CPU1_G0_CPU0_G2_TX_DP<12>")
	)
	(segment
		(start 207.113632 -188.356494)
		(end 212.4329 -189.294516)
		(width 0.14224)
		(layer "In6.Cu")
		(net "GMI_CPU1_G0_CPU0_G2_TX_DP<12>")
	)
	(segment
		(start 363.189266 -238.489998)
		(end 363.19079 -238.491014)
		(width 0.1143)
		(layer "In6.Cu")
		(net "GMI_CPU1_G0_CPU0_G2_TX_DP<12>")
	)
	(segment
		(start 363.193838 -240.112804)
		(end 363.223556 -240.129822)
		(width 0.1143)
		(layer "In6.Cu")
		(net "GMI_CPU1_G0_CPU0_G2_TX_DP<12>")
	)
	(segment
		(start 108.304076 -239.136936)
		(end 108.303314 -239.136428)
		(width 0.1143)
		(layer "In6.Cu")
		(net "GMI_CPU1_G0_CPU0_G2_TX_DP<12>")
	)
	(segment
		(start 363.1819 -238.48568)
		(end 363.183424 -238.486696)
		(width 0.1143)
		(layer "In6.Cu")
		(net "GMI_CPU1_G0_CPU0_G2_TX_DP<12>")
	)
	(segment
		(start 361.259628 -235.219494)
		(end 361.269534 -235.22686)
		(width 0.1143)
		(layer "In6.Cu")
		(net "GMI_CPU1_G0_CPU0_G2_TX_DP<12>")
	)
	(segment
		(start 108.305092 -238.491268)
		(end 108.306616 -238.490252)
		(width 0.1143)
		(layer "In6.Cu")
		(net "GMI_CPU1_G0_CPU0_G2_TX_DP<12>")
	)
	(segment
		(start 361.269534 -235.22686)
		(end 361.342432 -235.269278)
		(width 0.1143)
		(layer "In6.Cu")
		(net "GMI_CPU1_G0_CPU0_G2_TX_DP<12>")
	)
	(segment
		(start 236.299756 -198.787004)
		(end 239.204246 -198.27494)
		(width 0.14224)
		(layer "In6.Cu")
		(net "GMI_CPU1_G0_CPU0_G2_TX_DP<12>")
	)
	(segment
		(start 363.16031 -239.15497)
		(end 363.159548 -239.155478)
		(width 0.1143)
		(layer "In6.Cu")
		(net "GMI_CPU1_G0_CPU0_G2_TX_DP<12>")
	)
	(segment
		(start 109.139736 -237.676944)
		(end 109.148118 -237.68177)
		(width 0.1143)
		(layer "In6.Cu")
		(net "GMI_CPU1_G0_CPU0_G2_TX_DP<12>")
	)
	(segment
		(start 108.303314 -239.136428)
		(end 108.30052 -239.134904)
		(width 0.1143)
		(layer "In6.Cu")
		(net "GMI_CPU1_G0_CPU0_G2_TX_DP<12>")
	)
	(segment
		(start 361.342432 -235.878878)
		(end 361.272836 -235.919518)
		(width 0.1143)
		(layer "In6.Cu")
		(net "GMI_CPU1_G0_CPU0_G2_TX_DP<12>")
	)
	(segment
		(start 364.782608 -242.794282)
		(end 364.712758 -242.864132)
		(width 0.1143)
		(layer "In6.Cu")
		(net "GMI_CPU1_G0_CPU0_G2_TX_DP<12>")
	)
	(segment
		(start 108.293662 -239.131094)
		(end 108.272326 -239.118648)
		(width 0.1143)
		(layer "In6.Cu")
		(net "GMI_CPU1_G0_CPU0_G2_TX_DP<12>")
	)
	(segment
		(start 108.272326 -240.130076)
		(end 108.29544 -240.116868)
		(width 0.1143)
		(layer "In6.Cu")
		(net "GMI_CPU1_G0_CPU0_G2_TX_DP<12>")
	)
	(segment
		(start 114.265202 -221.203012)
		(end 114.265202 -221.174564)
		(width 0.1143)
		(layer "In6.Cu")
		(net "GMI_CPU1_G0_CPU0_G2_TX_DP<12>")
	)
	(segment
		(start 231.85374 -197.339204)
		(end 232.240836 -197.499478)
		(width 0.14224)
		(layer "In6.Cu")
		(net "GMI_CPU1_G0_CPU0_G2_TX_DP<12>")
	)
	(segment
		(start 363.223556 -239.118394)
		(end 363.20222 -239.13084)
		(width 0.1143)
		(layer "In6.Cu")
		(net "GMI_CPU1_G0_CPU0_G2_TX_DP<12>")
	)
	(segment
		(start 361.029504 -236.384084)
		(end 361.029758 -236.384084)
		(width 0.1143)
		(layer "In6.Cu")
		(net "GMI_CPU1_G0_CPU0_G2_TX_DP<12>")
	)
	(segment
		(start 162.312096 -188.546994)
		(end 207.113632 -188.356494)
		(width 0.14224)
		(layer "In6.Cu")
		(net "GMI_CPU1_G0_CPU0_G2_TX_DP<12>")
	)
	(segment
		(start 361.342432 -227.779072)
		(end 361.272836 -227.819712)
		(width 0.1143)
		(layer "In6.Cu")
		(net "GMI_CPU1_G0_CPU0_G2_TX_DP<12>")
	)
	(segment
		(start 110.15218 -232.030524)
		(end 110.223046 -231.988868)
		(width 0.1143)
		(layer "In6.Cu")
		(net "GMI_CPU1_G0_CPU0_G2_TX_DP<12>")
	)
	(segment
		(start 110.15345 -232.638854)
		(end 110.15345 -232.639108)
		(width 0.1143)
		(layer "In6.Cu")
		(net "GMI_CPU1_G0_CPU0_G2_TX_DP<12>")
	)
	(segment
		(start 363.189266 -240.11001)
		(end 363.19079 -240.111026)
		(width 0.1143)
		(layer "In6.Cu")
		(net "GMI_CPU1_G0_CPU0_G2_TX_DP<12>")
	)
	(segment
		(start 363.15269 -240.088674)
		(end 363.180884 -240.105184)
		(width 0.1143)
		(layer "In6.Cu")
		(net "GMI_CPU1_G0_CPU0_G2_TX_DP<12>")
	)
	(segment
		(start 114.219482 -221.248732)
		(end 114.265202 -221.203012)
		(width 0.1143)
		(layer "In6.Cu")
		(net "GMI_CPU1_G0_CPU0_G2_TX_DP<12>")
	)
	(segment
		(start 110.622334 -226.360228)
		(end 110.697518 -226.316286)
		(width 0.1143)
		(layer "In6.Cu")
		(net "GMI_CPU1_G0_CPU0_G2_TX_DP<12>")
	)
	(segment
		(start 110.226348 -235.227114)
		(end 110.236254 -235.219748)
		(width 0.1143)
		(layer "In6.Cu")
		(net "GMI_CPU1_G0_CPU0_G2_TX_DP<12>")
	)
	(segment
		(start 303.70526 -188.483748)
		(end 308.680866 -188.483748)
		(width 0.14224)
		(layer "In6.Cu")
		(net "GMI_CPU1_G0_CPU0_G2_TX_DP<12>")
	)
	(segment
		(start 361.311952 -231.036622)
		(end 361.272836 -231.059482)
		(width 0.1143)
		(layer "In6.Cu")
		(net "GMI_CPU1_G0_CPU0_G2_TX_DP<12>")
	)
	(segment
		(start 108.302044 -240.113058)
		(end 108.303314 -240.112296)
		(width 0.1143)
		(layer "In6.Cu")
		(net "GMI_CPU1_G0_CPU0_G2_TX_DP<12>")
	)
	(segment
		(start 110.15345 -235.269532)
		(end 110.226348 -235.227114)
		(width 0.1143)
		(layer "In6.Cu")
		(net "GMI_CPU1_G0_CPU0_G2_TX_DP<12>")
	)
	(segment
		(start 361.311952 -229.41661)
		(end 361.274868 -229.437946)
		(width 0.1143)
		(layer "In6.Cu")
		(net "GMI_CPU1_G0_CPU0_G2_TX_DP<12>")
	)
	(segment
		(start 364.712758 -242.864132)
		(end 364.414816 -242.864132)
		(width 0.1143)
		(layer "In6.Cu")
		(net "GMI_CPU1_G0_CPU0_G2_TX_DP<12>")
	)
	(segment
		(start 110.918498 -226.057206)
		(end 111.083852 -225.634804)
		(width 0.1143)
		(layer "In6.Cu")
		(net "GMI_CPU1_G0_CPU0_G2_TX_DP<12>")
	)
	(segment
		(start 113.467388 -223.101916)
		(end 113.467896 -223.101662)
		(width 0.1143)
		(layer "In6.Cu")
		(net "GMI_CPU1_G0_CPU0_G2_TX_DP<12>")
	)
	(segment
		(start 363.19968 -239.13211)
		(end 363.19841 -239.132872)
		(width 0.1143)
		(layer "In6.Cu")
		(net "GMI_CPU1_G0_CPU0_G2_TX_DP<12>")
	)
	(segment
		(start 106.783124 -242.864386)
		(end 106.713274 -242.794536)
		(width 0.1143)
		(layer "In6.Cu")
		(net "GMI_CPU1_G0_CPU0_G2_TX_DP<12>")
	)
	(segment
		(start 110.15345 -236.889544)
		(end 110.18393 -236.871764)
		(width 0.1143)
		(layer "In6.Cu")
		(net "GMI_CPU1_G0_CPU0_G2_TX_DP<12>")
	)
	(segment
		(start 357.2764 -221.248478)
		(end 357.2764 -221.623128)
		(width 0.1143)
		(layer "In6.Cu")
		(net "GMI_CPU1_G0_CPU0_G2_TX_DP<12>")
	)
	(segment
		(start 233.724704 -198.259954)
		(end 233.900472 -198.187056)
		(width 0.14224)
		(layer "In6.Cu")
		(net "GMI_CPU1_G0_CPU0_G2_TX_DP<12>")
	)
	(segment
		(start 110.221014 -229.4382)
		(end 110.18393 -229.416864)
		(width 0.1143)
		(layer "In6.Cu")
		(net "GMI_CPU1_G0_CPU0_G2_TX_DP<12>")
	)
	(segment
		(start 107.36326 -241.732054)
		(end 107.36326 -241.732308)
		(width 0.1143)
		(layer "In6.Cu")
		(net "GMI_CPU1_G0_CPU0_G2_TX_DP<12>")
	)
	(segment
		(start 108.302044 -238.493046)
		(end 108.303314 -238.492284)
		(width 0.1143)
		(layer "In6.Cu")
		(net "GMI_CPU1_G0_CPU0_G2_TX_DP<12>")
	)
	(segment
		(start 229.243636 -196.403722)
		(end 229.63124 -196.56425)
		(width 0.14224)
		(layer "In6.Cu")
		(net "GMI_CPU1_G0_CPU0_G2_TX_DP<12>")
	)
	(segment
		(start 107.081066 -242.864386)
		(end 106.783124 -242.864386)
		(width 0.1143)
		(layer "In6.Cu")
		(net "GMI_CPU1_G0_CPU0_G2_TX_DP<12>")
	)
	(segment
		(start 230.267002 -196.827648)
		(end 230.654606 -196.988176)
		(width 0.14224)
		(layer "In6.Cu")
		(net "GMI_CPU1_G0_CPU0_G2_TX_DP<12>")
	)
	(segment
		(start 229.170738 -196.2277)
		(end 229.243636 -196.403722)
		(width 0.14224)
		(layer "In6.Cu")
		(net "GMI_CPU1_G0_CPU0_G2_TX_DP<12>")
	)
	(segment
		(start 234.646724 -198.49592)
		(end 236.299756 -198.787004)
		(width 0.14224)
		(layer "In6.Cu")
		(net "GMI_CPU1_G0_CPU0_G2_TX_DP<12>")
	)
	(segment
		(start 107.36834 -241.72926)
		(end 107.372404 -241.726974)
		(width 0.1143)
		(layer "In6.Cu")
		(net "GMI_CPU1_G0_CPU0_G2_TX_DP<12>")
	)
	(segment
		(start 106.862372 -242.560094)
		(end 106.930444 -242.520724)
		(width 0.1143)
		(layer "In6.Cu")
		(net "GMI_CPU1_G0_CPU0_G2_TX_DP<12>")
	)
	(segment
		(start 142.73149 -200.345294)
		(end 142.731744 -200.345294)
		(width 0.14224)
		(layer "In6.Cu")
		(net "GMI_CPU1_G0_CPU0_G2_TX_DP<12>")
	)
	(segment
		(start 232.701338 -197.836028)
		(end 232.877106 -197.76313)
		(width 0.14224)
		(layer "In6.Cu")
		(net "GMI_CPU1_G0_CPU0_G2_TX_DP<12>")
	)
	(segment
		(start 110.18393 -228.771958)
		(end 110.223046 -228.749098)
		(width 0.1143)
		(layer "In6.Cu")
		(net "GMI_CPU1_G0_CPU0_G2_TX_DP<12>")
	)
	(segment
		(start 364.130844 -241.730784)
		(end 364.132368 -241.731546)
		(width 0.1143)
		(layer "In6.Cu")
		(net "GMI_CPU1_G0_CPU0_G2_TX_DP<12>")
	)
	(segment
		(start 361.779312 -237.679992)
		(end 361.780836 -237.681008)
		(width 0.1143)
		(layer "In6.Cu")
		(net "GMI_CPU1_G0_CPU0_G2_TX_DP<12>")
	)
	(segment
		(start 110.223046 -235.919772)
		(end 110.15345 -235.879132)
		(width 0.1143)
		(layer "In6.Cu")
		(net "GMI_CPU1_G0_CPU0_G2_TX_DP<12>")
	)
	(segment
		(start 363.191806 -239.136682)
		(end 363.16031 -239.15497)
		(width 0.1143)
		(layer "In6.Cu")
		(net "GMI_CPU1_G0_CPU0_G2_TX_DP<12>")
	)
	(segment
		(start 215.396064 -190.522098)
		(end 229.170738 -196.2277)
		(width 0.14224)
		(layer "In6.Cu")
		(net "GMI_CPU1_G0_CPU0_G2_TX_DP<12>")
	)
	(segment
		(start 110.18393 -227.151946)
		(end 110.223046 -227.129086)
		(width 0.1143)
		(layer "In6.Cu")
		(net "GMI_CPU1_G0_CPU0_G2_TX_DP<12>")
	)
	(segment
		(start 231.677972 -197.412102)
		(end 231.85374 -197.339204)
		(width 0.14224)
		(layer "In6.Cu")
		(net "GMI_CPU1_G0_CPU0_G2_TX_DP<12>")
	)
	(segment
		(start 361.274868 -229.437946)
		(end 361.272836 -229.43947)
		(width 0.1143)
		(layer "In6.Cu")
		(net "GMI_CPU1_G0_CPU0_G2_TX_DP<12>")
	)
	(segment
		(start 364.130844 -241.731038)
		(end 364.130844 -241.730784)
		(width 0.1143)
		(layer "In6.Cu")
		(net "GMI_CPU1_G0_CPU0_G2_TX_DP<12>")
	)
	(segment
		(start 110.15345 -234.258866)
		(end 110.15345 -234.25912)
		(width 0.1143)
		(layer "In6.Cu")
		(net "GMI_CPU1_G0_CPU0_G2_TX_DP<12>")
	)
	(segment
		(start 363.622844 -240.89868)
		(end 363.69244 -240.93932)
		(width 0.1143)
		(layer "In6.Cu")
		(net "GMI_CPU1_G0_CPU0_G2_TX_DP<12>")
	)
	(segment
		(start 233.900472 -198.187056)
		(end 234.259374 -198.3359)
		(width 0.14224)
		(layer "In6.Cu")
		(net "GMI_CPU1_G0_CPU0_G2_TX_DP<12>")
	)
	(segment
		(start 239.204246 -198.27494)
		(end 250.68657 -190.234824)
		(width 0.14224)
		(layer "In6.Cu")
		(net "GMI_CPU1_G0_CPU0_G2_TX_DP<12>")
	)
	(segment
		(start 111.083852 -225.634804)
		(end 111.333026 -225.246438)
		(width 0.1143)
		(layer "In6.Cu")
		(net "GMI_CPU1_G0_CPU0_G2_TX_DP<12>")
	)
	(segment
		(start 117.564662 -216.513664)
		(end 123.15063 -212.143848)
		(width 0.14224)
		(layer "In6.Cu")
		(net "GMI_CPU1_G0_CPU0_G2_TX_DP<12>")
	)
	(segment
		(start 232.313734 -197.6755)
		(end 232.701338 -197.836028)
		(width 0.14224)
		(layer "In6.Cu")
		(net "GMI_CPU1_G0_CPU0_G2_TX_DP<12>")
	)
	(segment
		(start 107.366562 -241.730276)
		(end 107.367578 -241.729768)
		(width 0.1143)
		(layer "In6.Cu")
		(net "GMI_CPU1_G0_CPU0_G2_TX_DP<12>")
	)
	(segment
		(start 108.29544 -238.496856)
		(end 108.296202 -238.496348)
		(width 0.1143)
		(layer "In6.Cu")
		(net "GMI_CPU1_G0_CPU0_G2_TX_DP<12>")
	)
	(segment
		(start 230.654606 -196.988176)
		(end 230.830374 -196.915278)
		(width 0.14224)
		(layer "In6.Cu")
		(net "GMI_CPU1_G0_CPU0_G2_TX_DP<12>")
	)
	(segment
		(start 361.269534 -232.681272)
		(end 361.259628 -232.688638)
		(width 0.1143)
		(layer "In6.Cu")
		(net "GMI_CPU1_G0_CPU0_G2_TX_DP<12>")
	)
	(segment
		(start 233.3371 -198.099426)
		(end 233.724704 -198.259954)
		(width 0.14224)
		(layer "In6.Cu")
		(net "GMI_CPU1_G0_CPU0_G2_TX_DP<12>")
	)
	(segment
		(start 363.1819 -240.105692)
		(end 363.183424 -240.106708)
		(width 0.1143)
		(layer "In6.Cu")
		(net "GMI_CPU1_G0_CPU0_G2_TX_DP<12>")
	)
	(segment
		(start 212.4329 -189.294516)
		(end 212.660484 -189.389004)
		(width 0.14224)
		(layer "In6.Cu")
		(net "GMI_CPU1_G0_CPU0_G2_TX_DP<12>")
	)
	(segment
		(start 363.197648 -239.13338)
		(end 363.196124 -239.134142)
		(width 0.1143)
		(layer "In6.Cu")
		(net "GMI_CPU1_G0_CPU0_G2_TX_DP<12>")
	)
	(segment
		(start 113.907062 -222.30969)
		(end 113.937542 -222.29191)
		(width 0.1143)
		(layer "In6.Cu")
		(net "GMI_CPU1_G0_CPU0_G2_TX_DP<12>")
	)
	(segment
		(start 361.272836 -228.748844)
		(end 361.342432 -228.789484)
		(width 0.1143)
		(layer "In6.Cu")
		(net "GMI_CPU1_G0_CPU0_G2_TX_DP<12>")
	)
	(segment
		(start 108.312458 -240.106962)
		(end 108.313982 -240.105946)
		(width 0.1143)
		(layer "In6.Cu")
		(net "GMI_CPU1_G0_CPU0_G2_TX_DP<12>")
	)
	(segment
		(start 107.334304 -241.749072)
		(end 107.33532 -241.748564)
		(width 0.1143)
		(layer "In6.Cu")
		(net "GMI_CPU1_G0_CPU0_G2_TX_DP<12>")
	)
	(segment
		(start 108.297726 -238.495586)
		(end 108.302044 -238.493046)
		(width 0.1143)
		(layer "In6.Cu")
		(net "GMI_CPU1_G0_CPU0_G2_TX_DP<12>")
	)
	(segment
		(start 108.314998 -238.485426)
		(end 108.343192 -238.468916)
		(width 0.1143)
		(layer "In6.Cu")
		(net "GMI_CPU1_G0_CPU0_G2_TX_DP<12>")
	)
	(segment
		(start 231.290368 -197.251574)
		(end 231.677972 -197.412102)
		(width 0.14224)
		(layer "In6.Cu")
		(net "GMI_CPU1_G0_CPU0_G2_TX_DP<12>")
	)
	(arc
		(start 361.499404 -237.19409)
		(mid 361.563919 -237.456309)
		(end 361.742736 -237.658656)
		(width 0.1143)
		(layer "In6.Cu")
		(net "GMI_CPU1_G0_CPU0_G2_TX_DP<12>")
	)
	(arc
		(start 109.148118 -237.68177)
		(mid 109.431074 -237.757947)
		(end 109.71403 -237.68177)
		(width 0.1143)
		(layer "In6.Cu")
		(net "GMI_CPU1_G0_CPU0_G2_TX_DP<12>")
	)
	(arc
		(start 361.029758 -236.375448)
		(mid 361.029615 -236.379766)
		(end 361.029504 -236.384084)
		(width 0.1143)
		(layer "In6.Cu")
		(net "GMI_CPU1_G0_CPU0_G2_TX_DP<12>")
	)
	(arc
		(start 108.773976 -237.68177)
		(mid 108.956227 -237.63142)
		(end 109.139736 -237.676944)
		(width 0.1143)
		(layer "In6.Cu")
		(net "GMI_CPU1_G0_CPU0_G2_TX_DP<12>")
	)
	(arc
		(start 110.15345 -235.879132)
		(mid 109.996473 -235.574332)
		(end 110.15345 -235.269532)
		(width 0.1143)
		(layer "In6.Cu")
		(net "GMI_CPU1_G0_CPU0_G2_TX_DP<12>")
	)
	(arc
		(start 360.975148 -226.469956)
		(mid 361.015669 -226.563379)
		(end 361.029504 -226.664266)
		(width 0.1143)
		(layer "In6.Cu")
		(net "GMI_CPU1_G0_CPU0_G2_TX_DP<12>")
	)
	(arc
		(start 358.466136 -223.355408)
		(mid 358.538961 -223.403761)
		(end 358.605836 -223.460056)
		(width 0.1143)
		(layer "In6.Cu")
		(net "GMI_CPU1_G0_CPU0_G2_TX_DP<12>")
	)
	(arc
		(start 109.996478 -230.71455)
		(mid 110.038027 -230.543128)
		(end 110.15345 -230.40975)
		(width 0.1143)
		(layer "In6.Cu")
		(net "GMI_CPU1_G0_CPU0_G2_TX_DP<12>")
	)
	(arc
		(start 110.697518 -226.316286)
		(mid 110.829794 -226.205338)
		(end 110.918498 -226.057206)
		(width 0.1143)
		(layer "In6.Cu")
		(net "GMI_CPU1_G0_CPU0_G2_TX_DP<12>")
	)
	(arc
		(start 361.342432 -230.409496)
		(mid 361.457859 -230.542872)
		(end 361.499404 -230.714296)
		(width 0.1143)
		(layer "In6.Cu")
		(net "GMI_CPU1_G0_CPU0_G2_TX_DP<12>")
	)
	(arc
		(start 359.27157 -224.085404)
		(mid 359.312213 -224.125583)
		(end 359.350564 -224.167954)
		(width 0.1143)
		(layer "In6.Cu")
		(net "GMI_CPU1_G0_CPU0_G2_TX_DP<12>")
	)
	(arc
		(start 110.15345 -232.639108)
		(mid 109.99658 -232.33512)
		(end 110.15218 -232.030524)
		(width 0.1143)
		(layer "In6.Cu")
		(net "GMI_CPU1_G0_CPU0_G2_TX_DP<12>")
	)
	(arc
		(start 110.220252 -236.850682)
		(mid 110.400904 -236.647937)
		(end 110.466124 -236.384338)
		(width 0.1143)
		(layer "In6.Cu")
		(net "GMI_CPU1_G0_CPU0_G2_TX_DP<12>")
	)
	(arc
		(start 362.356146 -237.67669)
		(mid 362.539654 -237.631196)
		(end 362.721906 -237.681516)
		(width 0.1143)
		(layer "In6.Cu")
		(net "GMI_CPU1_G0_CPU0_G2_TX_DP<12>")
	)
	(arc
		(start 361.029504 -231.526842)
		(mid 361.092467 -231.780466)
		(end 361.260898 -231.980232)
		(width 0.1143)
		(layer "In6.Cu")
		(net "GMI_CPU1_G0_CPU0_G2_TX_DP<12>")
	)
	(arc
		(start 360.50982 -225.7679)
		(mid 360.527199 -225.81913)
		(end 360.54411 -225.870516)
		(width 0.1143)
		(layer "In6.Cu")
		(net "GMI_CPU1_G0_CPU0_G2_TX_DP<12>")
	)
	(arc
		(start 363.15269 -239.159542)
		(mid 362.909363 -239.624108)
		(end 363.15269 -240.088674)
		(width 0.1143)
		(layer "In6.Cu")
		(net "GMI_CPU1_G0_CPU0_G2_TX_DP<12>")
	)
	(arc
		(start 357.745792 -222.614236)
		(mid 357.810307 -222.876455)
		(end 357.989124 -223.078802)
		(width 0.1143)
		(layer "In6.Cu")
		(net "GMI_CPU1_G0_CPU0_G2_TX_DP<12>")
	)
	(arc
		(start 361.029758 -236.384084)
		(mid 361.094994 -236.647675)
		(end 361.27563 -236.850428)
		(width 0.1143)
		(layer "In6.Cu")
		(net "GMI_CPU1_G0_CPU0_G2_TX_DP<12>")
	)
	(arc
		(start 361.029504 -226.664266)
		(mid 361.094019 -226.926485)
		(end 361.272836 -227.128832)
		(width 0.1143)
		(layer "In6.Cu")
		(net "GMI_CPU1_G0_CPU0_G2_TX_DP<12>")
	)
	(arc
		(start 113.448846 -223.112838)
		(mid 113.453287 -223.110291)
		(end 113.457736 -223.107758)
		(width 0.1143)
		(layer "In6.Cu")
		(net "GMI_CPU1_G0_CPU0_G2_TX_DP<12>")
	)
	(arc
		(start 106.930444 -242.520724)
		(mid 107.111096 -242.317979)
		(end 107.176316 -242.05438)
		(width 0.1143)
		(layer "In6.Cu")
		(net "GMI_CPU1_G0_CPU0_G2_TX_DP<12>")
	)
	(arc
		(start 364.161578 -241.748818)
		(mid 364.162468 -241.749452)
		(end 364.163356 -241.750088)
		(width 0.1143)
		(layer "In6.Cu")
		(net "GMI_CPU1_G0_CPU0_G2_TX_DP<12>")
	)
	(arc
		(start 361.260898 -231.980232)
		(mid 361.26684 -231.984462)
		(end 361.272836 -231.988614)
		(width 0.1143)
		(layer "In6.Cu")
		(net "GMI_CPU1_G0_CPU0_G2_TX_DP<12>")
	)
	(arc
		(start 361.342432 -227.169472)
		(mid 361.499409 -227.474272)
		(end 361.342432 -227.779072)
		(width 0.1143)
		(layer "In6.Cu")
		(net "GMI_CPU1_G0_CPU0_G2_TX_DP<12>")
	)
	(arc
		(start 361.272836 -235.919518)
		(mid 361.099843 -236.120055)
		(end 361.029758 -236.375448)
		(width 0.1143)
		(layer "In6.Cu")
		(net "GMI_CPU1_G0_CPU0_G2_TX_DP<12>")
	)
	(arc
		(start 363.849412 -241.24412)
		(mid 363.913927 -241.506339)
		(end 364.092744 -241.708686)
		(width 0.1143)
		(layer "In6.Cu")
		(net "GMI_CPU1_G0_CPU0_G2_TX_DP<12>")
	)
	(arc
		(start 107.873038 -240.898934)
		(mid 108.051851 -240.696584)
		(end 108.11637 -240.434368)
		(width 0.1143)
		(layer "In6.Cu")
		(net "GMI_CPU1_G0_CPU0_G2_TX_DP<12>")
	)
	(arc
		(start 110.466378 -231.527096)
		(mid 110.402516 -231.263318)
		(end 110.223046 -231.059736)
		(width 0.1143)
		(layer "In6.Cu")
		(net "GMI_CPU1_G0_CPU0_G2_TX_DP<12>")
	)
	(arc
		(start 110.151418 -231.01808)
		(mid 110.037489 -230.884933)
		(end 109.996478 -230.71455)
		(width 0.1143)
		(layer "In6.Cu")
		(net "GMI_CPU1_G0_CPU0_G2_TX_DP<12>")
	)
	(arc
		(start 361.343702 -232.03027)
		(mid 361.499217 -232.334866)
		(end 361.342432 -232.638854)
		(width 0.1143)
		(layer "In6.Cu")
		(net "GMI_CPU1_G0_CPU0_G2_TX_DP<12>")
	)
	(arc
		(start 363.223556 -240.129822)
		(mid 363.338232 -240.263156)
		(end 363.379512 -240.434114)
		(width 0.1143)
		(layer "In6.Cu")
		(net "GMI_CPU1_G0_CPU0_G2_TX_DP<12>")
	)
	(arc
		(start 364.63351 -242.55984)
		(mid 364.730645 -242.662709)
		(end 364.782608 -242.794282)
		(width 0.1143)
		(layer "In6.Cu")
		(net "GMI_CPU1_G0_CPU0_G2_TX_DP<12>")
	)
	(arc
		(start 108.11637 -240.434368)
		(mid 108.157625 -240.263397)
		(end 108.272326 -240.130076)
		(width 0.1143)
		(layer "In6.Cu")
		(net "GMI_CPU1_G0_CPU0_G2_TX_DP<12>")
	)
	(arc
		(start 113.505234 -223.080072)
		(mid 113.685119 -222.877503)
		(end 113.75009 -222.61449)
		(width 0.1143)
		(layer "In6.Cu")
		(net "GMI_CPU1_G0_CPU0_G2_TX_DP<12>")
	)
	(arc
		(start 360.343958 -225.465386)
		(mid 360.370218 -225.503656)
		(end 360.39425 -225.543364)
		(width 0.1143)
		(layer "In6.Cu")
		(net "GMI_CPU1_G0_CPU0_G2_TX_DP<12>")
	)
	(arc
		(start 110.220506 -230.370634)
		(mid 110.401158 -230.167889)
		(end 110.466378 -229.90429)
		(width 0.1143)
		(layer "In6.Cu")
		(net "GMI_CPU1_G0_CPU0_G2_TX_DP<12>")
	)
	(arc
		(start 108.343192 -238.468916)
		(mid 108.522005 -238.266566)
		(end 108.586524 -238.00435)
		(width 0.1143)
		(layer "In6.Cu")
		(net "GMI_CPU1_G0_CPU0_G2_TX_DP<12>")
	)
	(arc
		(start 112.43564 -223.868996)
		(mid 112.922901 -223.465)
		(end 113.448846 -223.112838)
		(width 0.1143)
		(layer "In6.Cu")
		(net "GMI_CPU1_G0_CPU0_G2_TX_DP<12>")
	)
	(arc
		(start 110.234984 -231.980486)
		(mid 110.403313 -231.780667)
		(end 110.466378 -231.527096)
		(width 0.1143)
		(layer "In6.Cu")
		(net "GMI_CPU1_G0_CPU0_G2_TX_DP<12>")
	)
	(arc
		(start 108.272326 -239.118648)
		(mid 108.116398 -238.814356)
		(end 108.272326 -238.510064)
		(width 0.1143)
		(layer "In6.Cu")
		(net "GMI_CPU1_G0_CPU0_G2_TX_DP<12>")
	)
	(arc
		(start 109.996478 -229.094538)
		(mid 110.038027 -228.923116)
		(end 110.15345 -228.789738)
		(width 0.1143)
		(layer "In6.Cu")
		(net "GMI_CPU1_G0_CPU0_G2_TX_DP<12>")
	)
	(arc
		(start 361.272836 -231.059482)
		(mid 361.093377 -231.26307)
		(end 361.029504 -231.526842)
		(width 0.1143)
		(layer "In6.Cu")
		(net "GMI_CPU1_G0_CPU0_G2_TX_DP<12>")
	)
	(arc
		(start 362.752386 -237.699296)
		(mid 362.867813 -237.832672)
		(end 362.909358 -238.004096)
		(width 0.1143)
		(layer "In6.Cu")
		(net "GMI_CPU1_G0_CPU0_G2_TX_DP<12>")
	)
	(arc
		(start 360.453686 -225.647758)
		(mid 360.484196 -225.706687)
		(end 360.50982 -225.7679)
		(width 0.1143)
		(layer "In6.Cu")
		(net "GMI_CPU1_G0_CPU0_G2_TX_DP<12>")
	)
	(arc
		(start 107.176316 -242.05438)
		(mid 107.217695 -241.883482)
		(end 107.332526 -241.750342)
		(width 0.1143)
		(layer "In6.Cu")
		(net "GMI_CPU1_G0_CPU0_G2_TX_DP<12>")
	)
	(arc
		(start 363.69244 -240.93932)
		(mid 363.807867 -241.072696)
		(end 363.849412 -241.24412)
		(width 0.1143)
		(layer "In6.Cu")
		(net "GMI_CPU1_G0_CPU0_G2_TX_DP<12>")
	)
	(arc
		(start 360.54411 -225.87077)
		(mid 360.560675 -225.925587)
		(end 360.575098 -225.981006)
		(width 0.1143)
		(layer "In6.Cu")
		(net "GMI_CPU1_G0_CPU0_G2_TX_DP<12>")
	)
	(arc
		(start 112.08258 -224.23628)
		(mid 112.253587 -224.047329)
		(end 112.43564 -223.868996)
		(width 0.1143)
		(layer "In6.Cu")
		(net "GMI_CPU1_G0_CPU0_G2_TX_DP<12>")
	)
	(arc
		(start 109.753146 -237.65891)
		(mid 109.931959 -237.45656)
		(end 109.996478 -237.194344)
		(width 0.1143)
		(layer "In6.Cu")
		(net "GMI_CPU1_G0_CPU0_G2_TX_DP<12>")
	)
	(arc
		(start 361.342432 -233.649266)
		(mid 361.499409 -233.954066)
		(end 361.342432 -234.258866)
		(width 0.1143)
		(layer "In6.Cu")
		(net "GMI_CPU1_G0_CPU0_G2_TX_DP<12>")
	)
	(arc
		(start 110.466378 -229.90429)
		(mid 110.401863 -229.642071)
		(end 110.223046 -229.439724)
		(width 0.1143)
		(layer "In6.Cu")
		(net "GMI_CPU1_G0_CPU0_G2_TX_DP<12>")
	)
	(arc
		(start 361.029504 -229.904036)
		(mid 361.09474 -230.167627)
		(end 361.275376 -230.37038)
		(width 0.1143)
		(layer "In6.Cu")
		(net "GMI_CPU1_G0_CPU0_G2_TX_DP<12>")
	)
	(arc
		(start 113.976658 -222.26905)
		(mid 114.155548 -222.066726)
		(end 114.21999 -221.804484)
		(width 0.1143)
		(layer "In6.Cu")
		(net "GMI_CPU1_G0_CPU0_G2_TX_DP<12>")
	)
	(arc
		(start 361.342432 -235.269278)
		(mid 361.499409 -235.574078)
		(end 361.342432 -235.878878)
		(width 0.1143)
		(layer "In6.Cu")
		(net "GMI_CPU1_G0_CPU0_G2_TX_DP<12>")
	)
	(arc
		(start 108.343192 -240.088928)
		(mid 108.586519 -239.624362)
		(end 108.343192 -239.159796)
		(width 0.1143)
		(layer "In6.Cu")
		(net "GMI_CPU1_G0_CPU0_G2_TX_DP<12>")
	)
	(arc
		(start 360.873548 -226.359974)
		(mid 360.929908 -226.409831)
		(end 360.975148 -226.469956)
		(width 0.1143)
		(layer "In6.Cu")
		(net "GMI_CPU1_G0_CPU0_G2_TX_DP<12>")
	)
	(arc
		(start 110.236254 -233.599736)
		(mid 110.467853 -233.144314)
		(end 110.236254 -232.688892)
		(width 0.1143)
		(layer "In6.Cu")
		(net "GMI_CPU1_G0_CPU0_G2_TX_DP<12>")
	)
	(arc
		(start 361.259628 -232.688638)
		(mid 361.028029 -233.14406)
		(end 361.259628 -233.599482)
		(width 0.1143)
		(layer "In6.Cu")
		(net "GMI_CPU1_G0_CPU0_G2_TX_DP<12>")
	)
	(arc
		(start 113.75009 -222.61449)
		(mid 113.791639 -222.443068)
		(end 113.907062 -222.30969)
		(width 0.1143)
		(layer "In6.Cu")
		(net "GMI_CPU1_G0_CPU0_G2_TX_DP<12>")
	)
	(arc
		(start 362.909358 -238.004096)
		(mid 362.973873 -238.266315)
		(end 363.15269 -238.468662)
		(width 0.1143)
		(layer "In6.Cu")
		(net "GMI_CPU1_G0_CPU0_G2_TX_DP<12>")
	)
	(arc
		(start 364.319566 -242.054126)
		(mid 364.384802 -242.317717)
		(end 364.565438 -242.52047)
		(width 0.1143)
		(layer "In6.Cu")
		(net "GMI_CPU1_G0_CPU0_G2_TX_DP<12>")
	)
	(arc
		(start 361.342432 -236.88929)
		(mid 361.457859 -237.022666)
		(end 361.499404 -237.19409)
		(width 0.1143)
		(layer "In6.Cu")
		(net "GMI_CPU1_G0_CPU0_G2_TX_DP<12>")
	)
	(arc
		(start 110.151418 -229.398068)
		(mid 110.037489 -229.264921)
		(end 109.996478 -229.094538)
		(width 0.1143)
		(layer "In6.Cu")
		(net "GMI_CPU1_G0_CPU0_G2_TX_DP<12>")
	)
	(arc
		(start 361.272836 -227.819712)
		(mid 361.029509 -228.284278)
		(end 361.272836 -228.748844)
		(width 0.1143)
		(layer "In6.Cu")
		(net "GMI_CPU1_G0_CPU0_G2_TX_DP<12>")
	)
	(arc
		(start 361.342432 -228.789484)
		(mid 361.457859 -228.92286)
		(end 361.499404 -229.094284)
		(width 0.1143)
		(layer "In6.Cu")
		(net "GMI_CPU1_G0_CPU0_G2_TX_DP<12>")
	)
	(arc
		(start 360.737658 -226.265232)
		(mid 360.781285 -226.30243)
		(end 360.829098 -226.334066)
		(width 0.1143)
		(layer "In6.Cu")
		(net "GMI_CPU1_G0_CPU0_G2_TX_DP<12>")
	)
	(arc
		(start 361.272836 -229.43947)
		(mid 361.094023 -229.64182)
		(end 361.029504 -229.904036)
		(width 0.1143)
		(layer "In6.Cu")
		(net "GMI_CPU1_G0_CPU0_G2_TX_DP<12>")
	)
	(arc
		(start 111.619792 -224.82556)
		(mid 111.842713 -224.528505)
		(end 112.078262 -224.24136)
		(width 0.1143)
		(layer "In6.Cu")
		(net "GMI_CPU1_G0_CPU0_G2_TX_DP<12>")
	)
	(arc
		(start 109.996478 -237.194344)
		(mid 110.038027 -237.022922)
		(end 110.15345 -236.889544)
		(width 0.1143)
		(layer "In6.Cu")
		(net "GMI_CPU1_G0_CPU0_G2_TX_DP<12>")
	)
	(arc
		(start 361.259628 -234.30865)
		(mid 361.028029 -234.764072)
		(end 361.259628 -235.219494)
		(width 0.1143)
		(layer "In6.Cu")
		(net "GMI_CPU1_G0_CPU0_G2_TX_DP<12>")
	)
	(arc
		(start 108.586524 -238.00435)
		(mid 108.628073 -237.832928)
		(end 108.743496 -237.69955)
		(width 0.1143)
		(layer "In6.Cu")
		(net "GMI_CPU1_G0_CPU0_G2_TX_DP<12>")
	)
	(arc
		(start 357.58882 -222.309436)
		(mid 357.704247 -222.442812)
		(end 357.745792 -222.614236)
		(width 0.1143)
		(layer "In6.Cu")
		(net "GMI_CPU1_G0_CPU0_G2_TX_DP<12>")
	)
	(arc
		(start 364.163356 -241.750088)
		(mid 364.278124 -241.88326)
		(end 364.319566 -242.054126)
		(width 0.1143)
		(layer "In6.Cu")
		(net "GMI_CPU1_G0_CPU0_G2_TX_DP<12>")
	)
	(arc
		(start 360.575098 -225.981006)
		(mid 360.636221 -226.134648)
		(end 360.737658 -226.265232)
		(width 0.1143)
		(layer "In6.Cu")
		(net "GMI_CPU1_G0_CPU0_G2_TX_DP<12>")
	)
	(arc
		(start 110.223046 -231.988868)
		(mid 110.229042 -231.984715)
		(end 110.234984 -231.980486)
		(width 0.1143)
		(layer "In6.Cu")
		(net "GMI_CPU1_G0_CPU0_G2_TX_DP<12>")
	)
	(arc
		(start 363.379512 -240.434114)
		(mid 363.444027 -240.696333)
		(end 363.622844 -240.89868)
		(width 0.1143)
		(layer "In6.Cu")
		(net "GMI_CPU1_G0_CPU0_G2_TX_DP<12>")
	)
	(arc
		(start 113.457736 -223.107758)
		(mid 113.462557 -223.104829)
		(end 113.467388 -223.101916)
		(width 0.1143)
		(layer "In6.Cu")
		(net "GMI_CPU1_G0_CPU0_G2_TX_DP<12>")
	)
	(arc
		(start 110.466378 -226.66452)
		(mid 110.507633 -226.493549)
		(end 110.622334 -226.360228)
		(width 0.1143)
		(layer "In6.Cu")
		(net "GMI_CPU1_G0_CPU0_G2_TX_DP<12>")
	)
	(arc
		(start 110.466378 -236.384338)
		(mid 110.466266 -236.38002)
		(end 110.466124 -236.375702)
		(width 0.1143)
		(layer "In6.Cu")
		(net "GMI_CPU1_G0_CPU0_G2_TX_DP<12>")
	)
	(arc
		(start 110.15345 -227.779326)
		(mid 109.996473 -227.474526)
		(end 110.15345 -227.169726)
		(width 0.1143)
		(layer "In6.Cu")
		(net "GMI_CPU1_G0_CPU0_G2_TX_DP<12>")
	)
	(arc
		(start 110.223046 -228.749098)
		(mid 110.466373 -228.284532)
		(end 110.223046 -227.819966)
		(width 0.1143)
		(layer "In6.Cu")
		(net "GMI_CPU1_G0_CPU0_G2_TX_DP<12>")
	)
	(arc
		(start 361.499404 -230.714296)
		(mid 361.458438 -230.884702)
		(end 361.344464 -231.017826)
		(width 0.1143)
		(layer "In6.Cu")
		(net "GMI_CPU1_G0_CPU0_G2_TX_DP<12>")
	)
	(arc
		(start 111.333026 -225.246438)
		(mid 111.473306 -225.034225)
		(end 111.619538 -224.826068)
		(width 0.1143)
		(layer "In6.Cu")
		(net "GMI_CPU1_G0_CPU0_G2_TX_DP<12>")
	)
	(arc
		(start 107.403138 -241.70894)
		(mid 107.581951 -241.50659)
		(end 107.64647 -241.244374)
		(width 0.1143)
		(layer "In6.Cu")
		(net "GMI_CPU1_G0_CPU0_G2_TX_DP<12>")
	)
	(arc
		(start 110.15345 -234.25912)
		(mid 109.996473 -233.95432)
		(end 110.15345 -233.64952)
		(width 0.1143)
		(layer "In6.Cu")
		(net "GMI_CPU1_G0_CPU0_G2_TX_DP<12>")
	)
	(arc
		(start 357.275892 -221.80423)
		(mid 357.340426 -222.066423)
		(end 357.519224 -222.268796)
		(width 0.1143)
		(layer "In6.Cu")
		(net "GMI_CPU1_G0_CPU0_G2_TX_DP<12>")
	)
	(arc
		(start 361.781852 -237.681516)
		(mid 362.064808 -237.757693)
		(end 362.347764 -237.681516)
		(width 0.1143)
		(layer "In6.Cu")
		(net "GMI_CPU1_G0_CPU0_G2_TX_DP<12>")
	)
	(arc
		(start 106.713274 -242.794536)
		(mid 106.765323 -242.663017)
		(end 106.862372 -242.560094)
		(width 0.1143)
		(layer "In6.Cu")
		(net "GMI_CPU1_G0_CPU0_G2_TX_DP<12>")
	)
	(arc
		(start 107.64647 -241.244374)
		(mid 107.688019 -241.072952)
		(end 107.803442 -240.939574)
		(width 0.1143)
		(layer "In6.Cu")
		(net "GMI_CPU1_G0_CPU0_G2_TX_DP<12>")
	)
	(arc
		(start 107.332526 -241.750342)
		(mid 107.333414 -241.749705)
		(end 107.334304 -241.749072)
		(width 0.1143)
		(layer "In6.Cu")
		(net "GMI_CPU1_G0_CPU0_G2_TX_DP<12>")
	)
	(arc
		(start 363.223556 -238.50981)
		(mid 363.379484 -238.814102)
		(end 363.223556 -239.118394)
		(width 0.1143)
		(layer "In6.Cu")
		(net "GMI_CPU1_G0_CPU0_G2_TX_DP<12>")
	)
	(arc
		(start 110.236254 -235.219748)
		(mid 110.467853 -234.764326)
		(end 110.236254 -234.308904)
		(width 0.1143)
		(layer "In6.Cu")
		(net "GMI_CPU1_G0_CPU0_G2_TX_DP<12>")
	)
	(arc
		(start 110.466124 -236.375702)
		(mid 110.396008 -236.120325)
		(end 110.223046 -235.919772)
		(width 0.1143)
		(layer "In6.Cu")
		(net "GMI_CPU1_G0_CPU0_G2_TX_DP<12>")
	)
	(arc
		(start 110.223046 -227.129086)
		(mid 110.401859 -226.926736)
		(end 110.466378 -226.66452)
		(width 0.1143)
		(layer "In6.Cu")
		(net "GMI_CPU1_G0_CPU0_G2_TX_DP<12>")
	)
	(arc
		(start 359.634028 -224.500948)
		(mid 359.670297 -224.545118)
		(end 359.704894 -224.59061)
		(width 0.1143)
		(layer "In6.Cu")
		(net "GMI_CPU1_G0_CPU0_G2_TX_DP<12>")
	)
	(arc
		(start 361.499404 -229.094284)
		(mid 361.458438 -229.26469)
		(end 361.344464 -229.397814)
		(width 0.1143)
		(layer "In6.Cu")
		(net "GMI_CPU1_G0_CPU0_G2_TX_DP<12>")
	)
	(segment
		(start 363.947964 -238.270034)
		(end 364.414816 -238.004096)
		(width 0.12954)
		(layer "F.Cu")
		(net "GMI_CPU1_G0_CPU0_G2_TX_DP<11>")
	)
	(segment
		(start 107.547918 -238.270288)
		(end 107.081066 -238.00435)
		(width 0.12954)
		(layer "F.Cu")
		(net "GMI_CPU1_G0_CPU0_G2_TX_DP<11>")
	)
	(segment
		(start 363.192568 -227.796344)
		(end 363.191806 -227.796852)
		(width 0.1143)
		(layer "In6.Cu")
		(net "GMI_CPU1_G0_CPU0_G2_TX_DP<11>")
	)
	(segment
		(start 107.333288 -236.889544)
		(end 107.36326 -236.872272)
		(width 0.1143)
		(layer "In6.Cu")
		(net "GMI_CPU1_G0_CPU0_G2_TX_DP<11>")
	)
	(segment
		(start 313.701938 -188.90742)
		(end 313.998102 -189.203584)
		(width 0.14224)
		(layer "In6.Cu")
		(net "GMI_CPU1_G0_CPU0_G2_TX_DP<11>")
	)
	(segment
		(start 361.781598 -224.721674)
		(end 361.812078 -224.739454)
		(width 0.1143)
		(layer "In6.Cu")
		(net "GMI_CPU1_G0_CPU0_G2_TX_DP<11>")
	)
	(segment
		(start 363.15269 -235.228638)
		(end 363.189266 -235.249974)
		(width 0.1143)
		(layer "In6.Cu")
		(net "GMI_CPU1_G0_CPU0_G2_TX_DP<11>")
	)
	(segment
		(start 363.19079 -235.25099)
		(end 363.191806 -235.251498)
		(width 0.1143)
		(layer "In6.Cu")
		(net "GMI_CPU1_G0_CPU0_G2_TX_DP<11>")
	)
	(segment
		(start 164.953696 -184.579006)
		(end 168.304464 -183.691276)
		(width 0.14224)
		(layer "In6.Cu")
		(net "GMI_CPU1_G0_CPU0_G2_TX_DP<11>")
	)
	(segment
		(start 364.12932 -236.869986)
		(end 364.130844 -236.871002)
		(width 0.1143)
		(layer "In6.Cu")
		(net "GMI_CPU1_G0_CPU0_G2_TX_DP<11>")
	)
	(segment
		(start 311.62752 -187.513976)
		(end 311.9882 -187.728098)
		(width 0.14224)
		(layer "In6.Cu")
		(net "GMI_CPU1_G0_CPU0_G2_TX_DP<11>")
	)
	(segment
		(start 363.192568 -232.011982)
		(end 363.193838 -232.012744)
		(width 0.1143)
		(layer "In6.Cu")
		(net "GMI_CPU1_G0_CPU0_G2_TX_DP<11>")
	)
	(segment
		(start 313.21502 -188.611002)
		(end 313.511692 -188.90742)
		(width 0.14224)
		(layer "In6.Cu")
		(net "GMI_CPU1_G0_CPU0_G2_TX_DP<11>")
	)
	(segment
		(start 106.894122 -237.68177)
		(end 106.895646 -237.681008)
		(width 0.1143)
		(layer "In6.Cu")
		(net "GMI_CPU1_G0_CPU0_G2_TX_DP<11>")
	)
	(segment
		(start 363.191806 -234.276646)
		(end 363.19079 -234.277154)
		(width 0.1143)
		(layer "In6.Cu")
		(net "GMI_CPU1_G0_CPU0_G2_TX_DP<11>")
	)
	(segment
		(start 108.305092 -228.77145)
		(end 108.306616 -228.770434)
		(width 0.1143)
		(layer "In6.Cu")
		(net "GMI_CPU1_G0_CPU0_G2_TX_DP<11>")
	)
	(segment
		(start 363.193838 -235.252768)
		(end 363.223556 -235.269786)
		(width 0.1143)
		(layer "In6.Cu")
		(net "GMI_CPU1_G0_CPU0_G2_TX_DP<11>")
	)
	(segment
		(start 360.843068 -223.102932)
		(end 360.872786 -223.11995)
		(width 0.1143)
		(layer "In6.Cu")
		(net "GMI_CPU1_G0_CPU0_G2_TX_DP<11>")
	)
	(segment
		(start 108.306616 -232.010204)
		(end 108.311188 -232.007664)
		(width 0.1143)
		(layer "In6.Cu")
		(net "GMI_CPU1_G0_CPU0_G2_TX_DP<11>")
	)
	(segment
		(start 364.565438 -237.660434)
		(end 364.572296 -237.664244)
		(width 0.1143)
		(layer "In6.Cu")
		(net "GMI_CPU1_G0_CPU0_G2_TX_DP<11>")
	)
	(segment
		(start 363.19079 -233.630978)
		(end 363.191806 -233.631486)
		(width 0.1143)
		(layer "In6.Cu")
		(net "GMI_CPU1_G0_CPU0_G2_TX_DP<11>")
	)
	(segment
		(start 364.130844 -236.871002)
		(end 364.13186 -236.87151)
		(width 0.1143)
		(layer "In6.Cu")
		(net "GMI_CPU1_G0_CPU0_G2_TX_DP<11>")
	)
	(segment
		(start 360.80192 -223.078802)
		(end 360.838496 -223.100138)
		(width 0.1143)
		(layer "In6.Cu")
		(net "GMI_CPU1_G0_CPU0_G2_TX_DP<11>")
	)
	(segment
		(start 108.302044 -234.27563)
		(end 108.272326 -234.258612)
		(width 0.1143)
		(layer "In6.Cu")
		(net "GMI_CPU1_G0_CPU0_G2_TX_DP<11>")
	)
	(segment
		(start 111.453676 -220.688154)
		(end 112.118902 -219.082366)
		(width 0.14224)
		(layer "In6.Cu")
		(net "GMI_CPU1_G0_CPU0_G2_TX_DP<11>")
	)
	(segment
		(start 312.918856 -188.124338)
		(end 313.21502 -188.420502)
		(width 0.14224)
		(layer "In6.Cu")
		(net "GMI_CPU1_G0_CPU0_G2_TX_DP<11>")
	)
	(segment
		(start 108.343192 -229.439724)
		(end 108.304076 -229.416864)
		(width 0.1143)
		(layer "In6.Cu")
		(net "GMI_CPU1_G0_CPU0_G2_TX_DP<11>")
	)
	(segment
		(start 364.13186 -236.87151)
		(end 364.132622 -236.872018)
		(width 0.1143)
		(layer "In6.Cu")
		(net "GMI_CPU1_G0_CPU0_G2_TX_DP<11>")
	)
	(segment
		(start 356.919276 -216.836244)
		(end 359.625392 -219.541344)
		(width 0.14224)
		(layer "In6.Cu")
		(net "GMI_CPU1_G0_CPU0_G2_TX_DP<11>")
	)
	(segment
		(start 361.779312 -224.720404)
		(end 361.780836 -224.721166)
		(width 0.1143)
		(layer "In6.Cu")
		(net "GMI_CPU1_G0_CPU0_G2_TX_DP<11>")
	)
	(segment
		(start 363.19079 -228.771196)
		(end 363.191806 -228.771704)
		(width 0.1143)
		(layer "In6.Cu")
		(net "GMI_CPU1_G0_CPU0_G2_TX_DP<11>")
	)
	(segment
		(start 363.192568 -233.631994)
		(end 363.193838 -233.632756)
		(width 0.1143)
		(layer "In6.Cu")
		(net "GMI_CPU1_G0_CPU0_G2_TX_DP<11>")
	)
	(segment
		(start 108.272326 -232.030016)
		(end 108.303314 -232.012236)
		(width 0.1143)
		(layer "In6.Cu")
		(net "GMI_CPU1_G0_CPU0_G2_TX_DP<11>")
	)
	(segment
		(start 108.311188 -235.247688)
		(end 108.343192 -235.228892)
		(width 0.1143)
		(layer "In6.Cu")
		(net "GMI_CPU1_G0_CPU0_G2_TX_DP<11>")
	)
	(segment
		(start 310.090566 -186.595004)
		(end 310.268112 -186.549792)
		(width 0.14224)
		(layer "In6.Cu")
		(net "GMI_CPU1_G0_CPU0_G2_TX_DP<11>")
	)
	(segment
		(start 364.712758 -238.004096)
		(end 364.414816 -238.004096)
		(width 0.1143)
		(layer "In6.Cu")
		(net "GMI_CPU1_G0_CPU0_G2_TX_DP<11>")
	)
	(segment
		(start 108.305092 -235.251244)
		(end 108.306616 -235.250228)
		(width 0.1143)
		(layer "In6.Cu")
		(net "GMI_CPU1_G0_CPU0_G2_TX_DP<11>")
	)
	(segment
		(start 361.780836 -224.721166)
		(end 361.781598 -224.721674)
		(width 0.1143)
		(layer "In6.Cu")
		(net "GMI_CPU1_G0_CPU0_G2_TX_DP<11>")
	)
	(segment
		(start 302.888904 -184.474866)
		(end 306.283106 -184.474866)
		(width 0.14224)
		(layer "In6.Cu")
		(net "GMI_CPU1_G0_CPU0_G2_TX_DP<11>")
	)
	(segment
		(start 363.192568 -228.772212)
		(end 363.193838 -228.772974)
		(width 0.1143)
		(layer "In6.Cu")
		(net "GMI_CPU1_G0_CPU0_G2_TX_DP<11>")
	)
	(segment
		(start 108.311188 -228.767894)
		(end 108.343192 -228.749098)
		(width 0.1143)
		(layer "In6.Cu")
		(net "GMI_CPU1_G0_CPU0_G2_TX_DP<11>")
	)
	(segment
		(start 363.15269 -227.128832)
		(end 363.189266 -227.150168)
		(width 0.1143)
		(layer "In6.Cu")
		(net "GMI_CPU1_G0_CPU0_G2_TX_DP<11>")
	)
	(segment
		(start 363.191806 -228.771704)
		(end 363.192568 -228.772212)
		(width 0.1143)
		(layer "In6.Cu")
		(net "GMI_CPU1_G0_CPU0_G2_TX_DP<11>")
	)
	(segment
		(start 360.042206 -221.17431)
		(end 360.042206 -221.202758)
		(width 0.1143)
		(layer "In6.Cu")
		(net "GMI_CPU1_G0_CPU0_G2_TX_DP<11>")
	)
	(segment
		(start 112.118902 -219.082366)
		(end 112.771682 -218.429586)
		(width 0.14224)
		(layer "In6.Cu")
		(net "GMI_CPU1_G0_CPU0_G2_TX_DP<11>")
	)
	(segment
		(start 363.189266 -227.798376)
		(end 363.15269 -227.819712)
		(width 0.1143)
		(layer "In6.Cu")
		(net "GMI_CPU1_G0_CPU0_G2_TX_DP<11>")
	)
	(segment
		(start 362.68279 -226.318826)
		(end 362.752386 -226.359466)
		(width 0.1143)
		(layer "In6.Cu")
		(net "GMI_CPU1_G0_CPU0_G2_TX_DP<11>")
	)
	(segment
		(start 362.24845 -225.528378)
		(end 362.251498 -225.530156)
		(width 0.1143)
		(layer "In6.Cu")
		(net "GMI_CPU1_G0_CPU0_G2_TX_DP<11>")
	)
	(segment
		(start 109.715046 -224.72142)
		(end 109.718094 -224.719642)
		(width 0.1143)
		(layer "In6.Cu")
		(net "GMI_CPU1_G0_CPU0_G2_TX_DP<11>")
	)
	(segment
		(start 361.777788 -224.719388)
		(end 361.779312 -224.720404)
		(width 0.1143)
		(layer "In6.Cu")
		(net "GMI_CPU1_G0_CPU0_G2_TX_DP<11>")
	)
	(segment
		(start 314.789312 -189.994794)
		(end 353.261422 -213.933024)
		(width 0.14224)
		(layer "In6.Cu")
		(net "GMI_CPU1_G0_CPU0_G2_TX_DP<11>")
	)
	(segment
		(start 310.675274 -186.948572)
		(end 311.0357 -187.16244)
		(width 0.14224)
		(layer "In6.Cu")
		(net "GMI_CPU1_G0_CPU0_G2_TX_DP<11>")
	)
	(segment
		(start 108.336334 -227.815902)
		(end 108.335572 -227.815394)
		(width 0.1143)
		(layer "In6.Cu")
		(net "GMI_CPU1_G0_CPU0_G2_TX_DP<11>")
	)
	(segment
		(start 235.596938 -184.083198)
		(end 235.596938 -184.083452)
		(width 0.14224)
		(layer "In6.Cu")
		(net "GMI_CPU1_G0_CPU0_G2_TX_DP<11>")
	)
	(segment
		(start 115.099592 -216.101676)
		(end 118.89613 -212.773006)
		(width 0.14224)
		(layer "In6.Cu")
		(net "GMI_CPU1_G0_CPU0_G2_TX_DP<11>")
	)
	(segment
		(start 108.304076 -229.416864)
		(end 108.270548 -229.397306)
		(width 0.1143)
		(layer "In6.Cu")
		(net "GMI_CPU1_G0_CPU0_G2_TX_DP<11>")
	)
	(segment
		(start 363.193838 -232.655364)
		(end 363.192568 -232.656126)
		(width 0.1143)
		(layer "In6.Cu")
		(net "GMI_CPU1_G0_CPU0_G2_TX_DP<11>")
	)
	(segment
		(start 363.19079 -232.657142)
		(end 363.189266 -232.658158)
		(width 0.1143)
		(layer "In6.Cu")
		(net "GMI_CPU1_G0_CPU0_G2_TX_DP<11>")
	)
	(segment
		(start 360.042206 -220.54693)
		(end 360.042206 -221.17431)
		(width 0.14224)
		(layer "In6.Cu")
		(net "GMI_CPU1_G0_CPU0_G2_TX_DP<11>")
	)
	(segment
		(start 363.191806 -233.631486)
		(end 363.192568 -233.631994)
		(width 0.1143)
		(layer "In6.Cu")
		(net "GMI_CPU1_G0_CPU0_G2_TX_DP<11>")
	)
	(segment
		(start 114.506756 -216.877646)
		(end 114.803428 -216.580974)
		(width 0.14224)
		(layer "In6.Cu")
		(net "GMI_CPU1_G0_CPU0_G2_TX_DP<11>")
	)
	(segment
		(start 363.191806 -227.796852)
		(end 363.19079 -227.79736)
		(width 0.1143)
		(layer "In6.Cu")
		(net "GMI_CPU1_G0_CPU0_G2_TX_DP<11>")
	)
	(segment
		(start 363.191806 -227.151692)
		(end 363.192568 -227.1522)
		(width 0.1143)
		(layer "In6.Cu")
		(net "GMI_CPU1_G0_CPU0_G2_TX_DP<11>")
	)
	(segment
		(start 109.243622 -225.530918)
		(end 109.244384 -225.53041)
		(width 0.1143)
		(layer "In6.Cu")
		(net "GMI_CPU1_G0_CPU0_G2_TX_DP<11>")
	)
	(segment
		(start 362.24083 -225.519234)
		(end 362.247688 -225.525076)
		(width 0.1143)
		(layer "In6.Cu")
		(net "GMI_CPU1_G0_CPU0_G2_TX_DP<11>")
	)
	(segment
		(start 111.09325 -222.310198)
		(end 111.125 -222.29191)
		(width 0.1143)
		(layer "In6.Cu")
		(net "GMI_CPU1_G0_CPU0_G2_TX_DP<11>")
	)
	(segment
		(start 363.193838 -234.275376)
		(end 363.192568 -234.276138)
		(width 0.1143)
		(layer "In6.Cu")
		(net "GMI_CPU1_G0_CPU0_G2_TX_DP<11>")
	)
	(segment
		(start 360.087926 -221.248478)
		(end 360.087926 -221.702122)
		(width 0.1143)
		(layer "In6.Cu")
		(net "GMI_CPU1_G0_CPU0_G2_TX_DP<11>")
	)
	(segment
		(start 364.782608 -237.934246)
		(end 364.712758 -238.004096)
		(width 0.1143)
		(layer "In6.Cu")
		(net "GMI_CPU1_G0_CPU0_G2_TX_DP<11>")
	)
	(segment
		(start 364.60176 -237.681516)
		(end 364.602522 -237.682024)
		(width 0.1143)
		(layer "In6.Cu")
		(net "GMI_CPU1_G0_CPU0_G2_TX_DP<11>")
	)
	(segment
		(start 307.196998 -184.725818)
		(end 309.684674 -186.203336)
		(width 0.14224)
		(layer "In6.Cu")
		(net "GMI_CPU1_G0_CPU0_G2_TX_DP<11>")
	)
	(segment
		(start 363.193838 -227.152962)
		(end 363.223556 -227.16998)
		(width 0.1143)
		(layer "In6.Cu")
		(net "GMI_CPU1_G0_CPU0_G2_TX_DP<11>")
	)
	(segment
		(start 111.125 -222.29191)
		(end 111.164116 -222.26905)
		(width 0.1143)
		(layer "In6.Cu")
		(net "GMI_CPU1_G0_CPU0_G2_TX_DP<11>")
	)
	(segment
		(start 108.304076 -234.2769)
		(end 108.303314 -234.276392)
		(width 0.1143)
		(layer "In6.Cu")
		(net "GMI_CPU1_G0_CPU0_G2_TX_DP<11>")
	)
	(segment
		(start 111.407448 -221.702884)
		(end 111.407956 -221.702376)
		(width 0.1143)
		(layer "In6.Cu")
		(net "GMI_CPU1_G0_CPU0_G2_TX_DP<11>")
	)
	(segment
		(start 109.247432 -225.528632)
		(end 109.248194 -225.52533)
		(width 0.1143)
		(layer "In6.Cu")
		(net "GMI_CPU1_G0_CPU0_G2_TX_DP<11>")
	)
	(segment
		(start 108.343192 -231.059736)
		(end 108.304076 -231.036876)
		(width 0.1143)
		(layer "In6.Cu")
		(net "GMI_CPU1_G0_CPU0_G2_TX_DP<11>")
	)
	(segment
		(start 363.223556 -227.778564)
		(end 363.193838 -227.795582)
		(width 0.1143)
		(layer "In6.Cu")
		(net "GMI_CPU1_G0_CPU0_G2_TX_DP<11>")
	)
	(segment
		(start 108.343192 -232.679748)
		(end 108.336334 -232.675684)
		(width 0.1143)
		(layer "In6.Cu")
		(net "GMI_CPU1_G0_CPU0_G2_TX_DP<11>")
	)
	(segment
		(start 363.189266 -233.629962)
		(end 363.19079 -233.630978)
		(width 0.1143)
		(layer "In6.Cu")
		(net "GMI_CPU1_G0_CPU0_G2_TX_DP<11>")
	)
	(segment
		(start 108.306616 -235.250228)
		(end 108.311188 -235.247688)
		(width 0.1143)
		(layer "In6.Cu")
		(net "GMI_CPU1_G0_CPU0_G2_TX_DP<11>")
	)
	(segment
		(start 106.862372 -237.700058)
		(end 106.89336 -237.682278)
		(width 0.1143)
		(layer "In6.Cu")
		(net "GMI_CPU1_G0_CPU0_G2_TX_DP<11>")
	)
	(segment
		(start 108.335572 -232.675176)
		(end 108.304076 -232.656888)
		(width 0.1143)
		(layer "In6.Cu")
		(net "GMI_CPU1_G0_CPU0_G2_TX_DP<11>")
	)
	(segment
		(start 363.15269 -228.748844)
		(end 363.189266 -228.77018)
		(width 0.1143)
		(layer "In6.Cu")
		(net "GMI_CPU1_G0_CPU0_G2_TX_DP<11>")
	)
	(segment
		(start 108.304076 -232.011728)
		(end 108.305092 -232.01122)
		(width 0.1143)
		(layer "In6.Cu")
		(net "GMI_CPU1_G0_CPU0_G2_TX_DP<11>")
	)
	(segment
		(start 364.602522 -237.682024)
		(end 364.603792 -237.682786)
		(width 0.1143)
		(layer "In6.Cu")
		(net "GMI_CPU1_G0_CPU0_G2_TX_DP<11>")
	)
	(segment
		(start 311.9882 -187.728098)
		(end 312.172604 -187.681108)
		(width 0.14224)
		(layer "In6.Cu")
		(net "GMI_CPU1_G0_CPU0_G2_TX_DP<11>")
	)
	(segment
		(start 113.547652 -217.653616)
		(end 113.730786 -217.653616)
		(width 0.14224)
		(layer "In6.Cu")
		(net "GMI_CPU1_G0_CPU0_G2_TX_DP<11>")
	)
	(segment
		(start 311.58053 -187.329318)
		(end 311.62752 -187.513976)
		(width 0.14224)
		(layer "In6.Cu")
		(net "GMI_CPU1_G0_CPU0_G2_TX_DP<11>")
	)
	(segment
		(start 364.132622 -236.872018)
		(end 364.162594 -236.88929)
		(width 0.1143)
		(layer "In6.Cu")
		(net "GMI_CPU1_G0_CPU0_G2_TX_DP<11>")
	)
	(segment
		(start 108.311188 -232.007664)
		(end 108.343192 -231.988868)
		(width 0.1143)
		(layer "In6.Cu")
		(net "GMI_CPU1_G0_CPU0_G2_TX_DP<11>")
	)
	(segment
		(start 108.303314 -227.796598)
		(end 108.302044 -227.795836)
		(width 0.1143)
		(layer "In6.Cu")
		(net "GMI_CPU1_G0_CPU0_G2_TX_DP<11>")
	)
	(segment
		(start 107.081066 -238.00435)
		(end 106.783124 -238.00435)
		(width 0.1143)
		(layer "In6.Cu")
		(net "GMI_CPU1_G0_CPU0_G2_TX_DP<11>")
	)
	(segment
		(start 360.841798 -223.10217)
		(end 360.843068 -223.102932)
		(width 0.1143)
		(layer "In6.Cu")
		(net "GMI_CPU1_G0_CPU0_G2_TX_DP<11>")
	)
	(segment
		(start 109.243368 -225.531172)
		(end 109.243622 -225.530918)
		(width 0.1143)
		(layer "In6.Cu")
		(net "GMI_CPU1_G0_CPU0_G2_TX_DP<11>")
	)
	(segment
		(start 108.272326 -230.410258)
		(end 108.304076 -230.39197)
		(width 0.1143)
		(layer "In6.Cu")
		(net "GMI_CPU1_G0_CPU0_G2_TX_DP<11>")
	)
	(segment
		(start 107.833922 -236.061758)
		(end 107.873038 -236.038898)
		(width 0.1143)
		(layer "In6.Cu")
		(net "GMI_CPU1_G0_CPU0_G2_TX_DP<11>")
	)
	(segment
		(start 363.189266 -228.77018)
		(end 363.19079 -228.771196)
		(width 0.1143)
		(layer "In6.Cu")
		(net "GMI_CPU1_G0_CPU0_G2_TX_DP<11>")
	)
	(segment
		(start 108.304076 -230.39197)
		(end 108.340652 -230.370634)
		(width 0.1143)
		(layer "In6.Cu")
		(net "GMI_CPU1_G0_CPU0_G2_TX_DP<11>")
	)
	(segment
		(start 363.192568 -227.1522)
		(end 363.193838 -227.152962)
		(width 0.1143)
		(layer "In6.Cu")
		(net "GMI_CPU1_G0_CPU0_G2_TX_DP<11>")
	)
	(segment
		(start 363.19079 -227.79736)
		(end 363.189266 -227.798376)
		(width 0.1143)
		(layer "In6.Cu")
		(net "GMI_CPU1_G0_CPU0_G2_TX_DP<11>")
	)
	(segment
		(start 107.36326 -236.872272)
		(end 107.364022 -236.871764)
		(width 0.1143)
		(layer "In6.Cu")
		(net "GMI_CPU1_G0_CPU0_G2_TX_DP<11>")
	)
	(segment
		(start 108.335572 -227.815394)
		(end 108.304076 -227.797106)
		(width 0.1143)
		(layer "In6.Cu")
		(net "GMI_CPU1_G0_CPU0_G2_TX_DP<11>")
	)
	(segment
		(start 108.303314 -234.276392)
		(end 108.302044 -234.27563)
		(width 0.1143)
		(layer "In6.Cu")
		(net "GMI_CPU1_G0_CPU0_G2_TX_DP<11>")
	)
	(segment
		(start 363.19079 -232.010966)
		(end 363.191806 -232.011474)
		(width 0.1143)
		(layer "In6.Cu")
		(net "GMI_CPU1_G0_CPU0_G2_TX_DP<11>")
	)
	(segment
		(start 108.305092 -232.01122)
		(end 108.306616 -232.010204)
		(width 0.1143)
		(layer "In6.Cu")
		(net "GMI_CPU1_G0_CPU0_G2_TX_DP<11>")
	)
	(segment
		(start 113.730786 -217.653616)
		(end 114.027458 -217.356944)
		(width 0.14224)
		(layer "In6.Cu")
		(net "GMI_CPU1_G0_CPU0_G2_TX_DP<11>")
	)
	(segment
		(start 363.15269 -233.608626)
		(end 363.189266 -233.629962)
		(width 0.1143)
		(layer "In6.Cu")
		(net "GMI_CPU1_G0_CPU0_G2_TX_DP<11>")
	)
	(segment
		(start 108.306616 -233.630216)
		(end 108.311188 -233.627676)
		(width 0.1143)
		(layer "In6.Cu")
		(net "GMI_CPU1_G0_CPU0_G2_TX_DP<11>")
	)
	(segment
		(start 106.895646 -237.681008)
		(end 106.923586 -237.664498)
		(width 0.1143)
		(layer "In6.Cu")
		(net "GMI_CPU1_G0_CPU0_G2_TX_DP<11>")
	)
	(segment
		(start 363.225334 -229.397052)
		(end 363.15269 -229.43947)
		(width 0.1143)
		(layer "In6.Cu")
		(net "GMI_CPU1_G0_CPU0_G2_TX_DP<11>")
	)
	(segment
		(start 108.303314 -232.65638)
		(end 108.302044 -232.655618)
		(width 0.1143)
		(layer "In6.Cu")
		(net "GMI_CPU1_G0_CPU0_G2_TX_DP<11>")
	)
	(segment
		(start 309.684674 -186.203336)
		(end 309.729886 -186.380882)
		(width 0.14224)
		(layer "In6.Cu")
		(net "GMI_CPU1_G0_CPU0_G2_TX_DP<11>")
	)
	(segment
		(start 108.305092 -233.631232)
		(end 108.306616 -233.630216)
		(width 0.1143)
		(layer "In6.Cu")
		(net "GMI_CPU1_G0_CPU0_G2_TX_DP<11>")
	)
	(segment
		(start 133.417564 -202.788266)
		(end 164.953696 -184.579006)
		(width 0.14224)
		(layer "In6.Cu")
		(net "GMI_CPU1_G0_CPU0_G2_TX_DP<11>")
	)
	(segment
		(start 108.303314 -235.25226)
		(end 108.304076 -235.251752)
		(width 0.1143)
		(layer "In6.Cu")
		(net "GMI_CPU1_G0_CPU0_G2_TX_DP<11>")
	)
	(segment
		(start 108.304076 -232.656888)
		(end 108.303314 -232.65638)
		(width 0.1143)
		(layer "In6.Cu")
		(net "GMI_CPU1_G0_CPU0_G2_TX_DP<11>")
	)
	(segment
		(start 362.251498 -225.530156)
		(end 362.25226 -225.530664)
		(width 0.1143)
		(layer "In6.Cu")
		(net "GMI_CPU1_G0_CPU0_G2_TX_DP<11>")
	)
	(segment
		(start 353.261422 -213.933024)
		(end 356.919276 -216.836244)
		(width 0.14224)
		(layer "In6.Cu")
		(net "GMI_CPU1_G0_CPU0_G2_TX_DP<11>")
	)
	(segment
		(start 360.370882 -222.291656)
		(end 360.402632 -222.309944)
		(width 0.1143)
		(layer "In6.Cu")
		(net "GMI_CPU1_G0_CPU0_G2_TX_DP<11>")
	)
	(segment
		(start 360.087926 -221.702122)
		(end 360.088434 -221.70263)
		(width 0.1143)
		(layer "In6.Cu")
		(net "GMI_CPU1_G0_CPU0_G2_TX_DP<11>")
	)
	(segment
		(start 363.189266 -234.27817)
		(end 363.15269 -234.299506)
		(width 0.1143)
		(layer "In6.Cu")
		(net "GMI_CPU1_G0_CPU0_G2_TX_DP<11>")
	)
	(segment
		(start 314.294774 -189.690502)
		(end 314.48502 -189.690502)
		(width 0.14224)
		(layer "In6.Cu")
		(net "GMI_CPU1_G0_CPU0_G2_TX_DP<11>")
	)
	(segment
		(start 306.283106 -184.474866)
		(end 307.196998 -184.725818)
		(width 0.14224)
		(layer "In6.Cu")
		(net "GMI_CPU1_G0_CPU0_G2_TX_DP<11>")
	)
	(segment
		(start 314.48502 -189.690502)
		(end 314.789312 -189.994794)
		(width 0.14224)
		(layer "In6.Cu")
		(net "GMI_CPU1_G0_CPU0_G2_TX_DP<11>")
	)
	(segment
		(start 108.303314 -233.632248)
		(end 108.304076 -233.63174)
		(width 0.1143)
		(layer "In6.Cu")
		(net "GMI_CPU1_G0_CPU0_G2_TX_DP<11>")
	)
	(segment
		(start 360.838496 -223.100138)
		(end 360.84002 -223.101154)
		(width 0.1143)
		(layer "In6.Cu")
		(net "GMI_CPU1_G0_CPU0_G2_TX_DP<11>")
	)
	(segment
		(start 108.336334 -234.295696)
		(end 108.335572 -234.295188)
		(width 0.1143)
		(layer "In6.Cu")
		(net "GMI_CPU1_G0_CPU0_G2_TX_DP<11>")
	)
	(segment
		(start 106.89336 -237.682278)
		(end 106.894122 -237.68177)
		(width 0.1143)
		(layer "In6.Cu")
		(net "GMI_CPU1_G0_CPU0_G2_TX_DP<11>")
	)
	(segment
		(start 113.251488 -217.94978)
		(end 113.547652 -217.653616)
		(width 0.14224)
		(layer "In6.Cu")
		(net "GMI_CPU1_G0_CPU0_G2_TX_DP<11>")
	)
	(segment
		(start 110.655862 -223.101408)
		(end 110.657386 -223.100392)
		(width 0.1143)
		(layer "In6.Cu")
		(net "GMI_CPU1_G0_CPU0_G2_TX_DP<11>")
	)
	(segment
		(start 362.247688 -225.525076)
		(end 362.24845 -225.528378)
		(width 0.1143)
		(layer "In6.Cu")
		(net "GMI_CPU1_G0_CPU0_G2_TX_DP<11>")
	)
	(segment
		(start 363.15269 -231.988614)
		(end 363.189266 -232.00995)
		(width 0.1143)
		(layer "In6.Cu")
		(net "GMI_CPU1_G0_CPU0_G2_TX_DP<11>")
	)
	(segment
		(start 110.661958 -223.097852)
		(end 110.693962 -223.079056)
		(width 0.1143)
		(layer "In6.Cu")
		(net "GMI_CPU1_G0_CPU0_G2_TX_DP<11>")
	)
	(segment
		(start 363.223556 -232.638346)
		(end 363.193838 -232.655364)
		(width 0.1143)
		(layer "In6.Cu")
		(net "GMI_CPU1_G0_CPU0_G2_TX_DP<11>")
	)
	(segment
		(start 110.654084 -223.102424)
		(end 110.654846 -223.101916)
		(width 0.1143)
		(layer "In6.Cu")
		(net "GMI_CPU1_G0_CPU0_G2_TX_DP<11>")
	)
	(segment
		(start 114.803428 -216.39784)
		(end 115.099592 -216.101676)
		(width 0.14224)
		(layer "In6.Cu")
		(net "GMI_CPU1_G0_CPU0_G2_TX_DP<11>")
	)
	(segment
		(start 112.954816 -218.429586)
		(end 113.251488 -218.132914)
		(width 0.14224)
		(layer "In6.Cu")
		(net "GMI_CPU1_G0_CPU0_G2_TX_DP<11>")
	)
	(segment
		(start 364.600236 -237.680754)
		(end 364.60176 -237.681516)
		(width 0.1143)
		(layer "In6.Cu")
		(net "GMI_CPU1_G0_CPU0_G2_TX_DP<11>")
	)
	(segment
		(start 114.027458 -217.356944)
		(end 114.027458 -217.17381)
		(width 0.14224)
		(layer "In6.Cu")
		(net "GMI_CPU1_G0_CPU0_G2_TX_DP<11>")
	)
	(segment
		(start 310.268112 -186.549792)
		(end 310.268112 -186.550046)
		(width 0.14224)
		(layer "In6.Cu")
		(net "GMI_CPU1_G0_CPU0_G2_TX_DP<11>")
	)
	(segment
		(start 310.628284 -186.76366)
		(end 310.675274 -186.948572)
		(width 0.14224)
		(layer "In6.Cu")
		(net "GMI_CPU1_G0_CPU0_G2_TX_DP<11>")
	)
	(segment
		(start 107.803442 -236.079538)
		(end 107.833922 -236.061758)
		(width 0.1143)
		(layer "In6.Cu")
		(net "GMI_CPU1_G0_CPU0_G2_TX_DP<11>")
	)
	(segment
		(start 114.803428 -216.580974)
		(end 114.803428 -216.39784)
		(width 0.14224)
		(layer "In6.Cu")
		(net "GMI_CPU1_G0_CPU0_G2_TX_DP<11>")
	)
	(segment
		(start 111.453676 -221.203012)
		(end 111.453676 -221.174564)
		(width 0.1143)
		(layer "In6.Cu")
		(net "GMI_CPU1_G0_CPU0_G2_TX_DP<11>")
	)
	(segment
		(start 111.407448 -221.804484)
		(end 111.407448 -221.702884)
		(width 0.1143)
		(layer "In6.Cu")
		(net "GMI_CPU1_G0_CPU0_G2_TX_DP<11>")
	)
	(segment
		(start 310.268112 -186.550046)
		(end 310.62803 -186.763914)
		(width 0.14224)
		(layer "In6.Cu")
		(net "GMI_CPU1_G0_CPU0_G2_TX_DP<11>")
	)
	(segment
		(start 107.366562 -236.87024)
		(end 107.403138 -236.848904)
		(width 0.1143)
		(layer "In6.Cu")
		(net "GMI_CPU1_G0_CPU0_G2_TX_DP<11>")
	)
	(segment
		(start 109.714284 -224.721928)
		(end 109.715046 -224.72142)
		(width 0.1143)
		(layer "In6.Cu")
		(net "GMI_CPU1_G0_CPU0_G2_TX_DP<11>")
	)
	(segment
		(start 363.189266 -232.00995)
		(end 363.19079 -232.010966)
		(width 0.1143)
		(layer "In6.Cu")
		(net "GMI_CPU1_G0_CPU0_G2_TX_DP<11>")
	)
	(segment
		(start 108.743496 -226.35972)
		(end 108.813092 -226.31908)
		(width 0.1143)
		(layer "In6.Cu")
		(net "GMI_CPU1_G0_CPU0_G2_TX_DP<11>")
	)
	(segment
		(start 313.21502 -188.420502)
		(end 313.21502 -188.611002)
		(width 0.14224)
		(layer "In6.Cu")
		(net "GMI_CPU1_G0_CPU0_G2_TX_DP<11>")
	)
	(segment
		(start 363.225334 -231.017064)
		(end 363.15269 -231.059482)
		(width 0.1143)
		(layer "In6.Cu")
		(net "GMI_CPU1_G0_CPU0_G2_TX_DP<11>")
	)
	(segment
		(start 362.233464 -225.514662)
		(end 362.24083 -225.519234)
		(width 0.1143)
		(layer "In6.Cu")
		(net "GMI_CPU1_G0_CPU0_G2_TX_DP<11>")
	)
	(segment
		(start 107.364022 -236.871764)
		(end 107.365038 -236.871256)
		(width 0.1143)
		(layer "In6.Cu")
		(net "GMI_CPU1_G0_CPU0_G2_TX_DP<11>")
	)
	(segment
		(start 309.729886 -186.380882)
		(end 310.090566 -186.595004)
		(width 0.14224)
		(layer "In6.Cu")
		(net "GMI_CPU1_G0_CPU0_G2_TX_DP<11>")
	)
	(segment
		(start 364.092744 -236.84865)
		(end 364.12932 -236.869986)
		(width 0.1143)
		(layer "In6.Cu")
		(net "GMI_CPU1_G0_CPU0_G2_TX_DP<11>")
	)
	(segment
		(start 313.998102 -189.394084)
		(end 314.294774 -189.690502)
		(width 0.14224)
		(layer "In6.Cu")
		(net "GMI_CPU1_G0_CPU0_G2_TX_DP<11>")
	)
	(segment
		(start 107.365038 -236.871256)
		(end 107.366562 -236.87024)
		(width 0.1143)
		(layer "In6.Cu")
		(net "GMI_CPU1_G0_CPU0_G2_TX_DP<11>")
	)
	(segment
		(start 112.771682 -218.429586)
		(end 112.954816 -218.429586)
		(width 0.14224)
		(layer "In6.Cu")
		(net "GMI_CPU1_G0_CPU0_G2_TX_DP<11>")
	)
	(segment
		(start 312.172604 -187.681108)
		(end 312.918856 -188.124338)
		(width 0.14224)
		(layer "In6.Cu")
		(net "GMI_CPU1_G0_CPU0_G2_TX_DP<11>")
	)
	(segment
		(start 363.191806 -235.251498)
		(end 363.192568 -235.252006)
		(width 0.1143)
		(layer "In6.Cu")
		(net "GMI_CPU1_G0_CPU0_G2_TX_DP<11>")
	)
	(segment
		(start 360.841036 -223.101662)
		(end 360.841798 -223.10217)
		(width 0.1143)
		(layer "In6.Cu")
		(net "GMI_CPU1_G0_CPU0_G2_TX_DP<11>")
	)
	(segment
		(start 110.15091 -223.93148)
		(end 110.223808 -223.889062)
		(width 0.1143)
		(layer "In6.Cu")
		(net "GMI_CPU1_G0_CPU0_G2_TX_DP<11>")
	)
	(segment
		(start 113.251488 -218.132914)
		(end 113.251488 -217.94978)
		(width 0.14224)
		(layer "In6.Cu")
		(net "GMI_CPU1_G0_CPU0_G2_TX_DP<11>")
	)
	(segment
		(start 108.272326 -235.27004)
		(end 108.303314 -235.25226)
		(width 0.1143)
		(layer "In6.Cu")
		(net "GMI_CPU1_G0_CPU0_G2_TX_DP<11>")
	)
	(segment
		(start 363.189266 -235.249974)
		(end 363.19079 -235.25099)
		(width 0.1143)
		(layer "In6.Cu")
		(net "GMI_CPU1_G0_CPU0_G2_TX_DP<11>")
	)
	(segment
		(start 363.19079 -234.277154)
		(end 363.189266 -234.27817)
		(width 0.1143)
		(layer "In6.Cu")
		(net "GMI_CPU1_G0_CPU0_G2_TX_DP<11>")
	)
	(segment
		(start 108.272326 -227.170234)
		(end 108.303314 -227.152454)
		(width 0.1143)
		(layer "In6.Cu")
		(net "GMI_CPU1_G0_CPU0_G2_TX_DP<11>")
	)
	(segment
		(start 363.15523 -230.37038)
		(end 363.191806 -230.391716)
		(width 0.1143)
		(layer "In6.Cu")
		(net "GMI_CPU1_G0_CPU0_G2_TX_DP<11>")
	)
	(segment
		(start 363.192568 -235.252006)
		(end 363.193838 -235.252768)
		(width 0.1143)
		(layer "In6.Cu")
		(net "GMI_CPU1_G0_CPU0_G2_TX_DP<11>")
	)
	(segment
		(start 108.335572 -234.295188)
		(end 108.304076 -234.2769)
		(width 0.1143)
		(layer "In6.Cu")
		(net "GMI_CPU1_G0_CPU0_G2_TX_DP<11>")
	)
	(segment
		(start 108.272326 -228.790246)
		(end 108.303314 -228.772466)
		(width 0.1143)
		(layer "In6.Cu")
		(net "GMI_CPU1_G0_CPU0_G2_TX_DP<11>")
	)
	(segment
		(start 363.193838 -232.012744)
		(end 363.223556 -232.029762)
		(width 0.1143)
		(layer "In6.Cu")
		(net "GMI_CPU1_G0_CPU0_G2_TX_DP<11>")
	)
	(segment
		(start 108.304076 -227.797106)
		(end 108.303314 -227.796598)
		(width 0.1143)
		(layer "In6.Cu")
		(net "GMI_CPU1_G0_CPU0_G2_TX_DP<11>")
	)
	(segment
		(start 108.302044 -232.655618)
		(end 108.272326 -232.6386)
		(width 0.1143)
		(layer "In6.Cu")
		(net "GMI_CPU1_G0_CPU0_G2_TX_DP<11>")
	)
	(segment
		(start 235.596938 -184.083452)
		(end 302.888904 -184.474866)
		(width 0.14224)
		(layer "In6.Cu")
		(net "GMI_CPU1_G0_CPU0_G2_TX_DP<11>")
	)
	(segment
		(start 108.304076 -231.036876)
		(end 108.270548 -231.017318)
		(width 0.1143)
		(layer "In6.Cu")
		(net "GMI_CPU1_G0_CPU0_G2_TX_DP<11>")
	)
	(segment
		(start 111.407956 -221.248732)
		(end 111.453676 -221.203012)
		(width 0.1143)
		(layer "In6.Cu")
		(net "GMI_CPU1_G0_CPU0_G2_TX_DP<11>")
	)
	(segment
		(start 311.220358 -187.11545)
		(end 311.58053 -187.329318)
		(width 0.14224)
		(layer "In6.Cu")
		(net "GMI_CPU1_G0_CPU0_G2_TX_DP<11>")
	)
	(segment
		(start 311.0357 -187.16244)
		(end 311.220358 -187.11545)
		(width 0.14224)
		(layer "In6.Cu")
		(net "GMI_CPU1_G0_CPU0_G2_TX_DP<11>")
	)
	(segment
		(start 108.303314 -232.012236)
		(end 108.304076 -232.011728)
		(width 0.1143)
		(layer "In6.Cu")
		(net "GMI_CPU1_G0_CPU0_G2_TX_DP<11>")
	)
	(segment
		(start 363.189266 -232.658158)
		(end 363.15269 -232.679494)
		(width 0.1143)
		(layer "In6.Cu")
		(net "GMI_CPU1_G0_CPU0_G2_TX_DP<11>")
	)
	(segment
		(start 121.735342 -210.594702)
		(end 133.417564 -202.788266)
		(width 0.14224)
		(layer "In6.Cu")
		(net "GMI_CPU1_G0_CPU0_G2_TX_DP<11>")
	)
	(segment
		(start 109.244384 -225.53041)
		(end 109.247432 -225.528632)
		(width 0.1143)
		(layer "In6.Cu")
		(net "GMI_CPU1_G0_CPU0_G2_TX_DP<11>")
	)
	(segment
		(start 111.407956 -221.702376)
		(end 111.407956 -221.248732)
		(width 0.1143)
		(layer "In6.Cu")
		(net "GMI_CPU1_G0_CPU0_G2_TX_DP<11>")
	)
	(segment
		(start 110.657386 -223.100392)
		(end 110.661958 -223.097852)
		(width 0.1143)
		(layer "In6.Cu")
		(net "GMI_CPU1_G0_CPU0_G2_TX_DP<11>")
	)
	(segment
		(start 313.511692 -188.90742)
		(end 313.701938 -188.90742)
		(width 0.14224)
		(layer "In6.Cu")
		(net "GMI_CPU1_G0_CPU0_G2_TX_DP<11>")
	)
	(segment
		(start 360.84002 -223.101154)
		(end 360.841036 -223.101662)
		(width 0.1143)
		(layer "In6.Cu")
		(net "GMI_CPU1_G0_CPU0_G2_TX_DP<11>")
	)
	(segment
		(start 360.088434 -221.70263)
		(end 360.088434 -221.80423)
		(width 0.1143)
		(layer "In6.Cu")
		(net "GMI_CPU1_G0_CPU0_G2_TX_DP<11>")
	)
	(segment
		(start 108.336334 -232.675684)
		(end 108.335572 -232.675176)
		(width 0.1143)
		(layer "In6.Cu")
		(net "GMI_CPU1_G0_CPU0_G2_TX_DP<11>")
	)
	(segment
		(start 364.603792 -237.682786)
		(end 364.63351 -237.699804)
		(width 0.1143)
		(layer "In6.Cu")
		(net "GMI_CPU1_G0_CPU0_G2_TX_DP<11>")
	)
	(segment
		(start 108.303314 -228.772466)
		(end 108.304076 -228.771958)
		(width 0.1143)
		(layer "In6.Cu")
		(net "GMI_CPU1_G0_CPU0_G2_TX_DP<11>")
	)
	(segment
		(start 108.306616 -227.150422)
		(end 108.311188 -227.147882)
		(width 0.1143)
		(layer "In6.Cu")
		(net "GMI_CPU1_G0_CPU0_G2_TX_DP<11>")
	)
	(segment
		(start 363.192568 -232.656126)
		(end 363.191806 -232.656634)
		(width 0.1143)
		(layer "In6.Cu")
		(net "GMI_CPU1_G0_CPU0_G2_TX_DP<11>")
	)
	(segment
		(start 363.193838 -233.632756)
		(end 363.223556 -233.649774)
		(width 0.1143)
		(layer "In6.Cu")
		(net "GMI_CPU1_G0_CPU0_G2_TX_DP<11>")
	)
	(segment
		(start 110.623096 -223.120204)
		(end 110.654084 -223.102424)
		(width 0.1143)
		(layer "In6.Cu")
		(net "GMI_CPU1_G0_CPU0_G2_TX_DP<11>")
	)
	(segment
		(start 114.323622 -216.877646)
		(end 114.506756 -216.877646)
		(width 0.14224)
		(layer "In6.Cu")
		(net "GMI_CPU1_G0_CPU0_G2_TX_DP<11>")
	)
	(segment
		(start 108.304076 -227.151946)
		(end 108.305092 -227.151438)
		(width 0.1143)
		(layer "In6.Cu")
		(net "GMI_CPU1_G0_CPU0_G2_TX_DP<11>")
	)
	(segment
		(start 363.191806 -230.391716)
		(end 363.223556 -230.410004)
		(width 0.1143)
		(layer "In6.Cu")
		(net "GMI_CPU1_G0_CPU0_G2_TX_DP<11>")
	)
	(segment
		(start 363.189266 -227.150168)
		(end 363.19079 -227.151184)
		(width 0.1143)
		(layer "In6.Cu")
		(net "GMI_CPU1_G0_CPU0_G2_TX_DP<11>")
	)
	(segment
		(start 108.304076 -233.63174)
		(end 108.305092 -233.631232)
		(width 0.1143)
		(layer "In6.Cu")
		(net "GMI_CPU1_G0_CPU0_G2_TX_DP<11>")
	)
	(segment
		(start 363.191806 -232.656634)
		(end 363.19079 -232.657142)
		(width 0.1143)
		(layer "In6.Cu")
		(net "GMI_CPU1_G0_CPU0_G2_TX_DP<11>")
	)
	(segment
		(start 108.311188 -227.147882)
		(end 108.343192 -227.129086)
		(width 0.1143)
		(layer "In6.Cu")
		(net "GMI_CPU1_G0_CPU0_G2_TX_DP<11>")
	)
	(segment
		(start 108.304076 -235.251752)
		(end 108.305092 -235.251244)
		(width 0.1143)
		(layer "In6.Cu")
		(net "GMI_CPU1_G0_CPU0_G2_TX_DP<11>")
	)
	(segment
		(start 109.683804 -224.739708)
		(end 109.714284 -224.721928)
		(width 0.1143)
		(layer "In6.Cu")
		(net "GMI_CPU1_G0_CPU0_G2_TX_DP<11>")
	)
	(segment
		(start 108.272326 -233.650028)
		(end 108.303314 -233.632248)
		(width 0.1143)
		(layer "In6.Cu")
		(net "GMI_CPU1_G0_CPU0_G2_TX_DP<11>")
	)
	(segment
		(start 360.331766 -222.268796)
		(end 360.370882 -222.291656)
		(width 0.1143)
		(layer "In6.Cu")
		(net "GMI_CPU1_G0_CPU0_G2_TX_DP<11>")
	)
	(segment
		(start 108.302044 -227.795836)
		(end 108.272326 -227.778818)
		(width 0.1143)
		(layer "In6.Cu")
		(net "GMI_CPU1_G0_CPU0_G2_TX_DP<11>")
	)
	(segment
		(start 114.027458 -217.17381)
		(end 114.323622 -216.877646)
		(width 0.14224)
		(layer "In6.Cu")
		(net "GMI_CPU1_G0_CPU0_G2_TX_DP<11>")
	)
	(segment
		(start 313.998102 -189.203584)
		(end 313.998102 -189.394084)
		(width 0.14224)
		(layer "In6.Cu")
		(net "GMI_CPU1_G0_CPU0_G2_TX_DP<11>")
	)
	(segment
		(start 361.272074 -223.888808)
		(end 361.344972 -223.931226)
		(width 0.1143)
		(layer "In6.Cu")
		(net "GMI_CPU1_G0_CPU0_G2_TX_DP<11>")
	)
	(segment
		(start 310.62803 -186.763914)
		(end 310.628284 -186.76366)
		(width 0.14224)
		(layer "In6.Cu")
		(net "GMI_CPU1_G0_CPU0_G2_TX_DP<11>")
	)
	(segment
		(start 108.311188 -233.627676)
		(end 108.343192 -233.60888)
		(width 0.1143)
		(layer "In6.Cu")
		(net "GMI_CPU1_G0_CPU0_G2_TX_DP<11>")
	)
	(segment
		(start 111.453676 -221.174564)
		(end 111.453676 -220.688154)
		(width 0.14224)
		(layer "In6.Cu")
		(net "GMI_CPU1_G0_CPU0_G2_TX_DP<11>")
	)
	(segment
		(start 106.923586 -237.664498)
		(end 106.930444 -237.660688)
		(width 0.1143)
		(layer "In6.Cu")
		(net "GMI_CPU1_G0_CPU0_G2_TX_DP<11>")
	)
	(segment
		(start 363.622844 -236.038644)
		(end 363.69244 -236.079284)
		(width 0.1143)
		(layer "In6.Cu")
		(net "GMI_CPU1_G0_CPU0_G2_TX_DP<11>")
	)
	(segment
		(start 108.304076 -228.771958)
		(end 108.305092 -228.77145)
		(width 0.1143)
		(layer "In6.Cu")
		(net "GMI_CPU1_G0_CPU0_G2_TX_DP<11>")
	)
	(segment
		(start 106.783124 -238.00435)
		(end 106.713274 -237.9345)
		(width 0.1143)
		(layer "In6.Cu")
		(net "GMI_CPU1_G0_CPU0_G2_TX_DP<11>")
	)
	(segment
		(start 108.305092 -227.151438)
		(end 108.306616 -227.150422)
		(width 0.1143)
		(layer "In6.Cu")
		(net "GMI_CPU1_G0_CPU0_G2_TX_DP<11>")
	)
	(segment
		(start 363.191806 -232.011474)
		(end 363.192568 -232.011982)
		(width 0.1143)
		(layer "In6.Cu")
		(net "GMI_CPU1_G0_CPU0_G2_TX_DP<11>")
	)
	(segment
		(start 363.192568 -234.276138)
		(end 363.191806 -234.276646)
		(width 0.1143)
		(layer "In6.Cu")
		(net "GMI_CPU1_G0_CPU0_G2_TX_DP<11>")
	)
	(segment
		(start 108.343192 -234.29976)
		(end 108.336334 -234.295696)
		(width 0.1143)
		(layer "In6.Cu")
		(net "GMI_CPU1_G0_CPU0_G2_TX_DP<11>")
	)
	(segment
		(start 109.255052 -225.519488)
		(end 109.262418 -225.514916)
		(width 0.1143)
		(layer "In6.Cu")
		(net "GMI_CPU1_G0_CPU0_G2_TX_DP<11>")
	)
	(segment
		(start 168.304464 -183.691276)
		(end 235.596938 -184.083198)
		(width 0.14224)
		(layer "In6.Cu")
		(net "GMI_CPU1_G0_CPU0_G2_TX_DP<11>")
	)
	(segment
		(start 109.248194 -225.52533)
		(end 109.255052 -225.519488)
		(width 0.1143)
		(layer "In6.Cu")
		(net "GMI_CPU1_G0_CPU0_G2_TX_DP<11>")
	)
	(segment
		(start 364.572296 -237.664244)
		(end 364.600236 -237.680754)
		(width 0.1143)
		(layer "In6.Cu")
		(net "GMI_CPU1_G0_CPU0_G2_TX_DP<11>")
	)
	(segment
		(start 362.25226 -225.530664)
		(end 362.252514 -225.530918)
		(width 0.1143)
		(layer "In6.Cu")
		(net "GMI_CPU1_G0_CPU0_G2_TX_DP<11>")
	)
	(segment
		(start 108.303314 -227.152454)
		(end 108.304076 -227.151946)
		(width 0.1143)
		(layer "In6.Cu")
		(net "GMI_CPU1_G0_CPU0_G2_TX_DP<11>")
	)
	(segment
		(start 363.193838 -228.772974)
		(end 363.223556 -228.789992)
		(width 0.1143)
		(layer "In6.Cu")
		(net "GMI_CPU1_G0_CPU0_G2_TX_DP<11>")
	)
	(segment
		(start 108.306616 -228.770434)
		(end 108.311188 -228.767894)
		(width 0.1143)
		(layer "In6.Cu")
		(net "GMI_CPU1_G0_CPU0_G2_TX_DP<11>")
	)
	(segment
		(start 363.223556 -234.258358)
		(end 363.193838 -234.275376)
		(width 0.1143)
		(layer "In6.Cu")
		(net "GMI_CPU1_G0_CPU0_G2_TX_DP<11>")
	)
	(segment
		(start 110.654846 -223.101916)
		(end 110.655862 -223.101408)
		(width 0.1143)
		(layer "In6.Cu")
		(net "GMI_CPU1_G0_CPU0_G2_TX_DP<11>")
	)
	(segment
		(start 108.343192 -227.819966)
		(end 108.336334 -227.815902)
		(width 0.1143)
		(layer "In6.Cu")
		(net "GMI_CPU1_G0_CPU0_G2_TX_DP<11>")
	)
	(segment
		(start 118.89613 -212.773006)
		(end 121.735342 -210.594702)
		(width 0.14224)
		(layer "In6.Cu")
		(net "GMI_CPU1_G0_CPU0_G2_TX_DP<11>")
	)
	(segment
		(start 363.19079 -227.151184)
		(end 363.191806 -227.151692)
		(width 0.1143)
		(layer "In6.Cu")
		(net "GMI_CPU1_G0_CPU0_G2_TX_DP<11>")
	)
	(segment
		(start 360.042206 -221.202758)
		(end 360.087926 -221.248478)
		(width 0.1143)
		(layer "In6.Cu")
		(net "GMI_CPU1_G0_CPU0_G2_TX_DP<11>")
	)
	(segment
		(start 359.625392 -219.541344)
		(end 360.042206 -220.54693)
		(width 0.14224)
		(layer "In6.Cu")
		(net "GMI_CPU1_G0_CPU0_G2_TX_DP<11>")
	)
	(segment
		(start 363.193838 -227.795582)
		(end 363.192568 -227.796344)
		(width 0.1143)
		(layer "In6.Cu")
		(net "GMI_CPU1_G0_CPU0_G2_TX_DP<11>")
	)
	(arc
		(start 108.343192 -235.228892)
		(mid 108.586519 -234.764326)
		(end 108.343192 -234.29976)
		(width 0.1143)
		(layer "In6.Cu")
		(net "GMI_CPU1_G0_CPU0_G2_TX_DP<11>")
	)
	(arc
		(start 360.558588 -222.614236)
		(mid 360.623103 -222.876455)
		(end 360.80192 -223.078802)
		(width 0.1143)
		(layer "In6.Cu")
		(net "GMI_CPU1_G0_CPU0_G2_TX_DP<11>")
	)
	(arc
		(start 109.056424 -225.854514)
		(mid 109.102018 -225.675845)
		(end 109.22762 -225.540824)
		(width 0.1143)
		(layer "In6.Cu")
		(net "GMI_CPU1_G0_CPU0_G2_TX_DP<11>")
	)
	(arc
		(start 362.268262 -225.54057)
		(mid 362.393912 -225.675564)
		(end 362.439458 -225.85426)
		(width 0.1143)
		(layer "In6.Cu")
		(net "GMI_CPU1_G0_CPU0_G2_TX_DP<11>")
	)
	(arc
		(start 363.379512 -235.574078)
		(mid 363.444027 -235.836297)
		(end 363.622844 -236.038644)
		(width 0.1143)
		(layer "In6.Cu")
		(net "GMI_CPU1_G0_CPU0_G2_TX_DP<11>")
	)
	(arc
		(start 363.15269 -232.679494)
		(mid 362.909363 -233.14406)
		(end 363.15269 -233.608626)
		(width 0.1143)
		(layer "In6.Cu")
		(net "GMI_CPU1_G0_CPU0_G2_TX_DP<11>")
	)
	(arc
		(start 108.272326 -227.778818)
		(mid 108.116398 -227.474526)
		(end 108.272326 -227.170234)
		(width 0.1143)
		(layer "In6.Cu")
		(net "GMI_CPU1_G0_CPU0_G2_TX_DP<11>")
	)
	(arc
		(start 361.028742 -223.424242)
		(mid 361.093257 -223.686461)
		(end 361.272074 -223.888808)
		(width 0.1143)
		(layer "In6.Cu")
		(net "GMI_CPU1_G0_CPU0_G2_TX_DP<11>")
	)
	(arc
		(start 109.718094 -224.719642)
		(mid 109.922139 -224.514242)
		(end 109.996732 -224.234502)
		(width 0.1143)
		(layer "In6.Cu")
		(net "GMI_CPU1_G0_CPU0_G2_TX_DP<11>")
	)
	(arc
		(start 361.344972 -223.931226)
		(mid 361.458379 -224.064256)
		(end 361.49915 -224.234248)
		(width 0.1143)
		(layer "In6.Cu")
		(net "GMI_CPU1_G0_CPU0_G2_TX_DP<11>")
	)
	(arc
		(start 363.15269 -231.059482)
		(mid 362.909363 -231.524048)
		(end 363.15269 -231.988614)
		(width 0.1143)
		(layer "In6.Cu")
		(net "GMI_CPU1_G0_CPU0_G2_TX_DP<11>")
	)
	(arc
		(start 364.32236 -237.232444)
		(mid 364.393765 -237.457763)
		(end 364.541308 -237.6424)
		(width 0.1143)
		(layer "In6.Cu")
		(net "GMI_CPU1_G0_CPU0_G2_TX_DP<11>")
	)
	(arc
		(start 111.164116 -222.26905)
		(mid 111.242539 -222.203569)
		(end 111.30788 -222.125032)
		(width 0.1143)
		(layer "In6.Cu")
		(net "GMI_CPU1_G0_CPU0_G2_TX_DP<11>")
	)
	(arc
		(start 364.541308 -237.6424)
		(mid 364.553253 -237.651577)
		(end 364.565438 -237.660434)
		(width 0.1143)
		(layer "In6.Cu")
		(net "GMI_CPU1_G0_CPU0_G2_TX_DP<11>")
	)
	(arc
		(start 108.272326 -232.6386)
		(mid 108.116398 -232.334308)
		(end 108.272326 -232.030016)
		(width 0.1143)
		(layer "In6.Cu")
		(net "GMI_CPU1_G0_CPU0_G2_TX_DP<11>")
	)
	(arc
		(start 107.176316 -237.187486)
		(mid 107.219463 -237.019902)
		(end 107.333288 -236.889544)
		(width 0.1143)
		(layer "In6.Cu")
		(net "GMI_CPU1_G0_CPU0_G2_TX_DP<11>")
	)
	(arc
		(start 108.11637 -230.71455)
		(mid 108.157625 -230.543579)
		(end 108.272326 -230.410258)
		(width 0.1143)
		(layer "In6.Cu")
		(net "GMI_CPU1_G0_CPU0_G2_TX_DP<11>")
	)
	(arc
		(start 108.343192 -233.60888)
		(mid 108.586519 -233.144314)
		(end 108.343192 -232.679748)
		(width 0.1143)
		(layer "In6.Cu")
		(net "GMI_CPU1_G0_CPU0_G2_TX_DP<11>")
	)
	(arc
		(start 111.30788 -222.125032)
		(mid 111.381994 -221.972318)
		(end 111.407448 -221.804484)
		(width 0.1143)
		(layer "In6.Cu")
		(net "GMI_CPU1_G0_CPU0_G2_TX_DP<11>")
	)
	(arc
		(start 108.586524 -229.90429)
		(mid 108.522009 -229.642071)
		(end 108.343192 -229.439724)
		(width 0.1143)
		(layer "In6.Cu")
		(net "GMI_CPU1_G0_CPU0_G2_TX_DP<11>")
	)
	(arc
		(start 106.713274 -237.9345)
		(mid 106.765323 -237.802981)
		(end 106.862372 -237.700058)
		(width 0.1143)
		(layer "In6.Cu")
		(net "GMI_CPU1_G0_CPU0_G2_TX_DP<11>")
	)
	(arc
		(start 108.340652 -230.370634)
		(mid 108.521304 -230.167889)
		(end 108.586524 -229.90429)
		(width 0.1143)
		(layer "In6.Cu")
		(net "GMI_CPU1_G0_CPU0_G2_TX_DP<11>")
	)
	(arc
		(start 362.909358 -229.904036)
		(mid 362.974594 -230.167627)
		(end 363.15523 -230.37038)
		(width 0.1143)
		(layer "In6.Cu")
		(net "GMI_CPU1_G0_CPU0_G2_TX_DP<11>")
	)
	(arc
		(start 363.223556 -235.269786)
		(mid 363.338232 -235.40312)
		(end 363.379512 -235.574078)
		(width 0.1143)
		(layer "In6.Cu")
		(net "GMI_CPU1_G0_CPU0_G2_TX_DP<11>")
	)
	(arc
		(start 363.379512 -229.094284)
		(mid 363.33875 -229.264168)
		(end 363.225334 -229.397052)
		(width 0.1143)
		(layer "In6.Cu")
		(net "GMI_CPU1_G0_CPU0_G2_TX_DP<11>")
	)
	(arc
		(start 361.812078 -224.739454)
		(mid 361.927505 -224.87283)
		(end 361.96905 -225.044254)
		(width 0.1143)
		(layer "In6.Cu")
		(net "GMI_CPU1_G0_CPU0_G2_TX_DP<11>")
	)
	(arc
		(start 360.188002 -222.124778)
		(mid 360.253354 -222.203305)
		(end 360.331766 -222.268796)
		(width 0.1143)
		(layer "In6.Cu")
		(net "GMI_CPU1_G0_CPU0_G2_TX_DP<11>")
	)
	(arc
		(start 360.402632 -222.309944)
		(mid 360.517308 -222.443278)
		(end 360.558588 -222.614236)
		(width 0.1143)
		(layer "In6.Cu")
		(net "GMI_CPU1_G0_CPU0_G2_TX_DP<11>")
	)
	(arc
		(start 108.270548 -231.017318)
		(mid 108.157141 -230.884429)
		(end 108.11637 -230.71455)
		(width 0.1143)
		(layer "In6.Cu")
		(net "GMI_CPU1_G0_CPU0_G2_TX_DP<11>")
	)
	(arc
		(start 108.586524 -226.66452)
		(mid 108.628073 -226.493098)
		(end 108.743496 -226.35972)
		(width 0.1143)
		(layer "In6.Cu")
		(net "GMI_CPU1_G0_CPU0_G2_TX_DP<11>")
	)
	(arc
		(start 363.223556 -232.029762)
		(mid 363.379484 -232.334054)
		(end 363.223556 -232.638346)
		(width 0.1143)
		(layer "In6.Cu")
		(net "GMI_CPU1_G0_CPU0_G2_TX_DP<11>")
	)
	(arc
		(start 362.909358 -226.664266)
		(mid 362.973873 -226.926485)
		(end 363.15269 -227.128832)
		(width 0.1143)
		(layer "In6.Cu")
		(net "GMI_CPU1_G0_CPU0_G2_TX_DP<11>")
	)
	(arc
		(start 108.343192 -231.988868)
		(mid 108.586519 -231.524302)
		(end 108.343192 -231.059736)
		(width 0.1143)
		(layer "In6.Cu")
		(net "GMI_CPU1_G0_CPU0_G2_TX_DP<11>")
	)
	(arc
		(start 363.849412 -236.384084)
		(mid 363.913927 -236.646303)
		(end 364.092744 -236.84865)
		(width 0.1143)
		(layer "In6.Cu")
		(net "GMI_CPU1_G0_CPU0_G2_TX_DP<11>")
	)
	(arc
		(start 110.937294 -222.61449)
		(mid 110.978549 -222.443519)
		(end 111.09325 -222.310198)
		(width 0.1143)
		(layer "In6.Cu")
		(net "GMI_CPU1_G0_CPU0_G2_TX_DP<11>")
	)
	(arc
		(start 110.693962 -223.079056)
		(mid 110.872775 -222.876706)
		(end 110.937294 -222.61449)
		(width 0.1143)
		(layer "In6.Cu")
		(net "GMI_CPU1_G0_CPU0_G2_TX_DP<11>")
	)
	(arc
		(start 364.162594 -236.88929)
		(mid 364.276453 -237.01963)
		(end 364.319566 -237.187232)
		(width 0.1143)
		(layer "In6.Cu")
		(net "GMI_CPU1_G0_CPU0_G2_TX_DP<11>")
	)
	(arc
		(start 363.69244 -236.079284)
		(mid 363.807867 -236.21266)
		(end 363.849412 -236.384084)
		(width 0.1143)
		(layer "In6.Cu")
		(net "GMI_CPU1_G0_CPU0_G2_TX_DP<11>")
	)
	(arc
		(start 108.270548 -229.397306)
		(mid 108.157141 -229.264417)
		(end 108.11637 -229.094538)
		(width 0.1143)
		(layer "In6.Cu")
		(net "GMI_CPU1_G0_CPU0_G2_TX_DP<11>")
	)
	(arc
		(start 108.813092 -226.31908)
		(mid 108.991905 -226.11673)
		(end 109.056424 -225.854514)
		(width 0.1143)
		(layer "In6.Cu")
		(net "GMI_CPU1_G0_CPU0_G2_TX_DP<11>")
	)
	(arc
		(start 109.526832 -225.044508)
		(mid 109.568381 -224.873086)
		(end 109.683804 -224.739708)
		(width 0.1143)
		(layer "In6.Cu")
		(net "GMI_CPU1_G0_CPU0_G2_TX_DP<11>")
	)
	(arc
		(start 108.343192 -228.749098)
		(mid 108.586519 -228.284532)
		(end 108.343192 -227.819966)
		(width 0.1143)
		(layer "In6.Cu")
		(net "GMI_CPU1_G0_CPU0_G2_TX_DP<11>")
	)
	(arc
		(start 109.996732 -224.234502)
		(mid 110.03749 -224.064504)
		(end 110.15091 -223.93148)
		(width 0.1143)
		(layer "In6.Cu")
		(net "GMI_CPU1_G0_CPU0_G2_TX_DP<11>")
	)
	(arc
		(start 360.088434 -221.80423)
		(mid 360.113854 -221.972075)
		(end 360.188002 -222.124778)
		(width 0.1143)
		(layer "In6.Cu")
		(net "GMI_CPU1_G0_CPU0_G2_TX_DP<11>")
	)
	(arc
		(start 363.15269 -227.819712)
		(mid 362.909363 -228.284278)
		(end 363.15269 -228.748844)
		(width 0.1143)
		(layer "In6.Cu")
		(net "GMI_CPU1_G0_CPU0_G2_TX_DP<11>")
	)
	(arc
		(start 363.379512 -230.714296)
		(mid 363.33875 -230.88418)
		(end 363.225334 -231.017064)
		(width 0.1143)
		(layer "In6.Cu")
		(net "GMI_CPU1_G0_CPU0_G2_TX_DP<11>")
	)
	(arc
		(start 361.49915 -224.234248)
		(mid 361.573771 -224.513972)
		(end 361.777788 -224.719388)
		(width 0.1143)
		(layer "In6.Cu")
		(net "GMI_CPU1_G0_CPU0_G2_TX_DP<11>")
	)
	(arc
		(start 364.63351 -237.699804)
		(mid 364.730645 -237.802673)
		(end 364.782608 -237.934246)
		(width 0.1143)
		(layer "In6.Cu")
		(net "GMI_CPU1_G0_CPU0_G2_TX_DP<11>")
	)
	(arc
		(start 109.262418 -225.514916)
		(mid 109.456105 -225.314289)
		(end 109.526832 -225.044508)
		(width 0.1143)
		(layer "In6.Cu")
		(net "GMI_CPU1_G0_CPU0_G2_TX_DP<11>")
	)
	(arc
		(start 108.11637 -235.574332)
		(mid 108.157625 -235.403361)
		(end 108.272326 -235.27004)
		(width 0.1143)
		(layer "In6.Cu")
		(net "GMI_CPU1_G0_CPU0_G2_TX_DP<11>")
	)
	(arc
		(start 107.873038 -236.038898)
		(mid 108.051851 -235.836548)
		(end 108.11637 -235.574332)
		(width 0.1143)
		(layer "In6.Cu")
		(net "GMI_CPU1_G0_CPU0_G2_TX_DP<11>")
	)
	(arc
		(start 363.15269 -234.299506)
		(mid 362.909363 -234.764072)
		(end 363.15269 -235.228638)
		(width 0.1143)
		(layer "In6.Cu")
		(net "GMI_CPU1_G0_CPU0_G2_TX_DP<11>")
	)
	(arc
		(start 108.343192 -227.129086)
		(mid 108.522005 -226.926736)
		(end 108.586524 -226.66452)
		(width 0.1143)
		(layer "In6.Cu")
		(net "GMI_CPU1_G0_CPU0_G2_TX_DP<11>")
	)
	(arc
		(start 362.752386 -226.359466)
		(mid 362.867813 -226.492842)
		(end 362.909358 -226.664266)
		(width 0.1143)
		(layer "In6.Cu")
		(net "GMI_CPU1_G0_CPU0_G2_TX_DP<11>")
	)
	(arc
		(start 106.930444 -237.660688)
		(mid 106.94263 -237.651833)
		(end 106.954574 -237.642654)
		(width 0.1143)
		(layer "In6.Cu")
		(net "GMI_CPU1_G0_CPU0_G2_TX_DP<11>")
	)
	(arc
		(start 363.223556 -227.16998)
		(mid 363.379484 -227.474272)
		(end 363.223556 -227.778564)
		(width 0.1143)
		(layer "In6.Cu")
		(net "GMI_CPU1_G0_CPU0_G2_TX_DP<11>")
	)
	(arc
		(start 108.11637 -229.094538)
		(mid 108.157625 -228.923567)
		(end 108.272326 -228.790246)
		(width 0.1143)
		(layer "In6.Cu")
		(net "GMI_CPU1_G0_CPU0_G2_TX_DP<11>")
	)
	(arc
		(start 362.439458 -225.85426)
		(mid 362.503973 -226.116479)
		(end 362.68279 -226.318826)
		(width 0.1143)
		(layer "In6.Cu")
		(net "GMI_CPU1_G0_CPU0_G2_TX_DP<11>")
	)
	(arc
		(start 363.223556 -233.649774)
		(mid 363.379484 -233.954066)
		(end 363.223556 -234.258358)
		(width 0.1143)
		(layer "In6.Cu")
		(net "GMI_CPU1_G0_CPU0_G2_TX_DP<11>")
	)
	(arc
		(start 363.223556 -230.410004)
		(mid 363.338232 -230.543338)
		(end 363.379512 -230.714296)
		(width 0.1143)
		(layer "In6.Cu")
		(net "GMI_CPU1_G0_CPU0_G2_TX_DP<11>")
	)
	(arc
		(start 107.403138 -236.848904)
		(mid 107.581951 -236.646554)
		(end 107.64647 -236.384338)
		(width 0.1143)
		(layer "In6.Cu")
		(net "GMI_CPU1_G0_CPU0_G2_TX_DP<11>")
	)
	(arc
		(start 363.15269 -229.43947)
		(mid 362.973877 -229.64182)
		(end 362.909358 -229.904036)
		(width 0.1143)
		(layer "In6.Cu")
		(net "GMI_CPU1_G0_CPU0_G2_TX_DP<11>")
	)
	(arc
		(start 109.22762 -225.540824)
		(mid 109.235435 -225.535902)
		(end 109.243368 -225.531172)
		(width 0.1143)
		(layer "In6.Cu")
		(net "GMI_CPU1_G0_CPU0_G2_TX_DP<11>")
	)
	(arc
		(start 110.46714 -223.424496)
		(mid 110.508395 -223.253525)
		(end 110.623096 -223.120204)
		(width 0.1143)
		(layer "In6.Cu")
		(net "GMI_CPU1_G0_CPU0_G2_TX_DP<11>")
	)
	(arc
		(start 110.223808 -223.889062)
		(mid 110.402621 -223.686712)
		(end 110.46714 -223.424496)
		(width 0.1143)
		(layer "In6.Cu")
		(net "GMI_CPU1_G0_CPU0_G2_TX_DP<11>")
	)
	(arc
		(start 363.223556 -228.789992)
		(mid 363.338232 -228.923326)
		(end 363.379512 -229.094284)
		(width 0.1143)
		(layer "In6.Cu")
		(net "GMI_CPU1_G0_CPU0_G2_TX_DP<11>")
	)
	(arc
		(start 364.319566 -237.187232)
		(mid 364.320357 -237.209875)
		(end 364.32236 -237.232444)
		(width 0.1143)
		(layer "In6.Cu")
		(net "GMI_CPU1_G0_CPU0_G2_TX_DP<11>")
	)
	(arc
		(start 362.252514 -225.530918)
		(mid 362.260449 -225.535645)
		(end 362.268262 -225.54057)
		(width 0.1143)
		(layer "In6.Cu")
		(net "GMI_CPU1_G0_CPU0_G2_TX_DP<11>")
	)
	(arc
		(start 360.872786 -223.11995)
		(mid 360.987462 -223.253284)
		(end 361.028742 -223.424242)
		(width 0.1143)
		(layer "In6.Cu")
		(net "GMI_CPU1_G0_CPU0_G2_TX_DP<11>")
	)
	(arc
		(start 106.954574 -237.642654)
		(mid 107.102038 -237.457975)
		(end 107.173522 -237.232698)
		(width 0.1143)
		(layer "In6.Cu")
		(net "GMI_CPU1_G0_CPU0_G2_TX_DP<11>")
	)
	(arc
		(start 107.64647 -236.384338)
		(mid 107.688019 -236.212916)
		(end 107.803442 -236.079538)
		(width 0.1143)
		(layer "In6.Cu")
		(net "GMI_CPU1_G0_CPU0_G2_TX_DP<11>")
	)
	(arc
		(start 108.272326 -234.258612)
		(mid 108.116398 -233.95432)
		(end 108.272326 -233.650028)
		(width 0.1143)
		(layer "In6.Cu")
		(net "GMI_CPU1_G0_CPU0_G2_TX_DP<11>")
	)
	(arc
		(start 107.173522 -237.232698)
		(mid 107.175535 -237.21013)
		(end 107.176316 -237.187486)
		(width 0.1143)
		(layer "In6.Cu")
		(net "GMI_CPU1_G0_CPU0_G2_TX_DP<11>")
	)
	(arc
		(start 361.96905 -225.044254)
		(mid 362.039661 -225.314101)
		(end 362.233464 -225.514662)
		(width 0.1143)
		(layer "In6.Cu")
		(net "GMI_CPU1_G0_CPU0_G2_TX_DP<11>")
	)
	(segment
		(start 363.947964 -239.890046)
		(end 364.414816 -239.624108)
		(width 0.12954)
		(layer "F.Cu")
		(net "GMI_CPU1_G0_CPU0_G2_TX_DP<10>")
	)
	(segment
		(start 107.547918 -239.8903)
		(end 107.081066 -239.624362)
		(width 0.12954)
		(layer "F.Cu")
		(net "GMI_CPU1_G0_CPU0_G2_TX_DP<10>")
	)
	(segment
		(start 361.03052 -221.325694)
		(end 361.02925 -221.326964)
		(width 0.1143)
		(layer "In6.Cu")
		(net "GMI_CPU1_G0_CPU0_G2_TX_DP<10>")
	)
	(segment
		(start 364.092744 -227.128832)
		(end 364.12932 -227.150168)
		(width 0.1143)
		(layer "In6.Cu")
		(net "GMI_CPU1_G0_CPU0_G2_TX_DP<10>")
	)
	(segment
		(start 364.134908 -235.253276)
		(end 364.148116 -235.260896)
		(width 0.1143)
		(layer "In6.Cu")
		(net "GMI_CPU1_G0_CPU0_G2_TX_DP<10>")
	)
	(segment
		(start 130.18008 -203.727812)
		(end 130.229356 -203.543662)
		(width 0.14224)
		(layer "In6.Cu")
		(net "GMI_CPU1_G0_CPU0_G2_TX_DP<10>")
	)
	(segment
		(start 107.365038 -232.01122)
		(end 107.366562 -232.010204)
		(width 0.1143)
		(layer "In6.Cu")
		(net "GMI_CPU1_G0_CPU0_G2_TX_DP<10>")
	)
	(segment
		(start 107.36326 -233.632248)
		(end 107.364022 -233.63174)
		(width 0.1143)
		(layer "In6.Cu")
		(net "GMI_CPU1_G0_CPU0_G2_TX_DP<10>")
	)
	(segment
		(start 360.9848 -221.17431)
		(end 360.9848 -221.202758)
		(width 0.1143)
		(layer "In6.Cu")
		(net "GMI_CPU1_G0_CPU0_G2_TX_DP<10>")
	)
	(segment
		(start 361.781852 -223.101662)
		(end 361.813602 -223.11995)
		(width 0.1143)
		(layer "In6.Cu")
		(net "GMI_CPU1_G0_CPU0_G2_TX_DP<10>")
	)
	(segment
		(start 364.13186 -227.796852)
		(end 364.100364 -227.81514)
		(width 0.1143)
		(layer "In6.Cu")
		(net "GMI_CPU1_G0_CPU0_G2_TX_DP<10>")
	)
	(segment
		(start 107.364022 -227.797106)
		(end 107.36326 -227.796598)
		(width 0.1143)
		(layer "In6.Cu")
		(net "GMI_CPU1_G0_CPU0_G2_TX_DP<10>")
	)
	(segment
		(start 105.954068 -237.68177)
		(end 105.955084 -237.681262)
		(width 0.1143)
		(layer "In6.Cu")
		(net "GMI_CPU1_G0_CPU0_G2_TX_DP<10>")
	)
	(segment
		(start 105.986326 -238.345726)
		(end 105.985564 -238.345218)
		(width 0.1143)
		(layer "In6.Cu")
		(net "GMI_CPU1_G0_CPU0_G2_TX_DP<10>")
	)
	(segment
		(start 107.39628 -232.675684)
		(end 107.395518 -232.675176)
		(width 0.1143)
		(layer "In6.Cu")
		(net "GMI_CPU1_G0_CPU0_G2_TX_DP<10>")
	)
	(segment
		(start 363.155484 -225.510598)
		(end 363.191806 -225.53168)
		(width 0.1143)
		(layer "In6.Cu")
		(net "GMI_CPU1_G0_CPU0_G2_TX_DP<10>")
	)
	(segment
		(start 235.526834 -183.142382)
		(end 302.891952 -183.534812)
		(width 0.14224)
		(layer "In6.Cu")
		(net "GMI_CPU1_G0_CPU0_G2_TX_DP<10>")
	)
	(segment
		(start 107.365038 -228.77145)
		(end 107.366562 -228.770434)
		(width 0.1143)
		(layer "In6.Cu")
		(net "GMI_CPU1_G0_CPU0_G2_TX_DP<10>")
	)
	(segment
		(start 364.12932 -232.00995)
		(end 364.130844 -232.010966)
		(width 0.1143)
		(layer "In6.Cu")
		(net "GMI_CPU1_G0_CPU0_G2_TX_DP<10>")
	)
	(segment
		(start 107.364022 -233.63174)
		(end 107.365038 -233.631232)
		(width 0.1143)
		(layer "In6.Cu")
		(net "GMI_CPU1_G0_CPU0_G2_TX_DP<10>")
	)
	(segment
		(start 123.803918 -207.992218)
		(end 123.828556 -207.803496)
		(width 0.14224)
		(layer "In6.Cu")
		(net "GMI_CPU1_G0_CPU0_G2_TX_DP<10>")
	)
	(segment
		(start 107.176316 -235.64342)
		(end 107.176316 -235.574332)
		(width 0.1143)
		(layer "In6.Cu")
		(net "GMI_CPU1_G0_CPU0_G2_TX_DP<10>")
	)
	(segment
		(start 107.365038 -235.251244)
		(end 107.366562 -235.250228)
		(width 0.1143)
		(layer "In6.Cu")
		(net "GMI_CPU1_G0_CPU0_G2_TX_DP<10>")
	)
	(segment
		(start 108.773976 -224.721928)
		(end 108.813092 -224.699068)
		(width 0.1143)
		(layer "In6.Cu")
		(net "GMI_CPU1_G0_CPU0_G2_TX_DP<10>")
	)
	(segment
		(start 353.666298 -213.057232)
		(end 357.531416 -216.125298)
		(width 0.14224)
		(layer "In6.Cu")
		(net "GMI_CPU1_G0_CPU0_G2_TX_DP<10>")
	)
	(segment
		(start 364.16361 -227.778564)
		(end 364.132622 -227.796344)
		(width 0.1143)
		(layer "In6.Cu")
		(net "GMI_CPU1_G0_CPU0_G2_TX_DP<10>")
	)
	(segment
		(start 107.347766 -235.26115)
		(end 107.360974 -235.25353)
		(width 0.1143)
		(layer "In6.Cu")
		(net "GMI_CPU1_G0_CPU0_G2_TX_DP<10>")
	)
	(segment
		(start 364.095284 -230.37038)
		(end 364.152434 -230.403654)
		(width 0.1143)
		(layer "In6.Cu")
		(net "GMI_CPU1_G0_CPU0_G2_TX_DP<10>")
	)
	(segment
		(start 364.099602 -227.815648)
		(end 364.092744 -227.819712)
		(width 0.1143)
		(layer "In6.Cu")
		(net "GMI_CPU1_G0_CPU0_G2_TX_DP<10>")
	)
	(segment
		(start 105.953306 -238.326422)
		(end 105.952036 -238.32566)
		(width 0.1143)
		(layer "In6.Cu")
		(net "GMI_CPU1_G0_CPU0_G2_TX_DP<10>")
	)
	(segment
		(start 125.228604 -206.899002)
		(end 125.561344 -206.643478)
		(width 0.14224)
		(layer "In6.Cu")
		(net "GMI_CPU1_G0_CPU0_G2_TX_DP<10>")
	)
	(segment
		(start 128.857756 -204.491082)
		(end 129.220976 -204.281532)
		(width 0.14224)
		(layer "In6.Cu")
		(net "GMI_CPU1_G0_CPU0_G2_TX_DP<10>")
	)
	(segment
		(start 360.9848 -221.202758)
		(end 361.03052 -221.248478)
		(width 0.1143)
		(layer "In6.Cu")
		(net "GMI_CPU1_G0_CPU0_G2_TX_DP<10>")
	)
	(segment
		(start 364.130844 -232.010966)
		(end 364.13186 -232.011474)
		(width 0.1143)
		(layer "In6.Cu")
		(net "GMI_CPU1_G0_CPU0_G2_TX_DP<10>")
	)
	(segment
		(start 302.891952 -183.534812)
		(end 306.388008 -183.534812)
		(width 0.14224)
		(layer "In6.Cu")
		(net "GMI_CPU1_G0_CPU0_G2_TX_DP<10>")
	)
	(segment
		(start 364.100364 -227.81514)
		(end 364.099602 -227.815648)
		(width 0.1143)
		(layer "In6.Cu")
		(net "GMI_CPU1_G0_CPU0_G2_TX_DP<10>")
	)
	(segment
		(start 129.81686 -203.937362)
		(end 130.18008 -203.727812)
		(width 0.14224)
		(layer "In6.Cu")
		(net "GMI_CPU1_G0_CPU0_G2_TX_DP<10>")
	)
	(segment
		(start 362.21289 -223.888808)
		(end 362.282486 -223.929448)
		(width 0.1143)
		(layer "In6.Cu")
		(net "GMI_CPU1_G0_CPU0_G2_TX_DP<10>")
	)
	(segment
		(start 107.364022 -227.151946)
		(end 107.365038 -227.151438)
		(width 0.1143)
		(layer "In6.Cu")
		(net "GMI_CPU1_G0_CPU0_G2_TX_DP<10>")
	)
	(segment
		(start 124.707396 -207.129126)
		(end 125.039882 -206.87411)
		(width 0.14224)
		(layer "In6.Cu")
		(net "GMI_CPU1_G0_CPU0_G2_TX_DP<10>")
	)
	(segment
		(start 364.130844 -228.771196)
		(end 364.135416 -228.773482)
		(width 0.1143)
		(layer "In6.Cu")
		(net "GMI_CPU1_G0_CPU0_G2_TX_DP<10>")
	)
	(segment
		(start 168.161716 -182.749952)
		(end 235.527088 -183.142382)
		(width 0.14224)
		(layer "In6.Cu")
		(net "GMI_CPU1_G0_CPU0_G2_TX_DP<10>")
	)
	(segment
		(start 364.092744 -235.228638)
		(end 364.12932 -235.249974)
		(width 0.1143)
		(layer "In6.Cu")
		(net "GMI_CPU1_G0_CPU0_G2_TX_DP<10>")
	)
	(segment
		(start 124.161042 -207.54848)
		(end 124.350018 -207.573372)
		(width 0.14224)
		(layer "In6.Cu")
		(net "GMI_CPU1_G0_CPU0_G2_TX_DP<10>")
	)
	(segment
		(start 105.993184 -238.34979)
		(end 105.986326 -238.345726)
		(width 0.1143)
		(layer "In6.Cu")
		(net "GMI_CPU1_G0_CPU0_G2_TX_DP<10>")
	)
	(segment
		(start 111.354616 -218.47175)
		(end 116.06784 -213.758526)
		(width 0.14224)
		(layer "In6.Cu")
		(net "GMI_CPU1_G0_CPU0_G2_TX_DP<10>")
	)
	(segment
		(start 364.100364 -232.674922)
		(end 364.099602 -232.67543)
		(width 0.1143)
		(layer "In6.Cu")
		(net "GMI_CPU1_G0_CPU0_G2_TX_DP<10>")
	)
	(segment
		(start 107.39628 -227.815902)
		(end 107.395518 -227.815394)
		(width 0.1143)
		(layer "In6.Cu")
		(net "GMI_CPU1_G0_CPU0_G2_TX_DP<10>")
	)
	(segment
		(start 361.780836 -223.101154)
		(end 361.781852 -223.101662)
		(width 0.1143)
		(layer "In6.Cu")
		(net "GMI_CPU1_G0_CPU0_G2_TX_DP<10>")
	)
	(segment
		(start 364.12932 -233.629962)
		(end 364.130844 -233.630978)
		(width 0.1143)
		(layer "In6.Cu")
		(net "GMI_CPU1_G0_CPU0_G2_TX_DP<10>")
	)
	(segment
		(start 105.956608 -237.680246)
		(end 105.993184 -237.65891)
		(width 0.1143)
		(layer "In6.Cu")
		(net "GMI_CPU1_G0_CPU0_G2_TX_DP<10>")
	)
	(segment
		(start 364.13186 -234.276646)
		(end 364.100364 -234.294934)
		(width 0.1143)
		(layer "In6.Cu")
		(net "GMI_CPU1_G0_CPU0_G2_TX_DP<10>")
	)
	(segment
		(start 306.388008 -183.534812)
		(end 307.558694 -183.856376)
		(width 0.14224)
		(layer "In6.Cu")
		(net "GMI_CPU1_G0_CPU0_G2_TX_DP<10>")
	)
	(segment
		(start 164.611558 -183.690514)
		(end 168.161716 -182.749952)
		(width 0.14224)
		(layer "In6.Cu")
		(net "GMI_CPU1_G0_CPU0_G2_TX_DP<10>")
	)
	(segment
		(start 364.130844 -233.630978)
		(end 364.13186 -233.631486)
		(width 0.1143)
		(layer "In6.Cu")
		(net "GMI_CPU1_G0_CPU0_G2_TX_DP<10>")
	)
	(segment
		(start 365.502698 -237.658656)
		(end 365.539274 -237.679992)
		(width 0.1143)
		(layer "In6.Cu")
		(net "GMI_CPU1_G0_CPU0_G2_TX_DP<10>")
	)
	(segment
		(start 129.270252 -204.097382)
		(end 129.632964 -203.888086)
		(width 0.14224)
		(layer "In6.Cu")
		(net "GMI_CPU1_G0_CPU0_G2_TX_DP<10>")
	)
	(segment
		(start 365.539274 -237.679992)
		(end 365.540798 -237.681008)
		(width 0.1143)
		(layer "In6.Cu")
		(net "GMI_CPU1_G0_CPU0_G2_TX_DP<10>")
	)
	(segment
		(start 107.334304 -235.269024)
		(end 107.347766 -235.26115)
		(width 0.1143)
		(layer "In6.Cu")
		(net "GMI_CPU1_G0_CPU0_G2_TX_DP<10>")
	)
	(segment
		(start 107.36326 -227.152454)
		(end 107.364022 -227.151946)
		(width 0.1143)
		(layer "In6.Cu")
		(net "GMI_CPU1_G0_CPU0_G2_TX_DP<10>")
	)
	(segment
		(start 364.132622 -233.631994)
		(end 364.16361 -233.649774)
		(width 0.1143)
		(layer "In6.Cu")
		(net "GMI_CPU1_G0_CPU0_G2_TX_DP<10>")
	)
	(segment
		(start 364.13186 -232.011474)
		(end 364.132622 -232.011982)
		(width 0.1143)
		(layer "In6.Cu")
		(net "GMI_CPU1_G0_CPU0_G2_TX_DP<10>")
	)
	(segment
		(start 364.100364 -234.294934)
		(end 364.099602 -234.295442)
		(width 0.1143)
		(layer "In6.Cu")
		(net "GMI_CPU1_G0_CPU0_G2_TX_DP<10>")
	)
	(segment
		(start 235.527088 -183.142382)
		(end 235.526834 -183.142382)
		(width 0.14224)
		(layer "In6.Cu")
		(net "GMI_CPU1_G0_CPU0_G2_TX_DP<10>")
	)
	(segment
		(start 107.361736 -235.253022)
		(end 107.36326 -235.25226)
		(width 0.1143)
		(layer "In6.Cu")
		(net "GMI_CPU1_G0_CPU0_G2_TX_DP<10>")
	)
	(segment
		(start 109.71403 -223.101916)
		(end 109.715046 -223.101408)
		(width 0.1143)
		(layer "In6.Cu")
		(net "GMI_CPU1_G0_CPU0_G2_TX_DP<10>")
	)
	(segment
		(start 361.272582 -222.268796)
		(end 361.311698 -222.291656)
		(width 0.1143)
		(layer "In6.Cu")
		(net "GMI_CPU1_G0_CPU0_G2_TX_DP<10>")
	)
	(segment
		(start 129.632964 -203.888086)
		(end 129.81686 -203.937362)
		(width 0.14224)
		(layer "In6.Cu")
		(net "GMI_CPU1_G0_CPU0_G2_TX_DP<10>")
	)
	(segment
		(start 364.132622 -234.276138)
		(end 364.13186 -234.276646)
		(width 0.1143)
		(layer "In6.Cu")
		(net "GMI_CPU1_G0_CPU0_G2_TX_DP<10>")
	)
	(segment
		(start 107.366562 -232.010204)
		(end 107.403138 -231.988868)
		(width 0.1143)
		(layer "In6.Cu")
		(net "GMI_CPU1_G0_CPU0_G2_TX_DP<10>")
	)
	(segment
		(start 364.132622 -232.011982)
		(end 364.16361 -232.029762)
		(width 0.1143)
		(layer "In6.Cu")
		(net "GMI_CPU1_G0_CPU0_G2_TX_DP<10>")
	)
	(segment
		(start 106.423968 -236.871764)
		(end 106.463084 -236.848904)
		(width 0.1143)
		(layer "In6.Cu")
		(net "GMI_CPU1_G0_CPU0_G2_TX_DP<10>")
	)
	(segment
		(start 364.092744 -233.608626)
		(end 364.12932 -233.629962)
		(width 0.1143)
		(layer "In6.Cu")
		(net "GMI_CPU1_G0_CPU0_G2_TX_DP<10>")
	)
	(segment
		(start 363.622844 -226.318826)
		(end 363.69244 -226.359466)
		(width 0.1143)
		(layer "In6.Cu")
		(net "GMI_CPU1_G0_CPU0_G2_TX_DP<10>")
	)
	(segment
		(start 364.092744 -231.988614)
		(end 364.12932 -232.00995)
		(width 0.1143)
		(layer "In6.Cu")
		(net "GMI_CPU1_G0_CPU0_G2_TX_DP<10>")
	)
	(segment
		(start 364.498636 -235.99267)
		(end 364.56239 -236.038898)
		(width 0.1143)
		(layer "In6.Cu")
		(net "GMI_CPU1_G0_CPU0_G2_TX_DP<10>")
	)
	(segment
		(start 105.954068 -238.32693)
		(end 105.953306 -238.326422)
		(width 0.1143)
		(layer "In6.Cu")
		(net "GMI_CPU1_G0_CPU0_G2_TX_DP<10>")
	)
	(segment
		(start 364.132622 -235.252006)
		(end 364.134146 -235.252768)
		(width 0.1143)
		(layer "In6.Cu")
		(net "GMI_CPU1_G0_CPU0_G2_TX_DP<10>")
	)
	(segment
		(start 107.364022 -232.656888)
		(end 107.36326 -232.65638)
		(width 0.1143)
		(layer "In6.Cu")
		(net "GMI_CPU1_G0_CPU0_G2_TX_DP<10>")
	)
	(segment
		(start 107.278932 -230.459788)
		(end 107.343448 -230.403908)
		(width 0.1143)
		(layer "In6.Cu")
		(net "GMI_CPU1_G0_CPU0_G2_TX_DP<10>")
	)
	(segment
		(start 127.714756 -204.995526)
		(end 127.898652 -205.044802)
		(width 0.14224)
		(layer "In6.Cu")
		(net "GMI_CPU1_G0_CPU0_G2_TX_DP<10>")
	)
	(segment
		(start 128.311148 -204.651102)
		(end 128.67386 -204.441806)
		(width 0.14224)
		(layer "In6.Cu")
		(net "GMI_CPU1_G0_CPU0_G2_TX_DP<10>")
	)
	(segment
		(start 364.12932 -228.77018)
		(end 364.130844 -228.771196)
		(width 0.1143)
		(layer "In6.Cu")
		(net "GMI_CPU1_G0_CPU0_G2_TX_DP<10>")
	)
	(segment
		(start 364.795562 -239.541304)
		(end 364.712758 -239.624108)
		(width 0.1143)
		(layer "In6.Cu")
		(net "GMI_CPU1_G0_CPU0_G2_TX_DP<10>")
	)
	(segment
		(start 125.918468 -206.19974)
		(end 126.10719 -206.224632)
		(width 0.14224)
		(layer "In6.Cu")
		(net "GMI_CPU1_G0_CPU0_G2_TX_DP<10>")
	)
	(segment
		(start 365.032798 -236.84865)
		(end 365.102394 -236.88929)
		(width 0.1143)
		(layer "In6.Cu")
		(net "GMI_CPU1_G0_CPU0_G2_TX_DP<10>")
	)
	(segment
		(start 364.135416 -228.773482)
		(end 364.152942 -228.783642)
		(width 0.1143)
		(layer "In6.Cu")
		(net "GMI_CPU1_G0_CPU0_G2_TX_DP<10>")
	)
	(segment
		(start 130.229356 -203.543662)
		(end 130.592068 -203.334112)
		(width 0.14224)
		(layer "In6.Cu")
		(net "GMI_CPU1_G0_CPU0_G2_TX_DP<10>")
	)
	(segment
		(start 364.092744 -228.748844)
		(end 364.12932 -228.77018)
		(width 0.1143)
		(layer "In6.Cu")
		(net "GMI_CPU1_G0_CPU0_G2_TX_DP<10>")
	)
	(segment
		(start 107.403138 -227.819966)
		(end 107.39628 -227.815902)
		(width 0.1143)
		(layer "In6.Cu")
		(net "GMI_CPU1_G0_CPU0_G2_TX_DP<10>")
	)
	(segment
		(start 109.68228 -223.120204)
		(end 109.71403 -223.101916)
		(width 0.1143)
		(layer "In6.Cu")
		(net "GMI_CPU1_G0_CPU0_G2_TX_DP<10>")
	)
	(segment
		(start 107.332272 -232.030016)
		(end 107.36326 -232.012236)
		(width 0.1143)
		(layer "In6.Cu")
		(net "GMI_CPU1_G0_CPU0_G2_TX_DP<10>")
	)
	(segment
		(start 360.444796 -219.037408)
		(end 360.9848 -220.340682)
		(width 0.14224)
		(layer "In6.Cu")
		(net "GMI_CPU1_G0_CPU0_G2_TX_DP<10>")
	)
	(segment
		(start 131.139184 -203.173838)
		(end 131.18846 -202.989688)
		(width 0.14224)
		(layer "In6.Cu")
		(net "GMI_CPU1_G0_CPU0_G2_TX_DP<10>")
	)
	(segment
		(start 125.585982 -206.454756)
		(end 125.918468 -206.19974)
		(width 0.14224)
		(layer "In6.Cu")
		(net "GMI_CPU1_G0_CPU0_G2_TX_DP<10>")
	)
	(segment
		(start 365.573564 -238.308388)
		(end 365.543846 -238.325406)
		(width 0.1143)
		(layer "In6.Cu")
		(net "GMI_CPU1_G0_CPU0_G2_TX_DP<10>")
	)
	(segment
		(start 109.213396 -223.929702)
		(end 109.243876 -223.911922)
		(width 0.1143)
		(layer "In6.Cu")
		(net "GMI_CPU1_G0_CPU0_G2_TX_DP<10>")
	)
	(segment
		(start 107.17657 -230.72471)
		(end 107.185206 -230.639874)
		(width 0.1143)
		(layer "In6.Cu")
		(net "GMI_CPU1_G0_CPU0_G2_TX_DP<10>")
	)
	(segment
		(start 110.465362 -221.248732)
		(end 110.511082 -221.203012)
		(width 0.1143)
		(layer "In6.Cu")
		(net "GMI_CPU1_G0_CPU0_G2_TX_DP<10>")
	)
	(segment
		(start 126.464568 -205.780386)
		(end 126.464568 -205.78064)
		(width 0.14224)
		(layer "In6.Cu")
		(net "GMI_CPU1_G0_CPU0_G2_TX_DP<10>")
	)
	(segment
		(start 364.12932 -235.249974)
		(end 364.130844 -235.25099)
		(width 0.1143)
		(layer "In6.Cu")
		(net "GMI_CPU1_G0_CPU0_G2_TX_DP<10>")
	)
	(segment
		(start 364.130844 -235.25099)
		(end 364.13186 -235.251498)
		(width 0.1143)
		(layer "In6.Cu")
		(net "GMI_CPU1_G0_CPU0_G2_TX_DP<10>")
	)
	(segment
		(start 362.68279 -224.698814)
		(end 362.721906 -224.721674)
		(width 0.1143)
		(layer "In6.Cu")
		(net "GMI_CPU1_G0_CPU0_G2_TX_DP<10>")
	)
	(segment
		(start 107.403138 -229.439724)
		(end 107.39755 -229.43693)
		(width 0.1143)
		(layer "In6.Cu")
		(net "GMI_CPU1_G0_CPU0_G2_TX_DP<10>")
	)
	(segment
		(start 107.364022 -234.2769)
		(end 107.36326 -234.276392)
		(width 0.1143)
		(layer "In6.Cu")
		(net "GMI_CPU1_G0_CPU0_G2_TX_DP<10>")
	)
	(segment
		(start 130.775964 -203.383388)
		(end 131.139184 -203.173838)
		(width 0.14224)
		(layer "In6.Cu")
		(net "GMI_CPU1_G0_CPU0_G2_TX_DP<10>")
	)
	(segment
		(start 107.36326 -234.276392)
		(end 107.332272 -234.258612)
		(width 0.1143)
		(layer "In6.Cu")
		(net "GMI_CPU1_G0_CPU0_G2_TX_DP<10>")
	)
	(segment
		(start 364.132622 -227.796344)
		(end 364.13186 -227.796852)
		(width 0.1143)
		(layer "In6.Cu")
		(net "GMI_CPU1_G0_CPU0_G2_TX_DP<10>")
	)
	(segment
		(start 126.797054 -205.52537)
		(end 127.714756 -204.995526)
		(width 0.14224)
		(layer "In6.Cu")
		(net "GMI_CPU1_G0_CPU0_G2_TX_DP<10>")
	)
	(segment
		(start 365.102394 -239.118902)
		(end 365.032798 -239.159542)
		(width 0.1143)
		(layer "In6.Cu")
		(net "GMI_CPU1_G0_CPU0_G2_TX_DP<10>")
	)
	(segment
		(start 106.423968 -239.136936)
		(end 106.393488 -239.119156)
		(width 0.1143)
		(layer "In6.Cu")
		(net "GMI_CPU1_G0_CPU0_G2_TX_DP<10>")
	)
	(segment
		(start 105.922318 -237.700058)
		(end 105.952036 -237.68304)
		(width 0.1143)
		(layer "In6.Cu")
		(net "GMI_CPU1_G0_CPU0_G2_TX_DP<10>")
	)
	(segment
		(start 107.36326 -232.012236)
		(end 107.364022 -232.011728)
		(width 0.1143)
		(layer "In6.Cu")
		(net "GMI_CPU1_G0_CPU0_G2_TX_DP<10>")
	)
	(segment
		(start 106.933492 -236.039152)
		(end 106.997246 -235.992924)
		(width 0.1143)
		(layer "In6.Cu")
		(net "GMI_CPU1_G0_CPU0_G2_TX_DP<10>")
	)
	(segment
		(start 360.9848 -220.340682)
		(end 360.9848 -221.17431)
		(width 0.14224)
		(layer "In6.Cu")
		(net "GMI_CPU1_G0_CPU0_G2_TX_DP<10>")
	)
	(segment
		(start 105.952036 -238.32566)
		(end 105.922318 -238.308642)
		(width 0.1143)
		(layer "In6.Cu")
		(net "GMI_CPU1_G0_CPU0_G2_TX_DP<10>")
	)
	(segment
		(start 364.132622 -227.1522)
		(end 364.16361 -227.16998)
		(width 0.1143)
		(layer "In6.Cu")
		(net "GMI_CPU1_G0_CPU0_G2_TX_DP<10>")
	)
	(segment
		(start 307.558694 -183.856376)
		(end 313.74207 -187.528454)
		(width 0.14224)
		(layer "In6.Cu")
		(net "GMI_CPU1_G0_CPU0_G2_TX_DP<10>")
	)
	(segment
		(start 364.13186 -232.656634)
		(end 364.100364 -232.674922)
		(width 0.1143)
		(layer "In6.Cu")
		(net "GMI_CPU1_G0_CPU0_G2_TX_DP<10>")
	)
	(segment
		(start 107.803442 -226.35972)
		(end 107.833922 -226.34194)
		(width 0.1143)
		(layer "In6.Cu")
		(net "GMI_CPU1_G0_CPU0_G2_TX_DP<10>")
	)
	(segment
		(start 124.350018 -207.573372)
		(end 124.682758 -207.317848)
		(width 0.14224)
		(layer "In6.Cu")
		(net "GMI_CPU1_G0_CPU0_G2_TX_DP<10>")
	)
	(segment
		(start 107.395518 -234.295188)
		(end 107.364022 -234.2769)
		(width 0.1143)
		(layer "In6.Cu")
		(net "GMI_CPU1_G0_CPU0_G2_TX_DP<10>")
	)
	(segment
		(start 107.833922 -226.34194)
		(end 107.873038 -226.31908)
		(width 0.1143)
		(layer "In6.Cu")
		(net "GMI_CPU1_G0_CPU0_G2_TX_DP<10>")
	)
	(segment
		(start 123.282202 -208.22285)
		(end 123.471178 -208.247742)
		(width 0.14224)
		(layer "In6.Cu")
		(net "GMI_CPU1_G0_CPU0_G2_TX_DP<10>")
	)
	(segment
		(start 123.828556 -207.803496)
		(end 124.161042 -207.54848)
		(width 0.14224)
		(layer "In6.Cu")
		(net "GMI_CPU1_G0_CPU0_G2_TX_DP<10>")
	)
	(segment
		(start 365.543846 -238.325406)
		(end 365.542576 -238.326168)
		(width 0.1143)
		(layer "In6.Cu")
		(net "GMI_CPU1_G0_CPU0_G2_TX_DP<10>")
	)
	(segment
		(start 365.541814 -238.326676)
		(end 365.510318 -238.344964)
		(width 0.1143)
		(layer "In6.Cu")
		(net "GMI_CPU1_G0_CPU0_G2_TX_DP<10>")
	)
	(segment
		(start 126.464568 -205.78064)
		(end 126.797054 -205.52537)
		(width 0.14224)
		(layer "In6.Cu")
		(net "GMI_CPU1_G0_CPU0_G2_TX_DP<10>")
	)
	(segment
		(start 124.682758 -207.317848)
		(end 124.707396 -207.129126)
		(width 0.14224)
		(layer "In6.Cu")
		(net "GMI_CPU1_G0_CPU0_G2_TX_DP<10>")
	)
	(segment
		(start 109.715046 -223.101408)
		(end 109.71657 -223.100392)
		(width 0.1143)
		(layer "In6.Cu")
		(net "GMI_CPU1_G0_CPU0_G2_TX_DP<10>")
	)
	(segment
		(start 107.36326 -232.65638)
		(end 107.332272 -232.6386)
		(width 0.1143)
		(layer "In6.Cu")
		(net "GMI_CPU1_G0_CPU0_G2_TX_DP<10>")
	)
	(segment
		(start 110.511082 -221.174564)
		(end 110.511082 -220.508068)
		(width 0.14224)
		(layer "In6.Cu")
		(net "GMI_CPU1_G0_CPU0_G2_TX_DP<10>")
	)
	(segment
		(start 364.098332 -229.436676)
		(end 364.092744 -229.43947)
		(width 0.1143)
		(layer "In6.Cu")
		(net "GMI_CPU1_G0_CPU0_G2_TX_DP<10>")
	)
	(segment
		(start 315.333126 -189.207394)
		(end 353.666298 -213.057232)
		(width 0.14224)
		(layer "In6.Cu")
		(net "GMI_CPU1_G0_CPU0_G2_TX_DP<10>")
	)
	(segment
		(start 364.712758 -239.624108)
		(end 364.414816 -239.624108)
		(width 0.1143)
		(layer "In6.Cu")
		(net "GMI_CPU1_G0_CPU0_G2_TX_DP<10>")
	)
	(segment
		(start 364.148116 -235.260896)
		(end 364.161578 -235.26877)
		(width 0.1143)
		(layer "In6.Cu")
		(net "GMI_CPU1_G0_CPU0_G2_TX_DP<10>")
	)
	(segment
		(start 107.403138 -231.059736)
		(end 107.334812 -231.020366)
		(width 0.1143)
		(layer "In6.Cu")
		(net "GMI_CPU1_G0_CPU0_G2_TX_DP<10>")
	)
	(segment
		(start 107.332272 -233.650028)
		(end 107.36326 -233.632248)
		(width 0.1143)
		(layer "In6.Cu")
		(net "GMI_CPU1_G0_CPU0_G2_TX_DP<10>")
	)
	(segment
		(start 107.081066 -239.624362)
		(end 106.783124 -239.624362)
		(width 0.1143)
		(layer "In6.Cu")
		(net "GMI_CPU1_G0_CPU0_G2_TX_DP<10>")
	)
	(segment
		(start 107.36326 -227.796598)
		(end 107.332272 -227.778818)
		(width 0.1143)
		(layer "In6.Cu")
		(net "GMI_CPU1_G0_CPU0_G2_TX_DP<10>")
	)
	(segment
		(start 107.39755 -229.43693)
		(end 107.343194 -229.40518)
		(width 0.1143)
		(layer "In6.Cu")
		(net "GMI_CPU1_G0_CPU0_G2_TX_DP<10>")
	)
	(segment
		(start 365.509556 -238.345472)
		(end 365.502698 -238.349536)
		(width 0.1143)
		(layer "In6.Cu")
		(net "GMI_CPU1_G0_CPU0_G2_TX_DP<10>")
	)
	(segment
		(start 129.220976 -204.281532)
		(end 129.270252 -204.097382)
		(width 0.14224)
		(layer "In6.Cu")
		(net "GMI_CPU1_G0_CPU0_G2_TX_DP<10>")
	)
	(segment
		(start 107.366562 -233.630216)
		(end 107.403138 -233.60888)
		(width 0.1143)
		(layer "In6.Cu")
		(net "GMI_CPU1_G0_CPU0_G2_TX_DP<10>")
	)
	(segment
		(start 364.152688 -229.404926)
		(end 364.098332 -229.436676)
		(width 0.1143)
		(layer "In6.Cu")
		(net "GMI_CPU1_G0_CPU0_G2_TX_DP<10>")
	)
	(segment
		(start 364.132622 -232.656126)
		(end 364.13186 -232.656634)
		(width 0.1143)
		(layer "In6.Cu")
		(net "GMI_CPU1_G0_CPU0_G2_TX_DP<10>")
	)
	(segment
		(start 365.510318 -238.344964)
		(end 365.509556 -238.345472)
		(width 0.1143)
		(layer "In6.Cu")
		(net "GMI_CPU1_G0_CPU0_G2_TX_DP<10>")
	)
	(segment
		(start 365.542576 -238.326168)
		(end 365.541814 -238.326676)
		(width 0.1143)
		(layer "In6.Cu")
		(net "GMI_CPU1_G0_CPU0_G2_TX_DP<10>")
	)
	(segment
		(start 107.332272 -227.170234)
		(end 107.36326 -227.152454)
		(width 0.1143)
		(layer "In6.Cu")
		(net "GMI_CPU1_G0_CPU0_G2_TX_DP<10>")
	)
	(segment
		(start 110.184184 -222.29191)
		(end 110.2233 -222.26905)
		(width 0.1143)
		(layer "In6.Cu")
		(net "GMI_CPU1_G0_CPU0_G2_TX_DP<10>")
	)
	(segment
		(start 107.343448 -230.403908)
		(end 107.400598 -230.370634)
		(width 0.1143)
		(layer "In6.Cu")
		(net "GMI_CPU1_G0_CPU0_G2_TX_DP<10>")
	)
	(segment
		(start 106.862372 -236.080046)
		(end 106.933492 -236.039152)
		(width 0.1143)
		(layer "In6.Cu")
		(net "GMI_CPU1_G0_CPU0_G2_TX_DP<10>")
	)
	(segment
		(start 361.02925 -221.326964)
		(end 361.02925 -221.80423)
		(width 0.1143)
		(layer "In6.Cu")
		(net "GMI_CPU1_G0_CPU0_G2_TX_DP<10>")
	)
	(segment
		(start 105.952036 -237.68304)
		(end 105.953306 -237.682278)
		(width 0.1143)
		(layer "In6.Cu")
		(net "GMI_CPU1_G0_CPU0_G2_TX_DP<10>")
	)
	(segment
		(start 107.360466 -228.773736)
		(end 107.365038 -228.77145)
		(width 0.1143)
		(layer "In6.Cu")
		(net "GMI_CPU1_G0_CPU0_G2_TX_DP<10>")
	)
	(segment
		(start 107.366562 -235.250228)
		(end 107.403138 -235.228892)
		(width 0.1143)
		(layer "In6.Cu")
		(net "GMI_CPU1_G0_CPU0_G2_TX_DP<10>")
	)
	(segment
		(start 107.395518 -227.815394)
		(end 107.364022 -227.797106)
		(width 0.1143)
		(layer "In6.Cu")
		(net "GMI_CPU1_G0_CPU0_G2_TX_DP<10>")
	)
	(segment
		(start 109.243876 -223.911922)
		(end 109.282992 -223.889062)
		(width 0.1143)
		(layer "In6.Cu")
		(net "GMI_CPU1_G0_CPU0_G2_TX_DP<10>")
	)
	(segment
		(start 364.099602 -232.67543)
		(end 364.092744 -232.679494)
		(width 0.1143)
		(layer "In6.Cu")
		(net "GMI_CPU1_G0_CPU0_G2_TX_DP<10>")
	)
	(segment
		(start 127.898652 -205.044802)
		(end 128.261872 -204.835252)
		(width 0.14224)
		(layer "In6.Cu")
		(net "GMI_CPU1_G0_CPU0_G2_TX_DP<10>")
	)
	(segment
		(start 110.466632 -221.327218)
		(end 110.465362 -221.325948)
		(width 0.1143)
		(layer "In6.Cu")
		(net "GMI_CPU1_G0_CPU0_G2_TX_DP<10>")
	)
	(segment
		(start 107.365038 -233.631232)
		(end 107.366562 -233.630216)
		(width 0.1143)
		(layer "In6.Cu")
		(net "GMI_CPU1_G0_CPU0_G2_TX_DP<10>")
	)
	(segment
		(start 313.74207 -187.528454)
		(end 315.333126 -189.207394)
		(width 0.14224)
		(layer "In6.Cu")
		(net "GMI_CPU1_G0_CPU0_G2_TX_DP<10>")
	)
	(segment
		(start 107.360974 -235.25353)
		(end 107.361736 -235.253022)
		(width 0.1143)
		(layer "In6.Cu")
		(net "GMI_CPU1_G0_CPU0_G2_TX_DP<10>")
	)
	(segment
		(start 110.511082 -221.203012)
		(end 110.511082 -221.174564)
		(width 0.1143)
		(layer "In6.Cu")
		(net "GMI_CPU1_G0_CPU0_G2_TX_DP<10>")
	)
	(segment
		(start 105.985564 -238.345218)
		(end 105.954068 -238.32693)
		(width 0.1143)
		(layer "In6.Cu")
		(net "GMI_CPU1_G0_CPU0_G2_TX_DP<10>")
	)
	(segment
		(start 128.261872 -204.835252)
		(end 128.311148 -204.651102)
		(width 0.14224)
		(layer "In6.Cu")
		(net "GMI_CPU1_G0_CPU0_G2_TX_DP<10>")
	)
	(segment
		(start 107.36326 -235.25226)
		(end 107.364022 -235.251752)
		(width 0.1143)
		(layer "In6.Cu")
		(net "GMI_CPU1_G0_CPU0_G2_TX_DP<10>")
	)
	(segment
		(start 108.744258 -224.738946)
		(end 108.773976 -224.721928)
		(width 0.1143)
		(layer "In6.Cu")
		(net "GMI_CPU1_G0_CPU0_G2_TX_DP<10>")
	)
	(segment
		(start 131.18846 -202.989688)
		(end 164.611558 -183.690514)
		(width 0.14224)
		(layer "In6.Cu")
		(net "GMI_CPU1_G0_CPU0_G2_TX_DP<10>")
	)
	(segment
		(start 364.16361 -234.258358)
		(end 364.132622 -234.276138)
		(width 0.1143)
		(layer "In6.Cu")
		(net "GMI_CPU1_G0_CPU0_G2_TX_DP<10>")
	)
	(segment
		(start 364.13186 -227.151692)
		(end 364.132622 -227.1522)
		(width 0.1143)
		(layer "In6.Cu")
		(net "GMI_CPU1_G0_CPU0_G2_TX_DP<10>")
	)
	(segment
		(start 107.365038 -227.151438)
		(end 107.366562 -227.150422)
		(width 0.1143)
		(layer "In6.Cu")
		(net "GMI_CPU1_G0_CPU0_G2_TX_DP<10>")
	)
	(segment
		(start 125.561344 -206.643478)
		(end 125.585982 -206.454756)
		(width 0.14224)
		(layer "In6.Cu")
		(net "GMI_CPU1_G0_CPU0_G2_TX_DP<10>")
	)
	(segment
		(start 125.039882 -206.87411)
		(end 125.228604 -206.899002)
		(width 0.14224)
		(layer "In6.Cu")
		(net "GMI_CPU1_G0_CPU0_G2_TX_DP<10>")
	)
	(segment
		(start 108.272326 -225.550222)
		(end 108.304076 -225.531934)
		(width 0.1143)
		(layer "In6.Cu")
		(net "GMI_CPU1_G0_CPU0_G2_TX_DP<10>")
	)
	(segment
		(start 107.366562 -227.150422)
		(end 107.403138 -227.129086)
		(width 0.1143)
		(layer "In6.Cu")
		(net "GMI_CPU1_G0_CPU0_G2_TX_DP<10>")
	)
	(segment
		(start 363.191806 -225.53168)
		(end 363.223556 -225.549968)
		(width 0.1143)
		(layer "In6.Cu")
		(net "GMI_CPU1_G0_CPU0_G2_TX_DP<10>")
	)
	(segment
		(start 365.542576 -237.682024)
		(end 365.543846 -237.682786)
		(width 0.1143)
		(layer "In6.Cu")
		(net "GMI_CPU1_G0_CPU0_G2_TX_DP<10>")
	)
	(segment
		(start 110.511082 -220.508068)
		(end 111.354616 -218.47175)
		(width 0.14224)
		(layer "In6.Cu")
		(net "GMI_CPU1_G0_CPU0_G2_TX_DP<10>")
	)
	(segment
		(start 365.541814 -237.681516)
		(end 365.542576 -237.682024)
		(width 0.1143)
		(layer "In6.Cu")
		(net "GMI_CPU1_G0_CPU0_G2_TX_DP<10>")
	)
	(segment
		(start 108.304076 -225.531934)
		(end 108.340398 -225.510852)
		(width 0.1143)
		(layer "In6.Cu")
		(net "GMI_CPU1_G0_CPU0_G2_TX_DP<10>")
	)
	(segment
		(start 365.540798 -237.681008)
		(end 365.541814 -237.681516)
		(width 0.1143)
		(layer "In6.Cu")
		(net "GMI_CPU1_G0_CPU0_G2_TX_DP<10>")
	)
	(segment
		(start 364.099602 -234.295442)
		(end 364.092744 -234.299506)
		(width 0.1143)
		(layer "In6.Cu")
		(net "GMI_CPU1_G0_CPU0_G2_TX_DP<10>")
	)
	(segment
		(start 128.67386 -204.441806)
		(end 128.857756 -204.491082)
		(width 0.14224)
		(layer "In6.Cu")
		(net "GMI_CPU1_G0_CPU0_G2_TX_DP<10>")
	)
	(segment
		(start 364.134146 -235.252768)
		(end 364.134908 -235.253276)
		(width 0.1143)
		(layer "In6.Cu")
		(net "GMI_CPU1_G0_CPU0_G2_TX_DP<10>")
	)
	(segment
		(start 107.403138 -232.679748)
		(end 107.39628 -232.675684)
		(width 0.1143)
		(layer "In6.Cu")
		(net "GMI_CPU1_G0_CPU0_G2_TX_DP<10>")
	)
	(segment
		(start 361.779312 -223.100138)
		(end 361.780836 -223.101154)
		(width 0.1143)
		(layer "In6.Cu")
		(net "GMI_CPU1_G0_CPU0_G2_TX_DP<10>")
	)
	(segment
		(start 107.366562 -228.770434)
		(end 107.403138 -228.749098)
		(width 0.1143)
		(layer "In6.Cu")
		(net "GMI_CPU1_G0_CPU0_G2_TX_DP<10>")
	)
	(segment
		(start 364.56239 -236.038898)
		(end 364.63351 -236.079792)
		(width 0.1143)
		(layer "In6.Cu")
		(net "GMI_CPU1_G0_CPU0_G2_TX_DP<10>")
	)
	(segment
		(start 364.100618 -231.05491)
		(end 364.092744 -231.059482)
		(width 0.1143)
		(layer "In6.Cu")
		(net "GMI_CPU1_G0_CPU0_G2_TX_DP<10>")
	)
	(segment
		(start 106.393488 -236.889544)
		(end 106.423968 -236.871764)
		(width 0.1143)
		(layer "In6.Cu")
		(net "GMI_CPU1_G0_CPU0_G2_TX_DP<10>")
	)
	(segment
		(start 107.364022 -235.251752)
		(end 107.365038 -235.251244)
		(width 0.1143)
		(layer "In6.Cu")
		(net "GMI_CPU1_G0_CPU0_G2_TX_DP<10>")
	)
	(segment
		(start 110.465362 -221.325948)
		(end 110.465362 -221.248732)
		(width 0.1143)
		(layer "In6.Cu")
		(net "GMI_CPU1_G0_CPU0_G2_TX_DP<10>")
	)
	(segment
		(start 365.543846 -237.682786)
		(end 365.573564 -237.699804)
		(width 0.1143)
		(layer "In6.Cu")
		(net "GMI_CPU1_G0_CPU0_G2_TX_DP<10>")
	)
	(segment
		(start 116.06784 -213.758526)
		(end 123.282202 -208.22285)
		(width 0.14224)
		(layer "In6.Cu")
		(net "GMI_CPU1_G0_CPU0_G2_TX_DP<10>")
	)
	(segment
		(start 364.319566 -235.574078)
		(end 364.319566 -235.643166)
		(width 0.1143)
		(layer "In6.Cu")
		(net "GMI_CPU1_G0_CPU0_G2_TX_DP<10>")
	)
	(segment
		(start 107.403138 -234.29976)
		(end 107.39628 -234.295696)
		(width 0.1143)
		(layer "In6.Cu")
		(net "GMI_CPU1_G0_CPU0_G2_TX_DP<10>")
	)
	(segment
		(start 362.721906 -224.721674)
		(end 362.751624 -224.738692)
		(width 0.1143)
		(layer "In6.Cu")
		(net "GMI_CPU1_G0_CPU0_G2_TX_DP<10>")
	)
	(segment
		(start 364.16107 -231.020112)
		(end 364.10138 -231.054402)
		(width 0.1143)
		(layer "In6.Cu")
		(net "GMI_CPU1_G0_CPU0_G2_TX_DP<10>")
	)
	(segment
		(start 109.71657 -223.100392)
		(end 109.753146 -223.079056)
		(width 0.1143)
		(layer "In6.Cu")
		(net "GMI_CPU1_G0_CPU0_G2_TX_DP<10>")
	)
	(segment
		(start 357.531416 -216.125298)
		(end 360.444796 -219.037408)
		(width 0.14224)
		(layer "In6.Cu")
		(net "GMI_CPU1_G0_CPU0_G2_TX_DP<10>")
	)
	(segment
		(start 361.742736 -223.078802)
		(end 361.779312 -223.100138)
		(width 0.1143)
		(layer "In6.Cu")
		(net "GMI_CPU1_G0_CPU0_G2_TX_DP<10>")
	)
	(segment
		(start 110.152434 -222.310198)
		(end 110.184184 -222.29191)
		(width 0.1143)
		(layer "In6.Cu")
		(net "GMI_CPU1_G0_CPU0_G2_TX_DP<10>")
	)
	(segment
		(start 130.592068 -203.334112)
		(end 130.775964 -203.383388)
		(width 0.14224)
		(layer "In6.Cu")
		(net "GMI_CPU1_G0_CPU0_G2_TX_DP<10>")
	)
	(segment
		(start 364.16361 -232.638346)
		(end 364.132622 -232.656126)
		(width 0.1143)
		(layer "In6.Cu")
		(net "GMI_CPU1_G0_CPU0_G2_TX_DP<10>")
	)
	(segment
		(start 123.471178 -208.247742)
		(end 123.803918 -207.992218)
		(width 0.14224)
		(layer "In6.Cu")
		(net "GMI_CPU1_G0_CPU0_G2_TX_DP<10>")
	)
	(segment
		(start 361.03052 -221.248478)
		(end 361.03052 -221.325694)
		(width 0.1143)
		(layer "In6.Cu")
		(net "GMI_CPU1_G0_CPU0_G2_TX_DP<10>")
	)
	(segment
		(start 364.13186 -233.631486)
		(end 364.132622 -233.631994)
		(width 0.1143)
		(layer "In6.Cu")
		(net "GMI_CPU1_G0_CPU0_G2_TX_DP<10>")
	)
	(segment
		(start 107.39628 -234.295696)
		(end 107.395518 -234.295188)
		(width 0.1143)
		(layer "In6.Cu")
		(net "GMI_CPU1_G0_CPU0_G2_TX_DP<10>")
	)
	(segment
		(start 364.13186 -235.251498)
		(end 364.132622 -235.252006)
		(width 0.1143)
		(layer "In6.Cu")
		(net "GMI_CPU1_G0_CPU0_G2_TX_DP<10>")
	)
	(segment
		(start 107.34294 -228.783896)
		(end 107.360466 -228.773736)
		(width 0.1143)
		(layer "In6.Cu")
		(net "GMI_CPU1_G0_CPU0_G2_TX_DP<10>")
	)
	(segment
		(start 106.783124 -239.624362)
		(end 106.70032 -239.541558)
		(width 0.1143)
		(layer "In6.Cu")
		(net "GMI_CPU1_G0_CPU0_G2_TX_DP<10>")
	)
	(segment
		(start 361.311698 -222.291656)
		(end 361.343448 -222.309944)
		(width 0.1143)
		(layer "In6.Cu")
		(net "GMI_CPU1_G0_CPU0_G2_TX_DP<10>")
	)
	(segment
		(start 364.10138 -231.054402)
		(end 364.100618 -231.05491)
		(width 0.1143)
		(layer "In6.Cu")
		(net "GMI_CPU1_G0_CPU0_G2_TX_DP<10>")
	)
	(segment
		(start 364.130844 -227.151184)
		(end 364.13186 -227.151692)
		(width 0.1143)
		(layer "In6.Cu")
		(net "GMI_CPU1_G0_CPU0_G2_TX_DP<10>")
	)
	(segment
		(start 107.364022 -232.011728)
		(end 107.365038 -232.01122)
		(width 0.1143)
		(layer "In6.Cu")
		(net "GMI_CPU1_G0_CPU0_G2_TX_DP<10>")
	)
	(segment
		(start 105.955084 -237.681262)
		(end 105.956608 -237.680246)
		(width 0.1143)
		(layer "In6.Cu")
		(net "GMI_CPU1_G0_CPU0_G2_TX_DP<10>")
	)
	(segment
		(start 364.12932 -227.150168)
		(end 364.130844 -227.151184)
		(width 0.1143)
		(layer "In6.Cu")
		(net "GMI_CPU1_G0_CPU0_G2_TX_DP<10>")
	)
	(segment
		(start 107.395518 -232.675176)
		(end 107.364022 -232.656888)
		(width 0.1143)
		(layer "In6.Cu")
		(net "GMI_CPU1_G0_CPU0_G2_TX_DP<10>")
	)
	(segment
		(start 110.466632 -221.804484)
		(end 110.466632 -221.327218)
		(width 0.1143)
		(layer "In6.Cu")
		(net "GMI_CPU1_G0_CPU0_G2_TX_DP<10>")
	)
	(segment
		(start 105.953306 -237.682278)
		(end 105.954068 -237.68177)
		(width 0.1143)
		(layer "In6.Cu")
		(net "GMI_CPU1_G0_CPU0_G2_TX_DP<10>")
	)
	(segment
		(start 126.10719 -206.224632)
		(end 126.43993 -205.969108)
		(width 0.14224)
		(layer "In6.Cu")
		(net "GMI_CPU1_G0_CPU0_G2_TX_DP<10>")
	)
	(segment
		(start 106.463084 -239.159796)
		(end 106.423968 -239.136936)
		(width 0.1143)
		(layer "In6.Cu")
		(net "GMI_CPU1_G0_CPU0_G2_TX_DP<10>")
	)
	(segment
		(start 126.43993 -205.969108)
		(end 126.464568 -205.780386)
		(width 0.14224)
		(layer "In6.Cu")
		(net "GMI_CPU1_G0_CPU0_G2_TX_DP<10>")
	)
	(arc
		(start 362.282486 -223.929448)
		(mid 362.397913 -224.062824)
		(end 362.439458 -224.234248)
		(width 0.1143)
		(layer "In6.Cu")
		(net "GMI_CPU1_G0_CPU0_G2_TX_DP<10>")
	)
	(arc
		(start 107.873038 -226.31908)
		(mid 108.051851 -226.11673)
		(end 108.11637 -225.854514)
		(width 0.1143)
		(layer "In6.Cu")
		(net "GMI_CPU1_G0_CPU0_G2_TX_DP<10>")
	)
	(arc
		(start 106.236516 -238.814356)
		(mid 106.172001 -238.552137)
		(end 105.993184 -238.34979)
		(width 0.1143)
		(layer "In6.Cu")
		(net "GMI_CPU1_G0_CPU0_G2_TX_DP<10>")
	)
	(arc
		(start 365.259366 -238.814102)
		(mid 365.217817 -238.985524)
		(end 365.102394 -239.118902)
		(width 0.1143)
		(layer "In6.Cu")
		(net "GMI_CPU1_G0_CPU0_G2_TX_DP<10>")
	)
	(arc
		(start 106.236516 -237.194344)
		(mid 106.278065 -237.022922)
		(end 106.393488 -236.889544)
		(width 0.1143)
		(layer "In6.Cu")
		(net "GMI_CPU1_G0_CPU0_G2_TX_DP<10>")
	)
	(arc
		(start 108.58627 -225.044508)
		(mid 108.62811 -224.872522)
		(end 108.744258 -224.738946)
		(width 0.1143)
		(layer "In6.Cu")
		(net "GMI_CPU1_G0_CPU0_G2_TX_DP<10>")
	)
	(arc
		(start 364.319566 -235.643166)
		(mid 364.366945 -235.839512)
		(end 364.498636 -235.99267)
		(width 0.1143)
		(layer "In6.Cu")
		(net "GMI_CPU1_G0_CPU0_G2_TX_DP<10>")
	)
	(arc
		(start 363.849412 -226.664266)
		(mid 363.913927 -226.926485)
		(end 364.092744 -227.128832)
		(width 0.1143)
		(layer "In6.Cu")
		(net "GMI_CPU1_G0_CPU0_G2_TX_DP<10>")
	)
	(arc
		(start 364.092744 -232.679494)
		(mid 363.849417 -233.14406)
		(end 364.092744 -233.608626)
		(width 0.1143)
		(layer "In6.Cu")
		(net "GMI_CPU1_G0_CPU0_G2_TX_DP<10>")
	)
	(arc
		(start 365.102394 -236.88929)
		(mid 365.217821 -237.022666)
		(end 365.259366 -237.19409)
		(width 0.1143)
		(layer "In6.Cu")
		(net "GMI_CPU1_G0_CPU0_G2_TX_DP<10>")
	)
	(arc
		(start 364.16361 -227.16998)
		(mid 364.313995 -227.474272)
		(end 364.16361 -227.778564)
		(width 0.1143)
		(layer "In6.Cu")
		(net "GMI_CPU1_G0_CPU0_G2_TX_DP<10>")
	)
	(arc
		(start 364.16361 -232.029762)
		(mid 364.315199 -232.334054)
		(end 364.16361 -232.638346)
		(width 0.1143)
		(layer "In6.Cu")
		(net "GMI_CPU1_G0_CPU0_G2_TX_DP<10>")
	)
	(arc
		(start 364.63351 -236.079792)
		(mid 364.748186 -236.213126)
		(end 364.789466 -236.384084)
		(width 0.1143)
		(layer "In6.Cu")
		(net "GMI_CPU1_G0_CPU0_G2_TX_DP<10>")
	)
	(arc
		(start 363.69244 -226.359466)
		(mid 363.807867 -226.492842)
		(end 363.849412 -226.664266)
		(width 0.1143)
		(layer "In6.Cu")
		(net "GMI_CPU1_G0_CPU0_G2_TX_DP<10>")
	)
	(arc
		(start 362.751624 -224.738692)
		(mid 362.867805 -224.872251)
		(end 362.909612 -225.044254)
		(width 0.1143)
		(layer "In6.Cu")
		(net "GMI_CPU1_G0_CPU0_G2_TX_DP<10>")
	)
	(arc
		(start 108.11637 -225.854514)
		(mid 108.157625 -225.683543)
		(end 108.272326 -225.550222)
		(width 0.1143)
		(layer "In6.Cu")
		(net "GMI_CPU1_G0_CPU0_G2_TX_DP<10>")
	)
	(arc
		(start 364.799372 -239.518444)
		(mid 364.797349 -239.529854)
		(end 364.795562 -239.541304)
		(width 0.1143)
		(layer "In6.Cu")
		(net "GMI_CPU1_G0_CPU0_G2_TX_DP<10>")
	)
	(arc
		(start 108.813092 -224.699068)
		(mid 108.991905 -224.496718)
		(end 109.056424 -224.234502)
		(width 0.1143)
		(layer "In6.Cu")
		(net "GMI_CPU1_G0_CPU0_G2_TX_DP<10>")
	)
	(arc
		(start 107.332272 -234.258612)
		(mid 107.181887 -233.95432)
		(end 107.332272 -233.650028)
		(width 0.1143)
		(layer "In6.Cu")
		(net "GMI_CPU1_G0_CPU0_G2_TX_DP<10>")
	)
	(arc
		(start 106.393488 -239.119156)
		(mid 106.278061 -238.98578)
		(end 106.236516 -238.814356)
		(width 0.1143)
		(layer "In6.Cu")
		(net "GMI_CPU1_G0_CPU0_G2_TX_DP<10>")
	)
	(arc
		(start 107.176316 -235.574332)
		(mid 107.218195 -235.402463)
		(end 107.334304 -235.269024)
		(width 0.1143)
		(layer "In6.Cu")
		(net "GMI_CPU1_G0_CPU0_G2_TX_DP<10>")
	)
	(arc
		(start 109.056424 -224.234502)
		(mid 109.097973 -224.06308)
		(end 109.213396 -223.929702)
		(width 0.1143)
		(layer "In6.Cu")
		(net "GMI_CPU1_G0_CPU0_G2_TX_DP<10>")
	)
	(arc
		(start 364.161578 -235.26877)
		(mid 364.277625 -235.402241)
		(end 364.319566 -235.574078)
		(width 0.1143)
		(layer "In6.Cu")
		(net "GMI_CPU1_G0_CPU0_G2_TX_DP<10>")
	)
	(arc
		(start 364.092744 -234.299506)
		(mid 363.849417 -234.764072)
		(end 364.092744 -235.228638)
		(width 0.1143)
		(layer "In6.Cu")
		(net "GMI_CPU1_G0_CPU0_G2_TX_DP<10>")
	)
	(arc
		(start 107.334812 -231.020366)
		(mid 107.332903 -231.018975)
		(end 107.331002 -231.017572)
		(width 0.1143)
		(layer "In6.Cu")
		(net "GMI_CPU1_G0_CPU0_G2_TX_DP<10>")
	)
	(arc
		(start 109.526324 -223.424496)
		(mid 109.567579 -223.253525)
		(end 109.68228 -223.120204)
		(width 0.1143)
		(layer "In6.Cu")
		(net "GMI_CPU1_G0_CPU0_G2_TX_DP<10>")
	)
	(arc
		(start 364.092744 -227.819712)
		(mid 363.849417 -228.284278)
		(end 364.092744 -228.748844)
		(width 0.1143)
		(layer "In6.Cu")
		(net "GMI_CPU1_G0_CPU0_G2_TX_DP<10>")
	)
	(arc
		(start 107.332272 -232.6386)
		(mid 107.180683 -232.334308)
		(end 107.332272 -232.030016)
		(width 0.1143)
		(layer "In6.Cu")
		(net "GMI_CPU1_G0_CPU0_G2_TX_DP<10>")
	)
	(arc
		(start 364.16488 -231.017318)
		(mid 364.16298 -231.018721)
		(end 364.16107 -231.020112)
		(width 0.1143)
		(layer "In6.Cu")
		(net "GMI_CPU1_G0_CPU0_G2_TX_DP<10>")
	)
	(arc
		(start 107.400598 -230.370634)
		(mid 107.58125 -230.167889)
		(end 107.64647 -229.90429)
		(width 0.1143)
		(layer "In6.Cu")
		(net "GMI_CPU1_G0_CPU0_G2_TX_DP<10>")
	)
	(arc
		(start 108.340398 -225.510852)
		(mid 108.52105 -225.308107)
		(end 108.58627 -225.044508)
		(width 0.1143)
		(layer "In6.Cu")
		(net "GMI_CPU1_G0_CPU0_G2_TX_DP<10>")
	)
	(arc
		(start 107.64647 -229.90429)
		(mid 107.581955 -229.642071)
		(end 107.403138 -229.439724)
		(width 0.1143)
		(layer "In6.Cu")
		(net "GMI_CPU1_G0_CPU0_G2_TX_DP<10>")
	)
	(arc
		(start 364.092744 -231.059482)
		(mid 363.849417 -231.524048)
		(end 364.092744 -231.988614)
		(width 0.1143)
		(layer "In6.Cu")
		(net "GMI_CPU1_G0_CPU0_G2_TX_DP<10>")
	)
	(arc
		(start 365.573564 -237.699804)
		(mid 365.729492 -238.004096)
		(end 365.573564 -238.308388)
		(width 0.1143)
		(layer "In6.Cu")
		(net "GMI_CPU1_G0_CPU0_G2_TX_DP<10>")
	)
	(arc
		(start 365.032798 -239.159542)
		(mid 364.880811 -239.31605)
		(end 364.799372 -239.518444)
		(width 0.1143)
		(layer "In6.Cu")
		(net "GMI_CPU1_G0_CPU0_G2_TX_DP<10>")
	)
	(arc
		(start 364.789466 -236.384084)
		(mid 364.853981 -236.646303)
		(end 365.032798 -236.84865)
		(width 0.1143)
		(layer "In6.Cu")
		(net "GMI_CPU1_G0_CPU0_G2_TX_DP<10>")
	)
	(arc
		(start 107.343194 -229.40518)
		(mid 107.164339 -229.094648)
		(end 107.34294 -228.783896)
		(width 0.1143)
		(layer "In6.Cu")
		(net "GMI_CPU1_G0_CPU0_G2_TX_DP<10>")
	)
	(arc
		(start 109.996478 -222.61449)
		(mid 110.037733 -222.443519)
		(end 110.152434 -222.310198)
		(width 0.1143)
		(layer "In6.Cu")
		(net "GMI_CPU1_G0_CPU0_G2_TX_DP<10>")
	)
	(arc
		(start 365.502698 -238.349536)
		(mid 365.323885 -238.551886)
		(end 365.259366 -238.814102)
		(width 0.1143)
		(layer "In6.Cu")
		(net "GMI_CPU1_G0_CPU0_G2_TX_DP<10>")
	)
	(arc
		(start 109.282992 -223.889062)
		(mid 109.461805 -223.686712)
		(end 109.526324 -223.424496)
		(width 0.1143)
		(layer "In6.Cu")
		(net "GMI_CPU1_G0_CPU0_G2_TX_DP<10>")
	)
	(arc
		(start 107.403138 -235.228892)
		(mid 107.646465 -234.764326)
		(end 107.403138 -234.29976)
		(width 0.1143)
		(layer "In6.Cu")
		(net "GMI_CPU1_G0_CPU0_G2_TX_DP<10>")
	)
	(arc
		(start 105.922318 -238.308642)
		(mid 105.76639 -238.00435)
		(end 105.922318 -237.700058)
		(width 0.1143)
		(layer "In6.Cu")
		(net "GMI_CPU1_G0_CPU0_G2_TX_DP<10>")
	)
	(arc
		(start 364.152942 -228.783642)
		(mid 364.33167 -229.094394)
		(end 364.152688 -229.404926)
		(width 0.1143)
		(layer "In6.Cu")
		(net "GMI_CPU1_G0_CPU0_G2_TX_DP<10>")
	)
	(arc
		(start 107.403138 -233.60888)
		(mid 107.646465 -233.144314)
		(end 107.403138 -232.679748)
		(width 0.1143)
		(layer "In6.Cu")
		(net "GMI_CPU1_G0_CPU0_G2_TX_DP<10>")
	)
	(arc
		(start 107.332272 -227.778818)
		(mid 107.181887 -227.474526)
		(end 107.332272 -227.170234)
		(width 0.1143)
		(layer "In6.Cu")
		(net "GMI_CPU1_G0_CPU0_G2_TX_DP<10>")
	)
	(arc
		(start 362.909612 -225.044254)
		(mid 362.974848 -225.307845)
		(end 363.155484 -225.510598)
		(width 0.1143)
		(layer "In6.Cu")
		(net "GMI_CPU1_G0_CPU0_G2_TX_DP<10>")
	)
	(arc
		(start 107.403138 -231.988868)
		(mid 107.646465 -231.524302)
		(end 107.403138 -231.059736)
		(width 0.1143)
		(layer "In6.Cu")
		(net "GMI_CPU1_G0_CPU0_G2_TX_DP<10>")
	)
	(arc
		(start 365.259366 -237.19409)
		(mid 365.323881 -237.456309)
		(end 365.502698 -237.658656)
		(width 0.1143)
		(layer "In6.Cu")
		(net "GMI_CPU1_G0_CPU0_G2_TX_DP<10>")
	)
	(arc
		(start 107.403138 -228.749098)
		(mid 107.646465 -228.284532)
		(end 107.403138 -227.819966)
		(width 0.1143)
		(layer "In6.Cu")
		(net "GMI_CPU1_G0_CPU0_G2_TX_DP<10>")
	)
	(arc
		(start 109.753146 -223.079056)
		(mid 109.931959 -222.876706)
		(end 109.996478 -222.61449)
		(width 0.1143)
		(layer "In6.Cu")
		(net "GMI_CPU1_G0_CPU0_G2_TX_DP<10>")
	)
	(arc
		(start 107.185206 -230.639874)
		(mid 107.214894 -230.540901)
		(end 107.278932 -230.459788)
		(width 0.1143)
		(layer "In6.Cu")
		(net "GMI_CPU1_G0_CPU0_G2_TX_DP<10>")
	)
	(arc
		(start 110.2233 -222.26905)
		(mid 110.301723 -222.203569)
		(end 110.367064 -222.125032)
		(width 0.1143)
		(layer "In6.Cu")
		(net "GMI_CPU1_G0_CPU0_G2_TX_DP<10>")
	)
	(arc
		(start 364.319312 -230.724456)
		(mid 364.276214 -230.888863)
		(end 364.16488 -231.017318)
		(width 0.1143)
		(layer "In6.Cu")
		(net "GMI_CPU1_G0_CPU0_G2_TX_DP<10>")
	)
	(arc
		(start 362.439458 -224.234248)
		(mid 362.503973 -224.496467)
		(end 362.68279 -224.698814)
		(width 0.1143)
		(layer "In6.Cu")
		(net "GMI_CPU1_G0_CPU0_G2_TX_DP<10>")
	)
	(arc
		(start 361.499404 -222.614236)
		(mid 361.563919 -222.876455)
		(end 361.742736 -223.078802)
		(width 0.1143)
		(layer "In6.Cu")
		(net "GMI_CPU1_G0_CPU0_G2_TX_DP<10>")
	)
	(arc
		(start 105.993184 -237.65891)
		(mid 106.171997 -237.45656)
		(end 106.236516 -237.194344)
		(width 0.1143)
		(layer "In6.Cu")
		(net "GMI_CPU1_G0_CPU0_G2_TX_DP<10>")
	)
	(arc
		(start 106.706416 -236.384338)
		(mid 106.747671 -236.213367)
		(end 106.862372 -236.080046)
		(width 0.1143)
		(layer "In6.Cu")
		(net "GMI_CPU1_G0_CPU0_G2_TX_DP<10>")
	)
	(arc
		(start 106.463084 -236.848904)
		(mid 106.641897 -236.646554)
		(end 106.706416 -236.384338)
		(width 0.1143)
		(layer "In6.Cu")
		(net "GMI_CPU1_G0_CPU0_G2_TX_DP<10>")
	)
	(arc
		(start 106.70032 -239.541558)
		(mid 106.698532 -239.530109)
		(end 106.69651 -239.518698)
		(width 0.1143)
		(layer "In6.Cu")
		(net "GMI_CPU1_G0_CPU0_G2_TX_DP<10>")
	)
	(arc
		(start 361.128818 -222.124778)
		(mid 361.19417 -222.203305)
		(end 361.272582 -222.268796)
		(width 0.1143)
		(layer "In6.Cu")
		(net "GMI_CPU1_G0_CPU0_G2_TX_DP<10>")
	)
	(arc
		(start 361.969558 -223.424242)
		(mid 362.034073 -223.686461)
		(end 362.21289 -223.888808)
		(width 0.1143)
		(layer "In6.Cu")
		(net "GMI_CPU1_G0_CPU0_G2_TX_DP<10>")
	)
	(arc
		(start 363.379512 -225.85426)
		(mid 363.444027 -226.116479)
		(end 363.622844 -226.318826)
		(width 0.1143)
		(layer "In6.Cu")
		(net "GMI_CPU1_G0_CPU0_G2_TX_DP<10>")
	)
	(arc
		(start 361.02925 -221.80423)
		(mid 361.05467 -221.972075)
		(end 361.128818 -222.124778)
		(width 0.1143)
		(layer "In6.Cu")
		(net "GMI_CPU1_G0_CPU0_G2_TX_DP<10>")
	)
	(arc
		(start 364.16361 -233.649774)
		(mid 364.313995 -233.954066)
		(end 364.16361 -234.258358)
		(width 0.1143)
		(layer "In6.Cu")
		(net "GMI_CPU1_G0_CPU0_G2_TX_DP<10>")
	)
	(arc
		(start 364.092744 -229.43947)
		(mid 363.913931 -229.64182)
		(end 363.849412 -229.904036)
		(width 0.1143)
		(layer "In6.Cu")
		(net "GMI_CPU1_G0_CPU0_G2_TX_DP<10>")
	)
	(arc
		(start 361.813602 -223.11995)
		(mid 361.928278 -223.253284)
		(end 361.969558 -223.424242)
		(width 0.1143)
		(layer "In6.Cu")
		(net "GMI_CPU1_G0_CPU0_G2_TX_DP<10>")
	)
	(arc
		(start 107.331002 -231.017572)
		(mid 107.219564 -230.889171)
		(end 107.17657 -230.72471)
		(width 0.1143)
		(layer "In6.Cu")
		(net "GMI_CPU1_G0_CPU0_G2_TX_DP<10>")
	)
	(arc
		(start 106.69651 -239.518698)
		(mid 106.615077 -239.3163)
		(end 106.463084 -239.159796)
		(width 0.1143)
		(layer "In6.Cu")
		(net "GMI_CPU1_G0_CPU0_G2_TX_DP<10>")
	)
	(arc
		(start 110.367064 -222.125032)
		(mid 110.441178 -221.972318)
		(end 110.466632 -221.804484)
		(width 0.1143)
		(layer "In6.Cu")
		(net "GMI_CPU1_G0_CPU0_G2_TX_DP<10>")
	)
	(arc
		(start 107.403138 -227.129086)
		(mid 107.581951 -226.926736)
		(end 107.64647 -226.66452)
		(width 0.1143)
		(layer "In6.Cu")
		(net "GMI_CPU1_G0_CPU0_G2_TX_DP<10>")
	)
	(arc
		(start 361.343448 -222.309944)
		(mid 361.458124 -222.443278)
		(end 361.499404 -222.614236)
		(width 0.1143)
		(layer "In6.Cu")
		(net "GMI_CPU1_G0_CPU0_G2_TX_DP<10>")
	)
	(arc
		(start 364.152434 -230.403654)
		(mid 364.266579 -230.548093)
		(end 364.319312 -230.724456)
		(width 0.1143)
		(layer "In6.Cu")
		(net "GMI_CPU1_G0_CPU0_G2_TX_DP<10>")
	)
	(arc
		(start 363.223556 -225.549968)
		(mid 363.338232 -225.683302)
		(end 363.379512 -225.85426)
		(width 0.1143)
		(layer "In6.Cu")
		(net "GMI_CPU1_G0_CPU0_G2_TX_DP<10>")
	)
	(arc
		(start 363.849412 -229.904036)
		(mid 363.914648 -230.167627)
		(end 364.095284 -230.37038)
		(width 0.1143)
		(layer "In6.Cu")
		(net "GMI_CPU1_G0_CPU0_G2_TX_DP<10>")
	)
	(arc
		(start 106.997246 -235.992924)
		(mid 107.128967 -235.839781)
		(end 107.176316 -235.64342)
		(width 0.1143)
		(layer "In6.Cu")
		(net "GMI_CPU1_G0_CPU0_G2_TX_DP<10>")
	)
	(arc
		(start 107.64647 -226.66452)
		(mid 107.688019 -226.493098)
		(end 107.803442 -226.35972)
		(width 0.1143)
		(layer "In6.Cu")
		(net "GMI_CPU1_G0_CPU0_G2_TX_DP<10>")
	)
	(segment
		(start 372.407942 -241.510058)
		(end 372.874794 -241.24412)
		(width 0.12954)
		(layer "F.Cu")
		(net "GMI_CPU1_G0_CPU0_G2_TX_DP<0>")
	)
	(segment
		(start 99.08794 -241.510312)
		(end 98.621088 -241.244374)
		(width 0.12954)
		(layer "F.Cu")
		(net "GMI_CPU1_G0_CPU0_G2_TX_DP<0>")
	)
	(segment
		(start 98.904044 -232.656888)
		(end 98.960686 -232.689908)
		(width 0.1143)
		(layer "In6.Cu")
		(net "GMI_CPU1_G0_CPU0_G2_TX_DP<0>")
	)
	(segment
		(start 98.870516 -231.017318)
		(end 98.904044 -231.036876)
		(width 0.1143)
		(layer "In6.Cu")
		(net "GMI_CPU1_G0_CPU0_G2_TX_DP<0>")
	)
	(segment
		(start 307.316886 -175.066452)
		(end 302.919384 -175.066452)
		(width 0.14224)
		(layer "In6.Cu")
		(net "GMI_CPU1_G0_CPU0_G2_TX_DP<0>")
	)
	(segment
		(start 371.213634 -224.739962)
		(end 371.203982 -224.734374)
		(width 0.1143)
		(layer "In6.Cu")
		(net "GMI_CPU1_G0_CPU0_G2_TX_DP<0>")
	)
	(segment
		(start 101.25964 -223.098868)
		(end 101.259386 -223.099122)
		(width 0.1143)
		(layer "In6.Cu")
		(net "GMI_CPU1_G0_CPU0_G2_TX_DP<0>")
	)
	(segment
		(start 108.884466 -208.236566)
		(end 108.588302 -208.53273)
		(width 0.14224)
		(layer "In6.Cu")
		(net "GMI_CPU1_G0_CPU0_G2_TX_DP<0>")
	)
	(segment
		(start 372.623588 -235.269786)
		(end 372.598696 -235.255308)
		(width 0.1143)
		(layer "In6.Cu")
		(net "GMI_CPU1_G0_CPU0_G2_TX_DP<0>")
	)
	(segment
		(start 372.779544 -229.093014)
		(end 372.77929 -229.090982)
		(width 0.1143)
		(layer "In6.Cu")
		(net "GMI_CPU1_G0_CPU0_G2_TX_DP<0>")
	)
	(segment
		(start 371.185948 -224.724214)
		(end 371.182646 -224.722182)
		(width 0.1143)
		(layer "In6.Cu")
		(net "GMI_CPU1_G0_CPU0_G2_TX_DP<0>")
	)
	(segment
		(start 374.033542 -237.699804)
		(end 374.001792 -237.681516)
		(width 0.1143)
		(layer "In6.Cu")
		(net "GMI_CPU1_G0_CPU0_G2_TX_DP<0>")
	)
	(segment
		(start 302.919384 -175.066452)
		(end 200.695052 -174.468282)
		(width 0.14224)
		(layer "In6.Cu")
		(net "GMI_CPU1_G0_CPU0_G2_TX_DP<0>")
	)
	(segment
		(start 98.960686 -232.689908)
		(end 98.962972 -232.691686)
		(width 0.1143)
		(layer "In6.Cu")
		(net "GMI_CPU1_G0_CPU0_G2_TX_DP<0>")
	)
	(segment
		(start 373.543322 -236.878368)
		(end 373.539512 -236.876082)
		(width 0.1143)
		(layer "In6.Cu")
		(net "GMI_CPU1_G0_CPU0_G2_TX_DP<0>")
	)
	(segment
		(start 100.313998 -224.721928)
		(end 100.313236 -224.722436)
		(width 0.1143)
		(layer "In6.Cu")
		(net "GMI_CPU1_G0_CPU0_G2_TX_DP<0>")
	)
	(segment
		(start 371.202204 -224.733358)
		(end 371.20068 -224.732596)
		(width 0.1143)
		(layer "In6.Cu")
		(net "GMI_CPU1_G0_CPU0_G2_TX_DP<0>")
	)
	(segment
		(start 370.238274 -223.099884)
		(end 370.237258 -223.099376)
		(width 0.1143)
		(layer "In6.Cu")
		(net "GMI_CPU1_G0_CPU0_G2_TX_DP<0>")
	)
	(segment
		(start 372.597426 -227.79355)
		(end 372.602506 -227.790756)
		(width 0.1143)
		(layer "In6.Cu")
		(net "GMI_CPU1_G0_CPU0_G2_TX_DP<0>")
	)
	(segment
		(start 105.942384 -211.368894)
		(end 105.752138 -211.368894)
		(width 0.14224)
		(layer "In6.Cu")
		(net "GMI_CPU1_G0_CPU0_G2_TX_DP<0>")
	)
	(segment
		(start 372.623588 -230.410004)
		(end 372.591838 -230.391716)
		(width 0.1143)
		(layer "In6.Cu")
		(net "GMI_CPU1_G0_CPU0_G2_TX_DP<0>")
	)
	(segment
		(start 104.30637 -212.814662)
		(end 103.389176 -214.187532)
		(width 0.14224)
		(layer "In6.Cu")
		(net "GMI_CPU1_G0_CPU0_G2_TX_DP<0>")
	)
	(segment
		(start 372.602252 -227.157534)
		(end 372.59387 -227.153724)
		(width 0.1143)
		(layer "In6.Cu")
		(net "GMI_CPU1_G0_CPU0_G2_TX_DP<0>")
	)
	(segment
		(start 98.898456 -232.653586)
		(end 98.903282 -232.65638)
		(width 0.1143)
		(layer "In6.Cu")
		(net "GMI_CPU1_G0_CPU0_G2_TX_DP<0>")
	)
	(segment
		(start 371.198902 -224.73158)
		(end 371.193314 -224.728532)
		(width 0.1143)
		(layer "In6.Cu")
		(net "GMI_CPU1_G0_CPU0_G2_TX_DP<0>")
	)
	(segment
		(start 200.694798 -174.468282)
		(end 166.650924 -174.269146)
		(width 0.14224)
		(layer "In6.Cu")
		(net "GMI_CPU1_G0_CPU0_G2_TX_DP<0>")
	)
	(segment
		(start 110.633764 -206.670402)
		(end 110.45063 -206.670402)
		(width 0.14224)
		(layer "In6.Cu")
		(net "GMI_CPU1_G0_CPU0_G2_TX_DP<0>")
	)
	(segment
		(start 98.893376 -227.79101)
		(end 98.898456 -227.793804)
		(width 0.1143)
		(layer "In6.Cu")
		(net "GMI_CPU1_G0_CPU0_G2_TX_DP<0>")
	)
	(segment
		(start 372.552722 -227.819712)
		(end 372.591838 -227.796852)
		(width 0.1143)
		(layer "In6.Cu")
		(net "GMI_CPU1_G0_CPU0_G2_TX_DP<0>")
	)
	(segment
		(start 370.742464 -223.929448)
		(end 370.672868 -223.888808)
		(width 0.1143)
		(layer "In6.Cu")
		(net "GMI_CPU1_G0_CPU0_G2_TX_DP<0>")
	)
	(segment
		(start 105.455974 -211.665058)
		(end 105.455974 -211.855304)
		(width 0.14224)
		(layer "In6.Cu")
		(net "GMI_CPU1_G0_CPU0_G2_TX_DP<0>")
	)
	(segment
		(start 109.371384 -207.939894)
		(end 109.074966 -208.236566)
		(width 0.14224)
		(layer "In6.Cu")
		(net "GMI_CPU1_G0_CPU0_G2_TX_DP<0>")
	)
	(segment
		(start 107.508802 -209.80273)
		(end 107.318302 -209.80273)
		(width 0.14224)
		(layer "In6.Cu")
		(net "GMI_CPU1_G0_CPU0_G2_TX_DP<0>")
	)
	(segment
		(start 372.597426 -232.653332)
		(end 372.602506 -232.650538)
		(width 0.1143)
		(layer "In6.Cu")
		(net "GMI_CPU1_G0_CPU0_G2_TX_DP<0>")
	)
	(segment
		(start 98.893376 -232.650792)
		(end 98.898456 -232.653586)
		(width 0.1143)
		(layer "In6.Cu")
		(net "GMI_CPU1_G0_CPU0_G2_TX_DP<0>")
	)
	(segment
		(start 101.259386 -223.099122)
		(end 101.258624 -223.09963)
		(width 0.1143)
		(layer "In6.Cu")
		(net "GMI_CPU1_G0_CPU0_G2_TX_DP<0>")
	)
	(segment
		(start 99.413314 -226.318826)
		(end 99.366832 -226.346258)
		(width 0.1143)
		(layer "In6.Cu")
		(net "GMI_CPU1_G0_CPU0_G2_TX_DP<0>")
	)
	(segment
		(start 370.236496 -223.098868)
		(end 370.236242 -223.098614)
		(width 0.1143)
		(layer "In6.Cu")
		(net "GMI_CPU1_G0_CPU0_G2_TX_DP<0>")
	)
	(segment
		(start 108.101384 -209.019648)
		(end 107.80522 -209.315812)
		(width 0.14224)
		(layer "In6.Cu")
		(net "GMI_CPU1_G0_CPU0_G2_TX_DP<0>")
	)
	(segment
		(start 373.54891 -236.881416)
		(end 373.543322 -236.878368)
		(width 0.1143)
		(layer "In6.Cu")
		(net "GMI_CPU1_G0_CPU0_G2_TX_DP<0>")
	)
	(segment
		(start 372.12905 -226.346004)
		(end 372.082568 -226.318572)
		(width 0.1143)
		(layer "In6.Cu")
		(net "GMI_CPU1_G0_CPU0_G2_TX_DP<0>")
	)
	(segment
		(start 101.257608 -223.100138)
		(end 101.254814 -223.101916)
		(width 0.1143)
		(layer "In6.Cu")
		(net "GMI_CPU1_G0_CPU0_G2_TX_DP<0>")
	)
	(segment
		(start 372.603014 -234.270296)
		(end 372.623842 -234.258358)
		(width 0.1143)
		(layer "In6.Cu")
		(net "GMI_CPU1_G0_CPU0_G2_TX_DP<0>")
	)
	(segment
		(start 105.455974 -211.855304)
		(end 105.159302 -212.151976)
		(width 0.14224)
		(layer "In6.Cu")
		(net "GMI_CPU1_G0_CPU0_G2_TX_DP<0>")
	)
	(segment
		(start 108.588302 -208.53273)
		(end 108.588302 -208.722976)
		(width 0.14224)
		(layer "In6.Cu")
		(net "GMI_CPU1_G0_CPU0_G2_TX_DP<0>")
	)
	(segment
		(start 98.240342 -241.16157)
		(end 98.323146 -241.244374)
		(width 0.1143)
		(layer "In6.Cu")
		(net "GMI_CPU1_G0_CPU0_G2_TX_DP<0>")
	)
	(segment
		(start 99.88042 -225.510852)
		(end 99.844098 -225.531934)
		(width 0.1143)
		(layer "In6.Cu")
		(net "GMI_CPU1_G0_CPU0_G2_TX_DP<0>")
	)
	(segment
		(start 98.903282 -232.65638)
		(end 98.904044 -232.656888)
		(width 0.1143)
		(layer "In6.Cu")
		(net "GMI_CPU1_G0_CPU0_G2_TX_DP<0>")
	)
	(segment
		(start 371.651784 -225.53168)
		(end 371.615462 -225.510598)
		(width 0.1143)
		(layer "In6.Cu")
		(net "GMI_CPU1_G0_CPU0_G2_TX_DP<0>")
	)
	(segment
		(start 102.051612 -217.416634)
		(end 102.051612 -221.064836)
		(width 0.14224)
		(layer "In6.Cu")
		(net "GMI_CPU1_G0_CPU0_G2_TX_DP<0>")
	)
	(segment
		(start 372.61673 -228.786944)
		(end 372.615206 -228.785928)
		(width 0.1143)
		(layer "In6.Cu")
		(net "GMI_CPU1_G0_CPU0_G2_TX_DP<0>")
	)
	(segment
		(start 371.193314 -224.728532)
		(end 371.189504 -224.726246)
		(width 0.1143)
		(layer "In6.Cu")
		(net "GMI_CPU1_G0_CPU0_G2_TX_DP<0>")
	)
	(segment
		(start 372.602506 -232.650538)
		(end 372.623588 -232.638346)
		(width 0.1143)
		(layer "In6.Cu")
		(net "GMI_CPU1_G0_CPU0_G2_TX_DP<0>")
	)
	(segment
		(start 98.89363 -234.270804)
		(end 98.903282 -234.276392)
		(width 0.1143)
		(layer "In6.Cu")
		(net "GMI_CPU1_G0_CPU0_G2_TX_DP<0>")
	)
	(segment
		(start 371.189504 -224.726246)
		(end 371.188742 -224.725738)
		(width 0.1143)
		(layer "In6.Cu")
		(net "GMI_CPU1_G0_CPU0_G2_TX_DP<0>")
	)
	(segment
		(start 107.80522 -209.506058)
		(end 107.508802 -209.80273)
		(width 0.14224)
		(layer "In6.Cu")
		(net "GMI_CPU1_G0_CPU0_G2_TX_DP<0>")
	)
	(segment
		(start 98.003106 -236.848904)
		(end 97.96399 -236.871764)
		(width 0.1143)
		(layer "In6.Cu")
		(net "GMI_CPU1_G0_CPU0_G2_TX_DP<0>")
	)
	(segment
		(start 101.254814 -223.101916)
		(end 101.239066 -223.110552)
		(width 0.1143)
		(layer "In6.Cu")
		(net "GMI_CPU1_G0_CPU0_G2_TX_DP<0>")
	)
	(segment
		(start 371.203982 -224.734374)
		(end 371.202204 -224.733358)
		(width 0.1143)
		(layer "In6.Cu")
		(net "GMI_CPU1_G0_CPU0_G2_TX_DP<0>")
	)
	(segment
		(start 369.44427 -221.107508)
		(end 369.44427 -221.09303)
		(width 0.1143)
		(layer "In6.Cu")
		(net "GMI_CPU1_G0_CPU0_G2_TX_DP<0>")
	)
	(segment
		(start 98.94316 -231.988868)
		(end 98.90506 -232.011474)
		(width 0.1143)
		(layer "In6.Cu")
		(net "GMI_CPU1_G0_CPU0_G2_TX_DP<0>")
	)
	(segment
		(start 369.48999 -221.2467)
		(end 369.48999 -221.153228)
		(width 0.1143)
		(layer "In6.Cu")
		(net "GMI_CPU1_G0_CPU0_G2_TX_DP<0>")
	)
	(segment
		(start 98.910902 -227.148136)
		(end 98.902012 -227.153978)
		(width 0.1143)
		(layer "In6.Cu")
		(net "GMI_CPU1_G0_CPU0_G2_TX_DP<0>")
	)
	(segment
		(start 373.492776 -240.779554)
		(end 373.531892 -240.756694)
		(width 0.1143)
		(layer "In6.Cu")
		(net "GMI_CPU1_G0_CPU0_G2_TX_DP<0>")
	)
	(segment
		(start 97.963228 -236.872272)
		(end 97.93224 -236.890052)
		(width 0.1143)
		(layer "In6.Cu")
		(net "GMI_CPU1_G0_CPU0_G2_TX_DP<0>")
	)
	(segment
		(start 372.597934 -235.2548)
		(end 372.595902 -235.253784)
		(width 0.1143)
		(layer "In6.Cu")
		(net "GMI_CPU1_G0_CPU0_G2_TX_DP<0>")
	)
	(segment
		(start 370.237258 -223.099376)
		(end 370.236496 -223.098868)
		(width 0.1143)
		(layer "In6.Cu")
		(net "GMI_CPU1_G0_CPU0_G2_TX_DP<0>")
	)
	(segment
		(start 374.001792 -238.326676)
		(end 374.033542 -238.308388)
		(width 0.1143)
		(layer "In6.Cu")
		(net "GMI_CPU1_G0_CPU0_G2_TX_DP<0>")
	)
	(segment
		(start 372.5926 -227.796344)
		(end 372.597426 -227.79355)
		(width 0.1143)
		(layer "In6.Cu")
		(net "GMI_CPU1_G0_CPU0_G2_TX_DP<0>")
	)
	(segment
		(start 97.46234 -238.308642)
		(end 97.49409 -238.32693)
		(width 0.1143)
		(layer "In6.Cu")
		(net "GMI_CPU1_G0_CPU0_G2_TX_DP<0>")
	)
	(segment
		(start 371.182646 -224.722182)
		(end 371.181884 -224.721674)
		(width 0.1143)
		(layer "In6.Cu")
		(net "GMI_CPU1_G0_CPU0_G2_TX_DP<0>")
	)
	(segment
		(start 98.90506 -235.251244)
		(end 98.904044 -235.251752)
		(width 0.1143)
		(layer "In6.Cu")
		(net "GMI_CPU1_G0_CPU0_G2_TX_DP<0>")
	)
	(segment
		(start 98.880676 -228.786182)
		(end 98.879152 -228.787198)
		(width 0.1143)
		(layer "In6.Cu")
		(net "GMI_CPU1_G0_CPU0_G2_TX_DP<0>")
	)
	(segment
		(start 373.552212 -236.883194)
		(end 373.550688 -236.882432)
		(width 0.1143)
		(layer "In6.Cu")
		(net "GMI_CPU1_G0_CPU0_G2_TX_DP<0>")
	)
	(segment
		(start 98.943668 -228.748844)
		(end 98.880676 -228.786182)
		(width 0.1143)
		(layer "In6.Cu")
		(net "GMI_CPU1_G0_CPU0_G2_TX_DP<0>")
	)
	(segment
		(start 373.092472 -236.079284)
		(end 373.022876 -236.038644)
		(width 0.1143)
		(layer "In6.Cu")
		(net "GMI_CPU1_G0_CPU0_G2_TX_DP<0>")
	)
	(segment
		(start 374.001792 -239.301528)
		(end 373.96547 -239.280446)
		(width 0.1143)
		(layer "In6.Cu")
		(net "GMI_CPU1_G0_CPU0_G2_TX_DP<0>")
	)
	(segment
		(start 372.590822 -235.25099)
		(end 372.589298 -235.249974)
		(width 0.1143)
		(layer "In6.Cu")
		(net "GMI_CPU1_G0_CPU0_G2_TX_DP<0>")
	)
	(segment
		(start 372.591838 -232.656634)
		(end 372.5926 -232.656126)
		(width 0.1143)
		(layer "In6.Cu")
		(net "GMI_CPU1_G0_CPU0_G2_TX_DP<0>")
	)
	(segment
		(start 109.371384 -207.749648)
		(end 109.371384 -207.939894)
		(width 0.14224)
		(layer "In6.Cu")
		(net "GMI_CPU1_G0_CPU0_G2_TX_DP<0>")
	)
	(segment
		(start 372.874794 -241.24412)
		(end 373.172736 -241.24412)
		(width 0.1143)
		(layer "In6.Cu")
		(net "GMI_CPU1_G0_CPU0_G2_TX_DP<0>")
	)
	(segment
		(start 372.638828 -232.043224)
		(end 372.590822 -232.01122)
		(width 0.1143)
		(layer "In6.Cu")
		(net "GMI_CPU1_G0_CPU0_G2_TX_DP<0>")
	)
	(segment
		(start 373.96547 -238.347758)
		(end 374.001792 -238.326676)
		(width 0.1143)
		(layer "In6.Cu")
		(net "GMI_CPU1_G0_CPU0_G2_TX_DP<0>")
	)
	(segment
		(start 105.752138 -211.368894)
		(end 105.455974 -211.665058)
		(width 0.14224)
		(layer "In6.Cu")
		(net "GMI_CPU1_G0_CPU0_G2_TX_DP<0>")
	)
	(segment
		(start 101.239066 -223.110552)
		(end 101.222302 -223.120204)
		(width 0.1143)
		(layer "In6.Cu")
		(net "GMI_CPU1_G0_CPU0_G2_TX_DP<0>")
	)
	(segment
		(start 107.022138 -210.098894)
		(end 107.022138 -210.28914)
		(width 0.14224)
		(layer "In6.Cu")
		(net "GMI_CPU1_G0_CPU0_G2_TX_DP<0>")
	)
	(segment
		(start 369.44427 -217.943938)
		(end 368.186716 -214.905844)
		(width 0.14224)
		(layer "In6.Cu")
		(net "GMI_CPU1_G0_CPU0_G2_TX_DP<0>")
	)
	(segment
		(start 97.49409 -237.68177)
		(end 97.46234 -237.700058)
		(width 0.1143)
		(layer "In6.Cu")
		(net "GMI_CPU1_G0_CPU0_G2_TX_DP<0>")
	)
	(segment
		(start 102.005892 -221.139004)
		(end 102.005892 -221.246954)
		(width 0.1143)
		(layer "In6.Cu")
		(net "GMI_CPU1_G0_CPU0_G2_TX_DP<0>")
	)
	(segment
		(start 98.904044 -230.39197)
		(end 98.872294 -230.410258)
		(width 0.1143)
		(layer "In6.Cu")
		(net "GMI_CPU1_G0_CPU0_G2_TX_DP<0>")
	)
	(segment
		(start 110.45063 -206.670402)
		(end 110.154466 -206.966566)
		(width 0.14224)
		(layer "In6.Cu")
		(net "GMI_CPU1_G0_CPU0_G2_TX_DP<0>")
	)
	(segment
		(start 372.602252 -234.27055)
		(end 372.603014 -234.270296)
		(width 0.1143)
		(layer "In6.Cu")
		(net "GMI_CPU1_G0_CPU0_G2_TX_DP<0>")
	)
	(segment
		(start 98.903282 -227.796598)
		(end 98.904044 -227.797106)
		(width 0.1143)
		(layer "In6.Cu")
		(net "GMI_CPU1_G0_CPU0_G2_TX_DP<0>")
	)
	(segment
		(start 106.239056 -211.072222)
		(end 105.942384 -211.368894)
		(width 0.14224)
		(layer "In6.Cu")
		(net "GMI_CPU1_G0_CPU0_G2_TX_DP<0>")
	)
	(segment
		(start 106.239056 -210.881976)
		(end 106.239056 -211.072222)
		(width 0.14224)
		(layer "In6.Cu")
		(net "GMI_CPU1_G0_CPU0_G2_TX_DP<0>")
	)
	(segment
		(start 98.872294 -232.6386)
		(end 98.893376 -232.650792)
		(width 0.1143)
		(layer "In6.Cu")
		(net "GMI_CPU1_G0_CPU0_G2_TX_DP<0>")
	)
	(segment
		(start 372.627398 -228.79304)
		(end 372.61673 -228.786944)
		(width 0.1143)
		(layer "In6.Cu")
		(net "GMI_CPU1_G0_CPU0_G2_TX_DP<0>")
	)
	(segment
		(start 373.55399 -236.88421)
		(end 373.552212 -236.883194)
		(width 0.1143)
		(layer "In6.Cu")
		(net "GMI_CPU1_G0_CPU0_G2_TX_DP<0>")
	)
	(segment
		(start 357.562912 -205.327758)
		(end 332.253844 -189.440566)
		(width 0.14224)
		(layer "In6.Cu")
		(net "GMI_CPU1_G0_CPU0_G2_TX_DP<0>")
	)
	(segment
		(start 103.389176 -214.187532)
		(end 102.051612 -217.416634)
		(width 0.14224)
		(layer "In6.Cu")
		(net "GMI_CPU1_G0_CPU0_G2_TX_DP<0>")
	)
	(segment
		(start 97.530412 -237.660688)
		(end 97.49409 -237.68177)
		(width 0.1143)
		(layer "In6.Cu")
		(net "GMI_CPU1_G0_CPU0_G2_TX_DP<0>")
	)
	(segment
		(start 97.963228 -240.75644)
		(end 97.96399 -240.756948)
		(width 0.1143)
		(layer "In6.Cu")
		(net "GMI_CPU1_G0_CPU0_G2_TX_DP<0>")
	)
	(segment
		(start 110.154466 -207.156812)
		(end 109.858048 -207.453484)
		(width 0.14224)
		(layer "In6.Cu")
		(net "GMI_CPU1_G0_CPU0_G2_TX_DP<0>")
	)
	(segment
		(start 98.902012 -227.153978)
		(end 98.89363 -227.157788)
		(width 0.1143)
		(layer "In6.Cu")
		(net "GMI_CPU1_G0_CPU0_G2_TX_DP<0>")
	)
	(segment
		(start 373.563642 -236.889798)
		(end 373.55399 -236.88421)
		(width 0.1143)
		(layer "In6.Cu")
		(net "GMI_CPU1_G0_CPU0_G2_TX_DP<0>")
	)
	(segment
		(start 368.186716 -214.905844)
		(end 367.844578 -214.393526)
		(width 0.14224)
		(layer "In6.Cu")
		(net "GMI_CPU1_G0_CPU0_G2_TX_DP<0>")
	)
	(segment
		(start 98.716338 -229.093268)
		(end 98.716338 -229.094538)
		(width 0.1143)
		(layer "In6.Cu")
		(net "GMI_CPU1_G0_CPU0_G2_TX_DP<0>")
	)
	(segment
		(start 97.49409 -238.32693)
		(end 97.530412 -238.348012)
		(width 0.1143)
		(layer "In6.Cu")
		(net "GMI_CPU1_G0_CPU0_G2_TX_DP<0>")
	)
	(segment
		(start 104.969056 -212.151976)
		(end 104.30637 -212.814662)
		(width 0.14224)
		(layer "In6.Cu")
		(net "GMI_CPU1_G0_CPU0_G2_TX_DP<0>")
	)
	(segment
		(start 370.27358 -223.11995)
		(end 370.256816 -223.110298)
		(width 0.1143)
		(layer "In6.Cu")
		(net "GMI_CPU1_G0_CPU0_G2_TX_DP<0>")
	)
	(segment
		(start 98.90506 -232.011474)
		(end 98.857054 -232.043478)
		(width 0.1143)
		(layer "In6.Cu")
		(net "GMI_CPU1_G0_CPU0_G2_TX_DP<0>")
	)
	(segment
		(start 372.630446 -233.654854)
		(end 372.626382 -233.652314)
		(width 0.1143)
		(layer "In6.Cu")
		(net "GMI_CPU1_G0_CPU0_G2_TX_DP<0>")
	)
	(segment
		(start 101.763068 -222.26905)
		(end 101.693218 -222.30969)
		(width 0.1143)
		(layer "In6.Cu")
		(net "GMI_CPU1_G0_CPU0_G2_TX_DP<0>")
	)
	(segment
		(start 371.188742 -224.725738)
		(end 371.185948 -224.724214)
		(width 0.1143)
		(layer "In6.Cu")
		(net "GMI_CPU1_G0_CPU0_G2_TX_DP<0>")
	)
	(segment
		(start 372.589298 -233.630216)
		(end 372.588282 -233.629708)
		(width 0.1143)
		(layer "In6.Cu")
		(net "GMI_CPU1_G0_CPU0_G2_TX_DP<0>")
	)
	(segment
		(start 372.615206 -228.785928)
		(end 372.552214 -228.74859)
		(width 0.1143)
		(layer "In6.Cu")
		(net "GMI_CPU1_G0_CPU0_G2_TX_DP<0>")
	)
	(segment
		(start 372.595902 -235.253784)
		(end 372.59514 -235.253276)
		(width 0.1143)
		(layer "In6.Cu")
		(net "GMI_CPU1_G0_CPU0_G2_TX_DP<0>")
	)
	(segment
		(start 373.531892 -240.756694)
		(end 373.532654 -240.756186)
		(width 0.1143)
		(layer "In6.Cu")
		(net "GMI_CPU1_G0_CPU0_G2_TX_DP<0>")
	)
	(segment
		(start 98.829876 -234.22356)
		(end 98.87204 -234.258612)
		(width 0.1143)
		(layer "In6.Cu")
		(net "GMI_CPU1_G0_CPU0_G2_TX_DP<0>")
	)
	(segment
		(start 372.5926 -232.656126)
		(end 372.597426 -232.653332)
		(width 0.1143)
		(layer "In6.Cu")
		(net "GMI_CPU1_G0_CPU0_G2_TX_DP<0>")
	)
	(segment
		(start 98.904044 -227.797106)
		(end 98.94316 -227.819966)
		(width 0.1143)
		(layer "In6.Cu")
		(net "GMI_CPU1_G0_CPU0_G2_TX_DP<0>")
	)
	(segment
		(start 372.552722 -229.43947)
		(end 372.625366 -229.397052)
		(width 0.1143)
		(layer "In6.Cu")
		(net "GMI_CPU1_G0_CPU0_G2_TX_DP<0>")
	)
	(segment
		(start 373.531892 -236.87151)
		(end 373.492776 -236.84865)
		(width 0.1143)
		(layer "In6.Cu")
		(net "GMI_CPU1_G0_CPU0_G2_TX_DP<0>")
	)
	(segment
		(start 98.904044 -235.251752)
		(end 98.872294 -235.27004)
		(width 0.1143)
		(layer "In6.Cu")
		(net "GMI_CPU1_G0_CPU0_G2_TX_DP<0>")
	)
	(segment
		(start 101.258624 -223.09963)
		(end 101.257608 -223.100138)
		(width 0.1143)
		(layer "In6.Cu")
		(net "GMI_CPU1_G0_CPU0_G2_TX_DP<0>")
	)
	(segment
		(start 102.005892 -221.246954)
		(end 102.0064 -221.247462)
		(width 0.1143)
		(layer "In6.Cu")
		(net "GMI_CPU1_G0_CPU0_G2_TX_DP<0>")
	)
	(segment
		(start 109.667548 -207.453484)
		(end 109.371384 -207.749648)
		(width 0.14224)
		(layer "In6.Cu")
		(net "GMI_CPU1_G0_CPU0_G2_TX_DP<0>")
	)
	(segment
		(start 369.802664 -222.309436)
		(end 369.732814 -222.268796)
		(width 0.1143)
		(layer "In6.Cu")
		(net "GMI_CPU1_G0_CPU0_G2_TX_DP<0>")
	)
	(segment
		(start 98.87204 -234.258612)
		(end 98.892868 -234.27055)
		(width 0.1143)
		(layer "In6.Cu")
		(net "GMI_CPU1_G0_CPU0_G2_TX_DP<0>")
	)
	(segment
		(start 372.602506 -227.790756)
		(end 372.623588 -227.778564)
		(width 0.1143)
		(layer "In6.Cu")
		(net "GMI_CPU1_G0_CPU0_G2_TX_DP<0>")
	)
	(segment
		(start 100.783898 -223.911922)
		(end 100.753418 -223.929702)
		(width 0.1143)
		(layer "In6.Cu")
		(net "GMI_CPU1_G0_CPU0_G2_TX_DP<0>")
	)
	(segment
		(start 98.903282 -234.276392)
		(end 98.904044 -234.2769)
		(width 0.1143)
		(layer "In6.Cu")
		(net "GMI_CPU1_G0_CPU0_G2_TX_DP<0>")
	)
	(segment
		(start 329.85202 -187.237624)
		(end 311.10809 -176.107344)
		(width 0.14224)
		(layer "In6.Cu")
		(net "GMI_CPU1_G0_CPU0_G2_TX_DP<0>")
	)
	(segment
		(start 369.489482 -221.247208)
		(end 369.48999 -221.2467)
		(width 0.1143)
		(layer "In6.Cu")
		(net "GMI_CPU1_G0_CPU0_G2_TX_DP<0>")
	)
	(segment
		(start 371.20068 -224.732596)
		(end 371.198902 -224.73158)
		(width 0.1143)
		(layer "In6.Cu")
		(net "GMI_CPU1_G0_CPU0_G2_TX_DP<0>")
	)
	(segment
		(start 107.318302 -209.80273)
		(end 107.022138 -210.098894)
		(width 0.14224)
		(layer "In6.Cu")
		(net "GMI_CPU1_G0_CPU0_G2_TX_DP<0>")
	)
	(segment
		(start 98.43389 -236.061758)
		(end 98.40341 -236.079538)
		(width 0.1143)
		(layer "In6.Cu")
		(net "GMI_CPU1_G0_CPU0_G2_TX_DP<0>")
	)
	(segment
		(start 98.872294 -227.778818)
		(end 98.893376 -227.79101)
		(width 0.1143)
		(layer "In6.Cu")
		(net "GMI_CPU1_G0_CPU0_G2_TX_DP<0>")
	)
	(segment
		(start 372.591838 -234.276646)
		(end 372.5926 -234.276138)
		(width 0.1143)
		(layer "In6.Cu")
		(net "GMI_CPU1_G0_CPU0_G2_TX_DP<0>")
	)
	(segment
		(start 100.353114 -224.699068)
		(end 100.313998 -224.721928)
		(width 0.1143)
		(layer "In6.Cu")
		(net "GMI_CPU1_G0_CPU0_G2_TX_DP<0>")
	)
	(segment
		(start 98.904044 -234.2769)
		(end 98.94316 -234.29976)
		(width 0.1143)
		(layer "In6.Cu")
		(net "GMI_CPU1_G0_CPU0_G2_TX_DP<0>")
	)
	(segment
		(start 110.930436 -206.190596)
		(end 110.930436 -206.37373)
		(width 0.14224)
		(layer "In6.Cu")
		(net "GMI_CPU1_G0_CPU0_G2_TX_DP<0>")
	)
	(segment
		(start 98.904044 -229.416864)
		(end 98.94316 -229.439724)
		(width 0.1143)
		(layer "In6.Cu")
		(net "GMI_CPU1_G0_CPU0_G2_TX_DP<0>")
	)
	(segment
		(start 161.758122 -175.565308)
		(end 116.531644 -201.681842)
		(width 0.14224)
		(layer "In6.Cu")
		(net "GMI_CPU1_G0_CPU0_G2_TX_DP<0>")
	)
	(segment
		(start 106.53522 -210.585812)
		(end 106.239056 -210.881976)
		(width 0.14224)
		(layer "In6.Cu")
		(net "GMI_CPU1_G0_CPU0_G2_TX_DP<0>")
	)
	(segment
		(start 374.001792 -239.946688)
		(end 374.033542 -239.9284)
		(width 0.1143)
		(layer "In6.Cu")
		(net "GMI_CPU1_G0_CPU0_G2_TX_DP<0>")
	)
	(segment
		(start 373.532654 -240.756186)
		(end 373.563642 -240.738406)
		(width 0.1143)
		(layer "In6.Cu")
		(net "GMI_CPU1_G0_CPU0_G2_TX_DP<0>")
	)
	(segment
		(start 372.588282 -233.629708)
		(end 372.585742 -233.62793)
		(width 0.1143)
		(layer "In6.Cu")
		(net "GMI_CPU1_G0_CPU0_G2_TX_DP<0>")
	)
	(segment
		(start 98.879152 -228.787198)
		(end 98.868484 -228.793294)
		(width 0.1143)
		(layer "In6.Cu")
		(net "GMI_CPU1_G0_CPU0_G2_TX_DP<0>")
	)
	(segment
		(start 372.59514 -235.253276)
		(end 372.593108 -235.25226)
		(width 0.1143)
		(layer "In6.Cu")
		(net "GMI_CPU1_G0_CPU0_G2_TX_DP<0>")
	)
	(segment
		(start 372.598696 -235.255308)
		(end 372.597934 -235.2548)
		(width 0.1143)
		(layer "In6.Cu")
		(net "GMI_CPU1_G0_CPU0_G2_TX_DP<0>")
	)
	(segment
		(start 332.253844 -189.440566)
		(end 329.85202 -187.237624)
		(width 0.14224)
		(layer "In6.Cu")
		(net "GMI_CPU1_G0_CPU0_G2_TX_DP<0>")
	)
	(segment
		(start 98.906584 -235.250228)
		(end 98.90506 -235.251244)
		(width 0.1143)
		(layer "In6.Cu")
		(net "GMI_CPU1_G0_CPU0_G2_TX_DP<0>")
	)
	(segment
		(start 98.892868 -234.27055)
		(end 98.89363 -234.270804)
		(width 0.1143)
		(layer "In6.Cu")
		(net "GMI_CPU1_G0_CPU0_G2_TX_DP<0>")
	)
	(segment
		(start 371.683534 -225.549968)
		(end 371.651784 -225.53168)
		(width 0.1143)
		(layer "In6.Cu")
		(net "GMI_CPU1_G0_CPU0_G2_TX_DP<0>")
	)
	(segment
		(start 373.172736 -241.24412)
		(end 373.25554 -241.161316)
		(width 0.1143)
		(layer "In6.Cu")
		(net "GMI_CPU1_G0_CPU0_G2_TX_DP<0>")
	)
	(segment
		(start 98.904044 -231.036876)
		(end 98.94316 -231.059736)
		(width 0.1143)
		(layer "In6.Cu")
		(net "GMI_CPU1_G0_CPU0_G2_TX_DP<0>")
	)
	(segment
		(start 372.591838 -235.251498)
		(end 372.590822 -235.25099)
		(width 0.1143)
		(layer "In6.Cu")
		(net "GMI_CPU1_G0_CPU0_G2_TX_DP<0>")
	)
	(segment
		(start 98.857054 -232.043478)
		(end 98.854768 -232.043478)
		(width 0.1143)
		(layer "In6.Cu")
		(net "GMI_CPU1_G0_CPU0_G2_TX_DP<0>")
	)
	(segment
		(start 367.844578 -214.393526)
		(end 363.555026 -210.103974)
		(width 0.14224)
		(layer "In6.Cu")
		(net "GMI_CPU1_G0_CPU0_G2_TX_DP<0>")
	)
	(segment
		(start 97.96399 -236.871764)
		(end 97.963228 -236.872272)
		(width 0.1143)
		(layer "In6.Cu")
		(net "GMI_CPU1_G0_CPU0_G2_TX_DP<0>")
	)
	(segment
		(start 372.585742 -233.62793)
		(end 372.552722 -233.608626)
		(width 0.1143)
		(layer "In6.Cu")
		(net "GMI_CPU1_G0_CPU0_G2_TX_DP<0>")
	)
	(segment
		(start 372.641114 -232.043224)
		(end 372.638828 -232.043224)
		(width 0.1143)
		(layer "In6.Cu")
		(net "GMI_CPU1_G0_CPU0_G2_TX_DP<0>")
	)
	(segment
		(start 110.930436 -206.37373)
		(end 110.633764 -206.670402)
		(width 0.14224)
		(layer "In6.Cu")
		(net "GMI_CPU1_G0_CPU0_G2_TX_DP<0>")
	)
	(segment
		(start 100.823014 -223.889062)
		(end 100.783898 -223.911922)
		(width 0.1143)
		(layer "In6.Cu")
		(net "GMI_CPU1_G0_CPU0_G2_TX_DP<0>")
	)
	(segment
		(start 98.89363 -227.157788)
		(end 98.872294 -227.170234)
		(width 0.1143)
		(layer "In6.Cu")
		(net "GMI_CPU1_G0_CPU0_G2_TX_DP<0>")
	)
	(segment
		(start 372.590822 -232.01122)
		(end 372.552722 -231.988614)
		(width 0.1143)
		(layer "In6.Cu")
		(net "GMI_CPU1_G0_CPU0_G2_TX_DP<0>")
	)
	(segment
		(start 98.473006 -236.038898)
		(end 98.43389 -236.061758)
		(width 0.1143)
		(layer "In6.Cu")
		(net "GMI_CPU1_G0_CPU0_G2_TX_DP<0>")
	)
	(segment
		(start 102.051612 -221.064836)
		(end 102.051612 -221.093284)
		(width 0.1143)
		(layer "In6.Cu")
		(net "GMI_CPU1_G0_CPU0_G2_TX_DP<0>")
	)
	(segment
		(start 373.96547 -239.96777)
		(end 374.001792 -239.946688)
		(width 0.1143)
		(layer "In6.Cu")
		(net "GMI_CPU1_G0_CPU0_G2_TX_DP<0>")
	)
	(segment
		(start 107.80522 -209.315812)
		(end 107.80522 -209.506058)
		(width 0.14224)
		(layer "In6.Cu")
		(net "GMI_CPU1_G0_CPU0_G2_TX_DP<0>")
	)
	(segment
		(start 102.051612 -221.093284)
		(end 102.005892 -221.139004)
		(width 0.1143)
		(layer "In6.Cu")
		(net "GMI_CPU1_G0_CPU0_G2_TX_DP<0>")
	)
	(segment
		(start 372.552722 -232.679494)
		(end 372.591838 -232.656634)
		(width 0.1143)
		(layer "In6.Cu")
		(net "GMI_CPU1_G0_CPU0_G2_TX_DP<0>")
	)
	(segment
		(start 373.53875 -236.875574)
		(end 373.535956 -236.87405)
		(width 0.1143)
		(layer "In6.Cu")
		(net "GMI_CPU1_G0_CPU0_G2_TX_DP<0>")
	)
	(segment
		(start 372.589298 -235.249974)
		(end 372.552722 -235.228638)
		(width 0.1143)
		(layer "In6.Cu")
		(net "GMI_CPU1_G0_CPU0_G2_TX_DP<0>")
	)
	(segment
		(start 98.323146 -241.244374)
		(end 98.621088 -241.244374)
		(width 0.1143)
		(layer "In6.Cu")
		(net "GMI_CPU1_G0_CPU0_G2_TX_DP<0>")
	)
	(segment
		(start 369.48999 -221.153228)
		(end 369.44427 -221.107508)
		(width 0.1143)
		(layer "In6.Cu")
		(net "GMI_CPU1_G0_CPU0_G2_TX_DP<0>")
	)
	(segment
		(start 98.94316 -235.228892)
		(end 98.906584 -235.250228)
		(width 0.1143)
		(layer "In6.Cu")
		(net "GMI_CPU1_G0_CPU0_G2_TX_DP<0>")
	)
	(segment
		(start 372.626382 -233.652314)
		(end 372.589298 -233.630216)
		(width 0.1143)
		(layer "In6.Cu")
		(net "GMI_CPU1_G0_CPU0_G2_TX_DP<0>")
	)
	(segment
		(start 372.623588 -227.16998)
		(end 372.602252 -227.157534)
		(width 0.1143)
		(layer "In6.Cu")
		(net "GMI_CPU1_G0_CPU0_G2_TX_DP<0>")
	)
	(segment
		(start 374.033542 -239.319816)
		(end 374.001792 -239.301528)
		(width 0.1143)
		(layer "In6.Cu")
		(net "GMI_CPU1_G0_CPU0_G2_TX_DP<0>")
	)
	(segment
		(start 97.96399 -240.756948)
		(end 98.003106 -240.779808)
		(width 0.1143)
		(layer "In6.Cu")
		(net "GMI_CPU1_G0_CPU0_G2_TX_DP<0>")
	)
	(segment
		(start 108.291884 -209.019648)
		(end 108.101384 -209.019648)
		(width 0.14224)
		(layer "In6.Cu")
		(net "GMI_CPU1_G0_CPU0_G2_TX_DP<0>")
	)
	(segment
		(start 97.530412 -239.2807)
		(end 97.49409 -239.301782)
		(width 0.1143)
		(layer "In6.Cu")
		(net "GMI_CPU1_G0_CPU0_G2_TX_DP<0>")
	)
	(segment
		(start 372.5926 -234.276138)
		(end 372.602252 -234.27055)
		(width 0.1143)
		(layer "In6.Cu")
		(net "GMI_CPU1_G0_CPU0_G2_TX_DP<0>")
	)
	(segment
		(start 98.898456 -227.793804)
		(end 98.903282 -227.796598)
		(width 0.1143)
		(layer "In6.Cu")
		(net "GMI_CPU1_G0_CPU0_G2_TX_DP<0>")
	)
	(segment
		(start 373.535956 -236.87405)
		(end 373.532654 -236.872018)
		(width 0.1143)
		(layer "In6.Cu")
		(net "GMI_CPU1_G0_CPU0_G2_TX_DP<0>")
	)
	(segment
		(start 372.552722 -234.299506)
		(end 372.591838 -234.276646)
		(width 0.1143)
		(layer "In6.Cu")
		(net "GMI_CPU1_G0_CPU0_G2_TX_DP<0>")
	)
	(segment
		(start 111.834422 -205.28661)
		(end 110.930436 -206.190596)
		(width 0.14224)
		(layer "In6.Cu")
		(net "GMI_CPU1_G0_CPU0_G2_TX_DP<0>")
	)
	(segment
		(start 106.72572 -210.585812)
		(end 106.53522 -210.585812)
		(width 0.14224)
		(layer "In6.Cu")
		(net "GMI_CPU1_G0_CPU0_G2_TX_DP<0>")
	)
	(segment
		(start 373.539512 -236.876082)
		(end 373.53875 -236.875574)
		(width 0.1143)
		(layer "In6.Cu")
		(net "GMI_CPU1_G0_CPU0_G2_TX_DP<0>")
	)
	(segment
		(start 372.59387 -227.153724)
		(end 372.58498 -227.147882)
		(width 0.1143)
		(layer "In6.Cu")
		(net "GMI_CPU1_G0_CPU0_G2_TX_DP<0>")
	)
	(segment
		(start 372.779544 -229.094284)
		(end 372.779544 -229.093014)
		(width 0.1143)
		(layer "In6.Cu")
		(net "GMI_CPU1_G0_CPU0_G2_TX_DP<0>")
	)
	(segment
		(start 98.94062 -230.370634)
		(end 98.904044 -230.39197)
		(width 0.1143)
		(layer "In6.Cu")
		(net "GMI_CPU1_G0_CPU0_G2_TX_DP<0>")
	)
	(segment
		(start 109.074966 -208.236566)
		(end 108.884466 -208.236566)
		(width 0.14224)
		(layer "In6.Cu")
		(net "GMI_CPU1_G0_CPU0_G2_TX_DP<0>")
	)
	(segment
		(start 371.181884 -224.721674)
		(end 371.142768 -224.698814)
		(width 0.1143)
		(layer "In6.Cu")
		(net "GMI_CPU1_G0_CPU0_G2_TX_DP<0>")
	)
	(segment
		(start 311.10809 -176.107344)
		(end 307.316886 -175.066452)
		(width 0.14224)
		(layer "In6.Cu")
		(net "GMI_CPU1_G0_CPU0_G2_TX_DP<0>")
	)
	(segment
		(start 369.489482 -222.038418)
		(end 369.489482 -221.247208)
		(width 0.1143)
		(layer "In6.Cu")
		(net "GMI_CPU1_G0_CPU0_G2_TX_DP<0>")
	)
	(segment
		(start 97.93224 -240.73866)
		(end 97.963228 -240.75644)
		(width 0.1143)
		(layer "In6.Cu")
		(net "GMI_CPU1_G0_CPU0_G2_TX_DP<0>")
	)
	(segment
		(start 98.716592 -229.091236)
		(end 98.716338 -229.093268)
		(width 0.1143)
		(layer "In6.Cu")
		(net "GMI_CPU1_G0_CPU0_G2_TX_DP<0>")
	)
	(segment
		(start 99.844098 -225.531934)
		(end 99.812348 -225.550222)
		(width 0.1143)
		(layer "In6.Cu")
		(net "GMI_CPU1_G0_CPU0_G2_TX_DP<0>")
	)
	(segment
		(start 372.591838 -230.391716)
		(end 372.555262 -230.37038)
		(width 0.1143)
		(layer "In6.Cu")
		(net "GMI_CPU1_G0_CPU0_G2_TX_DP<0>")
	)
	(segment
		(start 107.022138 -210.28914)
		(end 106.72572 -210.585812)
		(width 0.14224)
		(layer "In6.Cu")
		(net "GMI_CPU1_G0_CPU0_G2_TX_DP<0>")
	)
	(segment
		(start 200.695052 -174.468282)
		(end 200.694798 -174.468282)
		(width 0.14224)
		(layer "In6.Cu")
		(net "GMI_CPU1_G0_CPU0_G2_TX_DP<0>")
	)
	(segment
		(start 100.313236 -224.722436)
		(end 100.282248 -224.740216)
		(width 0.1143)
		(layer "In6.Cu")
		(net "GMI_CPU1_G0_CPU0_G2_TX_DP<0>")
	)
	(segment
		(start 369.44427 -221.09303)
		(end 369.44427 -217.943938)
		(width 0.14224)
		(layer "In6.Cu")
		(net "GMI_CPU1_G0_CPU0_G2_TX_DP<0>")
	)
	(segment
		(start 116.531644 -201.681842)
		(end 111.834422 -205.28661)
		(width 0.14224)
		(layer "In6.Cu")
		(net "GMI_CPU1_G0_CPU0_G2_TX_DP<0>")
	)
	(segment
		(start 370.256816 -223.110298)
		(end 370.241068 -223.101662)
		(width 0.1143)
		(layer "In6.Cu")
		(net "GMI_CPU1_G0_CPU0_G2_TX_DP<0>")
	)
	(segment
		(start 102.0064 -221.247462)
		(end 102.0064 -222.038672)
		(width 0.1143)
		(layer "In6.Cu")
		(net "GMI_CPU1_G0_CPU0_G2_TX_DP<0>")
	)
	(segment
		(start 97.49409 -239.301782)
		(end 97.46234 -239.32007)
		(width 0.1143)
		(layer "In6.Cu")
		(net "GMI_CPU1_G0_CPU0_G2_TX_DP<0>")
	)
	(segment
		(start 373.550688 -236.882432)
		(end 373.54891 -236.881416)
		(width 0.1143)
		(layer "In6.Cu")
		(net "GMI_CPU1_G0_CPU0_G2_TX_DP<0>")
	)
	(segment
		(start 98.904552 -233.63809)
		(end 98.860356 -233.665776)
		(width 0.1143)
		(layer "In6.Cu")
		(net "GMI_CPU1_G0_CPU0_G2_TX_DP<0>")
	)
	(segment
		(start 363.555026 -210.103974)
		(end 357.562912 -205.327758)
		(width 0.14224)
		(layer "In6.Cu")
		(net "GMI_CPU1_G0_CPU0_G2_TX_DP<0>")
	)
	(segment
		(start 97.46234 -239.928654)
		(end 97.49409 -239.946942)
		(width 0.1143)
		(layer "In6.Cu")
		(net "GMI_CPU1_G0_CPU0_G2_TX_DP<0>")
	)
	(segment
		(start 370.241068 -223.101662)
		(end 370.238274 -223.099884)
		(width 0.1143)
		(layer "In6.Cu")
		(net "GMI_CPU1_G0_CPU0_G2_TX_DP<0>")
	)
	(segment
		(start 108.588302 -208.722976)
		(end 108.291884 -209.019648)
		(width 0.14224)
		(layer "In6.Cu")
		(net "GMI_CPU1_G0_CPU0_G2_TX_DP<0>")
	)
	(segment
		(start 105.159302 -212.151976)
		(end 104.969056 -212.151976)
		(width 0.14224)
		(layer "In6.Cu")
		(net "GMI_CPU1_G0_CPU0_G2_TX_DP<0>")
	)
	(segment
		(start 372.593108 -235.25226)
		(end 372.591838 -235.251498)
		(width 0.1143)
		(layer "In6.Cu")
		(net "GMI_CPU1_G0_CPU0_G2_TX_DP<0>")
	)
	(segment
		(start 110.154466 -206.966566)
		(end 110.154466 -207.156812)
		(width 0.14224)
		(layer "In6.Cu")
		(net "GMI_CPU1_G0_CPU0_G2_TX_DP<0>")
	)
	(segment
		(start 373.532654 -236.872018)
		(end 373.531892 -236.87151)
		(width 0.1143)
		(layer "In6.Cu")
		(net "GMI_CPU1_G0_CPU0_G2_TX_DP<0>")
	)
	(segment
		(start 374.001792 -237.681516)
		(end 373.96547 -237.660434)
		(width 0.1143)
		(layer "In6.Cu")
		(net "GMI_CPU1_G0_CPU0_G2_TX_DP<0>")
	)
	(segment
		(start 98.870516 -229.397306)
		(end 98.904044 -229.416864)
		(width 0.1143)
		(layer "In6.Cu")
		(net "GMI_CPU1_G0_CPU0_G2_TX_DP<0>")
	)
	(segment
		(start 166.650924 -174.269146)
		(end 161.758122 -175.565308)
		(width 0.14224)
		(layer "In6.Cu")
		(net "GMI_CPU1_G0_CPU0_G2_TX_DP<0>")
	)
	(segment
		(start 97.49409 -239.946942)
		(end 97.530412 -239.968024)
		(width 0.1143)
		(layer "In6.Cu")
		(net "GMI_CPU1_G0_CPU0_G2_TX_DP<0>")
	)
	(segment
		(start 109.858048 -207.453484)
		(end 109.667548 -207.453484)
		(width 0.14224)
		(layer "In6.Cu")
		(net "GMI_CPU1_G0_CPU0_G2_TX_DP<0>")
	)
	(segment
		(start 372.591838 -227.796852)
		(end 372.5926 -227.796344)
		(width 0.1143)
		(layer "In6.Cu")
		(net "GMI_CPU1_G0_CPU0_G2_TX_DP<0>")
	)
	(segment
		(start 372.552722 -231.059482)
		(end 372.625366 -231.017064)
		(width 0.1143)
		(layer "In6.Cu")
		(net "GMI_CPU1_G0_CPU0_G2_TX_DP<0>")
	)
	(arc
		(start 371.36959 -225.044254)
		(mid 371.328335 -224.873283)
		(end 371.213634 -224.739962)
		(width 0.1143)
		(layer "In6.Cu")
		(net "GMI_CPU1_G0_CPU0_G2_TX_DP<0>")
	)
	(arc
		(start 100.282248 -224.740216)
		(mid 100.167572 -224.87355)
		(end 100.126292 -225.044508)
		(width 0.1143)
		(layer "In6.Cu")
		(net "GMI_CPU1_G0_CPU0_G2_TX_DP<0>")
	)
	(arc
		(start 101.693218 -222.30969)
		(mid 101.578033 -222.443134)
		(end 101.536754 -222.61449)
		(width 0.1143)
		(layer "In6.Cu")
		(net "GMI_CPU1_G0_CPU0_G2_TX_DP<0>")
	)
	(arc
		(start 99.812348 -225.550222)
		(mid 99.697672 -225.683556)
		(end 99.656392 -225.854514)
		(width 0.1143)
		(layer "In6.Cu")
		(net "GMI_CPU1_G0_CPU0_G2_TX_DP<0>")
	)
	(arc
		(start 101.066346 -223.424496)
		(mid 101.001831 -223.686715)
		(end 100.823014 -223.889062)
		(width 0.1143)
		(layer "In6.Cu")
		(net "GMI_CPU1_G0_CPU0_G2_TX_DP<0>")
	)
	(arc
		(start 372.555262 -230.37038)
		(mid 372.37461 -230.167635)
		(end 372.30939 -229.904036)
		(width 0.1143)
		(layer "In6.Cu")
		(net "GMI_CPU1_G0_CPU0_G2_TX_DP<0>")
	)
	(arc
		(start 370.899436 -224.234248)
		(mid 370.857887 -224.062826)
		(end 370.742464 -223.929448)
		(width 0.1143)
		(layer "In6.Cu")
		(net "GMI_CPU1_G0_CPU0_G2_TX_DP<0>")
	)
	(arc
		(start 100.126292 -225.044508)
		(mid 100.061056 -225.308099)
		(end 99.88042 -225.510852)
		(width 0.1143)
		(layer "In6.Cu")
		(net "GMI_CPU1_G0_CPU0_G2_TX_DP<0>")
	)
	(arc
		(start 372.58498 -227.147882)
		(mid 372.385587 -226.941993)
		(end 372.312946 -226.664774)
		(width 0.1143)
		(layer "In6.Cu")
		(net "GMI_CPU1_G0_CPU0_G2_TX_DP<0>")
	)
	(arc
		(start 98.77552 -233.742484)
		(mid 98.705773 -233.993994)
		(end 98.829876 -234.22356)
		(width 0.1143)
		(layer "In6.Cu")
		(net "GMI_CPU1_G0_CPU0_G2_TX_DP<0>")
	)
	(arc
		(start 101.222302 -223.120204)
		(mid 101.107626 -223.253538)
		(end 101.066346 -223.424496)
		(width 0.1143)
		(layer "In6.Cu")
		(net "GMI_CPU1_G0_CPU0_G2_TX_DP<0>")
	)
	(arc
		(start 372.312946 -226.664774)
		(mid 372.263682 -226.48076)
		(end 372.12905 -226.346004)
		(width 0.1143)
		(layer "In6.Cu")
		(net "GMI_CPU1_G0_CPU0_G2_TX_DP<0>")
	)
	(arc
		(start 98.246438 -236.384338)
		(mid 98.181923 -236.646557)
		(end 98.003106 -236.848904)
		(width 0.1143)
		(layer "In6.Cu")
		(net "GMI_CPU1_G0_CPU0_G2_TX_DP<0>")
	)
	(arc
		(start 373.25554 -241.161316)
		(mid 373.33457 -240.945833)
		(end 373.492776 -240.779554)
		(width 0.1143)
		(layer "In6.Cu")
		(net "GMI_CPU1_G0_CPU0_G2_TX_DP<0>")
	)
	(arc
		(start 98.94316 -229.439724)
		(mid 99.121973 -229.642074)
		(end 99.186492 -229.90429)
		(width 0.1143)
		(layer "In6.Cu")
		(net "GMI_CPU1_G0_CPU0_G2_TX_DP<0>")
	)
	(arc
		(start 100.596446 -224.234502)
		(mid 100.531931 -224.496721)
		(end 100.353114 -224.699068)
		(width 0.1143)
		(layer "In6.Cu")
		(net "GMI_CPU1_G0_CPU0_G2_TX_DP<0>")
	)
	(arc
		(start 98.003106 -240.779808)
		(mid 98.161305 -240.946092)
		(end 98.240342 -241.16157)
		(width 0.1143)
		(layer "In6.Cu")
		(net "GMI_CPU1_G0_CPU0_G2_TX_DP<0>")
	)
	(arc
		(start 99.186492 -229.90429)
		(mid 99.121256 -230.167881)
		(end 98.94062 -230.370634)
		(width 0.1143)
		(layer "In6.Cu")
		(net "GMI_CPU1_G0_CPU0_G2_TX_DP<0>")
	)
	(arc
		(start 372.082568 -226.318572)
		(mid 371.90422 -226.11674)
		(end 371.83949 -225.855276)
		(width 0.1143)
		(layer "In6.Cu")
		(net "GMI_CPU1_G0_CPU0_G2_TX_DP<0>")
	)
	(arc
		(start 97.93224 -236.890052)
		(mid 97.817564 -237.023386)
		(end 97.776284 -237.194344)
		(width 0.1143)
		(layer "In6.Cu")
		(net "GMI_CPU1_G0_CPU0_G2_TX_DP<0>")
	)
	(arc
		(start 370.429536 -223.424242)
		(mid 370.388281 -223.253271)
		(end 370.27358 -223.11995)
		(width 0.1143)
		(layer "In6.Cu")
		(net "GMI_CPU1_G0_CPU0_G2_TX_DP<0>")
	)
	(arc
		(start 98.716338 -229.094538)
		(mid 98.7571 -229.264422)
		(end 98.870516 -229.397306)
		(width 0.1143)
		(layer "In6.Cu")
		(net "GMI_CPU1_G0_CPU0_G2_TX_DP<0>")
	)
	(arc
		(start 369.959128 -222.614236)
		(mid 369.917765 -222.442923)
		(end 369.802664 -222.309436)
		(width 0.1143)
		(layer "In6.Cu")
		(net "GMI_CPU1_G0_CPU0_G2_TX_DP<0>")
	)
	(arc
		(start 373.719598 -237.19409)
		(mid 373.678343 -237.023119)
		(end 373.563642 -236.889798)
		(width 0.1143)
		(layer "In6.Cu")
		(net "GMI_CPU1_G0_CPU0_G2_TX_DP<0>")
	)
	(arc
		(start 374.033542 -239.9284)
		(mid 374.18947 -239.624108)
		(end 374.033542 -239.319816)
		(width 0.1143)
		(layer "In6.Cu")
		(net "GMI_CPU1_G0_CPU0_G2_TX_DP<0>")
	)
	(arc
		(start 98.872294 -235.27004)
		(mid 98.757618 -235.403374)
		(end 98.716338 -235.574332)
		(width 0.1143)
		(layer "In6.Cu")
		(net "GMI_CPU1_G0_CPU0_G2_TX_DP<0>")
	)
	(arc
		(start 373.492776 -236.84865)
		(mid 373.313963 -236.6463)
		(end 373.249444 -236.384084)
		(width 0.1143)
		(layer "In6.Cu")
		(net "GMI_CPU1_G0_CPU0_G2_TX_DP<0>")
	)
	(arc
		(start 98.872294 -227.170234)
		(mid 98.716366 -227.474526)
		(end 98.872294 -227.778818)
		(width 0.1143)
		(layer "In6.Cu")
		(net "GMI_CPU1_G0_CPU0_G2_TX_DP<0>")
	)
	(arc
		(start 373.022876 -236.038644)
		(mid 372.844063 -235.836294)
		(end 372.779544 -235.574078)
		(width 0.1143)
		(layer "In6.Cu")
		(net "GMI_CPU1_G0_CPU0_G2_TX_DP<0>")
	)
	(arc
		(start 98.868484 -228.793294)
		(mid 98.76063 -228.926002)
		(end 98.716592 -229.091236)
		(width 0.1143)
		(layer "In6.Cu")
		(net "GMI_CPU1_G0_CPU0_G2_TX_DP<0>")
	)
	(arc
		(start 372.625366 -231.017064)
		(mid 372.738773 -230.884175)
		(end 372.779544 -230.714296)
		(width 0.1143)
		(layer "In6.Cu")
		(net "GMI_CPU1_G0_CPU0_G2_TX_DP<0>")
	)
	(arc
		(start 372.552722 -233.608626)
		(mid 372.309395 -233.14406)
		(end 372.552722 -232.679494)
		(width 0.1143)
		(layer "In6.Cu")
		(net "GMI_CPU1_G0_CPU0_G2_TX_DP<0>")
	)
	(arc
		(start 369.732814 -222.268796)
		(mid 369.594229 -222.171472)
		(end 369.489482 -222.038418)
		(width 0.1143)
		(layer "In6.Cu")
		(net "GMI_CPU1_G0_CPU0_G2_TX_DP<0>")
	)
	(arc
		(start 371.83949 -225.85426)
		(mid 371.798235 -225.683289)
		(end 371.683534 -225.549968)
		(width 0.1143)
		(layer "In6.Cu")
		(net "GMI_CPU1_G0_CPU0_G2_TX_DP<0>")
	)
	(arc
		(start 371.83949 -225.855276)
		(mid 371.83949 -225.854768)
		(end 371.83949 -225.85426)
		(width 0.1143)
		(layer "In6.Cu")
		(net "GMI_CPU1_G0_CPU0_G2_TX_DP<0>")
	)
	(arc
		(start 102.0064 -222.038672)
		(mid 101.90162 -222.171691)
		(end 101.763068 -222.26905)
		(width 0.1143)
		(layer "In6.Cu")
		(net "GMI_CPU1_G0_CPU0_G2_TX_DP<0>")
	)
	(arc
		(start 372.77929 -229.090982)
		(mid 372.735221 -228.925764)
		(end 372.627398 -228.79304)
		(width 0.1143)
		(layer "In6.Cu")
		(net "GMI_CPU1_G0_CPU0_G2_TX_DP<0>")
	)
	(arc
		(start 372.625366 -229.397052)
		(mid 372.738773 -229.264163)
		(end 372.779544 -229.094284)
		(width 0.1143)
		(layer "In6.Cu")
		(net "GMI_CPU1_G0_CPU0_G2_TX_DP<0>")
	)
	(arc
		(start 372.552722 -231.988614)
		(mid 372.309395 -231.524048)
		(end 372.552722 -231.059482)
		(width 0.1143)
		(layer "In6.Cu")
		(net "GMI_CPU1_G0_CPU0_G2_TX_DP<0>")
	)
	(arc
		(start 98.854768 -232.043478)
		(mid 98.716569 -232.345357)
		(end 98.872294 -232.6386)
		(width 0.1143)
		(layer "In6.Cu")
		(net "GMI_CPU1_G0_CPU0_G2_TX_DP<0>")
	)
	(arc
		(start 98.94316 -227.819966)
		(mid 99.186596 -228.284251)
		(end 98.943668 -228.748844)
		(width 0.1143)
		(layer "In6.Cu")
		(net "GMI_CPU1_G0_CPU0_G2_TX_DP<0>")
	)
	(arc
		(start 373.563642 -240.738406)
		(mid 373.678318 -240.605072)
		(end 373.719598 -240.434114)
		(width 0.1143)
		(layer "In6.Cu")
		(net "GMI_CPU1_G0_CPU0_G2_TX_DP<0>")
	)
	(arc
		(start 372.552214 -228.74859)
		(mid 372.309206 -228.283997)
		(end 372.552722 -227.819712)
		(width 0.1143)
		(layer "In6.Cu")
		(net "GMI_CPU1_G0_CPU0_G2_TX_DP<0>")
	)
	(arc
		(start 373.96547 -239.280446)
		(mid 373.71958 -238.814102)
		(end 373.96547 -238.347758)
		(width 0.1143)
		(layer "In6.Cu")
		(net "GMI_CPU1_G0_CPU0_G2_TX_DP<0>")
	)
	(arc
		(start 372.779544 -230.714296)
		(mid 372.738289 -230.543325)
		(end 372.623588 -230.410004)
		(width 0.1143)
		(layer "In6.Cu")
		(net "GMI_CPU1_G0_CPU0_G2_TX_DP<0>")
	)
	(arc
		(start 98.40341 -236.079538)
		(mid 98.287983 -236.212914)
		(end 98.246438 -236.384338)
		(width 0.1143)
		(layer "In6.Cu")
		(net "GMI_CPU1_G0_CPU0_G2_TX_DP<0>")
	)
	(arc
		(start 372.623588 -227.778564)
		(mid 372.779516 -227.474272)
		(end 372.623588 -227.16998)
		(width 0.1143)
		(layer "In6.Cu")
		(net "GMI_CPU1_G0_CPU0_G2_TX_DP<0>")
	)
	(arc
		(start 98.94316 -231.059736)
		(mid 99.186487 -231.524302)
		(end 98.94316 -231.988868)
		(width 0.1143)
		(layer "In6.Cu")
		(net "GMI_CPU1_G0_CPU0_G2_TX_DP<0>")
	)
	(arc
		(start 374.033542 -238.308388)
		(mid 374.18947 -238.004096)
		(end 374.033542 -237.699804)
		(width 0.1143)
		(layer "In6.Cu")
		(net "GMI_CPU1_G0_CPU0_G2_TX_DP<0>")
	)
	(arc
		(start 99.182936 -226.665028)
		(mid 99.11017 -226.942177)
		(end 98.910902 -227.148136)
		(width 0.1143)
		(layer "In6.Cu")
		(net "GMI_CPU1_G0_CPU0_G2_TX_DP<0>")
	)
	(arc
		(start 372.552722 -235.228638)
		(mid 372.309395 -234.764072)
		(end 372.552722 -234.299506)
		(width 0.1143)
		(layer "In6.Cu")
		(net "GMI_CPU1_G0_CPU0_G2_TX_DP<0>")
	)
	(arc
		(start 98.962972 -232.691686)
		(mid 99.180581 -233.144568)
		(end 98.962972 -233.59745)
		(width 0.1143)
		(layer "In6.Cu")
		(net "GMI_CPU1_G0_CPU0_G2_TX_DP<0>")
	)
	(arc
		(start 371.142768 -224.698814)
		(mid 370.963955 -224.496464)
		(end 370.899436 -224.234248)
		(width 0.1143)
		(layer "In6.Cu")
		(net "GMI_CPU1_G0_CPU0_G2_TX_DP<0>")
	)
	(arc
		(start 370.236242 -223.098614)
		(mid 370.033369 -222.893222)
		(end 369.959128 -222.614236)
		(width 0.1143)
		(layer "In6.Cu")
		(net "GMI_CPU1_G0_CPU0_G2_TX_DP<0>")
	)
	(arc
		(start 97.776284 -240.434368)
		(mid 97.817539 -240.605339)
		(end 97.93224 -240.73866)
		(width 0.1143)
		(layer "In6.Cu")
		(net "GMI_CPU1_G0_CPU0_G2_TX_DP<0>")
	)
	(arc
		(start 98.716338 -230.71455)
		(mid 98.7571 -230.884434)
		(end 98.870516 -231.017318)
		(width 0.1143)
		(layer "In6.Cu")
		(net "GMI_CPU1_G0_CPU0_G2_TX_DP<0>")
	)
	(arc
		(start 371.615462 -225.510598)
		(mid 371.43481 -225.307853)
		(end 371.36959 -225.044254)
		(width 0.1143)
		(layer "In6.Cu")
		(net "GMI_CPU1_G0_CPU0_G2_TX_DP<0>")
	)
	(arc
		(start 372.623588 -232.638346)
		(mid 372.779353 -232.345104)
		(end 372.641114 -232.043224)
		(width 0.1143)
		(layer "In6.Cu")
		(net "GMI_CPU1_G0_CPU0_G2_TX_DP<0>")
	)
	(arc
		(start 100.753418 -223.929702)
		(mid 100.637991 -224.063078)
		(end 100.596446 -224.234502)
		(width 0.1143)
		(layer "In6.Cu")
		(net "GMI_CPU1_G0_CPU0_G2_TX_DP<0>")
	)
	(arc
		(start 373.249444 -236.384084)
		(mid 373.207895 -236.212662)
		(end 373.092472 -236.079284)
		(width 0.1143)
		(layer "In6.Cu")
		(net "GMI_CPU1_G0_CPU0_G2_TX_DP<0>")
	)
	(arc
		(start 97.46234 -237.700058)
		(mid 97.306412 -238.00435)
		(end 97.46234 -238.308642)
		(width 0.1143)
		(layer "In6.Cu")
		(net "GMI_CPU1_G0_CPU0_G2_TX_DP<0>")
	)
	(arc
		(start 99.366832 -226.346258)
		(mid 99.232231 -226.481031)
		(end 99.182936 -226.665028)
		(width 0.1143)
		(layer "In6.Cu")
		(net "GMI_CPU1_G0_CPU0_G2_TX_DP<0>")
	)
	(arc
		(start 101.536754 -222.61449)
		(mid 101.462523 -222.893482)
		(end 101.25964 -223.098868)
		(width 0.1143)
		(layer "In6.Cu")
		(net "GMI_CPU1_G0_CPU0_G2_TX_DP<0>")
	)
	(arc
		(start 98.872294 -230.410258)
		(mid 98.757618 -230.543592)
		(end 98.716338 -230.71455)
		(width 0.1143)
		(layer "In6.Cu")
		(net "GMI_CPU1_G0_CPU0_G2_TX_DP<0>")
	)
	(arc
		(start 97.530412 -239.968024)
		(mid 97.711064 -240.170769)
		(end 97.776284 -240.434368)
		(width 0.1143)
		(layer "In6.Cu")
		(net "GMI_CPU1_G0_CPU0_G2_TX_DP<0>")
	)
	(arc
		(start 99.656392 -225.854514)
		(mid 99.656392 -225.855022)
		(end 99.656392 -225.85553)
		(width 0.1143)
		(layer "In6.Cu")
		(net "GMI_CPU1_G0_CPU0_G2_TX_DP<0>")
	)
	(arc
		(start 98.962972 -233.59745)
		(mid 98.93426 -233.618487)
		(end 98.904552 -233.63809)
		(width 0.1143)
		(layer "In6.Cu")
		(net "GMI_CPU1_G0_CPU0_G2_TX_DP<0>")
	)
	(arc
		(start 97.530412 -238.348012)
		(mid 97.776302 -238.814356)
		(end 97.530412 -239.2807)
		(width 0.1143)
		(layer "In6.Cu")
		(net "GMI_CPU1_G0_CPU0_G2_TX_DP<0>")
	)
	(arc
		(start 373.719598 -240.434114)
		(mid 373.784834 -240.170523)
		(end 373.96547 -239.96777)
		(width 0.1143)
		(layer "In6.Cu")
		(net "GMI_CPU1_G0_CPU0_G2_TX_DP<0>")
	)
	(arc
		(start 97.46234 -239.32007)
		(mid 97.306412 -239.624362)
		(end 97.46234 -239.928654)
		(width 0.1143)
		(layer "In6.Cu")
		(net "GMI_CPU1_G0_CPU0_G2_TX_DP<0>")
	)
	(arc
		(start 372.623842 -234.258358)
		(mid 372.779641 -233.958232)
		(end 372.630446 -233.654854)
		(width 0.1143)
		(layer "In6.Cu")
		(net "GMI_CPU1_G0_CPU0_G2_TX_DP<0>")
	)
	(arc
		(start 373.96547 -237.660434)
		(mid 373.784818 -237.457689)
		(end 373.719598 -237.19409)
		(width 0.1143)
		(layer "In6.Cu")
		(net "GMI_CPU1_G0_CPU0_G2_TX_DP<0>")
	)
	(arc
		(start 372.30939 -229.904036)
		(mid 372.373905 -229.641817)
		(end 372.552722 -229.43947)
		(width 0.1143)
		(layer "In6.Cu")
		(net "GMI_CPU1_G0_CPU0_G2_TX_DP<0>")
	)
	(arc
		(start 370.672868 -223.888808)
		(mid 370.494055 -223.686458)
		(end 370.429536 -223.424242)
		(width 0.1143)
		(layer "In6.Cu")
		(net "GMI_CPU1_G0_CPU0_G2_TX_DP<0>")
	)
	(arc
		(start 98.716338 -235.574332)
		(mid 98.651823 -235.836551)
		(end 98.473006 -236.038898)
		(width 0.1143)
		(layer "In6.Cu")
		(net "GMI_CPU1_G0_CPU0_G2_TX_DP<0>")
	)
	(arc
		(start 98.860356 -233.665776)
		(mid 98.814489 -233.700315)
		(end 98.77552 -233.742484)
		(width 0.1143)
		(layer "In6.Cu")
		(net "GMI_CPU1_G0_CPU0_G2_TX_DP<0>")
	)
	(arc
		(start 97.776284 -237.194344)
		(mid 97.711048 -237.457935)
		(end 97.530412 -237.660688)
		(width 0.1143)
		(layer "In6.Cu")
		(net "GMI_CPU1_G0_CPU0_G2_TX_DP<0>")
	)
	(arc
		(start 372.779544 -235.574078)
		(mid 372.738289 -235.403107)
		(end 372.623588 -235.269786)
		(width 0.1143)
		(layer "In6.Cu")
		(net "GMI_CPU1_G0_CPU0_G2_TX_DP<0>")
	)
	(arc
		(start 98.94316 -234.29976)
		(mid 99.186487 -234.764326)
		(end 98.94316 -235.228892)
		(width 0.1143)
		(layer "In6.Cu")
		(net "GMI_CPU1_G0_CPU0_G2_TX_DP<0>")
	)
	(arc
		(start 99.656392 -225.85553)
		(mid 99.591724 -226.117027)
		(end 99.413314 -226.318826)
		(width 0.1143)
		(layer "In6.Cu")
		(net "GMI_CPU1_G0_CPU0_G2_TX_DP<0>")
	)
	(segment
		(start 106.607864 -241.510312)
		(end 106.141012 -241.244374)
		(width 0.12954)
		(layer "F.Cu")
		(net "GMI_CPU1_G0_CPU0_G2_TX_DN<9>")
	)
	(segment
		(start 364.888018 -241.510058)
		(end 365.35487 -241.24412)
		(width 0.12954)
		(layer "F.Cu")
		(net "GMI_CPU1_G0_CPU0_G2_TX_DN<9>")
	)
	(segment
		(start 363.287818 -236.706664)
		(end 363.288834 -236.707172)
		(width 0.1143)
		(layer "In6.Cu")
		(net "GMI_CPU1_G0_CPU0_G2_TX_DN<9>")
	)
	(segment
		(start 109.148118 -227.961952)
		(end 109.109002 -227.939092)
		(width 0.1143)
		(layer "In6.Cu")
		(net "GMI_CPU1_G0_CPU0_G2_TX_DN<9>")
	)
	(segment
		(start 302.886872 -185.13298)
		(end 306.212748 -185.13298)
		(width 0.14224)
		(layer "In6.Cu")
		(net "GMI_CPU1_G0_CPU0_G2_TX_DN<9>")
	)
	(segment
		(start 359.026714 -219.871798)
		(end 359.387648 -220.742764)
		(width 0.14224)
		(layer "In6.Cu")
		(net "GMI_CPU1_G0_CPU0_G2_TX_DN<9>")
	)
	(segment
		(start 109.14888 -236.70641)
		(end 109.179868 -236.68863)
		(width 0.1143)
		(layer "In6.Cu")
		(net "GMI_CPU1_G0_CPU0_G2_TX_DN<9>")
	)
	(segment
		(start 362.316014 -232.839768)
		(end 362.296202 -232.853992)
		(width 0.1143)
		(layer "In6.Cu")
		(net "GMI_CPU1_G0_CPU0_G2_TX_DN<9>")
	)
	(segment
		(start 109.148118 -231.201976)
		(end 109.109002 -231.179116)
		(width 0.1143)
		(layer "In6.Cu")
		(net "GMI_CPU1_G0_CPU0_G2_TX_DN<9>")
	)
	(segment
		(start 311.057544 -188.195712)
		(end 312.457338 -189.379352)
		(width 0.14224)
		(layer "In6.Cu")
		(net "GMI_CPU1_G0_CPU0_G2_TX_DN<9>")
	)
	(segment
		(start 362.38688 -236.038644)
		(end 362.347764 -236.061504)
		(width 0.1143)
		(layer "In6.Cu")
		(net "GMI_CPU1_G0_CPU0_G2_TX_DN<9>")
	)
	(segment
		(start 107.268772 -239.30229)
		(end 107.26801 -239.301782)
		(width 0.1143)
		(layer "In6.Cu")
		(net "GMI_CPU1_G0_CPU0_G2_TX_DN<9>")
	)
	(segment
		(start 359.387648 -221.17431)
		(end 359.387648 -221.202758)
		(width 0.1143)
		(layer "In6.Cu")
		(net "GMI_CPU1_G0_CPU0_G2_TX_DN<9>")
	)
	(segment
		(start 106.758994 -240.779808)
		(end 106.805222 -240.752884)
		(width 0.1143)
		(layer "In6.Cu")
		(net "GMI_CPU1_G0_CPU0_G2_TX_DN<9>")
	)
	(segment
		(start 353.159314 -214.727028)
		(end 356.666038 -217.511884)
		(width 0.14224)
		(layer "In6.Cu")
		(net "GMI_CPU1_G0_CPU0_G2_TX_DN<9>")
	)
	(segment
		(start 107.29976 -239.32007)
		(end 107.268772 -239.30229)
		(width 0.1143)
		(layer "In6.Cu")
		(net "GMI_CPU1_G0_CPU0_G2_TX_DN<9>")
	)
	(segment
		(start 109.148118 -233.466894)
		(end 109.179868 -233.448606)
		(width 0.1143)
		(layer "In6.Cu")
		(net "GMI_CPU1_G0_CPU0_G2_TX_DN<9>")
	)
	(segment
		(start 362.296202 -235.05414)
		(end 362.316014 -235.068364)
		(width 0.1143)
		(layer "In6.Cu")
		(net "GMI_CPU1_G0_CPU0_G2_TX_DN<9>")
	)
	(segment
		(start 108.207048 -236.707426)
		(end 108.208064 -236.706918)
		(width 0.1143)
		(layer "In6.Cu")
		(net "GMI_CPU1_G0_CPU0_G2_TX_DN<9>")
	)
	(segment
		(start 362.316014 -236.688376)
		(end 362.347002 -236.706156)
		(width 0.1143)
		(layer "In6.Cu")
		(net "GMI_CPU1_G0_CPU0_G2_TX_DN<9>")
	)
	(segment
		(start 106.438954 -241.244374)
		(end 106.521758 -241.16157)
		(width 0.1143)
		(layer "In6.Cu")
		(net "GMI_CPU1_G0_CPU0_G2_TX_DN<9>")
	)
	(segment
		(start 123.888754 -209.938366)
		(end 133.737604 -203.356972)
		(width 0.14224)
		(layer "In6.Cu")
		(net "GMI_CPU1_G0_CPU0_G2_TX_DN<9>")
	)
	(segment
		(start 112.153954 -221.661736)
		(end 112.153954 -221.248732)
		(width 0.1143)
		(layer "In6.Cu")
		(net "GMI_CPU1_G0_CPU0_G2_TX_DN<9>")
	)
	(segment
		(start 133.737604 -203.356972)
		(end 148.088096 -195.07073)
		(width 0.14224)
		(layer "In6.Cu")
		(net "GMI_CPU1_G0_CPU0_G2_TX_DN<9>")
	)
	(segment
		(start 112.108234 -221.203012)
		(end 112.108234 -221.174564)
		(width 0.1143)
		(layer "In6.Cu")
		(net "GMI_CPU1_G0_CPU0_G2_TX_DN<9>")
	)
	(segment
		(start 109.179868 -236.080046)
		(end 109.148118 -236.061758)
		(width 0.1143)
		(layer "In6.Cu")
		(net "GMI_CPU1_G0_CPU0_G2_TX_DN<9>")
	)
	(segment
		(start 109.19968 -232.854246)
		(end 109.179868 -232.840022)
		(width 0.1143)
		(layer "In6.Cu")
		(net "GMI_CPU1_G0_CPU0_G2_TX_DN<9>")
	)
	(segment
		(start 363.727238 -237.49889)
		(end 363.796834 -237.53953)
		(width 0.1143)
		(layer "In6.Cu")
		(net "GMI_CPU1_G0_CPU0_G2_TX_DN<9>")
	)
	(segment
		(start 362.38688 -234.418632)
		(end 362.316014 -234.45978)
		(width 0.1143)
		(layer "In6.Cu")
		(net "GMI_CPU1_G0_CPU0_G2_TX_DN<9>")
	)
	(segment
		(start 362.347764 -235.086652)
		(end 362.38688 -235.109512)
		(width 0.1143)
		(layer "In6.Cu")
		(net "GMI_CPU1_G0_CPU0_G2_TX_DN<9>")
	)
	(segment
		(start 109.179868 -233.448606)
		(end 109.19968 -233.434382)
		(width 0.1143)
		(layer "In6.Cu")
		(net "GMI_CPU1_G0_CPU0_G2_TX_DN<9>")
	)
	(segment
		(start 109.109002 -233.489754)
		(end 109.148118 -233.466894)
		(width 0.1143)
		(layer "In6.Cu")
		(net "GMI_CPU1_G0_CPU0_G2_TX_DN<9>")
	)
	(segment
		(start 362.347764 -236.061504)
		(end 362.316014 -236.079792)
		(width 0.1143)
		(layer "In6.Cu")
		(net "GMI_CPU1_G0_CPU0_G2_TX_DN<9>")
	)
	(segment
		(start 163.02609 -186.445144)
		(end 163.026344 -186.445144)
		(width 0.14224)
		(layer "In6.Cu")
		(net "GMI_CPU1_G0_CPU0_G2_TX_DN<9>")
	)
	(segment
		(start 109.148118 -231.846882)
		(end 109.148626 -231.846882)
		(width 0.1143)
		(layer "In6.Cu")
		(net "GMI_CPU1_G0_CPU0_G2_TX_DN<9>")
	)
	(segment
		(start 109.109002 -227.00996)
		(end 109.149896 -226.986084)
		(width 0.1143)
		(layer "In6.Cu")
		(net "GMI_CPU1_G0_CPU0_G2_TX_DN<9>")
	)
	(segment
		(start 161.131504 -187.538868)
		(end 163.02609 -186.445144)
		(width 0.14224)
		(layer "In6.Cu")
		(net "GMI_CPU1_G0_CPU0_G2_TX_DN<9>")
	)
	(segment
		(start 109.181646 -231.221534)
		(end 109.148118 -231.201976)
		(width 0.1143)
		(layer "In6.Cu")
		(net "GMI_CPU1_G0_CPU0_G2_TX_DN<9>")
	)
	(segment
		(start 109.179868 -235.068618)
		(end 109.19968 -235.054394)
		(width 0.1143)
		(layer "In6.Cu")
		(net "GMI_CPU1_G0_CPU0_G2_TX_DN<9>")
	)
	(segment
		(start 163.026344 -186.445144)
		(end 165.204648 -185.187336)
		(width 0.14224)
		(layer "In6.Cu")
		(net "GMI_CPU1_G0_CPU0_G2_TX_DN<9>")
	)
	(segment
		(start 362.347256 -231.846628)
		(end 362.347764 -231.846628)
		(width 0.1143)
		(layer "In6.Cu")
		(net "GMI_CPU1_G0_CPU0_G2_TX_DN<9>")
	)
	(segment
		(start 109.109002 -231.869742)
		(end 109.148118 -231.846882)
		(width 0.1143)
		(layer "In6.Cu")
		(net "GMI_CPU1_G0_CPU0_G2_TX_DN<9>")
	)
	(segment
		(start 109.108494 -230.249984)
		(end 109.168946 -230.214678)
		(width 0.1143)
		(layer "In6.Cu")
		(net "GMI_CPU1_G0_CPU0_G2_TX_DN<9>")
	)
	(segment
		(start 109.805216 -225.871786)
		(end 109.805216 -225.871532)
		(width 0.1143)
		(layer "In6.Cu")
		(net "GMI_CPU1_G0_CPU0_G2_TX_DN<9>")
	)
	(segment
		(start 109.148118 -235.086906)
		(end 109.179868 -235.068618)
		(width 0.1143)
		(layer "In6.Cu")
		(net "GMI_CPU1_G0_CPU0_G2_TX_DN<9>")
	)
	(segment
		(start 362.296202 -233.434128)
		(end 362.316014 -233.448352)
		(width 0.1143)
		(layer "In6.Cu")
		(net "GMI_CPU1_G0_CPU0_G2_TX_DN<9>")
	)
	(segment
		(start 108.168948 -236.729778)
		(end 108.207048 -236.707426)
		(width 0.1143)
		(layer "In6.Cu")
		(net "GMI_CPU1_G0_CPU0_G2_TX_DN<9>")
	)
	(segment
		(start 364.69066 -240.75263)
		(end 364.736888 -240.779554)
		(width 0.1143)
		(layer "In6.Cu")
		(net "GMI_CPU1_G0_CPU0_G2_TX_DN<9>")
	)
	(segment
		(start 109.181646 -229.601522)
		(end 109.109002 -229.559104)
		(width 0.1143)
		(layer "In6.Cu")
		(net "GMI_CPU1_G0_CPU0_G2_TX_DN<9>")
	)
	(segment
		(start 362.38688 -229.55885)
		(end 362.314236 -229.601268)
		(width 0.1143)
		(layer "In6.Cu")
		(net "GMI_CPU1_G0_CPU0_G2_TX_DN<9>")
	)
	(segment
		(start 306.212748 -185.13298)
		(end 306.222654 -185.142886)
		(width 0.14224)
		(layer "In6.Cu")
		(net "GMI_CPU1_G0_CPU0_G2_TX_DN<9>")
	)
	(segment
		(start 362.321348 -231.831388)
		(end 362.347256 -231.846628)
		(width 0.1143)
		(layer "In6.Cu")
		(net "GMI_CPU1_G0_CPU0_G2_TX_DN<9>")
	)
	(segment
		(start 109.19968 -234.474258)
		(end 109.179868 -234.460034)
		(width 0.1143)
		(layer "In6.Cu")
		(net "GMI_CPU1_G0_CPU0_G2_TX_DN<9>")
	)
	(segment
		(start 364.974124 -241.161316)
		(end 365.056928 -241.24412)
		(width 0.1143)
		(layer "In6.Cu")
		(net "GMI_CPU1_G0_CPU0_G2_TX_DN<9>")
	)
	(segment
		(start 109.148118 -236.061758)
		(end 109.109002 -236.038898)
		(width 0.1143)
		(layer "In6.Cu")
		(net "GMI_CPU1_G0_CPU0_G2_TX_DN<9>")
	)
	(segment
		(start 106.99115 -240.431066)
		(end 106.99115 -240.427764)
		(width 0.1143)
		(layer "In6.Cu")
		(net "GMI_CPU1_G0_CPU0_G2_TX_DN<9>")
	)
	(segment
		(start 107.699048 -237.539784)
		(end 107.738164 -237.516924)
		(width 0.1143)
		(layer "In6.Cu")
		(net "GMI_CPU1_G0_CPU0_G2_TX_DN<9>")
	)
	(segment
		(start 362.347002 -236.706156)
		(end 362.347764 -236.706664)
		(width 0.1143)
		(layer "In6.Cu")
		(net "GMI_CPU1_G0_CPU0_G2_TX_DN<9>")
	)
	(segment
		(start 364.264194 -239.280446)
		(end 364.227872 -239.301528)
		(width 0.1143)
		(layer "In6.Cu")
		(net "GMI_CPU1_G0_CPU0_G2_TX_DN<9>")
	)
	(segment
		(start 362.347764 -233.46664)
		(end 362.38688 -233.4895)
		(width 0.1143)
		(layer "In6.Cu")
		(net "GMI_CPU1_G0_CPU0_G2_TX_DN<9>")
	)
	(segment
		(start 362.326936 -230.214424)
		(end 362.387388 -230.24973)
		(width 0.1143)
		(layer "In6.Cu")
		(net "GMI_CPU1_G0_CPU0_G2_TX_DN<9>")
	)
	(segment
		(start 109.148626 -231.846882)
		(end 109.174534 -231.831642)
		(width 0.1143)
		(layer "In6.Cu")
		(net "GMI_CPU1_G0_CPU0_G2_TX_DN<9>")
	)
	(segment
		(start 362.38688 -231.178862)
		(end 362.314236 -231.22128)
		(width 0.1143)
		(layer "In6.Cu")
		(net "GMI_CPU1_G0_CPU0_G2_TX_DN<9>")
	)
	(segment
		(start 109.148118 -228.607112)
		(end 109.179868 -228.588824)
		(width 0.1143)
		(layer "In6.Cu")
		(net "GMI_CPU1_G0_CPU0_G2_TX_DN<9>")
	)
	(segment
		(start 360.910886 -224.655888)
		(end 361.408472 -225.153474)
		(width 0.1143)
		(layer "In6.Cu")
		(net "GMI_CPU1_G0_CPU0_G2_TX_DN<9>")
	)
	(segment
		(start 107.738164 -237.516924)
		(end 107.768644 -237.499144)
		(width 0.1143)
		(layer "In6.Cu")
		(net "GMI_CPU1_G0_CPU0_G2_TX_DN<9>")
	)
	(segment
		(start 363.288834 -236.707172)
		(end 363.326934 -236.729524)
		(width 0.1143)
		(layer "In6.Cu")
		(net "GMI_CPU1_G0_CPU0_G2_TX_DN<9>")
	)
	(segment
		(start 112.108234 -220.816678)
		(end 112.518444 -219.825824)
		(width 0.14224)
		(layer "In6.Cu")
		(net "GMI_CPU1_G0_CPU0_G2_TX_DN<9>")
	)
	(segment
		(start 361.879642 -226.177856)
		(end 361.88015 -226.17811)
		(width 0.1143)
		(layer "In6.Cu")
		(net "GMI_CPU1_G0_CPU0_G2_TX_DN<9>")
	)
	(segment
		(start 364.504732 -240.42751)
		(end 364.504732 -240.430812)
		(width 0.1143)
		(layer "In6.Cu")
		(net "GMI_CPU1_G0_CPU0_G2_TX_DN<9>")
	)
	(segment
		(start 109.805216 -225.871532)
		(end 109.811312 -225.729546)
		(width 0.1143)
		(layer "In6.Cu")
		(net "GMI_CPU1_G0_CPU0_G2_TX_DN<9>")
	)
	(segment
		(start 112.518444 -219.825824)
		(end 116.897404 -215.446864)
		(width 0.14224)
		(layer "In6.Cu")
		(net "GMI_CPU1_G0_CPU0_G2_TX_DN<9>")
	)
	(segment
		(start 165.204648 -185.187336)
		(end 168.366948 -184.349898)
		(width 0.14224)
		(layer "In6.Cu")
		(net "GMI_CPU1_G0_CPU0_G2_TX_DN<9>")
	)
	(segment
		(start 109.109002 -228.629972)
		(end 109.148118 -228.607112)
		(width 0.1143)
		(layer "In6.Cu")
		(net "GMI_CPU1_G0_CPU0_G2_TX_DN<9>")
	)
	(segment
		(start 364.227872 -239.301528)
		(end 364.22711 -239.302036)
		(width 0.1143)
		(layer "In6.Cu")
		(net "GMI_CPU1_G0_CPU0_G2_TX_DN<9>")
	)
	(segment
		(start 362.38688 -232.79862)
		(end 362.316014 -232.839768)
		(width 0.1143)
		(layer "In6.Cu")
		(net "GMI_CPU1_G0_CPU0_G2_TX_DN<9>")
	)
	(segment
		(start 109.139736 -236.711744)
		(end 109.148118 -236.706918)
		(width 0.1143)
		(layer "In6.Cu")
		(net "GMI_CPU1_G0_CPU0_G2_TX_DN<9>")
	)
	(segment
		(start 362.347764 -231.846628)
		(end 362.34878 -231.847136)
		(width 0.1143)
		(layer "In6.Cu")
		(net "GMI_CPU1_G0_CPU0_G2_TX_DN<9>")
	)
	(segment
		(start 362.320586 -231.83088)
		(end 362.321348 -231.831388)
		(width 0.1143)
		(layer "In6.Cu")
		(net "GMI_CPU1_G0_CPU0_G2_TX_DN<9>")
	)
	(segment
		(start 359.341928 -222.015558)
		(end 359.660444 -222.784416)
		(width 0.1143)
		(layer "In6.Cu")
		(net "GMI_CPU1_G0_CPU0_G2_TX_DN<9>")
	)
	(segment
		(start 362.38688 -227.938838)
		(end 362.347764 -227.961698)
		(width 0.1143)
		(layer "In6.Cu")
		(net "GMI_CPU1_G0_CPU0_G2_TX_DN<9>")
	)
	(segment
		(start 109.174534 -231.831642)
		(end 109.175296 -231.831134)
		(width 0.1143)
		(layer "In6.Cu")
		(net "GMI_CPU1_G0_CPU0_G2_TX_DN<9>")
	)
	(segment
		(start 109.109002 -235.109766)
		(end 109.148118 -235.086906)
		(width 0.1143)
		(layer "In6.Cu")
		(net "GMI_CPU1_G0_CPU0_G2_TX_DN<9>")
	)
	(segment
		(start 122.384058 -210.944206)
		(end 123.889008 -209.938366)
		(width 0.14224)
		(layer "In6.Cu")
		(net "GMI_CPU1_G0_CPU0_G2_TX_DN<9>")
	)
	(segment
		(start 306.971954 -185.348626)
		(end 307.501544 -185.663332)
		(width 0.14224)
		(layer "In6.Cu")
		(net "GMI_CPU1_G0_CPU0_G2_TX_DN<9>")
	)
	(segment
		(start 359.387648 -221.202758)
		(end 359.341928 -221.248478)
		(width 0.1143)
		(layer "In6.Cu")
		(net "GMI_CPU1_G0_CPU0_G2_TX_DN<9>")
	)
	(segment
		(start 107.26801 -238.32693)
		(end 107.29976 -238.308642)
		(width 0.1143)
		(layer "In6.Cu")
		(net "GMI_CPU1_G0_CPU0_G2_TX_DN<9>")
	)
	(segment
		(start 362.34878 -231.847136)
		(end 362.350304 -231.848152)
		(width 0.1143)
		(layer "In6.Cu")
		(net "GMI_CPU1_G0_CPU0_G2_TX_DN<9>")
	)
	(segment
		(start 109.179868 -234.460034)
		(end 109.109002 -234.418886)
		(width 0.1143)
		(layer "In6.Cu")
		(net "GMI_CPU1_G0_CPU0_G2_TX_DN<9>")
	)
	(segment
		(start 359.341928 -221.248478)
		(end 359.341928 -222.015558)
		(width 0.1143)
		(layer "In6.Cu")
		(net "GMI_CPU1_G0_CPU0_G2_TX_DN<9>")
	)
	(segment
		(start 312.457338 -189.379352)
		(end 353.159314 -214.727028)
		(width 0.14224)
		(layer "In6.Cu")
		(net "GMI_CPU1_G0_CPU0_G2_TX_DN<9>")
	)
	(segment
		(start 109.179868 -227.98024)
		(end 109.148118 -227.961952)
		(width 0.1143)
		(layer "In6.Cu")
		(net "GMI_CPU1_G0_CPU0_G2_TX_DN<9>")
	)
	(segment
		(start 116.897404 -215.446864)
		(end 122.384058 -210.944206)
		(width 0.14224)
		(layer "In6.Cu")
		(net "GMI_CPU1_G0_CPU0_G2_TX_DN<9>")
	)
	(segment
		(start 364.22711 -239.302036)
		(end 364.196122 -239.319816)
		(width 0.1143)
		(layer "In6.Cu")
		(net "GMI_CPU1_G0_CPU0_G2_TX_DN<9>")
	)
	(segment
		(start 356.666038 -217.511884)
		(end 359.026714 -219.871798)
		(width 0.14224)
		(layer "In6.Cu")
		(net "GMI_CPU1_G0_CPU0_G2_TX_DN<9>")
	)
	(segment
		(start 362.347764 -236.706664)
		(end 362.356146 -236.71149)
		(width 0.1143)
		(layer "In6.Cu")
		(net "GMI_CPU1_G0_CPU0_G2_TX_DN<9>")
	)
	(segment
		(start 123.889008 -209.938366)
		(end 123.888754 -209.938366)
		(width 0.14224)
		(layer "In6.Cu")
		(net "GMI_CPU1_G0_CPU0_G2_TX_DN<9>")
	)
	(segment
		(start 109.148118 -236.706918)
		(end 109.14888 -236.70641)
		(width 0.1143)
		(layer "In6.Cu")
		(net "GMI_CPU1_G0_CPU0_G2_TX_DN<9>")
	)
	(segment
		(start 362.316014 -233.448352)
		(end 362.347764 -233.46664)
		(width 0.1143)
		(layer "In6.Cu")
		(net "GMI_CPU1_G0_CPU0_G2_TX_DN<9>")
	)
	(segment
		(start 359.660444 -222.784416)
		(end 360.910886 -224.655888)
		(width 0.1143)
		(layer "In6.Cu")
		(net "GMI_CPU1_G0_CPU0_G2_TX_DN<9>")
	)
	(segment
		(start 109.179868 -232.840022)
		(end 109.109002 -232.798874)
		(width 0.1143)
		(layer "In6.Cu")
		(net "GMI_CPU1_G0_CPU0_G2_TX_DN<9>")
	)
	(segment
		(start 107.26801 -239.946942)
		(end 107.29976 -239.928654)
		(width 0.1143)
		(layer "In6.Cu")
		(net "GMI_CPU1_G0_CPU0_G2_TX_DN<9>")
	)
	(segment
		(start 106.141012 -241.244374)
		(end 106.438954 -241.244374)
		(width 0.1143)
		(layer "In6.Cu")
		(net "GMI_CPU1_G0_CPU0_G2_TX_DN<9>")
	)
	(segment
		(start 307.501544 -185.663332)
		(end 311.057544 -188.195712)
		(width 0.14224)
		(layer "In6.Cu")
		(net "GMI_CPU1_G0_CPU0_G2_TX_DN<9>")
	)
	(segment
		(start 168.366948 -184.349898)
		(end 302.886872 -185.13298)
		(width 0.14224)
		(layer "In6.Cu")
		(net "GMI_CPU1_G0_CPU0_G2_TX_DN<9>")
	)
	(segment
		(start 362.316014 -234.45978)
		(end 362.296202 -234.474004)
		(width 0.1143)
		(layer "In6.Cu")
		(net "GMI_CPU1_G0_CPU0_G2_TX_DN<9>")
	)
	(segment
		(start 361.846622 -226.158806)
		(end 361.879642 -226.177856)
		(width 0.1143)
		(layer "In6.Cu")
		(net "GMI_CPU1_G0_CPU0_G2_TX_DN<9>")
	)
	(segment
		(start 109.61624 -226.17811)
		(end 109.64926 -226.15906)
		(width 0.1143)
		(layer "In6.Cu")
		(net "GMI_CPU1_G0_CPU0_G2_TX_DN<9>")
	)
	(segment
		(start 362.347764 -227.961698)
		(end 362.316014 -227.979986)
		(width 0.1143)
		(layer "In6.Cu")
		(net "GMI_CPU1_G0_CPU0_G2_TX_DN<9>")
	)
	(segment
		(start 109.615732 -226.178364)
		(end 109.61624 -226.17811)
		(width 0.1143)
		(layer "In6.Cu")
		(net "GMI_CPU1_G0_CPU0_G2_TX_DN<9>")
	)
	(segment
		(start 362.345986 -226.98583)
		(end 362.38688 -227.009706)
		(width 0.1143)
		(layer "In6.Cu")
		(net "GMI_CPU1_G0_CPU0_G2_TX_DN<9>")
	)
	(segment
		(start 148.088096 -195.07073)
		(end 161.131504 -187.538868)
		(width 0.14224)
		(layer "In6.Cu")
		(net "GMI_CPU1_G0_CPU0_G2_TX_DN<9>")
	)
	(segment
		(start 107.26801 -239.301782)
		(end 107.231688 -239.2807)
		(width 0.1143)
		(layer "In6.Cu")
		(net "GMI_CPU1_G0_CPU0_G2_TX_DN<9>")
	)
	(segment
		(start 362.316014 -235.068364)
		(end 362.347764 -235.086652)
		(width 0.1143)
		(layer "In6.Cu")
		(net "GMI_CPU1_G0_CPU0_G2_TX_DN<9>")
	)
	(segment
		(start 364.227872 -238.326676)
		(end 364.264194 -238.347758)
		(width 0.1143)
		(layer "In6.Cu")
		(net "GMI_CPU1_G0_CPU0_G2_TX_DN<9>")
	)
	(segment
		(start 306.222654 -185.142886)
		(end 306.971954 -185.348626)
		(width 0.14224)
		(layer "In6.Cu")
		(net "GMI_CPU1_G0_CPU0_G2_TX_DN<9>")
	)
	(segment
		(start 364.196122 -239.9284)
		(end 364.227872 -239.946688)
		(width 0.1143)
		(layer "In6.Cu")
		(net "GMI_CPU1_G0_CPU0_G2_TX_DN<9>")
	)
	(segment
		(start 112.153954 -221.248732)
		(end 112.108234 -221.203012)
		(width 0.1143)
		(layer "In6.Cu")
		(net "GMI_CPU1_G0_CPU0_G2_TX_DN<9>")
	)
	(segment
		(start 365.056928 -241.24412)
		(end 365.35487 -241.24412)
		(width 0.1143)
		(layer "In6.Cu")
		(net "GMI_CPU1_G0_CPU0_G2_TX_DN<9>")
	)
	(segment
		(start 364.196122 -238.308388)
		(end 364.227872 -238.326676)
		(width 0.1143)
		(layer "In6.Cu")
		(net "GMI_CPU1_G0_CPU0_G2_TX_DN<9>")
	)
	(segment
		(start 359.387648 -220.742764)
		(end 359.387648 -221.17431)
		(width 0.14224)
		(layer "In6.Cu")
		(net "GMI_CPU1_G0_CPU0_G2_TX_DN<9>")
	)
	(segment
		(start 112.108234 -221.174564)
		(end 112.108234 -220.816678)
		(width 0.14224)
		(layer "In6.Cu")
		(net "GMI_CPU1_G0_CPU0_G2_TX_DN<9>")
	)
	(segment
		(start 362.350304 -231.848152)
		(end 362.38688 -231.869488)
		(width 0.1143)
		(layer "In6.Cu")
		(net "GMI_CPU1_G0_CPU0_G2_TX_DN<9>")
	)
	(segment
		(start 107.231688 -238.348012)
		(end 107.26801 -238.32693)
		(width 0.1143)
		(layer "In6.Cu")
		(net "GMI_CPU1_G0_CPU0_G2_TX_DN<9>")
	)
	(segment
		(start 109.885226 -225.519234)
		(end 111.71809 -223.000824)
		(width 0.1143)
		(layer "In6.Cu")
		(net "GMI_CPU1_G0_CPU0_G2_TX_DN<9>")
	)
	(segment
		(start 362.316014 -228.58857)
		(end 362.347764 -228.606858)
		(width 0.1143)
		(layer "In6.Cu")
		(net "GMI_CPU1_G0_CPU0_G2_TX_DN<9>")
	)
	(segment
		(start 362.347764 -228.606858)
		(end 362.38688 -228.629718)
		(width 0.1143)
		(layer "In6.Cu")
		(net "GMI_CPU1_G0_CPU0_G2_TX_DN<9>")
	)
	(arc
		(start 362.721906 -236.706664)
		(mid 363.004862 -236.630487)
		(end 363.287818 -236.706664)
		(width 0.1143)
		(layer "In6.Cu")
		(net "GMI_CPU1_G0_CPU0_G2_TX_DN<9>")
	)
	(arc
		(start 111.71809 -223.000824)
		(mid 112.042156 -222.365832)
		(end 112.153954 -221.661736)
		(width 0.1143)
		(layer "In6.Cu")
		(net "GMI_CPU1_G0_CPU0_G2_TX_DN<9>")
	)
	(arc
		(start 362.316014 -236.079792)
		(mid 362.164425 -236.384084)
		(end 362.316014 -236.688376)
		(width 0.1143)
		(layer "In6.Cu")
		(net "GMI_CPU1_G0_CPU0_G2_TX_DN<9>")
	)
	(arc
		(start 361.690666 -225.871532)
		(mid 361.735672 -226.03307)
		(end 361.846622 -226.158806)
		(width 0.1143)
		(layer "In6.Cu")
		(net "GMI_CPU1_G0_CPU0_G2_TX_DN<9>")
	)
	(arc
		(start 362.38688 -233.4895)
		(mid 362.630207 -233.954066)
		(end 362.38688 -234.418632)
		(width 0.1143)
		(layer "In6.Cu")
		(net "GMI_CPU1_G0_CPU0_G2_TX_DN<9>")
	)
	(arc
		(start 106.805222 -240.752884)
		(mid 106.941283 -240.616884)
		(end 106.99115 -240.431066)
		(width 0.1143)
		(layer "In6.Cu")
		(net "GMI_CPU1_G0_CPU0_G2_TX_DN<9>")
	)
	(arc
		(start 108.208064 -236.706918)
		(mid 108.49102 -236.630741)
		(end 108.773976 -236.706918)
		(width 0.1143)
		(layer "In6.Cu")
		(net "GMI_CPU1_G0_CPU0_G2_TX_DN<9>")
	)
	(arc
		(start 107.768644 -237.499144)
		(mid 107.884071 -237.365768)
		(end 107.925616 -237.194344)
		(width 0.1143)
		(layer "In6.Cu")
		(net "GMI_CPU1_G0_CPU0_G2_TX_DN<9>")
	)
	(arc
		(start 362.160058 -226.664266)
		(mid 362.209881 -226.849996)
		(end 362.345986 -226.98583)
		(width 0.1143)
		(layer "In6.Cu")
		(net "GMI_CPU1_G0_CPU0_G2_TX_DN<9>")
	)
	(arc
		(start 107.455716 -238.00435)
		(mid 107.520231 -237.742131)
		(end 107.699048 -237.539784)
		(width 0.1143)
		(layer "In6.Cu")
		(net "GMI_CPU1_G0_CPU0_G2_TX_DN<9>")
	)
	(arc
		(start 109.19968 -235.054394)
		(mid 109.348394 -234.764326)
		(end 109.19968 -234.474258)
		(width 0.1143)
		(layer "In6.Cu")
		(net "GMI_CPU1_G0_CPU0_G2_TX_DN<9>")
	)
	(arc
		(start 362.38688 -227.009706)
		(mid 362.630207 -227.474272)
		(end 362.38688 -227.938838)
		(width 0.1143)
		(layer "In6.Cu")
		(net "GMI_CPU1_G0_CPU0_G2_TX_DN<9>")
	)
	(arc
		(start 107.231688 -239.2807)
		(mid 107.224024 -239.275429)
		(end 107.216448 -239.270032)
		(width 0.1143)
		(layer "In6.Cu")
		(net "GMI_CPU1_G0_CPU0_G2_TX_DN<9>")
	)
	(arc
		(start 362.38688 -235.109512)
		(mid 362.630207 -235.574078)
		(end 362.38688 -236.038644)
		(width 0.1143)
		(layer "In6.Cu")
		(net "GMI_CPU1_G0_CPU0_G2_TX_DN<9>")
	)
	(arc
		(start 107.216448 -239.270032)
		(mid 106.991277 -238.814356)
		(end 107.216448 -238.35868)
		(width 0.1143)
		(layer "In6.Cu")
		(net "GMI_CPU1_G0_CPU0_G2_TX_DN<9>")
	)
	(arc
		(start 361.676442 -225.775012)
		(mid 361.68604 -225.822905)
		(end 361.690666 -225.871532)
		(width 0.1143)
		(layer "In6.Cu")
		(net "GMI_CPU1_G0_CPU0_G2_TX_DN<9>")
	)
	(arc
		(start 109.19968 -233.434382)
		(mid 109.348394 -233.144314)
		(end 109.19968 -232.854246)
		(width 0.1143)
		(layer "In6.Cu")
		(net "GMI_CPU1_G0_CPU0_G2_TX_DN<9>")
	)
	(arc
		(start 106.99115 -240.427764)
		(mid 107.065307 -240.15034)
		(end 107.26801 -239.946942)
		(width 0.1143)
		(layer "In6.Cu")
		(net "GMI_CPU1_G0_CPU0_G2_TX_DN<9>")
	)
	(arc
		(start 109.175296 -231.831134)
		(mid 109.179896 -231.827613)
		(end 109.18444 -231.824022)
		(width 0.1143)
		(layer "In6.Cu")
		(net "GMI_CPU1_G0_CPU0_G2_TX_DN<9>")
	)
	(arc
		(start 364.040166 -238.004096)
		(mid 364.081421 -238.175067)
		(end 364.196122 -238.308388)
		(width 0.1143)
		(layer "In6.Cu")
		(net "GMI_CPU1_G0_CPU0_G2_TX_DN<9>")
	)
	(arc
		(start 107.29976 -239.928654)
		(mid 107.455688 -239.624362)
		(end 107.29976 -239.32007)
		(width 0.1143)
		(layer "In6.Cu")
		(net "GMI_CPU1_G0_CPU0_G2_TX_DN<9>")
	)
	(arc
		(start 109.18444 -231.824022)
		(mid 109.28473 -231.686591)
		(end 109.335824 -231.524302)
		(width 0.1143)
		(layer "In6.Cu")
		(net "GMI_CPU1_G0_CPU0_G2_TX_DN<9>")
	)
	(arc
		(start 364.196122 -239.319816)
		(mid 364.040194 -239.624108)
		(end 364.196122 -239.9284)
		(width 0.1143)
		(layer "In6.Cu")
		(net "GMI_CPU1_G0_CPU0_G2_TX_DN<9>")
	)
	(arc
		(start 109.149896 -226.986084)
		(mid 109.285977 -226.850236)
		(end 109.335824 -226.66452)
		(width 0.1143)
		(layer "In6.Cu")
		(net "GMI_CPU1_G0_CPU0_G2_TX_DN<9>")
	)
	(arc
		(start 107.216448 -238.35868)
		(mid 107.224024 -238.353284)
		(end 107.231688 -238.348012)
		(width 0.1143)
		(layer "In6.Cu")
		(net "GMI_CPU1_G0_CPU0_G2_TX_DN<9>")
	)
	(arc
		(start 109.335824 -226.66452)
		(mid 109.410804 -226.384036)
		(end 109.615732 -226.178364)
		(width 0.1143)
		(layer "In6.Cu")
		(net "GMI_CPU1_G0_CPU0_G2_TX_DN<9>")
	)
	(arc
		(start 109.335824 -231.524302)
		(mid 109.295062 -231.354418)
		(end 109.181646 -231.221534)
		(width 0.1143)
		(layer "In6.Cu")
		(net "GMI_CPU1_G0_CPU0_G2_TX_DN<9>")
	)
	(arc
		(start 362.311442 -231.823768)
		(mid 362.315986 -231.827359)
		(end 362.320586 -231.83088)
		(width 0.1143)
		(layer "In6.Cu")
		(net "GMI_CPU1_G0_CPU0_G2_TX_DN<9>")
	)
	(arc
		(start 109.109002 -231.179116)
		(mid 108.930189 -230.976766)
		(end 108.86567 -230.71455)
		(width 0.1143)
		(layer "In6.Cu")
		(net "GMI_CPU1_G0_CPU0_G2_TX_DN<9>")
	)
	(arc
		(start 109.109002 -236.038898)
		(mid 108.865675 -235.574332)
		(end 109.109002 -235.109766)
		(width 0.1143)
		(layer "In6.Cu")
		(net "GMI_CPU1_G0_CPU0_G2_TX_DN<9>")
	)
	(arc
		(start 362.630212 -230.714296)
		(mid 362.565697 -230.976515)
		(end 362.38688 -231.178862)
		(width 0.1143)
		(layer "In6.Cu")
		(net "GMI_CPU1_G0_CPU0_G2_TX_DN<9>")
	)
	(arc
		(start 362.38688 -228.629718)
		(mid 362.630207 -229.094284)
		(end 362.38688 -229.55885)
		(width 0.1143)
		(layer "In6.Cu")
		(net "GMI_CPU1_G0_CPU0_G2_TX_DN<9>")
	)
	(arc
		(start 362.314236 -229.601268)
		(mid 362.224261 -229.694514)
		(end 362.171488 -229.81285)
		(width 0.1143)
		(layer "In6.Cu")
		(net "GMI_CPU1_G0_CPU0_G2_TX_DN<9>")
	)
	(arc
		(start 362.171488 -229.81285)
		(mid 362.16367 -229.853056)
		(end 362.160312 -229.893876)
		(width 0.1143)
		(layer "In6.Cu")
		(net "GMI_CPU1_G0_CPU0_G2_TX_DN<9>")
	)
	(arc
		(start 363.796834 -237.53953)
		(mid 363.975647 -237.74188)
		(end 364.040166 -238.004096)
		(width 0.1143)
		(layer "In6.Cu")
		(net "GMI_CPU1_G0_CPU0_G2_TX_DN<9>")
	)
	(arc
		(start 364.264194 -238.347758)
		(mid 364.271858 -238.353029)
		(end 364.279434 -238.358426)
		(width 0.1143)
		(layer "In6.Cu")
		(net "GMI_CPU1_G0_CPU0_G2_TX_DN<9>")
	)
	(arc
		(start 109.64926 -226.15906)
		(mid 109.760202 -226.03332)
		(end 109.805216 -225.871786)
		(width 0.1143)
		(layer "In6.Cu")
		(net "GMI_CPU1_G0_CPU0_G2_TX_DN<9>")
	)
	(arc
		(start 108.86567 -230.71455)
		(mid 108.930049 -230.452466)
		(end 109.108494 -230.249984)
		(width 0.1143)
		(layer "In6.Cu")
		(net "GMI_CPU1_G0_CPU0_G2_TX_DN<9>")
	)
	(arc
		(start 362.296202 -234.474004)
		(mid 362.147488 -234.764072)
		(end 362.296202 -235.05414)
		(width 0.1143)
		(layer "In6.Cu")
		(net "GMI_CPU1_G0_CPU0_G2_TX_DN<9>")
	)
	(arc
		(start 109.179868 -236.68863)
		(mid 109.331457 -236.384338)
		(end 109.179868 -236.080046)
		(width 0.1143)
		(layer "In6.Cu")
		(net "GMI_CPU1_G0_CPU0_G2_TX_DN<9>")
	)
	(arc
		(start 363.326934 -236.729524)
		(mid 363.505747 -236.931874)
		(end 363.570266 -237.19409)
		(width 0.1143)
		(layer "In6.Cu")
		(net "GMI_CPU1_G0_CPU0_G2_TX_DN<9>")
	)
	(arc
		(start 109.168946 -230.214678)
		(mid 109.282897 -230.070322)
		(end 109.33557 -229.89413)
		(width 0.1143)
		(layer "In6.Cu")
		(net "GMI_CPU1_G0_CPU0_G2_TX_DN<9>")
	)
	(arc
		(start 109.811312 -225.729546)
		(mid 109.832731 -225.618925)
		(end 109.885226 -225.519234)
		(width 0.1143)
		(layer "In6.Cu")
		(net "GMI_CPU1_G0_CPU0_G2_TX_DN<9>")
	)
	(arc
		(start 363.570266 -237.19409)
		(mid 363.611815 -237.365512)
		(end 363.727238 -237.49889)
		(width 0.1143)
		(layer "In6.Cu")
		(net "GMI_CPU1_G0_CPU0_G2_TX_DN<9>")
	)
	(arc
		(start 362.314236 -231.22128)
		(mid 362.200829 -231.354169)
		(end 362.160058 -231.524048)
		(width 0.1143)
		(layer "In6.Cu")
		(net "GMI_CPU1_G0_CPU0_G2_TX_DN<9>")
	)
	(arc
		(start 109.109002 -227.939092)
		(mid 108.865675 -227.474526)
		(end 109.109002 -227.00996)
		(width 0.1143)
		(layer "In6.Cu")
		(net "GMI_CPU1_G0_CPU0_G2_TX_DN<9>")
	)
	(arc
		(start 364.736888 -240.779554)
		(mid 364.888875 -240.936062)
		(end 364.970314 -241.138456)
		(width 0.1143)
		(layer "In6.Cu")
		(net "GMI_CPU1_G0_CPU0_G2_TX_DN<9>")
	)
	(arc
		(start 106.521758 -241.16157)
		(mid 106.523546 -241.150121)
		(end 106.525568 -241.13871)
		(width 0.1143)
		(layer "In6.Cu")
		(net "GMI_CPU1_G0_CPU0_G2_TX_DN<9>")
	)
	(arc
		(start 108.773976 -236.706918)
		(mid 108.956227 -236.757268)
		(end 109.139736 -236.711744)
		(width 0.1143)
		(layer "In6.Cu")
		(net "GMI_CPU1_G0_CPU0_G2_TX_DN<9>")
	)
	(arc
		(start 107.925616 -237.194344)
		(mid 107.990131 -236.932125)
		(end 108.168948 -236.729778)
		(width 0.1143)
		(layer "In6.Cu")
		(net "GMI_CPU1_G0_CPU0_G2_TX_DN<9>")
	)
	(arc
		(start 364.970314 -241.138456)
		(mid 364.972337 -241.149866)
		(end 364.974124 -241.161316)
		(width 0.1143)
		(layer "In6.Cu")
		(net "GMI_CPU1_G0_CPU0_G2_TX_DN<9>")
	)
	(arc
		(start 362.296202 -232.853992)
		(mid 362.147488 -233.14406)
		(end 362.296202 -233.434128)
		(width 0.1143)
		(layer "In6.Cu")
		(net "GMI_CPU1_G0_CPU0_G2_TX_DN<9>")
	)
	(arc
		(start 364.504732 -240.430812)
		(mid 364.554545 -240.616661)
		(end 364.69066 -240.75263)
		(width 0.1143)
		(layer "In6.Cu")
		(net "GMI_CPU1_G0_CPU0_G2_TX_DN<9>")
	)
	(arc
		(start 364.227872 -239.946688)
		(mid 364.430551 -240.1501)
		(end 364.504732 -240.42751)
		(width 0.1143)
		(layer "In6.Cu")
		(net "GMI_CPU1_G0_CPU0_G2_TX_DN<9>")
	)
	(arc
		(start 109.109002 -232.798874)
		(mid 108.865675 -232.334308)
		(end 109.109002 -231.869742)
		(width 0.1143)
		(layer "In6.Cu")
		(net "GMI_CPU1_G0_CPU0_G2_TX_DN<9>")
	)
	(arc
		(start 364.279434 -238.358426)
		(mid 364.504605 -238.814102)
		(end 364.279434 -239.269778)
		(width 0.1143)
		(layer "In6.Cu")
		(net "GMI_CPU1_G0_CPU0_G2_TX_DN<9>")
	)
	(arc
		(start 361.88015 -226.17811)
		(mid 362.085095 -226.383772)
		(end 362.160058 -226.664266)
		(width 0.1143)
		(layer "In6.Cu")
		(net "GMI_CPU1_G0_CPU0_G2_TX_DN<9>")
	)
	(arc
		(start 109.179868 -228.588824)
		(mid 109.331457 -228.284532)
		(end 109.179868 -227.98024)
		(width 0.1143)
		(layer "In6.Cu")
		(net "GMI_CPU1_G0_CPU0_G2_TX_DN<9>")
	)
	(arc
		(start 362.38688 -231.869488)
		(mid 362.630207 -232.334054)
		(end 362.38688 -232.79862)
		(width 0.1143)
		(layer "In6.Cu")
		(net "GMI_CPU1_G0_CPU0_G2_TX_DN<9>")
	)
	(arc
		(start 362.356146 -236.71149)
		(mid 362.539654 -236.756984)
		(end 362.721906 -236.706664)
		(width 0.1143)
		(layer "In6.Cu")
		(net "GMI_CPU1_G0_CPU0_G2_TX_DN<9>")
	)
	(arc
		(start 109.324394 -229.813104)
		(mid 109.271584 -229.694793)
		(end 109.181646 -229.601522)
		(width 0.1143)
		(layer "In6.Cu")
		(net "GMI_CPU1_G0_CPU0_G2_TX_DN<9>")
	)
	(arc
		(start 362.160058 -231.524048)
		(mid 362.211103 -231.686362)
		(end 362.311442 -231.823768)
		(width 0.1143)
		(layer "In6.Cu")
		(net "GMI_CPU1_G0_CPU0_G2_TX_DN<9>")
	)
	(arc
		(start 109.33557 -229.89413)
		(mid 109.332192 -229.853313)
		(end 109.324394 -229.813104)
		(width 0.1143)
		(layer "In6.Cu")
		(net "GMI_CPU1_G0_CPU0_G2_TX_DN<9>")
	)
	(arc
		(start 109.109002 -229.559104)
		(mid 108.865675 -229.094538)
		(end 109.109002 -228.629972)
		(width 0.1143)
		(layer "In6.Cu")
		(net "GMI_CPU1_G0_CPU0_G2_TX_DN<9>")
	)
	(arc
		(start 362.316014 -227.979986)
		(mid 362.164425 -228.284278)
		(end 362.316014 -228.58857)
		(width 0.1143)
		(layer "In6.Cu")
		(net "GMI_CPU1_G0_CPU0_G2_TX_DN<9>")
	)
	(arc
		(start 106.525568 -241.13871)
		(mid 106.607001 -240.936312)
		(end 106.758994 -240.779808)
		(width 0.1143)
		(layer "In6.Cu")
		(net "GMI_CPU1_G0_CPU0_G2_TX_DN<9>")
	)
	(arc
		(start 362.160312 -229.893876)
		(mid 362.213053 -230.070033)
		(end 362.326936 -230.214424)
		(width 0.1143)
		(layer "In6.Cu")
		(net "GMI_CPU1_G0_CPU0_G2_TX_DN<9>")
	)
	(arc
		(start 107.29976 -238.308642)
		(mid 107.414436 -238.175308)
		(end 107.455716 -238.00435)
		(width 0.1143)
		(layer "In6.Cu")
		(net "GMI_CPU1_G0_CPU0_G2_TX_DN<9>")
	)
	(arc
		(start 109.109002 -234.418886)
		(mid 108.865675 -233.95432)
		(end 109.109002 -233.489754)
		(width 0.1143)
		(layer "In6.Cu")
		(net "GMI_CPU1_G0_CPU0_G2_TX_DN<9>")
	)
	(arc
		(start 361.408472 -225.153474)
		(mid 361.56679 -225.453751)
		(end 361.676442 -225.775012)
		(width 0.1143)
		(layer "In6.Cu")
		(net "GMI_CPU1_G0_CPU0_G2_TX_DN<9>")
	)
	(arc
		(start 362.387388 -230.24973)
		(mid 362.565891 -230.452181)
		(end 362.630212 -230.714296)
		(width 0.1143)
		(layer "In6.Cu")
		(net "GMI_CPU1_G0_CPU0_G2_TX_DN<9>")
	)
	(arc
		(start 364.279434 -239.269778)
		(mid 364.271858 -239.275174)
		(end 364.264194 -239.280446)
		(width 0.1143)
		(layer "In6.Cu")
		(net "GMI_CPU1_G0_CPU0_G2_TX_DN<9>")
	)
	(segment
		(start 103.787956 -243.130324)
		(end 103.321104 -242.864386)
		(width 0.12954)
		(layer "F.Cu")
		(net "GMI_CPU1_G0_CPU0_G2_TX_DN<8>")
	)
	(segment
		(start 367.707926 -243.13007)
		(end 368.174778 -242.864132)
		(width 0.12954)
		(layer "F.Cu")
		(net "GMI_CPU1_G0_CPU0_G2_TX_DN<8>")
	)
	(segment
		(start 362.81741 -222.936816)
		(end 362.787946 -222.919798)
		(width 0.1143)
		(layer "In6.Cu")
		(net "GMI_CPU1_G0_CPU0_G2_TX_DN<8>")
	)
	(segment
		(start 105.889806 -235.878624)
		(end 105.860088 -235.895642)
		(width 0.1143)
		(layer "In6.Cu")
		(net "GMI_CPU1_G0_CPU0_G2_TX_DN<8>")
	)
	(segment
		(start 365.635794 -235.895388)
		(end 365.606076 -235.87837)
		(width 0.1143)
		(layer "In6.Cu")
		(net "GMI_CPU1_G0_CPU0_G2_TX_DN<8>")
	)
	(segment
		(start 104.479852 -240.940082)
		(end 104.497886 -240.953036)
		(width 0.1143)
		(layer "In6.Cu")
		(net "GMI_CPU1_G0_CPU0_G2_TX_DN<8>")
	)
	(segment
		(start 366.580674 -238.489744)
		(end 366.616742 -238.468916)
		(width 0.1143)
		(layer "In6.Cu")
		(net "GMI_CPU1_G0_CPU0_G2_TX_DN<8>")
	)
	(segment
		(start 104.920288 -237.515654)
		(end 104.919526 -237.516162)
		(width 0.1143)
		(layer "In6.Cu")
		(net "GMI_CPU1_G0_CPU0_G2_TX_DN<8>")
	)
	(segment
		(start 367.01603 -240.939828)
		(end 367.04778 -240.92154)
		(width 0.1143)
		(layer "In6.Cu")
		(net "GMI_CPU1_G0_CPU0_G2_TX_DN<8>")
	)
	(segment
		(start 106.35869 -235.069126)
		(end 106.32821 -235.086906)
		(width 0.1143)
		(layer "In6.Cu")
		(net "GMI_CPU1_G0_CPU0_G2_TX_DN<8>")
	)
	(segment
		(start 365.206788 -227.009706)
		(end 365.137192 -226.969066)
		(width 0.1143)
		(layer "In6.Cu")
		(net "GMI_CPU1_G0_CPU0_G2_TX_DN<8>")
	)
	(segment
		(start 366.644682 -237.559342)
		(end 366.616742 -237.539276)
		(width 0.1143)
		(layer "In6.Cu")
		(net "GMI_CPU1_G0_CPU0_G2_TX_DN<8>")
	)
	(segment
		(start 366.616742 -237.539276)
		(end 366.576356 -237.515908)
		(width 0.1143)
		(layer "In6.Cu")
		(net "GMI_CPU1_G0_CPU0_G2_TX_DN<8>")
	)
	(segment
		(start 104.448102 -240.921794)
		(end 104.479852 -240.940082)
		(width 0.1143)
		(layer "In6.Cu")
		(net "GMI_CPU1_G0_CPU0_G2_TX_DN<8>")
	)
	(segment
		(start 106.32821 -231.846882)
		(end 106.289094 -231.869742)
		(width 0.1143)
		(layer "In6.Cu")
		(net "GMI_CPU1_G0_CPU0_G2_TX_DN<8>")
	)
	(segment
		(start 364.497366 -225.844608)
		(end 364.497366 -225.83394)
		(width 0.1143)
		(layer "In6.Cu")
		(net "GMI_CPU1_G0_CPU0_G2_TX_DN<8>")
	)
	(segment
		(start 106.289094 -232.798874)
		(end 106.32821 -232.821734)
		(width 0.1143)
		(layer "In6.Cu")
		(net "GMI_CPU1_G0_CPU0_G2_TX_DN<8>")
	)
	(segment
		(start 365.137192 -232.83926)
		(end 365.206788 -232.79862)
		(width 0.1143)
		(layer "In6.Cu")
		(net "GMI_CPU1_G0_CPU0_G2_TX_DN<8>")
	)
	(segment
		(start 366.574578 -237.514892)
		(end 366.573816 -237.514384)
		(width 0.1143)
		(layer "In6.Cu")
		(net "GMI_CPU1_G0_CPU0_G2_TX_DN<8>")
	)
	(segment
		(start 367.556796 -242.399566)
		(end 367.4872 -242.358926)
		(width 0.1143)
		(layer "In6.Cu")
		(net "GMI_CPU1_G0_CPU0_G2_TX_DN<8>")
	)
	(segment
		(start 109.29239 -220.215968)
		(end 109.29239 -221.064836)
		(width 0.14224)
		(layer "In6.Cu")
		(net "GMI_CPU1_G0_CPU0_G2_TX_DN<8>")
	)
	(segment
		(start 104.87914 -238.46917)
		(end 104.915208 -238.489998)
		(width 0.1143)
		(layer "In6.Cu")
		(net "GMI_CPU1_G0_CPU0_G2_TX_DN<8>")
	)
	(segment
		(start 104.479852 -241.548666)
		(end 104.408986 -241.589814)
		(width 0.1143)
		(layer "In6.Cu")
		(net "GMI_CPU1_G0_CPU0_G2_TX_DN<8>")
	)
	(segment
		(start 106.32821 -226.9871)
		(end 106.289094 -227.00996)
		(width 0.1143)
		(layer "In6.Cu")
		(net "GMI_CPU1_G0_CPU0_G2_TX_DN<8>")
	)
	(segment
		(start 104.918002 -239.136936)
		(end 104.914192 -239.139222)
		(width 0.1143)
		(layer "In6.Cu")
		(net "GMI_CPU1_G0_CPU0_G2_TX_DN<8>")
	)
	(segment
		(start 106.32821 -228.607112)
		(end 106.289094 -228.629972)
		(width 0.1143)
		(layer "In6.Cu")
		(net "GMI_CPU1_G0_CPU0_G2_TX_DN<8>")
	)
	(segment
		(start 106.32821 -234.441746)
		(end 106.35869 -234.459526)
		(width 0.1143)
		(layer "In6.Cu")
		(net "GMI_CPU1_G0_CPU0_G2_TX_DN<8>")
	)
	(segment
		(start 106.32821 -229.581964)
		(end 106.360722 -229.60076)
		(width 0.1143)
		(layer "In6.Cu")
		(net "GMI_CPU1_G0_CPU0_G2_TX_DN<8>")
	)
	(segment
		(start 105.858056 -235.896912)
		(end 105.85704 -235.89742)
		(width 0.1143)
		(layer "In6.Cu")
		(net "GMI_CPU1_G0_CPU0_G2_TX_DN<8>")
	)
	(segment
		(start 103.978202 -242.37696)
		(end 103.939086 -242.39982)
		(width 0.1143)
		(layer "In6.Cu")
		(net "GMI_CPU1_G0_CPU0_G2_TX_DN<8>")
	)
	(segment
		(start 366.146842 -236.729524)
		(end 366.077246 -236.688884)
		(width 0.1143)
		(layer "In6.Cu")
		(net "GMI_CPU1_G0_CPU0_G2_TX_DN<8>")
	)
	(segment
		(start 365.13516 -229.600506)
		(end 365.167672 -229.58171)
		(width 0.1143)
		(layer "In6.Cu")
		(net "GMI_CPU1_G0_CPU0_G2_TX_DN<8>")
	)
	(segment
		(start 365.206788 -235.109512)
		(end 365.137192 -235.068872)
		(width 0.1143)
		(layer "In6.Cu")
		(net "GMI_CPU1_G0_CPU0_G2_TX_DN<8>")
	)
	(segment
		(start 365.640366 -235.898182)
		(end 365.638842 -235.897166)
		(width 0.1143)
		(layer "In6.Cu")
		(net "GMI_CPU1_G0_CPU0_G2_TX_DN<8>")
	)
	(segment
		(start 104.915208 -238.489998)
		(end 104.918002 -238.491776)
		(width 0.1143)
		(layer "In6.Cu")
		(net "GMI_CPU1_G0_CPU0_G2_TX_DN<8>")
	)
	(segment
		(start 363.322108 -223.767396)
		(end 363.252766 -223.726502)
		(width 0.1143)
		(layer "In6.Cu")
		(net "GMI_CPU1_G0_CPU0_G2_TX_DN<8>")
	)
	(segment
		(start 366.57788 -238.491522)
		(end 366.580674 -238.489744)
		(width 0.1143)
		(layer "In6.Cu")
		(net "GMI_CPU1_G0_CPU0_G2_TX_DN<8>")
	)
	(segment
		(start 104.925368 -237.51286)
		(end 104.924606 -237.513368)
		(width 0.1143)
		(layer "In6.Cu")
		(net "GMI_CPU1_G0_CPU0_G2_TX_DN<8>")
	)
	(segment
		(start 367.086896 -239.969548)
		(end 367.04778 -239.946688)
		(width 0.1143)
		(layer "In6.Cu")
		(net "GMI_CPU1_G0_CPU0_G2_TX_DN<8>")
	)
	(segment
		(start 365.637064 -235.89615)
		(end 365.635794 -235.895388)
		(width 0.1143)
		(layer "In6.Cu")
		(net "GMI_CPU1_G0_CPU0_G2_TX_DN<8>")
	)
	(segment
		(start 106.289094 -234.418886)
		(end 106.32821 -234.441746)
		(width 0.1143)
		(layer "In6.Cu")
		(net "GMI_CPU1_G0_CPU0_G2_TX_DN<8>")
	)
	(segment
		(start 107.769152 -224.539302)
		(end 107.738418 -224.557082)
		(width 0.1143)
		(layer "In6.Cu")
		(net "GMI_CPU1_G0_CPU0_G2_TX_DN<8>")
	)
	(segment
		(start 116.011198 -212.081364)
		(end 110.293404 -217.799412)
		(width 0.14224)
		(layer "In6.Cu")
		(net "GMI_CPU1_G0_CPU0_G2_TX_DN<8>")
	)
	(segment
		(start 106.35869 -228.589332)
		(end 106.32821 -228.607112)
		(width 0.1143)
		(layer "In6.Cu")
		(net "GMI_CPU1_G0_CPU0_G2_TX_DN<8>")
	)
	(segment
		(start 104.918764 -238.492284)
		(end 104.949752 -238.510064)
		(width 0.1143)
		(layer "In6.Cu")
		(net "GMI_CPU1_G0_CPU0_G2_TX_DN<8>")
	)
	(segment
		(start 104.497886 -241.535712)
		(end 104.479852 -241.548666)
		(width 0.1143)
		(layer "In6.Cu")
		(net "GMI_CPU1_G0_CPU0_G2_TX_DN<8>")
	)
	(segment
		(start 166.907464 -181.758082)
		(end 166.907464 -181.757828)
		(width 0.14224)
		(layer "In6.Cu")
		(net "GMI_CPU1_G0_CPU0_G2_TX_DN<8>")
	)
	(segment
		(start 105.85704 -235.89742)
		(end 105.81894 -235.919772)
		(width 0.1143)
		(layer "In6.Cu")
		(net "GMI_CPU1_G0_CPU0_G2_TX_DN<8>")
	)
	(segment
		(start 366.576356 -237.515908)
		(end 366.575594 -237.5154)
		(width 0.1143)
		(layer "In6.Cu")
		(net "GMI_CPU1_G0_CPU0_G2_TX_DN<8>")
	)
	(segment
		(start 367.04778 -240.92154)
		(end 367.086896 -240.89868)
		(width 0.1143)
		(layer "In6.Cu")
		(net "GMI_CPU1_G0_CPU0_G2_TX_DN<8>")
	)
	(segment
		(start 308.012084 -182.711852)
		(end 306.555648 -182.311548)
		(width 0.14224)
		(layer "In6.Cu")
		(net "GMI_CPU1_G0_CPU0_G2_TX_DN<8>")
	)
	(segment
		(start 105.858818 -235.896404)
		(end 105.858056 -235.896912)
		(width 0.1143)
		(layer "In6.Cu")
		(net "GMI_CPU1_G0_CPU0_G2_TX_DN<8>")
	)
	(segment
		(start 106.32821 -235.086906)
		(end 106.289094 -235.109766)
		(width 0.1143)
		(layer "In6.Cu")
		(net "GMI_CPU1_G0_CPU0_G2_TX_DN<8>")
	)
	(segment
		(start 364.227618 -225.366834)
		(end 364.196884 -225.349054)
		(width 0.1143)
		(layer "In6.Cu")
		(net "GMI_CPU1_G0_CPU0_G2_TX_DN<8>")
	)
	(segment
		(start 104.448102 -239.946942)
		(end 104.408986 -239.969802)
		(width 0.1143)
		(layer "In6.Cu")
		(net "GMI_CPU1_G0_CPU0_G2_TX_DN<8>")
	)
	(segment
		(start 365.638842 -235.897166)
		(end 365.637826 -235.896658)
		(width 0.1143)
		(layer "In6.Cu")
		(net "GMI_CPU1_G0_CPU0_G2_TX_DN<8>")
	)
	(segment
		(start 106.32821 -232.821734)
		(end 106.35869 -232.839514)
		(width 0.1143)
		(layer "In6.Cu")
		(net "GMI_CPU1_G0_CPU0_G2_TX_DN<8>")
	)
	(segment
		(start 105.388156 -236.706918)
		(end 105.34904 -236.729778)
		(width 0.1143)
		(layer "In6.Cu")
		(net "GMI_CPU1_G0_CPU0_G2_TX_DN<8>")
	)
	(segment
		(start 365.206788 -228.629718)
		(end 365.137192 -228.589078)
		(width 0.1143)
		(layer "In6.Cu")
		(net "GMI_CPU1_G0_CPU0_G2_TX_DN<8>")
	)
	(segment
		(start 365.637826 -235.896658)
		(end 365.637064 -235.89615)
		(width 0.1143)
		(layer "In6.Cu")
		(net "GMI_CPU1_G0_CPU0_G2_TX_DN<8>")
	)
	(segment
		(start 104.008682 -242.35918)
		(end 103.978202 -242.37696)
		(width 0.1143)
		(layer "In6.Cu")
		(net "GMI_CPU1_G0_CPU0_G2_TX_DN<8>")
	)
	(segment
		(start 365.137192 -234.459272)
		(end 365.206788 -234.418632)
		(width 0.1143)
		(layer "In6.Cu")
		(net "GMI_CPU1_G0_CPU0_G2_TX_DN<8>")
	)
	(segment
		(start 103.70185 -242.781582)
		(end 103.619046 -242.864386)
		(width 0.1143)
		(layer "In6.Cu")
		(net "GMI_CPU1_G0_CPU0_G2_TX_DN<8>")
	)
	(segment
		(start 366.57788 -239.136682)
		(end 366.54613 -239.118394)
		(width 0.1143)
		(layer "In6.Cu")
		(net "GMI_CPU1_G0_CPU0_G2_TX_DN<8>")
	)
	(segment
		(start 363.79531 -224.578672)
		(end 363.72673 -224.539048)
		(width 0.1143)
		(layer "In6.Cu")
		(net "GMI_CPU1_G0_CPU0_G2_TX_DN<8>")
	)
	(segment
		(start 366.58169 -239.138968)
		(end 366.57788 -239.136682)
		(width 0.1143)
		(layer "In6.Cu")
		(net "GMI_CPU1_G0_CPU0_G2_TX_DN<8>")
	)
	(segment
		(start 365.167672 -231.201722)
		(end 365.206788 -231.178862)
		(width 0.1143)
		(layer "In6.Cu")
		(net "GMI_CPU1_G0_CPU0_G2_TX_DN<8>")
	)
	(segment
		(start 362.203492 -221.09303)
		(end 362.203492 -220.14561)
		(width 0.14224)
		(layer "In6.Cu")
		(net "GMI_CPU1_G0_CPU0_G2_TX_DN<8>")
	)
	(segment
		(start 366.997996 -240.952782)
		(end 367.01603 -240.939828)
		(width 0.1143)
		(layer "In6.Cu")
		(net "GMI_CPU1_G0_CPU0_G2_TX_DN<8>")
	)
	(segment
		(start 314.53201 -186.583574)
		(end 308.012084 -182.711852)
		(width 0.14224)
		(layer "In6.Cu")
		(net "GMI_CPU1_G0_CPU0_G2_TX_DN<8>")
	)
	(segment
		(start 104.949752 -239.118648)
		(end 104.918002 -239.136936)
		(width 0.1143)
		(layer "In6.Cu")
		(net "GMI_CPU1_G0_CPU0_G2_TX_DN<8>")
	)
	(segment
		(start 103.619046 -242.864386)
		(end 103.321104 -242.864386)
		(width 0.1143)
		(layer "In6.Cu")
		(net "GMI_CPU1_G0_CPU0_G2_TX_DN<8>")
	)
	(segment
		(start 104.949752 -237.498636)
		(end 104.925368 -237.51286)
		(width 0.1143)
		(layer "In6.Cu")
		(net "GMI_CPU1_G0_CPU0_G2_TX_DN<8>")
	)
	(segment
		(start 107.738418 -224.557082)
		(end 107.700572 -224.578926)
		(width 0.1143)
		(layer "In6.Cu")
		(net "GMI_CPU1_G0_CPU0_G2_TX_DN<8>")
	)
	(segment
		(start 105.418636 -236.689138)
		(end 105.388156 -236.706918)
		(width 0.1143)
		(layer "In6.Cu")
		(net "GMI_CPU1_G0_CPU0_G2_TX_DN<8>")
	)
	(segment
		(start 164.331396 -182.44058)
		(end 125.169422 -205.053946)
		(width 0.14224)
		(layer "In6.Cu")
		(net "GMI_CPU1_G0_CPU0_G2_TX_DN<8>")
	)
	(segment
		(start 366.54613 -238.50981)
		(end 366.577118 -238.49203)
		(width 0.1143)
		(layer "In6.Cu")
		(net "GMI_CPU1_G0_CPU0_G2_TX_DN<8>")
	)
	(segment
		(start 365.137192 -227.979478)
		(end 365.206788 -227.938838)
		(width 0.1143)
		(layer "In6.Cu")
		(net "GMI_CPU1_G0_CPU0_G2_TX_DN<8>")
	)
	(segment
		(start 367.01603 -241.548412)
		(end 366.997996 -241.535458)
		(width 0.1143)
		(layer "In6.Cu")
		(net "GMI_CPU1_G0_CPU0_G2_TX_DN<8>")
	)
	(segment
		(start 104.924606 -237.513368)
		(end 104.922066 -237.514638)
		(width 0.1143)
		(layer "In6.Cu")
		(net "GMI_CPU1_G0_CPU0_G2_TX_DN<8>")
	)
	(segment
		(start 367.04778 -239.946688)
		(end 367.047526 -239.946434)
		(width 0.1143)
		(layer "In6.Cu")
		(net "GMI_CPU1_G0_CPU0_G2_TX_DN<8>")
	)
	(segment
		(start 104.408986 -240.898934)
		(end 104.448102 -240.921794)
		(width 0.1143)
		(layer "In6.Cu")
		(net "GMI_CPU1_G0_CPU0_G2_TX_DN<8>")
	)
	(segment
		(start 106.289094 -229.559104)
		(end 106.32821 -229.581964)
		(width 0.1143)
		(layer "In6.Cu")
		(net "GMI_CPU1_G0_CPU0_G2_TX_DN<8>")
	)
	(segment
		(start 106.81081 -226.169728)
		(end 106.758994 -226.199954)
		(width 0.1143)
		(layer "In6.Cu")
		(net "GMI_CPU1_G0_CPU0_G2_TX_DN<8>")
	)
	(segment
		(start 118.034054 -210.528916)
		(end 118.034054 -210.52917)
		(width 0.14224)
		(layer "In6.Cu")
		(net "GMI_CPU1_G0_CPU0_G2_TX_DN<8>")
	)
	(segment
		(start 116.634514 -211.603082)
		(end 116.011198 -212.081364)
		(width 0.14224)
		(layer "In6.Cu")
		(net "GMI_CPU1_G0_CPU0_G2_TX_DN<8>")
	)
	(segment
		(start 104.448356 -239.946688)
		(end 104.448102 -239.946942)
		(width 0.1143)
		(layer "In6.Cu")
		(net "GMI_CPU1_G0_CPU0_G2_TX_DN<8>")
	)
	(segment
		(start 107.298998 -225.349308)
		(end 107.268264 -225.367088)
		(width 0.1143)
		(layer "In6.Cu")
		(net "GMI_CPU1_G0_CPU0_G2_TX_DN<8>")
	)
	(segment
		(start 365.13516 -231.220518)
		(end 365.167672 -231.201722)
		(width 0.1143)
		(layer "In6.Cu")
		(net "GMI_CPU1_G0_CPU0_G2_TX_DN<8>")
	)
	(segment
		(start 365.206788 -233.4895)
		(end 365.137192 -233.44886)
		(width 0.1143)
		(layer "In6.Cu")
		(net "GMI_CPU1_G0_CPU0_G2_TX_DN<8>")
	)
	(segment
		(start 362.38688 -222.14967)
		(end 362.316014 -222.108522)
		(width 0.1143)
		(layer "In6.Cu")
		(net "GMI_CPU1_G0_CPU0_G2_TX_DN<8>")
	)
	(segment
		(start 306.555648 -182.311548)
		(end 302.896016 -182.311548)
		(width 0.14224)
		(layer "In6.Cu")
		(net "GMI_CPU1_G0_CPU0_G2_TX_DN<8>")
	)
	(segment
		(start 106.32821 -227.961952)
		(end 106.35869 -227.979732)
		(width 0.1143)
		(layer "In6.Cu")
		(net "GMI_CPU1_G0_CPU0_G2_TX_DN<8>")
	)
	(segment
		(start 166.907464 -181.757828)
		(end 166.060882 -181.982364)
		(width 0.14224)
		(layer "In6.Cu")
		(net "GMI_CPU1_G0_CPU0_G2_TX_DN<8>")
	)
	(segment
		(start 110.293404 -217.799412)
		(end 109.29239 -220.215968)
		(width 0.14224)
		(layer "In6.Cu")
		(net "GMI_CPU1_G0_CPU0_G2_TX_DN<8>")
	)
	(segment
		(start 105.860088 -235.895642)
		(end 105.858818 -235.896404)
		(width 0.1143)
		(layer "In6.Cu")
		(net "GMI_CPU1_G0_CPU0_G2_TX_DN<8>")
	)
	(segment
		(start 366.575594 -237.5154)
		(end 366.574578 -237.514892)
		(width 0.1143)
		(layer "In6.Cu")
		(net "GMI_CPU1_G0_CPU0_G2_TX_DN<8>")
	)
	(segment
		(start 109.29239 -221.093284)
		(end 109.33811 -221.139004)
		(width 0.1143)
		(layer "In6.Cu")
		(net "GMI_CPU1_G0_CPU0_G2_TX_DN<8>")
	)
	(segment
		(start 365.676942 -235.919518)
		(end 365.640366 -235.898182)
		(width 0.1143)
		(layer "In6.Cu")
		(net "GMI_CPU1_G0_CPU0_G2_TX_DN<8>")
	)
	(segment
		(start 104.87914 -237.53953)
		(end 104.8512 -237.559596)
		(width 0.1143)
		(layer "In6.Cu")
		(net "GMI_CPU1_G0_CPU0_G2_TX_DN<8>")
	)
	(segment
		(start 361.718098 -218.547442)
		(end 358.51973 -215.349582)
		(width 0.14224)
		(layer "In6.Cu")
		(net "GMI_CPU1_G0_CPU0_G2_TX_DN<8>")
	)
	(segment
		(start 104.922066 -237.514638)
		(end 104.921304 -237.515146)
		(width 0.1143)
		(layer "In6.Cu")
		(net "GMI_CPU1_G0_CPU0_G2_TX_DN<8>")
	)
	(segment
		(start 109.33811 -221.139004)
		(end 109.33811 -221.325948)
		(width 0.1143)
		(layer "In6.Cu")
		(net "GMI_CPU1_G0_CPU0_G2_TX_DN<8>")
	)
	(segment
		(start 106.998516 -225.834194)
		(end 106.998516 -225.844862)
		(width 0.1143)
		(layer "In6.Cu")
		(net "GMI_CPU1_G0_CPU0_G2_TX_DN<8>")
	)
	(segment
		(start 108.678472 -222.93707)
		(end 108.64215 -222.958152)
		(width 0.1143)
		(layer "In6.Cu")
		(net "GMI_CPU1_G0_CPU0_G2_TX_DN<8>")
	)
	(segment
		(start 365.167672 -229.58171)
		(end 365.206788 -229.55885)
		(width 0.1143)
		(layer "In6.Cu")
		(net "GMI_CPU1_G0_CPU0_G2_TX_DN<8>")
	)
	(segment
		(start 104.921304 -237.515146)
		(end 104.920288 -237.515654)
		(width 0.1143)
		(layer "In6.Cu")
		(net "GMI_CPU1_G0_CPU0_G2_TX_DN<8>")
	)
	(segment
		(start 106.32821 -233.466894)
		(end 106.289094 -233.489754)
		(width 0.1143)
		(layer "In6.Cu")
		(net "GMI_CPU1_G0_CPU0_G2_TX_DN<8>")
	)
	(segment
		(start 366.577118 -238.49203)
		(end 366.57788 -238.491522)
		(width 0.1143)
		(layer "In6.Cu")
		(net "GMI_CPU1_G0_CPU0_G2_TX_DN<8>")
	)
	(segment
		(start 104.919526 -237.516162)
		(end 104.87914 -237.53953)
		(width 0.1143)
		(layer "In6.Cu")
		(net "GMI_CPU1_G0_CPU0_G2_TX_DN<8>")
	)
	(segment
		(start 109.33811 -221.325948)
		(end 109.336078 -221.32798)
		(width 0.1143)
		(layer "In6.Cu")
		(net "GMI_CPU1_G0_CPU0_G2_TX_DN<8>")
	)
	(segment
		(start 109.179868 -222.108776)
		(end 109.109002 -222.149924)
		(width 0.1143)
		(layer "In6.Cu")
		(net "GMI_CPU1_G0_CPU0_G2_TX_DN<8>")
	)
	(segment
		(start 166.060882 -181.98211)
		(end 164.331396 -182.44058)
		(width 0.14224)
		(layer "In6.Cu")
		(net "GMI_CPU1_G0_CPU0_G2_TX_DN<8>")
	)
	(segment
		(start 108.243116 -223.726756)
		(end 108.173774 -223.76765)
		(width 0.1143)
		(layer "In6.Cu")
		(net "GMI_CPU1_G0_CPU0_G2_TX_DN<8>")
	)
	(segment
		(start 364.736888 -226.1997)
		(end 364.685072 -226.169474)
		(width 0.1143)
		(layer "In6.Cu")
		(net "GMI_CPU1_G0_CPU0_G2_TX_DN<8>")
	)
	(segment
		(start 302.896016 -182.311548)
		(end 167.790622 -181.524148)
		(width 0.14224)
		(layer "In6.Cu")
		(net "GMI_CPU1_G0_CPU0_G2_TX_DN<8>")
	)
	(segment
		(start 167.790622 -181.524148)
		(end 166.907464 -181.758082)
		(width 0.14224)
		(layer "In6.Cu")
		(net "GMI_CPU1_G0_CPU0_G2_TX_DN<8>")
	)
	(segment
		(start 365.206788 -231.869488)
		(end 365.137192 -231.828848)
		(width 0.1143)
		(layer "In6.Cu")
		(net "GMI_CPU1_G0_CPU0_G2_TX_DN<8>")
	)
	(segment
		(start 106.35869 -230.20909)
		(end 106.291634 -230.248206)
		(width 0.1143)
		(layer "In6.Cu")
		(net "GMI_CPU1_G0_CPU0_G2_TX_DN<8>")
	)
	(segment
		(start 122.871484 -206.81696)
		(end 122.871738 -206.81696)
		(width 0.14224)
		(layer "In6.Cu")
		(net "GMI_CPU1_G0_CPU0_G2_TX_DN<8>")
	)
	(segment
		(start 358.51973 -215.349582)
		(end 354.357178 -212.037422)
		(width 0.14224)
		(layer "In6.Cu")
		(net "GMI_CPU1_G0_CPU0_G2_TX_DN<8>")
	)
	(segment
		(start 315.798962 -187.921392)
		(end 314.53201 -186.583574)
		(width 0.14224)
		(layer "In6.Cu")
		(net "GMI_CPU1_G0_CPU0_G2_TX_DN<8>")
	)
	(segment
		(start 122.871738 -206.81696)
		(end 118.034054 -210.528916)
		(width 0.14224)
		(layer "In6.Cu")
		(net "GMI_CPU1_G0_CPU0_G2_TX_DN<8>")
	)
	(segment
		(start 104.8512 -238.449104)
		(end 104.87914 -238.46917)
		(width 0.1143)
		(layer "In6.Cu")
		(net "GMI_CPU1_G0_CPU0_G2_TX_DN<8>")
	)
	(segment
		(start 106.289094 -231.179116)
		(end 106.32821 -231.201976)
		(width 0.1143)
		(layer "In6.Cu")
		(net "GMI_CPU1_G0_CPU0_G2_TX_DN<8>")
	)
	(segment
		(start 362.157772 -221.325694)
		(end 362.157772 -221.13875)
		(width 0.1143)
		(layer "In6.Cu")
		(net "GMI_CPU1_G0_CPU0_G2_TX_DN<8>")
	)
	(segment
		(start 109.336078 -221.32798)
		(end 109.336078 -221.804484)
		(width 0.1143)
		(layer "In6.Cu")
		(net "GMI_CPU1_G0_CPU0_G2_TX_DN<8>")
	)
	(segment
		(start 106.35869 -231.829102)
		(end 106.32821 -231.846882)
		(width 0.1143)
		(layer "In6.Cu")
		(net "GMI_CPU1_G0_CPU0_G2_TX_DN<8>")
	)
	(segment
		(start 106.289094 -227.939092)
		(end 106.32821 -227.961952)
		(width 0.1143)
		(layer "In6.Cu")
		(net "GMI_CPU1_G0_CPU0_G2_TX_DN<8>")
	)
	(segment
		(start 368.174778 -242.864132)
		(end 367.876836 -242.864132)
		(width 0.1143)
		(layer "In6.Cu")
		(net "GMI_CPU1_G0_CPU0_G2_TX_DN<8>")
	)
	(segment
		(start 106.35869 -226.96932)
		(end 106.32821 -226.9871)
		(width 0.1143)
		(layer "In6.Cu")
		(net "GMI_CPU1_G0_CPU0_G2_TX_DN<8>")
	)
	(segment
		(start 367.876836 -242.864132)
		(end 367.794032 -242.781328)
		(width 0.1143)
		(layer "In6.Cu")
		(net "GMI_CPU1_G0_CPU0_G2_TX_DN<8>")
	)
	(segment
		(start 366.616742 -238.468916)
		(end 366.644682 -238.44885)
		(width 0.1143)
		(layer "In6.Cu")
		(net "GMI_CPU1_G0_CPU0_G2_TX_DN<8>")
	)
	(segment
		(start 363.569758 -224.234248)
		(end 363.569758 -224.23247)
		(width 0.1143)
		(layer "In6.Cu")
		(net "GMI_CPU1_G0_CPU0_G2_TX_DN<8>")
	)
	(segment
		(start 125.169422 -205.053946)
		(end 122.871484 -206.81696)
		(width 0.14224)
		(layer "In6.Cu")
		(net "GMI_CPU1_G0_CPU0_G2_TX_DN<8>")
	)
	(segment
		(start 118.034054 -210.52917)
		(end 116.634514 -211.603082)
		(width 0.14224)
		(layer "In6.Cu")
		(net "GMI_CPU1_G0_CPU0_G2_TX_DN<8>")
	)
	(segment
		(start 108.707936 -222.920052)
		(end 108.678472 -222.93707)
		(width 0.1143)
		(layer "In6.Cu")
		(net "GMI_CPU1_G0_CPU0_G2_TX_DN<8>")
	)
	(segment
		(start 366.573816 -237.514384)
		(end 366.54613 -237.498382)
		(width 0.1143)
		(layer "In6.Cu")
		(net "GMI_CPU1_G0_CPU0_G2_TX_DN<8>")
	)
	(segment
		(start 367.086896 -241.58956)
		(end 367.01603 -241.548412)
		(width 0.1143)
		(layer "In6.Cu")
		(net "GMI_CPU1_G0_CPU0_G2_TX_DN<8>")
	)
	(segment
		(start 106.32821 -231.201976)
		(end 106.360722 -231.220772)
		(width 0.1143)
		(layer "In6.Cu")
		(net "GMI_CPU1_G0_CPU0_G2_TX_DN<8>")
	)
	(segment
		(start 362.157772 -221.13875)
		(end 362.203492 -221.09303)
		(width 0.1143)
		(layer "In6.Cu")
		(net "GMI_CPU1_G0_CPU0_G2_TX_DN<8>")
	)
	(segment
		(start 362.159804 -221.80423)
		(end 362.159804 -221.327726)
		(width 0.1143)
		(layer "In6.Cu")
		(net "GMI_CPU1_G0_CPU0_G2_TX_DN<8>")
	)
	(segment
		(start 166.060882 -181.982364)
		(end 166.060882 -181.98211)
		(width 0.14224)
		(layer "In6.Cu")
		(net "GMI_CPU1_G0_CPU0_G2_TX_DN<8>")
	)
	(segment
		(start 362.159804 -221.327726)
		(end 362.157772 -221.325694)
		(width 0.1143)
		(layer "In6.Cu")
		(net "GMI_CPU1_G0_CPU0_G2_TX_DN<8>")
	)
	(segment
		(start 106.35869 -233.449114)
		(end 106.32821 -233.466894)
		(width 0.1143)
		(layer "In6.Cu")
		(net "GMI_CPU1_G0_CPU0_G2_TX_DN<8>")
	)
	(segment
		(start 362.853732 -222.957898)
		(end 362.81741 -222.936816)
		(width 0.1143)
		(layer "In6.Cu")
		(net "GMI_CPU1_G0_CPU0_G2_TX_DN<8>")
	)
	(segment
		(start 365.204248 -230.247952)
		(end 365.137192 -230.208836)
		(width 0.1143)
		(layer "In6.Cu")
		(net "GMI_CPU1_G0_CPU0_G2_TX_DN<8>")
	)
	(segment
		(start 104.918002 -238.491776)
		(end 104.918764 -238.492284)
		(width 0.1143)
		(layer "In6.Cu")
		(net "GMI_CPU1_G0_CPU0_G2_TX_DN<8>")
	)
	(segment
		(start 107.926124 -224.232724)
		(end 107.926124 -224.234502)
		(width 0.1143)
		(layer "In6.Cu")
		(net "GMI_CPU1_G0_CPU0_G2_TX_DN<8>")
	)
	(segment
		(start 354.357178 -212.037422)
		(end 315.798962 -187.921392)
		(width 0.14224)
		(layer "In6.Cu")
		(net "GMI_CPU1_G0_CPU0_G2_TX_DN<8>")
	)
	(segment
		(start 109.29239 -221.064836)
		(end 109.29239 -221.093284)
		(width 0.1143)
		(layer "In6.Cu")
		(net "GMI_CPU1_G0_CPU0_G2_TX_DN<8>")
	)
	(segment
		(start 362.203492 -220.14561)
		(end 361.718098 -218.547442)
		(width 0.14224)
		(layer "In6.Cu")
		(net "GMI_CPU1_G0_CPU0_G2_TX_DN<8>")
	)
	(arc
		(start 366.997996 -241.535458)
		(mid 366.848674 -241.24412)
		(end 366.997996 -240.952782)
		(width 0.1143)
		(layer "In6.Cu")
		(net "GMI_CPU1_G0_CPU0_G2_TX_DN<8>")
	)
	(arc
		(start 363.569758 -224.23247)
		(mid 363.503938 -223.96904)
		(end 363.322108 -223.767396)
		(width 0.1143)
		(layer "In6.Cu")
		(net "GMI_CPU1_G0_CPU0_G2_TX_DN<8>")
	)
	(arc
		(start 362.226098 -222.016574)
		(mid 362.176778 -221.915445)
		(end 362.159804 -221.80423)
		(width 0.1143)
		(layer "In6.Cu")
		(net "GMI_CPU1_G0_CPU0_G2_TX_DN<8>")
	)
	(arc
		(start 365.45012 -230.714296)
		(mid 365.384884 -230.450705)
		(end 365.204248 -230.247952)
		(width 0.1143)
		(layer "In6.Cu")
		(net "GMI_CPU1_G0_CPU0_G2_TX_DN<8>")
	)
	(arc
		(start 367.330228 -242.054126)
		(mid 367.265713 -241.791907)
		(end 367.086896 -241.58956)
		(width 0.1143)
		(layer "In6.Cu")
		(net "GMI_CPU1_G0_CPU0_G2_TX_DN<8>")
	)
	(arc
		(start 103.70566 -242.758722)
		(mid 103.703637 -242.770132)
		(end 103.70185 -242.781582)
		(width 0.1143)
		(layer "In6.Cu")
		(net "GMI_CPU1_G0_CPU0_G2_TX_DN<8>")
	)
	(arc
		(start 366.077246 -236.688884)
		(mid 365.961819 -236.555508)
		(end 365.920274 -236.384084)
		(width 0.1143)
		(layer "In6.Cu")
		(net "GMI_CPU1_G0_CPU0_G2_TX_DN<8>")
	)
	(arc
		(start 362.630212 -222.614236)
		(mid 362.565697 -222.352017)
		(end 362.38688 -222.14967)
		(width 0.1143)
		(layer "In6.Cu")
		(net "GMI_CPU1_G0_CPU0_G2_TX_DN<8>")
	)
	(arc
		(start 106.360722 -229.60076)
		(mid 106.474651 -229.733907)
		(end 106.515662 -229.90429)
		(width 0.1143)
		(layer "In6.Cu")
		(net "GMI_CPU1_G0_CPU0_G2_TX_DN<8>")
	)
	(arc
		(start 107.45597 -225.044508)
		(mid 107.414421 -225.21593)
		(end 107.298998 -225.349308)
		(width 0.1143)
		(layer "In6.Cu")
		(net "GMI_CPU1_G0_CPU0_G2_TX_DN<8>")
	)
	(arc
		(start 109.269784 -222.016828)
		(mid 109.228801 -222.06669)
		(end 109.179868 -222.108776)
		(width 0.1143)
		(layer "In6.Cu")
		(net "GMI_CPU1_G0_CPU0_G2_TX_DN<8>")
	)
	(arc
		(start 365.206788 -227.938838)
		(mid 365.450115 -227.474272)
		(end 365.206788 -227.009706)
		(width 0.1143)
		(layer "In6.Cu")
		(net "GMI_CPU1_G0_CPU0_G2_TX_DN<8>")
	)
	(arc
		(start 106.35869 -227.979732)
		(mid 106.515667 -228.284532)
		(end 106.35869 -228.589332)
		(width 0.1143)
		(layer "In6.Cu")
		(net "GMI_CPU1_G0_CPU0_G2_TX_DN<8>")
	)
	(arc
		(start 107.700572 -224.578926)
		(mid 107.520843 -224.781546)
		(end 107.45597 -225.044508)
		(width 0.1143)
		(layer "In6.Cu")
		(net "GMI_CPU1_G0_CPU0_G2_TX_DN<8>")
	)
	(arc
		(start 106.045762 -235.574332)
		(mid 106.004507 -235.745303)
		(end 105.889806 -235.878624)
		(width 0.1143)
		(layer "In6.Cu")
		(net "GMI_CPU1_G0_CPU0_G2_TX_DN<8>")
	)
	(arc
		(start 364.98022 -231.524048)
		(mid 365.021186 -231.353642)
		(end 365.13516 -231.220518)
		(width 0.1143)
		(layer "In6.Cu")
		(net "GMI_CPU1_G0_CPU0_G2_TX_DN<8>")
	)
	(arc
		(start 363.09935 -223.424242)
		(mid 363.034183 -223.160718)
		(end 362.853732 -222.957898)
		(width 0.1143)
		(layer "In6.Cu")
		(net "GMI_CPU1_G0_CPU0_G2_TX_DN<8>")
	)
	(arc
		(start 366.54613 -237.498382)
		(mid 366.431454 -237.365048)
		(end 366.390174 -237.19409)
		(width 0.1143)
		(layer "In6.Cu")
		(net "GMI_CPU1_G0_CPU0_G2_TX_DN<8>")
	)
	(arc
		(start 106.515662 -229.90429)
		(mid 106.474113 -230.075712)
		(end 106.35869 -230.20909)
		(width 0.1143)
		(layer "In6.Cu")
		(net "GMI_CPU1_G0_CPU0_G2_TX_DN<8>")
	)
	(arc
		(start 363.72673 -224.539048)
		(mid 363.611303 -224.405672)
		(end 363.569758 -224.234248)
		(width 0.1143)
		(layer "In6.Cu")
		(net "GMI_CPU1_G0_CPU0_G2_TX_DN<8>")
	)
	(arc
		(start 104.165654 -242.05438)
		(mid 104.124105 -242.225802)
		(end 104.008682 -242.35918)
		(width 0.1143)
		(layer "In6.Cu")
		(net "GMI_CPU1_G0_CPU0_G2_TX_DN<8>")
	)
	(arc
		(start 365.137192 -231.828848)
		(mid 365.021765 -231.695472)
		(end 364.98022 -231.524048)
		(width 0.1143)
		(layer "In6.Cu")
		(net "GMI_CPU1_G0_CPU0_G2_TX_DN<8>")
	)
	(arc
		(start 367.047526 -239.946434)
		(mid 367.039592 -239.941706)
		(end 367.031778 -239.936782)
		(width 0.1143)
		(layer "In6.Cu")
		(net "GMI_CPU1_G0_CPU0_G2_TX_DN<8>")
	)
	(arc
		(start 106.35869 -234.459526)
		(mid 106.515667 -234.764326)
		(end 106.35869 -235.069126)
		(width 0.1143)
		(layer "In6.Cu")
		(net "GMI_CPU1_G0_CPU0_G2_TX_DN<8>")
	)
	(arc
		(start 106.289094 -231.869742)
		(mid 106.045767 -232.334308)
		(end 106.289094 -232.798874)
		(width 0.1143)
		(layer "In6.Cu")
		(net "GMI_CPU1_G0_CPU0_G2_TX_DN<8>")
	)
	(arc
		(start 365.137192 -233.44886)
		(mid 364.980215 -233.14406)
		(end 365.137192 -232.83926)
		(width 0.1143)
		(layer "In6.Cu")
		(net "GMI_CPU1_G0_CPU0_G2_TX_DN<8>")
	)
	(arc
		(start 106.045762 -230.71455)
		(mid 106.110277 -230.976769)
		(end 106.289094 -231.179116)
		(width 0.1143)
		(layer "In6.Cu")
		(net "GMI_CPU1_G0_CPU0_G2_TX_DN<8>")
	)
	(arc
		(start 104.497886 -240.953036)
		(mid 104.647208 -241.244374)
		(end 104.497886 -241.535712)
		(width 0.1143)
		(layer "In6.Cu")
		(net "GMI_CPU1_G0_CPU0_G2_TX_DN<8>")
	)
	(arc
		(start 366.390174 -237.19409)
		(mid 366.325659 -236.931871)
		(end 366.146842 -236.729524)
		(width 0.1143)
		(layer "In6.Cu")
		(net "GMI_CPU1_G0_CPU0_G2_TX_DN<8>")
	)
	(arc
		(start 109.336078 -221.804484)
		(mid 109.319028 -221.915675)
		(end 109.269784 -222.016828)
		(width 0.1143)
		(layer "In6.Cu")
		(net "GMI_CPU1_G0_CPU0_G2_TX_DN<8>")
	)
	(arc
		(start 367.794032 -242.781328)
		(mid 367.792244 -242.769879)
		(end 367.790222 -242.758468)
		(width 0.1143)
		(layer "In6.Cu")
		(net "GMI_CPU1_G0_CPU0_G2_TX_DN<8>")
	)
	(arc
		(start 108.86567 -222.61449)
		(mid 108.823916 -222.786433)
		(end 108.707936 -222.920052)
		(width 0.1143)
		(layer "In6.Cu")
		(net "GMI_CPU1_G0_CPU0_G2_TX_DN<8>")
	)
	(arc
		(start 362.316014 -222.108522)
		(mid 362.267082 -222.066434)
		(end 362.226098 -222.016574)
		(width 0.1143)
		(layer "In6.Cu")
		(net "GMI_CPU1_G0_CPU0_G2_TX_DN<8>")
	)
	(arc
		(start 104.408986 -241.589814)
		(mid 104.230173 -241.792164)
		(end 104.165654 -242.05438)
		(width 0.1143)
		(layer "In6.Cu")
		(net "GMI_CPU1_G0_CPU0_G2_TX_DN<8>")
	)
	(arc
		(start 104.949752 -238.510064)
		(mid 105.10568 -238.814356)
		(end 104.949752 -239.118648)
		(width 0.1143)
		(layer "In6.Cu")
		(net "GMI_CPU1_G0_CPU0_G2_TX_DN<8>")
	)
	(arc
		(start 106.291634 -230.248206)
		(mid 106.110982 -230.450951)
		(end 106.045762 -230.71455)
		(width 0.1143)
		(layer "In6.Cu")
		(net "GMI_CPU1_G0_CPU0_G2_TX_DN<8>")
	)
	(arc
		(start 366.861598 -239.62487)
		(mid 366.786608 -239.344504)
		(end 366.58169 -239.138968)
		(width 0.1143)
		(layer "In6.Cu")
		(net "GMI_CPU1_G0_CPU0_G2_TX_DN<8>")
	)
	(arc
		(start 364.98022 -226.664266)
		(mid 364.915705 -226.402047)
		(end 364.736888 -226.1997)
		(width 0.1143)
		(layer "In6.Cu")
		(net "GMI_CPU1_G0_CPU0_G2_TX_DN<8>")
	)
	(arc
		(start 106.289094 -227.00996)
		(mid 106.045767 -227.474526)
		(end 106.289094 -227.939092)
		(width 0.1143)
		(layer "In6.Cu")
		(net "GMI_CPU1_G0_CPU0_G2_TX_DN<8>")
	)
	(arc
		(start 104.634284 -239.625124)
		(mid 104.588964 -239.802773)
		(end 104.464104 -239.937036)
		(width 0.1143)
		(layer "In6.Cu")
		(net "GMI_CPU1_G0_CPU0_G2_TX_DN<8>")
	)
	(arc
		(start 107.268264 -225.367088)
		(mid 107.070775 -225.564486)
		(end 106.998516 -225.834194)
		(width 0.1143)
		(layer "In6.Cu")
		(net "GMI_CPU1_G0_CPU0_G2_TX_DN<8>")
	)
	(arc
		(start 108.173774 -223.76765)
		(mid 107.99198 -223.969313)
		(end 107.926124 -224.232724)
		(width 0.1143)
		(layer "In6.Cu")
		(net "GMI_CPU1_G0_CPU0_G2_TX_DN<8>")
	)
	(arc
		(start 106.289094 -228.629972)
		(mid 106.045767 -229.094538)
		(end 106.289094 -229.559104)
		(width 0.1143)
		(layer "In6.Cu")
		(net "GMI_CPU1_G0_CPU0_G2_TX_DN<8>")
	)
	(arc
		(start 364.98022 -229.904036)
		(mid 365.021186 -229.73363)
		(end 365.13516 -229.600506)
		(width 0.1143)
		(layer "In6.Cu")
		(net "GMI_CPU1_G0_CPU0_G2_TX_DN<8>")
	)
	(arc
		(start 366.54613 -239.118394)
		(mid 366.390202 -238.814102)
		(end 366.54613 -238.50981)
		(width 0.1143)
		(layer "In6.Cu")
		(net "GMI_CPU1_G0_CPU0_G2_TX_DN<8>")
	)
	(arc
		(start 365.206788 -232.79862)
		(mid 365.450115 -232.334054)
		(end 365.206788 -231.869488)
		(width 0.1143)
		(layer "In6.Cu")
		(net "GMI_CPU1_G0_CPU0_G2_TX_DN<8>")
	)
	(arc
		(start 363.252766 -223.726502)
		(mid 363.13988 -223.593731)
		(end 363.09935 -223.424242)
		(width 0.1143)
		(layer "In6.Cu")
		(net "GMI_CPU1_G0_CPU0_G2_TX_DN<8>")
	)
	(arc
		(start 106.35869 -232.839514)
		(mid 106.515667 -233.144314)
		(end 106.35869 -233.449114)
		(width 0.1143)
		(layer "In6.Cu")
		(net "GMI_CPU1_G0_CPU0_G2_TX_DN<8>")
	)
	(arc
		(start 107.926124 -224.234502)
		(mid 107.884575 -224.405924)
		(end 107.769152 -224.539302)
		(width 0.1143)
		(layer "In6.Cu")
		(net "GMI_CPU1_G0_CPU0_G2_TX_DN<8>")
	)
	(arc
		(start 364.039912 -225.044254)
		(mid 363.97504 -224.781291)
		(end 363.79531 -224.578672)
		(width 0.1143)
		(layer "In6.Cu")
		(net "GMI_CPU1_G0_CPU0_G2_TX_DN<8>")
	)
	(arc
		(start 104.408986 -239.969802)
		(mid 104.165659 -240.434368)
		(end 104.408986 -240.898934)
		(width 0.1143)
		(layer "In6.Cu")
		(net "GMI_CPU1_G0_CPU0_G2_TX_DN<8>")
	)
	(arc
		(start 364.497366 -225.83394)
		(mid 364.42508 -225.564248)
		(end 364.227618 -225.366834)
		(width 0.1143)
		(layer "In6.Cu")
		(net "GMI_CPU1_G0_CPU0_G2_TX_DN<8>")
	)
	(arc
		(start 108.396532 -223.424496)
		(mid 108.355977 -223.593972)
		(end 108.243116 -223.726756)
		(width 0.1143)
		(layer "In6.Cu")
		(net "GMI_CPU1_G0_CPU0_G2_TX_DN<8>")
	)
	(arc
		(start 365.137192 -226.969066)
		(mid 365.021765 -226.83569)
		(end 364.98022 -226.664266)
		(width 0.1143)
		(layer "In6.Cu")
		(net "GMI_CPU1_G0_CPU0_G2_TX_DN<8>")
	)
	(arc
		(start 106.515662 -226.66452)
		(mid 106.474113 -226.835942)
		(end 106.35869 -226.96932)
		(width 0.1143)
		(layer "In6.Cu")
		(net "GMI_CPU1_G0_CPU0_G2_TX_DN<8>")
	)
	(arc
		(start 367.4872 -242.358926)
		(mid 367.371773 -242.22555)
		(end 367.330228 -242.054126)
		(width 0.1143)
		(layer "In6.Cu")
		(net "GMI_CPU1_G0_CPU0_G2_TX_DN<8>")
	)
	(arc
		(start 105.105708 -237.194344)
		(mid 105.064453 -237.365315)
		(end 104.949752 -237.498636)
		(width 0.1143)
		(layer "In6.Cu")
		(net "GMI_CPU1_G0_CPU0_G2_TX_DN<8>")
	)
	(arc
		(start 105.34904 -236.729778)
		(mid 105.170227 -236.932128)
		(end 105.105708 -237.194344)
		(width 0.1143)
		(layer "In6.Cu")
		(net "GMI_CPU1_G0_CPU0_G2_TX_DN<8>")
	)
	(arc
		(start 367.086896 -240.89868)
		(mid 367.330223 -240.434114)
		(end 367.086896 -239.969548)
		(width 0.1143)
		(layer "In6.Cu")
		(net "GMI_CPU1_G0_CPU0_G2_TX_DN<8>")
	)
	(arc
		(start 106.515662 -231.524302)
		(mid 106.474113 -231.695724)
		(end 106.35869 -231.829102)
		(width 0.1143)
		(layer "In6.Cu")
		(net "GMI_CPU1_G0_CPU0_G2_TX_DN<8>")
	)
	(arc
		(start 365.137192 -228.589078)
		(mid 364.980215 -228.284278)
		(end 365.137192 -227.979478)
		(width 0.1143)
		(layer "In6.Cu")
		(net "GMI_CPU1_G0_CPU0_G2_TX_DN<8>")
	)
	(arc
		(start 366.644682 -238.44885)
		(mid 366.872682 -238.004096)
		(end 366.644682 -237.559342)
		(width 0.1143)
		(layer "In6.Cu")
		(net "GMI_CPU1_G0_CPU0_G2_TX_DN<8>")
	)
	(arc
		(start 365.137192 -230.208836)
		(mid 365.021765 -230.07546)
		(end 364.98022 -229.904036)
		(width 0.1143)
		(layer "In6.Cu")
		(net "GMI_CPU1_G0_CPU0_G2_TX_DN<8>")
	)
	(arc
		(start 367.790222 -242.758468)
		(mid 367.708789 -242.55607)
		(end 367.556796 -242.399566)
		(width 0.1143)
		(layer "In6.Cu")
		(net "GMI_CPU1_G0_CPU0_G2_TX_DN<8>")
	)
	(arc
		(start 106.360722 -231.220772)
		(mid 106.474651 -231.353919)
		(end 106.515662 -231.524302)
		(width 0.1143)
		(layer "In6.Cu")
		(net "GMI_CPU1_G0_CPU0_G2_TX_DN<8>")
	)
	(arc
		(start 103.939086 -242.39982)
		(mid 103.787099 -242.556328)
		(end 103.70566 -242.758722)
		(width 0.1143)
		(layer "In6.Cu")
		(net "GMI_CPU1_G0_CPU0_G2_TX_DN<8>")
	)
	(arc
		(start 365.45012 -235.574078)
		(mid 365.385605 -235.311859)
		(end 365.206788 -235.109512)
		(width 0.1143)
		(layer "In6.Cu")
		(net "GMI_CPU1_G0_CPU0_G2_TX_DN<8>")
	)
	(arc
		(start 367.031778 -239.936782)
		(mid 366.906881 -239.802539)
		(end 366.861598 -239.62487)
		(width 0.1143)
		(layer "In6.Cu")
		(net "GMI_CPU1_G0_CPU0_G2_TX_DN<8>")
	)
	(arc
		(start 364.685072 -226.169474)
		(mid 364.54764 -226.032215)
		(end 364.497366 -225.844608)
		(width 0.1143)
		(layer "In6.Cu")
		(net "GMI_CPU1_G0_CPU0_G2_TX_DN<8>")
	)
	(arc
		(start 364.196884 -225.349054)
		(mid 364.081457 -225.215678)
		(end 364.039912 -225.044254)
		(width 0.1143)
		(layer "In6.Cu")
		(net "GMI_CPU1_G0_CPU0_G2_TX_DN<8>")
	)
	(arc
		(start 104.464104 -239.937036)
		(mid 104.45629 -239.94196)
		(end 104.448356 -239.946688)
		(width 0.1143)
		(layer "In6.Cu")
		(net "GMI_CPU1_G0_CPU0_G2_TX_DN<8>")
	)
	(arc
		(start 105.575608 -236.384338)
		(mid 105.534059 -236.55576)
		(end 105.418636 -236.689138)
		(width 0.1143)
		(layer "In6.Cu")
		(net "GMI_CPU1_G0_CPU0_G2_TX_DN<8>")
	)
	(arc
		(start 106.289094 -235.109766)
		(mid 106.110281 -235.312116)
		(end 106.045762 -235.574332)
		(width 0.1143)
		(layer "In6.Cu")
		(net "GMI_CPU1_G0_CPU0_G2_TX_DN<8>")
	)
	(arc
		(start 365.137192 -235.068872)
		(mid 364.980215 -234.764072)
		(end 365.137192 -234.459272)
		(width 0.1143)
		(layer "In6.Cu")
		(net "GMI_CPU1_G0_CPU0_G2_TX_DN<8>")
	)
	(arc
		(start 362.787946 -222.919798)
		(mid 362.671993 -222.786165)
		(end 362.630212 -222.614236)
		(width 0.1143)
		(layer "In6.Cu")
		(net "GMI_CPU1_G0_CPU0_G2_TX_DN<8>")
	)
	(arc
		(start 106.998516 -225.844862)
		(mid 106.94821 -226.03245)
		(end 106.81081 -226.169728)
		(width 0.1143)
		(layer "In6.Cu")
		(net "GMI_CPU1_G0_CPU0_G2_TX_DN<8>")
	)
	(arc
		(start 365.606076 -235.87837)
		(mid 365.4914 -235.745036)
		(end 365.45012 -235.574078)
		(width 0.1143)
		(layer "In6.Cu")
		(net "GMI_CPU1_G0_CPU0_G2_TX_DN<8>")
	)
	(arc
		(start 104.8512 -237.559596)
		(mid 104.6232 -238.00435)
		(end 104.8512 -238.449104)
		(width 0.1143)
		(layer "In6.Cu")
		(net "GMI_CPU1_G0_CPU0_G2_TX_DN<8>")
	)
	(arc
		(start 365.920274 -236.384084)
		(mid 365.855759 -236.121865)
		(end 365.676942 -235.919518)
		(width 0.1143)
		(layer "In6.Cu")
		(net "GMI_CPU1_G0_CPU0_G2_TX_DN<8>")
	)
	(arc
		(start 106.758994 -226.199954)
		(mid 106.580181 -226.402304)
		(end 106.515662 -226.66452)
		(width 0.1143)
		(layer "In6.Cu")
		(net "GMI_CPU1_G0_CPU0_G2_TX_DN<8>")
	)
	(arc
		(start 365.206788 -229.55885)
		(mid 365.450115 -229.094284)
		(end 365.206788 -228.629718)
		(width 0.1143)
		(layer "In6.Cu")
		(net "GMI_CPU1_G0_CPU0_G2_TX_DN<8>")
	)
	(arc
		(start 365.206788 -231.178862)
		(mid 365.385601 -230.976512)
		(end 365.45012 -230.714296)
		(width 0.1143)
		(layer "In6.Cu")
		(net "GMI_CPU1_G0_CPU0_G2_TX_DN<8>")
	)
	(arc
		(start 104.914192 -239.139222)
		(mid 104.709228 -239.344732)
		(end 104.634284 -239.625124)
		(width 0.1143)
		(layer "In6.Cu")
		(net "GMI_CPU1_G0_CPU0_G2_TX_DN<8>")
	)
	(arc
		(start 109.109002 -222.149924)
		(mid 108.930189 -222.352274)
		(end 108.86567 -222.61449)
		(width 0.1143)
		(layer "In6.Cu")
		(net "GMI_CPU1_G0_CPU0_G2_TX_DN<8>")
	)
	(arc
		(start 106.289094 -233.489754)
		(mid 106.045767 -233.95432)
		(end 106.289094 -234.418886)
		(width 0.1143)
		(layer "In6.Cu")
		(net "GMI_CPU1_G0_CPU0_G2_TX_DN<8>")
	)
	(arc
		(start 108.64215 -222.958152)
		(mid 108.461654 -223.160948)
		(end 108.396532 -223.424496)
		(width 0.1143)
		(layer "In6.Cu")
		(net "GMI_CPU1_G0_CPU0_G2_TX_DN<8>")
	)
	(arc
		(start 365.206788 -234.418632)
		(mid 365.450115 -233.954066)
		(end 365.206788 -233.4895)
		(width 0.1143)
		(layer "In6.Cu")
		(net "GMI_CPU1_G0_CPU0_G2_TX_DN<8>")
	)
	(arc
		(start 105.81894 -235.919772)
		(mid 105.640127 -236.122122)
		(end 105.575608 -236.384338)
		(width 0.1143)
		(layer "In6.Cu")
		(net "GMI_CPU1_G0_CPU0_G2_TX_DN<8>")
	)
	(segment
		(start 367.707926 -239.890046)
		(end 368.174778 -239.624108)
		(width 0.12954)
		(layer "F.Cu")
		(net "GMI_CPU1_G0_CPU0_G2_TX_DN<7>")
	)
	(segment
		(start 103.787956 -239.8903)
		(end 103.321104 -239.624362)
		(width 0.12954)
		(layer "F.Cu")
		(net "GMI_CPU1_G0_CPU0_G2_TX_DN<7>")
	)
	(segment
		(start 108.349288 -221.064836)
		(end 108.349288 -219.969842)
		(width 0.14224)
		(layer "In6.Cu")
		(net "GMI_CPU1_G0_CPU0_G2_TX_DN<7>")
	)
	(segment
		(start 115.850924 -210.85937)
		(end 116.160296 -210.62188)
		(width 0.14224)
		(layer "In6.Cu")
		(net "GMI_CPU1_G0_CPU0_G2_TX_DN<7>")
	)
	(segment
		(start 107.702096 -222.958152)
		(end 107.738418 -222.93707)
		(width 0.1143)
		(layer "In6.Cu")
		(net "GMI_CPU1_G0_CPU0_G2_TX_DN<7>")
	)
	(segment
		(start 367.794032 -239.541304)
		(end 367.876836 -239.624108)
		(width 0.1143)
		(layer "In6.Cu")
		(net "GMI_CPU1_G0_CPU0_G2_TX_DN<7>")
	)
	(segment
		(start 108.208826 -222.126556)
		(end 108.210096 -222.125794)
		(width 0.1143)
		(layer "In6.Cu")
		(net "GMI_CPU1_G0_CPU0_G2_TX_DN<7>")
	)
	(segment
		(start 108.207048 -222.127572)
		(end 108.208064 -222.127064)
		(width 0.1143)
		(layer "In6.Cu")
		(net "GMI_CPU1_G0_CPU0_G2_TX_DN<7>")
	)
	(segment
		(start 105.420668 -229.60076)
		(end 105.388156 -229.581964)
		(width 0.1143)
		(layer "In6.Cu")
		(net "GMI_CPU1_G0_CPU0_G2_TX_DN<7>")
	)
	(segment
		(start 366.077246 -230.208836)
		(end 366.144302 -230.247952)
		(width 0.1143)
		(layer "In6.Cu")
		(net "GMI_CPU1_G0_CPU0_G2_TX_DN<7>")
	)
	(segment
		(start 106.798364 -224.557082)
		(end 106.813858 -224.548192)
		(width 0.1143)
		(layer "In6.Cu")
		(net "GMI_CPU1_G0_CPU0_G2_TX_DN<7>")
	)
	(segment
		(start 104.88168 -235.917994)
		(end 104.918002 -235.896912)
		(width 0.1143)
		(layer "In6.Cu")
		(net "GMI_CPU1_G0_CPU0_G2_TX_DN<7>")
	)
	(segment
		(start 363.287818 -222.12681)
		(end 363.288834 -222.127318)
		(width 0.1143)
		(layer "In6.Cu")
		(net "GMI_CPU1_G0_CPU0_G2_TX_DN<7>")
	)
	(segment
		(start 105.418636 -232.839514)
		(end 105.388156 -232.821734)
		(width 0.1143)
		(layer "In6.Cu")
		(net "GMI_CPU1_G0_CPU0_G2_TX_DN<7>")
	)
	(segment
		(start 302.899064 -181.377336)
		(end 306.67833 -181.377336)
		(width 0.14224)
		(layer "In6.Cu")
		(net "GMI_CPU1_G0_CPU0_G2_TX_DN<7>")
	)
	(segment
		(start 123.803156 -204.75702)
		(end 163.980114 -181.557422)
		(width 0.14224)
		(layer "In6.Cu")
		(net "GMI_CPU1_G0_CPU0_G2_TX_DN<7>")
	)
	(segment
		(start 362.515658 -218.023694)
		(end 363.146594 -219.546932)
		(width 0.14224)
		(layer "In6.Cu")
		(net "GMI_CPU1_G0_CPU0_G2_TX_DN<7>")
	)
	(segment
		(start 105.388156 -234.441746)
		(end 105.34904 -234.418886)
		(width 0.1143)
		(layer "In6.Cu")
		(net "GMI_CPU1_G0_CPU0_G2_TX_DN<7>")
	)
	(segment
		(start 103.321104 -239.624362)
		(end 103.619046 -239.624362)
		(width 0.1143)
		(layer "In6.Cu")
		(net "GMI_CPU1_G0_CPU0_G2_TX_DN<7>")
	)
	(segment
		(start 105.388156 -235.086906)
		(end 105.418636 -235.069126)
		(width 0.1143)
		(layer "In6.Cu")
		(net "GMI_CPU1_G0_CPU0_G2_TX_DN<7>")
	)
	(segment
		(start 105.861612 -226.175062)
		(end 105.889806 -226.158552)
		(width 0.1143)
		(layer "In6.Cu")
		(net "GMI_CPU1_G0_CPU0_G2_TX_DN<7>")
	)
	(segment
		(start 105.388156 -231.846882)
		(end 105.418636 -231.829102)
		(width 0.1143)
		(layer "In6.Cu")
		(net "GMI_CPU1_G0_CPU0_G2_TX_DN<7>")
	)
	(segment
		(start 315.286644 -185.944002)
		(end 316.173104 -186.87796)
		(width 0.14224)
		(layer "In6.Cu")
		(net "GMI_CPU1_G0_CPU0_G2_TX_DN<7>")
	)
	(segment
		(start 366.57788 -235.896658)
		(end 366.614202 -235.91774)
		(width 0.1143)
		(layer "In6.Cu")
		(net "GMI_CPU1_G0_CPU0_G2_TX_DN<7>")
	)
	(segment
		(start 106.813858 -224.548192)
		(end 106.83113 -224.538032)
		(width 0.1143)
		(layer "In6.Cu")
		(net "GMI_CPU1_G0_CPU0_G2_TX_DN<7>")
	)
	(segment
		(start 105.858818 -226.176586)
		(end 105.860088 -226.175824)
		(width 0.1143)
		(layer "In6.Cu")
		(net "GMI_CPU1_G0_CPU0_G2_TX_DN<7>")
	)
	(segment
		(start 364.697518 -224.556828)
		(end 364.699804 -224.557844)
		(width 0.1143)
		(layer "In6.Cu")
		(net "GMI_CPU1_G0_CPU0_G2_TX_DN<7>")
	)
	(segment
		(start 108.168948 -222.149924)
		(end 108.207048 -222.127572)
		(width 0.1143)
		(layer "In6.Cu")
		(net "GMI_CPU1_G0_CPU0_G2_TX_DN<7>")
	)
	(segment
		(start 105.858056 -226.177094)
		(end 105.858818 -226.176586)
		(width 0.1143)
		(layer "In6.Cu")
		(net "GMI_CPU1_G0_CPU0_G2_TX_DN<7>")
	)
	(segment
		(start 107.226862 -223.77146)
		(end 107.268772 -223.747076)
		(width 0.1143)
		(layer "In6.Cu")
		(net "GMI_CPU1_G0_CPU0_G2_TX_DN<7>")
	)
	(segment
		(start 103.939086 -239.159796)
		(end 103.978202 -239.136936)
		(width 0.1143)
		(layer "In6.Cu")
		(net "GMI_CPU1_G0_CPU0_G2_TX_DN<7>")
	)
	(segment
		(start 105.418636 -234.459526)
		(end 105.388156 -234.441746)
		(width 0.1143)
		(layer "In6.Cu")
		(net "GMI_CPU1_G0_CPU0_G2_TX_DN<7>")
	)
	(segment
		(start 108.349288 -219.969842)
		(end 109.486954 -217.22334)
		(width 0.14224)
		(layer "In6.Cu")
		(net "GMI_CPU1_G0_CPU0_G2_TX_DN<7>")
	)
	(segment
		(start 108.210096 -222.125794)
		(end 108.239814 -222.108776)
		(width 0.1143)
		(layer "In6.Cu")
		(net "GMI_CPU1_G0_CPU0_G2_TX_DN<7>")
	)
	(segment
		(start 366.575848 -235.895388)
		(end 366.577118 -235.89615)
		(width 0.1143)
		(layer "In6.Cu")
		(net "GMI_CPU1_G0_CPU0_G2_TX_DN<7>")
	)
	(segment
		(start 367.556796 -238.468662)
		(end 367.4872 -238.509302)
		(width 0.1143)
		(layer "In6.Cu")
		(net "GMI_CPU1_G0_CPU0_G2_TX_DN<7>")
	)
	(segment
		(start 105.34904 -233.489754)
		(end 105.388156 -233.466894)
		(width 0.1143)
		(layer "In6.Cu")
		(net "GMI_CPU1_G0_CPU0_G2_TX_DN<7>")
	)
	(segment
		(start 104.447086 -236.707426)
		(end 104.44988 -236.705902)
		(width 0.1143)
		(layer "In6.Cu")
		(net "GMI_CPU1_G0_CPU0_G2_TX_DN<7>")
	)
	(segment
		(start 105.860088 -226.175824)
		(end 105.861612 -226.175062)
		(width 0.1143)
		(layer "In6.Cu")
		(net "GMI_CPU1_G0_CPU0_G2_TX_DN<7>")
	)
	(segment
		(start 306.67833 -181.377336)
		(end 308.386734 -181.846474)
		(width 0.14224)
		(layer "In6.Cu")
		(net "GMI_CPU1_G0_CPU0_G2_TX_DN<7>")
	)
	(segment
		(start 163.980114 -181.557422)
		(end 167.637968 -180.588666)
		(width 0.14224)
		(layer "In6.Cu")
		(net "GMI_CPU1_G0_CPU0_G2_TX_DN<7>")
	)
	(segment
		(start 105.34904 -235.109766)
		(end 105.388156 -235.086906)
		(width 0.1143)
		(layer "In6.Cu")
		(net "GMI_CPU1_G0_CPU0_G2_TX_DN<7>")
	)
	(segment
		(start 103.978202 -239.136936)
		(end 104.008682 -239.119156)
		(width 0.1143)
		(layer "In6.Cu")
		(net "GMI_CPU1_G0_CPU0_G2_TX_DN<7>")
	)
	(segment
		(start 107.738418 -222.93707)
		(end 107.767882 -222.920052)
		(width 0.1143)
		(layer "In6.Cu")
		(net "GMI_CPU1_G0_CPU0_G2_TX_DN<7>")
	)
	(segment
		(start 108.208064 -222.127064)
		(end 108.208826 -222.126556)
		(width 0.1143)
		(layer "In6.Cu")
		(net "GMI_CPU1_G0_CPU0_G2_TX_DN<7>")
	)
	(segment
		(start 364.682024 -224.547938)
		(end 364.697518 -224.556828)
		(width 0.1143)
		(layer "In6.Cu")
		(net "GMI_CPU1_G0_CPU0_G2_TX_DN<7>")
	)
	(segment
		(start 366.54613 -235.87837)
		(end 366.575848 -235.895388)
		(width 0.1143)
		(layer "In6.Cu")
		(net "GMI_CPU1_G0_CPU0_G2_TX_DN<7>")
	)
	(segment
		(start 105.420668 -231.220772)
		(end 105.388156 -231.201976)
		(width 0.1143)
		(layer "In6.Cu")
		(net "GMI_CPU1_G0_CPU0_G2_TX_DN<7>")
	)
	(segment
		(start 365.638842 -226.177348)
		(end 365.640366 -226.178364)
		(width 0.1143)
		(layer "In6.Cu")
		(net "GMI_CPU1_G0_CPU0_G2_TX_DN<7>")
	)
	(segment
		(start 103.619046 -239.624362)
		(end 103.70185 -239.541558)
		(width 0.1143)
		(layer "In6.Cu")
		(net "GMI_CPU1_G0_CPU0_G2_TX_DN<7>")
	)
	(segment
		(start 105.34904 -231.869742)
		(end 105.388156 -231.846882)
		(width 0.1143)
		(layer "In6.Cu")
		(net "GMI_CPU1_G0_CPU0_G2_TX_DN<7>")
	)
	(segment
		(start 363.146594 -219.546932)
		(end 363.146594 -221.09303)
		(width 0.14224)
		(layer "In6.Cu")
		(net "GMI_CPU1_G0_CPU0_G2_TX_DN<7>")
	)
	(segment
		(start 364.19536 -223.728534)
		(end 364.22711 -223.746822)
		(width 0.1143)
		(layer "In6.Cu")
		(net "GMI_CPU1_G0_CPU0_G2_TX_DN<7>")
	)
	(segment
		(start 105.34904 -228.629972)
		(end 105.388156 -228.607112)
		(width 0.1143)
		(layer "In6.Cu")
		(net "GMI_CPU1_G0_CPU0_G2_TX_DN<7>")
	)
	(segment
		(start 363.256068 -222.108522)
		(end 363.285786 -222.12554)
		(width 0.1143)
		(layer "In6.Cu")
		(net "GMI_CPU1_G0_CPU0_G2_TX_DN<7>")
	)
	(segment
		(start 108.396024 -221.804484)
		(end 108.396024 -221.326964)
		(width 0.1143)
		(layer "In6.Cu")
		(net "GMI_CPU1_G0_CPU0_G2_TX_DN<7>")
	)
	(segment
		(start 105.388156 -228.607112)
		(end 105.418636 -228.589332)
		(width 0.1143)
		(layer "In6.Cu")
		(net "GMI_CPU1_G0_CPU0_G2_TX_DN<7>")
	)
	(segment
		(start 366.107726 -229.58171)
		(end 366.075214 -229.600506)
		(width 0.1143)
		(layer "In6.Cu")
		(net "GMI_CPU1_G0_CPU0_G2_TX_DN<7>")
	)
	(segment
		(start 366.077246 -233.44886)
		(end 366.146842 -233.4895)
		(width 0.1143)
		(layer "In6.Cu")
		(net "GMI_CPU1_G0_CPU0_G2_TX_DN<7>")
	)
	(segment
		(start 363.285786 -222.12554)
		(end 363.287056 -222.126302)
		(width 0.1143)
		(layer "In6.Cu")
		(net "GMI_CPU1_G0_CPU0_G2_TX_DN<7>")
	)
	(segment
		(start 105.388156 -227.961952)
		(end 105.34904 -227.939092)
		(width 0.1143)
		(layer "In6.Cu")
		(net "GMI_CPU1_G0_CPU0_G2_TX_DN<7>")
	)
	(segment
		(start 107.268772 -223.747076)
		(end 107.300522 -223.728788)
		(width 0.1143)
		(layer "In6.Cu")
		(net "GMI_CPU1_G0_CPU0_G2_TX_DN<7>")
	)
	(segment
		(start 108.349288 -221.093284)
		(end 108.349288 -221.064836)
		(width 0.1143)
		(layer "In6.Cu")
		(net "GMI_CPU1_G0_CPU0_G2_TX_DN<7>")
	)
	(segment
		(start 366.107726 -231.201722)
		(end 366.075214 -231.220518)
		(width 0.1143)
		(layer "In6.Cu")
		(net "GMI_CPU1_G0_CPU0_G2_TX_DN<7>")
	)
	(segment
		(start 108.396024 -221.326964)
		(end 108.395008 -221.325948)
		(width 0.1143)
		(layer "In6.Cu")
		(net "GMI_CPU1_G0_CPU0_G2_TX_DN<7>")
	)
	(segment
		(start 364.22711 -223.746822)
		(end 364.26902 -223.771206)
		(width 0.1143)
		(layer "In6.Cu")
		(net "GMI_CPU1_G0_CPU0_G2_TX_DN<7>")
	)
	(segment
		(start 109.486954 -217.22334)
		(end 115.850924 -210.85937)
		(width 0.14224)
		(layer "In6.Cu")
		(net "GMI_CPU1_G0_CPU0_G2_TX_DN<7>")
	)
	(segment
		(start 116.160296 -210.62188)
		(end 116.160296 -210.621626)
		(width 0.14224)
		(layer "In6.Cu")
		(net "GMI_CPU1_G0_CPU0_G2_TX_DN<7>")
	)
	(segment
		(start 105.388156 -229.581964)
		(end 105.34904 -229.559104)
		(width 0.1143)
		(layer "In6.Cu")
		(net "GMI_CPU1_G0_CPU0_G2_TX_DN<7>")
	)
	(segment
		(start 363.287056 -222.126302)
		(end 363.287818 -222.12681)
		(width 0.1143)
		(layer "In6.Cu")
		(net "GMI_CPU1_G0_CPU0_G2_TX_DN<7>")
	)
	(segment
		(start 104.920034 -235.895642)
		(end 104.949752 -235.878624)
		(width 0.1143)
		(layer "In6.Cu")
		(net "GMI_CPU1_G0_CPU0_G2_TX_DN<7>")
	)
	(segment
		(start 103.978202 -238.491776)
		(end 103.939086 -238.468916)
		(width 0.1143)
		(layer "In6.Cu")
		(net "GMI_CPU1_G0_CPU0_G2_TX_DN<7>")
	)
	(segment
		(start 363.146594 -221.09303)
		(end 363.100874 -221.13875)
		(width 0.1143)
		(layer "In6.Cu")
		(net "GMI_CPU1_G0_CPU0_G2_TX_DN<7>")
	)
	(segment
		(start 105.388156 -232.821734)
		(end 105.34904 -232.798874)
		(width 0.1143)
		(layer "In6.Cu")
		(net "GMI_CPU1_G0_CPU0_G2_TX_DN<7>")
	)
	(segment
		(start 363.288834 -222.127318)
		(end 363.326934 -222.14967)
		(width 0.1143)
		(layer "In6.Cu")
		(net "GMI_CPU1_G0_CPU0_G2_TX_DN<7>")
	)
	(segment
		(start 367.048796 -236.707172)
		(end 367.05032 -236.708188)
		(width 0.1143)
		(layer "In6.Cu")
		(net "GMI_CPU1_G0_CPU0_G2_TX_DN<7>")
	)
	(segment
		(start 105.35158 -230.248206)
		(end 105.418636 -230.20909)
		(width 0.1143)
		(layer "In6.Cu")
		(net "GMI_CPU1_G0_CPU0_G2_TX_DN<7>")
	)
	(segment
		(start 103.939086 -237.539784)
		(end 103.978202 -237.516924)
		(width 0.1143)
		(layer "In6.Cu")
		(net "GMI_CPU1_G0_CPU0_G2_TX_DN<7>")
	)
	(segment
		(start 105.388156 -226.9871)
		(end 105.418636 -226.96932)
		(width 0.1143)
		(layer "In6.Cu")
		(net "GMI_CPU1_G0_CPU0_G2_TX_DN<7>")
	)
	(segment
		(start 104.008682 -238.509556)
		(end 103.978202 -238.491776)
		(width 0.1143)
		(layer "In6.Cu")
		(net "GMI_CPU1_G0_CPU0_G2_TX_DN<7>")
	)
	(segment
		(start 366.146842 -229.55885)
		(end 366.107726 -229.58171)
		(width 0.1143)
		(layer "In6.Cu")
		(net "GMI_CPU1_G0_CPU0_G2_TX_DN<7>")
	)
	(segment
		(start 367.876836 -239.624108)
		(end 368.174778 -239.624108)
		(width 0.1143)
		(layer "In6.Cu")
		(net "GMI_CPU1_G0_CPU0_G2_TX_DN<7>")
	)
	(segment
		(start 366.077246 -228.589078)
		(end 366.146842 -228.629718)
		(width 0.1143)
		(layer "In6.Cu")
		(net "GMI_CPU1_G0_CPU0_G2_TX_DN<7>")
	)
	(segment
		(start 365.637826 -226.17684)
		(end 365.638842 -226.177348)
		(width 0.1143)
		(layer "In6.Cu")
		(net "GMI_CPU1_G0_CPU0_G2_TX_DN<7>")
	)
	(segment
		(start 354.7999 -211.168234)
		(end 359.045764 -214.55507)
		(width 0.14224)
		(layer "In6.Cu")
		(net "GMI_CPU1_G0_CPU0_G2_TX_DN<7>")
	)
	(segment
		(start 366.146842 -227.938838)
		(end 366.077246 -227.979478)
		(width 0.1143)
		(layer "In6.Cu")
		(net "GMI_CPU1_G0_CPU0_G2_TX_DN<7>")
	)
	(segment
		(start 366.577118 -235.89615)
		(end 366.57788 -235.896658)
		(width 0.1143)
		(layer "In6.Cu")
		(net "GMI_CPU1_G0_CPU0_G2_TX_DN<7>")
	)
	(segment
		(start 366.146842 -232.79862)
		(end 366.077246 -232.83926)
		(width 0.1143)
		(layer "In6.Cu")
		(net "GMI_CPU1_G0_CPU0_G2_TX_DN<7>")
	)
	(segment
		(start 167.637968 -180.588666)
		(end 302.899064 -181.377336)
		(width 0.14224)
		(layer "In6.Cu")
		(net "GMI_CPU1_G0_CPU0_G2_TX_DN<7>")
	)
	(segment
		(start 359.045764 -214.55507)
		(end 362.515658 -218.023694)
		(width 0.14224)
		(layer "In6.Cu")
		(net "GMI_CPU1_G0_CPU0_G2_TX_DN<7>")
	)
	(segment
		(start 120.390666 -207.375506)
		(end 123.803156 -204.75702)
		(width 0.14224)
		(layer "In6.Cu")
		(net "GMI_CPU1_G0_CPU0_G2_TX_DN<7>")
	)
	(segment
		(start 363.728 -222.919798)
		(end 363.757464 -222.936816)
		(width 0.1143)
		(layer "In6.Cu")
		(net "GMI_CPU1_G0_CPU0_G2_TX_DN<7>")
	)
	(segment
		(start 105.388156 -233.466894)
		(end 105.418636 -233.449114)
		(width 0.1143)
		(layer "In6.Cu")
		(net "GMI_CPU1_G0_CPU0_G2_TX_DN<7>")
	)
	(segment
		(start 105.85704 -226.177602)
		(end 105.858056 -226.177094)
		(width 0.1143)
		(layer "In6.Cu")
		(net "GMI_CPU1_G0_CPU0_G2_TX_DN<7>")
	)
	(segment
		(start 104.918764 -235.896404)
		(end 104.920034 -235.895642)
		(width 0.1143)
		(layer "In6.Cu")
		(net "GMI_CPU1_G0_CPU0_G2_TX_DN<7>")
	)
	(segment
		(start 366.077246 -231.828848)
		(end 366.146842 -231.869488)
		(width 0.1143)
		(layer "In6.Cu")
		(net "GMI_CPU1_G0_CPU0_G2_TX_DN<7>")
	)
	(segment
		(start 366.146842 -231.178862)
		(end 366.107726 -231.201722)
		(width 0.1143)
		(layer "In6.Cu")
		(net "GMI_CPU1_G0_CPU0_G2_TX_DN<7>")
	)
	(segment
		(start 105.418636 -227.979732)
		(end 105.388156 -227.961952)
		(width 0.1143)
		(layer "In6.Cu")
		(net "GMI_CPU1_G0_CPU0_G2_TX_DN<7>")
	)
	(segment
		(start 105.388156 -231.201976)
		(end 105.34904 -231.179116)
		(width 0.1143)
		(layer "In6.Cu")
		(net "GMI_CPU1_G0_CPU0_G2_TX_DN<7>")
	)
	(segment
		(start 365.637064 -226.176332)
		(end 365.637826 -226.17684)
		(width 0.1143)
		(layer "In6.Cu")
		(net "GMI_CPU1_G0_CPU0_G2_TX_DN<7>")
	)
	(segment
		(start 308.386734 -181.846474)
		(end 315.286644 -185.944002)
		(width 0.14224)
		(layer "In6.Cu")
		(net "GMI_CPU1_G0_CPU0_G2_TX_DN<7>")
	)
	(segment
		(start 106.325162 -225.372168)
		(end 106.331004 -225.36912)
		(width 0.1143)
		(layer "In6.Cu")
		(net "GMI_CPU1_G0_CPU0_G2_TX_DN<7>")
	)
	(segment
		(start 365.63427 -226.174808)
		(end 365.635794 -226.17557)
		(width 0.1143)
		(layer "In6.Cu")
		(net "GMI_CPU1_G0_CPU0_G2_TX_DN<7>")
	)
	(segment
		(start 108.395008 -221.325948)
		(end 108.395008 -221.139004)
		(width 0.1143)
		(layer "In6.Cu")
		(net "GMI_CPU1_G0_CPU0_G2_TX_DN<7>")
	)
	(segment
		(start 104.918002 -235.896912)
		(end 104.918764 -235.896404)
		(width 0.1143)
		(layer "In6.Cu")
		(net "GMI_CPU1_G0_CPU0_G2_TX_DN<7>")
	)
	(segment
		(start 365.640366 -226.178364)
		(end 365.676942 -226.1997)
		(width 0.1143)
		(layer "In6.Cu")
		(net "GMI_CPU1_G0_CPU0_G2_TX_DN<7>")
	)
	(segment
		(start 367.05032 -236.708188)
		(end 367.086896 -236.729524)
		(width 0.1143)
		(layer "In6.Cu")
		(net "GMI_CPU1_G0_CPU0_G2_TX_DN<7>")
	)
	(segment
		(start 366.077246 -235.068872)
		(end 366.146842 -235.109512)
		(width 0.1143)
		(layer "In6.Cu")
		(net "GMI_CPU1_G0_CPU0_G2_TX_DN<7>")
	)
	(segment
		(start 365.164878 -225.368866)
		(end 365.17072 -225.371914)
		(width 0.1143)
		(layer "In6.Cu")
		(net "GMI_CPU1_G0_CPU0_G2_TX_DN<7>")
	)
	(segment
		(start 367.4872 -237.49889)
		(end 367.556796 -237.53953)
		(width 0.1143)
		(layer "In6.Cu")
		(net "GMI_CPU1_G0_CPU0_G2_TX_DN<7>")
	)
	(segment
		(start 367.046002 -236.705648)
		(end 367.048796 -236.707172)
		(width 0.1143)
		(layer "In6.Cu")
		(net "GMI_CPU1_G0_CPU0_G2_TX_DN<7>")
	)
	(segment
		(start 363.757464 -222.936816)
		(end 363.793786 -222.957898)
		(width 0.1143)
		(layer "In6.Cu")
		(net "GMI_CPU1_G0_CPU0_G2_TX_DN<7>")
	)
	(segment
		(start 364.664752 -224.537778)
		(end 364.682024 -224.547938)
		(width 0.1143)
		(layer "In6.Cu")
		(net "GMI_CPU1_G0_CPU0_G2_TX_DN<7>")
	)
	(segment
		(start 365.635794 -226.17557)
		(end 365.637064 -226.176332)
		(width 0.1143)
		(layer "In6.Cu")
		(net "GMI_CPU1_G0_CPU0_G2_TX_DN<7>")
	)
	(segment
		(start 116.160296 -210.621626)
		(end 120.39092 -207.375506)
		(width 0.14224)
		(layer "In6.Cu")
		(net "GMI_CPU1_G0_CPU0_G2_TX_DN<7>")
	)
	(segment
		(start 363.099858 -221.32671)
		(end 363.099858 -221.80423)
		(width 0.1143)
		(layer "In6.Cu")
		(net "GMI_CPU1_G0_CPU0_G2_TX_DN<7>")
	)
	(segment
		(start 363.100874 -221.325694)
		(end 363.099858 -221.32671)
		(width 0.1143)
		(layer "In6.Cu")
		(net "GMI_CPU1_G0_CPU0_G2_TX_DN<7>")
	)
	(segment
		(start 103.978202 -237.516924)
		(end 104.008682 -237.499144)
		(width 0.1143)
		(layer "In6.Cu")
		(net "GMI_CPU1_G0_CPU0_G2_TX_DN<7>")
	)
	(segment
		(start 363.100874 -221.13875)
		(end 363.100874 -221.325694)
		(width 0.1143)
		(layer "In6.Cu")
		(net "GMI_CPU1_G0_CPU0_G2_TX_DN<7>")
	)
	(segment
		(start 105.34904 -227.00996)
		(end 105.388156 -226.9871)
		(width 0.1143)
		(layer "In6.Cu")
		(net "GMI_CPU1_G0_CPU0_G2_TX_DN<7>")
	)
	(segment
		(start 365.606076 -226.158298)
		(end 365.63427 -226.174808)
		(width 0.1143)
		(layer "In6.Cu")
		(net "GMI_CPU1_G0_CPU0_G2_TX_DN<7>")
	)
	(segment
		(start 120.39092 -207.375506)
		(end 120.390666 -207.375506)
		(width 0.14224)
		(layer "In6.Cu")
		(net "GMI_CPU1_G0_CPU0_G2_TX_DN<7>")
	)
	(segment
		(start 316.173104 -186.87796)
		(end 354.7999 -211.168234)
		(width 0.14224)
		(layer "In6.Cu")
		(net "GMI_CPU1_G0_CPU0_G2_TX_DN<7>")
	)
	(segment
		(start 366.146842 -234.418632)
		(end 366.077246 -234.459272)
		(width 0.1143)
		(layer "In6.Cu")
		(net "GMI_CPU1_G0_CPU0_G2_TX_DN<7>")
	)
	(segment
		(start 105.81894 -226.199954)
		(end 105.85704 -226.177602)
		(width 0.1143)
		(layer "In6.Cu")
		(net "GMI_CPU1_G0_CPU0_G2_TX_DN<7>")
	)
	(segment
		(start 367.4872 -239.118902)
		(end 367.556796 -239.159542)
		(width 0.1143)
		(layer "In6.Cu")
		(net "GMI_CPU1_G0_CPU0_G2_TX_DN<7>")
	)
	(segment
		(start 106.796078 -224.558098)
		(end 106.798364 -224.557082)
		(width 0.1143)
		(layer "In6.Cu")
		(net "GMI_CPU1_G0_CPU0_G2_TX_DN<7>")
	)
	(segment
		(start 104.408986 -236.729778)
		(end 104.447086 -236.707426)
		(width 0.1143)
		(layer "In6.Cu")
		(net "GMI_CPU1_G0_CPU0_G2_TX_DN<7>")
	)
	(segment
		(start 366.077246 -226.969066)
		(end 366.146842 -227.009706)
		(width 0.1143)
		(layer "In6.Cu")
		(net "GMI_CPU1_G0_CPU0_G2_TX_DN<7>")
	)
	(segment
		(start 108.395008 -221.139004)
		(end 108.349288 -221.093284)
		(width 0.1143)
		(layer "In6.Cu")
		(net "GMI_CPU1_G0_CPU0_G2_TX_DN<7>")
	)
	(arc
		(start 366.390174 -230.714296)
		(mid 366.325659 -230.976515)
		(end 366.146842 -231.178862)
		(width 0.1143)
		(layer "In6.Cu")
		(net "GMI_CPU1_G0_CPU0_G2_TX_DN<7>")
	)
	(arc
		(start 105.34904 -227.939092)
		(mid 105.105713 -227.474526)
		(end 105.34904 -227.00996)
		(width 0.1143)
		(layer "In6.Cu")
		(net "GMI_CPU1_G0_CPU0_G2_TX_DN<7>")
	)
	(arc
		(start 367.556796 -237.53953)
		(mid 367.800123 -238.004096)
		(end 367.556796 -238.468662)
		(width 0.1143)
		(layer "In6.Cu")
		(net "GMI_CPU1_G0_CPU0_G2_TX_DN<7>")
	)
	(arc
		(start 366.860074 -236.384084)
		(mid 366.909897 -236.569814)
		(end 367.046002 -236.705648)
		(width 0.1143)
		(layer "In6.Cu")
		(net "GMI_CPU1_G0_CPU0_G2_TX_DN<7>")
	)
	(arc
		(start 367.556796 -239.159542)
		(mid 367.708783 -239.31605)
		(end 367.790222 -239.518444)
		(width 0.1143)
		(layer "In6.Cu")
		(net "GMI_CPU1_G0_CPU0_G2_TX_DN<7>")
	)
	(arc
		(start 365.920274 -226.664266)
		(mid 365.961823 -226.835688)
		(end 366.077246 -226.969066)
		(width 0.1143)
		(layer "In6.Cu")
		(net "GMI_CPU1_G0_CPU0_G2_TX_DN<7>")
	)
	(arc
		(start 104.949752 -235.878624)
		(mid 105.064428 -235.74529)
		(end 105.105708 -235.574332)
		(width 0.1143)
		(layer "In6.Cu")
		(net "GMI_CPU1_G0_CPU0_G2_TX_DN<7>")
	)
	(arc
		(start 105.575608 -229.90429)
		(mid 105.534642 -229.733884)
		(end 105.420668 -229.60076)
		(width 0.1143)
		(layer "In6.Cu")
		(net "GMI_CPU1_G0_CPU0_G2_TX_DN<7>")
	)
	(arc
		(start 366.390174 -235.574078)
		(mid 366.431429 -235.745049)
		(end 366.54613 -235.87837)
		(width 0.1143)
		(layer "In6.Cu")
		(net "GMI_CPU1_G0_CPU0_G2_TX_DN<7>")
	)
	(arc
		(start 106.83113 -224.538032)
		(mid 106.945059 -224.404885)
		(end 106.98607 -224.234502)
		(width 0.1143)
		(layer "In6.Cu")
		(net "GMI_CPU1_G0_CPU0_G2_TX_DN<7>")
	)
	(arc
		(start 366.146842 -233.4895)
		(mid 366.390169 -233.954066)
		(end 366.146842 -234.418632)
		(width 0.1143)
		(layer "In6.Cu")
		(net "GMI_CPU1_G0_CPU0_G2_TX_DN<7>")
	)
	(arc
		(start 106.331004 -225.36912)
		(mid 106.466599 -225.231355)
		(end 106.51617 -225.044508)
		(width 0.1143)
		(layer "In6.Cu")
		(net "GMI_CPU1_G0_CPU0_G2_TX_DN<7>")
	)
	(arc
		(start 367.330228 -237.19409)
		(mid 367.371777 -237.365512)
		(end 367.4872 -237.49889)
		(width 0.1143)
		(layer "In6.Cu")
		(net "GMI_CPU1_G0_CPU0_G2_TX_DN<7>")
	)
	(arc
		(start 365.676942 -226.1997)
		(mid 365.855755 -226.40205)
		(end 365.920274 -226.664266)
		(width 0.1143)
		(layer "In6.Cu")
		(net "GMI_CPU1_G0_CPU0_G2_TX_DN<7>")
	)
	(arc
		(start 103.70185 -239.541558)
		(mid 103.703638 -239.530109)
		(end 103.70566 -239.518698)
		(width 0.1143)
		(layer "In6.Cu")
		(net "GMI_CPU1_G0_CPU0_G2_TX_DN<7>")
	)
	(arc
		(start 105.105708 -230.71455)
		(mid 105.170944 -230.450959)
		(end 105.35158 -230.248206)
		(width 0.1143)
		(layer "In6.Cu")
		(net "GMI_CPU1_G0_CPU0_G2_TX_DN<7>")
	)
	(arc
		(start 108.239814 -222.108776)
		(mid 108.288746 -222.066688)
		(end 108.32973 -222.016828)
		(width 0.1143)
		(layer "In6.Cu")
		(net "GMI_CPU1_G0_CPU0_G2_TX_DN<7>")
	)
	(arc
		(start 107.925616 -222.61449)
		(mid 107.990131 -222.352271)
		(end 108.168948 -222.149924)
		(width 0.1143)
		(layer "In6.Cu")
		(net "GMI_CPU1_G0_CPU0_G2_TX_DN<7>")
	)
	(arc
		(start 105.418636 -226.96932)
		(mid 105.534063 -226.835944)
		(end 105.575608 -226.66452)
		(width 0.1143)
		(layer "In6.Cu")
		(net "GMI_CPU1_G0_CPU0_G2_TX_DN<7>")
	)
	(arc
		(start 363.166152 -222.016574)
		(mid 363.207135 -222.066436)
		(end 363.256068 -222.108522)
		(width 0.1143)
		(layer "In6.Cu")
		(net "GMI_CPU1_G0_CPU0_G2_TX_DN<7>")
	)
	(arc
		(start 365.920274 -229.904036)
		(mid 365.961823 -230.075458)
		(end 366.077246 -230.208836)
		(width 0.1143)
		(layer "In6.Cu")
		(net "GMI_CPU1_G0_CPU0_G2_TX_DN<7>")
	)
	(arc
		(start 366.146842 -235.109512)
		(mid 366.325655 -235.311862)
		(end 366.390174 -235.574078)
		(width 0.1143)
		(layer "In6.Cu")
		(net "GMI_CPU1_G0_CPU0_G2_TX_DN<7>")
	)
	(arc
		(start 104.165654 -237.194344)
		(mid 104.230169 -236.932125)
		(end 104.408986 -236.729778)
		(width 0.1143)
		(layer "In6.Cu")
		(net "GMI_CPU1_G0_CPU0_G2_TX_DN<7>")
	)
	(arc
		(start 103.939086 -238.468916)
		(mid 103.695759 -238.00435)
		(end 103.939086 -237.539784)
		(width 0.1143)
		(layer "In6.Cu")
		(net "GMI_CPU1_G0_CPU0_G2_TX_DN<7>")
	)
	(arc
		(start 104.44988 -236.705902)
		(mid 104.585961 -236.570054)
		(end 104.635808 -236.384338)
		(width 0.1143)
		(layer "In6.Cu")
		(net "GMI_CPU1_G0_CPU0_G2_TX_DN<7>")
	)
	(arc
		(start 105.34904 -232.798874)
		(mid 105.105713 -232.334308)
		(end 105.34904 -231.869742)
		(width 0.1143)
		(layer "In6.Cu")
		(net "GMI_CPU1_G0_CPU0_G2_TX_DN<7>")
	)
	(arc
		(start 366.077246 -232.83926)
		(mid 365.920269 -233.14406)
		(end 366.077246 -233.44886)
		(width 0.1143)
		(layer "In6.Cu")
		(net "GMI_CPU1_G0_CPU0_G2_TX_DN<7>")
	)
	(arc
		(start 366.146842 -231.869488)
		(mid 366.390169 -232.334054)
		(end 366.146842 -232.79862)
		(width 0.1143)
		(layer "In6.Cu")
		(net "GMI_CPU1_G0_CPU0_G2_TX_DN<7>")
	)
	(arc
		(start 366.075214 -231.220518)
		(mid 365.961285 -231.353665)
		(end 365.920274 -231.524048)
		(width 0.1143)
		(layer "In6.Cu")
		(net "GMI_CPU1_G0_CPU0_G2_TX_DN<7>")
	)
	(arc
		(start 366.075214 -229.600506)
		(mid 365.961285 -229.733653)
		(end 365.920274 -229.904036)
		(width 0.1143)
		(layer "In6.Cu")
		(net "GMI_CPU1_G0_CPU0_G2_TX_DN<7>")
	)
	(arc
		(start 366.614202 -235.91774)
		(mid 366.794854 -236.120485)
		(end 366.860074 -236.384084)
		(width 0.1143)
		(layer "In6.Cu")
		(net "GMI_CPU1_G0_CPU0_G2_TX_DN<7>")
	)
	(arc
		(start 365.17072 -225.371914)
		(mid 365.375058 -225.575595)
		(end 365.449866 -225.85426)
		(width 0.1143)
		(layer "In6.Cu")
		(net "GMI_CPU1_G0_CPU0_G2_TX_DN<7>")
	)
	(arc
		(start 363.099858 -221.80423)
		(mid 363.116908 -221.915421)
		(end 363.166152 -222.016574)
		(width 0.1143)
		(layer "In6.Cu")
		(net "GMI_CPU1_G0_CPU0_G2_TX_DN<7>")
	)
	(arc
		(start 363.326934 -222.14967)
		(mid 363.505747 -222.35202)
		(end 363.570266 -222.614236)
		(width 0.1143)
		(layer "In6.Cu")
		(net "GMI_CPU1_G0_CPU0_G2_TX_DN<7>")
	)
	(arc
		(start 105.34904 -229.559104)
		(mid 105.105713 -229.094538)
		(end 105.34904 -228.629972)
		(width 0.1143)
		(layer "In6.Cu")
		(net "GMI_CPU1_G0_CPU0_G2_TX_DN<7>")
	)
	(arc
		(start 105.575608 -231.524302)
		(mid 105.534642 -231.353896)
		(end 105.420668 -231.220772)
		(width 0.1143)
		(layer "In6.Cu")
		(net "GMI_CPU1_G0_CPU0_G2_TX_DN<7>")
	)
	(arc
		(start 107.300522 -223.728788)
		(mid 107.415198 -223.595454)
		(end 107.456478 -223.424496)
		(width 0.1143)
		(layer "In6.Cu")
		(net "GMI_CPU1_G0_CPU0_G2_TX_DN<7>")
	)
	(arc
		(start 364.039404 -223.424242)
		(mid 364.080659 -223.595213)
		(end 364.19536 -223.728534)
		(width 0.1143)
		(layer "In6.Cu")
		(net "GMI_CPU1_G0_CPU0_G2_TX_DN<7>")
	)
	(arc
		(start 106.98607 -224.234502)
		(mid 107.049862 -223.973543)
		(end 107.226862 -223.77146)
		(width 0.1143)
		(layer "In6.Cu")
		(net "GMI_CPU1_G0_CPU0_G2_TX_DN<7>")
	)
	(arc
		(start 366.077246 -234.459272)
		(mid 365.920269 -234.764072)
		(end 366.077246 -235.068872)
		(width 0.1143)
		(layer "In6.Cu")
		(net "GMI_CPU1_G0_CPU0_G2_TX_DN<7>")
	)
	(arc
		(start 106.046016 -225.854514)
		(mid 106.120763 -225.575814)
		(end 106.325162 -225.372168)
		(width 0.1143)
		(layer "In6.Cu")
		(net "GMI_CPU1_G0_CPU0_G2_TX_DN<7>")
	)
	(arc
		(start 367.086896 -236.729524)
		(mid 367.265709 -236.931874)
		(end 367.330228 -237.19409)
		(width 0.1143)
		(layer "In6.Cu")
		(net "GMI_CPU1_G0_CPU0_G2_TX_DN<7>")
	)
	(arc
		(start 104.008682 -239.119156)
		(mid 104.165659 -238.814356)
		(end 104.008682 -238.509556)
		(width 0.1143)
		(layer "In6.Cu")
		(net "GMI_CPU1_G0_CPU0_G2_TX_DN<7>")
	)
	(arc
		(start 105.418636 -230.20909)
		(mid 105.534063 -230.075714)
		(end 105.575608 -229.90429)
		(width 0.1143)
		(layer "In6.Cu")
		(net "GMI_CPU1_G0_CPU0_G2_TX_DN<7>")
	)
	(arc
		(start 364.979712 -225.044254)
		(mid 365.029252 -225.231118)
		(end 365.164878 -225.368866)
		(width 0.1143)
		(layer "In6.Cu")
		(net "GMI_CPU1_G0_CPU0_G2_TX_DN<7>")
	)
	(arc
		(start 363.570266 -222.614236)
		(mid 363.61202 -222.786179)
		(end 363.728 -222.919798)
		(width 0.1143)
		(layer "In6.Cu")
		(net "GMI_CPU1_G0_CPU0_G2_TX_DN<7>")
	)
	(arc
		(start 105.418636 -233.449114)
		(mid 105.575613 -233.144314)
		(end 105.418636 -232.839514)
		(width 0.1143)
		(layer "In6.Cu")
		(net "GMI_CPU1_G0_CPU0_G2_TX_DN<7>")
	)
	(arc
		(start 364.26902 -223.771206)
		(mid 364.446002 -223.973298)
		(end 364.509812 -224.234248)
		(width 0.1143)
		(layer "In6.Cu")
		(net "GMI_CPU1_G0_CPU0_G2_TX_DN<7>")
	)
	(arc
		(start 367.4872 -238.509302)
		(mid 367.330223 -238.814102)
		(end 367.4872 -239.118902)
		(width 0.1143)
		(layer "In6.Cu")
		(net "GMI_CPU1_G0_CPU0_G2_TX_DN<7>")
	)
	(arc
		(start 366.146842 -227.009706)
		(mid 366.390169 -227.474272)
		(end 366.146842 -227.938838)
		(width 0.1143)
		(layer "In6.Cu")
		(net "GMI_CPU1_G0_CPU0_G2_TX_DN<7>")
	)
	(arc
		(start 105.105708 -235.574332)
		(mid 105.170223 -235.312113)
		(end 105.34904 -235.109766)
		(width 0.1143)
		(layer "In6.Cu")
		(net "GMI_CPU1_G0_CPU0_G2_TX_DN<7>")
	)
	(arc
		(start 107.456478 -223.424496)
		(mid 107.521645 -223.160972)
		(end 107.702096 -222.958152)
		(width 0.1143)
		(layer "In6.Cu")
		(net "GMI_CPU1_G0_CPU0_G2_TX_DN<7>")
	)
	(arc
		(start 108.32973 -222.016828)
		(mid 108.37905 -221.915699)
		(end 108.396024 -221.804484)
		(width 0.1143)
		(layer "In6.Cu")
		(net "GMI_CPU1_G0_CPU0_G2_TX_DN<7>")
	)
	(arc
		(start 104.635808 -236.384338)
		(mid 104.701044 -236.120747)
		(end 104.88168 -235.917994)
		(width 0.1143)
		(layer "In6.Cu")
		(net "GMI_CPU1_G0_CPU0_G2_TX_DN<7>")
	)
	(arc
		(start 105.889806 -226.158552)
		(mid 106.004649 -226.025404)
		(end 106.046016 -225.854514)
		(width 0.1143)
		(layer "In6.Cu")
		(net "GMI_CPU1_G0_CPU0_G2_TX_DN<7>")
	)
	(arc
		(start 363.793786 -222.957898)
		(mid 363.974282 -223.160694)
		(end 364.039404 -223.424242)
		(width 0.1143)
		(layer "In6.Cu")
		(net "GMI_CPU1_G0_CPU0_G2_TX_DN<7>")
	)
	(arc
		(start 364.699804 -224.557844)
		(mid 364.90473 -224.763658)
		(end 364.979712 -225.044254)
		(width 0.1143)
		(layer "In6.Cu")
		(net "GMI_CPU1_G0_CPU0_G2_TX_DN<7>")
	)
	(arc
		(start 365.449866 -225.85426)
		(mid 365.491264 -226.025134)
		(end 365.606076 -226.158298)
		(width 0.1143)
		(layer "In6.Cu")
		(net "GMI_CPU1_G0_CPU0_G2_TX_DN<7>")
	)
	(arc
		(start 105.34904 -231.179116)
		(mid 105.170227 -230.976766)
		(end 105.105708 -230.71455)
		(width 0.1143)
		(layer "In6.Cu")
		(net "GMI_CPU1_G0_CPU0_G2_TX_DN<7>")
	)
	(arc
		(start 106.51617 -225.044508)
		(mid 106.59114 -224.763906)
		(end 106.796078 -224.558098)
		(width 0.1143)
		(layer "In6.Cu")
		(net "GMI_CPU1_G0_CPU0_G2_TX_DN<7>")
	)
	(arc
		(start 366.077246 -227.979478)
		(mid 365.920269 -228.284278)
		(end 366.077246 -228.589078)
		(width 0.1143)
		(layer "In6.Cu")
		(net "GMI_CPU1_G0_CPU0_G2_TX_DN<7>")
	)
	(arc
		(start 104.008682 -237.499144)
		(mid 104.124109 -237.365768)
		(end 104.165654 -237.194344)
		(width 0.1143)
		(layer "In6.Cu")
		(net "GMI_CPU1_G0_CPU0_G2_TX_DN<7>")
	)
	(arc
		(start 105.575608 -226.66452)
		(mid 105.640123 -226.402301)
		(end 105.81894 -226.199954)
		(width 0.1143)
		(layer "In6.Cu")
		(net "GMI_CPU1_G0_CPU0_G2_TX_DN<7>")
	)
	(arc
		(start 367.790222 -239.518444)
		(mid 367.792245 -239.529854)
		(end 367.794032 -239.541304)
		(width 0.1143)
		(layer "In6.Cu")
		(net "GMI_CPU1_G0_CPU0_G2_TX_DN<7>")
	)
	(arc
		(start 364.509812 -224.234248)
		(mid 364.550778 -224.404654)
		(end 364.664752 -224.537778)
		(width 0.1143)
		(layer "In6.Cu")
		(net "GMI_CPU1_G0_CPU0_G2_TX_DN<7>")
	)
	(arc
		(start 105.418636 -235.069126)
		(mid 105.575613 -234.764326)
		(end 105.418636 -234.459526)
		(width 0.1143)
		(layer "In6.Cu")
		(net "GMI_CPU1_G0_CPU0_G2_TX_DN<7>")
	)
	(arc
		(start 365.920274 -231.524048)
		(mid 365.961823 -231.69547)
		(end 366.077246 -231.828848)
		(width 0.1143)
		(layer "In6.Cu")
		(net "GMI_CPU1_G0_CPU0_G2_TX_DN<7>")
	)
	(arc
		(start 366.146842 -228.629718)
		(mid 366.390169 -229.094284)
		(end 366.146842 -229.55885)
		(width 0.1143)
		(layer "In6.Cu")
		(net "GMI_CPU1_G0_CPU0_G2_TX_DN<7>")
	)
	(arc
		(start 107.767882 -222.920052)
		(mid 107.883835 -222.786419)
		(end 107.925616 -222.61449)
		(width 0.1143)
		(layer "In6.Cu")
		(net "GMI_CPU1_G0_CPU0_G2_TX_DN<7>")
	)
	(arc
		(start 105.418636 -228.589332)
		(mid 105.575613 -228.284532)
		(end 105.418636 -227.979732)
		(width 0.1143)
		(layer "In6.Cu")
		(net "GMI_CPU1_G0_CPU0_G2_TX_DN<7>")
	)
	(arc
		(start 105.418636 -231.829102)
		(mid 105.534063 -231.695726)
		(end 105.575608 -231.524302)
		(width 0.1143)
		(layer "In6.Cu")
		(net "GMI_CPU1_G0_CPU0_G2_TX_DN<7>")
	)
	(arc
		(start 105.34904 -234.418886)
		(mid 105.105713 -233.95432)
		(end 105.34904 -233.489754)
		(width 0.1143)
		(layer "In6.Cu")
		(net "GMI_CPU1_G0_CPU0_G2_TX_DN<7>")
	)
	(arc
		(start 103.70566 -239.518698)
		(mid 103.787093 -239.3163)
		(end 103.939086 -239.159796)
		(width 0.1143)
		(layer "In6.Cu")
		(net "GMI_CPU1_G0_CPU0_G2_TX_DN<7>")
	)
	(arc
		(start 366.144302 -230.247952)
		(mid 366.324954 -230.450697)
		(end 366.390174 -230.714296)
		(width 0.1143)
		(layer "In6.Cu")
		(net "GMI_CPU1_G0_CPU0_G2_TX_DN<7>")
	)
	(segment
		(start 367.707926 -241.510058)
		(end 368.174778 -241.24412)
		(width 0.12954)
		(layer "F.Cu")
		(net "GMI_CPU1_G0_CPU0_G2_TX_DN<6>")
	)
	(segment
		(start 103.787956 -241.510312)
		(end 103.321104 -241.244374)
		(width 0.12954)
		(layer "F.Cu")
		(net "GMI_CPU1_G0_CPU0_G2_TX_DN<6>")
	)
	(segment
		(start 367.04778 -234.441492)
		(end 367.086896 -234.418632)
		(width 0.1143)
		(layer "In6.Cu")
		(net "GMI_CPU1_G0_CPU0_G2_TX_DN<6>")
	)
	(segment
		(start 102.999032 -238.468916)
		(end 103.038148 -238.491776)
		(width 0.1143)
		(layer "In6.Cu")
		(net "GMI_CPU1_G0_CPU0_G2_TX_DN<6>")
	)
	(segment
		(start 364.040674 -221.325694)
		(end 364.040674 -221.13875)
		(width 0.1143)
		(layer "In6.Cu")
		(net "GMI_CPU1_G0_CPU0_G2_TX_DN<6>")
	)
	(segment
		(start 367.057686 -229.575868)
		(end 367.086896 -229.55885)
		(width 0.1143)
		(layer "In6.Cu")
		(net "GMI_CPU1_G0_CPU0_G2_TX_DN<6>")
	)
	(segment
		(start 367.014252 -229.601268)
		(end 367.057686 -229.575868)
		(width 0.1143)
		(layer "In6.Cu")
		(net "GMI_CPU1_G0_CPU0_G2_TX_DN<6>")
	)
	(segment
		(start 104.635808 -231.525064)
		(end 104.630982 -231.56418)
		(width 0.1143)
		(layer "In6.Cu")
		(net "GMI_CPU1_G0_CPU0_G2_TX_DN<6>")
	)
	(segment
		(start 105.887774 -224.53981)
		(end 105.82021 -224.578926)
		(width 0.1143)
		(layer "In6.Cu")
		(net "GMI_CPU1_G0_CPU0_G2_TX_DN<6>")
	)
	(segment
		(start 103.068628 -237.499144)
		(end 103.038148 -237.516924)
		(width 0.1143)
		(layer "In6.Cu")
		(net "GMI_CPU1_G0_CPU0_G2_TX_DN<6>")
	)
	(segment
		(start 106.765852 -222.955612)
		(end 106.76128 -222.958152)
		(width 0.1143)
		(layer "In6.Cu")
		(net "GMI_CPU1_G0_CPU0_G2_TX_DN<6>")
	)
	(segment
		(start 115.76558 -209.561938)
		(end 115.418616 -209.82813)
		(width 0.14224)
		(layer "In6.Cu")
		(net "GMI_CPU1_G0_CPU0_G2_TX_DN<6>")
	)
	(segment
		(start 107.29976 -222.108776)
		(end 107.299506 -222.108776)
		(width 0.1143)
		(layer "In6.Cu")
		(net "GMI_CPU1_G0_CPU0_G2_TX_DN<6>")
	)
	(segment
		(start 367.01603 -233.448352)
		(end 366.997996 -233.435398)
		(width 0.1143)
		(layer "In6.Cu")
		(net "GMI_CPU1_G0_CPU0_G2_TX_DN<6>")
	)
	(segment
		(start 107.455716 -221.326456)
		(end 107.455716 -221.804484)
		(width 0.1143)
		(layer "In6.Cu")
		(net "GMI_CPU1_G0_CPU0_G2_TX_DN<6>")
	)
	(segment
		(start 364.51032 -222.614236)
		(end 364.51032 -222.569278)
		(width 0.1143)
		(layer "In6.Cu")
		(net "GMI_CPU1_G0_CPU0_G2_TX_DN<6>")
	)
	(segment
		(start 367.087404 -230.24973)
		(end 367.026952 -230.214424)
		(width 0.1143)
		(layer "In6.Cu")
		(net "GMI_CPU1_G0_CPU0_G2_TX_DN<6>")
	)
	(segment
		(start 367.987834 -236.706664)
		(end 367.987072 -236.706156)
		(width 0.1143)
		(layer "In6.Cu")
		(net "GMI_CPU1_G0_CPU0_G2_TX_DN<6>")
	)
	(segment
		(start 359.684574 -213.863174)
		(end 355.226874 -210.306158)
		(width 0.14224)
		(layer "In6.Cu")
		(net "GMI_CPU1_G0_CPU0_G2_TX_DN<6>")
	)
	(segment
		(start 367.956084 -240.939828)
		(end 367.985802 -240.92281)
		(width 0.1143)
		(layer "In6.Cu")
		(net "GMI_CPU1_G0_CPU0_G2_TX_DN<6>")
	)
	(segment
		(start 368.174778 -241.24412)
		(end 367.876836 -241.24412)
		(width 0.1143)
		(layer "In6.Cu")
		(net "GMI_CPU1_G0_CPU0_G2_TX_DN<6>")
	)
	(segment
		(start 103.508048 -236.706918)
		(end 103.468932 -236.729778)
		(width 0.1143)
		(layer "In6.Cu")
		(net "GMI_CPU1_G0_CPU0_G2_TX_DN<6>")
	)
	(segment
		(start 122.341894 -204.515466)
		(end 115.76558 -209.561684)
		(width 0.14224)
		(layer "In6.Cu")
		(net "GMI_CPU1_G0_CPU0_G2_TX_DN<6>")
	)
	(segment
		(start 368.02695 -236.729524)
		(end 367.990374 -236.708188)
		(width 0.1143)
		(layer "In6.Cu")
		(net "GMI_CPU1_G0_CPU0_G2_TX_DN<6>")
	)
	(segment
		(start 367.086896 -227.009452)
		(end 367.024666 -226.973384)
		(width 0.1143)
		(layer "In6.Cu")
		(net "GMI_CPU1_G0_CPU0_G2_TX_DN<6>")
	)
	(segment
		(start 107.455208 -221.139004)
		(end 107.455208 -221.325948)
		(width 0.1143)
		(layer "In6.Cu")
		(net "GMI_CPU1_G0_CPU0_G2_TX_DN<6>")
	)
	(segment
		(start 104.448102 -231.846882)
		(end 104.408986 -231.869742)
		(width 0.1143)
		(layer "In6.Cu")
		(net "GMI_CPU1_G0_CPU0_G2_TX_DN<6>")
	)
	(segment
		(start 104.918002 -226.177094)
		(end 104.88168 -226.198176)
		(width 0.1143)
		(layer "In6.Cu")
		(net "GMI_CPU1_G0_CPU0_G2_TX_DN<6>")
	)
	(segment
		(start 367.985802 -236.705394)
		(end 367.956084 -236.688376)
		(width 0.1143)
		(layer "In6.Cu")
		(net "GMI_CPU1_G0_CPU0_G2_TX_DN<6>")
	)
	(segment
		(start 103.508048 -240.921794)
		(end 103.50881 -240.922302)
		(width 0.1143)
		(layer "In6.Cu")
		(net "GMI_CPU1_G0_CPU0_G2_TX_DN<6>")
	)
	(segment
		(start 103.619046 -241.244374)
		(end 103.321104 -241.244374)
		(width 0.1143)
		(layer "In6.Cu")
		(net "GMI_CPU1_G0_CPU0_G2_TX_DN<6>")
	)
	(segment
		(start 104.949752 -226.158806)
		(end 104.918002 -226.177094)
		(width 0.1143)
		(layer "In6.Cu")
		(net "GMI_CPU1_G0_CPU0_G2_TX_DN<6>")
	)
	(segment
		(start 368.427254 -240.129314)
		(end 368.49685 -240.088674)
		(width 0.1143)
		(layer "In6.Cu")
		(net "GMI_CPU1_G0_CPU0_G2_TX_DN<6>")
	)
	(segment
		(start 103.688896 -241.174524)
		(end 103.619046 -241.244374)
		(width 0.1143)
		(layer "In6.Cu")
		(net "GMI_CPU1_G0_CPU0_G2_TX_DN<6>")
	)
	(segment
		(start 115.76558 -209.561684)
		(end 115.76558 -209.561938)
		(width 0.14224)
		(layer "In6.Cu")
		(net "GMI_CPU1_G0_CPU0_G2_TX_DN<6>")
	)
	(segment
		(start 103.468932 -240.898934)
		(end 103.505508 -240.92027)
		(width 0.1143)
		(layer "In6.Cu")
		(net "GMI_CPU1_G0_CPU0_G2_TX_DN<6>")
	)
	(segment
		(start 368.49685 -239.159542)
		(end 368.427254 -239.118902)
		(width 0.1143)
		(layer "In6.Cu")
		(net "GMI_CPU1_G0_CPU0_G2_TX_DN<6>")
	)
	(segment
		(start 102.999032 -240.088928)
		(end 103.038148 -240.111788)
		(width 0.1143)
		(layer "In6.Cu")
		(net "GMI_CPU1_G0_CPU0_G2_TX_DN<6>")
	)
	(segment
		(start 104.44861 -231.846882)
		(end 104.448102 -231.846882)
		(width 0.1143)
		(layer "In6.Cu")
		(net "GMI_CPU1_G0_CPU0_G2_TX_DN<6>")
	)
	(segment
		(start 367.876836 -241.24412)
		(end 367.806986 -241.17427)
		(width 0.1143)
		(layer "In6.Cu")
		(net "GMI_CPU1_G0_CPU0_G2_TX_DN<6>")
	)
	(segment
		(start 104.506776 -230.181658)
		(end 104.46893 -230.214678)
		(width 0.1143)
		(layer "In6.Cu")
		(net "GMI_CPU1_G0_CPU0_G2_TX_DN<6>")
	)
	(segment
		(start 366.867948 -226.713796)
		(end 366.862106 -226.67341)
		(width 0.1143)
		(layer "In6.Cu")
		(net "GMI_CPU1_G0_CPU0_G2_TX_DN<6>")
	)
	(segment
		(start 104.408986 -227.939092)
		(end 104.479852 -227.980494)
		(width 0.1143)
		(layer "In6.Cu")
		(net "GMI_CPU1_G0_CPU0_G2_TX_DN<6>")
	)
	(segment
		(start 103.539798 -236.68863)
		(end 103.51008 -236.705648)
		(width 0.1143)
		(layer "In6.Cu")
		(net "GMI_CPU1_G0_CPU0_G2_TX_DN<6>")
	)
	(segment
		(start 104.499664 -235.054394)
		(end 104.479852 -235.068618)
		(width 0.1143)
		(layer "In6.Cu")
		(net "GMI_CPU1_G0_CPU0_G2_TX_DN<6>")
	)
	(segment
		(start 104.471216 -226.973638)
		(end 104.408986 -227.009706)
		(width 0.1143)
		(layer "In6.Cu")
		(net "GMI_CPU1_G0_CPU0_G2_TX_DN<6>")
	)
	(segment
		(start 367.990374 -240.920016)
		(end 368.02695 -240.89868)
		(width 0.1143)
		(layer "In6.Cu")
		(net "GMI_CPU1_G0_CPU0_G2_TX_DN<6>")
	)
	(segment
		(start 367.98885 -236.707172)
		(end 367.987834 -236.706664)
		(width 0.1143)
		(layer "In6.Cu")
		(net "GMI_CPU1_G0_CPU0_G2_TX_DN<6>")
	)
	(segment
		(start 103.038148 -238.491776)
		(end 103.068628 -238.509556)
		(width 0.1143)
		(layer "In6.Cu")
		(net "GMI_CPU1_G0_CPU0_G2_TX_DN<6>")
	)
	(segment
		(start 104.479852 -228.58857)
		(end 104.408986 -228.629972)
		(width 0.1143)
		(layer "In6.Cu")
		(net "GMI_CPU1_G0_CPU0_G2_TX_DN<6>")
	)
	(segment
		(start 104.497886 -233.435652)
		(end 104.479852 -233.448606)
		(width 0.1143)
		(layer "In6.Cu")
		(net "GMI_CPU1_G0_CPU0_G2_TX_DN<6>")
	)
	(segment
		(start 104.479852 -232.840022)
		(end 104.497886 -232.852976)
		(width 0.1143)
		(layer "In6.Cu")
		(net "GMI_CPU1_G0_CPU0_G2_TX_DN<6>")
	)
	(segment
		(start 104.479852 -235.068618)
		(end 104.408986 -235.109766)
		(width 0.1143)
		(layer "In6.Cu")
		(net "GMI_CPU1_G0_CPU0_G2_TX_DN<6>")
	)
	(segment
		(start 367.026952 -230.214424)
		(end 367.002568 -230.193088)
		(width 0.1143)
		(layer "In6.Cu")
		(net "GMI_CPU1_G0_CPU0_G2_TX_DN<6>")
	)
	(segment
		(start 104.479852 -233.448606)
		(end 104.448102 -233.466894)
		(width 0.1143)
		(layer "In6.Cu")
		(net "GMI_CPU1_G0_CPU0_G2_TX_DN<6>")
	)
	(segment
		(start 104.408986 -232.798874)
		(end 104.479852 -232.840022)
		(width 0.1143)
		(layer "In6.Cu")
		(net "GMI_CPU1_G0_CPU0_G2_TX_DN<6>")
	)
	(segment
		(start 108.793534 -216.452958)
		(end 107.409488 -219.794582)
		(width 0.14224)
		(layer "In6.Cu")
		(net "GMI_CPU1_G0_CPU0_G2_TX_DN<6>")
	)
	(segment
		(start 104.47147 -231.83342)
		(end 104.44861 -231.846882)
		(width 0.1143)
		(layer "In6.Cu")
		(net "GMI_CPU1_G0_CPU0_G2_TX_DN<6>")
	)
	(segment
		(start 103.50881 -236.70641)
		(end 103.508048 -236.706918)
		(width 0.1143)
		(layer "In6.Cu")
		(net "GMI_CPU1_G0_CPU0_G2_TX_DN<6>")
	)
	(segment
		(start 106.829352 -222.918528)
		(end 106.765852 -222.955612)
		(width 0.1143)
		(layer "In6.Cu")
		(net "GMI_CPU1_G0_CPU0_G2_TX_DN<6>")
	)
	(segment
		(start 367.047272 -231.846628)
		(end 367.021364 -231.831388)
		(width 0.1143)
		(layer "In6.Cu")
		(net "GMI_CPU1_G0_CPU0_G2_TX_DN<6>")
	)
	(segment
		(start 103.978202 -235.896912)
		(end 103.939086 -235.919772)
		(width 0.1143)
		(layer "In6.Cu")
		(net "GMI_CPU1_G0_CPU0_G2_TX_DN<6>")
	)
	(segment
		(start 364.040166 -221.326202)
		(end 364.040674 -221.325694)
		(width 0.1143)
		(layer "In6.Cu")
		(net "GMI_CPU1_G0_CPU0_G2_TX_DN<6>")
	)
	(segment
		(start 306.755292 -180.429408)
		(end 302.90262 -180.429408)
		(width 0.14224)
		(layer "In6.Cu")
		(net "GMI_CPU1_G0_CPU0_G2_TX_DN<6>")
	)
	(segment
		(start 366.614202 -226.197922)
		(end 366.57788 -226.17684)
		(width 0.1143)
		(layer "In6.Cu")
		(net "GMI_CPU1_G0_CPU0_G2_TX_DN<6>")
	)
	(segment
		(start 167.550338 -179.639976)
		(end 163.616894 -180.681884)
		(width 0.14224)
		(layer "In6.Cu")
		(net "GMI_CPU1_G0_CPU0_G2_TX_DN<6>")
	)
	(segment
		(start 368.49685 -237.53953)
		(end 368.427254 -237.49889)
		(width 0.1143)
		(layer "In6.Cu")
		(net "GMI_CPU1_G0_CPU0_G2_TX_DN<6>")
	)
	(segment
		(start 367.01603 -235.068364)
		(end 366.996218 -235.05414)
		(width 0.1143)
		(layer "In6.Cu")
		(net "GMI_CPU1_G0_CPU0_G2_TX_DN<6>")
	)
	(segment
		(start 364.270036 -222.151194)
		(end 364.196376 -222.108522)
		(width 0.1143)
		(layer "In6.Cu")
		(net "GMI_CPU1_G0_CPU0_G2_TX_DN<6>")
	)
	(segment
		(start 367.048796 -231.847136)
		(end 367.04778 -231.846628)
		(width 0.1143)
		(layer "In6.Cu")
		(net "GMI_CPU1_G0_CPU0_G2_TX_DN<6>")
	)
	(segment
		(start 366.146842 -225.389694)
		(end 366.077246 -225.349054)
		(width 0.1143)
		(layer "In6.Cu")
		(net "GMI_CPU1_G0_CPU0_G2_TX_DN<6>")
	)
	(segment
		(start 308.747414 -180.97627)
		(end 306.755292 -180.429408)
		(width 0.14224)
		(layer "In6.Cu")
		(net "GMI_CPU1_G0_CPU0_G2_TX_DN<6>")
	)
	(segment
		(start 367.05032 -231.848152)
		(end 367.048796 -231.847136)
		(width 0.1143)
		(layer "In6.Cu")
		(net "GMI_CPU1_G0_CPU0_G2_TX_DN<6>")
	)
	(segment
		(start 103.50881 -240.922302)
		(end 103.539798 -240.940082)
		(width 0.1143)
		(layer "In6.Cu")
		(net "GMI_CPU1_G0_CPU0_G2_TX_DN<6>")
	)
	(segment
		(start 367.086896 -235.109512)
		(end 367.01603 -235.068364)
		(width 0.1143)
		(layer "In6.Cu")
		(net "GMI_CPU1_G0_CPU0_G2_TX_DN<6>")
	)
	(segment
		(start 366.867186 -231.574594)
		(end 366.860074 -231.524048)
		(width 0.1143)
		(layer "In6.Cu")
		(net "GMI_CPU1_G0_CPU0_G2_TX_DN<6>")
	)
	(segment
		(start 104.448102 -233.466894)
		(end 104.408986 -233.489754)
		(width 0.1143)
		(layer "In6.Cu")
		(net "GMI_CPU1_G0_CPU0_G2_TX_DN<6>")
	)
	(segment
		(start 364.196376 -222.108522)
		(end 364.196122 -222.108522)
		(width 0.1143)
		(layer "In6.Cu")
		(net "GMI_CPU1_G0_CPU0_G2_TX_DN<6>")
	)
	(segment
		(start 367.01603 -228.588316)
		(end 366.996726 -228.5746)
		(width 0.1143)
		(layer "In6.Cu")
		(net "GMI_CPU1_G0_CPU0_G2_TX_DN<6>")
	)
	(segment
		(start 104.479852 -227.980494)
		(end 104.499156 -227.99421)
		(width 0.1143)
		(layer "In6.Cu")
		(net "GMI_CPU1_G0_CPU0_G2_TX_DN<6>")
	)
	(segment
		(start 367.024666 -226.973384)
		(end 366.993932 -226.94646)
		(width 0.1143)
		(layer "In6.Cu")
		(net "GMI_CPU1_G0_CPU0_G2_TX_DN<6>")
	)
	(segment
		(start 104.008682 -235.879132)
		(end 103.978202 -235.896912)
		(width 0.1143)
		(layer "In6.Cu")
		(net "GMI_CPU1_G0_CPU0_G2_TX_DN<6>")
	)
	(segment
		(start 104.502712 -226.945952)
		(end 104.471216 -226.973638)
		(width 0.1143)
		(layer "In6.Cu")
		(net "GMI_CPU1_G0_CPU0_G2_TX_DN<6>")
	)
	(segment
		(start 115.418616 -209.82813)
		(end 108.793534 -216.452958)
		(width 0.14224)
		(layer "In6.Cu")
		(net "GMI_CPU1_G0_CPU0_G2_TX_DN<6>")
	)
	(segment
		(start 104.408986 -229.559104)
		(end 104.48163 -229.601522)
		(width 0.1143)
		(layer "In6.Cu")
		(net "GMI_CPU1_G0_CPU0_G2_TX_DN<6>")
	)
	(segment
		(start 163.616894 -180.681884)
		(end 122.341894 -204.515466)
		(width 0.14224)
		(layer "In6.Cu")
		(net "GMI_CPU1_G0_CPU0_G2_TX_DN<6>")
	)
	(segment
		(start 366.996726 -227.993956)
		(end 367.01603 -227.98024)
		(width 0.1143)
		(layer "In6.Cu")
		(net "GMI_CPU1_G0_CPU0_G2_TX_DN<6>")
	)
	(segment
		(start 367.987072 -240.922048)
		(end 367.987834 -240.92154)
		(width 0.1143)
		(layer "In6.Cu")
		(net "GMI_CPU1_G0_CPU0_G2_TX_DN<6>")
	)
	(segment
		(start 366.996218 -234.474004)
		(end 367.01603 -234.45978)
		(width 0.1143)
		(layer "In6.Cu")
		(net "GMI_CPU1_G0_CPU0_G2_TX_DN<6>")
	)
	(segment
		(start 319.531492 -187.844176)
		(end 317.351918 -186.085988)
		(width 0.14224)
		(layer "In6.Cu")
		(net "GMI_CPU1_G0_CPU0_G2_TX_DN<6>")
	)
	(segment
		(start 364.73003 -222.955358)
		(end 364.66653 -222.918274)
		(width 0.1143)
		(layer "In6.Cu")
		(net "GMI_CPU1_G0_CPU0_G2_TX_DN<6>")
	)
	(segment
		(start 363.354366 -217.532712)
		(end 359.684574 -213.863174)
		(width 0.14224)
		(layer "In6.Cu")
		(net "GMI_CPU1_G0_CPU0_G2_TX_DN<6>")
	)
	(segment
		(start 103.505508 -240.92027)
		(end 103.507032 -240.921286)
		(width 0.1143)
		(layer "In6.Cu")
		(net "GMI_CPU1_G0_CPU0_G2_TX_DN<6>")
	)
	(segment
		(start 104.493568 -231.811322)
		(end 104.47147 -231.83342)
		(width 0.1143)
		(layer "In6.Cu")
		(net "GMI_CPU1_G0_CPU0_G2_TX_DN<6>")
	)
	(segment
		(start 368.427254 -238.509302)
		(end 368.49685 -238.468662)
		(width 0.1143)
		(layer "In6.Cu")
		(net "GMI_CPU1_G0_CPU0_G2_TX_DN<6>")
	)
	(segment
		(start 104.633776 -226.673664)
		(end 104.627934 -226.71532)
		(width 0.1143)
		(layer "In6.Cu")
		(net "GMI_CPU1_G0_CPU0_G2_TX_DN<6>")
	)
	(segment
		(start 302.90262 -180.429408)
		(end 167.550338 -179.639976)
		(width 0.14224)
		(layer "In6.Cu")
		(net "GMI_CPU1_G0_CPU0_G2_TX_DN<6>")
	)
	(segment
		(start 104.479852 -234.460034)
		(end 104.499664 -234.474258)
		(width 0.1143)
		(layer "In6.Cu")
		(net "GMI_CPU1_G0_CPU0_G2_TX_DN<6>")
	)
	(segment
		(start 355.226874 -210.306158)
		(end 319.531492 -187.844176)
		(width 0.14224)
		(layer "In6.Cu")
		(net "GMI_CPU1_G0_CPU0_G2_TX_DN<6>")
	)
	(segment
		(start 364.040674 -221.13875)
		(end 364.086394 -221.09303)
		(width 0.1143)
		(layer "In6.Cu")
		(net "GMI_CPU1_G0_CPU0_G2_TX_DN<6>")
	)
	(segment
		(start 107.299506 -222.108776)
		(end 107.225846 -222.151448)
		(width 0.1143)
		(layer "In6.Cu")
		(net "GMI_CPU1_G0_CPU0_G2_TX_DN<6>")
	)
	(segment
		(start 364.734602 -222.957898)
		(end 364.73003 -222.955358)
		(width 0.1143)
		(layer "In6.Cu")
		(net "GMI_CPU1_G0_CPU0_G2_TX_DN<6>")
	)
	(segment
		(start 367.556796 -235.919518)
		(end 367.4872 -235.878878)
		(width 0.1143)
		(layer "In6.Cu")
		(net "GMI_CPU1_G0_CPU0_G2_TX_DN<6>")
	)
	(segment
		(start 367.987072 -236.706156)
		(end 367.985802 -236.705394)
		(width 0.1143)
		(layer "In6.Cu")
		(net "GMI_CPU1_G0_CPU0_G2_TX_DN<6>")
	)
	(segment
		(start 103.51008 -236.705648)
		(end 103.50881 -236.70641)
		(width 0.1143)
		(layer "In6.Cu")
		(net "GMI_CPU1_G0_CPU0_G2_TX_DN<6>")
	)
	(segment
		(start 107.455208 -221.325948)
		(end 107.455716 -221.326456)
		(width 0.1143)
		(layer "In6.Cu")
		(net "GMI_CPU1_G0_CPU0_G2_TX_DN<6>")
	)
	(segment
		(start 364.314486 -222.18396)
		(end 364.270036 -222.151194)
		(width 0.1143)
		(layer "In6.Cu")
		(net "GMI_CPU1_G0_CPU0_G2_TX_DN<6>")
	)
	(segment
		(start 103.038148 -237.516924)
		(end 102.999032 -237.539784)
		(width 0.1143)
		(layer "In6.Cu")
		(net "GMI_CPU1_G0_CPU0_G2_TX_DN<6>")
	)
	(segment
		(start 107.409488 -221.093284)
		(end 107.455208 -221.139004)
		(width 0.1143)
		(layer "In6.Cu")
		(net "GMI_CPU1_G0_CPU0_G2_TX_DN<6>")
	)
	(segment
		(start 104.448102 -234.441746)
		(end 104.479852 -234.460034)
		(width 0.1143)
		(layer "In6.Cu")
		(net "GMI_CPU1_G0_CPU0_G2_TX_DN<6>")
	)
	(segment
		(start 364.040166 -221.80423)
		(end 364.040166 -221.326202)
		(width 0.1143)
		(layer "In6.Cu")
		(net "GMI_CPU1_G0_CPU0_G2_TX_DN<6>")
	)
	(segment
		(start 365.675672 -224.578672)
		(end 365.608108 -224.539556)
		(width 0.1143)
		(layer "In6.Cu")
		(net "GMI_CPU1_G0_CPU0_G2_TX_DN<6>")
	)
	(segment
		(start 104.408986 -231.179116)
		(end 104.448102 -231.201976)
		(width 0.1143)
		(layer "In6.Cu")
		(net "GMI_CPU1_G0_CPU0_G2_TX_DN<6>")
	)
	(segment
		(start 364.086394 -221.09303)
		(end 364.086394 -219.29979)
		(width 0.14224)
		(layer "In6.Cu")
		(net "GMI_CPU1_G0_CPU0_G2_TX_DN<6>")
	)
	(segment
		(start 107.225846 -222.151448)
		(end 107.181396 -222.184214)
		(width 0.1143)
		(layer "In6.Cu")
		(net "GMI_CPU1_G0_CPU0_G2_TX_DN<6>")
	)
	(segment
		(start 317.351918 -186.085988)
		(end 308.747414 -180.97627)
		(width 0.14224)
		(layer "In6.Cu")
		(net "GMI_CPU1_G0_CPU0_G2_TX_DN<6>")
	)
	(segment
		(start 107.409488 -219.794582)
		(end 107.409488 -221.064836)
		(width 0.14224)
		(layer "In6.Cu")
		(net "GMI_CPU1_G0_CPU0_G2_TX_DN<6>")
	)
	(segment
		(start 367.04778 -233.46664)
		(end 367.01603 -233.448352)
		(width 0.1143)
		(layer "In6.Cu")
		(net "GMI_CPU1_G0_CPU0_G2_TX_DN<6>")
	)
	(segment
		(start 367.086896 -228.629718)
		(end 367.01603 -228.588316)
		(width 0.1143)
		(layer "In6.Cu")
		(net "GMI_CPU1_G0_CPU0_G2_TX_DN<6>")
	)
	(segment
		(start 366.86363 -229.926134)
		(end 366.860328 -229.893876)
		(width 0.1143)
		(layer "In6.Cu")
		(net "GMI_CPU1_G0_CPU0_G2_TX_DN<6>")
	)
	(segment
		(start 104.448102 -231.201976)
		(end 104.48163 -231.221534)
		(width 0.1143)
		(layer "In6.Cu")
		(net "GMI_CPU1_G0_CPU0_G2_TX_DN<6>")
	)
	(segment
		(start 367.04778 -231.846628)
		(end 367.047272 -231.846628)
		(width 0.1143)
		(layer "In6.Cu")
		(net "GMI_CPU1_G0_CPU0_G2_TX_DN<6>")
	)
	(segment
		(start 105.418636 -225.349308)
		(end 105.388156 -225.367088)
		(width 0.1143)
		(layer "In6.Cu")
		(net "GMI_CPU1_G0_CPU0_G2_TX_DN<6>")
	)
	(segment
		(start 364.086394 -219.29979)
		(end 363.354366 -217.532712)
		(width 0.14224)
		(layer "In6.Cu")
		(net "GMI_CPU1_G0_CPU0_G2_TX_DN<6>")
	)
	(segment
		(start 103.507032 -240.921286)
		(end 103.508048 -240.921794)
		(width 0.1143)
		(layer "In6.Cu")
		(net "GMI_CPU1_G0_CPU0_G2_TX_DN<6>")
	)
	(segment
		(start 367.086896 -233.4895)
		(end 367.04778 -233.46664)
		(width 0.1143)
		(layer "In6.Cu")
		(net "GMI_CPU1_G0_CPU0_G2_TX_DN<6>")
	)
	(segment
		(start 103.038148 -240.111788)
		(end 103.068628 -240.129568)
		(width 0.1143)
		(layer "In6.Cu")
		(net "GMI_CPU1_G0_CPU0_G2_TX_DN<6>")
	)
	(segment
		(start 367.086896 -231.869488)
		(end 367.05032 -231.848152)
		(width 0.1143)
		(layer "In6.Cu")
		(net "GMI_CPU1_G0_CPU0_G2_TX_DN<6>")
	)
	(segment
		(start 106.985562 -222.569532)
		(end 106.985562 -222.61449)
		(width 0.1143)
		(layer "In6.Cu")
		(net "GMI_CPU1_G0_CPU0_G2_TX_DN<6>")
	)
	(segment
		(start 104.408986 -234.418886)
		(end 104.448102 -234.441746)
		(width 0.1143)
		(layer "In6.Cu")
		(net "GMI_CPU1_G0_CPU0_G2_TX_DN<6>")
	)
	(segment
		(start 367.014252 -231.22128)
		(end 367.086896 -231.178862)
		(width 0.1143)
		(layer "In6.Cu")
		(net "GMI_CPU1_G0_CPU0_G2_TX_DN<6>")
	)
	(segment
		(start 104.499156 -228.574854)
		(end 104.479852 -228.58857)
		(width 0.1143)
		(layer "In6.Cu")
		(net "GMI_CPU1_G0_CPU0_G2_TX_DN<6>")
	)
	(segment
		(start 367.021364 -231.831388)
		(end 367.020602 -231.83088)
		(width 0.1143)
		(layer "In6.Cu")
		(net "GMI_CPU1_G0_CPU0_G2_TX_DN<6>")
	)
	(segment
		(start 104.46893 -230.214678)
		(end 104.408478 -230.249984)
		(width 0.1143)
		(layer "In6.Cu")
		(net "GMI_CPU1_G0_CPU0_G2_TX_DN<6>")
	)
	(segment
		(start 367.985802 -240.92281)
		(end 367.987072 -240.922048)
		(width 0.1143)
		(layer "In6.Cu")
		(net "GMI_CPU1_G0_CPU0_G2_TX_DN<6>")
	)
	(segment
		(start 104.635554 -229.89413)
		(end 104.630474 -229.944168)
		(width 0.1143)
		(layer "In6.Cu")
		(net "GMI_CPU1_G0_CPU0_G2_TX_DN<6>")
	)
	(segment
		(start 367.01603 -227.98024)
		(end 367.086896 -227.938838)
		(width 0.1143)
		(layer "In6.Cu")
		(net "GMI_CPU1_G0_CPU0_G2_TX_DN<6>")
	)
	(segment
		(start 104.51592 -231.793796)
		(end 104.497632 -231.811322)
		(width 0.1143)
		(layer "In6.Cu")
		(net "GMI_CPU1_G0_CPU0_G2_TX_DN<6>")
	)
	(segment
		(start 367.01603 -232.839768)
		(end 367.086896 -232.79862)
		(width 0.1143)
		(layer "In6.Cu")
		(net "GMI_CPU1_G0_CPU0_G2_TX_DN<6>")
	)
	(segment
		(start 367.01603 -234.45978)
		(end 367.04778 -234.441492)
		(width 0.1143)
		(layer "In6.Cu")
		(net "GMI_CPU1_G0_CPU0_G2_TX_DN<6>")
	)
	(segment
		(start 104.497632 -231.811322)
		(end 104.493568 -231.811322)
		(width 0.1143)
		(layer "In6.Cu")
		(net "GMI_CPU1_G0_CPU0_G2_TX_DN<6>")
	)
	(segment
		(start 103.038148 -239.136936)
		(end 102.999032 -239.159796)
		(width 0.1143)
		(layer "In6.Cu")
		(net "GMI_CPU1_G0_CPU0_G2_TX_DN<6>")
	)
	(segment
		(start 107.409488 -221.064836)
		(end 107.409488 -221.093284)
		(width 0.1143)
		(layer "In6.Cu")
		(net "GMI_CPU1_G0_CPU0_G2_TX_DN<6>")
	)
	(segment
		(start 366.57788 -226.17684)
		(end 366.54613 -226.158552)
		(width 0.1143)
		(layer "In6.Cu")
		(net "GMI_CPU1_G0_CPU0_G2_TX_DN<6>")
	)
	(segment
		(start 103.068628 -239.119156)
		(end 103.038148 -239.136936)
		(width 0.1143)
		(layer "In6.Cu")
		(net "GMI_CPU1_G0_CPU0_G2_TX_DN<6>")
	)
	(segment
		(start 367.98885 -240.921032)
		(end 367.990374 -240.920016)
		(width 0.1143)
		(layer "In6.Cu")
		(net "GMI_CPU1_G0_CPU0_G2_TX_DN<6>")
	)
	(segment
		(start 367.011458 -231.823768)
		(end 366.97158 -231.78389)
		(width 0.1143)
		(layer "In6.Cu")
		(net "GMI_CPU1_G0_CPU0_G2_TX_DN<6>")
	)
	(segment
		(start 366.997996 -232.852722)
		(end 367.01603 -232.839768)
		(width 0.1143)
		(layer "In6.Cu")
		(net "GMI_CPU1_G0_CPU0_G2_TX_DN<6>")
	)
	(segment
		(start 367.987834 -240.92154)
		(end 367.98885 -240.921032)
		(width 0.1143)
		(layer "In6.Cu")
		(net "GMI_CPU1_G0_CPU0_G2_TX_DN<6>")
	)
	(segment
		(start 105.388156 -225.367088)
		(end 105.34904 -225.389948)
		(width 0.1143)
		(layer "In6.Cu")
		(net "GMI_CPU1_G0_CPU0_G2_TX_DN<6>")
	)
	(segment
		(start 367.990374 -236.708188)
		(end 367.98885 -236.707172)
		(width 0.1143)
		(layer "In6.Cu")
		(net "GMI_CPU1_G0_CPU0_G2_TX_DN<6>")
	)
	(arc
		(start 367.086896 -227.938838)
		(mid 367.090845 -227.936061)
		(end 367.09477 -227.93325)
		(width 0.1143)
		(layer "In6.Cu")
		(net "GMI_CPU1_G0_CPU0_G2_TX_DN<6>")
	)
	(arc
		(start 364.196122 -222.108522)
		(mid 364.081446 -221.975188)
		(end 364.040166 -221.80423)
		(width 0.1143)
		(layer "In6.Cu")
		(net "GMI_CPU1_G0_CPU0_G2_TX_DN<6>")
	)
	(arc
		(start 104.88168 -226.198176)
		(mid 104.876324 -226.201827)
		(end 104.871012 -226.205542)
		(width 0.1143)
		(layer "In6.Cu")
		(net "GMI_CPU1_G0_CPU0_G2_TX_DN<6>")
	)
	(arc
		(start 104.408986 -227.009706)
		(mid 104.165789 -227.469518)
		(end 104.401112 -227.933504)
		(width 0.1143)
		(layer "In6.Cu")
		(net "GMI_CPU1_G0_CPU0_G2_TX_DN<6>")
	)
	(arc
		(start 367.086896 -229.55885)
		(mid 367.330223 -229.094284)
		(end 367.086896 -228.629718)
		(width 0.1143)
		(layer "In6.Cu")
		(net "GMI_CPU1_G0_CPU0_G2_TX_DN<6>")
	)
	(arc
		(start 103.939086 -235.919772)
		(mid 103.760273 -236.122122)
		(end 103.695754 -236.384338)
		(width 0.1143)
		(layer "In6.Cu")
		(net "GMI_CPU1_G0_CPU0_G2_TX_DN<6>")
	)
	(arc
		(start 366.62487 -226.205288)
		(mid 366.619556 -226.201576)
		(end 366.614202 -226.197922)
		(width 0.1143)
		(layer "In6.Cu")
		(net "GMI_CPU1_G0_CPU0_G2_TX_DN<6>")
	)
	(arc
		(start 368.02695 -240.89868)
		(mid 368.205763 -240.69633)
		(end 368.270282 -240.434114)
		(width 0.1143)
		(layer "In6.Cu")
		(net "GMI_CPU1_G0_CPU0_G2_TX_DN<6>")
	)
	(arc
		(start 105.34904 -225.389948)
		(mid 105.170227 -225.592298)
		(end 105.105708 -225.854514)
		(width 0.1143)
		(layer "In6.Cu")
		(net "GMI_CPU1_G0_CPU0_G2_TX_DN<6>")
	)
	(arc
		(start 104.499664 -234.474258)
		(mid 104.648378 -234.764326)
		(end 104.499664 -235.054394)
		(width 0.1143)
		(layer "In6.Cu")
		(net "GMI_CPU1_G0_CPU0_G2_TX_DN<6>")
	)
	(arc
		(start 107.455716 -221.804484)
		(mid 107.414461 -221.975455)
		(end 107.29976 -222.108776)
		(width 0.1143)
		(layer "In6.Cu")
		(net "GMI_CPU1_G0_CPU0_G2_TX_DN<6>")
	)
	(arc
		(start 104.497886 -232.852976)
		(mid 104.647208 -233.144314)
		(end 104.497886 -233.435652)
		(width 0.1143)
		(layer "In6.Cu")
		(net "GMI_CPU1_G0_CPU0_G2_TX_DN<6>")
	)
	(arc
		(start 366.871504 -229.81285)
		(mid 366.924314 -229.694539)
		(end 367.014252 -229.601268)
		(width 0.1143)
		(layer "In6.Cu")
		(net "GMI_CPU1_G0_CPU0_G2_TX_DN<6>")
	)
	(arc
		(start 105.894124 -224.53473)
		(mid 105.890963 -224.537288)
		(end 105.887774 -224.53981)
		(width 0.1143)
		(layer "In6.Cu")
		(net "GMI_CPU1_G0_CPU0_G2_TX_DN<6>")
	)
	(arc
		(start 103.068628 -238.509556)
		(mid 103.225605 -238.814356)
		(end 103.068628 -239.119156)
		(width 0.1143)
		(layer "In6.Cu")
		(net "GMI_CPU1_G0_CPU0_G2_TX_DN<6>")
	)
	(arc
		(start 103.2256 -237.194344)
		(mid 103.184051 -237.365766)
		(end 103.068628 -237.499144)
		(width 0.1143)
		(layer "In6.Cu")
		(net "GMI_CPU1_G0_CPU0_G2_TX_DN<6>")
	)
	(arc
		(start 365.601758 -224.534476)
		(mid 365.50761 -224.409188)
		(end 365.454692 -224.26168)
		(width 0.1143)
		(layer "In6.Cu")
		(net "GMI_CPU1_G0_CPU0_G2_TX_DN<6>")
	)
	(arc
		(start 105.575608 -225.044508)
		(mid 105.534059 -225.21593)
		(end 105.418636 -225.349308)
		(width 0.1143)
		(layer "In6.Cu")
		(net "GMI_CPU1_G0_CPU0_G2_TX_DN<6>")
	)
	(arc
		(start 364.749842 -222.968566)
		(mid 364.742266 -222.96317)
		(end 364.734602 -222.957898)
		(width 0.1143)
		(layer "In6.Cu")
		(net "GMI_CPU1_G0_CPU0_G2_TX_DN<6>")
	)
	(arc
		(start 367.800128 -236.384084)
		(mid 367.735613 -236.121865)
		(end 367.556796 -235.919518)
		(width 0.1143)
		(layer "In6.Cu")
		(net "GMI_CPU1_G0_CPU0_G2_TX_DN<6>")
	)
	(arc
		(start 103.2256 -240.434368)
		(mid 103.290115 -240.696587)
		(end 103.468932 -240.898934)
		(width 0.1143)
		(layer "In6.Cu")
		(net "GMI_CPU1_G0_CPU0_G2_TX_DN<6>")
	)
	(arc
		(start 102.999032 -239.159796)
		(mid 102.755705 -239.624362)
		(end 102.999032 -240.088928)
		(width 0.1143)
		(layer "In6.Cu")
		(net "GMI_CPU1_G0_CPU0_G2_TX_DN<6>")
	)
	(arc
		(start 104.408986 -228.629972)
		(mid 104.165659 -229.094538)
		(end 104.408986 -229.559104)
		(width 0.1143)
		(layer "In6.Cu")
		(net "GMI_CPU1_G0_CPU0_G2_TX_DN<6>")
	)
	(arc
		(start 364.980474 -223.424242)
		(mid 364.98048 -223.421575)
		(end 364.980474 -223.418908)
		(width 0.1143)
		(layer "In6.Cu")
		(net "GMI_CPU1_G0_CPU0_G2_TX_DN<6>")
	)
	(arc
		(start 106.388154 -223.705674)
		(mid 106.370959 -223.718913)
		(end 106.35234 -223.730058)
		(width 0.1143)
		(layer "In6.Cu")
		(net "GMI_CPU1_G0_CPU0_G2_TX_DN<6>")
	)
	(arc
		(start 106.74604 -222.96882)
		(mid 106.579795 -223.16792)
		(end 106.515408 -223.419162)
		(width 0.1143)
		(layer "In6.Cu")
		(net "GMI_CPU1_G0_CPU0_G2_TX_DN<6>")
	)
	(arc
		(start 106.280966 -223.775524)
		(mid 106.111517 -223.969495)
		(end 106.045762 -224.2185)
		(width 0.1143)
		(layer "In6.Cu")
		(net "GMI_CPU1_G0_CPU0_G2_TX_DN<6>")
	)
	(arc
		(start 367.086896 -231.178862)
		(mid 367.265709 -230.976512)
		(end 367.330228 -230.714296)
		(width 0.1143)
		(layer "In6.Cu")
		(net "GMI_CPU1_G0_CPU0_G2_TX_DN<6>")
	)
	(arc
		(start 104.408986 -231.869742)
		(mid 104.165659 -232.334308)
		(end 104.408986 -232.798874)
		(width 0.1143)
		(layer "In6.Cu")
		(net "GMI_CPU1_G0_CPU0_G2_TX_DN<6>")
	)
	(arc
		(start 106.76128 -222.958152)
		(mid 106.753616 -222.963423)
		(end 106.74604 -222.96882)
		(width 0.1143)
		(layer "In6.Cu")
		(net "GMI_CPU1_G0_CPU0_G2_TX_DN<6>")
	)
	(arc
		(start 366.390174 -225.85426)
		(mid 366.325659 -225.592041)
		(end 366.146842 -225.389694)
		(width 0.1143)
		(layer "In6.Cu")
		(net "GMI_CPU1_G0_CPU0_G2_TX_DN<6>")
	)
	(arc
		(start 366.860328 -229.893876)
		(mid 366.863706 -229.853059)
		(end 366.871504 -229.81285)
		(width 0.1143)
		(layer "In6.Cu")
		(net "GMI_CPU1_G0_CPU0_G2_TX_DN<6>")
	)
	(arc
		(start 367.020602 -231.83088)
		(mid 367.016002 -231.827359)
		(end 367.011458 -231.823768)
		(width 0.1143)
		(layer "In6.Cu")
		(net "GMI_CPU1_G0_CPU0_G2_TX_DN<6>")
	)
	(arc
		(start 364.980474 -223.418908)
		(mid 364.916012 -223.167704)
		(end 364.749842 -222.968566)
		(width 0.1143)
		(layer "In6.Cu")
		(net "GMI_CPU1_G0_CPU0_G2_TX_DN<6>")
	)
	(arc
		(start 103.468932 -236.729778)
		(mid 103.290119 -236.932128)
		(end 103.2256 -237.194344)
		(width 0.1143)
		(layer "In6.Cu")
		(net "GMI_CPU1_G0_CPU0_G2_TX_DN<6>")
	)
	(arc
		(start 104.627934 -226.71532)
		(mid 104.586002 -226.841861)
		(end 104.502712 -226.945952)
		(width 0.1143)
		(layer "In6.Cu")
		(net "GMI_CPU1_G0_CPU0_G2_TX_DN<6>")
	)
	(arc
		(start 106.515408 -223.424496)
		(mid 106.482122 -223.578822)
		(end 106.388154 -223.705674)
		(width 0.1143)
		(layer "In6.Cu")
		(net "GMI_CPU1_G0_CPU0_G2_TX_DN<6>")
	)
	(arc
		(start 366.97158 -231.78389)
		(mid 366.902313 -231.687753)
		(end 366.867186 -231.574594)
		(width 0.1143)
		(layer "In6.Cu")
		(net "GMI_CPU1_G0_CPU0_G2_TX_DN<6>")
	)
	(arc
		(start 104.635808 -226.649534)
		(mid 104.635095 -226.661625)
		(end 104.633776 -226.673664)
		(width 0.1143)
		(layer "In6.Cu")
		(net "GMI_CPU1_G0_CPU0_G2_TX_DN<6>")
	)
	(arc
		(start 104.499156 -227.99421)
		(mid 104.648076 -228.284532)
		(end 104.499156 -228.574854)
		(width 0.1143)
		(layer "In6.Cu")
		(net "GMI_CPU1_G0_CPU0_G2_TX_DN<6>")
	)
	(arc
		(start 104.408478 -230.249984)
		(mid 104.229975 -230.452435)
		(end 104.165654 -230.71455)
		(width 0.1143)
		(layer "In6.Cu")
		(net "GMI_CPU1_G0_CPU0_G2_TX_DN<6>")
	)
	(arc
		(start 104.48163 -231.221534)
		(mid 104.595209 -231.354762)
		(end 104.635808 -231.525064)
		(width 0.1143)
		(layer "In6.Cu")
		(net "GMI_CPU1_G0_CPU0_G2_TX_DN<6>")
	)
	(arc
		(start 366.862106 -226.67341)
		(mid 366.860797 -226.66137)
		(end 366.860074 -226.64928)
		(width 0.1143)
		(layer "In6.Cu")
		(net "GMI_CPU1_G0_CPU0_G2_TX_DN<6>")
	)
	(arc
		(start 104.624378 -229.813104)
		(mid 104.632196 -229.85331)
		(end 104.635554 -229.89413)
		(width 0.1143)
		(layer "In6.Cu")
		(net "GMI_CPU1_G0_CPU0_G2_TX_DN<6>")
	)
	(arc
		(start 104.165654 -235.574332)
		(mid 104.124105 -235.745754)
		(end 104.008682 -235.879132)
		(width 0.1143)
		(layer "In6.Cu")
		(net "GMI_CPU1_G0_CPU0_G2_TX_DN<6>")
	)
	(arc
		(start 106.04119 -224.261934)
		(mid 105.988237 -224.409423)
		(end 105.894124 -224.53473)
		(width 0.1143)
		(layer "In6.Cu")
		(net "GMI_CPU1_G0_CPU0_G2_TX_DN<6>")
	)
	(arc
		(start 365.143542 -223.729804)
		(mid 365.12493 -223.718648)
		(end 365.107728 -223.70542)
		(width 0.1143)
		(layer "In6.Cu")
		(net "GMI_CPU1_G0_CPU0_G2_TX_DN<6>")
	)
	(arc
		(start 364.51032 -222.569278)
		(mid 364.458554 -222.353162)
		(end 364.314486 -222.18396)
		(width 0.1143)
		(layer "In6.Cu")
		(net "GMI_CPU1_G0_CPU0_G2_TX_DN<6>")
	)
	(arc
		(start 104.401112 -227.933504)
		(mid 104.405037 -227.936315)
		(end 104.408986 -227.939092)
		(width 0.1143)
		(layer "In6.Cu")
		(net "GMI_CPU1_G0_CPU0_G2_TX_DN<6>")
	)
	(arc
		(start 105.105708 -225.854514)
		(mid 105.064453 -226.025485)
		(end 104.949752 -226.158806)
		(width 0.1143)
		(layer "In6.Cu")
		(net "GMI_CPU1_G0_CPU0_G2_TX_DN<6>")
	)
	(arc
		(start 104.165654 -230.71455)
		(mid 104.230169 -230.976769)
		(end 104.408986 -231.179116)
		(width 0.1143)
		(layer "In6.Cu")
		(net "GMI_CPU1_G0_CPU0_G2_TX_DN<6>")
	)
	(arc
		(start 366.860074 -231.524048)
		(mid 366.900836 -231.354164)
		(end 367.014252 -231.22128)
		(width 0.1143)
		(layer "In6.Cu")
		(net "GMI_CPU1_G0_CPU0_G2_TX_DN<6>")
	)
	(arc
		(start 365.608108 -224.539556)
		(mid 365.60492 -224.537033)
		(end 365.601758 -224.534476)
		(width 0.1143)
		(layer "In6.Cu")
		(net "GMI_CPU1_G0_CPU0_G2_TX_DN<6>")
	)
	(arc
		(start 365.107728 -223.70542)
		(mid 365.013799 -223.57855)
		(end 364.980474 -223.424242)
		(width 0.1143)
		(layer "In6.Cu")
		(net "GMI_CPU1_G0_CPU0_G2_TX_DN<6>")
	)
	(arc
		(start 365.920274 -225.044254)
		(mid 365.855402 -224.781291)
		(end 365.675672 -224.578672)
		(width 0.1143)
		(layer "In6.Cu")
		(net "GMI_CPU1_G0_CPU0_G2_TX_DN<6>")
	)
	(arc
		(start 368.270282 -237.19409)
		(mid 368.205767 -236.931871)
		(end 368.02695 -236.729524)
		(width 0.1143)
		(layer "In6.Cu")
		(net "GMI_CPU1_G0_CPU0_G2_TX_DN<6>")
	)
	(arc
		(start 368.49685 -238.468662)
		(mid 368.740177 -238.004096)
		(end 368.49685 -237.53953)
		(width 0.1143)
		(layer "In6.Cu")
		(net "GMI_CPU1_G0_CPU0_G2_TX_DN<6>")
	)
	(arc
		(start 367.806986 -241.17427)
		(mid 367.859035 -241.042751)
		(end 367.956084 -240.939828)
		(width 0.1143)
		(layer "In6.Cu")
		(net "GMI_CPU1_G0_CPU0_G2_TX_DN<6>")
	)
	(arc
		(start 103.068628 -240.129568)
		(mid 103.184055 -240.262944)
		(end 103.2256 -240.434368)
		(width 0.1143)
		(layer "In6.Cu")
		(net "GMI_CPU1_G0_CPU0_G2_TX_DN<6>")
	)
	(arc
		(start 365.45012 -224.218246)
		(mid 365.384287 -223.969282)
		(end 365.214916 -223.77527)
		(width 0.1143)
		(layer "In6.Cu")
		(net "GMI_CPU1_G0_CPU0_G2_TX_DN<6>")
	)
	(arc
		(start 366.997996 -233.435398)
		(mid 366.848674 -233.14406)
		(end 366.997996 -232.852722)
		(width 0.1143)
		(layer "In6.Cu")
		(net "GMI_CPU1_G0_CPU0_G2_TX_DN<6>")
	)
	(arc
		(start 103.695754 -236.384338)
		(mid 103.654499 -236.555309)
		(end 103.539798 -236.68863)
		(width 0.1143)
		(layer "In6.Cu")
		(net "GMI_CPU1_G0_CPU0_G2_TX_DN<6>")
	)
	(arc
		(start 366.993932 -226.94646)
		(mid 366.910098 -226.841418)
		(end 366.867948 -226.713796)
		(width 0.1143)
		(layer "In6.Cu")
		(net "GMI_CPU1_G0_CPU0_G2_TX_DN<6>")
	)
	(arc
		(start 106.515408 -223.419162)
		(mid 106.515401 -223.421829)
		(end 106.515408 -223.424496)
		(width 0.1143)
		(layer "In6.Cu")
		(net "GMI_CPU1_G0_CPU0_G2_TX_DN<6>")
	)
	(arc
		(start 105.82021 -224.578926)
		(mid 105.640481 -224.781546)
		(end 105.575608 -225.044508)
		(width 0.1143)
		(layer "In6.Cu")
		(net "GMI_CPU1_G0_CPU0_G2_TX_DN<6>")
	)
	(arc
		(start 366.860074 -226.64928)
		(mid 366.794454 -226.399762)
		(end 366.62487 -226.205288)
		(width 0.1143)
		(layer "In6.Cu")
		(net "GMI_CPU1_G0_CPU0_G2_TX_DN<6>")
	)
	(arc
		(start 368.49685 -240.088674)
		(mid 368.740177 -239.624108)
		(end 368.49685 -239.159542)
		(width 0.1143)
		(layer "In6.Cu")
		(net "GMI_CPU1_G0_CPU0_G2_TX_DN<6>")
	)
	(arc
		(start 104.408986 -233.489754)
		(mid 104.165659 -233.95432)
		(end 104.408986 -234.418886)
		(width 0.1143)
		(layer "In6.Cu")
		(net "GMI_CPU1_G0_CPU0_G2_TX_DN<6>")
	)
	(arc
		(start 103.539798 -240.940082)
		(mid 103.636933 -241.042951)
		(end 103.688896 -241.174524)
		(width 0.1143)
		(layer "In6.Cu")
		(net "GMI_CPU1_G0_CPU0_G2_TX_DN<6>")
	)
	(arc
		(start 367.002568 -230.193088)
		(mid 366.907615 -230.072872)
		(end 366.86363 -229.926134)
		(width 0.1143)
		(layer "In6.Cu")
		(net "GMI_CPU1_G0_CPU0_G2_TX_DN<6>")
	)
	(arc
		(start 367.086896 -234.418632)
		(mid 367.330223 -233.954066)
		(end 367.086896 -233.4895)
		(width 0.1143)
		(layer "In6.Cu")
		(net "GMI_CPU1_G0_CPU0_G2_TX_DN<6>")
	)
	(arc
		(start 365.214916 -223.77527)
		(mid 365.180078 -223.751204)
		(end 365.143542 -223.729804)
		(width 0.1143)
		(layer "In6.Cu")
		(net "GMI_CPU1_G0_CPU0_G2_TX_DN<6>")
	)
	(arc
		(start 104.48163 -229.601522)
		(mid 104.571605 -229.694768)
		(end 104.624378 -229.813104)
		(width 0.1143)
		(layer "In6.Cu")
		(net "GMI_CPU1_G0_CPU0_G2_TX_DN<6>")
	)
	(arc
		(start 366.077246 -225.349054)
		(mid 365.961819 -225.215678)
		(end 365.920274 -225.044254)
		(width 0.1143)
		(layer "In6.Cu")
		(net "GMI_CPU1_G0_CPU0_G2_TX_DN<6>")
	)
	(arc
		(start 368.270282 -240.434114)
		(mid 368.311831 -240.262692)
		(end 368.427254 -240.129314)
		(width 0.1143)
		(layer "In6.Cu")
		(net "GMI_CPU1_G0_CPU0_G2_TX_DN<6>")
	)
	(arc
		(start 366.996218 -235.05414)
		(mid 366.847504 -234.764072)
		(end 366.996218 -234.474004)
		(width 0.1143)
		(layer "In6.Cu")
		(net "GMI_CPU1_G0_CPU0_G2_TX_DN<6>")
	)
	(arc
		(start 367.09477 -227.93325)
		(mid 367.330276 -227.469263)
		(end 367.086896 -227.009452)
		(width 0.1143)
		(layer "In6.Cu")
		(net "GMI_CPU1_G0_CPU0_G2_TX_DN<6>")
	)
	(arc
		(start 367.4872 -235.878878)
		(mid 367.371773 -235.745502)
		(end 367.330228 -235.574078)
		(width 0.1143)
		(layer "In6.Cu")
		(net "GMI_CPU1_G0_CPU0_G2_TX_DN<6>")
	)
	(arc
		(start 104.630982 -231.56418)
		(mid 104.593183 -231.688871)
		(end 104.51592 -231.793796)
		(width 0.1143)
		(layer "In6.Cu")
		(net "GMI_CPU1_G0_CPU0_G2_TX_DN<6>")
	)
	(arc
		(start 102.999032 -237.539784)
		(mid 102.755705 -238.00435)
		(end 102.999032 -238.468916)
		(width 0.1143)
		(layer "In6.Cu")
		(net "GMI_CPU1_G0_CPU0_G2_TX_DN<6>")
	)
	(arc
		(start 367.956084 -236.688376)
		(mid 367.841408 -236.555042)
		(end 367.800128 -236.384084)
		(width 0.1143)
		(layer "In6.Cu")
		(net "GMI_CPU1_G0_CPU0_G2_TX_DN<6>")
	)
	(arc
		(start 104.630474 -229.944168)
		(mid 104.591288 -230.074715)
		(end 104.506776 -230.181658)
		(width 0.1143)
		(layer "In6.Cu")
		(net "GMI_CPU1_G0_CPU0_G2_TX_DN<6>")
	)
	(arc
		(start 106.985562 -222.61449)
		(mid 106.944164 -222.785364)
		(end 106.829352 -222.918528)
		(width 0.1143)
		(layer "In6.Cu")
		(net "GMI_CPU1_G0_CPU0_G2_TX_DN<6>")
	)
	(arc
		(start 106.35234 -223.730058)
		(mid 106.315799 -223.75145)
		(end 106.280966 -223.775524)
		(width 0.1143)
		(layer "In6.Cu")
		(net "GMI_CPU1_G0_CPU0_G2_TX_DN<6>")
	)
	(arc
		(start 368.427254 -239.118902)
		(mid 368.270277 -238.814102)
		(end 368.427254 -238.509302)
		(width 0.1143)
		(layer "In6.Cu")
		(net "GMI_CPU1_G0_CPU0_G2_TX_DN<6>")
	)
	(arc
		(start 368.427254 -237.49889)
		(mid 368.311827 -237.365514)
		(end 368.270282 -237.19409)
		(width 0.1143)
		(layer "In6.Cu")
		(net "GMI_CPU1_G0_CPU0_G2_TX_DN<6>")
	)
	(arc
		(start 364.66653 -222.918274)
		(mid 364.551687 -222.785126)
		(end 364.51032 -222.614236)
		(width 0.1143)
		(layer "In6.Cu")
		(net "GMI_CPU1_G0_CPU0_G2_TX_DN<6>")
	)
	(arc
		(start 106.045762 -224.2185)
		(mid 106.044386 -224.240313)
		(end 106.04119 -224.261934)
		(width 0.1143)
		(layer "In6.Cu")
		(net "GMI_CPU1_G0_CPU0_G2_TX_DN<6>")
	)
	(arc
		(start 107.181396 -222.184214)
		(mid 107.037337 -222.35342)
		(end 106.985562 -222.569532)
		(width 0.1143)
		(layer "In6.Cu")
		(net "GMI_CPU1_G0_CPU0_G2_TX_DN<6>")
	)
	(arc
		(start 104.408986 -235.109766)
		(mid 104.230173 -235.312116)
		(end 104.165654 -235.574332)
		(width 0.1143)
		(layer "In6.Cu")
		(net "GMI_CPU1_G0_CPU0_G2_TX_DN<6>")
	)
	(arc
		(start 367.086896 -232.79862)
		(mid 367.330223 -232.334054)
		(end 367.086896 -231.869488)
		(width 0.1143)
		(layer "In6.Cu")
		(net "GMI_CPU1_G0_CPU0_G2_TX_DN<6>")
	)
	(arc
		(start 366.996726 -228.5746)
		(mid 366.847806 -228.284278)
		(end 366.996726 -227.993956)
		(width 0.1143)
		(layer "In6.Cu")
		(net "GMI_CPU1_G0_CPU0_G2_TX_DN<6>")
	)
	(arc
		(start 104.871012 -226.205542)
		(mid 104.701325 -226.399962)
		(end 104.635808 -226.649534)
		(width 0.1143)
		(layer "In6.Cu")
		(net "GMI_CPU1_G0_CPU0_G2_TX_DN<6>")
	)
	(arc
		(start 367.330228 -230.714296)
		(mid 367.265849 -230.452212)
		(end 367.087404 -230.24973)
		(width 0.1143)
		(layer "In6.Cu")
		(net "GMI_CPU1_G0_CPU0_G2_TX_DN<6>")
	)
	(arc
		(start 365.454692 -224.26168)
		(mid 365.451504 -224.240058)
		(end 365.45012 -224.218246)
		(width 0.1143)
		(layer "In6.Cu")
		(net "GMI_CPU1_G0_CPU0_G2_TX_DN<6>")
	)
	(arc
		(start 366.54613 -226.158552)
		(mid 366.431454 -226.025218)
		(end 366.390174 -225.85426)
		(width 0.1143)
		(layer "In6.Cu")
		(net "GMI_CPU1_G0_CPU0_G2_TX_DN<6>")
	)
	(arc
		(start 367.330228 -235.574078)
		(mid 367.265713 -235.311859)
		(end 367.086896 -235.109512)
		(width 0.1143)
		(layer "In6.Cu")
		(net "GMI_CPU1_G0_CPU0_G2_TX_DN<6>")
	)
	(segment
		(start 370.527834 -243.13007)
		(end 370.994686 -242.864132)
		(width 0.12954)
		(layer "F.Cu")
		(net "GMI_CPU1_G0_CPU0_G2_TX_DN<5>")
	)
	(segment
		(start 100.967794 -243.130324)
		(end 100.500942 -242.864386)
		(width 0.12954)
		(layer "F.Cu")
		(net "GMI_CPU1_G0_CPU0_G2_TX_DN<5>")
	)
	(segment
		(start 102.098094 -239.136936)
		(end 102.129844 -239.118648)
		(width 0.1143)
		(layer "In6.Cu")
		(net "GMI_CPU1_G0_CPU0_G2_TX_DN<5>")
	)
	(segment
		(start 368.925856 -236.705394)
		(end 368.927126 -236.706156)
		(width 0.1143)
		(layer "In6.Cu")
		(net "GMI_CPU1_G0_CPU0_G2_TX_DN<5>")
	)
	(segment
		(start 367.987834 -231.846628)
		(end 367.98885 -231.847136)
		(width 0.1143)
		(layer "In6.Cu")
		(net "GMI_CPU1_G0_CPU0_G2_TX_DN<5>")
	)
	(segment
		(start 367.987072 -235.086144)
		(end 367.987834 -235.086652)
		(width 0.1143)
		(layer "In6.Cu")
		(net "GMI_CPU1_G0_CPU0_G2_TX_DN<5>")
	)
	(segment
		(start 367.98885 -233.467148)
		(end 367.990374 -233.468164)
		(width 0.1143)
		(layer "In6.Cu")
		(net "GMI_CPU1_G0_CPU0_G2_TX_DN<5>")
	)
	(segment
		(start 368.896138 -236.688376)
		(end 368.925856 -236.705394)
		(width 0.1143)
		(layer "In6.Cu")
		(net "GMI_CPU1_G0_CPU0_G2_TX_DN<5>")
	)
	(segment
		(start 100.798884 -242.864386)
		(end 100.881688 -242.781582)
		(width 0.1143)
		(layer "In6.Cu")
		(net "GMI_CPU1_G0_CPU0_G2_TX_DN<5>")
	)
	(segment
		(start 370.338858 -242.377214)
		(end 370.340382 -242.37823)
		(width 0.1143)
		(layer "In6.Cu")
		(net "GMI_CPU1_G0_CPU0_G2_TX_DN<5>")
	)
	(segment
		(start 104.44861 -225.367088)
		(end 104.474518 -225.351848)
		(width 0.1143)
		(layer "In6.Cu")
		(net "GMI_CPU1_G0_CPU0_G2_TX_DN<5>")
	)
	(segment
		(start 367.956084 -230.208328)
		(end 367.987834 -230.226616)
		(width 0.1143)
		(layer "In6.Cu")
		(net "GMI_CPU1_G0_CPU0_G2_TX_DN<5>")
	)
	(segment
		(start 102.098094 -240.756948)
		(end 102.129844 -240.73866)
		(width 0.1143)
		(layer "In6.Cu")
		(net "GMI_CPU1_G0_CPU0_G2_TX_DN<5>")
	)
	(segment
		(start 103.939086 -226.199954)
		(end 103.978202 -226.177094)
		(width 0.1143)
		(layer "In6.Cu")
		(net "GMI_CPU1_G0_CPU0_G2_TX_DN<5>")
	)
	(segment
		(start 367.985802 -233.46537)
		(end 367.987072 -233.466132)
		(width 0.1143)
		(layer "In6.Cu")
		(net "GMI_CPU1_G0_CPU0_G2_TX_DN<5>")
	)
	(segment
		(start 104.474518 -225.351848)
		(end 104.47528 -225.35134)
		(width 0.1143)
		(layer "In6.Cu")
		(net "GMI_CPU1_G0_CPU0_G2_TX_DN<5>")
	)
	(segment
		(start 103.51008 -231.845612)
		(end 103.539798 -231.828594)
		(width 0.1143)
		(layer "In6.Cu")
		(net "GMI_CPU1_G0_CPU0_G2_TX_DN<5>")
	)
	(segment
		(start 103.508048 -229.581964)
		(end 103.468932 -229.559104)
		(width 0.1143)
		(layer "In6.Cu")
		(net "GMI_CPU1_G0_CPU0_G2_TX_DN<5>")
	)
	(segment
		(start 105.820972 -222.958914)
		(end 105.892346 -222.917512)
		(width 0.1143)
		(layer "In6.Cu")
		(net "GMI_CPU1_G0_CPU0_G2_TX_DN<5>")
	)
	(segment
		(start 367.985802 -235.085382)
		(end 367.987072 -235.086144)
		(width 0.1143)
		(layer "In6.Cu")
		(net "GMI_CPU1_G0_CPU0_G2_TX_DN<5>")
	)
	(segment
		(start 367.987834 -226.986846)
		(end 367.98885 -226.987354)
		(width 0.1143)
		(layer "In6.Cu")
		(net "GMI_CPU1_G0_CPU0_G2_TX_DN<5>")
	)
	(segment
		(start 102.129844 -240.130076)
		(end 102.098094 -240.111788)
		(width 0.1143)
		(layer "In6.Cu")
		(net "GMI_CPU1_G0_CPU0_G2_TX_DN<5>")
	)
	(segment
		(start 365.026702 -221.09303)
		(end 364.980982 -221.13875)
		(width 0.1143)
		(layer "In6.Cu")
		(net "GMI_CPU1_G0_CPU0_G2_TX_DN<5>")
	)
	(segment
		(start 106.515408 -221.139004)
		(end 106.469688 -221.093284)
		(width 0.1143)
		(layer "In6.Cu")
		(net "GMI_CPU1_G0_CPU0_G2_TX_DN<5>")
	)
	(segment
		(start 103.468932 -233.489754)
		(end 103.507032 -233.467402)
		(width 0.1143)
		(layer "In6.Cu")
		(net "GMI_CPU1_G0_CPU0_G2_TX_DN<5>")
	)
	(segment
		(start 370.306092 -242.358418)
		(end 370.33581 -242.375436)
		(width 0.1143)
		(layer "In6.Cu")
		(net "GMI_CPU1_G0_CPU0_G2_TX_DN<5>")
	)
	(segment
		(start 107.874816 -215.89492)
		(end 114.883184 -208.886806)
		(width 0.14224)
		(layer "In6.Cu")
		(net "GMI_CPU1_G0_CPU0_G2_TX_DN<5>")
	)
	(segment
		(start 103.539798 -234.460034)
		(end 103.50881 -234.442254)
		(width 0.1143)
		(layer "In6.Cu")
		(net "GMI_CPU1_G0_CPU0_G2_TX_DN<5>")
	)
	(segment
		(start 365.606076 -222.918528)
		(end 365.637826 -222.936816)
		(width 0.1143)
		(layer "In6.Cu")
		(net "GMI_CPU1_G0_CPU0_G2_TX_DN<5>")
	)
	(segment
		(start 103.468932 -227.00996)
		(end 103.507032 -226.987608)
		(width 0.1143)
		(layer "In6.Cu")
		(net "GMI_CPU1_G0_CPU0_G2_TX_DN<5>")
	)
	(segment
		(start 103.038148 -235.896912)
		(end 103.068628 -235.879132)
		(width 0.1143)
		(layer "In6.Cu")
		(net "GMI_CPU1_G0_CPU0_G2_TX_DN<5>")
	)
	(segment
		(start 370.33708 -242.376198)
		(end 370.337842 -242.376706)
		(width 0.1143)
		(layer "In6.Cu")
		(net "GMI_CPU1_G0_CPU0_G2_TX_DN<5>")
	)
	(segment
		(start 120.938036 -204.240638)
		(end 163.238688 -179.814982)
		(width 0.14224)
		(layer "In6.Cu")
		(net "GMI_CPU1_G0_CPU0_G2_TX_DN<5>")
	)
	(segment
		(start 367.4872 -226.15906)
		(end 367.556796 -226.1997)
		(width 0.1143)
		(layer "In6.Cu")
		(net "GMI_CPU1_G0_CPU0_G2_TX_DN<5>")
	)
	(segment
		(start 103.468932 -228.629972)
		(end 103.507032 -228.60762)
		(width 0.1143)
		(layer "In6.Cu")
		(net "GMI_CPU1_G0_CPU0_G2_TX_DN<5>")
	)
	(segment
		(start 366.54613 -224.53854)
		(end 366.575848 -224.555558)
		(width 0.1143)
		(layer "In6.Cu")
		(net "GMI_CPU1_G0_CPU0_G2_TX_DN<5>")
	)
	(segment
		(start 367.98885 -232.820972)
		(end 367.987834 -232.82148)
		(width 0.1143)
		(layer "In6.Cu")
		(net "GMI_CPU1_G0_CPU0_G2_TX_DN<5>")
	)
	(segment
		(start 106.469688 -221.093284)
		(end 106.469688 -221.064836)
		(width 0.1143)
		(layer "In6.Cu")
		(net "GMI_CPU1_G0_CPU0_G2_TX_DN<5>")
	)
	(segment
		(start 103.508048 -235.086906)
		(end 103.50881 -235.086398)
		(width 0.1143)
		(layer "In6.Cu")
		(net "GMI_CPU1_G0_CPU0_G2_TX_DN<5>")
	)
	(segment
		(start 367.985802 -231.845358)
		(end 367.987072 -231.84612)
		(width 0.1143)
		(layer "In6.Cu")
		(net "GMI_CPU1_G0_CPU0_G2_TX_DN<5>")
	)
	(segment
		(start 369.397788 -240.756694)
		(end 369.436904 -240.779554)
		(width 0.1143)
		(layer "In6.Cu")
		(net "GMI_CPU1_G0_CPU0_G2_TX_DN<5>")
	)
	(segment
		(start 103.507032 -228.60762)
		(end 103.508048 -228.607112)
		(width 0.1143)
		(layer "In6.Cu")
		(net "GMI_CPU1_G0_CPU0_G2_TX_DN<5>")
	)
	(segment
		(start 367.98885 -227.96119)
		(end 367.987834 -227.961698)
		(width 0.1143)
		(layer "In6.Cu")
		(net "GMI_CPU1_G0_CPU0_G2_TX_DN<5>")
	)
	(segment
		(start 370.33581 -242.375436)
		(end 370.33708 -242.376198)
		(width 0.1143)
		(layer "In6.Cu")
		(net "GMI_CPU1_G0_CPU0_G2_TX_DN<5>")
	)
	(segment
		(start 368.02695 -231.178862)
		(end 367.954306 -231.22128)
		(width 0.1143)
		(layer "In6.Cu")
		(net "GMI_CPU1_G0_CPU0_G2_TX_DN<5>")
	)
	(segment
		(start 103.507032 -231.84739)
		(end 103.508048 -231.846882)
		(width 0.1143)
		(layer "In6.Cu")
		(net "GMI_CPU1_G0_CPU0_G2_TX_DN<5>")
	)
	(segment
		(start 101.15804 -242.37696)
		(end 101.158802 -242.376452)
		(width 0.1143)
		(layer "In6.Cu")
		(net "GMI_CPU1_G0_CPU0_G2_TX_DN<5>")
	)
	(segment
		(start 368.929158 -236.707426)
		(end 368.96421 -236.727746)
		(width 0.1143)
		(layer "In6.Cu")
		(net "GMI_CPU1_G0_CPU0_G2_TX_DN<5>")
	)
	(segment
		(start 369.436904 -238.468662)
		(end 369.397788 -238.491522)
		(width 0.1143)
		(layer "In6.Cu")
		(net "GMI_CPU1_G0_CPU0_G2_TX_DN<5>")
	)
	(segment
		(start 367.990374 -226.98837)
		(end 368.02695 -227.009706)
		(width 0.1143)
		(layer "In6.Cu")
		(net "GMI_CPU1_G0_CPU0_G2_TX_DN<5>")
	)
	(segment
		(start 106.469688 -221.064836)
		(end 106.469688 -219.288106)
		(width 0.14224)
		(layer "In6.Cu")
		(net "GMI_CPU1_G0_CPU0_G2_TX_DN<5>")
	)
	(segment
		(start 367.956084 -226.968558)
		(end 367.985802 -226.985576)
		(width 0.1143)
		(layer "In6.Cu")
		(net "GMI_CPU1_G0_CPU0_G2_TX_DN<5>")
	)
	(segment
		(start 102.2858 -237.328456)
		(end 102.2858 -237.194344)
		(width 0.1143)
		(layer "In6.Cu")
		(net "GMI_CPU1_G0_CPU0_G2_TX_DN<5>")
	)
	(segment
		(start 367.987072 -234.442)
		(end 367.985802 -234.442762)
		(width 0.1143)
		(layer "In6.Cu")
		(net "GMI_CPU1_G0_CPU0_G2_TX_DN<5>")
	)
	(segment
		(start 103.51008 -233.465624)
		(end 103.539798 -233.448606)
		(width 0.1143)
		(layer "In6.Cu")
		(net "GMI_CPU1_G0_CPU0_G2_TX_DN<5>")
	)
	(segment
		(start 364.192058 -217.05189)
		(end 365.026702 -219.066618)
		(width 0.14224)
		(layer "In6.Cu")
		(net "GMI_CPU1_G0_CPU0_G2_TX_DN<5>")
	)
	(segment
		(start 104.635808 -225.028506)
		(end 104.635808 -225.028252)
		(width 0.1143)
		(layer "In6.Cu")
		(net "GMI_CPU1_G0_CPU0_G2_TX_DN<5>")
	)
	(segment
		(start 366.57788 -224.556828)
		(end 366.614202 -224.57791)
		(width 0.1143)
		(layer "In6.Cu")
		(net "GMI_CPU1_G0_CPU0_G2_TX_DN<5>")
	)
	(segment
		(start 103.507032 -232.821226)
		(end 103.505508 -232.82021)
		(width 0.1143)
		(layer "In6.Cu")
		(net "GMI_CPU1_G0_CPU0_G2_TX_DN<5>")
	)
	(segment
		(start 367.985802 -234.442762)
		(end 367.956084 -234.45978)
		(width 0.1143)
		(layer "In6.Cu")
		(net "GMI_CPU1_G0_CPU0_G2_TX_DN<5>")
	)
	(segment
		(start 302.90516 -179.492148)
		(end 306.862988 -179.492148)
		(width 0.14224)
		(layer "In6.Cu")
		(net "GMI_CPU1_G0_CPU0_G2_TX_DN<5>")
	)
	(segment
		(start 163.238688 -179.814982)
		(end 167.441118 -178.701954)
		(width 0.14224)
		(layer "In6.Cu")
		(net "GMI_CPU1_G0_CPU0_G2_TX_DN<5>")
	)
	(segment
		(start 103.51008 -235.085636)
		(end 103.539798 -235.068618)
		(width 0.1143)
		(layer "In6.Cu")
		(net "GMI_CPU1_G0_CPU0_G2_TX_DN<5>")
	)
	(segment
		(start 365.026702 -219.066618)
		(end 365.026702 -221.09303)
		(width 0.14224)
		(layer "In6.Cu")
		(net "GMI_CPU1_G0_CPU0_G2_TX_DN<5>")
	)
	(segment
		(start 367.990374 -231.848152)
		(end 368.02695 -231.869488)
		(width 0.1143)
		(layer "In6.Cu")
		(net "GMI_CPU1_G0_CPU0_G2_TX_DN<5>")
	)
	(segment
		(start 114.883184 -208.886806)
		(end 120.938036 -204.240638)
		(width 0.14224)
		(layer "In6.Cu")
		(net "GMI_CPU1_G0_CPU0_G2_TX_DN<5>")
	)
	(segment
		(start 106.079544 -222.592646)
		(end 106.079544 -222.591122)
		(width 0.1143)
		(layer "In6.Cu")
		(net "GMI_CPU1_G0_CPU0_G2_TX_DN<5>")
	)
	(segment
		(start 104.88168 -224.578164)
		(end 104.918002 -224.557082)
		(width 0.1143)
		(layer "In6.Cu")
		(net "GMI_CPU1_G0_CPU0_G2_TX_DN<5>")
	)
	(segment
		(start 103.508048 -233.466894)
		(end 103.50881 -233.466386)
		(width 0.1143)
		(layer "In6.Cu")
		(net "GMI_CPU1_G0_CPU0_G2_TX_DN<5>")
	)
	(segment
		(start 364.979966 -221.32671)
		(end 364.979966 -221.80423)
		(width 0.1143)
		(layer "In6.Cu")
		(net "GMI_CPU1_G0_CPU0_G2_TX_DN<5>")
	)
	(segment
		(start 367.021364 -225.351594)
		(end 367.047272 -225.366834)
		(width 0.1143)
		(layer "In6.Cu")
		(net "GMI_CPU1_G0_CPU0_G2_TX_DN<5>")
	)
	(segment
		(start 103.508048 -231.201976)
		(end 103.468932 -231.179116)
		(width 0.1143)
		(layer "In6.Cu")
		(net "GMI_CPU1_G0_CPU0_G2_TX_DN<5>")
	)
	(segment
		(start 369.366038 -240.738406)
		(end 369.397788 -240.756694)
		(width 0.1143)
		(layer "In6.Cu")
		(net "GMI_CPU1_G0_CPU0_G2_TX_DN<5>")
	)
	(segment
		(start 106.516424 -221.326964)
		(end 106.515408 -221.325948)
		(width 0.1143)
		(layer "In6.Cu")
		(net "GMI_CPU1_G0_CPU0_G2_TX_DN<5>")
	)
	(segment
		(start 103.505508 -232.82021)
		(end 103.468932 -232.798874)
		(width 0.1143)
		(layer "In6.Cu")
		(net "GMI_CPU1_G0_CPU0_G2_TX_DN<5>")
	)
	(segment
		(start 367.98885 -235.08716)
		(end 368.02695 -235.109512)
		(width 0.1143)
		(layer "In6.Cu")
		(net "GMI_CPU1_G0_CPU0_G2_TX_DN<5>")
	)
	(segment
		(start 367.990374 -228.608382)
		(end 368.02695 -228.629718)
		(width 0.1143)
		(layer "In6.Cu")
		(net "GMI_CPU1_G0_CPU0_G2_TX_DN<5>")
	)
	(segment
		(start 103.539798 -232.840022)
		(end 103.508048 -232.821734)
		(width 0.1143)
		(layer "In6.Cu")
		(net "GMI_CPU1_G0_CPU0_G2_TX_DN<5>")
	)
	(segment
		(start 367.987834 -227.961698)
		(end 367.987072 -227.962206)
		(width 0.1143)
		(layer "In6.Cu")
		(net "GMI_CPU1_G0_CPU0_G2_TX_DN<5>")
	)
	(segment
		(start 367.987834 -235.086652)
		(end 367.98885 -235.08716)
		(width 0.1143)
		(layer "In6.Cu")
		(net "GMI_CPU1_G0_CPU0_G2_TX_DN<5>")
	)
	(segment
		(start 365.670592 -222.955612)
		(end 365.67491 -222.95866)
		(width 0.1143)
		(layer "In6.Cu")
		(net "GMI_CPU1_G0_CPU0_G2_TX_DN<5>")
	)
	(segment
		(start 367.987072 -227.962206)
		(end 367.985802 -227.962968)
		(width 0.1143)
		(layer "In6.Cu")
		(net "GMI_CPU1_G0_CPU0_G2_TX_DN<5>")
	)
	(segment
		(start 367.987834 -228.606858)
		(end 367.98885 -228.607366)
		(width 0.1143)
		(layer "In6.Cu")
		(net "GMI_CPU1_G0_CPU0_G2_TX_DN<5>")
	)
	(segment
		(start 102.570026 -236.705648)
		(end 102.599744 -236.68863)
		(width 0.1143)
		(layer "In6.Cu")
		(net "GMI_CPU1_G0_CPU0_G2_TX_DN<5>")
	)
	(segment
		(start 103.468932 -235.109766)
		(end 103.507032 -235.087414)
		(width 0.1143)
		(layer "In6.Cu")
		(net "GMI_CPU1_G0_CPU0_G2_TX_DN<5>")
	)
	(segment
		(start 102.567994 -236.706918)
		(end 102.568756 -236.70641)
		(width 0.1143)
		(layer "In6.Cu")
		(net "GMI_CPU1_G0_CPU0_G2_TX_DN<5>")
	)
	(segment
		(start 367.985802 -227.962968)
		(end 367.956084 -227.979986)
		(width 0.1143)
		(layer "In6.Cu")
		(net "GMI_CPU1_G0_CPU0_G2_TX_DN<5>")
	)
	(segment
		(start 103.51008 -226.98583)
		(end 103.539798 -226.968812)
		(width 0.1143)
		(layer "In6.Cu")
		(net "GMI_CPU1_G0_CPU0_G2_TX_DN<5>")
	)
	(segment
		(start 103.505508 -234.440222)
		(end 103.468932 -234.418886)
		(width 0.1143)
		(layer "In6.Cu")
		(net "GMI_CPU1_G0_CPU0_G2_TX_DN<5>")
	)
	(segment
		(start 167.441118 -178.701954)
		(end 302.90516 -179.492148)
		(width 0.14224)
		(layer "In6.Cu")
		(net "GMI_CPU1_G0_CPU0_G2_TX_DN<5>")
	)
	(segment
		(start 369.436904 -240.088674)
		(end 369.397788 -240.111534)
		(width 0.1143)
		(layer "In6.Cu")
		(net "GMI_CPU1_G0_CPU0_G2_TX_DN<5>")
	)
	(segment
		(start 102.098094 -238.491776)
		(end 102.058978 -238.468916)
		(width 0.1143)
		(layer "In6.Cu")
		(net "GMI_CPU1_G0_CPU0_G2_TX_DN<5>")
	)
	(segment
		(start 367.98885 -228.607366)
		(end 367.990374 -228.608382)
		(width 0.1143)
		(layer "In6.Cu")
		(net "GMI_CPU1_G0_CPU0_G2_TX_DN<5>")
	)
	(segment
		(start 103.50881 -226.986592)
		(end 103.51008 -226.98583)
		(width 0.1143)
		(layer "In6.Cu")
		(net "GMI_CPU1_G0_CPU0_G2_TX_DN<5>")
	)
	(segment
		(start 367.05032 -225.368358)
		(end 367.086896 -225.389694)
		(width 0.1143)
		(layer "In6.Cu")
		(net "GMI_CPU1_G0_CPU0_G2_TX_DN<5>")
	)
	(segment
		(start 367.987834 -234.441492)
		(end 367.987072 -234.442)
		(width 0.1143)
		(layer "In6.Cu")
		(net "GMI_CPU1_G0_CPU0_G2_TX_DN<5>")
	)
	(segment
		(start 101.118924 -242.39982)
		(end 101.157024 -242.377468)
		(width 0.1143)
		(layer "In6.Cu")
		(net "GMI_CPU1_G0_CPU0_G2_TX_DN<5>")
	)
	(segment
		(start 105.38841 -223.747076)
		(end 105.421176 -223.728026)
		(width 0.1143)
		(layer "In6.Cu")
		(net "GMI_CPU1_G0_CPU0_G2_TX_DN<5>")
	)
	(segment
		(start 102.058978 -240.779808)
		(end 102.098094 -240.756948)
		(width 0.1143)
		(layer "In6.Cu")
		(net "GMI_CPU1_G0_CPU0_G2_TX_DN<5>")
	)
	(segment
		(start 367.987834 -230.226616)
		(end 368.02441 -230.247952)
		(width 0.1143)
		(layer "In6.Cu")
		(net "GMI_CPU1_G0_CPU0_G2_TX_DN<5>")
	)
	(segment
		(start 103.541576 -231.221534)
		(end 103.508048 -231.201976)
		(width 0.1143)
		(layer "In6.Cu")
		(net "GMI_CPU1_G0_CPU0_G2_TX_DN<5>")
	)
	(segment
		(start 367.987072 -231.84612)
		(end 367.987834 -231.846628)
		(width 0.1143)
		(layer "In6.Cu")
		(net "GMI_CPU1_G0_CPU0_G2_TX_DN<5>")
	)
	(segment
		(start 104.918764 -224.556574)
		(end 104.920034 -224.555812)
		(width 0.1143)
		(layer "In6.Cu")
		(net "GMI_CPU1_G0_CPU0_G2_TX_DN<5>")
	)
	(segment
		(start 369.366038 -239.118394)
		(end 369.397788 -239.136682)
		(width 0.1143)
		(layer "In6.Cu")
		(net "GMI_CPU1_G0_CPU0_G2_TX_DN<5>")
	)
	(segment
		(start 318.182498 -185.494676)
		(end 320.058034 -187.052458)
		(width 0.14224)
		(layer "In6.Cu")
		(net "GMI_CPU1_G0_CPU0_G2_TX_DN<5>")
	)
	(segment
		(start 102.058978 -239.159796)
		(end 102.098094 -239.136936)
		(width 0.1143)
		(layer "In6.Cu")
		(net "GMI_CPU1_G0_CPU0_G2_TX_DN<5>")
	)
	(segment
		(start 368.02695 -227.938838)
		(end 367.990374 -227.960174)
		(width 0.1143)
		(layer "In6.Cu")
		(net "GMI_CPU1_G0_CPU0_G2_TX_DN<5>")
	)
	(segment
		(start 367.987834 -232.82148)
		(end 367.956084 -232.839768)
		(width 0.1143)
		(layer "In6.Cu")
		(net "GMI_CPU1_G0_CPU0_G2_TX_DN<5>")
	)
	(segment
		(start 309.116222 -180.110638)
		(end 318.182498 -185.494676)
		(width 0.14224)
		(layer "In6.Cu")
		(net "GMI_CPU1_G0_CPU0_G2_TX_DN<5>")
	)
	(segment
		(start 104.918002 -224.557082)
		(end 104.918764 -224.556574)
		(width 0.1143)
		(layer "In6.Cu")
		(net "GMI_CPU1_G0_CPU0_G2_TX_DN<5>")
	)
	(segment
		(start 368.02695 -234.418632)
		(end 367.990374 -234.439968)
		(width 0.1143)
		(layer "In6.Cu")
		(net "GMI_CPU1_G0_CPU0_G2_TX_DN<5>")
	)
	(segment
		(start 103.50881 -235.086398)
		(end 103.51008 -235.085636)
		(width 0.1143)
		(layer "In6.Cu")
		(net "GMI_CPU1_G0_CPU0_G2_TX_DN<5>")
	)
	(segment
		(start 106.355896 -222.11157)
		(end 106.356404 -222.111316)
		(width 0.1143)
		(layer "In6.Cu")
		(net "GMI_CPU1_G0_CPU0_G2_TX_DN<5>")
	)
	(segment
		(start 367.98885 -231.847136)
		(end 367.990374 -231.848152)
		(width 0.1143)
		(layer "In6.Cu")
		(net "GMI_CPU1_G0_CPU0_G2_TX_DN<5>")
	)
	(segment
		(start 367.985802 -226.985576)
		(end 367.987072 -226.986338)
		(width 0.1143)
		(layer "In6.Cu")
		(net "GMI_CPU1_G0_CPU0_G2_TX_DN<5>")
	)
	(segment
		(start 102.098094 -240.111788)
		(end 102.058978 -240.088928)
		(width 0.1143)
		(layer "In6.Cu")
		(net "GMI_CPU1_G0_CPU0_G2_TX_DN<5>")
	)
	(segment
		(start 367.98885 -234.440984)
		(end 367.987834 -234.441492)
		(width 0.1143)
		(layer "In6.Cu")
		(net "GMI_CPU1_G0_CPU0_G2_TX_DN<5>")
	)
	(segment
		(start 103.508048 -234.441746)
		(end 103.507032 -234.441238)
		(width 0.1143)
		(layer "In6.Cu")
		(net "GMI_CPU1_G0_CPU0_G2_TX_DN<5>")
	)
	(segment
		(start 368.427254 -235.878878)
		(end 368.49685 -235.919518)
		(width 0.1143)
		(layer "In6.Cu")
		(net "GMI_CPU1_G0_CPU0_G2_TX_DN<5>")
	)
	(segment
		(start 368.927888 -236.706664)
		(end 368.929158 -236.707426)
		(width 0.1143)
		(layer "In6.Cu")
		(net "GMI_CPU1_G0_CPU0_G2_TX_DN<5>")
	)
	(segment
		(start 102.129844 -237.498636)
		(end 102.23881 -237.42015)
		(width 0.1143)
		(layer "In6.Cu")
		(net "GMI_CPU1_G0_CPU0_G2_TX_DN<5>")
	)
	(segment
		(start 101.628194 -241.566954)
		(end 101.658674 -241.549174)
		(width 0.1143)
		(layer "In6.Cu")
		(net "GMI_CPU1_G0_CPU0_G2_TX_DN<5>")
	)
	(segment
		(start 306.862988 -179.492148)
		(end 309.116222 -180.110638)
		(width 0.14224)
		(layer "In6.Cu")
		(net "GMI_CPU1_G0_CPU0_G2_TX_DN<5>")
	)
	(segment
		(start 368.02695 -229.55885)
		(end 367.954306 -229.601268)
		(width 0.1143)
		(layer "In6.Cu")
		(net "GMI_CPU1_G0_CPU0_G2_TX_DN<5>")
	)
	(segment
		(start 103.50881 -227.96246)
		(end 103.508048 -227.961952)
		(width 0.1143)
		(layer "In6.Cu")
		(net "GMI_CPU1_G0_CPU0_G2_TX_DN<5>")
	)
	(segment
		(start 103.505508 -227.960428)
		(end 103.468932 -227.939092)
		(width 0.1143)
		(layer "In6.Cu")
		(net "GMI_CPU1_G0_CPU0_G2_TX_DN<5>")
	)
	(segment
		(start 370.696998 -242.864132)
		(end 370.994686 -242.864132)
		(width 0.1143)
		(layer "In6.Cu")
		(net "GMI_CPU1_G0_CPU0_G2_TX_DN<5>")
	)
	(segment
		(start 369.397788 -239.136682)
		(end 369.436904 -239.159542)
		(width 0.1143)
		(layer "In6.Cu")
		(net "GMI_CPU1_G0_CPU0_G2_TX_DN<5>")
	)
	(segment
		(start 103.51008 -228.605842)
		(end 103.539798 -228.588824)
		(width 0.1143)
		(layer "In6.Cu")
		(net "GMI_CPU1_G0_CPU0_G2_TX_DN<5>")
	)
	(segment
		(start 369.257072 -237.419896)
		(end 369.366038 -237.498382)
		(width 0.1143)
		(layer "In6.Cu")
		(net "GMI_CPU1_G0_CPU0_G2_TX_DN<5>")
	)
	(segment
		(start 355.525324 -209.343244)
		(end 360.257344 -213.117176)
		(width 0.14224)
		(layer "In6.Cu")
		(net "GMI_CPU1_G0_CPU0_G2_TX_DN<5>")
	)
	(segment
		(start 367.990374 -227.960174)
		(end 367.98885 -227.96119)
		(width 0.1143)
		(layer "In6.Cu")
		(net "GMI_CPU1_G0_CPU0_G2_TX_DN<5>")
	)
	(segment
		(start 367.04778 -225.366834)
		(end 367.048796 -225.367342)
		(width 0.1143)
		(layer "In6.Cu")
		(net "GMI_CPU1_G0_CPU0_G2_TX_DN<5>")
	)
	(segment
		(start 367.956084 -228.58857)
		(end 367.985802 -228.605588)
		(width 0.1143)
		(layer "In6.Cu")
		(net "GMI_CPU1_G0_CPU0_G2_TX_DN<5>")
	)
	(segment
		(start 103.508048 -228.607112)
		(end 103.50881 -228.606604)
		(width 0.1143)
		(layer "In6.Cu")
		(net "GMI_CPU1_G0_CPU0_G2_TX_DN<5>")
	)
	(segment
		(start 367.020602 -225.351086)
		(end 367.021364 -225.351594)
		(width 0.1143)
		(layer "In6.Cu")
		(net "GMI_CPU1_G0_CPU0_G2_TX_DN<5>")
	)
	(segment
		(start 366.860074 -225.027998)
		(end 366.860074 -225.028252)
		(width 0.1143)
		(layer "In6.Cu")
		(net "GMI_CPU1_G0_CPU0_G2_TX_DN<5>")
	)
	(segment
		(start 102.058978 -237.539784)
		(end 102.098094 -237.516924)
		(width 0.1143)
		(layer "In6.Cu")
		(net "GMI_CPU1_G0_CPU0_G2_TX_DN<5>")
	)
	(segment
		(start 366.577118 -224.55632)
		(end 366.57788 -224.556828)
		(width 0.1143)
		(layer "In6.Cu")
		(net "GMI_CPU1_G0_CPU0_G2_TX_DN<5>")
	)
	(segment
		(start 370.340382 -242.37823)
		(end 370.376958 -242.399566)
		(width 0.1143)
		(layer "In6.Cu")
		(net "GMI_CPU1_G0_CPU0_G2_TX_DN<5>")
	)
	(segment
		(start 366.107472 -223.746822)
		(end 366.147858 -223.770444)
		(width 0.1143)
		(layer "In6.Cu")
		(net "GMI_CPU1_G0_CPU0_G2_TX_DN<5>")
	)
	(segment
		(start 102.568756 -236.70641)
		(end 102.570026 -236.705648)
		(width 0.1143)
		(layer "In6.Cu")
		(net "GMI_CPU1_G0_CPU0_G2_TX_DN<5>")
	)
	(segment
		(start 367.047272 -225.366834)
		(end 367.04778 -225.366834)
		(width 0.1143)
		(layer "In6.Cu")
		(net "GMI_CPU1_G0_CPU0_G2_TX_DN<5>")
	)
	(segment
		(start 103.508048 -231.846882)
		(end 103.50881 -231.846374)
		(width 0.1143)
		(layer "In6.Cu")
		(net "GMI_CPU1_G0_CPU0_G2_TX_DN<5>")
	)
	(segment
		(start 101.160072 -242.37569)
		(end 101.18979 -242.358672)
		(width 0.1143)
		(layer "In6.Cu")
		(net "GMI_CPU1_G0_CPU0_G2_TX_DN<5>")
	)
	(segment
		(start 105.348024 -223.770698)
		(end 105.38841 -223.747076)
		(width 0.1143)
		(layer "In6.Cu")
		(net "GMI_CPU1_G0_CPU0_G2_TX_DN<5>")
	)
	(segment
		(start 367.985802 -228.605588)
		(end 367.987072 -228.60635)
		(width 0.1143)
		(layer "In6.Cu")
		(net "GMI_CPU1_G0_CPU0_G2_TX_DN<5>")
	)
	(segment
		(start 367.98885 -226.987354)
		(end 367.990374 -226.98837)
		(width 0.1143)
		(layer "In6.Cu")
		(net "GMI_CPU1_G0_CPU0_G2_TX_DN<5>")
	)
	(segment
		(start 364.980982 -221.13875)
		(end 364.980982 -221.325694)
		(width 0.1143)
		(layer "In6.Cu")
		(net "GMI_CPU1_G0_CPU0_G2_TX_DN<5>")
	)
	(segment
		(start 101.158802 -242.376452)
		(end 101.160072 -242.37569)
		(width 0.1143)
		(layer "In6.Cu")
		(net "GMI_CPU1_G0_CPU0_G2_TX_DN<5>")
	)
	(segment
		(start 103.50881 -228.606604)
		(end 103.51008 -228.605842)
		(width 0.1143)
		(layer "In6.Cu")
		(net "GMI_CPU1_G0_CPU0_G2_TX_DN<5>")
	)
	(segment
		(start 106.515408 -221.325948)
		(end 106.515408 -221.139004)
		(width 0.1143)
		(layer "In6.Cu")
		(net "GMI_CPU1_G0_CPU0_G2_TX_DN<5>")
	)
	(segment
		(start 101.589078 -241.589814)
		(end 101.628194 -241.566954)
		(width 0.1143)
		(layer "In6.Cu")
		(net "GMI_CPU1_G0_CPU0_G2_TX_DN<5>")
	)
	(segment
		(start 103.507032 -234.441238)
		(end 103.505508 -234.440222)
		(width 0.1143)
		(layer "In6.Cu")
		(net "GMI_CPU1_G0_CPU0_G2_TX_DN<5>")
	)
	(segment
		(start 103.508048 -226.9871)
		(end 103.50881 -226.986592)
		(width 0.1143)
		(layer "In6.Cu")
		(net "GMI_CPU1_G0_CPU0_G2_TX_DN<5>")
	)
	(segment
		(start 103.507032 -226.987608)
		(end 103.508048 -226.9871)
		(width 0.1143)
		(layer "In6.Cu")
		(net "GMI_CPU1_G0_CPU0_G2_TX_DN<5>")
	)
	(segment
		(start 104.920034 -224.555812)
		(end 104.949752 -224.538794)
		(width 0.1143)
		(layer "In6.Cu")
		(net "GMI_CPU1_G0_CPU0_G2_TX_DN<5>")
	)
	(segment
		(start 369.397788 -238.491522)
		(end 369.366038 -238.50981)
		(width 0.1143)
		(layer "In6.Cu")
		(net "GMI_CPU1_G0_CPU0_G2_TX_DN<5>")
	)
	(segment
		(start 103.539798 -227.98024)
		(end 103.50881 -227.96246)
		(width 0.1143)
		(layer "In6.Cu")
		(net "GMI_CPU1_G0_CPU0_G2_TX_DN<5>")
	)
	(segment
		(start 102.531672 -236.728)
		(end 102.567994 -236.706918)
		(width 0.1143)
		(layer "In6.Cu")
		(net "GMI_CPU1_G0_CPU0_G2_TX_DN<5>")
	)
	(segment
		(start 103.50881 -231.846374)
		(end 103.51008 -231.845612)
		(width 0.1143)
		(layer "In6.Cu")
		(net "GMI_CPU1_G0_CPU0_G2_TX_DN<5>")
	)
	(segment
		(start 320.058034 -187.052458)
		(end 355.525324 -209.343244)
		(width 0.14224)
		(layer "In6.Cu")
		(net "GMI_CPU1_G0_CPU0_G2_TX_DN<5>")
	)
	(segment
		(start 103.508048 -232.821734)
		(end 103.507032 -232.821226)
		(width 0.1143)
		(layer "In6.Cu")
		(net "GMI_CPU1_G0_CPU0_G2_TX_DN<5>")
	)
	(segment
		(start 103.508048 -227.961952)
		(end 103.507032 -227.961444)
		(width 0.1143)
		(layer "In6.Cu")
		(net "GMI_CPU1_G0_CPU0_G2_TX_DN<5>")
	)
	(segment
		(start 367.048796 -225.367342)
		(end 367.05032 -225.368358)
		(width 0.1143)
		(layer "In6.Cu")
		(net "GMI_CPU1_G0_CPU0_G2_TX_DN<5>")
	)
	(segment
		(start 101.157024 -242.377468)
		(end 101.15804 -242.37696)
		(width 0.1143)
		(layer "In6.Cu")
		(net "GMI_CPU1_G0_CPU0_G2_TX_DN<5>")
	)
	(segment
		(start 370.614194 -242.781328)
		(end 370.696998 -242.864132)
		(width 0.1143)
		(layer "In6.Cu")
		(net "GMI_CPU1_G0_CPU0_G2_TX_DN<5>")
	)
	(segment
		(start 104.448102 -225.367088)
		(end 104.44861 -225.367088)
		(width 0.1143)
		(layer "In6.Cu")
		(net "GMI_CPU1_G0_CPU0_G2_TX_DN<5>")
	)
	(segment
		(start 103.507032 -233.467402)
		(end 103.508048 -233.466894)
		(width 0.1143)
		(layer "In6.Cu")
		(net "GMI_CPU1_G0_CPU0_G2_TX_DN<5>")
	)
	(segment
		(start 368.927126 -236.706156)
		(end 368.927888 -236.706664)
		(width 0.1143)
		(layer "In6.Cu")
		(net "GMI_CPU1_G0_CPU0_G2_TX_DN<5>")
	)
	(segment
		(start 366.575848 -224.555558)
		(end 366.577118 -224.55632)
		(width 0.1143)
		(layer "In6.Cu")
		(net "GMI_CPU1_G0_CPU0_G2_TX_DN<5>")
	)
	(segment
		(start 106.516424 -221.804484)
		(end 106.516424 -221.326964)
		(width 0.1143)
		(layer "In6.Cu")
		(net "GMI_CPU1_G0_CPU0_G2_TX_DN<5>")
	)
	(segment
		(start 367.956084 -231.82834)
		(end 367.985802 -231.845358)
		(width 0.1143)
		(layer "In6.Cu")
		(net "GMI_CPU1_G0_CPU0_G2_TX_DN<5>")
	)
	(segment
		(start 103.508048 -230.22687)
		(end 103.539798 -230.208582)
		(width 0.1143)
		(layer "In6.Cu")
		(net "GMI_CPU1_G0_CPU0_G2_TX_DN<5>")
	)
	(segment
		(start 102.098094 -237.516924)
		(end 102.129844 -237.498636)
		(width 0.1143)
		(layer "In6.Cu")
		(net "GMI_CPU1_G0_CPU0_G2_TX_DN<5>")
	)
	(segment
		(start 360.257344 -213.117176)
		(end 364.192058 -217.05189)
		(width 0.14224)
		(layer "In6.Cu")
		(net "GMI_CPU1_G0_CPU0_G2_TX_DN<5>")
	)
	(segment
		(start 103.507032 -227.961444)
		(end 103.505508 -227.960428)
		(width 0.1143)
		(layer "In6.Cu")
		(net "GMI_CPU1_G0_CPU0_G2_TX_DN<5>")
	)
	(segment
		(start 103.541576 -229.601522)
		(end 103.508048 -229.581964)
		(width 0.1143)
		(layer "In6.Cu")
		(net "GMI_CPU1_G0_CPU0_G2_TX_DN<5>")
	)
	(segment
		(start 367.987834 -233.46664)
		(end 367.98885 -233.467148)
		(width 0.1143)
		(layer "In6.Cu")
		(net "GMI_CPU1_G0_CPU0_G2_TX_DN<5>")
	)
	(segment
		(start 103.978202 -226.177094)
		(end 104.008682 -226.159314)
		(width 0.1143)
		(layer "In6.Cu")
		(net "GMI_CPU1_G0_CPU0_G2_TX_DN<5>")
	)
	(segment
		(start 103.507032 -235.087414)
		(end 103.508048 -235.086906)
		(width 0.1143)
		(layer "In6.Cu")
		(net "GMI_CPU1_G0_CPU0_G2_TX_DN<5>")
	)
	(segment
		(start 367.990374 -234.439968)
		(end 367.98885 -234.440984)
		(width 0.1143)
		(layer "In6.Cu")
		(net "GMI_CPU1_G0_CPU0_G2_TX_DN<5>")
	)
	(segment
		(start 367.956084 -233.448352)
		(end 367.985802 -233.46537)
		(width 0.1143)
		(layer "In6.Cu")
		(net "GMI_CPU1_G0_CPU0_G2_TX_DN<5>")
	)
	(segment
		(start 103.50881 -233.466386)
		(end 103.51008 -233.465624)
		(width 0.1143)
		(layer "In6.Cu")
		(net "GMI_CPU1_G0_CPU0_G2_TX_DN<5>")
	)
	(segment
		(start 367.987072 -228.60635)
		(end 367.987834 -228.606858)
		(width 0.1143)
		(layer "In6.Cu")
		(net "GMI_CPU1_G0_CPU0_G2_TX_DN<5>")
	)
	(segment
		(start 369.837208 -241.54892)
		(end 369.906804 -241.58956)
		(width 0.1143)
		(layer "In6.Cu")
		(net "GMI_CPU1_G0_CPU0_G2_TX_DN<5>")
	)
	(segment
		(start 367.956084 -235.068364)
		(end 367.985802 -235.085382)
		(width 0.1143)
		(layer "In6.Cu")
		(net "GMI_CPU1_G0_CPU0_G2_TX_DN<5>")
	)
	(segment
		(start 102.129844 -238.510064)
		(end 102.098094 -238.491776)
		(width 0.1143)
		(layer "In6.Cu")
		(net "GMI_CPU1_G0_CPU0_G2_TX_DN<5>")
	)
	(segment
		(start 369.397788 -240.111534)
		(end 369.366038 -240.129822)
		(width 0.1143)
		(layer "In6.Cu")
		(net "GMI_CPU1_G0_CPU0_G2_TX_DN<5>")
	)
	(segment
		(start 370.337842 -242.376706)
		(end 370.338858 -242.377214)
		(width 0.1143)
		(layer "In6.Cu")
		(net "GMI_CPU1_G0_CPU0_G2_TX_DN<5>")
	)
	(segment
		(start 369.210082 -237.19409)
		(end 369.210082 -237.328202)
		(width 0.1143)
		(layer "In6.Cu")
		(net "GMI_CPU1_G0_CPU0_G2_TX_DN<5>")
	)
	(segment
		(start 367.990374 -233.468164)
		(end 368.02695 -233.4895)
		(width 0.1143)
		(layer "In6.Cu")
		(net "GMI_CPU1_G0_CPU0_G2_TX_DN<5>")
	)
	(segment
		(start 369.397788 -237.51667)
		(end 369.436904 -237.53953)
		(width 0.1143)
		(layer "In6.Cu")
		(net "GMI_CPU1_G0_CPU0_G2_TX_DN<5>")
	)
	(segment
		(start 103.471472 -230.248206)
		(end 103.508048 -230.22687)
		(width 0.1143)
		(layer "In6.Cu")
		(net "GMI_CPU1_G0_CPU0_G2_TX_DN<5>")
	)
	(segment
		(start 369.366038 -237.498382)
		(end 369.397788 -237.51667)
		(width 0.1143)
		(layer "In6.Cu")
		(net "GMI_CPU1_G0_CPU0_G2_TX_DN<5>")
	)
	(segment
		(start 367.987072 -226.986338)
		(end 367.987834 -226.986846)
		(width 0.1143)
		(layer "In6.Cu")
		(net "GMI_CPU1_G0_CPU0_G2_TX_DN<5>")
	)
	(segment
		(start 365.637826 -222.936816)
		(end 365.670592 -222.955612)
		(width 0.1143)
		(layer "In6.Cu")
		(net "GMI_CPU1_G0_CPU0_G2_TX_DN<5>")
	)
	(segment
		(start 364.980982 -221.325694)
		(end 364.979966 -221.32671)
		(width 0.1143)
		(layer "In6.Cu")
		(net "GMI_CPU1_G0_CPU0_G2_TX_DN<5>")
	)
	(segment
		(start 104.408986 -225.389948)
		(end 104.448102 -225.367088)
		(width 0.1143)
		(layer "In6.Cu")
		(net "GMI_CPU1_G0_CPU0_G2_TX_DN<5>")
	)
	(segment
		(start 102.999032 -235.919772)
		(end 103.038148 -235.896912)
		(width 0.1143)
		(layer "In6.Cu")
		(net "GMI_CPU1_G0_CPU0_G2_TX_DN<5>")
	)
	(segment
		(start 106.469688 -219.288106)
		(end 107.874816 -215.89492)
		(width 0.14224)
		(layer "In6.Cu")
		(net "GMI_CPU1_G0_CPU0_G2_TX_DN<5>")
	)
	(segment
		(start 103.50881 -234.442254)
		(end 103.508048 -234.441746)
		(width 0.1143)
		(layer "In6.Cu")
		(net "GMI_CPU1_G0_CPU0_G2_TX_DN<5>")
	)
	(segment
		(start 367.987072 -233.466132)
		(end 367.987834 -233.46664)
		(width 0.1143)
		(layer "In6.Cu")
		(net "GMI_CPU1_G0_CPU0_G2_TX_DN<5>")
	)
	(segment
		(start 103.468932 -231.869742)
		(end 103.507032 -231.84739)
		(width 0.1143)
		(layer "In6.Cu")
		(net "GMI_CPU1_G0_CPU0_G2_TX_DN<5>")
	)
	(segment
		(start 367.990374 -232.819956)
		(end 367.98885 -232.820972)
		(width 0.1143)
		(layer "In6.Cu")
		(net "GMI_CPU1_G0_CPU0_G2_TX_DN<5>")
	)
	(segment
		(start 368.02695 -232.79862)
		(end 367.990374 -232.819956)
		(width 0.1143)
		(layer "In6.Cu")
		(net "GMI_CPU1_G0_CPU0_G2_TX_DN<5>")
	)
	(segment
		(start 365.137192 -222.10903)
		(end 365.206788 -222.14967)
		(width 0.1143)
		(layer "In6.Cu")
		(net "GMI_CPU1_G0_CPU0_G2_TX_DN<5>")
	)
	(segment
		(start 366.074706 -223.727772)
		(end 366.107472 -223.746822)
		(width 0.1143)
		(layer "In6.Cu")
		(net "GMI_CPU1_G0_CPU0_G2_TX_DN<5>")
	)
	(segment
		(start 100.500942 -242.864386)
		(end 100.798884 -242.864386)
		(width 0.1143)
		(layer "In6.Cu")
		(net "GMI_CPU1_G0_CPU0_G2_TX_DN<5>")
	)
	(arc
		(start 103.068628 -235.879132)
		(mid 103.184055 -235.745756)
		(end 103.2256 -235.574332)
		(width 0.1143)
		(layer "In6.Cu")
		(net "GMI_CPU1_G0_CPU0_G2_TX_DN<5>")
	)
	(arc
		(start 368.270282 -230.714296)
		(mid 368.205767 -230.976515)
		(end 368.02695 -231.178862)
		(width 0.1143)
		(layer "In6.Cu")
		(net "GMI_CPU1_G0_CPU0_G2_TX_DN<5>")
	)
	(arc
		(start 367.800128 -229.904036)
		(mid 367.841383 -230.075007)
		(end 367.956084 -230.208328)
		(width 0.1143)
		(layer "In6.Cu")
		(net "GMI_CPU1_G0_CPU0_G2_TX_DN<5>")
	)
	(arc
		(start 368.02695 -228.629718)
		(mid 368.270277 -229.094284)
		(end 368.02695 -229.55885)
		(width 0.1143)
		(layer "In6.Cu")
		(net "GMI_CPU1_G0_CPU0_G2_TX_DN<5>")
	)
	(arc
		(start 103.539798 -235.068618)
		(mid 103.695726 -234.764326)
		(end 103.539798 -234.460034)
		(width 0.1143)
		(layer "In6.Cu")
		(net "GMI_CPU1_G0_CPU0_G2_TX_DN<5>")
	)
	(arc
		(start 100.885498 -242.758722)
		(mid 100.966931 -242.556324)
		(end 101.118924 -242.39982)
		(width 0.1143)
		(layer "In6.Cu")
		(net "GMI_CPU1_G0_CPU0_G2_TX_DN<5>")
	)
	(arc
		(start 367.011458 -225.343974)
		(mid 367.016002 -225.347565)
		(end 367.020602 -225.351086)
		(width 0.1143)
		(layer "In6.Cu")
		(net "GMI_CPU1_G0_CPU0_G2_TX_DN<5>")
	)
	(arc
		(start 100.881688 -242.781582)
		(mid 100.883476 -242.770133)
		(end 100.885498 -242.758722)
		(width 0.1143)
		(layer "In6.Cu")
		(net "GMI_CPU1_G0_CPU0_G2_TX_DN<5>")
	)
	(arc
		(start 368.49685 -235.919518)
		(mid 368.675663 -236.121868)
		(end 368.740182 -236.384084)
		(width 0.1143)
		(layer "In6.Cu")
		(net "GMI_CPU1_G0_CPU0_G2_TX_DN<5>")
	)
	(arc
		(start 104.484424 -225.344228)
		(mid 104.578341 -225.219144)
		(end 104.631236 -225.07194)
		(width 0.1143)
		(layer "In6.Cu")
		(net "GMI_CPU1_G0_CPU0_G2_TX_DN<5>")
	)
	(arc
		(start 103.539798 -233.448606)
		(mid 103.695726 -233.144314)
		(end 103.539798 -232.840022)
		(width 0.1143)
		(layer "In6.Cu")
		(net "GMI_CPU1_G0_CPU0_G2_TX_DN<5>")
	)
	(arc
		(start 102.058978 -240.088928)
		(mid 101.815651 -239.624362)
		(end 102.058978 -239.159796)
		(width 0.1143)
		(layer "In6.Cu")
		(net "GMI_CPU1_G0_CPU0_G2_TX_DN<5>")
	)
	(arc
		(start 103.539798 -230.208582)
		(mid 103.654474 -230.075248)
		(end 103.695754 -229.90429)
		(width 0.1143)
		(layer "In6.Cu")
		(net "GMI_CPU1_G0_CPU0_G2_TX_DN<5>")
	)
	(arc
		(start 102.23881 -237.42015)
		(mid 102.273347 -237.379966)
		(end 102.2858 -237.328456)
		(width 0.1143)
		(layer "In6.Cu")
		(net "GMI_CPU1_G0_CPU0_G2_TX_DN<5>")
	)
	(arc
		(start 365.919512 -223.424242)
		(mid 365.960562 -223.594692)
		(end 366.074706 -223.727772)
		(width 0.1143)
		(layer "In6.Cu")
		(net "GMI_CPU1_G0_CPU0_G2_TX_DN<5>")
	)
	(arc
		(start 367.956084 -234.45978)
		(mid 367.800156 -234.764072)
		(end 367.956084 -235.068364)
		(width 0.1143)
		(layer "In6.Cu")
		(net "GMI_CPU1_G0_CPU0_G2_TX_DN<5>")
	)
	(arc
		(start 103.539798 -228.588824)
		(mid 103.695726 -228.284532)
		(end 103.539798 -227.98024)
		(width 0.1143)
		(layer "In6.Cu")
		(net "GMI_CPU1_G0_CPU0_G2_TX_DN<5>")
	)
	(arc
		(start 102.129844 -240.73866)
		(mid 102.281433 -240.434368)
		(end 102.129844 -240.130076)
		(width 0.1143)
		(layer "In6.Cu")
		(net "GMI_CPU1_G0_CPU0_G2_TX_DN<5>")
	)
	(arc
		(start 369.680236 -241.24412)
		(mid 369.721785 -241.415542)
		(end 369.837208 -241.54892)
		(width 0.1143)
		(layer "In6.Cu")
		(net "GMI_CPU1_G0_CPU0_G2_TX_DN<5>")
	)
	(arc
		(start 368.740182 -236.384084)
		(mid 368.781437 -236.555055)
		(end 368.896138 -236.688376)
		(width 0.1143)
		(layer "In6.Cu")
		(net "GMI_CPU1_G0_CPU0_G2_TX_DN<5>")
	)
	(arc
		(start 370.376958 -242.399566)
		(mid 370.528945 -242.556074)
		(end 370.610384 -242.758468)
		(width 0.1143)
		(layer "In6.Cu")
		(net "GMI_CPU1_G0_CPU0_G2_TX_DN<5>")
	)
	(arc
		(start 101.815646 -241.244374)
		(mid 101.880161 -240.982155)
		(end 102.058978 -240.779808)
		(width 0.1143)
		(layer "In6.Cu")
		(net "GMI_CPU1_G0_CPU0_G2_TX_DN<5>")
	)
	(arc
		(start 103.468932 -231.179116)
		(mid 103.290119 -230.976766)
		(end 103.2256 -230.71455)
		(width 0.1143)
		(layer "In6.Cu")
		(net "GMI_CPU1_G0_CPU0_G2_TX_DN<5>")
	)
	(arc
		(start 102.058978 -238.468916)
		(mid 101.815651 -238.00435)
		(end 102.058978 -237.539784)
		(width 0.1143)
		(layer "In6.Cu")
		(net "GMI_CPU1_G0_CPU0_G2_TX_DN<5>")
	)
	(arc
		(start 368.270282 -235.574078)
		(mid 368.311831 -235.7455)
		(end 368.427254 -235.878878)
		(width 0.1143)
		(layer "In6.Cu")
		(net "GMI_CPU1_G0_CPU0_G2_TX_DN<5>")
	)
	(arc
		(start 364.979966 -221.80423)
		(mid 365.013452 -221.958744)
		(end 365.107728 -222.085662)
		(width 0.1143)
		(layer "In6.Cu")
		(net "GMI_CPU1_G0_CPU0_G2_TX_DN<5>")
	)
	(arc
		(start 366.147858 -223.770444)
		(mid 366.325923 -223.972621)
		(end 366.390174 -224.234248)
		(width 0.1143)
		(layer "In6.Cu")
		(net "GMI_CPU1_G0_CPU0_G2_TX_DN<5>")
	)
	(arc
		(start 102.2858 -237.194344)
		(mid 102.351036 -236.930753)
		(end 102.531672 -236.728)
		(width 0.1143)
		(layer "In6.Cu")
		(net "GMI_CPU1_G0_CPU0_G2_TX_DN<5>")
	)
	(arc
		(start 365.67491 -222.95866)
		(mid 365.854639 -223.16128)
		(end 365.919512 -223.424242)
		(width 0.1143)
		(layer "In6.Cu")
		(net "GMI_CPU1_G0_CPU0_G2_TX_DN<5>")
	)
	(arc
		(start 365.107728 -222.085662)
		(mid 365.122163 -222.097721)
		(end 365.137192 -222.10903)
		(width 0.1143)
		(layer "In6.Cu")
		(net "GMI_CPU1_G0_CPU0_G2_TX_DN<5>")
	)
	(arc
		(start 368.96421 -236.727746)
		(mid 369.144862 -236.930491)
		(end 369.210082 -237.19409)
		(width 0.1143)
		(layer "In6.Cu")
		(net "GMI_CPU1_G0_CPU0_G2_TX_DN<5>")
	)
	(arc
		(start 105.57637 -223.424496)
		(mid 105.641242 -223.161533)
		(end 105.820972 -222.958914)
		(width 0.1143)
		(layer "In6.Cu")
		(net "GMI_CPU1_G0_CPU0_G2_TX_DN<5>")
	)
	(arc
		(start 368.02695 -227.009706)
		(mid 368.270277 -227.474272)
		(end 368.02695 -227.938838)
		(width 0.1143)
		(layer "In6.Cu")
		(net "GMI_CPU1_G0_CPU0_G2_TX_DN<5>")
	)
	(arc
		(start 367.086896 -225.389694)
		(mid 367.265709 -225.592044)
		(end 367.330228 -225.85426)
		(width 0.1143)
		(layer "In6.Cu")
		(net "GMI_CPU1_G0_CPU0_G2_TX_DN<5>")
	)
	(arc
		(start 103.2256 -230.71455)
		(mid 103.290836 -230.450959)
		(end 103.471472 -230.248206)
		(width 0.1143)
		(layer "In6.Cu")
		(net "GMI_CPU1_G0_CPU0_G2_TX_DN<5>")
	)
	(arc
		(start 103.468932 -232.798874)
		(mid 103.225605 -232.334308)
		(end 103.468932 -231.869742)
		(width 0.1143)
		(layer "In6.Cu")
		(net "GMI_CPU1_G0_CPU0_G2_TX_DN<5>")
	)
	(arc
		(start 367.954306 -231.22128)
		(mid 367.840899 -231.354169)
		(end 367.800128 -231.524048)
		(width 0.1143)
		(layer "In6.Cu")
		(net "GMI_CPU1_G0_CPU0_G2_TX_DN<5>")
	)
	(arc
		(start 367.330228 -225.85426)
		(mid 367.371777 -226.025682)
		(end 367.4872 -226.15906)
		(width 0.1143)
		(layer "In6.Cu")
		(net "GMI_CPU1_G0_CPU0_G2_TX_DN<5>")
	)
	(arc
		(start 365.206788 -222.14967)
		(mid 365.385601 -222.35202)
		(end 365.45012 -222.614236)
		(width 0.1143)
		(layer "In6.Cu")
		(net "GMI_CPU1_G0_CPU0_G2_TX_DN<5>")
	)
	(arc
		(start 101.345746 -242.05438)
		(mid 101.410261 -241.792161)
		(end 101.589078 -241.589814)
		(width 0.1143)
		(layer "In6.Cu")
		(net "GMI_CPU1_G0_CPU0_G2_TX_DN<5>")
	)
	(arc
		(start 102.599744 -236.68863)
		(mid 102.71442 -236.555296)
		(end 102.7557 -236.384338)
		(width 0.1143)
		(layer "In6.Cu")
		(net "GMI_CPU1_G0_CPU0_G2_TX_DN<5>")
	)
	(arc
		(start 367.956084 -227.979986)
		(mid 367.800156 -228.284278)
		(end 367.956084 -228.58857)
		(width 0.1143)
		(layer "In6.Cu")
		(net "GMI_CPU1_G0_CPU0_G2_TX_DN<5>")
	)
	(arc
		(start 102.129844 -239.118648)
		(mid 102.281433 -238.814356)
		(end 102.129844 -238.510064)
		(width 0.1143)
		(layer "In6.Cu")
		(net "GMI_CPU1_G0_CPU0_G2_TX_DN<5>")
	)
	(arc
		(start 103.468932 -234.418886)
		(mid 103.225605 -233.95432)
		(end 103.468932 -233.489754)
		(width 0.1143)
		(layer "In6.Cu")
		(net "GMI_CPU1_G0_CPU0_G2_TX_DN<5>")
	)
	(arc
		(start 103.468932 -229.559104)
		(mid 103.225605 -229.094538)
		(end 103.468932 -228.629972)
		(width 0.1143)
		(layer "In6.Cu")
		(net "GMI_CPU1_G0_CPU0_G2_TX_DN<5>")
	)
	(arc
		(start 368.02695 -235.109512)
		(mid 368.205763 -235.311862)
		(end 368.270282 -235.574078)
		(width 0.1143)
		(layer "In6.Cu")
		(net "GMI_CPU1_G0_CPU0_G2_TX_DN<5>")
	)
	(arc
		(start 103.695754 -229.90429)
		(mid 103.654992 -229.734406)
		(end 103.541576 -229.601522)
		(width 0.1143)
		(layer "In6.Cu")
		(net "GMI_CPU1_G0_CPU0_G2_TX_DN<5>")
	)
	(arc
		(start 104.949752 -224.538794)
		(mid 105.064428 -224.40546)
		(end 105.105708 -224.234502)
		(width 0.1143)
		(layer "In6.Cu")
		(net "GMI_CPU1_G0_CPU0_G2_TX_DN<5>")
	)
	(arc
		(start 369.436904 -240.779554)
		(mid 369.615717 -240.981904)
		(end 369.680236 -241.24412)
		(width 0.1143)
		(layer "In6.Cu")
		(net "GMI_CPU1_G0_CPU0_G2_TX_DN<5>")
	)
	(arc
		(start 368.02695 -233.4895)
		(mid 368.270277 -233.954066)
		(end 368.02695 -234.418632)
		(width 0.1143)
		(layer "In6.Cu")
		(net "GMI_CPU1_G0_CPU0_G2_TX_DN<5>")
	)
	(arc
		(start 104.635808 -225.028252)
		(mid 104.704769 -224.773721)
		(end 104.88168 -224.578164)
		(width 0.1143)
		(layer "In6.Cu")
		(net "GMI_CPU1_G0_CPU0_G2_TX_DN<5>")
	)
	(arc
		(start 103.695754 -231.524302)
		(mid 103.654992 -231.354418)
		(end 103.541576 -231.221534)
		(width 0.1143)
		(layer "In6.Cu")
		(net "GMI_CPU1_G0_CPU0_G2_TX_DN<5>")
	)
	(arc
		(start 366.864646 -225.071686)
		(mid 366.91753 -225.218896)
		(end 367.011458 -225.343974)
		(width 0.1143)
		(layer "In6.Cu")
		(net "GMI_CPU1_G0_CPU0_G2_TX_DN<5>")
	)
	(arc
		(start 368.02441 -230.247952)
		(mid 368.205062 -230.450697)
		(end 368.270282 -230.714296)
		(width 0.1143)
		(layer "In6.Cu")
		(net "GMI_CPU1_G0_CPU0_G2_TX_DN<5>")
	)
	(arc
		(start 366.614202 -224.57791)
		(mid 366.791102 -224.773473)
		(end 366.860074 -225.027998)
		(width 0.1143)
		(layer "In6.Cu")
		(net "GMI_CPU1_G0_CPU0_G2_TX_DN<5>")
	)
	(arc
		(start 369.436904 -237.53953)
		(mid 369.680231 -238.004096)
		(end 369.436904 -238.468662)
		(width 0.1143)
		(layer "In6.Cu")
		(net "GMI_CPU1_G0_CPU0_G2_TX_DN<5>")
	)
	(arc
		(start 367.800128 -226.664266)
		(mid 367.841383 -226.835237)
		(end 367.956084 -226.968558)
		(width 0.1143)
		(layer "In6.Cu")
		(net "GMI_CPU1_G0_CPU0_G2_TX_DN<5>")
	)
	(arc
		(start 369.366038 -238.50981)
		(mid 369.214449 -238.814102)
		(end 369.366038 -239.118394)
		(width 0.1143)
		(layer "In6.Cu")
		(net "GMI_CPU1_G0_CPU0_G2_TX_DN<5>")
	)
	(arc
		(start 104.165654 -225.854514)
		(mid 104.230169 -225.592295)
		(end 104.408986 -225.389948)
		(width 0.1143)
		(layer "In6.Cu")
		(net "GMI_CPU1_G0_CPU0_G2_TX_DN<5>")
	)
	(arc
		(start 101.18979 -242.358672)
		(mid 101.304466 -242.225338)
		(end 101.345746 -242.05438)
		(width 0.1143)
		(layer "In6.Cu")
		(net "GMI_CPU1_G0_CPU0_G2_TX_DN<5>")
	)
	(arc
		(start 369.210082 -237.328202)
		(mid 369.222508 -237.379725)
		(end 369.257072 -237.419896)
		(width 0.1143)
		(layer "In6.Cu")
		(net "GMI_CPU1_G0_CPU0_G2_TX_DN<5>")
	)
	(arc
		(start 102.7557 -236.384338)
		(mid 102.820215 -236.122119)
		(end 102.999032 -235.919772)
		(width 0.1143)
		(layer "In6.Cu")
		(net "GMI_CPU1_G0_CPU0_G2_TX_DN<5>")
	)
	(arc
		(start 106.356404 -222.111316)
		(mid 106.474027 -221.977514)
		(end 106.516424 -221.804484)
		(width 0.1143)
		(layer "In6.Cu")
		(net "GMI_CPU1_G0_CPU0_G2_TX_DN<5>")
	)
	(arc
		(start 369.436904 -239.159542)
		(mid 369.680231 -239.624108)
		(end 369.436904 -240.088674)
		(width 0.1143)
		(layer "In6.Cu")
		(net "GMI_CPU1_G0_CPU0_G2_TX_DN<5>")
	)
	(arc
		(start 105.892346 -222.917512)
		(mid 106.029422 -222.780126)
		(end 106.079544 -222.592646)
		(width 0.1143)
		(layer "In6.Cu")
		(net "GMI_CPU1_G0_CPU0_G2_TX_DN<5>")
	)
	(arc
		(start 101.658674 -241.549174)
		(mid 101.774101 -241.415798)
		(end 101.815646 -241.244374)
		(width 0.1143)
		(layer "In6.Cu")
		(net "GMI_CPU1_G0_CPU0_G2_TX_DN<5>")
	)
	(arc
		(start 368.02695 -231.869488)
		(mid 368.270277 -232.334054)
		(end 368.02695 -232.79862)
		(width 0.1143)
		(layer "In6.Cu")
		(net "GMI_CPU1_G0_CPU0_G2_TX_DN<5>")
	)
	(arc
		(start 367.800128 -231.524048)
		(mid 367.841383 -231.695019)
		(end 367.956084 -231.82834)
		(width 0.1143)
		(layer "In6.Cu")
		(net "GMI_CPU1_G0_CPU0_G2_TX_DN<5>")
	)
	(arc
		(start 103.539798 -226.968812)
		(mid 103.654474 -226.835478)
		(end 103.695754 -226.66452)
		(width 0.1143)
		(layer "In6.Cu")
		(net "GMI_CPU1_G0_CPU0_G2_TX_DN<5>")
	)
	(arc
		(start 104.631236 -225.07194)
		(mid 104.634421 -225.050318)
		(end 104.635808 -225.028506)
		(width 0.1143)
		(layer "In6.Cu")
		(net "GMI_CPU1_G0_CPU0_G2_TX_DN<5>")
	)
	(arc
		(start 104.008682 -226.159314)
		(mid 104.124109 -226.025938)
		(end 104.165654 -225.854514)
		(width 0.1143)
		(layer "In6.Cu")
		(net "GMI_CPU1_G0_CPU0_G2_TX_DN<5>")
	)
	(arc
		(start 104.47528 -225.35134)
		(mid 104.47988 -225.347819)
		(end 104.484424 -225.344228)
		(width 0.1143)
		(layer "In6.Cu")
		(net "GMI_CPU1_G0_CPU0_G2_TX_DN<5>")
	)
	(arc
		(start 103.539798 -231.828594)
		(mid 103.654474 -231.69526)
		(end 103.695754 -231.524302)
		(width 0.1143)
		(layer "In6.Cu")
		(net "GMI_CPU1_G0_CPU0_G2_TX_DN<5>")
	)
	(arc
		(start 370.610384 -242.758468)
		(mid 370.612407 -242.769878)
		(end 370.614194 -242.781328)
		(width 0.1143)
		(layer "In6.Cu")
		(net "GMI_CPU1_G0_CPU0_G2_TX_DN<5>")
	)
	(arc
		(start 365.45012 -222.614236)
		(mid 365.491375 -222.785207)
		(end 365.606076 -222.918528)
		(width 0.1143)
		(layer "In6.Cu")
		(net "GMI_CPU1_G0_CPU0_G2_TX_DN<5>")
	)
	(arc
		(start 106.079544 -222.591122)
		(mid 106.153579 -222.314386)
		(end 106.355896 -222.11157)
		(width 0.1143)
		(layer "In6.Cu")
		(net "GMI_CPU1_G0_CPU0_G2_TX_DN<5>")
	)
	(arc
		(start 366.860074 -225.028252)
		(mid 366.861449 -225.050065)
		(end 366.864646 -225.071686)
		(width 0.1143)
		(layer "In6.Cu")
		(net "GMI_CPU1_G0_CPU0_G2_TX_DN<5>")
	)
	(arc
		(start 367.954306 -229.601268)
		(mid 367.840899 -229.734157)
		(end 367.800128 -229.904036)
		(width 0.1143)
		(layer "In6.Cu")
		(net "GMI_CPU1_G0_CPU0_G2_TX_DN<5>")
	)
	(arc
		(start 367.956084 -232.839768)
		(mid 367.800156 -233.14406)
		(end 367.956084 -233.448352)
		(width 0.1143)
		(layer "In6.Cu")
		(net "GMI_CPU1_G0_CPU0_G2_TX_DN<5>")
	)
	(arc
		(start 366.390174 -224.234248)
		(mid 366.431429 -224.405219)
		(end 366.54613 -224.53854)
		(width 0.1143)
		(layer "In6.Cu")
		(net "GMI_CPU1_G0_CPU0_G2_TX_DN<5>")
	)
	(arc
		(start 103.2256 -235.574332)
		(mid 103.290115 -235.312113)
		(end 103.468932 -235.109766)
		(width 0.1143)
		(layer "In6.Cu")
		(net "GMI_CPU1_G0_CPU0_G2_TX_DN<5>")
	)
	(arc
		(start 370.150136 -242.054126)
		(mid 370.191391 -242.225097)
		(end 370.306092 -242.358418)
		(width 0.1143)
		(layer "In6.Cu")
		(net "GMI_CPU1_G0_CPU0_G2_TX_DN<5>")
	)
	(arc
		(start 369.366038 -240.129822)
		(mid 369.214449 -240.434114)
		(end 369.366038 -240.738406)
		(width 0.1143)
		(layer "In6.Cu")
		(net "GMI_CPU1_G0_CPU0_G2_TX_DN<5>")
	)
	(arc
		(start 369.906804 -241.58956)
		(mid 370.085617 -241.79191)
		(end 370.150136 -242.054126)
		(width 0.1143)
		(layer "In6.Cu")
		(net "GMI_CPU1_G0_CPU0_G2_TX_DN<5>")
	)
	(arc
		(start 105.105708 -224.234502)
		(mid 105.170001 -223.972897)
		(end 105.348024 -223.770698)
		(width 0.1143)
		(layer "In6.Cu")
		(net "GMI_CPU1_G0_CPU0_G2_TX_DN<5>")
	)
	(arc
		(start 103.695754 -226.66452)
		(mid 103.760269 -226.402301)
		(end 103.939086 -226.199954)
		(width 0.1143)
		(layer "In6.Cu")
		(net "GMI_CPU1_G0_CPU0_G2_TX_DN<5>")
	)
	(arc
		(start 103.468932 -227.939092)
		(mid 103.225605 -227.474526)
		(end 103.468932 -227.00996)
		(width 0.1143)
		(layer "In6.Cu")
		(net "GMI_CPU1_G0_CPU0_G2_TX_DN<5>")
	)
	(arc
		(start 105.421176 -223.728026)
		(mid 105.535329 -223.59495)
		(end 105.57637 -223.424496)
		(width 0.1143)
		(layer "In6.Cu")
		(net "GMI_CPU1_G0_CPU0_G2_TX_DN<5>")
	)
	(arc
		(start 367.556796 -226.1997)
		(mid 367.735609 -226.40205)
		(end 367.800128 -226.664266)
		(width 0.1143)
		(layer "In6.Cu")
		(net "GMI_CPU1_G0_CPU0_G2_TX_DN<5>")
	)
	(segment
		(start 100.967794 -239.8903)
		(end 100.500942 -239.624362)
		(width 0.12954)
		(layer "F.Cu")
		(net "GMI_CPU1_G0_CPU0_G2_TX_DN<4>")
	)
	(segment
		(start 370.527834 -239.890046)
		(end 370.994686 -239.624108)
		(width 0.12954)
		(layer "F.Cu")
		(net "GMI_CPU1_G0_CPU0_G2_TX_DN<4>")
	)
	(segment
		(start 368.927888 -227.961698)
		(end 368.927126 -227.962206)
		(width 0.1143)
		(layer "In6.Cu")
		(net "GMI_CPU1_G0_CPU0_G2_TX_DN<4>")
	)
	(segment
		(start 102.60076 -229.601014)
		(end 102.567994 -229.581964)
		(width 0.1143)
		(layer "In6.Cu")
		(net "GMI_CPU1_G0_CPU0_G2_TX_DN<4>")
	)
	(segment
		(start 101.118924 -239.159796)
		(end 101.15804 -239.136936)
		(width 0.1143)
		(layer "In6.Cu")
		(net "GMI_CPU1_G0_CPU0_G2_TX_DN<4>")
	)
	(segment
		(start 367.987834 -225.366834)
		(end 367.98885 -225.367342)
		(width 0.1143)
		(layer "In6.Cu")
		(net "GMI_CPU1_G0_CPU0_G2_TX_DN<4>")
	)
	(segment
		(start 365.966248 -221.09303)
		(end 365.920528 -221.13875)
		(width 0.1143)
		(layer "In6.Cu")
		(net "GMI_CPU1_G0_CPU0_G2_TX_DN<4>")
	)
	(segment
		(start 101.154484 -238.489744)
		(end 101.151944 -238.48822)
		(width 0.1143)
		(layer "In6.Cu")
		(net "GMI_CPU1_G0_CPU0_G2_TX_DN<4>")
	)
	(segment
		(start 105.575862 -221.804484)
		(end 105.575862 -221.326456)
		(width 0.1143)
		(layer "In6.Cu")
		(net "GMI_CPU1_G0_CPU0_G2_TX_DN<4>")
	)
	(segment
		(start 368.96421 -234.42041)
		(end 368.927888 -234.441492)
		(width 0.1143)
		(layer "In6.Cu")
		(net "GMI_CPU1_G0_CPU0_G2_TX_DN<4>")
	)
	(segment
		(start 102.599744 -234.460034)
		(end 102.568756 -234.442254)
		(width 0.1143)
		(layer "In6.Cu")
		(net "GMI_CPU1_G0_CPU0_G2_TX_DN<4>")
	)
	(segment
		(start 102.567994 -231.846882)
		(end 102.568756 -231.846374)
		(width 0.1143)
		(layer "In6.Cu")
		(net "GMI_CPU1_G0_CPU0_G2_TX_DN<4>")
	)
	(segment
		(start 368.927126 -232.821988)
		(end 368.925856 -232.82275)
		(width 0.1143)
		(layer "In6.Cu")
		(net "GMI_CPU1_G0_CPU0_G2_TX_DN<4>")
	)
	(segment
		(start 102.529132 -230.24973)
		(end 102.58425 -230.217726)
		(width 0.1143)
		(layer "In6.Cu")
		(net "GMI_CPU1_G0_CPU0_G2_TX_DN<4>")
	)
	(segment
		(start 104.879902 -222.958914)
		(end 104.917748 -222.93707)
		(width 0.1143)
		(layer "In6.Cu")
		(net "GMI_CPU1_G0_CPU0_G2_TX_DN<4>")
	)
	(segment
		(start 368.911632 -230.217472)
		(end 368.96675 -230.249476)
		(width 0.1143)
		(layer "In6.Cu")
		(net "GMI_CPU1_G0_CPU0_G2_TX_DN<4>")
	)
	(segment
		(start 367.98885 -225.367342)
		(end 367.990374 -225.368358)
		(width 0.1143)
		(layer "In6.Cu")
		(net "GMI_CPU1_G0_CPU0_G2_TX_DN<4>")
	)
	(segment
		(start 368.925856 -231.845358)
		(end 368.927126 -231.84612)
		(width 0.1143)
		(layer "In6.Cu")
		(net "GMI_CPU1_G0_CPU0_G2_TX_DN<4>")
	)
	(segment
		(start 368.925856 -226.985576)
		(end 368.927126 -226.986338)
		(width 0.1143)
		(layer "In6.Cu")
		(net "GMI_CPU1_G0_CPU0_G2_TX_DN<4>")
	)
	(segment
		(start 102.568756 -231.846374)
		(end 102.570026 -231.845612)
		(width 0.1143)
		(layer "In6.Cu")
		(net "GMI_CPU1_G0_CPU0_G2_TX_DN<4>")
	)
	(segment
		(start 101.151944 -238.48822)
		(end 101.15042 -238.487204)
		(width 0.1143)
		(layer "In6.Cu")
		(net "GMI_CPU1_G0_CPU0_G2_TX_DN<4>")
	)
	(segment
		(start 106.843576 -215.591136)
		(end 114.922046 -207.512412)
		(width 0.14224)
		(layer "In6.Cu")
		(net "GMI_CPU1_G0_CPU0_G2_TX_DN<4>")
	)
	(segment
		(start 115.339622 -207.192118)
		(end 115.339368 -207.192118)
		(width 0.14224)
		(layer "In6.Cu")
		(net "GMI_CPU1_G0_CPU0_G2_TX_DN<4>")
	)
	(segment
		(start 370.340382 -238.489998)
		(end 370.338858 -238.491014)
		(width 0.1143)
		(layer "In6.Cu")
		(net "GMI_CPU1_G0_CPU0_G2_TX_DN<4>")
	)
	(segment
		(start 368.927126 -228.60635)
		(end 368.927888 -228.606858)
		(width 0.1143)
		(layer "In6.Cu")
		(net "GMI_CPU1_G0_CPU0_G2_TX_DN<4>")
	)
	(segment
		(start 370.338858 -239.13719)
		(end 370.340382 -239.138206)
		(width 0.1143)
		(layer "In6.Cu")
		(net "GMI_CPU1_G0_CPU0_G2_TX_DN<4>")
	)
	(segment
		(start 368.96675 -230.249476)
		(end 368.98707 -230.263954)
		(width 0.1143)
		(layer "In6.Cu")
		(net "GMI_CPU1_G0_CPU0_G2_TX_DN<4>")
	)
	(segment
		(start 367.987072 -225.366326)
		(end 367.987834 -225.366834)
		(width 0.1143)
		(layer "In6.Cu")
		(net "GMI_CPU1_G0_CPU0_G2_TX_DN<4>")
	)
	(segment
		(start 368.96421 -227.940616)
		(end 368.927888 -227.961698)
		(width 0.1143)
		(layer "In6.Cu")
		(net "GMI_CPU1_G0_CPU0_G2_TX_DN<4>")
	)
	(segment
		(start 102.599744 -232.840022)
		(end 102.568756 -232.822242)
		(width 0.1143)
		(layer "In6.Cu")
		(net "GMI_CPU1_G0_CPU0_G2_TX_DN<4>")
	)
	(segment
		(start 102.568756 -233.466386)
		(end 102.570026 -233.465624)
		(width 0.1143)
		(layer "In6.Cu")
		(net "GMI_CPU1_G0_CPU0_G2_TX_DN<4>")
	)
	(segment
		(start 102.531672 -227.008182)
		(end 102.567994 -226.9871)
		(width 0.1143)
		(layer "In6.Cu")
		(net "GMI_CPU1_G0_CPU0_G2_TX_DN<4>")
	)
	(segment
		(start 102.570026 -235.085636)
		(end 102.599744 -235.068618)
		(width 0.1143)
		(layer "In6.Cu")
		(net "GMI_CPU1_G0_CPU0_G2_TX_DN<4>")
	)
	(segment
		(start 104.917748 -222.93707)
		(end 104.950514 -222.91802)
		(width 0.1143)
		(layer "In6.Cu")
		(net "GMI_CPU1_G0_CPU0_G2_TX_DN<4>")
	)
	(segment
		(start 101.158802 -239.136428)
		(end 101.160072 -239.135666)
		(width 0.1143)
		(layer "In6.Cu")
		(net "GMI_CPU1_G0_CPU0_G2_TX_DN<4>")
	)
	(segment
		(start 102.567994 -234.441746)
		(end 102.531672 -234.420664)
		(width 0.1143)
		(layer "In6.Cu")
		(net "GMI_CPU1_G0_CPU0_G2_TX_DN<4>")
	)
	(segment
		(start 102.2858 -230.71455)
		(end 102.2858 -230.69931)
		(width 0.1143)
		(layer "In6.Cu")
		(net "GMI_CPU1_G0_CPU0_G2_TX_DN<4>")
	)
	(segment
		(start 367.048034 -223.746822)
		(end 367.085626 -223.768666)
		(width 0.1143)
		(layer "In6.Cu")
		(net "GMI_CPU1_G0_CPU0_G2_TX_DN<4>")
	)
	(segment
		(start 103.468932 -225.389948)
		(end 103.508048 -225.367088)
		(width 0.1143)
		(layer "In6.Cu")
		(net "GMI_CPU1_G0_CPU0_G2_TX_DN<4>")
	)
	(segment
		(start 368.925856 -235.085382)
		(end 368.927126 -235.086144)
		(width 0.1143)
		(layer "In6.Cu")
		(net "GMI_CPU1_G0_CPU0_G2_TX_DN<4>")
	)
	(segment
		(start 367.4872 -224.539048)
		(end 367.556796 -224.579688)
		(width 0.1143)
		(layer "In6.Cu")
		(net "GMI_CPU1_G0_CPU0_G2_TX_DN<4>")
	)
	(segment
		(start 102.567994 -232.821734)
		(end 102.531672 -232.800652)
		(width 0.1143)
		(layer "In6.Cu")
		(net "GMI_CPU1_G0_CPU0_G2_TX_DN<4>")
	)
	(segment
		(start 105.529634 -218.763342)
		(end 106.843576 -215.591136)
		(width 0.14224)
		(layer "In6.Cu")
		(net "GMI_CPU1_G0_CPU0_G2_TX_DN<4>")
	)
	(segment
		(start 368.896138 -230.208328)
		(end 368.9096 -230.215948)
		(width 0.1143)
		(layer "In6.Cu")
		(net "GMI_CPU1_G0_CPU0_G2_TX_DN<4>")
	)
	(segment
		(start 104.447848 -223.747076)
		(end 104.478328 -223.729296)
		(width 0.1143)
		(layer "In6.Cu")
		(net "GMI_CPU1_G0_CPU0_G2_TX_DN<4>")
	)
	(segment
		(start 105.529634 -221.064836)
		(end 105.529634 -218.763342)
		(width 0.14224)
		(layer "In6.Cu")
		(net "GMI_CPU1_G0_CPU0_G2_TX_DN<4>")
	)
	(segment
		(start 103.939086 -224.579942)
		(end 103.978202 -224.557082)
		(width 0.1143)
		(layer "In6.Cu")
		(net "GMI_CPU1_G0_CPU0_G2_TX_DN<4>")
	)
	(segment
		(start 102.568756 -235.086398)
		(end 102.570026 -235.085636)
		(width 0.1143)
		(layer "In6.Cu")
		(net "GMI_CPU1_G0_CPU0_G2_TX_DN<4>")
	)
	(segment
		(start 102.58425 -230.217472)
		(end 102.585012 -230.216964)
		(width 0.1143)
		(layer "In6.Cu")
		(net "GMI_CPU1_G0_CPU0_G2_TX_DN<4>")
	)
	(segment
		(start 102.568756 -234.442254)
		(end 102.567994 -234.441746)
		(width 0.1143)
		(layer "In6.Cu")
		(net "GMI_CPU1_G0_CPU0_G2_TX_DN<4>")
	)
	(segment
		(start 302.908208 -178.549808)
		(end 306.952142 -178.549808)
		(width 0.14224)
		(layer "In6.Cu")
		(net "GMI_CPU1_G0_CPU0_G2_TX_DN<4>")
	)
	(segment
		(start 368.925856 -232.82275)
		(end 368.896138 -232.839768)
		(width 0.1143)
		(layer "In6.Cu")
		(net "GMI_CPU1_G0_CPU0_G2_TX_DN<4>")
	)
	(segment
		(start 322.403724 -187.413646)
		(end 356.11689 -208.601818)
		(width 0.14224)
		(layer "In6.Cu")
		(net "GMI_CPU1_G0_CPU0_G2_TX_DN<4>")
	)
	(segment
		(start 306.952142 -178.549808)
		(end 309.538624 -179.259738)
		(width 0.14224)
		(layer "In6.Cu")
		(net "GMI_CPU1_G0_CPU0_G2_TX_DN<4>")
	)
	(segment
		(start 102.531672 -233.487976)
		(end 102.567994 -233.466894)
		(width 0.1143)
		(layer "In6.Cu")
		(net "GMI_CPU1_G0_CPU0_G2_TX_DN<4>")
	)
	(segment
		(start 101.160072 -239.135666)
		(end 101.18979 -239.118648)
		(width 0.1143)
		(layer "In6.Cu")
		(net "GMI_CPU1_G0_CPU0_G2_TX_DN<4>")
	)
	(segment
		(start 367.985802 -225.365564)
		(end 367.987072 -225.366326)
		(width 0.1143)
		(layer "In6.Cu")
		(net "GMI_CPU1_G0_CPU0_G2_TX_DN<4>")
	)
	(segment
		(start 102.585012 -230.216964)
		(end 102.586282 -230.216202)
		(width 0.1143)
		(layer "In6.Cu")
		(net "GMI_CPU1_G0_CPU0_G2_TX_DN<4>")
	)
	(segment
		(start 370.33581 -237.5154)
		(end 370.33708 -237.516162)
		(width 0.1143)
		(layer "In6.Cu")
		(net "GMI_CPU1_G0_CPU0_G2_TX_DN<4>")
	)
	(segment
		(start 367.017554 -223.729042)
		(end 367.048034 -223.746822)
		(width 0.1143)
		(layer "In6.Cu")
		(net "GMI_CPU1_G0_CPU0_G2_TX_DN<4>")
	)
	(segment
		(start 360.806492 -212.341714)
		(end 365.005874 -216.541096)
		(width 0.14224)
		(layer "In6.Cu")
		(net "GMI_CPU1_G0_CPU0_G2_TX_DN<4>")
	)
	(segment
		(start 369.210082 -230.699056)
		(end 369.210082 -230.714296)
		(width 0.1143)
		(layer "In6.Cu")
		(net "GMI_CPU1_G0_CPU0_G2_TX_DN<4>")
	)
	(segment
		(start 102.570026 -226.98583)
		(end 102.599744 -226.968812)
		(width 0.1143)
		(layer "In6.Cu")
		(net "GMI_CPU1_G0_CPU0_G2_TX_DN<4>")
	)
	(segment
		(start 368.927888 -226.986846)
		(end 368.96421 -227.007928)
		(width 0.1143)
		(layer "In6.Cu")
		(net "GMI_CPU1_G0_CPU0_G2_TX_DN<4>")
	)
	(segment
		(start 370.340382 -237.518194)
		(end 370.376958 -237.53953)
		(width 0.1143)
		(layer "In6.Cu")
		(net "GMI_CPU1_G0_CPU0_G2_TX_DN<4>")
	)
	(segment
		(start 102.570026 -231.845612)
		(end 102.599744 -231.828594)
		(width 0.1143)
		(layer "In6.Cu")
		(net "GMI_CPU1_G0_CPU0_G2_TX_DN<4>")
	)
	(segment
		(start 368.91087 -230.21671)
		(end 368.911632 -230.217218)
		(width 0.1143)
		(layer "In6.Cu")
		(net "GMI_CPU1_G0_CPU0_G2_TX_DN<4>")
	)
	(segment
		(start 370.340382 -239.138206)
		(end 370.376958 -239.159542)
		(width 0.1143)
		(layer "In6.Cu")
		(net "GMI_CPU1_G0_CPU0_G2_TX_DN<4>")
	)
	(segment
		(start 102.570026 -228.605842)
		(end 102.599744 -228.588824)
		(width 0.1143)
		(layer "In6.Cu")
		(net "GMI_CPU1_G0_CPU0_G2_TX_DN<4>")
	)
	(segment
		(start 370.33581 -239.135412)
		(end 370.33708 -239.136174)
		(width 0.1143)
		(layer "In6.Cu")
		(net "GMI_CPU1_G0_CPU0_G2_TX_DN<4>")
	)
	(segment
		(start 368.927126 -226.986338)
		(end 368.927888 -226.986846)
		(width 0.1143)
		(layer "In6.Cu")
		(net "GMI_CPU1_G0_CPU0_G2_TX_DN<4>")
	)
	(segment
		(start 101.15804 -238.491776)
		(end 101.157024 -238.491268)
		(width 0.1143)
		(layer "In6.Cu")
		(net "GMI_CPU1_G0_CPU0_G2_TX_DN<4>")
	)
	(segment
		(start 103.978202 -224.557082)
		(end 104.008682 -224.539302)
		(width 0.1143)
		(layer "In6.Cu")
		(net "GMI_CPU1_G0_CPU0_G2_TX_DN<4>")
	)
	(segment
		(start 368.896138 -235.068364)
		(end 368.925856 -235.085382)
		(width 0.1143)
		(layer "In6.Cu")
		(net "GMI_CPU1_G0_CPU0_G2_TX_DN<4>")
	)
	(segment
		(start 102.570026 -233.465624)
		(end 102.599744 -233.448606)
		(width 0.1143)
		(layer "In6.Cu")
		(net "GMI_CPU1_G0_CPU0_G2_TX_DN<4>")
	)
	(segment
		(start 105.575354 -221.139004)
		(end 105.529634 -221.093284)
		(width 0.1143)
		(layer "In6.Cu")
		(net "GMI_CPU1_G0_CPU0_G2_TX_DN<4>")
	)
	(segment
		(start 102.567994 -233.466894)
		(end 102.568756 -233.466386)
		(width 0.1143)
		(layer "In6.Cu")
		(net "GMI_CPU1_G0_CPU0_G2_TX_DN<4>")
	)
	(segment
		(start 370.33708 -237.516162)
		(end 370.337842 -237.51667)
		(width 0.1143)
		(layer "In6.Cu")
		(net "GMI_CPU1_G0_CPU0_G2_TX_DN<4>")
	)
	(segment
		(start 368.927126 -231.84612)
		(end 368.927888 -231.846628)
		(width 0.1143)
		(layer "In6.Cu")
		(net "GMI_CPU1_G0_CPU0_G2_TX_DN<4>")
	)
	(segment
		(start 102.058978 -235.919772)
		(end 102.135686 -235.875322)
		(width 0.1143)
		(layer "In6.Cu")
		(net "GMI_CPU1_G0_CPU0_G2_TX_DN<4>")
	)
	(segment
		(start 119.575834 -203.941426)
		(end 162.913314 -178.916584)
		(width 0.14224)
		(layer "In6.Cu")
		(net "GMI_CPU1_G0_CPU0_G2_TX_DN<4>")
	)
	(segment
		(start 368.927888 -234.441492)
		(end 368.927126 -234.442)
		(width 0.1143)
		(layer "In6.Cu")
		(net "GMI_CPU1_G0_CPU0_G2_TX_DN<4>")
	)
	(segment
		(start 370.696998 -239.624108)
		(end 370.994686 -239.624108)
		(width 0.1143)
		(layer "In6.Cu")
		(net "GMI_CPU1_G0_CPU0_G2_TX_DN<4>")
	)
	(segment
		(start 365.920528 -221.325694)
		(end 365.92002 -221.326202)
		(width 0.1143)
		(layer "In6.Cu")
		(net "GMI_CPU1_G0_CPU0_G2_TX_DN<4>")
	)
	(segment
		(start 321.329304 -186.488832)
		(end 321.329558 -186.489086)
		(width 0.14224)
		(layer "In6.Cu")
		(net "GMI_CPU1_G0_CPU0_G2_TX_DN<4>")
	)
	(segment
		(start 370.306092 -239.118394)
		(end 370.33581 -239.135412)
		(width 0.1143)
		(layer "In6.Cu")
		(net "GMI_CPU1_G0_CPU0_G2_TX_DN<4>")
	)
	(segment
		(start 115.339876 -207.191864)
		(end 119.575834 -203.941426)
		(width 0.14224)
		(layer "In6.Cu")
		(net "GMI_CPU1_G0_CPU0_G2_TX_DN<4>")
	)
	(segment
		(start 167.287448 -177.758344)
		(end 302.908208 -178.549808)
		(width 0.14224)
		(layer "In6.Cu")
		(net "GMI_CPU1_G0_CPU0_G2_TX_DN<4>")
	)
	(segment
		(start 370.343938 -238.487966)
		(end 370.341398 -238.48949)
		(width 0.1143)
		(layer "In6.Cu")
		(net "GMI_CPU1_G0_CPU0_G2_TX_DN<4>")
	)
	(segment
		(start 102.601522 -229.601522)
		(end 102.60076 -229.601014)
		(width 0.1143)
		(layer "In6.Cu")
		(net "GMI_CPU1_G0_CPU0_G2_TX_DN<4>")
	)
	(segment
		(start 368.896138 -233.448352)
		(end 368.925856 -233.46537)
		(width 0.1143)
		(layer "In6.Cu")
		(net "GMI_CPU1_G0_CPU0_G2_TX_DN<4>")
	)
	(segment
		(start 162.913314 -178.916584)
		(end 167.287448 -177.758344)
		(width 0.14224)
		(layer "In6.Cu")
		(net "GMI_CPU1_G0_CPU0_G2_TX_DN<4>")
	)
	(segment
		(start 101.15042 -238.487204)
		(end 101.118924 -238.468916)
		(width 0.1143)
		(layer "In6.Cu")
		(net "GMI_CPU1_G0_CPU0_G2_TX_DN<4>")
	)
	(segment
		(start 368.895122 -229.60076)
		(end 368.89436 -229.601268)
		(width 0.1143)
		(layer "In6.Cu")
		(net "GMI_CPU1_G0_CPU0_G2_TX_DN<4>")
	)
	(segment
		(start 103.50881 -225.36658)
		(end 103.51008 -225.365818)
		(width 0.1143)
		(layer "In6.Cu")
		(net "GMI_CPU1_G0_CPU0_G2_TX_DN<4>")
	)
	(segment
		(start 370.341398 -238.48949)
		(end 370.340382 -238.489998)
		(width 0.1143)
		(layer "In6.Cu")
		(net "GMI_CPU1_G0_CPU0_G2_TX_DN<4>")
	)
	(segment
		(start 368.927888 -231.846628)
		(end 368.96421 -231.86771)
		(width 0.1143)
		(layer "In6.Cu")
		(net "GMI_CPU1_G0_CPU0_G2_TX_DN<4>")
	)
	(segment
		(start 101.160072 -237.515654)
		(end 101.18979 -237.498636)
		(width 0.1143)
		(layer "In6.Cu")
		(net "GMI_CPU1_G0_CPU0_G2_TX_DN<4>")
	)
	(segment
		(start 105.575354 -221.325948)
		(end 105.575354 -221.139004)
		(width 0.1143)
		(layer "In6.Cu")
		(net "GMI_CPU1_G0_CPU0_G2_TX_DN<4>")
	)
	(segment
		(start 102.568756 -227.96246)
		(end 102.567994 -227.961952)
		(width 0.1143)
		(layer "In6.Cu")
		(net "GMI_CPU1_G0_CPU0_G2_TX_DN<4>")
	)
	(segment
		(start 370.337842 -238.491522)
		(end 370.33708 -238.49203)
		(width 0.1143)
		(layer "In6.Cu")
		(net "GMI_CPU1_G0_CPU0_G2_TX_DN<4>")
	)
	(segment
		(start 102.287324 -235.61294)
		(end 102.287324 -235.574332)
		(width 0.1143)
		(layer "In6.Cu")
		(net "GMI_CPU1_G0_CPU0_G2_TX_DN<4>")
	)
	(segment
		(start 368.896138 -231.82834)
		(end 368.925856 -231.845358)
		(width 0.1143)
		(layer "In6.Cu")
		(net "GMI_CPU1_G0_CPU0_G2_TX_DN<4>")
	)
	(segment
		(start 366.07496 -222.10776)
		(end 366.146842 -222.14967)
		(width 0.1143)
		(layer "In6.Cu")
		(net "GMI_CPU1_G0_CPU0_G2_TX_DN<4>")
	)
	(segment
		(start 370.33581 -238.492792)
		(end 370.306092 -238.50981)
		(width 0.1143)
		(layer "In6.Cu")
		(net "GMI_CPU1_G0_CPU0_G2_TX_DN<4>")
	)
	(segment
		(start 101.158802 -238.492284)
		(end 101.15804 -238.491776)
		(width 0.1143)
		(layer "In6.Cu")
		(net "GMI_CPU1_G0_CPU0_G2_TX_DN<4>")
	)
	(segment
		(start 370.306092 -237.498382)
		(end 370.33581 -237.5154)
		(width 0.1143)
		(layer "In6.Cu")
		(net "GMI_CPU1_G0_CPU0_G2_TX_DN<4>")
	)
	(segment
		(start 369.208558 -235.574078)
		(end 369.208558 -235.612686)
		(width 0.1143)
		(layer "In6.Cu")
		(net "GMI_CPU1_G0_CPU0_G2_TX_DN<4>")
	)
	(segment
		(start 105.529634 -221.093284)
		(end 105.529634 -221.064836)
		(width 0.1143)
		(layer "In6.Cu")
		(net "GMI_CPU1_G0_CPU0_G2_TX_DN<4>")
	)
	(segment
		(start 101.18979 -238.510064)
		(end 101.158802 -238.492284)
		(width 0.1143)
		(layer "In6.Cu")
		(net "GMI_CPU1_G0_CPU0_G2_TX_DN<4>")
	)
	(segment
		(start 369.360196 -235.875068)
		(end 369.436904 -235.919518)
		(width 0.1143)
		(layer "In6.Cu")
		(net "GMI_CPU1_G0_CPU0_G2_TX_DN<4>")
	)
	(segment
		(start 366.578134 -222.936816)
		(end 366.61598 -222.95866)
		(width 0.1143)
		(layer "In6.Cu")
		(net "GMI_CPU1_G0_CPU0_G2_TX_DN<4>")
	)
	(segment
		(start 367.956084 -225.348546)
		(end 367.985802 -225.365564)
		(width 0.1143)
		(layer "In6.Cu")
		(net "GMI_CPU1_G0_CPU0_G2_TX_DN<4>")
	)
	(segment
		(start 104.410256 -223.76892)
		(end 104.447848 -223.747076)
		(width 0.1143)
		(layer "In6.Cu")
		(net "GMI_CPU1_G0_CPU0_G2_TX_DN<4>")
	)
	(segment
		(start 114.922046 -207.512412)
		(end 115.339622 -207.192118)
		(width 0.14224)
		(layer "In6.Cu")
		(net "GMI_CPU1_G0_CPU0_G2_TX_DN<4>")
	)
	(segment
		(start 368.427254 -226.15906)
		(end 368.49685 -226.1997)
		(width 0.1143)
		(layer "In6.Cu")
		(net "GMI_CPU1_G0_CPU0_G2_TX_DN<4>")
	)
	(segment
		(start 102.568756 -228.606604)
		(end 102.570026 -228.605842)
		(width 0.1143)
		(layer "In6.Cu")
		(net "GMI_CPU1_G0_CPU0_G2_TX_DN<4>")
	)
	(segment
		(start 321.329558 -186.489086)
		(end 322.403724 -187.413646)
		(width 0.14224)
		(layer "In6.Cu")
		(net "GMI_CPU1_G0_CPU0_G2_TX_DN<4>")
	)
	(segment
		(start 103.038148 -226.177094)
		(end 103.068628 -226.159314)
		(width 0.1143)
		(layer "In6.Cu")
		(net "GMI_CPU1_G0_CPU0_G2_TX_DN<4>")
	)
	(segment
		(start 356.11689 -208.601818)
		(end 360.806492 -212.341714)
		(width 0.14224)
		(layer "In6.Cu")
		(net "GMI_CPU1_G0_CPU0_G2_TX_DN<4>")
	)
	(segment
		(start 102.568756 -232.822242)
		(end 102.567994 -232.821734)
		(width 0.1143)
		(layer "In6.Cu")
		(net "GMI_CPU1_G0_CPU0_G2_TX_DN<4>")
	)
	(segment
		(start 102.567994 -235.086906)
		(end 102.568756 -235.086398)
		(width 0.1143)
		(layer "In6.Cu")
		(net "GMI_CPU1_G0_CPU0_G2_TX_DN<4>")
	)
	(segment
		(start 370.345462 -238.48695)
		(end 370.343938 -238.487966)
		(width 0.1143)
		(layer "In6.Cu")
		(net "GMI_CPU1_G0_CPU0_G2_TX_DN<4>")
	)
	(segment
		(start 370.33708 -238.49203)
		(end 370.33581 -238.492792)
		(width 0.1143)
		(layer "In6.Cu")
		(net "GMI_CPU1_G0_CPU0_G2_TX_DN<4>")
	)
	(segment
		(start 370.338858 -238.491014)
		(end 370.337842 -238.491522)
		(width 0.1143)
		(layer "In6.Cu")
		(net "GMI_CPU1_G0_CPU0_G2_TX_DN<4>")
	)
	(segment
		(start 115.339368 -207.192118)
		(end 115.339876 -207.191864)
		(width 0.14224)
		(layer "In6.Cu")
		(net "GMI_CPU1_G0_CPU0_G2_TX_DN<4>")
	)
	(segment
		(start 102.531672 -231.867964)
		(end 102.567994 -231.846882)
		(width 0.1143)
		(layer "In6.Cu")
		(net "GMI_CPU1_G0_CPU0_G2_TX_DN<4>")
	)
	(segment
		(start 368.927888 -233.46664)
		(end 368.96421 -233.487722)
		(width 0.1143)
		(layer "In6.Cu")
		(net "GMI_CPU1_G0_CPU0_G2_TX_DN<4>")
	)
	(segment
		(start 368.925856 -234.442762)
		(end 368.896138 -234.45978)
		(width 0.1143)
		(layer "In6.Cu")
		(net "GMI_CPU1_G0_CPU0_G2_TX_DN<4>")
	)
	(segment
		(start 102.999032 -226.199954)
		(end 103.038148 -226.177094)
		(width 0.1143)
		(layer "In6.Cu")
		(net "GMI_CPU1_G0_CPU0_G2_TX_DN<4>")
	)
	(segment
		(start 105.34904 -222.149924)
		(end 105.420922 -222.108014)
		(width 0.1143)
		(layer "In6.Cu")
		(net "GMI_CPU1_G0_CPU0_G2_TX_DN<4>")
	)
	(segment
		(start 102.601522 -231.221534)
		(end 102.526846 -231.177592)
		(width 0.1143)
		(layer "In6.Cu")
		(net "GMI_CPU1_G0_CPU0_G2_TX_DN<4>")
	)
	(segment
		(start 368.911632 -230.217218)
		(end 368.911632 -230.217472)
		(width 0.1143)
		(layer "In6.Cu")
		(net "GMI_CPU1_G0_CPU0_G2_TX_DN<4>")
	)
	(segment
		(start 368.927126 -233.466132)
		(end 368.927888 -233.46664)
		(width 0.1143)
		(layer "In6.Cu")
		(net "GMI_CPU1_G0_CPU0_G2_TX_DN<4>")
	)
	(segment
		(start 368.927126 -235.086144)
		(end 368.927888 -235.086652)
		(width 0.1143)
		(layer "In6.Cu")
		(net "GMI_CPU1_G0_CPU0_G2_TX_DN<4>")
	)
	(segment
		(start 368.927888 -232.82148)
		(end 368.927126 -232.821988)
		(width 0.1143)
		(layer "In6.Cu")
		(net "GMI_CPU1_G0_CPU0_G2_TX_DN<4>")
	)
	(segment
		(start 368.9096 -230.215948)
		(end 368.91087 -230.21671)
		(width 0.1143)
		(layer "In6.Cu")
		(net "GMI_CPU1_G0_CPU0_G2_TX_DN<4>")
	)
	(segment
		(start 309.538624 -179.259738)
		(end 320.478912 -185.756804)
		(width 0.14224)
		(layer "In6.Cu")
		(net "GMI_CPU1_G0_CPU0_G2_TX_DN<4>")
	)
	(segment
		(start 100.500942 -239.624362)
		(end 100.798884 -239.624362)
		(width 0.1143)
		(layer "In6.Cu")
		(net "GMI_CPU1_G0_CPU0_G2_TX_DN<4>")
	)
	(segment
		(start 368.927888 -229.58171)
		(end 368.895122 -229.60076)
		(width 0.1143)
		(layer "In6.Cu")
		(net "GMI_CPU1_G0_CPU0_G2_TX_DN<4>")
	)
	(segment
		(start 366.545368 -222.917766)
		(end 366.578134 -222.936816)
		(width 0.1143)
		(layer "In6.Cu")
		(net "GMI_CPU1_G0_CPU0_G2_TX_DN<4>")
	)
	(segment
		(start 370.338858 -237.517178)
		(end 370.340382 -237.518194)
		(width 0.1143)
		(layer "In6.Cu")
		(net "GMI_CPU1_G0_CPU0_G2_TX_DN<4>")
	)
	(segment
		(start 367.990374 -225.368358)
		(end 368.02695 -225.389694)
		(width 0.1143)
		(layer "In6.Cu")
		(net "GMI_CPU1_G0_CPU0_G2_TX_DN<4>")
	)
	(segment
		(start 102.567994 -226.9871)
		(end 102.568756 -226.986592)
		(width 0.1143)
		(layer "In6.Cu")
		(net "GMI_CPU1_G0_CPU0_G2_TX_DN<4>")
	)
	(segment
		(start 370.337842 -239.136682)
		(end 370.338858 -239.13719)
		(width 0.1143)
		(layer "In6.Cu")
		(net "GMI_CPU1_G0_CPU0_G2_TX_DN<4>")
	)
	(segment
		(start 370.337842 -237.51667)
		(end 370.338858 -237.517178)
		(width 0.1143)
		(layer "In6.Cu")
		(net "GMI_CPU1_G0_CPU0_G2_TX_DN<4>")
	)
	(segment
		(start 368.927126 -227.962206)
		(end 368.925856 -227.962968)
		(width 0.1143)
		(layer "In6.Cu")
		(net "GMI_CPU1_G0_CPU0_G2_TX_DN<4>")
	)
	(segment
		(start 370.33708 -239.136174)
		(end 370.337842 -239.136682)
		(width 0.1143)
		(layer "In6.Cu")
		(net "GMI_CPU1_G0_CPU0_G2_TX_DN<4>")
	)
	(segment
		(start 368.925856 -233.46537)
		(end 368.927126 -233.466132)
		(width 0.1143)
		(layer "In6.Cu")
		(net "GMI_CPU1_G0_CPU0_G2_TX_DN<4>")
	)
	(segment
		(start 102.568756 -226.986592)
		(end 102.570026 -226.98583)
		(width 0.1143)
		(layer "In6.Cu")
		(net "GMI_CPU1_G0_CPU0_G2_TX_DN<4>")
	)
	(segment
		(start 370.614194 -239.541304)
		(end 370.696998 -239.624108)
		(width 0.1143)
		(layer "In6.Cu")
		(net "GMI_CPU1_G0_CPU0_G2_TX_DN<4>")
	)
	(segment
		(start 102.567994 -228.607112)
		(end 102.568756 -228.606604)
		(width 0.1143)
		(layer "In6.Cu")
		(net "GMI_CPU1_G0_CPU0_G2_TX_DN<4>")
	)
	(segment
		(start 101.15804 -239.136936)
		(end 101.158802 -239.136428)
		(width 0.1143)
		(layer "In6.Cu")
		(net "GMI_CPU1_G0_CPU0_G2_TX_DN<4>")
	)
	(segment
		(start 365.920528 -221.13875)
		(end 365.920528 -221.325694)
		(width 0.1143)
		(layer "In6.Cu")
		(net "GMI_CPU1_G0_CPU0_G2_TX_DN<4>")
	)
	(segment
		(start 320.478912 -185.756804)
		(end 321.329304 -186.488832)
		(width 0.14224)
		(layer "In6.Cu")
		(net "GMI_CPU1_G0_CPU0_G2_TX_DN<4>")
	)
	(segment
		(start 368.969036 -231.177338)
		(end 368.89436 -231.22128)
		(width 0.1143)
		(layer "In6.Cu")
		(net "GMI_CPU1_G0_CPU0_G2_TX_DN<4>")
	)
	(segment
		(start 368.927126 -234.442)
		(end 368.925856 -234.442762)
		(width 0.1143)
		(layer "In6.Cu")
		(net "GMI_CPU1_G0_CPU0_G2_TX_DN<4>")
	)
	(segment
		(start 100.798884 -239.624362)
		(end 100.881688 -239.541558)
		(width 0.1143)
		(layer "In6.Cu")
		(net "GMI_CPU1_G0_CPU0_G2_TX_DN<4>")
	)
	(segment
		(start 103.508048 -225.367088)
		(end 103.50881 -225.36658)
		(width 0.1143)
		(layer "In6.Cu")
		(net "GMI_CPU1_G0_CPU0_G2_TX_DN<4>")
	)
	(segment
		(start 105.575862 -221.326456)
		(end 105.575354 -221.325948)
		(width 0.1143)
		(layer "In6.Cu")
		(net "GMI_CPU1_G0_CPU0_G2_TX_DN<4>")
	)
	(segment
		(start 101.158802 -237.516416)
		(end 101.160072 -237.515654)
		(width 0.1143)
		(layer "In6.Cu")
		(net "GMI_CPU1_G0_CPU0_G2_TX_DN<4>")
	)
	(segment
		(start 368.96421 -232.800398)
		(end 368.927888 -232.82148)
		(width 0.1143)
		(layer "In6.Cu")
		(net "GMI_CPU1_G0_CPU0_G2_TX_DN<4>")
	)
	(segment
		(start 102.567994 -227.961952)
		(end 102.531672 -227.94087)
		(width 0.1143)
		(layer "In6.Cu")
		(net "GMI_CPU1_G0_CPU0_G2_TX_DN<4>")
	)
	(segment
		(start 101.1555 -238.490252)
		(end 101.154484 -238.489744)
		(width 0.1143)
		(layer "In6.Cu")
		(net "GMI_CPU1_G0_CPU0_G2_TX_DN<4>")
	)
	(segment
		(start 368.925856 -228.605588)
		(end 368.927126 -228.60635)
		(width 0.1143)
		(layer "In6.Cu")
		(net "GMI_CPU1_G0_CPU0_G2_TX_DN<4>")
	)
	(segment
		(start 101.628194 -236.706918)
		(end 101.658674 -236.689138)
		(width 0.1143)
		(layer "In6.Cu")
		(net "GMI_CPU1_G0_CPU0_G2_TX_DN<4>")
	)
	(segment
		(start 102.58425 -230.217726)
		(end 102.58425 -230.217472)
		(width 0.1143)
		(layer "In6.Cu")
		(net "GMI_CPU1_G0_CPU0_G2_TX_DN<4>")
	)
	(segment
		(start 103.51008 -225.365818)
		(end 103.539798 -225.3488)
		(width 0.1143)
		(layer "In6.Cu")
		(net "GMI_CPU1_G0_CPU0_G2_TX_DN<4>")
	)
	(segment
		(start 101.118924 -237.539784)
		(end 101.15804 -237.516924)
		(width 0.1143)
		(layer "In6.Cu")
		(net "GMI_CPU1_G0_CPU0_G2_TX_DN<4>")
	)
	(segment
		(start 368.925856 -227.962968)
		(end 368.896138 -227.979986)
		(width 0.1143)
		(layer "In6.Cu")
		(net "GMI_CPU1_G0_CPU0_G2_TX_DN<4>")
	)
	(segment
		(start 102.586282 -230.216202)
		(end 102.599744 -230.208582)
		(width 0.1143)
		(layer "In6.Cu")
		(net "GMI_CPU1_G0_CPU0_G2_TX_DN<4>")
	)
	(segment
		(start 370.376958 -238.468662)
		(end 370.345462 -238.48695)
		(width 0.1143)
		(layer "In6.Cu")
		(net "GMI_CPU1_G0_CPU0_G2_TX_DN<4>")
	)
	(segment
		(start 101.589078 -236.729778)
		(end 101.628194 -236.706918)
		(width 0.1143)
		(layer "In6.Cu")
		(net "GMI_CPU1_G0_CPU0_G2_TX_DN<4>")
	)
	(segment
		(start 368.896138 -226.968558)
		(end 368.925856 -226.985576)
		(width 0.1143)
		(layer "In6.Cu")
		(net "GMI_CPU1_G0_CPU0_G2_TX_DN<4>")
	)
	(segment
		(start 101.15804 -237.516924)
		(end 101.158802 -237.516416)
		(width 0.1143)
		(layer "In6.Cu")
		(net "GMI_CPU1_G0_CPU0_G2_TX_DN<4>")
	)
	(segment
		(start 368.896138 -228.58857)
		(end 368.925856 -228.605588)
		(width 0.1143)
		(layer "In6.Cu")
		(net "GMI_CPU1_G0_CPU0_G2_TX_DN<4>")
	)
	(segment
		(start 102.599744 -227.98024)
		(end 102.568756 -227.96246)
		(width 0.1143)
		(layer "In6.Cu")
		(net "GMI_CPU1_G0_CPU0_G2_TX_DN<4>")
	)
	(segment
		(start 369.837208 -236.688884)
		(end 369.906804 -236.729524)
		(width 0.1143)
		(layer "In6.Cu")
		(net "GMI_CPU1_G0_CPU0_G2_TX_DN<4>")
	)
	(segment
		(start 102.508812 -230.264208)
		(end 102.529132 -230.24973)
		(width 0.1143)
		(layer "In6.Cu")
		(net "GMI_CPU1_G0_CPU0_G2_TX_DN<4>")
	)
	(segment
		(start 365.966248 -218.859608)
		(end 365.966248 -221.09303)
		(width 0.14224)
		(layer "In6.Cu")
		(net "GMI_CPU1_G0_CPU0_G2_TX_DN<4>")
	)
	(segment
		(start 365.92002 -221.326202)
		(end 365.92002 -221.80423)
		(width 0.1143)
		(layer "In6.Cu")
		(net "GMI_CPU1_G0_CPU0_G2_TX_DN<4>")
	)
	(segment
		(start 101.157024 -238.491268)
		(end 101.1555 -238.490252)
		(width 0.1143)
		(layer "In6.Cu")
		(net "GMI_CPU1_G0_CPU0_G2_TX_DN<4>")
	)
	(segment
		(start 365.005874 -216.541096)
		(end 365.966248 -218.859608)
		(width 0.14224)
		(layer "In6.Cu")
		(net "GMI_CPU1_G0_CPU0_G2_TX_DN<4>")
	)
	(arc
		(start 102.7557 -231.524302)
		(mid 102.714938 -231.354418)
		(end 102.601522 -231.221534)
		(width 0.1143)
		(layer "In6.Cu")
		(net "GMI_CPU1_G0_CPU0_G2_TX_DN<4>")
	)
	(arc
		(start 103.068628 -226.159314)
		(mid 103.184055 -226.025938)
		(end 103.2256 -225.854514)
		(width 0.1143)
		(layer "In6.Cu")
		(net "GMI_CPU1_G0_CPU0_G2_TX_DN<4>")
	)
	(arc
		(start 369.208558 -235.612686)
		(mid 369.249198 -235.764204)
		(end 369.360196 -235.875068)
		(width 0.1143)
		(layer "In6.Cu")
		(net "GMI_CPU1_G0_CPU0_G2_TX_DN<4>")
	)
	(arc
		(start 367.085626 -223.768666)
		(mid 367.265355 -223.971286)
		(end 367.330228 -224.234248)
		(width 0.1143)
		(layer "In6.Cu")
		(net "GMI_CPU1_G0_CPU0_G2_TX_DN<4>")
	)
	(arc
		(start 103.539798 -225.3488)
		(mid 103.654474 -225.215466)
		(end 103.695754 -225.044508)
		(width 0.1143)
		(layer "In6.Cu")
		(net "GMI_CPU1_G0_CPU0_G2_TX_DN<4>")
	)
	(arc
		(start 102.516432 -232.789984)
		(mid 102.291261 -232.334308)
		(end 102.516432 -231.878632)
		(width 0.1143)
		(layer "In6.Cu")
		(net "GMI_CPU1_G0_CPU0_G2_TX_DN<4>")
	)
	(arc
		(start 102.516432 -227.01885)
		(mid 102.524008 -227.013454)
		(end 102.531672 -227.008182)
		(width 0.1143)
		(layer "In6.Cu")
		(net "GMI_CPU1_G0_CPU0_G2_TX_DN<4>")
	)
	(arc
		(start 105.105708 -222.61449)
		(mid 105.170223 -222.352271)
		(end 105.34904 -222.149924)
		(width 0.1143)
		(layer "In6.Cu")
		(net "GMI_CPU1_G0_CPU0_G2_TX_DN<4>")
	)
	(arc
		(start 368.97945 -234.409742)
		(mid 368.971874 -234.415138)
		(end 368.96421 -234.42041)
		(width 0.1143)
		(layer "In6.Cu")
		(net "GMI_CPU1_G0_CPU0_G2_TX_DN<4>")
	)
	(arc
		(start 104.950514 -222.91802)
		(mid 105.064667 -222.784944)
		(end 105.105708 -222.61449)
		(width 0.1143)
		(layer "In6.Cu")
		(net "GMI_CPU1_G0_CPU0_G2_TX_DN<4>")
	)
	(arc
		(start 102.7557 -226.66452)
		(mid 102.820215 -226.402301)
		(end 102.999032 -226.199954)
		(width 0.1143)
		(layer "In6.Cu")
		(net "GMI_CPU1_G0_CPU0_G2_TX_DN<4>")
	)
	(arc
		(start 102.516432 -234.409996)
		(mid 102.291261 -233.95432)
		(end 102.516432 -233.498644)
		(width 0.1143)
		(layer "In6.Cu")
		(net "GMI_CPU1_G0_CPU0_G2_TX_DN<4>")
	)
	(arc
		(start 103.695754 -225.044508)
		(mid 103.760269 -224.782289)
		(end 103.939086 -224.579942)
		(width 0.1143)
		(layer "In6.Cu")
		(net "GMI_CPU1_G0_CPU0_G2_TX_DN<4>")
	)
	(arc
		(start 367.800128 -225.044254)
		(mid 367.841383 -225.215225)
		(end 367.956084 -225.348546)
		(width 0.1143)
		(layer "In6.Cu")
		(net "GMI_CPU1_G0_CPU0_G2_TX_DN<4>")
	)
	(arc
		(start 102.599744 -231.828594)
		(mid 102.71442 -231.69526)
		(end 102.7557 -231.524302)
		(width 0.1143)
		(layer "In6.Cu")
		(net "GMI_CPU1_G0_CPU0_G2_TX_DN<4>")
	)
	(arc
		(start 102.599744 -230.208582)
		(mid 102.71442 -230.075248)
		(end 102.7557 -229.90429)
		(width 0.1143)
		(layer "In6.Cu")
		(net "GMI_CPU1_G0_CPU0_G2_TX_DN<4>")
	)
	(arc
		(start 101.815646 -236.384338)
		(mid 101.880161 -236.122119)
		(end 102.058978 -235.919772)
		(width 0.1143)
		(layer "In6.Cu")
		(net "GMI_CPU1_G0_CPU0_G2_TX_DN<4>")
	)
	(arc
		(start 368.97945 -232.78973)
		(mid 368.971874 -232.795126)
		(end 368.96421 -232.800398)
		(width 0.1143)
		(layer "In6.Cu")
		(net "GMI_CPU1_G0_CPU0_G2_TX_DN<4>")
	)
	(arc
		(start 368.97945 -233.49839)
		(mid 369.204621 -233.954066)
		(end 368.97945 -234.409742)
		(width 0.1143)
		(layer "In6.Cu")
		(net "GMI_CPU1_G0_CPU0_G2_TX_DN<4>")
	)
	(arc
		(start 102.531672 -234.420664)
		(mid 102.524008 -234.415393)
		(end 102.516432 -234.409996)
		(width 0.1143)
		(layer "In6.Cu")
		(net "GMI_CPU1_G0_CPU0_G2_TX_DN<4>")
	)
	(arc
		(start 101.345746 -237.194344)
		(mid 101.410261 -236.932125)
		(end 101.589078 -236.729778)
		(width 0.1143)
		(layer "In6.Cu")
		(net "GMI_CPU1_G0_CPU0_G2_TX_DN<4>")
	)
	(arc
		(start 102.599744 -228.588824)
		(mid 102.755672 -228.284532)
		(end 102.599744 -227.98024)
		(width 0.1143)
		(layer "In6.Cu")
		(net "GMI_CPU1_G0_CPU0_G2_TX_DN<4>")
	)
	(arc
		(start 368.97945 -227.929948)
		(mid 368.971874 -227.935344)
		(end 368.96421 -227.940616)
		(width 0.1143)
		(layer "In6.Cu")
		(net "GMI_CPU1_G0_CPU0_G2_TX_DN<4>")
	)
	(arc
		(start 104.6353 -223.424496)
		(mid 104.700172 -223.161533)
		(end 104.879902 -222.958914)
		(width 0.1143)
		(layer "In6.Cu")
		(net "GMI_CPU1_G0_CPU0_G2_TX_DN<4>")
	)
	(arc
		(start 102.516432 -231.878632)
		(mid 102.524008 -231.873236)
		(end 102.531672 -231.867964)
		(width 0.1143)
		(layer "In6.Cu")
		(net "GMI_CPU1_G0_CPU0_G2_TX_DN<4>")
	)
	(arc
		(start 104.008682 -224.539302)
		(mid 104.124109 -224.405926)
		(end 104.165654 -224.234502)
		(width 0.1143)
		(layer "In6.Cu")
		(net "GMI_CPU1_G0_CPU0_G2_TX_DN<4>")
	)
	(arc
		(start 366.146842 -222.14967)
		(mid 366.325655 -222.35202)
		(end 366.390174 -222.614236)
		(width 0.1143)
		(layer "In6.Cu")
		(net "GMI_CPU1_G0_CPU0_G2_TX_DN<4>")
	)
	(arc
		(start 100.881688 -239.541558)
		(mid 100.960767 -239.326113)
		(end 101.118924 -239.159796)
		(width 0.1143)
		(layer "In6.Cu")
		(net "GMI_CPU1_G0_CPU0_G2_TX_DN<4>")
	)
	(arc
		(start 368.02695 -225.389694)
		(mid 368.205763 -225.592044)
		(end 368.270282 -225.85426)
		(width 0.1143)
		(layer "In6.Cu")
		(net "GMI_CPU1_G0_CPU0_G2_TX_DN<4>")
	)
	(arc
		(start 368.927888 -228.606858)
		(mid 369.208535 -229.094284)
		(end 368.927888 -229.58171)
		(width 0.1143)
		(layer "In6.Cu")
		(net "GMI_CPU1_G0_CPU0_G2_TX_DN<4>")
	)
	(arc
		(start 368.740182 -229.904036)
		(mid 368.781437 -230.075007)
		(end 368.896138 -230.208328)
		(width 0.1143)
		(layer "In6.Cu")
		(net "GMI_CPU1_G0_CPU0_G2_TX_DN<4>")
	)
	(arc
		(start 102.599744 -226.968812)
		(mid 102.71442 -226.835478)
		(end 102.7557 -226.66452)
		(width 0.1143)
		(layer "In6.Cu")
		(net "GMI_CPU1_G0_CPU0_G2_TX_DN<4>")
	)
	(arc
		(start 366.860582 -223.424242)
		(mid 366.902131 -223.595664)
		(end 367.017554 -223.729042)
		(width 0.1143)
		(layer "In6.Cu")
		(net "GMI_CPU1_G0_CPU0_G2_TX_DN<4>")
	)
	(arc
		(start 368.89436 -229.601268)
		(mid 368.780953 -229.734157)
		(end 368.740182 -229.904036)
		(width 0.1143)
		(layer "In6.Cu")
		(net "GMI_CPU1_G0_CPU0_G2_TX_DN<4>")
	)
	(arc
		(start 101.18979 -239.118648)
		(mid 101.345718 -238.814356)
		(end 101.18979 -238.510064)
		(width 0.1143)
		(layer "In6.Cu")
		(net "GMI_CPU1_G0_CPU0_G2_TX_DN<4>")
	)
	(arc
		(start 104.165654 -224.234502)
		(mid 104.230526 -223.971539)
		(end 104.410256 -223.76892)
		(width 0.1143)
		(layer "In6.Cu")
		(net "GMI_CPU1_G0_CPU0_G2_TX_DN<4>")
	)
	(arc
		(start 368.96421 -231.86771)
		(mid 368.971874 -231.872981)
		(end 368.97945 -231.878378)
		(width 0.1143)
		(layer "In6.Cu")
		(net "GMI_CPU1_G0_CPU0_G2_TX_DN<4>")
	)
	(arc
		(start 367.330228 -224.234248)
		(mid 367.371777 -224.40567)
		(end 367.4872 -224.539048)
		(width 0.1143)
		(layer "In6.Cu")
		(net "GMI_CPU1_G0_CPU0_G2_TX_DN<4>")
	)
	(arc
		(start 368.896138 -232.839768)
		(mid 368.74021 -233.14406)
		(end 368.896138 -233.448352)
		(width 0.1143)
		(layer "In6.Cu")
		(net "GMI_CPU1_G0_CPU0_G2_TX_DN<4>")
	)
	(arc
		(start 368.270282 -225.85426)
		(mid 368.311831 -226.025682)
		(end 368.427254 -226.15906)
		(width 0.1143)
		(layer "In6.Cu")
		(net "GMI_CPU1_G0_CPU0_G2_TX_DN<4>")
	)
	(arc
		(start 102.516432 -227.930202)
		(mid 102.291261 -227.474526)
		(end 102.516432 -227.01885)
		(width 0.1143)
		(layer "In6.Cu")
		(net "GMI_CPU1_G0_CPU0_G2_TX_DN<4>")
	)
	(arc
		(start 102.599744 -235.068618)
		(mid 102.755672 -234.764326)
		(end 102.599744 -234.460034)
		(width 0.1143)
		(layer "In6.Cu")
		(net "GMI_CPU1_G0_CPU0_G2_TX_DN<4>")
	)
	(arc
		(start 102.287324 -235.574332)
		(mid 102.362502 -235.293097)
		(end 102.567994 -235.086906)
		(width 0.1143)
		(layer "In6.Cu")
		(net "GMI_CPU1_G0_CPU0_G2_TX_DN<4>")
	)
	(arc
		(start 365.92002 -221.80423)
		(mid 365.962198 -221.974016)
		(end 366.07496 -222.10776)
		(width 0.1143)
		(layer "In6.Cu")
		(net "GMI_CPU1_G0_CPU0_G2_TX_DN<4>")
	)
	(arc
		(start 368.97945 -231.878378)
		(mid 369.204621 -232.334054)
		(end 368.97945 -232.78973)
		(width 0.1143)
		(layer "In6.Cu")
		(net "GMI_CPU1_G0_CPU0_G2_TX_DN<4>")
	)
	(arc
		(start 370.376958 -239.159542)
		(mid 370.528945 -239.31605)
		(end 370.610384 -239.518444)
		(width 0.1143)
		(layer "In6.Cu")
		(net "GMI_CPU1_G0_CPU0_G2_TX_DN<4>")
	)
	(arc
		(start 366.390174 -222.614236)
		(mid 366.431224 -222.784686)
		(end 366.545368 -222.917766)
		(width 0.1143)
		(layer "In6.Cu")
		(net "GMI_CPU1_G0_CPU0_G2_TX_DN<4>")
	)
	(arc
		(start 102.7557 -229.90429)
		(mid 102.714938 -229.734406)
		(end 102.601522 -229.601522)
		(width 0.1143)
		(layer "In6.Cu")
		(net "GMI_CPU1_G0_CPU0_G2_TX_DN<4>")
	)
	(arc
		(start 369.436904 -235.919518)
		(mid 369.615717 -236.121868)
		(end 369.680236 -236.384084)
		(width 0.1143)
		(layer "In6.Cu")
		(net "GMI_CPU1_G0_CPU0_G2_TX_DN<4>")
	)
	(arc
		(start 368.97945 -227.018596)
		(mid 369.204621 -227.474272)
		(end 368.97945 -227.929948)
		(width 0.1143)
		(layer "In6.Cu")
		(net "GMI_CPU1_G0_CPU0_G2_TX_DN<4>")
	)
	(arc
		(start 101.118924 -238.468916)
		(mid 100.875597 -238.00435)
		(end 101.118924 -237.539784)
		(width 0.1143)
		(layer "In6.Cu")
		(net "GMI_CPU1_G0_CPU0_G2_TX_DN<4>")
	)
	(arc
		(start 370.150136 -237.19409)
		(mid 370.191391 -237.365061)
		(end 370.306092 -237.498382)
		(width 0.1143)
		(layer "In6.Cu")
		(net "GMI_CPU1_G0_CPU0_G2_TX_DN<4>")
	)
	(arc
		(start 370.376958 -237.53953)
		(mid 370.620285 -238.004096)
		(end 370.376958 -238.468662)
		(width 0.1143)
		(layer "In6.Cu")
		(net "GMI_CPU1_G0_CPU0_G2_TX_DN<4>")
	)
	(arc
		(start 105.420922 -222.108014)
		(mid 105.533644 -221.97425)
		(end 105.575862 -221.804484)
		(width 0.1143)
		(layer "In6.Cu")
		(net "GMI_CPU1_G0_CPU0_G2_TX_DN<4>")
	)
	(arc
		(start 368.740182 -231.524048)
		(mid 368.781437 -231.695019)
		(end 368.896138 -231.82834)
		(width 0.1143)
		(layer "In6.Cu")
		(net "GMI_CPU1_G0_CPU0_G2_TX_DN<4>")
	)
	(arc
		(start 102.135686 -235.875322)
		(mid 102.246707 -235.764471)
		(end 102.287324 -235.61294)
		(width 0.1143)
		(layer "In6.Cu")
		(net "GMI_CPU1_G0_CPU0_G2_TX_DN<4>")
	)
	(arc
		(start 368.89436 -231.22128)
		(mid 368.780953 -231.354169)
		(end 368.740182 -231.524048)
		(width 0.1143)
		(layer "In6.Cu")
		(net "GMI_CPU1_G0_CPU0_G2_TX_DN<4>")
	)
	(arc
		(start 369.210082 -230.714296)
		(mid 369.146276 -230.975349)
		(end 368.969036 -231.177338)
		(width 0.1143)
		(layer "In6.Cu")
		(net "GMI_CPU1_G0_CPU0_G2_TX_DN<4>")
	)
	(arc
		(start 368.98707 -230.263954)
		(mid 369.151085 -230.454592)
		(end 369.210082 -230.699056)
		(width 0.1143)
		(layer "In6.Cu")
		(net "GMI_CPU1_G0_CPU0_G2_TX_DN<4>")
	)
	(arc
		(start 102.567994 -229.581964)
		(mid 102.287347 -229.094538)
		(end 102.567994 -228.607112)
		(width 0.1143)
		(layer "In6.Cu")
		(net "GMI_CPU1_G0_CPU0_G2_TX_DN<4>")
	)
	(arc
		(start 370.306092 -238.50981)
		(mid 370.150164 -238.814102)
		(end 370.306092 -239.118394)
		(width 0.1143)
		(layer "In6.Cu")
		(net "GMI_CPU1_G0_CPU0_G2_TX_DN<4>")
	)
	(arc
		(start 368.896138 -227.979986)
		(mid 368.74021 -228.284278)
		(end 368.896138 -228.58857)
		(width 0.1143)
		(layer "In6.Cu")
		(net "GMI_CPU1_G0_CPU0_G2_TX_DN<4>")
	)
	(arc
		(start 102.2858 -230.69931)
		(mid 102.344802 -230.454849)
		(end 102.508812 -230.264208)
		(width 0.1143)
		(layer "In6.Cu")
		(net "GMI_CPU1_G0_CPU0_G2_TX_DN<4>")
	)
	(arc
		(start 102.531672 -227.94087)
		(mid 102.524008 -227.935599)
		(end 102.516432 -227.930202)
		(width 0.1143)
		(layer "In6.Cu")
		(net "GMI_CPU1_G0_CPU0_G2_TX_DN<4>")
	)
	(arc
		(start 104.478328 -223.729296)
		(mid 104.593755 -223.59592)
		(end 104.6353 -223.424496)
		(width 0.1143)
		(layer "In6.Cu")
		(net "GMI_CPU1_G0_CPU0_G2_TX_DN<4>")
	)
	(arc
		(start 366.61598 -222.95866)
		(mid 366.795709 -223.16128)
		(end 366.860582 -223.424242)
		(width 0.1143)
		(layer "In6.Cu")
		(net "GMI_CPU1_G0_CPU0_G2_TX_DN<4>")
	)
	(arc
		(start 368.49685 -226.1997)
		(mid 368.675663 -226.40205)
		(end 368.740182 -226.664266)
		(width 0.1143)
		(layer "In6.Cu")
		(net "GMI_CPU1_G0_CPU0_G2_TX_DN<4>")
	)
	(arc
		(start 103.2256 -225.854514)
		(mid 103.290115 -225.592295)
		(end 103.468932 -225.389948)
		(width 0.1143)
		(layer "In6.Cu")
		(net "GMI_CPU1_G0_CPU0_G2_TX_DN<4>")
	)
	(arc
		(start 367.556796 -224.579688)
		(mid 367.735609 -224.782038)
		(end 367.800128 -225.044254)
		(width 0.1143)
		(layer "In6.Cu")
		(net "GMI_CPU1_G0_CPU0_G2_TX_DN<4>")
	)
	(arc
		(start 368.896138 -234.45978)
		(mid 368.74021 -234.764072)
		(end 368.896138 -235.068364)
		(width 0.1143)
		(layer "In6.Cu")
		(net "GMI_CPU1_G0_CPU0_G2_TX_DN<4>")
	)
	(arc
		(start 102.531672 -232.800652)
		(mid 102.524008 -232.795381)
		(end 102.516432 -232.789984)
		(width 0.1143)
		(layer "In6.Cu")
		(net "GMI_CPU1_G0_CPU0_G2_TX_DN<4>")
	)
	(arc
		(start 102.526846 -231.177592)
		(mid 102.34965 -230.97558)
		(end 102.2858 -230.71455)
		(width 0.1143)
		(layer "In6.Cu")
		(net "GMI_CPU1_G0_CPU0_G2_TX_DN<4>")
	)
	(arc
		(start 368.96421 -227.007928)
		(mid 368.971874 -227.013199)
		(end 368.97945 -227.018596)
		(width 0.1143)
		(layer "In6.Cu")
		(net "GMI_CPU1_G0_CPU0_G2_TX_DN<4>")
	)
	(arc
		(start 368.96421 -233.487722)
		(mid 368.971874 -233.492993)
		(end 368.97945 -233.49839)
		(width 0.1143)
		(layer "In6.Cu")
		(net "GMI_CPU1_G0_CPU0_G2_TX_DN<4>")
	)
	(arc
		(start 370.610384 -239.518444)
		(mid 370.612407 -239.529854)
		(end 370.614194 -239.541304)
		(width 0.1143)
		(layer "In6.Cu")
		(net "GMI_CPU1_G0_CPU0_G2_TX_DN<4>")
	)
	(arc
		(start 102.516432 -233.498644)
		(mid 102.524008 -233.493248)
		(end 102.531672 -233.487976)
		(width 0.1143)
		(layer "In6.Cu")
		(net "GMI_CPU1_G0_CPU0_G2_TX_DN<4>")
	)
	(arc
		(start 101.658674 -236.689138)
		(mid 101.774101 -236.555762)
		(end 101.815646 -236.384338)
		(width 0.1143)
		(layer "In6.Cu")
		(net "GMI_CPU1_G0_CPU0_G2_TX_DN<4>")
	)
	(arc
		(start 102.599744 -233.448606)
		(mid 102.755672 -233.144314)
		(end 102.599744 -232.840022)
		(width 0.1143)
		(layer "In6.Cu")
		(net "GMI_CPU1_G0_CPU0_G2_TX_DN<4>")
	)
	(arc
		(start 101.18979 -237.498636)
		(mid 101.304466 -237.365302)
		(end 101.345746 -237.194344)
		(width 0.1143)
		(layer "In6.Cu")
		(net "GMI_CPU1_G0_CPU0_G2_TX_DN<4>")
	)
	(arc
		(start 369.680236 -236.384084)
		(mid 369.721785 -236.555506)
		(end 369.837208 -236.688884)
		(width 0.1143)
		(layer "In6.Cu")
		(net "GMI_CPU1_G0_CPU0_G2_TX_DN<4>")
	)
	(arc
		(start 368.740182 -226.664266)
		(mid 368.781437 -226.835237)
		(end 368.896138 -226.968558)
		(width 0.1143)
		(layer "In6.Cu")
		(net "GMI_CPU1_G0_CPU0_G2_TX_DN<4>")
	)
	(arc
		(start 368.927888 -235.086652)
		(mid 369.13336 -235.292854)
		(end 369.208558 -235.574078)
		(width 0.1143)
		(layer "In6.Cu")
		(net "GMI_CPU1_G0_CPU0_G2_TX_DN<4>")
	)
	(arc
		(start 369.906804 -236.729524)
		(mid 370.085617 -236.931874)
		(end 370.150136 -237.19409)
		(width 0.1143)
		(layer "In6.Cu")
		(net "GMI_CPU1_G0_CPU0_G2_TX_DN<4>")
	)
	(segment
		(start 100.967794 -241.510312)
		(end 100.500942 -241.244374)
		(width 0.12954)
		(layer "F.Cu")
		(net "GMI_CPU1_G0_CPU0_G2_TX_DN<3>")
	)
	(segment
		(start 370.527834 -241.510058)
		(end 370.994686 -241.24412)
		(width 0.12954)
		(layer "F.Cu")
		(net "GMI_CPU1_G0_CPU0_G2_TX_DN<3>")
	)
	(segment
		(start 101.628194 -235.086906)
		(end 101.589078 -235.109766)
		(width 0.1143)
		(layer "In6.Cu")
		(net "GMI_CPU1_G0_CPU0_G2_TX_DN<3>")
	)
	(segment
		(start 102.098094 -226.177094)
		(end 102.058978 -226.199954)
		(width 0.1143)
		(layer "In6.Cu")
		(net "GMI_CPU1_G0_CPU0_G2_TX_DN<3>")
	)
	(segment
		(start 104.448102 -222.127064)
		(end 104.414828 -222.146368)
		(width 0.1143)
		(layer "In6.Cu")
		(net "GMI_CPU1_G0_CPU0_G2_TX_DN<3>")
	)
	(segment
		(start 101.658674 -233.449114)
		(end 101.628194 -233.466894)
		(width 0.1143)
		(layer "In6.Cu")
		(net "GMI_CPU1_G0_CPU0_G2_TX_DN<3>")
	)
	(segment
		(start 101.658674 -230.20909)
		(end 101.591618 -230.248206)
		(width 0.1143)
		(layer "In6.Cu")
		(net "GMI_CPU1_G0_CPU0_G2_TX_DN<3>")
	)
	(segment
		(start 102.098602 -226.17684)
		(end 102.098094 -226.177094)
		(width 0.1143)
		(layer "In6.Cu")
		(net "GMI_CPU1_G0_CPU0_G2_TX_DN<3>")
	)
	(segment
		(start 371.246146 -238.50981)
		(end 371.275864 -238.492792)
		(width 0.1143)
		(layer "In6.Cu")
		(net "GMI_CPU1_G0_CPU0_G2_TX_DN<3>")
	)
	(segment
		(start 104.635808 -221.326202)
		(end 104.635808 -221.804484)
		(width 0.1143)
		(layer "In6.Cu")
		(net "GMI_CPU1_G0_CPU0_G2_TX_DN<3>")
	)
	(segment
		(start 101.15804 -235.896912)
		(end 101.118924 -235.919772)
		(width 0.1143)
		(layer "In6.Cu")
		(net "GMI_CPU1_G0_CPU0_G2_TX_DN<3>")
	)
	(segment
		(start 102.599744 -225.3488)
		(end 102.567994 -225.367088)
		(width 0.1143)
		(layer "In6.Cu")
		(net "GMI_CPU1_G0_CPU0_G2_TX_DN<3>")
	)
	(segment
		(start 367.516918 -222.936816)
		(end 367.489994 -222.921322)
		(width 0.1143)
		(layer "In6.Cu")
		(net "GMI_CPU1_G0_CPU0_G2_TX_DN<3>")
	)
	(segment
		(start 101.589078 -229.559104)
		(end 101.628194 -229.581964)
		(width 0.1143)
		(layer "In6.Cu")
		(net "GMI_CPU1_G0_CPU0_G2_TX_DN<3>")
	)
	(segment
		(start 100.21951 -239.136174)
		(end 100.179124 -239.159542)
		(width 0.1143)
		(layer "In6.Cu")
		(net "GMI_CPU1_G0_CPU0_G2_TX_DN<3>")
	)
	(segment
		(start 371.275864 -240.112804)
		(end 371.277134 -240.112042)
		(width 0.1143)
		(layer "In6.Cu")
		(net "GMI_CPU1_G0_CPU0_G2_TX_DN<3>")
	)
	(segment
		(start 118.218458 -203.639674)
		(end 115.458748 -205.757018)
		(width 0.14224)
		(layer "In6.Cu")
		(net "GMI_CPU1_G0_CPU0_G2_TX_DN<3>")
	)
	(segment
		(start 101.628194 -228.607112)
		(end 101.589078 -228.629972)
		(width 0.1143)
		(layer "In6.Cu")
		(net "GMI_CPU1_G0_CPU0_G2_TX_DN<3>")
	)
	(segment
		(start 369.867688 -229.58171)
		(end 369.906804 -229.55885)
		(width 0.1143)
		(layer "In6.Cu")
		(net "GMI_CPU1_G0_CPU0_G2_TX_DN<3>")
	)
	(segment
		(start 104.479852 -222.108776)
		(end 104.448102 -222.127064)
		(width 0.1143)
		(layer "In6.Cu")
		(net "GMI_CPU1_G0_CPU0_G2_TX_DN<3>")
	)
	(segment
		(start 100.649024 -240.898934)
		(end 100.68814 -240.921794)
		(width 0.1143)
		(layer "In6.Cu")
		(net "GMI_CPU1_G0_CPU0_G2_TX_DN<3>")
	)
	(segment
		(start 371.316758 -239.159288)
		(end 371.276372 -239.13592)
		(width 0.1143)
		(layer "In6.Cu")
		(net "GMI_CPU1_G0_CPU0_G2_TX_DN<3>")
	)
	(segment
		(start 371.273832 -239.134396)
		(end 371.246146 -239.118394)
		(width 0.1143)
		(layer "In6.Cu")
		(net "GMI_CPU1_G0_CPU0_G2_TX_DN<3>")
	)
	(segment
		(start 369.906804 -228.629718)
		(end 369.837208 -228.589078)
		(width 0.1143)
		(layer "In6.Cu")
		(net "GMI_CPU1_G0_CPU0_G2_TX_DN<3>")
	)
	(segment
		(start 101.628194 -227.961952)
		(end 101.658674 -227.979732)
		(width 0.1143)
		(layer "In6.Cu")
		(net "GMI_CPU1_G0_CPU0_G2_TX_DN<3>")
	)
	(segment
		(start 370.33581 -235.895388)
		(end 370.306092 -235.87837)
		(width 0.1143)
		(layer "In6.Cu")
		(net "GMI_CPU1_G0_CPU0_G2_TX_DN<3>")
	)
	(segment
		(start 369.904264 -230.247952)
		(end 369.837208 -230.208836)
		(width 0.1143)
		(layer "In6.Cu")
		(net "GMI_CPU1_G0_CPU0_G2_TX_DN<3>")
	)
	(segment
		(start 100.868734 -241.174524)
		(end 100.798884 -241.244374)
		(width 0.1143)
		(layer "In6.Cu")
		(net "GMI_CPU1_G0_CPU0_G2_TX_DN<3>")
	)
	(segment
		(start 356.53599 -207.73517)
		(end 325.711058 -188.358272)
		(width 0.14224)
		(layer "In6.Cu")
		(net "GMI_CPU1_G0_CPU0_G2_TX_DN<3>")
	)
	(segment
		(start 371.277134 -240.112042)
		(end 371.277896 -240.111534)
		(width 0.1143)
		(layer "In6.Cu")
		(net "GMI_CPU1_G0_CPU0_G2_TX_DN<3>")
	)
	(segment
		(start 371.316758 -240.088928)
		(end 371.344698 -240.068862)
		(width 0.1143)
		(layer "In6.Cu")
		(net "GMI_CPU1_G0_CPU0_G2_TX_DN<3>")
	)
	(segment
		(start 104.589834 -221.093284)
		(end 104.635554 -221.139004)
		(width 0.1143)
		(layer "In6.Cu")
		(net "GMI_CPU1_G0_CPU0_G2_TX_DN<3>")
	)
	(segment
		(start 371.344698 -239.179354)
		(end 371.316758 -239.159288)
		(width 0.1143)
		(layer "In6.Cu")
		(net "GMI_CPU1_G0_CPU0_G2_TX_DN<3>")
	)
	(segment
		(start 371.277134 -238.49203)
		(end 371.277896 -238.491522)
		(width 0.1143)
		(layer "In6.Cu")
		(net "GMI_CPU1_G0_CPU0_G2_TX_DN<3>")
	)
	(segment
		(start 370.777262 -240.93932)
		(end 370.846858 -240.89868)
		(width 0.1143)
		(layer "In6.Cu")
		(net "GMI_CPU1_G0_CPU0_G2_TX_DN<3>")
	)
	(segment
		(start 370.337842 -235.896658)
		(end 370.33708 -235.89615)
		(width 0.1143)
		(layer "In6.Cu")
		(net "GMI_CPU1_G0_CPU0_G2_TX_DN<3>")
	)
	(segment
		(start 100.798884 -241.244374)
		(end 100.500942 -241.244374)
		(width 0.1143)
		(layer "In6.Cu")
		(net "GMI_CPU1_G0_CPU0_G2_TX_DN<3>")
	)
	(segment
		(start 101.628194 -234.441746)
		(end 101.658674 -234.459526)
		(width 0.1143)
		(layer "In6.Cu")
		(net "GMI_CPU1_G0_CPU0_G2_TX_DN<3>")
	)
	(segment
		(start 369.867688 -231.201722)
		(end 369.906804 -231.178862)
		(width 0.1143)
		(layer "In6.Cu")
		(net "GMI_CPU1_G0_CPU0_G2_TX_DN<3>")
	)
	(segment
		(start 367.987834 -223.746822)
		(end 367.95202 -223.725994)
		(width 0.1143)
		(layer "In6.Cu")
		(net "GMI_CPU1_G0_CPU0_G2_TX_DN<3>")
	)
	(segment
		(start 101.628194 -231.201976)
		(end 101.660706 -231.220772)
		(width 0.1143)
		(layer "In6.Cu")
		(net "GMI_CPU1_G0_CPU0_G2_TX_DN<3>")
	)
	(segment
		(start 105.816908 -215.282526)
		(end 104.589834 -218.244928)
		(width 0.14224)
		(layer "In6.Cu")
		(net "GMI_CPU1_G0_CPU0_G2_TX_DN<3>")
	)
	(segment
		(start 369.397788 -226.17684)
		(end 369.39728 -226.176586)
		(width 0.1143)
		(layer "In6.Cu")
		(net "GMI_CPU1_G0_CPU0_G2_TX_DN<3>")
	)
	(segment
		(start 101.160072 -235.895642)
		(end 101.158802 -235.896404)
		(width 0.1143)
		(layer "In6.Cu")
		(net "GMI_CPU1_G0_CPU0_G2_TX_DN<3>")
	)
	(segment
		(start 104.005888 -222.921576)
		(end 103.978964 -222.93707)
		(width 0.1143)
		(layer "In6.Cu")
		(net "GMI_CPU1_G0_CPU0_G2_TX_DN<3>")
	)
	(segment
		(start 201.001884 -177.018188)
		(end 201.00163 -177.018188)
		(width 0.14224)
		(layer "In6.Cu")
		(net "GMI_CPU1_G0_CPU0_G2_TX_DN<3>")
	)
	(segment
		(start 101.158802 -235.896404)
		(end 101.15804 -235.896912)
		(width 0.1143)
		(layer "In6.Cu")
		(net "GMI_CPU1_G0_CPU0_G2_TX_DN<3>")
	)
	(segment
		(start 104.635554 -221.139004)
		(end 104.635554 -221.325948)
		(width 0.1143)
		(layer "In6.Cu")
		(net "GMI_CPU1_G0_CPU0_G2_TX_DN<3>")
	)
	(segment
		(start 369.835176 -231.220518)
		(end 369.867688 -231.201722)
		(width 0.1143)
		(layer "In6.Cu")
		(net "GMI_CPU1_G0_CPU0_G2_TX_DN<3>")
	)
	(segment
		(start 369.906804 -227.009706)
		(end 369.837208 -226.969066)
		(width 0.1143)
		(layer "In6.Cu")
		(net "GMI_CPU1_G0_CPU0_G2_TX_DN<3>")
	)
	(segment
		(start 114.958114 -206.141066)
		(end 105.816908 -215.282526)
		(width 0.14224)
		(layer "In6.Cu")
		(net "GMI_CPU1_G0_CPU0_G2_TX_DN<3>")
	)
	(segment
		(start 369.835176 -229.600506)
		(end 369.867688 -229.58171)
		(width 0.1143)
		(layer "In6.Cu")
		(net "GMI_CPU1_G0_CPU0_G2_TX_DN<3>")
	)
	(segment
		(start 101.628194 -232.821734)
		(end 101.658674 -232.839514)
		(width 0.1143)
		(layer "In6.Cu")
		(net "GMI_CPU1_G0_CPU0_G2_TX_DN<3>")
	)
	(segment
		(start 369.906804 -233.4895)
		(end 369.837208 -233.44886)
		(width 0.1143)
		(layer "In6.Cu")
		(net "GMI_CPU1_G0_CPU0_G2_TX_DN<3>")
	)
	(segment
		(start 103.068628 -224.539302)
		(end 103.038148 -224.557082)
		(width 0.1143)
		(layer "In6.Cu")
		(net "GMI_CPU1_G0_CPU0_G2_TX_DN<3>")
	)
	(segment
		(start 366.906048 -218.58097)
		(end 365.874554 -216.090754)
		(width 0.14224)
		(layer "In6.Cu")
		(net "GMI_CPU1_G0_CPU0_G2_TX_DN<3>")
	)
	(segment
		(start 101.658674 -226.96932)
		(end 101.628194 -226.9871)
		(width 0.1143)
		(layer "In6.Cu")
		(net "GMI_CPU1_G0_CPU0_G2_TX_DN<3>")
	)
	(segment
		(start 100.249736 -239.118648)
		(end 100.223828 -239.133634)
		(width 0.1143)
		(layer "In6.Cu")
		(net "GMI_CPU1_G0_CPU0_G2_TX_DN<3>")
	)
	(segment
		(start 100.181664 -238.470694)
		(end 100.217986 -238.491776)
		(width 0.1143)
		(layer "In6.Cu")
		(net "GMI_CPU1_G0_CPU0_G2_TX_DN<3>")
	)
	(segment
		(start 366.860328 -221.325694)
		(end 366.860328 -221.13875)
		(width 0.1143)
		(layer "In6.Cu")
		(net "GMI_CPU1_G0_CPU0_G2_TX_DN<3>")
	)
	(segment
		(start 366.906048 -221.09303)
		(end 366.906048 -218.58097)
		(width 0.14224)
		(layer "In6.Cu")
		(net "GMI_CPU1_G0_CPU0_G2_TX_DN<3>")
	)
	(segment
		(start 103.038148 -224.557082)
		(end 102.999032 -224.579942)
		(width 0.1143)
		(layer "In6.Cu")
		(net "GMI_CPU1_G0_CPU0_G2_TX_DN<3>")
	)
	(segment
		(start 101.589078 -227.939092)
		(end 101.628194 -227.961952)
		(width 0.1143)
		(layer "In6.Cu")
		(net "GMI_CPU1_G0_CPU0_G2_TX_DN<3>")
	)
	(segment
		(start 100.218748 -240.112296)
		(end 100.249736 -240.130076)
		(width 0.1143)
		(layer "In6.Cu")
		(net "GMI_CPU1_G0_CPU0_G2_TX_DN<3>")
	)
	(segment
		(start 103.978964 -222.93707)
		(end 103.937054 -222.961454)
		(width 0.1143)
		(layer "In6.Cu")
		(net "GMI_CPU1_G0_CPU0_G2_TX_DN<3>")
	)
	(segment
		(start 101.658674 -235.069126)
		(end 101.628194 -235.086906)
		(width 0.1143)
		(layer "In6.Cu")
		(net "GMI_CPU1_G0_CPU0_G2_TX_DN<3>")
	)
	(segment
		(start 101.18979 -235.878624)
		(end 101.160072 -235.895642)
		(width 0.1143)
		(layer "In6.Cu")
		(net "GMI_CPU1_G0_CPU0_G2_TX_DN<3>")
	)
	(segment
		(start 368.02695 -223.769682)
		(end 367.987834 -223.746822)
		(width 0.1143)
		(layer "In6.Cu")
		(net "GMI_CPU1_G0_CPU0_G2_TX_DN<3>")
	)
	(segment
		(start 100.179124 -239.159542)
		(end 100.151184 -239.179608)
		(width 0.1143)
		(layer "In6.Cu")
		(net "GMI_CPU1_G0_CPU0_G2_TX_DN<3>")
	)
	(segment
		(start 366.860074 -221.325948)
		(end 366.860328 -221.325694)
		(width 0.1143)
		(layer "In6.Cu")
		(net "GMI_CPU1_G0_CPU0_G2_TX_DN<3>")
	)
	(segment
		(start 115.459002 -205.757018)
		(end 114.958114 -206.141066)
		(width 0.14224)
		(layer "In6.Cu")
		(net "GMI_CPU1_G0_CPU0_G2_TX_DN<3>")
	)
	(segment
		(start 166.994078 -176.81956)
		(end 162.691572 -177.959258)
		(width 0.14224)
		(layer "In6.Cu")
		(net "GMI_CPU1_G0_CPU0_G2_TX_DN<3>")
	)
	(segment
		(start 371.28069 -240.109756)
		(end 371.316758 -240.088928)
		(width 0.1143)
		(layer "In6.Cu")
		(net "GMI_CPU1_G0_CPU0_G2_TX_DN<3>")
	)
	(segment
		(start 370.696998 -241.24412)
		(end 370.627148 -241.17427)
		(width 0.1143)
		(layer "In6.Cu")
		(net "GMI_CPU1_G0_CPU0_G2_TX_DN<3>")
	)
	(segment
		(start 101.628194 -231.846882)
		(end 101.589078 -231.869742)
		(width 0.1143)
		(layer "In6.Cu")
		(net "GMI_CPU1_G0_CPU0_G2_TX_DN<3>")
	)
	(segment
		(start 100.71862 -236.689138)
		(end 100.68814 -236.706918)
		(width 0.1143)
		(layer "In6.Cu")
		(net "GMI_CPU1_G0_CPU0_G2_TX_DN<3>")
	)
	(segment
		(start 101.658674 -228.589332)
		(end 101.628194 -228.607112)
		(width 0.1143)
		(layer "In6.Cu")
		(net "GMI_CPU1_G0_CPU0_G2_TX_DN<3>")
	)
	(segment
		(start 370.340382 -235.898182)
		(end 370.338858 -235.897166)
		(width 0.1143)
		(layer "In6.Cu")
		(net "GMI_CPU1_G0_CPU0_G2_TX_DN<3>")
	)
	(segment
		(start 102.567994 -225.367088)
		(end 102.564184 -225.369374)
		(width 0.1143)
		(layer "In6.Cu")
		(net "GMI_CPU1_G0_CPU0_G2_TX_DN<3>")
	)
	(segment
		(start 367.04778 -222.12681)
		(end 367.01603 -222.108522)
		(width 0.1143)
		(layer "In6.Cu")
		(net "GMI_CPU1_G0_CPU0_G2_TX_DN<3>")
	)
	(segment
		(start 371.27561 -239.135412)
		(end 371.274594 -239.134904)
		(width 0.1143)
		(layer "In6.Cu")
		(net "GMI_CPU1_G0_CPU0_G2_TX_DN<3>")
	)
	(segment
		(start 323.673724 -186.568842)
		(end 309.901336 -178.390804)
		(width 0.14224)
		(layer "In6.Cu")
		(net "GMI_CPU1_G0_CPU0_G2_TX_DN<3>")
	)
	(segment
		(start 371.277896 -237.51667)
		(end 371.246146 -237.498382)
		(width 0.1143)
		(layer "In6.Cu")
		(net "GMI_CPU1_G0_CPU0_G2_TX_DN<3>")
	)
	(segment
		(start 371.277896 -240.111534)
		(end 371.28069 -240.109756)
		(width 0.1143)
		(layer "In6.Cu")
		(net "GMI_CPU1_G0_CPU0_G2_TX_DN<3>")
	)
	(segment
		(start 371.246146 -240.129822)
		(end 371.275864 -240.112804)
		(width 0.1143)
		(layer "In6.Cu")
		(net "GMI_CPU1_G0_CPU0_G2_TX_DN<3>")
	)
	(segment
		(start 100.215192 -240.11001)
		(end 100.217986 -240.111788)
		(width 0.1143)
		(layer "In6.Cu")
		(net "GMI_CPU1_G0_CPU0_G2_TX_DN<3>")
	)
	(segment
		(start 369.906804 -235.109512)
		(end 369.837208 -235.068872)
		(width 0.1143)
		(layer "In6.Cu")
		(net "GMI_CPU1_G0_CPU0_G2_TX_DN<3>")
	)
	(segment
		(start 371.274594 -239.134904)
		(end 371.273832 -239.134396)
		(width 0.1143)
		(layer "In6.Cu")
		(net "GMI_CPU1_G0_CPU0_G2_TX_DN<3>")
	)
	(segment
		(start 100.223828 -239.133634)
		(end 100.223066 -239.134142)
		(width 0.1143)
		(layer "In6.Cu")
		(net "GMI_CPU1_G0_CPU0_G2_TX_DN<3>")
	)
	(segment
		(start 101.589078 -232.798874)
		(end 101.628194 -232.821734)
		(width 0.1143)
		(layer "In6.Cu")
		(net "GMI_CPU1_G0_CPU0_G2_TX_DN<3>")
	)
	(segment
		(start 100.68814 -240.921794)
		(end 100.71862 -240.939574)
		(width 0.1143)
		(layer "In6.Cu")
		(net "GMI_CPU1_G0_CPU0_G2_TX_DN<3>")
	)
	(segment
		(start 368.49685 -224.579688)
		(end 368.427254 -224.539048)
		(width 0.1143)
		(layer "In6.Cu")
		(net "GMI_CPU1_G0_CPU0_G2_TX_DN<3>")
	)
	(segment
		(start 370.33708 -235.89615)
		(end 370.33581 -235.895388)
		(width 0.1143)
		(layer "In6.Cu")
		(net "GMI_CPU1_G0_CPU0_G2_TX_DN<3>")
	)
	(segment
		(start 100.68814 -236.706918)
		(end 100.649024 -236.729778)
		(width 0.1143)
		(layer "In6.Cu")
		(net "GMI_CPU1_G0_CPU0_G2_TX_DN<3>")
	)
	(segment
		(start 369.837208 -234.459272)
		(end 369.906804 -234.418632)
		(width 0.1143)
		(layer "In6.Cu")
		(net "GMI_CPU1_G0_CPU0_G2_TX_DN<3>")
	)
	(segment
		(start 101.589078 -231.179116)
		(end 101.628194 -231.201976)
		(width 0.1143)
		(layer "In6.Cu")
		(net "GMI_CPU1_G0_CPU0_G2_TX_DN<3>")
	)
	(segment
		(start 100.217986 -237.516924)
		(end 100.181664 -237.538006)
		(width 0.1143)
		(layer "In6.Cu")
		(net "GMI_CPU1_G0_CPU0_G2_TX_DN<3>")
	)
	(segment
		(start 100.179124 -240.089182)
		(end 100.215192 -240.11001)
		(width 0.1143)
		(layer "In6.Cu")
		(net "GMI_CPU1_G0_CPU0_G2_TX_DN<3>")
	)
	(segment
		(start 370.376958 -235.919518)
		(end 370.340382 -235.898182)
		(width 0.1143)
		(layer "In6.Cu")
		(net "GMI_CPU1_G0_CPU0_G2_TX_DN<3>")
	)
	(segment
		(start 100.221288 -239.135158)
		(end 100.220272 -239.135666)
		(width 0.1143)
		(layer "In6.Cu")
		(net "GMI_CPU1_G0_CPU0_G2_TX_DN<3>")
	)
	(segment
		(start 100.217986 -240.111788)
		(end 100.218748 -240.112296)
		(width 0.1143)
		(layer "In6.Cu")
		(net "GMI_CPU1_G0_CPU0_G2_TX_DN<3>")
	)
	(segment
		(start 369.906804 -231.869488)
		(end 369.837208 -231.828848)
		(width 0.1143)
		(layer "In6.Cu")
		(net "GMI_CPU1_G0_CPU0_G2_TX_DN<3>")
	)
	(segment
		(start 307.06822 -177.613056)
		(end 302.911256 -177.613056)
		(width 0.14224)
		(layer "In6.Cu")
		(net "GMI_CPU1_G0_CPU0_G2_TX_DN<3>")
	)
	(segment
		(start 101.628194 -233.466894)
		(end 101.589078 -233.489754)
		(width 0.1143)
		(layer "In6.Cu")
		(net "GMI_CPU1_G0_CPU0_G2_TX_DN<3>")
	)
	(segment
		(start 100.218748 -238.492284)
		(end 100.249736 -238.510064)
		(width 0.1143)
		(layer "In6.Cu")
		(net "GMI_CPU1_G0_CPU0_G2_TX_DN<3>")
	)
	(segment
		(start 365.874554 -216.090754)
		(end 361.392724 -211.608924)
		(width 0.14224)
		(layer "In6.Cu")
		(net "GMI_CPU1_G0_CPU0_G2_TX_DN<3>")
	)
	(segment
		(start 302.911256 -177.613056)
		(end 201.001884 -177.018188)
		(width 0.14224)
		(layer "In6.Cu")
		(net "GMI_CPU1_G0_CPU0_G2_TX_DN<3>")
	)
	(segment
		(start 103.543862 -223.726248)
		(end 103.508048 -223.747076)
		(width 0.1143)
		(layer "In6.Cu")
		(net "GMI_CPU1_G0_CPU0_G2_TX_DN<3>")
	)
	(segment
		(start 100.217986 -238.491776)
		(end 100.218748 -238.492284)
		(width 0.1143)
		(layer "In6.Cu")
		(net "GMI_CPU1_G0_CPU0_G2_TX_DN<3>")
	)
	(segment
		(start 162.691572 -177.959258)
		(end 118.218458 -203.639674)
		(width 0.14224)
		(layer "In6.Cu")
		(net "GMI_CPU1_G0_CPU0_G2_TX_DN<3>")
	)
	(segment
		(start 100.151184 -240.069116)
		(end 100.179124 -240.089182)
		(width 0.1143)
		(layer "In6.Cu")
		(net "GMI_CPU1_G0_CPU0_G2_TX_DN<3>")
	)
	(segment
		(start 101.589078 -234.418886)
		(end 101.628194 -234.441746)
		(width 0.1143)
		(layer "In6.Cu")
		(net "GMI_CPU1_G0_CPU0_G2_TX_DN<3>")
	)
	(segment
		(start 101.628194 -226.9871)
		(end 101.589078 -227.00996)
		(width 0.1143)
		(layer "In6.Cu")
		(net "GMI_CPU1_G0_CPU0_G2_TX_DN<3>")
	)
	(segment
		(start 369.436904 -226.1997)
		(end 369.397788 -226.17684)
		(width 0.1143)
		(layer "In6.Cu")
		(net "GMI_CPU1_G0_CPU0_G2_TX_DN<3>")
	)
	(segment
		(start 366.860074 -221.80423)
		(end 366.860074 -221.325948)
		(width 0.1143)
		(layer "In6.Cu")
		(net "GMI_CPU1_G0_CPU0_G2_TX_DN<3>")
	)
	(segment
		(start 370.338858 -235.897166)
		(end 370.337842 -235.896658)
		(width 0.1143)
		(layer "In6.Cu")
		(net "GMI_CPU1_G0_CPU0_G2_TX_DN<3>")
	)
	(segment
		(start 369.837208 -232.83926)
		(end 369.906804 -232.79862)
		(width 0.1143)
		(layer "In6.Cu")
		(net "GMI_CPU1_G0_CPU0_G2_TX_DN<3>")
	)
	(segment
		(start 101.628194 -229.581964)
		(end 101.660706 -229.60076)
		(width 0.1143)
		(layer "In6.Cu")
		(net "GMI_CPU1_G0_CPU0_G2_TX_DN<3>")
	)
	(segment
		(start 370.846858 -236.729524)
		(end 370.777262 -236.688884)
		(width 0.1143)
		(layer "In6.Cu")
		(net "GMI_CPU1_G0_CPU0_G2_TX_DN<3>")
	)
	(segment
		(start 104.635554 -221.325948)
		(end 104.635808 -221.326202)
		(width 0.1143)
		(layer "In6.Cu")
		(net "GMI_CPU1_G0_CPU0_G2_TX_DN<3>")
	)
	(segment
		(start 100.223066 -239.134142)
		(end 100.22205 -239.13465)
		(width 0.1143)
		(layer "In6.Cu")
		(net "GMI_CPU1_G0_CPU0_G2_TX_DN<3>")
	)
	(segment
		(start 371.275864 -238.492792)
		(end 371.277134 -238.49203)
		(width 0.1143)
		(layer "In6.Cu")
		(net "GMI_CPU1_G0_CPU0_G2_TX_DN<3>")
	)
	(segment
		(start 368.931698 -225.36912)
		(end 368.927888 -225.366834)
		(width 0.1143)
		(layer "In6.Cu")
		(net "GMI_CPU1_G0_CPU0_G2_TX_DN<3>")
	)
	(segment
		(start 309.901336 -178.390804)
		(end 307.06822 -177.613056)
		(width 0.14224)
		(layer "In6.Cu")
		(net "GMI_CPU1_G0_CPU0_G2_TX_DN<3>")
	)
	(segment
		(start 366.860328 -221.13875)
		(end 366.906048 -221.09303)
		(width 0.1143)
		(layer "In6.Cu")
		(net "GMI_CPU1_G0_CPU0_G2_TX_DN<3>")
	)
	(segment
		(start 361.392724 -211.608924)
		(end 356.53599 -207.73517)
		(width 0.14224)
		(layer "In6.Cu")
		(net "GMI_CPU1_G0_CPU0_G2_TX_DN<3>")
	)
	(segment
		(start 100.22205 -239.13465)
		(end 100.221288 -239.135158)
		(width 0.1143)
		(layer "In6.Cu")
		(net "GMI_CPU1_G0_CPU0_G2_TX_DN<3>")
	)
	(segment
		(start 115.458748 -205.757018)
		(end 115.459002 -205.757018)
		(width 0.14224)
		(layer "In6.Cu")
		(net "GMI_CPU1_G0_CPU0_G2_TX_DN<3>")
	)
	(segment
		(start 201.00163 -177.018188)
		(end 166.994078 -176.81956)
		(width 0.14224)
		(layer "In6.Cu")
		(net "GMI_CPU1_G0_CPU0_G2_TX_DN<3>")
	)
	(segment
		(start 100.220272 -239.135666)
		(end 100.21951 -239.136174)
		(width 0.1143)
		(layer "In6.Cu")
		(net "GMI_CPU1_G0_CPU0_G2_TX_DN<3>")
	)
	(segment
		(start 371.314218 -237.537752)
		(end 371.277896 -237.51667)
		(width 0.1143)
		(layer "In6.Cu")
		(net "GMI_CPU1_G0_CPU0_G2_TX_DN<3>")
	)
	(segment
		(start 367.558828 -222.9612)
		(end 367.516918 -222.936816)
		(width 0.1143)
		(layer "In6.Cu")
		(net "GMI_CPU1_G0_CPU0_G2_TX_DN<3>")
	)
	(segment
		(start 371.276372 -239.13592)
		(end 371.27561 -239.135412)
		(width 0.1143)
		(layer "In6.Cu")
		(net "GMI_CPU1_G0_CPU0_G2_TX_DN<3>")
	)
	(segment
		(start 104.589834 -218.244928)
		(end 104.589834 -221.064836)
		(width 0.14224)
		(layer "In6.Cu")
		(net "GMI_CPU1_G0_CPU0_G2_TX_DN<3>")
	)
	(segment
		(start 100.249736 -237.498636)
		(end 100.217986 -237.516924)
		(width 0.1143)
		(layer "In6.Cu")
		(net "GMI_CPU1_G0_CPU0_G2_TX_DN<3>")
	)
	(segment
		(start 103.508048 -223.747076)
		(end 103.468932 -223.769936)
		(width 0.1143)
		(layer "In6.Cu")
		(net "GMI_CPU1_G0_CPU0_G2_TX_DN<3>")
	)
	(segment
		(start 367.081054 -222.146114)
		(end 367.04778 -222.12681)
		(width 0.1143)
		(layer "In6.Cu")
		(net "GMI_CPU1_G0_CPU0_G2_TX_DN<3>")
	)
	(segment
		(start 104.589834 -221.064836)
		(end 104.589834 -221.093284)
		(width 0.1143)
		(layer "In6.Cu")
		(net "GMI_CPU1_G0_CPU0_G2_TX_DN<3>")
	)
	(segment
		(start 101.658674 -231.829102)
		(end 101.628194 -231.846882)
		(width 0.1143)
		(layer "In6.Cu")
		(net "GMI_CPU1_G0_CPU0_G2_TX_DN<3>")
	)
	(segment
		(start 325.711058 -188.358272)
		(end 323.673724 -186.568842)
		(width 0.14224)
		(layer "In6.Cu")
		(net "GMI_CPU1_G0_CPU0_G2_TX_DN<3>")
	)
	(segment
		(start 369.837208 -227.979478)
		(end 369.906804 -227.938838)
		(width 0.1143)
		(layer "In6.Cu")
		(net "GMI_CPU1_G0_CPU0_G2_TX_DN<3>")
	)
	(segment
		(start 370.994686 -241.24412)
		(end 370.696998 -241.24412)
		(width 0.1143)
		(layer "In6.Cu")
		(net "GMI_CPU1_G0_CPU0_G2_TX_DN<3>")
	)
	(segment
		(start 368.927888 -225.366834)
		(end 368.896138 -225.348546)
		(width 0.1143)
		(layer "In6.Cu")
		(net "GMI_CPU1_G0_CPU0_G2_TX_DN<3>")
	)
	(segment
		(start 371.277896 -238.491522)
		(end 371.314218 -238.47044)
		(width 0.1143)
		(layer "In6.Cu")
		(net "GMI_CPU1_G0_CPU0_G2_TX_DN<3>")
	)
	(arc
		(start 100.405692 -237.194344)
		(mid 100.364437 -237.365315)
		(end 100.249736 -237.498636)
		(width 0.1143)
		(layer "In6.Cu")
		(net "GMI_CPU1_G0_CPU0_G2_TX_DN<3>")
	)
	(arc
		(start 100.649024 -236.729778)
		(mid 100.470211 -236.932128)
		(end 100.405692 -237.194344)
		(width 0.1143)
		(layer "In6.Cu")
		(net "GMI_CPU1_G0_CPU0_G2_TX_DN<3>")
	)
	(arc
		(start 104.414828 -222.146368)
		(mid 104.232166 -222.349449)
		(end 104.166162 -222.61449)
		(width 0.1143)
		(layer "In6.Cu")
		(net "GMI_CPU1_G0_CPU0_G2_TX_DN<3>")
	)
	(arc
		(start 101.660706 -229.60076)
		(mid 101.774635 -229.733907)
		(end 101.815646 -229.90429)
		(width 0.1143)
		(layer "In6.Cu")
		(net "GMI_CPU1_G0_CPU0_G2_TX_DN<3>")
	)
	(arc
		(start 101.815646 -231.524302)
		(mid 101.774097 -231.695724)
		(end 101.658674 -231.829102)
		(width 0.1143)
		(layer "In6.Cu")
		(net "GMI_CPU1_G0_CPU0_G2_TX_DN<3>")
	)
	(arc
		(start 369.680236 -231.524048)
		(mid 369.721202 -231.353642)
		(end 369.835176 -231.220518)
		(width 0.1143)
		(layer "In6.Cu")
		(net "GMI_CPU1_G0_CPU0_G2_TX_DN<3>")
	)
	(arc
		(start 369.837208 -226.969066)
		(mid 369.721781 -226.83569)
		(end 369.680236 -226.664266)
		(width 0.1143)
		(layer "In6.Cu")
		(net "GMI_CPU1_G0_CPU0_G2_TX_DN<3>")
	)
	(arc
		(start 369.837208 -230.208836)
		(mid 369.721781 -230.07546)
		(end 369.680236 -229.904036)
		(width 0.1143)
		(layer "In6.Cu")
		(net "GMI_CPU1_G0_CPU0_G2_TX_DN<3>")
	)
	(arc
		(start 369.837208 -231.828848)
		(mid 369.721781 -231.695472)
		(end 369.680236 -231.524048)
		(width 0.1143)
		(layer "In6.Cu")
		(net "GMI_CPU1_G0_CPU0_G2_TX_DN<3>")
	)
	(arc
		(start 369.837208 -235.068872)
		(mid 369.680231 -234.764072)
		(end 369.837208 -234.459272)
		(width 0.1143)
		(layer "In6.Cu")
		(net "GMI_CPU1_G0_CPU0_G2_TX_DN<3>")
	)
	(arc
		(start 100.71862 -240.939574)
		(mid 100.816385 -241.04255)
		(end 100.868734 -241.174524)
		(width 0.1143)
		(layer "In6.Cu")
		(net "GMI_CPU1_G0_CPU0_G2_TX_DN<3>")
	)
	(arc
		(start 101.660706 -231.220772)
		(mid 101.774635 -231.353919)
		(end 101.815646 -231.524302)
		(width 0.1143)
		(layer "In6.Cu")
		(net "GMI_CPU1_G0_CPU0_G2_TX_DN<3>")
	)
	(arc
		(start 100.405692 -240.434368)
		(mid 100.470207 -240.696587)
		(end 100.649024 -240.898934)
		(width 0.1143)
		(layer "In6.Cu")
		(net "GMI_CPU1_G0_CPU0_G2_TX_DN<3>")
	)
	(arc
		(start 101.658674 -227.979732)
		(mid 101.815651 -228.284532)
		(end 101.658674 -228.589332)
		(width 0.1143)
		(layer "In6.Cu")
		(net "GMI_CPU1_G0_CPU0_G2_TX_DN<3>")
	)
	(arc
		(start 104.166162 -222.61449)
		(mid 104.123689 -222.787694)
		(end 104.005888 -222.921576)
		(width 0.1143)
		(layer "In6.Cu")
		(net "GMI_CPU1_G0_CPU0_G2_TX_DN<3>")
	)
	(arc
		(start 367.32972 -222.614236)
		(mid 367.26369 -222.349208)
		(end 367.081054 -222.146114)
		(width 0.1143)
		(layer "In6.Cu")
		(net "GMI_CPU1_G0_CPU0_G2_TX_DN<3>")
	)
	(arc
		(start 371.314218 -238.47044)
		(mid 371.322396 -238.464797)
		(end 371.330474 -238.45901)
		(width 0.1143)
		(layer "In6.Cu")
		(net "GMI_CPU1_G0_CPU0_G2_TX_DN<3>")
	)
	(arc
		(start 102.999032 -224.579942)
		(mid 102.820219 -224.782292)
		(end 102.7557 -225.044508)
		(width 0.1143)
		(layer "In6.Cu")
		(net "GMI_CPU1_G0_CPU0_G2_TX_DN<3>")
	)
	(arc
		(start 101.118924 -235.919772)
		(mid 100.940111 -236.122122)
		(end 100.875592 -236.384338)
		(width 0.1143)
		(layer "In6.Cu")
		(net "GMI_CPU1_G0_CPU0_G2_TX_DN<3>")
	)
	(arc
		(start 101.589078 -233.489754)
		(mid 101.345751 -233.95432)
		(end 101.589078 -234.418886)
		(width 0.1143)
		(layer "In6.Cu")
		(net "GMI_CPU1_G0_CPU0_G2_TX_DN<3>")
	)
	(arc
		(start 101.345746 -230.71455)
		(mid 101.410261 -230.976769)
		(end 101.589078 -231.179116)
		(width 0.1143)
		(layer "In6.Cu")
		(net "GMI_CPU1_G0_CPU0_G2_TX_DN<3>")
	)
	(arc
		(start 101.815646 -226.66452)
		(mid 101.774097 -226.835942)
		(end 101.658674 -226.96932)
		(width 0.1143)
		(layer "In6.Cu")
		(net "GMI_CPU1_G0_CPU0_G2_TX_DN<3>")
	)
	(arc
		(start 100.249736 -238.510064)
		(mid 100.405664 -238.814356)
		(end 100.249736 -239.118648)
		(width 0.1143)
		(layer "In6.Cu")
		(net "GMI_CPU1_G0_CPU0_G2_TX_DN<3>")
	)
	(arc
		(start 371.344698 -240.068862)
		(mid 371.572698 -239.624108)
		(end 371.344698 -239.179354)
		(width 0.1143)
		(layer "In6.Cu")
		(net "GMI_CPU1_G0_CPU0_G2_TX_DN<3>")
	)
	(arc
		(start 371.246146 -239.118394)
		(mid 371.090218 -238.814102)
		(end 371.246146 -238.50981)
		(width 0.1143)
		(layer "In6.Cu")
		(net "GMI_CPU1_G0_CPU0_G2_TX_DN<3>")
	)
	(arc
		(start 103.2256 -224.234502)
		(mid 103.184051 -224.405924)
		(end 103.068628 -224.539302)
		(width 0.1143)
		(layer "In6.Cu")
		(net "GMI_CPU1_G0_CPU0_G2_TX_DN<3>")
	)
	(arc
		(start 368.270282 -224.234248)
		(mid 368.205767 -223.972029)
		(end 368.02695 -223.769682)
		(width 0.1143)
		(layer "In6.Cu")
		(net "GMI_CPU1_G0_CPU0_G2_TX_DN<3>")
	)
	(arc
		(start 371.246146 -237.498382)
		(mid 371.13147 -237.365048)
		(end 371.09019 -237.19409)
		(width 0.1143)
		(layer "In6.Cu")
		(net "GMI_CPU1_G0_CPU0_G2_TX_DN<3>")
	)
	(arc
		(start 368.740182 -225.044254)
		(mid 368.675667 -224.782035)
		(end 368.49685 -224.579688)
		(width 0.1143)
		(layer "In6.Cu")
		(net "GMI_CPU1_G0_CPU0_G2_TX_DN<3>")
	)
	(arc
		(start 101.815646 -229.90429)
		(mid 101.774097 -230.075712)
		(end 101.658674 -230.20909)
		(width 0.1143)
		(layer "In6.Cu")
		(net "GMI_CPU1_G0_CPU0_G2_TX_DN<3>")
	)
	(arc
		(start 101.589078 -235.109766)
		(mid 101.410265 -235.312116)
		(end 101.345746 -235.574332)
		(width 0.1143)
		(layer "In6.Cu")
		(net "GMI_CPU1_G0_CPU0_G2_TX_DN<3>")
	)
	(arc
		(start 102.7557 -225.044508)
		(mid 102.714445 -225.215479)
		(end 102.599744 -225.3488)
		(width 0.1143)
		(layer "In6.Cu")
		(net "GMI_CPU1_G0_CPU0_G2_TX_DN<3>")
	)
	(arc
		(start 369.680236 -229.904036)
		(mid 369.721202 -229.73363)
		(end 369.835176 -229.600506)
		(width 0.1143)
		(layer "In6.Cu")
		(net "GMI_CPU1_G0_CPU0_G2_TX_DN<3>")
	)
	(arc
		(start 369.837208 -228.589078)
		(mid 369.680231 -228.284278)
		(end 369.837208 -227.979478)
		(width 0.1143)
		(layer "In6.Cu")
		(net "GMI_CPU1_G0_CPU0_G2_TX_DN<3>")
	)
	(arc
		(start 101.589078 -231.869742)
		(mid 101.345751 -232.334308)
		(end 101.589078 -232.798874)
		(width 0.1143)
		(layer "In6.Cu")
		(net "GMI_CPU1_G0_CPU0_G2_TX_DN<3>")
	)
	(arc
		(start 367.01603 -222.108522)
		(mid 366.904233 -221.973721)
		(end 366.860074 -221.80423)
		(width 0.1143)
		(layer "In6.Cu")
		(net "GMI_CPU1_G0_CPU0_G2_TX_DN<3>")
	)
	(arc
		(start 104.635808 -221.804484)
		(mid 104.591737 -221.97402)
		(end 104.479852 -222.108776)
		(width 0.1143)
		(layer "In6.Cu")
		(net "GMI_CPU1_G0_CPU0_G2_TX_DN<3>")
	)
	(arc
		(start 369.906804 -229.55885)
		(mid 370.150131 -229.094284)
		(end 369.906804 -228.629718)
		(width 0.1143)
		(layer "In6.Cu")
		(net "GMI_CPU1_G0_CPU0_G2_TX_DN<3>")
	)
	(arc
		(start 103.468932 -223.769936)
		(mid 103.290119 -223.972286)
		(end 103.2256 -224.234502)
		(width 0.1143)
		(layer "In6.Cu")
		(net "GMI_CPU1_G0_CPU0_G2_TX_DN<3>")
	)
	(arc
		(start 371.330474 -237.549182)
		(mid 371.322396 -237.543396)
		(end 371.314218 -237.537752)
		(width 0.1143)
		(layer "In6.Cu")
		(net "GMI_CPU1_G0_CPU0_G2_TX_DN<3>")
	)
	(arc
		(start 369.906804 -227.938838)
		(mid 370.150131 -227.474272)
		(end 369.906804 -227.009706)
		(width 0.1143)
		(layer "In6.Cu")
		(net "GMI_CPU1_G0_CPU0_G2_TX_DN<3>")
	)
	(arc
		(start 370.777262 -236.688884)
		(mid 370.661835 -236.555508)
		(end 370.62029 -236.384084)
		(width 0.1143)
		(layer "In6.Cu")
		(net "GMI_CPU1_G0_CPU0_G2_TX_DN<3>")
	)
	(arc
		(start 101.591618 -230.248206)
		(mid 101.410966 -230.450951)
		(end 101.345746 -230.71455)
		(width 0.1143)
		(layer "In6.Cu")
		(net "GMI_CPU1_G0_CPU0_G2_TX_DN<3>")
	)
	(arc
		(start 100.875592 -236.384338)
		(mid 100.834043 -236.55576)
		(end 100.71862 -236.689138)
		(width 0.1143)
		(layer "In6.Cu")
		(net "GMI_CPU1_G0_CPU0_G2_TX_DN<3>")
	)
	(arc
		(start 371.09019 -237.19409)
		(mid 371.025675 -236.931871)
		(end 370.846858 -236.729524)
		(width 0.1143)
		(layer "In6.Cu")
		(net "GMI_CPU1_G0_CPU0_G2_TX_DN<3>")
	)
	(arc
		(start 101.345746 -235.574332)
		(mid 101.304491 -235.745303)
		(end 101.18979 -235.878624)
		(width 0.1143)
		(layer "In6.Cu")
		(net "GMI_CPU1_G0_CPU0_G2_TX_DN<3>")
	)
	(arc
		(start 369.39728 -226.176586)
		(mid 369.260464 -226.039836)
		(end 369.210336 -225.85299)
		(width 0.1143)
		(layer "In6.Cu")
		(net "GMI_CPU1_G0_CPU0_G2_TX_DN<3>")
	)
	(arc
		(start 101.589078 -228.629972)
		(mid 101.345751 -229.094538)
		(end 101.589078 -229.559104)
		(width 0.1143)
		(layer "In6.Cu")
		(net "GMI_CPU1_G0_CPU0_G2_TX_DN<3>")
	)
	(arc
		(start 369.837208 -233.44886)
		(mid 369.680231 -233.14406)
		(end 369.837208 -232.83926)
		(width 0.1143)
		(layer "In6.Cu")
		(net "GMI_CPU1_G0_CPU0_G2_TX_DN<3>")
	)
	(arc
		(start 370.306092 -235.87837)
		(mid 370.191416 -235.745036)
		(end 370.150136 -235.574078)
		(width 0.1143)
		(layer "In6.Cu")
		(net "GMI_CPU1_G0_CPU0_G2_TX_DN<3>")
	)
	(arc
		(start 103.696262 -223.424496)
		(mid 103.655998 -223.59352)
		(end 103.543862 -223.726248)
		(width 0.1143)
		(layer "In6.Cu")
		(net "GMI_CPU1_G0_CPU0_G2_TX_DN<3>")
	)
	(arc
		(start 369.210336 -225.85299)
		(mid 369.135707 -225.573795)
		(end 368.931698 -225.36912)
		(width 0.1143)
		(layer "In6.Cu")
		(net "GMI_CPU1_G0_CPU0_G2_TX_DN<3>")
	)
	(arc
		(start 367.489994 -222.921322)
		(mid 367.37222 -222.787427)
		(end 367.32972 -222.614236)
		(width 0.1143)
		(layer "In6.Cu")
		(net "GMI_CPU1_G0_CPU0_G2_TX_DN<3>")
	)
	(arc
		(start 103.937054 -222.961454)
		(mid 103.760072 -223.163546)
		(end 103.696262 -223.424496)
		(width 0.1143)
		(layer "In6.Cu")
		(net "GMI_CPU1_G0_CPU0_G2_TX_DN<3>")
	)
	(arc
		(start 370.150136 -230.714296)
		(mid 370.0849 -230.450705)
		(end 369.904264 -230.247952)
		(width 0.1143)
		(layer "In6.Cu")
		(net "GMI_CPU1_G0_CPU0_G2_TX_DN<3>")
	)
	(arc
		(start 367.79962 -223.424242)
		(mid 367.735828 -223.163283)
		(end 367.558828 -222.9612)
		(width 0.1143)
		(layer "In6.Cu")
		(net "GMI_CPU1_G0_CPU0_G2_TX_DN<3>")
	)
	(arc
		(start 370.627148 -241.17427)
		(mid 370.679565 -241.042339)
		(end 370.777262 -240.93932)
		(width 0.1143)
		(layer "In6.Cu")
		(net "GMI_CPU1_G0_CPU0_G2_TX_DN<3>")
	)
	(arc
		(start 367.95202 -223.725994)
		(mid 367.839873 -223.593271)
		(end 367.79962 -223.424242)
		(width 0.1143)
		(layer "In6.Cu")
		(net "GMI_CPU1_G0_CPU0_G2_TX_DN<3>")
	)
	(arc
		(start 368.427254 -224.539048)
		(mid 368.311827 -224.405672)
		(end 368.270282 -224.234248)
		(width 0.1143)
		(layer "In6.Cu")
		(net "GMI_CPU1_G0_CPU0_G2_TX_DN<3>")
	)
	(arc
		(start 101.658674 -234.459526)
		(mid 101.815651 -234.764326)
		(end 101.658674 -235.069126)
		(width 0.1143)
		(layer "In6.Cu")
		(net "GMI_CPU1_G0_CPU0_G2_TX_DN<3>")
	)
	(arc
		(start 369.906804 -231.178862)
		(mid 370.085617 -230.976512)
		(end 370.150136 -230.714296)
		(width 0.1143)
		(layer "In6.Cu")
		(net "GMI_CPU1_G0_CPU0_G2_TX_DN<3>")
	)
	(arc
		(start 100.165408 -238.459264)
		(mid 100.173486 -238.46505)
		(end 100.181664 -238.470694)
		(width 0.1143)
		(layer "In6.Cu")
		(net "GMI_CPU1_G0_CPU0_G2_TX_DN<3>")
	)
	(arc
		(start 369.680236 -226.664266)
		(mid 369.615721 -226.402047)
		(end 369.436904 -226.1997)
		(width 0.1143)
		(layer "In6.Cu")
		(net "GMI_CPU1_G0_CPU0_G2_TX_DN<3>")
	)
	(arc
		(start 102.058978 -226.199954)
		(mid 101.880165 -226.402304)
		(end 101.815646 -226.66452)
		(width 0.1143)
		(layer "In6.Cu")
		(net "GMI_CPU1_G0_CPU0_G2_TX_DN<3>")
	)
	(arc
		(start 101.658674 -232.839514)
		(mid 101.815651 -233.144314)
		(end 101.658674 -233.449114)
		(width 0.1143)
		(layer "In6.Cu")
		(net "GMI_CPU1_G0_CPU0_G2_TX_DN<3>")
	)
	(arc
		(start 370.150136 -235.574078)
		(mid 370.085621 -235.311859)
		(end 369.906804 -235.109512)
		(width 0.1143)
		(layer "In6.Cu")
		(net "GMI_CPU1_G0_CPU0_G2_TX_DN<3>")
	)
	(arc
		(start 100.249736 -240.130076)
		(mid 100.364412 -240.26341)
		(end 100.405692 -240.434368)
		(width 0.1143)
		(layer "In6.Cu")
		(net "GMI_CPU1_G0_CPU0_G2_TX_DN<3>")
	)
	(arc
		(start 369.906804 -232.79862)
		(mid 370.150131 -232.334054)
		(end 369.906804 -231.869488)
		(width 0.1143)
		(layer "In6.Cu")
		(net "GMI_CPU1_G0_CPU0_G2_TX_DN<3>")
	)
	(arc
		(start 368.896138 -225.348546)
		(mid 368.781462 -225.215212)
		(end 368.740182 -225.044254)
		(width 0.1143)
		(layer "In6.Cu")
		(net "GMI_CPU1_G0_CPU0_G2_TX_DN<3>")
	)
	(arc
		(start 369.906804 -234.418632)
		(mid 370.150131 -233.954066)
		(end 369.906804 -233.4895)
		(width 0.1143)
		(layer "In6.Cu")
		(net "GMI_CPU1_G0_CPU0_G2_TX_DN<3>")
	)
	(arc
		(start 370.846858 -240.89868)
		(mid 371.025671 -240.69633)
		(end 371.09019 -240.434114)
		(width 0.1143)
		(layer "In6.Cu")
		(net "GMI_CPU1_G0_CPU0_G2_TX_DN<3>")
	)
	(arc
		(start 371.09019 -240.434114)
		(mid 371.131445 -240.263143)
		(end 371.246146 -240.129822)
		(width 0.1143)
		(layer "In6.Cu")
		(net "GMI_CPU1_G0_CPU0_G2_TX_DN<3>")
	)
	(arc
		(start 102.564184 -225.369374)
		(mid 102.360223 -225.574076)
		(end 102.285546 -225.853244)
		(width 0.1143)
		(layer "In6.Cu")
		(net "GMI_CPU1_G0_CPU0_G2_TX_DN<3>")
	)
	(arc
		(start 371.330474 -238.45901)
		(mid 371.553358 -238.004096)
		(end 371.330474 -237.549182)
		(width 0.1143)
		(layer "In6.Cu")
		(net "GMI_CPU1_G0_CPU0_G2_TX_DN<3>")
	)
	(arc
		(start 100.151184 -239.179608)
		(mid 99.923184 -239.624362)
		(end 100.151184 -240.069116)
		(width 0.1143)
		(layer "In6.Cu")
		(net "GMI_CPU1_G0_CPU0_G2_TX_DN<3>")
	)
	(arc
		(start 370.62029 -236.384084)
		(mid 370.555775 -236.121865)
		(end 370.376958 -235.919518)
		(width 0.1143)
		(layer "In6.Cu")
		(net "GMI_CPU1_G0_CPU0_G2_TX_DN<3>")
	)
	(arc
		(start 102.285546 -225.853244)
		(mid 102.235459 -226.040113)
		(end 102.098602 -226.17684)
		(width 0.1143)
		(layer "In6.Cu")
		(net "GMI_CPU1_G0_CPU0_G2_TX_DN<3>")
	)
	(arc
		(start 100.181664 -237.538006)
		(mid 100.173486 -237.543649)
		(end 100.165408 -237.549436)
		(width 0.1143)
		(layer "In6.Cu")
		(net "GMI_CPU1_G0_CPU0_G2_TX_DN<3>")
	)
	(arc
		(start 100.165408 -237.549436)
		(mid 99.942524 -238.00435)
		(end 100.165408 -238.459264)
		(width 0.1143)
		(layer "In6.Cu")
		(net "GMI_CPU1_G0_CPU0_G2_TX_DN<3>")
	)
	(arc
		(start 101.589078 -227.00996)
		(mid 101.345751 -227.474526)
		(end 101.589078 -227.939092)
		(width 0.1143)
		(layer "In6.Cu")
		(net "GMI_CPU1_G0_CPU0_G2_TX_DN<3>")
	)
	(segment
		(start 98.147886 -243.130324)
		(end 97.681034 -242.864386)
		(width 0.12954)
		(layer "F.Cu")
		(net "GMI_CPU1_G0_CPU0_G2_TX_DN<2>")
	)
	(segment
		(start 373.347996 -243.13007)
		(end 373.814848 -242.864132)
		(width 0.12954)
		(layer "F.Cu")
		(net "GMI_CPU1_G0_CPU0_G2_TX_DN<2>")
	)
	(segment
		(start 367.799874 -221.325694)
		(end 367.799874 -221.13875)
		(width 0.1143)
		(layer "In6.Cu")
		(net "GMI_CPU1_G0_CPU0_G2_TX_DN<2>")
	)
	(segment
		(start 100.649024 -227.939092)
		(end 100.68814 -227.961952)
		(width 0.1143)
		(layer "In6.Cu")
		(net "GMI_CPU1_G0_CPU0_G2_TX_DN<2>")
	)
	(segment
		(start 100.217986 -235.896912)
		(end 100.214176 -235.899198)
		(width 0.1143)
		(layer "In6.Cu")
		(net "GMI_CPU1_G0_CPU0_G2_TX_DN<2>")
	)
	(segment
		(start 370.77523 -231.220518)
		(end 370.807742 -231.201722)
		(width 0.1143)
		(layer "In6.Cu")
		(net "GMI_CPU1_G0_CPU0_G2_TX_DN<2>")
	)
	(segment
		(start 367.959894 -222.111316)
		(end 367.959386 -222.111062)
		(width 0.1143)
		(layer "In6.Cu")
		(net "GMI_CPU1_G0_CPU0_G2_TX_DN<2>")
	)
	(segment
		(start 100.649024 -231.179116)
		(end 100.68814 -231.201976)
		(width 0.1143)
		(layer "In6.Cu")
		(net "GMI_CPU1_G0_CPU0_G2_TX_DN<2>")
	)
	(segment
		(start 372.187216 -238.509302)
		(end 372.256812 -238.468662)
		(width 0.1143)
		(layer "In6.Cu")
		(net "GMI_CPU1_G0_CPU0_G2_TX_DN<2>")
	)
	(segment
		(start 103.039164 -222.938848)
		(end 103.032052 -222.943166)
		(width 0.1143)
		(layer "In6.Cu")
		(net "GMI_CPU1_G0_CPU0_G2_TX_DN<2>")
	)
	(segment
		(start 166.865046 -175.87849)
		(end 162.337496 -177.077624)
		(width 0.14224)
		(layer "In6.Cu")
		(net "GMI_CPU1_G0_CPU0_G2_TX_DN<2>")
	)
	(segment
		(start 101.158802 -226.176586)
		(end 101.15804 -226.177094)
		(width 0.1143)
		(layer "In6.Cu")
		(net "GMI_CPU1_G0_CPU0_G2_TX_DN<2>")
	)
	(segment
		(start 99.23907 -238.468916)
		(end 99.278186 -238.491776)
		(width 0.1143)
		(layer "In6.Cu")
		(net "GMI_CPU1_G0_CPU0_G2_TX_DN<2>")
	)
	(segment
		(start 100.71862 -228.589332)
		(end 100.68814 -228.607112)
		(width 0.1143)
		(layer "In6.Cu")
		(net "GMI_CPU1_G0_CPU0_G2_TX_DN<2>")
	)
	(segment
		(start 372.68785 -239.946688)
		(end 372.687088 -239.94618)
		(width 0.1143)
		(layer "In6.Cu")
		(net "GMI_CPU1_G0_CPU0_G2_TX_DN<2>")
	)
	(segment
		(start 356.948486 -206.87157)
		(end 331.302106 -190.754508)
		(width 0.14224)
		(layer "In6.Cu")
		(net "GMI_CPU1_G0_CPU0_G2_TX_DN<2>")
	)
	(segment
		(start 98.810064 -239.945672)
		(end 98.808794 -239.946434)
		(width 0.1143)
		(layer "In6.Cu")
		(net "GMI_CPU1_G0_CPU0_G2_TX_DN<2>")
	)
	(segment
		(start 328.219816 -188.159136)
		(end 310.337708 -177.540412)
		(width 0.14224)
		(layer "In6.Cu")
		(net "GMI_CPU1_G0_CPU0_G2_TX_DN<2>")
	)
	(segment
		(start 372.695978 -240.916714)
		(end 372.726966 -240.89868)
		(width 0.1143)
		(layer "In6.Cu")
		(net "GMI_CPU1_G0_CPU0_G2_TX_DN<2>")
	)
	(segment
		(start 99.308666 -239.119156)
		(end 99.278186 -239.136936)
		(width 0.1143)
		(layer "In6.Cu")
		(net "GMI_CPU1_G0_CPU0_G2_TX_DN<2>")
	)
	(segment
		(start 98.338132 -242.37696)
		(end 98.299016 -242.39982)
		(width 0.1143)
		(layer "In6.Cu")
		(net "GMI_CPU1_G0_CPU0_G2_TX_DN<2>")
	)
	(segment
		(start 302.914304 -176.673002)
		(end 166.865046 -175.87849)
		(width 0.14224)
		(layer "In6.Cu")
		(net "GMI_CPU1_G0_CPU0_G2_TX_DN<2>")
	)
	(segment
		(start 101.628194 -225.367088)
		(end 101.589078 -225.389948)
		(width 0.1143)
		(layer "In6.Cu")
		(net "GMI_CPU1_G0_CPU0_G2_TX_DN<2>")
	)
	(segment
		(start 372.694454 -240.91773)
		(end 372.695978 -240.916714)
		(width 0.1143)
		(layer "In6.Cu")
		(net "GMI_CPU1_G0_CPU0_G2_TX_DN<2>")
	)
	(segment
		(start 102.16769 -224.51695)
		(end 102.058978 -224.579942)
		(width 0.1143)
		(layer "In6.Cu")
		(net "GMI_CPU1_G0_CPU0_G2_TX_DN<2>")
	)
	(segment
		(start 372.69039 -241.568224)
		(end 372.688866 -241.567208)
		(width 0.1143)
		(layer "In6.Cu")
		(net "GMI_CPU1_G0_CPU0_G2_TX_DN<2>")
	)
	(segment
		(start 372.688866 -241.567208)
		(end 372.68785 -241.5667)
		(width 0.1143)
		(layer "In6.Cu")
		(net "GMI_CPU1_G0_CPU0_G2_TX_DN<2>")
	)
	(segment
		(start 370.846858 -233.4895)
		(end 370.777262 -233.44886)
		(width 0.1143)
		(layer "In6.Cu")
		(net "GMI_CPU1_G0_CPU0_G2_TX_DN<2>")
	)
	(segment
		(start 372.256812 -237.53953)
		(end 372.187216 -237.49889)
		(width 0.1143)
		(layer "In6.Cu")
		(net "GMI_CPU1_G0_CPU0_G2_TX_DN<2>")
	)
	(segment
		(start 368.031014 -222.152464)
		(end 367.959894 -222.111316)
		(width 0.1143)
		(layer "In6.Cu")
		(net "GMI_CPU1_G0_CPU0_G2_TX_DN<2>")
	)
	(segment
		(start 100.68814 -235.086906)
		(end 100.649024 -235.109766)
		(width 0.1143)
		(layer "In6.Cu")
		(net "GMI_CPU1_G0_CPU0_G2_TX_DN<2>")
	)
	(segment
		(start 370.33708 -226.176332)
		(end 370.33581 -226.17557)
		(width 0.1143)
		(layer "In6.Cu")
		(net "GMI_CPU1_G0_CPU0_G2_TX_DN<2>")
	)
	(segment
		(start 369.436904 -224.579688)
		(end 369.328192 -224.516696)
		(width 0.1143)
		(layer "In6.Cu")
		(net "GMI_CPU1_G0_CPU0_G2_TX_DN<2>")
	)
	(segment
		(start 98.839782 -241.548666)
		(end 98.810064 -241.565684)
		(width 0.1143)
		(layer "In6.Cu")
		(net "GMI_CPU1_G0_CPU0_G2_TX_DN<2>")
	)
	(segment
		(start 372.688866 -239.947196)
		(end 372.68785 -239.946688)
		(width 0.1143)
		(layer "In6.Cu")
		(net "GMI_CPU1_G0_CPU0_G2_TX_DN<2>")
	)
	(segment
		(start 307.178202 -176.673256)
		(end 302.914558 -176.673256)
		(width 0.14224)
		(layer "In6.Cu")
		(net "GMI_CPU1_G0_CPU0_G2_TX_DN<2>")
	)
	(segment
		(start 371.281706 -235.898944)
		(end 371.277896 -235.896658)
		(width 0.1143)
		(layer "In6.Cu")
		(net "GMI_CPU1_G0_CPU0_G2_TX_DN<2>")
	)
	(segment
		(start 98.808794 -239.946434)
		(end 98.808032 -239.946942)
		(width 0.1143)
		(layer "In6.Cu")
		(net "GMI_CPU1_G0_CPU0_G2_TX_DN<2>")
	)
	(segment
		(start 370.376958 -226.1997)
		(end 370.340382 -226.178364)
		(width 0.1143)
		(layer "In6.Cu")
		(net "GMI_CPU1_G0_CPU0_G2_TX_DN<2>")
	)
	(segment
		(start 98.808794 -240.922302)
		(end 98.811588 -240.923826)
		(width 0.1143)
		(layer "In6.Cu")
		(net "GMI_CPU1_G0_CPU0_G2_TX_DN<2>")
	)
	(segment
		(start 371.752368 -236.709458)
		(end 371.747796 -236.706664)
		(width 0.1143)
		(layer "In6.Cu")
		(net "GMI_CPU1_G0_CPU0_G2_TX_DN<2>")
	)
	(segment
		(start 100.71862 -235.069126)
		(end 100.68814 -235.086906)
		(width 0.1143)
		(layer "In6.Cu")
		(net "GMI_CPU1_G0_CPU0_G2_TX_DN<2>")
	)
	(segment
		(start 372.685818 -240.92281)
		(end 372.687088 -240.922048)
		(width 0.1143)
		(layer "In6.Cu")
		(net "GMI_CPU1_G0_CPU0_G2_TX_DN<2>")
	)
	(segment
		(start 103.696516 -221.326456)
		(end 103.696516 -221.804484)
		(width 0.1143)
		(layer "In6.Cu")
		(net "GMI_CPU1_G0_CPU0_G2_TX_DN<2>")
	)
	(segment
		(start 371.747796 -236.706664)
		(end 371.747288 -236.70641)
		(width 0.1143)
		(layer "In6.Cu")
		(net "GMI_CPU1_G0_CPU0_G2_TX_DN<2>")
	)
	(segment
		(start 328.219562 -188.15939)
		(end 328.219816 -188.159136)
		(width 0.14224)
		(layer "In6.Cu")
		(net "GMI_CPU1_G0_CPU0_G2_TX_DN<2>")
	)
	(segment
		(start 103.696008 -221.325948)
		(end 103.696516 -221.326456)
		(width 0.1143)
		(layer "In6.Cu")
		(net "GMI_CPU1_G0_CPU0_G2_TX_DN<2>")
	)
	(segment
		(start 98.368612 -242.35918)
		(end 98.338132 -242.37696)
		(width 0.1143)
		(layer "In6.Cu")
		(net "GMI_CPU1_G0_CPU0_G2_TX_DN<2>")
	)
	(segment
		(start 102.599744 -223.728788)
		(end 102.567994 -223.747076)
		(width 0.1143)
		(layer "In6.Cu")
		(net "GMI_CPU1_G0_CPU0_G2_TX_DN<2>")
	)
	(segment
		(start 372.685818 -239.945418)
		(end 372.6561 -239.9284)
		(width 0.1143)
		(layer "In6.Cu")
		(net "GMI_CPU1_G0_CPU0_G2_TX_DN<2>")
	)
	(segment
		(start 368.927888 -223.746822)
		(end 368.896138 -223.728534)
		(width 0.1143)
		(layer "In6.Cu")
		(net "GMI_CPU1_G0_CPU0_G2_TX_DN<2>")
	)
	(segment
		(start 98.808032 -239.946942)
		(end 98.807016 -239.94745)
		(width 0.1143)
		(layer "In6.Cu")
		(net "GMI_CPU1_G0_CPU0_G2_TX_DN<2>")
	)
	(segment
		(start 367.799874 -221.13875)
		(end 367.845594 -221.09303)
		(width 0.1143)
		(layer "In6.Cu")
		(net "GMI_CPU1_G0_CPU0_G2_TX_DN<2>")
	)
	(segment
		(start 367.845594 -221.09303)
		(end 367.845594 -218.399106)
		(width 0.14224)
		(layer "In6.Cu")
		(net "GMI_CPU1_G0_CPU0_G2_TX_DN<2>")
	)
	(segment
		(start 372.693184 -240.918492)
		(end 372.694454 -240.91773)
		(width 0.1143)
		(layer "In6.Cu")
		(net "GMI_CPU1_G0_CPU0_G2_TX_DN<2>")
	)
	(segment
		(start 101.18979 -226.158806)
		(end 101.160072 -226.175824)
		(width 0.1143)
		(layer "In6.Cu")
		(net "GMI_CPU1_G0_CPU0_G2_TX_DN<2>")
	)
	(segment
		(start 103.696008 -221.139004)
		(end 103.696008 -221.325948)
		(width 0.1143)
		(layer "In6.Cu")
		(net "GMI_CPU1_G0_CPU0_G2_TX_DN<2>")
	)
	(segment
		(start 98.808794 -241.566446)
		(end 98.808032 -241.566954)
		(width 0.1143)
		(layer "In6.Cu")
		(net "GMI_CPU1_G0_CPU0_G2_TX_DN<2>")
	)
	(segment
		(start 103.650288 -217.735912)
		(end 103.650288 -221.064836)
		(width 0.14224)
		(layer "In6.Cu")
		(net "GMI_CPU1_G0_CPU0_G2_TX_DN<2>")
	)
	(segment
		(start 101.157024 -226.177602)
		(end 101.118924 -226.199954)
		(width 0.1143)
		(layer "In6.Cu")
		(net "GMI_CPU1_G0_CPU0_G2_TX_DN<2>")
	)
	(segment
		(start 99.308666 -237.499144)
		(end 99.278186 -237.516924)
		(width 0.1143)
		(layer "In6.Cu")
		(net "GMI_CPU1_G0_CPU0_G2_TX_DN<2>")
	)
	(segment
		(start 98.805492 -240.92027)
		(end 98.807016 -240.921286)
		(width 0.1143)
		(layer "In6.Cu")
		(net "GMI_CPU1_G0_CPU0_G2_TX_DN<2>")
	)
	(segment
		(start 100.68814 -233.466894)
		(end 100.649024 -233.489754)
		(width 0.1143)
		(layer "In6.Cu")
		(net "GMI_CPU1_G0_CPU0_G2_TX_DN<2>")
	)
	(segment
		(start 100.649024 -229.559104)
		(end 100.68814 -229.581964)
		(width 0.1143)
		(layer "In6.Cu")
		(net "GMI_CPU1_G0_CPU0_G2_TX_DN<2>")
	)
	(segment
		(start 100.68814 -228.607112)
		(end 100.649024 -228.629972)
		(width 0.1143)
		(layer "In6.Cu")
		(net "GMI_CPU1_G0_CPU0_G2_TX_DN<2>")
	)
	(segment
		(start 302.914558 -176.673256)
		(end 302.914304 -176.673002)
		(width 0.14224)
		(layer "In6.Cu")
		(net "GMI_CPU1_G0_CPU0_G2_TX_DN<2>")
	)
	(segment
		(start 100.68814 -231.846882)
		(end 100.649024 -231.869742)
		(width 0.1143)
		(layer "In6.Cu")
		(net "GMI_CPU1_G0_CPU0_G2_TX_DN<2>")
	)
	(segment
		(start 372.687088 -241.566192)
		(end 372.685818 -241.56543)
		(width 0.1143)
		(layer "In6.Cu")
		(net "GMI_CPU1_G0_CPU0_G2_TX_DN<2>")
	)
	(segment
		(start 372.687088 -239.94618)
		(end 372.685818 -239.945418)
		(width 0.1143)
		(layer "In6.Cu")
		(net "GMI_CPU1_G0_CPU0_G2_TX_DN<2>")
	)
	(segment
		(start 103.536496 -222.111316)
		(end 103.535988 -222.11157)
		(width 0.1143)
		(layer "In6.Cu")
		(net "GMI_CPU1_G0_CPU0_G2_TX_DN<2>")
	)
	(segment
		(start 100.71862 -226.96932)
		(end 100.68814 -226.9871)
		(width 0.1143)
		(layer "In6.Cu")
		(net "GMI_CPU1_G0_CPU0_G2_TX_DN<2>")
	)
	(segment
		(start 371.786912 -236.729524)
		(end 371.752368 -236.709458)
		(width 0.1143)
		(layer "In6.Cu")
		(net "GMI_CPU1_G0_CPU0_G2_TX_DN<2>")
	)
	(segment
		(start 103.535988 -222.11157)
		(end 103.464868 -222.152718)
		(width 0.1143)
		(layer "In6.Cu")
		(net "GMI_CPU1_G0_CPU0_G2_TX_DN<2>")
	)
	(segment
		(start 99.278186 -238.491776)
		(end 99.308666 -238.509556)
		(width 0.1143)
		(layer "In6.Cu")
		(net "GMI_CPU1_G0_CPU0_G2_TX_DN<2>")
	)
	(segment
		(start 98.807016 -241.567462)
		(end 98.768916 -241.589814)
		(width 0.1143)
		(layer "In6.Cu")
		(net "GMI_CPU1_G0_CPU0_G2_TX_DN<2>")
	)
	(segment
		(start 98.81235 -240.924334)
		(end 98.839782 -240.940082)
		(width 0.1143)
		(layer "In6.Cu")
		(net "GMI_CPU1_G0_CPU0_G2_TX_DN<2>")
	)
	(segment
		(start 369.906804 -225.389694)
		(end 369.837208 -225.349054)
		(width 0.1143)
		(layer "In6.Cu")
		(net "GMI_CPU1_G0_CPU0_G2_TX_DN<2>")
	)
	(segment
		(start 98.808032 -241.566954)
		(end 98.807016 -241.567462)
		(width 0.1143)
		(layer "In6.Cu")
		(net "GMI_CPU1_G0_CPU0_G2_TX_DN<2>")
	)
	(segment
		(start 101.15804 -226.177094)
		(end 101.157024 -226.177602)
		(width 0.1143)
		(layer "In6.Cu")
		(net "GMI_CPU1_G0_CPU0_G2_TX_DN<2>")
	)
	(segment
		(start 99.748594 -236.706664)
		(end 99.748086 -236.706918)
		(width 0.1143)
		(layer "In6.Cu")
		(net "GMI_CPU1_G0_CPU0_G2_TX_DN<2>")
	)
	(segment
		(start 117.684804 -202.86218)
		(end 114.312446 -205.449678)
		(width 0.14224)
		(layer "In6.Cu")
		(net "GMI_CPU1_G0_CPU0_G2_TX_DN<2>")
	)
	(segment
		(start 104.579166 -215.493092)
		(end 104.578912 -215.493092)
		(width 0.14224)
		(layer "In6.Cu")
		(net "GMI_CPU1_G0_CPU0_G2_TX_DN<2>")
	)
	(segment
		(start 100.649024 -234.418886)
		(end 100.68814 -234.441746)
		(width 0.1143)
		(layer "In6.Cu")
		(net "GMI_CPU1_G0_CPU0_G2_TX_DN<2>")
	)
	(segment
		(start 371.277896 -235.896658)
		(end 371.246146 -235.87837)
		(width 0.1143)
		(layer "In6.Cu")
		(net "GMI_CPU1_G0_CPU0_G2_TX_DN<2>")
	)
	(segment
		(start 370.777262 -232.83926)
		(end 370.846858 -232.79862)
		(width 0.1143)
		(layer "In6.Cu")
		(net "GMI_CPU1_G0_CPU0_G2_TX_DN<2>")
	)
	(segment
		(start 372.688866 -240.921032)
		(end 372.69039 -240.920016)
		(width 0.1143)
		(layer "In6.Cu")
		(net "GMI_CPU1_G0_CPU0_G2_TX_DN<2>")
	)
	(segment
		(start 104.578912 -215.493092)
		(end 103.650288 -217.735912)
		(width 0.14224)
		(layer "In6.Cu")
		(net "GMI_CPU1_G0_CPU0_G2_TX_DN<2>")
	)
	(segment
		(start 101.160072 -226.175824)
		(end 101.158802 -226.176586)
		(width 0.1143)
		(layer "In6.Cu")
		(net "GMI_CPU1_G0_CPU0_G2_TX_DN<2>")
	)
	(segment
		(start 367.799366 -221.80423)
		(end 367.799366 -221.326202)
		(width 0.1143)
		(layer "In6.Cu")
		(net "GMI_CPU1_G0_CPU0_G2_TX_DN<2>")
	)
	(segment
		(start 367.799366 -221.326202)
		(end 367.799874 -221.325694)
		(width 0.1143)
		(layer "In6.Cu")
		(net "GMI_CPU1_G0_CPU0_G2_TX_DN<2>")
	)
	(segment
		(start 98.808032 -240.921794)
		(end 98.808794 -240.922302)
		(width 0.1143)
		(layer "In6.Cu")
		(net "GMI_CPU1_G0_CPU0_G2_TX_DN<2>")
	)
	(segment
		(start 372.256812 -239.159542)
		(end 372.187216 -239.118902)
		(width 0.1143)
		(layer "In6.Cu")
		(net "GMI_CPU1_G0_CPU0_G2_TX_DN<2>")
	)
	(segment
		(start 100.68814 -232.821734)
		(end 100.71862 -232.839514)
		(width 0.1143)
		(layer "In6.Cu")
		(net "GMI_CPU1_G0_CPU0_G2_TX_DN<2>")
	)
	(segment
		(start 98.807016 -240.921286)
		(end 98.808032 -240.921794)
		(width 0.1143)
		(layer "In6.Cu")
		(net "GMI_CPU1_G0_CPU0_G2_TX_DN<2>")
	)
	(segment
		(start 101.658674 -225.349308)
		(end 101.628194 -225.367088)
		(width 0.1143)
		(layer "In6.Cu")
		(net "GMI_CPU1_G0_CPU0_G2_TX_DN<2>")
	)
	(segment
		(start 370.844318 -230.247952)
		(end 370.777262 -230.208836)
		(width 0.1143)
		(layer "In6.Cu")
		(net "GMI_CPU1_G0_CPU0_G2_TX_DN<2>")
	)
	(segment
		(start 372.6561 -240.939828)
		(end 372.685818 -240.92281)
		(width 0.1143)
		(layer "In6.Cu")
		(net "GMI_CPU1_G0_CPU0_G2_TX_DN<2>")
	)
	(segment
		(start 97.978976 -242.864386)
		(end 97.681034 -242.864386)
		(width 0.1143)
		(layer "In6.Cu")
		(net "GMI_CPU1_G0_CPU0_G2_TX_DN<2>")
	)
	(segment
		(start 372.68785 -240.92154)
		(end 372.688866 -240.921032)
		(width 0.1143)
		(layer "In6.Cu")
		(net "GMI_CPU1_G0_CPU0_G2_TX_DN<2>")
	)
	(segment
		(start 100.68814 -229.581964)
		(end 100.720652 -229.60076)
		(width 0.1143)
		(layer "In6.Cu")
		(net "GMI_CPU1_G0_CPU0_G2_TX_DN<2>")
	)
	(segment
		(start 331.302106 -190.754508)
		(end 330.360528 -189.918848)
		(width 0.14224)
		(layer "In6.Cu")
		(net "GMI_CPU1_G0_CPU0_G2_TX_DN<2>")
	)
	(segment
		(start 104.798368 -214.96401)
		(end 104.579166 -215.493092)
		(width 0.14224)
		(layer "In6.Cu")
		(net "GMI_CPU1_G0_CPU0_G2_TX_DN<2>")
	)
	(segment
		(start 98.802698 -240.918746)
		(end 98.805492 -240.92027)
		(width 0.1143)
		(layer "In6.Cu")
		(net "GMI_CPU1_G0_CPU0_G2_TX_DN<2>")
	)
	(segment
		(start 370.340382 -226.178364)
		(end 370.338858 -226.177348)
		(width 0.1143)
		(layer "In6.Cu")
		(net "GMI_CPU1_G0_CPU0_G2_TX_DN<2>")
	)
	(segment
		(start 372.726966 -241.58956)
		(end 372.69039 -241.568224)
		(width 0.1143)
		(layer "In6.Cu")
		(net "GMI_CPU1_G0_CPU0_G2_TX_DN<2>")
	)
	(segment
		(start 370.846858 -227.009706)
		(end 370.777262 -226.969066)
		(width 0.1143)
		(layer "In6.Cu")
		(net "GMI_CPU1_G0_CPU0_G2_TX_DN<2>")
	)
	(segment
		(start 99.278186 -239.136936)
		(end 99.23907 -239.159796)
		(width 0.1143)
		(layer "In6.Cu")
		(net "GMI_CPU1_G0_CPU0_G2_TX_DN<2>")
	)
	(segment
		(start 372.68785 -241.5667)
		(end 372.687088 -241.566192)
		(width 0.1143)
		(layer "In6.Cu")
		(net "GMI_CPU1_G0_CPU0_G2_TX_DN<2>")
	)
	(segment
		(start 100.71862 -233.449114)
		(end 100.68814 -233.466894)
		(width 0.1143)
		(layer "In6.Cu")
		(net "GMI_CPU1_G0_CPU0_G2_TX_DN<2>")
	)
	(segment
		(start 100.71862 -231.829102)
		(end 100.68814 -231.846882)
		(width 0.1143)
		(layer "In6.Cu")
		(net "GMI_CPU1_G0_CPU0_G2_TX_DN<2>")
	)
	(segment
		(start 372.69039 -240.920016)
		(end 372.693184 -240.918492)
		(width 0.1143)
		(layer "In6.Cu")
		(net "GMI_CPU1_G0_CPU0_G2_TX_DN<2>")
	)
	(segment
		(start 330.360782 -189.918848)
		(end 328.699114 -188.44387)
		(width 0.14224)
		(layer "In6.Cu")
		(net "GMI_CPU1_G0_CPU0_G2_TX_DN<2>")
	)
	(segment
		(start 373.196866 -242.399566)
		(end 373.12727 -242.358926)
		(width 0.1143)
		(layer "In6.Cu")
		(net "GMI_CPU1_G0_CPU0_G2_TX_DN<2>")
	)
	(segment
		(start 368.46383 -222.942912)
		(end 368.456718 -222.938594)
		(width 0.1143)
		(layer "In6.Cu")
		(net "GMI_CPU1_G0_CPU0_G2_TX_DN<2>")
	)
	(segment
		(start 370.338858 -226.177348)
		(end 370.337842 -226.17684)
		(width 0.1143)
		(layer "In6.Cu")
		(net "GMI_CPU1_G0_CPU0_G2_TX_DN<2>")
	)
	(segment
		(start 370.807742 -231.201722)
		(end 370.846858 -231.178862)
		(width 0.1143)
		(layer "In6.Cu")
		(net "GMI_CPU1_G0_CPU0_G2_TX_DN<2>")
	)
	(segment
		(start 100.71862 -230.20909)
		(end 100.651564 -230.248206)
		(width 0.1143)
		(layer "In6.Cu")
		(net "GMI_CPU1_G0_CPU0_G2_TX_DN<2>")
	)
	(segment
		(start 100.649024 -232.798874)
		(end 100.68814 -232.821734)
		(width 0.1143)
		(layer "In6.Cu")
		(net "GMI_CPU1_G0_CPU0_G2_TX_DN<2>")
	)
	(segment
		(start 114.312446 -205.449678)
		(end 104.798368 -214.96401)
		(width 0.14224)
		(layer "In6.Cu")
		(net "GMI_CPU1_G0_CPU0_G2_TX_DN<2>")
	)
	(segment
		(start 370.337842 -226.17684)
		(end 370.33708 -226.176332)
		(width 0.1143)
		(layer "In6.Cu")
		(net "GMI_CPU1_G0_CPU0_G2_TX_DN<2>")
	)
	(segment
		(start 99.278186 -237.516924)
		(end 99.23907 -237.539784)
		(width 0.1143)
		(layer "In6.Cu")
		(net "GMI_CPU1_G0_CPU0_G2_TX_DN<2>")
	)
	(segment
		(start 370.777262 -227.979478)
		(end 370.846858 -227.938838)
		(width 0.1143)
		(layer "In6.Cu")
		(net "GMI_CPU1_G0_CPU0_G2_TX_DN<2>")
	)
	(segment
		(start 369.205002 -224.30359)
		(end 369.205002 -224.228152)
		(width 0.1143)
		(layer "In6.Cu")
		(net "GMI_CPU1_G0_CPU0_G2_TX_DN<2>")
	)
	(segment
		(start 372.726966 -239.969548)
		(end 372.69039 -239.948212)
		(width 0.1143)
		(layer "In6.Cu")
		(net "GMI_CPU1_G0_CPU0_G2_TX_DN<2>")
	)
	(segment
		(start 98.06178 -242.781582)
		(end 97.978976 -242.864386)
		(width 0.1143)
		(layer "In6.Cu")
		(net "GMI_CPU1_G0_CPU0_G2_TX_DN<2>")
	)
	(segment
		(start 370.77523 -229.600506)
		(end 370.807742 -229.58171)
		(width 0.1143)
		(layer "In6.Cu")
		(net "GMI_CPU1_G0_CPU0_G2_TX_DN<2>")
	)
	(segment
		(start 98.768916 -240.898934)
		(end 98.799904 -240.916968)
		(width 0.1143)
		(layer "In6.Cu")
		(net "GMI_CPU1_G0_CPU0_G2_TX_DN<2>")
	)
	(segment
		(start 103.650288 -221.093284)
		(end 103.696008 -221.139004)
		(width 0.1143)
		(layer "In6.Cu")
		(net "GMI_CPU1_G0_CPU0_G2_TX_DN<2>")
	)
	(segment
		(start 98.810064 -241.565684)
		(end 98.808794 -241.566446)
		(width 0.1143)
		(layer "In6.Cu")
		(net "GMI_CPU1_G0_CPU0_G2_TX_DN<2>")
	)
	(segment
		(start 373.814848 -242.864132)
		(end 373.516906 -242.864132)
		(width 0.1143)
		(layer "In6.Cu")
		(net "GMI_CPU1_G0_CPU0_G2_TX_DN<2>")
	)
	(segment
		(start 367.845594 -218.399106)
		(end 366.673638 -215.5698)
		(width 0.14224)
		(layer "In6.Cu")
		(net "GMI_CPU1_G0_CPU0_G2_TX_DN<2>")
	)
	(segment
		(start 98.811588 -240.923826)
		(end 98.81235 -240.924334)
		(width 0.1143)
		(layer "In6.Cu")
		(net "GMI_CPU1_G0_CPU0_G2_TX_DN<2>")
	)
	(segment
		(start 370.846858 -228.629718)
		(end 370.777262 -228.589078)
		(width 0.1143)
		(layer "In6.Cu")
		(net "GMI_CPU1_G0_CPU0_G2_TX_DN<2>")
	)
	(segment
		(start 328.699114 -188.44387)
		(end 328.219562 -188.15939)
		(width 0.14224)
		(layer "In6.Cu")
		(net "GMI_CPU1_G0_CPU0_G2_TX_DN<2>")
	)
	(segment
		(start 372.685818 -241.56543)
		(end 372.6561 -241.548412)
		(width 0.1143)
		(layer "In6.Cu")
		(net "GMI_CPU1_G0_CPU0_G2_TX_DN<2>")
	)
	(segment
		(start 362.019342 -210.915504)
		(end 356.948486 -206.87157)
		(width 0.14224)
		(layer "In6.Cu")
		(net "GMI_CPU1_G0_CPU0_G2_TX_DN<2>")
	)
	(segment
		(start 98.839782 -239.928654)
		(end 98.810064 -239.945672)
		(width 0.1143)
		(layer "In6.Cu")
		(net "GMI_CPU1_G0_CPU0_G2_TX_DN<2>")
	)
	(segment
		(start 330.360528 -189.918848)
		(end 330.360782 -189.918848)
		(width 0.14224)
		(layer "In6.Cu")
		(net "GMI_CPU1_G0_CPU0_G2_TX_DN<2>")
	)
	(segment
		(start 100.68814 -227.961952)
		(end 100.71862 -227.979732)
		(width 0.1143)
		(layer "In6.Cu")
		(net "GMI_CPU1_G0_CPU0_G2_TX_DN<2>")
	)
	(segment
		(start 99.748086 -236.706918)
		(end 99.70897 -236.729778)
		(width 0.1143)
		(layer "In6.Cu")
		(net "GMI_CPU1_G0_CPU0_G2_TX_DN<2>")
	)
	(segment
		(start 370.33581 -226.17557)
		(end 370.306092 -226.158552)
		(width 0.1143)
		(layer "In6.Cu")
		(net "GMI_CPU1_G0_CPU0_G2_TX_DN<2>")
	)
	(segment
		(start 100.249736 -235.878624)
		(end 100.217986 -235.896912)
		(width 0.1143)
		(layer "In6.Cu")
		(net "GMI_CPU1_G0_CPU0_G2_TX_DN<2>")
	)
	(segment
		(start 366.673638 -215.5698)
		(end 362.019342 -210.915504)
		(width 0.14224)
		(layer "In6.Cu")
		(net "GMI_CPU1_G0_CPU0_G2_TX_DN<2>")
	)
	(segment
		(start 373.516906 -242.864132)
		(end 373.434102 -242.781328)
		(width 0.1143)
		(layer "In6.Cu")
		(net "GMI_CPU1_G0_CPU0_G2_TX_DN<2>")
	)
	(segment
		(start 162.337496 -177.077624)
		(end 117.684804 -202.86218)
		(width 0.14224)
		(layer "In6.Cu")
		(net "GMI_CPU1_G0_CPU0_G2_TX_DN<2>")
	)
	(segment
		(start 100.68814 -231.201976)
		(end 100.720652 -231.220772)
		(width 0.1143)
		(layer "In6.Cu")
		(net "GMI_CPU1_G0_CPU0_G2_TX_DN<2>")
	)
	(segment
		(start 372.687088 -240.922048)
		(end 372.68785 -240.92154)
		(width 0.1143)
		(layer "In6.Cu")
		(net "GMI_CPU1_G0_CPU0_G2_TX_DN<2>")
	)
	(segment
		(start 103.650288 -221.064836)
		(end 103.650288 -221.093284)
		(width 0.1143)
		(layer "In6.Cu")
		(net "GMI_CPU1_G0_CPU0_G2_TX_DN<2>")
	)
	(segment
		(start 98.801428 -240.917984)
		(end 98.802698 -240.918746)
		(width 0.1143)
		(layer "In6.Cu")
		(net "GMI_CPU1_G0_CPU0_G2_TX_DN<2>")
	)
	(segment
		(start 372.69039 -239.948212)
		(end 372.688866 -239.947196)
		(width 0.1143)
		(layer "In6.Cu")
		(net "GMI_CPU1_G0_CPU0_G2_TX_DN<2>")
	)
	(segment
		(start 370.777262 -234.459272)
		(end 370.846858 -234.418632)
		(width 0.1143)
		(layer "In6.Cu")
		(net "GMI_CPU1_G0_CPU0_G2_TX_DN<2>")
	)
	(segment
		(start 100.68814 -226.9871)
		(end 100.649024 -227.00996)
		(width 0.1143)
		(layer "In6.Cu")
		(net "GMI_CPU1_G0_CPU0_G2_TX_DN<2>")
	)
	(segment
		(start 370.807742 -229.58171)
		(end 370.846858 -229.55885)
		(width 0.1143)
		(layer "In6.Cu")
		(net "GMI_CPU1_G0_CPU0_G2_TX_DN<2>")
	)
	(segment
		(start 100.68814 -234.441746)
		(end 100.71862 -234.459526)
		(width 0.1143)
		(layer "In6.Cu")
		(net "GMI_CPU1_G0_CPU0_G2_TX_DN<2>")
	)
	(segment
		(start 98.799904 -240.916968)
		(end 98.801428 -240.917984)
		(width 0.1143)
		(layer "In6.Cu")
		(net "GMI_CPU1_G0_CPU0_G2_TX_DN<2>")
	)
	(segment
		(start 370.846858 -235.109512)
		(end 370.777262 -235.068872)
		(width 0.1143)
		(layer "In6.Cu")
		(net "GMI_CPU1_G0_CPU0_G2_TX_DN<2>")
	)
	(segment
		(start 98.807016 -239.94745)
		(end 98.768916 -239.969802)
		(width 0.1143)
		(layer "In6.Cu")
		(net "GMI_CPU1_G0_CPU0_G2_TX_DN<2>")
	)
	(segment
		(start 310.337708 -177.540412)
		(end 307.178202 -176.673256)
		(width 0.14224)
		(layer "In6.Cu")
		(net "GMI_CPU1_G0_CPU0_G2_TX_DN<2>")
	)
	(segment
		(start 370.846858 -231.869488)
		(end 370.777262 -231.828848)
		(width 0.1143)
		(layer "In6.Cu")
		(net "GMI_CPU1_G0_CPU0_G2_TX_DN<2>")
	)
	(segment
		(start 102.29088 -224.228406)
		(end 102.29088 -224.303844)
		(width 0.1143)
		(layer "In6.Cu")
		(net "GMI_CPU1_G0_CPU0_G2_TX_DN<2>")
	)
	(arc
		(start 370.62029 -231.524048)
		(mid 370.661256 -231.353642)
		(end 370.77523 -231.220518)
		(width 0.1143)
		(layer "In6.Cu")
		(net "GMI_CPU1_G0_CPU0_G2_TX_DN<2>")
	)
	(arc
		(start 100.405692 -230.71455)
		(mid 100.470207 -230.976769)
		(end 100.649024 -231.179116)
		(width 0.1143)
		(layer "In6.Cu")
		(net "GMI_CPU1_G0_CPU0_G2_TX_DN<2>")
	)
	(arc
		(start 100.649024 -227.00996)
		(mid 100.405697 -227.474526)
		(end 100.649024 -227.939092)
		(width 0.1143)
		(layer "In6.Cu")
		(net "GMI_CPU1_G0_CPU0_G2_TX_DN<2>")
	)
	(arc
		(start 101.589078 -225.389948)
		(mid 101.410265 -225.592298)
		(end 101.345746 -225.854514)
		(width 0.1143)
		(layer "In6.Cu")
		(net "GMI_CPU1_G0_CPU0_G2_TX_DN<2>")
	)
	(arc
		(start 99.70897 -236.729778)
		(mid 99.530157 -236.932128)
		(end 99.465638 -237.194344)
		(width 0.1143)
		(layer "In6.Cu")
		(net "GMI_CPU1_G0_CPU0_G2_TX_DN<2>")
	)
	(arc
		(start 100.651564 -230.248206)
		(mid 100.470912 -230.450951)
		(end 100.405692 -230.71455)
		(width 0.1143)
		(layer "In6.Cu")
		(net "GMI_CPU1_G0_CPU0_G2_TX_DN<2>")
	)
	(arc
		(start 372.030244 -237.19409)
		(mid 371.965729 -236.931871)
		(end 371.786912 -236.729524)
		(width 0.1143)
		(layer "In6.Cu")
		(net "GMI_CPU1_G0_CPU0_G2_TX_DN<2>")
	)
	(arc
		(start 370.846858 -232.79862)
		(mid 371.090185 -232.334054)
		(end 370.846858 -231.869488)
		(width 0.1143)
		(layer "In6.Cu")
		(net "GMI_CPU1_G0_CPU0_G2_TX_DN<2>")
	)
	(arc
		(start 100.875592 -226.66452)
		(mid 100.834043 -226.835942)
		(end 100.71862 -226.96932)
		(width 0.1143)
		(layer "In6.Cu")
		(net "GMI_CPU1_G0_CPU0_G2_TX_DN<2>")
	)
	(arc
		(start 370.150136 -225.85426)
		(mid 370.085621 -225.592041)
		(end 369.906804 -225.389694)
		(width 0.1143)
		(layer "In6.Cu")
		(net "GMI_CPU1_G0_CPU0_G2_TX_DN<2>")
	)
	(arc
		(start 101.345746 -225.854514)
		(mid 101.304491 -226.025485)
		(end 101.18979 -226.158806)
		(width 0.1143)
		(layer "In6.Cu")
		(net "GMI_CPU1_G0_CPU0_G2_TX_DN<2>")
	)
	(arc
		(start 369.328192 -224.516696)
		(mid 369.237998 -224.426671)
		(end 369.205002 -224.30359)
		(width 0.1143)
		(layer "In6.Cu")
		(net "GMI_CPU1_G0_CPU0_G2_TX_DN<2>")
	)
	(arc
		(start 370.777262 -235.068872)
		(mid 370.620285 -234.764072)
		(end 370.777262 -234.459272)
		(width 0.1143)
		(layer "In6.Cu")
		(net "GMI_CPU1_G0_CPU0_G2_TX_DN<2>")
	)
	(arc
		(start 373.12727 -242.358926)
		(mid 373.011843 -242.22555)
		(end 372.970298 -242.054126)
		(width 0.1143)
		(layer "In6.Cu")
		(net "GMI_CPU1_G0_CPU0_G2_TX_DN<2>")
	)
	(arc
		(start 100.875592 -231.524302)
		(mid 100.834043 -231.695724)
		(end 100.71862 -231.829102)
		(width 0.1143)
		(layer "In6.Cu")
		(net "GMI_CPU1_G0_CPU0_G2_TX_DN<2>")
	)
	(arc
		(start 372.970298 -242.054126)
		(mid 372.905783 -241.791907)
		(end 372.726966 -241.58956)
		(width 0.1143)
		(layer "In6.Cu")
		(net "GMI_CPU1_G0_CPU0_G2_TX_DN<2>")
	)
	(arc
		(start 100.649024 -228.629972)
		(mid 100.405697 -229.094538)
		(end 100.649024 -229.559104)
		(width 0.1143)
		(layer "In6.Cu")
		(net "GMI_CPU1_G0_CPU0_G2_TX_DN<2>")
	)
	(arc
		(start 371.246146 -235.87837)
		(mid 371.13147 -235.745036)
		(end 371.09019 -235.574078)
		(width 0.1143)
		(layer "In6.Cu")
		(net "GMI_CPU1_G0_CPU0_G2_TX_DN<2>")
	)
	(arc
		(start 373.434102 -242.781328)
		(mid 373.432314 -242.769879)
		(end 373.430292 -242.758468)
		(width 0.1143)
		(layer "In6.Cu")
		(net "GMI_CPU1_G0_CPU0_G2_TX_DN<2>")
	)
	(arc
		(start 99.308666 -238.509556)
		(mid 99.465643 -238.814356)
		(end 99.308666 -239.119156)
		(width 0.1143)
		(layer "In6.Cu")
		(net "GMI_CPU1_G0_CPU0_G2_TX_DN<2>")
	)
	(arc
		(start 103.696516 -221.804484)
		(mid 103.654105 -221.977507)
		(end 103.536496 -222.111316)
		(width 0.1143)
		(layer "In6.Cu")
		(net "GMI_CPU1_G0_CPU0_G2_TX_DN<2>")
	)
	(arc
		(start 101.815646 -225.044508)
		(mid 101.774097 -225.21593)
		(end 101.658674 -225.349308)
		(width 0.1143)
		(layer "In6.Cu")
		(net "GMI_CPU1_G0_CPU0_G2_TX_DN<2>")
	)
	(arc
		(start 102.29088 -224.303844)
		(mid 102.257863 -224.426913)
		(end 102.16769 -224.51695)
		(width 0.1143)
		(layer "In6.Cu")
		(net "GMI_CPU1_G0_CPU0_G2_TX_DN<2>")
	)
	(arc
		(start 370.846858 -231.178862)
		(mid 371.025671 -230.976512)
		(end 371.09019 -230.714296)
		(width 0.1143)
		(layer "In6.Cu")
		(net "GMI_CPU1_G0_CPU0_G2_TX_DN<2>")
	)
	(arc
		(start 370.306092 -226.158552)
		(mid 370.191416 -226.025218)
		(end 370.150136 -225.85426)
		(width 0.1143)
		(layer "In6.Cu")
		(net "GMI_CPU1_G0_CPU0_G2_TX_DN<2>")
	)
	(arc
		(start 98.768916 -241.589814)
		(mid 98.590103 -241.792164)
		(end 98.525584 -242.05438)
		(width 0.1143)
		(layer "In6.Cu")
		(net "GMI_CPU1_G0_CPU0_G2_TX_DN<2>")
	)
	(arc
		(start 100.720652 -231.220772)
		(mid 100.834581 -231.353919)
		(end 100.875592 -231.524302)
		(width 0.1143)
		(layer "In6.Cu")
		(net "GMI_CPU1_G0_CPU0_G2_TX_DN<2>")
	)
	(arc
		(start 372.187216 -239.118902)
		(mid 372.030239 -238.814102)
		(end 372.187216 -238.509302)
		(width 0.1143)
		(layer "In6.Cu")
		(net "GMI_CPU1_G0_CPU0_G2_TX_DN<2>")
	)
	(arc
		(start 98.299016 -242.39982)
		(mid 98.147029 -242.556328)
		(end 98.06559 -242.758722)
		(width 0.1143)
		(layer "In6.Cu")
		(net "GMI_CPU1_G0_CPU0_G2_TX_DN<2>")
	)
	(arc
		(start 372.726966 -240.89868)
		(mid 372.970293 -240.434114)
		(end 372.726966 -239.969548)
		(width 0.1143)
		(layer "In6.Cu")
		(net "GMI_CPU1_G0_CPU0_G2_TX_DN<2>")
	)
	(arc
		(start 98.525584 -242.05438)
		(mid 98.484035 -242.225802)
		(end 98.368612 -242.35918)
		(width 0.1143)
		(layer "In6.Cu")
		(net "GMI_CPU1_G0_CPU0_G2_TX_DN<2>")
	)
	(arc
		(start 100.71862 -232.839514)
		(mid 100.875597 -233.144314)
		(end 100.71862 -233.449114)
		(width 0.1143)
		(layer "In6.Cu")
		(net "GMI_CPU1_G0_CPU0_G2_TX_DN<2>")
	)
	(arc
		(start 370.62029 -229.904036)
		(mid 370.661256 -229.73363)
		(end 370.77523 -229.600506)
		(width 0.1143)
		(layer "In6.Cu")
		(net "GMI_CPU1_G0_CPU0_G2_TX_DN<2>")
	)
	(arc
		(start 372.500144 -239.624108)
		(mid 372.435629 -239.361889)
		(end 372.256812 -239.159542)
		(width 0.1143)
		(layer "In6.Cu")
		(net "GMI_CPU1_G0_CPU0_G2_TX_DN<2>")
	)
	(arc
		(start 99.23907 -239.159796)
		(mid 99.060257 -239.362146)
		(end 98.995738 -239.624362)
		(width 0.1143)
		(layer "In6.Cu")
		(net "GMI_CPU1_G0_CPU0_G2_TX_DN<2>")
	)
	(arc
		(start 100.405692 -235.574332)
		(mid 100.364437 -235.745303)
		(end 100.249736 -235.878624)
		(width 0.1143)
		(layer "In6.Cu")
		(net "GMI_CPU1_G0_CPU0_G2_TX_DN<2>")
	)
	(arc
		(start 102.7557 -223.424496)
		(mid 102.714445 -223.595467)
		(end 102.599744 -223.728788)
		(width 0.1143)
		(layer "In6.Cu")
		(net "GMI_CPU1_G0_CPU0_G2_TX_DN<2>")
	)
	(arc
		(start 369.205002 -224.228152)
		(mid 369.130769 -223.950459)
		(end 368.927888 -223.746822)
		(width 0.1143)
		(layer "In6.Cu")
		(net "GMI_CPU1_G0_CPU0_G2_TX_DN<2>")
	)
	(arc
		(start 371.09019 -235.574078)
		(mid 371.025675 -235.311859)
		(end 370.846858 -235.109512)
		(width 0.1143)
		(layer "In6.Cu")
		(net "GMI_CPU1_G0_CPU0_G2_TX_DN<2>")
	)
	(arc
		(start 103.464868 -222.152718)
		(mid 103.289326 -222.354566)
		(end 103.226108 -222.61449)
		(width 0.1143)
		(layer "In6.Cu")
		(net "GMI_CPU1_G0_CPU0_G2_TX_DN<2>")
	)
	(arc
		(start 98.995738 -239.624362)
		(mid 98.954483 -239.795333)
		(end 98.839782 -239.928654)
		(width 0.1143)
		(layer "In6.Cu")
		(net "GMI_CPU1_G0_CPU0_G2_TX_DN<2>")
	)
	(arc
		(start 372.187216 -237.49889)
		(mid 372.071789 -237.365514)
		(end 372.030244 -237.19409)
		(width 0.1143)
		(layer "In6.Cu")
		(net "GMI_CPU1_G0_CPU0_G2_TX_DN<2>")
	)
	(arc
		(start 371.747288 -236.70641)
		(mid 371.611893 -236.571192)
		(end 371.562376 -236.38637)
		(width 0.1143)
		(layer "In6.Cu")
		(net "GMI_CPU1_G0_CPU0_G2_TX_DN<2>")
	)
	(arc
		(start 371.09019 -230.714296)
		(mid 371.024954 -230.450705)
		(end 370.844318 -230.247952)
		(width 0.1143)
		(layer "In6.Cu")
		(net "GMI_CPU1_G0_CPU0_G2_TX_DN<2>")
	)
	(arc
		(start 100.71862 -234.459526)
		(mid 100.875597 -234.764326)
		(end 100.71862 -235.069126)
		(width 0.1143)
		(layer "In6.Cu")
		(net "GMI_CPU1_G0_CPU0_G2_TX_DN<2>")
	)
	(arc
		(start 370.846858 -234.418632)
		(mid 371.090185 -233.954066)
		(end 370.846858 -233.4895)
		(width 0.1143)
		(layer "In6.Cu")
		(net "GMI_CPU1_G0_CPU0_G2_TX_DN<2>")
	)
	(arc
		(start 100.71862 -227.979732)
		(mid 100.875597 -228.284532)
		(end 100.71862 -228.589332)
		(width 0.1143)
		(layer "In6.Cu")
		(net "GMI_CPU1_G0_CPU0_G2_TX_DN<2>")
	)
	(arc
		(start 100.875592 -229.90429)
		(mid 100.834043 -230.075712)
		(end 100.71862 -230.20909)
		(width 0.1143)
		(layer "In6.Cu")
		(net "GMI_CPU1_G0_CPU0_G2_TX_DN<2>")
	)
	(arc
		(start 370.777262 -231.828848)
		(mid 370.661835 -231.695472)
		(end 370.62029 -231.524048)
		(width 0.1143)
		(layer "In6.Cu")
		(net "GMI_CPU1_G0_CPU0_G2_TX_DN<2>")
	)
	(arc
		(start 372.6561 -241.548412)
		(mid 372.500172 -241.24412)
		(end 372.6561 -240.939828)
		(width 0.1143)
		(layer "In6.Cu")
		(net "GMI_CPU1_G0_CPU0_G2_TX_DN<2>")
	)
	(arc
		(start 99.23907 -237.539784)
		(mid 98.995743 -238.00435)
		(end 99.23907 -238.468916)
		(width 0.1143)
		(layer "In6.Cu")
		(net "GMI_CPU1_G0_CPU0_G2_TX_DN<2>")
	)
	(arc
		(start 370.846858 -227.938838)
		(mid 371.090185 -227.474272)
		(end 370.846858 -227.009706)
		(width 0.1143)
		(layer "In6.Cu")
		(net "GMI_CPU1_G0_CPU0_G2_TX_DN<2>")
	)
	(arc
		(start 100.649024 -235.109766)
		(mid 100.470211 -235.312116)
		(end 100.405692 -235.574332)
		(width 0.1143)
		(layer "In6.Cu")
		(net "GMI_CPU1_G0_CPU0_G2_TX_DN<2>")
	)
	(arc
		(start 372.256812 -238.468662)
		(mid 372.500139 -238.004096)
		(end 372.256812 -237.53953)
		(width 0.1143)
		(layer "In6.Cu")
		(net "GMI_CPU1_G0_CPU0_G2_TX_DN<2>")
	)
	(arc
		(start 372.6561 -239.9284)
		(mid 372.541424 -239.795066)
		(end 372.500144 -239.624108)
		(width 0.1143)
		(layer "In6.Cu")
		(net "GMI_CPU1_G0_CPU0_G2_TX_DN<2>")
	)
	(arc
		(start 370.846858 -229.55885)
		(mid 371.090185 -229.094284)
		(end 370.846858 -228.629718)
		(width 0.1143)
		(layer "In6.Cu")
		(net "GMI_CPU1_G0_CPU0_G2_TX_DN<2>")
	)
	(arc
		(start 368.740182 -223.424242)
		(mid 368.666175 -223.14674)
		(end 368.46383 -222.942912)
		(width 0.1143)
		(layer "In6.Cu")
		(net "GMI_CPU1_G0_CPU0_G2_TX_DN<2>")
	)
	(arc
		(start 103.032052 -222.943166)
		(mid 102.829675 -223.146976)
		(end 102.7557 -223.424496)
		(width 0.1143)
		(layer "In6.Cu")
		(net "GMI_CPU1_G0_CPU0_G2_TX_DN<2>")
	)
	(arc
		(start 98.839782 -240.940082)
		(mid 98.99571 -241.244374)
		(end 98.839782 -241.548666)
		(width 0.1143)
		(layer "In6.Cu")
		(net "GMI_CPU1_G0_CPU0_G2_TX_DN<2>")
	)
	(arc
		(start 369.837208 -225.349054)
		(mid 369.721781 -225.215678)
		(end 369.680236 -225.044254)
		(width 0.1143)
		(layer "In6.Cu")
		(net "GMI_CPU1_G0_CPU0_G2_TX_DN<2>")
	)
	(arc
		(start 368.456718 -222.938594)
		(mid 368.31987 -222.801418)
		(end 368.269774 -222.614236)
		(width 0.1143)
		(layer "In6.Cu")
		(net "GMI_CPU1_G0_CPU0_G2_TX_DN<2>")
	)
	(arc
		(start 102.567994 -223.747076)
		(mid 102.365086 -223.950697)
		(end 102.29088 -224.228406)
		(width 0.1143)
		(layer "In6.Cu")
		(net "GMI_CPU1_G0_CPU0_G2_TX_DN<2>")
	)
	(arc
		(start 370.777262 -228.589078)
		(mid 370.620285 -228.284278)
		(end 370.777262 -227.979478)
		(width 0.1143)
		(layer "In6.Cu")
		(net "GMI_CPU1_G0_CPU0_G2_TX_DN<2>")
	)
	(arc
		(start 100.649024 -231.869742)
		(mid 100.405697 -232.334308)
		(end 100.649024 -232.798874)
		(width 0.1143)
		(layer "In6.Cu")
		(net "GMI_CPU1_G0_CPU0_G2_TX_DN<2>")
	)
	(arc
		(start 102.058978 -224.579942)
		(mid 101.880165 -224.782292)
		(end 101.815646 -225.044508)
		(width 0.1143)
		(layer "In6.Cu")
		(net "GMI_CPU1_G0_CPU0_G2_TX_DN<2>")
	)
	(arc
		(start 101.118924 -226.199954)
		(mid 100.940111 -226.402304)
		(end 100.875592 -226.66452)
		(width 0.1143)
		(layer "In6.Cu")
		(net "GMI_CPU1_G0_CPU0_G2_TX_DN<2>")
	)
	(arc
		(start 98.06559 -242.758722)
		(mid 98.063567 -242.770132)
		(end 98.06178 -242.781582)
		(width 0.1143)
		(layer "In6.Cu")
		(net "GMI_CPU1_G0_CPU0_G2_TX_DN<2>")
	)
	(arc
		(start 369.680236 -225.044254)
		(mid 369.615721 -224.782035)
		(end 369.436904 -224.579688)
		(width 0.1143)
		(layer "In6.Cu")
		(net "GMI_CPU1_G0_CPU0_G2_TX_DN<2>")
	)
	(arc
		(start 367.959386 -222.111062)
		(mid 367.841763 -221.97726)
		(end 367.799366 -221.80423)
		(width 0.1143)
		(layer "In6.Cu")
		(net "GMI_CPU1_G0_CPU0_G2_TX_DN<2>")
	)
	(arc
		(start 99.465638 -237.194344)
		(mid 99.424089 -237.365766)
		(end 99.308666 -237.499144)
		(width 0.1143)
		(layer "In6.Cu")
		(net "GMI_CPU1_G0_CPU0_G2_TX_DN<2>")
	)
	(arc
		(start 370.777262 -226.969066)
		(mid 370.661835 -226.83569)
		(end 370.62029 -226.664266)
		(width 0.1143)
		(layer "In6.Cu")
		(net "GMI_CPU1_G0_CPU0_G2_TX_DN<2>")
	)
	(arc
		(start 370.62029 -226.664266)
		(mid 370.555775 -226.402047)
		(end 370.376958 -226.1997)
		(width 0.1143)
		(layer "In6.Cu")
		(net "GMI_CPU1_G0_CPU0_G2_TX_DN<2>")
	)
	(arc
		(start 370.777262 -233.44886)
		(mid 370.620285 -233.14406)
		(end 370.777262 -232.83926)
		(width 0.1143)
		(layer "In6.Cu")
		(net "GMI_CPU1_G0_CPU0_G2_TX_DN<2>")
	)
	(arc
		(start 103.226108 -222.61449)
		(mid 103.17603 -222.801682)
		(end 103.039164 -222.938848)
		(width 0.1143)
		(layer "In6.Cu")
		(net "GMI_CPU1_G0_CPU0_G2_TX_DN<2>")
	)
	(arc
		(start 100.720652 -229.60076)
		(mid 100.834581 -229.733907)
		(end 100.875592 -229.90429)
		(width 0.1143)
		(layer "In6.Cu")
		(net "GMI_CPU1_G0_CPU0_G2_TX_DN<2>")
	)
	(arc
		(start 98.768916 -239.969802)
		(mid 98.525589 -240.434368)
		(end 98.768916 -240.898934)
		(width 0.1143)
		(layer "In6.Cu")
		(net "GMI_CPU1_G0_CPU0_G2_TX_DN<2>")
	)
	(arc
		(start 373.430292 -242.758468)
		(mid 373.348859 -242.55607)
		(end 373.196866 -242.399566)
		(width 0.1143)
		(layer "In6.Cu")
		(net "GMI_CPU1_G0_CPU0_G2_TX_DN<2>")
	)
	(arc
		(start 100.649024 -233.489754)
		(mid 100.405697 -233.95432)
		(end 100.649024 -234.418886)
		(width 0.1143)
		(layer "In6.Cu")
		(net "GMI_CPU1_G0_CPU0_G2_TX_DN<2>")
	)
	(arc
		(start 99.933506 -236.386624)
		(mid 99.883947 -236.571421)
		(end 99.748594 -236.706664)
		(width 0.1143)
		(layer "In6.Cu")
		(net "GMI_CPU1_G0_CPU0_G2_TX_DN<2>")
	)
	(arc
		(start 370.777262 -230.208836)
		(mid 370.661835 -230.07546)
		(end 370.62029 -229.904036)
		(width 0.1143)
		(layer "In6.Cu")
		(net "GMI_CPU1_G0_CPU0_G2_TX_DN<2>")
	)
	(arc
		(start 371.562376 -236.38637)
		(mid 371.487198 -236.105135)
		(end 371.281706 -235.898944)
		(width 0.1143)
		(layer "In6.Cu")
		(net "GMI_CPU1_G0_CPU0_G2_TX_DN<2>")
	)
	(arc
		(start 368.896138 -223.728534)
		(mid 368.781462 -223.5952)
		(end 368.740182 -223.424242)
		(width 0.1143)
		(layer "In6.Cu")
		(net "GMI_CPU1_G0_CPU0_G2_TX_DN<2>")
	)
	(arc
		(start 368.269774 -222.614236)
		(mid 368.206552 -222.354314)
		(end 368.031014 -222.152464)
		(width 0.1143)
		(layer "In6.Cu")
		(net "GMI_CPU1_G0_CPU0_G2_TX_DN<2>")
	)
	(arc
		(start 100.214176 -235.899198)
		(mid 100.008704 -236.1054)
		(end 99.933506 -236.386624)
		(width 0.1143)
		(layer "In6.Cu")
		(net "GMI_CPU1_G0_CPU0_G2_TX_DN<2>")
	)
	(segment
		(start 98.147886 -239.8903)
		(end 97.681034 -239.624362)
		(width 0.12954)
		(layer "F.Cu")
		(net "GMI_CPU1_G0_CPU0_G2_TX_DN<1>")
	)
	(segment
		(start 373.347996 -239.890046)
		(end 373.814848 -239.624108)
		(width 0.12954)
		(layer "F.Cu")
		(net "GMI_CPU1_G0_CPU0_G2_TX_DN<1>")
	)
	(segment
		(start 362.744766 -210.292188)
		(end 357.21925 -205.888336)
		(width 0.14224)
		(layer "In6.Cu")
		(net "GMI_CPU1_G0_CPU0_G2_TX_DN<1>")
	)
	(segment
		(start 98.810064 -236.705648)
		(end 98.808794 -236.70641)
		(width 0.1143)
		(layer "In6.Cu")
		(net "GMI_CPU1_G0_CPU0_G2_TX_DN<1>")
	)
	(segment
		(start 101.15804 -224.557082)
		(end 101.118924 -224.579942)
		(width 0.1143)
		(layer "In6.Cu")
		(net "GMI_CPU1_G0_CPU0_G2_TX_DN<1>")
	)
	(segment
		(start 99.70897 -234.418886)
		(end 99.748086 -234.441746)
		(width 0.1143)
		(layer "In6.Cu")
		(net "GMI_CPU1_G0_CPU0_G2_TX_DN<1>")
	)
	(segment
		(start 102.602284 -222.119698)
		(end 102.534212 -222.159068)
		(width 0.1143)
		(layer "In6.Cu")
		(net "GMI_CPU1_G0_CPU0_G2_TX_DN<1>")
	)
	(segment
		(start 307.311298 -175.740822)
		(end 302.917352 -175.740822)
		(width 0.14224)
		(layer "In6.Cu")
		(net "GMI_CPU1_G0_CPU0_G2_TX_DN<1>")
	)
	(segment
		(start 98.808794 -236.70641)
		(end 98.808032 -236.706918)
		(width 0.1143)
		(layer "In6.Cu")
		(net "GMI_CPU1_G0_CPU0_G2_TX_DN<1>")
	)
	(segment
		(start 373.196866 -239.159542)
		(end 373.12727 -239.118902)
		(width 0.1143)
		(layer "In6.Cu")
		(net "GMI_CPU1_G0_CPU0_G2_TX_DN<1>")
	)
	(segment
		(start 368.740182 -221.325948)
		(end 368.740436 -221.325694)
		(width 0.1143)
		(layer "In6.Cu")
		(net "GMI_CPU1_G0_CPU0_G2_TX_DN<1>")
	)
	(segment
		(start 100.217986 -226.177094)
		(end 100.20808 -226.18319)
		(width 0.1143)
		(layer "In6.Cu")
		(net "GMI_CPU1_G0_CPU0_G2_TX_DN<1>")
	)
	(segment
		(start 97.978976 -239.624362)
		(end 97.681034 -239.624362)
		(width 0.1143)
		(layer "In6.Cu")
		(net "GMI_CPU1_G0_CPU0_G2_TX_DN<1>")
	)
	(segment
		(start 368.740182 -221.820232)
		(end 368.740182 -221.325948)
		(width 0.1143)
		(layer "In6.Cu")
		(net "GMI_CPU1_G0_CPU0_G2_TX_DN<1>")
	)
	(segment
		(start 100.249736 -226.158806)
		(end 100.217986 -226.177094)
		(width 0.1143)
		(layer "In6.Cu")
		(net "GMI_CPU1_G0_CPU0_G2_TX_DN<1>")
	)
	(segment
		(start 369.906804 -223.769682)
		(end 369.837208 -223.729042)
		(width 0.1143)
		(layer "In6.Cu")
		(net "GMI_CPU1_G0_CPU0_G2_TX_DN<1>")
	)
	(segment
		(start 99.727004 -226.999292)
		(end 99.709732 -227.009452)
		(width 0.1143)
		(layer "In6.Cu")
		(net "GMI_CPU1_G0_CPU0_G2_TX_DN<1>")
	)
	(segment
		(start 371.716046 -233.448352)
		(end 371.705378 -233.440732)
		(width 0.1143)
		(layer "In6.Cu")
		(net "GMI_CPU1_G0_CPU0_G2_TX_DN<1>")
	)
	(segment
		(start 370.376958 -224.579688)
		(end 370.340382 -224.558352)
		(width 0.1143)
		(layer "In6.Cu")
		(net "GMI_CPU1_G0_CPU0_G2_TX_DN<1>")
	)
	(segment
		(start 99.747324 -231.201214)
		(end 99.748086 -231.201722)
		(width 0.1143)
		(layer "In6.Cu")
		(net "GMI_CPU1_G0_CPU0_G2_TX_DN<1>")
	)
	(segment
		(start 98.368612 -237.499144)
		(end 98.338132 -237.516924)
		(width 0.1143)
		(layer "In6.Cu")
		(net "GMI_CPU1_G0_CPU0_G2_TX_DN<1>")
	)
	(segment
		(start 357.21925 -205.888336)
		(end 331.777086 -189.921896)
		(width 0.14224)
		(layer "In6.Cu")
		(net "GMI_CPU1_G0_CPU0_G2_TX_DN<1>")
	)
	(segment
		(start 98.299016 -238.468916)
		(end 98.338132 -238.491776)
		(width 0.1143)
		(layer "In6.Cu")
		(net "GMI_CPU1_G0_CPU0_G2_TX_DN<1>")
	)
	(segment
		(start 102.709726 -217.546174)
		(end 102.709726 -221.064836)
		(width 0.14224)
		(layer "In6.Cu")
		(net "GMI_CPU1_G0_CPU0_G2_TX_DN<1>")
	)
	(segment
		(start 112.946434 -205.293214)
		(end 104.428036 -213.811866)
		(width 0.14224)
		(layer "In6.Cu")
		(net "GMI_CPU1_G0_CPU0_G2_TX_DN<1>")
	)
	(segment
		(start 99.768914 -230.214678)
		(end 99.708462 -230.249984)
		(width 0.1143)
		(layer "In6.Cu")
		(net "GMI_CPU1_G0_CPU0_G2_TX_DN<1>")
	)
	(segment
		(start 371.788944 -231.177338)
		(end 371.789198 -231.177338)
		(width 0.1143)
		(layer "In6.Cu")
		(net "GMI_CPU1_G0_CPU0_G2_TX_DN<1>")
	)
	(segment
		(start 99.793552 -233.440732)
		(end 99.70897 -233.489754)
		(width 0.1143)
		(layer "In6.Cu")
		(net "GMI_CPU1_G0_CPU0_G2_TX_DN<1>")
	)
	(segment
		(start 369.436904 -222.959676)
		(end 369.382548 -222.92818)
		(width 0.1143)
		(layer "In6.Cu")
		(net "GMI_CPU1_G0_CPU0_G2_TX_DN<1>")
	)
	(segment
		(start 98.368612 -239.119156)
		(end 98.338132 -239.136936)
		(width 0.1143)
		(layer "In6.Cu")
		(net "GMI_CPU1_G0_CPU0_G2_TX_DN<1>")
	)
	(segment
		(start 373.516906 -239.624108)
		(end 373.434102 -239.541304)
		(width 0.1143)
		(layer "In6.Cu")
		(net "GMI_CPU1_G0_CPU0_G2_TX_DN<1>")
	)
	(segment
		(start 371.705378 -232.847388)
		(end 371.716046 -232.839768)
		(width 0.1143)
		(layer "In6.Cu")
		(net "GMI_CPU1_G0_CPU0_G2_TX_DN<1>")
	)
	(segment
		(start 98.839782 -236.68863)
		(end 98.810064 -236.705648)
		(width 0.1143)
		(layer "In6.Cu")
		(net "GMI_CPU1_G0_CPU0_G2_TX_DN<1>")
	)
	(segment
		(start 99.70897 -232.798874)
		(end 99.712526 -232.800906)
		(width 0.1143)
		(layer "In6.Cu")
		(net "GMI_CPU1_G0_CPU0_G2_TX_DN<1>")
	)
	(segment
		(start 101.628194 -223.747076)
		(end 101.589078 -223.769936)
		(width 0.1143)
		(layer "In6.Cu")
		(net "GMI_CPU1_G0_CPU0_G2_TX_DN<1>")
	)
	(segment
		(start 98.338132 -237.516924)
		(end 98.299016 -237.539784)
		(width 0.1143)
		(layer "In6.Cu")
		(net "GMI_CPU1_G0_CPU0_G2_TX_DN<1>")
	)
	(segment
		(start 371.768878 -226.999038)
		(end 371.768624 -226.999038)
		(width 0.1143)
		(layer "In6.Cu")
		(net "GMI_CPU1_G0_CPU0_G2_TX_DN<1>")
	)
	(segment
		(start 371.747796 -235.086652)
		(end 371.716046 -235.068364)
		(width 0.1143)
		(layer "In6.Cu")
		(net "GMI_CPU1_G0_CPU0_G2_TX_DN<1>")
	)
	(segment
		(start 98.338132 -238.491776)
		(end 98.368612 -238.509556)
		(width 0.1143)
		(layer "In6.Cu")
		(net "GMI_CPU1_G0_CPU0_G2_TX_DN<1>")
	)
	(segment
		(start 368.786156 -221.09303)
		(end 368.786156 -218.167712)
		(width 0.14224)
		(layer "In6.Cu")
		(net "GMI_CPU1_G0_CPU0_G2_TX_DN<1>")
	)
	(segment
		(start 99.70897 -229.559104)
		(end 99.781614 -229.601522)
		(width 0.1143)
		(layer "In6.Cu")
		(net "GMI_CPU1_G0_CPU0_G2_TX_DN<1>")
	)
	(segment
		(start 101.160072 -224.555812)
		(end 101.158802 -224.556574)
		(width 0.1143)
		(layer "In6.Cu")
		(net "GMI_CPU1_G0_CPU0_G2_TX_DN<1>")
	)
	(segment
		(start 98.06178 -239.541558)
		(end 97.978976 -239.624362)
		(width 0.1143)
		(layer "In6.Cu")
		(net "GMI_CPU1_G0_CPU0_G2_TX_DN<1>")
	)
	(segment
		(start 370.33581 -224.555558)
		(end 370.306092 -224.53854)
		(width 0.1143)
		(layer "In6.Cu")
		(net "GMI_CPU1_G0_CPU0_G2_TX_DN<1>")
	)
	(segment
		(start 367.493042 -215.040464)
		(end 362.744766 -210.292188)
		(width 0.14224)
		(layer "In6.Cu")
		(net "GMI_CPU1_G0_CPU0_G2_TX_DN<1>")
	)
	(segment
		(start 99.748086 -234.441746)
		(end 99.779836 -234.460034)
		(width 0.1143)
		(layer "In6.Cu")
		(net "GMI_CPU1_G0_CPU0_G2_TX_DN<1>")
	)
	(segment
		(start 371.747796 -234.441492)
		(end 371.786912 -234.418632)
		(width 0.1143)
		(layer "In6.Cu")
		(net "GMI_CPU1_G0_CPU0_G2_TX_DN<1>")
	)
	(segment
		(start 99.748594 -231.846882)
		(end 99.709732 -231.869234)
		(width 0.1143)
		(layer "In6.Cu")
		(net "GMI_CPU1_G0_CPU0_G2_TX_DN<1>")
	)
	(segment
		(start 166.721282 -174.944532)
		(end 161.97199 -176.20234)
		(width 0.14224)
		(layer "In6.Cu")
		(net "GMI_CPU1_G0_CPU0_G2_TX_DN<1>")
	)
	(segment
		(start 98.808032 -236.706918)
		(end 98.768916 -236.729778)
		(width 0.1143)
		(layer "In6.Cu")
		(net "GMI_CPU1_G0_CPU0_G2_TX_DN<1>")
	)
	(segment
		(start 373.12727 -238.509302)
		(end 373.196866 -238.468662)
		(width 0.1143)
		(layer "In6.Cu")
		(net "GMI_CPU1_G0_CPU0_G2_TX_DN<1>")
	)
	(segment
		(start 370.337842 -224.556828)
		(end 370.33708 -224.55632)
		(width 0.1143)
		(layer "In6.Cu")
		(net "GMI_CPU1_G0_CPU0_G2_TX_DN<1>")
	)
	(segment
		(start 372.685818 -236.705394)
		(end 372.6561 -236.688376)
		(width 0.1143)
		(layer "In6.Cu")
		(net "GMI_CPU1_G0_CPU0_G2_TX_DN<1>")
	)
	(segment
		(start 372.69039 -236.708188)
		(end 372.688866 -236.707172)
		(width 0.1143)
		(layer "In6.Cu")
		(net "GMI_CPU1_G0_CPU0_G2_TX_DN<1>")
	)
	(segment
		(start 371.748812 -228.607366)
		(end 371.736366 -228.600254)
		(width 0.1143)
		(layer "In6.Cu")
		(net "GMI_CPU1_G0_CPU0_G2_TX_DN<1>")
	)
	(segment
		(start 102.709726 -221.064836)
		(end 102.709726 -221.093284)
		(width 0.1143)
		(layer "In6.Cu")
		(net "GMI_CPU1_G0_CPU0_G2_TX_DN<1>")
	)
	(segment
		(start 102.113334 -222.928434)
		(end 102.058978 -222.95993)
		(width 0.1143)
		(layer "In6.Cu")
		(net "GMI_CPU1_G0_CPU0_G2_TX_DN<1>")
	)
	(segment
		(start 99.278186 -235.896912)
		(end 99.23907 -235.919772)
		(width 0.1143)
		(layer "In6.Cu")
		(net "GMI_CPU1_G0_CPU0_G2_TX_DN<1>")
	)
	(segment
		(start 102.755446 -221.139004)
		(end 102.755446 -221.325948)
		(width 0.1143)
		(layer "In6.Cu")
		(net "GMI_CPU1_G0_CPU0_G2_TX_DN<1>")
	)
	(segment
		(start 371.78615 -231.86898)
		(end 371.747288 -231.846628)
		(width 0.1143)
		(layer "In6.Cu")
		(net "GMI_CPU1_G0_CPU0_G2_TX_DN<1>")
	)
	(segment
		(start 102.755446 -221.325948)
		(end 102.7557 -221.326202)
		(width 0.1143)
		(layer "In6.Cu")
		(net "GMI_CPU1_G0_CPU0_G2_TX_DN<1>")
	)
	(segment
		(start 371.786912 -228.629718)
		(end 371.75059 -228.608382)
		(width 0.1143)
		(layer "In6.Cu")
		(net "GMI_CPU1_G0_CPU0_G2_TX_DN<1>")
	)
	(segment
		(start 371.716046 -234.45978)
		(end 371.747796 -234.441492)
		(width 0.1143)
		(layer "In6.Cu")
		(net "GMI_CPU1_G0_CPU0_G2_TX_DN<1>")
	)
	(segment
		(start 371.749574 -228.607874)
		(end 371.748812 -228.607366)
		(width 0.1143)
		(layer "In6.Cu")
		(net "GMI_CPU1_G0_CPU0_G2_TX_DN<1>")
	)
	(segment
		(start 99.709732 -227.9396)
		(end 99.759516 -227.968556)
		(width 0.1143)
		(layer "In6.Cu")
		(net "GMI_CPU1_G0_CPU0_G2_TX_DN<1>")
	)
	(segment
		(start 99.748086 -235.086906)
		(end 99.70897 -235.109766)
		(width 0.1143)
		(layer "In6.Cu")
		(net "GMI_CPU1_G0_CPU0_G2_TX_DN<1>")
	)
	(segment
		(start 101.658674 -223.729296)
		(end 101.628194 -223.747076)
		(width 0.1143)
		(layer "In6.Cu")
		(net "GMI_CPU1_G0_CPU0_G2_TX_DN<1>")
	)
	(segment
		(start 370.338858 -224.557336)
		(end 370.337842 -224.556828)
		(width 0.1143)
		(layer "In6.Cu")
		(net "GMI_CPU1_G0_CPU0_G2_TX_DN<1>")
	)
	(segment
		(start 370.846858 -225.389694)
		(end 370.777262 -225.349054)
		(width 0.1143)
		(layer "In6.Cu")
		(net "GMI_CPU1_G0_CPU0_G2_TX_DN<1>")
	)
	(segment
		(start 371.78615 -227.009198)
		(end 371.768878 -226.999038)
		(width 0.1143)
		(layer "In6.Cu")
		(net "GMI_CPU1_G0_CPU0_G2_TX_DN<1>")
	)
	(segment
		(start 370.340382 -224.558352)
		(end 370.338858 -224.557336)
		(width 0.1143)
		(layer "In6.Cu")
		(net "GMI_CPU1_G0_CPU0_G2_TX_DN<1>")
	)
	(segment
		(start 302.917352 -175.740822)
		(end 268.88567 -175.54194)
		(width 0.14224)
		(layer "In6.Cu")
		(net "GMI_CPU1_G0_CPU0_G2_TX_DN<1>")
	)
	(segment
		(start 101.18979 -224.538794)
		(end 101.160072 -224.555812)
		(width 0.1143)
		(layer "In6.Cu")
		(net "GMI_CPU1_G0_CPU0_G2_TX_DN<1>")
	)
	(segment
		(start 100.68814 -225.367088)
		(end 100.649024 -225.389948)
		(width 0.1143)
		(layer "In6.Cu")
		(net "GMI_CPU1_G0_CPU0_G2_TX_DN<1>")
	)
	(segment
		(start 372.256812 -235.919518)
		(end 372.187216 -235.878878)
		(width 0.1143)
		(layer "In6.Cu")
		(net "GMI_CPU1_G0_CPU0_G2_TX_DN<1>")
	)
	(segment
		(start 371.786912 -233.4895)
		(end 371.716046 -233.448352)
		(width 0.1143)
		(layer "In6.Cu")
		(net "GMI_CPU1_G0_CPU0_G2_TX_DN<1>")
	)
	(segment
		(start 371.716046 -232.839768)
		(end 371.786912 -232.79862)
		(width 0.1143)
		(layer "In6.Cu")
		(net "GMI_CPU1_G0_CPU0_G2_TX_DN<1>")
	)
	(segment
		(start 99.748594 -226.986846)
		(end 99.727258 -226.999292)
		(width 0.1143)
		(layer "In6.Cu")
		(net "GMI_CPU1_G0_CPU0_G2_TX_DN<1>")
	)
	(segment
		(start 368.740436 -221.13875)
		(end 368.786156 -221.09303)
		(width 0.1143)
		(layer "In6.Cu")
		(net "GMI_CPU1_G0_CPU0_G2_TX_DN<1>")
	)
	(segment
		(start 117.057424 -202.138788)
		(end 112.946434 -205.293214)
		(width 0.14224)
		(layer "In6.Cu")
		(net "GMI_CPU1_G0_CPU0_G2_TX_DN<1>")
	)
	(segment
		(start 371.768624 -226.999038)
		(end 371.747288 -226.986592)
		(width 0.1143)
		(layer "In6.Cu")
		(net "GMI_CPU1_G0_CPU0_G2_TX_DN<1>")
	)
	(segment
		(start 372.726966 -236.729524)
		(end 372.69039 -236.708188)
		(width 0.1143)
		(layer "In6.Cu")
		(net "GMI_CPU1_G0_CPU0_G2_TX_DN<1>")
	)
	(segment
		(start 310.798464 -176.698148)
		(end 307.311298 -175.740822)
		(width 0.14224)
		(layer "In6.Cu")
		(net "GMI_CPU1_G0_CPU0_G2_TX_DN<1>")
	)
	(segment
		(start 99.748086 -231.201722)
		(end 99.748594 -231.201722)
		(width 0.1143)
		(layer "In6.Cu")
		(net "GMI_CPU1_G0_CPU0_G2_TX_DN<1>")
	)
	(segment
		(start 371.748558 -231.20096)
		(end 371.788944 -231.177338)
		(width 0.1143)
		(layer "In6.Cu")
		(net "GMI_CPU1_G0_CPU0_G2_TX_DN<1>")
	)
	(segment
		(start 102.7557 -221.326202)
		(end 102.7557 -221.820486)
		(width 0.1143)
		(layer "In6.Cu")
		(net "GMI_CPU1_G0_CPU0_G2_TX_DN<1>")
	)
	(segment
		(start 371.736366 -227.968302)
		(end 371.78615 -227.939346)
		(width 0.1143)
		(layer "In6.Cu")
		(net "GMI_CPU1_G0_CPU0_G2_TX_DN<1>")
	)
	(segment
		(start 99.759516 -228.600508)
		(end 99.70897 -228.629972)
		(width 0.1143)
		(layer "In6.Cu")
		(net "GMI_CPU1_G0_CPU0_G2_TX_DN<1>")
	)
	(segment
		(start 371.786912 -235.109512)
		(end 371.747796 -235.086652)
		(width 0.1143)
		(layer "In6.Cu")
		(net "GMI_CPU1_G0_CPU0_G2_TX_DN<1>")
	)
	(segment
		(start 373.814848 -239.624108)
		(end 373.516906 -239.624108)
		(width 0.1143)
		(layer "In6.Cu")
		(net "GMI_CPU1_G0_CPU0_G2_TX_DN<1>")
	)
	(segment
		(start 368.96167 -222.158814)
		(end 368.893598 -222.119444)
		(width 0.1143)
		(layer "In6.Cu")
		(net "GMI_CPU1_G0_CPU0_G2_TX_DN<1>")
	)
	(segment
		(start 101.158802 -224.556574)
		(end 101.15804 -224.557082)
		(width 0.1143)
		(layer "In6.Cu")
		(net "GMI_CPU1_G0_CPU0_G2_TX_DN<1>")
	)
	(segment
		(start 371.747288 -231.201468)
		(end 371.747796 -231.201468)
		(width 0.1143)
		(layer "In6.Cu")
		(net "GMI_CPU1_G0_CPU0_G2_TX_DN<1>")
	)
	(segment
		(start 372.688866 -236.707172)
		(end 372.68785 -236.706664)
		(width 0.1143)
		(layer "In6.Cu")
		(net "GMI_CPU1_G0_CPU0_G2_TX_DN<1>")
	)
	(segment
		(start 102.709726 -221.093284)
		(end 102.755446 -221.139004)
		(width 0.1143)
		(layer "In6.Cu")
		(net "GMI_CPU1_G0_CPU0_G2_TX_DN<1>")
	)
	(segment
		(start 371.78742 -230.24973)
		(end 371.726968 -230.214424)
		(width 0.1143)
		(layer "In6.Cu")
		(net "GMI_CPU1_G0_CPU0_G2_TX_DN<1>")
	)
	(segment
		(start 371.714268 -229.601268)
		(end 371.786912 -229.55885)
		(width 0.1143)
		(layer "In6.Cu")
		(net "GMI_CPU1_G0_CPU0_G2_TX_DN<1>")
	)
	(segment
		(start 99.308666 -235.879132)
		(end 99.278186 -235.896912)
		(width 0.1143)
		(layer "In6.Cu")
		(net "GMI_CPU1_G0_CPU0_G2_TX_DN<1>")
	)
	(segment
		(start 371.287802 -226.182936)
		(end 371.282722 -226.179888)
		(width 0.1143)
		(layer "In6.Cu")
		(net "GMI_CPU1_G0_CPU0_G2_TX_DN<1>")
	)
	(segment
		(start 371.282722 -226.179888)
		(end 371.277896 -226.17684)
		(width 0.1143)
		(layer "In6.Cu")
		(net "GMI_CPU1_G0_CPU0_G2_TX_DN<1>")
	)
	(segment
		(start 100.71862 -225.349308)
		(end 100.68814 -225.367088)
		(width 0.1143)
		(layer "In6.Cu")
		(net "GMI_CPU1_G0_CPU0_G2_TX_DN<1>")
	)
	(segment
		(start 372.687088 -236.706156)
		(end 372.685818 -236.705394)
		(width 0.1143)
		(layer "In6.Cu")
		(net "GMI_CPU1_G0_CPU0_G2_TX_DN<1>")
	)
	(segment
		(start 104.428036 -213.811866)
		(end 103.976678 -214.487506)
		(width 0.14224)
		(layer "In6.Cu")
		(net "GMI_CPU1_G0_CPU0_G2_TX_DN<1>")
	)
	(segment
		(start 99.727258 -226.999292)
		(end 99.727004 -226.999292)
		(width 0.1143)
		(layer "In6.Cu")
		(net "GMI_CPU1_G0_CPU0_G2_TX_DN<1>")
	)
	(segment
		(start 373.196866 -237.53953)
		(end 373.12727 -237.49889)
		(width 0.1143)
		(layer "In6.Cu")
		(net "GMI_CPU1_G0_CPU0_G2_TX_DN<1>")
	)
	(segment
		(start 99.779836 -235.068618)
		(end 99.748086 -235.086906)
		(width 0.1143)
		(layer "In6.Cu")
		(net "GMI_CPU1_G0_CPU0_G2_TX_DN<1>")
	)
	(segment
		(start 368.786156 -218.167712)
		(end 367.493042 -215.040464)
		(width 0.14224)
		(layer "In6.Cu")
		(net "GMI_CPU1_G0_CPU0_G2_TX_DN<1>")
	)
	(segment
		(start 268.885924 -175.54194)
		(end 166.721282 -174.944532)
		(width 0.14224)
		(layer "In6.Cu")
		(net "GMI_CPU1_G0_CPU0_G2_TX_DN<1>")
	)
	(segment
		(start 99.712526 -232.800906)
		(end 99.794568 -232.859834)
		(width 0.1143)
		(layer "In6.Cu")
		(net "GMI_CPU1_G0_CPU0_G2_TX_DN<1>")
	)
	(segment
		(start 371.747796 -231.201468)
		(end 371.748558 -231.20096)
		(width 0.1143)
		(layer "In6.Cu")
		(net "GMI_CPU1_G0_CPU0_G2_TX_DN<1>")
	)
	(segment
		(start 103.976678 -214.487506)
		(end 102.709726 -217.546174)
		(width 0.14224)
		(layer "In6.Cu")
		(net "GMI_CPU1_G0_CPU0_G2_TX_DN<1>")
	)
	(segment
		(start 329.360276 -187.720478)
		(end 310.798464 -176.698148)
		(width 0.14224)
		(layer "In6.Cu")
		(net "GMI_CPU1_G0_CPU0_G2_TX_DN<1>")
	)
	(segment
		(start 371.277896 -226.17684)
		(end 371.246146 -226.158552)
		(width 0.1143)
		(layer "In6.Cu")
		(net "GMI_CPU1_G0_CPU0_G2_TX_DN<1>")
	)
	(segment
		(start 268.88567 -175.54194)
		(end 268.885924 -175.54194)
		(width 0.14224)
		(layer "In6.Cu")
		(net "GMI_CPU1_G0_CPU0_G2_TX_DN<1>")
	)
	(segment
		(start 98.338132 -239.136936)
		(end 98.299016 -239.159796)
		(width 0.1143)
		(layer "In6.Cu")
		(net "GMI_CPU1_G0_CPU0_G2_TX_DN<1>")
	)
	(segment
		(start 372.68785 -236.706664)
		(end 372.687088 -236.706156)
		(width 0.1143)
		(layer "In6.Cu")
		(net "GMI_CPU1_G0_CPU0_G2_TX_DN<1>")
	)
	(segment
		(start 161.97199 -176.20234)
		(end 117.057424 -202.138788)
		(width 0.14224)
		(layer "In6.Cu")
		(net "GMI_CPU1_G0_CPU0_G2_TX_DN<1>")
	)
	(segment
		(start 99.706684 -231.177592)
		(end 99.706938 -231.177592)
		(width 0.1143)
		(layer "In6.Cu")
		(net "GMI_CPU1_G0_CPU0_G2_TX_DN<1>")
	)
	(segment
		(start 368.740436 -221.325694)
		(end 368.740436 -221.13875)
		(width 0.1143)
		(layer "In6.Cu")
		(net "GMI_CPU1_G0_CPU0_G2_TX_DN<1>")
	)
	(segment
		(start 99.706938 -231.177592)
		(end 99.747324 -231.201214)
		(width 0.1143)
		(layer "In6.Cu")
		(net "GMI_CPU1_G0_CPU0_G2_TX_DN<1>")
	)
	(segment
		(start 370.33708 -224.55632)
		(end 370.33581 -224.555558)
		(width 0.1143)
		(layer "In6.Cu")
		(net "GMI_CPU1_G0_CPU0_G2_TX_DN<1>")
	)
	(segment
		(start 99.794568 -233.439716)
		(end 99.793552 -233.440732)
		(width 0.1143)
		(layer "In6.Cu")
		(net "GMI_CPU1_G0_CPU0_G2_TX_DN<1>")
	)
	(segment
		(start 371.75059 -228.608382)
		(end 371.749574 -228.607874)
		(width 0.1143)
		(layer "In6.Cu")
		(net "GMI_CPU1_G0_CPU0_G2_TX_DN<1>")
	)
	(segment
		(start 331.777086 -189.921896)
		(end 329.360276 -187.720478)
		(width 0.14224)
		(layer "In6.Cu")
		(net "GMI_CPU1_G0_CPU0_G2_TX_DN<1>")
	)
	(arc
		(start 369.382548 -222.92818)
		(mid 369.254406 -222.800133)
		(end 369.207542 -222.625158)
		(width 0.1143)
		(layer "In6.Cu")
		(net "GMI_CPU1_G0_CPU0_G2_TX_DN<1>")
	)
	(arc
		(start 372.030244 -235.574078)
		(mid 371.965729 -235.311859)
		(end 371.786912 -235.109512)
		(width 0.1143)
		(layer "In6.Cu")
		(net "GMI_CPU1_G0_CPU0_G2_TX_DN<1>")
	)
	(arc
		(start 371.786912 -227.938838)
		(mid 371.790861 -227.936061)
		(end 371.794786 -227.93325)
		(width 0.1143)
		(layer "In6.Cu")
		(net "GMI_CPU1_G0_CPU0_G2_TX_DN<1>")
	)
	(arc
		(start 372.970298 -237.19409)
		(mid 372.905783 -236.931871)
		(end 372.726966 -236.729524)
		(width 0.1143)
		(layer "In6.Cu")
		(net "GMI_CPU1_G0_CPU0_G2_TX_DN<1>")
	)
	(arc
		(start 370.62029 -225.044254)
		(mid 370.555775 -224.782035)
		(end 370.376958 -224.579688)
		(width 0.1143)
		(layer "In6.Cu")
		(net "GMI_CPU1_G0_CPU0_G2_TX_DN<1>")
	)
	(arc
		(start 99.709732 -227.009452)
		(mid 99.465903 -227.469241)
		(end 99.701096 -227.933504)
		(width 0.1143)
		(layer "In6.Cu")
		(net "GMI_CPU1_G0_CPU0_G2_TX_DN<1>")
	)
	(arc
		(start 100.649024 -225.389948)
		(mid 100.470211 -225.592298)
		(end 100.405692 -225.854514)
		(width 0.1143)
		(layer "In6.Cu")
		(net "GMI_CPU1_G0_CPU0_G2_TX_DN<1>")
	)
	(arc
		(start 371.562122 -226.665536)
		(mid 371.488743 -226.387987)
		(end 371.287802 -226.182936)
		(width 0.1143)
		(layer "In6.Cu")
		(net "GMI_CPU1_G0_CPU0_G2_TX_DN<1>")
	)
	(arc
		(start 102.534212 -222.159068)
		(mid 102.35356 -222.361813)
		(end 102.28834 -222.625412)
		(width 0.1143)
		(layer "In6.Cu")
		(net "GMI_CPU1_G0_CPU0_G2_TX_DN<1>")
	)
	(arc
		(start 101.589078 -223.769936)
		(mid 101.410265 -223.972286)
		(end 101.345746 -224.234502)
		(width 0.1143)
		(layer "In6.Cu")
		(net "GMI_CPU1_G0_CPU0_G2_TX_DN<1>")
	)
	(arc
		(start 371.747288 -226.986592)
		(mid 371.611703 -226.850859)
		(end 371.562122 -226.665536)
		(width 0.1143)
		(layer "In6.Cu")
		(net "GMI_CPU1_G0_CPU0_G2_TX_DN<1>")
	)
	(arc
		(start 372.02999 -230.714296)
		(mid 371.965732 -230.452252)
		(end 371.78742 -230.24973)
		(width 0.1143)
		(layer "In6.Cu")
		(net "GMI_CPU1_G0_CPU0_G2_TX_DN<1>")
	)
	(arc
		(start 99.748594 -231.201722)
		(mid 99.934232 -231.524302)
		(end 99.748594 -231.846882)
		(width 0.1143)
		(layer "In6.Cu")
		(net "GMI_CPU1_G0_CPU0_G2_TX_DN<1>")
	)
	(arc
		(start 369.837208 -223.729042)
		(mid 369.721781 -223.595666)
		(end 369.680236 -223.424242)
		(width 0.1143)
		(layer "In6.Cu")
		(net "GMI_CPU1_G0_CPU0_G2_TX_DN<1>")
	)
	(arc
		(start 370.777262 -225.349054)
		(mid 370.661835 -225.215678)
		(end 370.62029 -225.044254)
		(width 0.1143)
		(layer "In6.Cu")
		(net "GMI_CPU1_G0_CPU0_G2_TX_DN<1>")
	)
	(arc
		(start 102.058978 -222.95993)
		(mid 101.880165 -223.16228)
		(end 101.815646 -223.424496)
		(width 0.1143)
		(layer "In6.Cu")
		(net "GMI_CPU1_G0_CPU0_G2_TX_DN<1>")
	)
	(arc
		(start 371.747288 -231.846628)
		(mid 371.56165 -231.524048)
		(end 371.747288 -231.201468)
		(width 0.1143)
		(layer "In6.Cu")
		(net "GMI_CPU1_G0_CPU0_G2_TX_DN<1>")
	)
	(arc
		(start 102.28834 -222.625412)
		(mid 102.241438 -222.800365)
		(end 102.113334 -222.928434)
		(width 0.1143)
		(layer "In6.Cu")
		(net "GMI_CPU1_G0_CPU0_G2_TX_DN<1>")
	)
	(arc
		(start 373.430292 -239.518444)
		(mid 373.348859 -239.316046)
		(end 373.196866 -239.159542)
		(width 0.1143)
		(layer "In6.Cu")
		(net "GMI_CPU1_G0_CPU0_G2_TX_DN<1>")
	)
	(arc
		(start 371.736366 -228.600254)
		(mid 371.561416 -228.284278)
		(end 371.736366 -227.968302)
		(width 0.1143)
		(layer "In6.Cu")
		(net "GMI_CPU1_G0_CPU0_G2_TX_DN<1>")
	)
	(arc
		(start 368.893598 -222.119444)
		(mid 368.780791 -221.988351)
		(end 368.740182 -221.820232)
		(width 0.1143)
		(layer "In6.Cu")
		(net "GMI_CPU1_G0_CPU0_G2_TX_DN<1>")
	)
	(arc
		(start 370.306092 -224.53854)
		(mid 370.191416 -224.405206)
		(end 370.150136 -224.234248)
		(width 0.1143)
		(layer "In6.Cu")
		(net "GMI_CPU1_G0_CPU0_G2_TX_DN<1>")
	)
	(arc
		(start 371.726968 -230.214424)
		(mid 371.613017 -230.070068)
		(end 371.560344 -229.893876)
		(width 0.1143)
		(layer "In6.Cu")
		(net "GMI_CPU1_G0_CPU0_G2_TX_DN<1>")
	)
	(arc
		(start 99.93376 -226.66579)
		(mid 99.884144 -226.851093)
		(end 99.748594 -226.986846)
		(width 0.1143)
		(layer "In6.Cu")
		(net "GMI_CPU1_G0_CPU0_G2_TX_DN<1>")
	)
	(arc
		(start 371.786912 -229.55885)
		(mid 372.030239 -229.094284)
		(end 371.786912 -228.629718)
		(width 0.1143)
		(layer "In6.Cu")
		(net "GMI_CPU1_G0_CPU0_G2_TX_DN<1>")
	)
	(arc
		(start 371.560344 -229.893876)
		(mid 371.563722 -229.853059)
		(end 371.57152 -229.81285)
		(width 0.1143)
		(layer "In6.Cu")
		(net "GMI_CPU1_G0_CPU0_G2_TX_DN<1>")
	)
	(arc
		(start 372.500144 -236.384084)
		(mid 372.435629 -236.121865)
		(end 372.256812 -235.919518)
		(width 0.1143)
		(layer "In6.Cu")
		(net "GMI_CPU1_G0_CPU0_G2_TX_DN<1>")
	)
	(arc
		(start 371.786912 -234.418632)
		(mid 372.030239 -233.954066)
		(end 371.786912 -233.4895)
		(width 0.1143)
		(layer "In6.Cu")
		(net "GMI_CPU1_G0_CPU0_G2_TX_DN<1>")
	)
	(arc
		(start 99.708462 -230.249984)
		(mid 99.530051 -230.452454)
		(end 99.465892 -230.71455)
		(width 0.1143)
		(layer "In6.Cu")
		(net "GMI_CPU1_G0_CPU0_G2_TX_DN<1>")
	)
	(arc
		(start 99.701096 -232.793286)
		(mid 99.705021 -232.796097)
		(end 99.70897 -232.798874)
		(width 0.1143)
		(layer "In6.Cu")
		(net "GMI_CPU1_G0_CPU0_G2_TX_DN<1>")
	)
	(arc
		(start 99.70897 -227.939092)
		(mid 99.709351 -227.939346)
		(end 99.709732 -227.9396)
		(width 0.1143)
		(layer "In6.Cu")
		(net "GMI_CPU1_G0_CPU0_G2_TX_DN<1>")
	)
	(arc
		(start 99.70897 -233.489754)
		(mid 99.465643 -233.95432)
		(end 99.70897 -234.418886)
		(width 0.1143)
		(layer "In6.Cu")
		(net "GMI_CPU1_G0_CPU0_G2_TX_DN<1>")
	)
	(arc
		(start 99.781614 -229.601522)
		(mid 99.871589 -229.694768)
		(end 99.924362 -229.813104)
		(width 0.1143)
		(layer "In6.Cu")
		(net "GMI_CPU1_G0_CPU0_G2_TX_DN<1>")
	)
	(arc
		(start 373.196866 -238.468662)
		(mid 373.440193 -238.004096)
		(end 373.196866 -237.53953)
		(width 0.1143)
		(layer "In6.Cu")
		(net "GMI_CPU1_G0_CPU0_G2_TX_DN<1>")
	)
	(arc
		(start 371.246146 -226.158552)
		(mid 371.13147 -226.025218)
		(end 371.09019 -225.85426)
		(width 0.1143)
		(layer "In6.Cu")
		(net "GMI_CPU1_G0_CPU0_G2_TX_DN<1>")
	)
	(arc
		(start 373.434102 -239.541304)
		(mid 373.432314 -239.529855)
		(end 373.430292 -239.518444)
		(width 0.1143)
		(layer "In6.Cu")
		(net "GMI_CPU1_G0_CPU0_G2_TX_DN<1>")
	)
	(arc
		(start 99.924362 -229.813104)
		(mid 99.93218 -229.85331)
		(end 99.935538 -229.89413)
		(width 0.1143)
		(layer "In6.Cu")
		(net "GMI_CPU1_G0_CPU0_G2_TX_DN<1>")
	)
	(arc
		(start 99.709732 -231.869234)
		(mid 99.465903 -232.329023)
		(end 99.701096 -232.793286)
		(width 0.1143)
		(layer "In6.Cu")
		(net "GMI_CPU1_G0_CPU0_G2_TX_DN<1>")
	)
	(arc
		(start 99.465638 -235.574332)
		(mid 99.424089 -235.745754)
		(end 99.308666 -235.879132)
		(width 0.1143)
		(layer "In6.Cu")
		(net "GMI_CPU1_G0_CPU0_G2_TX_DN<1>")
	)
	(arc
		(start 370.150136 -224.234248)
		(mid 370.085621 -223.972029)
		(end 369.906804 -223.769682)
		(width 0.1143)
		(layer "In6.Cu")
		(net "GMI_CPU1_G0_CPU0_G2_TX_DN<1>")
	)
	(arc
		(start 371.794786 -232.793032)
		(mid 372.029975 -232.328769)
		(end 371.78615 -231.86898)
		(width 0.1143)
		(layer "In6.Cu")
		(net "GMI_CPU1_G0_CPU0_G2_TX_DN<1>")
	)
	(arc
		(start 98.299016 -237.539784)
		(mid 98.055689 -238.00435)
		(end 98.299016 -238.468916)
		(width 0.1143)
		(layer "In6.Cu")
		(net "GMI_CPU1_G0_CPU0_G2_TX_DN<1>")
	)
	(arc
		(start 372.187216 -235.878878)
		(mid 372.071789 -235.745502)
		(end 372.030244 -235.574078)
		(width 0.1143)
		(layer "In6.Cu")
		(net "GMI_CPU1_G0_CPU0_G2_TX_DN<1>")
	)
	(arc
		(start 369.680236 -223.424242)
		(mid 369.615721 -223.162023)
		(end 369.436904 -222.959676)
		(width 0.1143)
		(layer "In6.Cu")
		(net "GMI_CPU1_G0_CPU0_G2_TX_DN<1>")
	)
	(arc
		(start 102.7557 -221.820486)
		(mid 102.715115 -221.988617)
		(end 102.602284 -222.119698)
		(width 0.1143)
		(layer "In6.Cu")
		(net "GMI_CPU1_G0_CPU0_G2_TX_DN<1>")
	)
	(arc
		(start 373.12727 -239.118902)
		(mid 372.970293 -238.814102)
		(end 373.12727 -238.509302)
		(width 0.1143)
		(layer "In6.Cu")
		(net "GMI_CPU1_G0_CPU0_G2_TX_DN<1>")
	)
	(arc
		(start 101.118924 -224.579942)
		(mid 100.940111 -224.782292)
		(end 100.875592 -225.044508)
		(width 0.1143)
		(layer "In6.Cu")
		(net "GMI_CPU1_G0_CPU0_G2_TX_DN<1>")
	)
	(arc
		(start 101.345746 -224.234502)
		(mid 101.304491 -224.405473)
		(end 101.18979 -224.538794)
		(width 0.1143)
		(layer "In6.Cu")
		(net "GMI_CPU1_G0_CPU0_G2_TX_DN<1>")
	)
	(arc
		(start 100.20808 -226.18319)
		(mid 100.007107 -226.388223)
		(end 99.93376 -226.66579)
		(width 0.1143)
		(layer "In6.Cu")
		(net "GMI_CPU1_G0_CPU0_G2_TX_DN<1>")
	)
	(arc
		(start 98.768916 -236.729778)
		(mid 98.590103 -236.932128)
		(end 98.525584 -237.194344)
		(width 0.1143)
		(layer "In6.Cu")
		(net "GMI_CPU1_G0_CPU0_G2_TX_DN<1>")
	)
	(arc
		(start 373.12727 -237.49889)
		(mid 373.011843 -237.365514)
		(end 372.970298 -237.19409)
		(width 0.1143)
		(layer "In6.Cu")
		(net "GMI_CPU1_G0_CPU0_G2_TX_DN<1>")
	)
	(arc
		(start 371.789198 -231.177338)
		(mid 371.966241 -230.975276)
		(end 372.02999 -230.714296)
		(width 0.1143)
		(layer "In6.Cu")
		(net "GMI_CPU1_G0_CPU0_G2_TX_DN<1>")
	)
	(arc
		(start 101.815646 -223.424496)
		(mid 101.774097 -223.595918)
		(end 101.658674 -223.729296)
		(width 0.1143)
		(layer "In6.Cu")
		(net "GMI_CPU1_G0_CPU0_G2_TX_DN<1>")
	)
	(arc
		(start 371.09019 -225.85426)
		(mid 371.025675 -225.592041)
		(end 370.846858 -225.389694)
		(width 0.1143)
		(layer "In6.Cu")
		(net "GMI_CPU1_G0_CPU0_G2_TX_DN<1>")
	)
	(arc
		(start 371.78615 -227.939346)
		(mid 371.786531 -227.939092)
		(end 371.786912 -227.938838)
		(width 0.1143)
		(layer "In6.Cu")
		(net "GMI_CPU1_G0_CPU0_G2_TX_DN<1>")
	)
	(arc
		(start 98.995738 -236.384338)
		(mid 98.954483 -236.555309)
		(end 98.839782 -236.68863)
		(width 0.1143)
		(layer "In6.Cu")
		(net "GMI_CPU1_G0_CPU0_G2_TX_DN<1>")
	)
	(arc
		(start 98.368612 -238.509556)
		(mid 98.525589 -238.814356)
		(end 98.368612 -239.119156)
		(width 0.1143)
		(layer "In6.Cu")
		(net "GMI_CPU1_G0_CPU0_G2_TX_DN<1>")
	)
	(arc
		(start 99.759516 -227.968556)
		(mid 99.934466 -228.284532)
		(end 99.759516 -228.600508)
		(width 0.1143)
		(layer "In6.Cu")
		(net "GMI_CPU1_G0_CPU0_G2_TX_DN<1>")
	)
	(arc
		(start 100.875592 -225.044508)
		(mid 100.834043 -225.21593)
		(end 100.71862 -225.349308)
		(width 0.1143)
		(layer "In6.Cu")
		(net "GMI_CPU1_G0_CPU0_G2_TX_DN<1>")
	)
	(arc
		(start 99.701096 -227.933504)
		(mid 99.705021 -227.936315)
		(end 99.70897 -227.939092)
		(width 0.1143)
		(layer "In6.Cu")
		(net "GMI_CPU1_G0_CPU0_G2_TX_DN<1>")
	)
	(arc
		(start 371.716046 -235.068364)
		(mid 371.564356 -234.764072)
		(end 371.716046 -234.45978)
		(width 0.1143)
		(layer "In6.Cu")
		(net "GMI_CPU1_G0_CPU0_G2_TX_DN<1>")
	)
	(arc
		(start 99.935538 -229.89413)
		(mid 99.882797 -230.070287)
		(end 99.768914 -230.214678)
		(width 0.1143)
		(layer "In6.Cu")
		(net "GMI_CPU1_G0_CPU0_G2_TX_DN<1>")
	)
	(arc
		(start 99.794568 -232.859834)
		(mid 99.943176 -233.149828)
		(end 99.794568 -233.439716)
		(width 0.1143)
		(layer "In6.Cu")
		(net "GMI_CPU1_G0_CPU0_G2_TX_DN<1>")
	)
	(arc
		(start 99.779836 -234.460034)
		(mid 99.931526 -234.764326)
		(end 99.779836 -235.068618)
		(width 0.1143)
		(layer "In6.Cu")
		(net "GMI_CPU1_G0_CPU0_G2_TX_DN<1>")
	)
	(arc
		(start 98.525584 -237.194344)
		(mid 98.484035 -237.365766)
		(end 98.368612 -237.499144)
		(width 0.1143)
		(layer "In6.Cu")
		(net "GMI_CPU1_G0_CPU0_G2_TX_DN<1>")
	)
	(arc
		(start 99.465892 -230.71455)
		(mid 99.52963 -230.975536)
		(end 99.706684 -231.177592)
		(width 0.1143)
		(layer "In6.Cu")
		(net "GMI_CPU1_G0_CPU0_G2_TX_DN<1>")
	)
	(arc
		(start 371.57152 -229.81285)
		(mid 371.62433 -229.694539)
		(end 371.714268 -229.601268)
		(width 0.1143)
		(layer "In6.Cu")
		(net "GMI_CPU1_G0_CPU0_G2_TX_DN<1>")
	)
	(arc
		(start 98.06559 -239.518698)
		(mid 98.063567 -239.530108)
		(end 98.06178 -239.541558)
		(width 0.1143)
		(layer "In6.Cu")
		(net "GMI_CPU1_G0_CPU0_G2_TX_DN<1>")
	)
	(arc
		(start 371.794786 -227.93325)
		(mid 372.029975 -227.468987)
		(end 371.78615 -227.009198)
		(width 0.1143)
		(layer "In6.Cu")
		(net "GMI_CPU1_G0_CPU0_G2_TX_DN<1>")
	)
	(arc
		(start 371.786912 -232.79862)
		(mid 371.790861 -232.795843)
		(end 371.794786 -232.793032)
		(width 0.1143)
		(layer "In6.Cu")
		(net "GMI_CPU1_G0_CPU0_G2_TX_DN<1>")
	)
	(arc
		(start 99.70897 -235.109766)
		(mid 99.530157 -235.312116)
		(end 99.465638 -235.574332)
		(width 0.1143)
		(layer "In6.Cu")
		(net "GMI_CPU1_G0_CPU0_G2_TX_DN<1>")
	)
	(arc
		(start 98.299016 -239.159796)
		(mid 98.147029 -239.316304)
		(end 98.06559 -239.518698)
		(width 0.1143)
		(layer "In6.Cu")
		(net "GMI_CPU1_G0_CPU0_G2_TX_DN<1>")
	)
	(arc
		(start 371.705378 -233.440732)
		(mid 371.553205 -233.14406)
		(end 371.705378 -232.847388)
		(width 0.1143)
		(layer "In6.Cu")
		(net "GMI_CPU1_G0_CPU0_G2_TX_DN<1>")
	)
	(arc
		(start 369.207542 -222.625158)
		(mid 369.142306 -222.361567)
		(end 368.96167 -222.158814)
		(width 0.1143)
		(layer "In6.Cu")
		(net "GMI_CPU1_G0_CPU0_G2_TX_DN<1>")
	)
	(arc
		(start 99.70897 -228.629972)
		(mid 99.465643 -229.094538)
		(end 99.70897 -229.559104)
		(width 0.1143)
		(layer "In6.Cu")
		(net "GMI_CPU1_G0_CPU0_G2_TX_DN<1>")
	)
	(arc
		(start 100.405692 -225.854514)
		(mid 100.364437 -226.025485)
		(end 100.249736 -226.158806)
		(width 0.1143)
		(layer "In6.Cu")
		(net "GMI_CPU1_G0_CPU0_G2_TX_DN<1>")
	)
	(arc
		(start 99.23907 -235.919772)
		(mid 99.060257 -236.122122)
		(end 98.995738 -236.384338)
		(width 0.1143)
		(layer "In6.Cu")
		(net "GMI_CPU1_G0_CPU0_G2_TX_DN<1>")
	)
	(arc
		(start 372.6561 -236.688376)
		(mid 372.541424 -236.555042)
		(end 372.500144 -236.384084)
		(width 0.1143)
		(layer "In6.Cu")
		(net "GMI_CPU1_G0_CPU0_G2_TX_DN<1>")
	)
	(segment
		(start 108.957872 -242.320318)
		(end 108.49102 -242.05438)
		(width 0.12954)
		(layer "F.Cu")
		(net "GMI_CPU1_G0_CPU0_G2_TX_DN<15>")
	)
	(segment
		(start 362.53801 -242.320064)
		(end 363.004862 -242.054126)
		(width 0.12954)
		(layer "F.Cu")
		(net "GMI_CPU1_G0_CPU0_G2_TX_DN<15>")
	)
	(segment
		(start 356.249478 -224.559876)
		(end 356.250748 -224.560638)
		(width 0.1143)
		(layer "In6.Cu")
		(net "GMI_CPU1_G0_CPU0_G2_TX_DN<15>")
	)
	(segment
		(start 356.250748 -224.560638)
		(end 356.252272 -224.561654)
		(width 0.1143)
		(layer "In6.Cu")
		(net "GMI_CPU1_G0_CPU0_G2_TX_DN<15>")
	)
	(segment
		(start 116.849906 -221.545912)
		(end 116.849906 -221.248732)
		(width 0.1143)
		(layer "In6.Cu")
		(net "GMI_CPU1_G0_CPU0_G2_TX_DN<15>")
	)
	(segment
		(start 354.645976 -221.248478)
		(end 354.645976 -221.545658)
		(width 0.1143)
		(layer "In6.Cu")
		(net "GMI_CPU1_G0_CPU0_G2_TX_DN<15>")
	)
	(segment
		(start 362.70692 -242.054126)
		(end 363.004862 -242.054126)
		(width 0.1143)
		(layer "In6.Cu")
		(net "GMI_CPU1_G0_CPU0_G2_TX_DN<15>")
	)
	(segment
		(start 110.164372 -241.508026)
		(end 110.164626 -241.508026)
		(width 0.1143)
		(layer "In6.Cu")
		(net "GMI_CPU1_G0_CPU0_G2_TX_DN<15>")
	)
	(segment
		(start 124.54382 -214.267542)
		(end 162.95878 -191.120268)
		(width 0.14224)
		(layer "In6.Cu")
		(net "GMI_CPU1_G0_CPU0_G2_TX_DN<15>")
	)
	(segment
		(start 114.781838 -225.367088)
		(end 114.812318 -225.349308)
		(width 0.1143)
		(layer "In6.Cu")
		(net "GMI_CPU1_G0_CPU0_G2_TX_DN<15>")
	)
	(segment
		(start 115.251738 -224.557082)
		(end 115.2525 -224.556574)
		(width 0.1143)
		(layer "In6.Cu")
		(net "GMI_CPU1_G0_CPU0_G2_TX_DN<15>")
	)
	(segment
		(start 362.624116 -241.971322)
		(end 362.70692 -242.054126)
		(width 0.1143)
		(layer "In6.Cu")
		(net "GMI_CPU1_G0_CPU0_G2_TX_DN<15>")
	)
	(segment
		(start 307.873908 -191.04991)
		(end 348.963488 -216.735152)
		(width 0.14224)
		(layer "In6.Cu")
		(net "GMI_CPU1_G0_CPU0_G2_TX_DN<15>")
	)
	(segment
		(start 236.351064 -201.372978)
		(end 240.165128 -200.700386)
		(width 0.14224)
		(layer "In6.Cu")
		(net "GMI_CPU1_G0_CPU0_G2_TX_DN<15>")
	)
	(segment
		(start 354.645976 -221.545658)
		(end 354.646484 -221.546166)
		(width 0.1143)
		(layer "In6.Cu")
		(net "GMI_CPU1_G0_CPU0_G2_TX_DN<15>")
	)
	(segment
		(start 116.849398 -221.804484)
		(end 116.849398 -221.54642)
		(width 0.1143)
		(layer "In6.Cu")
		(net "GMI_CPU1_G0_CPU0_G2_TX_DN<15>")
	)
	(segment
		(start 116.804186 -221.203012)
		(end 116.804186 -221.174564)
		(width 0.1143)
		(layer "In6.Cu")
		(net "GMI_CPU1_G0_CPU0_G2_TX_DN<15>")
	)
	(segment
		(start 115.682776 -223.769936)
		(end 115.721892 -223.747076)
		(width 0.1143)
		(layer "In6.Cu")
		(net "GMI_CPU1_G0_CPU0_G2_TX_DN<15>")
	)
	(segment
		(start 303.734724 -191.04991)
		(end 307.873908 -191.04991)
		(width 0.14224)
		(layer "In6.Cu")
		(net "GMI_CPU1_G0_CPU0_G2_TX_DN<15>")
	)
	(segment
		(start 109.71403 -241.566954)
		(end 109.722412 -241.57178)
		(width 0.1143)
		(layer "In6.Cu")
		(net "GMI_CPU1_G0_CPU0_G2_TX_DN<15>")
	)
	(segment
		(start 115.2525 -224.556574)
		(end 115.25377 -224.555812)
		(width 0.1143)
		(layer "In6.Cu")
		(net "GMI_CPU1_G0_CPU0_G2_TX_DN<15>")
	)
	(segment
		(start 251.681234 -192.63614)
		(end 262.818118 -190.67272)
		(width 0.14224)
		(layer "In6.Cu")
		(net "GMI_CPU1_G0_CPU0_G2_TX_DN<15>")
	)
	(segment
		(start 354.80244 -222.108522)
		(end 354.832158 -222.12554)
		(width 0.1143)
		(layer "In6.Cu")
		(net "GMI_CPU1_G0_CPU0_G2_TX_DN<15>")
	)
	(segment
		(start 356.243382 -224.55632)
		(end 356.244144 -224.556828)
		(width 0.1143)
		(layer "In6.Cu")
		(net "GMI_CPU1_G0_CPU0_G2_TX_DN<15>")
	)
	(segment
		(start 115.212622 -224.579942)
		(end 115.249198 -224.558606)
		(width 0.1143)
		(layer "In6.Cu")
		(net "GMI_CPU1_G0_CPU0_G2_TX_DN<15>")
	)
	(segment
		(start 362.347764 -241.5667)
		(end 362.38688 -241.58956)
		(width 0.1143)
		(layer "In6.Cu")
		(net "GMI_CPU1_G0_CPU0_G2_TX_DN<15>")
	)
	(segment
		(start 356.246684 -224.558352)
		(end 356.249478 -224.559876)
		(width 0.1143)
		(layer "In6.Cu")
		(net "GMI_CPU1_G0_CPU0_G2_TX_DN<15>")
	)
	(segment
		(start 116.662454 -222.126556)
		(end 116.663724 -222.125794)
		(width 0.1143)
		(layer "In6.Cu")
		(net "GMI_CPU1_G0_CPU0_G2_TX_DN<15>")
	)
	(segment
		(start 116.804186 -220.835474)
		(end 119.16283 -218.47683)
		(width 0.14224)
		(layer "In6.Cu")
		(net "GMI_CPU1_G0_CPU0_G2_TX_DN<15>")
	)
	(segment
		(start 116.849398 -221.54642)
		(end 116.849906 -221.545912)
		(width 0.1143)
		(layer "In6.Cu")
		(net "GMI_CPU1_G0_CPU0_G2_TX_DN<15>")
	)
	(segment
		(start 262.818118 -190.67272)
		(end 303.734724 -191.04991)
		(width 0.14224)
		(layer "In6.Cu")
		(net "GMI_CPU1_G0_CPU0_G2_TX_DN<15>")
	)
	(segment
		(start 112.643412 -227.307648)
		(end 112.866424 -226.769422)
		(width 0.1143)
		(layer "In6.Cu")
		(net "GMI_CPU1_G0_CPU0_G2_TX_DN<15>")
	)
	(segment
		(start 355.124512 -222.62084)
		(end 355.124512 -222.626174)
		(width 0.1143)
		(layer "In6.Cu")
		(net "GMI_CPU1_G0_CPU0_G2_TX_DN<15>")
	)
	(segment
		(start 116.663724 -222.125794)
		(end 116.693442 -222.108776)
		(width 0.1143)
		(layer "In6.Cu")
		(net "GMI_CPU1_G0_CPU0_G2_TX_DN<15>")
	)
	(segment
		(start 356.244144 -224.556828)
		(end 356.24516 -224.557336)
		(width 0.1143)
		(layer "In6.Cu")
		(net "GMI_CPU1_G0_CPU0_G2_TX_DN<15>")
	)
	(segment
		(start 162.95878 -191.120268)
		(end 207.112362 -190.933324)
		(width 0.14224)
		(layer "In6.Cu")
		(net "GMI_CPU1_G0_CPU0_G2_TX_DN<15>")
	)
	(segment
		(start 114.311684 -226.177094)
		(end 114.343434 -226.158806)
		(width 0.1143)
		(layer "In6.Cu")
		(net "GMI_CPU1_G0_CPU0_G2_TX_DN<15>")
	)
	(segment
		(start 354.646484 -221.546166)
		(end 354.646484 -221.80423)
		(width 0.1143)
		(layer "In6.Cu")
		(net "GMI_CPU1_G0_CPU0_G2_TX_DN<15>")
	)
	(segment
		(start 115.721892 -223.747076)
		(end 115.752372 -223.729296)
		(width 0.1143)
		(layer "In6.Cu")
		(net "GMI_CPU1_G0_CPU0_G2_TX_DN<15>")
	)
	(segment
		(start 361.407456 -241.5667)
		(end 361.40771 -241.5667)
		(width 0.1143)
		(layer "In6.Cu")
		(net "GMI_CPU1_G0_CPU0_G2_TX_DN<15>")
	)
	(segment
		(start 116.652802 -222.132144)
		(end 116.661692 -222.127064)
		(width 0.1143)
		(layer "In6.Cu")
		(net "GMI_CPU1_G0_CPU0_G2_TX_DN<15>")
	)
	(segment
		(start 356.212394 -224.53854)
		(end 356.242112 -224.555558)
		(width 0.1143)
		(layer "In6.Cu")
		(net "GMI_CPU1_G0_CPU0_G2_TX_DN<15>")
	)
	(segment
		(start 356.683564 -225.349054)
		(end 356.75316 -225.389694)
		(width 0.1143)
		(layer "In6.Cu")
		(net "GMI_CPU1_G0_CPU0_G2_TX_DN<15>")
	)
	(segment
		(start 357.152448 -226.158552)
		(end 357.184198 -226.17684)
		(width 0.1143)
		(layer "In6.Cu")
		(net "GMI_CPU1_G0_CPU0_G2_TX_DN<15>")
	)
	(segment
		(start 115.250722 -224.55759)
		(end 115.251738 -224.557082)
		(width 0.1143)
		(layer "In6.Cu")
		(net "GMI_CPU1_G0_CPU0_G2_TX_DN<15>")
	)
	(segment
		(start 358.914446 -227.890324)
		(end 358.914446 -236.812074)
		(width 0.1143)
		(layer "In6.Cu")
		(net "GMI_CPU1_G0_CPU0_G2_TX_DN<15>")
	)
	(segment
		(start 119.16283 -218.47683)
		(end 124.54382 -214.267542)
		(width 0.14224)
		(layer "In6.Cu")
		(net "GMI_CPU1_G0_CPU0_G2_TX_DN<15>")
	)
	(segment
		(start 356.252272 -224.561654)
		(end 356.28326 -224.579688)
		(width 0.1143)
		(layer "In6.Cu")
		(net "GMI_CPU1_G0_CPU0_G2_TX_DN<15>")
	)
	(segment
		(start 360.526076 -240.702338)
		(end 361.331256 -241.507772)
		(width 0.1143)
		(layer "In6.Cu")
		(net "GMI_CPU1_G0_CPU0_G2_TX_DN<15>")
	)
	(segment
		(start 355.74351 -223.729042)
		(end 355.813106 -223.769682)
		(width 0.1143)
		(layer "In6.Cu")
		(net "GMI_CPU1_G0_CPU0_G2_TX_DN<15>")
	)
	(segment
		(start 209.814922 -191.410082)
		(end 232.027222 -200.61047)
		(width 0.14224)
		(layer "In6.Cu")
		(net "GMI_CPU1_G0_CPU0_G2_TX_DN<15>")
	)
	(segment
		(start 354.691696 -221.17431)
		(end 354.691696 -221.202758)
		(width 0.1143)
		(layer "In6.Cu")
		(net "GMI_CPU1_G0_CPU0_G2_TX_DN<15>")
	)
	(segment
		(start 110.164626 -241.508026)
		(end 111.263684 -240.408714)
		(width 0.1143)
		(layer "In6.Cu")
		(net "GMI_CPU1_G0_CPU0_G2_TX_DN<15>")
	)
	(segment
		(start 116.849906 -221.248732)
		(end 116.804186 -221.203012)
		(width 0.1143)
		(layer "In6.Cu")
		(net "GMI_CPU1_G0_CPU0_G2_TX_DN<15>")
	)
	(segment
		(start 356.242112 -224.555558)
		(end 356.243382 -224.55632)
		(width 0.1143)
		(layer "In6.Cu")
		(net "GMI_CPU1_G0_CPU0_G2_TX_DN<15>")
	)
	(segment
		(start 110.088172 -241.566954)
		(end 110.088426 -241.566954)
		(width 0.1143)
		(layer "In6.Cu")
		(net "GMI_CPU1_G0_CPU0_G2_TX_DN<15>")
	)
	(segment
		(start 240.165128 -200.700386)
		(end 251.681234 -192.63614)
		(width 0.14224)
		(layer "In6.Cu")
		(net "GMI_CPU1_G0_CPU0_G2_TX_DN<15>")
	)
	(segment
		(start 116.152676 -222.95993)
		(end 116.191792 -222.93707)
		(width 0.1143)
		(layer "In6.Cu")
		(net "GMI_CPU1_G0_CPU0_G2_TX_DN<15>")
	)
	(segment
		(start 116.661692 -222.127064)
		(end 116.662454 -222.126556)
		(width 0.1143)
		(layer "In6.Cu")
		(net "GMI_CPU1_G0_CPU0_G2_TX_DN<15>")
	)
	(segment
		(start 356.24516 -224.557336)
		(end 356.246684 -224.558352)
		(width 0.1143)
		(layer "In6.Cu")
		(net "GMI_CPU1_G0_CPU0_G2_TX_DN<15>")
	)
	(segment
		(start 361.331256 -241.507772)
		(end 361.33151 -241.507772)
		(width 0.1143)
		(layer "In6.Cu")
		(net "GMI_CPU1_G0_CPU0_G2_TX_DN<15>")
	)
	(segment
		(start 116.804186 -221.174564)
		(end 116.804186 -220.835474)
		(width 0.14224)
		(layer "In6.Cu")
		(net "GMI_CPU1_G0_CPU0_G2_TX_DN<15>")
	)
	(segment
		(start 361.77347 -241.571526)
		(end 361.781852 -241.5667)
		(width 0.1143)
		(layer "In6.Cu")
		(net "GMI_CPU1_G0_CPU0_G2_TX_DN<15>")
	)
	(segment
		(start 232.027222 -200.61047)
		(end 236.351064 -201.372978)
		(width 0.14224)
		(layer "In6.Cu")
		(net "GMI_CPU1_G0_CPU0_G2_TX_DN<15>")
	)
	(segment
		(start 348.963488 -216.735152)
		(end 354.447348 -220.611954)
		(width 0.14224)
		(layer "In6.Cu")
		(net "GMI_CPU1_G0_CPU0_G2_TX_DN<15>")
	)
	(segment
		(start 355.30409 -222.936816)
		(end 355.343206 -222.959676)
		(width 0.1143)
		(layer "In6.Cu")
		(net "GMI_CPU1_G0_CPU0_G2_TX_DN<15>")
	)
	(segment
		(start 354.83419 -222.12681)
		(end 354.84308 -222.13189)
		(width 0.1143)
		(layer "In6.Cu")
		(net "GMI_CPU1_G0_CPU0_G2_TX_DN<15>")
	)
	(segment
		(start 109.109002 -241.589814)
		(end 109.148118 -241.566954)
		(width 0.1143)
		(layer "In6.Cu")
		(net "GMI_CPU1_G0_CPU0_G2_TX_DN<15>")
	)
	(segment
		(start 114.742722 -225.389948)
		(end 114.781838 -225.367088)
		(width 0.1143)
		(layer "In6.Cu")
		(net "GMI_CPU1_G0_CPU0_G2_TX_DN<15>")
	)
	(segment
		(start 358.239568 -226.265994)
		(end 358.24287 -226.269042)
		(width 0.1143)
		(layer "In6.Cu")
		(net "GMI_CPU1_G0_CPU0_G2_TX_DN<15>")
	)
	(segment
		(start 108.49102 -242.05438)
		(end 108.788962 -242.05438)
		(width 0.1143)
		(layer "In6.Cu")
		(net "GMI_CPU1_G0_CPU0_G2_TX_DN<15>")
	)
	(segment
		(start 354.691696 -220.856302)
		(end 354.691696 -221.17431)
		(width 0.14224)
		(layer "In6.Cu")
		(net "GMI_CPU1_G0_CPU0_G2_TX_DN<15>")
	)
	(segment
		(start 354.691696 -221.202758)
		(end 354.645976 -221.248478)
		(width 0.1143)
		(layer "In6.Cu")
		(net "GMI_CPU1_G0_CPU0_G2_TX_DN<15>")
	)
	(segment
		(start 115.25377 -224.555812)
		(end 115.283488 -224.538794)
		(width 0.1143)
		(layer "In6.Cu")
		(net "GMI_CPU1_G0_CPU0_G2_TX_DN<15>")
	)
	(segment
		(start 207.112362 -190.933324)
		(end 209.814922 -191.410082)
		(width 0.14224)
		(layer "In6.Cu")
		(net "GMI_CPU1_G0_CPU0_G2_TX_DN<15>")
	)
	(segment
		(start 115.249198 -224.558606)
		(end 115.250722 -224.55759)
		(width 0.1143)
		(layer "In6.Cu")
		(net "GMI_CPU1_G0_CPU0_G2_TX_DN<15>")
	)
	(segment
		(start 116.37137 -222.626428)
		(end 116.37137 -222.621094)
		(width 0.1143)
		(layer "In6.Cu")
		(net "GMI_CPU1_G0_CPU0_G2_TX_DN<15>")
	)
	(segment
		(start 108.788962 -242.05438)
		(end 108.871766 -241.971576)
		(width 0.1143)
		(layer "In6.Cu")
		(net "GMI_CPU1_G0_CPU0_G2_TX_DN<15>")
	)
	(segment
		(start 354.447348 -220.611954)
		(end 354.691696 -220.856302)
		(width 0.14224)
		(layer "In6.Cu")
		(net "GMI_CPU1_G0_CPU0_G2_TX_DN<15>")
	)
	(segment
		(start 354.832158 -222.12554)
		(end 354.833428 -222.126302)
		(width 0.1143)
		(layer "In6.Cu")
		(net "GMI_CPU1_G0_CPU0_G2_TX_DN<15>")
	)
	(segment
		(start 112.606582 -237.06074)
		(end 112.606582 -227.491798)
		(width 0.1143)
		(layer "In6.Cu")
		(net "GMI_CPU1_G0_CPU0_G2_TX_DN<15>")
	)
	(segment
		(start 354.833428 -222.126302)
		(end 354.83419 -222.12681)
		(width 0.1143)
		(layer "In6.Cu")
		(net "GMI_CPU1_G0_CPU0_G2_TX_DN<15>")
	)
	(arc
		(start 112.866424 -226.769422)
		(mid 112.875345 -226.746797)
		(end 112.883696 -226.723956)
		(width 0.1143)
		(layer "In6.Cu")
		(net "GMI_CPU1_G0_CPU0_G2_TX_DN<15>")
	)
	(arc
		(start 115.439444 -224.234502)
		(mid 115.503959 -223.972283)
		(end 115.682776 -223.769936)
		(width 0.1143)
		(layer "In6.Cu")
		(net "GMI_CPU1_G0_CPU0_G2_TX_DN<15>")
	)
	(arc
		(start 115.909344 -223.424496)
		(mid 115.973859 -223.162277)
		(end 116.152676 -222.95993)
		(width 0.1143)
		(layer "In6.Cu")
		(net "GMI_CPU1_G0_CPU0_G2_TX_DN<15>")
	)
	(arc
		(start 116.37137 -222.621094)
		(mid 116.446757 -222.339021)
		(end 116.652802 -222.132144)
		(width 0.1143)
		(layer "In6.Cu")
		(net "GMI_CPU1_G0_CPU0_G2_TX_DN<15>")
	)
	(arc
		(start 358.914446 -236.812074)
		(mid 359.333336 -238.917504)
		(end 360.526076 -240.702338)
		(width 0.1143)
		(layer "In6.Cu")
		(net "GMI_CPU1_G0_CPU0_G2_TX_DN<15>")
	)
	(arc
		(start 354.646484 -221.80423)
		(mid 354.687739 -221.975201)
		(end 354.80244 -222.108522)
		(width 0.1143)
		(layer "In6.Cu")
		(net "GMI_CPU1_G0_CPU0_G2_TX_DN<15>")
	)
	(arc
		(start 357.184198 -226.17684)
		(mid 357.371142 -226.227095)
		(end 357.558086 -226.17684)
		(width 0.1143)
		(layer "In6.Cu")
		(net "GMI_CPU1_G0_CPU0_G2_TX_DN<15>")
	)
	(arc
		(start 110.088426 -241.566954)
		(mid 110.128303 -241.539944)
		(end 110.164372 -241.508026)
		(width 0.1143)
		(layer "In6.Cu")
		(net "GMI_CPU1_G0_CPU0_G2_TX_DN<15>")
	)
	(arc
		(start 358.24287 -226.269042)
		(mid 358.739973 -227.012865)
		(end 358.914446 -227.890324)
		(width 0.1143)
		(layer "In6.Cu")
		(net "GMI_CPU1_G0_CPU0_G2_TX_DN<15>")
	)
	(arc
		(start 114.96929 -225.044508)
		(mid 115.033805 -224.782289)
		(end 115.212622 -224.579942)
		(width 0.1143)
		(layer "In6.Cu")
		(net "GMI_CPU1_G0_CPU0_G2_TX_DN<15>")
	)
	(arc
		(start 357.558086 -226.17684)
		(mid 357.841042 -226.100663)
		(end 358.123998 -226.17684)
		(width 0.1143)
		(layer "In6.Cu")
		(net "GMI_CPU1_G0_CPU0_G2_TX_DN<15>")
	)
	(arc
		(start 115.283488 -224.538794)
		(mid 115.398164 -224.40546)
		(end 115.439444 -224.234502)
		(width 0.1143)
		(layer "In6.Cu")
		(net "GMI_CPU1_G0_CPU0_G2_TX_DN<15>")
	)
	(arc
		(start 362.620306 -241.948462)
		(mid 362.622329 -241.959872)
		(end 362.624116 -241.971322)
		(width 0.1143)
		(layer "In6.Cu")
		(net "GMI_CPU1_G0_CPU0_G2_TX_DN<15>")
	)
	(arc
		(start 355.343206 -222.959676)
		(mid 355.522019 -223.162026)
		(end 355.586538 -223.424242)
		(width 0.1143)
		(layer "In6.Cu")
		(net "GMI_CPU1_G0_CPU0_G2_TX_DN<15>")
	)
	(arc
		(start 109.722412 -241.57178)
		(mid 109.90592 -241.617274)
		(end 110.088172 -241.566954)
		(width 0.1143)
		(layer "In6.Cu")
		(net "GMI_CPU1_G0_CPU0_G2_TX_DN<15>")
	)
	(arc
		(start 356.526592 -225.044254)
		(mid 356.568141 -225.215676)
		(end 356.683564 -225.349054)
		(width 0.1143)
		(layer "In6.Cu")
		(net "GMI_CPU1_G0_CPU0_G2_TX_DN<15>")
	)
	(arc
		(start 358.123998 -226.17684)
		(mid 358.184694 -226.217646)
		(end 358.239568 -226.265994)
		(width 0.1143)
		(layer "In6.Cu")
		(net "GMI_CPU1_G0_CPU0_G2_TX_DN<15>")
	)
	(arc
		(start 356.056438 -224.234248)
		(mid 356.097693 -224.405219)
		(end 356.212394 -224.53854)
		(width 0.1143)
		(layer "In6.Cu")
		(net "GMI_CPU1_G0_CPU0_G2_TX_DN<15>")
	)
	(arc
		(start 112.883696 -226.723956)
		(mid 113.074314 -226.402779)
		(end 113.371884 -226.177094)
		(width 0.1143)
		(layer "In6.Cu")
		(net "GMI_CPU1_G0_CPU0_G2_TX_DN<15>")
	)
	(arc
		(start 356.28326 -224.579688)
		(mid 356.462073 -224.782038)
		(end 356.526592 -225.044254)
		(width 0.1143)
		(layer "In6.Cu")
		(net "GMI_CPU1_G0_CPU0_G2_TX_DN<15>")
	)
	(arc
		(start 108.871766 -241.971576)
		(mid 108.873554 -241.960127)
		(end 108.875576 -241.948716)
		(width 0.1143)
		(layer "In6.Cu")
		(net "GMI_CPU1_G0_CPU0_G2_TX_DN<15>")
	)
	(arc
		(start 114.49939 -225.854514)
		(mid 114.563905 -225.592295)
		(end 114.742722 -225.389948)
		(width 0.1143)
		(layer "In6.Cu")
		(net "GMI_CPU1_G0_CPU0_G2_TX_DN<15>")
	)
	(arc
		(start 111.263684 -240.408714)
		(mid 112.170965 -239.114658)
		(end 112.582706 -237.588806)
		(width 0.1143)
		(layer "In6.Cu")
		(net "GMI_CPU1_G0_CPU0_G2_TX_DN<15>")
	)
	(arc
		(start 362.38688 -241.58956)
		(mid 362.538867 -241.746068)
		(end 362.620306 -241.948462)
		(width 0.1143)
		(layer "In6.Cu")
		(net "GMI_CPU1_G0_CPU0_G2_TX_DN<15>")
	)
	(arc
		(start 355.124512 -222.626174)
		(mid 355.172643 -222.805571)
		(end 355.30409 -222.936816)
		(width 0.1143)
		(layer "In6.Cu")
		(net "GMI_CPU1_G0_CPU0_G2_TX_DN<15>")
	)
	(arc
		(start 354.84308 -222.13189)
		(mid 355.049148 -222.338753)
		(end 355.124512 -222.62084)
		(width 0.1143)
		(layer "In6.Cu")
		(net "GMI_CPU1_G0_CPU0_G2_TX_DN<15>")
	)
	(arc
		(start 108.875576 -241.948716)
		(mid 108.957009 -241.746318)
		(end 109.109002 -241.589814)
		(width 0.1143)
		(layer "In6.Cu")
		(net "GMI_CPU1_G0_CPU0_G2_TX_DN<15>")
	)
	(arc
		(start 112.582706 -237.588806)
		(mid 112.600674 -237.325046)
		(end 112.606582 -237.06074)
		(width 0.1143)
		(layer "In6.Cu")
		(net "GMI_CPU1_G0_CPU0_G2_TX_DN<15>")
	)
	(arc
		(start 113.371884 -226.177094)
		(mid 113.65484 -226.100917)
		(end 113.937796 -226.177094)
		(width 0.1143)
		(layer "In6.Cu")
		(net "GMI_CPU1_G0_CPU0_G2_TX_DN<15>")
	)
	(arc
		(start 355.813106 -223.769682)
		(mid 355.991919 -223.972032)
		(end 356.056438 -224.234248)
		(width 0.1143)
		(layer "In6.Cu")
		(net "GMI_CPU1_G0_CPU0_G2_TX_DN<15>")
	)
	(arc
		(start 361.781852 -241.5667)
		(mid 362.064808 -241.490523)
		(end 362.347764 -241.5667)
		(width 0.1143)
		(layer "In6.Cu")
		(net "GMI_CPU1_G0_CPU0_G2_TX_DN<15>")
	)
	(arc
		(start 356.75316 -225.389694)
		(mid 356.931973 -225.592044)
		(end 356.996492 -225.85426)
		(width 0.1143)
		(layer "In6.Cu")
		(net "GMI_CPU1_G0_CPU0_G2_TX_DN<15>")
	)
	(arc
		(start 361.40771 -241.5667)
		(mid 361.589961 -241.61705)
		(end 361.77347 -241.571526)
		(width 0.1143)
		(layer "In6.Cu")
		(net "GMI_CPU1_G0_CPU0_G2_TX_DN<15>")
	)
	(arc
		(start 114.343434 -226.158806)
		(mid 114.45811 -226.025472)
		(end 114.49939 -225.854514)
		(width 0.1143)
		(layer "In6.Cu")
		(net "GMI_CPU1_G0_CPU0_G2_TX_DN<15>")
	)
	(arc
		(start 115.752372 -223.729296)
		(mid 115.867799 -223.59592)
		(end 115.909344 -223.424496)
		(width 0.1143)
		(layer "In6.Cu")
		(net "GMI_CPU1_G0_CPU0_G2_TX_DN<15>")
	)
	(arc
		(start 116.191792 -222.93707)
		(mid 116.323272 -222.805844)
		(end 116.37137 -222.626428)
		(width 0.1143)
		(layer "In6.Cu")
		(net "GMI_CPU1_G0_CPU0_G2_TX_DN<15>")
	)
	(arc
		(start 356.996492 -225.85426)
		(mid 357.037747 -226.025231)
		(end 357.152448 -226.158552)
		(width 0.1143)
		(layer "In6.Cu")
		(net "GMI_CPU1_G0_CPU0_G2_TX_DN<15>")
	)
	(arc
		(start 116.693442 -222.108776)
		(mid 116.808118 -221.975442)
		(end 116.849398 -221.804484)
		(width 0.1143)
		(layer "In6.Cu")
		(net "GMI_CPU1_G0_CPU0_G2_TX_DN<15>")
	)
	(arc
		(start 114.812318 -225.349308)
		(mid 114.927745 -225.215932)
		(end 114.96929 -225.044508)
		(width 0.1143)
		(layer "In6.Cu")
		(net "GMI_CPU1_G0_CPU0_G2_TX_DN<15>")
	)
	(arc
		(start 112.606582 -227.491798)
		(mid 112.615924 -227.397907)
		(end 112.643412 -227.307648)
		(width 0.1143)
		(layer "In6.Cu")
		(net "GMI_CPU1_G0_CPU0_G2_TX_DN<15>")
	)
	(arc
		(start 355.586538 -223.424242)
		(mid 355.628087 -223.595664)
		(end 355.74351 -223.729042)
		(width 0.1143)
		(layer "In6.Cu")
		(net "GMI_CPU1_G0_CPU0_G2_TX_DN<15>")
	)
	(arc
		(start 109.148118 -241.566954)
		(mid 109.431074 -241.490777)
		(end 109.71403 -241.566954)
		(width 0.1143)
		(layer "In6.Cu")
		(net "GMI_CPU1_G0_CPU0_G2_TX_DN<15>")
	)
	(arc
		(start 113.937796 -226.177094)
		(mid 114.12474 -226.227349)
		(end 114.311684 -226.177094)
		(width 0.1143)
		(layer "In6.Cu")
		(net "GMI_CPU1_G0_CPU0_G2_TX_DN<15>")
	)
	(arc
		(start 361.33151 -241.507772)
		(mid 361.367573 -241.539698)
		(end 361.407456 -241.5667)
		(width 0.1143)
		(layer "In6.Cu")
		(net "GMI_CPU1_G0_CPU0_G2_TX_DN<15>")
	)
	(segment
		(start 362.53801 -240.700052)
		(end 363.004862 -240.434114)
		(width 0.12954)
		(layer "F.Cu")
		(net "GMI_CPU1_G0_CPU0_G2_TX_DN<14>")
	)
	(segment
		(start 108.957872 -240.700306)
		(end 108.49102 -240.434368)
		(width 0.12954)
		(layer "F.Cu")
		(net "GMI_CPU1_G0_CPU0_G2_TX_DN<14>")
	)
	(segment
		(start 357.653082 -225.366326)
		(end 357.653336 -225.366326)
		(width 0.1143)
		(layer "In6.Cu")
		(net "GMI_CPU1_G0_CPU0_G2_TX_DN<14>")
	)
	(segment
		(start 239.782858 -199.820784)
		(end 251.312934 -191.746886)
		(width 0.14224)
		(layer "In6.Cu")
		(net "GMI_CPU1_G0_CPU0_G2_TX_DN<14>")
	)
	(segment
		(start 113.833402 -225.371914)
		(end 113.841784 -225.367088)
		(width 0.1143)
		(layer "In6.Cu")
		(net "GMI_CPU1_G0_CPU0_G2_TX_DN<14>")
	)
	(segment
		(start 114.742722 -223.769936)
		(end 114.781838 -223.747076)
		(width 0.1143)
		(layer "In6.Cu")
		(net "GMI_CPU1_G0_CPU0_G2_TX_DN<14>")
	)
	(segment
		(start 360.789728 -239.344962)
		(end 360.929936 -239.48517)
		(width 0.1143)
		(layer "In6.Cu")
		(net "GMI_CPU1_G0_CPU0_G2_TX_DN<14>")
	)
	(segment
		(start 356.239826 -222.934276)
		(end 356.240588 -222.934784)
		(width 0.1143)
		(layer "In6.Cu")
		(net "GMI_CPU1_G0_CPU0_G2_TX_DN<14>")
	)
	(segment
		(start 351.292414 -217.021664)
		(end 353.245166 -218.4019)
		(width 0.14224)
		(layer "In6.Cu")
		(net "GMI_CPU1_G0_CPU0_G2_TX_DN<14>")
	)
	(segment
		(start 358.620822 -225.383344)
		(end 358.620822 -225.383598)
		(width 0.1143)
		(layer "In6.Cu")
		(net "GMI_CPU1_G0_CPU0_G2_TX_DN<14>")
	)
	(segment
		(start 356.212394 -222.918528)
		(end 356.239826 -222.934276)
		(width 0.1143)
		(layer "In6.Cu")
		(net "GMI_CPU1_G0_CPU0_G2_TX_DN<14>")
	)
	(segment
		(start 355.586792 -221.248478)
		(end 355.586792 -221.624652)
		(width 0.1143)
		(layer "In6.Cu")
		(net "GMI_CPU1_G0_CPU0_G2_TX_DN<14>")
	)
	(segment
		(start 108.49102 -240.434368)
		(end 108.788962 -240.434368)
		(width 0.1143)
		(layer "In6.Cu")
		(net "GMI_CPU1_G0_CPU0_G2_TX_DN<14>")
	)
	(segment
		(start 115.250722 -222.937578)
		(end 115.251738 -222.93707)
		(width 0.1143)
		(layer "In6.Cu")
		(net "GMI_CPU1_G0_CPU0_G2_TX_DN<14>")
	)
	(segment
		(start 358.709722 -225.455734)
		(end 358.719882 -225.465894)
		(width 0.1143)
		(layer "In6.Cu")
		(net "GMI_CPU1_G0_CPU0_G2_TX_DN<14>")
	)
	(segment
		(start 114.781838 -223.747076)
		(end 114.812318 -223.729296)
		(width 0.1143)
		(layer "In6.Cu")
		(net "GMI_CPU1_G0_CPU0_G2_TX_DN<14>")
	)
	(segment
		(start 115.721892 -222.127064)
		(end 115.752372 -222.109284)
		(width 0.1143)
		(layer "In6.Cu")
		(net "GMI_CPU1_G0_CPU0_G2_TX_DN<14>")
	)
	(segment
		(start 113.841784 -225.367088)
		(end 113.842546 -225.36658)
		(width 0.1143)
		(layer "In6.Cu")
		(net "GMI_CPU1_G0_CPU0_G2_TX_DN<14>")
	)
	(segment
		(start 109.109002 -239.969802)
		(end 109.148118 -239.946942)
		(width 0.1143)
		(layer "In6.Cu")
		(net "GMI_CPU1_G0_CPU0_G2_TX_DN<14>")
	)
	(segment
		(start 236.371892 -200.422256)
		(end 239.782858 -199.820784)
		(width 0.14224)
		(layer "In6.Cu")
		(net "GMI_CPU1_G0_CPU0_G2_TX_DN<14>")
	)
	(segment
		(start 361.77347 -239.951514)
		(end 361.781852 -239.946688)
		(width 0.1143)
		(layer "In6.Cu")
		(net "GMI_CPU1_G0_CPU0_G2_TX_DN<14>")
	)
	(segment
		(start 115.909344 -221.804484)
		(end 115.909344 -221.62516)
		(width 0.1143)
		(layer "In6.Cu")
		(net "GMI_CPU1_G0_CPU0_G2_TX_DN<14>")
	)
	(segment
		(start 355.74351 -222.10903)
		(end 355.813106 -222.14967)
		(width 0.1143)
		(layer "In6.Cu")
		(net "GMI_CPU1_G0_CPU0_G2_TX_DN<14>")
	)
	(segment
		(start 111.722662 -237.682786)
		(end 111.783876 -237.324138)
		(width 0.1143)
		(layer "In6.Cu")
		(net "GMI_CPU1_G0_CPU0_G2_TX_DN<14>")
	)
	(segment
		(start 118.599712 -217.719148)
		(end 123.98121 -213.509352)
		(width 0.14224)
		(layer "In6.Cu")
		(net "GMI_CPU1_G0_CPU0_G2_TX_DN<14>")
	)
	(segment
		(start 115.86337 -221.174564)
		(end 115.86337 -220.45549)
		(width 0.14224)
		(layer "In6.Cu")
		(net "GMI_CPU1_G0_CPU0_G2_TX_DN<14>")
	)
	(segment
		(start 115.86337 -220.45549)
		(end 118.599712 -217.719148)
		(width 0.14224)
		(layer "In6.Cu")
		(net "GMI_CPU1_G0_CPU0_G2_TX_DN<14>")
	)
	(segment
		(start 113.842546 -225.36658)
		(end 113.8428 -225.36658)
		(width 0.1143)
		(layer "In6.Cu")
		(net "GMI_CPU1_G0_CPU0_G2_TX_DN<14>")
	)
	(segment
		(start 362.70692 -240.434114)
		(end 363.004862 -240.434114)
		(width 0.1143)
		(layer "In6.Cu")
		(net "GMI_CPU1_G0_CPU0_G2_TX_DN<14>")
	)
	(segment
		(start 115.248182 -222.939102)
		(end 115.249198 -222.938594)
		(width 0.1143)
		(layer "In6.Cu")
		(net "GMI_CPU1_G0_CPU0_G2_TX_DN<14>")
	)
	(segment
		(start 353.245166 -218.4019)
		(end 354.819966 -219.654628)
		(width 0.14224)
		(layer "In6.Cu")
		(net "GMI_CPU1_G0_CPU0_G2_TX_DN<14>")
	)
	(segment
		(start 115.90909 -221.248732)
		(end 115.86337 -221.203012)
		(width 0.1143)
		(layer "In6.Cu")
		(net "GMI_CPU1_G0_CPU0_G2_TX_DN<14>")
	)
	(segment
		(start 111.793528 -237.210092)
		(end 111.793528 -227.657152)
		(width 0.1143)
		(layer "In6.Cu")
		(net "GMI_CPU1_G0_CPU0_G2_TX_DN<14>")
	)
	(segment
		(start 356.24516 -222.937324)
		(end 356.246684 -222.93834)
		(width 0.1143)
		(layer "In6.Cu")
		(net "GMI_CPU1_G0_CPU0_G2_TX_DN<14>")
	)
	(segment
		(start 360.929936 -239.48517)
		(end 361.350052 -239.90554)
		(width 0.1143)
		(layer "In6.Cu")
		(net "GMI_CPU1_G0_CPU0_G2_TX_DN<14>")
	)
	(segment
		(start 207.15224 -189.986158)
		(end 210.660996 -190.605156)
		(width 0.14224)
		(layer "In6.Cu")
		(net "GMI_CPU1_G0_CPU0_G2_TX_DN<14>")
	)
	(segment
		(start 114.30889 -224.558606)
		(end 114.311684 -224.557082)
		(width 0.1143)
		(layer "In6.Cu")
		(net "GMI_CPU1_G0_CPU0_G2_TX_DN<14>")
	)
	(segment
		(start 356.683564 -223.729042)
		(end 356.75316 -223.769682)
		(width 0.1143)
		(layer "In6.Cu")
		(net "GMI_CPU1_G0_CPU0_G2_TX_DN<14>")
	)
	(segment
		(start 251.312934 -191.746886)
		(end 262.742426 -189.73165)
		(width 0.14224)
		(layer "In6.Cu")
		(net "GMI_CPU1_G0_CPU0_G2_TX_DN<14>")
	)
	(segment
		(start 109.71403 -239.946942)
		(end 109.722412 -239.951768)
		(width 0.1143)
		(layer "In6.Cu")
		(net "GMI_CPU1_G0_CPU0_G2_TX_DN<14>")
	)
	(segment
		(start 303.734724 -190.109856)
		(end 308.240684 -190.109856)
		(width 0.14224)
		(layer "In6.Cu")
		(net "GMI_CPU1_G0_CPU0_G2_TX_DN<14>")
	)
	(segment
		(start 356.2477 -222.938848)
		(end 356.28326 -222.959676)
		(width 0.1143)
		(layer "In6.Cu")
		(net "GMI_CPU1_G0_CPU0_G2_TX_DN<14>")
	)
	(segment
		(start 358.583484 -225.360738)
		(end 358.593898 -225.366834)
		(width 0.1143)
		(layer "In6.Cu")
		(net "GMI_CPU1_G0_CPU0_G2_TX_DN<14>")
	)
	(segment
		(start 308.240684 -190.109856)
		(end 351.292414 -217.021664)
		(width 0.14224)
		(layer "In6.Cu")
		(net "GMI_CPU1_G0_CPU0_G2_TX_DN<14>")
	)
	(segment
		(start 115.909344 -221.62516)
		(end 115.90909 -221.624906)
		(width 0.1143)
		(layer "In6.Cu")
		(net "GMI_CPU1_G0_CPU0_G2_TX_DN<14>")
	)
	(segment
		(start 115.86337 -221.203012)
		(end 115.86337 -221.174564)
		(width 0.1143)
		(layer "In6.Cu")
		(net "GMI_CPU1_G0_CPU0_G2_TX_DN<14>")
	)
	(segment
		(start 115.682776 -222.149924)
		(end 115.721892 -222.127064)
		(width 0.1143)
		(layer "In6.Cu")
		(net "GMI_CPU1_G0_CPU0_G2_TX_DN<14>")
	)
	(segment
		(start 262.742426 -189.73165)
		(end 303.734724 -190.109856)
		(width 0.14224)
		(layer "In6.Cu")
		(net "GMI_CPU1_G0_CPU0_G2_TX_DN<14>")
	)
	(segment
		(start 210.660996 -190.605156)
		(end 230.531416 -198.835772)
		(width 0.14224)
		(layer "In6.Cu")
		(net "GMI_CPU1_G0_CPU0_G2_TX_DN<14>")
	)
	(segment
		(start 357.653336 -225.366326)
		(end 357.654098 -225.366834)
		(width 0.1143)
		(layer "In6.Cu")
		(net "GMI_CPU1_G0_CPU0_G2_TX_DN<14>")
	)
	(segment
		(start 115.90909 -221.624906)
		(end 115.90909 -221.248732)
		(width 0.1143)
		(layer "In6.Cu")
		(net "GMI_CPU1_G0_CPU0_G2_TX_DN<14>")
	)
	(segment
		(start 356.243382 -222.936308)
		(end 356.244144 -222.936816)
		(width 0.1143)
		(layer "In6.Cu")
		(net "GMI_CPU1_G0_CPU0_G2_TX_DN<14>")
	)
	(segment
		(start 112.901984 -225.367088)
		(end 112.912398 -225.360992)
		(width 0.1143)
		(layer "In6.Cu")
		(net "GMI_CPU1_G0_CPU0_G2_TX_DN<14>")
	)
	(segment
		(start 115.25377 -222.9358)
		(end 115.283488 -222.918782)
		(width 0.1143)
		(layer "In6.Cu")
		(net "GMI_CPU1_G0_CPU0_G2_TX_DN<14>")
	)
	(segment
		(start 123.98121 -213.509352)
		(end 162.70732 -190.17488)
		(width 0.14224)
		(layer "In6.Cu")
		(net "GMI_CPU1_G0_CPU0_G2_TX_DN<14>")
	)
	(segment
		(start 114.311684 -224.557082)
		(end 114.343434 -224.538794)
		(width 0.1143)
		(layer "In6.Cu")
		(net "GMI_CPU1_G0_CPU0_G2_TX_DN<14>")
	)
	(segment
		(start 357.654098 -225.366834)
		(end 357.66248 -225.37166)
		(width 0.1143)
		(layer "In6.Cu")
		(net "GMI_CPU1_G0_CPU0_G2_TX_DN<14>")
	)
	(segment
		(start 355.632512 -221.17431)
		(end 355.632512 -221.202758)
		(width 0.1143)
		(layer "In6.Cu")
		(net "GMI_CPU1_G0_CPU0_G2_TX_DN<14>")
	)
	(segment
		(start 354.819966 -219.654628)
		(end 355.632512 -220.467428)
		(width 0.14224)
		(layer "In6.Cu")
		(net "GMI_CPU1_G0_CPU0_G2_TX_DN<14>")
	)
	(segment
		(start 232.873804 -199.805798)
		(end 236.371892 -200.422256)
		(width 0.14224)
		(layer "In6.Cu")
		(net "GMI_CPU1_G0_CPU0_G2_TX_DN<14>")
	)
	(segment
		(start 355.632512 -220.467428)
		(end 355.632512 -221.17431)
		(width 0.14224)
		(layer "In6.Cu")
		(net "GMI_CPU1_G0_CPU0_G2_TX_DN<14>")
	)
	(segment
		(start 115.2525 -222.936562)
		(end 115.25377 -222.9358)
		(width 0.1143)
		(layer "In6.Cu")
		(net "GMI_CPU1_G0_CPU0_G2_TX_DN<14>")
	)
	(segment
		(start 111.83747 -227.44049)
		(end 112.488472 -225.902774)
		(width 0.1143)
		(layer "In6.Cu")
		(net "GMI_CPU1_G0_CPU0_G2_TX_DN<14>")
	)
	(segment
		(start 162.70732 -190.17488)
		(end 207.15224 -189.986158)
		(width 0.14224)
		(layer "In6.Cu")
		(net "GMI_CPU1_G0_CPU0_G2_TX_DN<14>")
	)
	(segment
		(start 108.788962 -240.434368)
		(end 108.871766 -240.351564)
		(width 0.1143)
		(layer "In6.Cu")
		(net "GMI_CPU1_G0_CPU0_G2_TX_DN<14>")
	)
	(segment
		(start 356.244144 -222.936816)
		(end 356.24516 -222.937324)
		(width 0.1143)
		(layer "In6.Cu")
		(net "GMI_CPU1_G0_CPU0_G2_TX_DN<14>")
	)
	(segment
		(start 359.7275 -227.89896)
		(end 359.7275 -236.781086)
		(width 0.1143)
		(layer "In6.Cu")
		(net "GMI_CPU1_G0_CPU0_G2_TX_DN<14>")
	)
	(segment
		(start 111.783876 -237.324138)
		(end 111.783876 -237.323884)
		(width 0.1143)
		(layer "In6.Cu")
		(net "GMI_CPU1_G0_CPU0_G2_TX_DN<14>")
	)
	(segment
		(start 355.586538 -221.624906)
		(end 355.586538 -221.80423)
		(width 0.1143)
		(layer "In6.Cu")
		(net "GMI_CPU1_G0_CPU0_G2_TX_DN<14>")
	)
	(segment
		(start 356.240588 -222.934784)
		(end 356.243382 -222.936308)
		(width 0.1143)
		(layer "In6.Cu")
		(net "GMI_CPU1_G0_CPU0_G2_TX_DN<14>")
	)
	(segment
		(start 355.586792 -221.624652)
		(end 355.586538 -221.624906)
		(width 0.1143)
		(layer "In6.Cu")
		(net "GMI_CPU1_G0_CPU0_G2_TX_DN<14>")
	)
	(segment
		(start 110.1598 -239.89157)
		(end 110.788958 -239.262666)
		(width 0.1143)
		(layer "In6.Cu")
		(net "GMI_CPU1_G0_CPU0_G2_TX_DN<14>")
	)
	(segment
		(start 355.632512 -221.202758)
		(end 355.586792 -221.248478)
		(width 0.1143)
		(layer "In6.Cu")
		(net "GMI_CPU1_G0_CPU0_G2_TX_DN<14>")
	)
	(segment
		(start 115.249198 -222.938594)
		(end 115.250722 -222.937578)
		(width 0.1143)
		(layer "In6.Cu")
		(net "GMI_CPU1_G0_CPU0_G2_TX_DN<14>")
	)
	(segment
		(start 115.251738 -222.93707)
		(end 115.2525 -222.936562)
		(width 0.1143)
		(layer "In6.Cu")
		(net "GMI_CPU1_G0_CPU0_G2_TX_DN<14>")
	)
	(segment
		(start 115.212622 -222.95993)
		(end 115.248182 -222.939102)
		(width 0.1143)
		(layer "In6.Cu")
		(net "GMI_CPU1_G0_CPU0_G2_TX_DN<14>")
	)
	(segment
		(start 362.624116 -240.35131)
		(end 362.70692 -240.434114)
		(width 0.1143)
		(layer "In6.Cu")
		(net "GMI_CPU1_G0_CPU0_G2_TX_DN<14>")
	)
	(segment
		(start 362.347764 -239.946688)
		(end 362.38688 -239.969548)
		(width 0.1143)
		(layer "In6.Cu")
		(net "GMI_CPU1_G0_CPU0_G2_TX_DN<14>")
	)
	(segment
		(start 357.184198 -224.556828)
		(end 357.186992 -224.558352)
		(width 0.1143)
		(layer "In6.Cu")
		(net "GMI_CPU1_G0_CPU0_G2_TX_DN<14>")
	)
	(segment
		(start 230.531416 -198.835772)
		(end 232.873804 -199.805798)
		(width 0.14224)
		(layer "In6.Cu")
		(net "GMI_CPU1_G0_CPU0_G2_TX_DN<14>")
	)
	(segment
		(start 356.246684 -222.93834)
		(end 356.2477 -222.938848)
		(width 0.1143)
		(layer "In6.Cu")
		(net "GMI_CPU1_G0_CPU0_G2_TX_DN<14>")
	)
	(segment
		(start 357.152448 -224.53854)
		(end 357.184198 -224.556828)
		(width 0.1143)
		(layer "In6.Cu")
		(net "GMI_CPU1_G0_CPU0_G2_TX_DN<14>")
	)
	(arc
		(start 356.526592 -223.424242)
		(mid 356.568141 -223.595664)
		(end 356.683564 -223.729042)
		(width 0.1143)
		(layer "In6.Cu")
		(net "GMI_CPU1_G0_CPU0_G2_TX_DN<14>")
	)
	(arc
		(start 357.186992 -224.558352)
		(mid 357.39155 -224.763715)
		(end 357.466392 -225.043746)
		(width 0.1143)
		(layer "In6.Cu")
		(net "GMI_CPU1_G0_CPU0_G2_TX_DN<14>")
	)
	(arc
		(start 110.06709 -239.958626)
		(mid 110.116179 -239.928876)
		(end 110.1598 -239.89157)
		(width 0.1143)
		(layer "In6.Cu")
		(net "GMI_CPU1_G0_CPU0_G2_TX_DN<14>")
	)
	(arc
		(start 112.488472 -225.902774)
		(mid 112.615924 -225.66513)
		(end 112.78616 -225.455988)
		(width 0.1143)
		(layer "In6.Cu")
		(net "GMI_CPU1_G0_CPU0_G2_TX_DN<14>")
	)
	(arc
		(start 114.343434 -224.538794)
		(mid 114.45811 -224.40546)
		(end 114.49939 -224.234502)
		(width 0.1143)
		(layer "In6.Cu")
		(net "GMI_CPU1_G0_CPU0_G2_TX_DN<14>")
	)
	(arc
		(start 355.586538 -221.80423)
		(mid 355.628087 -221.975652)
		(end 355.74351 -222.10903)
		(width 0.1143)
		(layer "In6.Cu")
		(net "GMI_CPU1_G0_CPU0_G2_TX_DN<14>")
	)
	(arc
		(start 109.722412 -239.951768)
		(mid 109.8939 -239.997376)
		(end 110.06709 -239.958626)
		(width 0.1143)
		(layer "In6.Cu")
		(net "GMI_CPU1_G0_CPU0_G2_TX_DN<14>")
	)
	(arc
		(start 113.8428 -225.36658)
		(mid 113.979427 -225.230345)
		(end 114.02949 -225.044)
		(width 0.1143)
		(layer "In6.Cu")
		(net "GMI_CPU1_G0_CPU0_G2_TX_DN<14>")
	)
	(arc
		(start 112.912398 -225.360992)
		(mid 113.19083 -225.290894)
		(end 113.467642 -225.367088)
		(width 0.1143)
		(layer "In6.Cu")
		(net "GMI_CPU1_G0_CPU0_G2_TX_DN<14>")
	)
	(arc
		(start 112.78616 -225.455988)
		(mid 112.82876 -225.417521)
		(end 112.87506 -225.383598)
		(width 0.1143)
		(layer "In6.Cu")
		(net "GMI_CPU1_G0_CPU0_G2_TX_DN<14>")
	)
	(arc
		(start 357.66248 -225.37166)
		(mid 357.845988 -225.417154)
		(end 358.02824 -225.366834)
		(width 0.1143)
		(layer "In6.Cu")
		(net "GMI_CPU1_G0_CPU0_G2_TX_DN<14>")
	)
	(arc
		(start 355.813106 -222.14967)
		(mid 355.991919 -222.35202)
		(end 356.056438 -222.614236)
		(width 0.1143)
		(layer "In6.Cu")
		(net "GMI_CPU1_G0_CPU0_G2_TX_DN<14>")
	)
	(arc
		(start 114.812318 -223.729296)
		(mid 114.927745 -223.59592)
		(end 114.96929 -223.424496)
		(width 0.1143)
		(layer "In6.Cu")
		(net "GMI_CPU1_G0_CPU0_G2_TX_DN<14>")
	)
	(arc
		(start 356.996492 -224.234248)
		(mid 357.037747 -224.405219)
		(end 357.152448 -224.53854)
		(width 0.1143)
		(layer "In6.Cu")
		(net "GMI_CPU1_G0_CPU0_G2_TX_DN<14>")
	)
	(arc
		(start 358.593898 -225.366834)
		(mid 358.607477 -225.374899)
		(end 358.620822 -225.383344)
		(width 0.1143)
		(layer "In6.Cu")
		(net "GMI_CPU1_G0_CPU0_G2_TX_DN<14>")
	)
	(arc
		(start 111.793528 -227.657152)
		(mid 111.804621 -227.546614)
		(end 111.83747 -227.44049)
		(width 0.1143)
		(layer "In6.Cu")
		(net "GMI_CPU1_G0_CPU0_G2_TX_DN<14>")
	)
	(arc
		(start 361.781852 -239.946688)
		(mid 362.064808 -239.870511)
		(end 362.347764 -239.946688)
		(width 0.1143)
		(layer "In6.Cu")
		(net "GMI_CPU1_G0_CPU0_G2_TX_DN<14>")
	)
	(arc
		(start 114.02949 -225.044)
		(mid 114.104328 -224.763967)
		(end 114.30889 -224.558606)
		(width 0.1143)
		(layer "In6.Cu")
		(net "GMI_CPU1_G0_CPU0_G2_TX_DN<14>")
	)
	(arc
		(start 115.439444 -222.61449)
		(mid 115.503959 -222.352271)
		(end 115.682776 -222.149924)
		(width 0.1143)
		(layer "In6.Cu")
		(net "GMI_CPU1_G0_CPU0_G2_TX_DN<14>")
	)
	(arc
		(start 356.28326 -222.959676)
		(mid 356.462073 -223.162026)
		(end 356.526592 -223.424242)
		(width 0.1143)
		(layer "In6.Cu")
		(net "GMI_CPU1_G0_CPU0_G2_TX_DN<14>")
	)
	(arc
		(start 108.875576 -240.328704)
		(mid 108.957009 -240.126306)
		(end 109.109002 -239.969802)
		(width 0.1143)
		(layer "In6.Cu")
		(net "GMI_CPU1_G0_CPU0_G2_TX_DN<14>")
	)
	(arc
		(start 358.719882 -225.465894)
		(mid 359.465687 -226.582209)
		(end 359.7275 -227.89896)
		(width 0.1143)
		(layer "In6.Cu")
		(net "GMI_CPU1_G0_CPU0_G2_TX_DN<14>")
	)
	(arc
		(start 115.283488 -222.918782)
		(mid 115.398164 -222.785448)
		(end 115.439444 -222.61449)
		(width 0.1143)
		(layer "In6.Cu")
		(net "GMI_CPU1_G0_CPU0_G2_TX_DN<14>")
	)
	(arc
		(start 110.788958 -239.262666)
		(mid 111.303153 -238.582319)
		(end 111.684816 -237.819692)
		(width 0.1143)
		(layer "In6.Cu")
		(net "GMI_CPU1_G0_CPU0_G2_TX_DN<14>")
	)
	(arc
		(start 357.466392 -225.043746)
		(mid 357.516423 -225.230109)
		(end 357.653082 -225.366326)
		(width 0.1143)
		(layer "In6.Cu")
		(net "GMI_CPU1_G0_CPU0_G2_TX_DN<14>")
	)
	(arc
		(start 108.871766 -240.351564)
		(mid 108.873554 -240.340115)
		(end 108.875576 -240.328704)
		(width 0.1143)
		(layer "In6.Cu")
		(net "GMI_CPU1_G0_CPU0_G2_TX_DN<14>")
	)
	(arc
		(start 113.467642 -225.367088)
		(mid 113.649893 -225.417438)
		(end 113.833402 -225.371914)
		(width 0.1143)
		(layer "In6.Cu")
		(net "GMI_CPU1_G0_CPU0_G2_TX_DN<14>")
	)
	(arc
		(start 111.684816 -237.819692)
		(mid 111.707229 -237.752203)
		(end 111.722662 -237.682786)
		(width 0.1143)
		(layer "In6.Cu")
		(net "GMI_CPU1_G0_CPU0_G2_TX_DN<14>")
	)
	(arc
		(start 356.056438 -222.614236)
		(mid 356.097693 -222.785207)
		(end 356.212394 -222.918528)
		(width 0.1143)
		(layer "In6.Cu")
		(net "GMI_CPU1_G0_CPU0_G2_TX_DN<14>")
	)
	(arc
		(start 359.7275 -236.781086)
		(mid 360.003604 -238.168682)
		(end 360.789728 -239.344962)
		(width 0.1143)
		(layer "In6.Cu")
		(net "GMI_CPU1_G0_CPU0_G2_TX_DN<14>")
	)
	(arc
		(start 362.38688 -239.969548)
		(mid 362.538867 -240.126056)
		(end 362.620306 -240.32845)
		(width 0.1143)
		(layer "In6.Cu")
		(net "GMI_CPU1_G0_CPU0_G2_TX_DN<14>")
	)
	(arc
		(start 114.49939 -224.234502)
		(mid 114.563905 -223.972283)
		(end 114.742722 -223.769936)
		(width 0.1143)
		(layer "In6.Cu")
		(net "GMI_CPU1_G0_CPU0_G2_TX_DN<14>")
	)
	(arc
		(start 111.783876 -237.323884)
		(mid 111.791105 -237.267192)
		(end 111.793528 -237.210092)
		(width 0.1143)
		(layer "In6.Cu")
		(net "GMI_CPU1_G0_CPU0_G2_TX_DN<14>")
	)
	(arc
		(start 115.752372 -222.109284)
		(mid 115.867799 -221.975908)
		(end 115.909344 -221.804484)
		(width 0.1143)
		(layer "In6.Cu")
		(net "GMI_CPU1_G0_CPU0_G2_TX_DN<14>")
	)
	(arc
		(start 109.148118 -239.946942)
		(mid 109.431074 -239.870765)
		(end 109.71403 -239.946942)
		(width 0.1143)
		(layer "In6.Cu")
		(net "GMI_CPU1_G0_CPU0_G2_TX_DN<14>")
	)
	(arc
		(start 112.87506 -225.383598)
		(mid 112.888407 -225.375156)
		(end 112.901984 -225.367088)
		(width 0.1143)
		(layer "In6.Cu")
		(net "GMI_CPU1_G0_CPU0_G2_TX_DN<14>")
	)
	(arc
		(start 114.96929 -223.424496)
		(mid 115.033805 -223.162277)
		(end 115.212622 -222.95993)
		(width 0.1143)
		(layer "In6.Cu")
		(net "GMI_CPU1_G0_CPU0_G2_TX_DN<14>")
	)
	(arc
		(start 356.75316 -223.769682)
		(mid 356.931973 -223.972032)
		(end 356.996492 -224.234248)
		(width 0.1143)
		(layer "In6.Cu")
		(net "GMI_CPU1_G0_CPU0_G2_TX_DN<14>")
	)
	(arc
		(start 362.620306 -240.32845)
		(mid 362.622329 -240.33986)
		(end 362.624116 -240.35131)
		(width 0.1143)
		(layer "In6.Cu")
		(net "GMI_CPU1_G0_CPU0_G2_TX_DN<14>")
	)
	(arc
		(start 361.350052 -239.90554)
		(mid 361.3779 -239.92749)
		(end 361.40771 -239.946688)
		(width 0.1143)
		(layer "In6.Cu")
		(net "GMI_CPU1_G0_CPU0_G2_TX_DN<14>")
	)
	(arc
		(start 358.620822 -225.383598)
		(mid 358.667119 -225.41739)
		(end 358.709722 -225.455734)
		(width 0.1143)
		(layer "In6.Cu")
		(net "GMI_CPU1_G0_CPU0_G2_TX_DN<14>")
	)
	(arc
		(start 358.02824 -225.366834)
		(mid 358.305053 -225.290691)
		(end 358.583484 -225.360738)
		(width 0.1143)
		(layer "In6.Cu")
		(net "GMI_CPU1_G0_CPU0_G2_TX_DN<14>")
	)
	(arc
		(start 361.40771 -239.946688)
		(mid 361.589961 -239.997038)
		(end 361.77347 -239.951514)
		(width 0.1143)
		(layer "In6.Cu")
		(net "GMI_CPU1_G0_CPU0_G2_TX_DN<14>")
	)
	(segment
		(start 108.957872 -239.080294)
		(end 108.49102 -238.814356)
		(width 0.12954)
		(layer "F.Cu")
		(net "GMI_CPU1_G0_CPU0_G2_TX_DN<13>")
	)
	(segment
		(start 362.53801 -239.08004)
		(end 363.004862 -238.814102)
		(width 0.12954)
		(layer "F.Cu")
		(net "GMI_CPU1_G0_CPU0_G2_TX_DN<13>")
	)
	(segment
		(start 112.246918 -224.936558)
		(end 112.24768 -224.935796)
		(width 0.1143)
		(layer "In6.Cu")
		(net "GMI_CPU1_G0_CPU0_G2_TX_DN<13>")
	)
	(segment
		(start 114.96929 -221.546166)
		(end 114.969544 -221.545912)
		(width 0.1143)
		(layer "In6.Cu")
		(net "GMI_CPU1_G0_CPU0_G2_TX_DN<13>")
	)
	(segment
		(start 233.841036 -199.021192)
		(end 236.278928 -199.451214)
		(width 0.14224)
		(layer "In6.Cu")
		(net "GMI_CPU1_G0_CPU0_G2_TX_DN<13>")
	)
	(segment
		(start 359.411524 -225.100642)
		(end 359.644442 -225.368104)
		(width 0.1143)
		(layer "In6.Cu")
		(net "GMI_CPU1_G0_CPU0_G2_TX_DN<13>")
	)
	(segment
		(start 113.762282 -223.802702)
		(end 113.79962 -223.771714)
		(width 0.1143)
		(layer "In6.Cu")
		(net "GMI_CPU1_G0_CPU0_G2_TX_DN<13>")
	)
	(segment
		(start 360.540554 -228.109272)
		(end 360.540554 -236.771434)
		(width 0.1143)
		(layer "In6.Cu")
		(net "GMI_CPU1_G0_CPU0_G2_TX_DN<13>")
	)
	(segment
		(start 358.311196 -224.607374)
		(end 358.603042 -224.607374)
		(width 0.1143)
		(layer "In6.Cu")
		(net "GMI_CPU1_G0_CPU0_G2_TX_DN<13>")
	)
	(segment
		(start 117.987318 -217.011758)
		(end 123.487434 -212.709252)
		(width 0.14224)
		(layer "In6.Cu")
		(net "GMI_CPU1_G0_CPU0_G2_TX_DN<13>")
	)
	(segment
		(start 355.453188 -218.957906)
		(end 356.572058 -220.07703)
		(width 0.14224)
		(layer "In6.Cu")
		(net "GMI_CPU1_G0_CPU0_G2_TX_DN<13>")
	)
	(segment
		(start 114.923824 -220.075252)
		(end 117.987318 -217.011758)
		(width 0.14224)
		(layer "In6.Cu")
		(net "GMI_CPU1_G0_CPU0_G2_TX_DN<13>")
	)
	(segment
		(start 361.399582 -238.32185)
		(end 361.403646 -238.32439)
		(width 0.1143)
		(layer "In6.Cu")
		(net "GMI_CPU1_G0_CPU0_G2_TX_DN<13>")
	)
	(segment
		(start 114.742722 -222.149924)
		(end 114.781838 -222.127064)
		(width 0.1143)
		(layer "In6.Cu")
		(net "GMI_CPU1_G0_CPU0_G2_TX_DN<13>")
	)
	(segment
		(start 357.627682 -223.731582)
		(end 357.65359 -223.746822)
		(width 0.1143)
		(layer "In6.Cu")
		(net "GMI_CPU1_G0_CPU0_G2_TX_DN<13>")
	)
	(segment
		(start 362.347764 -238.326676)
		(end 362.38688 -238.349536)
		(width 0.1143)
		(layer "In6.Cu")
		(net "GMI_CPU1_G0_CPU0_G2_TX_DN<13>")
	)
	(segment
		(start 113.841784 -223.747076)
		(end 113.842292 -223.747076)
		(width 0.1143)
		(layer "In6.Cu")
		(net "GMI_CPU1_G0_CPU0_G2_TX_DN<13>")
	)
	(segment
		(start 112.22609 -224.96018)
		(end 112.246918 -224.936558)
		(width 0.1143)
		(layer "In6.Cu")
		(net "GMI_CPU1_G0_CPU0_G2_TX_DN<13>")
	)
	(segment
		(start 357.184198 -222.936816)
		(end 357.22052 -222.957898)
		(width 0.1143)
		(layer "In6.Cu")
		(net "GMI_CPU1_G0_CPU0_G2_TX_DN<13>")
	)
	(segment
		(start 358.910636 -224.68967)
		(end 359.016554 -224.751138)
		(width 0.1143)
		(layer "In6.Cu")
		(net "GMI_CPU1_G0_CPU0_G2_TX_DN<13>")
	)
	(segment
		(start 109.109002 -238.34979)
		(end 109.148118 -238.32693)
		(width 0.1143)
		(layer "In6.Cu")
		(net "GMI_CPU1_G0_CPU0_G2_TX_DN<13>")
	)
	(segment
		(start 357.655114 -223.74733)
		(end 357.656638 -223.748346)
		(width 0.1143)
		(layer "In6.Cu")
		(net "GMI_CPU1_G0_CPU0_G2_TX_DN<13>")
	)
	(segment
		(start 113.842292 -223.747076)
		(end 113.8682 -223.731836)
		(width 0.1143)
		(layer "In6.Cu")
		(net "GMI_CPU1_G0_CPU0_G2_TX_DN<13>")
	)
	(segment
		(start 361.396788 -238.320326)
		(end 361.399582 -238.32185)
		(width 0.1143)
		(layer "In6.Cu")
		(net "GMI_CPU1_G0_CPU0_G2_TX_DN<13>")
	)
	(segment
		(start 356.683564 -222.10903)
		(end 356.75316 -222.14967)
		(width 0.1143)
		(layer "In6.Cu")
		(net "GMI_CPU1_G0_CPU0_G2_TX_DN<13>")
	)
	(segment
		(start 211.629244 -189.82055)
		(end 233.841036 -199.021192)
		(width 0.14224)
		(layer "In6.Cu")
		(net "GMI_CPU1_G0_CPU0_G2_TX_DN<13>")
	)
	(segment
		(start 113.839244 -223.7486)
		(end 113.840768 -223.747584)
		(width 0.1143)
		(layer "In6.Cu")
		(net "GMI_CPU1_G0_CPU0_G2_TX_DN<13>")
	)
	(segment
		(start 114.313716 -222.9358)
		(end 114.343434 -222.918782)
		(width 0.1143)
		(layer "In6.Cu")
		(net "GMI_CPU1_G0_CPU0_G2_TX_DN<13>")
	)
	(segment
		(start 357.152448 -222.918528)
		(end 357.182166 -222.935546)
		(width 0.1143)
		(layer "In6.Cu")
		(net "GMI_CPU1_G0_CPU0_G2_TX_DN<13>")
	)
	(segment
		(start 113.840768 -223.747584)
		(end 113.841784 -223.747076)
		(width 0.1143)
		(layer "In6.Cu")
		(net "GMI_CPU1_G0_CPU0_G2_TX_DN<13>")
	)
	(segment
		(start 303.734724 -189.169548)
		(end 308.511194 -189.169548)
		(width 0.14224)
		(layer "In6.Cu")
		(net "GMI_CPU1_G0_CPU0_G2_TX_DN<13>")
	)
	(segment
		(start 110.980474 -236.992414)
		(end 110.980474 -228.051106)
		(width 0.1143)
		(layer "In6.Cu")
		(net "GMI_CPU1_G0_CPU0_G2_TX_DN<13>")
	)
	(segment
		(start 262.665718 -188.790326)
		(end 303.734724 -189.169548)
		(width 0.14224)
		(layer "In6.Cu")
		(net "GMI_CPU1_G0_CPU0_G2_TX_DN<13>")
	)
	(segment
		(start 356.572058 -221.202758)
		(end 356.526338 -221.248478)
		(width 0.1143)
		(layer "In6.Cu")
		(net "GMI_CPU1_G0_CPU0_G2_TX_DN<13>")
	)
	(segment
		(start 112.24768 -224.935796)
		(end 112.269524 -224.911158)
		(width 0.1143)
		(layer "In6.Cu")
		(net "GMI_CPU1_G0_CPU0_G2_TX_DN<13>")
	)
	(segment
		(start 112.011968 -225.228404)
		(end 112.013238 -225.226626)
		(width 0.1143)
		(layer "In6.Cu")
		(net "GMI_CPU1_G0_CPU0_G2_TX_DN<13>")
	)
	(segment
		(start 357.182166 -222.935546)
		(end 357.183436 -222.936308)
		(width 0.1143)
		(layer "In6.Cu")
		(net "GMI_CPU1_G0_CPU0_G2_TX_DN<13>")
	)
	(segment
		(start 357.62692 -223.731074)
		(end 357.627682 -223.731582)
		(width 0.1143)
		(layer "In6.Cu")
		(net "GMI_CPU1_G0_CPU0_G2_TX_DN<13>")
	)
	(segment
		(start 352.846386 -216.883996)
		(end 355.453188 -218.957906)
		(width 0.14224)
		(layer "In6.Cu")
		(net "GMI_CPU1_G0_CPU0_G2_TX_DN<13>")
	)
	(segment
		(start 114.312446 -222.936562)
		(end 114.313716 -222.9358)
		(width 0.1143)
		(layer "In6.Cu")
		(net "GMI_CPU1_G0_CPU0_G2_TX_DN<13>")
	)
	(segment
		(start 250.94438 -190.857124)
		(end 262.665718 -188.790326)
		(width 0.14224)
		(layer "In6.Cu")
		(net "GMI_CPU1_G0_CPU0_G2_TX_DN<13>")
	)
	(segment
		(start 358.123236 -224.55632)
		(end 358.123998 -224.556828)
		(width 0.1143)
		(layer "In6.Cu")
		(net "GMI_CPU1_G0_CPU0_G2_TX_DN<13>")
	)
	(segment
		(start 162.509454 -189.196472)
		(end 207.018382 -189.007496)
		(width 0.14224)
		(layer "In6.Cu")
		(net "GMI_CPU1_G0_CPU0_G2_TX_DN<13>")
	)
	(segment
		(start 113.839244 -223.748854)
		(end 113.839244 -223.7486)
		(width 0.1143)
		(layer "In6.Cu")
		(net "GMI_CPU1_G0_CPU0_G2_TX_DN<13>")
	)
	(segment
		(start 108.788962 -238.814356)
		(end 108.871766 -238.731552)
		(width 0.1143)
		(layer "In6.Cu")
		(net "GMI_CPU1_G0_CPU0_G2_TX_DN<13>")
	)
	(segment
		(start 357.657654 -223.748854)
		(end 357.660194 -223.750378)
		(width 0.1143)
		(layer "In6.Cu")
		(net "GMI_CPU1_G0_CPU0_G2_TX_DN<13>")
	)
	(segment
		(start 239.47628 -198.887334)
		(end 250.94438 -190.857124)
		(width 0.14224)
		(layer "In6.Cu")
		(net "GMI_CPU1_G0_CPU0_G2_TX_DN<13>")
	)
	(segment
		(start 114.275362 -222.958152)
		(end 114.311684 -222.93707)
		(width 0.1143)
		(layer "In6.Cu")
		(net "GMI_CPU1_G0_CPU0_G2_TX_DN<13>")
	)
	(segment
		(start 356.572058 -220.07703)
		(end 356.572058 -221.17431)
		(width 0.14224)
		(layer "In6.Cu")
		(net "GMI_CPU1_G0_CPU0_G2_TX_DN<13>")
	)
	(segment
		(start 111.062008 -227.673408)
		(end 111.913924 -225.411792)
		(width 0.1143)
		(layer "In6.Cu")
		(net "GMI_CPU1_G0_CPU0_G2_TX_DN<13>")
	)
	(segment
		(start 113.79962 -223.771714)
		(end 113.838228 -223.749362)
		(width 0.1143)
		(layer "In6.Cu")
		(net "GMI_CPU1_G0_CPU0_G2_TX_DN<13>")
	)
	(segment
		(start 114.311684 -222.93707)
		(end 114.312446 -222.936562)
		(width 0.1143)
		(layer "In6.Cu")
		(net "GMI_CPU1_G0_CPU0_G2_TX_DN<13>")
	)
	(segment
		(start 356.526338 -221.248478)
		(end 356.526338 -221.545658)
		(width 0.1143)
		(layer "In6.Cu")
		(net "GMI_CPU1_G0_CPU0_G2_TX_DN<13>")
	)
	(segment
		(start 359.23855 -224.926398)
		(end 359.3211 -225.005646)
		(width 0.1143)
		(layer "In6.Cu")
		(net "GMI_CPU1_G0_CPU0_G2_TX_DN<13>")
	)
	(segment
		(start 112.407954 -224.780094)
		(end 112.482884 -224.720658)
		(width 0.1143)
		(layer "In6.Cu")
		(net "GMI_CPU1_G0_CPU0_G2_TX_DN<13>")
	)
	(segment
		(start 357.183436 -222.936308)
		(end 357.184198 -222.936816)
		(width 0.1143)
		(layer "In6.Cu")
		(net "GMI_CPU1_G0_CPU0_G2_TX_DN<13>")
	)
	(segment
		(start 114.923824 -221.203012)
		(end 114.923824 -221.174564)
		(width 0.1143)
		(layer "In6.Cu")
		(net "GMI_CPU1_G0_CPU0_G2_TX_DN<13>")
	)
	(segment
		(start 357.65359 -223.746822)
		(end 357.654098 -223.746822)
		(width 0.1143)
		(layer "In6.Cu")
		(net "GMI_CPU1_G0_CPU0_G2_TX_DN<13>")
	)
	(segment
		(start 114.923824 -221.174564)
		(end 114.923824 -220.075252)
		(width 0.14224)
		(layer "In6.Cu")
		(net "GMI_CPU1_G0_CPU0_G2_TX_DN<13>")
	)
	(segment
		(start 361.77347 -238.331502)
		(end 361.781852 -238.326676)
		(width 0.1143)
		(layer "In6.Cu")
		(net "GMI_CPU1_G0_CPU0_G2_TX_DN<13>")
	)
	(segment
		(start 123.487434 -212.709252)
		(end 162.509454 -189.196472)
		(width 0.14224)
		(layer "In6.Cu")
		(net "GMI_CPU1_G0_CPU0_G2_TX_DN<13>")
	)
	(segment
		(start 113.83899 -223.748854)
		(end 113.839244 -223.748854)
		(width 0.1143)
		(layer "In6.Cu")
		(net "GMI_CPU1_G0_CPU0_G2_TX_DN<13>")
	)
	(segment
		(start 207.018382 -189.007496)
		(end 211.629244 -189.82055)
		(width 0.14224)
		(layer "In6.Cu")
		(net "GMI_CPU1_G0_CPU0_G2_TX_DN<13>")
	)
	(segment
		(start 356.572058 -221.17431)
		(end 356.572058 -221.202758)
		(width 0.1143)
		(layer "In6.Cu")
		(net "GMI_CPU1_G0_CPU0_G2_TX_DN<13>")
	)
	(segment
		(start 308.511194 -189.169548)
		(end 352.846386 -216.883996)
		(width 0.14224)
		(layer "In6.Cu")
		(net "GMI_CPU1_G0_CPU0_G2_TX_DN<13>")
	)
	(segment
		(start 108.49102 -238.814356)
		(end 108.788962 -238.814356)
		(width 0.1143)
		(layer "In6.Cu")
		(net "GMI_CPU1_G0_CPU0_G2_TX_DN<13>")
	)
	(segment
		(start 357.656638 -223.748346)
		(end 357.657654 -223.748854)
		(width 0.1143)
		(layer "In6.Cu")
		(net "GMI_CPU1_G0_CPU0_G2_TX_DN<13>")
	)
	(segment
		(start 357.654098 -223.746822)
		(end 357.655114 -223.74733)
		(width 0.1143)
		(layer "In6.Cu")
		(net "GMI_CPU1_G0_CPU0_G2_TX_DN<13>")
	)
	(segment
		(start 114.969544 -221.545912)
		(end 114.969544 -221.248732)
		(width 0.1143)
		(layer "In6.Cu")
		(net "GMI_CPU1_G0_CPU0_G2_TX_DN<13>")
	)
	(segment
		(start 358.123998 -224.556828)
		(end 358.123744 -224.556828)
		(width 0.1143)
		(layer "In6.Cu")
		(net "GMI_CPU1_G0_CPU0_G2_TX_DN<13>")
	)
	(segment
		(start 114.781838 -222.127064)
		(end 114.812318 -222.109284)
		(width 0.1143)
		(layer "In6.Cu")
		(net "GMI_CPU1_G0_CPU0_G2_TX_DN<13>")
	)
	(segment
		(start 357.466392 -223.407986)
		(end 357.466392 -223.40824)
		(width 0.1143)
		(layer "In6.Cu")
		(net "GMI_CPU1_G0_CPU0_G2_TX_DN<13>")
	)
	(segment
		(start 110.128558 -238.29137)
		(end 110.776258 -237.64367)
		(width 0.1143)
		(layer "In6.Cu")
		(net "GMI_CPU1_G0_CPU0_G2_TX_DN<13>")
	)
	(segment
		(start 362.70692 -238.814102)
		(end 363.004862 -238.814102)
		(width 0.1143)
		(layer "In6.Cu")
		(net "GMI_CPU1_G0_CPU0_G2_TX_DN<13>")
	)
	(segment
		(start 110.128558 -238.291116)
		(end 110.128558 -238.29137)
		(width 0.1143)
		(layer "In6.Cu")
		(net "GMI_CPU1_G0_CPU0_G2_TX_DN<13>")
	)
	(segment
		(start 356.526592 -221.545912)
		(end 356.526592 -221.80423)
		(width 0.1143)
		(layer "In6.Cu")
		(net "GMI_CPU1_G0_CPU0_G2_TX_DN<13>")
	)
	(segment
		(start 362.624116 -238.731298)
		(end 362.70692 -238.814102)
		(width 0.1143)
		(layer "In6.Cu")
		(net "GMI_CPU1_G0_CPU0_G2_TX_DN<13>")
	)
	(segment
		(start 114.969544 -221.248732)
		(end 114.923824 -221.203012)
		(width 0.1143)
		(layer "In6.Cu")
		(net "GMI_CPU1_G0_CPU0_G2_TX_DN<13>")
	)
	(segment
		(start 109.71403 -238.32693)
		(end 109.722412 -238.331756)
		(width 0.1143)
		(layer "In6.Cu")
		(net "GMI_CPU1_G0_CPU0_G2_TX_DN<13>")
	)
	(segment
		(start 112.803178 -224.607374)
		(end 113.183416 -224.607374)
		(width 0.1143)
		(layer "In6.Cu")
		(net "GMI_CPU1_G0_CPU0_G2_TX_DN<13>")
	)
	(segment
		(start 113.8682 -223.731836)
		(end 113.868962 -223.731328)
		(width 0.1143)
		(layer "In6.Cu")
		(net "GMI_CPU1_G0_CPU0_G2_TX_DN<13>")
	)
	(segment
		(start 113.838228 -223.749362)
		(end 113.83899 -223.748854)
		(width 0.1143)
		(layer "In6.Cu")
		(net "GMI_CPU1_G0_CPU0_G2_TX_DN<13>")
	)
	(segment
		(start 357.661718 -223.751394)
		(end 357.693214 -223.769682)
		(width 0.1143)
		(layer "In6.Cu")
		(net "GMI_CPU1_G0_CPU0_G2_TX_DN<13>")
	)
	(segment
		(start 114.02949 -223.408494)
		(end 114.02949 -223.40824)
		(width 0.1143)
		(layer "In6.Cu")
		(net "GMI_CPU1_G0_CPU0_G2_TX_DN<13>")
	)
	(segment
		(start 236.278928 -199.451214)
		(end 239.47628 -198.887334)
		(width 0.14224)
		(layer "In6.Cu")
		(net "GMI_CPU1_G0_CPU0_G2_TX_DN<13>")
	)
	(segment
		(start 361.403646 -238.32439)
		(end 361.405932 -238.32566)
		(width 0.1143)
		(layer "In6.Cu")
		(net "GMI_CPU1_G0_CPU0_G2_TX_DN<13>")
	)
	(segment
		(start 114.96929 -221.804484)
		(end 114.96929 -221.546166)
		(width 0.1143)
		(layer "In6.Cu")
		(net "GMI_CPU1_G0_CPU0_G2_TX_DN<13>")
	)
	(segment
		(start 357.660194 -223.750378)
		(end 357.661718 -223.751394)
		(width 0.1143)
		(layer "In6.Cu")
		(net "GMI_CPU1_G0_CPU0_G2_TX_DN<13>")
	)
	(segment
		(start 361.030774 -237.954312)
		(end 361.396788 -238.320326)
		(width 0.1143)
		(layer "In6.Cu")
		(net "GMI_CPU1_G0_CPU0_G2_TX_DN<13>")
	)
	(segment
		(start 111.061754 -227.673662)
		(end 111.062008 -227.673408)
		(width 0.1143)
		(layer "In6.Cu")
		(net "GMI_CPU1_G0_CPU0_G2_TX_DN<13>")
	)
	(segment
		(start 356.526338 -221.545658)
		(end 356.526592 -221.545912)
		(width 0.1143)
		(layer "In6.Cu")
		(net "GMI_CPU1_G0_CPU0_G2_TX_DN<13>")
	)
	(segment
		(start 112.601248 -224.649792)
		(end 112.601756 -224.649538)
		(width 0.1143)
		(layer "In6.Cu")
		(net "GMI_CPU1_G0_CPU0_G2_TX_DN<13>")
	)
	(segment
		(start 358.093518 -224.539048)
		(end 358.123236 -224.55632)
		(width 0.1143)
		(layer "In6.Cu")
		(net "GMI_CPU1_G0_CPU0_G2_TX_DN<13>")
	)
	(segment
		(start 361.405932 -238.32566)
		(end 361.40771 -238.326676)
		(width 0.1143)
		(layer "In6.Cu")
		(net "GMI_CPU1_G0_CPU0_G2_TX_DN<13>")
	)
	(segment
		(start 359.139744 -224.839276)
		(end 359.225596 -224.91446)
		(width 0.1143)
		(layer "In6.Cu")
		(net "GMI_CPU1_G0_CPU0_G2_TX_DN<13>")
	)
	(arc
		(start 111.913924 -225.411792)
		(mid 111.956982 -225.316909)
		(end 112.011968 -225.228404)
		(width 0.1143)
		(layer "In6.Cu")
		(net "GMI_CPU1_G0_CPU0_G2_TX_DN<13>")
	)
	(arc
		(start 114.812318 -222.109284)
		(mid 114.927745 -221.975908)
		(end 114.96929 -221.804484)
		(width 0.1143)
		(layer "In6.Cu")
		(net "GMI_CPU1_G0_CPU0_G2_TX_DN<13>")
	)
	(arc
		(start 110.024418 -238.356648)
		(mid 110.080183 -238.329753)
		(end 110.128558 -238.291116)
		(width 0.1143)
		(layer "In6.Cu")
		(net "GMI_CPU1_G0_CPU0_G2_TX_DN<13>")
	)
	(arc
		(start 357.22052 -222.957898)
		(mid 357.39742 -223.153461)
		(end 357.466392 -223.407986)
		(width 0.1143)
		(layer "In6.Cu")
		(net "GMI_CPU1_G0_CPU0_G2_TX_DN<13>")
	)
	(arc
		(start 359.3211 -225.005646)
		(mid 359.367349 -225.052157)
		(end 359.411524 -225.100642)
		(width 0.1143)
		(layer "In6.Cu")
		(net "GMI_CPU1_G0_CPU0_G2_TX_DN<13>")
	)
	(arc
		(start 359.016554 -224.751138)
		(mid 359.08029 -224.792214)
		(end 359.139744 -224.839276)
		(width 0.1143)
		(layer "In6.Cu")
		(net "GMI_CPU1_G0_CPU0_G2_TX_DN<13>")
	)
	(arc
		(start 359.644442 -225.368104)
		(mid 359.687965 -225.420957)
		(end 359.728262 -225.476308)
		(width 0.1143)
		(layer "In6.Cu")
		(net "GMI_CPU1_G0_CPU0_G2_TX_DN<13>")
	)
	(arc
		(start 357.693214 -223.769682)
		(mid 357.872027 -223.972032)
		(end 357.936546 -224.234248)
		(width 0.1143)
		(layer "In6.Cu")
		(net "GMI_CPU1_G0_CPU0_G2_TX_DN<13>")
	)
	(arc
		(start 358.603042 -224.607374)
		(mid 358.762267 -224.628236)
		(end 358.910636 -224.68967)
		(width 0.1143)
		(layer "In6.Cu")
		(net "GMI_CPU1_G0_CPU0_G2_TX_DN<13>")
	)
	(arc
		(start 357.617776 -223.723962)
		(mid 357.62232 -223.727553)
		(end 357.62692 -223.731074)
		(width 0.1143)
		(layer "In6.Cu")
		(net "GMI_CPU1_G0_CPU0_G2_TX_DN<13>")
	)
	(arc
		(start 112.482884 -224.720658)
		(mid 112.539775 -224.681399)
		(end 112.601248 -224.649792)
		(width 0.1143)
		(layer "In6.Cu")
		(net "GMI_CPU1_G0_CPU0_G2_TX_DN<13>")
	)
	(arc
		(start 361.781852 -238.326676)
		(mid 362.064808 -238.250499)
		(end 362.347764 -238.326676)
		(width 0.1143)
		(layer "In6.Cu")
		(net "GMI_CPU1_G0_CPU0_G2_TX_DN<13>")
	)
	(arc
		(start 114.024918 -223.451928)
		(mid 114.028103 -223.430306)
		(end 114.02949 -223.408494)
		(width 0.1143)
		(layer "In6.Cu")
		(net "GMI_CPU1_G0_CPU0_G2_TX_DN<13>")
	)
	(arc
		(start 110.980474 -228.051106)
		(mid 110.984443 -227.973977)
		(end 110.996476 -227.89769)
		(width 0.1143)
		(layer "In6.Cu")
		(net "GMI_CPU1_G0_CPU0_G2_TX_DN<13>")
	)
	(arc
		(start 114.49939 -222.61449)
		(mid 114.563905 -222.352271)
		(end 114.742722 -222.149924)
		(width 0.1143)
		(layer "In6.Cu")
		(net "GMI_CPU1_G0_CPU0_G2_TX_DN<13>")
	)
	(arc
		(start 357.466392 -223.40824)
		(mid 357.467767 -223.430053)
		(end 357.470964 -223.451674)
		(width 0.1143)
		(layer "In6.Cu")
		(net "GMI_CPU1_G0_CPU0_G2_TX_DN<13>")
	)
	(arc
		(start 110.910878 -237.424214)
		(mid 110.962914 -237.211094)
		(end 110.980474 -236.992414)
		(width 0.1143)
		(layer "In6.Cu")
		(net "GMI_CPU1_G0_CPU0_G2_TX_DN<13>")
	)
	(arc
		(start 356.75316 -222.14967)
		(mid 356.931973 -222.35202)
		(end 356.996492 -222.614236)
		(width 0.1143)
		(layer "In6.Cu")
		(net "GMI_CPU1_G0_CPU0_G2_TX_DN<13>")
	)
	(arc
		(start 113.878106 -223.724216)
		(mid 113.972023 -223.599132)
		(end 114.024918 -223.451928)
		(width 0.1143)
		(layer "In6.Cu")
		(net "GMI_CPU1_G0_CPU0_G2_TX_DN<13>")
	)
	(arc
		(start 362.38688 -238.349536)
		(mid 362.538867 -238.506044)
		(end 362.620306 -238.708438)
		(width 0.1143)
		(layer "In6.Cu")
		(net "GMI_CPU1_G0_CPU0_G2_TX_DN<13>")
	)
	(arc
		(start 356.526592 -221.80423)
		(mid 356.568141 -221.975652)
		(end 356.683564 -222.10903)
		(width 0.1143)
		(layer "In6.Cu")
		(net "GMI_CPU1_G0_CPU0_G2_TX_DN<13>")
	)
	(arc
		(start 112.601756 -224.649538)
		(mid 112.700279 -224.618015)
		(end 112.803178 -224.607374)
		(width 0.1143)
		(layer "In6.Cu")
		(net "GMI_CPU1_G0_CPU0_G2_TX_DN<13>")
	)
	(arc
		(start 108.871766 -238.731552)
		(mid 108.873554 -238.720103)
		(end 108.875576 -238.708692)
		(width 0.1143)
		(layer "In6.Cu")
		(net "GMI_CPU1_G0_CPU0_G2_TX_DN<13>")
	)
	(arc
		(start 114.343434 -222.918782)
		(mid 114.45811 -222.785448)
		(end 114.49939 -222.61449)
		(width 0.1143)
		(layer "In6.Cu")
		(net "GMI_CPU1_G0_CPU0_G2_TX_DN<13>")
	)
	(arc
		(start 357.470964 -223.451674)
		(mid 357.523848 -223.598884)
		(end 357.617776 -223.723962)
		(width 0.1143)
		(layer "In6.Cu")
		(net "GMI_CPU1_G0_CPU0_G2_TX_DN<13>")
	)
	(arc
		(start 113.868962 -223.731328)
		(mid 113.873562 -223.727807)
		(end 113.878106 -223.724216)
		(width 0.1143)
		(layer "In6.Cu")
		(net "GMI_CPU1_G0_CPU0_G2_TX_DN<13>")
	)
	(arc
		(start 356.996492 -222.614236)
		(mid 357.037747 -222.785207)
		(end 357.152448 -222.918528)
		(width 0.1143)
		(layer "In6.Cu")
		(net "GMI_CPU1_G0_CPU0_G2_TX_DN<13>")
	)
	(arc
		(start 113.183416 -224.607374)
		(mid 113.448624 -224.496842)
		(end 113.559336 -224.231708)
		(width 0.1143)
		(layer "In6.Cu")
		(net "GMI_CPU1_G0_CPU0_G2_TX_DN<13>")
	)
	(arc
		(start 110.996476 -227.89769)
		(mid 111.024955 -227.784464)
		(end 111.061754 -227.673662)
		(width 0.1143)
		(layer "In6.Cu")
		(net "GMI_CPU1_G0_CPU0_G2_TX_DN<13>")
	)
	(arc
		(start 110.776258 -237.64367)
		(mid 110.856403 -237.541816)
		(end 110.910878 -237.424214)
		(width 0.1143)
		(layer "In6.Cu")
		(net "GMI_CPU1_G0_CPU0_G2_TX_DN<13>")
	)
	(arc
		(start 108.875576 -238.708692)
		(mid 108.957009 -238.506294)
		(end 109.109002 -238.34979)
		(width 0.1143)
		(layer "In6.Cu")
		(net "GMI_CPU1_G0_CPU0_G2_TX_DN<13>")
	)
	(arc
		(start 357.936546 -224.234248)
		(mid 357.978095 -224.40567)
		(end 358.093518 -224.539048)
		(width 0.1143)
		(layer "In6.Cu")
		(net "GMI_CPU1_G0_CPU0_G2_TX_DN<13>")
	)
	(arc
		(start 114.02949 -223.40824)
		(mid 114.098451 -223.153709)
		(end 114.275362 -222.958152)
		(width 0.1143)
		(layer "In6.Cu")
		(net "GMI_CPU1_G0_CPU0_G2_TX_DN<13>")
	)
	(arc
		(start 361.40771 -238.326676)
		(mid 361.589961 -238.377026)
		(end 361.77347 -238.331502)
		(width 0.1143)
		(layer "In6.Cu")
		(net "GMI_CPU1_G0_CPU0_G2_TX_DN<13>")
	)
	(arc
		(start 109.722412 -238.331756)
		(mid 109.870777 -238.376292)
		(end 110.024418 -238.356648)
		(width 0.1143)
		(layer "In6.Cu")
		(net "GMI_CPU1_G0_CPU0_G2_TX_DN<13>")
	)
	(arc
		(start 362.620306 -238.708438)
		(mid 362.622329 -238.719848)
		(end 362.624116 -238.731298)
		(width 0.1143)
		(layer "In6.Cu")
		(net "GMI_CPU1_G0_CPU0_G2_TX_DN<13>")
	)
	(arc
		(start 109.148118 -238.32693)
		(mid 109.431074 -238.250753)
		(end 109.71403 -238.32693)
		(width 0.1143)
		(layer "In6.Cu")
		(net "GMI_CPU1_G0_CPU0_G2_TX_DN<13>")
	)
	(arc
		(start 359.225596 -224.91446)
		(mid 359.232145 -224.92035)
		(end 359.23855 -224.926398)
		(width 0.1143)
		(layer "In6.Cu")
		(net "GMI_CPU1_G0_CPU0_G2_TX_DN<13>")
	)
	(arc
		(start 360.540554 -236.771434)
		(mid 360.668009 -237.411633)
		(end 361.030774 -237.954312)
		(width 0.1143)
		(layer "In6.Cu")
		(net "GMI_CPU1_G0_CPU0_G2_TX_DN<13>")
	)
	(arc
		(start 358.123744 -224.556828)
		(mid 358.214127 -224.594489)
		(end 358.311196 -224.607374)
		(width 0.1143)
		(layer "In6.Cu")
		(net "GMI_CPU1_G0_CPU0_G2_TX_DN<13>")
	)
	(arc
		(start 359.728262 -225.476308)
		(mid 360.33284 -226.731569)
		(end 360.540554 -228.109272)
		(width 0.1143)
		(layer "In6.Cu")
		(net "GMI_CPU1_G0_CPU0_G2_TX_DN<13>")
	)
	(arc
		(start 112.269524 -224.911158)
		(mid 112.335896 -224.842622)
		(end 112.407954 -224.780094)
		(width 0.1143)
		(layer "In6.Cu")
		(net "GMI_CPU1_G0_CPU0_G2_TX_DN<13>")
	)
	(arc
		(start 112.013238 -225.226626)
		(mid 112.116046 -225.090513)
		(end 112.22609 -224.96018)
		(width 0.1143)
		(layer "In6.Cu")
		(net "GMI_CPU1_G0_CPU0_G2_TX_DN<13>")
	)
	(arc
		(start 113.559336 -224.231708)
		(mid 113.613226 -223.994685)
		(end 113.762282 -223.802702)
		(width 0.1143)
		(layer "In6.Cu")
		(net "GMI_CPU1_G0_CPU0_G2_TX_DN<13>")
	)
	(segment
		(start 106.607864 -243.130324)
		(end 106.141012 -242.864386)
		(width 0.12954)
		(layer "F.Cu")
		(net "GMI_CPU1_G0_CPU0_G2_TX_DN<12>")
	)
	(segment
		(start 364.888018 -243.13007)
		(end 365.35487 -242.864132)
		(width 0.12954)
		(layer "F.Cu")
		(net "GMI_CPU1_G0_CPU0_G2_TX_DN<12>")
	)
	(segment
		(start 108.204508 -239.29975)
		(end 108.168948 -239.278922)
		(width 0.1143)
		(layer "In6.Cu")
		(net "GMI_CPU1_G0_CPU0_G2_TX_DN<12>")
	)
	(segment
		(start 108.214668 -238.32312)
		(end 108.215938 -238.322358)
		(width 0.1143)
		(layer "In6.Cu")
		(net "GMI_CPU1_G0_CPU0_G2_TX_DN<12>")
	)
	(segment
		(start 364.227872 -241.5667)
		(end 364.264194 -241.587782)
		(width 0.1143)
		(layer "In6.Cu")
		(net "GMI_CPU1_G0_CPU0_G2_TX_DN<12>")
	)
	(segment
		(start 359.495598 -224.044002)
		(end 359.779316 -224.37725)
		(width 0.1143)
		(layer "In6.Cu")
		(net "GMI_CPU1_G0_CPU0_G2_TX_DN<12>")
	)
	(segment
		(start 361.374944 -233.44759)
		(end 361.40771 -233.46664)
		(width 0.1143)
		(layer "In6.Cu")
		(net "GMI_CPU1_G0_CPU0_G2_TX_DN<12>")
	)
	(segment
		(start 363.290358 -239.300004)
		(end 363.288834 -239.30102)
		(width 0.1143)
		(layer "In6.Cu")
		(net "GMI_CPU1_G0_CPU0_G2_TX_DN<12>")
	)
	(segment
		(start 358.736646 -223.321118)
		(end 359.401872 -223.946212)
		(width 0.1143)
		(layer "In6.Cu")
		(net "GMI_CPU1_G0_CPU0_G2_TX_DN<12>")
	)
	(segment
		(start 363.281214 -239.942878)
		(end 363.28223 -239.943386)
		(width 0.1143)
		(layer "In6.Cu")
		(net "GMI_CPU1_G0_CPU0_G2_TX_DN<12>")
	)
	(segment
		(start 364.219998 -241.562128)
		(end 364.221268 -241.56289)
		(width 0.1143)
		(layer "In6.Cu")
		(net "GMI_CPU1_G0_CPU0_G2_TX_DN<12>")
	)
	(segment
		(start 111.933482 -224.117408)
		(end 111.935514 -224.114868)
		(width 0.1143)
		(layer "In6.Cu")
		(net "GMI_CPU1_G0_CPU0_G2_TX_DN<12>")
	)
	(segment
		(start 108.208826 -238.326422)
		(end 108.210096 -238.32566)
		(width 0.1143)
		(layer "In6.Cu")
		(net "GMI_CPU1_G0_CPU0_G2_TX_DN<12>")
	)
	(segment
		(start 122.990356 -211.911184)
		(end 162.233102 -188.265308)
		(width 0.14224)
		(layer "In6.Cu")
		(net "GMI_CPU1_G0_CPU0_G2_TX_DN<12>")
	)
	(segment
		(start 107.231688 -241.588036)
		(end 107.267248 -241.567462)
		(width 0.1143)
		(layer "In6.Cu")
		(net "GMI_CPU1_G0_CPU0_G2_TX_DN<12>")
	)
	(segment
		(start 108.210096 -238.32566)
		(end 108.21162 -238.324898)
		(width 0.1143)
		(layer "In6.Cu")
		(net "GMI_CPU1_G0_CPU0_G2_TX_DN<12>")
	)
	(segment
		(start 363.284262 -239.944656)
		(end 363.285786 -239.945418)
		(width 0.1143)
		(layer "In6.Cu")
		(net "GMI_CPU1_G0_CPU0_G2_TX_DN<12>")
	)
	(segment
		(start 110.120684 -231.220772)
		(end 110.088172 -231.201976)
		(width 0.1143)
		(layer "In6.Cu")
		(net "GMI_CPU1_G0_CPU0_G2_TX_DN<12>")
	)
	(segment
		(start 108.208064 -238.32693)
		(end 108.208826 -238.326422)
		(width 0.1143)
		(layer "In6.Cu")
		(net "GMI_CPU1_G0_CPU0_G2_TX_DN<12>")
	)
	(segment
		(start 365.056928 -242.864132)
		(end 365.35487 -242.864132)
		(width 0.1143)
		(layer "In6.Cu")
		(net "GMI_CPU1_G0_CPU0_G2_TX_DN<12>")
	)
	(segment
		(start 363.290358 -239.948212)
		(end 363.326934 -239.969548)
		(width 0.1143)
		(layer "In6.Cu")
		(net "GMI_CPU1_G0_CPU0_G2_TX_DN<12>")
	)
	(segment
		(start 363.288834 -239.30102)
		(end 363.287818 -239.301528)
		(width 0.1143)
		(layer "In6.Cu")
		(net "GMI_CPU1_G0_CPU0_G2_TX_DN<12>")
	)
	(segment
		(start 108.208064 -239.301782)
		(end 108.207048 -239.301274)
		(width 0.1143)
		(layer "In6.Cu")
		(net "GMI_CPU1_G0_CPU0_G2_TX_DN<12>")
	)
	(segment
		(start 358.093518 -222.919036)
		(end 358.351836 -223.068388)
		(width 0.1143)
		(layer "In6.Cu")
		(net "GMI_CPU1_G0_CPU0_G2_TX_DN<12>")
	)
	(segment
		(start 364.224316 -241.564668)
		(end 364.22584 -241.56543)
		(width 0.1143)
		(layer "In6.Cu")
		(net "GMI_CPU1_G0_CPU0_G2_TX_DN<12>")
	)
	(segment
		(start 234.008422 -197.926198)
		(end 234.008422 -197.926452)
		(width 0.14224)
		(layer "In6.Cu")
		(net "GMI_CPU1_G0_CPU0_G2_TX_DN<12>")
	)
	(segment
		(start 363.279944 -238.322104)
		(end 363.281214 -238.322866)
		(width 0.1143)
		(layer "In6.Cu")
		(net "GMI_CPU1_G0_CPU0_G2_TX_DN<12>")
	)
	(segment
		(start 110.088172 -229.581964)
		(end 110.049056 -229.559104)
		(width 0.1143)
		(layer "In6.Cu")
		(net "GMI_CPU1_G0_CPU0_G2_TX_DN<12>")
	)
	(segment
		(start 108.210096 -239.945672)
		(end 108.21162 -239.94491)
		(width 0.1143)
		(layer "In6.Cu")
		(net "GMI_CPU1_G0_CPU0_G2_TX_DN<12>")
	)
	(segment
		(start 108.215938 -238.322358)
		(end 108.218478 -238.321088)
		(width 0.1143)
		(layer "In6.Cu")
		(net "GMI_CPU1_G0_CPU0_G2_TX_DN<12>")
	)
	(segment
		(start 363.287056 -238.326168)
		(end 363.287818 -238.326676)
		(width 0.1143)
		(layer "In6.Cu")
		(net "GMI_CPU1_G0_CPU0_G2_TX_DN<12>")
	)
	(segment
		(start 363.287818 -238.326676)
		(end 363.288834 -238.327184)
		(width 0.1143)
		(layer "In6.Cu")
		(net "GMI_CPU1_G0_CPU0_G2_TX_DN<12>")
	)
	(segment
		(start 113.802668 -222.149924)
		(end 113.872264 -222.109284)
		(width 0.1143)
		(layer "In6.Cu")
		(net "GMI_CPU1_G0_CPU0_G2_TX_DN<12>")
	)
	(segment
		(start 207.137762 -188.0743)
		(end 212.512402 -189.022228)
		(width 0.14224)
		(layer "In6.Cu")
		(net "GMI_CPU1_G0_CPU0_G2_TX_DN<12>")
	)
	(segment
		(start 107.267248 -241.567462)
		(end 107.268772 -241.566446)
		(width 0.1143)
		(layer "In6.Cu")
		(net "GMI_CPU1_G0_CPU0_G2_TX_DN<12>")
	)
	(segment
		(start 108.207048 -239.94745)
		(end 108.208064 -239.946942)
		(width 0.1143)
		(layer "In6.Cu")
		(net "GMI_CPU1_G0_CPU0_G2_TX_DN<12>")
	)
	(segment
		(start 359.85704 -224.475802)
		(end 359.858818 -224.478342)
		(width 0.1143)
		(layer "In6.Cu")
		(net "GMI_CPU1_G0_CPU0_G2_TX_DN<12>")
	)
	(segment
		(start 361.40771 -235.086652)
		(end 361.446826 -235.109512)
		(width 0.1143)
		(layer "In6.Cu")
		(net "GMI_CPU1_G0_CPU0_G2_TX_DN<12>")
	)
	(segment
		(start 108.21289 -239.944148)
		(end 108.213652 -239.94364)
		(width 0.1143)
		(layer "In6.Cu")
		(net "GMI_CPU1_G0_CPU0_G2_TX_DN<12>")
	)
	(segment
		(start 361.846114 -237.498382)
		(end 361.875832 -237.5154)
		(width 0.1143)
		(layer "In6.Cu")
		(net "GMI_CPU1_G0_CPU0_G2_TX_DN<12>")
	)
	(segment
		(start 364.223046 -241.563906)
		(end 364.224316 -241.564668)
		(width 0.1143)
		(layer "In6.Cu")
		(net "GMI_CPU1_G0_CPU0_G2_TX_DN<12>")
	)
	(segment
		(start 108.208064 -239.946942)
		(end 108.208826 -239.946434)
		(width 0.1143)
		(layer "In6.Cu")
		(net "GMI_CPU1_G0_CPU0_G2_TX_DN<12>")
	)
	(segment
		(start 363.281214 -238.322866)
		(end 363.28223 -238.323374)
		(width 0.1143)
		(layer "In6.Cu")
		(net "GMI_CPU1_G0_CPU0_G2_TX_DN<12>")
	)
	(segment
		(start 363.285786 -238.325406)
		(end 363.287056 -238.326168)
		(width 0.1143)
		(layer "In6.Cu")
		(net "GMI_CPU1_G0_CPU0_G2_TX_DN<12>")
	)
	(segment
		(start 361.446826 -231.178862)
		(end 361.40771 -231.201722)
		(width 0.1143)
		(layer "In6.Cu")
		(net "GMI_CPU1_G0_CPU0_G2_TX_DN<12>")
	)
	(segment
		(start 363.256068 -239.9284)
		(end 363.277404 -239.940846)
		(width 0.1143)
		(layer "In6.Cu")
		(net "GMI_CPU1_G0_CPU0_G2_TX_DN<12>")
	)
	(segment
		(start 108.213652 -239.94364)
		(end 108.214668 -239.943132)
		(width 0.1143)
		(layer "In6.Cu")
		(net "GMI_CPU1_G0_CPU0_G2_TX_DN<12>")
	)
	(segment
		(start 364.22584 -241.56543)
		(end 364.22711 -241.566192)
		(width 0.1143)
		(layer "In6.Cu")
		(net "GMI_CPU1_G0_CPU0_G2_TX_DN<12>")
	)
	(segment
		(start 361.37723 -230.208836)
		(end 361.444286 -230.247952)
		(width 0.1143)
		(layer "In6.Cu")
		(net "GMI_CPU1_G0_CPU0_G2_TX_DN<12>")
	)
	(segment
		(start 114.02949 -221.702884)
		(end 114.028982 -221.702376)
		(width 0.1143)
		(layer "In6.Cu")
		(net "GMI_CPU1_G0_CPU0_G2_TX_DN<12>")
	)
	(segment
		(start 113.377218 -222.933768)
		(end 113.38179 -222.931228)
		(width 0.1143)
		(layer "In6.Cu")
		(net "GMI_CPU1_G0_CPU0_G2_TX_DN<12>")
	)
	(segment
		(start 236.299756 -198.500492)
		(end 239.093756 -198.007986)
		(width 0.14224)
		(layer "In6.Cu")
		(net "GMI_CPU1_G0_CPU0_G2_TX_DN<12>")
	)
	(segment
		(start 108.21162 -238.324898)
		(end 108.21289 -238.324136)
		(width 0.1143)
		(layer "In6.Cu")
		(net "GMI_CPU1_G0_CPU0_G2_TX_DN<12>")
	)
	(segment
		(start 303.706784 -188.201808)
		(end 308.761638 -188.201808)
		(width 0.14224)
		(layer "In6.Cu")
		(net "GMI_CPU1_G0_CPU0_G2_TX_DN<12>")
	)
	(segment
		(start 110.049056 -227.00996)
		(end 110.088172 -226.9871)
		(width 0.1143)
		(layer "In6.Cu")
		(net "GMI_CPU1_G0_CPU0_G2_TX_DN<12>")
	)
	(segment
		(start 110.088172 -231.201976)
		(end 110.049056 -231.179116)
		(width 0.1143)
		(layer "In6.Cu")
		(net "GMI_CPU1_G0_CPU0_G2_TX_DN<12>")
	)
	(segment
		(start 108.168948 -239.969802)
		(end 108.205524 -239.948466)
		(width 0.1143)
		(layer "In6.Cu")
		(net "GMI_CPU1_G0_CPU0_G2_TX_DN<12>")
	)
	(segment
		(start 110.120938 -233.447844)
		(end 110.12297 -233.44632)
		(width 0.1143)
		(layer "In6.Cu")
		(net "GMI_CPU1_G0_CPU0_G2_TX_DN<12>")
	)
	(segment
		(start 361.37723 -226.969066)
		(end 361.446826 -227.009706)
		(width 0.1143)
		(layer "In6.Cu")
		(net "GMI_CPU1_G0_CPU0_G2_TX_DN<12>")
	)
	(segment
		(start 363.287056 -239.302036)
		(end 363.256068 -239.319816)
		(width 0.1143)
		(layer "In6.Cu")
		(net "GMI_CPU1_G0_CPU0_G2_TX_DN<12>")
	)
	(segment
		(start 107.273598 -241.563652)
		(end 107.274614 -241.563144)
		(width 0.1143)
		(layer "In6.Cu")
		(net "GMI_CPU1_G0_CPU0_G2_TX_DN<12>")
	)
	(segment
		(start 108.208826 -239.946434)
		(end 108.210096 -239.945672)
		(width 0.1143)
		(layer "In6.Cu")
		(net "GMI_CPU1_G0_CPU0_G2_TX_DN<12>")
	)
	(segment
		(start 106.438954 -242.864386)
		(end 106.521758 -242.781582)
		(width 0.1143)
		(layer "In6.Cu")
		(net "GMI_CPU1_G0_CPU0_G2_TX_DN<12>")
	)
	(segment
		(start 364.217458 -241.560858)
		(end 364.219998 -241.562128)
		(width 0.1143)
		(layer "In6.Cu")
		(net "GMI_CPU1_G0_CPU0_G2_TX_DN<12>")
	)
	(segment
		(start 361.372912 -235.066078)
		(end 361.374944 -235.067602)
		(width 0.1143)
		(layer "In6.Cu")
		(net "GMI_CPU1_G0_CPU0_G2_TX_DN<12>")
	)
	(segment
		(start 107.271566 -241.564922)
		(end 107.272836 -241.56416)
		(width 0.1143)
		(layer "In6.Cu")
		(net "GMI_CPU1_G0_CPU0_G2_TX_DN<12>")
	)
	(segment
		(start 356.032308 -218.209368)
		(end 357.51262 -219.68968)
		(width 0.14224)
		(layer "In6.Cu")
		(net "GMI_CPU1_G0_CPU0_G2_TX_DN<12>")
	)
	(segment
		(start 250.57608 -189.96787)
		(end 262.7376 -187.823348)
		(width 0.14224)
		(layer "In6.Cu")
		(net "GMI_CPU1_G0_CPU0_G2_TX_DN<12>")
	)
	(segment
		(start 110.913164 -225.547682)
		(end 111.172498 -225.143568)
		(width 0.1143)
		(layer "In6.Cu")
		(net "GMI_CPU1_G0_CPU0_G2_TX_DN<12>")
	)
	(segment
		(start 110.120938 -235.067856)
		(end 110.12297 -235.066332)
		(width 0.1143)
		(layer "In6.Cu")
		(net "GMI_CPU1_G0_CPU0_G2_TX_DN<12>")
	)
	(segment
		(start 106.141012 -242.864386)
		(end 106.438954 -242.864386)
		(width 0.1143)
		(layer "In6.Cu")
		(net "GMI_CPU1_G0_CPU0_G2_TX_DN<12>")
	)
	(segment
		(start 110.740952 -225.987864)
		(end 110.913164 -225.547682)
		(width 0.1143)
		(layer "In6.Cu")
		(net "GMI_CPU1_G0_CPU0_G2_TX_DN<12>")
	)
	(segment
		(start 110.118652 -227.979732)
		(end 110.088172 -227.961952)
		(width 0.1143)
		(layer "In6.Cu")
		(net "GMI_CPU1_G0_CPU0_G2_TX_DN<12>")
	)
	(segment
		(start 364.196122 -241.548412)
		(end 364.217458 -241.560858)
		(width 0.1143)
		(layer "In6.Cu")
		(net "GMI_CPU1_G0_CPU0_G2_TX_DN<12>")
	)
	(segment
		(start 308.761638 -188.201808)
		(end 352.733864 -215.589612)
		(width 0.14224)
		(layer "In6.Cu")
		(net "GMI_CPU1_G0_CPU0_G2_TX_DN<12>")
	)
	(segment
		(start 110.12297 -234.46232)
		(end 110.120938 -234.460796)
		(width 0.1143)
		(layer "In6.Cu")
		(net "GMI_CPU1_G0_CPU0_G2_TX_DN<12>")
	)
	(segment
		(start 110.088172 -233.466894)
		(end 110.120938 -233.447844)
		(width 0.1143)
		(layer "In6.Cu")
		(net "GMI_CPU1_G0_CPU0_G2_TX_DN<12>")
	)
	(segment
		(start 363.277404 -238.320834)
		(end 363.279944 -238.322104)
		(width 0.1143)
		(layer "In6.Cu")
		(net "GMI_CPU1_G0_CPU0_G2_TX_DN<12>")
	)
	(segment
		(start 363.285786 -239.945418)
		(end 363.287056 -239.94618)
		(width 0.1143)
		(layer "In6.Cu")
		(net "GMI_CPU1_G0_CPU0_G2_TX_DN<12>")
	)
	(segment
		(start 108.218478 -238.321088)
		(end 108.239814 -238.308642)
		(width 0.1143)
		(layer "In6.Cu")
		(net "GMI_CPU1_G0_CPU0_G2_TX_DN<12>")
	)
	(segment
		(start 107.272836 -241.56416)
		(end 107.273598 -241.563652)
		(width 0.1143)
		(layer "In6.Cu")
		(net "GMI_CPU1_G0_CPU0_G2_TX_DN<12>")
	)
	(segment
		(start 361.374944 -231.827578)
		(end 361.446826 -231.869488)
		(width 0.1143)
		(layer "In6.Cu")
		(net "GMI_CPU1_G0_CPU0_G2_TX_DN<12>")
	)
	(segment
		(start 364.697772 -242.376706)
		(end 364.736888 -242.399566)
		(width 0.1143)
		(layer "In6.Cu")
		(net "GMI_CPU1_G0_CPU0_G2_TX_DN<12>")
	)
	(segment
		(start 359.858818 -224.478342)
		(end 360.497882 -225.353118)
		(width 0.1143)
		(layer "In6.Cu")
		(net "GMI_CPU1_G0_CPU0_G2_TX_DN<12>")
	)
	(segment
		(start 357.51262 -219.68968)
		(end 357.51262 -221.17431)
		(width 0.14224)
		(layer "In6.Cu")
		(net "GMI_CPU1_G0_CPU0_G2_TX_DN<12>")
	)
	(segment
		(start 357.4669 -221.248478)
		(end 357.4669 -221.702122)
		(width 0.1143)
		(layer "In6.Cu")
		(net "GMI_CPU1_G0_CPU0_G2_TX_DN<12>")
	)
	(segment
		(start 363.284262 -238.324644)
		(end 363.285786 -238.325406)
		(width 0.1143)
		(layer "In6.Cu")
		(net "GMI_CPU1_G0_CPU0_G2_TX_DN<12>")
	)
	(segment
		(start 361.446826 -232.79862)
		(end 361.374944 -232.84053)
		(width 0.1143)
		(layer "In6.Cu")
		(net "GMI_CPU1_G0_CPU0_G2_TX_DN<12>")
	)
	(segment
		(start 364.668054 -242.359434)
		(end 364.697772 -242.376706)
		(width 0.1143)
		(layer "In6.Cu")
		(net "GMI_CPU1_G0_CPU0_G2_TX_DN<12>")
	)
	(segment
		(start 108.21162 -239.94491)
		(end 108.21289 -239.944148)
		(width 0.1143)
		(layer "In6.Cu")
		(net "GMI_CPU1_G0_CPU0_G2_TX_DN<12>")
	)
	(segment
		(start 108.239814 -239.32007)
		(end 108.208826 -239.30229)
		(width 0.1143)
		(layer "In6.Cu")
		(net "GMI_CPU1_G0_CPU0_G2_TX_DN<12>")
	)
	(segment
		(start 361.40771 -233.46664)
		(end 361.446826 -233.4895)
		(width 0.1143)
		(layer "In6.Cu")
		(net "GMI_CPU1_G0_CPU0_G2_TX_DN<12>")
	)
	(segment
		(start 363.287818 -239.301528)
		(end 363.287056 -239.302036)
		(width 0.1143)
		(layer "In6.Cu")
		(net "GMI_CPU1_G0_CPU0_G2_TX_DN<12>")
	)
	(segment
		(start 361.374944 -232.84053)
		(end 361.372912 -232.842054)
		(width 0.1143)
		(layer "In6.Cu")
		(net "GMI_CPU1_G0_CPU0_G2_TX_DN<12>")
	)
	(segment
		(start 110.088172 -235.086906)
		(end 110.120938 -235.067856)
		(width 0.1143)
		(layer "In6.Cu")
		(net "GMI_CPU1_G0_CPU0_G2_TX_DN<12>")
	)
	(segment
		(start 361.40771 -231.201722)
		(end 361.375198 -231.220518)
		(width 0.1143)
		(layer "In6.Cu")
		(net "GMI_CPU1_G0_CPU0_G2_TX_DN<12>")
	)
	(segment
		(start 108.207048 -238.327438)
		(end 108.208064 -238.32693)
		(width 0.1143)
		(layer "In6.Cu")
		(net "GMI_CPU1_G0_CPU0_G2_TX_DN<12>")
	)
	(segment
		(start 234.725972 -198.223378)
		(end 236.299756 -198.500492)
		(width 0.14224)
		(layer "In6.Cu")
		(net "GMI_CPU1_G0_CPU0_G2_TX_DN<12>")
	)
	(segment
		(start 363.282992 -238.323882)
		(end 363.284262 -238.324644)
		(width 0.1143)
		(layer "In6.Cu")
		(net "GMI_CPU1_G0_CPU0_G2_TX_DN<12>")
	)
	(segment
		(start 363.291374 -239.299496)
		(end 363.290358 -239.300004)
		(width 0.1143)
		(layer "In6.Cu")
		(net "GMI_CPU1_G0_CPU0_G2_TX_DN<12>")
	)
	(segment
		(start 107.738164 -240.756948)
		(end 107.768644 -240.739168)
		(width 0.1143)
		(layer "In6.Cu")
		(net "GMI_CPU1_G0_CPU0_G2_TX_DN<12>")
	)
	(segment
		(start 110.275624 -226.66452)
		(end 110.275878 -226.66452)
		(width 0.1143)
		(layer "In6.Cu")
		(net "GMI_CPU1_G0_CPU0_G2_TX_DN<12>")
	)
	(segment
		(start 212.512402 -189.022228)
		(end 234.008422 -197.926198)
		(width 0.14224)
		(layer "In6.Cu")
		(net "GMI_CPU1_G0_CPU0_G2_TX_DN<12>")
	)
	(segment
		(start 113.983262 -221.203012)
		(end 113.983262 -221.174564)
		(width 0.1143)
		(layer "In6.Cu")
		(net "GMI_CPU1_G0_CPU0_G2_TX_DN<12>")
	)
	(segment
		(start 234.008422 -197.926452)
		(end 234.725972 -198.223378)
		(width 0.14224)
		(layer "In6.Cu")
		(net "GMI_CPU1_G0_CPU0_G2_TX_DN<12>")
	)
	(segment
		(start 358.351836 -223.068388)
		(end 358.562148 -223.190816)
		(width 0.1143)
		(layer "In6.Cu")
		(net "GMI_CPU1_G0_CPU0_G2_TX_DN<12>")
	)
	(segment
		(start 361.446826 -229.55885)
		(end 361.40771 -229.58171)
		(width 0.1143)
		(layer "In6.Cu")
		(net "GMI_CPU1_G0_CPU0_G2_TX_DN<12>")
	)
	(segment
		(start 108.639102 -237.539784)
		(end 108.678218 -237.516924)
		(width 0.1143)
		(layer "In6.Cu")
		(net "GMI_CPU1_G0_CPU0_G2_TX_DN<12>")
	)
	(segment
		(start 108.205524 -239.300258)
		(end 108.204508 -239.29975)
		(width 0.1143)
		(layer "In6.Cu")
		(net "GMI_CPU1_G0_CPU0_G2_TX_DN<12>")
	)
	(segment
		(start 361.40771 -229.58171)
		(end 361.375198 -229.600506)
		(width 0.1143)
		(layer "In6.Cu")
		(net "GMI_CPU1_G0_CPU0_G2_TX_DN<12>")
	)
	(segment
		(start 110.117382 -236.078776)
		(end 110.049056 -236.038898)
		(width 0.1143)
		(layer "In6.Cu")
		(net "GMI_CPU1_G0_CPU0_G2_TX_DN<12>")
	)
	(segment
		(start 364.221268 -241.56289)
		(end 364.222284 -241.563398)
		(width 0.1143)
		(layer "In6.Cu")
		(net "GMI_CPU1_G0_CPU0_G2_TX_DN<12>")
	)
	(segment
		(start 361.37723 -228.589078)
		(end 361.446826 -228.629718)
		(width 0.1143)
		(layer "In6.Cu")
		(net "GMI_CPU1_G0_CPU0_G2_TX_DN<12>")
	)
	(segment
		(start 357.4669 -221.702122)
		(end 357.466392 -221.70263)
		(width 0.1143)
		(layer "In6.Cu")
		(net "GMI_CPU1_G0_CPU0_G2_TX_DN<12>")
	)
	(segment
		(start 360.559858 -225.44913)
		(end 360.619294 -225.553524)
		(width 0.1143)
		(layer "In6.Cu")
		(net "GMI_CPU1_G0_CPU0_G2_TX_DN<12>")
	)
	(segment
		(start 363.727238 -240.738914)
		(end 363.796834 -240.779554)
		(width 0.1143)
		(layer "In6.Cu")
		(net "GMI_CPU1_G0_CPU0_G2_TX_DN<12>")
	)
	(segment
		(start 357.51262 -221.17431)
		(end 357.51262 -221.202758)
		(width 0.1143)
		(layer "In6.Cu")
		(net "GMI_CPU1_G0_CPU0_G2_TX_DN<12>")
	)
	(segment
		(start 362.817664 -237.51667)
		(end 362.85678 -237.53953)
		(width 0.1143)
		(layer "In6.Cu")
		(net "GMI_CPU1_G0_CPU0_G2_TX_DN<12>")
	)
	(segment
		(start 106.79811 -242.37696)
		(end 106.827828 -242.359688)
		(width 0.1143)
		(layer "In6.Cu")
		(net "GMI_CPU1_G0_CPU0_G2_TX_DN<12>")
	)
	(segment
		(start 363.287818 -239.946688)
		(end 363.288834 -239.947196)
		(width 0.1143)
		(layer "In6.Cu")
		(net "GMI_CPU1_G0_CPU0_G2_TX_DN<12>")
	)
	(segment
		(start 357.466392 -221.70263)
		(end 357.466392 -221.80423)
		(width 0.1143)
		(layer "In6.Cu")
		(net "GMI_CPU1_G0_CPU0_G2_TX_DN<12>")
	)
	(segment
		(start 108.218478 -239.9411)
		(end 108.239814 -239.928654)
		(width 0.1143)
		(layer "In6.Cu")
		(net "GMI_CPU1_G0_CPU0_G2_TX_DN<12>")
	)
	(segment
		(start 110.275624 -236.384338)
		(end 110.275624 -236.383576)
		(width 0.1143)
		(layer "In6.Cu")
		(net "GMI_CPU1_G0_CPU0_G2_TX_DN<12>")
	)
	(segment
		(start 363.279944 -239.942116)
		(end 363.281214 -239.942878)
		(width 0.1143)
		(layer "In6.Cu")
		(net "GMI_CPU1_G0_CPU0_G2_TX_DN<12>")
	)
	(segment
		(start 110.049056 -235.109766)
		(end 110.088172 -235.086906)
		(width 0.1143)
		(layer "In6.Cu")
		(net "GMI_CPU1_G0_CPU0_G2_TX_DN<12>")
	)
	(segment
		(start 107.275884 -241.562382)
		(end 107.278424 -241.561112)
		(width 0.1143)
		(layer "In6.Cu")
		(net "GMI_CPU1_G0_CPU0_G2_TX_DN<12>")
	)
	(segment
		(start 110.518956 -226.1997)
		(end 110.600998 -226.151694)
		(width 0.1143)
		(layer "In6.Cu")
		(net "GMI_CPU1_G0_CPU0_G2_TX_DN<12>")
	)
	(segment
		(start 363.288834 -239.947196)
		(end 363.290358 -239.948212)
		(width 0.1143)
		(layer "In6.Cu")
		(net "GMI_CPU1_G0_CPU0_G2_TX_DN<12>")
	)
	(segment
		(start 113.371884 -222.93707)
		(end 113.376456 -222.934276)
		(width 0.1143)
		(layer "In6.Cu")
		(net "GMI_CPU1_G0_CPU0_G2_TX_DN<12>")
	)
	(segment
		(start 363.277404 -239.940846)
		(end 363.279944 -239.942116)
		(width 0.1143)
		(layer "In6.Cu")
		(net "GMI_CPU1_G0_CPU0_G2_TX_DN<12>")
	)
	(segment
		(start 364.974124 -242.781328)
		(end 365.056928 -242.864132)
		(width 0.1143)
		(layer "In6.Cu")
		(net "GMI_CPU1_G0_CPU0_G2_TX_DN<12>")
	)
	(segment
		(start 110.049056 -236.729778)
		(end 110.088172 -236.706918)
		(width 0.1143)
		(layer "In6.Cu")
		(net "GMI_CPU1_G0_CPU0_G2_TX_DN<12>")
	)
	(segment
		(start 110.275878 -231.524302)
		(end 110.275624 -231.524302)
		(width 0.1143)
		(layer "In6.Cu")
		(net "GMI_CPU1_G0_CPU0_G2_TX_DN<12>")
	)
	(segment
		(start 110.049056 -228.629972)
		(end 110.088172 -228.607112)
		(width 0.1143)
		(layer "In6.Cu")
		(net "GMI_CPU1_G0_CPU0_G2_TX_DN<12>")
	)
	(segment
		(start 363.326934 -239.278668)
		(end 363.291374 -239.299496)
		(width 0.1143)
		(layer "In6.Cu")
		(net "GMI_CPU1_G0_CPU0_G2_TX_DN<12>")
	)
	(segment
		(start 262.7376 -187.823348)
		(end 303.706784 -188.201808)
		(width 0.14224)
		(layer "In6.Cu")
		(net "GMI_CPU1_G0_CPU0_G2_TX_DN<12>")
	)
	(segment
		(start 117.377464 -216.302082)
		(end 122.990356 -211.911184)
		(width 0.14224)
		(layer "In6.Cu")
		(net "GMI_CPU1_G0_CPU0_G2_TX_DN<12>")
	)
	(segment
		(start 361.372912 -233.446066)
		(end 361.374944 -233.44759)
		(width 0.1143)
		(layer "In6.Cu")
		(net "GMI_CPU1_G0_CPU0_G2_TX_DN<12>")
	)
	(segment
		(start 113.38179 -222.931228)
		(end 113.402618 -222.919036)
		(width 0.1143)
		(layer "In6.Cu")
		(net "GMI_CPU1_G0_CPU0_G2_TX_DN<12>")
	)
	(segment
		(start 106.758994 -242.39982)
		(end 106.79811 -242.37696)
		(width 0.1143)
		(layer "In6.Cu")
		(net "GMI_CPU1_G0_CPU0_G2_TX_DN<12>")
	)
	(segment
		(start 110.051596 -230.248206)
		(end 110.118652 -230.20909)
		(width 0.1143)
		(layer "In6.Cu")
		(net "GMI_CPU1_G0_CPU0_G2_TX_DN<12>")
	)
	(segment
		(start 363.256068 -238.308388)
		(end 363.277404 -238.320834)
		(width 0.1143)
		(layer "In6.Cu")
		(net "GMI_CPU1_G0_CPU0_G2_TX_DN<12>")
	)
	(segment
		(start 239.093756 -198.007986)
		(end 250.57608 -189.96787)
		(width 0.14224)
		(layer "In6.Cu")
		(net "GMI_CPU1_G0_CPU0_G2_TX_DN<12>")
	)
	(segment
		(start 361.220258 -236.383322)
		(end 361.220258 -236.384084)
		(width 0.1143)
		(layer "In6.Cu")
		(net "GMI_CPU1_G0_CPU0_G2_TX_DN<12>")
	)
	(segment
		(start 108.208826 -239.30229)
		(end 108.208064 -239.301782)
		(width 0.1143)
		(layer "In6.Cu")
		(net "GMI_CPU1_G0_CPU0_G2_TX_DN<12>")
	)
	(segment
		(start 107.699048 -240.779808)
		(end 107.738164 -240.756948)
		(width 0.1143)
		(layer "In6.Cu")
		(net "GMI_CPU1_G0_CPU0_G2_TX_DN<12>")
	)
	(segment
		(start 113.376456 -222.934276)
		(end 113.377218 -222.933768)
		(width 0.1143)
		(layer "In6.Cu")
		(net "GMI_CPU1_G0_CPU0_G2_TX_DN<12>")
	)
	(segment
		(start 114.028982 -221.248732)
		(end 113.983262 -221.203012)
		(width 0.1143)
		(layer "In6.Cu")
		(net "GMI_CPU1_G0_CPU0_G2_TX_DN<12>")
	)
	(segment
		(start 110.120684 -229.60076)
		(end 110.088172 -229.581964)
		(width 0.1143)
		(layer "In6.Cu")
		(net "GMI_CPU1_G0_CPU0_G2_TX_DN<12>")
	)
	(segment
		(start 114.028982 -221.702376)
		(end 114.028982 -221.248732)
		(width 0.1143)
		(layer "In6.Cu")
		(net "GMI_CPU1_G0_CPU0_G2_TX_DN<12>")
	)
	(segment
		(start 110.049056 -233.489754)
		(end 110.088172 -233.466894)
		(width 0.1143)
		(layer "In6.Cu")
		(net "GMI_CPU1_G0_CPU0_G2_TX_DN<12>")
	)
	(segment
		(start 364.222284 -241.563398)
		(end 364.223046 -241.563906)
		(width 0.1143)
		(layer "In6.Cu")
		(net "GMI_CPU1_G0_CPU0_G2_TX_DN<12>")
	)
	(segment
		(start 107.278424 -241.561112)
		(end 107.29976 -241.548666)
		(width 0.1143)
		(layer "In6.Cu")
		(net "GMI_CPU1_G0_CPU0_G2_TX_DN<12>")
	)
	(segment
		(start 110.088172 -226.9871)
		(end 110.118652 -226.96932)
		(width 0.1143)
		(layer "In6.Cu")
		(net "GMI_CPU1_G0_CPU0_G2_TX_DN<12>")
	)
	(segment
		(start 361.37723 -236.688884)
		(end 361.446826 -236.729524)
		(width 0.1143)
		(layer "In6.Cu")
		(net "GMI_CPU1_G0_CPU0_G2_TX_DN<12>")
	)
	(segment
		(start 110.120938 -232.840784)
		(end 110.049056 -232.798874)
		(width 0.1143)
		(layer "In6.Cu")
		(net "GMI_CPU1_G0_CPU0_G2_TX_DN<12>")
	)
	(segment
		(start 363.28223 -238.323374)
		(end 363.282992 -238.323882)
		(width 0.1143)
		(layer "In6.Cu")
		(net "GMI_CPU1_G0_CPU0_G2_TX_DN<12>")
	)
	(segment
		(start 361.877102 -237.516162)
		(end 361.877864 -237.51667)
		(width 0.1143)
		(layer "In6.Cu")
		(net "GMI_CPU1_G0_CPU0_G2_TX_DN<12>")
	)
	(segment
		(start 361.875832 -237.5154)
		(end 361.877102 -237.516162)
		(width 0.1143)
		(layer "In6.Cu")
		(net "GMI_CPU1_G0_CPU0_G2_TX_DN<12>")
	)
	(segment
		(start 110.120938 -234.460796)
		(end 110.049056 -234.418886)
		(width 0.1143)
		(layer "In6.Cu")
		(net "GMI_CPU1_G0_CPU0_G2_TX_DN<12>")
	)
	(segment
		(start 110.088172 -228.607112)
		(end 110.118652 -228.589332)
		(width 0.1143)
		(layer "In6.Cu")
		(net "GMI_CPU1_G0_CPU0_G2_TX_DN<12>")
	)
	(segment
		(start 108.205524 -239.948466)
		(end 108.207048 -239.94745)
		(width 0.1143)
		(layer "In6.Cu")
		(net "GMI_CPU1_G0_CPU0_G2_TX_DN<12>")
	)
	(segment
		(start 361.446826 -227.938838)
		(end 361.37723 -227.979478)
		(width 0.1143)
		(layer "In6.Cu")
		(net "GMI_CPU1_G0_CPU0_G2_TX_DN<12>")
	)
	(segment
		(start 108.213652 -238.323628)
		(end 108.214668 -238.32312)
		(width 0.1143)
		(layer "In6.Cu")
		(net "GMI_CPU1_G0_CPU0_G2_TX_DN<12>")
	)
	(segment
		(start 109.61878 -237.516416)
		(end 109.62005 -237.515654)
		(width 0.1143)
		(layer "In6.Cu")
		(net "GMI_CPU1_G0_CPU0_G2_TX_DN<12>")
	)
	(segment
		(start 364.22711 -241.566192)
		(end 364.227872 -241.5667)
		(width 0.1143)
		(layer "In6.Cu")
		(net "GMI_CPU1_G0_CPU0_G2_TX_DN<12>")
	)
	(segment
		(start 361.374944 -234.460542)
		(end 361.372912 -234.462066)
		(width 0.1143)
		(layer "In6.Cu")
		(net "GMI_CPU1_G0_CPU0_G2_TX_DN<12>")
	)
	(segment
		(start 363.288834 -238.327184)
		(end 363.290358 -238.3282)
		(width 0.1143)
		(layer "In6.Cu")
		(net "GMI_CPU1_G0_CPU0_G2_TX_DN<12>")
	)
	(segment
		(start 363.287056 -239.94618)
		(end 363.287818 -239.946688)
		(width 0.1143)
		(layer "In6.Cu")
		(net "GMI_CPU1_G0_CPU0_G2_TX_DN<12>")
	)
	(segment
		(start 108.214668 -239.943132)
		(end 108.215938 -239.94237)
		(width 0.1143)
		(layer "In6.Cu")
		(net "GMI_CPU1_G0_CPU0_G2_TX_DN<12>")
	)
	(segment
		(start 113.983262 -219.696284)
		(end 117.377464 -216.302082)
		(width 0.14224)
		(layer "In6.Cu")
		(net "GMI_CPU1_G0_CPU0_G2_TX_DN<12>")
	)
	(segment
		(start 107.274614 -241.563144)
		(end 107.275884 -241.562382)
		(width 0.1143)
		(layer "In6.Cu")
		(net "GMI_CPU1_G0_CPU0_G2_TX_DN<12>")
	)
	(segment
		(start 108.21289 -238.324136)
		(end 108.213652 -238.323628)
		(width 0.1143)
		(layer "In6.Cu")
		(net "GMI_CPU1_G0_CPU0_G2_TX_DN<12>")
	)
	(segment
		(start 108.205524 -238.328454)
		(end 108.207048 -238.327438)
		(width 0.1143)
		(layer "In6.Cu")
		(net "GMI_CPU1_G0_CPU0_G2_TX_DN<12>")
	)
	(segment
		(start 107.270042 -241.565684)
		(end 107.271566 -241.564922)
		(width 0.1143)
		(layer "In6.Cu")
		(net "GMI_CPU1_G0_CPU0_G2_TX_DN<12>")
	)
	(segment
		(start 360.915458 -226.163632)
		(end 360.966766 -226.19335)
		(width 0.1143)
		(layer "In6.Cu")
		(net "GMI_CPU1_G0_CPU0_G2_TX_DN<12>")
	)
	(segment
		(start 109.618018 -237.516924)
		(end 109.61878 -237.516416)
		(width 0.1143)
		(layer "In6.Cu")
		(net "GMI_CPU1_G0_CPU0_G2_TX_DN<12>")
	)
	(segment
		(start 107.268772 -241.566446)
		(end 107.270042 -241.565684)
		(width 0.1143)
		(layer "In6.Cu")
		(net "GMI_CPU1_G0_CPU0_G2_TX_DN<12>")
	)
	(segment
		(start 114.02949 -221.804484)
		(end 114.02949 -221.702884)
		(width 0.1143)
		(layer "In6.Cu")
		(net "GMI_CPU1_G0_CPU0_G2_TX_DN<12>")
	)
	(segment
		(start 363.28223 -239.943386)
		(end 363.282992 -239.943894)
		(width 0.1143)
		(layer "In6.Cu")
		(net "GMI_CPU1_G0_CPU0_G2_TX_DN<12>")
	)
	(segment
		(start 352.733864 -215.589612)
		(end 356.032308 -218.209368)
		(width 0.14224)
		(layer "In6.Cu")
		(net "GMI_CPU1_G0_CPU0_G2_TX_DN<12>")
	)
	(segment
		(start 109.62005 -237.515654)
		(end 109.649768 -237.498636)
		(width 0.1143)
		(layer "In6.Cu")
		(net "GMI_CPU1_G0_CPU0_G2_TX_DN<12>")
	)
	(segment
		(start 361.374944 -235.067602)
		(end 361.40771 -235.086652)
		(width 0.1143)
		(layer "In6.Cu")
		(net "GMI_CPU1_G0_CPU0_G2_TX_DN<12>")
	)
	(segment
		(start 162.233102 -188.265308)
		(end 207.137762 -188.0743)
		(width 0.14224)
		(layer "In6.Cu")
		(net "GMI_CPU1_G0_CPU0_G2_TX_DN<12>")
	)
	(segment
		(start 357.51262 -221.202758)
		(end 357.4669 -221.248478)
		(width 0.1143)
		(layer "In6.Cu")
		(net "GMI_CPU1_G0_CPU0_G2_TX_DN<12>")
	)
	(segment
		(start 361.446826 -236.038644)
		(end 361.3785 -236.078522)
		(width 0.1143)
		(layer "In6.Cu")
		(net "GMI_CPU1_G0_CPU0_G2_TX_DN<12>")
	)
	(segment
		(start 110.088172 -236.706918)
		(end 110.118652 -236.689138)
		(width 0.1143)
		(layer "In6.Cu")
		(net "GMI_CPU1_G0_CPU0_G2_TX_DN<12>")
	)
	(segment
		(start 361.220258 -231.524048)
		(end 361.220004 -231.524048)
		(width 0.1143)
		(layer "In6.Cu")
		(net "GMI_CPU1_G0_CPU0_G2_TX_DN<12>")
	)
	(segment
		(start 110.049056 -231.869742)
		(end 110.120938 -231.827832)
		(width 0.1143)
		(layer "In6.Cu")
		(net "GMI_CPU1_G0_CPU0_G2_TX_DN<12>")
	)
	(segment
		(start 357.623618 -222.10903)
		(end 357.693214 -222.14967)
		(width 0.1143)
		(layer "In6.Cu")
		(net "GMI_CPU1_G0_CPU0_G2_TX_DN<12>")
	)
	(segment
		(start 110.088172 -227.961952)
		(end 110.049056 -227.939092)
		(width 0.1143)
		(layer "In6.Cu")
		(net "GMI_CPU1_G0_CPU0_G2_TX_DN<12>")
	)
	(segment
		(start 363.282992 -239.943894)
		(end 363.284262 -239.944656)
		(width 0.1143)
		(layer "In6.Cu")
		(net "GMI_CPU1_G0_CPU0_G2_TX_DN<12>")
	)
	(segment
		(start 361.446826 -234.418632)
		(end 361.374944 -234.460542)
		(width 0.1143)
		(layer "In6.Cu")
		(net "GMI_CPU1_G0_CPU0_G2_TX_DN<12>")
	)
	(segment
		(start 110.12297 -232.842308)
		(end 110.120938 -232.840784)
		(width 0.1143)
		(layer "In6.Cu")
		(net "GMI_CPU1_G0_CPU0_G2_TX_DN<12>")
	)
	(segment
		(start 108.215938 -239.94237)
		(end 108.218478 -239.9411)
		(width 0.1143)
		(layer "In6.Cu")
		(net "GMI_CPU1_G0_CPU0_G2_TX_DN<12>")
	)
	(segment
		(start 108.168948 -238.34979)
		(end 108.205524 -238.328454)
		(width 0.1143)
		(layer "In6.Cu")
		(net "GMI_CPU1_G0_CPU0_G2_TX_DN<12>")
	)
	(segment
		(start 360.688382 -225.701352)
		(end 360.688636 -225.701098)
		(width 0.1143)
		(layer "In6.Cu")
		(net "GMI_CPU1_G0_CPU0_G2_TX_DN<12>")
	)
	(segment
		(start 113.983262 -221.174564)
		(end 113.983262 -219.696284)
		(width 0.14224)
		(layer "In6.Cu")
		(net "GMI_CPU1_G0_CPU0_G2_TX_DN<12>")
	)
	(segment
		(start 108.207048 -239.301274)
		(end 108.205524 -239.300258)
		(width 0.1143)
		(layer "In6.Cu")
		(net "GMI_CPU1_G0_CPU0_G2_TX_DN<12>")
	)
	(segment
		(start 363.290358 -238.3282)
		(end 363.326934 -238.349536)
		(width 0.1143)
		(layer "In6.Cu")
		(net "GMI_CPU1_G0_CPU0_G2_TX_DN<12>")
	)
	(arc
		(start 110.120938 -231.827832)
		(mid 110.23366 -231.694068)
		(end 110.275878 -231.524302)
		(width 0.1143)
		(layer "In6.Cu")
		(net "GMI_CPU1_G0_CPU0_G2_TX_DN<12>")
	)
	(arc
		(start 106.521758 -242.781582)
		(mid 106.523546 -242.770133)
		(end 106.525568 -242.758722)
		(width 0.1143)
		(layer "In6.Cu")
		(net "GMI_CPU1_G0_CPU0_G2_TX_DN<12>")
	)
	(arc
		(start 110.118652 -236.689138)
		(mid 110.234079 -236.555762)
		(end 110.275624 -236.384338)
		(width 0.1143)
		(layer "In6.Cu")
		(net "GMI_CPU1_G0_CPU0_G2_TX_DN<12>")
	)
	(arc
		(start 106.829606 -242.358418)
		(mid 106.944374 -242.225246)
		(end 106.985816 -242.05438)
		(width 0.1143)
		(layer "In6.Cu")
		(net "GMI_CPU1_G0_CPU0_G2_TX_DN<12>")
	)
	(arc
		(start 360.725466 -225.811842)
		(mid 360.744201 -225.873732)
		(end 360.760518 -225.936302)
		(width 0.1143)
		(layer "In6.Cu")
		(net "GMI_CPU1_G0_CPU0_G2_TX_DN<12>")
	)
	(arc
		(start 363.326934 -238.349536)
		(mid 363.570261 -238.814102)
		(end 363.326934 -239.278668)
		(width 0.1143)
		(layer "In6.Cu")
		(net "GMI_CPU1_G0_CPU0_G2_TX_DN<12>")
	)
	(arc
		(start 113.402618 -222.919036)
		(mid 113.51782 -222.78573)
		(end 113.559336 -222.61449)
		(width 0.1143)
		(layer "In6.Cu")
		(net "GMI_CPU1_G0_CPU0_G2_TX_DN<12>")
	)
	(arc
		(start 110.12297 -235.066332)
		(mid 110.27715 -234.764326)
		(end 110.12297 -234.46232)
		(width 0.1143)
		(layer "In6.Cu")
		(net "GMI_CPU1_G0_CPU0_G2_TX_DN<12>")
	)
	(arc
		(start 113.901728 -222.085916)
		(mid 113.996007 -221.958999)
		(end 114.02949 -221.804484)
		(width 0.1143)
		(layer "In6.Cu")
		(net "GMI_CPU1_G0_CPU0_G2_TX_DN<12>")
	)
	(arc
		(start 106.525568 -242.758722)
		(mid 106.607001 -242.556324)
		(end 106.758994 -242.39982)
		(width 0.1143)
		(layer "In6.Cu")
		(net "GMI_CPU1_G0_CPU0_G2_TX_DN<12>")
	)
	(arc
		(start 110.275878 -226.66452)
		(mid 110.340266 -226.402227)
		(end 110.518956 -226.1997)
		(width 0.1143)
		(layer "In6.Cu")
		(net "GMI_CPU1_G0_CPU0_G2_TX_DN<12>")
	)
	(arc
		(start 360.989118 -226.207828)
		(mid 361.071697 -226.282018)
		(end 361.138216 -226.370896)
		(width 0.1143)
		(layer "In6.Cu")
		(net "GMI_CPU1_G0_CPU0_G2_TX_DN<12>")
	)
	(arc
		(start 107.925616 -240.434368)
		(mid 107.990131 -240.172149)
		(end 108.168948 -239.969802)
		(width 0.1143)
		(layer "In6.Cu")
		(net "GMI_CPU1_G0_CPU0_G2_TX_DN<12>")
	)
	(arc
		(start 111.465106 -224.714308)
		(mid 111.692843 -224.410796)
		(end 111.933482 -224.117408)
		(width 0.1143)
		(layer "In6.Cu")
		(net "GMI_CPU1_G0_CPU0_G2_TX_DN<12>")
	)
	(arc
		(start 110.049056 -227.939092)
		(mid 109.805729 -227.474526)
		(end 110.049056 -227.00996)
		(width 0.1143)
		(layer "In6.Cu")
		(net "GMI_CPU1_G0_CPU0_G2_TX_DN<12>")
	)
	(arc
		(start 363.570266 -240.434114)
		(mid 363.611815 -240.605536)
		(end 363.727238 -240.738914)
		(width 0.1143)
		(layer "In6.Cu")
		(net "GMI_CPU1_G0_CPU0_G2_TX_DN<12>")
	)
	(arc
		(start 361.446826 -227.009706)
		(mid 361.690153 -227.474272)
		(end 361.446826 -227.938838)
		(width 0.1143)
		(layer "In6.Cu")
		(net "GMI_CPU1_G0_CPU0_G2_TX_DN<12>")
	)
	(arc
		(start 358.562148 -223.190816)
		(mid 358.653105 -223.251003)
		(end 358.736646 -223.321118)
		(width 0.1143)
		(layer "In6.Cu")
		(net "GMI_CPU1_G0_CPU0_G2_TX_DN<12>")
	)
	(arc
		(start 362.85678 -237.53953)
		(mid 363.035593 -237.74188)
		(end 363.100112 -238.004096)
		(width 0.1143)
		(layer "In6.Cu")
		(net "GMI_CPU1_G0_CPU0_G2_TX_DN<12>")
	)
	(arc
		(start 359.401872 -223.946212)
		(mid 359.450092 -223.993806)
		(end 359.495598 -224.044002)
		(width 0.1143)
		(layer "In6.Cu")
		(net "GMI_CPU1_G0_CPU0_G2_TX_DN<12>")
	)
	(arc
		(start 360.688636 -225.701098)
		(mid 360.707314 -225.756382)
		(end 360.725466 -225.811842)
		(width 0.1143)
		(layer "In6.Cu")
		(net "GMI_CPU1_G0_CPU0_G2_TX_DN<12>")
	)
	(arc
		(start 109.649768 -237.498636)
		(mid 109.764444 -237.365302)
		(end 109.805724 -237.194344)
		(width 0.1143)
		(layer "In6.Cu")
		(net "GMI_CPU1_G0_CPU0_G2_TX_DN<12>")
	)
	(arc
		(start 364.264194 -241.587782)
		(mid 364.444846 -241.790527)
		(end 364.510066 -242.054126)
		(width 0.1143)
		(layer "In6.Cu")
		(net "GMI_CPU1_G0_CPU0_G2_TX_DN<12>")
	)
	(arc
		(start 112.306608 -223.728788)
		(mid 112.8089 -223.31232)
		(end 113.351056 -222.949262)
		(width 0.1143)
		(layer "In6.Cu")
		(net "GMI_CPU1_G0_CPU0_G2_TX_DN<12>")
	)
	(arc
		(start 362.251752 -237.51667)
		(mid 362.534708 -237.440493)
		(end 362.817664 -237.51667)
		(width 0.1143)
		(layer "In6.Cu")
		(net "GMI_CPU1_G0_CPU0_G2_TX_DN<12>")
	)
	(arc
		(start 108.239814 -238.308642)
		(mid 108.35449 -238.175308)
		(end 108.39577 -238.00435)
		(width 0.1143)
		(layer "In6.Cu")
		(net "GMI_CPU1_G0_CPU0_G2_TX_DN<12>")
	)
	(arc
		(start 360.497882 -225.353118)
		(mid 360.530238 -225.400241)
		(end 360.559858 -225.44913)
		(width 0.1143)
		(layer "In6.Cu")
		(net "GMI_CPU1_G0_CPU0_G2_TX_DN<12>")
	)
	(arc
		(start 110.118652 -226.96932)
		(mid 110.234079 -226.835944)
		(end 110.275624 -226.66452)
		(width 0.1143)
		(layer "In6.Cu")
		(net "GMI_CPU1_G0_CPU0_G2_TX_DN<12>")
	)
	(arc
		(start 106.985816 -242.05438)
		(mid 107.051052 -241.790789)
		(end 107.231688 -241.588036)
		(width 0.1143)
		(layer "In6.Cu")
		(net "GMI_CPU1_G0_CPU0_G2_TX_DN<12>")
	)
	(arc
		(start 364.970314 -242.758468)
		(mid 364.972337 -242.769878)
		(end 364.974124 -242.781328)
		(width 0.1143)
		(layer "In6.Cu")
		(net "GMI_CPU1_G0_CPU0_G2_TX_DN<12>")
	)
	(arc
		(start 360.966766 -226.19335)
		(mid 360.978136 -226.200289)
		(end 360.989118 -226.207828)
		(width 0.1143)
		(layer "In6.Cu")
		(net "GMI_CPU1_G0_CPU0_G2_TX_DN<12>")
	)
	(arc
		(start 359.779316 -224.37725)
		(mid 359.819077 -224.425817)
		(end 359.85704 -224.475802)
		(width 0.1143)
		(layer "In6.Cu")
		(net "GMI_CPU1_G0_CPU0_G2_TX_DN<12>")
	)
	(arc
		(start 108.39577 -238.00435)
		(mid 108.460285 -237.742131)
		(end 108.639102 -237.539784)
		(width 0.1143)
		(layer "In6.Cu")
		(net "GMI_CPU1_G0_CPU0_G2_TX_DN<12>")
	)
	(arc
		(start 110.049056 -232.798874)
		(mid 109.805729 -232.334308)
		(end 110.049056 -231.869742)
		(width 0.1143)
		(layer "In6.Cu")
		(net "GMI_CPU1_G0_CPU0_G2_TX_DN<12>")
	)
	(arc
		(start 361.372912 -232.842054)
		(mid 361.218732 -233.14406)
		(end 361.372912 -233.446066)
		(width 0.1143)
		(layer "In6.Cu")
		(net "GMI_CPU1_G0_CPU0_G2_TX_DN<12>")
	)
	(arc
		(start 361.446826 -233.4895)
		(mid 361.690153 -233.954066)
		(end 361.446826 -234.418632)
		(width 0.1143)
		(layer "In6.Cu")
		(net "GMI_CPU1_G0_CPU0_G2_TX_DN<12>")
	)
	(arc
		(start 364.040166 -241.24412)
		(mid 364.081421 -241.415091)
		(end 364.196122 -241.548412)
		(width 0.1143)
		(layer "In6.Cu")
		(net "GMI_CPU1_G0_CPU0_G2_TX_DN<12>")
	)
	(arc
		(start 113.559336 -222.61449)
		(mid 113.622187 -222.355727)
		(end 113.796572 -222.154496)
		(width 0.1143)
		(layer "In6.Cu")
		(net "GMI_CPU1_G0_CPU0_G2_TX_DN<12>")
	)
	(arc
		(start 361.690158 -237.19409)
		(mid 361.731413 -237.365061)
		(end 361.846114 -237.498382)
		(width 0.1143)
		(layer "In6.Cu")
		(net "GMI_CPU1_G0_CPU0_G2_TX_DN<12>")
	)
	(arc
		(start 357.466392 -221.80423)
		(mid 357.499878 -221.958744)
		(end 357.594154 -222.085662)
		(width 0.1143)
		(layer "In6.Cu")
		(net "GMI_CPU1_G0_CPU0_G2_TX_DN<12>")
	)
	(arc
		(start 107.29976 -241.548666)
		(mid 107.414436 -241.415332)
		(end 107.455716 -241.244374)
		(width 0.1143)
		(layer "In6.Cu")
		(net "GMI_CPU1_G0_CPU0_G2_TX_DN<12>")
	)
	(arc
		(start 106.827828 -242.359688)
		(mid 106.828718 -242.359054)
		(end 106.829606 -242.358418)
		(width 0.1143)
		(layer "In6.Cu")
		(net "GMI_CPU1_G0_CPU0_G2_TX_DN<12>")
	)
	(arc
		(start 364.736888 -242.399566)
		(mid 364.888875 -242.556074)
		(end 364.970314 -242.758468)
		(width 0.1143)
		(layer "In6.Cu")
		(net "GMI_CPU1_G0_CPU0_G2_TX_DN<12>")
	)
	(arc
		(start 108.239814 -239.928654)
		(mid 108.395742 -239.624362)
		(end 108.239814 -239.32007)
		(width 0.1143)
		(layer "In6.Cu")
		(net "GMI_CPU1_G0_CPU0_G2_TX_DN<12>")
	)
	(arc
		(start 357.594154 -222.085662)
		(mid 357.608589 -222.097721)
		(end 357.623618 -222.10903)
		(width 0.1143)
		(layer "In6.Cu")
		(net "GMI_CPU1_G0_CPU0_G2_TX_DN<12>")
	)
	(arc
		(start 361.3785 -236.078522)
		(mid 361.266032 -236.213604)
		(end 361.220258 -236.383322)
		(width 0.1143)
		(layer "In6.Cu")
		(net "GMI_CPU1_G0_CPU0_G2_TX_DN<12>")
	)
	(arc
		(start 360.870246 -226.128072)
		(mid 360.891941 -226.147011)
		(end 360.915458 -226.163632)
		(width 0.1143)
		(layer "In6.Cu")
		(net "GMI_CPU1_G0_CPU0_G2_TX_DN<12>")
	)
	(arc
		(start 361.375198 -229.600506)
		(mid 361.261269 -229.733653)
		(end 361.220258 -229.904036)
		(width 0.1143)
		(layer "In6.Cu")
		(net "GMI_CPU1_G0_CPU0_G2_TX_DN<12>")
	)
	(arc
		(start 361.37723 -227.979478)
		(mid 361.220253 -228.284278)
		(end 361.37723 -228.589078)
		(width 0.1143)
		(layer "In6.Cu")
		(net "GMI_CPU1_G0_CPU0_G2_TX_DN<12>")
	)
	(arc
		(start 113.872264 -222.109284)
		(mid 113.887286 -222.097966)
		(end 113.901728 -222.085916)
		(width 0.1143)
		(layer "In6.Cu")
		(net "GMI_CPU1_G0_CPU0_G2_TX_DN<12>")
	)
	(arc
		(start 107.768644 -240.739168)
		(mid 107.884071 -240.605792)
		(end 107.925616 -240.434368)
		(width 0.1143)
		(layer "In6.Cu")
		(net "GMI_CPU1_G0_CPU0_G2_TX_DN<12>")
	)
	(arc
		(start 361.446826 -231.869488)
		(mid 361.690153 -232.334054)
		(end 361.446826 -232.79862)
		(width 0.1143)
		(layer "In6.Cu")
		(net "GMI_CPU1_G0_CPU0_G2_TX_DN<12>")
	)
	(arc
		(start 357.693214 -222.14967)
		(mid 357.872027 -222.35202)
		(end 357.936546 -222.614236)
		(width 0.1143)
		(layer "In6.Cu")
		(net "GMI_CPU1_G0_CPU0_G2_TX_DN<12>")
	)
	(arc
		(start 361.220258 -229.904036)
		(mid 361.261807 -230.075458)
		(end 361.37723 -230.208836)
		(width 0.1143)
		(layer "In6.Cu")
		(net "GMI_CPU1_G0_CPU0_G2_TX_DN<12>")
	)
	(arc
		(start 109.805724 -230.71455)
		(mid 109.87096 -230.450959)
		(end 110.051596 -230.248206)
		(width 0.1143)
		(layer "In6.Cu")
		(net "GMI_CPU1_G0_CPU0_G2_TX_DN<12>")
	)
	(arc
		(start 360.760518 -225.936302)
		(mid 360.801847 -226.039925)
		(end 360.870246 -226.128072)
		(width 0.1143)
		(layer "In6.Cu")
		(net "GMI_CPU1_G0_CPU0_G2_TX_DN<12>")
	)
	(arc
		(start 363.326934 -239.969548)
		(mid 363.505747 -240.171898)
		(end 363.570266 -240.434114)
		(width 0.1143)
		(layer "In6.Cu")
		(net "GMI_CPU1_G0_CPU0_G2_TX_DN<12>")
	)
	(arc
		(start 360.619294 -225.553524)
		(mid 360.656854 -225.626029)
		(end 360.688382 -225.701352)
		(width 0.1143)
		(layer "In6.Cu")
		(net "GMI_CPU1_G0_CPU0_G2_TX_DN<12>")
	)
	(arc
		(start 113.351056 -222.949262)
		(mid 113.36145 -222.943133)
		(end 113.371884 -222.93707)
		(width 0.1143)
		(layer "In6.Cu")
		(net "GMI_CPU1_G0_CPU0_G2_TX_DN<12>")
	)
	(arc
		(start 361.446826 -235.109512)
		(mid 361.690153 -235.574078)
		(end 361.446826 -236.038644)
		(width 0.1143)
		(layer "In6.Cu")
		(net "GMI_CPU1_G0_CPU0_G2_TX_DN<12>")
	)
	(arc
		(start 361.372912 -234.462066)
		(mid 361.218732 -234.764072)
		(end 361.372912 -235.066078)
		(width 0.1143)
		(layer "In6.Cu")
		(net "GMI_CPU1_G0_CPU0_G2_TX_DN<12>")
	)
	(arc
		(start 361.220004 -231.524048)
		(mid 361.262182 -231.693834)
		(end 361.374944 -231.827578)
		(width 0.1143)
		(layer "In6.Cu")
		(net "GMI_CPU1_G0_CPU0_G2_TX_DN<12>")
	)
	(arc
		(start 110.118652 -230.20909)
		(mid 110.234079 -230.075714)
		(end 110.275624 -229.90429)
		(width 0.1143)
		(layer "In6.Cu")
		(net "GMI_CPU1_G0_CPU0_G2_TX_DN<12>")
	)
	(arc
		(start 109.805724 -237.194344)
		(mid 109.870239 -236.932125)
		(end 110.049056 -236.729778)
		(width 0.1143)
		(layer "In6.Cu")
		(net "GMI_CPU1_G0_CPU0_G2_TX_DN<12>")
	)
	(arc
		(start 111.172498 -225.143568)
		(mid 111.315759 -224.926863)
		(end 111.465106 -224.714308)
		(width 0.1143)
		(layer "In6.Cu")
		(net "GMI_CPU1_G0_CPU0_G2_TX_DN<12>")
	)
	(arc
		(start 110.049056 -234.418886)
		(mid 109.805729 -233.95432)
		(end 110.049056 -233.489754)
		(width 0.1143)
		(layer "In6.Cu")
		(net "GMI_CPU1_G0_CPU0_G2_TX_DN<12>")
	)
	(arc
		(start 110.049056 -236.038898)
		(mid 109.805729 -235.574332)
		(end 110.049056 -235.109766)
		(width 0.1143)
		(layer "In6.Cu")
		(net "GMI_CPU1_G0_CPU0_G2_TX_DN<12>")
	)
	(arc
		(start 361.446826 -228.629718)
		(mid 361.690153 -229.094284)
		(end 361.446826 -229.55885)
		(width 0.1143)
		(layer "In6.Cu")
		(net "GMI_CPU1_G0_CPU0_G2_TX_DN<12>")
	)
	(arc
		(start 357.936546 -222.614236)
		(mid 357.978095 -222.785658)
		(end 358.093518 -222.919036)
		(width 0.1143)
		(layer "In6.Cu")
		(net "GMI_CPU1_G0_CPU0_G2_TX_DN<12>")
	)
	(arc
		(start 363.100112 -238.004096)
		(mid 363.141367 -238.175067)
		(end 363.256068 -238.308388)
		(width 0.1143)
		(layer "In6.Cu")
		(net "GMI_CPU1_G0_CPU0_G2_TX_DN<12>")
	)
	(arc
		(start 111.935514 -224.114868)
		(mid 112.115226 -223.916219)
		(end 112.306608 -223.728788)
		(width 0.1143)
		(layer "In6.Cu")
		(net "GMI_CPU1_G0_CPU0_G2_TX_DN<12>")
	)
	(arc
		(start 110.275624 -229.90429)
		(mid 110.234658 -229.733884)
		(end 110.120684 -229.60076)
		(width 0.1143)
		(layer "In6.Cu")
		(net "GMI_CPU1_G0_CPU0_G2_TX_DN<12>")
	)
	(arc
		(start 364.510066 -242.054126)
		(mid 364.551445 -242.225024)
		(end 364.666276 -242.358164)
		(width 0.1143)
		(layer "In6.Cu")
		(net "GMI_CPU1_G0_CPU0_G2_TX_DN<12>")
	)
	(arc
		(start 364.666276 -242.358164)
		(mid 364.667164 -242.358801)
		(end 364.668054 -242.359434)
		(width 0.1143)
		(layer "In6.Cu")
		(net "GMI_CPU1_G0_CPU0_G2_TX_DN<12>")
	)
	(arc
		(start 361.138216 -226.370896)
		(mid 361.199404 -226.511945)
		(end 361.220258 -226.664266)
		(width 0.1143)
		(layer "In6.Cu")
		(net "GMI_CPU1_G0_CPU0_G2_TX_DN<12>")
	)
	(arc
		(start 361.877864 -237.51667)
		(mid 362.064808 -237.566925)
		(end 362.251752 -237.51667)
		(width 0.1143)
		(layer "In6.Cu")
		(net "GMI_CPU1_G0_CPU0_G2_TX_DN<12>")
	)
	(arc
		(start 109.24413 -237.516924)
		(mid 109.431074 -237.567179)
		(end 109.618018 -237.516924)
		(width 0.1143)
		(layer "In6.Cu")
		(net "GMI_CPU1_G0_CPU0_G2_TX_DN<12>")
	)
	(arc
		(start 110.049056 -231.179116)
		(mid 109.870243 -230.976766)
		(end 109.805724 -230.71455)
		(width 0.1143)
		(layer "In6.Cu")
		(net "GMI_CPU1_G0_CPU0_G2_TX_DN<12>")
	)
	(arc
		(start 108.168948 -239.278922)
		(mid 107.925621 -238.814356)
		(end 108.168948 -238.34979)
		(width 0.1143)
		(layer "In6.Cu")
		(net "GMI_CPU1_G0_CPU0_G2_TX_DN<12>")
	)
	(arc
		(start 361.375198 -231.220518)
		(mid 361.261269 -231.353665)
		(end 361.220258 -231.524048)
		(width 0.1143)
		(layer "In6.Cu")
		(net "GMI_CPU1_G0_CPU0_G2_TX_DN<12>")
	)
	(arc
		(start 361.690158 -230.714296)
		(mid 361.625643 -230.976515)
		(end 361.446826 -231.178862)
		(width 0.1143)
		(layer "In6.Cu")
		(net "GMI_CPU1_G0_CPU0_G2_TX_DN<12>")
	)
	(arc
		(start 363.796834 -240.779554)
		(mid 363.975647 -240.981904)
		(end 364.040166 -241.24412)
		(width 0.1143)
		(layer "In6.Cu")
		(net "GMI_CPU1_G0_CPU0_G2_TX_DN<12>")
	)
	(arc
		(start 110.12297 -233.44632)
		(mid 110.27715 -233.144314)
		(end 110.12297 -232.842308)
		(width 0.1143)
		(layer "In6.Cu")
		(net "GMI_CPU1_G0_CPU0_G2_TX_DN<12>")
	)
	(arc
		(start 361.446826 -236.729524)
		(mid 361.625639 -236.931874)
		(end 361.690158 -237.19409)
		(width 0.1143)
		(layer "In6.Cu")
		(net "GMI_CPU1_G0_CPU0_G2_TX_DN<12>")
	)
	(arc
		(start 113.796572 -222.154496)
		(mid 113.799612 -222.1522)
		(end 113.802668 -222.149924)
		(width 0.1143)
		(layer "In6.Cu")
		(net "GMI_CPU1_G0_CPU0_G2_TX_DN<12>")
	)
	(arc
		(start 110.600998 -226.151694)
		(mid 110.684749 -226.081551)
		(end 110.740952 -225.987864)
		(width 0.1143)
		(layer "In6.Cu")
		(net "GMI_CPU1_G0_CPU0_G2_TX_DN<12>")
	)
	(arc
		(start 361.444286 -230.247952)
		(mid 361.624938 -230.450697)
		(end 361.690158 -230.714296)
		(width 0.1143)
		(layer "In6.Cu")
		(net "GMI_CPU1_G0_CPU0_G2_TX_DN<12>")
	)
	(arc
		(start 110.118652 -228.589332)
		(mid 110.275629 -228.284532)
		(end 110.118652 -227.979732)
		(width 0.1143)
		(layer "In6.Cu")
		(net "GMI_CPU1_G0_CPU0_G2_TX_DN<12>")
	)
	(arc
		(start 363.256068 -239.319816)
		(mid 363.10014 -239.624108)
		(end 363.256068 -239.9284)
		(width 0.1143)
		(layer "In6.Cu")
		(net "GMI_CPU1_G0_CPU0_G2_TX_DN<12>")
	)
	(arc
		(start 110.275624 -231.524302)
		(mid 110.234658 -231.353896)
		(end 110.120684 -231.220772)
		(width 0.1143)
		(layer "In6.Cu")
		(net "GMI_CPU1_G0_CPU0_G2_TX_DN<12>")
	)
	(arc
		(start 107.455716 -241.244374)
		(mid 107.520231 -240.982155)
		(end 107.699048 -240.779808)
		(width 0.1143)
		(layer "In6.Cu")
		(net "GMI_CPU1_G0_CPU0_G2_TX_DN<12>")
	)
	(arc
		(start 108.678218 -237.516924)
		(mid 108.961174 -237.440747)
		(end 109.24413 -237.516924)
		(width 0.1143)
		(layer "In6.Cu")
		(net "GMI_CPU1_G0_CPU0_G2_TX_DN<12>")
	)
	(arc
		(start 110.049056 -229.559104)
		(mid 109.805729 -229.094538)
		(end 110.049056 -228.629972)
		(width 0.1143)
		(layer "In6.Cu")
		(net "GMI_CPU1_G0_CPU0_G2_TX_DN<12>")
	)
	(arc
		(start 361.220258 -236.384084)
		(mid 361.261807 -236.555506)
		(end 361.37723 -236.688884)
		(width 0.1143)
		(layer "In6.Cu")
		(net "GMI_CPU1_G0_CPU0_G2_TX_DN<12>")
	)
	(arc
		(start 110.275624 -236.383576)
		(mid 110.229892 -236.213836)
		(end 110.117382 -236.078776)
		(width 0.1143)
		(layer "In6.Cu")
		(net "GMI_CPU1_G0_CPU0_G2_TX_DN<12>")
	)
	(arc
		(start 361.220258 -226.664266)
		(mid 361.261807 -226.835688)
		(end 361.37723 -226.969066)
		(width 0.1143)
		(layer "In6.Cu")
		(net "GMI_CPU1_G0_CPU0_G2_TX_DN<12>")
	)
	(segment
		(start 364.888018 -238.270034)
		(end 365.35487 -238.004096)
		(width 0.12954)
		(layer "F.Cu")
		(net "GMI_CPU1_G0_CPU0_G2_TX_DN<11>")
	)
	(segment
		(start 106.607864 -238.270288)
		(end 106.141012 -238.00435)
		(width 0.12954)
		(layer "F.Cu")
		(net "GMI_CPU1_G0_CPU0_G2_TX_DN<11>")
	)
	(segment
		(start 363.284262 -235.08462)
		(end 363.285786 -235.085382)
		(width 0.1143)
		(layer "In6.Cu")
		(net "GMI_CPU1_G0_CPU0_G2_TX_DN<11>")
	)
	(segment
		(start 108.208826 -235.086398)
		(end 108.210096 -235.085636)
		(width 0.1143)
		(layer "In6.Cu")
		(net "GMI_CPU1_G0_CPU0_G2_TX_DN<11>")
	)
	(segment
		(start 363.287056 -227.962206)
		(end 363.285786 -227.962968)
		(width 0.1143)
		(layer "In6.Cu")
		(net "GMI_CPU1_G0_CPU0_G2_TX_DN<11>")
	)
	(segment
		(start 108.207048 -233.467402)
		(end 108.208064 -233.466894)
		(width 0.1143)
		(layer "In6.Cu")
		(net "GMI_CPU1_G0_CPU0_G2_TX_DN<11>")
	)
	(segment
		(start 110.989872 -222.149924)
		(end 111.060738 -222.108776)
		(width 0.1143)
		(layer "In6.Cu")
		(net "GMI_CPU1_G0_CPU0_G2_TX_DN<11>")
	)
	(segment
		(start 363.290358 -231.848152)
		(end 363.326934 -231.869488)
		(width 0.1143)
		(layer "In6.Cu")
		(net "GMI_CPU1_G0_CPU0_G2_TX_DN<11>")
	)
	(segment
		(start 108.168948 -233.489754)
		(end 108.207048 -233.467402)
		(width 0.1143)
		(layer "In6.Cu")
		(net "GMI_CPU1_G0_CPU0_G2_TX_DN<11>")
	)
	(segment
		(start 363.256068 -226.968558)
		(end 363.280706 -226.982782)
		(width 0.1143)
		(layer "In6.Cu")
		(net "GMI_CPU1_G0_CPU0_G2_TX_DN<11>")
	)
	(segment
		(start 107.738164 -235.896912)
		(end 107.768644 -235.879132)
		(width 0.1143)
		(layer "In6.Cu")
		(net "GMI_CPU1_G0_CPU0_G2_TX_DN<11>")
	)
	(segment
		(start 364.698788 -237.517178)
		(end 364.700312 -237.518194)
		(width 0.1143)
		(layer "In6.Cu")
		(net "GMI_CPU1_G0_CPU0_G2_TX_DN<11>")
	)
	(segment
		(start 312.316622 -187.438538)
		(end 312.316368 -187.438538)
		(width 0.14224)
		(layer "In6.Cu")
		(net "GMI_CPU1_G0_CPU0_G2_TX_DN<11>")
	)
	(segment
		(start 108.215176 -233.46283)
		(end 108.239814 -233.448606)
		(width 0.1143)
		(layer "In6.Cu")
		(net "GMI_CPU1_G0_CPU0_G2_TX_DN<11>")
	)
	(segment
		(start 360.435144 -222.108522)
		(end 360.50601 -222.14967)
		(width 0.1143)
		(layer "In6.Cu")
		(net "GMI_CPU1_G0_CPU0_G2_TX_DN<11>")
	)
	(segment
		(start 360.938064 -222.937324)
		(end 360.939588 -222.93834)
		(width 0.1143)
		(layer "In6.Cu")
		(net "GMI_CPU1_G0_CPU0_G2_TX_DN<11>")
	)
	(segment
		(start 361.876848 -224.55632)
		(end 361.914948 -224.578672)
		(width 0.1143)
		(layer "In6.Cu")
		(net "GMI_CPU1_G0_CPU0_G2_TX_DN<11>")
	)
	(segment
		(start 108.207048 -231.84739)
		(end 108.208064 -231.846882)
		(width 0.1143)
		(layer "In6.Cu")
		(net "GMI_CPU1_G0_CPU0_G2_TX_DN<11>")
	)
	(segment
		(start 108.208064 -229.581964)
		(end 108.168948 -229.559104)
		(width 0.1143)
		(layer "In6.Cu")
		(net "GMI_CPU1_G0_CPU0_G2_TX_DN<11>")
	)
	(segment
		(start 108.208064 -234.441746)
		(end 108.207048 -234.441238)
		(width 0.1143)
		(layer "In6.Cu")
		(net "GMI_CPU1_G0_CPU0_G2_TX_DN<11>")
	)
	(segment
		(start 363.287056 -232.821988)
		(end 363.285786 -232.82275)
		(width 0.1143)
		(layer "In6.Cu")
		(net "GMI_CPU1_G0_CPU0_G2_TX_DN<11>")
	)
	(segment
		(start 108.208064 -228.607112)
		(end 108.208826 -228.606604)
		(width 0.1143)
		(layer "In6.Cu")
		(net "GMI_CPU1_G0_CPU0_G2_TX_DN<11>")
	)
	(segment
		(start 363.281722 -228.603302)
		(end 363.282484 -228.60381)
		(width 0.1143)
		(layer "In6.Cu")
		(net "GMI_CPU1_G0_CPU0_G2_TX_DN<11>")
	)
	(segment
		(start 235.598462 -183.801258)
		(end 235.598462 -183.801004)
		(width 0.14224)
		(layer "In6.Cu")
		(net "GMI_CPU1_G0_CPU0_G2_TX_DN<11>")
	)
	(segment
		(start 307.30825 -184.463944)
		(end 312.316622 -187.438538)
		(width 0.14224)
		(layer "In6.Cu")
		(net "GMI_CPU1_G0_CPU0_G2_TX_DN<11>")
	)
	(segment
		(start 106.141012 -238.00435)
		(end 106.438954 -238.00435)
		(width 0.1143)
		(layer "In6.Cu")
		(net "GMI_CPU1_G0_CPU0_G2_TX_DN<11>")
	)
	(segment
		(start 360.931714 -222.933768)
		(end 360.93273 -222.934276)
		(width 0.1143)
		(layer "In6.Cu")
		(net "GMI_CPU1_G0_CPU0_G2_TX_DN<11>")
	)
	(segment
		(start 110.560866 -222.9358)
		(end 110.56239 -222.935038)
		(width 0.1143)
		(layer "In6.Cu")
		(net "GMI_CPU1_G0_CPU0_G2_TX_DN<11>")
	)
	(segment
		(start 302.88992 -184.192926)
		(end 306.321206 -184.192926)
		(width 0.14224)
		(layer "In6.Cu")
		(net "GMI_CPU1_G0_CPU0_G2_TX_DN<11>")
	)
	(segment
		(start 363.282484 -226.983798)
		(end 363.2835 -226.984306)
		(width 0.1143)
		(layer "In6.Cu")
		(net "GMI_CPU1_G0_CPU0_G2_TX_DN<11>")
	)
	(segment
		(start 363.287818 -226.986846)
		(end 363.288834 -226.987354)
		(width 0.1143)
		(layer "In6.Cu")
		(net "GMI_CPU1_G0_CPU0_G2_TX_DN<11>")
	)
	(segment
		(start 363.326934 -227.938838)
		(end 363.290358 -227.960174)
		(width 0.1143)
		(layer "In6.Cu")
		(net "GMI_CPU1_G0_CPU0_G2_TX_DN<11>")
	)
	(segment
		(start 360.936286 -222.936308)
		(end 360.937048 -222.936816)
		(width 0.1143)
		(layer "In6.Cu")
		(net "GMI_CPU1_G0_CPU0_G2_TX_DN<11>")
	)
	(segment
		(start 363.280706 -231.842564)
		(end 363.281722 -231.843072)
		(width 0.1143)
		(layer "In6.Cu")
		(net "GMI_CPU1_G0_CPU0_G2_TX_DN<11>")
	)
	(segment
		(start 363.287818 -234.441492)
		(end 363.287056 -234.442)
		(width 0.1143)
		(layer "In6.Cu")
		(net "GMI_CPU1_G0_CPU0_G2_TX_DN<11>")
	)
	(segment
		(start 108.213398 -226.984052)
		(end 108.21416 -226.983544)
		(width 0.1143)
		(layer "In6.Cu")
		(net "GMI_CPU1_G0_CPU0_G2_TX_DN<11>")
	)
	(segment
		(start 363.287818 -232.82148)
		(end 363.287056 -232.821988)
		(width 0.1143)
		(layer "In6.Cu")
		(net "GMI_CPU1_G0_CPU0_G2_TX_DN<11>")
	)
	(segment
		(start 363.287056 -226.986338)
		(end 363.287818 -226.986846)
		(width 0.1143)
		(layer "In6.Cu")
		(net "GMI_CPU1_G0_CPU0_G2_TX_DN<11>")
	)
	(segment
		(start 106.438954 -238.00435)
		(end 106.521758 -237.921546)
		(width 0.1143)
		(layer "In6.Cu")
		(net "GMI_CPU1_G0_CPU0_G2_TX_DN<11>")
	)
	(segment
		(start 111.217456 -221.623382)
		(end 111.217456 -221.248732)
		(width 0.1143)
		(layer "In6.Cu")
		(net "GMI_CPU1_G0_CPU0_G2_TX_DN<11>")
	)
	(segment
		(start 353.424236 -213.701884)
		(end 357.107236 -216.625424)
		(width 0.14224)
		(layer "In6.Cu")
		(net "GMI_CPU1_G0_CPU0_G2_TX_DN<11>")
	)
	(segment
		(start 111.171736 -221.174564)
		(end 111.171736 -220.63202)
		(width 0.14224)
		(layer "In6.Cu")
		(net "GMI_CPU1_G0_CPU0_G2_TX_DN<11>")
	)
	(segment
		(start 363.256068 -233.448352)
		(end 363.280706 -233.462576)
		(width 0.1143)
		(layer "In6.Cu")
		(net "GMI_CPU1_G0_CPU0_G2_TX_DN<11>")
	)
	(segment
		(start 108.215176 -235.082842)
		(end 108.239814 -235.068618)
		(width 0.1143)
		(layer "In6.Cu")
		(net "GMI_CPU1_G0_CPU0_G2_TX_DN<11>")
	)
	(segment
		(start 164.844984 -184.315862)
		(end 168.26865 -183.409082)
		(width 0.14224)
		(layer "In6.Cu")
		(net "GMI_CPU1_G0_CPU0_G2_TX_DN<11>")
	)
	(segment
		(start 108.207048 -227.961444)
		(end 108.205524 -227.960428)
		(width 0.1143)
		(layer "In6.Cu")
		(net "GMI_CPU1_G0_CPU0_G2_TX_DN<11>")
	)
	(segment
		(start 362.786168 -226.158298)
		(end 362.85678 -226.1997)
		(width 0.1143)
		(layer "In6.Cu")
		(net "GMI_CPU1_G0_CPU0_G2_TX_DN<11>")
	)
	(segment
		(start 357.107236 -216.625424)
		(end 359.864406 -219.381578)
		(width 0.14224)
		(layer "In6.Cu")
		(net "GMI_CPU1_G0_CPU0_G2_TX_DN<11>")
	)
	(segment
		(start 363.280706 -226.982782)
		(end 363.281722 -226.98329)
		(width 0.1143)
		(layer "In6.Cu")
		(net "GMI_CPU1_G0_CPU0_G2_TX_DN<11>")
	)
	(segment
		(start 363.287818 -231.846628)
		(end 363.288834 -231.847136)
		(width 0.1143)
		(layer "In6.Cu")
		(net "GMI_CPU1_G0_CPU0_G2_TX_DN<11>")
	)
	(segment
		(start 364.697264 -237.51667)
		(end 364.697772 -237.51667)
		(width 0.1143)
		(layer "In6.Cu")
		(net "GMI_CPU1_G0_CPU0_G2_TX_DN<11>")
	)
	(segment
		(start 108.212382 -231.844342)
		(end 108.213398 -231.843834)
		(width 0.1143)
		(layer "In6.Cu")
		(net "GMI_CPU1_G0_CPU0_G2_TX_DN<11>")
	)
	(segment
		(start 108.207048 -226.987608)
		(end 108.208064 -226.9871)
		(width 0.1143)
		(layer "In6.Cu")
		(net "GMI_CPU1_G0_CPU0_G2_TX_DN<11>")
	)
	(segment
		(start 363.282484 -228.60381)
		(end 363.2835 -228.604318)
		(width 0.1143)
		(layer "In6.Cu")
		(net "GMI_CPU1_G0_CPU0_G2_TX_DN<11>")
	)
	(segment
		(start 363.288834 -235.08716)
		(end 363.290358 -235.088176)
		(width 0.1143)
		(layer "In6.Cu")
		(net "GMI_CPU1_G0_CPU0_G2_TX_DN<11>")
	)
	(segment
		(start 360.93273 -222.934276)
		(end 360.933492 -222.934784)
		(width 0.1143)
		(layer "In6.Cu")
		(net "GMI_CPU1_G0_CPU0_G2_TX_DN<11>")
	)
	(segment
		(start 108.239814 -234.460034)
		(end 108.208826 -234.442254)
		(width 0.1143)
		(layer "In6.Cu")
		(net "GMI_CPU1_G0_CPU0_G2_TX_DN<11>")
	)
	(segment
		(start 360.929936 -222.932752)
		(end 360.930952 -222.93326)
		(width 0.1143)
		(layer "In6.Cu")
		(net "GMI_CPU1_G0_CPU0_G2_TX_DN<11>")
	)
	(segment
		(start 108.208064 -233.466894)
		(end 108.208826 -233.466386)
		(width 0.1143)
		(layer "In6.Cu")
		(net "GMI_CPU1_G0_CPU0_G2_TX_DN<11>")
	)
	(segment
		(start 110.56493 -222.933514)
		(end 110.565946 -222.933006)
		(width 0.1143)
		(layer "In6.Cu")
		(net "GMI_CPU1_G0_CPU0_G2_TX_DN<11>")
	)
	(segment
		(start 110.557818 -222.937578)
		(end 110.558834 -222.93707)
		(width 0.1143)
		(layer "In6.Cu")
		(net "GMI_CPU1_G0_CPU0_G2_TX_DN<11>")
	)
	(segment
		(start 106.798618 -237.516924)
		(end 106.826558 -237.500414)
		(width 0.1143)
		(layer "In6.Cu")
		(net "GMI_CPU1_G0_CPU0_G2_TX_DN<11>")
	)
	(segment
		(start 121.571004 -210.36534)
		(end 133.268466 -202.548744)
		(width 0.14224)
		(layer "In6.Cu")
		(net "GMI_CPU1_G0_CPU0_G2_TX_DN<11>")
	)
	(segment
		(start 360.278426 -221.248478)
		(end 360.278426 -221.623128)
		(width 0.1143)
		(layer "In6.Cu")
		(net "GMI_CPU1_G0_CPU0_G2_TX_DN<11>")
	)
	(segment
		(start 363.287818 -233.46664)
		(end 363.288834 -233.467148)
		(width 0.1143)
		(layer "In6.Cu")
		(net "GMI_CPU1_G0_CPU0_G2_TX_DN<11>")
	)
	(segment
		(start 363.285786 -231.845358)
		(end 363.287056 -231.84612)
		(width 0.1143)
		(layer "In6.Cu")
		(net "GMI_CPU1_G0_CPU0_G2_TX_DN<11>")
	)
	(segment
		(start 363.290358 -232.819956)
		(end 363.288834 -232.820972)
		(width 0.1143)
		(layer "In6.Cu")
		(net "GMI_CPU1_G0_CPU0_G2_TX_DN<11>")
	)
	(segment
		(start 108.208064 -231.846882)
		(end 108.208826 -231.846374)
		(width 0.1143)
		(layer "In6.Cu")
		(net "GMI_CPU1_G0_CPU0_G2_TX_DN<11>")
	)
	(segment
		(start 108.241592 -231.221534)
		(end 108.208064 -231.201976)
		(width 0.1143)
		(layer "In6.Cu")
		(net "GMI_CPU1_G0_CPU0_G2_TX_DN<11>")
	)
	(segment
		(start 108.21162 -235.084874)
		(end 108.212382 -235.084366)
		(width 0.1143)
		(layer "In6.Cu")
		(net "GMI_CPU1_G0_CPU0_G2_TX_DN<11>")
	)
	(segment
		(start 108.207048 -235.087414)
		(end 108.208064 -235.086906)
		(width 0.1143)
		(layer "In6.Cu")
		(net "GMI_CPU1_G0_CPU0_G2_TX_DN<11>")
	)
	(segment
		(start 109.620558 -224.555812)
		(end 109.622082 -224.55505)
		(width 0.1143)
		(layer "In6.Cu")
		(net "GMI_CPU1_G0_CPU0_G2_TX_DN<11>")
	)
	(segment
		(start 363.2835 -228.604318)
		(end 363.284262 -228.604826)
		(width 0.1143)
		(layer "In6.Cu")
		(net "GMI_CPU1_G0_CPU0_G2_TX_DN<11>")
	)
	(segment
		(start 363.288834 -226.987354)
		(end 363.290358 -226.98837)
		(width 0.1143)
		(layer "In6.Cu")
		(net "GMI_CPU1_G0_CPU0_G2_TX_DN<11>")
	)
	(segment
		(start 108.21416 -235.08335)
		(end 108.215176 -235.082842)
		(width 0.1143)
		(layer "In6.Cu")
		(net "GMI_CPU1_G0_CPU0_G2_TX_DN<11>")
	)
	(segment
		(start 363.287056 -231.84612)
		(end 363.287818 -231.846628)
		(width 0.1143)
		(layer "In6.Cu")
		(net "GMI_CPU1_G0_CPU0_G2_TX_DN<11>")
	)
	(segment
		(start 108.210096 -235.085636)
		(end 108.21162 -235.084874)
		(width 0.1143)
		(layer "In6.Cu")
		(net "GMI_CPU1_G0_CPU0_G2_TX_DN<11>")
	)
	(segment
		(start 312.316368 -187.438538)
		(end 313.093354 -187.899802)
		(width 0.14224)
		(layer "In6.Cu")
		(net "GMI_CPU1_G0_CPU0_G2_TX_DN<11>")
	)
	(segment
		(start 108.208826 -234.442254)
		(end 108.208064 -234.441746)
		(width 0.1143)
		(layer "In6.Cu")
		(net "GMI_CPU1_G0_CPU0_G2_TX_DN<11>")
	)
	(segment
		(start 108.213398 -228.604064)
		(end 108.21416 -228.603556)
		(width 0.1143)
		(layer "In6.Cu")
		(net "GMI_CPU1_G0_CPU0_G2_TX_DN<11>")
	)
	(segment
		(start 363.284262 -231.844596)
		(end 363.285786 -231.845358)
		(width 0.1143)
		(layer "In6.Cu")
		(net "GMI_CPU1_G0_CPU0_G2_TX_DN<11>")
	)
	(segment
		(start 235.598462 -183.801004)
		(end 302.88992 -184.192926)
		(width 0.14224)
		(layer "In6.Cu")
		(net "GMI_CPU1_G0_CPU0_G2_TX_DN<11>")
	)
	(segment
		(start 108.21162 -233.464862)
		(end 108.212382 -233.464354)
		(width 0.1143)
		(layer "In6.Cu")
		(net "GMI_CPU1_G0_CPU0_G2_TX_DN<11>")
	)
	(segment
		(start 363.282484 -235.083604)
		(end 363.2835 -235.084112)
		(width 0.1143)
		(layer "In6.Cu")
		(net "GMI_CPU1_G0_CPU0_G2_TX_DN<11>")
	)
	(segment
		(start 360.324146 -220.490796)
		(end 360.324146 -221.17431)
		(width 0.14224)
		(layer "In6.Cu")
		(net "GMI_CPU1_G0_CPU0_G2_TX_DN<11>")
	)
	(segment
		(start 111.216948 -221.804484)
		(end 111.216948 -221.62389)
		(width 0.1143)
		(layer "In6.Cu")
		(net "GMI_CPU1_G0_CPU0_G2_TX_DN<11>")
	)
	(segment
		(start 363.256068 -231.82834)
		(end 363.280706 -231.842564)
		(width 0.1143)
		(layer "In6.Cu")
		(net "GMI_CPU1_G0_CPU0_G2_TX_DN<11>")
	)
	(segment
		(start 363.288834 -233.467148)
		(end 363.290358 -233.468164)
		(width 0.1143)
		(layer "In6.Cu")
		(net "GMI_CPU1_G0_CPU0_G2_TX_DN<11>")
	)
	(segment
		(start 363.290358 -227.960174)
		(end 363.288834 -227.96119)
		(width 0.1143)
		(layer "In6.Cu")
		(net "GMI_CPU1_G0_CPU0_G2_TX_DN<11>")
	)
	(segment
		(start 108.212382 -226.98456)
		(end 108.213398 -226.984052)
		(width 0.1143)
		(layer "In6.Cu")
		(net "GMI_CPU1_G0_CPU0_G2_TX_DN<11>")
	)
	(segment
		(start 108.21162 -226.985068)
		(end 108.212382 -226.98456)
		(width 0.1143)
		(layer "In6.Cu")
		(net "GMI_CPU1_G0_CPU0_G2_TX_DN<11>")
	)
	(segment
		(start 363.288834 -232.820972)
		(end 363.287818 -232.82148)
		(width 0.1143)
		(layer "In6.Cu")
		(net "GMI_CPU1_G0_CPU0_G2_TX_DN<11>")
	)
	(segment
		(start 363.326934 -229.55885)
		(end 363.25429 -229.601268)
		(width 0.1143)
		(layer "In6.Cu")
		(net "GMI_CPU1_G0_CPU0_G2_TX_DN<11>")
	)
	(segment
		(start 114.906806 -215.895682)
		(end 118.717314 -212.55482)
		(width 0.14224)
		(layer "In6.Cu")
		(net "GMI_CPU1_G0_CPU0_G2_TX_DN<11>")
	)
	(segment
		(start 108.168948 -228.629972)
		(end 108.207048 -228.60762)
		(width 0.1143)
		(layer "In6.Cu")
		(net "GMI_CPU1_G0_CPU0_G2_TX_DN<11>")
	)
	(segment
		(start 111.171736 -221.203012)
		(end 111.171736 -221.174564)
		(width 0.1143)
		(layer "In6.Cu")
		(net "GMI_CPU1_G0_CPU0_G2_TX_DN<11>")
	)
	(segment
		(start 314.965842 -189.772544)
		(end 353.424236 -213.701884)
		(width 0.14224)
		(layer "In6.Cu")
		(net "GMI_CPU1_G0_CPU0_G2_TX_DN<11>")
	)
	(segment
		(start 363.288834 -227.96119)
		(end 363.287818 -227.961698)
		(width 0.1143)
		(layer "In6.Cu")
		(net "GMI_CPU1_G0_CPU0_G2_TX_DN<11>")
	)
	(segment
		(start 108.208064 -230.22687)
		(end 108.239814 -230.208582)
		(width 0.1143)
		(layer "In6.Cu")
		(net "GMI_CPU1_G0_CPU0_G2_TX_DN<11>")
	)
	(segment
		(start 363.290358 -233.468164)
		(end 363.326934 -233.4895)
		(width 0.1143)
		(layer "In6.Cu")
		(net "GMI_CPU1_G0_CPU0_G2_TX_DN<11>")
	)
	(segment
		(start 108.215176 -228.603048)
		(end 108.239814 -228.588824)
		(width 0.1143)
		(layer "In6.Cu")
		(net "GMI_CPU1_G0_CPU0_G2_TX_DN<11>")
	)
	(segment
		(start 363.284262 -226.984814)
		(end 363.285786 -226.985576)
		(width 0.1143)
		(layer "In6.Cu")
		(net "GMI_CPU1_G0_CPU0_G2_TX_DN<11>")
	)
	(segment
		(start 363.280706 -233.462576)
		(end 363.281722 -233.463084)
		(width 0.1143)
		(layer "In6.Cu")
		(net "GMI_CPU1_G0_CPU0_G2_TX_DN<11>")
	)
	(segment
		(start 363.281722 -235.083096)
		(end 363.282484 -235.083604)
		(width 0.1143)
		(layer "In6.Cu")
		(net "GMI_CPU1_G0_CPU0_G2_TX_DN<11>")
	)
	(segment
		(start 360.939588 -222.93834)
		(end 360.976164 -222.959676)
		(width 0.1143)
		(layer "In6.Cu")
		(net "GMI_CPU1_G0_CPU0_G2_TX_DN<11>")
	)
	(segment
		(start 108.208064 -232.821734)
		(end 108.207048 -232.821226)
		(width 0.1143)
		(layer "In6.Cu")
		(net "GMI_CPU1_G0_CPU0_G2_TX_DN<11>")
	)
	(segment
		(start 363.285786 -233.46537)
		(end 363.287056 -233.466132)
		(width 0.1143)
		(layer "In6.Cu")
		(net "GMI_CPU1_G0_CPU0_G2_TX_DN<11>")
	)
	(segment
		(start 363.287818 -228.606858)
		(end 363.288834 -228.607366)
		(width 0.1143)
		(layer "In6.Cu")
		(net "GMI_CPU1_G0_CPU0_G2_TX_DN<11>")
	)
	(segment
		(start 108.208826 -227.96246)
		(end 108.208064 -227.961952)
		(width 0.1143)
		(layer "In6.Cu")
		(net "GMI_CPU1_G0_CPU0_G2_TX_DN<11>")
	)
	(segment
		(start 365.056928 -238.004096)
		(end 365.35487 -238.004096)
		(width 0.1143)
		(layer "In6.Cu")
		(net "GMI_CPU1_G0_CPU0_G2_TX_DN<11>")
	)
	(segment
		(start 110.559596 -222.936562)
		(end 110.560866 -222.9358)
		(width 0.1143)
		(layer "In6.Cu")
		(net "GMI_CPU1_G0_CPU0_G2_TX_DN<11>")
	)
	(segment
		(start 363.287818 -227.961698)
		(end 363.287056 -227.962206)
		(width 0.1143)
		(layer "In6.Cu")
		(net "GMI_CPU1_G0_CPU0_G2_TX_DN<11>")
	)
	(segment
		(start 108.241592 -229.601522)
		(end 108.208064 -229.581964)
		(width 0.1143)
		(layer "In6.Cu")
		(net "GMI_CPU1_G0_CPU0_G2_TX_DN<11>")
	)
	(segment
		(start 363.282484 -233.463592)
		(end 363.2835 -233.4641)
		(width 0.1143)
		(layer "In6.Cu")
		(net "GMI_CPU1_G0_CPU0_G2_TX_DN<11>")
	)
	(segment
		(start 360.937048 -222.936816)
		(end 360.938064 -222.937324)
		(width 0.1143)
		(layer "In6.Cu")
		(net "GMI_CPU1_G0_CPU0_G2_TX_DN<11>")
	)
	(segment
		(start 108.210096 -231.845612)
		(end 108.21162 -231.84485)
		(width 0.1143)
		(layer "In6.Cu")
		(net "GMI_CPU1_G0_CPU0_G2_TX_DN<11>")
	)
	(segment
		(start 363.285786 -227.962968)
		(end 363.256068 -227.979986)
		(width 0.1143)
		(layer "In6.Cu")
		(net "GMI_CPU1_G0_CPU0_G2_TX_DN<11>")
	)
	(segment
		(start 110.558834 -222.93707)
		(end 110.559596 -222.936562)
		(width 0.1143)
		(layer "In6.Cu")
		(net "GMI_CPU1_G0_CPU0_G2_TX_DN<11>")
	)
	(segment
		(start 363.284262 -228.604826)
		(end 363.285786 -228.605588)
		(width 0.1143)
		(layer "In6.Cu")
		(net "GMI_CPU1_G0_CPU0_G2_TX_DN<11>")
	)
	(segment
		(start 108.213398 -235.083858)
		(end 108.21416 -235.08335)
		(width 0.1143)
		(layer "In6.Cu")
		(net "GMI_CPU1_G0_CPU0_G2_TX_DN<11>")
	)
	(segment
		(start 168.26865 -183.409082)
		(end 235.598462 -183.801258)
		(width 0.14224)
		(layer "In6.Cu")
		(net "GMI_CPU1_G0_CPU0_G2_TX_DN<11>")
	)
	(segment
		(start 108.208064 -235.086906)
		(end 108.208826 -235.086398)
		(width 0.1143)
		(layer "In6.Cu")
		(net "GMI_CPU1_G0_CPU0_G2_TX_DN<11>")
	)
	(segment
		(start 363.290358 -226.98837)
		(end 363.326934 -227.009706)
		(width 0.1143)
		(layer "In6.Cu")
		(net "GMI_CPU1_G0_CPU0_G2_TX_DN<11>")
	)
	(segment
		(start 363.287056 -235.086144)
		(end 363.287818 -235.086652)
		(width 0.1143)
		(layer "In6.Cu")
		(net "GMI_CPU1_G0_CPU0_G2_TX_DN<11>")
	)
	(segment
		(start 106.79811 -237.516924)
		(end 106.798618 -237.516924)
		(width 0.1143)
		(layer "In6.Cu")
		(net "GMI_CPU1_G0_CPU0_G2_TX_DN<11>")
	)
	(segment
		(start 362.332778 -225.351848)
		(end 362.352336 -225.363786)
		(width 0.1143)
		(layer "In6.Cu")
		(net "GMI_CPU1_G0_CPU0_G2_TX_DN<11>")
	)
	(segment
		(start 108.215176 -226.983036)
		(end 108.239814 -226.968812)
		(width 0.1143)
		(layer "In6.Cu")
		(net "GMI_CPU1_G0_CPU0_G2_TX_DN<11>")
	)
	(segment
		(start 363.285786 -234.442762)
		(end 363.256068 -234.45978)
		(width 0.1143)
		(layer "In6.Cu")
		(net "GMI_CPU1_G0_CPU0_G2_TX_DN<11>")
	)
	(segment
		(start 110.564168 -222.934022)
		(end 110.56493 -222.933514)
		(width 0.1143)
		(layer "In6.Cu")
		(net "GMI_CPU1_G0_CPU0_G2_TX_DN<11>")
	)
	(segment
		(start 363.326934 -231.178862)
		(end 363.25429 -231.22128)
		(width 0.1143)
		(layer "In6.Cu")
		(net "GMI_CPU1_G0_CPU0_G2_TX_DN<11>")
	)
	(segment
		(start 108.207048 -234.441238)
		(end 108.205524 -234.440222)
		(width 0.1143)
		(layer "In6.Cu")
		(net "GMI_CPU1_G0_CPU0_G2_TX_DN<11>")
	)
	(segment
		(start 363.281722 -226.98329)
		(end 363.282484 -226.983798)
		(width 0.1143)
		(layer "In6.Cu")
		(net "GMI_CPU1_G0_CPU0_G2_TX_DN<11>")
	)
	(segment
		(start 106.985816 -237.1852)
		(end 106.985816 -237.184946)
		(width 0.1143)
		(layer "In6.Cu")
		(net "GMI_CPU1_G0_CPU0_G2_TX_DN<11>")
	)
	(segment
		(start 110.519718 -222.95993)
		(end 110.557818 -222.937578)
		(width 0.1143)
		(layer "In6.Cu")
		(net "GMI_CPU1_G0_CPU0_G2_TX_DN<11>")
	)
	(segment
		(start 108.212382 -228.604572)
		(end 108.213398 -228.604064)
		(width 0.1143)
		(layer "In6.Cu")
		(net "GMI_CPU1_G0_CPU0_G2_TX_DN<11>")
	)
	(segment
		(start 108.208826 -226.986592)
		(end 108.210096 -226.98583)
		(width 0.1143)
		(layer "In6.Cu")
		(net "GMI_CPU1_G0_CPU0_G2_TX_DN<11>")
	)
	(segment
		(start 360.324146 -221.17431)
		(end 360.324146 -221.202758)
		(width 0.1143)
		(layer "In6.Cu")
		(net "GMI_CPU1_G0_CPU0_G2_TX_DN<11>")
	)
	(segment
		(start 363.284262 -233.464608)
		(end 363.285786 -233.46537)
		(width 0.1143)
		(layer "In6.Cu")
		(net "GMI_CPU1_G0_CPU0_G2_TX_DN<11>")
	)
	(segment
		(start 363.2835 -231.844088)
		(end 363.284262 -231.844596)
		(width 0.1143)
		(layer "In6.Cu")
		(net "GMI_CPU1_G0_CPU0_G2_TX_DN<11>")
	)
	(segment
		(start 360.935016 -222.935546)
		(end 360.936286 -222.936308)
		(width 0.1143)
		(layer "In6.Cu")
		(net "GMI_CPU1_G0_CPU0_G2_TX_DN<11>")
	)
	(segment
		(start 110.047532 -223.771206)
		(end 110.12043 -223.728788)
		(width 0.1143)
		(layer "In6.Cu")
		(net "GMI_CPU1_G0_CPU0_G2_TX_DN<11>")
	)
	(segment
		(start 364.700312 -237.518194)
		(end 364.736888 -237.53953)
		(width 0.1143)
		(layer "In6.Cu")
		(net "GMI_CPU1_G0_CPU0_G2_TX_DN<11>")
	)
	(segment
		(start 110.563152 -222.93453)
		(end 110.564168 -222.934022)
		(width 0.1143)
		(layer "In6.Cu")
		(net "GMI_CPU1_G0_CPU0_G2_TX_DN<11>")
	)
	(segment
		(start 118.717314 -212.55482)
		(end 121.571004 -210.36534)
		(width 0.14224)
		(layer "In6.Cu")
		(net "GMI_CPU1_G0_CPU0_G2_TX_DN<11>")
	)
	(segment
		(start 364.22711 -236.706156)
		(end 364.227872 -236.706664)
		(width 0.1143)
		(layer "In6.Cu")
		(net "GMI_CPU1_G0_CPU0_G2_TX_DN<11>")
	)
	(segment
		(start 363.2835 -233.4641)
		(end 363.284262 -233.464608)
		(width 0.1143)
		(layer "In6.Cu")
		(net "GMI_CPU1_G0_CPU0_G2_TX_DN<11>")
	)
	(segment
		(start 108.21162 -231.84485)
		(end 108.212382 -231.844342)
		(width 0.1143)
		(layer "In6.Cu")
		(net "GMI_CPU1_G0_CPU0_G2_TX_DN<11>")
	)
	(segment
		(start 111.171736 -220.63202)
		(end 111.879888 -218.9226)
		(width 0.14224)
		(layer "In6.Cu")
		(net "GMI_CPU1_G0_CPU0_G2_TX_DN<11>")
	)
	(segment
		(start 363.285786 -232.82275)
		(end 363.256068 -232.839768)
		(width 0.1143)
		(layer "In6.Cu")
		(net "GMI_CPU1_G0_CPU0_G2_TX_DN<11>")
	)
	(segment
		(start 363.290358 -228.608382)
		(end 363.326934 -228.629718)
		(width 0.1143)
		(layer "In6.Cu")
		(net "GMI_CPU1_G0_CPU0_G2_TX_DN<11>")
	)
	(segment
		(start 107.270042 -236.705648)
		(end 107.29976 -236.68863)
		(width 0.1143)
		(layer "In6.Cu")
		(net "GMI_CPU1_G0_CPU0_G2_TX_DN<11>")
	)
	(segment
		(start 363.288834 -231.847136)
		(end 363.290358 -231.848152)
		(width 0.1143)
		(layer "In6.Cu")
		(net "GMI_CPU1_G0_CPU0_G2_TX_DN<11>")
	)
	(segment
		(start 363.285786 -235.085382)
		(end 363.287056 -235.086144)
		(width 0.1143)
		(layer "In6.Cu")
		(net "GMI_CPU1_G0_CPU0_G2_TX_DN<11>")
	)
	(segment
		(start 108.21416 -228.603556)
		(end 108.215176 -228.603048)
		(width 0.1143)
		(layer "In6.Cu")
		(net "GMI_CPU1_G0_CPU0_G2_TX_DN<11>")
	)
	(segment
		(start 108.208064 -227.961952)
		(end 108.207048 -227.961444)
		(width 0.1143)
		(layer "In6.Cu")
		(net "GMI_CPU1_G0_CPU0_G2_TX_DN<11>")
	)
	(segment
		(start 108.21416 -233.463338)
		(end 108.215176 -233.46283)
		(width 0.1143)
		(layer "In6.Cu")
		(net "GMI_CPU1_G0_CPU0_G2_TX_DN<11>")
	)
	(segment
		(start 363.287056 -228.60635)
		(end 363.287818 -228.606858)
		(width 0.1143)
		(layer "In6.Cu")
		(net "GMI_CPU1_G0_CPU0_G2_TX_DN<11>")
	)
	(segment
		(start 363.287818 -235.086652)
		(end 363.288834 -235.08716)
		(width 0.1143)
		(layer "In6.Cu")
		(net "GMI_CPU1_G0_CPU0_G2_TX_DN<11>")
	)
	(segment
		(start 108.168948 -227.00996)
		(end 108.207048 -226.987608)
		(width 0.1143)
		(layer "In6.Cu")
		(net "GMI_CPU1_G0_CPU0_G2_TX_DN<11>")
	)
	(segment
		(start 108.21416 -226.983544)
		(end 108.215176 -226.983036)
		(width 0.1143)
		(layer "In6.Cu")
		(net "GMI_CPU1_G0_CPU0_G2_TX_DN<11>")
	)
	(segment
		(start 363.288834 -234.440984)
		(end 363.287818 -234.441492)
		(width 0.1143)
		(layer "In6.Cu")
		(net "GMI_CPU1_G0_CPU0_G2_TX_DN<11>")
	)
	(segment
		(start 360.324146 -221.202758)
		(end 360.278426 -221.248478)
		(width 0.1143)
		(layer "In6.Cu")
		(net "GMI_CPU1_G0_CPU0_G2_TX_DN<11>")
	)
	(segment
		(start 363.280706 -235.082588)
		(end 363.281722 -235.083096)
		(width 0.1143)
		(layer "In6.Cu")
		(net "GMI_CPU1_G0_CPU0_G2_TX_DN<11>")
	)
	(segment
		(start 108.21162 -228.60508)
		(end 108.212382 -228.604572)
		(width 0.1143)
		(layer "In6.Cu")
		(net "GMI_CPU1_G0_CPU0_G2_TX_DN<11>")
	)
	(segment
		(start 111.216948 -221.62389)
		(end 111.217456 -221.623382)
		(width 0.1143)
		(layer "In6.Cu")
		(net "GMI_CPU1_G0_CPU0_G2_TX_DN<11>")
	)
	(segment
		(start 362.352336 -225.363786)
		(end 362.371386 -225.380042)
		(width 0.1143)
		(layer "In6.Cu")
		(net "GMI_CPU1_G0_CPU0_G2_TX_DN<11>")
	)
	(segment
		(start 363.281722 -233.463084)
		(end 363.282484 -233.463592)
		(width 0.1143)
		(layer "In6.Cu")
		(net "GMI_CPU1_G0_CPU0_G2_TX_DN<11>")
	)
	(segment
		(start 108.168948 -235.109766)
		(end 108.207048 -235.087414)
		(width 0.1143)
		(layer "In6.Cu")
		(net "GMI_CPU1_G0_CPU0_G2_TX_DN<11>")
	)
	(segment
		(start 107.231688 -236.728)
		(end 107.26801 -236.706918)
		(width 0.1143)
		(layer "In6.Cu")
		(net "GMI_CPU1_G0_CPU0_G2_TX_DN<11>")
	)
	(segment
		(start 108.239814 -227.98024)
		(end 108.208826 -227.96246)
		(width 0.1143)
		(layer "In6.Cu")
		(net "GMI_CPU1_G0_CPU0_G2_TX_DN<11>")
	)
	(segment
		(start 363.281722 -231.843072)
		(end 363.282484 -231.84358)
		(width 0.1143)
		(layer "In6.Cu")
		(net "GMI_CPU1_G0_CPU0_G2_TX_DN<11>")
	)
	(segment
		(start 363.256068 -235.068364)
		(end 363.280706 -235.082588)
		(width 0.1143)
		(layer "In6.Cu")
		(net "GMI_CPU1_G0_CPU0_G2_TX_DN<11>")
	)
	(segment
		(start 363.280706 -228.602794)
		(end 363.281722 -228.603302)
		(width 0.1143)
		(layer "In6.Cu")
		(net "GMI_CPU1_G0_CPU0_G2_TX_DN<11>")
	)
	(segment
		(start 111.217456 -221.248732)
		(end 111.171736 -221.203012)
		(width 0.1143)
		(layer "In6.Cu")
		(net "GMI_CPU1_G0_CPU0_G2_TX_DN<11>")
	)
	(segment
		(start 363.282484 -231.84358)
		(end 363.2835 -231.844088)
		(width 0.1143)
		(layer "In6.Cu")
		(net "GMI_CPU1_G0_CPU0_G2_TX_DN<11>")
	)
	(segment
		(start 108.208826 -233.466386)
		(end 108.210096 -233.465624)
		(width 0.1143)
		(layer "In6.Cu")
		(net "GMI_CPU1_G0_CPU0_G2_TX_DN<11>")
	)
	(segment
		(start 108.171488 -230.248206)
		(end 108.208064 -230.22687)
		(width 0.1143)
		(layer "In6.Cu")
		(net "GMI_CPU1_G0_CPU0_G2_TX_DN<11>")
	)
	(segment
		(start 108.207048 -232.821226)
		(end 108.205524 -232.82021)
		(width 0.1143)
		(layer "In6.Cu")
		(net "GMI_CPU1_G0_CPU0_G2_TX_DN<11>")
	)
	(segment
		(start 109.580934 -224.578926)
		(end 109.620558 -224.555812)
		(width 0.1143)
		(layer "In6.Cu")
		(net "GMI_CPU1_G0_CPU0_G2_TX_DN<11>")
	)
	(segment
		(start 109.143546 -225.36404)
		(end 109.163104 -225.352102)
		(width 0.1143)
		(layer "In6.Cu")
		(net "GMI_CPU1_G0_CPU0_G2_TX_DN<11>")
	)
	(segment
		(start 108.213398 -233.463846)
		(end 108.21416 -233.463338)
		(width 0.1143)
		(layer "In6.Cu")
		(net "GMI_CPU1_G0_CPU0_G2_TX_DN<11>")
	)
	(segment
		(start 133.268466 -202.548744)
		(end 164.844984 -184.315862)
		(width 0.14224)
		(layer "In6.Cu")
		(net "GMI_CPU1_G0_CPU0_G2_TX_DN<11>")
	)
	(segment
		(start 108.205524 -232.82021)
		(end 108.168948 -232.798874)
		(width 0.1143)
		(layer "In6.Cu")
		(net "GMI_CPU1_G0_CPU0_G2_TX_DN<11>")
	)
	(segment
		(start 360.278426 -221.623128)
		(end 360.278934 -221.623636)
		(width 0.1143)
		(layer "In6.Cu")
		(net "GMI_CPU1_G0_CPU0_G2_TX_DN<11>")
	)
	(segment
		(start 108.210096 -228.605842)
		(end 108.21162 -228.60508)
		(width 0.1143)
		(layer "In6.Cu")
		(net "GMI_CPU1_G0_CPU0_G2_TX_DN<11>")
	)
	(segment
		(start 108.21416 -231.843326)
		(end 108.215176 -231.842818)
		(width 0.1143)
		(layer "In6.Cu")
		(net "GMI_CPU1_G0_CPU0_G2_TX_DN<11>")
	)
	(segment
		(start 363.288834 -228.607366)
		(end 363.290358 -228.608382)
		(width 0.1143)
		(layer "In6.Cu")
		(net "GMI_CPU1_G0_CPU0_G2_TX_DN<11>")
	)
	(segment
		(start 363.290358 -235.088176)
		(end 363.326934 -235.109512)
		(width 0.1143)
		(layer "In6.Cu")
		(net "GMI_CPU1_G0_CPU0_G2_TX_DN<11>")
	)
	(segment
		(start 360.930952 -222.93326)
		(end 360.931714 -222.933768)
		(width 0.1143)
		(layer "In6.Cu")
		(net "GMI_CPU1_G0_CPU0_G2_TX_DN<11>")
	)
	(segment
		(start 364.22584 -236.705394)
		(end 364.22711 -236.706156)
		(width 0.1143)
		(layer "In6.Cu")
		(net "GMI_CPU1_G0_CPU0_G2_TX_DN<11>")
	)
	(segment
		(start 108.210096 -226.98583)
		(end 108.21162 -226.985068)
		(width 0.1143)
		(layer "In6.Cu")
		(net "GMI_CPU1_G0_CPU0_G2_TX_DN<11>")
	)
	(segment
		(start 363.285786 -226.985576)
		(end 363.287056 -226.986338)
		(width 0.1143)
		(layer "In6.Cu")
		(net "GMI_CPU1_G0_CPU0_G2_TX_DN<11>")
	)
	(segment
		(start 363.727238 -235.878878)
		(end 363.796834 -235.919518)
		(width 0.1143)
		(layer "In6.Cu")
		(net "GMI_CPU1_G0_CPU0_G2_TX_DN<11>")
	)
	(segment
		(start 363.326934 -234.418632)
		(end 363.290358 -234.439968)
		(width 0.1143)
		(layer "In6.Cu")
		(net "GMI_CPU1_G0_CPU0_G2_TX_DN<11>")
	)
	(segment
		(start 110.565946 -222.933006)
		(end 110.590584 -222.918782)
		(width 0.1143)
		(layer "In6.Cu")
		(net "GMI_CPU1_G0_CPU0_G2_TX_DN<11>")
	)
	(segment
		(start 363.256068 -230.208328)
		(end 363.287818 -230.226616)
		(width 0.1143)
		(layer "In6.Cu")
		(net "GMI_CPU1_G0_CPU0_G2_TX_DN<11>")
	)
	(segment
		(start 306.321206 -184.192926)
		(end 307.30825 -184.463944)
		(width 0.14224)
		(layer "In6.Cu")
		(net "GMI_CPU1_G0_CPU0_G2_TX_DN<11>")
	)
	(segment
		(start 360.905298 -222.918528)
		(end 360.929936 -222.932752)
		(width 0.1143)
		(layer "In6.Cu")
		(net "GMI_CPU1_G0_CPU0_G2_TX_DN<11>")
	)
	(segment
		(start 364.697772 -237.51667)
		(end 364.698788 -237.517178)
		(width 0.1143)
		(layer "In6.Cu")
		(net "GMI_CPU1_G0_CPU0_G2_TX_DN<11>")
	)
	(segment
		(start 108.208064 -226.9871)
		(end 108.208826 -226.986592)
		(width 0.1143)
		(layer "In6.Cu")
		(net "GMI_CPU1_G0_CPU0_G2_TX_DN<11>")
	)
	(segment
		(start 108.639102 -226.199954)
		(end 108.709714 -226.158552)
		(width 0.1143)
		(layer "In6.Cu")
		(net "GMI_CPU1_G0_CPU0_G2_TX_DN<11>")
	)
	(segment
		(start 111.879888 -218.9226)
		(end 114.906806 -215.895682)
		(width 0.14224)
		(layer "In6.Cu")
		(net "GMI_CPU1_G0_CPU0_G2_TX_DN<11>")
	)
	(segment
		(start 108.208826 -228.606604)
		(end 108.210096 -228.605842)
		(width 0.1143)
		(layer "In6.Cu")
		(net "GMI_CPU1_G0_CPU0_G2_TX_DN<11>")
	)
	(segment
		(start 107.268772 -236.70641)
		(end 107.270042 -236.705648)
		(width 0.1143)
		(layer "In6.Cu")
		(net "GMI_CPU1_G0_CPU0_G2_TX_DN<11>")
	)
	(segment
		(start 363.287056 -233.466132)
		(end 363.287818 -233.46664)
		(width 0.1143)
		(layer "In6.Cu")
		(net "GMI_CPU1_G0_CPU0_G2_TX_DN<11>")
	)
	(segment
		(start 364.227872 -236.706664)
		(end 364.264194 -236.727746)
		(width 0.1143)
		(layer "In6.Cu")
		(net "GMI_CPU1_G0_CPU0_G2_TX_DN<11>")
	)
	(segment
		(start 108.215176 -231.842818)
		(end 108.239814 -231.828594)
		(width 0.1143)
		(layer "In6.Cu")
		(net "GMI_CPU1_G0_CPU0_G2_TX_DN<11>")
	)
	(segment
		(start 363.256068 -228.58857)
		(end 363.280706 -228.602794)
		(width 0.1143)
		(layer "In6.Cu")
		(net "GMI_CPU1_G0_CPU0_G2_TX_DN<11>")
	)
	(segment
		(start 108.205524 -227.960428)
		(end 108.168948 -227.939092)
		(width 0.1143)
		(layer "In6.Cu")
		(net "GMI_CPU1_G0_CPU0_G2_TX_DN<11>")
	)
	(segment
		(start 108.212382 -233.464354)
		(end 108.213398 -233.463846)
		(width 0.1143)
		(layer "In6.Cu")
		(net "GMI_CPU1_G0_CPU0_G2_TX_DN<11>")
	)
	(segment
		(start 108.208826 -232.822242)
		(end 108.208064 -232.821734)
		(width 0.1143)
		(layer "In6.Cu")
		(net "GMI_CPU1_G0_CPU0_G2_TX_DN<11>")
	)
	(segment
		(start 363.326934 -232.79862)
		(end 363.290358 -232.819956)
		(width 0.1143)
		(layer "In6.Cu")
		(net "GMI_CPU1_G0_CPU0_G2_TX_DN<11>")
	)
	(segment
		(start 108.210096 -233.465624)
		(end 108.21162 -233.464862)
		(width 0.1143)
		(layer "In6.Cu")
		(net "GMI_CPU1_G0_CPU0_G2_TX_DN<11>")
	)
	(segment
		(start 313.093354 -187.899802)
		(end 314.965842 -189.772544)
		(width 0.14224)
		(layer "In6.Cu")
		(net "GMI_CPU1_G0_CPU0_G2_TX_DN<11>")
	)
	(segment
		(start 110.56239 -222.935038)
		(end 110.563152 -222.93453)
		(width 0.1143)
		(layer "In6.Cu")
		(net "GMI_CPU1_G0_CPU0_G2_TX_DN<11>")
	)
	(segment
		(start 364.974124 -237.921292)
		(end 365.056928 -238.004096)
		(width 0.1143)
		(layer "In6.Cu")
		(net "GMI_CPU1_G0_CPU0_G2_TX_DN<11>")
	)
	(segment
		(start 361.375452 -223.728534)
		(end 361.44835 -223.770952)
		(width 0.1143)
		(layer "In6.Cu")
		(net "GMI_CPU1_G0_CPU0_G2_TX_DN<11>")
	)
	(segment
		(start 108.207048 -228.60762)
		(end 108.208064 -228.607112)
		(width 0.1143)
		(layer "In6.Cu")
		(net "GMI_CPU1_G0_CPU0_G2_TX_DN<11>")
	)
	(segment
		(start 106.758994 -237.539784)
		(end 106.79811 -237.516924)
		(width 0.1143)
		(layer "In6.Cu")
		(net "GMI_CPU1_G0_CPU0_G2_TX_DN<11>")
	)
	(segment
		(start 108.239814 -232.840022)
		(end 108.208826 -232.822242)
		(width 0.1143)
		(layer "In6.Cu")
		(net "GMI_CPU1_G0_CPU0_G2_TX_DN<11>")
	)
	(segment
		(start 361.8738 -224.554796)
		(end 361.876848 -224.55632)
		(width 0.1143)
		(layer "In6.Cu")
		(net "GMI_CPU1_G0_CPU0_G2_TX_DN<11>")
	)
	(segment
		(start 364.196122 -236.688376)
		(end 364.22584 -236.705394)
		(width 0.1143)
		(layer "In6.Cu")
		(net "GMI_CPU1_G0_CPU0_G2_TX_DN<11>")
	)
	(segment
		(start 363.2835 -235.084112)
		(end 363.284262 -235.08462)
		(width 0.1143)
		(layer "In6.Cu")
		(net "GMI_CPU1_G0_CPU0_G2_TX_DN<11>")
	)
	(segment
		(start 107.699048 -235.919772)
		(end 107.738164 -235.896912)
		(width 0.1143)
		(layer "In6.Cu")
		(net "GMI_CPU1_G0_CPU0_G2_TX_DN<11>")
	)
	(segment
		(start 108.205524 -234.440222)
		(end 108.168948 -234.418886)
		(width 0.1143)
		(layer "In6.Cu")
		(net "GMI_CPU1_G0_CPU0_G2_TX_DN<11>")
	)
	(segment
		(start 359.864406 -219.381578)
		(end 360.324146 -220.490796)
		(width 0.14224)
		(layer "In6.Cu")
		(net "GMI_CPU1_G0_CPU0_G2_TX_DN<11>")
	)
	(segment
		(start 363.287818 -230.226616)
		(end 363.324394 -230.247952)
		(width 0.1143)
		(layer "In6.Cu")
		(net "GMI_CPU1_G0_CPU0_G2_TX_DN<11>")
	)
	(segment
		(start 107.26801 -236.706918)
		(end 107.268772 -236.70641)
		(width 0.1143)
		(layer "In6.Cu")
		(net "GMI_CPU1_G0_CPU0_G2_TX_DN<11>")
	)
	(segment
		(start 363.2835 -226.984306)
		(end 363.284262 -226.984814)
		(width 0.1143)
		(layer "In6.Cu")
		(net "GMI_CPU1_G0_CPU0_G2_TX_DN<11>")
	)
	(segment
		(start 363.290358 -234.439968)
		(end 363.288834 -234.440984)
		(width 0.1143)
		(layer "In6.Cu")
		(net "GMI_CPU1_G0_CPU0_G2_TX_DN<11>")
	)
	(segment
		(start 108.208826 -231.846374)
		(end 108.210096 -231.845612)
		(width 0.1143)
		(layer "In6.Cu")
		(net "GMI_CPU1_G0_CPU0_G2_TX_DN<11>")
	)
	(segment
		(start 363.287056 -234.442)
		(end 363.285786 -234.442762)
		(width 0.1143)
		(layer "In6.Cu")
		(net "GMI_CPU1_G0_CPU0_G2_TX_DN<11>")
	)
	(segment
		(start 363.285786 -228.605588)
		(end 363.287056 -228.60635)
		(width 0.1143)
		(layer "In6.Cu")
		(net "GMI_CPU1_G0_CPU0_G2_TX_DN<11>")
	)
	(segment
		(start 364.510066 -237.184692)
		(end 364.510066 -237.184946)
		(width 0.1143)
		(layer "In6.Cu")
		(net "GMI_CPU1_G0_CPU0_G2_TX_DN<11>")
	)
	(segment
		(start 108.168948 -231.869742)
		(end 108.207048 -231.84739)
		(width 0.1143)
		(layer "In6.Cu")
		(net "GMI_CPU1_G0_CPU0_G2_TX_DN<11>")
	)
	(segment
		(start 108.213398 -231.843834)
		(end 108.21416 -231.843326)
		(width 0.1143)
		(layer "In6.Cu")
		(net "GMI_CPU1_G0_CPU0_G2_TX_DN<11>")
	)
	(segment
		(start 364.669324 -237.50016)
		(end 364.697264 -237.51667)
		(width 0.1143)
		(layer "In6.Cu")
		(net "GMI_CPU1_G0_CPU0_G2_TX_DN<11>")
	)
	(segment
		(start 108.212382 -235.084366)
		(end 108.213398 -235.083858)
		(width 0.1143)
		(layer "In6.Cu")
		(net "GMI_CPU1_G0_CPU0_G2_TX_DN<11>")
	)
	(segment
		(start 109.124496 -225.380296)
		(end 109.143546 -225.36404)
		(width 0.1143)
		(layer "In6.Cu")
		(net "GMI_CPU1_G0_CPU0_G2_TX_DN<11>")
	)
	(segment
		(start 108.208064 -231.201976)
		(end 108.168948 -231.179116)
		(width 0.1143)
		(layer "In6.Cu")
		(net "GMI_CPU1_G0_CPU0_G2_TX_DN<11>")
	)
	(segment
		(start 360.278934 -221.623636)
		(end 360.278934 -221.80423)
		(width 0.1143)
		(layer "In6.Cu")
		(net "GMI_CPU1_G0_CPU0_G2_TX_DN<11>")
	)
	(segment
		(start 360.933492 -222.934784)
		(end 360.935016 -222.935546)
		(width 0.1143)
		(layer "In6.Cu")
		(net "GMI_CPU1_G0_CPU0_G2_TX_DN<11>")
	)
	(arc
		(start 363.326934 -228.629718)
		(mid 363.570261 -229.094284)
		(end 363.326934 -229.55885)
		(width 0.1143)
		(layer "In6.Cu")
		(net "GMI_CPU1_G0_CPU0_G2_TX_DN<11>")
	)
	(arc
		(start 110.12043 -223.728788)
		(mid 110.235106 -223.595454)
		(end 110.276386 -223.424496)
		(width 0.1143)
		(layer "In6.Cu")
		(net "GMI_CPU1_G0_CPU0_G2_TX_DN<11>")
	)
	(arc
		(start 108.239814 -233.448606)
		(mid 108.395742 -233.144314)
		(end 108.239814 -232.840022)
		(width 0.1143)
		(layer "In6.Cu")
		(net "GMI_CPU1_G0_CPU0_G2_TX_DN<11>")
	)
	(arc
		(start 106.985816 -237.184946)
		(mid 107.053192 -236.926569)
		(end 107.231688 -236.728)
		(width 0.1143)
		(layer "In6.Cu")
		(net "GMI_CPU1_G0_CPU0_G2_TX_DN<11>")
	)
	(arc
		(start 108.168948 -231.179116)
		(mid 107.990135 -230.976766)
		(end 107.925616 -230.71455)
		(width 0.1143)
		(layer "In6.Cu")
		(net "GMI_CPU1_G0_CPU0_G2_TX_DN<11>")
	)
	(arc
		(start 106.984292 -237.210092)
		(mid 106.985395 -237.197667)
		(end 106.985816 -237.1852)
		(width 0.1143)
		(layer "In6.Cu")
		(net "GMI_CPU1_G0_CPU0_G2_TX_DN<11>")
	)
	(arc
		(start 108.865924 -225.854514)
		(mid 108.934715 -225.584423)
		(end 109.124496 -225.380296)
		(width 0.1143)
		(layer "In6.Cu")
		(net "GMI_CPU1_G0_CPU0_G2_TX_DN<11>")
	)
	(arc
		(start 108.709714 -226.158552)
		(mid 108.824557 -226.025404)
		(end 108.865924 -225.854514)
		(width 0.1143)
		(layer "In6.Cu")
		(net "GMI_CPU1_G0_CPU0_G2_TX_DN<11>")
	)
	(arc
		(start 108.239814 -230.208582)
		(mid 108.35449 -230.075248)
		(end 108.39577 -229.90429)
		(width 0.1143)
		(layer "In6.Cu")
		(net "GMI_CPU1_G0_CPU0_G2_TX_DN<11>")
	)
	(arc
		(start 108.168948 -232.798874)
		(mid 107.925621 -232.334308)
		(end 108.168948 -231.869742)
		(width 0.1143)
		(layer "In6.Cu")
		(net "GMI_CPU1_G0_CPU0_G2_TX_DN<11>")
	)
	(arc
		(start 108.168948 -227.939092)
		(mid 107.925621 -227.474526)
		(end 108.168948 -227.00996)
		(width 0.1143)
		(layer "In6.Cu")
		(net "GMI_CPU1_G0_CPU0_G2_TX_DN<11>")
	)
	(arc
		(start 109.163104 -225.352102)
		(mid 109.289804 -225.220932)
		(end 109.336078 -225.044508)
		(width 0.1143)
		(layer "In6.Cu")
		(net "GMI_CPU1_G0_CPU0_G2_TX_DN<11>")
	)
	(arc
		(start 364.040166 -236.384084)
		(mid 364.081421 -236.555055)
		(end 364.196122 -236.688376)
		(width 0.1143)
		(layer "In6.Cu")
		(net "GMI_CPU1_G0_CPU0_G2_TX_DN<11>")
	)
	(arc
		(start 106.521758 -237.921546)
		(mid 106.523546 -237.910097)
		(end 106.525568 -237.898686)
		(width 0.1143)
		(layer "In6.Cu")
		(net "GMI_CPU1_G0_CPU0_G2_TX_DN<11>")
	)
	(arc
		(start 108.239814 -231.828594)
		(mid 108.35449 -231.69526)
		(end 108.39577 -231.524302)
		(width 0.1143)
		(layer "In6.Cu")
		(net "GMI_CPU1_G0_CPU0_G2_TX_DN<11>")
	)
	(arc
		(start 364.51159 -237.209838)
		(mid 364.561243 -237.366384)
		(end 364.662974 -237.495334)
		(width 0.1143)
		(layer "In6.Cu")
		(net "GMI_CPU1_G0_CPU0_G2_TX_DN<11>")
	)
	(arc
		(start 108.239814 -228.588824)
		(mid 108.395742 -228.284532)
		(end 108.239814 -227.98024)
		(width 0.1143)
		(layer "In6.Cu")
		(net "GMI_CPU1_G0_CPU0_G2_TX_DN<11>")
	)
	(arc
		(start 363.256068 -232.839768)
		(mid 363.10014 -233.14406)
		(end 363.256068 -233.448352)
		(width 0.1143)
		(layer "In6.Cu")
		(net "GMI_CPU1_G0_CPU0_G2_TX_DN<11>")
	)
	(arc
		(start 360.278934 -221.80423)
		(mid 360.295984 -221.915421)
		(end 360.345228 -222.016574)
		(width 0.1143)
		(layer "In6.Cu")
		(net "GMI_CPU1_G0_CPU0_G2_TX_DN<11>")
	)
	(arc
		(start 109.806232 -224.234502)
		(mid 109.870173 -223.973319)
		(end 110.047532 -223.771206)
		(width 0.1143)
		(layer "In6.Cu")
		(net "GMI_CPU1_G0_CPU0_G2_TX_DN<11>")
	)
	(arc
		(start 363.326934 -231.869488)
		(mid 363.570261 -232.334054)
		(end 363.326934 -232.79862)
		(width 0.1143)
		(layer "In6.Cu")
		(net "GMI_CPU1_G0_CPU0_G2_TX_DN<11>")
	)
	(arc
		(start 364.662974 -237.495334)
		(mid 364.666136 -237.497765)
		(end 364.669324 -237.50016)
		(width 0.1143)
		(layer "In6.Cu")
		(net "GMI_CPU1_G0_CPU0_G2_TX_DN<11>")
	)
	(arc
		(start 360.50601 -222.14967)
		(mid 360.684823 -222.35202)
		(end 360.749342 -222.614236)
		(width 0.1143)
		(layer "In6.Cu")
		(net "GMI_CPU1_G0_CPU0_G2_TX_DN<11>")
	)
	(arc
		(start 363.25429 -231.22128)
		(mid 363.140883 -231.354169)
		(end 363.100112 -231.524048)
		(width 0.1143)
		(layer "In6.Cu")
		(net "GMI_CPU1_G0_CPU0_G2_TX_DN<11>")
	)
	(arc
		(start 111.150654 -222.016828)
		(mid 111.199974 -221.915699)
		(end 111.216948 -221.804484)
		(width 0.1143)
		(layer "In6.Cu")
		(net "GMI_CPU1_G0_CPU0_G2_TX_DN<11>")
	)
	(arc
		(start 107.925616 -230.71455)
		(mid 107.990852 -230.450959)
		(end 108.171488 -230.248206)
		(width 0.1143)
		(layer "In6.Cu")
		(net "GMI_CPU1_G0_CPU0_G2_TX_DN<11>")
	)
	(arc
		(start 111.060738 -222.108776)
		(mid 111.10967 -222.066688)
		(end 111.150654 -222.016828)
		(width 0.1143)
		(layer "In6.Cu")
		(net "GMI_CPU1_G0_CPU0_G2_TX_DN<11>")
	)
	(arc
		(start 107.768644 -235.879132)
		(mid 107.884071 -235.745756)
		(end 107.925616 -235.574332)
		(width 0.1143)
		(layer "In6.Cu")
		(net "GMI_CPU1_G0_CPU0_G2_TX_DN<11>")
	)
	(arc
		(start 363.100112 -229.904036)
		(mid 363.141367 -230.075007)
		(end 363.256068 -230.208328)
		(width 0.1143)
		(layer "In6.Cu")
		(net "GMI_CPU1_G0_CPU0_G2_TX_DN<11>")
	)
	(arc
		(start 360.976164 -222.959676)
		(mid 361.154977 -223.162026)
		(end 361.219496 -223.424242)
		(width 0.1143)
		(layer "In6.Cu")
		(net "GMI_CPU1_G0_CPU0_G2_TX_DN<11>")
	)
	(arc
		(start 108.239814 -235.068618)
		(mid 108.395742 -234.764326)
		(end 108.239814 -234.460034)
		(width 0.1143)
		(layer "In6.Cu")
		(net "GMI_CPU1_G0_CPU0_G2_TX_DN<11>")
	)
	(arc
		(start 107.29976 -236.68863)
		(mid 107.414436 -236.555296)
		(end 107.455716 -236.384338)
		(width 0.1143)
		(layer "In6.Cu")
		(net "GMI_CPU1_G0_CPU0_G2_TX_DN<11>")
	)
	(arc
		(start 360.345228 -222.016574)
		(mid 360.386211 -222.066436)
		(end 360.435144 -222.108522)
		(width 0.1143)
		(layer "In6.Cu")
		(net "GMI_CPU1_G0_CPU0_G2_TX_DN<11>")
	)
	(arc
		(start 107.925616 -235.574332)
		(mid 107.990131 -235.312113)
		(end 108.168948 -235.109766)
		(width 0.1143)
		(layer "In6.Cu")
		(net "GMI_CPU1_G0_CPU0_G2_TX_DN<11>")
	)
	(arc
		(start 110.590584 -222.918782)
		(mid 110.70526 -222.785448)
		(end 110.74654 -222.61449)
		(width 0.1143)
		(layer "In6.Cu")
		(net "GMI_CPU1_G0_CPU0_G2_TX_DN<11>")
	)
	(arc
		(start 362.371386 -225.380042)
		(mid 362.561187 -225.584158)
		(end 362.629958 -225.85426)
		(width 0.1143)
		(layer "In6.Cu")
		(net "GMI_CPU1_G0_CPU0_G2_TX_DN<11>")
	)
	(arc
		(start 363.100112 -231.524048)
		(mid 363.141367 -231.695019)
		(end 363.256068 -231.82834)
		(width 0.1143)
		(layer "In6.Cu")
		(net "GMI_CPU1_G0_CPU0_G2_TX_DN<11>")
	)
	(arc
		(start 108.39577 -231.524302)
		(mid 108.355008 -231.354418)
		(end 108.241592 -231.221534)
		(width 0.1143)
		(layer "In6.Cu")
		(net "GMI_CPU1_G0_CPU0_G2_TX_DN<11>")
	)
	(arc
		(start 364.970314 -237.898432)
		(mid 364.972337 -237.909842)
		(end 364.974124 -237.921292)
		(width 0.1143)
		(layer "In6.Cu")
		(net "GMI_CPU1_G0_CPU0_G2_TX_DN<11>")
	)
	(arc
		(start 362.629958 -225.85426)
		(mid 362.671356 -226.025134)
		(end 362.786168 -226.158298)
		(width 0.1143)
		(layer "In6.Cu")
		(net "GMI_CPU1_G0_CPU0_G2_TX_DN<11>")
	)
	(arc
		(start 364.736888 -237.53953)
		(mid 364.888875 -237.696038)
		(end 364.970314 -237.898432)
		(width 0.1143)
		(layer "In6.Cu")
		(net "GMI_CPU1_G0_CPU0_G2_TX_DN<11>")
	)
	(arc
		(start 108.168948 -234.418886)
		(mid 107.925621 -233.95432)
		(end 108.168948 -233.489754)
		(width 0.1143)
		(layer "In6.Cu")
		(net "GMI_CPU1_G0_CPU0_G2_TX_DN<11>")
	)
	(arc
		(start 362.85678 -226.1997)
		(mid 363.035593 -226.40205)
		(end 363.100112 -226.664266)
		(width 0.1143)
		(layer "In6.Cu")
		(net "GMI_CPU1_G0_CPU0_G2_TX_DN<11>")
	)
	(arc
		(start 363.256068 -227.979986)
		(mid 363.10014 -228.284278)
		(end 363.256068 -228.58857)
		(width 0.1143)
		(layer "In6.Cu")
		(net "GMI_CPU1_G0_CPU0_G2_TX_DN<11>")
	)
	(arc
		(start 106.826558 -237.500414)
		(mid 106.829745 -237.498017)
		(end 106.832908 -237.495588)
		(width 0.1143)
		(layer "In6.Cu")
		(net "GMI_CPU1_G0_CPU0_G2_TX_DN<11>")
	)
	(arc
		(start 363.256068 -234.45978)
		(mid 363.10014 -234.764072)
		(end 363.256068 -235.068364)
		(width 0.1143)
		(layer "In6.Cu")
		(net "GMI_CPU1_G0_CPU0_G2_TX_DN<11>")
	)
	(arc
		(start 361.219496 -223.424242)
		(mid 361.260751 -223.595213)
		(end 361.375452 -223.728534)
		(width 0.1143)
		(layer "In6.Cu")
		(net "GMI_CPU1_G0_CPU0_G2_TX_DN<11>")
	)
	(arc
		(start 107.455716 -236.384338)
		(mid 107.520231 -236.122119)
		(end 107.699048 -235.919772)
		(width 0.1143)
		(layer "In6.Cu")
		(net "GMI_CPU1_G0_CPU0_G2_TX_DN<11>")
	)
	(arc
		(start 108.39577 -229.90429)
		(mid 108.355008 -229.734406)
		(end 108.241592 -229.601522)
		(width 0.1143)
		(layer "In6.Cu")
		(net "GMI_CPU1_G0_CPU0_G2_TX_DN<11>")
	)
	(arc
		(start 362.159804 -225.044254)
		(mid 362.205998 -225.220724)
		(end 362.332778 -225.351848)
		(width 0.1143)
		(layer "In6.Cu")
		(net "GMI_CPU1_G0_CPU0_G2_TX_DN<11>")
	)
	(arc
		(start 360.749342 -222.614236)
		(mid 360.790597 -222.785207)
		(end 360.905298 -222.918528)
		(width 0.1143)
		(layer "In6.Cu")
		(net "GMI_CPU1_G0_CPU0_G2_TX_DN<11>")
	)
	(arc
		(start 109.336078 -225.044508)
		(mid 109.401018 -224.781478)
		(end 109.580934 -224.578926)
		(width 0.1143)
		(layer "In6.Cu")
		(net "GMI_CPU1_G0_CPU0_G2_TX_DN<11>")
	)
	(arc
		(start 363.570266 -230.714296)
		(mid 363.505751 -230.976515)
		(end 363.326934 -231.178862)
		(width 0.1143)
		(layer "In6.Cu")
		(net "GMI_CPU1_G0_CPU0_G2_TX_DN<11>")
	)
	(arc
		(start 363.326934 -227.009706)
		(mid 363.570261 -227.474272)
		(end 363.326934 -227.938838)
		(width 0.1143)
		(layer "In6.Cu")
		(net "GMI_CPU1_G0_CPU0_G2_TX_DN<11>")
	)
	(arc
		(start 109.622082 -224.55505)
		(mid 109.756906 -224.419337)
		(end 109.806232 -224.234502)
		(width 0.1143)
		(layer "In6.Cu")
		(net "GMI_CPU1_G0_CPU0_G2_TX_DN<11>")
	)
	(arc
		(start 363.326934 -233.4895)
		(mid 363.570261 -233.954066)
		(end 363.326934 -234.418632)
		(width 0.1143)
		(layer "In6.Cu")
		(net "GMI_CPU1_G0_CPU0_G2_TX_DN<11>")
	)
	(arc
		(start 364.510066 -237.184946)
		(mid 364.510489 -237.197413)
		(end 364.51159 -237.209838)
		(width 0.1143)
		(layer "In6.Cu")
		(net "GMI_CPU1_G0_CPU0_G2_TX_DN<11>")
	)
	(arc
		(start 108.239814 -226.968812)
		(mid 108.35449 -226.835478)
		(end 108.39577 -226.66452)
		(width 0.1143)
		(layer "In6.Cu")
		(net "GMI_CPU1_G0_CPU0_G2_TX_DN<11>")
	)
	(arc
		(start 110.74654 -222.61449)
		(mid 110.811055 -222.352271)
		(end 110.989872 -222.149924)
		(width 0.1143)
		(layer "In6.Cu")
		(net "GMI_CPU1_G0_CPU0_G2_TX_DN<11>")
	)
	(arc
		(start 361.44835 -223.770952)
		(mid 361.625713 -223.973063)
		(end 361.68965 -224.234248)
		(width 0.1143)
		(layer "In6.Cu")
		(net "GMI_CPU1_G0_CPU0_G2_TX_DN<11>")
	)
	(arc
		(start 361.914948 -224.578672)
		(mid 362.094833 -224.781241)
		(end 362.159804 -225.044254)
		(width 0.1143)
		(layer "In6.Cu")
		(net "GMI_CPU1_G0_CPU0_G2_TX_DN<11>")
	)
	(arc
		(start 108.168948 -229.559104)
		(mid 107.925621 -229.094538)
		(end 108.168948 -228.629972)
		(width 0.1143)
		(layer "In6.Cu")
		(net "GMI_CPU1_G0_CPU0_G2_TX_DN<11>")
	)
	(arc
		(start 364.264194 -236.727746)
		(mid 364.442638 -236.926343)
		(end 364.510066 -237.184692)
		(width 0.1143)
		(layer "In6.Cu")
		(net "GMI_CPU1_G0_CPU0_G2_TX_DN<11>")
	)
	(arc
		(start 363.796834 -235.919518)
		(mid 363.975647 -236.121868)
		(end 364.040166 -236.384084)
		(width 0.1143)
		(layer "In6.Cu")
		(net "GMI_CPU1_G0_CPU0_G2_TX_DN<11>")
	)
	(arc
		(start 363.25429 -229.601268)
		(mid 363.140883 -229.734157)
		(end 363.100112 -229.904036)
		(width 0.1143)
		(layer "In6.Cu")
		(net "GMI_CPU1_G0_CPU0_G2_TX_DN<11>")
	)
	(arc
		(start 110.276386 -223.424496)
		(mid 110.340901 -223.162277)
		(end 110.519718 -222.95993)
		(width 0.1143)
		(layer "In6.Cu")
		(net "GMI_CPU1_G0_CPU0_G2_TX_DN<11>")
	)
	(arc
		(start 106.832908 -237.495588)
		(mid 106.934712 -237.366677)
		(end 106.984292 -237.210092)
		(width 0.1143)
		(layer "In6.Cu")
		(net "GMI_CPU1_G0_CPU0_G2_TX_DN<11>")
	)
	(arc
		(start 363.570266 -235.574078)
		(mid 363.611815 -235.7455)
		(end 363.727238 -235.878878)
		(width 0.1143)
		(layer "In6.Cu")
		(net "GMI_CPU1_G0_CPU0_G2_TX_DN<11>")
	)
	(arc
		(start 106.525568 -237.898686)
		(mid 106.607001 -237.696288)
		(end 106.758994 -237.539784)
		(width 0.1143)
		(layer "In6.Cu")
		(net "GMI_CPU1_G0_CPU0_G2_TX_DN<11>")
	)
	(arc
		(start 363.100112 -226.664266)
		(mid 363.141367 -226.835237)
		(end 363.256068 -226.968558)
		(width 0.1143)
		(layer "In6.Cu")
		(net "GMI_CPU1_G0_CPU0_G2_TX_DN<11>")
	)
	(arc
		(start 363.326934 -235.109512)
		(mid 363.505747 -235.311862)
		(end 363.570266 -235.574078)
		(width 0.1143)
		(layer "In6.Cu")
		(net "GMI_CPU1_G0_CPU0_G2_TX_DN<11>")
	)
	(arc
		(start 108.39577 -226.66452)
		(mid 108.460285 -226.402301)
		(end 108.639102 -226.199954)
		(width 0.1143)
		(layer "In6.Cu")
		(net "GMI_CPU1_G0_CPU0_G2_TX_DN<11>")
	)
	(arc
		(start 363.324394 -230.247952)
		(mid 363.505046 -230.450697)
		(end 363.570266 -230.714296)
		(width 0.1143)
		(layer "In6.Cu")
		(net "GMI_CPU1_G0_CPU0_G2_TX_DN<11>")
	)
	(arc
		(start 361.68965 -224.234248)
		(mid 361.738962 -224.419091)
		(end 361.8738 -224.554796)
		(width 0.1143)
		(layer "In6.Cu")
		(net "GMI_CPU1_G0_CPU0_G2_TX_DN<11>")
	)
	(segment
		(start 106.607864 -239.8903)
		(end 106.141012 -239.624362)
		(width 0.12954)
		(layer "F.Cu")
		(net "GMI_CPU1_G0_CPU0_G2_TX_DN<10>")
	)
	(segment
		(start 364.888018 -239.890046)
		(end 365.35487 -239.624108)
		(width 0.12954)
		(layer "F.Cu")
		(net "GMI_CPU1_G0_CPU0_G2_TX_DN<10>")
	)
	(segment
		(start 109.148118 -223.747076)
		(end 109.178598 -223.729296)
		(width 0.1143)
		(layer "In6.Cu")
		(net "GMI_CPU1_G0_CPU0_G2_TX_DN<10>")
	)
	(segment
		(start 364.227872 -228.606858)
		(end 364.248446 -228.618796)
		(width 0.1143)
		(layer "In6.Cu")
		(net "GMI_CPU1_G0_CPU0_G2_TX_DN<10>")
	)
	(segment
		(start 107.26801 -232.821734)
		(end 107.231688 -232.800652)
		(width 0.1143)
		(layer "In6.Cu")
		(net "GMI_CPU1_G0_CPU0_G2_TX_DN<10>")
	)
	(segment
		(start 364.666022 -235.87837)
		(end 364.697772 -235.896658)
		(width 0.1143)
		(layer "In6.Cu")
		(net "GMI_CPU1_G0_CPU0_G2_TX_DN<10>")
	)
	(segment
		(start 364.609888 -235.837984)
		(end 364.666022 -235.87837)
		(width 0.1143)
		(layer "In6.Cu")
		(net "GMI_CPU1_G0_CPU0_G2_TX_DN<10>")
	)
	(segment
		(start 365.606076 -237.498382)
		(end 365.635794 -237.5154)
		(width 0.1143)
		(layer "In6.Cu")
		(net "GMI_CPU1_G0_CPU0_G2_TX_DN<10>")
	)
	(segment
		(start 107.270042 -226.98583)
		(end 107.29976 -226.968812)
		(width 0.1143)
		(layer "In6.Cu")
		(net "GMI_CPU1_G0_CPU0_G2_TX_DN<10>")
	)
	(segment
		(start 107.268772 -234.442254)
		(end 107.26801 -234.441746)
		(width 0.1143)
		(layer "In6.Cu")
		(net "GMI_CPU1_G0_CPU0_G2_TX_DN<10>")
	)
	(segment
		(start 107.29976 -232.840022)
		(end 107.268772 -232.822242)
		(width 0.1143)
		(layer "In6.Cu")
		(net "GMI_CPU1_G0_CPU0_G2_TX_DN<10>")
	)
	(segment
		(start 107.26801 -231.846882)
		(end 107.268772 -231.846374)
		(width 0.1143)
		(layer "In6.Cu")
		(net "GMI_CPU1_G0_CPU0_G2_TX_DN<10>")
	)
	(segment
		(start 364.227872 -232.82148)
		(end 364.22711 -232.821988)
		(width 0.1143)
		(layer "In6.Cu")
		(net "GMI_CPU1_G0_CPU0_G2_TX_DN<10>")
	)
	(segment
		(start 364.196122 -226.968558)
		(end 364.22584 -226.985576)
		(width 0.1143)
		(layer "In6.Cu")
		(net "GMI_CPU1_G0_CPU0_G2_TX_DN<10>")
	)
	(segment
		(start 364.22711 -232.821988)
		(end 364.196122 -232.839768)
		(width 0.1143)
		(layer "In6.Cu")
		(net "GMI_CPU1_G0_CPU0_G2_TX_DN<10>")
	)
	(segment
		(start 110.274862 -221.404942)
		(end 110.274862 -221.248732)
		(width 0.1143)
		(layer "In6.Cu")
		(net "GMI_CPU1_G0_CPU0_G2_TX_DN<10>")
	)
	(segment
		(start 107.231688 -231.867964)
		(end 107.26801 -231.846882)
		(width 0.1143)
		(layer "In6.Cu")
		(net "GMI_CPU1_G0_CPU0_G2_TX_DN<10>")
	)
	(segment
		(start 364.196122 -231.82834)
		(end 364.22584 -231.845358)
		(width 0.1143)
		(layer "In6.Cu")
		(net "GMI_CPU1_G0_CPU0_G2_TX_DN<10>")
	)
	(segment
		(start 106.32821 -239.301782)
		(end 106.289094 -239.278922)
		(width 0.1143)
		(layer "In6.Cu")
		(net "GMI_CPU1_G0_CPU0_G2_TX_DN<10>")
	)
	(segment
		(start 107.301538 -231.221534)
		(end 107.300014 -231.220518)
		(width 0.1143)
		(layer "In6.Cu")
		(net "GMI_CPU1_G0_CPU0_G2_TX_DN<10>")
	)
	(segment
		(start 362.787184 -224.539048)
		(end 362.817664 -224.556828)
		(width 0.1143)
		(layer "In6.Cu")
		(net "GMI_CPU1_G0_CPU0_G2_TX_DN<10>")
	)
	(segment
		(start 362.317284 -223.729042)
		(end 362.38688 -223.769682)
		(width 0.1143)
		(layer "In6.Cu")
		(net "GMI_CPU1_G0_CPU0_G2_TX_DN<10>")
	)
	(segment
		(start 108.640118 -224.578926)
		(end 108.678218 -224.557082)
		(width 0.1143)
		(layer "In6.Cu")
		(net "GMI_CPU1_G0_CPU0_G2_TX_DN<10>")
	)
	(segment
		(start 107.26801 -227.961952)
		(end 107.231688 -227.94087)
		(width 0.1143)
		(layer "In6.Cu")
		(net "GMI_CPU1_G0_CPU0_G2_TX_DN<10>")
	)
	(segment
		(start 306.462684 -183.262778)
		(end 307.669946 -183.594502)
		(width 0.14224)
		(layer "In6.Cu")
		(net "GMI_CPU1_G0_CPU0_G2_TX_DN<10>")
	)
	(segment
		(start 106.438954 -239.624362)
		(end 106.508804 -239.554512)
		(width 0.1143)
		(layer "In6.Cu")
		(net "GMI_CPU1_G0_CPU0_G2_TX_DN<10>")
	)
	(segment
		(start 364.510066 -235.574078)
		(end 364.510066 -235.643166)
		(width 0.1143)
		(layer "In6.Cu")
		(net "GMI_CPU1_G0_CPU0_G2_TX_DN<10>")
	)
	(segment
		(start 105.85704 -237.517432)
		(end 105.858056 -237.516924)
		(width 0.1143)
		(layer "In6.Cu")
		(net "GMI_CPU1_G0_CPU0_G2_TX_DN<10>")
	)
	(segment
		(start 123.110498 -207.999076)
		(end 123.110244 -207.999076)
		(width 0.14224)
		(layer "In6.Cu")
		(net "GMI_CPU1_G0_CPU0_G2_TX_DN<10>")
	)
	(segment
		(start 364.22711 -226.986338)
		(end 364.227872 -226.986846)
		(width 0.1143)
		(layer "In6.Cu")
		(net "GMI_CPU1_G0_CPU0_G2_TX_DN<10>")
	)
	(segment
		(start 364.22711 -235.086144)
		(end 364.227872 -235.086652)
		(width 0.1143)
		(layer "In6.Cu")
		(net "GMI_CPU1_G0_CPU0_G2_TX_DN<10>")
	)
	(segment
		(start 363.287818 -225.366834)
		(end 363.326934 -225.389694)
		(width 0.1143)
		(layer "In6.Cu")
		(net "GMI_CPU1_G0_CPU0_G2_TX_DN<10>")
	)
	(segment
		(start 107.247436 -228.61905)
		(end 107.26801 -228.607112)
		(width 0.1143)
		(layer "In6.Cu")
		(net "GMI_CPU1_G0_CPU0_G2_TX_DN<10>")
	)
	(segment
		(start 365.638842 -238.491014)
		(end 365.637826 -238.491522)
		(width 0.1143)
		(layer "In6.Cu")
		(net "GMI_CPU1_G0_CPU0_G2_TX_DN<10>")
	)
	(segment
		(start 109.617002 -222.937578)
		(end 109.618018 -222.93707)
		(width 0.1143)
		(layer "In6.Cu")
		(net "GMI_CPU1_G0_CPU0_G2_TX_DN<10>")
	)
	(segment
		(start 107.26801 -235.086906)
		(end 107.268772 -235.086398)
		(width 0.1143)
		(layer "In6.Cu")
		(net "GMI_CPU1_G0_CPU0_G2_TX_DN<10>")
	)
	(segment
		(start 164.5031 -183.42737)
		(end 168.125902 -182.467758)
		(width 0.14224)
		(layer "In6.Cu")
		(net "GMI_CPU1_G0_CPU0_G2_TX_DN<10>")
	)
	(segment
		(start 361.26674 -221.17431)
		(end 361.26674 -221.202758)
		(width 0.1143)
		(layer "In6.Cu")
		(net "GMI_CPU1_G0_CPU0_G2_TX_DN<10>")
	)
	(segment
		(start 365.640366 -237.518194)
		(end 365.676942 -237.53953)
		(width 0.1143)
		(layer "In6.Cu")
		(net "GMI_CPU1_G0_CPU0_G2_TX_DN<10>")
	)
	(segment
		(start 365.638842 -237.517178)
		(end 365.640366 -237.518194)
		(width 0.1143)
		(layer "In6.Cu")
		(net "GMI_CPU1_G0_CPU0_G2_TX_DN<10>")
	)
	(segment
		(start 107.26801 -229.581964)
		(end 107.247436 -229.570026)
		(width 0.1143)
		(layer "In6.Cu")
		(net "GMI_CPU1_G0_CPU0_G2_TX_DN<10>")
	)
	(segment
		(start 361.87888 -222.937324)
		(end 361.91698 -222.959676)
		(width 0.1143)
		(layer "In6.Cu")
		(net "GMI_CPU1_G0_CPU0_G2_TX_DN<10>")
	)
	(segment
		(start 107.26801 -231.201976)
		(end 107.231688 -231.180894)
		(width 0.1143)
		(layer "In6.Cu")
		(net "GMI_CPU1_G0_CPU0_G2_TX_DN<10>")
	)
	(segment
		(start 105.858056 -238.491776)
		(end 105.85704 -238.491268)
		(width 0.1143)
		(layer "In6.Cu")
		(net "GMI_CPU1_G0_CPU0_G2_TX_DN<10>")
	)
	(segment
		(start 110.276132 -221.406212)
		(end 110.274862 -221.404942)
		(width 0.1143)
		(layer "In6.Cu")
		(net "GMI_CPU1_G0_CPU0_G2_TX_DN<10>")
	)
	(segment
		(start 364.22711 -228.60635)
		(end 364.227872 -228.606858)
		(width 0.1143)
		(layer "In6.Cu")
		(net "GMI_CPU1_G0_CPU0_G2_TX_DN<10>")
	)
	(segment
		(start 361.875832 -222.935546)
		(end 361.877102 -222.936308)
		(width 0.1143)
		(layer "In6.Cu")
		(net "GMI_CPU1_G0_CPU0_G2_TX_DN<10>")
	)
	(segment
		(start 364.22584 -231.845358)
		(end 364.22711 -231.84612)
		(width 0.1143)
		(layer "In6.Cu")
		(net "GMI_CPU1_G0_CPU0_G2_TX_DN<10>")
	)
	(segment
		(start 126.640082 -205.29042)
		(end 164.5031 -183.42737)
		(width 0.14224)
		(layer "In6.Cu")
		(net "GMI_CPU1_G0_CPU0_G2_TX_DN<10>")
	)
	(segment
		(start 105.858056 -237.516924)
		(end 105.858818 -237.516416)
		(width 0.1143)
		(layer "In6.Cu")
		(net "GMI_CPU1_G0_CPU0_G2_TX_DN<10>")
	)
	(segment
		(start 107.270042 -231.845612)
		(end 107.29976 -231.828594)
		(width 0.1143)
		(layer "In6.Cu")
		(net "GMI_CPU1_G0_CPU0_G2_TX_DN<10>")
	)
	(segment
		(start 107.268772 -227.96246)
		(end 107.26801 -227.961952)
		(width 0.1143)
		(layer "In6.Cu")
		(net "GMI_CPU1_G0_CPU0_G2_TX_DN<10>")
	)
	(segment
		(start 360.68381 -218.877642)
		(end 361.26674 -220.284548)
		(width 0.14224)
		(layer "In6.Cu")
		(net "GMI_CPU1_G0_CPU0_G2_TX_DN<10>")
	)
	(segment
		(start 364.22711 -234.442)
		(end 364.196122 -234.45978)
		(width 0.1143)
		(layer "In6.Cu")
		(net "GMI_CPU1_G0_CPU0_G2_TX_DN<10>")
	)
	(segment
		(start 109.109002 -223.769936)
		(end 109.148118 -223.747076)
		(width 0.1143)
		(layer "In6.Cu")
		(net "GMI_CPU1_G0_CPU0_G2_TX_DN<10>")
	)
	(segment
		(start 105.85704 -238.491268)
		(end 105.855516 -238.490252)
		(width 0.1143)
		(layer "In6.Cu")
		(net "GMI_CPU1_G0_CPU0_G2_TX_DN<10>")
	)
	(segment
		(start 107.268772 -233.466386)
		(end 107.270042 -233.465624)
		(width 0.1143)
		(layer "In6.Cu")
		(net "GMI_CPU1_G0_CPU0_G2_TX_DN<10>")
	)
	(segment
		(start 365.637064 -238.49203)
		(end 365.606076 -238.50981)
		(width 0.1143)
		(layer "In6.Cu")
		(net "GMI_CPU1_G0_CPU0_G2_TX_DN<10>")
	)
	(segment
		(start 107.270042 -228.605842)
		(end 107.29976 -228.588824)
		(width 0.1143)
		(layer "In6.Cu")
		(net "GMI_CPU1_G0_CPU0_G2_TX_DN<10>")
	)
	(segment
		(start 361.877864 -222.936816)
		(end 361.87888 -222.937324)
		(width 0.1143)
		(layer "In6.Cu")
		(net "GMI_CPU1_G0_CPU0_G2_TX_DN<10>")
	)
	(segment
		(start 364.196122 -230.208328)
		(end 364.227872 -230.226616)
		(width 0.1143)
		(layer "In6.Cu")
		(net "GMI_CPU1_G0_CPU0_G2_TX_DN<10>")
	)
	(segment
		(start 107.301538 -229.601522)
		(end 107.26801 -229.581964)
		(width 0.1143)
		(layer "In6.Cu")
		(net "GMI_CPU1_G0_CPU0_G2_TX_DN<10>")
	)
	(segment
		(start 107.268772 -232.822242)
		(end 107.26801 -232.821734)
		(width 0.1143)
		(layer "In6.Cu")
		(net "GMI_CPU1_G0_CPU0_G2_TX_DN<10>")
	)
	(segment
		(start 107.26801 -233.466894)
		(end 107.268772 -233.466386)
		(width 0.1143)
		(layer "In6.Cu")
		(net "GMI_CPU1_G0_CPU0_G2_TX_DN<10>")
	)
	(segment
		(start 364.22584 -226.985576)
		(end 364.22711 -226.986338)
		(width 0.1143)
		(layer "In6.Cu")
		(net "GMI_CPU1_G0_CPU0_G2_TX_DN<10>")
	)
	(segment
		(start 306.452778 -183.252872)
		(end 306.462684 -183.262778)
		(width 0.14224)
		(layer "In6.Cu")
		(net "GMI_CPU1_G0_CPU0_G2_TX_DN<10>")
	)
	(segment
		(start 105.858818 -237.516416)
		(end 105.860088 -237.515654)
		(width 0.1143)
		(layer "In6.Cu")
		(net "GMI_CPU1_G0_CPU0_G2_TX_DN<10>")
	)
	(segment
		(start 364.227872 -231.846628)
		(end 364.264194 -231.86771)
		(width 0.1143)
		(layer "In6.Cu")
		(net "GMI_CPU1_G0_CPU0_G2_TX_DN<10>")
	)
	(segment
		(start 107.699048 -226.199954)
		(end 107.738164 -226.177094)
		(width 0.1143)
		(layer "In6.Cu")
		(net "GMI_CPU1_G0_CPU0_G2_TX_DN<10>")
	)
	(segment
		(start 108.678218 -224.557082)
		(end 108.708698 -224.539302)
		(width 0.1143)
		(layer "In6.Cu")
		(net "GMI_CPU1_G0_CPU0_G2_TX_DN<10>")
	)
	(segment
		(start 110.229142 -221.203012)
		(end 110.229142 -221.174564)
		(width 0.1143)
		(layer "In6.Cu")
		(net "GMI_CPU1_G0_CPU0_G2_TX_DN<10>")
	)
	(segment
		(start 107.26801 -226.9871)
		(end 107.268772 -226.986592)
		(width 0.1143)
		(layer "In6.Cu")
		(net "GMI_CPU1_G0_CPU0_G2_TX_DN<10>")
	)
	(segment
		(start 110.274862 -221.248732)
		(end 110.229142 -221.203012)
		(width 0.1143)
		(layer "In6.Cu")
		(net "GMI_CPU1_G0_CPU0_G2_TX_DN<10>")
	)
	(segment
		(start 107.270042 -233.465624)
		(end 107.29976 -233.448606)
		(width 0.1143)
		(layer "In6.Cu")
		(net "GMI_CPU1_G0_CPU0_G2_TX_DN<10>")
	)
	(segment
		(start 107.231688 -227.008182)
		(end 107.26801 -226.9871)
		(width 0.1143)
		(layer "In6.Cu")
		(net "GMI_CPU1_G0_CPU0_G2_TX_DN<10>")
	)
	(segment
		(start 364.196122 -228.58857)
		(end 364.22584 -228.605588)
		(width 0.1143)
		(layer "In6.Cu")
		(net "GMI_CPU1_G0_CPU0_G2_TX_DN<10>")
	)
	(segment
		(start 364.264194 -231.18064)
		(end 364.19663 -231.219756)
		(width 0.1143)
		(layer "In6.Cu")
		(net "GMI_CPU1_G0_CPU0_G2_TX_DN<10>")
	)
	(segment
		(start 361.26674 -221.202758)
		(end 361.22102 -221.248478)
		(width 0.1143)
		(layer "In6.Cu")
		(net "GMI_CPU1_G0_CPU0_G2_TX_DN<10>")
	)
	(segment
		(start 365.676942 -238.468662)
		(end 365.640366 -238.489998)
		(width 0.1143)
		(layer "In6.Cu")
		(net "GMI_CPU1_G0_CPU0_G2_TX_DN<10>")
	)
	(segment
		(start 106.985816 -235.64342)
		(end 106.985816 -235.574332)
		(width 0.1143)
		(layer "In6.Cu")
		(net "GMI_CPU1_G0_CPU0_G2_TX_DN<10>")
	)
	(segment
		(start 364.697772 -235.896658)
		(end 364.736888 -235.919518)
		(width 0.1143)
		(layer "In6.Cu")
		(net "GMI_CPU1_G0_CPU0_G2_TX_DN<10>")
	)
	(segment
		(start 361.877102 -222.936308)
		(end 361.877864 -222.936816)
		(width 0.1143)
		(layer "In6.Cu")
		(net "GMI_CPU1_G0_CPU0_G2_TX_DN<10>")
	)
	(segment
		(start 110.229142 -221.174564)
		(end 110.229142 -220.451934)
		(width 0.14224)
		(layer "In6.Cu")
		(net "GMI_CPU1_G0_CPU0_G2_TX_DN<10>")
	)
	(segment
		(start 364.987078 -239.554258)
		(end 365.056928 -239.624108)
		(width 0.1143)
		(layer "In6.Cu")
		(net "GMI_CPU1_G0_CPU0_G2_TX_DN<10>")
	)
	(segment
		(start 105.860088 -237.515654)
		(end 105.889806 -237.498636)
		(width 0.1143)
		(layer "In6.Cu")
		(net "GMI_CPU1_G0_CPU0_G2_TX_DN<10>")
	)
	(segment
		(start 107.232196 -230.248206)
		(end 107.297982 -230.209852)
		(width 0.1143)
		(layer "In6.Cu")
		(net "GMI_CPU1_G0_CPU0_G2_TX_DN<10>")
	)
	(segment
		(start 364.227872 -226.986846)
		(end 364.264194 -227.007928)
		(width 0.1143)
		(layer "In6.Cu")
		(net "GMI_CPU1_G0_CPU0_G2_TX_DN<10>")
	)
	(segment
		(start 364.196122 -233.448352)
		(end 364.22584 -233.46537)
		(width 0.1143)
		(layer "In6.Cu")
		(net "GMI_CPU1_G0_CPU0_G2_TX_DN<10>")
	)
	(segment
		(start 168.125902 -182.467758)
		(end 302.892968 -183.252872)
		(width 0.14224)
		(layer "In6.Cu")
		(net "GMI_CPU1_G0_CPU0_G2_TX_DN<10>")
	)
	(segment
		(start 313.91987 -187.30595)
		(end 315.512958 -188.987176)
		(width 0.14224)
		(layer "In6.Cu")
		(net "GMI_CPU1_G0_CPU0_G2_TX_DN<10>")
	)
	(segment
		(start 364.227872 -230.226616)
		(end 364.2614 -230.246174)
		(width 0.1143)
		(layer "In6.Cu")
		(net "GMI_CPU1_G0_CPU0_G2_TX_DN<10>")
	)
	(segment
		(start 106.289094 -236.729778)
		(end 106.32821 -236.706918)
		(width 0.1143)
		(layer "In6.Cu")
		(net "GMI_CPU1_G0_CPU0_G2_TX_DN<10>")
	)
	(segment
		(start 107.26801 -234.441746)
		(end 107.231688 -234.420664)
		(width 0.1143)
		(layer "In6.Cu")
		(net "GMI_CPU1_G0_CPU0_G2_TX_DN<10>")
	)
	(segment
		(start 106.82986 -235.878624)
		(end 106.885994 -235.838238)
		(width 0.1143)
		(layer "In6.Cu")
		(net "GMI_CPU1_G0_CPU0_G2_TX_DN<10>")
	)
	(segment
		(start 106.35869 -239.319562)
		(end 106.32821 -239.301782)
		(width 0.1143)
		(layer "In6.Cu")
		(net "GMI_CPU1_G0_CPU0_G2_TX_DN<10>")
	)
	(segment
		(start 365.637826 -238.491522)
		(end 365.637064 -238.49203)
		(width 0.1143)
		(layer "In6.Cu")
		(net "GMI_CPU1_G0_CPU0_G2_TX_DN<10>")
	)
	(segment
		(start 107.268772 -226.986592)
		(end 107.270042 -226.98583)
		(width 0.1143)
		(layer "In6.Cu")
		(net "GMI_CPU1_G0_CPU0_G2_TX_DN<10>")
	)
	(segment
		(start 364.264194 -234.42041)
		(end 364.227872 -234.441492)
		(width 0.1143)
		(layer "In6.Cu")
		(net "GMI_CPU1_G0_CPU0_G2_TX_DN<10>")
	)
	(segment
		(start 362.817664 -224.556828)
		(end 362.855764 -224.578672)
		(width 0.1143)
		(layer "In6.Cu")
		(net "GMI_CPU1_G0_CPU0_G2_TX_DN<10>")
	)
	(segment
		(start 364.196122 -235.068364)
		(end 364.22584 -235.085382)
		(width 0.1143)
		(layer "In6.Cu")
		(net "GMI_CPU1_G0_CPU0_G2_TX_DN<10>")
	)
	(segment
		(start 363.258354 -225.349816)
		(end 363.287818 -225.366834)
		(width 0.1143)
		(layer "In6.Cu")
		(net "GMI_CPU1_G0_CPU0_G2_TX_DN<10>")
	)
	(segment
		(start 302.892968 -183.252872)
		(end 306.452778 -183.252872)
		(width 0.14224)
		(layer "In6.Cu")
		(net "GMI_CPU1_G0_CPU0_G2_TX_DN<10>")
	)
	(segment
		(start 364.22711 -231.84612)
		(end 364.227872 -231.846628)
		(width 0.1143)
		(layer "In6.Cu")
		(net "GMI_CPU1_G0_CPU0_G2_TX_DN<10>")
	)
	(segment
		(start 110.229142 -220.451934)
		(end 111.115602 -218.311984)
		(width 0.14224)
		(layer "In6.Cu")
		(net "GMI_CPU1_G0_CPU0_G2_TX_DN<10>")
	)
	(segment
		(start 361.846114 -222.918528)
		(end 361.875832 -222.935546)
		(width 0.1143)
		(layer "In6.Cu")
		(net "GMI_CPU1_G0_CPU0_G2_TX_DN<10>")
	)
	(segment
		(start 105.855516 -238.490252)
		(end 105.81894 -238.468916)
		(width 0.1143)
		(layer "In6.Cu")
		(net "GMI_CPU1_G0_CPU0_G2_TX_DN<10>")
	)
	(segment
		(start 353.829112 -212.826092)
		(end 357.719376 -215.914478)
		(width 0.14224)
		(layer "In6.Cu")
		(net "GMI_CPU1_G0_CPU0_G2_TX_DN<10>")
	)
	(segment
		(start 364.227872 -233.46664)
		(end 364.264194 -233.487722)
		(width 0.1143)
		(layer "In6.Cu")
		(net "GMI_CPU1_G0_CPU0_G2_TX_DN<10>")
	)
	(segment
		(start 107.26801 -228.607112)
		(end 107.268772 -228.606604)
		(width 0.1143)
		(layer "In6.Cu")
		(net "GMI_CPU1_G0_CPU0_G2_TX_DN<10>")
	)
	(segment
		(start 364.227872 -229.58171)
		(end 364.194344 -229.601268)
		(width 0.1143)
		(layer "In6.Cu")
		(net "GMI_CPU1_G0_CPU0_G2_TX_DN<10>")
	)
	(segment
		(start 361.26674 -220.284548)
		(end 361.26674 -221.17431)
		(width 0.14224)
		(layer "In6.Cu")
		(net "GMI_CPU1_G0_CPU0_G2_TX_DN<10>")
	)
	(segment
		(start 108.168948 -225.389948)
		(end 108.208064 -225.367088)
		(width 0.1143)
		(layer "In6.Cu")
		(net "GMI_CPU1_G0_CPU0_G2_TX_DN<10>")
	)
	(segment
		(start 307.669946 -183.594502)
		(end 313.91987 -187.30595)
		(width 0.14224)
		(layer "In6.Cu")
		(net "GMI_CPU1_G0_CPU0_G2_TX_DN<10>")
	)
	(segment
		(start 365.056928 -239.624108)
		(end 365.35487 -239.624108)
		(width 0.1143)
		(layer "In6.Cu")
		(net "GMI_CPU1_G0_CPU0_G2_TX_DN<10>")
	)
	(segment
		(start 107.231688 -233.487976)
		(end 107.26801 -233.466894)
		(width 0.1143)
		(layer "In6.Cu")
		(net "GMI_CPU1_G0_CPU0_G2_TX_DN<10>")
	)
	(segment
		(start 365.637826 -237.51667)
		(end 365.638842 -237.517178)
		(width 0.1143)
		(layer "In6.Cu")
		(net "GMI_CPU1_G0_CPU0_G2_TX_DN<10>")
	)
	(segment
		(start 315.512958 -188.987176)
		(end 353.829112 -212.826092)
		(width 0.14224)
		(layer "In6.Cu")
		(net "GMI_CPU1_G0_CPU0_G2_TX_DN<10>")
	)
	(segment
		(start 364.22584 -235.085382)
		(end 364.22711 -235.086144)
		(width 0.1143)
		(layer "In6.Cu")
		(net "GMI_CPU1_G0_CPU0_G2_TX_DN<10>")
	)
	(segment
		(start 107.29976 -234.460034)
		(end 107.268772 -234.442254)
		(width 0.1143)
		(layer "In6.Cu")
		(net "GMI_CPU1_G0_CPU0_G2_TX_DN<10>")
	)
	(segment
		(start 107.300014 -231.220518)
		(end 107.26801 -231.201976)
		(width 0.1143)
		(layer "In6.Cu")
		(net "GMI_CPU1_G0_CPU0_G2_TX_DN<10>")
	)
	(segment
		(start 365.640366 -238.489998)
		(end 365.638842 -238.491014)
		(width 0.1143)
		(layer "In6.Cu")
		(net "GMI_CPU1_G0_CPU0_G2_TX_DN<10>")
	)
	(segment
		(start 108.208064 -225.367088)
		(end 108.237528 -225.35007)
		(width 0.1143)
		(layer "In6.Cu")
		(net "GMI_CPU1_G0_CPU0_G2_TX_DN<10>")
	)
	(segment
		(start 364.248446 -229.569772)
		(end 364.227872 -229.58171)
		(width 0.1143)
		(layer "In6.Cu")
		(net "GMI_CPU1_G0_CPU0_G2_TX_DN<10>")
	)
	(segment
		(start 364.227872 -227.961698)
		(end 364.22711 -227.962206)
		(width 0.1143)
		(layer "In6.Cu")
		(net "GMI_CPU1_G0_CPU0_G2_TX_DN<10>")
	)
	(segment
		(start 107.154218 -230.31577)
		(end 107.232196 -230.248206)
		(width 0.1143)
		(layer "In6.Cu")
		(net "GMI_CPU1_G0_CPU0_G2_TX_DN<10>")
	)
	(segment
		(start 365.206788 -239.278668)
		(end 365.137192 -239.319308)
		(width 0.1143)
		(layer "In6.Cu")
		(net "GMI_CPU1_G0_CPU0_G2_TX_DN<10>")
	)
	(segment
		(start 361.37596 -222.108522)
		(end 361.446826 -222.14967)
		(width 0.1143)
		(layer "In6.Cu")
		(net "GMI_CPU1_G0_CPU0_G2_TX_DN<10>")
	)
	(segment
		(start 365.137192 -236.688884)
		(end 365.206788 -236.729524)
		(width 0.1143)
		(layer "In6.Cu")
		(net "GMI_CPU1_G0_CPU0_G2_TX_DN<10>")
	)
	(segment
		(start 364.22584 -233.46537)
		(end 364.22711 -233.466132)
		(width 0.1143)
		(layer "In6.Cu")
		(net "GMI_CPU1_G0_CPU0_G2_TX_DN<10>")
	)
	(segment
		(start 364.22711 -227.962206)
		(end 364.196122 -227.979986)
		(width 0.1143)
		(layer "In6.Cu")
		(net "GMI_CPU1_G0_CPU0_G2_TX_DN<10>")
	)
	(segment
		(start 105.81894 -237.539784)
		(end 105.85704 -237.517432)
		(width 0.1143)
		(layer "In6.Cu")
		(net "GMI_CPU1_G0_CPU0_G2_TX_DN<10>")
	)
	(segment
		(start 109.578902 -222.95993)
		(end 109.617002 -222.937578)
		(width 0.1143)
		(layer "In6.Cu")
		(net "GMI_CPU1_G0_CPU0_G2_TX_DN<10>")
	)
	(segment
		(start 105.858818 -238.492284)
		(end 105.858056 -238.491776)
		(width 0.1143)
		(layer "In6.Cu")
		(net "GMI_CPU1_G0_CPU0_G2_TX_DN<10>")
	)
	(segment
		(start 364.227872 -235.086652)
		(end 364.230666 -235.088176)
		(width 0.1143)
		(layer "In6.Cu")
		(net "GMI_CPU1_G0_CPU0_G2_TX_DN<10>")
	)
	(segment
		(start 107.231688 -235.107988)
		(end 107.26801 -235.086906)
		(width 0.1143)
		(layer "In6.Cu")
		(net "GMI_CPU1_G0_CPU0_G2_TX_DN<10>")
	)
	(segment
		(start 106.141012 -239.624362)
		(end 106.438954 -239.624362)
		(width 0.1143)
		(layer "In6.Cu")
		(net "GMI_CPU1_G0_CPU0_G2_TX_DN<10>")
	)
	(segment
		(start 361.22102 -221.248478)
		(end 361.22102 -221.404688)
		(width 0.1143)
		(layer "In6.Cu")
		(net "GMI_CPU1_G0_CPU0_G2_TX_DN<10>")
	)
	(segment
		(start 107.29976 -227.98024)
		(end 107.268772 -227.96246)
		(width 0.1143)
		(layer "In6.Cu")
		(net "GMI_CPU1_G0_CPU0_G2_TX_DN<10>")
	)
	(segment
		(start 110.049056 -222.149924)
		(end 110.119922 -222.108776)
		(width 0.1143)
		(layer "In6.Cu")
		(net "GMI_CPU1_G0_CPU0_G2_TX_DN<10>")
	)
	(segment
		(start 106.985816 -230.716328)
		(end 106.995468 -230.62057)
		(width 0.1143)
		(layer "In6.Cu")
		(net "GMI_CPU1_G0_CPU0_G2_TX_DN<10>")
	)
	(segment
		(start 363.727238 -226.15906)
		(end 363.796834 -226.1997)
		(width 0.1143)
		(layer "In6.Cu")
		(net "GMI_CPU1_G0_CPU0_G2_TX_DN<10>")
	)
	(segment
		(start 364.264194 -227.940616)
		(end 364.227872 -227.961698)
		(width 0.1143)
		(layer "In6.Cu")
		(net "GMI_CPU1_G0_CPU0_G2_TX_DN<10>")
	)
	(segment
		(start 123.110244 -207.999076)
		(end 126.640082 -205.29042)
		(width 0.14224)
		(layer "In6.Cu")
		(net "GMI_CPU1_G0_CPU0_G2_TX_DN<10>")
	)
	(segment
		(start 106.32821 -236.706918)
		(end 106.35869 -236.689138)
		(width 0.1143)
		(layer "In6.Cu")
		(net "GMI_CPU1_G0_CPU0_G2_TX_DN<10>")
	)
	(segment
		(start 111.115602 -218.311984)
		(end 115.881404 -213.545928)
		(width 0.14224)
		(layer "In6.Cu")
		(net "GMI_CPU1_G0_CPU0_G2_TX_DN<10>")
	)
	(segment
		(start 107.270042 -235.085636)
		(end 107.29976 -235.068618)
		(width 0.1143)
		(layer "In6.Cu")
		(net "GMI_CPU1_G0_CPU0_G2_TX_DN<10>")
	)
	(segment
		(start 109.618018 -222.93707)
		(end 109.61878 -222.936562)
		(width 0.1143)
		(layer "In6.Cu")
		(net "GMI_CPU1_G0_CPU0_G2_TX_DN<10>")
	)
	(segment
		(start 115.881404 -213.545928)
		(end 123.110498 -207.999076)
		(width 0.14224)
		(layer "In6.Cu")
		(net "GMI_CPU1_G0_CPU0_G2_TX_DN<10>")
	)
	(segment
		(start 361.21975 -221.405958)
		(end 361.21975 -221.80423)
		(width 0.1143)
		(layer "In6.Cu")
		(net "GMI_CPU1_G0_CPU0_G2_TX_DN<10>")
	)
	(segment
		(start 109.62005 -222.9358)
		(end 109.649768 -222.918782)
		(width 0.1143)
		(layer "In6.Cu")
		(net "GMI_CPU1_G0_CPU0_G2_TX_DN<10>")
	)
	(segment
		(start 107.738164 -226.177094)
		(end 107.768644 -226.159314)
		(width 0.1143)
		(layer "In6.Cu")
		(net "GMI_CPU1_G0_CPU0_G2_TX_DN<10>")
	)
	(segment
		(start 106.758994 -235.919772)
		(end 106.79811 -235.896912)
		(width 0.1143)
		(layer "In6.Cu")
		(net "GMI_CPU1_G0_CPU0_G2_TX_DN<10>")
	)
	(segment
		(start 105.889806 -238.510064)
		(end 105.858818 -238.492284)
		(width 0.1143)
		(layer "In6.Cu")
		(net "GMI_CPU1_G0_CPU0_G2_TX_DN<10>")
	)
	(segment
		(start 365.635794 -237.5154)
		(end 365.637064 -237.516162)
		(width 0.1143)
		(layer "In6.Cu")
		(net "GMI_CPU1_G0_CPU0_G2_TX_DN<10>")
	)
	(segment
		(start 364.22584 -228.605588)
		(end 364.22711 -228.60635)
		(width 0.1143)
		(layer "In6.Cu")
		(net "GMI_CPU1_G0_CPU0_G2_TX_DN<10>")
	)
	(segment
		(start 107.268772 -231.846374)
		(end 107.270042 -231.845612)
		(width 0.1143)
		(layer "In6.Cu")
		(net "GMI_CPU1_G0_CPU0_G2_TX_DN<10>")
	)
	(segment
		(start 365.637064 -237.516162)
		(end 365.637826 -237.51667)
		(width 0.1143)
		(layer "In6.Cu")
		(net "GMI_CPU1_G0_CPU0_G2_TX_DN<10>")
	)
	(segment
		(start 364.264194 -232.800398)
		(end 364.227872 -232.82148)
		(width 0.1143)
		(layer "In6.Cu")
		(net "GMI_CPU1_G0_CPU0_G2_TX_DN<10>")
	)
	(segment
		(start 364.19663 -231.219756)
		(end 364.194344 -231.22128)
		(width 0.1143)
		(layer "In6.Cu")
		(net "GMI_CPU1_G0_CPU0_G2_TX_DN<10>")
	)
	(segment
		(start 107.268772 -235.086398)
		(end 107.270042 -235.085636)
		(width 0.1143)
		(layer "In6.Cu")
		(net "GMI_CPU1_G0_CPU0_G2_TX_DN<10>")
	)
	(segment
		(start 361.22102 -221.404688)
		(end 361.21975 -221.405958)
		(width 0.1143)
		(layer "In6.Cu")
		(net "GMI_CPU1_G0_CPU0_G2_TX_DN<10>")
	)
	(segment
		(start 364.227872 -234.441492)
		(end 364.22711 -234.442)
		(width 0.1143)
		(layer "In6.Cu")
		(net "GMI_CPU1_G0_CPU0_G2_TX_DN<10>")
	)
	(segment
		(start 107.268772 -228.606604)
		(end 107.270042 -228.605842)
		(width 0.1143)
		(layer "In6.Cu")
		(net "GMI_CPU1_G0_CPU0_G2_TX_DN<10>")
	)
	(segment
		(start 106.79811 -235.896912)
		(end 106.82986 -235.878624)
		(width 0.1143)
		(layer "In6.Cu")
		(net "GMI_CPU1_G0_CPU0_G2_TX_DN<10>")
	)
	(segment
		(start 357.719376 -215.914478)
		(end 360.68381 -218.877642)
		(width 0.14224)
		(layer "In6.Cu")
		(net "GMI_CPU1_G0_CPU0_G2_TX_DN<10>")
	)
	(segment
		(start 109.61878 -222.936562)
		(end 109.62005 -222.9358)
		(width 0.1143)
		(layer "In6.Cu")
		(net "GMI_CPU1_G0_CPU0_G2_TX_DN<10>")
	)
	(segment
		(start 364.22711 -233.466132)
		(end 364.227872 -233.46664)
		(width 0.1143)
		(layer "In6.Cu")
		(net "GMI_CPU1_G0_CPU0_G2_TX_DN<10>")
	)
	(segment
		(start 110.276132 -221.804484)
		(end 110.276132 -221.406212)
		(width 0.1143)
		(layer "In6.Cu")
		(net "GMI_CPU1_G0_CPU0_G2_TX_DN<10>")
	)
	(segment
		(start 364.230666 -235.088176)
		(end 364.264194 -235.107734)
		(width 0.1143)
		(layer "In6.Cu")
		(net "GMI_CPU1_G0_CPU0_G2_TX_DN<10>")
	)
	(arc
		(start 364.040166 -231.524048)
		(mid 364.081421 -231.695019)
		(end 364.196122 -231.82834)
		(width 0.1143)
		(layer "In6.Cu")
		(net "GMI_CPU1_G0_CPU0_G2_TX_DN<10>")
	)
	(arc
		(start 364.279434 -233.49839)
		(mid 364.504605 -233.954066)
		(end 364.279434 -234.409742)
		(width 0.1143)
		(layer "In6.Cu")
		(net "GMI_CPU1_G0_CPU0_G2_TX_DN<10>")
	)
	(arc
		(start 364.278418 -232.790492)
		(mid 364.271345 -232.795501)
		(end 364.264194 -232.800398)
		(width 0.1143)
		(layer "In6.Cu")
		(net "GMI_CPU1_G0_CPU0_G2_TX_DN<10>")
	)
	(arc
		(start 106.045762 -237.194344)
		(mid 106.110277 -236.932125)
		(end 106.289094 -236.729778)
		(width 0.1143)
		(layer "In6.Cu")
		(net "GMI_CPU1_G0_CPU0_G2_TX_DN<10>")
	)
	(arc
		(start 363.796834 -226.1997)
		(mid 363.975647 -226.40205)
		(end 364.040166 -226.664266)
		(width 0.1143)
		(layer "In6.Cu")
		(net "GMI_CPU1_G0_CPU0_G2_TX_DN<10>")
	)
	(arc
		(start 107.216448 -233.498644)
		(mid 107.224024 -233.493248)
		(end 107.231688 -233.487976)
		(width 0.1143)
		(layer "In6.Cu")
		(net "GMI_CPU1_G0_CPU0_G2_TX_DN<10>")
	)
	(arc
		(start 363.570266 -225.85426)
		(mid 363.611815 -226.025682)
		(end 363.727238 -226.15906)
		(width 0.1143)
		(layer "In6.Cu")
		(net "GMI_CPU1_G0_CPU0_G2_TX_DN<10>")
	)
	(arc
		(start 361.286044 -222.016574)
		(mid 361.327027 -222.066436)
		(end 361.37596 -222.108522)
		(width 0.1143)
		(layer "In6.Cu")
		(net "GMI_CPU1_G0_CPU0_G2_TX_DN<10>")
	)
	(arc
		(start 106.289094 -239.278922)
		(mid 106.110281 -239.076572)
		(end 106.045762 -238.814356)
		(width 0.1143)
		(layer "In6.Cu")
		(net "GMI_CPU1_G0_CPU0_G2_TX_DN<10>")
	)
	(arc
		(start 107.217464 -232.790746)
		(mid 106.990081 -232.334308)
		(end 107.217464 -231.87787)
		(width 0.1143)
		(layer "In6.Cu")
		(net "GMI_CPU1_G0_CPU0_G2_TX_DN<10>")
	)
	(arc
		(start 364.278418 -231.877616)
		(mid 364.505801 -232.334054)
		(end 364.278418 -232.790492)
		(width 0.1143)
		(layer "In6.Cu")
		(net "GMI_CPU1_G0_CPU0_G2_TX_DN<10>")
	)
	(arc
		(start 109.33557 -223.424496)
		(mid 109.400085 -223.162277)
		(end 109.578902 -222.95993)
		(width 0.1143)
		(layer "In6.Cu")
		(net "GMI_CPU1_G0_CPU0_G2_TX_DN<10>")
	)
	(arc
		(start 108.708698 -224.539302)
		(mid 108.824125 -224.405926)
		(end 108.86567 -224.234502)
		(width 0.1143)
		(layer "In6.Cu")
		(net "GMI_CPU1_G0_CPU0_G2_TX_DN<10>")
	)
	(arc
		(start 107.216448 -227.01885)
		(mid 107.224024 -227.013454)
		(end 107.231688 -227.008182)
		(width 0.1143)
		(layer "In6.Cu")
		(net "GMI_CPU1_G0_CPU0_G2_TX_DN<10>")
	)
	(arc
		(start 106.995468 -230.62057)
		(mid 107.045683 -230.452978)
		(end 107.154218 -230.31577)
		(width 0.1143)
		(layer "In6.Cu")
		(net "GMI_CPU1_G0_CPU0_G2_TX_DN<10>")
	)
	(arc
		(start 361.21975 -221.80423)
		(mid 361.2368 -221.915421)
		(end 361.286044 -222.016574)
		(width 0.1143)
		(layer "In6.Cu")
		(net "GMI_CPU1_G0_CPU0_G2_TX_DN<10>")
	)
	(arc
		(start 365.45012 -238.814102)
		(mid 365.385605 -239.076321)
		(end 365.206788 -239.278668)
		(width 0.1143)
		(layer "In6.Cu")
		(net "GMI_CPU1_G0_CPU0_G2_TX_DN<10>")
	)
	(arc
		(start 106.885994 -235.838238)
		(mid 106.959405 -235.75287)
		(end 106.985816 -235.64342)
		(width 0.1143)
		(layer "In6.Cu")
		(net "GMI_CPU1_G0_CPU0_G2_TX_DN<10>")
	)
	(arc
		(start 364.277656 -231.170988)
		(mid 364.270961 -231.175864)
		(end 364.264194 -231.18064)
		(width 0.1143)
		(layer "In6.Cu")
		(net "GMI_CPU1_G0_CPU0_G2_TX_DN<10>")
	)
	(arc
		(start 364.196122 -234.45978)
		(mid 364.040194 -234.764072)
		(end 364.196122 -235.068364)
		(width 0.1143)
		(layer "In6.Cu")
		(net "GMI_CPU1_G0_CPU0_G2_TX_DN<10>")
	)
	(arc
		(start 364.248446 -228.618796)
		(mid 364.522183 -229.094284)
		(end 364.248446 -229.569772)
		(width 0.1143)
		(layer "In6.Cu")
		(net "GMI_CPU1_G0_CPU0_G2_TX_DN<10>")
	)
	(arc
		(start 107.29976 -228.588824)
		(mid 107.455688 -228.284532)
		(end 107.29976 -227.98024)
		(width 0.1143)
		(layer "In6.Cu")
		(net "GMI_CPU1_G0_CPU0_G2_TX_DN<10>")
	)
	(arc
		(start 107.455716 -231.524302)
		(mid 107.414954 -231.354418)
		(end 107.301538 -231.221534)
		(width 0.1143)
		(layer "In6.Cu")
		(net "GMI_CPU1_G0_CPU0_G2_TX_DN<10>")
	)
	(arc
		(start 364.98022 -236.384084)
		(mid 365.021769 -236.555506)
		(end 365.137192 -236.688884)
		(width 0.1143)
		(layer "In6.Cu")
		(net "GMI_CPU1_G0_CPU0_G2_TX_DN<10>")
	)
	(arc
		(start 105.889806 -237.498636)
		(mid 106.004482 -237.365302)
		(end 106.045762 -237.194344)
		(width 0.1143)
		(layer "In6.Cu")
		(net "GMI_CPU1_G0_CPU0_G2_TX_DN<10>")
	)
	(arc
		(start 361.91698 -222.959676)
		(mid 362.095793 -223.162026)
		(end 362.160312 -223.424242)
		(width 0.1143)
		(layer "In6.Cu")
		(net "GMI_CPU1_G0_CPU0_G2_TX_DN<10>")
	)
	(arc
		(start 105.81894 -238.468916)
		(mid 105.575613 -238.00435)
		(end 105.81894 -237.539784)
		(width 0.1143)
		(layer "In6.Cu")
		(net "GMI_CPU1_G0_CPU0_G2_TX_DN<10>")
	)
	(arc
		(start 107.231688 -227.94087)
		(mid 107.224024 -227.935599)
		(end 107.216448 -227.930202)
		(width 0.1143)
		(layer "In6.Cu")
		(net "GMI_CPU1_G0_CPU0_G2_TX_DN<10>")
	)
	(arc
		(start 364.510066 -230.714296)
		(mid 364.448621 -230.970508)
		(end 364.277656 -231.170988)
		(width 0.1143)
		(layer "In6.Cu")
		(net "GMI_CPU1_G0_CPU0_G2_TX_DN<10>")
	)
	(arc
		(start 107.216448 -227.930202)
		(mid 106.991277 -227.474526)
		(end 107.216448 -227.01885)
		(width 0.1143)
		(layer "In6.Cu")
		(net "GMI_CPU1_G0_CPU0_G2_TX_DN<10>")
	)
	(arc
		(start 364.196122 -227.979986)
		(mid 364.040194 -228.284278)
		(end 364.196122 -228.58857)
		(width 0.1143)
		(layer "In6.Cu")
		(net "GMI_CPU1_G0_CPU0_G2_TX_DN<10>")
	)
	(arc
		(start 361.690158 -222.614236)
		(mid 361.731413 -222.785207)
		(end 361.846114 -222.918528)
		(width 0.1143)
		(layer "In6.Cu")
		(net "GMI_CPU1_G0_CPU0_G2_TX_DN<10>")
	)
	(arc
		(start 107.218226 -231.171242)
		(mid 107.047585 -230.971581)
		(end 106.985816 -230.716328)
		(width 0.1143)
		(layer "In6.Cu")
		(net "GMI_CPU1_G0_CPU0_G2_TX_DN<10>")
	)
	(arc
		(start 362.160312 -223.424242)
		(mid 362.201861 -223.595664)
		(end 362.317284 -223.729042)
		(width 0.1143)
		(layer "In6.Cu")
		(net "GMI_CPU1_G0_CPU0_G2_TX_DN<10>")
	)
	(arc
		(start 362.38688 -223.769682)
		(mid 362.565693 -223.972032)
		(end 362.630212 -224.234248)
		(width 0.1143)
		(layer "In6.Cu")
		(net "GMI_CPU1_G0_CPU0_G2_TX_DN<10>")
	)
	(arc
		(start 107.455716 -226.66452)
		(mid 107.520231 -226.402301)
		(end 107.699048 -226.199954)
		(width 0.1143)
		(layer "In6.Cu")
		(net "GMI_CPU1_G0_CPU0_G2_TX_DN<10>")
	)
	(arc
		(start 106.045762 -238.814356)
		(mid 106.004507 -238.643385)
		(end 105.889806 -238.510064)
		(width 0.1143)
		(layer "In6.Cu")
		(net "GMI_CPU1_G0_CPU0_G2_TX_DN<10>")
	)
	(arc
		(start 107.216448 -234.409996)
		(mid 106.991277 -233.95432)
		(end 107.216448 -233.498644)
		(width 0.1143)
		(layer "In6.Cu")
		(net "GMI_CPU1_G0_CPU0_G2_TX_DN<10>")
	)
	(arc
		(start 361.446826 -222.14967)
		(mid 361.625639 -222.35202)
		(end 361.690158 -222.614236)
		(width 0.1143)
		(layer "In6.Cu")
		(net "GMI_CPU1_G0_CPU0_G2_TX_DN<10>")
	)
	(arc
		(start 364.194344 -229.601268)
		(mid 364.080937 -229.734157)
		(end 364.040166 -229.904036)
		(width 0.1143)
		(layer "In6.Cu")
		(net "GMI_CPU1_G0_CPU0_G2_TX_DN<10>")
	)
	(arc
		(start 107.231688 -231.180894)
		(mid 107.224922 -231.176117)
		(end 107.218226 -231.171242)
		(width 0.1143)
		(layer "In6.Cu")
		(net "GMI_CPU1_G0_CPU0_G2_TX_DN<10>")
	)
	(arc
		(start 107.768644 -226.159314)
		(mid 107.884071 -226.025938)
		(end 107.925616 -225.854514)
		(width 0.1143)
		(layer "In6.Cu")
		(net "GMI_CPU1_G0_CPU0_G2_TX_DN<10>")
	)
	(arc
		(start 109.178598 -223.729296)
		(mid 109.294025 -223.59592)
		(end 109.33557 -223.424496)
		(width 0.1143)
		(layer "In6.Cu")
		(net "GMI_CPU1_G0_CPU0_G2_TX_DN<10>")
	)
	(arc
		(start 106.985816 -235.574332)
		(mid 107.051052 -235.310741)
		(end 107.231688 -235.107988)
		(width 0.1143)
		(layer "In6.Cu")
		(net "GMI_CPU1_G0_CPU0_G2_TX_DN<10>")
	)
	(arc
		(start 365.676942 -237.53953)
		(mid 365.920269 -238.004096)
		(end 365.676942 -238.468662)
		(width 0.1143)
		(layer "In6.Cu")
		(net "GMI_CPU1_G0_CPU0_G2_TX_DN<10>")
	)
	(arc
		(start 365.45012 -237.19409)
		(mid 365.491375 -237.365061)
		(end 365.606076 -237.498382)
		(width 0.1143)
		(layer "In6.Cu")
		(net "GMI_CPU1_G0_CPU0_G2_TX_DN<10>")
	)
	(arc
		(start 364.264194 -231.86771)
		(mid 364.271344 -231.872608)
		(end 364.278418 -231.877616)
		(width 0.1143)
		(layer "In6.Cu")
		(net "GMI_CPU1_G0_CPU0_G2_TX_DN<10>")
	)
	(arc
		(start 365.606076 -238.50981)
		(mid 365.4914 -238.643144)
		(end 365.45012 -238.814102)
		(width 0.1143)
		(layer "In6.Cu")
		(net "GMI_CPU1_G0_CPU0_G2_TX_DN<10>")
	)
	(arc
		(start 363.326934 -225.389694)
		(mid 363.505747 -225.592044)
		(end 363.570266 -225.85426)
		(width 0.1143)
		(layer "In6.Cu")
		(net "GMI_CPU1_G0_CPU0_G2_TX_DN<10>")
	)
	(arc
		(start 107.29976 -226.968812)
		(mid 107.414436 -226.835478)
		(end 107.455716 -226.66452)
		(width 0.1143)
		(layer "In6.Cu")
		(net "GMI_CPU1_G0_CPU0_G2_TX_DN<10>")
	)
	(arc
		(start 106.35869 -236.689138)
		(mid 106.474117 -236.555762)
		(end 106.515662 -236.384338)
		(width 0.1143)
		(layer "In6.Cu")
		(net "GMI_CPU1_G0_CPU0_G2_TX_DN<10>")
	)
	(arc
		(start 107.231688 -234.420664)
		(mid 107.224024 -234.415393)
		(end 107.216448 -234.409996)
		(width 0.1143)
		(layer "In6.Cu")
		(net "GMI_CPU1_G0_CPU0_G2_TX_DN<10>")
	)
	(arc
		(start 365.137192 -239.319308)
		(mid 365.039427 -239.422284)
		(end 364.987078 -239.554258)
		(width 0.1143)
		(layer "In6.Cu")
		(net "GMI_CPU1_G0_CPU0_G2_TX_DN<10>")
	)
	(arc
		(start 364.264194 -235.107734)
		(mid 364.444846 -235.310479)
		(end 364.510066 -235.574078)
		(width 0.1143)
		(layer "In6.Cu")
		(net "GMI_CPU1_G0_CPU0_G2_TX_DN<10>")
	)
	(arc
		(start 364.264194 -233.487722)
		(mid 364.271858 -233.492993)
		(end 364.279434 -233.49839)
		(width 0.1143)
		(layer "In6.Cu")
		(net "GMI_CPU1_G0_CPU0_G2_TX_DN<10>")
	)
	(arc
		(start 106.508804 -239.554512)
		(mid 106.456387 -239.422581)
		(end 106.35869 -239.319562)
		(width 0.1143)
		(layer "In6.Cu")
		(net "GMI_CPU1_G0_CPU0_G2_TX_DN<10>")
	)
	(arc
		(start 107.29976 -230.208582)
		(mid 107.414436 -230.075248)
		(end 107.455716 -229.90429)
		(width 0.1143)
		(layer "In6.Cu")
		(net "GMI_CPU1_G0_CPU0_G2_TX_DN<10>")
	)
	(arc
		(start 106.515662 -236.384338)
		(mid 106.580177 -236.122119)
		(end 106.758994 -235.919772)
		(width 0.1143)
		(layer "In6.Cu")
		(net "GMI_CPU1_G0_CPU0_G2_TX_DN<10>")
	)
	(arc
		(start 364.510066 -235.643166)
		(mid 364.536474 -235.752618)
		(end 364.609888 -235.837984)
		(width 0.1143)
		(layer "In6.Cu")
		(net "GMI_CPU1_G0_CPU0_G2_TX_DN<10>")
	)
	(arc
		(start 363.100366 -225.044254)
		(mid 363.142206 -225.21624)
		(end 363.258354 -225.349816)
		(width 0.1143)
		(layer "In6.Cu")
		(net "GMI_CPU1_G0_CPU0_G2_TX_DN<10>")
	)
	(arc
		(start 362.855764 -224.578672)
		(mid 363.035493 -224.781292)
		(end 363.100366 -225.044254)
		(width 0.1143)
		(layer "In6.Cu")
		(net "GMI_CPU1_G0_CPU0_G2_TX_DN<10>")
	)
	(arc
		(start 364.264194 -227.007928)
		(mid 364.271858 -227.013199)
		(end 364.279434 -227.018596)
		(width 0.1143)
		(layer "In6.Cu")
		(net "GMI_CPU1_G0_CPU0_G2_TX_DN<10>")
	)
	(arc
		(start 107.29976 -233.448606)
		(mid 107.455688 -233.144314)
		(end 107.29976 -232.840022)
		(width 0.1143)
		(layer "In6.Cu")
		(net "GMI_CPU1_G0_CPU0_G2_TX_DN<10>")
	)
	(arc
		(start 108.237528 -225.35007)
		(mid 108.353709 -225.216511)
		(end 108.395516 -225.044508)
		(width 0.1143)
		(layer "In6.Cu")
		(net "GMI_CPU1_G0_CPU0_G2_TX_DN<10>")
	)
	(arc
		(start 364.279434 -227.929948)
		(mid 364.271858 -227.935344)
		(end 364.264194 -227.940616)
		(width 0.1143)
		(layer "In6.Cu")
		(net "GMI_CPU1_G0_CPU0_G2_TX_DN<10>")
	)
	(arc
		(start 364.194344 -231.22128)
		(mid 364.080937 -231.354169)
		(end 364.040166 -231.524048)
		(width 0.1143)
		(layer "In6.Cu")
		(net "GMI_CPU1_G0_CPU0_G2_TX_DN<10>")
	)
	(arc
		(start 107.231688 -232.800652)
		(mid 107.224539 -232.795752)
		(end 107.217464 -232.790746)
		(width 0.1143)
		(layer "In6.Cu")
		(net "GMI_CPU1_G0_CPU0_G2_TX_DN<10>")
	)
	(arc
		(start 107.247436 -229.570026)
		(mid 106.973699 -229.094538)
		(end 107.247436 -228.61905)
		(width 0.1143)
		(layer "In6.Cu")
		(net "GMI_CPU1_G0_CPU0_G2_TX_DN<10>")
	)
	(arc
		(start 107.29976 -235.068618)
		(mid 107.455688 -234.764326)
		(end 107.29976 -234.460034)
		(width 0.1143)
		(layer "In6.Cu")
		(net "GMI_CPU1_G0_CPU0_G2_TX_DN<10>")
	)
	(arc
		(start 107.925616 -225.854514)
		(mid 107.990131 -225.592295)
		(end 108.168948 -225.389948)
		(width 0.1143)
		(layer "In6.Cu")
		(net "GMI_CPU1_G0_CPU0_G2_TX_DN<10>")
	)
	(arc
		(start 110.209838 -222.016828)
		(mid 110.259158 -221.915699)
		(end 110.276132 -221.804484)
		(width 0.1143)
		(layer "In6.Cu")
		(net "GMI_CPU1_G0_CPU0_G2_TX_DN<10>")
	)
	(arc
		(start 364.279434 -234.409742)
		(mid 364.271858 -234.415138)
		(end 364.264194 -234.42041)
		(width 0.1143)
		(layer "In6.Cu")
		(net "GMI_CPU1_G0_CPU0_G2_TX_DN<10>")
	)
	(arc
		(start 364.196122 -232.839768)
		(mid 364.040194 -233.14406)
		(end 364.196122 -233.448352)
		(width 0.1143)
		(layer "In6.Cu")
		(net "GMI_CPU1_G0_CPU0_G2_TX_DN<10>")
	)
	(arc
		(start 365.206788 -236.729524)
		(mid 365.385601 -236.931874)
		(end 365.45012 -237.19409)
		(width 0.1143)
		(layer "In6.Cu")
		(net "GMI_CPU1_G0_CPU0_G2_TX_DN<10>")
	)
	(arc
		(start 109.649768 -222.918782)
		(mid 109.764444 -222.785448)
		(end 109.805724 -222.61449)
		(width 0.1143)
		(layer "In6.Cu")
		(net "GMI_CPU1_G0_CPU0_G2_TX_DN<10>")
	)
	(arc
		(start 107.217464 -231.87787)
		(mid 107.224538 -231.872863)
		(end 107.231688 -231.867964)
		(width 0.1143)
		(layer "In6.Cu")
		(net "GMI_CPU1_G0_CPU0_G2_TX_DN<10>")
	)
	(arc
		(start 110.119922 -222.108776)
		(mid 110.168854 -222.066688)
		(end 110.209838 -222.016828)
		(width 0.1143)
		(layer "In6.Cu")
		(net "GMI_CPU1_G0_CPU0_G2_TX_DN<10>")
	)
	(arc
		(start 364.2614 -230.246174)
		(mid 364.433117 -230.455059)
		(end 364.510066 -230.714296)
		(width 0.1143)
		(layer "In6.Cu")
		(net "GMI_CPU1_G0_CPU0_G2_TX_DN<10>")
	)
	(arc
		(start 107.29976 -231.828594)
		(mid 107.414436 -231.69526)
		(end 107.455716 -231.524302)
		(width 0.1143)
		(layer "In6.Cu")
		(net "GMI_CPU1_G0_CPU0_G2_TX_DN<10>")
	)
	(arc
		(start 107.297982 -230.209852)
		(mid 107.298872 -230.209218)
		(end 107.29976 -230.208582)
		(width 0.1143)
		(layer "In6.Cu")
		(net "GMI_CPU1_G0_CPU0_G2_TX_DN<10>")
	)
	(arc
		(start 364.040166 -229.904036)
		(mid 364.081421 -230.075007)
		(end 364.196122 -230.208328)
		(width 0.1143)
		(layer "In6.Cu")
		(net "GMI_CPU1_G0_CPU0_G2_TX_DN<10>")
	)
	(arc
		(start 108.86567 -224.234502)
		(mid 108.930185 -223.972283)
		(end 109.109002 -223.769936)
		(width 0.1143)
		(layer "In6.Cu")
		(net "GMI_CPU1_G0_CPU0_G2_TX_DN<10>")
	)
	(arc
		(start 107.455716 -229.90429)
		(mid 107.414954 -229.734406)
		(end 107.301538 -229.601522)
		(width 0.1143)
		(layer "In6.Cu")
		(net "GMI_CPU1_G0_CPU0_G2_TX_DN<10>")
	)
	(arc
		(start 364.040166 -226.664266)
		(mid 364.081421 -226.835237)
		(end 364.196122 -226.968558)
		(width 0.1143)
		(layer "In6.Cu")
		(net "GMI_CPU1_G0_CPU0_G2_TX_DN<10>")
	)
	(arc
		(start 364.736888 -235.919518)
		(mid 364.915701 -236.121868)
		(end 364.98022 -236.384084)
		(width 0.1143)
		(layer "In6.Cu")
		(net "GMI_CPU1_G0_CPU0_G2_TX_DN<10>")
	)
	(arc
		(start 362.630212 -224.234248)
		(mid 362.671761 -224.40567)
		(end 362.787184 -224.539048)
		(width 0.1143)
		(layer "In6.Cu")
		(net "GMI_CPU1_G0_CPU0_G2_TX_DN<10>")
	)
	(arc
		(start 364.279434 -227.018596)
		(mid 364.504605 -227.474272)
		(end 364.279434 -227.929948)
		(width 0.1143)
		(layer "In6.Cu")
		(net "GMI_CPU1_G0_CPU0_G2_TX_DN<10>")
	)
	(arc
		(start 109.805724 -222.61449)
		(mid 109.870239 -222.352271)
		(end 110.049056 -222.149924)
		(width 0.1143)
		(layer "In6.Cu")
		(net "GMI_CPU1_G0_CPU0_G2_TX_DN<10>")
	)
	(arc
		(start 108.395516 -225.044508)
		(mid 108.460388 -224.781545)
		(end 108.640118 -224.578926)
		(width 0.1143)
		(layer "In6.Cu")
		(net "GMI_CPU1_G0_CPU0_G2_TX_DN<10>")
	)
	(segment
		(start 98.147886 -241.510312)
		(end 97.681034 -241.244374)
		(width 0.12954)
		(layer "F.Cu")
		(net "GMI_CPU1_G0_CPU0_G2_TX_DN<0>")
	)
	(segment
		(start 373.347996 -241.510058)
		(end 373.814848 -241.24412)
		(width 0.12954)
		(layer "F.Cu")
		(net "GMI_CPU1_G0_CPU0_G2_TX_DN<0>")
	)
	(segment
		(start 98.838004 -230.209852)
		(end 98.80854 -230.227124)
		(width 0.1143)
		(layer "In6.Cu")
		(net "GMI_CPU1_G0_CPU0_G2_TX_DN<0>")
	)
	(segment
		(start 98.80854 -226.9871)
		(end 98.807778 -226.987608)
		(width 0.1143)
		(layer "In6.Cu")
		(net "GMI_CPU1_G0_CPU0_G2_TX_DN<0>")
	)
	(segment
		(start 101.769672 -221.064836)
		(end 101.769672 -221.093284)
		(width 0.1143)
		(layer "In6.Cu")
		(net "GMI_CPU1_G0_CPU0_G2_TX_DN<0>")
	)
	(segment
		(start 373.645684 -236.71657)
		(end 373.639842 -236.713268)
		(width 0.1143)
		(layer "In6.Cu")
		(net "GMI_CPU1_G0_CPU0_G2_TX_DN<0>")
	)
	(segment
		(start 98.809556 -235.08589)
		(end 98.777044 -235.10494)
		(width 0.1143)
		(layer "In6.Cu")
		(net "GMI_CPU1_G0_CPU0_G2_TX_DN<0>")
	)
	(segment
		(start 104.087422 -212.63483)
		(end 103.13924 -214.053928)
		(width 0.14224)
		(layer "In6.Cu")
		(net "GMI_CPU1_G0_CPU0_G2_TX_DN<0>")
	)
	(segment
		(start 372.689374 -235.087414)
		(end 372.688358 -235.086906)
		(width 0.1143)
		(layer "In6.Cu")
		(net "GMI_CPU1_G0_CPU0_G2_TX_DN<0>")
	)
	(segment
		(start 100.213668 -224.559622)
		(end 100.212906 -224.56013)
		(width 0.1143)
		(layer "In6.Cu")
		(net "GMI_CPU1_G0_CPU0_G2_TX_DN<0>")
	)
	(segment
		(start 373.63908 -236.71276)
		(end 373.637556 -236.711998)
		(width 0.1143)
		(layer "In6.Cu")
		(net "GMI_CPU1_G0_CPU0_G2_TX_DN<0>")
	)
	(segment
		(start 372.680738 -234.445556)
		(end 372.68785 -234.442)
		(width 0.1143)
		(layer "In6.Cu")
		(net "GMI_CPU1_G0_CPU0_G2_TX_DN<0>")
	)
	(segment
		(start 372.698518 -228.613462)
		(end 372.6561 -228.588316)
		(width 0.1143)
		(layer "In6.Cu")
		(net "GMI_CPU1_G0_CPU0_G2_TX_DN<0>")
	)
	(segment
		(start 98.839782 -231.82834)
		(end 98.807778 -231.84739)
		(width 0.1143)
		(layer "In6.Cu")
		(net "GMI_CPU1_G0_CPU0_G2_TX_DN<0>")
	)
	(segment
		(start 372.68658 -235.08589)
		(end 372.68277 -235.083858)
		(width 0.1143)
		(layer "In6.Cu")
		(net "GMI_CPU1_G0_CPU0_G2_TX_DN<0>")
	)
	(segment
		(start 372.698264 -226.992942)
		(end 372.69293 -226.98964)
		(width 0.1143)
		(layer "In6.Cu")
		(net "GMI_CPU1_G0_CPU0_G2_TX_DN<0>")
	)
	(segment
		(start 374.136158 -237.539022)
		(end 374.068086 -237.499398)
		(width 0.1143)
		(layer "In6.Cu")
		(net "GMI_CPU1_G0_CPU0_G2_TX_DN<0>")
	)
	(segment
		(start 373.639842 -236.713268)
		(end 373.63908 -236.71276)
		(width 0.1143)
		(layer "In6.Cu")
		(net "GMI_CPU1_G0_CPU0_G2_TX_DN<0>")
	)
	(segment
		(start 97.359724 -240.089436)
		(end 97.398586 -240.112042)
		(width 0.1143)
		(layer "In6.Cu")
		(net "GMI_CPU1_G0_CPU0_G2_TX_DN<0>")
	)
	(segment
		(start 101.162866 -222.93453)
		(end 101.15677 -222.938086)
		(width 0.1143)
		(layer "In6.Cu")
		(net "GMI_CPU1_G0_CPU0_G2_TX_DN<0>")
	)
	(segment
		(start 99.748594 -225.366834)
		(end 99.709732 -225.38944)
		(width 0.1143)
		(layer "In6.Cu")
		(net "GMI_CPU1_G0_CPU0_G2_TX_DN<0>")
	)
	(segment
		(start 373.636794 -236.71149)
		(end 373.633238 -236.709712)
		(width 0.1143)
		(layer "In6.Cu")
		(net "GMI_CPU1_G0_CPU0_G2_TX_DN<0>")
	)
	(segment
		(start 330.021184 -187.01004)
		(end 311.219342 -175.84547)
		(width 0.14224)
		(layer "In6.Cu")
		(net "GMI_CPU1_G0_CPU0_G2_TX_DN<0>")
	)
	(segment
		(start 99.309682 -226.158552)
		(end 99.271328 -226.181158)
		(width 0.1143)
		(layer "In6.Cu")
		(net "GMI_CPU1_G0_CPU0_G2_TX_DN<0>")
	)
	(segment
		(start 98.809302 -235.086144)
		(end 98.809556 -235.08589)
		(width 0.1143)
		(layer "In6.Cu")
		(net "GMI_CPU1_G0_CPU0_G2_TX_DN<0>")
	)
	(segment
		(start 369.68049 -221.325694)
		(end 369.68049 -221.13875)
		(width 0.1143)
		(layer "In6.Cu")
		(net "GMI_CPU1_G0_CPU0_G2_TX_DN<0>")
	)
	(segment
		(start 371.295676 -224.566734)
		(end 371.289834 -224.563432)
		(width 0.1143)
		(layer "In6.Cu")
		(net "GMI_CPU1_G0_CPU0_G2_TX_DN<0>")
	)
	(segment
		(start 97.427796 -239.119664)
		(end 97.398586 -239.136682)
		(width 0.1143)
		(layer "In6.Cu")
		(net "GMI_CPU1_G0_CPU0_G2_TX_DN<0>")
	)
	(segment
		(start 99.777804 -225.349816)
		(end 99.748594 -225.366834)
		(width 0.1143)
		(layer "In6.Cu")
		(net "GMI_CPU1_G0_CPU0_G2_TX_DN<0>")
	)
	(segment
		(start 372.696486 -227.956618)
		(end 372.697248 -227.95611)
		(width 0.1143)
		(layer "In6.Cu")
		(net "GMI_CPU1_G0_CPU0_G2_TX_DN<0>")
	)
	(segment
		(start 372.6561 -232.840022)
		(end 372.680738 -232.825544)
		(width 0.1143)
		(layer "In6.Cu")
		(net "GMI_CPU1_G0_CPU0_G2_TX_DN<0>")
	)
	(segment
		(start 373.666258 -236.728762)
		(end 373.645684 -236.71657)
		(width 0.1143)
		(layer "In6.Cu")
		(net "GMI_CPU1_G0_CPU0_G2_TX_DN<0>")
	)
	(segment
		(start 372.698772 -228.613208)
		(end 372.698518 -228.613462)
		(width 0.1143)
		(layer "In6.Cu")
		(net "GMI_CPU1_G0_CPU0_G2_TX_DN<0>")
	)
	(segment
		(start 372.6561 -227.98024)
		(end 372.680738 -227.965762)
		(width 0.1143)
		(layer "In6.Cu")
		(net "GMI_CPU1_G0_CPU0_G2_TX_DN<0>")
	)
	(segment
		(start 101.769672 -217.3605)
		(end 101.769672 -221.064836)
		(width 0.14224)
		(layer "In6.Cu")
		(net "GMI_CPU1_G0_CPU0_G2_TX_DN<0>")
	)
	(segment
		(start 98.798126 -234.435904)
		(end 98.798634 -234.436158)
		(width 0.1143)
		(layer "In6.Cu")
		(net "GMI_CPU1_G0_CPU0_G2_TX_DN<0>")
	)
	(segment
		(start 98.808032 -227.96246)
		(end 98.815144 -227.966016)
		(width 0.1143)
		(layer "In6.Cu")
		(net "GMI_CPU1_G0_CPU0_G2_TX_DN<0>")
	)
	(segment
		(start 98.806762 -231.847898)
		(end 98.799142 -231.852978)
		(width 0.1143)
		(layer "In6.Cu")
		(net "GMI_CPU1_G0_CPU0_G2_TX_DN<0>")
	)
	(segment
		(start 372.696486 -234.436412)
		(end 372.697248 -234.435904)
		(width 0.1143)
		(layer "In6.Cu")
		(net "GMI_CPU1_G0_CPU0_G2_TX_DN<0>")
	)
	(segment
		(start 372.726204 -235.109004)
		(end 372.695216 -235.090716)
		(width 0.1143)
		(layer "In6.Cu")
		(net "GMI_CPU1_G0_CPU0_G2_TX_DN<0>")
	)
	(segment
		(start 101.769672 -221.093284)
		(end 101.815392 -221.139004)
		(width 0.1143)
		(layer "In6.Cu")
		(net "GMI_CPU1_G0_CPU0_G2_TX_DN<0>")
	)
	(segment
		(start 98.80346 -233.476546)
		(end 98.759264 -233.504232)
		(width 0.1143)
		(layer "In6.Cu")
		(net "GMI_CPU1_G0_CPU0_G2_TX_DN<0>")
	)
	(segment
		(start 357.726234 -205.09738)
		(end 332.425548 -189.215268)
		(width 0.14224)
		(layer "In6.Cu")
		(net "GMI_CPU1_G0_CPU0_G2_TX_DN<0>")
	)
	(segment
		(start 371.282976 -224.559876)
		(end 371.246146 -224.538286)
		(width 0.1143)
		(layer "In6.Cu")
		(net "GMI_CPU1_G0_CPU0_G2_TX_DN<0>")
	)
	(segment
		(start 369.90528 -222.148654)
		(end 369.824 -222.101156)
		(width 0.1143)
		(layer "In6.Cu")
		(net "GMI_CPU1_G0_CPU0_G2_TX_DN<0>")
	)
	(segment
		(start 372.655338 -231.220264)
		(end 372.688104 -231.201214)
		(width 0.1143)
		(layer "In6.Cu")
		(net "GMI_CPU1_G0_CPU0_G2_TX_DN<0>")
	)
	(segment
		(start 98.799396 -227.956872)
		(end 98.799142 -227.956618)
		(width 0.1143)
		(layer "In6.Cu")
		(net "GMI_CPU1_G0_CPU0_G2_TX_DN<0>")
	)
	(segment
		(start 371.78615 -225.389186)
		(end 371.718078 -225.349562)
		(width 0.1143)
		(layer "In6.Cu")
		(net "GMI_CPU1_G0_CPU0_G2_TX_DN<0>")
	)
	(segment
		(start 369.68049 -221.13875)
		(end 369.72621 -221.09303)
		(width 0.1143)
		(layer "In6.Cu")
		(net "GMI_CPU1_G0_CPU0_G2_TX_DN<0>")
	)
	(segment
		(start 372.6942 -235.090208)
		(end 372.692676 -235.089192)
		(width 0.1143)
		(layer "In6.Cu")
		(net "GMI_CPU1_G0_CPU0_G2_TX_DN<0>")
	)
	(segment
		(start 101.671882 -222.10141)
		(end 101.590602 -222.148908)
		(width 0.1143)
		(layer "In6.Cu")
		(net "GMI_CPU1_G0_CPU0_G2_TX_DN<0>")
	)
	(segment
		(start 373.158004 -235.896912)
		(end 373.126254 -235.878116)
		(width 0.1143)
		(layer "In6.Cu")
		(net "GMI_CPU1_G0_CPU0_G2_TX_DN<0>")
	)
	(segment
		(start 103.13924 -214.053928)
		(end 101.769672 -217.3605)
		(width 0.14224)
		(layer "In6.Cu")
		(net "GMI_CPU1_G0_CPU0_G2_TX_DN<0>")
	)
	(segment
		(start 98.799396 -232.816654)
		(end 98.799142 -232.8164)
		(width 0.1143)
		(layer "In6.Cu")
		(net "GMI_CPU1_G0_CPU0_G2_TX_DN<0>")
	)
	(segment
		(start 363.74324 -209.893408)
		(end 357.726234 -205.09738)
		(width 0.14224)
		(layer "In6.Cu")
		(net "GMI_CPU1_G0_CPU0_G2_TX_DN<0>")
	)
	(segment
		(start 372.69674 -234.436158)
		(end 372.696486 -234.436412)
		(width 0.1143)
		(layer "In6.Cu")
		(net "GMI_CPU1_G0_CPU0_G2_TX_DN<0>")
	)
	(segment
		(start 372.68785 -232.821988)
		(end 372.694454 -232.81767)
		(width 0.1143)
		(layer "In6.Cu")
		(net "GMI_CPU1_G0_CPU0_G2_TX_DN<0>")
	)
	(segment
		(start 372.692676 -235.089192)
		(end 372.69166 -235.088684)
		(width 0.1143)
		(layer "In6.Cu")
		(net "GMI_CPU1_G0_CPU0_G2_TX_DN<0>")
	)
	(segment
		(start 372.697248 -232.815892)
		(end 372.726204 -232.799382)
		(width 0.1143)
		(layer "In6.Cu")
		(net "GMI_CPU1_G0_CPU0_G2_TX_DN<0>")
	)
	(segment
		(start 98.801428 -227.958142)
		(end 98.808032 -227.96246)
		(width 0.1143)
		(layer "In6.Cu")
		(net "GMI_CPU1_G0_CPU0_G2_TX_DN<0>")
	)
	(segment
		(start 372.72468 -233.487976)
		(end 372.724172 -233.488484)
		(width 0.1143)
		(layer "In6.Cu")
		(net "GMI_CPU1_G0_CPU0_G2_TX_DN<0>")
	)
	(segment
		(start 98.798634 -234.436158)
		(end 98.799396 -234.436666)
		(width 0.1143)
		(layer "In6.Cu")
		(net "GMI_CPU1_G0_CPU0_G2_TX_DN<0>")
	)
	(segment
		(start 98.777044 -235.10494)
		(end 98.769678 -235.109258)
		(width 0.1143)
		(layer "In6.Cu")
		(net "GMI_CPU1_G0_CPU0_G2_TX_DN<0>")
	)
	(segment
		(start 101.815392 -221.139004)
		(end 101.815392 -221.325948)
		(width 0.1143)
		(layer "In6.Cu")
		(net "GMI_CPU1_G0_CPU0_G2_TX_DN<0>")
	)
	(segment
		(start 374.136158 -239.159034)
		(end 374.068086 -239.11941)
		(width 0.1143)
		(layer "In6.Cu")
		(net "GMI_CPU1_G0_CPU0_G2_TX_DN<0>")
	)
	(segment
		(start 372.68912 -233.467656)
		(end 372.6561 -233.448098)
		(width 0.1143)
		(layer "In6.Cu")
		(net "GMI_CPU1_G0_CPU0_G2_TX_DN<0>")
	)
	(segment
		(start 98.798634 -232.816146)
		(end 98.799396 -232.816654)
		(width 0.1143)
		(layer "In6.Cu")
		(net "GMI_CPU1_G0_CPU0_G2_TX_DN<0>")
	)
	(segment
		(start 370.333016 -222.934276)
		(end 370.332 -222.933768)
		(width 0.1143)
		(layer "In6.Cu")
		(net "GMI_CPU1_G0_CPU0_G2_TX_DN<0>")
	)
	(segment
		(start 98.815144 -227.966016)
		(end 98.839782 -227.980494)
		(width 0.1143)
		(layer "In6.Cu")
		(net "GMI_CPU1_G0_CPU0_G2_TX_DN<0>")
	)
	(segment
		(start 98.799142 -227.956618)
		(end 98.801428 -227.958142)
		(width 0.1143)
		(layer "In6.Cu")
		(net "GMI_CPU1_G0_CPU0_G2_TX_DN<0>")
	)
	(segment
		(start 373.596154 -240.940082)
		(end 373.620792 -240.925604)
		(width 0.1143)
		(layer "In6.Cu")
		(net "GMI_CPU1_G0_CPU0_G2_TX_DN<0>")
	)
	(segment
		(start 372.69293 -226.98964)
		(end 372.688104 -226.987354)
		(width 0.1143)
		(layer "In6.Cu")
		(net "GMI_CPU1_G0_CPU0_G2_TX_DN<0>")
	)
	(segment
		(start 97.859342 -240.916714)
		(end 97.859088 -240.91646)
		(width 0.1143)
		(layer "In6.Cu")
		(net "GMI_CPU1_G0_CPU0_G2_TX_DN<0>")
	)
	(segment
		(start 97.398586 -239.136682)
		(end 97.359724 -239.159288)
		(width 0.1143)
		(layer "In6.Cu")
		(net "GMI_CPU1_G0_CPU0_G2_TX_DN<0>")
	)
	(segment
		(start 98.807778 -231.84739)
		(end 98.806762 -231.847898)
		(width 0.1143)
		(layer "In6.Cu")
		(net "GMI_CPU1_G0_CPU0_G2_TX_DN<0>")
	)
	(segment
		(start 98.048826 -241.174524)
		(end 97.978976 -241.244374)
		(width 0.1143)
		(layer "In6.Cu")
		(net "GMI_CPU1_G0_CPU0_G2_TX_DN<0>")
	)
	(segment
		(start 98.840036 -235.068364)
		(end 98.813112 -235.084112)
		(width 0.1143)
		(layer "In6.Cu")
		(net "GMI_CPU1_G0_CPU0_G2_TX_DN<0>")
	)
	(segment
		(start 101.156008 -222.938594)
		(end 101.147626 -222.943166)
		(width 0.1143)
		(layer "In6.Cu")
		(net "GMI_CPU1_G0_CPU0_G2_TX_DN<0>")
	)
	(segment
		(start 372.68785 -229.581202)
		(end 372.728998 -229.557326)
		(width 0.1143)
		(layer "In6.Cu")
		(net "GMI_CPU1_G0_CPU0_G2_TX_DN<0>")
	)
	(segment
		(start 116.374672 -201.446892)
		(end 111.647986 -205.074012)
		(width 0.14224)
		(layer "In6.Cu")
		(net "GMI_CPU1_G0_CPU0_G2_TX_DN<0>")
	)
	(segment
		(start 372.694454 -232.81767)
		(end 372.69674 -232.816146)
		(width 0.1143)
		(layer "In6.Cu")
		(net "GMI_CPU1_G0_CPU0_G2_TX_DN<0>")
	)
	(segment
		(start 372.712488 -228.621082)
		(end 372.698772 -228.613208)
		(width 0.1143)
		(layer "In6.Cu")
		(net "GMI_CPU1_G0_CPU0_G2_TX_DN<0>")
	)
	(segment
		(start 373.633238 -236.709712)
		(end 373.632984 -236.709712)
		(width 0.1143)
		(layer "In6.Cu")
		(net "GMI_CPU1_G0_CPU0_G2_TX_DN<0>")
	)
	(segment
		(start 370.339874 -222.93834)
		(end 370.339112 -222.937832)
		(width 0.1143)
		(layer "In6.Cu")
		(net "GMI_CPU1_G0_CPU0_G2_TX_DN<0>")
	)
	(segment
		(start 369.72621 -221.09303)
		(end 369.72621 -217.887804)
		(width 0.14224)
		(layer "In6.Cu")
		(net "GMI_CPU1_G0_CPU0_G2_TX_DN<0>")
	)
	(segment
		(start 101.8159 -221.326456)
		(end 101.8159 -221.982284)
		(width 0.1143)
		(layer "In6.Cu")
		(net "GMI_CPU1_G0_CPU0_G2_TX_DN<0>")
	)
	(segment
		(start 372.698264 -231.852724)
		(end 372.69674 -231.852724)
		(width 0.1143)
		(layer "In6.Cu")
		(net "GMI_CPU1_G0_CPU0_G2_TX_DN<0>")
	)
	(segment
		(start 98.801428 -232.817924)
		(end 98.808032 -232.822242)
		(width 0.1143)
		(layer "In6.Cu")
		(net "GMI_CPU1_G0_CPU0_G2_TX_DN<0>")
	)
	(segment
		(start 374.068086 -240.128806)
		(end 374.136158 -240.089182)
		(width 0.1143)
		(layer "In6.Cu")
		(net "GMI_CPU1_G0_CPU0_G2_TX_DN<0>")
	)
	(segment
		(start 372.726204 -231.868726)
		(end 372.698264 -231.852724)
		(width 0.1143)
		(layer "In6.Cu")
		(net "GMI_CPU1_G0_CPU0_G2_TX_DN<0>")
	)
	(segment
		(start 371.289834 -224.563432)
		(end 371.289072 -224.562924)
		(width 0.1143)
		(layer "In6.Cu")
		(net "GMI_CPU1_G0_CPU0_G2_TX_DN<0>")
	)
	(segment
		(start 98.766884 -231.177592)
		(end 98.807778 -231.201468)
		(width 0.1143)
		(layer "In6.Cu")
		(net "GMI_CPU1_G0_CPU0_G2_TX_DN<0>")
	)
	(segment
		(start 98.337878 -235.897166)
		(end 98.30054 -235.918756)
		(width 0.1143)
		(layer "In6.Cu")
		(net "GMI_CPU1_G0_CPU0_G2_TX_DN<0>")
	)
	(segment
		(start 370.376196 -222.958914)
		(end 370.348256 -222.942912)
		(width 0.1143)
		(layer "In6.Cu")
		(net "GMI_CPU1_G0_CPU0_G2_TX_DN<0>")
	)
	(segment
		(start 98.766884 -229.55758)
		(end 98.808032 -229.581456)
		(width 0.1143)
		(layer "In6.Cu")
		(net "GMI_CPU1_G0_CPU0_G2_TX_DN<0>")
	)
	(segment
		(start 100.719636 -223.728534)
		(end 100.687886 -223.74733)
		(width 0.1143)
		(layer "In6.Cu")
		(net "GMI_CPU1_G0_CPU0_G2_TX_DN<0>")
	)
	(segment
		(start 98.815144 -234.44581)
		(end 98.839782 -234.460288)
		(width 0.1143)
		(layer "In6.Cu")
		(net "GMI_CPU1_G0_CPU0_G2_TX_DN<0>")
	)
	(segment
		(start 369.679982 -221.98203)
		(end 369.679982 -221.326202)
		(width 0.1143)
		(layer "In6.Cu")
		(net "GMI_CPU1_G0_CPU0_G2_TX_DN<0>")
	)
	(segment
		(start 372.688104 -231.847136)
		(end 372.6561 -231.828086)
		(width 0.1143)
		(layer "In6.Cu")
		(net "GMI_CPU1_G0_CPU0_G2_TX_DN<0>")
	)
	(segment
		(start 369.679982 -221.326202)
		(end 369.68049 -221.325694)
		(width 0.1143)
		(layer "In6.Cu")
		(net "GMI_CPU1_G0_CPU0_G2_TX_DN<0>")
	)
	(segment
		(start 373.634508 -240.91773)
		(end 373.636794 -240.916206)
		(width 0.1143)
		(layer "In6.Cu")
		(net "GMI_CPU1_G0_CPU0_G2_TX_DN<0>")
	)
	(segment
		(start 372.68785 -234.442)
		(end 372.694454 -234.437682)
		(width 0.1143)
		(layer "In6.Cu")
		(net "GMI_CPU1_G0_CPU0_G2_TX_DN<0>")
	)
	(segment
		(start 372.688358 -235.086906)
		(end 372.686326 -235.085636)
		(width 0.1143)
		(layer "In6.Cu")
		(net "GMI_CPU1_G0_CPU0_G2_TX_DN<0>")
	)
	(segment
		(start 98.799396 -234.436666)
		(end 98.799142 -234.436412)
		(width 0.1143)
		(layer "In6.Cu")
		(net "GMI_CPU1_G0_CPU0_G2_TX_DN<0>")
	)
	(segment
		(start 373.637302 -240.915952)
		(end 373.666258 -240.899442)
		(width 0.1143)
		(layer "In6.Cu")
		(net "GMI_CPU1_G0_CPU0_G2_TX_DN<0>")
	)
	(segment
		(start 98.807778 -226.987608)
		(end 98.802952 -226.989894)
		(width 0.1143)
		(layer "In6.Cu")
		(net "GMI_CPU1_G0_CPU0_G2_TX_DN<0>")
	)
	(segment
		(start 372.697248 -227.95611)
		(end 372.726204 -227.9396)
		(width 0.1143)
		(layer "In6.Cu")
		(net "GMI_CPU1_G0_CPU0_G2_TX_DN<0>")
	)
	(segment
		(start 372.69674 -232.816146)
		(end 372.696486 -232.8164)
		(width 0.1143)
		(layer "In6.Cu")
		(net "GMI_CPU1_G0_CPU0_G2_TX_DN<0>")
	)
	(segment
		(start 161.649664 -175.302164)
		(end 116.374672 -201.446892)
		(width 0.14224)
		(layer "In6.Cu")
		(net "GMI_CPU1_G0_CPU0_G2_TX_DN<0>")
	)
	(segment
		(start 98.04908 -241.174524)
		(end 98.048826 -241.174524)
		(width 0.1143)
		(layer "In6.Cu")
		(net "GMI_CPU1_G0_CPU0_G2_TX_DN<0>")
	)
	(segment
		(start 97.86366 -236.709458)
		(end 97.862898 -236.709966)
		(width 0.1143)
		(layer "In6.Cu")
		(net "GMI_CPU1_G0_CPU0_G2_TX_DN<0>")
	)
	(segment
		(start 166.61511 -173.986952)
		(end 161.649664 -175.302164)
		(width 0.14224)
		(layer "In6.Cu")
		(net "GMI_CPU1_G0_CPU0_G2_TX_DN<0>")
	)
	(segment
		(start 372.696486 -232.8164)
		(end 372.697248 -232.815892)
		(width 0.1143)
		(layer "In6.Cu")
		(net "GMI_CPU1_G0_CPU0_G2_TX_DN<0>")
	)
	(segment
		(start 97.359724 -238.469424)
		(end 97.398586 -238.49203)
		(width 0.1143)
		(layer "In6.Cu")
		(net "GMI_CPU1_G0_CPU0_G2_TX_DN<0>")
	)
	(segment
		(start 372.689882 -233.468164)
		(end 372.68912 -233.467656)
		(width 0.1143)
		(layer "In6.Cu")
		(net "GMI_CPU1_G0_CPU0_G2_TX_DN<0>")
	)
	(segment
		(start 370.845334 -223.768666)
		(end 370.807996 -223.747076)
		(width 0.1143)
		(layer "In6.Cu")
		(net "GMI_CPU1_G0_CPU0_G2_TX_DN<0>")
	)
	(segment
		(start 111.647986 -205.074012)
		(end 104.087422 -212.63483)
		(width 0.14224)
		(layer "In6.Cu")
		(net "GMI_CPU1_G0_CPU0_G2_TX_DN<0>")
	)
	(segment
		(start 98.802952 -226.989894)
		(end 98.797618 -226.993196)
		(width 0.1143)
		(layer "In6.Cu")
		(net "GMI_CPU1_G0_CPU0_G2_TX_DN<0>")
	)
	(segment
		(start 98.797618 -231.852978)
		(end 98.769678 -231.86898)
		(width 0.1143)
		(layer "In6.Cu")
		(net "GMI_CPU1_G0_CPU0_G2_TX_DN<0>")
	)
	(segment
		(start 372.688104 -231.201214)
		(end 372.728998 -231.177338)
		(width 0.1143)
		(layer "In6.Cu")
		(net "GMI_CPU1_G0_CPU0_G2_TX_DN<0>")
	)
	(segment
		(start 98.799142 -234.436412)
		(end 98.801428 -234.437936)
		(width 0.1143)
		(layer "In6.Cu")
		(net "GMI_CPU1_G0_CPU0_G2_TX_DN<0>")
	)
	(segment
		(start 100.249736 -224.53854)
		(end 100.217478 -224.557336)
		(width 0.1143)
		(layer "In6.Cu")
		(net "GMI_CPU1_G0_CPU0_G2_TX_DN<0>")
	)
	(segment
		(start 200.696068 -174.186342)
		(end 200.695814 -174.186342)
		(width 0.14224)
		(layer "In6.Cu")
		(net "GMI_CPU1_G0_CPU0_G2_TX_DN<0>")
	)
	(segment
		(start 97.85858 -240.916206)
		(end 97.859342 -240.916714)
		(width 0.1143)
		(layer "In6.Cu")
		(net "GMI_CPU1_G0_CPU0_G2_TX_DN<0>")
	)
	(segment
		(start 332.425548 -189.215268)
		(end 330.021184 -187.01004)
		(width 0.14224)
		(layer "In6.Cu")
		(net "GMI_CPU1_G0_CPU0_G2_TX_DN<0>")
	)
	(segment
		(start 98.799142 -232.8164)
		(end 98.801428 -232.817924)
		(width 0.1143)
		(layer "In6.Cu")
		(net "GMI_CPU1_G0_CPU0_G2_TX_DN<0>")
	)
	(segment
		(start 372.655846 -229.599998)
		(end 372.68785 -229.581202)
		(width 0.1143)
		(layer "In6.Cu")
		(net "GMI_CPU1_G0_CPU0_G2_TX_DN<0>")
	)
	(segment
		(start 100.212652 -224.56013)
		(end 100.179632 -224.57918)
		(width 0.1143)
		(layer "In6.Cu")
		(net "GMI_CPU1_G0_CPU0_G2_TX_DN<0>")
	)
	(segment
		(start 98.801428 -234.437936)
		(end 98.808032 -234.442254)
		(width 0.1143)
		(layer "In6.Cu")
		(net "GMI_CPU1_G0_CPU0_G2_TX_DN<0>")
	)
	(segment
		(start 97.862898 -236.709966)
		(end 97.862644 -236.709966)
		(width 0.1143)
		(layer "In6.Cu")
		(net "GMI_CPU1_G0_CPU0_G2_TX_DN<0>")
	)
	(segment
		(start 101.147626 -222.943166)
		(end 101.119686 -222.959168)
		(width 0.1143)
		(layer "In6.Cu")
		(net "GMI_CPU1_G0_CPU0_G2_TX_DN<0>")
	)
	(segment
		(start 97.87509 -240.925858)
		(end 97.899728 -240.940336)
		(width 0.1143)
		(layer "In6.Cu")
		(net "GMI_CPU1_G0_CPU0_G2_TX_DN<0>")
	)
	(segment
		(start 372.686326 -235.085636)
		(end 372.68658 -235.08589)
		(width 0.1143)
		(layer "In6.Cu")
		(net "GMI_CPU1_G0_CPU0_G2_TX_DN<0>")
	)
	(segment
		(start 98.798634 -227.956364)
		(end 98.799396 -227.956872)
		(width 0.1143)
		(layer "In6.Cu")
		(net "GMI_CPU1_G0_CPU0_G2_TX_DN<0>")
	)
	(segment
		(start 371.28323 -224.559876)
		(end 371.282976 -224.559876)
		(width 0.1143)
		(layer "In6.Cu")
		(net "GMI_CPU1_G0_CPU0_G2_TX_DN<0>")
	)
	(segment
		(start 372.724172 -233.488484)
		(end 372.689882 -233.468164)
		(width 0.1143)
		(layer "In6.Cu")
		(net "GMI_CPU1_G0_CPU0_G2_TX_DN<0>")
	)
	(segment
		(start 370.348256 -222.942912)
		(end 370.339874 -222.93834)
		(width 0.1143)
		(layer "In6.Cu")
		(net "GMI_CPU1_G0_CPU0_G2_TX_DN<0>")
	)
	(segment
		(start 98.797364 -228.613716)
		(end 98.79711 -228.613462)
		(width 0.1143)
		(layer "In6.Cu")
		(net "GMI_CPU1_G0_CPU0_G2_TX_DN<0>")
	)
	(segment
		(start 98.783394 -228.621336)
		(end 98.782378 -228.621844)
		(width 0.1143)
		(layer "In6.Cu")
		(net "GMI_CPU1_G0_CPU0_G2_TX_DN<0>")
	)
	(segment
		(start 100.217478 -224.557336)
		(end 100.213668 -224.559622)
		(width 0.1143)
		(layer "In6.Cu")
		(net "GMI_CPU1_G0_CPU0_G2_TX_DN<0>")
	)
	(segment
		(start 98.813112 -235.084112)
		(end 98.809302 -235.086144)
		(width 0.1143)
		(layer "In6.Cu")
		(net "GMI_CPU1_G0_CPU0_G2_TX_DN<0>")
	)
	(segment
		(start 372.224554 -226.180904)
		(end 372.1862 -226.158298)
		(width 0.1143)
		(layer "In6.Cu")
		(net "GMI_CPU1_G0_CPU0_G2_TX_DN<0>")
	)
	(segment
		(start 97.867978 -240.922302)
		(end 97.87509 -240.925858)
		(width 0.1143)
		(layer "In6.Cu")
		(net "GMI_CPU1_G0_CPU0_G2_TX_DN<0>")
	)
	(segment
		(start 373.627904 -240.922048)
		(end 373.634508 -240.91773)
		(width 0.1143)
		(layer "In6.Cu")
		(net "GMI_CPU1_G0_CPU0_G2_TX_DN<0>")
	)
	(segment
		(start 97.899728 -236.688376)
		(end 97.86747 -236.707172)
		(width 0.1143)
		(layer "In6.Cu")
		(net "GMI_CPU1_G0_CPU0_G2_TX_DN<0>")
	)
	(segment
		(start 373.632984 -236.709712)
		(end 373.596154 -236.688122)
		(width 0.1143)
		(layer "In6.Cu")
		(net "GMI_CPU1_G0_CPU0_G2_TX_DN<0>")
	)
	(segment
		(start 372.680738 -227.965762)
		(end 372.68785 -227.962206)
		(width 0.1143)
		(layer "In6.Cu")
		(net "GMI_CPU1_G0_CPU0_G2_TX_DN<0>")
	)
	(segment
		(start 302.9204 -174.784512)
		(end 200.696068 -174.186342)
		(width 0.14224)
		(layer "In6.Cu")
		(net "GMI_CPU1_G0_CPU0_G2_TX_DN<0>")
	)
	(segment
		(start 368.436652 -214.77224)
		(end 368.063526 -214.213694)
		(width 0.14224)
		(layer "In6.Cu")
		(net "GMI_CPU1_G0_CPU0_G2_TX_DN<0>")
	)
	(segment
		(start 372.726204 -227.008944)
		(end 372.698264 -226.992942)
		(width 0.1143)
		(layer "In6.Cu")
		(net "GMI_CPU1_G0_CPU0_G2_TX_DN<0>")
	)
	(segment
		(start 98.815144 -232.825798)
		(end 98.851974 -232.847134)
		(width 0.1143)
		(layer "In6.Cu")
		(net "GMI_CPU1_G0_CPU0_G2_TX_DN<0>")
	)
	(segment
		(start 97.978976 -241.244374)
		(end 97.681034 -241.244374)
		(width 0.1143)
		(layer "In6.Cu")
		(net "GMI_CPU1_G0_CPU0_G2_TX_DN<0>")
	)
	(segment
		(start 372.68912 -231.847644)
		(end 372.688104 -231.847136)
		(width 0.1143)
		(layer "In6.Cu")
		(net "GMI_CPU1_G0_CPU0_G2_TX_DN<0>")
	)
	(segment
		(start 372.697248 -234.435904)
		(end 372.726204 -234.419394)
		(width 0.1143)
		(layer "In6.Cu")
		(net "GMI_CPU1_G0_CPU0_G2_TX_DN<0>")
	)
	(segment
		(start 373.516906 -241.24412)
		(end 373.447056 -241.17427)
		(width 0.1143)
		(layer "In6.Cu")
		(net "GMI_CPU1_G0_CPU0_G2_TX_DN<0>")
	)
	(segment
		(start 373.814848 -241.24412)
		(end 373.516906 -241.24412)
		(width 0.1143)
		(layer "In6.Cu")
		(net "GMI_CPU1_G0_CPU0_G2_TX_DN<0>")
	)
	(segment
		(start 373.637556 -236.711998)
		(end 373.636794 -236.71149)
		(width 0.1143)
		(layer "In6.Cu")
		(net "GMI_CPU1_G0_CPU0_G2_TX_DN<0>")
	)
	(segment
		(start 369.72621 -217.887804)
		(end 368.436652 -214.77224)
		(width 0.14224)
		(layer "In6.Cu")
		(net "GMI_CPU1_G0_CPU0_G2_TX_DN<0>")
	)
	(segment
		(start 97.861374 -240.917984)
		(end 97.867978 -240.922302)
		(width 0.1143)
		(layer "In6.Cu")
		(net "GMI_CPU1_G0_CPU0_G2_TX_DN<0>")
	)
	(segment
		(start 372.68277 -235.083858)
		(end 372.655846 -235.06811)
		(width 0.1143)
		(layer "In6.Cu")
		(net "GMI_CPU1_G0_CPU0_G2_TX_DN<0>")
	)
	(segment
		(start 97.398586 -237.51667)
		(end 97.359724 -237.539276)
		(width 0.1143)
		(layer "In6.Cu")
		(net "GMI_CPU1_G0_CPU0_G2_TX_DN<0>")
	)
	(segment
		(start 370.807996 -223.747076)
		(end 370.776246 -223.72828)
		(width 0.1143)
		(layer "In6.Cu")
		(net "GMI_CPU1_G0_CPU0_G2_TX_DN<0>")
	)
	(segment
		(start 372.688104 -226.987354)
		(end 372.687342 -226.986846)
		(width 0.1143)
		(layer "In6.Cu")
		(net "GMI_CPU1_G0_CPU0_G2_TX_DN<0>")
	)
	(segment
		(start 100.687886 -223.74733)
		(end 100.650548 -223.76892)
		(width 0.1143)
		(layer "In6.Cu")
		(net "GMI_CPU1_G0_CPU0_G2_TX_DN<0>")
	)
	(segment
		(start 200.695814 -174.186342)
		(end 166.61511 -173.986952)
		(width 0.14224)
		(layer "In6.Cu")
		(net "GMI_CPU1_G0_CPU0_G2_TX_DN<0>")
	)
	(segment
		(start 369.824 -222.101156)
		(end 369.818666 -222.098362)
		(width 0.1143)
		(layer "In6.Cu")
		(net "GMI_CPU1_G0_CPU0_G2_TX_DN<0>")
	)
	(segment
		(start 372.726204 -233.488738)
		(end 372.72468 -233.487976)
		(width 0.1143)
		(layer "In6.Cu")
		(net "GMI_CPU1_G0_CPU0_G2_TX_DN<0>")
	)
	(segment
		(start 98.80854 -230.227124)
		(end 98.769678 -230.249476)
		(width 0.1143)
		(layer "In6.Cu")
		(net "GMI_CPU1_G0_CPU0_G2_TX_DN<0>")
	)
	(segment
		(start 101.15677 -222.938086)
		(end 101.156008 -222.938594)
		(width 0.1143)
		(layer "In6.Cu")
		(net "GMI_CPU1_G0_CPU0_G2_TX_DN<0>")
	)
	(segment
		(start 372.69166 -235.088684)
		(end 372.689374 -235.087414)
		(width 0.1143)
		(layer "In6.Cu")
		(net "GMI_CPU1_G0_CPU0_G2_TX_DN<0>")
	)
	(segment
		(start 97.427796 -237.499652)
		(end 97.398586 -237.51667)
		(width 0.1143)
		(layer "In6.Cu")
		(net "GMI_CPU1_G0_CPU0_G2_TX_DN<0>")
	)
	(segment
		(start 371.287548 -224.562162)
		(end 371.286786 -224.561654)
		(width 0.1143)
		(layer "In6.Cu")
		(net "GMI_CPU1_G0_CPU0_G2_TX_DN<0>")
	)
	(segment
		(start 373.195342 -235.918502)
		(end 373.158004 -235.896912)
		(width 0.1143)
		(layer "In6.Cu")
		(net "GMI_CPU1_G0_CPU0_G2_TX_DN<0>")
	)
	(segment
		(start 372.726204 -230.249222)
		(end 372.687342 -230.22687)
		(width 0.1143)
		(layer "In6.Cu")
		(net "GMI_CPU1_G0_CPU0_G2_TX_DN<0>")
	)
	(segment
		(start 368.063526 -214.213694)
		(end 363.74324 -209.893408)
		(width 0.14224)
		(layer "In6.Cu")
		(net "GMI_CPU1_G0_CPU0_G2_TX_DN<0>")
	)
	(segment
		(start 373.447056 -241.17427)
		(end 373.446802 -241.17427)
		(width 0.1143)
		(layer "In6.Cu")
		(net "GMI_CPU1_G0_CPU0_G2_TX_DN<0>")
	)
	(segment
		(start 372.6561 -234.460034)
		(end 372.680738 -234.445556)
		(width 0.1143)
		(layer "In6.Cu")
		(net "GMI_CPU1_G0_CPU0_G2_TX_DN<0>")
	)
	(segment
		(start 371.31625 -224.578926)
		(end 371.295676 -224.566734)
		(width 0.1143)
		(layer "In6.Cu")
		(net "GMI_CPU1_G0_CPU0_G2_TX_DN<0>")
	)
	(segment
		(start 97.398586 -240.112042)
		(end 97.427796 -240.12906)
		(width 0.1143)
		(layer "In6.Cu")
		(net "GMI_CPU1_G0_CPU0_G2_TX_DN<0>")
	)
	(segment
		(start 101.163882 -222.934022)
		(end 101.162866 -222.93453)
		(width 0.1143)
		(layer "In6.Cu")
		(net "GMI_CPU1_G0_CPU0_G2_TX_DN<0>")
	)
	(segment
		(start 98.799142 -231.852978)
		(end 98.797618 -231.852978)
		(width 0.1143)
		(layer "In6.Cu")
		(net "GMI_CPU1_G0_CPU0_G2_TX_DN<0>")
	)
	(segment
		(start 373.63654 -240.91646)
		(end 373.637302 -240.915952)
		(width 0.1143)
		(layer "In6.Cu")
		(net "GMI_CPU1_G0_CPU0_G2_TX_DN<0>")
	)
	(segment
		(start 372.694454 -234.437682)
		(end 372.69674 -234.436158)
		(width 0.1143)
		(layer "In6.Cu")
		(net "GMI_CPU1_G0_CPU0_G2_TX_DN<0>")
	)
	(segment
		(start 97.829624 -240.899696)
		(end 97.85858 -240.916206)
		(width 0.1143)
		(layer "In6.Cu")
		(net "GMI_CPU1_G0_CPU0_G2_TX_DN<0>")
	)
	(segment
		(start 98.839782 -228.58857)
		(end 98.797364 -228.613716)
		(width 0.1143)
		(layer "In6.Cu")
		(net "GMI_CPU1_G0_CPU0_G2_TX_DN<0>")
	)
	(segment
		(start 307.354986 -174.784512)
		(end 302.9204 -174.784512)
		(width 0.14224)
		(layer "In6.Cu")
		(net "GMI_CPU1_G0_CPU0_G2_TX_DN<0>")
	)
	(segment
		(start 98.807778 -231.201468)
		(end 98.840544 -231.220518)
		(width 0.1143)
		(layer "In6.Cu")
		(net "GMI_CPU1_G0_CPU0_G2_TX_DN<0>")
	)
	(segment
		(start 373.636794 -240.916206)
		(end 373.63654 -240.91646)
		(width 0.1143)
		(layer "In6.Cu")
		(net "GMI_CPU1_G0_CPU0_G2_TX_DN<0>")
	)
	(segment
		(start 98.369628 -235.87837)
		(end 98.337878 -235.897166)
		(width 0.1143)
		(layer "In6.Cu")
		(net "GMI_CPU1_G0_CPU0_G2_TX_DN<0>")
	)
	(segment
		(start 372.680738 -232.825544)
		(end 372.68785 -232.821988)
		(width 0.1143)
		(layer "In6.Cu")
		(net "GMI_CPU1_G0_CPU0_G2_TX_DN<0>")
	)
	(segment
		(start 372.69674 -227.956364)
		(end 372.696486 -227.956618)
		(width 0.1143)
		(layer "In6.Cu")
		(net "GMI_CPU1_G0_CPU0_G2_TX_DN<0>")
	)
	(segment
		(start 98.76282 -234.415838)
		(end 98.798126 -234.435904)
		(width 0.1143)
		(layer "In6.Cu")
		(net "GMI_CPU1_G0_CPU0_G2_TX_DN<0>")
	)
	(segment
		(start 98.769678 -232.799636)
		(end 98.798634 -232.816146)
		(width 0.1143)
		(layer "In6.Cu")
		(net "GMI_CPU1_G0_CPU0_G2_TX_DN<0>")
	)
	(segment
		(start 101.815392 -221.325948)
		(end 101.8159 -221.326456)
		(width 0.1143)
		(layer "In6.Cu")
		(net "GMI_CPU1_G0_CPU0_G2_TX_DN<0>")
	)
	(segment
		(start 98.707956 -234.370118)
		(end 98.76282 -234.415838)
		(width 0.1143)
		(layer "In6.Cu")
		(net "GMI_CPU1_G0_CPU0_G2_TX_DN<0>")
	)
	(segment
		(start 311.219342 -175.84547)
		(end 307.354986 -174.784512)
		(width 0.14224)
		(layer "In6.Cu")
		(net "GMI_CPU1_G0_CPU0_G2_TX_DN<0>")
	)
	(segment
		(start 370.339112 -222.937832)
		(end 370.333016 -222.934276)
		(width 0.1143)
		(layer "In6.Cu")
		(net "GMI_CPU1_G0_CPU0_G2_TX_DN<0>")
	)
	(segment
		(start 371.286786 -224.561654)
		(end 371.28323 -224.559876)
		(width 0.1143)
		(layer "In6.Cu")
		(net "GMI_CPU1_G0_CPU0_G2_TX_DN<0>")
	)
	(segment
		(start 98.769678 -227.939854)
		(end 98.798634 -227.956364)
		(width 0.1143)
		(layer "In6.Cu")
		(net "GMI_CPU1_G0_CPU0_G2_TX_DN<0>")
	)
	(segment
		(start 98.808032 -229.581456)
		(end 98.840036 -229.600252)
		(width 0.1143)
		(layer "In6.Cu")
		(net "GMI_CPU1_G0_CPU0_G2_TX_DN<0>")
	)
	(segment
		(start 372.687342 -230.22687)
		(end 372.657878 -230.209598)
		(width 0.1143)
		(layer "In6.Cu")
		(net "GMI_CPU1_G0_CPU0_G2_TX_DN<0>")
	)
	(segment
		(start 98.808032 -234.442254)
		(end 98.815144 -234.44581)
		(width 0.1143)
		(layer "In6.Cu")
		(net "GMI_CPU1_G0_CPU0_G2_TX_DN<0>")
	)
	(segment
		(start 97.86747 -236.707172)
		(end 97.86366 -236.709458)
		(width 0.1143)
		(layer "In6.Cu")
		(net "GMI_CPU1_G0_CPU0_G2_TX_DN<0>")
	)
	(segment
		(start 98.808032 -232.822242)
		(end 98.815144 -232.825798)
		(width 0.1143)
		(layer "In6.Cu")
		(net "GMI_CPU1_G0_CPU0_G2_TX_DN<0>")
	)
	(segment
		(start 101.677216 -222.098616)
		(end 101.671882 -222.10141)
		(width 0.1143)
		(layer "In6.Cu")
		(net "GMI_CPU1_G0_CPU0_G2_TX_DN<0>")
	)
	(segment
		(start 97.862644 -236.709966)
		(end 97.829624 -236.729016)
		(width 0.1143)
		(layer "In6.Cu")
		(net "GMI_CPU1_G0_CPU0_G2_TX_DN<0>")
	)
	(segment
		(start 372.695216 -235.090716)
		(end 372.6942 -235.090208)
		(width 0.1143)
		(layer "In6.Cu")
		(net "GMI_CPU1_G0_CPU0_G2_TX_DN<0>")
	)
	(segment
		(start 98.797618 -226.993196)
		(end 98.769678 -227.009198)
		(width 0.1143)
		(layer "In6.Cu")
		(net "GMI_CPU1_G0_CPU0_G2_TX_DN<0>")
	)
	(segment
		(start 372.694454 -227.957888)
		(end 372.69674 -227.956364)
		(width 0.1143)
		(layer "In6.Cu")
		(net "GMI_CPU1_G0_CPU0_G2_TX_DN<0>")
	)
	(segment
		(start 372.713504 -228.62159)
		(end 372.712488 -228.621082)
		(width 0.1143)
		(layer "In6.Cu")
		(net "GMI_CPU1_G0_CPU0_G2_TX_DN<0>")
	)
	(segment
		(start 374.068086 -238.508794)
		(end 374.136158 -238.46917)
		(width 0.1143)
		(layer "In6.Cu")
		(net "GMI_CPU1_G0_CPU0_G2_TX_DN<0>")
	)
	(segment
		(start 98.79711 -228.613462)
		(end 98.783394 -228.621336)
		(width 0.1143)
		(layer "In6.Cu")
		(net "GMI_CPU1_G0_CPU0_G2_TX_DN<0>")
	)
	(segment
		(start 97.859088 -240.91646)
		(end 97.861374 -240.917984)
		(width 0.1143)
		(layer "In6.Cu")
		(net "GMI_CPU1_G0_CPU0_G2_TX_DN<0>")
	)
	(segment
		(start 100.212906 -224.56013)
		(end 100.212652 -224.56013)
		(width 0.1143)
		(layer "In6.Cu")
		(net "GMI_CPU1_G0_CPU0_G2_TX_DN<0>")
	)
	(segment
		(start 97.398586 -238.49203)
		(end 97.427796 -238.509048)
		(width 0.1143)
		(layer "In6.Cu")
		(net "GMI_CPU1_G0_CPU0_G2_TX_DN<0>")
	)
	(segment
		(start 372.68785 -227.962206)
		(end 372.694454 -227.957888)
		(width 0.1143)
		(layer "In6.Cu")
		(net "GMI_CPU1_G0_CPU0_G2_TX_DN<0>")
	)
	(segment
		(start 371.289072 -224.562924)
		(end 371.287548 -224.562162)
		(width 0.1143)
		(layer "In6.Cu")
		(net "GMI_CPU1_G0_CPU0_G2_TX_DN<0>")
	)
	(segment
		(start 372.69674 -231.852724)
		(end 372.68912 -231.847644)
		(width 0.1143)
		(layer "In6.Cu")
		(net "GMI_CPU1_G0_CPU0_G2_TX_DN<0>")
	)
	(segment
		(start 373.620792 -240.925604)
		(end 373.627904 -240.922048)
		(width 0.1143)
		(layer "In6.Cu")
		(net "GMI_CPU1_G0_CPU0_G2_TX_DN<0>")
	)
	(arc
		(start 371.56009 -225.044254)
		(mid 371.49549 -224.781555)
		(end 371.31625 -224.578926)
		(width 0.1143)
		(layer "In6.Cu")
		(net "GMI_CPU1_G0_CPU0_G2_TX_DN<0>")
	)
	(arc
		(start 374.068086 -239.11941)
		(mid 373.910375 -238.814102)
		(end 374.068086 -238.508794)
		(width 0.1143)
		(layer "In6.Cu")
		(net "GMI_CPU1_G0_CPU0_G2_TX_DN<0>")
	)
	(arc
		(start 372.728998 -231.177338)
		(mid 372.906194 -230.975326)
		(end 372.970044 -230.714296)
		(width 0.1143)
		(layer "In6.Cu")
		(net "GMI_CPU1_G0_CPU0_G2_TX_DN<0>")
	)
	(arc
		(start 101.119686 -222.959168)
		(mid 100.940434 -223.161791)
		(end 100.875846 -223.424496)
		(width 0.1143)
		(layer "In6.Cu")
		(net "GMI_CPU1_G0_CPU0_G2_TX_DN<0>")
	)
	(arc
		(start 372.741444 -228.640132)
		(mid 372.727774 -228.630408)
		(end 372.713504 -228.62159)
		(width 0.1143)
		(layer "In6.Cu")
		(net "GMI_CPU1_G0_CPU0_G2_TX_DN<0>")
	)
	(arc
		(start 372.970044 -229.08641)
		(mid 372.904698 -228.838187)
		(end 372.741444 -228.640132)
		(width 0.1143)
		(layer "In6.Cu")
		(net "GMI_CPU1_G0_CPU0_G2_TX_DN<0>")
	)
	(arc
		(start 98.62439 -233.626406)
		(mid 98.51633 -234.015096)
		(end 98.707956 -234.370118)
		(width 0.1143)
		(layer "In6.Cu")
		(net "GMI_CPU1_G0_CPU0_G2_TX_DN<0>")
	)
	(arc
		(start 98.055938 -236.384338)
		(mid 98.01454 -236.555212)
		(end 97.899728 -236.688376)
		(width 0.1143)
		(layer "In6.Cu")
		(net "GMI_CPU1_G0_CPU0_G2_TX_DN<0>")
	)
	(arc
		(start 372.6561 -233.448098)
		(mid 372.500167 -233.14406)
		(end 372.6561 -232.840022)
		(width 0.1143)
		(layer "In6.Cu")
		(net "GMI_CPU1_G0_CPU0_G2_TX_DN<0>")
	)
	(arc
		(start 98.851974 -232.847134)
		(mid 98.989885 -233.148991)
		(end 98.845116 -233.44759)
		(width 0.1143)
		(layer "In6.Cu")
		(net "GMI_CPU1_G0_CPU0_G2_TX_DN<0>")
	)
	(arc
		(start 98.769678 -231.86898)
		(mid 98.751769 -231.881845)
		(end 98.734372 -231.895396)
		(width 0.1143)
		(layer "In6.Cu")
		(net "GMI_CPU1_G0_CPU0_G2_TX_DN<0>")
	)
	(arc
		(start 98.525838 -230.71455)
		(mid 98.589644 -230.975603)
		(end 98.766884 -231.177592)
		(width 0.1143)
		(layer "In6.Cu")
		(net "GMI_CPU1_G0_CPU0_G2_TX_DN<0>")
	)
	(arc
		(start 100.405946 -224.234502)
		(mid 100.364548 -224.405376)
		(end 100.249736 -224.53854)
		(width 0.1143)
		(layer "In6.Cu")
		(net "GMI_CPU1_G0_CPU0_G2_TX_DN<0>")
	)
	(arc
		(start 374.136158 -238.46917)
		(mid 374.380012 -238.004096)
		(end 374.136158 -237.539022)
		(width 0.1143)
		(layer "In6.Cu")
		(net "GMI_CPU1_G0_CPU0_G2_TX_DN<0>")
	)
	(arc
		(start 98.840544 -231.220518)
		(mid 98.995748 -231.52458)
		(end 98.839782 -231.82834)
		(width 0.1143)
		(layer "In6.Cu")
		(net "GMI_CPU1_G0_CPU0_G2_TX_DN<0>")
	)
	(arc
		(start 370.620036 -223.424242)
		(mid 370.555436 -223.161543)
		(end 370.376196 -222.958914)
		(width 0.1143)
		(layer "In6.Cu")
		(net "GMI_CPU1_G0_CPU0_G2_TX_DN<0>")
	)
	(arc
		(start 372.657878 -230.209598)
		(mid 372.541697 -230.076039)
		(end 372.49989 -229.904036)
		(width 0.1143)
		(layer "In6.Cu")
		(net "GMI_CPU1_G0_CPU0_G2_TX_DN<0>")
	)
	(arc
		(start 372.1862 -226.158298)
		(mid 372.071357 -226.02515)
		(end 372.02999 -225.85426)
		(width 0.1143)
		(layer "In6.Cu")
		(net "GMI_CPU1_G0_CPU0_G2_TX_DN<0>")
	)
	(arc
		(start 372.726204 -227.9396)
		(mid 372.970267 -227.474272)
		(end 372.726204 -227.008944)
		(width 0.1143)
		(layer "In6.Cu")
		(net "GMI_CPU1_G0_CPU0_G2_TX_DN<0>")
	)
	(arc
		(start 98.995992 -229.90429)
		(mid 98.954152 -230.076276)
		(end 98.838004 -230.209852)
		(width 0.1143)
		(layer "In6.Cu")
		(net "GMI_CPU1_G0_CPU0_G2_TX_DN<0>")
	)
	(arc
		(start 373.910098 -240.434114)
		(mid 373.951977 -240.262245)
		(end 374.068086 -240.128806)
		(width 0.1143)
		(layer "In6.Cu")
		(net "GMI_CPU1_G0_CPU0_G2_TX_DN<0>")
	)
	(arc
		(start 99.935792 -225.044508)
		(mid 99.893913 -225.216377)
		(end 99.777804 -225.349816)
		(width 0.1143)
		(layer "In6.Cu")
		(net "GMI_CPU1_G0_CPU0_G2_TX_DN<0>")
	)
	(arc
		(start 372.6561 -231.828086)
		(mid 372.499961 -231.524326)
		(end 372.655338 -231.220264)
		(width 0.1143)
		(layer "In6.Cu")
		(net "GMI_CPU1_G0_CPU0_G2_TX_DN<0>")
	)
	(arc
		(start 373.596154 -236.688122)
		(mid 373.481311 -236.554974)
		(end 373.439944 -236.384084)
		(width 0.1143)
		(layer "In6.Cu")
		(net "GMI_CPU1_G0_CPU0_G2_TX_DN<0>")
	)
	(arc
		(start 98.759264 -233.504232)
		(mid 98.686344 -233.559266)
		(end 98.62439 -233.626406)
		(width 0.1143)
		(layer "In6.Cu")
		(net "GMI_CPU1_G0_CPU0_G2_TX_DN<0>")
	)
	(arc
		(start 98.840036 -229.600252)
		(mid 98.954712 -229.733443)
		(end 98.995992 -229.90429)
		(width 0.1143)
		(layer "In6.Cu")
		(net "GMI_CPU1_G0_CPU0_G2_TX_DN<0>")
	)
	(arc
		(start 97.427796 -238.509048)
		(mid 97.585507 -238.814356)
		(end 97.427796 -239.119664)
		(width 0.1143)
		(layer "In6.Cu")
		(net "GMI_CPU1_G0_CPU0_G2_TX_DN<0>")
	)
	(arc
		(start 101.8159 -221.982284)
		(mid 101.753349 -222.048543)
		(end 101.677216 -222.098616)
		(width 0.1143)
		(layer "In6.Cu")
		(net "GMI_CPU1_G0_CPU0_G2_TX_DN<0>")
	)
	(arc
		(start 99.271328 -226.181158)
		(mid 99.067012 -226.385734)
		(end 98.992182 -226.665028)
		(width 0.1143)
		(layer "In6.Cu")
		(net "GMI_CPU1_G0_CPU0_G2_TX_DN<0>")
	)
	(arc
		(start 98.769678 -230.249476)
		(mid 98.590485 -230.451986)
		(end 98.525838 -230.71455)
		(width 0.1143)
		(layer "In6.Cu")
		(net "GMI_CPU1_G0_CPU0_G2_TX_DN<0>")
	)
	(arc
		(start 99.709732 -225.38944)
		(mid 99.530539 -225.59195)
		(end 99.465892 -225.854514)
		(width 0.1143)
		(layer "In6.Cu")
		(net "GMI_CPU1_G0_CPU0_G2_TX_DN<0>")
	)
	(arc
		(start 98.992182 -226.665028)
		(mid 98.942984 -226.850364)
		(end 98.80854 -226.9871)
		(width 0.1143)
		(layer "In6.Cu")
		(net "GMI_CPU1_G0_CPU0_G2_TX_DN<0>")
	)
	(arc
		(start 98.30054 -235.918756)
		(mid 98.120748 -236.121344)
		(end 98.055938 -236.384338)
		(width 0.1143)
		(layer "In6.Cu")
		(net "GMI_CPU1_G0_CPU0_G2_TX_DN<0>")
	)
	(arc
		(start 97.585784 -240.434368)
		(mid 97.650384 -240.697067)
		(end 97.829624 -240.899696)
		(width 0.1143)
		(layer "In6.Cu")
		(net "GMI_CPU1_G0_CPU0_G2_TX_DN<0>")
	)
	(arc
		(start 373.439944 -236.384084)
		(mid 373.375126 -236.121095)
		(end 373.195342 -235.918502)
		(width 0.1143)
		(layer "In6.Cu")
		(net "GMI_CPU1_G0_CPU0_G2_TX_DN<0>")
	)
	(arc
		(start 369.818666 -222.098362)
		(mid 369.742514 -222.048311)
		(end 369.679982 -221.98203)
		(width 0.1143)
		(layer "In6.Cu")
		(net "GMI_CPU1_G0_CPU0_G2_TX_DN<0>")
	)
	(arc
		(start 373.126254 -235.878116)
		(mid 373.011411 -235.744968)
		(end 372.970044 -235.574078)
		(width 0.1143)
		(layer "In6.Cu")
		(net "GMI_CPU1_G0_CPU0_G2_TX_DN<0>")
	)
	(arc
		(start 371.246146 -224.538286)
		(mid 371.131303 -224.405138)
		(end 371.089936 -224.234248)
		(width 0.1143)
		(layer "In6.Cu")
		(net "GMI_CPU1_G0_CPU0_G2_TX_DN<0>")
	)
	(arc
		(start 98.839782 -227.980494)
		(mid 98.995715 -228.284532)
		(end 98.839782 -228.58857)
		(width 0.1143)
		(layer "In6.Cu")
		(net "GMI_CPU1_G0_CPU0_G2_TX_DN<0>")
	)
	(arc
		(start 97.359724 -239.159288)
		(mid 97.11587 -239.624362)
		(end 97.359724 -240.089436)
		(width 0.1143)
		(layer "In6.Cu")
		(net "GMI_CPU1_G0_CPU0_G2_TX_DN<0>")
	)
	(arc
		(start 99.465892 -225.854514)
		(mid 99.424494 -226.025388)
		(end 99.309682 -226.158552)
		(width 0.1143)
		(layer "In6.Cu")
		(net "GMI_CPU1_G0_CPU0_G2_TX_DN<0>")
	)
	(arc
		(start 98.525838 -235.574332)
		(mid 98.48444 -235.745206)
		(end 98.369628 -235.87837)
		(width 0.1143)
		(layer "In6.Cu")
		(net "GMI_CPU1_G0_CPU0_G2_TX_DN<0>")
	)
	(arc
		(start 97.427796 -240.12906)
		(mid 97.543843 -240.262531)
		(end 97.585784 -240.434368)
		(width 0.1143)
		(layer "In6.Cu")
		(net "GMI_CPU1_G0_CPU0_G2_TX_DN<0>")
	)
	(arc
		(start 372.728998 -229.557326)
		(mid 372.906194 -229.355314)
		(end 372.970044 -229.094284)
		(width 0.1143)
		(layer "In6.Cu")
		(net "GMI_CPU1_G0_CPU0_G2_TX_DN<0>")
	)
	(arc
		(start 98.754438 -228.640386)
		(mid 98.59124 -228.83847)
		(end 98.525838 -229.086664)
		(width 0.1143)
		(layer "In6.Cu")
		(net "GMI_CPU1_G0_CPU0_G2_TX_DN<0>")
	)
	(arc
		(start 98.839782 -234.460288)
		(mid 98.995715 -234.764223)
		(end 98.840036 -235.068364)
		(width 0.1143)
		(layer "In6.Cu")
		(net "GMI_CPU1_G0_CPU0_G2_TX_DN<0>")
	)
	(arc
		(start 372.687342 -226.986846)
		(mid 372.55288 -226.85012)
		(end 372.5037 -226.664774)
		(width 0.1143)
		(layer "In6.Cu")
		(net "GMI_CPU1_G0_CPU0_G2_TX_DN<0>")
	)
	(arc
		(start 97.359724 -237.539276)
		(mid 97.11587 -238.00435)
		(end 97.359724 -238.469424)
		(width 0.1143)
		(layer "In6.Cu")
		(net "GMI_CPU1_G0_CPU0_G2_TX_DN<0>")
	)
	(arc
		(start 98.845116 -233.44759)
		(mid 98.824626 -233.462554)
		(end 98.80346 -233.476546)
		(width 0.1143)
		(layer "In6.Cu")
		(net "GMI_CPU1_G0_CPU0_G2_TX_DN<0>")
	)
	(arc
		(start 373.910098 -237.19409)
		(mid 373.845498 -236.931391)
		(end 373.666258 -236.728762)
		(width 0.1143)
		(layer "In6.Cu")
		(net "GMI_CPU1_G0_CPU0_G2_TX_DN<0>")
	)
	(arc
		(start 374.136158 -240.089182)
		(mid 374.380012 -239.624108)
		(end 374.136158 -239.159034)
		(width 0.1143)
		(layer "In6.Cu")
		(net "GMI_CPU1_G0_CPU0_G2_TX_DN<0>")
	)
	(arc
		(start 100.650548 -223.76892)
		(mid 100.470756 -223.971508)
		(end 100.405946 -224.234502)
		(width 0.1143)
		(layer "In6.Cu")
		(net "GMI_CPU1_G0_CPU0_G2_TX_DN<0>")
	)
	(arc
		(start 98.769678 -227.009198)
		(mid 98.525615 -227.474526)
		(end 98.769678 -227.939854)
		(width 0.1143)
		(layer "In6.Cu")
		(net "GMI_CPU1_G0_CPU0_G2_TX_DN<0>")
	)
	(arc
		(start 372.726204 -234.419394)
		(mid 372.970145 -233.965803)
		(end 372.745254 -233.502454)
		(width 0.1143)
		(layer "In6.Cu")
		(net "GMI_CPU1_G0_CPU0_G2_TX_DN<0>")
	)
	(arc
		(start 372.02999 -225.85426)
		(mid 371.965331 -225.591703)
		(end 371.78615 -225.389186)
		(width 0.1143)
		(layer "In6.Cu")
		(net "GMI_CPU1_G0_CPU0_G2_TX_DN<0>")
	)
	(arc
		(start 372.6561 -228.588316)
		(mid 372.500167 -228.284278)
		(end 372.6561 -227.98024)
		(width 0.1143)
		(layer "In6.Cu")
		(net "GMI_CPU1_G0_CPU0_G2_TX_DN<0>")
	)
	(arc
		(start 372.726204 -232.799382)
		(mid 372.969837 -232.3561)
		(end 372.76151 -231.895142)
		(width 0.1143)
		(layer "In6.Cu")
		(net "GMI_CPU1_G0_CPU0_G2_TX_DN<0>")
	)
	(arc
		(start 371.718078 -225.349562)
		(mid 371.602031 -225.216091)
		(end 371.56009 -225.044254)
		(width 0.1143)
		(layer "In6.Cu")
		(net "GMI_CPU1_G0_CPU0_G2_TX_DN<0>")
	)
	(arc
		(start 372.970044 -229.094284)
		(mid 372.970057 -229.090347)
		(end 372.970044 -229.08641)
		(width 0.1143)
		(layer "In6.Cu")
		(net "GMI_CPU1_G0_CPU0_G2_TX_DN<0>")
	)
	(arc
		(start 372.5037 -226.664774)
		(mid 372.428919 -226.385452)
		(end 372.224554 -226.180904)
		(width 0.1143)
		(layer "In6.Cu")
		(net "GMI_CPU1_G0_CPU0_G2_TX_DN<0>")
	)
	(arc
		(start 370.149882 -222.614236)
		(mid 370.085064 -222.351247)
		(end 369.90528 -222.148654)
		(width 0.1143)
		(layer "In6.Cu")
		(net "GMI_CPU1_G0_CPU0_G2_TX_DN<0>")
	)
	(arc
		(start 370.776246 -223.72828)
		(mid 370.661403 -223.595132)
		(end 370.620036 -223.424242)
		(width 0.1143)
		(layer "In6.Cu")
		(net "GMI_CPU1_G0_CPU0_G2_TX_DN<0>")
	)
	(arc
		(start 101.590602 -222.148908)
		(mid 101.41081 -222.351496)
		(end 101.346 -222.61449)
		(width 0.1143)
		(layer "In6.Cu")
		(net "GMI_CPU1_G0_CPU0_G2_TX_DN<0>")
	)
	(arc
		(start 373.446802 -241.17427)
		(mid 373.499 -241.042848)
		(end 373.596154 -240.940082)
		(width 0.1143)
		(layer "In6.Cu")
		(net "GMI_CPU1_G0_CPU0_G2_TX_DN<0>")
	)
	(arc
		(start 373.666258 -240.899442)
		(mid 373.84551 -240.696819)
		(end 373.910098 -240.434114)
		(width 0.1143)
		(layer "In6.Cu")
		(net "GMI_CPU1_G0_CPU0_G2_TX_DN<0>")
	)
	(arc
		(start 372.745254 -233.502454)
		(mid 372.735799 -233.495499)
		(end 372.726204 -233.488738)
		(width 0.1143)
		(layer "In6.Cu")
		(net "GMI_CPU1_G0_CPU0_G2_TX_DN<0>")
	)
	(arc
		(start 97.585784 -237.194344)
		(mid 97.543905 -237.366213)
		(end 97.427796 -237.499652)
		(width 0.1143)
		(layer "In6.Cu")
		(net "GMI_CPU1_G0_CPU0_G2_TX_DN<0>")
	)
	(arc
		(start 98.525838 -229.094538)
		(mid 98.589644 -229.355591)
		(end 98.766884 -229.55758)
		(width 0.1143)
		(layer "In6.Cu")
		(net "GMI_CPU1_G0_CPU0_G2_TX_DN<0>")
	)
	(arc
		(start 374.068086 -237.499398)
		(mid 373.952039 -237.365927)
		(end 373.910098 -237.19409)
		(width 0.1143)
		(layer "In6.Cu")
		(net "GMI_CPU1_G0_CPU0_G2_TX_DN<0>")
	)
	(arc
		(start 101.346 -222.61449)
		(mid 101.297198 -222.798324)
		(end 101.163882 -222.934022)
		(width 0.1143)
		(layer "In6.Cu")
		(net "GMI_CPU1_G0_CPU0_G2_TX_DN<0>")
	)
	(arc
		(start 98.525838 -229.086664)
		(mid 98.525823 -229.090601)
		(end 98.525838 -229.094538)
		(width 0.1143)
		(layer "In6.Cu")
		(net "GMI_CPU1_G0_CPU0_G2_TX_DN<0>")
	)
	(arc
		(start 372.970044 -235.574078)
		(mid 372.905385 -235.311521)
		(end 372.726204 -235.109004)
		(width 0.1143)
		(layer "In6.Cu")
		(net "GMI_CPU1_G0_CPU0_G2_TX_DN<0>")
	)
	(arc
		(start 370.332 -222.933768)
		(mid 370.198592 -222.798123)
		(end 370.149882 -222.614236)
		(width 0.1143)
		(layer "In6.Cu")
		(net "GMI_CPU1_G0_CPU0_G2_TX_DN<0>")
	)
	(arc
		(start 372.49989 -229.904036)
		(mid 372.541149 -229.733179)
		(end 372.655846 -229.599998)
		(width 0.1143)
		(layer "In6.Cu")
		(net "GMI_CPU1_G0_CPU0_G2_TX_DN<0>")
	)
	(arc
		(start 372.655846 -235.06811)
		(mid 372.500019 -234.763969)
		(end 372.6561 -234.460034)
		(width 0.1143)
		(layer "In6.Cu")
		(net "GMI_CPU1_G0_CPU0_G2_TX_DN<0>")
	)
	(arc
		(start 371.089936 -224.234248)
		(mid 371.025118 -223.971259)
		(end 370.845334 -223.768666)
		(width 0.1143)
		(layer "In6.Cu")
		(net "GMI_CPU1_G0_CPU0_G2_TX_DN<0>")
	)
	(arc
		(start 97.829624 -236.729016)
		(mid 97.650372 -236.931639)
		(end 97.585784 -237.194344)
		(width 0.1143)
		(layer "In6.Cu")
		(net "GMI_CPU1_G0_CPU0_G2_TX_DN<0>")
	)
	(arc
		(start 372.76151 -231.895142)
		(mid 372.744115 -231.881589)
		(end 372.726204 -231.868726)
		(width 0.1143)
		(layer "In6.Cu")
		(net "GMI_CPU1_G0_CPU0_G2_TX_DN<0>")
	)
	(arc
		(start 100.875846 -223.424496)
		(mid 100.834448 -223.59537)
		(end 100.719636 -223.728534)
		(width 0.1143)
		(layer "In6.Cu")
		(net "GMI_CPU1_G0_CPU0_G2_TX_DN<0>")
	)
	(arc
		(start 98.782378 -228.621844)
		(mid 98.768106 -228.63066)
		(end 98.754438 -228.640386)
		(width 0.1143)
		(layer "In6.Cu")
		(net "GMI_CPU1_G0_CPU0_G2_TX_DN<0>")
	)
	(arc
		(start 372.970044 -230.714296)
		(mid 372.905385 -230.451739)
		(end 372.726204 -230.249222)
		(width 0.1143)
		(layer "In6.Cu")
		(net "GMI_CPU1_G0_CPU0_G2_TX_DN<0>")
	)
	(arc
		(start 97.899728 -240.940336)
		(mid 97.996936 -241.043068)
		(end 98.04908 -241.174524)
		(width 0.1143)
		(layer "In6.Cu")
		(net "GMI_CPU1_G0_CPU0_G2_TX_DN<0>")
	)
	(arc
		(start 98.734372 -231.895396)
		(mid 98.525986 -232.356356)
		(end 98.769678 -232.799636)
		(width 0.1143)
		(layer "In6.Cu")
		(net "GMI_CPU1_G0_CPU0_G2_TX_DN<0>")
	)
	(arc
		(start 100.179632 -224.57918)
		(mid 100.00038 -224.781803)
		(end 99.935792 -225.044508)
		(width 0.1143)
		(layer "In6.Cu")
		(net "GMI_CPU1_G0_CPU0_G2_TX_DN<0>")
	)
	(arc
		(start 98.769678 -235.109258)
		(mid 98.590485 -235.311768)
		(end 98.525838 -235.574332)
		(width 0.1143)
		(layer "In6.Cu")
		(net "GMI_CPU1_G0_CPU0_G2_TX_DN<0>")
	)
	(segment
		(start 40.856916 -7.709154)
		(end 40.856916 -8.320024)
		(width 0.12954)
		(layer "F.Cu")
		(net "P5E_CPU1_G1_RX_DP<6>")
	)
	(segment
		(start 40.9956 -5.22859)
		(end 40.9956 -7.57047)
		(width 0.12954)
		(layer "F.Cu")
		(net "P5E_CPU1_G1_RX_DP<6>")
	)
	(segment
		(start 40.9956 -7.57047)
		(end 40.856916 -7.709154)
		(width 0.12954)
		(layer "F.Cu")
		(net "P5E_CPU1_G1_RX_DP<6>")
	)
	(segment
		(start 103.787956 -235.030264)
		(end 103.321104 -234.764326)
		(width 0.12954)
		(layer "F.Cu")
		(net "P5E_CPU1_G1_RX_DP<6>")
	)
	(segment
		(start 40.730424 -4.963414)
		(end 40.9956 -5.22859)
		(width 0.12954)
		(layer "F.Cu")
		(net "P5E_CPU1_G1_RX_DP<6>")
	)
	(segment
		(start 42.742104 -26.803096)
		(end 52.172362 -50.284888)
		(width 0.14224)
		(layer "In4.Cu")
		(net "P5E_CPU1_G1_RX_DP<6>")
	)
	(segment
		(start 104.611424 -221.378526)
		(end 104.611424 -221.637352)
		(width 0.1143)
		(layer "In4.Cu")
		(net "P5E_CPU1_G1_RX_DP<6>")
	)
	(segment
		(start 104.623362 -233.153458)
		(end 104.623362 -233.163618)
		(width 0.1143)
		(layer "In4.Cu")
		(net "P5E_CPU1_G1_RX_DP<6>")
	)
	(segment
		(start 104.918002 -225.531934)
		(end 104.918764 -225.532442)
		(width 0.1143)
		(layer "In4.Cu")
		(net "P5E_CPU1_G1_RX_DP<6>")
	)
	(segment
		(start 109.762036 -205.849728)
		(end 104.565704 -214.603076)
		(width 0.14224)
		(layer "In4.Cu")
		(net "P5E_CPU1_G1_RX_DP<6>")
	)
	(segment
		(start 105.34904 -226.31908)
		(end 105.388156 -226.34194)
		(width 0.1143)
		(layer "In4.Cu")
		(net "P5E_CPU1_G1_RX_DP<6>")
	)
	(segment
		(start 105.388156 -227.961952)
		(end 105.418636 -227.979732)
		(width 0.1143)
		(layer "In4.Cu")
		(net "P5E_CPU1_G1_RX_DP<6>")
	)
	(segment
		(start 104.44353 -223.74987)
		(end 104.408986 -223.769936)
		(width 0.1143)
		(layer "In4.Cu")
		(net "P5E_CPU1_G1_RX_DP<6>")
	)
	(segment
		(start 42.691304 -26.690828)
		(end 42.691558 -26.690574)
		(width 0.14224)
		(layer "In4.Cu")
		(net "P5E_CPU1_G1_RX_DP<6>")
	)
	(segment
		(start 104.611424 -221.637352)
		(end 104.635808 -221.661736)
		(width 0.1143)
		(layer "In4.Cu")
		(net "P5E_CPU1_G1_RX_DP<6>")
	)
	(segment
		(start 104.479852 -223.728788)
		(end 104.450134 -223.745806)
		(width 0.1143)
		(layer "In4.Cu")
		(net "P5E_CPU1_G1_RX_DP<6>")
	)
	(segment
		(start 60.027566 -58.358278)
		(end 148.364956 -137.79373)
		(width 0.14224)
		(layer "In4.Cu")
		(net "P5E_CPU1_G1_RX_DP<6>")
	)
	(segment
		(start 58.7375 -57.27827)
		(end 60.027566 -58.358278)
		(width 0.14224)
		(layer "In4.Cu")
		(net "P5E_CPU1_G1_RX_DP<6>")
	)
	(segment
		(start 104.635808 -221.661736)
		(end 104.635808 -221.835218)
		(width 0.1143)
		(layer "In4.Cu")
		(net "P5E_CPU1_G1_RX_DP<6>")
	)
	(segment
		(start 104.448102 -223.101916)
		(end 104.448864 -223.102424)
		(width 0.1143)
		(layer "In4.Cu")
		(net "P5E_CPU1_G1_RX_DP<6>")
	)
	(segment
		(start 104.926384 -232.652062)
		(end 104.920034 -232.655618)
		(width 0.1143)
		(layer "In4.Cu")
		(net "P5E_CPU1_G1_RX_DP<6>")
	)
	(segment
		(start 104.504998 -222.090742)
		(end 104.479852 -222.108776)
		(width 0.1143)
		(layer "In4.Cu")
		(net "P5E_CPU1_G1_RX_DP<6>")
	)
	(segment
		(start 104.479852 -222.108776)
		(end 104.408986 -222.149924)
		(width 0.1143)
		(layer "In4.Cu")
		(net "P5E_CPU1_G1_RX_DP<6>")
	)
	(segment
		(start 103.978202 -234.2769)
		(end 103.939086 -234.29976)
		(width 0.1143)
		(layer "In4.Cu")
		(net "P5E_CPU1_G1_RX_DP<6>")
	)
	(segment
		(start 104.408986 -223.079056)
		(end 104.445562 -223.100392)
		(width 0.1143)
		(layer "In4.Cu")
		(net "P5E_CPU1_G1_RX_DP<6>")
	)
	(segment
		(start 55.623968 -54.652418)
		(end 57.846976 -56.477662)
		(width 0.14224)
		(layer "In4.Cu")
		(net "P5E_CPU1_G1_RX_DP<6>")
	)
	(segment
		(start 104.448102 -233.466894)
		(end 104.408986 -233.489754)
		(width 0.1143)
		(layer "In4.Cu")
		(net "P5E_CPU1_G1_RX_DP<6>")
	)
	(segment
		(start 42.691558 -26.690574)
		(end 42.692066 -26.692352)
		(width 0.14224)
		(layer "In4.Cu")
		(net "P5E_CPU1_G1_RX_DP<6>")
	)
	(segment
		(start 39.524686 -19.12112)
		(end 39.701978 -20.084034)
		(width 0.14224)
		(layer "In4.Cu")
		(net "P5E_CPU1_G1_RX_DP<6>")
	)
	(segment
		(start 104.565704 -221.332806)
		(end 104.611424 -221.378526)
		(width 0.1143)
		(layer "In4.Cu")
		(net "P5E_CPU1_G1_RX_DP<6>")
	)
	(segment
		(start 104.44861 -224.722182)
		(end 104.458262 -224.727516)
		(width 0.1143)
		(layer "In4.Cu")
		(net "P5E_CPU1_G1_RX_DP<6>")
	)
	(segment
		(start 148.001482 -174.512732)
		(end 109.762036 -205.849728)
		(width 0.14224)
		(layer "In4.Cu")
		(net "P5E_CPU1_G1_RX_DP<6>")
	)
	(segment
		(start 105.418636 -226.96932)
		(end 105.388156 -226.9871)
		(width 0.1143)
		(layer "In4.Cu")
		(net "P5E_CPU1_G1_RX_DP<6>")
	)
	(segment
		(start 104.914192 -232.65892)
		(end 104.912922 -232.659682)
		(width 0.1143)
		(layer "In4.Cu")
		(net "P5E_CPU1_G1_RX_DP<6>")
	)
	(segment
		(start 52.172362 -50.284888)
		(end 54.567582 -53.599842)
		(width 0.14224)
		(layer "In4.Cu")
		(net "P5E_CPU1_G1_RX_DP<6>")
	)
	(segment
		(start 104.447086 -223.747584)
		(end 104.445816 -223.748346)
		(width 0.1143)
		(layer "In4.Cu")
		(net "P5E_CPU1_G1_RX_DP<6>")
	)
	(segment
		(start 104.916224 -232.657904)
		(end 104.914192 -232.65892)
		(width 0.1143)
		(layer "In4.Cu")
		(net "P5E_CPU1_G1_RX_DP<6>")
	)
	(segment
		(start 103.619046 -234.764326)
		(end 103.321104 -234.764326)
		(width 0.1143)
		(layer "In4.Cu")
		(net "P5E_CPU1_G1_RX_DP<6>")
	)
	(segment
		(start 153.33218 -159.85617)
		(end 153.33218 -163.943792)
		(width 0.14224)
		(layer "In4.Cu")
		(net "P5E_CPU1_G1_RX_DP<6>")
	)
	(segment
		(start 39.524686 -19.120866)
		(end 39.524686 -19.12112)
		(width 0.14224)
		(layer "In4.Cu")
		(net "P5E_CPU1_G1_RX_DP<6>")
	)
	(segment
		(start 105.418636 -230.20909)
		(end 105.35158 -230.248206)
		(width 0.1143)
		(layer "In4.Cu")
		(net "P5E_CPU1_G1_RX_DP<6>")
	)
	(segment
		(start 103.70185 -234.681522)
		(end 103.619046 -234.764326)
		(width 0.1143)
		(layer "In4.Cu")
		(net "P5E_CPU1_G1_RX_DP<6>")
	)
	(segment
		(start 153.33218 -163.943792)
		(end 151.442166 -169.494962)
		(width 0.14224)
		(layer "In4.Cu")
		(net "P5E_CPU1_G1_RX_DP<6>")
	)
	(segment
		(start 105.388156 -226.9871)
		(end 105.34904 -227.00996)
		(width 0.1143)
		(layer "In4.Cu")
		(net "P5E_CPU1_G1_RX_DP<6>")
	)
	(segment
		(start 104.918764 -232.65638)
		(end 104.918002 -232.656888)
		(width 0.1143)
		(layer "In4.Cu")
		(net "P5E_CPU1_G1_RX_DP<6>")
	)
	(segment
		(start 104.93502 -232.646982)
		(end 104.926384 -232.652062)
		(width 0.1143)
		(layer "In4.Cu")
		(net "P5E_CPU1_G1_RX_DP<6>")
	)
	(segment
		(start 104.918002 -232.656888)
		(end 104.916986 -232.657396)
		(width 0.1143)
		(layer "In4.Cu")
		(net "P5E_CPU1_G1_RX_DP<6>")
	)
	(segment
		(start 39.56431 -18.597626)
		(end 39.524686 -19.120866)
		(width 0.14224)
		(layer "In4.Cu")
		(net "P5E_CPU1_G1_RX_DP<6>")
	)
	(segment
		(start 55.087012 -54.169564)
		(end 55.623968 -54.652418)
		(width 0.14224)
		(layer "In4.Cu")
		(net "P5E_CPU1_G1_RX_DP<6>")
	)
	(segment
		(start 151.26081 -169.97553)
		(end 148.001482 -174.512732)
		(width 0.14224)
		(layer "In4.Cu")
		(net "P5E_CPU1_G1_RX_DP<6>")
	)
	(segment
		(start 104.008682 -234.25912)
		(end 103.978202 -234.2769)
		(width 0.1143)
		(layer "In4.Cu")
		(net "P5E_CPU1_G1_RX_DP<6>")
	)
	(segment
		(start 151.441404 -169.49801)
		(end 151.26081 -169.97553)
		(width 0.14224)
		(layer "In4.Cu")
		(net "P5E_CPU1_G1_RX_DP<6>")
	)
	(segment
		(start 54.567582 -53.599842)
		(end 55.087012 -54.169564)
		(width 0.14224)
		(layer "In4.Cu")
		(net "P5E_CPU1_G1_RX_DP<6>")
	)
	(segment
		(start 104.447086 -223.101408)
		(end 104.448102 -223.101916)
		(width 0.1143)
		(layer "In4.Cu")
		(net "P5E_CPU1_G1_RX_DP<6>")
	)
	(segment
		(start 151.442166 -169.494962)
		(end 151.44242 -169.494962)
		(width 0.14224)
		(layer "In4.Cu")
		(net "P5E_CPU1_G1_RX_DP<6>")
	)
	(segment
		(start 105.388156 -226.34194)
		(end 105.418636 -226.35972)
		(width 0.1143)
		(layer "In4.Cu")
		(net "P5E_CPU1_G1_RX_DP<6>")
	)
	(segment
		(start 39.701978 -20.084034)
		(end 42.691304 -26.690828)
		(width 0.14224)
		(layer "In4.Cu")
		(net "P5E_CPU1_G1_RX_DP<6>")
	)
	(segment
		(start 42.692066 -26.692352)
		(end 42.742104 -26.803096)
		(width 0.14224)
		(layer "In4.Cu")
		(net "P5E_CPU1_G1_RX_DP<6>")
	)
	(segment
		(start 148.364956 -137.79373)
		(end 152.484582 -146.302222)
		(width 0.14224)
		(layer "In4.Cu")
		(net "P5E_CPU1_G1_RX_DP<6>")
	)
	(segment
		(start 104.918764 -232.012236)
		(end 104.960674 -232.037382)
		(width 0.1143)
		(layer "In4.Cu")
		(net "P5E_CPU1_G1_RX_DP<6>")
	)
	(segment
		(start 152.484582 -146.302222)
		(end 153.33218 -159.85617)
		(width 0.14224)
		(layer "In4.Cu")
		(net "P5E_CPU1_G1_RX_DP<6>")
	)
	(segment
		(start 104.916986 -232.657396)
		(end 104.916224 -232.657904)
		(width 0.1143)
		(layer "In4.Cu")
		(net "P5E_CPU1_G1_RX_DP<6>")
	)
	(segment
		(start 104.918764 -225.532442)
		(end 104.949752 -225.550222)
		(width 0.1143)
		(layer "In4.Cu")
		(net "P5E_CPU1_G1_RX_DP<6>")
	)
	(segment
		(start 104.448864 -223.102424)
		(end 104.479852 -223.120204)
		(width 0.1143)
		(layer "In4.Cu")
		(net "P5E_CPU1_G1_RX_DP<6>")
	)
	(segment
		(start 105.34904 -227.939092)
		(end 105.388156 -227.961952)
		(width 0.1143)
		(layer "In4.Cu")
		(net "P5E_CPU1_G1_RX_DP<6>")
	)
	(segment
		(start 104.445816 -223.748346)
		(end 104.44353 -223.74987)
		(width 0.1143)
		(layer "In4.Cu")
		(net "P5E_CPU1_G1_RX_DP<6>")
	)
	(segment
		(start 104.920034 -232.655618)
		(end 104.918764 -232.65638)
		(width 0.1143)
		(layer "In4.Cu")
		(net "P5E_CPU1_G1_RX_DP<6>")
	)
	(segment
		(start 105.34904 -229.559104)
		(end 105.388156 -229.581964)
		(width 0.1143)
		(layer "In4.Cu")
		(net "P5E_CPU1_G1_RX_DP<6>")
	)
	(segment
		(start 39.957248 -17.648174)
		(end 39.56431 -18.597626)
		(width 0.14224)
		(layer "In4.Cu")
		(net "P5E_CPU1_G1_RX_DP<6>")
	)
	(segment
		(start 41.021254 -5.254244)
		(end 41.021254 -12.295886)
		(width 0.14224)
		(layer "In4.Cu")
		(net "P5E_CPU1_G1_RX_DP<6>")
	)
	(segment
		(start 105.388156 -229.581964)
		(end 105.420668 -229.60076)
		(width 0.1143)
		(layer "In4.Cu")
		(net "P5E_CPU1_G1_RX_DP<6>")
	)
	(segment
		(start 104.912922 -232.659682)
		(end 104.911906 -232.66019)
		(width 0.1143)
		(layer "In4.Cu")
		(net "P5E_CPU1_G1_RX_DP<6>")
	)
	(segment
		(start 104.409748 -224.699576)
		(end 104.44861 -224.722182)
		(width 0.1143)
		(layer "In4.Cu")
		(net "P5E_CPU1_G1_RX_DP<6>")
	)
	(segment
		(start 105.418636 -228.589332)
		(end 105.388156 -228.607112)
		(width 0.1143)
		(layer "In4.Cu")
		(net "P5E_CPU1_G1_RX_DP<6>")
	)
	(segment
		(start 41.021254 -12.295886)
		(end 39.957248 -17.648174)
		(width 0.14224)
		(layer "In4.Cu")
		(net "P5E_CPU1_G1_RX_DP<6>")
	)
	(segment
		(start 104.911906 -232.66019)
		(end 104.910128 -232.661206)
		(width 0.1143)
		(layer "In4.Cu")
		(net "P5E_CPU1_G1_RX_DP<6>")
	)
	(segment
		(start 104.565704 -214.603076)
		(end 104.565704 -221.304358)
		(width 0.14224)
		(layer "In4.Cu")
		(net "P5E_CPU1_G1_RX_DP<6>")
	)
	(segment
		(start 104.448864 -223.746568)
		(end 104.448102 -223.747076)
		(width 0.1143)
		(layer "In4.Cu")
		(net "P5E_CPU1_G1_RX_DP<6>")
	)
	(segment
		(start 104.565704 -221.304358)
		(end 104.565704 -221.332806)
		(width 0.1143)
		(layer "In4.Cu")
		(net "P5E_CPU1_G1_RX_DP<6>")
	)
	(segment
		(start 104.644698 -225.05162)
		(end 104.644698 -225.05924)
		(width 0.1143)
		(layer "In4.Cu")
		(net "P5E_CPU1_G1_RX_DP<6>")
	)
	(segment
		(start 104.908096 -225.525838)
		(end 104.918002 -225.531934)
		(width 0.1143)
		(layer "In4.Cu")
		(net "P5E_CPU1_G1_RX_DP<6>")
	)
	(segment
		(start 151.44242 -169.494962)
		(end 151.441404 -169.49801)
		(width 0.14224)
		(layer "In4.Cu")
		(net "P5E_CPU1_G1_RX_DP<6>")
	)
	(segment
		(start 105.388156 -228.607112)
		(end 105.34904 -228.629972)
		(width 0.1143)
		(layer "In4.Cu")
		(net "P5E_CPU1_G1_RX_DP<6>")
	)
	(segment
		(start 57.846976 -56.477662)
		(end 58.7375 -57.27827)
		(width 0.14224)
		(layer "In4.Cu")
		(net "P5E_CPU1_G1_RX_DP<6>")
	)
	(segment
		(start 104.910128 -232.661206)
		(end 104.904794 -232.664508)
		(width 0.1143)
		(layer "In4.Cu")
		(net "P5E_CPU1_G1_RX_DP<6>")
	)
	(segment
		(start 104.91724 -232.01122)
		(end 104.918764 -232.012236)
		(width 0.1143)
		(layer "In4.Cu")
		(net "P5E_CPU1_G1_RX_DP<6>")
	)
	(segment
		(start 104.95153 -231.017318)
		(end 104.88168 -231.057958)
		(width 0.1143)
		(layer "In4.Cu")
		(net "P5E_CPU1_G1_RX_DP<6>")
	)
	(segment
		(start 104.448102 -223.747076)
		(end 104.447086 -223.747584)
		(width 0.1143)
		(layer "In4.Cu")
		(net "P5E_CPU1_G1_RX_DP<6>")
	)
	(segment
		(start 40.730424 -4.963414)
		(end 41.021254 -5.254244)
		(width 0.14224)
		(layer "In4.Cu")
		(net "P5E_CPU1_G1_RX_DP<6>")
	)
	(segment
		(start 104.445562 -223.100392)
		(end 104.447086 -223.101408)
		(width 0.1143)
		(layer "In4.Cu")
		(net "P5E_CPU1_G1_RX_DP<6>")
	)
	(segment
		(start 104.450134 -223.745806)
		(end 104.448864 -223.746568)
		(width 0.1143)
		(layer "In4.Cu")
		(net "P5E_CPU1_G1_RX_DP<6>")
	)
	(arc
		(start 104.904794 -232.664508)
		(mid 104.698726 -232.871371)
		(end 104.623362 -233.153458)
		(width 0.1143)
		(layer "In4.Cu")
		(net "P5E_CPU1_G1_RX_DP<6>")
	)
	(arc
		(start 104.479852 -223.120204)
		(mid 104.63578 -223.424496)
		(end 104.479852 -223.728788)
		(width 0.1143)
		(layer "In4.Cu")
		(net "P5E_CPU1_G1_RX_DP<6>")
	)
	(arc
		(start 104.635808 -221.835218)
		(mid 104.601276 -221.978798)
		(end 104.504998 -222.090742)
		(width 0.1143)
		(layer "In4.Cu")
		(net "P5E_CPU1_G1_RX_DP<6>")
	)
	(arc
		(start 105.34904 -227.00996)
		(mid 105.105713 -227.474526)
		(end 105.34904 -227.939092)
		(width 0.1143)
		(layer "In4.Cu")
		(net "P5E_CPU1_G1_RX_DP<6>")
	)
	(arc
		(start 105.105708 -225.854514)
		(mid 105.170223 -226.116733)
		(end 105.34904 -226.31908)
		(width 0.1143)
		(layer "In4.Cu")
		(net "P5E_CPU1_G1_RX_DP<6>")
	)
	(arc
		(start 104.88168 -231.057958)
		(mid 104.636801 -231.544352)
		(end 104.91724 -232.01122)
		(width 0.1143)
		(layer "In4.Cu")
		(net "P5E_CPU1_G1_RX_DP<6>")
	)
	(arc
		(start 104.408986 -222.149924)
		(mid 104.165659 -222.61449)
		(end 104.408986 -223.079056)
		(width 0.1143)
		(layer "In4.Cu")
		(net "P5E_CPU1_G1_RX_DP<6>")
	)
	(arc
		(start 104.408986 -233.489754)
		(mid 104.230173 -233.692104)
		(end 104.165654 -233.95432)
		(width 0.1143)
		(layer "In4.Cu")
		(net "P5E_CPU1_G1_RX_DP<6>")
	)
	(arc
		(start 104.623362 -233.163618)
		(mid 104.576395 -233.338753)
		(end 104.448102 -233.466894)
		(width 0.1143)
		(layer "In4.Cu")
		(net "P5E_CPU1_G1_RX_DP<6>")
	)
	(arc
		(start 105.35158 -230.248206)
		(mid 105.170928 -230.450951)
		(end 105.105708 -230.71455)
		(width 0.1143)
		(layer "In4.Cu")
		(net "P5E_CPU1_G1_RX_DP<6>")
	)
	(arc
		(start 103.939086 -234.29976)
		(mid 103.787099 -234.456268)
		(end 103.70566 -234.658662)
		(width 0.1143)
		(layer "In4.Cu")
		(net "P5E_CPU1_G1_RX_DP<6>")
	)
	(arc
		(start 105.418636 -227.979732)
		(mid 105.575613 -228.284532)
		(end 105.418636 -228.589332)
		(width 0.1143)
		(layer "In4.Cu")
		(net "P5E_CPU1_G1_RX_DP<6>")
	)
	(arc
		(start 105.575608 -229.90429)
		(mid 105.534059 -230.075712)
		(end 105.418636 -230.20909)
		(width 0.1143)
		(layer "In4.Cu")
		(net "P5E_CPU1_G1_RX_DP<6>")
	)
	(arc
		(start 105.420668 -229.60076)
		(mid 105.534597 -229.733907)
		(end 105.575608 -229.90429)
		(width 0.1143)
		(layer "In4.Cu")
		(net "P5E_CPU1_G1_RX_DP<6>")
	)
	(arc
		(start 104.644698 -225.05924)
		(mid 104.715085 -225.327158)
		(end 104.908096 -225.525838)
		(width 0.1143)
		(layer "In4.Cu")
		(net "P5E_CPU1_G1_RX_DP<6>")
	)
	(arc
		(start 104.949752 -225.550222)
		(mid 105.064428 -225.683556)
		(end 105.105708 -225.854514)
		(width 0.1143)
		(layer "In4.Cu")
		(net "P5E_CPU1_G1_RX_DP<6>")
	)
	(arc
		(start 105.105708 -230.71455)
		(mid 105.064946 -230.884434)
		(end 104.95153 -231.017318)
		(width 0.1143)
		(layer "In4.Cu")
		(net "P5E_CPU1_G1_RX_DP<6>")
	)
	(arc
		(start 104.960674 -232.037382)
		(mid 105.114344 -232.349243)
		(end 104.93502 -232.646982)
		(width 0.1143)
		(layer "In4.Cu")
		(net "P5E_CPU1_G1_RX_DP<6>")
	)
	(arc
		(start 104.165654 -233.95432)
		(mid 104.124105 -234.125742)
		(end 104.008682 -234.25912)
		(width 0.1143)
		(layer "In4.Cu")
		(net "P5E_CPU1_G1_RX_DP<6>")
	)
	(arc
		(start 103.70566 -234.658662)
		(mid 103.703637 -234.670072)
		(end 103.70185 -234.681522)
		(width 0.1143)
		(layer "In4.Cu")
		(net "P5E_CPU1_G1_RX_DP<6>")
	)
	(arc
		(start 105.34904 -228.629972)
		(mid 105.105713 -229.094538)
		(end 105.34904 -229.559104)
		(width 0.1143)
		(layer "In4.Cu")
		(net "P5E_CPU1_G1_RX_DP<6>")
	)
	(arc
		(start 104.408986 -224.699068)
		(mid 104.409367 -224.699322)
		(end 104.409748 -224.699576)
		(width 0.1143)
		(layer "In4.Cu")
		(net "P5E_CPU1_G1_RX_DP<6>")
	)
	(arc
		(start 105.418636 -226.35972)
		(mid 105.575613 -226.66452)
		(end 105.418636 -226.96932)
		(width 0.1143)
		(layer "In4.Cu")
		(net "P5E_CPU1_G1_RX_DP<6>")
	)
	(arc
		(start 104.408986 -223.769936)
		(mid 104.165659 -224.234502)
		(end 104.408986 -224.699068)
		(width 0.1143)
		(layer "In4.Cu")
		(net "P5E_CPU1_G1_RX_DP<6>")
	)
	(arc
		(start 104.458262 -224.727516)
		(mid 104.594774 -224.864666)
		(end 104.644698 -225.05162)
		(width 0.1143)
		(layer "In4.Cu")
		(net "P5E_CPU1_G1_RX_DP<6>")
	)
	(segment
		(start 39.057072 -8.320024)
		(end 39.057072 -7.709154)
		(width 0.12954)
		(layer "F.Cu")
		(net "P5E_CPU1_G1_RX_DP<7>")
	)
	(segment
		(start 39.057072 -7.709154)
		(end 39.195756 -7.57047)
		(width 0.12954)
		(layer "F.Cu")
		(net "P5E_CPU1_G1_RX_DP<7>")
	)
	(segment
		(start 39.195756 -6.99516)
		(end 38.925754 -6.725158)
		(width 0.12954)
		(layer "F.Cu")
		(net "P5E_CPU1_G1_RX_DP<7>")
	)
	(segment
		(start 39.195756 -7.57047)
		(end 39.195756 -6.99516)
		(width 0.12954)
		(layer "F.Cu")
		(net "P5E_CPU1_G1_RX_DP<7>")
	)
	(segment
		(start 103.787956 -231.79024)
		(end 103.321104 -231.524302)
		(width 0.12954)
		(layer "F.Cu")
		(net "P5E_CPU1_G1_RX_DP<7>")
	)
	(segment
		(start 103.978202 -225.531934)
		(end 103.978964 -225.532442)
		(width 0.1143)
		(layer "In4.Cu")
		(net "P5E_CPU1_G1_RX_DP<7>")
	)
	(segment
		(start 37.3253 -19.271742)
		(end 40.950896 -26.808684)
		(width 0.14224)
		(layer "In4.Cu")
		(net "P5E_CPU1_G1_RX_DP<7>")
	)
	(segment
		(start 36.490402 -17.935702)
		(end 36.725606 -18.375122)
		(width 0.14224)
		(layer "In4.Cu")
		(net "P5E_CPU1_G1_RX_DP<7>")
	)
	(segment
		(start 103.66121 -221.378526)
		(end 103.66121 -221.479872)
		(width 0.1143)
		(layer "In4.Cu")
		(net "P5E_CPU1_G1_RX_DP<7>")
	)
	(segment
		(start 38.736778 -13.4112)
		(end 36.764976 -16.362426)
		(width 0.14224)
		(layer "In4.Cu")
		(net "P5E_CPU1_G1_RX_DP<7>")
	)
	(segment
		(start 103.66121 -221.479872)
		(end 103.359712 -222.207836)
		(width 0.1143)
		(layer "In4.Cu")
		(net "P5E_CPU1_G1_RX_DP<7>")
	)
	(segment
		(start 104.448356 -228.607112)
		(end 104.40924 -228.629972)
		(width 0.1143)
		(layer "In4.Cu")
		(net "P5E_CPU1_G1_RX_DP<7>")
	)
	(segment
		(start 103.975662 -225.53041)
		(end 103.977186 -225.531426)
		(width 0.1143)
		(layer "In4.Cu")
		(net "P5E_CPU1_G1_RX_DP<7>")
	)
	(segment
		(start 103.435912 -223.02216)
		(end 103.520494 -223.106742)
		(width 0.1143)
		(layer "In4.Cu")
		(net "P5E_CPU1_G1_RX_DP<7>")
	)
	(segment
		(start 36.41979 -17.500346)
		(end 36.41979 -17.765014)
		(width 0.14224)
		(layer "In4.Cu")
		(net "P5E_CPU1_G1_RX_DP<7>")
	)
	(segment
		(start 104.448356 -226.9871)
		(end 104.40924 -227.00996)
		(width 0.1143)
		(layer "In4.Cu")
		(net "P5E_CPU1_G1_RX_DP<7>")
	)
	(segment
		(start 103.520494 -223.106742)
		(end 103.534718 -223.116648)
		(width 0.1143)
		(layer "In4.Cu")
		(net "P5E_CPU1_G1_RX_DP<7>")
	)
	(segment
		(start 109.044232 -205.232254)
		(end 103.61549 -214.376254)
		(width 0.14224)
		(layer "In4.Cu")
		(net "P5E_CPU1_G1_RX_DP<7>")
	)
	(segment
		(start 38.925754 -6.725158)
		(end 39.216584 -7.015988)
		(width 0.14224)
		(layer "In4.Cu")
		(net "P5E_CPU1_G1_RX_DP<7>")
	)
	(segment
		(start 103.619046 -231.524302)
		(end 103.321104 -231.524302)
		(width 0.1143)
		(layer "In4.Cu")
		(net "P5E_CPU1_G1_RX_DP<7>")
	)
	(segment
		(start 55.016146 -55.359554)
		(end 57.239154 -57.184798)
		(width 0.14224)
		(layer "In4.Cu")
		(net "P5E_CPU1_G1_RX_DP<7>")
	)
	(segment
		(start 39.216584 -7.015988)
		(end 39.216584 -11.564874)
		(width 0.14224)
		(layer "In4.Cu")
		(net "P5E_CPU1_G1_RX_DP<7>")
	)
	(segment
		(start 149.85111 -143.004032)
		(end 151.551132 -146.516344)
		(width 0.14224)
		(layer "In4.Cu")
		(net "P5E_CPU1_G1_RX_DP<7>")
	)
	(segment
		(start 103.469186 -224.699068)
		(end 103.508302 -224.721928)
		(width 0.1143)
		(layer "In4.Cu")
		(net "P5E_CPU1_G1_RX_DP<7>")
	)
	(segment
		(start 103.939086 -225.509074)
		(end 103.975662 -225.53041)
		(width 0.1143)
		(layer "In4.Cu")
		(net "P5E_CPU1_G1_RX_DP<7>")
	)
	(segment
		(start 103.61549 -221.304358)
		(end 103.61549 -221.332806)
		(width 0.1143)
		(layer "In4.Cu")
		(net "P5E_CPU1_G1_RX_DP<7>")
	)
	(segment
		(start 39.21633 -11.565128)
		(end 38.953186 -12.888214)
		(width 0.14224)
		(layer "In4.Cu")
		(net "P5E_CPU1_G1_RX_DP<7>")
	)
	(segment
		(start 54.429406 -54.83225)
		(end 55.016146 -55.359554)
		(width 0.14224)
		(layer "In4.Cu")
		(net "P5E_CPU1_G1_RX_DP<7>")
	)
	(segment
		(start 104.448356 -227.961952)
		(end 104.478836 -227.979732)
		(width 0.1143)
		(layer "In4.Cu")
		(net "P5E_CPU1_G1_RX_DP<7>")
	)
	(segment
		(start 103.977186 -225.531426)
		(end 103.978202 -225.531934)
		(width 0.1143)
		(layer "In4.Cu")
		(net "P5E_CPU1_G1_RX_DP<7>")
	)
	(segment
		(start 59.416442 -59.06262)
		(end 147.605242 -138.364722)
		(width 0.14224)
		(layer "In4.Cu")
		(net "P5E_CPU1_G1_RX_DP<7>")
	)
	(segment
		(start 104.478836 -226.96932)
		(end 104.448356 -226.9871)
		(width 0.1143)
		(layer "In4.Cu")
		(net "P5E_CPU1_G1_RX_DP<7>")
	)
	(segment
		(start 36.764976 -16.362426)
		(end 36.41979 -17.500346)
		(width 0.14224)
		(layer "In4.Cu")
		(net "P5E_CPU1_G1_RX_DP<7>")
	)
	(segment
		(start 39.216584 -11.564874)
		(end 39.21633 -11.565128)
		(width 0.14224)
		(layer "In4.Cu")
		(net "P5E_CPU1_G1_RX_DP<7>")
	)
	(segment
		(start 38.953186 -12.888214)
		(end 38.736778 -13.4112)
		(width 0.14224)
		(layer "In4.Cu")
		(net "P5E_CPU1_G1_RX_DP<7>")
	)
	(segment
		(start 103.508302 -224.721928)
		(end 103.538782 -224.739708)
		(width 0.1143)
		(layer "In4.Cu")
		(net "P5E_CPU1_G1_RX_DP<7>")
	)
	(segment
		(start 147.020534 -174.110904)
		(end 109.044232 -205.232254)
		(width 0.14224)
		(layer "In4.Cu")
		(net "P5E_CPU1_G1_RX_DP<7>")
	)
	(segment
		(start 103.978202 -231.036876)
		(end 103.939086 -231.059736)
		(width 0.1143)
		(layer "In4.Cu")
		(net "P5E_CPU1_G1_RX_DP<7>")
	)
	(segment
		(start 103.978964 -225.532442)
		(end 104.009952 -225.550222)
		(width 0.1143)
		(layer "In4.Cu")
		(net "P5E_CPU1_G1_RX_DP<7>")
	)
	(segment
		(start 104.40924 -227.939092)
		(end 104.448356 -227.961952)
		(width 0.1143)
		(layer "In4.Cu")
		(net "P5E_CPU1_G1_RX_DP<7>")
	)
	(segment
		(start 104.40924 -229.559104)
		(end 104.448356 -229.581964)
		(width 0.1143)
		(layer "In4.Cu")
		(net "P5E_CPU1_G1_RX_DP<7>")
	)
	(segment
		(start 51.188112 -50.941732)
		(end 53.864764 -54.214014)
		(width 0.14224)
		(layer "In4.Cu")
		(net "P5E_CPU1_G1_RX_DP<7>")
	)
	(segment
		(start 103.359712 -222.207836)
		(end 103.359712 -222.838264)
		(width 0.1143)
		(layer "In4.Cu")
		(net "P5E_CPU1_G1_RX_DP<7>")
	)
	(segment
		(start 104.01173 -231.017318)
		(end 103.978202 -231.036876)
		(width 0.1143)
		(layer "In4.Cu")
		(net "P5E_CPU1_G1_RX_DP<7>")
	)
	(segment
		(start 152.3873 -159.885888)
		(end 152.3873 -163.722812)
		(width 0.14224)
		(layer "In4.Cu")
		(net "P5E_CPU1_G1_RX_DP<7>")
	)
	(segment
		(start 104.448356 -229.581964)
		(end 104.480868 -229.60076)
		(width 0.1143)
		(layer "In4.Cu")
		(net "P5E_CPU1_G1_RX_DP<7>")
	)
	(segment
		(start 147.605242 -138.364722)
		(end 149.85111 -143.004032)
		(width 0.14224)
		(layer "In4.Cu")
		(net "P5E_CPU1_G1_RX_DP<7>")
	)
	(segment
		(start 53.864764 -54.214014)
		(end 54.429406 -54.83225)
		(width 0.14224)
		(layer "In4.Cu")
		(net "P5E_CPU1_G1_RX_DP<7>")
	)
	(segment
		(start 104.448356 -226.34194)
		(end 104.478836 -226.35972)
		(width 0.1143)
		(layer "In4.Cu")
		(net "P5E_CPU1_G1_RX_DP<7>")
	)
	(segment
		(start 103.538782 -223.729296)
		(end 103.469186 -223.769936)
		(width 0.1143)
		(layer "In4.Cu")
		(net "P5E_CPU1_G1_RX_DP<7>")
	)
	(segment
		(start 151.551132 -146.516344)
		(end 152.3873 -159.885888)
		(width 0.14224)
		(layer "In4.Cu")
		(net "P5E_CPU1_G1_RX_DP<7>")
	)
	(segment
		(start 57.239154 -57.184798)
		(end 58.126376 -57.982612)
		(width 0.14224)
		(layer "In4.Cu")
		(net "P5E_CPU1_G1_RX_DP<7>")
	)
	(segment
		(start 150.499064 -169.26814)
		(end 147.020534 -174.110904)
		(width 0.14224)
		(layer "In4.Cu")
		(net "P5E_CPU1_G1_RX_DP<7>")
	)
	(segment
		(start 103.359712 -222.838264)
		(end 103.435912 -223.02216)
		(width 0.1143)
		(layer "In4.Cu")
		(net "P5E_CPU1_G1_RX_DP<7>")
	)
	(segment
		(start 36.725606 -18.375122)
		(end 37.3253 -19.271742)
		(width 0.14224)
		(layer "In4.Cu")
		(net "P5E_CPU1_G1_RX_DP<7>")
	)
	(segment
		(start 152.3873 -163.722812)
		(end 150.499064 -169.26814)
		(width 0.14224)
		(layer "In4.Cu")
		(net "P5E_CPU1_G1_RX_DP<7>")
	)
	(segment
		(start 103.70185 -231.441498)
		(end 103.619046 -231.524302)
		(width 0.1143)
		(layer "In4.Cu")
		(net "P5E_CPU1_G1_RX_DP<7>")
	)
	(segment
		(start 40.950896 -26.808684)
		(end 51.188112 -50.941732)
		(width 0.14224)
		(layer "In4.Cu")
		(net "P5E_CPU1_G1_RX_DP<7>")
	)
	(segment
		(start 36.41979 -17.765014)
		(end 36.490402 -17.935702)
		(width 0.14224)
		(layer "In4.Cu")
		(net "P5E_CPU1_G1_RX_DP<7>")
	)
	(segment
		(start 104.478836 -228.589332)
		(end 104.448356 -228.607112)
		(width 0.1143)
		(layer "In4.Cu")
		(net "P5E_CPU1_G1_RX_DP<7>")
	)
	(segment
		(start 58.126376 -57.982612)
		(end 59.416442 -59.06262)
		(width 0.14224)
		(layer "In4.Cu")
		(net "P5E_CPU1_G1_RX_DP<7>")
	)
	(segment
		(start 103.61549 -214.376254)
		(end 103.61549 -221.304358)
		(width 0.14224)
		(layer "In4.Cu")
		(net "P5E_CPU1_G1_RX_DP<7>")
	)
	(segment
		(start 104.478836 -230.20909)
		(end 104.41178 -230.248206)
		(width 0.1143)
		(layer "In4.Cu")
		(net "P5E_CPU1_G1_RX_DP<7>")
	)
	(segment
		(start 103.61549 -221.332806)
		(end 103.66121 -221.378526)
		(width 0.1143)
		(layer "In4.Cu")
		(net "P5E_CPU1_G1_RX_DP<7>")
	)
	(segment
		(start 104.40924 -226.31908)
		(end 104.448356 -226.34194)
		(width 0.1143)
		(layer "In4.Cu")
		(net "P5E_CPU1_G1_RX_DP<7>")
	)
	(arc
		(start 104.41178 -230.248206)
		(mid 104.231128 -230.450951)
		(end 104.165908 -230.71455)
		(width 0.1143)
		(layer "In4.Cu")
		(net "P5E_CPU1_G1_RX_DP<7>")
	)
	(arc
		(start 103.538782 -224.739708)
		(mid 103.654209 -224.873084)
		(end 103.695754 -225.044508)
		(width 0.1143)
		(layer "In4.Cu")
		(net "P5E_CPU1_G1_RX_DP<7>")
	)
	(arc
		(start 103.695754 -225.044508)
		(mid 103.760269 -225.306727)
		(end 103.939086 -225.509074)
		(width 0.1143)
		(layer "In4.Cu")
		(net "P5E_CPU1_G1_RX_DP<7>")
	)
	(arc
		(start 103.469186 -223.769936)
		(mid 103.225859 -224.234502)
		(end 103.469186 -224.699068)
		(width 0.1143)
		(layer "In4.Cu")
		(net "P5E_CPU1_G1_RX_DP<7>")
	)
	(arc
		(start 104.009952 -225.550222)
		(mid 104.124628 -225.683556)
		(end 104.165908 -225.854514)
		(width 0.1143)
		(layer "In4.Cu")
		(net "P5E_CPU1_G1_RX_DP<7>")
	)
	(arc
		(start 104.635808 -229.90429)
		(mid 104.594259 -230.075712)
		(end 104.478836 -230.20909)
		(width 0.1143)
		(layer "In4.Cu")
		(net "P5E_CPU1_G1_RX_DP<7>")
	)
	(arc
		(start 104.478836 -227.979732)
		(mid 104.635813 -228.284532)
		(end 104.478836 -228.589332)
		(width 0.1143)
		(layer "In4.Cu")
		(net "P5E_CPU1_G1_RX_DP<7>")
	)
	(arc
		(start 103.939086 -231.059736)
		(mid 103.787099 -231.216244)
		(end 103.70566 -231.418638)
		(width 0.1143)
		(layer "In4.Cu")
		(net "P5E_CPU1_G1_RX_DP<7>")
	)
	(arc
		(start 103.534718 -223.116648)
		(mid 103.675126 -223.30212)
		(end 103.67899 -223.534732)
		(width 0.1143)
		(layer "In4.Cu")
		(net "P5E_CPU1_G1_RX_DP<7>")
	)
	(arc
		(start 104.40924 -227.00996)
		(mid 104.165913 -227.474526)
		(end 104.40924 -227.939092)
		(width 0.1143)
		(layer "In4.Cu")
		(net "P5E_CPU1_G1_RX_DP<7>")
	)
	(arc
		(start 103.67899 -223.534732)
		(mid 103.624909 -223.643567)
		(end 103.538782 -223.729296)
		(width 0.1143)
		(layer "In4.Cu")
		(net "P5E_CPU1_G1_RX_DP<7>")
	)
	(arc
		(start 104.165908 -225.854514)
		(mid 104.230423 -226.116733)
		(end 104.40924 -226.31908)
		(width 0.1143)
		(layer "In4.Cu")
		(net "P5E_CPU1_G1_RX_DP<7>")
	)
	(arc
		(start 104.480868 -229.60076)
		(mid 104.594797 -229.733907)
		(end 104.635808 -229.90429)
		(width 0.1143)
		(layer "In4.Cu")
		(net "P5E_CPU1_G1_RX_DP<7>")
	)
	(arc
		(start 103.70566 -231.418638)
		(mid 103.703637 -231.430048)
		(end 103.70185 -231.441498)
		(width 0.1143)
		(layer "In4.Cu")
		(net "P5E_CPU1_G1_RX_DP<7>")
	)
	(arc
		(start 104.165908 -230.71455)
		(mid 104.125146 -230.884434)
		(end 104.01173 -231.017318)
		(width 0.1143)
		(layer "In4.Cu")
		(net "P5E_CPU1_G1_RX_DP<7>")
	)
	(arc
		(start 104.478836 -226.35972)
		(mid 104.635813 -226.66452)
		(end 104.478836 -226.96932)
		(width 0.1143)
		(layer "In4.Cu")
		(net "P5E_CPU1_G1_RX_DP<7>")
	)
	(arc
		(start 104.40924 -228.629972)
		(mid 104.165913 -229.094538)
		(end 104.40924 -229.559104)
		(width 0.1143)
		(layer "In4.Cu")
		(net "P5E_CPU1_G1_RX_DP<7>")
	)
	(segment
		(start 31.746952 -7.709154)
		(end 31.746952 -8.320024)
		(width 0.12954)
		(layer "F.Cu")
		(net "P5E_CPU1_G1_RX_DP<8>")
	)
	(segment
		(start 31.62046 -4.963414)
		(end 31.886652 -5.229606)
		(width 0.12954)
		(layer "F.Cu")
		(net "P5E_CPU1_G1_RX_DP<8>")
	)
	(segment
		(start 31.886652 -5.229606)
		(end 31.886652 -7.569454)
		(width 0.12954)
		(layer "F.Cu")
		(net "P5E_CPU1_G1_RX_DP<8>")
	)
	(segment
		(start 103.787956 -233.410252)
		(end 103.321104 -233.144314)
		(width 0.12954)
		(layer "F.Cu")
		(net "P5E_CPU1_G1_RX_DP<8>")
	)
	(segment
		(start 31.886652 -7.569454)
		(end 31.746952 -7.709154)
		(width 0.12954)
		(layer "F.Cu")
		(net "P5E_CPU1_G1_RX_DP<8>")
	)
	(segment
		(start 103.51008 -226.98583)
		(end 103.50881 -226.986592)
		(width 0.1143)
		(layer "In4.Cu")
		(net "P5E_CPU1_G1_RX_DP<8>")
	)
	(segment
		(start 33.644332 -18.966942)
		(end 33.62579 -19.06016)
		(width 0.14224)
		(layer "In4.Cu")
		(net "P5E_CPU1_G1_RX_DP<8>")
	)
	(segment
		(start 102.7557 -225.044508)
		(end 102.755954 -225.044508)
		(width 0.1143)
		(layer "In4.Cu")
		(net "P5E_CPU1_G1_RX_DP<8>")
	)
	(segment
		(start 101.8159 -221.334076)
		(end 101.8159 -221.804484)
		(width 0.1143)
		(layer "In4.Cu")
		(net "P5E_CPU1_G1_RX_DP<8>")
	)
	(segment
		(start 102.598728 -223.729296)
		(end 102.568248 -223.747076)
		(width 0.1143)
		(layer "In4.Cu")
		(net "P5E_CPU1_G1_RX_DP<8>")
	)
	(segment
		(start 33.682686 -19.426428)
		(end 33.683956 -19.429222)
		(width 0.14224)
		(layer "In4.Cu")
		(net "P5E_CPU1_G1_RX_DP<8>")
	)
	(segment
		(start 102.089712 -222.287084)
		(end 102.091998 -222.288354)
		(width 0.1143)
		(layer "In4.Cu")
		(net "P5E_CPU1_G1_RX_DP<8>")
	)
	(segment
		(start 103.471726 -227.94087)
		(end 103.508048 -227.961952)
		(width 0.1143)
		(layer "In4.Cu")
		(net "P5E_CPU1_G1_RX_DP<8>")
	)
	(segment
		(start 103.038148 -225.531934)
		(end 103.039672 -225.53295)
		(width 0.1143)
		(layer "In4.Cu")
		(net "P5E_CPU1_G1_RX_DP<8>")
	)
	(segment
		(start 146.845528 -138.935714)
		(end 150.601934 -146.695668)
		(width 0.14224)
		(layer "In4.Cu")
		(net "P5E_CPU1_G1_RX_DP<8>")
	)
	(segment
		(start 51.718464 -53.063648)
		(end 53.154834 -54.820058)
		(width 0.14224)
		(layer "In4.Cu")
		(net "P5E_CPU1_G1_RX_DP<8>")
	)
	(segment
		(start 103.539798 -228.588824)
		(end 103.51008 -228.605842)
		(width 0.1143)
		(layer "In4.Cu")
		(net "P5E_CPU1_G1_RX_DP<8>")
	)
	(segment
		(start 53.154834 -54.820058)
		(end 53.772054 -55.49519)
		(width 0.14224)
		(layer "In4.Cu")
		(net "P5E_CPU1_G1_RX_DP<8>")
	)
	(segment
		(start 103.619046 -233.144314)
		(end 103.321104 -233.144314)
		(width 0.1143)
		(layer "In4.Cu")
		(net "P5E_CPU1_G1_RX_DP<8>")
	)
	(segment
		(start 58.805318 -59.766962)
		(end 146.845528 -138.935714)
		(width 0.14224)
		(layer "In4.Cu")
		(net "P5E_CPU1_G1_RX_DP<8>")
	)
	(segment
		(start 102.568248 -223.747076)
		(end 102.529132 -223.769936)
		(width 0.1143)
		(layer "In4.Cu")
		(net "P5E_CPU1_G1_RX_DP<8>")
	)
	(segment
		(start 33.654238 -18.91665)
		(end 33.644332 -18.965926)
		(width 0.14224)
		(layer "In4.Cu")
		(net "P5E_CPU1_G1_RX_DP<8>")
	)
	(segment
		(start 103.505254 -226.340162)
		(end 103.508048 -226.34194)
		(width 0.1143)
		(layer "In4.Cu")
		(net "P5E_CPU1_G1_RX_DP<8>")
	)
	(segment
		(start 108.32592 -204.615288)
		(end 101.77018 -215.657684)
		(width 0.14224)
		(layer "In4.Cu")
		(net "P5E_CPU1_G1_RX_DP<8>")
	)
	(segment
		(start 34.343594 -17.708626)
		(end 34.299652 -17.815052)
		(width 0.14224)
		(layer "In4.Cu")
		(net "P5E_CPU1_G1_RX_DP<8>")
	)
	(segment
		(start 103.225854 -225.854514)
		(end 103.225854 -225.861626)
		(width 0.1143)
		(layer "In4.Cu")
		(net "P5E_CPU1_G1_RX_DP<8>")
	)
	(segment
		(start 49.274984 -50.075592)
		(end 51.718464 -53.063648)
		(width 0.14224)
		(layer "In4.Cu")
		(net "P5E_CPU1_G1_RX_DP<8>")
	)
	(segment
		(start 34.077656 -18.229834)
		(end 33.712658 -18.77568)
		(width 0.14224)
		(layer "In4.Cu")
		(net "P5E_CPU1_G1_RX_DP<8>")
	)
	(segment
		(start 33.712658 -18.77568)
		(end 33.654238 -18.91665)
		(width 0.14224)
		(layer "In4.Cu")
		(net "P5E_CPU1_G1_RX_DP<8>")
	)
	(segment
		(start 102.091998 -222.288354)
		(end 102.093014 -222.288862)
		(width 0.1143)
		(layer "In4.Cu")
		(net "P5E_CPU1_G1_RX_DP<8>")
	)
	(segment
		(start 103.507286 -232.821226)
		(end 103.50881 -232.822242)
		(width 0.1143)
		(layer "In4.Cu")
		(net "P5E_CPU1_G1_RX_DP<8>")
	)
	(segment
		(start 103.508048 -226.9871)
		(end 103.471726 -227.008182)
		(width 0.1143)
		(layer "In4.Cu")
		(net "P5E_CPU1_G1_RX_DP<8>")
	)
	(segment
		(start 34.299652 -17.815052)
		(end 34.077656 -18.229834)
		(width 0.14224)
		(layer "In4.Cu")
		(net "P5E_CPU1_G1_RX_DP<8>")
	)
	(segment
		(start 149.80539 -168.364154)
		(end 149.664674 -168.81856)
		(width 0.14224)
		(layer "In4.Cu")
		(net "P5E_CPU1_G1_RX_DP<8>")
	)
	(segment
		(start 54.408324 -56.066944)
		(end 56.631332 -57.891934)
		(width 0.14224)
		(layer "In4.Cu")
		(net "P5E_CPU1_G1_RX_DP<8>")
	)
	(segment
		(start 103.043736 -225.535236)
		(end 103.067612 -225.548952)
		(width 0.1143)
		(layer "In4.Cu")
		(net "P5E_CPU1_G1_RX_DP<8>")
	)
	(segment
		(start 150.601934 -146.695668)
		(end 150.623524 -146.740372)
		(width 0.14224)
		(layer "In4.Cu")
		(net "P5E_CPU1_G1_RX_DP<8>")
	)
	(segment
		(start 33.683956 -19.429222)
		(end 33.68421 -19.430238)
		(width 0.14224)
		(layer "In4.Cu")
		(net "P5E_CPU1_G1_RX_DP<8>")
	)
	(segment
		(start 33.644332 -18.965926)
		(end 33.644332 -18.966942)
		(width 0.14224)
		(layer "In4.Cu")
		(net "P5E_CPU1_G1_RX_DP<8>")
	)
	(segment
		(start 149.664674 -168.81856)
		(end 146.312128 -173.485556)
		(width 0.14224)
		(layer "In4.Cu")
		(net "P5E_CPU1_G1_RX_DP<8>")
	)
	(segment
		(start 103.688896 -233.074464)
		(end 103.619046 -233.144314)
		(width 0.1143)
		(layer "In4.Cu")
		(net "P5E_CPU1_G1_RX_DP<8>")
	)
	(segment
		(start 31.62046 -4.963414)
		(end 31.91129 -5.254244)
		(width 0.14224)
		(layer "In4.Cu")
		(net "P5E_CPU1_G1_RX_DP<8>")
	)
	(segment
		(start 101.77018 -215.657684)
		(end 101.77018 -221.259908)
		(width 0.14224)
		(layer "In4.Cu")
		(net "P5E_CPU1_G1_RX_DP<8>")
	)
	(segment
		(start 102.097078 -222.291402)
		(end 102.098094 -222.29191)
		(width 0.1143)
		(layer "In4.Cu")
		(net "P5E_CPU1_G1_RX_DP<8>")
	)
	(segment
		(start 103.042466 -225.534474)
		(end 103.043736 -225.535236)
		(width 0.1143)
		(layer "In4.Cu")
		(net "P5E_CPU1_G1_RX_DP<8>")
	)
	(segment
		(start 102.095554 -222.290386)
		(end 102.097078 -222.291402)
		(width 0.1143)
		(layer "In4.Cu")
		(net "P5E_CPU1_G1_RX_DP<8>")
	)
	(segment
		(start 56.631332 -57.891934)
		(end 57.515252 -58.686954)
		(width 0.14224)
		(layer "In4.Cu")
		(net "P5E_CPU1_G1_RX_DP<8>")
	)
	(segment
		(start 103.539544 -229.599998)
		(end 103.539798 -229.600252)
		(width 0.1143)
		(layer "In4.Cu")
		(net "P5E_CPU1_G1_RX_DP<8>")
	)
	(segment
		(start 103.51008 -228.605842)
		(end 103.50881 -228.606604)
		(width 0.1143)
		(layer "In4.Cu")
		(net "P5E_CPU1_G1_RX_DP<8>")
	)
	(segment
		(start 103.508048 -227.961952)
		(end 103.50881 -227.96246)
		(width 0.1143)
		(layer "In4.Cu")
		(net "P5E_CPU1_G1_RX_DP<8>")
	)
	(segment
		(start 103.508048 -228.607112)
		(end 103.471726 -228.628194)
		(width 0.1143)
		(layer "In4.Cu")
		(net "P5E_CPU1_G1_RX_DP<8>")
	)
	(segment
		(start 103.50881 -228.606604)
		(end 103.508048 -228.607112)
		(width 0.1143)
		(layer "In4.Cu")
		(net "P5E_CPU1_G1_RX_DP<8>")
	)
	(segment
		(start 32.237426 -12.648438)
		(end 32.968184 -14.193012)
		(width 0.14224)
		(layer "In4.Cu")
		(net "P5E_CPU1_G1_RX_DP<8>")
	)
	(segment
		(start 150.623524 -146.740372)
		(end 151.448008 -159.915606)
		(width 0.14224)
		(layer "In4.Cu")
		(net "P5E_CPU1_G1_RX_DP<8>")
	)
	(segment
		(start 103.471726 -229.560882)
		(end 103.539544 -229.599998)
		(width 0.1143)
		(layer "In4.Cu")
		(net "P5E_CPU1_G1_RX_DP<8>")
	)
	(segment
		(start 101.77018 -221.259908)
		(end 101.77018 -221.288356)
		(width 0.1143)
		(layer "In4.Cu")
		(net "P5E_CPU1_G1_RX_DP<8>")
	)
	(segment
		(start 102.999794 -231.989376)
		(end 103.038656 -232.011982)
		(width 0.1143)
		(layer "In4.Cu")
		(net "P5E_CPU1_G1_RX_DP<8>")
	)
	(segment
		(start 103.539798 -226.968812)
		(end 103.51008 -226.98583)
		(width 0.1143)
		(layer "In4.Cu")
		(net "P5E_CPU1_G1_RX_DP<8>")
	)
	(segment
		(start 31.91129 -5.254244)
		(end 31.91129 -11.572748)
		(width 0.14224)
		(layer "In4.Cu")
		(net "P5E_CPU1_G1_RX_DP<8>")
	)
	(segment
		(start 33.68421 -19.430238)
		(end 33.692084 -19.448272)
		(width 0.14224)
		(layer "In4.Cu")
		(net "P5E_CPU1_G1_RX_DP<8>")
	)
	(segment
		(start 102.568248 -223.101916)
		(end 102.598728 -223.119696)
		(width 0.1143)
		(layer "In4.Cu")
		(net "P5E_CPU1_G1_RX_DP<8>")
	)
	(segment
		(start 103.039672 -225.53295)
		(end 103.041704 -225.533966)
		(width 0.1143)
		(layer "In4.Cu")
		(net "P5E_CPU1_G1_RX_DP<8>")
	)
	(segment
		(start 37.822124 -26.82367)
		(end 49.274984 -50.075592)
		(width 0.14224)
		(layer "In4.Cu")
		(net "P5E_CPU1_G1_RX_DP<8>")
	)
	(segment
		(start 57.515252 -58.686954)
		(end 58.805318 -59.766962)
		(width 0.14224)
		(layer "In4.Cu")
		(net "P5E_CPU1_G1_RX_DP<8>")
	)
	(segment
		(start 146.312128 -173.485556)
		(end 108.32592 -204.615288)
		(width 0.14224)
		(layer "In4.Cu")
		(net "P5E_CPU1_G1_RX_DP<8>")
	)
	(segment
		(start 33.692084 -19.448272)
		(end 37.822124 -26.82367)
		(width 0.14224)
		(layer "In4.Cu")
		(net "P5E_CPU1_G1_RX_DP<8>")
	)
	(segment
		(start 103.041704 -225.533966)
		(end 103.042466 -225.534474)
		(width 0.1143)
		(layer "In4.Cu")
		(net "P5E_CPU1_G1_RX_DP<8>")
	)
	(segment
		(start 102.058978 -222.26905)
		(end 102.089712 -222.287084)
		(width 0.1143)
		(layer "In4.Cu")
		(net "P5E_CPU1_G1_RX_DP<8>")
	)
	(segment
		(start 33.679384 -19.418808)
		(end 33.682686 -19.426428)
		(width 0.14224)
		(layer "In4.Cu")
		(net "P5E_CPU1_G1_RX_DP<8>")
	)
	(segment
		(start 102.529132 -224.699068)
		(end 102.568248 -224.721928)
		(width 0.1143)
		(layer "In4.Cu")
		(net "P5E_CPU1_G1_RX_DP<8>")
	)
	(segment
		(start 34.343594 -17.517364)
		(end 34.343594 -17.708626)
		(width 0.14224)
		(layer "In4.Cu")
		(net "P5E_CPU1_G1_RX_DP<8>")
	)
	(segment
		(start 103.509572 -230.229156)
		(end 103.505 -230.23195)
		(width 0.1143)
		(layer "In4.Cu")
		(net "P5E_CPU1_G1_RX_DP<8>")
	)
	(segment
		(start 103.50881 -227.96246)
		(end 103.539798 -227.98024)
		(width 0.1143)
		(layer "In4.Cu")
		(net "P5E_CPU1_G1_RX_DP<8>")
	)
	(segment
		(start 32.968184 -14.193012)
		(end 34.343594 -17.517364)
		(width 0.14224)
		(layer "In4.Cu")
		(net "P5E_CPU1_G1_RX_DP<8>")
	)
	(segment
		(start 151.448008 -159.915606)
		(end 151.448008 -163.501324)
		(width 0.14224)
		(layer "In4.Cu")
		(net "P5E_CPU1_G1_RX_DP<8>")
	)
	(segment
		(start 102.529132 -223.079056)
		(end 102.568248 -223.101916)
		(width 0.1143)
		(layer "In4.Cu")
		(net "P5E_CPU1_G1_RX_DP<8>")
	)
	(segment
		(start 103.220266 -232.327196)
		(end 103.220266 -232.329736)
		(width 0.1143)
		(layer "In4.Cu")
		(net "P5E_CPU1_G1_RX_DP<8>")
	)
	(segment
		(start 33.62579 -19.06016)
		(end 33.62579 -19.274536)
		(width 0.14224)
		(layer "In4.Cu")
		(net "P5E_CPU1_G1_RX_DP<8>")
	)
	(segment
		(start 33.675574 -19.40814)
		(end 33.679384 -19.418808)
		(width 0.14224)
		(layer "In4.Cu")
		(net "P5E_CPU1_G1_RX_DP<8>")
	)
	(segment
		(start 103.50881 -226.986592)
		(end 103.508048 -226.9871)
		(width 0.1143)
		(layer "In4.Cu")
		(net "P5E_CPU1_G1_RX_DP<8>")
	)
	(segment
		(start 33.62579 -19.274536)
		(end 33.675574 -19.40814)
		(width 0.14224)
		(layer "In4.Cu")
		(net "P5E_CPU1_G1_RX_DP<8>")
	)
	(segment
		(start 103.469186 -226.319334)
		(end 103.505254 -226.340162)
		(width 0.1143)
		(layer "In4.Cu")
		(net "P5E_CPU1_G1_RX_DP<8>")
	)
	(segment
		(start 103.508048 -226.34194)
		(end 103.50881 -226.342448)
		(width 0.1143)
		(layer "In4.Cu")
		(net "P5E_CPU1_G1_RX_DP<8>")
	)
	(segment
		(start 103.50881 -226.342448)
		(end 103.539798 -226.360228)
		(width 0.1143)
		(layer "In4.Cu")
		(net "P5E_CPU1_G1_RX_DP<8>")
	)
	(segment
		(start 31.91129 -11.572748)
		(end 32.237426 -12.648438)
		(width 0.14224)
		(layer "In4.Cu")
		(net "P5E_CPU1_G1_RX_DP<8>")
	)
	(segment
		(start 102.094538 -222.289878)
		(end 102.095554 -222.290386)
		(width 0.1143)
		(layer "In4.Cu")
		(net "P5E_CPU1_G1_RX_DP<8>")
	)
	(segment
		(start 53.772054 -55.49519)
		(end 54.408324 -56.066944)
		(width 0.14224)
		(layer "In4.Cu")
		(net "P5E_CPU1_G1_RX_DP<8>")
	)
	(segment
		(start 101.77018 -221.288356)
		(end 101.8159 -221.334076)
		(width 0.1143)
		(layer "In4.Cu")
		(net "P5E_CPU1_G1_RX_DP<8>")
	)
	(segment
		(start 103.03764 -225.531426)
		(end 103.038148 -225.531934)
		(width 0.1143)
		(layer "In4.Cu")
		(net "P5E_CPU1_G1_RX_DP<8>")
	)
	(segment
		(start 102.098094 -222.29191)
		(end 102.129844 -222.310198)
		(width 0.1143)
		(layer "In4.Cu")
		(net "P5E_CPU1_G1_RX_DP<8>")
	)
	(segment
		(start 103.067866 -231.019858)
		(end 102.999032 -231.059736)
		(width 0.1143)
		(layer "In4.Cu")
		(net "P5E_CPU1_G1_RX_DP<8>")
	)
	(segment
		(start 102.568248 -224.721928)
		(end 102.598728 -224.739708)
		(width 0.1143)
		(layer "In4.Cu")
		(net "P5E_CPU1_G1_RX_DP<8>")
	)
	(segment
		(start 151.448008 -163.501324)
		(end 149.80539 -168.364154)
		(width 0.14224)
		(layer "In4.Cu")
		(net "P5E_CPU1_G1_RX_DP<8>")
	)
	(segment
		(start 103.504746 -232.819956)
		(end 103.507286 -232.821226)
		(width 0.1143)
		(layer "In4.Cu")
		(net "P5E_CPU1_G1_RX_DP<8>")
	)
	(segment
		(start 103.458772 -226.31146)
		(end 103.469186 -226.319334)
		(width 0.1143)
		(layer "In4.Cu")
		(net "P5E_CPU1_G1_RX_DP<8>")
	)
	(segment
		(start 102.093014 -222.288862)
		(end 102.094538 -222.289878)
		(width 0.1143)
		(layer "In4.Cu")
		(net "P5E_CPU1_G1_RX_DP<8>")
	)
	(segment
		(start 103.50881 -232.822242)
		(end 103.539798 -232.840022)
		(width 0.1143)
		(layer "In4.Cu")
		(net "P5E_CPU1_G1_RX_DP<8>")
	)
	(arc
		(start 103.225854 -230.71455)
		(mid 103.183975 -230.886419)
		(end 103.067866 -231.019858)
		(width 0.1143)
		(layer "In4.Cu")
		(net "P5E_CPU1_G1_RX_DP<8>")
	)
	(arc
		(start 103.539798 -226.360228)
		(mid 103.695726 -226.66452)
		(end 103.539798 -226.968812)
		(width 0.1143)
		(layer "In4.Cu")
		(net "P5E_CPU1_G1_RX_DP<8>")
	)
	(arc
		(start 103.457502 -227.018088)
		(mid 103.230119 -227.474526)
		(end 103.457502 -227.930964)
		(width 0.1143)
		(layer "In4.Cu")
		(net "P5E_CPU1_G1_RX_DP<8>")
	)
	(arc
		(start 103.067612 -225.548952)
		(mid 103.183885 -225.682492)
		(end 103.225854 -225.854514)
		(width 0.1143)
		(layer "In4.Cu")
		(net "P5E_CPU1_G1_RX_DP<8>")
	)
	(arc
		(start 103.471726 -227.008182)
		(mid 103.464576 -227.01308)
		(end 103.457502 -227.018088)
		(width 0.1143)
		(layer "In4.Cu")
		(net "P5E_CPU1_G1_RX_DP<8>")
	)
	(arc
		(start 101.92512 -222.139002)
		(mid 101.986639 -222.209596)
		(end 102.058978 -222.26905)
		(width 0.1143)
		(layer "In4.Cu")
		(net "P5E_CPU1_G1_RX_DP<8>")
	)
	(arc
		(start 102.755954 -225.044508)
		(mid 102.831456 -225.32576)
		(end 103.03764 -225.531426)
		(width 0.1143)
		(layer "In4.Cu")
		(net "P5E_CPU1_G1_RX_DP<8>")
	)
	(arc
		(start 102.999032 -231.059736)
		(mid 102.755705 -231.524302)
		(end 102.999032 -231.988868)
		(width 0.1143)
		(layer "In4.Cu")
		(net "P5E_CPU1_G1_RX_DP<8>")
	)
	(arc
		(start 102.129844 -222.310198)
		(mid 102.24452 -222.443532)
		(end 102.2858 -222.61449)
		(width 0.1143)
		(layer "In4.Cu")
		(net "P5E_CPU1_G1_RX_DP<8>")
	)
	(arc
		(start 102.2858 -222.61449)
		(mid 102.350315 -222.876709)
		(end 102.529132 -223.079056)
		(width 0.1143)
		(layer "In4.Cu")
		(net "P5E_CPU1_G1_RX_DP<8>")
	)
	(arc
		(start 102.598728 -223.119696)
		(mid 102.755705 -223.424496)
		(end 102.598728 -223.729296)
		(width 0.1143)
		(layer "In4.Cu")
		(net "P5E_CPU1_G1_RX_DP<8>")
	)
	(arc
		(start 103.505 -230.23195)
		(mid 103.300676 -230.435795)
		(end 103.225854 -230.71455)
		(width 0.1143)
		(layer "In4.Cu")
		(net "P5E_CPU1_G1_RX_DP<8>")
	)
	(arc
		(start 103.471726 -228.628194)
		(mid 103.463548 -228.633837)
		(end 103.45547 -228.639624)
		(width 0.1143)
		(layer "In4.Cu")
		(net "P5E_CPU1_G1_RX_DP<8>")
	)
	(arc
		(start 103.539798 -227.98024)
		(mid 103.695726 -228.284532)
		(end 103.539798 -228.588824)
		(width 0.1143)
		(layer "In4.Cu")
		(net "P5E_CPU1_G1_RX_DP<8>")
	)
	(arc
		(start 102.529132 -223.769936)
		(mid 102.285805 -224.234502)
		(end 102.529132 -224.699068)
		(width 0.1143)
		(layer "In4.Cu")
		(net "P5E_CPU1_G1_RX_DP<8>")
	)
	(arc
		(start 102.598728 -224.739708)
		(mid 102.714155 -224.873084)
		(end 102.7557 -225.044508)
		(width 0.1143)
		(layer "In4.Cu")
		(net "P5E_CPU1_G1_RX_DP<8>")
	)
	(arc
		(start 102.999032 -231.988868)
		(mid 102.999413 -231.989122)
		(end 102.999794 -231.989376)
		(width 0.1143)
		(layer "In4.Cu")
		(net "P5E_CPU1_G1_RX_DP<8>")
	)
	(arc
		(start 103.539798 -232.840022)
		(mid 103.636933 -232.942891)
		(end 103.688896 -233.074464)
		(width 0.1143)
		(layer "In4.Cu")
		(net "P5E_CPU1_G1_RX_DP<8>")
	)
	(arc
		(start 103.696008 -229.90429)
		(mid 103.64608 -230.09156)
		(end 103.509572 -230.229156)
		(width 0.1143)
		(layer "In4.Cu")
		(net "P5E_CPU1_G1_RX_DP<8>")
	)
	(arc
		(start 103.038656 -232.011982)
		(mid 103.171576 -232.145329)
		(end 103.220266 -232.327196)
		(width 0.1143)
		(layer "In4.Cu")
		(net "P5E_CPU1_G1_RX_DP<8>")
	)
	(arc
		(start 103.220266 -232.329736)
		(mid 103.296482 -232.613157)
		(end 103.504746 -232.819956)
		(width 0.1143)
		(layer "In4.Cu")
		(net "P5E_CPU1_G1_RX_DP<8>")
	)
	(arc
		(start 103.457502 -227.930964)
		(mid 103.464575 -227.935973)
		(end 103.471726 -227.94087)
		(width 0.1143)
		(layer "In4.Cu")
		(net "P5E_CPU1_G1_RX_DP<8>")
	)
	(arc
		(start 101.8159 -221.804484)
		(mid 101.843816 -221.98046)
		(end 101.92512 -222.139002)
		(width 0.1143)
		(layer "In4.Cu")
		(net "P5E_CPU1_G1_RX_DP<8>")
	)
	(arc
		(start 103.45547 -228.639624)
		(mid 103.290803 -228.838231)
		(end 103.225854 -229.087934)
		(width 0.1143)
		(layer "In4.Cu")
		(net "P5E_CPU1_G1_RX_DP<8>")
	)
	(arc
		(start 103.225854 -229.087934)
		(mid 103.225844 -229.091236)
		(end 103.225854 -229.094538)
		(width 0.1143)
		(layer "In4.Cu")
		(net "P5E_CPU1_G1_RX_DP<8>")
	)
	(arc
		(start 103.225854 -225.861626)
		(mid 103.292056 -226.112559)
		(end 103.458772 -226.31146)
		(width 0.1143)
		(layer "In4.Cu")
		(net "P5E_CPU1_G1_RX_DP<8>")
	)
	(arc
		(start 103.225854 -229.094538)
		(mid 103.29109 -229.358129)
		(end 103.471726 -229.560882)
		(width 0.1143)
		(layer "In4.Cu")
		(net "P5E_CPU1_G1_RX_DP<8>")
	)
	(arc
		(start 103.539798 -229.600252)
		(mid 103.654641 -229.7334)
		(end 103.696008 -229.90429)
		(width 0.1143)
		(layer "In4.Cu")
		(net "P5E_CPU1_G1_RX_DP<8>")
	)
	(segment
		(start 29.947108 -8.320024)
		(end 29.947108 -7.709154)
		(width 0.12954)
		(layer "F.Cu")
		(net "P5E_CPU1_G1_RX_DP<9>")
	)
	(segment
		(start 30.085792 -6.99516)
		(end 29.81579 -6.725158)
		(width 0.12954)
		(layer "F.Cu")
		(net "P5E_CPU1_G1_RX_DP<9>")
	)
	(segment
		(start 100.967794 -236.650276)
		(end 100.500942 -236.384338)
		(width 0.12954)
		(layer "F.Cu")
		(net "P5E_CPU1_G1_RX_DP<9>")
	)
	(segment
		(start 30.085792 -7.57047)
		(end 30.085792 -6.99516)
		(width 0.12954)
		(layer "F.Cu")
		(net "P5E_CPU1_G1_RX_DP<9>")
	)
	(segment
		(start 29.947108 -7.709154)
		(end 30.085792 -7.57047)
		(width 0.12954)
		(layer "F.Cu")
		(net "P5E_CPU1_G1_RX_DP<9>")
	)
	(segment
		(start 101.153722 -235.899452)
		(end 101.152452 -235.900214)
		(width 0.1143)
		(layer "In4.Cu")
		(net "P5E_CPU1_G1_RX_DP<9>")
	)
	(segment
		(start 102.55504 -226.334574)
		(end 102.555802 -226.335082)
		(width 0.1143)
		(layer "In4.Cu")
		(net "P5E_CPU1_G1_RX_DP<9>")
	)
	(segment
		(start 102.599744 -228.588824)
		(end 102.568756 -228.606604)
		(width 0.1143)
		(layer "In4.Cu")
		(net "P5E_CPU1_G1_RX_DP<9>")
	)
	(segment
		(start 102.101396 -234.274868)
		(end 102.098856 -234.276392)
		(width 0.1143)
		(layer "In4.Cu")
		(net "P5E_CPU1_G1_RX_DP<9>")
	)
	(segment
		(start 102.559358 -226.33686)
		(end 102.56012 -226.337368)
		(width 0.1143)
		(layer "In4.Cu")
		(net "P5E_CPU1_G1_RX_DP<9>")
	)
	(segment
		(start 148.907246 -168.03116)
		(end 145.486628 -172.954442)
		(width 0.14224)
		(layer "In4.Cu")
		(net "P5E_CPU1_G1_RX_DP<9>")
	)
	(segment
		(start 102.5271 -232.798112)
		(end 102.56774 -232.82148)
		(width 0.1143)
		(layer "In4.Cu")
		(net "P5E_CPU1_G1_RX_DP<9>")
	)
	(segment
		(start 100.799138 -215.43899)
		(end 100.799138 -221.259908)
		(width 0.14224)
		(layer "In4.Cu")
		(net "P5E_CPU1_G1_RX_DP<9>")
	)
	(segment
		(start 56.02351 -58.599324)
		(end 56.904128 -59.391296)
		(width 0.14224)
		(layer "In4.Cu")
		(net "P5E_CPU1_G1_RX_DP<9>")
	)
	(segment
		(start 101.658674 -235.069126)
		(end 101.628194 -235.086906)
		(width 0.1143)
		(layer "In4.Cu")
		(net "P5E_CPU1_G1_RX_DP<9>")
	)
	(segment
		(start 58.194194 -60.471304)
		(end 146.085814 -139.506706)
		(width 0.14224)
		(layer "In4.Cu")
		(net "P5E_CPU1_G1_RX_DP<9>")
	)
	(segment
		(start 101.628194 -223.101916)
		(end 101.658674 -223.119696)
		(width 0.1143)
		(layer "In4.Cu")
		(net "P5E_CPU1_G1_RX_DP<9>")
	)
	(segment
		(start 102.097078 -232.01122)
		(end 102.098094 -232.011728)
		(width 0.1143)
		(layer "In4.Cu")
		(net "P5E_CPU1_G1_RX_DP<9>")
	)
	(segment
		(start 100.799138 -221.288356)
		(end 100.844858 -221.334076)
		(width 0.1143)
		(layer "In4.Cu")
		(net "P5E_CPU1_G1_RX_DP<9>")
	)
	(segment
		(start 101.157024 -235.89742)
		(end 101.1555 -235.898436)
		(width 0.1143)
		(layer "In4.Cu")
		(net "P5E_CPU1_G1_RX_DP<9>")
	)
	(segment
		(start 53.800248 -56.774334)
		(end 56.02351 -58.599324)
		(width 0.14224)
		(layer "In4.Cu")
		(net "P5E_CPU1_G1_RX_DP<9>")
	)
	(segment
		(start 52.444904 -55.425594)
		(end 53.114702 -56.15813)
		(width 0.14224)
		(layer "In4.Cu")
		(net "P5E_CPU1_G1_RX_DP<9>")
	)
	(segment
		(start 102.2858 -230.546656)
		(end 102.2858 -230.71455)
		(width 0.1143)
		(layer "In4.Cu")
		(net "P5E_CPU1_G1_RX_DP<9>")
	)
	(segment
		(start 102.065836 -231.992932)
		(end 102.066598 -231.99344)
		(width 0.1143)
		(layer "In4.Cu")
		(net "P5E_CPU1_G1_RX_DP<9>")
	)
	(segment
		(start 100.875846 -221.62389)
		(end 100.875846 -221.804484)
		(width 0.1143)
		(layer "In4.Cu")
		(net "P5E_CPU1_G1_RX_DP<9>")
	)
	(segment
		(start 101.152452 -235.900214)
		(end 101.15169 -235.900722)
		(width 0.1143)
		(layer "In4.Cu")
		(net "P5E_CPU1_G1_RX_DP<9>")
	)
	(segment
		(start 102.127812 -231.020112)
		(end 102.098602 -231.03713)
		(width 0.1143)
		(layer "In4.Cu")
		(net "P5E_CPU1_G1_RX_DP<9>")
	)
	(segment
		(start 102.570534 -232.823258)
		(end 102.599744 -232.840022)
		(width 0.1143)
		(layer "In4.Cu")
		(net "P5E_CPU1_G1_RX_DP<9>")
	)
	(segment
		(start 102.552246 -226.332796)
		(end 102.553008 -226.333304)
		(width 0.1143)
		(layer "In4.Cu")
		(net "P5E_CPU1_G1_RX_DP<9>")
	)
	(segment
		(start 102.56012 -226.337368)
		(end 102.561136 -226.337876)
		(width 0.1143)
		(layer "In4.Cu")
		(net "P5E_CPU1_G1_RX_DP<9>")
	)
	(segment
		(start 30.10662 -7.015988)
		(end 30.10662 -11.796776)
		(width 0.14224)
		(layer "In4.Cu")
		(net "P5E_CPU1_G1_RX_DP<9>")
	)
	(segment
		(start 46.982888 -48.745902)
		(end 52.444904 -55.425594)
		(width 0.14224)
		(layer "In4.Cu")
		(net "P5E_CPU1_G1_RX_DP<9>")
	)
	(segment
		(start 102.093776 -232.009188)
		(end 102.094538 -232.009696)
		(width 0.1143)
		(layer "In4.Cu")
		(net "P5E_CPU1_G1_RX_DP<9>")
	)
	(segment
		(start 102.066598 -225.513646)
		(end 102.093776 -225.529394)
		(width 0.1143)
		(layer "In4.Cu")
		(net "P5E_CPU1_G1_RX_DP<9>")
	)
	(segment
		(start 101.628194 -235.086906)
		(end 101.589078 -235.109766)
		(width 0.1143)
		(layer "In4.Cu")
		(net "P5E_CPU1_G1_RX_DP<9>")
	)
	(segment
		(start 101.18979 -235.878624)
		(end 101.16439 -235.893356)
		(width 0.1143)
		(layer "In4.Cu")
		(net "P5E_CPU1_G1_RX_DP<9>")
	)
	(segment
		(start 102.528624 -230.24973)
		(end 102.384606 -230.35387)
		(width 0.1143)
		(layer "In4.Cu")
		(net "P5E_CPU1_G1_RX_DP<9>")
	)
	(segment
		(start 102.079806 -231.047544)
		(end 102.058978 -231.059736)
		(width 0.1143)
		(layer "In4.Cu")
		(net "P5E_CPU1_G1_RX_DP<9>")
	)
	(segment
		(start 102.599744 -233.448606)
		(end 102.57028 -233.465624)
		(width 0.1143)
		(layer "In4.Cu")
		(net "P5E_CPU1_G1_RX_DP<9>")
	)
	(segment
		(start 102.529894 -226.319842)
		(end 102.548944 -226.331018)
		(width 0.1143)
		(layer "In4.Cu")
		(net "P5E_CPU1_G1_RX_DP<9>")
	)
	(segment
		(start 102.568756 -228.606604)
		(end 102.567994 -228.607112)
		(width 0.1143)
		(layer "In4.Cu")
		(net "P5E_CPU1_G1_RX_DP<9>")
	)
	(segment
		(start 102.098094 -234.2769)
		(end 102.097078 -234.277408)
		(width 0.1143)
		(layer "In4.Cu")
		(net "P5E_CPU1_G1_RX_DP<9>")
	)
	(segment
		(start 101.162358 -235.894372)
		(end 101.161596 -235.89488)
		(width 0.1143)
		(layer "In4.Cu")
		(net "P5E_CPU1_G1_RX_DP<9>")
	)
	(segment
		(start 56.904128 -59.391296)
		(end 58.194194 -60.471304)
		(width 0.14224)
		(layer "In4.Cu")
		(net "P5E_CPU1_G1_RX_DP<9>")
	)
	(segment
		(start 146.085814 -139.506706)
		(end 146.086322 -139.507214)
		(width 0.14224)
		(layer "In4.Cu")
		(net "P5E_CPU1_G1_RX_DP<9>")
	)
	(segment
		(start 146.086322 -139.507214)
		(end 146.086068 -139.507468)
		(width 0.14224)
		(layer "In4.Cu")
		(net "P5E_CPU1_G1_RX_DP<9>")
	)
	(segment
		(start 102.561136 -226.337876)
		(end 102.599744 -226.360228)
		(width 0.1143)
		(layer "In4.Cu")
		(net "P5E_CPU1_G1_RX_DP<9>")
	)
	(segment
		(start 102.548944 -226.331018)
		(end 102.54996 -226.331526)
		(width 0.1143)
		(layer "In4.Cu")
		(net "P5E_CPU1_G1_RX_DP<9>")
	)
	(segment
		(start 101.628194 -223.747076)
		(end 101.589078 -223.769936)
		(width 0.1143)
		(layer "In4.Cu")
		(net "P5E_CPU1_G1_RX_DP<9>")
	)
	(segment
		(start 100.881688 -236.301534)
		(end 100.798884 -236.384338)
		(width 0.1143)
		(layer "In4.Cu")
		(net "P5E_CPU1_G1_RX_DP<9>")
	)
	(segment
		(start 34.208974 -22.963632)
		(end 36.360862 -26.822654)
		(width 0.14224)
		(layer "In4.Cu")
		(net "P5E_CPU1_G1_RX_DP<9>")
	)
	(segment
		(start 102.531672 -229.560882)
		(end 102.534466 -229.562406)
		(width 0.1143)
		(layer "In4.Cu")
		(net "P5E_CPU1_G1_RX_DP<9>")
	)
	(segment
		(start 102.097078 -225.531426)
		(end 102.098094 -225.531934)
		(width 0.1143)
		(layer "In4.Cu")
		(net "P5E_CPU1_G1_RX_DP<9>")
	)
	(segment
		(start 53.114702 -56.15813)
		(end 53.800248 -56.774334)
		(width 0.14224)
		(layer "In4.Cu")
		(net "P5E_CPU1_G1_RX_DP<9>")
	)
	(segment
		(start 102.54996 -226.331526)
		(end 102.55123 -226.332288)
		(width 0.1143)
		(layer "In4.Cu")
		(net "P5E_CPU1_G1_RX_DP<9>")
	)
	(segment
		(start 102.098094 -232.011728)
		(end 102.098856 -232.012236)
		(width 0.1143)
		(layer "In4.Cu")
		(net "P5E_CPU1_G1_RX_DP<9>")
	)
	(segment
		(start 102.552754 -226.333304)
		(end 102.554024 -226.334066)
		(width 0.1143)
		(layer "In4.Cu")
		(net "P5E_CPU1_G1_RX_DP<9>")
	)
	(segment
		(start 102.553008 -226.333304)
		(end 102.552754 -226.333304)
		(width 0.1143)
		(layer "In4.Cu")
		(net "P5E_CPU1_G1_RX_DP<9>")
	)
	(segment
		(start 150.496778 -159.945578)
		(end 150.496778 -163.362894)
		(width 0.14224)
		(layer "In4.Cu")
		(net "P5E_CPU1_G1_RX_DP<9>")
	)
	(segment
		(start 100.799138 -221.259908)
		(end 100.799138 -221.288356)
		(width 0.1143)
		(layer "In4.Cu")
		(net "P5E_CPU1_G1_RX_DP<9>")
	)
	(segment
		(start 100.838508 -215.372696)
		(end 100.838254 -215.372696)
		(width 0.14224)
		(layer "In4.Cu")
		(net "P5E_CPU1_G1_RX_DP<9>")
	)
	(segment
		(start 102.098094 -231.036876)
		(end 102.079806 -231.047544)
		(width 0.1143)
		(layer "In4.Cu")
		(net "P5E_CPU1_G1_RX_DP<9>")
	)
	(segment
		(start 102.567994 -228.607112)
		(end 102.56647 -228.607874)
		(width 0.1143)
		(layer "In4.Cu")
		(net "P5E_CPU1_G1_RX_DP<9>")
	)
	(segment
		(start 41.671748 -37.784278)
		(end 46.982888 -48.745902)
		(width 0.14224)
		(layer "In4.Cu")
		(net "P5E_CPU1_G1_RX_DP<9>")
	)
	(segment
		(start 102.599744 -230.208582)
		(end 102.597966 -230.209852)
		(width 0.1143)
		(layer "In4.Cu")
		(net "P5E_CPU1_G1_RX_DP<9>")
	)
	(segment
		(start 30.842204 -17.750028)
		(end 30.87751 -17.889982)
		(width 0.14224)
		(layer "In4.Cu")
		(net "P5E_CPU1_G1_RX_DP<9>")
	)
	(segment
		(start 146.086068 -139.507468)
		(end 149.682708 -146.936714)
		(width 0.14224)
		(layer "In4.Cu")
		(net "P5E_CPU1_G1_RX_DP<9>")
	)
	(segment
		(start 102.569772 -232.82275)
		(end 102.570534 -232.823258)
		(width 0.1143)
		(layer "In4.Cu")
		(net "P5E_CPU1_G1_RX_DP<9>")
	)
	(segment
		(start 102.093776 -225.529394)
		(end 102.094538 -225.529902)
		(width 0.1143)
		(layer "In4.Cu")
		(net "P5E_CPU1_G1_RX_DP<9>")
	)
	(segment
		(start 101.16439 -235.893356)
		(end 101.162358 -235.894372)
		(width 0.1143)
		(layer "In4.Cu")
		(net "P5E_CPU1_G1_RX_DP<9>")
	)
	(segment
		(start 145.486628 -172.954442)
		(end 107.500166 -204.08646)
		(width 0.14224)
		(layer "In4.Cu")
		(net "P5E_CPU1_G1_RX_DP<9>")
	)
	(segment
		(start 149.682708 -146.936714)
		(end 150.496778 -159.945578)
		(width 0.14224)
		(layer "In4.Cu")
		(net "P5E_CPU1_G1_RX_DP<9>")
	)
	(segment
		(start 30.10662 -11.796776)
		(end 30.842204 -17.750028)
		(width 0.14224)
		(layer "In4.Cu")
		(net "P5E_CPU1_G1_RX_DP<9>")
	)
	(segment
		(start 100.838254 -215.372696)
		(end 100.799138 -215.43899)
		(width 0.14224)
		(layer "In4.Cu")
		(net "P5E_CPU1_G1_RX_DP<9>")
	)
	(segment
		(start 102.554024 -226.334066)
		(end 102.55504 -226.334574)
		(width 0.1143)
		(layer "In4.Cu")
		(net "P5E_CPU1_G1_RX_DP<9>")
	)
	(segment
		(start 31.137606 -18.375122)
		(end 34.208974 -22.963632)
		(width 0.14224)
		(layer "In4.Cu")
		(net "P5E_CPU1_G1_RX_DP<9>")
	)
	(segment
		(start 102.065836 -225.513138)
		(end 102.066598 -225.513646)
		(width 0.1143)
		(layer "In4.Cu")
		(net "P5E_CPU1_G1_RX_DP<9>")
	)
	(segment
		(start 102.56774 -232.82148)
		(end 102.569772 -232.82275)
		(width 0.1143)
		(layer "In4.Cu")
		(net "P5E_CPU1_G1_RX_DP<9>")
	)
	(segment
		(start 102.567994 -233.466894)
		(end 102.567486 -233.467148)
		(width 0.1143)
		(layer "In4.Cu")
		(net "P5E_CPU1_G1_RX_DP<9>")
	)
	(segment
		(start 102.10165 -225.533712)
		(end 102.102158 -225.533966)
		(width 0.1143)
		(layer "In4.Cu")
		(net "P5E_CPU1_G1_RX_DP<9>")
	)
	(segment
		(start 102.55123 -226.332288)
		(end 102.552246 -226.332796)
		(width 0.1143)
		(layer "In4.Cu")
		(net "P5E_CPU1_G1_RX_DP<9>")
	)
	(segment
		(start 101.658674 -223.729296)
		(end 101.628194 -223.747076)
		(width 0.1143)
		(layer "In4.Cu")
		(net "P5E_CPU1_G1_RX_DP<9>")
	)
	(segment
		(start 101.628194 -224.721928)
		(end 101.658674 -224.739708)
		(width 0.1143)
		(layer "In4.Cu")
		(net "P5E_CPU1_G1_RX_DP<9>")
	)
	(segment
		(start 100.844858 -221.334076)
		(end 100.844858 -221.592902)
		(width 0.1143)
		(layer "In4.Cu")
		(net "P5E_CPU1_G1_RX_DP<9>")
	)
	(segment
		(start 29.81579 -6.725158)
		(end 30.10662 -7.015988)
		(width 0.14224)
		(layer "In4.Cu")
		(net "P5E_CPU1_G1_RX_DP<9>")
	)
	(segment
		(start 102.094538 -232.009696)
		(end 102.097078 -232.01122)
		(width 0.1143)
		(layer "In4.Cu")
		(net "P5E_CPU1_G1_RX_DP<9>")
	)
	(segment
		(start 100.798884 -236.384338)
		(end 100.500942 -236.384338)
		(width 0.1143)
		(layer "In4.Cu")
		(net "P5E_CPU1_G1_RX_DP<9>")
	)
	(segment
		(start 102.097078 -234.277408)
		(end 102.058978 -234.29976)
		(width 0.1143)
		(layer "In4.Cu")
		(net "P5E_CPU1_G1_RX_DP<9>")
	)
	(segment
		(start 102.555802 -226.335082)
		(end 102.559358 -226.33686)
		(width 0.1143)
		(layer "In4.Cu")
		(net "P5E_CPU1_G1_RX_DP<9>")
	)
	(segment
		(start 102.058978 -225.509074)
		(end 102.065836 -225.513138)
		(width 0.1143)
		(layer "In4.Cu")
		(net "P5E_CPU1_G1_RX_DP<9>")
	)
	(segment
		(start 101.161596 -235.89488)
		(end 101.158802 -235.896404)
		(width 0.1143)
		(layer "In4.Cu")
		(net "P5E_CPU1_G1_RX_DP<9>")
	)
	(segment
		(start 102.098856 -225.532442)
		(end 102.10165 -225.533712)
		(width 0.1143)
		(layer "In4.Cu")
		(net "P5E_CPU1_G1_RX_DP<9>")
	)
	(segment
		(start 30.87751 -17.889982)
		(end 31.137606 -18.375122)
		(width 0.14224)
		(layer "In4.Cu")
		(net "P5E_CPU1_G1_RX_DP<9>")
	)
	(segment
		(start 102.098094 -225.531934)
		(end 102.098856 -225.532442)
		(width 0.1143)
		(layer "In4.Cu")
		(net "P5E_CPU1_G1_RX_DP<9>")
	)
	(segment
		(start 101.589078 -223.079056)
		(end 101.628194 -223.101916)
		(width 0.1143)
		(layer "In4.Cu")
		(net "P5E_CPU1_G1_RX_DP<9>")
	)
	(segment
		(start 102.098856 -232.012236)
		(end 102.10165 -232.013506)
		(width 0.1143)
		(layer "In4.Cu")
		(net "P5E_CPU1_G1_RX_DP<9>")
	)
	(segment
		(start 102.098602 -231.03713)
		(end 102.098094 -231.036876)
		(width 0.1143)
		(layer "In4.Cu")
		(net "P5E_CPU1_G1_RX_DP<9>")
	)
	(segment
		(start 36.360862 -26.822654)
		(end 41.671748 -37.784278)
		(width 0.14224)
		(layer "In4.Cu")
		(net "P5E_CPU1_G1_RX_DP<9>")
	)
	(segment
		(start 102.614984 -233.437684)
		(end 102.599744 -233.448606)
		(width 0.1143)
		(layer "In4.Cu")
		(net "P5E_CPU1_G1_RX_DP<9>")
	)
	(segment
		(start 102.599744 -226.968812)
		(end 102.567994 -226.9871)
		(width 0.1143)
		(layer "In4.Cu")
		(net "P5E_CPU1_G1_RX_DP<9>")
	)
	(segment
		(start 102.567232 -227.96373)
		(end 102.568248 -227.964238)
		(width 0.1143)
		(layer "In4.Cu")
		(net "P5E_CPU1_G1_RX_DP<9>")
	)
	(segment
		(start 102.098856 -234.276392)
		(end 102.098094 -234.2769)
		(width 0.1143)
		(layer "In4.Cu")
		(net "P5E_CPU1_G1_RX_DP<9>")
	)
	(segment
		(start 102.56647 -228.607874)
		(end 102.531672 -228.628194)
		(width 0.1143)
		(layer "In4.Cu")
		(net "P5E_CPU1_G1_RX_DP<9>")
	)
	(segment
		(start 102.599744 -232.840022)
		(end 102.614984 -232.850944)
		(width 0.1143)
		(layer "In4.Cu")
		(net "P5E_CPU1_G1_RX_DP<9>")
	)
	(segment
		(start 101.118924 -222.26905)
		(end 101.18979 -222.310198)
		(width 0.1143)
		(layer "In4.Cu")
		(net "P5E_CPU1_G1_RX_DP<9>")
	)
	(segment
		(start 101.589078 -224.699068)
		(end 101.628194 -224.721928)
		(width 0.1143)
		(layer "In4.Cu")
		(net "P5E_CPU1_G1_RX_DP<9>")
	)
	(segment
		(start 102.10165 -232.013506)
		(end 102.102158 -232.01376)
		(width 0.1143)
		(layer "In4.Cu")
		(net "P5E_CPU1_G1_RX_DP<9>")
	)
	(segment
		(start 102.066598 -231.99344)
		(end 102.093776 -232.009188)
		(width 0.1143)
		(layer "In4.Cu")
		(net "P5E_CPU1_G1_RX_DP<9>")
	)
	(segment
		(start 102.57028 -233.465624)
		(end 102.568756 -233.466386)
		(width 0.1143)
		(layer "In4.Cu")
		(net "P5E_CPU1_G1_RX_DP<9>")
	)
	(segment
		(start 100.844858 -221.592902)
		(end 100.875846 -221.62389)
		(width 0.1143)
		(layer "In4.Cu")
		(net "P5E_CPU1_G1_RX_DP<9>")
	)
	(segment
		(start 102.058978 -231.988868)
		(end 102.065836 -231.992932)
		(width 0.1143)
		(layer "In4.Cu")
		(net "P5E_CPU1_G1_RX_DP<9>")
	)
	(segment
		(start 101.15169 -235.900722)
		(end 101.118924 -235.919772)
		(width 0.1143)
		(layer "In4.Cu")
		(net "P5E_CPU1_G1_RX_DP<9>")
	)
	(segment
		(start 107.500166 -204.08646)
		(end 100.838508 -215.372696)
		(width 0.14224)
		(layer "In4.Cu")
		(net "P5E_CPU1_G1_RX_DP<9>")
	)
	(segment
		(start 102.597966 -230.209852)
		(end 102.528624 -230.24973)
		(width 0.1143)
		(layer "In4.Cu")
		(net "P5E_CPU1_G1_RX_DP<9>")
	)
	(segment
		(start 101.15804 -235.896912)
		(end 101.157024 -235.89742)
		(width 0.1143)
		(layer "In4.Cu")
		(net "P5E_CPU1_G1_RX_DP<9>")
	)
	(segment
		(start 101.1555 -235.898436)
		(end 101.153722 -235.899452)
		(width 0.1143)
		(layer "In4.Cu")
		(net "P5E_CPU1_G1_RX_DP<9>")
	)
	(segment
		(start 102.534466 -229.562406)
		(end 102.601522 -229.601522)
		(width 0.1143)
		(layer "In4.Cu")
		(net "P5E_CPU1_G1_RX_DP<9>")
	)
	(segment
		(start 102.567994 -226.9871)
		(end 102.531672 -227.008182)
		(width 0.1143)
		(layer "In4.Cu")
		(net "P5E_CPU1_G1_RX_DP<9>")
	)
	(segment
		(start 101.158802 -235.896404)
		(end 101.15804 -235.896912)
		(width 0.1143)
		(layer "In4.Cu")
		(net "P5E_CPU1_G1_RX_DP<9>")
	)
	(segment
		(start 150.496778 -163.362894)
		(end 148.907246 -168.03116)
		(width 0.14224)
		(layer "In4.Cu")
		(net "P5E_CPU1_G1_RX_DP<9>")
	)
	(segment
		(start 102.094538 -225.529902)
		(end 102.097078 -225.531426)
		(width 0.1143)
		(layer "In4.Cu")
		(net "P5E_CPU1_G1_RX_DP<9>")
	)
	(segment
		(start 102.568756 -233.466386)
		(end 102.567994 -233.466894)
		(width 0.1143)
		(layer "In4.Cu")
		(net "P5E_CPU1_G1_RX_DP<9>")
	)
	(arc
		(start 101.118924 -235.919772)
		(mid 100.966937 -236.07628)
		(end 100.885498 -236.278674)
		(width 0.1143)
		(layer "In4.Cu")
		(net "P5E_CPU1_G1_RX_DP<9>")
	)
	(arc
		(start 101.18979 -222.310198)
		(mid 101.304466 -222.443532)
		(end 101.345746 -222.61449)
		(width 0.1143)
		(layer "In4.Cu")
		(net "P5E_CPU1_G1_RX_DP<9>")
	)
	(arc
		(start 102.599744 -226.360228)
		(mid 102.755672 -226.66452)
		(end 102.599744 -226.968812)
		(width 0.1143)
		(layer "In4.Cu")
		(net "P5E_CPU1_G1_RX_DP<9>")
	)
	(arc
		(start 102.614984 -232.850944)
		(mid 102.765321 -233.144314)
		(end 102.614984 -233.437684)
		(width 0.1143)
		(layer "In4.Cu")
		(net "P5E_CPU1_G1_RX_DP<9>")
	)
	(arc
		(start 102.058978 -231.059736)
		(mid 101.815651 -231.524302)
		(end 102.058978 -231.988868)
		(width 0.1143)
		(layer "In4.Cu")
		(net "P5E_CPU1_G1_RX_DP<9>")
	)
	(arc
		(start 100.875846 -221.804484)
		(mid 100.940293 -222.066636)
		(end 101.118924 -222.26905)
		(width 0.1143)
		(layer "In4.Cu")
		(net "P5E_CPU1_G1_RX_DP<9>")
	)
	(arc
		(start 102.7557 -229.90429)
		(mid 102.714445 -230.075261)
		(end 102.599744 -230.208582)
		(width 0.1143)
		(layer "In4.Cu")
		(net "P5E_CPU1_G1_RX_DP<9>")
	)
	(arc
		(start 102.2858 -229.080822)
		(mid 102.344136 -229.344595)
		(end 102.51821 -229.55123)
		(width 0.1143)
		(layer "In4.Cu")
		(net "P5E_CPU1_G1_RX_DP<9>")
	)
	(arc
		(start 102.102158 -232.01376)
		(mid 102.237137 -232.150863)
		(end 102.285546 -232.337102)
		(width 0.1143)
		(layer "In4.Cu")
		(net "P5E_CPU1_G1_RX_DP<9>")
	)
	(arc
		(start 101.815646 -225.044508)
		(mid 101.880161 -225.306727)
		(end 102.058978 -225.509074)
		(width 0.1143)
		(layer "In4.Cu")
		(net "P5E_CPU1_G1_RX_DP<9>")
	)
	(arc
		(start 102.2858 -230.71455)
		(mid 102.24396 -230.886536)
		(end 102.127812 -231.020112)
		(width 0.1143)
		(layer "In4.Cu")
		(net "P5E_CPU1_G1_RX_DP<9>")
	)
	(arc
		(start 102.601522 -229.601522)
		(mid 102.714929 -229.734411)
		(end 102.7557 -229.90429)
		(width 0.1143)
		(layer "In4.Cu")
		(net "P5E_CPU1_G1_RX_DP<9>")
	)
	(arc
		(start 102.28834 -233.952034)
		(mid 102.238222 -234.138547)
		(end 102.101396 -234.274868)
		(width 0.1143)
		(layer "In4.Cu")
		(net "P5E_CPU1_G1_RX_DP<9>")
	)
	(arc
		(start 102.51821 -229.55123)
		(mid 102.524905 -229.556106)
		(end 102.531672 -229.560882)
		(width 0.1143)
		(layer "In4.Cu")
		(net "P5E_CPU1_G1_RX_DP<9>")
	)
	(arc
		(start 102.531672 -227.008182)
		(mid 102.286073 -227.495782)
		(end 102.567232 -227.96373)
		(width 0.1143)
		(layer "In4.Cu")
		(net "P5E_CPU1_G1_RX_DP<9>")
	)
	(arc
		(start 102.567486 -233.467148)
		(mid 102.363068 -233.67227)
		(end 102.28834 -233.952034)
		(width 0.1143)
		(layer "In4.Cu")
		(net "P5E_CPU1_G1_RX_DP<9>")
	)
	(arc
		(start 101.345746 -235.574332)
		(mid 101.304491 -235.745303)
		(end 101.18979 -235.878624)
		(width 0.1143)
		(layer "In4.Cu")
		(net "P5E_CPU1_G1_RX_DP<9>")
	)
	(arc
		(start 102.384606 -230.35387)
		(mid 102.311943 -230.438341)
		(end 102.2858 -230.546656)
		(width 0.1143)
		(layer "In4.Cu")
		(net "P5E_CPU1_G1_RX_DP<9>")
	)
	(arc
		(start 101.345746 -222.61449)
		(mid 101.410261 -222.876709)
		(end 101.589078 -223.079056)
		(width 0.1143)
		(layer "In4.Cu")
		(net "P5E_CPU1_G1_RX_DP<9>")
	)
	(arc
		(start 102.568248 -227.964238)
		(mid 102.754298 -228.268003)
		(end 102.599744 -228.588824)
		(width 0.1143)
		(layer "In4.Cu")
		(net "P5E_CPU1_G1_RX_DP<9>")
	)
	(arc
		(start 102.285546 -232.337102)
		(mid 102.35316 -232.595445)
		(end 102.5271 -232.798112)
		(width 0.1143)
		(layer "In4.Cu")
		(net "P5E_CPU1_G1_RX_DP<9>")
	)
	(arc
		(start 100.885498 -236.278674)
		(mid 100.883475 -236.290084)
		(end 100.881688 -236.301534)
		(width 0.1143)
		(layer "In4.Cu")
		(net "P5E_CPU1_G1_RX_DP<9>")
	)
	(arc
		(start 101.658674 -224.739708)
		(mid 101.774101 -224.873084)
		(end 101.815646 -225.044508)
		(width 0.1143)
		(layer "In4.Cu")
		(net "P5E_CPU1_G1_RX_DP<9>")
	)
	(arc
		(start 101.589078 -223.769936)
		(mid 101.345751 -224.234502)
		(end 101.589078 -224.699068)
		(width 0.1143)
		(layer "In4.Cu")
		(net "P5E_CPU1_G1_RX_DP<9>")
	)
	(arc
		(start 102.058978 -234.29976)
		(mid 101.880165 -234.50211)
		(end 101.815646 -234.764326)
		(width 0.1143)
		(layer "In4.Cu")
		(net "P5E_CPU1_G1_RX_DP<9>")
	)
	(arc
		(start 102.531672 -228.628194)
		(mid 102.515707 -228.640235)
		(end 102.500176 -228.652832)
		(width 0.1143)
		(layer "In4.Cu")
		(net "P5E_CPU1_G1_RX_DP<9>")
	)
	(arc
		(start 101.658674 -223.119696)
		(mid 101.815651 -223.424496)
		(end 101.658674 -223.729296)
		(width 0.1143)
		(layer "In4.Cu")
		(net "P5E_CPU1_G1_RX_DP<9>")
	)
	(arc
		(start 101.815646 -234.764326)
		(mid 101.774097 -234.935748)
		(end 101.658674 -235.069126)
		(width 0.1143)
		(layer "In4.Cu")
		(net "P5E_CPU1_G1_RX_DP<9>")
	)
	(arc
		(start 102.102158 -225.533966)
		(mid 102.23663 -225.669804)
		(end 102.2858 -225.854514)
		(width 0.1143)
		(layer "In4.Cu")
		(net "P5E_CPU1_G1_RX_DP<9>")
	)
	(arc
		(start 101.589078 -235.109766)
		(mid 101.410265 -235.312116)
		(end 101.345746 -235.574332)
		(width 0.1143)
		(layer "In4.Cu")
		(net "P5E_CPU1_G1_RX_DP<9>")
	)
	(arc
		(start 102.500176 -228.652832)
		(mid 102.356135 -228.848366)
		(end 102.2858 -229.080822)
		(width 0.1143)
		(layer "In4.Cu")
		(net "P5E_CPU1_G1_RX_DP<9>")
	)
	(arc
		(start 102.2858 -225.854514)
		(mid 102.350522 -226.117253)
		(end 102.529894 -226.319842)
		(width 0.1143)
		(layer "In4.Cu")
		(net "P5E_CPU1_G1_RX_DP<9>")
	)
	(segment
		(start 28.020264 -4.963414)
		(end 28.285694 -5.228844)
		(width 0.12954)
		(layer "F.Cu")
		(net "P5E_CPU1_G1_RX_DP<10>")
	)
	(segment
		(start 28.285694 -5.228844)
		(end 28.285694 -7.57047)
		(width 0.12954)
		(layer "F.Cu")
		(net "P5E_CPU1_G1_RX_DP<10>")
	)
	(segment
		(start 28.285694 -7.57047)
		(end 28.14701 -7.709154)
		(width 0.12954)
		(layer "F.Cu")
		(net "P5E_CPU1_G1_RX_DP<10>")
	)
	(segment
		(start 100.967794 -231.79024)
		(end 100.500942 -231.524302)
		(width 0.12954)
		(layer "F.Cu")
		(net "P5E_CPU1_G1_RX_DP<10>")
	)
	(segment
		(start 28.14701 -7.709154)
		(end 28.14701 -8.320024)
		(width 0.12954)
		(layer "F.Cu")
		(net "P5E_CPU1_G1_RX_DP<10>")
	)
	(segment
		(start 101.157024 -225.531426)
		(end 101.15804 -225.531934)
		(width 0.1143)
		(layer "In4.Cu")
		(net "P5E_CPU1_G1_RX_DP<10>")
	)
	(segment
		(start 52.45735 -56.820816)
		(end 53.192172 -57.481724)
		(width 0.14224)
		(layer "In4.Cu")
		(net "P5E_CPU1_G1_RX_DP<10>")
	)
	(segment
		(start 101.15804 -225.531934)
		(end 101.158802 -225.532442)
		(width 0.1143)
		(layer "In4.Cu")
		(net "P5E_CPU1_G1_RX_DP<10>")
	)
	(segment
		(start 99.854258 -221.259908)
		(end 99.854258 -221.288356)
		(width 0.1143)
		(layer "In4.Cu")
		(net "P5E_CPU1_G1_RX_DP<10>")
	)
	(segment
		(start 106.658918 -203.567792)
		(end 99.854258 -215.028018)
		(width 0.14224)
		(layer "In4.Cu")
		(net "P5E_CPU1_G1_RX_DP<10>")
	)
	(segment
		(start 99.899978 -221.592902)
		(end 99.935792 -221.628716)
		(width 0.1143)
		(layer "In4.Cu")
		(net "P5E_CPU1_G1_RX_DP<10>")
	)
	(segment
		(start 100.881688 -231.441498)
		(end 100.798884 -231.524302)
		(width 0.1143)
		(layer "In4.Cu")
		(net "P5E_CPU1_G1_RX_DP<10>")
	)
	(segment
		(start 101.589078 -229.559104)
		(end 101.628194 -229.581964)
		(width 0.1143)
		(layer "In4.Cu")
		(net "P5E_CPU1_G1_RX_DP<10>")
	)
	(segment
		(start 28.753816 -17.71269)
		(end 28.711652 -17.815052)
		(width 0.14224)
		(layer "In4.Cu")
		(net "P5E_CPU1_G1_RX_DP<10>")
	)
	(segment
		(start 28.711652 -17.815052)
		(end 28.489656 -18.229834)
		(width 0.14224)
		(layer "In4.Cu")
		(net "P5E_CPU1_G1_RX_DP<10>")
	)
	(segment
		(start 101.15804 -231.036876)
		(end 101.118924 -231.059736)
		(width 0.1143)
		(layer "In4.Cu")
		(net "P5E_CPU1_G1_RX_DP<10>")
	)
	(segment
		(start 28.489656 -18.229834)
		(end 27.936444 -19.057112)
		(width 0.14224)
		(layer "In4.Cu")
		(net "P5E_CPU1_G1_RX_DP<10>")
	)
	(segment
		(start 100.181664 -222.270828)
		(end 100.249736 -222.310198)
		(width 0.1143)
		(layer "In4.Cu")
		(net "P5E_CPU1_G1_RX_DP<10>")
	)
	(segment
		(start 101.658674 -230.20909)
		(end 101.591618 -230.248206)
		(width 0.1143)
		(layer "In4.Cu")
		(net "P5E_CPU1_G1_RX_DP<10>")
	)
	(segment
		(start 101.628194 -227.961952)
		(end 101.658674 -227.979732)
		(width 0.1143)
		(layer "In4.Cu")
		(net "P5E_CPU1_G1_RX_DP<10>")
	)
	(segment
		(start 28.311094 -5.254244)
		(end 28.311094 -11.822684)
		(width 0.14224)
		(layer "In4.Cu")
		(net "P5E_CPU1_G1_RX_DP<10>")
	)
	(segment
		(start 100.798884 -231.524302)
		(end 100.500942 -231.524302)
		(width 0.1143)
		(layer "In4.Cu")
		(net "P5E_CPU1_G1_RX_DP<10>")
	)
	(segment
		(start 27.936444 -19.057112)
		(end 27.930348 -19.347688)
		(width 0.14224)
		(layer "In4.Cu")
		(net "P5E_CPU1_G1_RX_DP<10>")
	)
	(segment
		(start 101.154484 -225.529902)
		(end 101.157024 -225.531426)
		(width 0.1143)
		(layer "In4.Cu")
		(net "P5E_CPU1_G1_RX_DP<10>")
	)
	(segment
		(start 149.557994 -159.975042)
		(end 149.557994 -163.188142)
		(width 0.14224)
		(layer "In4.Cu")
		(net "P5E_CPU1_G1_RX_DP<10>")
	)
	(segment
		(start 148.067014 -167.56761)
		(end 144.733264 -172.366178)
		(width 0.14224)
		(layer "In4.Cu")
		(net "P5E_CPU1_G1_RX_DP<10>")
	)
	(segment
		(start 149.557994 -163.188142)
		(end 148.067014 -167.56761)
		(width 0.14224)
		(layer "In4.Cu")
		(net "P5E_CPU1_G1_RX_DP<10>")
	)
	(segment
		(start 145.3261 -140.077698)
		(end 148.756624 -147.17014)
		(width 0.14224)
		(layer "In4.Cu")
		(net "P5E_CPU1_G1_RX_DP<10>")
	)
	(segment
		(start 53.192172 -57.481724)
		(end 55.415688 -59.306714)
		(width 0.14224)
		(layer "In4.Cu")
		(net "P5E_CPU1_G1_RX_DP<10>")
	)
	(segment
		(start 100.68814 -224.721928)
		(end 100.71862 -224.739708)
		(width 0.1143)
		(layer "In4.Cu")
		(net "P5E_CPU1_G1_RX_DP<10>")
	)
	(segment
		(start 101.628194 -226.34194)
		(end 101.658674 -226.35972)
		(width 0.1143)
		(layer "In4.Cu")
		(net "P5E_CPU1_G1_RX_DP<10>")
	)
	(segment
		(start 99.935792 -221.628716)
		(end 99.935792 -221.804484)
		(width 0.1143)
		(layer "In4.Cu")
		(net "P5E_CPU1_G1_RX_DP<10>")
	)
	(segment
		(start 101.158802 -225.532442)
		(end 101.18979 -225.550222)
		(width 0.1143)
		(layer "In4.Cu")
		(net "P5E_CPU1_G1_RX_DP<10>")
	)
	(segment
		(start 28.311094 -11.822684)
		(end 28.755594 -16.336518)
		(width 0.14224)
		(layer "In4.Cu")
		(net "P5E_CPU1_G1_RX_DP<10>")
	)
	(segment
		(start 100.179632 -222.269558)
		(end 100.180648 -222.27032)
		(width 0.1143)
		(layer "In4.Cu")
		(net "P5E_CPU1_G1_RX_DP<10>")
	)
	(segment
		(start 101.191568 -231.017318)
		(end 101.15804 -231.036876)
		(width 0.1143)
		(layer "In4.Cu")
		(net "P5E_CPU1_G1_RX_DP<10>")
	)
	(segment
		(start 144.733264 -172.366178)
		(end 106.658918 -203.567792)
		(width 0.14224)
		(layer "In4.Cu")
		(net "P5E_CPU1_G1_RX_DP<10>")
	)
	(segment
		(start 101.658674 -226.96932)
		(end 101.628194 -226.9871)
		(width 0.1143)
		(layer "In4.Cu")
		(net "P5E_CPU1_G1_RX_DP<10>")
	)
	(segment
		(start 99.854258 -221.288356)
		(end 99.899978 -221.334076)
		(width 0.1143)
		(layer "In4.Cu")
		(net "P5E_CPU1_G1_RX_DP<10>")
	)
	(segment
		(start 101.589078 -226.31908)
		(end 101.628194 -226.34194)
		(width 0.1143)
		(layer "In4.Cu")
		(net "P5E_CPU1_G1_RX_DP<10>")
	)
	(segment
		(start 32.524446 -26.844244)
		(end 44.489116 -47.715678)
		(width 0.14224)
		(layer "In4.Cu")
		(net "P5E_CPU1_G1_RX_DP<10>")
	)
	(segment
		(start 101.125782 -225.513138)
		(end 101.126544 -225.513646)
		(width 0.1143)
		(layer "In4.Cu")
		(net "P5E_CPU1_G1_RX_DP<10>")
	)
	(segment
		(start 28.020264 -4.963414)
		(end 28.311094 -5.254244)
		(width 0.14224)
		(layer "In4.Cu")
		(net "P5E_CPU1_G1_RX_DP<10>")
	)
	(segment
		(start 100.68814 -223.101916)
		(end 100.71862 -223.119696)
		(width 0.1143)
		(layer "In4.Cu")
		(net "P5E_CPU1_G1_RX_DP<10>")
	)
	(segment
		(start 101.628194 -229.581964)
		(end 101.660706 -229.60076)
		(width 0.1143)
		(layer "In4.Cu")
		(net "P5E_CPU1_G1_RX_DP<10>")
	)
	(segment
		(start 28.755594 -16.336518)
		(end 28.755594 -17.708626)
		(width 0.14224)
		(layer "In4.Cu")
		(net "P5E_CPU1_G1_RX_DP<10>")
	)
	(segment
		(start 31.794196 -25.803606)
		(end 32.524446 -26.844244)
		(width 0.14224)
		(layer "In4.Cu")
		(net "P5E_CPU1_G1_RX_DP<10>")
	)
	(segment
		(start 56.293004 -60.095638)
		(end 57.58307 -61.175646)
		(width 0.14224)
		(layer "In4.Cu")
		(net "P5E_CPU1_G1_RX_DP<10>")
	)
	(segment
		(start 101.589078 -227.939092)
		(end 101.628194 -227.961952)
		(width 0.1143)
		(layer "In4.Cu")
		(net "P5E_CPU1_G1_RX_DP<10>")
	)
	(segment
		(start 100.649024 -224.699068)
		(end 100.68814 -224.721928)
		(width 0.1143)
		(layer "In4.Cu")
		(net "P5E_CPU1_G1_RX_DP<10>")
	)
	(segment
		(start 55.415688 -59.306714)
		(end 56.293004 -60.095638)
		(width 0.14224)
		(layer "In4.Cu")
		(net "P5E_CPU1_G1_RX_DP<10>")
	)
	(segment
		(start 101.118924 -225.509074)
		(end 101.125782 -225.513138)
		(width 0.1143)
		(layer "In4.Cu")
		(net "P5E_CPU1_G1_RX_DP<10>")
	)
	(segment
		(start 101.153722 -225.529394)
		(end 101.154484 -225.529902)
		(width 0.1143)
		(layer "In4.Cu")
		(net "P5E_CPU1_G1_RX_DP<10>")
	)
	(segment
		(start 101.628194 -226.9871)
		(end 101.589078 -227.00996)
		(width 0.1143)
		(layer "In4.Cu")
		(net "P5E_CPU1_G1_RX_DP<10>")
	)
	(segment
		(start 100.71862 -223.729296)
		(end 100.68814 -223.747076)
		(width 0.1143)
		(layer "In4.Cu")
		(net "P5E_CPU1_G1_RX_DP<10>")
	)
	(segment
		(start 99.899978 -221.334076)
		(end 99.899978 -221.592902)
		(width 0.1143)
		(layer "In4.Cu")
		(net "P5E_CPU1_G1_RX_DP<10>")
	)
	(segment
		(start 27.930348 -19.347688)
		(end 31.416498 -25.265126)
		(width 0.14224)
		(layer "In4.Cu")
		(net "P5E_CPU1_G1_RX_DP<10>")
	)
	(segment
		(start 57.58307 -61.175646)
		(end 145.3261 -140.077698)
		(width 0.14224)
		(layer "In4.Cu")
		(net "P5E_CPU1_G1_RX_DP<10>")
	)
	(segment
		(start 31.416498 -25.265126)
		(end 31.794196 -25.803606)
		(width 0.14224)
		(layer "In4.Cu")
		(net "P5E_CPU1_G1_RX_DP<10>")
	)
	(segment
		(start 100.68814 -223.747076)
		(end 100.649024 -223.769936)
		(width 0.1143)
		(layer "In4.Cu")
		(net "P5E_CPU1_G1_RX_DP<10>")
	)
	(segment
		(start 101.126544 -225.513646)
		(end 101.153722 -225.529394)
		(width 0.1143)
		(layer "In4.Cu")
		(net "P5E_CPU1_G1_RX_DP<10>")
	)
	(segment
		(start 101.628194 -228.607112)
		(end 101.589078 -228.629972)
		(width 0.1143)
		(layer "In4.Cu")
		(net "P5E_CPU1_G1_RX_DP<10>")
	)
	(segment
		(start 101.658674 -228.589332)
		(end 101.628194 -228.607112)
		(width 0.1143)
		(layer "In4.Cu")
		(net "P5E_CPU1_G1_RX_DP<10>")
	)
	(segment
		(start 148.756624 -147.17014)
		(end 149.557994 -159.975042)
		(width 0.14224)
		(layer "In4.Cu")
		(net "P5E_CPU1_G1_RX_DP<10>")
	)
	(segment
		(start 44.489116 -47.715678)
		(end 49.921668 -54.04866)
		(width 0.14224)
		(layer "In4.Cu")
		(net "P5E_CPU1_G1_RX_DP<10>")
	)
	(segment
		(start 49.921668 -54.04866)
		(end 52.45735 -56.820816)
		(width 0.14224)
		(layer "In4.Cu")
		(net "P5E_CPU1_G1_RX_DP<10>")
	)
	(segment
		(start 100.180648 -222.27032)
		(end 100.181664 -222.270828)
		(width 0.1143)
		(layer "In4.Cu")
		(net "P5E_CPU1_G1_RX_DP<10>")
	)
	(segment
		(start 100.649024 -223.079056)
		(end 100.68814 -223.101916)
		(width 0.1143)
		(layer "In4.Cu")
		(net "P5E_CPU1_G1_RX_DP<10>")
	)
	(segment
		(start 28.755594 -17.708626)
		(end 28.753816 -17.71269)
		(width 0.14224)
		(layer "In4.Cu")
		(net "P5E_CPU1_G1_RX_DP<10>")
	)
	(segment
		(start 99.854258 -215.028018)
		(end 99.854258 -221.259908)
		(width 0.14224)
		(layer "In4.Cu")
		(net "P5E_CPU1_G1_RX_DP<10>")
	)
	(arc
		(start 100.71862 -224.739708)
		(mid 100.834047 -224.873084)
		(end 100.875592 -225.044508)
		(width 0.1143)
		(layer "In4.Cu")
		(net "P5E_CPU1_G1_RX_DP<10>")
	)
	(arc
		(start 100.875592 -225.044508)
		(mid 100.940107 -225.306727)
		(end 101.118924 -225.509074)
		(width 0.1143)
		(layer "In4.Cu")
		(net "P5E_CPU1_G1_RX_DP<10>")
	)
	(arc
		(start 101.591618 -230.248206)
		(mid 101.410966 -230.450951)
		(end 101.345746 -230.71455)
		(width 0.1143)
		(layer "In4.Cu")
		(net "P5E_CPU1_G1_RX_DP<10>")
	)
	(arc
		(start 100.649024 -223.769936)
		(mid 100.405697 -224.234502)
		(end 100.649024 -224.699068)
		(width 0.1143)
		(layer "In4.Cu")
		(net "P5E_CPU1_G1_RX_DP<10>")
	)
	(arc
		(start 101.658674 -227.979732)
		(mid 101.815651 -228.284532)
		(end 101.658674 -228.589332)
		(width 0.1143)
		(layer "In4.Cu")
		(net "P5E_CPU1_G1_RX_DP<10>")
	)
	(arc
		(start 101.815646 -229.90429)
		(mid 101.774097 -230.075712)
		(end 101.658674 -230.20909)
		(width 0.1143)
		(layer "In4.Cu")
		(net "P5E_CPU1_G1_RX_DP<10>")
	)
	(arc
		(start 101.660706 -229.60076)
		(mid 101.774635 -229.733907)
		(end 101.815646 -229.90429)
		(width 0.1143)
		(layer "In4.Cu")
		(net "P5E_CPU1_G1_RX_DP<10>")
	)
	(arc
		(start 99.935792 -221.804484)
		(mid 100.000451 -222.067041)
		(end 100.179632 -222.269558)
		(width 0.1143)
		(layer "In4.Cu")
		(net "P5E_CPU1_G1_RX_DP<10>")
	)
	(arc
		(start 101.658674 -226.35972)
		(mid 101.815651 -226.66452)
		(end 101.658674 -226.96932)
		(width 0.1143)
		(layer "In4.Cu")
		(net "P5E_CPU1_G1_RX_DP<10>")
	)
	(arc
		(start 101.589078 -227.00996)
		(mid 101.345751 -227.474526)
		(end 101.589078 -227.939092)
		(width 0.1143)
		(layer "In4.Cu")
		(net "P5E_CPU1_G1_RX_DP<10>")
	)
	(arc
		(start 101.345746 -225.854514)
		(mid 101.410261 -226.116733)
		(end 101.589078 -226.31908)
		(width 0.1143)
		(layer "In4.Cu")
		(net "P5E_CPU1_G1_RX_DP<10>")
	)
	(arc
		(start 101.345746 -230.71455)
		(mid 101.304984 -230.884434)
		(end 101.191568 -231.017318)
		(width 0.1143)
		(layer "In4.Cu")
		(net "P5E_CPU1_G1_RX_DP<10>")
	)
	(arc
		(start 101.589078 -228.629972)
		(mid 101.345751 -229.094538)
		(end 101.589078 -229.559104)
		(width 0.1143)
		(layer "In4.Cu")
		(net "P5E_CPU1_G1_RX_DP<10>")
	)
	(arc
		(start 101.118924 -231.059736)
		(mid 100.966937 -231.216244)
		(end 100.885498 -231.418638)
		(width 0.1143)
		(layer "In4.Cu")
		(net "P5E_CPU1_G1_RX_DP<10>")
	)
	(arc
		(start 100.885498 -231.418638)
		(mid 100.883475 -231.430048)
		(end 100.881688 -231.441498)
		(width 0.1143)
		(layer "In4.Cu")
		(net "P5E_CPU1_G1_RX_DP<10>")
	)
	(arc
		(start 100.405692 -222.61449)
		(mid 100.470207 -222.876709)
		(end 100.649024 -223.079056)
		(width 0.1143)
		(layer "In4.Cu")
		(net "P5E_CPU1_G1_RX_DP<10>")
	)
	(arc
		(start 100.249736 -222.310198)
		(mid 100.364412 -222.443532)
		(end 100.405692 -222.61449)
		(width 0.1143)
		(layer "In4.Cu")
		(net "P5E_CPU1_G1_RX_DP<10>")
	)
	(arc
		(start 101.18979 -225.550222)
		(mid 101.304466 -225.683556)
		(end 101.345746 -225.854514)
		(width 0.1143)
		(layer "In4.Cu")
		(net "P5E_CPU1_G1_RX_DP<10>")
	)
	(arc
		(start 100.71862 -223.119696)
		(mid 100.875597 -223.424496)
		(end 100.71862 -223.729296)
		(width 0.1143)
		(layer "In4.Cu")
		(net "P5E_CPU1_G1_RX_DP<10>")
	)
	(segment
		(start 100.967794 -233.410252)
		(end 100.500942 -233.144314)
		(width 0.12954)
		(layer "F.Cu")
		(net "P5E_CPU1_G1_RX_DP<11>")
	)
	(segment
		(start 26.485596 -6.99516)
		(end 26.215594 -6.725158)
		(width 0.12954)
		(layer "F.Cu")
		(net "P5E_CPU1_G1_RX_DP<11>")
	)
	(segment
		(start 26.485596 -7.57047)
		(end 26.485596 -6.99516)
		(width 0.12954)
		(layer "F.Cu")
		(net "P5E_CPU1_G1_RX_DP<11>")
	)
	(segment
		(start 26.346912 -8.320024)
		(end 26.346912 -7.709154)
		(width 0.12954)
		(layer "F.Cu")
		(net "P5E_CPU1_G1_RX_DP<11>")
	)
	(segment
		(start 26.346912 -7.709154)
		(end 26.485596 -7.57047)
		(width 0.12954)
		(layer "F.Cu")
		(net "P5E_CPU1_G1_RX_DP<11>")
	)
	(segment
		(start 42.61358 -46.962314)
		(end 51.100736 -56.855106)
		(width 0.14224)
		(layer "In4.Cu")
		(net "P5E_CPU1_G1_RX_DP<11>")
	)
	(segment
		(start 100.68941 -230.229156)
		(end 100.684838 -230.23195)
		(width 0.1143)
		(layer "In4.Cu")
		(net "P5E_CPU1_G1_RX_DP<11>")
	)
	(segment
		(start 99.271836 -222.288354)
		(end 99.272852 -222.288862)
		(width 0.1143)
		(layer "In4.Cu")
		(net "P5E_CPU1_G1_RX_DP<11>")
	)
	(segment
		(start 99.70897 -223.079056)
		(end 99.748086 -223.101916)
		(width 0.1143)
		(layer "In4.Cu")
		(net "P5E_CPU1_G1_RX_DP<11>")
	)
	(segment
		(start 99.275392 -222.290386)
		(end 99.276916 -222.291402)
		(width 0.1143)
		(layer "In4.Cu")
		(net "P5E_CPU1_G1_RX_DP<11>")
	)
	(segment
		(start 100.649024 -226.319334)
		(end 100.685092 -226.340162)
		(width 0.1143)
		(layer "In4.Cu")
		(net "P5E_CPU1_G1_RX_DP<11>")
	)
	(segment
		(start 99.26955 -222.287084)
		(end 99.271836 -222.288354)
		(width 0.1143)
		(layer "In4.Cu")
		(net "P5E_CPU1_G1_RX_DP<11>")
	)
	(segment
		(start 25.264618 -17.813782)
		(end 25.450546 -18.2626)
		(width 0.14224)
		(layer "In4.Cu")
		(net "P5E_CPU1_G1_RX_DP<11>")
	)
	(segment
		(start 26.215594 -6.725158)
		(end 26.506424 -7.015988)
		(width 0.14224)
		(layer "In4.Cu")
		(net "P5E_CPU1_G1_RX_DP<11>")
	)
	(segment
		(start 100.687886 -228.607112)
		(end 100.651564 -228.628194)
		(width 0.1143)
		(layer "In4.Cu")
		(net "P5E_CPU1_G1_RX_DP<11>")
	)
	(segment
		(start 98.904552 -214.801196)
		(end 98.904552 -221.259908)
		(width 0.14224)
		(layer "In4.Cu")
		(net "P5E_CPU1_G1_RX_DP<11>")
	)
	(segment
		(start 99.70897 -224.699068)
		(end 99.748086 -224.721928)
		(width 0.1143)
		(layer "In4.Cu")
		(net "P5E_CPU1_G1_RX_DP<11>")
	)
	(segment
		(start 100.688648 -227.96246)
		(end 100.719636 -227.98024)
		(width 0.1143)
		(layer "In4.Cu")
		(net "P5E_CPU1_G1_RX_DP<11>")
	)
	(segment
		(start 100.179632 -231.989376)
		(end 100.218494 -232.011982)
		(width 0.1143)
		(layer "In4.Cu")
		(net "P5E_CPU1_G1_RX_DP<11>")
	)
	(segment
		(start 100.719636 -228.588824)
		(end 100.689918 -228.605842)
		(width 0.1143)
		(layer "In4.Cu")
		(net "P5E_CPU1_G1_RX_DP<11>")
	)
	(segment
		(start 100.798884 -233.144314)
		(end 100.500942 -233.144314)
		(width 0.1143)
		(layer "In4.Cu")
		(net "P5E_CPU1_G1_RX_DP<11>")
	)
	(segment
		(start 147.837906 -147.4216)
		(end 148.62556 -160.004506)
		(width 0.14224)
		(layer "In4.Cu")
		(net "P5E_CPU1_G1_RX_DP<11>")
	)
	(segment
		(start 26.536904 -19.348958)
		(end 30.75813 -26.833068)
		(width 0.14224)
		(layer "In4.Cu")
		(net "P5E_CPU1_G1_RX_DP<11>")
	)
	(segment
		(start 105.95102 -202.933046)
		(end 98.904552 -214.801196)
		(width 0.14224)
		(layer "In4.Cu")
		(net "P5E_CPU1_G1_RX_DP<11>")
	)
	(segment
		(start 98.950272 -221.592902)
		(end 98.995738 -221.638368)
		(width 0.1143)
		(layer "In4.Cu")
		(net "P5E_CPU1_G1_RX_DP<11>")
	)
	(segment
		(start 98.904552 -221.259908)
		(end 98.904552 -221.288356)
		(width 0.1143)
		(layer "In4.Cu")
		(net "P5E_CPU1_G1_RX_DP<11>")
	)
	(segment
		(start 100.688648 -226.986592)
		(end 100.687886 -226.9871)
		(width 0.1143)
		(layer "In4.Cu")
		(net "P5E_CPU1_G1_RX_DP<11>")
	)
	(segment
		(start 100.400104 -232.327196)
		(end 100.400104 -232.329736)
		(width 0.1143)
		(layer "In4.Cu")
		(net "P5E_CPU1_G1_RX_DP<11>")
	)
	(segment
		(start 100.221542 -225.533966)
		(end 100.222304 -225.534474)
		(width 0.1143)
		(layer "In4.Cu")
		(net "P5E_CPU1_G1_RX_DP<11>")
	)
	(segment
		(start 100.689918 -226.98583)
		(end 100.688648 -226.986592)
		(width 0.1143)
		(layer "In4.Cu")
		(net "P5E_CPU1_G1_RX_DP<11>")
	)
	(segment
		(start 99.277932 -222.29191)
		(end 99.309682 -222.310198)
		(width 0.1143)
		(layer "In4.Cu")
		(net "P5E_CPU1_G1_RX_DP<11>")
	)
	(segment
		(start 100.217478 -225.531426)
		(end 100.217986 -225.531934)
		(width 0.1143)
		(layer "In4.Cu")
		(net "P5E_CPU1_G1_RX_DP<11>")
	)
	(segment
		(start 100.719382 -229.599998)
		(end 100.719636 -229.600252)
		(width 0.1143)
		(layer "In4.Cu")
		(net "P5E_CPU1_G1_RX_DP<11>")
	)
	(segment
		(start 100.685092 -226.340162)
		(end 100.687886 -226.34194)
		(width 0.1143)
		(layer "In4.Cu")
		(net "P5E_CPU1_G1_RX_DP<11>")
	)
	(segment
		(start 99.272852 -222.288862)
		(end 99.274376 -222.289878)
		(width 0.1143)
		(layer "In4.Cu")
		(net "P5E_CPU1_G1_RX_DP<11>")
	)
	(segment
		(start 52.58435 -58.189114)
		(end 54.807612 -60.014104)
		(width 0.14224)
		(layer "In4.Cu")
		(net "P5E_CPU1_G1_RX_DP<11>")
	)
	(segment
		(start 99.935538 -225.044508)
		(end 99.935792 -225.044508)
		(width 0.1143)
		(layer "In4.Cu")
		(net "P5E_CPU1_G1_RX_DP<11>")
	)
	(segment
		(start 30.75813 -26.833068)
		(end 42.61358 -46.962314)
		(width 0.14224)
		(layer "In4.Cu")
		(net "P5E_CPU1_G1_RX_DP<11>")
	)
	(segment
		(start 100.247704 -231.019858)
		(end 100.17887 -231.059736)
		(width 0.1143)
		(layer "In4.Cu")
		(net "P5E_CPU1_G1_RX_DP<11>")
	)
	(segment
		(start 100.222304 -225.534474)
		(end 100.223574 -225.535236)
		(width 0.1143)
		(layer "In4.Cu")
		(net "P5E_CPU1_G1_RX_DP<11>")
	)
	(segment
		(start 148.62556 -162.74161)
		(end 147.283678 -166.683182)
		(width 0.14224)
		(layer "In4.Cu")
		(net "P5E_CPU1_G1_RX_DP<11>")
	)
	(segment
		(start 26.506424 -7.015988)
		(end 26.506424 -11.113262)
		(width 0.14224)
		(layer "In4.Cu")
		(net "P5E_CPU1_G1_RX_DP<11>")
	)
	(segment
		(start 144.773904 -141.090904)
		(end 144.777968 -141.094714)
		(width 0.14224)
		(layer "In4.Cu")
		(net "P5E_CPU1_G1_RX_DP<11>")
	)
	(segment
		(start 100.689918 -228.605842)
		(end 100.688648 -228.606604)
		(width 0.1143)
		(layer "In4.Cu")
		(net "P5E_CPU1_G1_RX_DP<11>")
	)
	(segment
		(start 99.238816 -222.26905)
		(end 99.26955 -222.287084)
		(width 0.1143)
		(layer "In4.Cu")
		(net "P5E_CPU1_G1_RX_DP<11>")
	)
	(segment
		(start 144.62506 -140.78331)
		(end 144.773904 -141.090904)
		(width 0.14224)
		(layer "In4.Cu")
		(net "P5E_CPU1_G1_RX_DP<11>")
	)
	(segment
		(start 100.21951 -225.53295)
		(end 100.221542 -225.533966)
		(width 0.1143)
		(layer "In4.Cu")
		(net "P5E_CPU1_G1_RX_DP<11>")
	)
	(segment
		(start 100.687886 -227.961952)
		(end 100.688648 -227.96246)
		(width 0.1143)
		(layer "In4.Cu")
		(net "P5E_CPU1_G1_RX_DP<11>")
	)
	(segment
		(start 99.778566 -223.729296)
		(end 99.748086 -223.747076)
		(width 0.1143)
		(layer "In4.Cu")
		(net "P5E_CPU1_G1_RX_DP<11>")
	)
	(segment
		(start 99.276916 -222.291402)
		(end 99.277932 -222.29191)
		(width 0.1143)
		(layer "In4.Cu")
		(net "P5E_CPU1_G1_RX_DP<11>")
	)
	(segment
		(start 100.688648 -228.606604)
		(end 100.687886 -228.607112)
		(width 0.1143)
		(layer "In4.Cu")
		(net "P5E_CPU1_G1_RX_DP<11>")
	)
	(segment
		(start 144.016984 -171.746418)
		(end 105.95102 -202.933046)
		(width 0.14224)
		(layer "In4.Cu")
		(net "P5E_CPU1_G1_RX_DP<11>")
	)
	(segment
		(start 25.450546 -18.2626)
		(end 26.536904 -19.348958)
		(width 0.14224)
		(layer "In4.Cu")
		(net "P5E_CPU1_G1_RX_DP<11>")
	)
	(segment
		(start 99.748086 -224.721928)
		(end 99.778566 -224.739708)
		(width 0.1143)
		(layer "In4.Cu")
		(net "P5E_CPU1_G1_RX_DP<11>")
	)
	(segment
		(start 100.684584 -232.819956)
		(end 100.687124 -232.821226)
		(width 0.1143)
		(layer "In4.Cu")
		(net "P5E_CPU1_G1_RX_DP<11>")
	)
	(segment
		(start 51.100736 -56.855106)
		(end 52.58435 -58.189114)
		(width 0.14224)
		(layer "In4.Cu")
		(net "P5E_CPU1_G1_RX_DP<11>")
	)
	(segment
		(start 147.283678 -166.683182)
		(end 144.016984 -171.746418)
		(width 0.14224)
		(layer "In4.Cu")
		(net "P5E_CPU1_G1_RX_DP<11>")
	)
	(segment
		(start 99.748086 -223.747076)
		(end 99.70897 -223.769936)
		(width 0.1143)
		(layer "In4.Cu")
		(net "P5E_CPU1_G1_RX_DP<11>")
	)
	(segment
		(start 148.62556 -160.004506)
		(end 148.62556 -162.74161)
		(width 0.14224)
		(layer "In4.Cu")
		(net "P5E_CPU1_G1_RX_DP<11>")
	)
	(segment
		(start 100.687886 -226.9871)
		(end 100.651564 -227.008182)
		(width 0.1143)
		(layer "In4.Cu")
		(net "P5E_CPU1_G1_RX_DP<11>")
	)
	(segment
		(start 144.777968 -141.094714)
		(end 147.837906 -147.4216)
		(width 0.14224)
		(layer "In4.Cu")
		(net "P5E_CPU1_G1_RX_DP<11>")
	)
	(segment
		(start 98.950272 -221.334076)
		(end 98.950272 -221.592902)
		(width 0.1143)
		(layer "In4.Cu")
		(net "P5E_CPU1_G1_RX_DP<11>")
	)
	(segment
		(start 99.274376 -222.289878)
		(end 99.275392 -222.290386)
		(width 0.1143)
		(layer "In4.Cu")
		(net "P5E_CPU1_G1_RX_DP<11>")
	)
	(segment
		(start 100.687124 -232.821226)
		(end 100.688648 -232.822242)
		(width 0.1143)
		(layer "In4.Cu")
		(net "P5E_CPU1_G1_RX_DP<11>")
	)
	(segment
		(start 100.217986 -225.531934)
		(end 100.21951 -225.53295)
		(width 0.1143)
		(layer "In4.Cu")
		(net "P5E_CPU1_G1_RX_DP<11>")
	)
	(segment
		(start 100.651564 -227.94087)
		(end 100.687886 -227.961952)
		(width 0.1143)
		(layer "In4.Cu")
		(net "P5E_CPU1_G1_RX_DP<11>")
	)
	(segment
		(start 100.223574 -225.535236)
		(end 100.24745 -225.548952)
		(width 0.1143)
		(layer "In4.Cu")
		(net "P5E_CPU1_G1_RX_DP<11>")
	)
	(segment
		(start 100.688648 -232.822242)
		(end 100.719636 -232.840022)
		(width 0.1143)
		(layer "In4.Cu")
		(net "P5E_CPU1_G1_RX_DP<11>")
	)
	(segment
		(start 100.687886 -226.34194)
		(end 100.688648 -226.342448)
		(width 0.1143)
		(layer "In4.Cu")
		(net "P5E_CPU1_G1_RX_DP<11>")
	)
	(segment
		(start 100.651564 -229.560882)
		(end 100.719382 -229.599998)
		(width 0.1143)
		(layer "In4.Cu")
		(net "P5E_CPU1_G1_RX_DP<11>")
	)
	(segment
		(start 25.279096 -17.283176)
		(end 25.264618 -17.297654)
		(width 0.14224)
		(layer "In4.Cu")
		(net "P5E_CPU1_G1_RX_DP<11>")
	)
	(segment
		(start 100.868734 -233.074464)
		(end 100.798884 -233.144314)
		(width 0.1143)
		(layer "In4.Cu")
		(net "P5E_CPU1_G1_RX_DP<11>")
	)
	(segment
		(start 99.748086 -223.101916)
		(end 99.778566 -223.119696)
		(width 0.1143)
		(layer "In4.Cu")
		(net "P5E_CPU1_G1_RX_DP<11>")
	)
	(segment
		(start 100.688648 -226.342448)
		(end 100.719636 -226.360228)
		(width 0.1143)
		(layer "In4.Cu")
		(net "P5E_CPU1_G1_RX_DP<11>")
	)
	(segment
		(start 26.506424 -11.113262)
		(end 25.87879 -14.268196)
		(width 0.14224)
		(layer "In4.Cu")
		(net "P5E_CPU1_G1_RX_DP<11>")
	)
	(segment
		(start 25.87879 -14.268196)
		(end 25.279096 -17.283176)
		(width 0.14224)
		(layer "In4.Cu")
		(net "P5E_CPU1_G1_RX_DP<11>")
	)
	(segment
		(start 100.63861 -226.31146)
		(end 100.649024 -226.319334)
		(width 0.1143)
		(layer "In4.Cu")
		(net "P5E_CPU1_G1_RX_DP<11>")
	)
	(segment
		(start 100.405692 -225.854514)
		(end 100.405692 -225.861626)
		(width 0.1143)
		(layer "In4.Cu")
		(net "P5E_CPU1_G1_RX_DP<11>")
	)
	(segment
		(start 98.904552 -221.288356)
		(end 98.950272 -221.334076)
		(width 0.1143)
		(layer "In4.Cu")
		(net "P5E_CPU1_G1_RX_DP<11>")
	)
	(segment
		(start 54.807612 -60.014104)
		(end 144.62506 -140.78331)
		(width 0.14224)
		(layer "In4.Cu")
		(net "P5E_CPU1_G1_RX_DP<11>")
	)
	(segment
		(start 98.995738 -221.638368)
		(end 98.995738 -221.804484)
		(width 0.1143)
		(layer "In4.Cu")
		(net "P5E_CPU1_G1_RX_DP<11>")
	)
	(segment
		(start 25.264618 -17.297654)
		(end 25.264618 -17.813782)
		(width 0.14224)
		(layer "In4.Cu")
		(net "P5E_CPU1_G1_RX_DP<11>")
	)
	(segment
		(start 100.719636 -226.968812)
		(end 100.689918 -226.98583)
		(width 0.1143)
		(layer "In4.Cu")
		(net "P5E_CPU1_G1_RX_DP<11>")
	)
	(arc
		(start 100.218494 -232.011982)
		(mid 100.351414 -232.145329)
		(end 100.400104 -232.327196)
		(width 0.1143)
		(layer "In4.Cu")
		(net "P5E_CPU1_G1_RX_DP<11>")
	)
	(arc
		(start 100.719636 -226.360228)
		(mid 100.875564 -226.66452)
		(end 100.719636 -226.968812)
		(width 0.1143)
		(layer "In4.Cu")
		(net "P5E_CPU1_G1_RX_DP<11>")
	)
	(arc
		(start 100.405692 -229.094538)
		(mid 100.470928 -229.358129)
		(end 100.651564 -229.560882)
		(width 0.1143)
		(layer "In4.Cu")
		(net "P5E_CPU1_G1_RX_DP<11>")
	)
	(arc
		(start 99.778566 -224.739708)
		(mid 99.893993 -224.873084)
		(end 99.935538 -225.044508)
		(width 0.1143)
		(layer "In4.Cu")
		(net "P5E_CPU1_G1_RX_DP<11>")
	)
	(arc
		(start 100.17887 -231.988868)
		(mid 100.179251 -231.989122)
		(end 100.179632 -231.989376)
		(width 0.1143)
		(layer "In4.Cu")
		(net "P5E_CPU1_G1_RX_DP<11>")
	)
	(arc
		(start 100.684838 -230.23195)
		(mid 100.480514 -230.435795)
		(end 100.405692 -230.71455)
		(width 0.1143)
		(layer "In4.Cu")
		(net "P5E_CPU1_G1_RX_DP<11>")
	)
	(arc
		(start 100.719636 -232.840022)
		(mid 100.816771 -232.942891)
		(end 100.868734 -233.074464)
		(width 0.1143)
		(layer "In4.Cu")
		(net "P5E_CPU1_G1_RX_DP<11>")
	)
	(arc
		(start 99.104958 -222.139002)
		(mid 99.166477 -222.209596)
		(end 99.238816 -222.26905)
		(width 0.1143)
		(layer "In4.Cu")
		(net "P5E_CPU1_G1_RX_DP<11>")
	)
	(arc
		(start 100.17887 -231.059736)
		(mid 99.935543 -231.524302)
		(end 100.17887 -231.988868)
		(width 0.1143)
		(layer "In4.Cu")
		(net "P5E_CPU1_G1_RX_DP<11>")
	)
	(arc
		(start 99.935792 -225.044508)
		(mid 100.011294 -225.32576)
		(end 100.217478 -225.531426)
		(width 0.1143)
		(layer "In4.Cu")
		(net "P5E_CPU1_G1_RX_DP<11>")
	)
	(arc
		(start 99.778566 -223.119696)
		(mid 99.935543 -223.424496)
		(end 99.778566 -223.729296)
		(width 0.1143)
		(layer "In4.Cu")
		(net "P5E_CPU1_G1_RX_DP<11>")
	)
	(arc
		(start 99.70897 -223.769936)
		(mid 99.465643 -224.234502)
		(end 99.70897 -224.699068)
		(width 0.1143)
		(layer "In4.Cu")
		(net "P5E_CPU1_G1_RX_DP<11>")
	)
	(arc
		(start 100.405692 -225.861626)
		(mid 100.471894 -226.112559)
		(end 100.63861 -226.31146)
		(width 0.1143)
		(layer "In4.Cu")
		(net "P5E_CPU1_G1_RX_DP<11>")
	)
	(arc
		(start 99.465638 -222.61449)
		(mid 99.530153 -222.876709)
		(end 99.70897 -223.079056)
		(width 0.1143)
		(layer "In4.Cu")
		(net "P5E_CPU1_G1_RX_DP<11>")
	)
	(arc
		(start 98.995738 -221.804484)
		(mid 99.023654 -221.98046)
		(end 99.104958 -222.139002)
		(width 0.1143)
		(layer "In4.Cu")
		(net "P5E_CPU1_G1_RX_DP<11>")
	)
	(arc
		(start 100.635308 -228.639624)
		(mid 100.470641 -228.838231)
		(end 100.405692 -229.087934)
		(width 0.1143)
		(layer "In4.Cu")
		(net "P5E_CPU1_G1_RX_DP<11>")
	)
	(arc
		(start 100.719636 -227.98024)
		(mid 100.875564 -228.284532)
		(end 100.719636 -228.588824)
		(width 0.1143)
		(layer "In4.Cu")
		(net "P5E_CPU1_G1_RX_DP<11>")
	)
	(arc
		(start 100.63734 -227.930964)
		(mid 100.644413 -227.935973)
		(end 100.651564 -227.94087)
		(width 0.1143)
		(layer "In4.Cu")
		(net "P5E_CPU1_G1_RX_DP<11>")
	)
	(arc
		(start 100.719636 -229.600252)
		(mid 100.834479 -229.7334)
		(end 100.875846 -229.90429)
		(width 0.1143)
		(layer "In4.Cu")
		(net "P5E_CPU1_G1_RX_DP<11>")
	)
	(arc
		(start 100.875846 -229.90429)
		(mid 100.825918 -230.09156)
		(end 100.68941 -230.229156)
		(width 0.1143)
		(layer "In4.Cu")
		(net "P5E_CPU1_G1_RX_DP<11>")
	)
	(arc
		(start 100.400104 -232.329736)
		(mid 100.47632 -232.613157)
		(end 100.684584 -232.819956)
		(width 0.1143)
		(layer "In4.Cu")
		(net "P5E_CPU1_G1_RX_DP<11>")
	)
	(arc
		(start 100.405692 -229.087934)
		(mid 100.405682 -229.091236)
		(end 100.405692 -229.094538)
		(width 0.1143)
		(layer "In4.Cu")
		(net "P5E_CPU1_G1_RX_DP<11>")
	)
	(arc
		(start 100.651564 -227.008182)
		(mid 100.644414 -227.01308)
		(end 100.63734 -227.018088)
		(width 0.1143)
		(layer "In4.Cu")
		(net "P5E_CPU1_G1_RX_DP<11>")
	)
	(arc
		(start 100.24745 -225.548952)
		(mid 100.363723 -225.682492)
		(end 100.405692 -225.854514)
		(width 0.1143)
		(layer "In4.Cu")
		(net "P5E_CPU1_G1_RX_DP<11>")
	)
	(arc
		(start 100.405692 -230.71455)
		(mid 100.363813 -230.886419)
		(end 100.247704 -231.019858)
		(width 0.1143)
		(layer "In4.Cu")
		(net "P5E_CPU1_G1_RX_DP<11>")
	)
	(arc
		(start 100.63734 -227.018088)
		(mid 100.409957 -227.474526)
		(end 100.63734 -227.930964)
		(width 0.1143)
		(layer "In4.Cu")
		(net "P5E_CPU1_G1_RX_DP<11>")
	)
	(arc
		(start 99.309682 -222.310198)
		(mid 99.424358 -222.443532)
		(end 99.465638 -222.61449)
		(width 0.1143)
		(layer "In4.Cu")
		(net "P5E_CPU1_G1_RX_DP<11>")
	)
	(arc
		(start 100.651564 -228.628194)
		(mid 100.643386 -228.633837)
		(end 100.635308 -228.639624)
		(width 0.1143)
		(layer "In4.Cu")
		(net "P5E_CPU1_G1_RX_DP<11>")
	)
	(segment
		(start 24.685752 -5.228844)
		(end 24.685752 -7.57047)
		(width 0.12954)
		(layer "F.Cu")
		(net "P5E_CPU1_G1_RX_DP<12>")
	)
	(segment
		(start 24.420322 -4.963414)
		(end 24.685752 -5.228844)
		(width 0.12954)
		(layer "F.Cu")
		(net "P5E_CPU1_G1_RX_DP<12>")
	)
	(segment
		(start 24.685752 -7.57047)
		(end 24.547068 -7.709154)
		(width 0.12954)
		(layer "F.Cu")
		(net "P5E_CPU1_G1_RX_DP<12>")
	)
	(segment
		(start 100.967794 -235.030264)
		(end 100.500942 -234.764326)
		(width 0.12954)
		(layer "F.Cu")
		(net "P5E_CPU1_G1_RX_DP<12>")
	)
	(segment
		(start 24.547068 -7.709154)
		(end 24.547068 -8.320024)
		(width 0.12954)
		(layer "F.Cu")
		(net "P5E_CPU1_G1_RX_DP<12>")
	)
	(segment
		(start 98.005392 -221.334076)
		(end 98.005392 -221.592902)
		(width 0.1143)
		(layer "In4.Cu")
		(net "P5E_CPU1_G1_RX_DP<12>")
	)
	(segment
		(start 146.361404 -166.376096)
		(end 143.26362 -171.156884)
		(width 0.14224)
		(layer "In4.Cu")
		(net "P5E_CPU1_G1_RX_DP<12>")
	)
	(segment
		(start 26.640028 -25.27935)
		(end 27.608276 -26.69159)
		(width 0.14224)
		(layer "In4.Cu")
		(net "P5E_CPU1_G1_RX_DP<12>")
	)
	(segment
		(start 23.653496 -16.5354)
		(end 23.123652 -17.815052)
		(width 0.14224)
		(layer "In4.Cu")
		(net "P5E_CPU1_G1_RX_DP<12>")
	)
	(segment
		(start 99.245674 -225.513138)
		(end 99.246436 -225.513646)
		(width 0.1143)
		(layer "In4.Cu")
		(net "P5E_CPU1_G1_RX_DP<12>")
	)
	(segment
		(start 99.778566 -228.589332)
		(end 99.748086 -228.607112)
		(width 0.1143)
		(layer "In4.Cu")
		(net "P5E_CPU1_G1_RX_DP<12>")
	)
	(segment
		(start 98.055684 -221.643194)
		(end 98.055684 -221.804484)
		(width 0.1143)
		(layer "In4.Cu")
		(net "P5E_CPU1_G1_RX_DP<12>")
	)
	(segment
		(start 50.480976 -57.669176)
		(end 54.199536 -60.721494)
		(width 0.14224)
		(layer "In4.Cu")
		(net "P5E_CPU1_G1_RX_DP<12>")
	)
	(segment
		(start 97.959672 -221.288356)
		(end 98.005392 -221.334076)
		(width 0.1143)
		(layer "In4.Cu")
		(net "P5E_CPU1_G1_RX_DP<12>")
	)
	(segment
		(start 22.44979 -19.06016)
		(end 22.44979 -19.223482)
		(width 0.14224)
		(layer "In4.Cu")
		(net "P5E_CPU1_G1_RX_DP<12>")
	)
	(segment
		(start 24.711152 -5.254244)
		(end 24.711152 -11.219434)
		(width 0.14224)
		(layer "In4.Cu")
		(net "P5E_CPU1_G1_RX_DP<12>")
	)
	(segment
		(start 99.273614 -225.529394)
		(end 99.274376 -225.529902)
		(width 0.1143)
		(layer "In4.Cu")
		(net "P5E_CPU1_G1_RX_DP<12>")
	)
	(segment
		(start 100.798884 -234.764326)
		(end 100.500942 -234.764326)
		(width 0.1143)
		(layer "In4.Cu")
		(net "P5E_CPU1_G1_RX_DP<12>")
	)
	(segment
		(start 98.301556 -222.270828)
		(end 98.369628 -222.310198)
		(width 0.1143)
		(layer "In4.Cu")
		(net "P5E_CPU1_G1_RX_DP<12>")
	)
	(segment
		(start 22.478238 -18.91665)
		(end 22.468332 -18.965926)
		(width 0.14224)
		(layer "In4.Cu")
		(net "P5E_CPU1_G1_RX_DP<12>")
	)
	(segment
		(start 147.63242 -162.616896)
		(end 146.361404 -166.376096)
		(width 0.14224)
		(layer "In4.Cu")
		(net "P5E_CPU1_G1_RX_DP<12>")
	)
	(segment
		(start 99.279964 -225.533204)
		(end 99.309682 -225.550222)
		(width 0.1143)
		(layer "In4.Cu")
		(net "P5E_CPU1_G1_RX_DP<12>")
	)
	(segment
		(start 99.748086 -229.581964)
		(end 99.780598 -229.60076)
		(width 0.1143)
		(layer "In4.Cu")
		(net "P5E_CPU1_G1_RX_DP<12>")
	)
	(segment
		(start 100.868734 -234.694476)
		(end 100.798884 -234.764326)
		(width 0.1143)
		(layer "In4.Cu")
		(net "P5E_CPU1_G1_RX_DP<12>")
	)
	(segment
		(start 24.180546 -22.122384)
		(end 25.41016 -23.70074)
		(width 0.14224)
		(layer "In4.Cu")
		(net "P5E_CPU1_G1_RX_DP<12>")
	)
	(segment
		(start 98.808032 -223.101916)
		(end 98.838512 -223.119696)
		(width 0.1143)
		(layer "In4.Cu")
		(net "P5E_CPU1_G1_RX_DP<12>")
	)
	(segment
		(start 146.851878 -147.573492)
		(end 147.63242 -160.035748)
		(width 0.14224)
		(layer "In4.Cu")
		(net "P5E_CPU1_G1_RX_DP<12>")
	)
	(segment
		(start 99.277932 -225.531934)
		(end 99.278694 -225.532442)
		(width 0.1143)
		(layer "In4.Cu")
		(net "P5E_CPU1_G1_RX_DP<12>")
	)
	(segment
		(start 100.688648 -234.442254)
		(end 100.689918 -234.443016)
		(width 0.1143)
		(layer "In4.Cu")
		(net "P5E_CPU1_G1_RX_DP<12>")
	)
	(segment
		(start 143.872204 -141.375384)
		(end 146.836638 -147.504658)
		(width 0.14224)
		(layer "In4.Cu")
		(net "P5E_CPU1_G1_RX_DP<12>")
	)
	(segment
		(start 22.606 -19.908774)
		(end 24.180546 -22.122384)
		(width 0.14224)
		(layer "In4.Cu")
		(net "P5E_CPU1_G1_RX_DP<12>")
	)
	(segment
		(start 147.63242 -161.621978)
		(end 147.632674 -161.622232)
		(width 0.14224)
		(layer "In4.Cu")
		(net "P5E_CPU1_G1_RX_DP<12>")
	)
	(segment
		(start 98.005392 -221.592902)
		(end 98.055684 -221.643194)
		(width 0.1143)
		(layer "In4.Cu")
		(net "P5E_CPU1_G1_RX_DP<12>")
	)
	(segment
		(start 99.246436 -225.513646)
		(end 99.273614 -225.529394)
		(width 0.1143)
		(layer "In4.Cu")
		(net "P5E_CPU1_G1_RX_DP<12>")
	)
	(segment
		(start 97.959672 -214.469218)
		(end 97.959672 -221.259908)
		(width 0.14224)
		(layer "In4.Cu")
		(net "P5E_CPU1_G1_RX_DP<12>")
	)
	(segment
		(start 99.246436 -231.99344)
		(end 99.273614 -232.009188)
		(width 0.1143)
		(layer "In4.Cu")
		(net "P5E_CPU1_G1_RX_DP<12>")
	)
	(segment
		(start 27.705812 -26.832814)
		(end 27.70632 -26.834084)
		(width 0.14224)
		(layer "In4.Cu")
		(net "P5E_CPU1_G1_RX_DP<12>")
	)
	(segment
		(start 143.839946 -141.346174)
		(end 143.872204 -141.375384)
		(width 0.14224)
		(layer "In4.Cu")
		(net "P5E_CPU1_G1_RX_DP<12>")
	)
	(segment
		(start 99.748086 -227.961952)
		(end 99.778566 -227.979732)
		(width 0.1143)
		(layer "In4.Cu")
		(net "P5E_CPU1_G1_RX_DP<12>")
	)
	(segment
		(start 22.44979 -19.223482)
		(end 22.606 -19.908774)
		(width 0.14224)
		(layer "In4.Cu")
		(net "P5E_CPU1_G1_RX_DP<12>")
	)
	(segment
		(start 99.238816 -231.988868)
		(end 99.245674 -231.992932)
		(width 0.1143)
		(layer "In4.Cu")
		(net "P5E_CPU1_G1_RX_DP<12>")
	)
	(segment
		(start 105.063798 -202.440794)
		(end 97.959672 -214.469218)
		(width 0.14224)
		(layer "In4.Cu")
		(net "P5E_CPU1_G1_RX_DP<12>")
	)
	(segment
		(start 22.468332 -18.965926)
		(end 22.468332 -18.966688)
		(width 0.14224)
		(layer "In4.Cu")
		(net "P5E_CPU1_G1_RX_DP<12>")
	)
	(segment
		(start 143.827246 -141.320266)
		(end 143.839946 -141.346174)
		(width 0.14224)
		(layer "In4.Cu")
		(net "P5E_CPU1_G1_RX_DP<12>")
	)
	(segment
		(start 99.279964 -232.012998)
		(end 99.309682 -232.030016)
		(width 0.1143)
		(layer "In4.Cu")
		(net "P5E_CPU1_G1_RX_DP<12>")
	)
	(segment
		(start 99.276916 -232.01122)
		(end 99.277932 -232.011728)
		(width 0.1143)
		(layer "In4.Cu")
		(net "P5E_CPU1_G1_RX_DP<12>")
	)
	(segment
		(start 24.420322 -4.963414)
		(end 24.711152 -5.254244)
		(width 0.14224)
		(layer "In4.Cu")
		(net "P5E_CPU1_G1_RX_DP<12>")
	)
	(segment
		(start 24.711152 -11.219434)
		(end 23.653496 -16.5354)
		(width 0.14224)
		(layer "In4.Cu")
		(net "P5E_CPU1_G1_RX_DP<12>")
	)
	(segment
		(start 22.901656 -18.229834)
		(end 22.536658 -18.77568)
		(width 0.14224)
		(layer "In4.Cu")
		(net "P5E_CPU1_G1_RX_DP<12>")
	)
	(segment
		(start 22.468332 -18.966688)
		(end 22.44979 -19.06016)
		(width 0.14224)
		(layer "In4.Cu")
		(net "P5E_CPU1_G1_RX_DP<12>")
	)
	(segment
		(start 99.748086 -226.34194)
		(end 99.778566 -226.35972)
		(width 0.1143)
		(layer "In4.Cu")
		(net "P5E_CPU1_G1_RX_DP<12>")
	)
	(segment
		(start 97.959672 -221.259908)
		(end 97.959672 -221.288356)
		(width 0.1143)
		(layer "In4.Cu")
		(net "P5E_CPU1_G1_RX_DP<12>")
	)
	(segment
		(start 100.418392 -233.963972)
		(end 100.418392 -233.973624)
		(width 0.1143)
		(layer "In4.Cu")
		(net "P5E_CPU1_G1_RX_DP<12>")
	)
	(segment
		(start 99.278694 -225.532442)
		(end 99.279964 -225.533204)
		(width 0.1143)
		(layer "In4.Cu")
		(net "P5E_CPU1_G1_RX_DP<12>")
	)
	(segment
		(start 98.768916 -224.699068)
		(end 98.808032 -224.721928)
		(width 0.1143)
		(layer "In4.Cu")
		(net "P5E_CPU1_G1_RX_DP<12>")
	)
	(segment
		(start 99.273614 -232.009188)
		(end 99.274376 -232.009696)
		(width 0.1143)
		(layer "In4.Cu")
		(net "P5E_CPU1_G1_RX_DP<12>")
	)
	(segment
		(start 99.274376 -232.009696)
		(end 99.276916 -232.01122)
		(width 0.1143)
		(layer "In4.Cu")
		(net "P5E_CPU1_G1_RX_DP<12>")
	)
	(segment
		(start 99.70897 -229.559104)
		(end 99.748086 -229.581964)
		(width 0.1143)
		(layer "In4.Cu")
		(net "P5E_CPU1_G1_RX_DP<12>")
	)
	(segment
		(start 100.687886 -234.441746)
		(end 100.688648 -234.442254)
		(width 0.1143)
		(layer "In4.Cu")
		(net "P5E_CPU1_G1_RX_DP<12>")
	)
	(segment
		(start 98.30054 -222.27032)
		(end 98.301556 -222.270828)
		(width 0.1143)
		(layer "In4.Cu")
		(net "P5E_CPU1_G1_RX_DP<12>")
	)
	(segment
		(start 99.70897 -232.798874)
		(end 99.748086 -232.821734)
		(width 0.1143)
		(layer "In4.Cu")
		(net "P5E_CPU1_G1_RX_DP<12>")
	)
	(segment
		(start 99.748086 -232.821734)
		(end 99.778566 -232.839514)
		(width 0.1143)
		(layer "In4.Cu")
		(net "P5E_CPU1_G1_RX_DP<12>")
	)
	(segment
		(start 99.245674 -231.992932)
		(end 99.246436 -231.99344)
		(width 0.1143)
		(layer "In4.Cu")
		(net "P5E_CPU1_G1_RX_DP<12>")
	)
	(segment
		(start 147.632674 -162.616896)
		(end 147.63242 -162.616896)
		(width 0.14224)
		(layer "In4.Cu")
		(net "P5E_CPU1_G1_RX_DP<12>")
	)
	(segment
		(start 27.708098 -26.836624)
		(end 40.445944 -46.449234)
		(width 0.14224)
		(layer "In4.Cu")
		(net "P5E_CPU1_G1_RX_DP<12>")
	)
	(segment
		(start 40.445944 -46.449234)
		(end 50.480976 -57.669176)
		(width 0.14224)
		(layer "In4.Cu")
		(net "P5E_CPU1_G1_RX_DP<12>")
	)
	(segment
		(start 99.748086 -226.9871)
		(end 99.70897 -227.00996)
		(width 0.1143)
		(layer "In4.Cu")
		(net "P5E_CPU1_G1_RX_DP<12>")
	)
	(segment
		(start 98.808032 -223.747076)
		(end 98.768916 -223.769936)
		(width 0.1143)
		(layer "In4.Cu")
		(net "P5E_CPU1_G1_RX_DP<12>")
	)
	(segment
		(start 27.608276 -26.69159)
		(end 27.62504 -26.7081)
		(width 0.14224)
		(layer "In4.Cu")
		(net "P5E_CPU1_G1_RX_DP<12>")
	)
	(segment
		(start 147.63242 -160.035748)
		(end 147.63242 -161.621978)
		(width 0.14224)
		(layer "In4.Cu")
		(net "P5E_CPU1_G1_RX_DP<12>")
	)
	(segment
		(start 22.536658 -18.77568)
		(end 22.478238 -18.91665)
		(width 0.14224)
		(layer "In4.Cu")
		(net "P5E_CPU1_G1_RX_DP<12>")
	)
	(segment
		(start 99.274376 -225.529902)
		(end 99.276916 -225.531426)
		(width 0.1143)
		(layer "In4.Cu")
		(net "P5E_CPU1_G1_RX_DP<12>")
	)
	(segment
		(start 23.123652 -17.815052)
		(end 22.901656 -18.229834)
		(width 0.14224)
		(layer "In4.Cu")
		(net "P5E_CPU1_G1_RX_DP<12>")
	)
	(segment
		(start 99.778566 -226.96932)
		(end 99.748086 -226.9871)
		(width 0.1143)
		(layer "In4.Cu")
		(net "P5E_CPU1_G1_RX_DP<12>")
	)
	(segment
		(start 99.277932 -231.036876)
		(end 99.238816 -231.059736)
		(width 0.1143)
		(layer "In4.Cu")
		(net "P5E_CPU1_G1_RX_DP<12>")
	)
	(segment
		(start 99.70897 -227.939092)
		(end 99.748086 -227.961952)
		(width 0.1143)
		(layer "In4.Cu")
		(net "P5E_CPU1_G1_RX_DP<12>")
	)
	(segment
		(start 98.808032 -224.721928)
		(end 98.838512 -224.739708)
		(width 0.1143)
		(layer "In4.Cu")
		(net "P5E_CPU1_G1_RX_DP<12>")
	)
	(segment
		(start 98.299524 -222.269558)
		(end 98.30054 -222.27032)
		(width 0.1143)
		(layer "In4.Cu")
		(net "P5E_CPU1_G1_RX_DP<12>")
	)
	(segment
		(start 27.62504 -26.7081)
		(end 27.705812 -26.832814)
		(width 0.14224)
		(layer "In4.Cu")
		(net "P5E_CPU1_G1_RX_DP<12>")
	)
	(segment
		(start 143.26362 -171.156884)
		(end 105.063798 -202.440794)
		(width 0.14224)
		(layer "In4.Cu")
		(net "P5E_CPU1_G1_RX_DP<12>")
	)
	(segment
		(start 54.199536 -60.721494)
		(end 143.827246 -141.320266)
		(width 0.14224)
		(layer "In4.Cu")
		(net "P5E_CPU1_G1_RX_DP<12>")
	)
	(segment
		(start 27.70632 -26.834084)
		(end 27.708098 -26.836624)
		(width 0.14224)
		(layer "In4.Cu")
		(net "P5E_CPU1_G1_RX_DP<12>")
	)
	(segment
		(start 100.17887 -233.60888)
		(end 100.230686 -233.639106)
		(width 0.1143)
		(layer "In4.Cu")
		(net "P5E_CPU1_G1_RX_DP<12>")
	)
	(segment
		(start 99.778566 -230.20909)
		(end 99.71151 -230.248206)
		(width 0.1143)
		(layer "In4.Cu")
		(net "P5E_CPU1_G1_RX_DP<12>")
	)
	(segment
		(start 99.748086 -228.607112)
		(end 99.70897 -228.629972)
		(width 0.1143)
		(layer "In4.Cu")
		(net "P5E_CPU1_G1_RX_DP<12>")
	)
	(segment
		(start 147.632674 -161.622232)
		(end 147.632674 -162.616896)
		(width 0.14224)
		(layer "In4.Cu")
		(net "P5E_CPU1_G1_RX_DP<12>")
	)
	(segment
		(start 99.277932 -232.011728)
		(end 99.278694 -232.012236)
		(width 0.1143)
		(layer "In4.Cu")
		(net "P5E_CPU1_G1_RX_DP<12>")
	)
	(segment
		(start 99.31146 -231.017318)
		(end 99.277932 -231.036876)
		(width 0.1143)
		(layer "In4.Cu")
		(net "P5E_CPU1_G1_RX_DP<12>")
	)
	(segment
		(start 98.768916 -223.079056)
		(end 98.808032 -223.101916)
		(width 0.1143)
		(layer "In4.Cu")
		(net "P5E_CPU1_G1_RX_DP<12>")
	)
	(segment
		(start 99.278694 -232.012236)
		(end 99.279964 -232.012998)
		(width 0.1143)
		(layer "In4.Cu")
		(net "P5E_CPU1_G1_RX_DP<12>")
	)
	(segment
		(start 99.70897 -226.31908)
		(end 99.748086 -226.34194)
		(width 0.1143)
		(layer "In4.Cu")
		(net "P5E_CPU1_G1_RX_DP<12>")
	)
	(segment
		(start 98.838512 -223.729296)
		(end 98.808032 -223.747076)
		(width 0.1143)
		(layer "In4.Cu")
		(net "P5E_CPU1_G1_RX_DP<12>")
	)
	(segment
		(start 99.276916 -225.531426)
		(end 99.277932 -225.531934)
		(width 0.1143)
		(layer "In4.Cu")
		(net "P5E_CPU1_G1_RX_DP<12>")
	)
	(segment
		(start 25.41016 -23.70074)
		(end 26.640028 -25.27935)
		(width 0.14224)
		(layer "In4.Cu")
		(net "P5E_CPU1_G1_RX_DP<12>")
	)
	(segment
		(start 100.689918 -234.443016)
		(end 100.719636 -234.460034)
		(width 0.1143)
		(layer "In4.Cu")
		(net "P5E_CPU1_G1_RX_DP<12>")
	)
	(segment
		(start 146.836638 -147.504658)
		(end 146.839432 -147.547584)
		(width 0.14224)
		(layer "In4.Cu")
		(net "P5E_CPU1_G1_RX_DP<12>")
	)
	(segment
		(start 146.839432 -147.547584)
		(end 146.851878 -147.573492)
		(width 0.14224)
		(layer "In4.Cu")
		(net "P5E_CPU1_G1_RX_DP<12>")
	)
	(segment
		(start 99.238816 -225.509074)
		(end 99.245674 -225.513138)
		(width 0.1143)
		(layer "In4.Cu")
		(net "P5E_CPU1_G1_RX_DP<12>")
	)
	(arc
		(start 98.055684 -221.804484)
		(mid 98.120343 -222.067041)
		(end 98.299524 -222.269558)
		(width 0.1143)
		(layer "In4.Cu")
		(net "P5E_CPU1_G1_RX_DP<12>")
	)
	(arc
		(start 98.525584 -222.61449)
		(mid 98.590099 -222.876709)
		(end 98.768916 -223.079056)
		(width 0.1143)
		(layer "In4.Cu")
		(net "P5E_CPU1_G1_RX_DP<12>")
	)
	(arc
		(start 98.838512 -224.739708)
		(mid 98.953939 -224.873084)
		(end 98.995484 -225.044508)
		(width 0.1143)
		(layer "In4.Cu")
		(net "P5E_CPU1_G1_RX_DP<12>")
	)
	(arc
		(start 99.465638 -230.71455)
		(mid 99.424876 -230.884434)
		(end 99.31146 -231.017318)
		(width 0.1143)
		(layer "In4.Cu")
		(net "P5E_CPU1_G1_RX_DP<12>")
	)
	(arc
		(start 100.230686 -233.639106)
		(mid 100.368118 -233.776365)
		(end 100.418392 -233.963972)
		(width 0.1143)
		(layer "In4.Cu")
		(net "P5E_CPU1_G1_RX_DP<12>")
	)
	(arc
		(start 98.838512 -223.119696)
		(mid 98.995489 -223.424496)
		(end 98.838512 -223.729296)
		(width 0.1143)
		(layer "In4.Cu")
		(net "P5E_CPU1_G1_RX_DP<12>")
	)
	(arc
		(start 98.768916 -223.769936)
		(mid 98.525589 -224.234502)
		(end 98.768916 -224.699068)
		(width 0.1143)
		(layer "In4.Cu")
		(net "P5E_CPU1_G1_RX_DP<12>")
	)
	(arc
		(start 99.70897 -228.629972)
		(mid 99.465643 -229.094538)
		(end 99.70897 -229.559104)
		(width 0.1143)
		(layer "In4.Cu")
		(net "P5E_CPU1_G1_RX_DP<12>")
	)
	(arc
		(start 99.778566 -232.839514)
		(mid 99.893993 -232.97289)
		(end 99.935538 -233.144314)
		(width 0.1143)
		(layer "In4.Cu")
		(net "P5E_CPU1_G1_RX_DP<12>")
	)
	(arc
		(start 99.935538 -233.144314)
		(mid 100.000053 -233.406533)
		(end 100.17887 -233.60888)
		(width 0.1143)
		(layer "In4.Cu")
		(net "P5E_CPU1_G1_RX_DP<12>")
	)
	(arc
		(start 99.465638 -225.854514)
		(mid 99.530153 -226.116733)
		(end 99.70897 -226.31908)
		(width 0.1143)
		(layer "In4.Cu")
		(net "P5E_CPU1_G1_RX_DP<12>")
	)
	(arc
		(start 99.778566 -226.35972)
		(mid 99.935543 -226.66452)
		(end 99.778566 -226.96932)
		(width 0.1143)
		(layer "In4.Cu")
		(net "P5E_CPU1_G1_RX_DP<12>")
	)
	(arc
		(start 99.70897 -227.00996)
		(mid 99.465643 -227.474526)
		(end 99.70897 -227.939092)
		(width 0.1143)
		(layer "In4.Cu")
		(net "P5E_CPU1_G1_RX_DP<12>")
	)
	(arc
		(start 99.71151 -230.248206)
		(mid 99.530858 -230.450951)
		(end 99.465638 -230.71455)
		(width 0.1143)
		(layer "In4.Cu")
		(net "P5E_CPU1_G1_RX_DP<12>")
	)
	(arc
		(start 99.238816 -231.059736)
		(mid 98.995489 -231.524302)
		(end 99.238816 -231.988868)
		(width 0.1143)
		(layer "In4.Cu")
		(net "P5E_CPU1_G1_RX_DP<12>")
	)
	(arc
		(start 100.418392 -233.973624)
		(mid 100.490582 -234.243695)
		(end 100.687886 -234.441746)
		(width 0.1143)
		(layer "In4.Cu")
		(net "P5E_CPU1_G1_RX_DP<12>")
	)
	(arc
		(start 99.778566 -227.979732)
		(mid 99.935543 -228.284532)
		(end 99.778566 -228.589332)
		(width 0.1143)
		(layer "In4.Cu")
		(net "P5E_CPU1_G1_RX_DP<12>")
	)
	(arc
		(start 99.780598 -229.60076)
		(mid 99.894527 -229.733907)
		(end 99.935538 -229.90429)
		(width 0.1143)
		(layer "In4.Cu")
		(net "P5E_CPU1_G1_RX_DP<12>")
	)
	(arc
		(start 99.309682 -232.030016)
		(mid 99.424358 -232.16335)
		(end 99.465638 -232.334308)
		(width 0.1143)
		(layer "In4.Cu")
		(net "P5E_CPU1_G1_RX_DP<12>")
	)
	(arc
		(start 98.369628 -222.310198)
		(mid 98.484304 -222.443532)
		(end 98.525584 -222.61449)
		(width 0.1143)
		(layer "In4.Cu")
		(net "P5E_CPU1_G1_RX_DP<12>")
	)
	(arc
		(start 100.719636 -234.460034)
		(mid 100.816771 -234.562903)
		(end 100.868734 -234.694476)
		(width 0.1143)
		(layer "In4.Cu")
		(net "P5E_CPU1_G1_RX_DP<12>")
	)
	(arc
		(start 99.309682 -225.550222)
		(mid 99.424358 -225.683556)
		(end 99.465638 -225.854514)
		(width 0.1143)
		(layer "In4.Cu")
		(net "P5E_CPU1_G1_RX_DP<12>")
	)
	(arc
		(start 98.995484 -225.044508)
		(mid 99.059999 -225.306727)
		(end 99.238816 -225.509074)
		(width 0.1143)
		(layer "In4.Cu")
		(net "P5E_CPU1_G1_RX_DP<12>")
	)
	(arc
		(start 99.465638 -232.334308)
		(mid 99.530153 -232.596527)
		(end 99.70897 -232.798874)
		(width 0.1143)
		(layer "In4.Cu")
		(net "P5E_CPU1_G1_RX_DP<12>")
	)
	(arc
		(start 99.935538 -229.90429)
		(mid 99.893989 -230.075712)
		(end 99.778566 -230.20909)
		(width 0.1143)
		(layer "In4.Cu")
		(net "P5E_CPU1_G1_RX_DP<12>")
	)
	(segment
		(start 22.74697 -7.709154)
		(end 22.885654 -7.57047)
		(width 0.12954)
		(layer "F.Cu")
		(net "P5E_CPU1_G1_RX_DP<13>")
	)
	(segment
		(start 22.885654 -7.57047)
		(end 22.885654 -6.99516)
		(width 0.12954)
		(layer "F.Cu")
		(net "P5E_CPU1_G1_RX_DP<13>")
	)
	(segment
		(start 22.74697 -8.320024)
		(end 22.74697 -7.709154)
		(width 0.12954)
		(layer "F.Cu")
		(net "P5E_CPU1_G1_RX_DP<13>")
	)
	(segment
		(start 98.147886 -236.650276)
		(end 97.681034 -236.384338)
		(width 0.12954)
		(layer "F.Cu")
		(net "P5E_CPU1_G1_RX_DP<13>")
	)
	(segment
		(start 22.885654 -6.99516)
		(end 22.615652 -6.725158)
		(width 0.12954)
		(layer "F.Cu")
		(net "P5E_CPU1_G1_RX_DP<13>")
	)
	(segment
		(start 143.11249 -141.946376)
		(end 145.917412 -147.745704)
		(width 0.14224)
		(layer "In4.Cu")
		(net "P5E_CPU1_G1_RX_DP<13>")
	)
	(segment
		(start 98.808794 -228.606604)
		(end 98.808032 -228.607112)
		(width 0.1143)
		(layer "In4.Cu")
		(net "P5E_CPU1_G1_RX_DP<13>")
	)
	(segment
		(start 98.808794 -232.822242)
		(end 98.839782 -232.840022)
		(width 0.1143)
		(layer "In4.Cu")
		(net "P5E_CPU1_G1_RX_DP<13>")
	)
	(segment
		(start 98.808794 -235.086398)
		(end 98.808032 -235.086906)
		(width 0.1143)
		(layer "In4.Cu")
		(net "P5E_CPU1_G1_RX_DP<13>")
	)
	(segment
		(start 98.839782 -228.588824)
		(end 98.82251 -228.598476)
		(width 0.1143)
		(layer "In4.Cu")
		(net "P5E_CPU1_G1_RX_DP<13>")
	)
	(segment
		(start 145.917412 -147.745704)
		(end 146.689318 -160.065466)
		(width 0.14224)
		(layer "In4.Cu")
		(net "P5E_CPU1_G1_RX_DP<13>")
	)
	(segment
		(start 97.060512 -221.334076)
		(end 97.060512 -221.592902)
		(width 0.1143)
		(layer "In4.Cu")
		(net "P5E_CPU1_G1_RX_DP<13>")
	)
	(segment
		(start 97.115884 -221.648274)
		(end 97.115884 -221.804484)
		(width 0.1143)
		(layer "In4.Cu")
		(net "P5E_CPU1_G1_RX_DP<13>")
	)
	(segment
		(start 98.808032 -229.581964)
		(end 98.84156 -229.601522)
		(width 0.1143)
		(layer "In4.Cu")
		(net "P5E_CPU1_G1_RX_DP<13>")
	)
	(segment
		(start 98.802952 -234.438698)
		(end 98.804476 -234.439714)
		(width 0.1143)
		(layer "In4.Cu")
		(net "P5E_CPU1_G1_RX_DP<13>")
	)
	(segment
		(start 98.80346 -233.469688)
		(end 98.768916 -233.489754)
		(width 0.1143)
		(layer "In4.Cu")
		(net "P5E_CPU1_G1_RX_DP<13>")
	)
	(segment
		(start 19.647916 -17.822672)
		(end 20.461478 -19.039586)
		(width 0.14224)
		(layer "In4.Cu")
		(net "P5E_CPU1_G1_RX_DP<13>")
	)
	(segment
		(start 98.807016 -235.087414)
		(end 98.805746 -235.088176)
		(width 0.1143)
		(layer "In4.Cu")
		(net "P5E_CPU1_G1_RX_DP<13>")
	)
	(segment
		(start 98.817938 -228.60127)
		(end 98.81616 -228.602286)
		(width 0.1143)
		(layer "In4.Cu")
		(net "P5E_CPU1_G1_RX_DP<13>")
	)
	(segment
		(start 98.808794 -234.442254)
		(end 98.839782 -234.460034)
		(width 0.1143)
		(layer "In4.Cu")
		(net "P5E_CPU1_G1_RX_DP<13>")
	)
	(segment
		(start 98.812858 -233.4641)
		(end 98.811588 -233.464862)
		(width 0.1143)
		(layer "In4.Cu")
		(net "P5E_CPU1_G1_RX_DP<13>")
	)
	(segment
		(start 98.808794 -227.96246)
		(end 98.839782 -227.98024)
		(width 0.1143)
		(layer "In4.Cu")
		(net "P5E_CPU1_G1_RX_DP<13>")
	)
	(segment
		(start 98.810064 -235.085636)
		(end 98.808794 -235.086398)
		(width 0.1143)
		(layer "In4.Cu")
		(net "P5E_CPU1_G1_RX_DP<13>")
	)
	(segment
		(start 97.879916 -223.739964)
		(end 97.877884 -223.741234)
		(width 0.1143)
		(layer "In4.Cu")
		(net "P5E_CPU1_G1_RX_DP<13>")
	)
	(segment
		(start 98.801936 -232.818178)
		(end 98.802952 -232.818686)
		(width 0.1143)
		(layer "In4.Cu")
		(net "P5E_CPU1_G1_RX_DP<13>")
	)
	(segment
		(start 98.804476 -227.95992)
		(end 98.805492 -227.960428)
		(width 0.1143)
		(layer "In4.Cu")
		(net "P5E_CPU1_G1_RX_DP<13>")
	)
	(segment
		(start 98.370644 -231.01808)
		(end 98.338132 -231.036876)
		(width 0.1143)
		(layer "In4.Cu")
		(net "P5E_CPU1_G1_RX_DP<13>")
	)
	(segment
		(start 98.768916 -234.418886)
		(end 98.79965 -234.43692)
		(width 0.1143)
		(layer "In4.Cu")
		(net "P5E_CPU1_G1_RX_DP<13>")
	)
	(segment
		(start 98.81362 -226.983798)
		(end 98.812858 -226.984306)
		(width 0.1143)
		(layer "In4.Cu")
		(net "P5E_CPU1_G1_RX_DP<13>")
	)
	(segment
		(start 98.81997 -233.459782)
		(end 98.817938 -233.461052)
		(width 0.1143)
		(layer "In4.Cu")
		(net "P5E_CPU1_G1_RX_DP<13>")
	)
	(segment
		(start 98.804476 -234.439714)
		(end 98.805492 -234.440222)
		(width 0.1143)
		(layer "In4.Cu")
		(net "P5E_CPU1_G1_RX_DP<13>")
	)
	(segment
		(start 98.807016 -228.60762)
		(end 98.805746 -228.608382)
		(width 0.1143)
		(layer "In4.Cu")
		(net "P5E_CPU1_G1_RX_DP<13>")
	)
	(segment
		(start 97.882456 -223.73844)
		(end 97.88144 -223.738948)
		(width 0.1143)
		(layer "In4.Cu")
		(net "P5E_CPU1_G1_RX_DP<13>")
	)
	(segment
		(start 97.877884 -223.741234)
		(end 97.876106 -223.74225)
		(width 0.1143)
		(layer "In4.Cu")
		(net "P5E_CPU1_G1_RX_DP<13>")
	)
	(segment
		(start 98.808032 -233.466894)
		(end 98.807016 -233.467402)
		(width 0.1143)
		(layer "In4.Cu")
		(net "P5E_CPU1_G1_RX_DP<13>")
	)
	(segment
		(start 97.86874 -224.722436)
		(end 97.899728 -224.740216)
		(width 0.1143)
		(layer "In4.Cu")
		(net "P5E_CPU1_G1_RX_DP<13>")
	)
	(segment
		(start 98.299016 -231.988868)
		(end 98.338132 -232.011728)
		(width 0.1143)
		(layer "In4.Cu")
		(net "P5E_CPU1_G1_RX_DP<13>")
	)
	(segment
		(start 52.057554 -60.229242)
		(end 52.057808 -60.229496)
		(width 0.14224)
		(layer "In4.Cu")
		(net "P5E_CPU1_G1_RX_DP<13>")
	)
	(segment
		(start 98.82251 -233.458258)
		(end 98.821494 -233.458766)
		(width 0.1143)
		(layer "In4.Cu")
		(net "P5E_CPU1_G1_RX_DP<13>")
	)
	(segment
		(start 98.81362 -235.083604)
		(end 98.812858 -235.084112)
		(width 0.1143)
		(layer "In4.Cu")
		(net "P5E_CPU1_G1_RX_DP<13>")
	)
	(segment
		(start 98.81362 -233.463592)
		(end 98.812858 -233.4641)
		(width 0.1143)
		(layer "In4.Cu")
		(net "P5E_CPU1_G1_RX_DP<13>")
	)
	(segment
		(start 98.805746 -228.608382)
		(end 98.80346 -228.609906)
		(width 0.1143)
		(layer "In4.Cu")
		(net "P5E_CPU1_G1_RX_DP<13>")
	)
	(segment
		(start 98.839782 -233.448606)
		(end 98.82251 -233.458258)
		(width 0.1143)
		(layer "In4.Cu")
		(net "P5E_CPU1_G1_RX_DP<13>")
	)
	(segment
		(start 97.060512 -221.592902)
		(end 97.115884 -221.648274)
		(width 0.1143)
		(layer "In4.Cu")
		(net "P5E_CPU1_G1_RX_DP<13>")
	)
	(segment
		(start 97.014792 -214.184484)
		(end 97.014792 -221.259908)
		(width 0.14224)
		(layer "In4.Cu")
		(net "P5E_CPU1_G1_RX_DP<13>")
	)
	(segment
		(start 98.839782 -226.968812)
		(end 98.82251 -226.978464)
		(width 0.1143)
		(layer "In4.Cu")
		(net "P5E_CPU1_G1_RX_DP<13>")
	)
	(segment
		(start 98.808794 -226.342448)
		(end 98.839782 -226.360228)
		(width 0.1143)
		(layer "In4.Cu")
		(net "P5E_CPU1_G1_RX_DP<13>")
	)
	(segment
		(start 98.80346 -226.989894)
		(end 98.768916 -227.00996)
		(width 0.1143)
		(layer "In4.Cu")
		(net "P5E_CPU1_G1_RX_DP<13>")
	)
	(segment
		(start 98.810064 -233.465624)
		(end 98.808794 -233.466386)
		(width 0.1143)
		(layer "In4.Cu")
		(net "P5E_CPU1_G1_RX_DP<13>")
	)
	(segment
		(start 145.422112 -166.012114)
		(end 145.422112 -166.012368)
		(width 0.14224)
		(layer "In4.Cu")
		(net "P5E_CPU1_G1_RX_DP<13>")
	)
	(segment
		(start 98.801936 -234.43819)
		(end 98.802952 -234.438698)
		(width 0.1143)
		(layer "In4.Cu")
		(net "P5E_CPU1_G1_RX_DP<13>")
	)
	(segment
		(start 98.81362 -228.60381)
		(end 98.812858 -228.604318)
		(width 0.1143)
		(layer "In4.Cu")
		(net "P5E_CPU1_G1_RX_DP<13>")
	)
	(segment
		(start 49.894998 -58.451242)
		(end 52.057554 -60.229242)
		(width 0.14224)
		(layer "In4.Cu")
		(net "P5E_CPU1_G1_RX_DP<13>")
	)
	(segment
		(start 98.808032 -227.961952)
		(end 98.808794 -227.96246)
		(width 0.1143)
		(layer "In4.Cu")
		(net "P5E_CPU1_G1_RX_DP<13>")
	)
	(segment
		(start 98.81997 -226.979988)
		(end 98.817938 -226.981258)
		(width 0.1143)
		(layer "In4.Cu")
		(net "P5E_CPU1_G1_RX_DP<13>")
	)
	(segment
		(start 98.768916 -227.939092)
		(end 98.79965 -227.957126)
		(width 0.1143)
		(layer "In4.Cu")
		(net "P5E_CPU1_G1_RX_DP<13>")
	)
	(segment
		(start 98.808032 -232.821734)
		(end 98.808794 -232.822242)
		(width 0.1143)
		(layer "In4.Cu")
		(net "P5E_CPU1_G1_RX_DP<13>")
	)
	(segment
		(start 98.808032 -234.441746)
		(end 98.808794 -234.442254)
		(width 0.1143)
		(layer "In4.Cu")
		(net "P5E_CPU1_G1_RX_DP<13>")
	)
	(segment
		(start 98.82251 -235.07827)
		(end 98.821494 -235.078778)
		(width 0.1143)
		(layer "In4.Cu")
		(net "P5E_CPU1_G1_RX_DP<13>")
	)
	(segment
		(start 145.487898 -165.91534)
		(end 145.422112 -166.012114)
		(width 0.14224)
		(layer "In4.Cu")
		(net "P5E_CPU1_G1_RX_DP<13>")
	)
	(segment
		(start 98.807016 -234.441238)
		(end 98.808032 -234.441746)
		(width 0.1143)
		(layer "In4.Cu")
		(net "P5E_CPU1_G1_RX_DP<13>")
	)
	(segment
		(start 97.359724 -222.269558)
		(end 97.402142 -222.293942)
		(width 0.1143)
		(layer "In4.Cu")
		(net "P5E_CPU1_G1_RX_DP<13>")
	)
	(segment
		(start 98.82251 -226.978464)
		(end 98.821494 -226.978972)
		(width 0.1143)
		(layer "In4.Cu")
		(net "P5E_CPU1_G1_RX_DP<13>")
	)
	(segment
		(start 98.807016 -226.341432)
		(end 98.808032 -226.34194)
		(width 0.1143)
		(layer "In4.Cu")
		(net "P5E_CPU1_G1_RX_DP<13>")
	)
	(segment
		(start 22.615652 -6.725158)
		(end 22.906482 -7.015988)
		(width 0.14224)
		(layer "In4.Cu")
		(net "P5E_CPU1_G1_RX_DP<13>")
	)
	(segment
		(start 98.80346 -228.609906)
		(end 98.768916 -228.629972)
		(width 0.1143)
		(layer "In4.Cu")
		(net "P5E_CPU1_G1_RX_DP<13>")
	)
	(segment
		(start 98.812858 -228.604318)
		(end 98.811588 -228.60508)
		(width 0.1143)
		(layer "In4.Cu")
		(net "P5E_CPU1_G1_RX_DP<13>")
	)
	(segment
		(start 98.808032 -235.086906)
		(end 98.807016 -235.087414)
		(width 0.1143)
		(layer "In4.Cu")
		(net "P5E_CPU1_G1_RX_DP<13>")
	)
	(segment
		(start 98.802952 -232.818686)
		(end 98.804476 -232.819702)
		(width 0.1143)
		(layer "In4.Cu")
		(net "P5E_CPU1_G1_RX_DP<13>")
	)
	(segment
		(start 98.81616 -228.602286)
		(end 98.81362 -228.60381)
		(width 0.1143)
		(layer "In4.Cu")
		(net "P5E_CPU1_G1_RX_DP<13>")
	)
	(segment
		(start 97.014792 -221.259908)
		(end 97.014792 -221.288356)
		(width 0.1143)
		(layer "In4.Cu")
		(net "P5E_CPU1_G1_RX_DP<13>")
	)
	(segment
		(start 98.338132 -225.531934)
		(end 98.368612 -225.549714)
		(width 0.1143)
		(layer "In4.Cu")
		(net "P5E_CPU1_G1_RX_DP<13>")
	)
	(segment
		(start 98.808032 -228.607112)
		(end 98.807016 -228.60762)
		(width 0.1143)
		(layer "In4.Cu")
		(net "P5E_CPU1_G1_RX_DP<13>")
	)
	(segment
		(start 98.805492 -227.960428)
		(end 98.807016 -227.961444)
		(width 0.1143)
		(layer "In4.Cu")
		(net "P5E_CPU1_G1_RX_DP<13>")
	)
	(segment
		(start 97.831656 -224.700846)
		(end 97.867978 -224.721928)
		(width 0.1143)
		(layer "In4.Cu")
		(net "P5E_CPU1_G1_RX_DP<13>")
	)
	(segment
		(start 97.014792 -221.288356)
		(end 97.060512 -221.334076)
		(width 0.1143)
		(layer "In4.Cu")
		(net "P5E_CPU1_G1_RX_DP<13>")
	)
	(segment
		(start 98.368612 -235.879132)
		(end 98.338132 -235.896912)
		(width 0.1143)
		(layer "In4.Cu")
		(net "P5E_CPU1_G1_RX_DP<13>")
	)
	(segment
		(start 98.79965 -227.957126)
		(end 98.801936 -227.958396)
		(width 0.1143)
		(layer "In4.Cu")
		(net "P5E_CPU1_G1_RX_DP<13>")
	)
	(segment
		(start 98.802952 -226.338892)
		(end 98.804476 -226.339908)
		(width 0.1143)
		(layer "In4.Cu")
		(net "P5E_CPU1_G1_RX_DP<13>")
	)
	(segment
		(start 22.906482 -11.89101)
		(end 22.558248 -13.038328)
		(width 0.14224)
		(layer "In4.Cu")
		(net "P5E_CPU1_G1_RX_DP<13>")
	)
	(segment
		(start 98.768916 -229.559104)
		(end 98.808032 -229.581964)
		(width 0.1143)
		(layer "In4.Cu")
		(net "P5E_CPU1_G1_RX_DP<13>")
	)
	(segment
		(start 97.876106 -223.74225)
		(end 97.873566 -223.743774)
		(width 0.1143)
		(layer "In4.Cu")
		(net "P5E_CPU1_G1_RX_DP<13>")
	)
	(segment
		(start 145.422112 -166.012368)
		(end 142.123668 -170.883072)
		(width 0.14224)
		(layer "In4.Cu")
		(net "P5E_CPU1_G1_RX_DP<13>")
	)
	(segment
		(start 38.706552 -46.077378)
		(end 49.894998 -58.451242)
		(width 0.14224)
		(layer "In4.Cu")
		(net "P5E_CPU1_G1_RX_DP<13>")
	)
	(segment
		(start 98.805746 -235.088176)
		(end 98.80346 -235.0897)
		(width 0.1143)
		(layer "In4.Cu")
		(net "P5E_CPU1_G1_RX_DP<13>")
	)
	(segment
		(start 98.817938 -235.081064)
		(end 98.81616 -235.08208)
		(width 0.1143)
		(layer "In4.Cu")
		(net "P5E_CPU1_G1_RX_DP<13>")
	)
	(segment
		(start 98.810064 -226.98583)
		(end 98.808794 -226.986592)
		(width 0.1143)
		(layer "In4.Cu")
		(net "P5E_CPU1_G1_RX_DP<13>")
	)
	(segment
		(start 98.338132 -232.011728)
		(end 98.368612 -232.029508)
		(width 0.1143)
		(layer "In4.Cu")
		(net "P5E_CPU1_G1_RX_DP<13>")
	)
	(segment
		(start 98.805746 -226.98837)
		(end 98.80346 -226.989894)
		(width 0.1143)
		(layer "In4.Cu")
		(net "P5E_CPU1_G1_RX_DP<13>")
	)
	(segment
		(start 98.821494 -235.078778)
		(end 98.81997 -235.079794)
		(width 0.1143)
		(layer "In4.Cu")
		(net "P5E_CPU1_G1_RX_DP<13>")
	)
	(segment
		(start 19.74215 -17.252696)
		(end 19.647916 -17.48028)
		(width 0.14224)
		(layer "In4.Cu")
		(net "P5E_CPU1_G1_RX_DP<13>")
	)
	(segment
		(start 97.899728 -223.728788)
		(end 97.882456 -223.73844)
		(width 0.1143)
		(layer "In4.Cu")
		(net "P5E_CPU1_G1_RX_DP<13>")
	)
	(segment
		(start 98.808032 -226.9871)
		(end 98.807016 -226.987608)
		(width 0.1143)
		(layer "In4.Cu")
		(net "P5E_CPU1_G1_RX_DP<13>")
	)
	(segment
		(start 98.807016 -232.821226)
		(end 98.808032 -232.821734)
		(width 0.1143)
		(layer "In4.Cu")
		(net "P5E_CPU1_G1_RX_DP<13>")
	)
	(segment
		(start 98.807016 -226.987608)
		(end 98.805746 -226.98837)
		(width 0.1143)
		(layer "In4.Cu")
		(net "P5E_CPU1_G1_RX_DP<13>")
	)
	(segment
		(start 98.801936 -227.958396)
		(end 98.802952 -227.958904)
		(width 0.1143)
		(layer "In4.Cu")
		(net "P5E_CPU1_G1_RX_DP<13>")
	)
	(segment
		(start 98.805492 -226.340416)
		(end 98.807016 -226.341432)
		(width 0.1143)
		(layer "In4.Cu")
		(net "P5E_CPU1_G1_RX_DP<13>")
	)
	(segment
		(start 97.863152 -223.098868)
		(end 97.899728 -223.120204)
		(width 0.1143)
		(layer "In4.Cu")
		(net "P5E_CPU1_G1_RX_DP<13>")
	)
	(segment
		(start 98.805746 -233.468164)
		(end 98.80346 -233.469688)
		(width 0.1143)
		(layer "In4.Cu")
		(net "P5E_CPU1_G1_RX_DP<13>")
	)
	(segment
		(start 52.057808 -60.229496)
		(end 54.199536 -61.990478)
		(width 0.14224)
		(layer "In4.Cu")
		(net "P5E_CPU1_G1_RX_DP<13>")
	)
	(segment
		(start 104.289606 -201.869548)
		(end 97.014792 -214.184484)
		(width 0.14224)
		(layer "In4.Cu")
		(net "P5E_CPU1_G1_RX_DP<13>")
	)
	(segment
		(start 98.804476 -226.339908)
		(end 98.805492 -226.340416)
		(width 0.1143)
		(layer "In4.Cu")
		(net "P5E_CPU1_G1_RX_DP<13>")
	)
	(segment
		(start 146.689318 -162.386772)
		(end 145.487898 -165.91534)
		(width 0.14224)
		(layer "In4.Cu")
		(net "P5E_CPU1_G1_RX_DP<13>")
	)
	(segment
		(start 21.691854 -20.536916)
		(end 38.706552 -46.077378)
		(width 0.14224)
		(layer "In4.Cu")
		(net "P5E_CPU1_G1_RX_DP<13>")
	)
	(segment
		(start 98.81616 -235.08208)
		(end 98.81362 -235.083604)
		(width 0.1143)
		(layer "In4.Cu")
		(net "P5E_CPU1_G1_RX_DP<13>")
	)
	(segment
		(start 146.689318 -160.065466)
		(end 146.689318 -162.386772)
		(width 0.14224)
		(layer "In4.Cu")
		(net "P5E_CPU1_G1_RX_DP<13>")
	)
	(segment
		(start 98.768916 -226.31908)
		(end 98.79965 -226.337114)
		(width 0.1143)
		(layer "In4.Cu")
		(net "P5E_CPU1_G1_RX_DP<13>")
	)
	(segment
		(start 97.88144 -223.738948)
		(end 97.879916 -223.739964)
		(width 0.1143)
		(layer "In4.Cu")
		(net "P5E_CPU1_G1_RX_DP<13>")
	)
	(segment
		(start 98.79965 -232.816908)
		(end 98.801936 -232.818178)
		(width 0.1143)
		(layer "In4.Cu")
		(net "P5E_CPU1_G1_RX_DP<13>")
	)
	(segment
		(start 98.802952 -227.958904)
		(end 98.804476 -227.95992)
		(width 0.1143)
		(layer "In4.Cu")
		(net "P5E_CPU1_G1_RX_DP<13>")
	)
	(segment
		(start 98.299016 -225.509074)
		(end 98.338132 -225.531934)
		(width 0.1143)
		(layer "In4.Cu")
		(net "P5E_CPU1_G1_RX_DP<13>")
	)
	(segment
		(start 98.805492 -234.440222)
		(end 98.807016 -234.441238)
		(width 0.1143)
		(layer "In4.Cu")
		(net "P5E_CPU1_G1_RX_DP<13>")
	)
	(segment
		(start 98.811588 -233.464862)
		(end 98.810064 -233.465624)
		(width 0.1143)
		(layer "In4.Cu")
		(net "P5E_CPU1_G1_RX_DP<13>")
	)
	(segment
		(start 97.862644 -223.098868)
		(end 97.863152 -223.098868)
		(width 0.1143)
		(layer "In4.Cu")
		(net "P5E_CPU1_G1_RX_DP<13>")
	)
	(segment
		(start 97.86874 -223.746568)
		(end 97.867978 -223.747076)
		(width 0.1143)
		(layer "In4.Cu")
		(net "P5E_CPU1_G1_RX_DP<13>")
	)
	(segment
		(start 98.801936 -226.338384)
		(end 98.802952 -226.338892)
		(width 0.1143)
		(layer "In4.Cu")
		(net "P5E_CPU1_G1_RX_DP<13>")
	)
	(segment
		(start 98.839782 -230.208582)
		(end 98.808032 -230.22687)
		(width 0.1143)
		(layer "In4.Cu")
		(net "P5E_CPU1_G1_RX_DP<13>")
	)
	(segment
		(start 97.873566 -223.743774)
		(end 97.872804 -223.744282)
		(width 0.1143)
		(layer "In4.Cu")
		(net "P5E_CPU1_G1_RX_DP<13>")
	)
	(segment
		(start 98.821494 -226.978972)
		(end 98.81997 -226.979988)
		(width 0.1143)
		(layer "In4.Cu")
		(net "P5E_CPU1_G1_RX_DP<13>")
	)
	(segment
		(start 98.81997 -228.6)
		(end 98.817938 -228.60127)
		(width 0.1143)
		(layer "In4.Cu")
		(net "P5E_CPU1_G1_RX_DP<13>")
	)
	(segment
		(start 98.79965 -226.337114)
		(end 98.801936 -226.338384)
		(width 0.1143)
		(layer "In4.Cu")
		(net "P5E_CPU1_G1_RX_DP<13>")
	)
	(segment
		(start 19.647916 -17.48028)
		(end 19.647916 -17.822672)
		(width 0.14224)
		(layer "In4.Cu")
		(net "P5E_CPU1_G1_RX_DP<13>")
	)
	(segment
		(start 54.199536 -61.990478)
		(end 143.11249 -141.946376)
		(width 0.14224)
		(layer "In4.Cu")
		(net "P5E_CPU1_G1_RX_DP<13>")
	)
	(segment
		(start 97.867978 -223.747076)
		(end 97.831656 -223.768158)
		(width 0.1143)
		(layer "In4.Cu")
		(net "P5E_CPU1_G1_RX_DP<13>")
	)
	(segment
		(start 98.81616 -233.462068)
		(end 98.81362 -233.463592)
		(width 0.1143)
		(layer "In4.Cu")
		(net "P5E_CPU1_G1_RX_DP<13>")
	)
	(segment
		(start 98.81616 -226.982274)
		(end 98.81362 -226.983798)
		(width 0.1143)
		(layer "In4.Cu")
		(net "P5E_CPU1_G1_RX_DP<13>")
	)
	(segment
		(start 98.805492 -232.82021)
		(end 98.807016 -232.821226)
		(width 0.1143)
		(layer "In4.Cu")
		(net "P5E_CPU1_G1_RX_DP<13>")
	)
	(segment
		(start 98.81997 -235.079794)
		(end 98.817938 -235.081064)
		(width 0.1143)
		(layer "In4.Cu")
		(net "P5E_CPU1_G1_RX_DP<13>")
	)
	(segment
		(start 98.821494 -233.458766)
		(end 98.81997 -233.459782)
		(width 0.1143)
		(layer "In4.Cu")
		(net "P5E_CPU1_G1_RX_DP<13>")
	)
	(segment
		(start 98.807016 -233.467402)
		(end 98.805746 -233.468164)
		(width 0.1143)
		(layer "In4.Cu")
		(net "P5E_CPU1_G1_RX_DP<13>")
	)
	(segment
		(start 98.817938 -233.461052)
		(end 98.81616 -233.462068)
		(width 0.1143)
		(layer "In4.Cu")
		(net "P5E_CPU1_G1_RX_DP<13>")
	)
	(segment
		(start 98.80346 -235.0897)
		(end 98.768916 -235.109766)
		(width 0.1143)
		(layer "In4.Cu")
		(net "P5E_CPU1_G1_RX_DP<13>")
	)
	(segment
		(start 142.123668 -170.883072)
		(end 104.289606 -201.869548)
		(width 0.14224)
		(layer "In4.Cu")
		(net "P5E_CPU1_G1_RX_DP<13>")
	)
	(segment
		(start 20.461478 -19.039586)
		(end 21.691854 -20.536916)
		(width 0.14224)
		(layer "In4.Cu")
		(net "P5E_CPU1_G1_RX_DP<13>")
	)
	(segment
		(start 98.810064 -228.605842)
		(end 98.808794 -228.606604)
		(width 0.1143)
		(layer "In4.Cu")
		(net "P5E_CPU1_G1_RX_DP<13>")
	)
	(segment
		(start 98.811588 -235.084874)
		(end 98.810064 -235.085636)
		(width 0.1143)
		(layer "In4.Cu")
		(net "P5E_CPU1_G1_RX_DP<13>")
	)
	(segment
		(start 98.768916 -232.798874)
		(end 98.79965 -232.816908)
		(width 0.1143)
		(layer "In4.Cu")
		(net "P5E_CPU1_G1_RX_DP<13>")
	)
	(segment
		(start 98.811588 -226.985068)
		(end 98.810064 -226.98583)
		(width 0.1143)
		(layer "In4.Cu")
		(net "P5E_CPU1_G1_RX_DP<13>")
	)
	(segment
		(start 97.87001 -223.745806)
		(end 97.86874 -223.746568)
		(width 0.1143)
		(layer "In4.Cu")
		(net "P5E_CPU1_G1_RX_DP<13>")
	)
	(segment
		(start 97.871534 -223.745044)
		(end 97.87001 -223.745806)
		(width 0.1143)
		(layer "In4.Cu")
		(net "P5E_CPU1_G1_RX_DP<13>")
	)
	(segment
		(start 98.808794 -233.466386)
		(end 98.808032 -233.466894)
		(width 0.1143)
		(layer "In4.Cu")
		(net "P5E_CPU1_G1_RX_DP<13>")
	)
	(segment
		(start 22.558248 -13.038328)
		(end 19.74215 -17.252696)
		(width 0.14224)
		(layer "In4.Cu")
		(net "P5E_CPU1_G1_RX_DP<13>")
	)
	(segment
		(start 98.812858 -235.084112)
		(end 98.811588 -235.084874)
		(width 0.1143)
		(layer "In4.Cu")
		(net "P5E_CPU1_G1_RX_DP<13>")
	)
	(segment
		(start 98.839782 -235.068618)
		(end 98.82251 -235.07827)
		(width 0.1143)
		(layer "In4.Cu")
		(net "P5E_CPU1_G1_RX_DP<13>")
	)
	(segment
		(start 98.808794 -226.986592)
		(end 98.808032 -226.9871)
		(width 0.1143)
		(layer "In4.Cu")
		(net "P5E_CPU1_G1_RX_DP<13>")
	)
	(segment
		(start 97.872804 -223.744282)
		(end 97.871534 -223.745044)
		(width 0.1143)
		(layer "In4.Cu")
		(net "P5E_CPU1_G1_RX_DP<13>")
	)
	(segment
		(start 98.804476 -232.819702)
		(end 98.805492 -232.82021)
		(width 0.1143)
		(layer "In4.Cu")
		(net "P5E_CPU1_G1_RX_DP<13>")
	)
	(segment
		(start 98.812858 -226.984306)
		(end 98.811588 -226.985068)
		(width 0.1143)
		(layer "In4.Cu")
		(net "P5E_CPU1_G1_RX_DP<13>")
	)
	(segment
		(start 98.817938 -226.981258)
		(end 98.81616 -226.982274)
		(width 0.1143)
		(layer "In4.Cu")
		(net "P5E_CPU1_G1_RX_DP<13>")
	)
	(segment
		(start 98.807016 -227.961444)
		(end 98.808032 -227.961952)
		(width 0.1143)
		(layer "In4.Cu")
		(net "P5E_CPU1_G1_RX_DP<13>")
	)
	(segment
		(start 98.338132 -235.896912)
		(end 98.299016 -235.919772)
		(width 0.1143)
		(layer "In4.Cu")
		(net "P5E_CPU1_G1_RX_DP<13>")
	)
	(segment
		(start 97.978976 -236.384338)
		(end 97.681034 -236.384338)
		(width 0.1143)
		(layer "In4.Cu")
		(net "P5E_CPU1_G1_RX_DP<13>")
	)
	(segment
		(start 98.79965 -234.43692)
		(end 98.801936 -234.43819)
		(width 0.1143)
		(layer "In4.Cu")
		(net "P5E_CPU1_G1_RX_DP<13>")
	)
	(segment
		(start 98.821494 -228.598984)
		(end 98.81997 -228.6)
		(width 0.1143)
		(layer "In4.Cu")
		(net "P5E_CPU1_G1_RX_DP<13>")
	)
	(segment
		(start 98.808032 -230.22687)
		(end 98.771456 -230.248206)
		(width 0.1143)
		(layer "In4.Cu")
		(net "P5E_CPU1_G1_RX_DP<13>")
	)
	(segment
		(start 98.811588 -228.60508)
		(end 98.810064 -228.605842)
		(width 0.1143)
		(layer "In4.Cu")
		(net "P5E_CPU1_G1_RX_DP<13>")
	)
	(segment
		(start 98.338132 -231.036876)
		(end 98.299016 -231.059736)
		(width 0.1143)
		(layer "In4.Cu")
		(net "P5E_CPU1_G1_RX_DP<13>")
	)
	(segment
		(start 98.82251 -228.598476)
		(end 98.821494 -228.598984)
		(width 0.1143)
		(layer "In4.Cu")
		(net "P5E_CPU1_G1_RX_DP<13>")
	)
	(segment
		(start 98.808032 -226.34194)
		(end 98.808794 -226.342448)
		(width 0.1143)
		(layer "In4.Cu")
		(net "P5E_CPU1_G1_RX_DP<13>")
	)
	(segment
		(start 97.867978 -224.721928)
		(end 97.86874 -224.722436)
		(width 0.1143)
		(layer "In4.Cu")
		(net "P5E_CPU1_G1_RX_DP<13>")
	)
	(segment
		(start 22.906482 -7.015988)
		(end 22.906482 -11.89101)
		(width 0.14224)
		(layer "In4.Cu")
		(net "P5E_CPU1_G1_RX_DP<13>")
	)
	(segment
		(start 98.06178 -236.301534)
		(end 97.978976 -236.384338)
		(width 0.1143)
		(layer "In4.Cu")
		(net "P5E_CPU1_G1_RX_DP<13>")
	)
	(arc
		(start 98.768916 -227.00996)
		(mid 98.525589 -227.474526)
		(end 98.768916 -227.939092)
		(width 0.1143)
		(layer "In4.Cu")
		(net "P5E_CPU1_G1_RX_DP<13>")
	)
	(arc
		(start 98.525584 -235.574332)
		(mid 98.484035 -235.745754)
		(end 98.368612 -235.879132)
		(width 0.1143)
		(layer "In4.Cu")
		(net "P5E_CPU1_G1_RX_DP<13>")
	)
	(arc
		(start 98.995738 -229.90429)
		(mid 98.954483 -230.075261)
		(end 98.839782 -230.208582)
		(width 0.1143)
		(layer "In4.Cu")
		(net "P5E_CPU1_G1_RX_DP<13>")
	)
	(arc
		(start 97.899728 -224.740216)
		(mid 98.014404 -224.87355)
		(end 98.055684 -225.044508)
		(width 0.1143)
		(layer "In4.Cu")
		(net "P5E_CPU1_G1_RX_DP<13>")
	)
	(arc
		(start 98.839782 -234.460034)
		(mid 98.99571 -234.764326)
		(end 98.839782 -235.068618)
		(width 0.1143)
		(layer "In4.Cu")
		(net "P5E_CPU1_G1_RX_DP<13>")
	)
	(arc
		(start 97.831656 -223.768158)
		(mid 97.823992 -223.773429)
		(end 97.816416 -223.778826)
		(width 0.1143)
		(layer "In4.Cu")
		(net "P5E_CPU1_G1_RX_DP<13>")
	)
	(arc
		(start 98.771456 -230.248206)
		(mid 98.590804 -230.450951)
		(end 98.525584 -230.71455)
		(width 0.1143)
		(layer "In4.Cu")
		(net "P5E_CPU1_G1_RX_DP<13>")
	)
	(arc
		(start 98.768916 -233.489754)
		(mid 98.525589 -233.95432)
		(end 98.768916 -234.418886)
		(width 0.1143)
		(layer "In4.Cu")
		(net "P5E_CPU1_G1_RX_DP<13>")
	)
	(arc
		(start 98.768916 -228.629972)
		(mid 98.525589 -229.094538)
		(end 98.768916 -229.559104)
		(width 0.1143)
		(layer "In4.Cu")
		(net "P5E_CPU1_G1_RX_DP<13>")
	)
	(arc
		(start 98.299016 -235.919772)
		(mid 98.147029 -236.07628)
		(end 98.06559 -236.278674)
		(width 0.1143)
		(layer "In4.Cu")
		(net "P5E_CPU1_G1_RX_DP<13>")
	)
	(arc
		(start 98.839782 -232.840022)
		(mid 98.99571 -233.144314)
		(end 98.839782 -233.448606)
		(width 0.1143)
		(layer "In4.Cu")
		(net "P5E_CPU1_G1_RX_DP<13>")
	)
	(arc
		(start 98.84156 -229.601522)
		(mid 98.954967 -229.734411)
		(end 98.995738 -229.90429)
		(width 0.1143)
		(layer "In4.Cu")
		(net "P5E_CPU1_G1_RX_DP<13>")
	)
	(arc
		(start 98.839782 -226.360228)
		(mid 98.99571 -226.66452)
		(end 98.839782 -226.968812)
		(width 0.1143)
		(layer "In4.Cu")
		(net "P5E_CPU1_G1_RX_DP<13>")
	)
	(arc
		(start 98.299016 -231.059736)
		(mid 98.055689 -231.524302)
		(end 98.299016 -231.988868)
		(width 0.1143)
		(layer "In4.Cu")
		(net "P5E_CPU1_G1_RX_DP<13>")
	)
	(arc
		(start 98.525584 -230.71455)
		(mid 98.484618 -230.884956)
		(end 98.370644 -231.01808)
		(width 0.1143)
		(layer "In4.Cu")
		(net "P5E_CPU1_G1_RX_DP<13>")
	)
	(arc
		(start 97.115884 -221.804484)
		(mid 97.180543 -222.067041)
		(end 97.359724 -222.269558)
		(width 0.1143)
		(layer "In4.Cu")
		(net "P5E_CPU1_G1_RX_DP<13>")
	)
	(arc
		(start 98.06559 -236.278674)
		(mid 98.063567 -236.290084)
		(end 98.06178 -236.301534)
		(width 0.1143)
		(layer "In4.Cu")
		(net "P5E_CPU1_G1_RX_DP<13>")
	)
	(arc
		(start 97.899728 -223.120204)
		(mid 98.055656 -223.424496)
		(end 97.899728 -223.728788)
		(width 0.1143)
		(layer "In4.Cu")
		(net "P5E_CPU1_G1_RX_DP<13>")
	)
	(arc
		(start 98.055684 -225.044508)
		(mid 98.120199 -225.306727)
		(end 98.299016 -225.509074)
		(width 0.1143)
		(layer "In4.Cu")
		(net "P5E_CPU1_G1_RX_DP<13>")
	)
	(arc
		(start 98.368612 -225.549714)
		(mid 98.484039 -225.68309)
		(end 98.525584 -225.854514)
		(width 0.1143)
		(layer "In4.Cu")
		(net "P5E_CPU1_G1_RX_DP<13>")
	)
	(arc
		(start 97.402142 -222.293942)
		(mid 97.536614 -222.42978)
		(end 97.585784 -222.61449)
		(width 0.1143)
		(layer "In4.Cu")
		(net "P5E_CPU1_G1_RX_DP<13>")
	)
	(arc
		(start 97.816416 -223.778826)
		(mid 97.591245 -224.234502)
		(end 97.816416 -224.690178)
		(width 0.1143)
		(layer "In4.Cu")
		(net "P5E_CPU1_G1_RX_DP<13>")
	)
	(arc
		(start 97.816416 -224.690178)
		(mid 97.823992 -224.695574)
		(end 97.831656 -224.700846)
		(width 0.1143)
		(layer "In4.Cu")
		(net "P5E_CPU1_G1_RX_DP<13>")
	)
	(arc
		(start 98.839782 -227.98024)
		(mid 98.99571 -228.284532)
		(end 98.839782 -228.588824)
		(width 0.1143)
		(layer "In4.Cu")
		(net "P5E_CPU1_G1_RX_DP<13>")
	)
	(arc
		(start 98.525584 -225.854514)
		(mid 98.590099 -226.116733)
		(end 98.768916 -226.31908)
		(width 0.1143)
		(layer "In4.Cu")
		(net "P5E_CPU1_G1_RX_DP<13>")
	)
	(arc
		(start 98.368612 -232.029508)
		(mid 98.484039 -232.162884)
		(end 98.525584 -232.334308)
		(width 0.1143)
		(layer "In4.Cu")
		(net "P5E_CPU1_G1_RX_DP<13>")
	)
	(arc
		(start 98.768916 -235.109766)
		(mid 98.590103 -235.312116)
		(end 98.525584 -235.574332)
		(width 0.1143)
		(layer "In4.Cu")
		(net "P5E_CPU1_G1_RX_DP<13>")
	)
	(arc
		(start 98.525584 -232.334308)
		(mid 98.590099 -232.596527)
		(end 98.768916 -232.798874)
		(width 0.1143)
		(layer "In4.Cu")
		(net "P5E_CPU1_G1_RX_DP<13>")
	)
	(arc
		(start 97.585784 -222.61449)
		(mid 97.659833 -222.893469)
		(end 97.862644 -223.098868)
		(width 0.1143)
		(layer "In4.Cu")
		(net "P5E_CPU1_G1_RX_DP<13>")
	)
	(segment
		(start 21.085556 -7.57047)
		(end 21.085556 -5.22859)
		(width 0.12954)
		(layer "F.Cu")
		(net "P5E_CPU1_G1_RX_DP<14>")
	)
	(segment
		(start 20.946872 -7.709154)
		(end 21.085556 -7.57047)
		(width 0.12954)
		(layer "F.Cu")
		(net "P5E_CPU1_G1_RX_DP<14>")
	)
	(segment
		(start 21.085556 -5.22859)
		(end 20.82038 -4.963414)
		(width 0.12954)
		(layer "F.Cu")
		(net "P5E_CPU1_G1_RX_DP<14>")
	)
	(segment
		(start 98.147886 -233.410252)
		(end 97.681034 -233.144314)
		(width 0.12954)
		(layer "F.Cu")
		(net "P5E_CPU1_G1_RX_DP<14>")
	)
	(segment
		(start 20.946872 -8.320024)
		(end 20.946872 -7.709154)
		(width 0.12954)
		(layer "F.Cu")
		(net "P5E_CPU1_G1_RX_DP<14>")
	)
	(segment
		(start 97.867978 -226.9871)
		(end 97.831656 -227.008182)
		(width 0.1143)
		(layer "In4.Cu")
		(net "P5E_CPU1_G1_RX_DP<14>")
	)
	(segment
		(start 97.899474 -229.599998)
		(end 97.899728 -229.600252)
		(width 0.1143)
		(layer "In4.Cu")
		(net "P5E_CPU1_G1_RX_DP<14>")
	)
	(segment
		(start 16.882618 -18.954496)
		(end 16.882618 -18.955004)
		(width 0.14224)
		(layer "In4.Cu")
		(net "P5E_CPU1_G1_RX_DP<14>")
	)
	(segment
		(start 96.451928 -222.288354)
		(end 96.452944 -222.288862)
		(width 0.1143)
		(layer "In4.Cu")
		(net "P5E_CPU1_G1_RX_DP<14>")
	)
	(segment
		(start 17.313656 -18.229834)
		(end 16.948658 -18.775426)
		(width 0.14224)
		(layer "In4.Cu")
		(net "P5E_CPU1_G1_RX_DP<14>")
	)
	(segment
		(start 97.86874 -226.986592)
		(end 97.867978 -226.9871)
		(width 0.1143)
		(layer "In4.Cu")
		(net "P5E_CPU1_G1_RX_DP<14>")
	)
	(segment
		(start 97.87001 -228.605842)
		(end 97.86874 -228.606604)
		(width 0.1143)
		(layer "In4.Cu")
		(net "P5E_CPU1_G1_RX_DP<14>")
	)
	(segment
		(start 97.401634 -225.533966)
		(end 97.402396 -225.534474)
		(width 0.1143)
		(layer "In4.Cu")
		(net "P5E_CPU1_G1_RX_DP<14>")
	)
	(segment
		(start 97.398078 -225.531934)
		(end 97.399602 -225.53295)
		(width 0.1143)
		(layer "In4.Cu")
		(net "P5E_CPU1_G1_RX_DP<14>")
	)
	(segment
		(start 97.867978 -226.34194)
		(end 97.86874 -226.342448)
		(width 0.1143)
		(layer "In4.Cu")
		(net "P5E_CPU1_G1_RX_DP<14>")
	)
	(segment
		(start 97.865184 -226.340162)
		(end 97.867978 -226.34194)
		(width 0.1143)
		(layer "In4.Cu")
		(net "P5E_CPU1_G1_RX_DP<14>")
	)
	(segment
		(start 32.35071 -40.059356)
		(end 32.351726 -40.060626)
		(width 0.14224)
		(layer "In4.Cu")
		(net "P5E_CPU1_G1_RX_DP<14>")
	)
	(segment
		(start 20.733004 -24.116284)
		(end 32.346138 -40.052752)
		(width 0.14224)
		(layer "In4.Cu")
		(net "P5E_CPU1_G1_RX_DP<14>")
	)
	(segment
		(start 96.069912 -221.288356)
		(end 96.115632 -221.334076)
		(width 0.1143)
		(layer "In4.Cu")
		(net "P5E_CPU1_G1_RX_DP<14>")
	)
	(segment
		(start 97.403666 -225.535236)
		(end 97.427542 -225.548952)
		(width 0.1143)
		(layer "In4.Cu")
		(net "P5E_CPU1_G1_RX_DP<14>")
	)
	(segment
		(start 97.867216 -232.821226)
		(end 97.86874 -232.822242)
		(width 0.1143)
		(layer "In4.Cu")
		(net "P5E_CPU1_G1_RX_DP<14>")
	)
	(segment
		(start 32.346138 -40.052752)
		(end 32.3469 -40.054022)
		(width 0.14224)
		(layer "In4.Cu")
		(net "P5E_CPU1_G1_RX_DP<14>")
	)
	(segment
		(start 96.452944 -222.288862)
		(end 96.454468 -222.289878)
		(width 0.1143)
		(layer "In4.Cu")
		(net "P5E_CPU1_G1_RX_DP<14>")
	)
	(segment
		(start 21.11121 -11.991848)
		(end 20.84578 -12.865862)
		(width 0.14224)
		(layer "In4.Cu")
		(net "P5E_CPU1_G1_RX_DP<14>")
	)
	(segment
		(start 141.28623 -170.363388)
		(end 103.57104 -201.252582)
		(width 0.14224)
		(layer "In4.Cu")
		(net "P5E_CPU1_G1_RX_DP<14>")
	)
	(segment
		(start 97.867978 -228.607112)
		(end 97.831656 -228.628194)
		(width 0.1143)
		(layer "In4.Cu")
		(net "P5E_CPU1_G1_RX_DP<14>")
	)
	(segment
		(start 17.52219 -17.840198)
		(end 17.313656 -18.229834)
		(width 0.14224)
		(layer "In4.Cu")
		(net "P5E_CPU1_G1_RX_DP<14>")
	)
	(segment
		(start 97.585784 -225.854514)
		(end 97.585784 -225.861626)
		(width 0.1143)
		(layer "In4.Cu")
		(net "P5E_CPU1_G1_RX_DP<14>")
	)
	(segment
		(start 32.354266 -40.064182)
		(end 36.047426 -45.13199)
		(width 0.14224)
		(layer "In4.Cu")
		(net "P5E_CPU1_G1_RX_DP<14>")
	)
	(segment
		(start 96.928178 -224.721928)
		(end 96.958658 -224.739708)
		(width 0.1143)
		(layer "In4.Cu")
		(net "P5E_CPU1_G1_RX_DP<14>")
	)
	(segment
		(start 97.867978 -227.961952)
		(end 97.86874 -227.96246)
		(width 0.1143)
		(layer "In4.Cu")
		(net "P5E_CPU1_G1_RX_DP<14>")
	)
	(segment
		(start 96.115632 -221.592902)
		(end 96.17583 -221.6531)
		(width 0.1143)
		(layer "In4.Cu")
		(net "P5E_CPU1_G1_RX_DP<14>")
	)
	(segment
		(start 96.069912 -213.913466)
		(end 96.069912 -221.259908)
		(width 0.14224)
		(layer "In4.Cu")
		(net "P5E_CPU1_G1_RX_DP<14>")
	)
	(segment
		(start 144.73936 -164.944806)
		(end 141.28623 -170.363388)
		(width 0.14224)
		(layer "In4.Cu")
		(net "P5E_CPU1_G1_RX_DP<14>")
	)
	(segment
		(start 32.3469 -40.054022)
		(end 32.35071 -40.059356)
		(width 0.14224)
		(layer "In4.Cu")
		(net "P5E_CPU1_G1_RX_DP<14>")
	)
	(segment
		(start 98.048826 -233.074464)
		(end 97.978976 -233.144314)
		(width 0.1143)
		(layer "In4.Cu")
		(net "P5E_CPU1_G1_RX_DP<14>")
	)
	(segment
		(start 20.726908 -24.10841)
		(end 20.730972 -24.113744)
		(width 0.14224)
		(layer "In4.Cu")
		(net "P5E_CPU1_G1_RX_DP<14>")
	)
	(segment
		(start 97.87001 -226.98583)
		(end 97.86874 -226.986592)
		(width 0.1143)
		(layer "In4.Cu")
		(net "P5E_CPU1_G1_RX_DP<14>")
	)
	(segment
		(start 32.35325 -40.062912)
		(end 32.354266 -40.064182)
		(width 0.14224)
		(layer "In4.Cu")
		(net "P5E_CPU1_G1_RX_DP<14>")
	)
	(segment
		(start 20.82038 -4.963414)
		(end 21.11121 -5.254244)
		(width 0.14224)
		(layer "In4.Cu")
		(net "P5E_CPU1_G1_RX_DP<14>")
	)
	(segment
		(start 20.73148 -24.114506)
		(end 20.731734 -24.115014)
		(width 0.14224)
		(layer "In4.Cu")
		(net "P5E_CPU1_G1_RX_DP<14>")
	)
	(segment
		(start 145.682716 -162.144964)
		(end 144.73936 -164.944806)
		(width 0.14224)
		(layer "In4.Cu")
		(net "P5E_CPU1_G1_RX_DP<14>")
	)
	(segment
		(start 145.682716 -160.097216)
		(end 145.682716 -162.144964)
		(width 0.14224)
		(layer "In4.Cu")
		(net "P5E_CPU1_G1_RX_DP<14>")
	)
	(segment
		(start 96.17583 -221.6531)
		(end 96.17583 -221.804484)
		(width 0.1143)
		(layer "In4.Cu")
		(net "P5E_CPU1_G1_RX_DP<14>")
	)
	(segment
		(start 16.890238 -18.91665)
		(end 16.882618 -18.954496)
		(width 0.14224)
		(layer "In4.Cu")
		(net "P5E_CPU1_G1_RX_DP<14>")
	)
	(segment
		(start 97.899728 -228.588824)
		(end 97.87001 -228.605842)
		(width 0.1143)
		(layer "In4.Cu")
		(net "P5E_CPU1_G1_RX_DP<14>")
	)
	(segment
		(start 97.864676 -232.819956)
		(end 97.867216 -232.821226)
		(width 0.1143)
		(layer "In4.Cu")
		(net "P5E_CPU1_G1_RX_DP<14>")
	)
	(segment
		(start 49.825148 -59.761882)
		(end 54.541928 -63.6524)
		(width 0.14224)
		(layer "In4.Cu")
		(net "P5E_CPU1_G1_RX_DP<14>")
	)
	(segment
		(start 96.958658 -223.729296)
		(end 96.928178 -223.747076)
		(width 0.1143)
		(layer "In4.Cu")
		(net "P5E_CPU1_G1_RX_DP<14>")
	)
	(segment
		(start 54.541928 -63.6524)
		(end 142.438628 -142.69466)
		(width 0.14224)
		(layer "In4.Cu")
		(net "P5E_CPU1_G1_RX_DP<14>")
	)
	(segment
		(start 97.86874 -228.606604)
		(end 97.867978 -228.607112)
		(width 0.1143)
		(layer "In4.Cu")
		(net "P5E_CPU1_G1_RX_DP<14>")
	)
	(segment
		(start 96.889062 -223.079056)
		(end 96.928178 -223.101916)
		(width 0.1143)
		(layer "In4.Cu")
		(net "P5E_CPU1_G1_RX_DP<14>")
	)
	(segment
		(start 144.912334 -147.809204)
		(end 145.682716 -160.097216)
		(width 0.14224)
		(layer "In4.Cu")
		(net "P5E_CPU1_G1_RX_DP<14>")
	)
	(segment
		(start 16.948658 -18.775426)
		(end 16.890238 -18.91665)
		(width 0.14224)
		(layer "In4.Cu")
		(net "P5E_CPU1_G1_RX_DP<14>")
	)
	(segment
		(start 97.86874 -226.342448)
		(end 97.899728 -226.360228)
		(width 0.1143)
		(layer "In4.Cu")
		(net "P5E_CPU1_G1_RX_DP<14>")
	)
	(segment
		(start 20.719542 -24.098504)
		(end 20.7264 -24.107648)
		(width 0.14224)
		(layer "In4.Cu")
		(net "P5E_CPU1_G1_RX_DP<14>")
	)
	(segment
		(start 20.731734 -24.115014)
		(end 20.733004 -24.116284)
		(width 0.14224)
		(layer "In4.Cu")
		(net "P5E_CPU1_G1_RX_DP<14>")
	)
	(segment
		(start 97.86874 -232.822242)
		(end 97.899728 -232.840022)
		(width 0.1143)
		(layer "In4.Cu")
		(net "P5E_CPU1_G1_RX_DP<14>")
	)
	(segment
		(start 97.978976 -233.144314)
		(end 97.681034 -233.144314)
		(width 0.1143)
		(layer "In4.Cu")
		(net "P5E_CPU1_G1_RX_DP<14>")
	)
	(segment
		(start 20.718526 -24.097234)
		(end 20.719542 -24.098504)
		(width 0.14224)
		(layer "In4.Cu")
		(net "P5E_CPU1_G1_RX_DP<14>")
	)
	(segment
		(start 97.11563 -225.044508)
		(end 97.115884 -225.044508)
		(width 0.1143)
		(layer "In4.Cu")
		(net "P5E_CPU1_G1_RX_DP<14>")
	)
	(segment
		(start 96.457008 -222.291402)
		(end 96.458024 -222.29191)
		(width 0.1143)
		(layer "In4.Cu")
		(net "P5E_CPU1_G1_RX_DP<14>")
	)
	(segment
		(start 20.7264 -24.107648)
		(end 20.726908 -24.10841)
		(width 0.14224)
		(layer "In4.Cu")
		(net "P5E_CPU1_G1_RX_DP<14>")
	)
	(segment
		(start 97.399602 -225.53295)
		(end 97.401634 -225.533966)
		(width 0.1143)
		(layer "In4.Cu")
		(net "P5E_CPU1_G1_RX_DP<14>")
	)
	(segment
		(start 96.449642 -222.287084)
		(end 96.451928 -222.288354)
		(width 0.1143)
		(layer "In4.Cu")
		(net "P5E_CPU1_G1_RX_DP<14>")
	)
	(segment
		(start 96.889062 -224.699068)
		(end 96.928178 -224.721928)
		(width 0.1143)
		(layer "In4.Cu")
		(net "P5E_CPU1_G1_RX_DP<14>")
	)
	(segment
		(start 96.069912 -221.259908)
		(end 96.069912 -221.288356)
		(width 0.1143)
		(layer "In4.Cu")
		(net "P5E_CPU1_G1_RX_DP<14>")
	)
	(segment
		(start 142.438628 -142.69466)
		(end 144.912334 -147.809204)
		(width 0.14224)
		(layer "In4.Cu")
		(net "P5E_CPU1_G1_RX_DP<14>")
	)
	(segment
		(start 21.11121 -5.254244)
		(end 21.11121 -11.991848)
		(width 0.14224)
		(layer "In4.Cu")
		(net "P5E_CPU1_G1_RX_DP<14>")
	)
	(segment
		(start 16.863822 -19.357594)
		(end 17.49933 -20.381976)
		(width 0.14224)
		(layer "In4.Cu")
		(net "P5E_CPU1_G1_RX_DP<14>")
	)
	(segment
		(start 96.418908 -222.26905)
		(end 96.449642 -222.287084)
		(width 0.1143)
		(layer "In4.Cu")
		(net "P5E_CPU1_G1_RX_DP<14>")
	)
	(segment
		(start 16.882618 -18.955004)
		(end 16.834612 -19.197066)
		(width 0.14224)
		(layer "In4.Cu")
		(net "P5E_CPU1_G1_RX_DP<14>")
	)
	(segment
		(start 96.928178 -223.101916)
		(end 96.958658 -223.119696)
		(width 0.1143)
		(layer "In4.Cu")
		(net "P5E_CPU1_G1_RX_DP<14>")
	)
	(segment
		(start 97.869502 -230.229156)
		(end 97.86493 -230.23195)
		(width 0.1143)
		(layer "In4.Cu")
		(net "P5E_CPU1_G1_RX_DP<14>")
	)
	(segment
		(start 97.818702 -226.31146)
		(end 97.829116 -226.319334)
		(width 0.1143)
		(layer "In4.Cu")
		(net "P5E_CPU1_G1_RX_DP<14>")
	)
	(segment
		(start 97.580196 -232.327196)
		(end 97.580196 -232.329736)
		(width 0.1143)
		(layer "In4.Cu")
		(net "P5E_CPU1_G1_RX_DP<14>")
	)
	(segment
		(start 97.427796 -231.019858)
		(end 97.358962 -231.059736)
		(width 0.1143)
		(layer "In4.Cu")
		(net "P5E_CPU1_G1_RX_DP<14>")
	)
	(segment
		(start 36.047426 -45.13199)
		(end 49.825148 -59.761882)
		(width 0.14224)
		(layer "In4.Cu")
		(net "P5E_CPU1_G1_RX_DP<14>")
	)
	(segment
		(start 97.402396 -225.534474)
		(end 97.403666 -225.535236)
		(width 0.1143)
		(layer "In4.Cu")
		(net "P5E_CPU1_G1_RX_DP<14>")
	)
	(segment
		(start 20.730972 -24.113744)
		(end 20.73148 -24.114506)
		(width 0.14224)
		(layer "In4.Cu")
		(net "P5E_CPU1_G1_RX_DP<14>")
	)
	(segment
		(start 20.84578 -12.865862)
		(end 17.52219 -17.840198)
		(width 0.14224)
		(layer "In4.Cu")
		(net "P5E_CPU1_G1_RX_DP<14>")
	)
	(segment
		(start 97.831656 -229.560882)
		(end 97.899474 -229.599998)
		(width 0.1143)
		(layer "In4.Cu")
		(net "P5E_CPU1_G1_RX_DP<14>")
	)
	(segment
		(start 97.829116 -226.319334)
		(end 97.865184 -226.340162)
		(width 0.1143)
		(layer "In4.Cu")
		(net "P5E_CPU1_G1_RX_DP<14>")
	)
	(segment
		(start 97.899728 -226.968812)
		(end 97.87001 -226.98583)
		(width 0.1143)
		(layer "In4.Cu")
		(net "P5E_CPU1_G1_RX_DP<14>")
	)
	(segment
		(start 96.458024 -222.29191)
		(end 96.489774 -222.310198)
		(width 0.1143)
		(layer "In4.Cu")
		(net "P5E_CPU1_G1_RX_DP<14>")
	)
	(segment
		(start 103.57104 -201.252582)
		(end 96.069912 -213.913466)
		(width 0.14224)
		(layer "In4.Cu")
		(net "P5E_CPU1_G1_RX_DP<14>")
	)
	(segment
		(start 32.351726 -40.060626)
		(end 32.35325 -40.062912)
		(width 0.14224)
		(layer "In4.Cu")
		(net "P5E_CPU1_G1_RX_DP<14>")
	)
	(segment
		(start 96.455484 -222.290386)
		(end 96.457008 -222.291402)
		(width 0.1143)
		(layer "In4.Cu")
		(net "P5E_CPU1_G1_RX_DP<14>")
	)
	(segment
		(start 97.831656 -227.94087)
		(end 97.867978 -227.961952)
		(width 0.1143)
		(layer "In4.Cu")
		(net "P5E_CPU1_G1_RX_DP<14>")
	)
	(segment
		(start 97.86874 -227.96246)
		(end 97.899728 -227.98024)
		(width 0.1143)
		(layer "In4.Cu")
		(net "P5E_CPU1_G1_RX_DP<14>")
	)
	(segment
		(start 96.928178 -223.747076)
		(end 96.889062 -223.769936)
		(width 0.1143)
		(layer "In4.Cu")
		(net "P5E_CPU1_G1_RX_DP<14>")
	)
	(segment
		(start 97.39757 -225.531426)
		(end 97.398078 -225.531934)
		(width 0.1143)
		(layer "In4.Cu")
		(net "P5E_CPU1_G1_RX_DP<14>")
	)
	(segment
		(start 16.834612 -19.197066)
		(end 16.863822 -19.357594)
		(width 0.14224)
		(layer "In4.Cu")
		(net "P5E_CPU1_G1_RX_DP<14>")
	)
	(segment
		(start 96.115632 -221.334076)
		(end 96.115632 -221.592902)
		(width 0.1143)
		(layer "In4.Cu")
		(net "P5E_CPU1_G1_RX_DP<14>")
	)
	(segment
		(start 17.49933 -20.381976)
		(end 20.718526 -24.097234)
		(width 0.14224)
		(layer "In4.Cu")
		(net "P5E_CPU1_G1_RX_DP<14>")
	)
	(segment
		(start 97.359724 -231.989376)
		(end 97.398586 -232.011982)
		(width 0.1143)
		(layer "In4.Cu")
		(net "P5E_CPU1_G1_RX_DP<14>")
	)
	(segment
		(start 96.454468 -222.289878)
		(end 96.455484 -222.290386)
		(width 0.1143)
		(layer "In4.Cu")
		(net "P5E_CPU1_G1_RX_DP<14>")
	)
	(arc
		(start 97.817432 -227.930964)
		(mid 97.824505 -227.935973)
		(end 97.831656 -227.94087)
		(width 0.1143)
		(layer "In4.Cu")
		(net "P5E_CPU1_G1_RX_DP<14>")
	)
	(arc
		(start 96.64573 -222.61449)
		(mid 96.710245 -222.876709)
		(end 96.889062 -223.079056)
		(width 0.1143)
		(layer "In4.Cu")
		(net "P5E_CPU1_G1_RX_DP<14>")
	)
	(arc
		(start 96.28505 -222.139002)
		(mid 96.346569 -222.209596)
		(end 96.418908 -222.26905)
		(width 0.1143)
		(layer "In4.Cu")
		(net "P5E_CPU1_G1_RX_DP<14>")
	)
	(arc
		(start 97.358962 -231.988868)
		(mid 97.359343 -231.989122)
		(end 97.359724 -231.989376)
		(width 0.1143)
		(layer "In4.Cu")
		(net "P5E_CPU1_G1_RX_DP<14>")
	)
	(arc
		(start 96.958658 -223.119696)
		(mid 97.115635 -223.424496)
		(end 96.958658 -223.729296)
		(width 0.1143)
		(layer "In4.Cu")
		(net "P5E_CPU1_G1_RX_DP<14>")
	)
	(arc
		(start 97.899728 -227.98024)
		(mid 98.055656 -228.284532)
		(end 97.899728 -228.588824)
		(width 0.1143)
		(layer "In4.Cu")
		(net "P5E_CPU1_G1_RX_DP<14>")
	)
	(arc
		(start 97.899728 -226.360228)
		(mid 98.055656 -226.66452)
		(end 97.899728 -226.968812)
		(width 0.1143)
		(layer "In4.Cu")
		(net "P5E_CPU1_G1_RX_DP<14>")
	)
	(arc
		(start 97.115884 -225.044508)
		(mid 97.191386 -225.32576)
		(end 97.39757 -225.531426)
		(width 0.1143)
		(layer "In4.Cu")
		(net "P5E_CPU1_G1_RX_DP<14>")
	)
	(arc
		(start 97.398586 -232.011982)
		(mid 97.531506 -232.145329)
		(end 97.580196 -232.327196)
		(width 0.1143)
		(layer "In4.Cu")
		(net "P5E_CPU1_G1_RX_DP<14>")
	)
	(arc
		(start 97.8154 -228.639624)
		(mid 97.650733 -228.838231)
		(end 97.585784 -229.087934)
		(width 0.1143)
		(layer "In4.Cu")
		(net "P5E_CPU1_G1_RX_DP<14>")
	)
	(arc
		(start 97.831656 -228.628194)
		(mid 97.823478 -228.633837)
		(end 97.8154 -228.639624)
		(width 0.1143)
		(layer "In4.Cu")
		(net "P5E_CPU1_G1_RX_DP<14>")
	)
	(arc
		(start 97.585784 -225.861626)
		(mid 97.651986 -226.112559)
		(end 97.818702 -226.31146)
		(width 0.1143)
		(layer "In4.Cu")
		(net "P5E_CPU1_G1_RX_DP<14>")
	)
	(arc
		(start 98.055938 -229.90429)
		(mid 98.00601 -230.09156)
		(end 97.869502 -230.229156)
		(width 0.1143)
		(layer "In4.Cu")
		(net "P5E_CPU1_G1_RX_DP<14>")
	)
	(arc
		(start 97.831656 -227.008182)
		(mid 97.824506 -227.01308)
		(end 97.817432 -227.018088)
		(width 0.1143)
		(layer "In4.Cu")
		(net "P5E_CPU1_G1_RX_DP<14>")
	)
	(arc
		(start 97.585784 -230.71455)
		(mid 97.543905 -230.886419)
		(end 97.427796 -231.019858)
		(width 0.1143)
		(layer "In4.Cu")
		(net "P5E_CPU1_G1_RX_DP<14>")
	)
	(arc
		(start 97.899728 -232.840022)
		(mid 97.996863 -232.942891)
		(end 98.048826 -233.074464)
		(width 0.1143)
		(layer "In4.Cu")
		(net "P5E_CPU1_G1_RX_DP<14>")
	)
	(arc
		(start 96.17583 -221.804484)
		(mid 96.203746 -221.98046)
		(end 96.28505 -222.139002)
		(width 0.1143)
		(layer "In4.Cu")
		(net "P5E_CPU1_G1_RX_DP<14>")
	)
	(arc
		(start 96.958658 -224.739708)
		(mid 97.074085 -224.873084)
		(end 97.11563 -225.044508)
		(width 0.1143)
		(layer "In4.Cu")
		(net "P5E_CPU1_G1_RX_DP<14>")
	)
	(arc
		(start 97.585784 -229.087934)
		(mid 97.585774 -229.091236)
		(end 97.585784 -229.094538)
		(width 0.1143)
		(layer "In4.Cu")
		(net "P5E_CPU1_G1_RX_DP<14>")
	)
	(arc
		(start 97.580196 -232.329736)
		(mid 97.656412 -232.613157)
		(end 97.864676 -232.819956)
		(width 0.1143)
		(layer "In4.Cu")
		(net "P5E_CPU1_G1_RX_DP<14>")
	)
	(arc
		(start 97.817432 -227.018088)
		(mid 97.590049 -227.474526)
		(end 97.817432 -227.930964)
		(width 0.1143)
		(layer "In4.Cu")
		(net "P5E_CPU1_G1_RX_DP<14>")
	)
	(arc
		(start 97.358962 -231.059736)
		(mid 97.115635 -231.524302)
		(end 97.358962 -231.988868)
		(width 0.1143)
		(layer "In4.Cu")
		(net "P5E_CPU1_G1_RX_DP<14>")
	)
	(arc
		(start 97.86493 -230.23195)
		(mid 97.660606 -230.435795)
		(end 97.585784 -230.71455)
		(width 0.1143)
		(layer "In4.Cu")
		(net "P5E_CPU1_G1_RX_DP<14>")
	)
	(arc
		(start 97.899728 -229.600252)
		(mid 98.014571 -229.7334)
		(end 98.055938 -229.90429)
		(width 0.1143)
		(layer "In4.Cu")
		(net "P5E_CPU1_G1_RX_DP<14>")
	)
	(arc
		(start 96.489774 -222.310198)
		(mid 96.60445 -222.443532)
		(end 96.64573 -222.61449)
		(width 0.1143)
		(layer "In4.Cu")
		(net "P5E_CPU1_G1_RX_DP<14>")
	)
	(arc
		(start 97.427542 -225.548952)
		(mid 97.543815 -225.682492)
		(end 97.585784 -225.854514)
		(width 0.1143)
		(layer "In4.Cu")
		(net "P5E_CPU1_G1_RX_DP<14>")
	)
	(arc
		(start 96.889062 -223.769936)
		(mid 96.645735 -224.234502)
		(end 96.889062 -224.699068)
		(width 0.1143)
		(layer "In4.Cu")
		(net "P5E_CPU1_G1_RX_DP<14>")
	)
	(arc
		(start 97.585784 -229.094538)
		(mid 97.65102 -229.358129)
		(end 97.831656 -229.560882)
		(width 0.1143)
		(layer "In4.Cu")
		(net "P5E_CPU1_G1_RX_DP<14>")
	)
	(segment
		(start 108.957872 -235.84027)
		(end 108.49102 -235.574332)
		(width 0.12954)
		(layer "F.Cu")
		(net "P5E_CPU1_G1_RX_DP<0>")
	)
	(segment
		(start 55.805832 -5.228844)
		(end 55.805832 -7.57047)
		(width 0.12954)
		(layer "F.Cu")
		(net "P5E_CPU1_G1_RX_DP<0>")
	)
	(segment
		(start 55.666894 -7.709408)
		(end 55.666894 -8.320024)
		(width 0.12954)
		(layer "F.Cu")
		(net "P5E_CPU1_G1_RX_DP<0>")
	)
	(segment
		(start 55.805832 -7.57047)
		(end 55.666894 -7.709408)
		(width 0.12954)
		(layer "F.Cu")
		(net "P5E_CPU1_G1_RX_DP<0>")
	)
	(segment
		(start 55.540402 -4.963414)
		(end 55.805832 -5.228844)
		(width 0.12954)
		(layer "F.Cu")
		(net "P5E_CPU1_G1_RX_DP<0>")
	)
	(segment
		(start 109.623606 -234.273598)
		(end 109.622844 -234.274106)
		(width 0.1143)
		(layer "In4.Cu")
		(net "P5E_CPU1_G1_RX_DP<0>")
	)
	(segment
		(start 110.088172 -233.466894)
		(end 110.049056 -233.489754)
		(width 0.1143)
		(layer "In4.Cu")
		(net "P5E_CPU1_G1_RX_DP<0>")
	)
	(segment
		(start 158.98241 -159.696404)
		(end 158.98241 -164.943028)
		(width 0.14224)
		(layer "In4.Cu")
		(net "P5E_CPU1_G1_RX_DP<0>")
	)
	(segment
		(start 56.769508 -18.229834)
		(end 56.40451 -18.77568)
		(width 0.14224)
		(layer "In4.Cu")
		(net "P5E_CPU1_G1_RX_DP<0>")
	)
	(segment
		(start 56.186578 -20.624546)
		(end 59.28868 -48.959008)
		(width 0.14224)
		(layer "In4.Cu")
		(net "P5E_CPU1_G1_RX_DP<0>")
	)
	(segment
		(start 109.649768 -234.258612)
		(end 109.629448 -234.270042)
		(width 0.1143)
		(layer "In4.Cu")
		(net "P5E_CPU1_G1_RX_DP<0>")
	)
	(segment
		(start 158.061914 -144.954752)
		(end 158.98241 -159.696404)
		(width 0.14224)
		(layer "In4.Cu")
		(net "P5E_CPU1_G1_RX_DP<0>")
	)
	(segment
		(start 56.991504 -17.815052)
		(end 56.769508 -18.229834)
		(width 0.14224)
		(layer "In4.Cu")
		(net "P5E_CPU1_G1_RX_DP<0>")
	)
	(segment
		(start 110.363254 -220.865954)
		(end 110.363254 -221.449646)
		(width 0.14224)
		(layer "In4.Cu")
		(net "P5E_CPU1_G1_RX_DP<0>")
	)
	(segment
		(start 109.621574 -234.274868)
		(end 109.62005 -234.27563)
		(width 0.1143)
		(layer "In4.Cu")
		(net "P5E_CPU1_G1_RX_DP<0>")
	)
	(segment
		(start 110.363254 -221.449646)
		(end 110.823248 -222.560642)
		(width 0.14224)
		(layer "In4.Cu")
		(net "P5E_CPU1_G1_RX_DP<0>")
	)
	(segment
		(start 110.565692 -233.0069)
		(end 110.164626 -233.407966)
		(width 0.1143)
		(layer "In4.Cu")
		(net "P5E_CPU1_G1_RX_DP<0>")
	)
	(segment
		(start 158.98241 -164.943028)
		(end 156.564838 -172.039026)
		(width 0.14224)
		(layer "In4.Cu")
		(net "P5E_CPU1_G1_RX_DP<0>")
	)
	(segment
		(start 110.823248 -232.685336)
		(end 110.585758 -232.922826)
		(width 0.14224)
		(layer "In4.Cu")
		(net "P5E_CPU1_G1_RX_DP<0>")
	)
	(segment
		(start 109.624876 -234.272836)
		(end 109.623606 -234.273598)
		(width 0.1143)
		(layer "In4.Cu")
		(net "P5E_CPU1_G1_RX_DP<0>")
	)
	(segment
		(start 59.28868 -48.959008)
		(end 60.309506 -50.951384)
		(width 0.14224)
		(layer "In4.Cu")
		(net "P5E_CPU1_G1_RX_DP<0>")
	)
	(segment
		(start 109.622844 -234.274106)
		(end 109.621574 -234.274868)
		(width 0.1143)
		(layer "In4.Cu")
		(net "P5E_CPU1_G1_RX_DP<0>")
	)
	(segment
		(start 156.228034 -172.955712)
		(end 152.73147 -177.87239)
		(width 0.14224)
		(layer "In4.Cu")
		(net "P5E_CPU1_G1_RX_DP<0>")
	)
	(segment
		(start 55.540402 -4.963414)
		(end 55.831232 -5.254244)
		(width 0.14224)
		(layer "In4.Cu")
		(net "P5E_CPU1_G1_RX_DP<0>")
	)
	(segment
		(start 56.40451 -18.77568)
		(end 56.34609 -18.91665)
		(width 0.14224)
		(layer "In4.Cu")
		(net "P5E_CPU1_G1_RX_DP<0>")
	)
	(segment
		(start 109.629448 -234.270042)
		(end 109.626908 -234.271566)
		(width 0.1143)
		(layer "In4.Cu")
		(net "P5E_CPU1_G1_RX_DP<0>")
	)
	(segment
		(start 109.626908 -234.271566)
		(end 109.624876 -234.272836)
		(width 0.1143)
		(layer "In4.Cu")
		(net "P5E_CPU1_G1_RX_DP<0>")
	)
	(segment
		(start 109.62005 -234.27563)
		(end 109.61878 -234.276392)
		(width 0.1143)
		(layer "In4.Cu")
		(net "P5E_CPU1_G1_RX_DP<0>")
	)
	(segment
		(start 114.214148 -209.455258)
		(end 110.363254 -215.941148)
		(width 0.14224)
		(layer "In4.Cu")
		(net "P5E_CPU1_G1_RX_DP<0>")
	)
	(segment
		(start 56.342026 -18.936462)
		(end 56.32831 -18.948146)
		(width 0.14224)
		(layer "In4.Cu")
		(net "P5E_CPU1_G1_RX_DP<0>")
	)
	(segment
		(start 110.363254 -220.167454)
		(end 110.226094 -220.304614)
		(width 0.14224)
		(layer "In4.Cu")
		(net "P5E_CPU1_G1_RX_DP<0>")
	)
	(segment
		(start 56.32831 -18.948146)
		(end 56.186578 -20.624546)
		(width 0.14224)
		(layer "In4.Cu")
		(net "P5E_CPU1_G1_RX_DP<0>")
	)
	(segment
		(start 109.618018 -234.2769)
		(end 109.608112 -234.282996)
		(width 0.1143)
		(layer "In4.Cu")
		(net "P5E_CPU1_G1_RX_DP<0>")
	)
	(segment
		(start 152.73147 -177.87239)
		(end 114.214148 -209.455258)
		(width 0.14224)
		(layer "In4.Cu")
		(net "P5E_CPU1_G1_RX_DP<0>")
	)
	(segment
		(start 110.585758 -232.922826)
		(end 110.565692 -232.942892)
		(width 0.1143)
		(layer "In4.Cu")
		(net "P5E_CPU1_G1_RX_DP<0>")
	)
	(segment
		(start 110.226094 -220.728794)
		(end 110.363254 -220.865954)
		(width 0.14224)
		(layer "In4.Cu")
		(net "P5E_CPU1_G1_RX_DP<0>")
	)
	(segment
		(start 110.565692 -232.942892)
		(end 110.565692 -233.0069)
		(width 0.1143)
		(layer "In4.Cu")
		(net "P5E_CPU1_G1_RX_DP<0>")
	)
	(segment
		(start 109.61878 -234.276392)
		(end 109.618018 -234.2769)
		(width 0.1143)
		(layer "In4.Cu")
		(net "P5E_CPU1_G1_RX_DP<0>")
	)
	(segment
		(start 110.226094 -220.304614)
		(end 110.226094 -220.728794)
		(width 0.14224)
		(layer "In4.Cu")
		(net "P5E_CPU1_G1_RX_DP<0>")
	)
	(segment
		(start 57.035446 -17.70888)
		(end 56.991504 -17.815052)
		(width 0.14224)
		(layer "In4.Cu")
		(net "P5E_CPU1_G1_RX_DP<0>")
	)
	(segment
		(start 109.221524 -235.044488)
		(end 109.109002 -235.109766)
		(width 0.1143)
		(layer "In4.Cu")
		(net "P5E_CPU1_G1_RX_DP<0>")
	)
	(segment
		(start 156.564838 -172.039026)
		(end 156.228034 -172.955712)
		(width 0.14224)
		(layer "In4.Cu")
		(net "P5E_CPU1_G1_RX_DP<0>")
	)
	(segment
		(start 60.309506 -50.951384)
		(end 152.91689 -134.226808)
		(width 0.14224)
		(layer "In4.Cu")
		(net "P5E_CPU1_G1_RX_DP<0>")
	)
	(segment
		(start 55.831232 -11.05408)
		(end 57.035446 -17.108424)
		(width 0.14224)
		(layer "In4.Cu")
		(net "P5E_CPU1_G1_RX_DP<0>")
	)
	(segment
		(start 152.91689 -134.226808)
		(end 158.061914 -144.954752)
		(width 0.14224)
		(layer "In4.Cu")
		(net "P5E_CPU1_G1_RX_DP<0>")
	)
	(segment
		(start 110.823248 -222.560642)
		(end 110.823248 -232.685336)
		(width 0.14224)
		(layer "In4.Cu")
		(net "P5E_CPU1_G1_RX_DP<0>")
	)
	(segment
		(start 56.34609 -18.91665)
		(end 56.342026 -18.936462)
		(width 0.14224)
		(layer "In4.Cu")
		(net "P5E_CPU1_G1_RX_DP<0>")
	)
	(segment
		(start 57.035446 -17.108424)
		(end 57.035446 -17.70888)
		(width 0.14224)
		(layer "In4.Cu")
		(net "P5E_CPU1_G1_RX_DP<0>")
	)
	(segment
		(start 110.363254 -215.941148)
		(end 110.363254 -220.167454)
		(width 0.14224)
		(layer "In4.Cu")
		(net "P5E_CPU1_G1_RX_DP<0>")
	)
	(segment
		(start 55.831232 -5.254244)
		(end 55.831232 -11.05408)
		(width 0.14224)
		(layer "In4.Cu")
		(net "P5E_CPU1_G1_RX_DP<0>")
	)
	(segment
		(start 108.788962 -235.574332)
		(end 108.49102 -235.574332)
		(width 0.1143)
		(layer "In4.Cu")
		(net "P5E_CPU1_G1_RX_DP<0>")
	)
	(segment
		(start 108.871766 -235.491528)
		(end 108.788962 -235.574332)
		(width 0.1143)
		(layer "In4.Cu")
		(net "P5E_CPU1_G1_RX_DP<0>")
	)
	(segment
		(start 109.348524 -234.743244)
		(end 109.348524 -234.82427)
		(width 0.1143)
		(layer "In4.Cu")
		(net "P5E_CPU1_G1_RX_DP<0>")
	)
	(arc
		(start 109.348524 -234.82427)
		(mid 109.314505 -234.951387)
		(end 109.221524 -235.044488)
		(width 0.1143)
		(layer "In4.Cu")
		(net "P5E_CPU1_G1_RX_DP<0>")
	)
	(arc
		(start 108.875576 -235.468668)
		(mid 108.873553 -235.480078)
		(end 108.871766 -235.491528)
		(width 0.1143)
		(layer "In4.Cu")
		(net "P5E_CPU1_G1_RX_DP<0>")
	)
	(arc
		(start 110.049056 -233.489754)
		(mid 109.870243 -233.692104)
		(end 109.805724 -233.95432)
		(width 0.1143)
		(layer "In4.Cu")
		(net "P5E_CPU1_G1_RX_DP<0>")
	)
	(arc
		(start 109.109002 -235.109766)
		(mid 108.957015 -235.266274)
		(end 108.875576 -235.468668)
		(width 0.1143)
		(layer "In4.Cu")
		(net "P5E_CPU1_G1_RX_DP<0>")
	)
	(arc
		(start 110.164626 -233.407966)
		(mid 110.128311 -233.43991)
		(end 110.088172 -233.466894)
		(width 0.1143)
		(layer "In4.Cu")
		(net "P5E_CPU1_G1_RX_DP<0>")
	)
	(arc
		(start 109.608112 -234.282996)
		(mid 109.417866 -234.47903)
		(end 109.348524 -234.743244)
		(width 0.1143)
		(layer "In4.Cu")
		(net "P5E_CPU1_G1_RX_DP<0>")
	)
	(arc
		(start 109.805724 -233.95432)
		(mid 109.764469 -234.125291)
		(end 109.649768 -234.258612)
		(width 0.1143)
		(layer "In4.Cu")
		(net "P5E_CPU1_G1_RX_DP<0>")
	)
	(segment
		(start 53.86705 -8.320024)
		(end 53.86705 -7.709154)
		(width 0.12954)
		(layer "F.Cu")
		(net "P5E_CPU1_G1_RX_DP<1>")
	)
	(segment
		(start 53.86705 -7.709154)
		(end 54.005734 -7.57047)
		(width 0.12954)
		(layer "F.Cu")
		(net "P5E_CPU1_G1_RX_DP<1>")
	)
	(segment
		(start 54.005734 -7.57047)
		(end 54.005734 -6.99516)
		(width 0.12954)
		(layer "F.Cu")
		(net "P5E_CPU1_G1_RX_DP<1>")
	)
	(segment
		(start 108.957872 -234.220258)
		(end 108.49102 -233.95432)
		(width 0.12954)
		(layer "F.Cu")
		(net "P5E_CPU1_G1_RX_DP<1>")
	)
	(segment
		(start 54.005734 -6.99516)
		(end 53.735732 -6.725158)
		(width 0.12954)
		(layer "F.Cu")
		(net "P5E_CPU1_G1_RX_DP<1>")
	)
	(segment
		(start 109.589316 -232.675684)
		(end 109.588554 -232.676446)
		(width 0.1143)
		(layer "In4.Cu")
		(net "P5E_CPU1_G1_RX_DP<1>")
	)
	(segment
		(start 155.41625 -172.460666)
		(end 151.998172 -177.26787)
		(width 0.14224)
		(layer "In4.Cu")
		(net "P5E_CPU1_G1_RX_DP<1>")
	)
	(segment
		(start 110.088172 -229.581964)
		(end 110.100872 -229.589076)
		(width 0.1143)
		(layer "In4.Cu")
		(net "P5E_CPU1_G1_RX_DP<1>")
	)
	(segment
		(start 108.876084 -233.84891)
		(end 108.875322 -233.84891)
		(width 0.1143)
		(layer "In4.Cu")
		(net "P5E_CPU1_G1_RX_DP<1>")
	)
	(segment
		(start 158.04896 -164.751258)
		(end 156.777436 -168.484042)
		(width 0.14224)
		(layer "In4.Cu")
		(net "P5E_CPU1_G1_RX_DP<1>")
	)
	(segment
		(start 109.180122 -223.728788)
		(end 109.107986 -223.770698)
		(width 0.1143)
		(layer "In4.Cu")
		(net "P5E_CPU1_G1_RX_DP<1>")
	)
	(segment
		(start 59.491626 -51.470052)
		(end 152.0825 -134.730744)
		(width 0.14224)
		(layer "In4.Cu")
		(net "P5E_CPU1_G1_RX_DP<1>")
	)
	(segment
		(start 109.116876 -233.485182)
		(end 109.10951 -233.489246)
		(width 0.1143)
		(layer "In4.Cu")
		(net "P5E_CPU1_G1_RX_DP<1>")
	)
	(segment
		(start 156.777182 -168.484042)
		(end 155.506166 -172.216318)
		(width 0.14224)
		(layer "In4.Cu")
		(net "P5E_CPU1_G1_RX_DP<1>")
	)
	(segment
		(start 109.290104 -221.304358)
		(end 109.290104 -221.332806)
		(width 0.1143)
		(layer "In4.Cu")
		(net "P5E_CPU1_G1_RX_DP<1>")
	)
	(segment
		(start 109.336078 -221.637606)
		(end 109.336078 -223.424242)
		(width 0.1143)
		(layer "In4.Cu")
		(net "P5E_CPU1_G1_RX_DP<1>")
	)
	(segment
		(start 54.020466 -12.52855)
		(end 53.523642 -17.57553)
		(width 0.14224)
		(layer "In4.Cu")
		(net "P5E_CPU1_G1_RX_DP<1>")
	)
	(segment
		(start 53.829458 -18.375122)
		(end 54.186582 -18.909284)
		(width 0.14224)
		(layer "In4.Cu")
		(net "P5E_CPU1_G1_RX_DP<1>")
	)
	(segment
		(start 109.140498 -224.717356)
		(end 109.142022 -224.718372)
		(width 0.1143)
		(layer "In4.Cu")
		(net "P5E_CPU1_G1_RX_DP<1>")
	)
	(segment
		(start 110.049056 -229.559104)
		(end 110.088172 -229.581964)
		(width 0.1143)
		(layer "In4.Cu")
		(net "P5E_CPU1_G1_RX_DP<1>")
	)
	(segment
		(start 109.147102 -224.72142)
		(end 109.148118 -224.721928)
		(width 0.1143)
		(layer "In4.Cu")
		(net "P5E_CPU1_G1_RX_DP<1>")
	)
	(segment
		(start 110.086394 -231.203754)
		(end 110.086902 -231.204008)
		(width 0.1143)
		(layer "In4.Cu")
		(net "P5E_CPU1_G1_RX_DP<1>")
	)
	(segment
		(start 109.290104 -215.886284)
		(end 109.290104 -221.304358)
		(width 0.14224)
		(layer "In4.Cu")
		(net "P5E_CPU1_G1_RX_DP<1>")
	)
	(segment
		(start 53.523642 -17.57553)
		(end 53.523642 -17.765014)
		(width 0.14224)
		(layer "In4.Cu")
		(net "P5E_CPU1_G1_RX_DP<1>")
	)
	(segment
		(start 156.777436 -168.484042)
		(end 156.777182 -168.484042)
		(width 0.14224)
		(layer "In4.Cu")
		(net "P5E_CPU1_G1_RX_DP<1>")
	)
	(segment
		(start 108.871766 -233.871516)
		(end 108.788962 -233.95432)
		(width 0.1143)
		(layer "In4.Cu")
		(net "P5E_CPU1_G1_RX_DP<1>")
	)
	(segment
		(start 110.049056 -227.939092)
		(end 110.118652 -227.979732)
		(width 0.1143)
		(layer "In4.Cu")
		(net "P5E_CPU1_G1_RX_DP<1>")
	)
	(segment
		(start 110.089188 -231.849676)
		(end 110.083092 -231.853232)
		(width 0.1143)
		(layer "In4.Cu")
		(net "P5E_CPU1_G1_RX_DP<1>")
	)
	(segment
		(start 110.275624 -231.524302)
		(end 110.27537 -231.524302)
		(width 0.1143)
		(layer "In4.Cu")
		(net "P5E_CPU1_G1_RX_DP<1>")
	)
	(segment
		(start 109.616748 -232.659428)
		(end 109.589316 -232.675684)
		(width 0.1143)
		(layer "In4.Cu")
		(net "P5E_CPU1_G1_RX_DP<1>")
	)
	(segment
		(start 54.223666 -18.9992)
		(end 54.244748 -19.104356)
		(width 0.14224)
		(layer "In4.Cu")
		(net "P5E_CPU1_G1_RX_DP<1>")
	)
	(segment
		(start 109.331252 -233.131868)
		(end 109.331252 -233.132122)
		(width 0.1143)
		(layer "In4.Cu")
		(net "P5E_CPU1_G1_RX_DP<1>")
	)
	(segment
		(start 58.23204 -49.08423)
		(end 59.491626 -51.470052)
		(width 0.14224)
		(layer "In4.Cu")
		(net "P5E_CPU1_G1_RX_DP<1>")
	)
	(segment
		(start 109.14888 -224.722436)
		(end 109.179868 -224.740216)
		(width 0.1143)
		(layer "In4.Cu")
		(net "P5E_CPU1_G1_RX_DP<1>")
	)
	(segment
		(start 110.223554 -231.714802)
		(end 110.224062 -231.714802)
		(width 0.1143)
		(layer "In4.Cu")
		(net "P5E_CPU1_G1_RX_DP<1>")
	)
	(segment
		(start 54.186582 -18.909284)
		(end 54.223666 -18.998692)
		(width 0.14224)
		(layer "In4.Cu")
		(net "P5E_CPU1_G1_RX_DP<1>")
	)
	(segment
		(start 109.109002 -224.699068)
		(end 109.140498 -224.717356)
		(width 0.1143)
		(layer "In4.Cu")
		(net "P5E_CPU1_G1_RX_DP<1>")
	)
	(segment
		(start 158.04896 -159.707326)
		(end 158.04896 -164.751258)
		(width 0.14224)
		(layer "In4.Cu")
		(net "P5E_CPU1_G1_RX_DP<1>")
	)
	(segment
		(start 54.026562 -12.498578)
		(end 54.020466 -12.52855)
		(width 0.14224)
		(layer "In4.Cu")
		(net "P5E_CPU1_G1_RX_DP<1>")
	)
	(segment
		(start 54.026562 -7.015988)
		(end 54.026562 -12.498578)
		(width 0.14224)
		(layer "In4.Cu")
		(net "P5E_CPU1_G1_RX_DP<1>")
	)
	(segment
		(start 109.290104 -221.332806)
		(end 109.335824 -221.378526)
		(width 0.1143)
		(layer "In4.Cu")
		(net "P5E_CPU1_G1_RX_DP<1>")
	)
	(segment
		(start 53.523642 -17.765014)
		(end 53.594254 -17.935702)
		(width 0.14224)
		(layer "In4.Cu")
		(net "P5E_CPU1_G1_RX_DP<1>")
	)
	(segment
		(start 109.134402 -233.475022)
		(end 109.116876 -233.485182)
		(width 0.1143)
		(layer "In4.Cu")
		(net "P5E_CPU1_G1_RX_DP<1>")
	)
	(segment
		(start 109.148118 -224.721928)
		(end 109.14888 -224.722436)
		(width 0.1143)
		(layer "In4.Cu")
		(net "P5E_CPU1_G1_RX_DP<1>")
	)
	(segment
		(start 110.118652 -230.20909)
		(end 110.051596 -230.248206)
		(width 0.1143)
		(layer "In4.Cu")
		(net "P5E_CPU1_G1_RX_DP<1>")
	)
	(segment
		(start 151.998172 -177.26787)
		(end 113.454434 -208.872074)
		(width 0.14224)
		(layer "In4.Cu")
		(net "P5E_CPU1_G1_RX_DP<1>")
	)
	(segment
		(start 53.735732 -6.725158)
		(end 54.026562 -7.015988)
		(width 0.14224)
		(layer "In4.Cu")
		(net "P5E_CPU1_G1_RX_DP<1>")
	)
	(segment
		(start 109.335824 -221.378526)
		(end 109.335824 -221.637352)
		(width 0.1143)
		(layer "In4.Cu")
		(net "P5E_CPU1_G1_RX_DP<1>")
	)
	(segment
		(start 110.118652 -226.96932)
		(end 110.049056 -227.00996)
		(width 0.1143)
		(layer "In4.Cu")
		(net "P5E_CPU1_G1_RX_DP<1>")
	)
	(segment
		(start 109.588554 -232.676446)
		(end 109.554772 -232.698798)
		(width 0.1143)
		(layer "In4.Cu")
		(net "P5E_CPU1_G1_RX_DP<1>")
	)
	(segment
		(start 152.0825 -134.730744)
		(end 157.14218 -145.194782)
		(width 0.14224)
		(layer "In4.Cu")
		(net "P5E_CPU1_G1_RX_DP<1>")
	)
	(segment
		(start 53.594254 -17.935702)
		(end 53.829458 -18.375122)
		(width 0.14224)
		(layer "In4.Cu")
		(net "P5E_CPU1_G1_RX_DP<1>")
	)
	(segment
		(start 110.086902 -231.204008)
		(end 110.092744 -231.20731)
		(width 0.1143)
		(layer "In4.Cu")
		(net "P5E_CPU1_G1_RX_DP<1>")
	)
	(segment
		(start 54.244748 -19.104356)
		(end 54.244748 -19.296634)
		(width 0.14224)
		(layer "In4.Cu")
		(net "P5E_CPU1_G1_RX_DP<1>")
	)
	(segment
		(start 155.506166 -172.216318)
		(end 155.41625 -172.460666)
		(width 0.14224)
		(layer "In4.Cu")
		(net "P5E_CPU1_G1_RX_DP<1>")
	)
	(segment
		(start 110.049056 -226.31908)
		(end 110.118652 -226.35972)
		(width 0.1143)
		(layer "In4.Cu")
		(net "P5E_CPU1_G1_RX_DP<1>")
	)
	(segment
		(start 109.579156 -225.509074)
		(end 109.648752 -225.549714)
		(width 0.1143)
		(layer "In4.Cu")
		(net "P5E_CPU1_G1_RX_DP<1>")
	)
	(segment
		(start 109.142022 -224.718372)
		(end 109.147102 -224.72142)
		(width 0.1143)
		(layer "In4.Cu")
		(net "P5E_CPU1_G1_RX_DP<1>")
	)
	(segment
		(start 54.223666 -18.998692)
		(end 54.223666 -18.9992)
		(width 0.14224)
		(layer "In4.Cu")
		(net "P5E_CPU1_G1_RX_DP<1>")
	)
	(segment
		(start 109.335824 -221.637352)
		(end 109.336078 -221.637606)
		(width 0.1143)
		(layer "In4.Cu")
		(net "P5E_CPU1_G1_RX_DP<1>")
	)
	(segment
		(start 113.454434 -208.872074)
		(end 109.290104 -215.886284)
		(width 0.14224)
		(layer "In4.Cu")
		(net "P5E_CPU1_G1_RX_DP<1>")
	)
	(segment
		(start 54.244748 -19.296634)
		(end 58.23204 -49.08423)
		(width 0.14224)
		(layer "In4.Cu")
		(net "P5E_CPU1_G1_RX_DP<1>")
	)
	(segment
		(start 108.788962 -233.95432)
		(end 108.49102 -233.95432)
		(width 0.1143)
		(layer "In4.Cu")
		(net "P5E_CPU1_G1_RX_DP<1>")
	)
	(segment
		(start 157.14218 -145.194782)
		(end 158.04896 -159.707326)
		(width 0.14224)
		(layer "In4.Cu")
		(net "P5E_CPU1_G1_RX_DP<1>")
	)
	(segment
		(start 110.118652 -228.589332)
		(end 110.049056 -228.629972)
		(width 0.1143)
		(layer "In4.Cu")
		(net "P5E_CPU1_G1_RX_DP<1>")
	)
	(arc
		(start 110.275624 -229.90429)
		(mid 110.231377 -230.074323)
		(end 110.118652 -230.20909)
		(width 0.1143)
		(layer "In4.Cu")
		(net "P5E_CPU1_G1_RX_DP<1>")
	)
	(arc
		(start 110.051596 -230.248206)
		(mid 109.870944 -230.450951)
		(end 109.805724 -230.71455)
		(width 0.1143)
		(layer "In4.Cu")
		(net "P5E_CPU1_G1_RX_DP<1>")
	)
	(arc
		(start 109.805724 -230.71455)
		(mid 109.880875 -230.99655)
		(end 110.086394 -231.203754)
		(width 0.1143)
		(layer "In4.Cu")
		(net "P5E_CPU1_G1_RX_DP<1>")
	)
	(arc
		(start 110.27537 -231.524302)
		(mid 110.262264 -231.623038)
		(end 110.223554 -231.714802)
		(width 0.1143)
		(layer "In4.Cu")
		(net "P5E_CPU1_G1_RX_DP<1>")
	)
	(arc
		(start 109.331252 -233.132122)
		(mid 109.278534 -233.329806)
		(end 109.134402 -233.475022)
		(width 0.1143)
		(layer "In4.Cu")
		(net "P5E_CPU1_G1_RX_DP<1>")
	)
	(arc
		(start 109.648752 -225.549714)
		(mid 109.764179 -225.68309)
		(end 109.805724 -225.854514)
		(width 0.1143)
		(layer "In4.Cu")
		(net "P5E_CPU1_G1_RX_DP<1>")
	)
	(arc
		(start 110.083092 -231.853232)
		(mid 109.881048 -232.056456)
		(end 109.805978 -232.333038)
		(width 0.1143)
		(layer "In4.Cu")
		(net "P5E_CPU1_G1_RX_DP<1>")
	)
	(arc
		(start 110.118652 -226.35972)
		(mid 110.275629 -226.66452)
		(end 110.118652 -226.96932)
		(width 0.1143)
		(layer "In4.Cu")
		(net "P5E_CPU1_G1_RX_DP<1>")
	)
	(arc
		(start 110.049056 -227.00996)
		(mid 109.805729 -227.474526)
		(end 110.049056 -227.939092)
		(width 0.1143)
		(layer "In4.Cu")
		(net "P5E_CPU1_G1_RX_DP<1>")
	)
	(arc
		(start 110.118652 -227.979732)
		(mid 110.275629 -228.284532)
		(end 110.118652 -228.589332)
		(width 0.1143)
		(layer "In4.Cu")
		(net "P5E_CPU1_G1_RX_DP<1>")
	)
	(arc
		(start 109.10951 -233.489246)
		(mid 108.957387 -233.646093)
		(end 108.876084 -233.84891)
		(width 0.1143)
		(layer "In4.Cu")
		(net "P5E_CPU1_G1_RX_DP<1>")
	)
	(arc
		(start 109.336078 -223.424242)
		(mid 109.294809 -223.595303)
		(end 109.180122 -223.728788)
		(width 0.1143)
		(layer "In4.Cu")
		(net "P5E_CPU1_G1_RX_DP<1>")
	)
	(arc
		(start 109.805724 -225.854514)
		(mid 109.870239 -226.116733)
		(end 110.049056 -226.31908)
		(width 0.1143)
		(layer "In4.Cu")
		(net "P5E_CPU1_G1_RX_DP<1>")
	)
	(arc
		(start 110.049056 -228.629972)
		(mid 109.805729 -229.094538)
		(end 110.049056 -229.559104)
		(width 0.1143)
		(layer "In4.Cu")
		(net "P5E_CPU1_G1_RX_DP<1>")
	)
	(arc
		(start 108.875322 -233.84891)
		(mid 108.873432 -233.860195)
		(end 108.871766 -233.871516)
		(width 0.1143)
		(layer "In4.Cu")
		(net "P5E_CPU1_G1_RX_DP<1>")
	)
	(arc
		(start 109.554772 -232.698798)
		(mid 109.390389 -232.88817)
		(end 109.331252 -233.131868)
		(width 0.1143)
		(layer "In4.Cu")
		(net "P5E_CPU1_G1_RX_DP<1>")
	)
	(arc
		(start 110.092744 -231.20731)
		(mid 110.22659 -231.341333)
		(end 110.275624 -231.524302)
		(width 0.1143)
		(layer "In4.Cu")
		(net "P5E_CPU1_G1_RX_DP<1>")
	)
	(arc
		(start 109.107986 -223.770698)
		(mid 108.865722 -224.235137)
		(end 109.109002 -224.699068)
		(width 0.1143)
		(layer "In4.Cu")
		(net "P5E_CPU1_G1_RX_DP<1>")
	)
	(arc
		(start 109.335824 -225.044508)
		(mid 109.400339 -225.306727)
		(end 109.579156 -225.509074)
		(width 0.1143)
		(layer "In4.Cu")
		(net "P5E_CPU1_G1_RX_DP<1>")
	)
	(arc
		(start 109.805978 -232.333038)
		(mid 109.75474 -232.521396)
		(end 109.616748 -232.659428)
		(width 0.1143)
		(layer "In4.Cu")
		(net "P5E_CPU1_G1_RX_DP<1>")
	)
	(arc
		(start 110.224062 -231.714802)
		(mid 110.165295 -231.790909)
		(end 110.089188 -231.849676)
		(width 0.1143)
		(layer "In4.Cu")
		(net "P5E_CPU1_G1_RX_DP<1>")
	)
	(arc
		(start 110.100872 -229.589076)
		(mid 110.231935 -229.722473)
		(end 110.275624 -229.90429)
		(width 0.1143)
		(layer "In4.Cu")
		(net "P5E_CPU1_G1_RX_DP<1>")
	)
	(arc
		(start 109.179868 -224.740216)
		(mid 109.294544 -224.87355)
		(end 109.335824 -225.044508)
		(width 0.1143)
		(layer "In4.Cu")
		(net "P5E_CPU1_G1_RX_DP<1>")
	)
	(segment
		(start 52.066952 -7.709154)
		(end 52.066952 -8.320024)
		(width 0.12954)
		(layer "F.Cu")
		(net "P5E_CPU1_G1_RX_DP<2>")
	)
	(segment
		(start 52.205636 -7.57047)
		(end 52.066952 -7.709154)
		(width 0.12954)
		(layer "F.Cu")
		(net "P5E_CPU1_G1_RX_DP<2>")
	)
	(segment
		(start 51.94046 -4.963414)
		(end 52.205636 -5.22859)
		(width 0.12954)
		(layer "F.Cu")
		(net "P5E_CPU1_G1_RX_DP<2>")
	)
	(segment
		(start 108.957872 -232.600246)
		(end 108.49102 -232.334308)
		(width 0.12954)
		(layer "F.Cu")
		(net "P5E_CPU1_G1_RX_DP<2>")
	)
	(segment
		(start 52.205636 -5.22859)
		(end 52.205636 -7.57047)
		(width 0.12954)
		(layer "F.Cu")
		(net "P5E_CPU1_G1_RX_DP<2>")
	)
	(segment
		(start 112.628934 -208.343246)
		(end 108.345224 -215.558116)
		(width 0.14224)
		(layer "In4.Cu")
		(net "P5E_CPU1_G1_RX_DP<2>")
	)
	(segment
		(start 109.148626 -231.846882)
		(end 109.109764 -231.869234)
		(width 0.1143)
		(layer "In4.Cu")
		(net "P5E_CPU1_G1_RX_DP<2>")
	)
	(segment
		(start 155.031694 -170.679364)
		(end 154.881326 -171.157646)
		(width 0.14224)
		(layer "In4.Cu")
		(net "P5E_CPU1_G1_RX_DP<2>")
	)
	(segment
		(start 56.952642 -48.982122)
		(end 59.093608 -52.676044)
		(width 0.14224)
		(layer "In4.Cu")
		(net "P5E_CPU1_G1_RX_DP<2>")
	)
	(segment
		(start 51.94046 -4.963414)
		(end 52.23129 -5.254244)
		(width 0.14224)
		(layer "In4.Cu")
		(net "P5E_CPU1_G1_RX_DP<2>")
	)
	(segment
		(start 50.729134 -19.811746)
		(end 50.758852 -20.029424)
		(width 0.14224)
		(layer "In4.Cu")
		(net "P5E_CPU1_G1_RX_DP<2>")
	)
	(segment
		(start 109.143546 -226.339146)
		(end 109.144054 -226.3394)
		(width 0.1143)
		(layer "In4.Cu")
		(net "P5E_CPU1_G1_RX_DP<2>")
	)
	(segment
		(start 109.147356 -231.201214)
		(end 109.148118 -231.201722)
		(width 0.1143)
		(layer "In4.Cu")
		(net "P5E_CPU1_G1_RX_DP<2>")
	)
	(segment
		(start 108.871766 -232.251504)
		(end 108.788962 -232.334308)
		(width 0.1143)
		(layer "In4.Cu")
		(net "P5E_CPU1_G1_RX_DP<2>")
	)
	(segment
		(start 109.148118 -229.581964)
		(end 109.181646 -229.601522)
		(width 0.1143)
		(layer "In4.Cu")
		(net "P5E_CPU1_G1_RX_DP<2>")
	)
	(segment
		(start 157.111954 -159.73679)
		(end 157.111954 -164.571172)
		(width 0.14224)
		(layer "In4.Cu")
		(net "P5E_CPU1_G1_RX_DP<2>")
	)
	(segment
		(start 108.396024 -221.642432)
		(end 108.396024 -221.804738)
		(width 0.1143)
		(layer "In4.Cu")
		(net "P5E_CPU1_G1_RX_DP<2>")
	)
	(segment
		(start 50.823622 -18.769584)
		(end 50.692558 -19.026124)
		(width 0.14224)
		(layer "In4.Cu")
		(net "P5E_CPU1_G1_RX_DP<2>")
	)
	(segment
		(start 109.142784 -228.61016)
		(end 109.13999 -228.611684)
		(width 0.1143)
		(layer "In4.Cu")
		(net "P5E_CPU1_G1_RX_DP<2>")
	)
	(segment
		(start 108.345224 -221.304358)
		(end 108.345224 -221.332806)
		(width 0.1143)
		(layer "In4.Cu")
		(net "P5E_CPU1_G1_RX_DP<2>")
	)
	(segment
		(start 109.109002 -229.559104)
		(end 109.148118 -229.581964)
		(width 0.1143)
		(layer "In4.Cu")
		(net "P5E_CPU1_G1_RX_DP<2>")
	)
	(segment
		(start 154.678126 -171.755308)
		(end 151.080216 -176.814734)
		(width 0.14224)
		(layer "In4.Cu")
		(net "P5E_CPU1_G1_RX_DP<2>")
	)
	(segment
		(start 109.109764 -227.9396)
		(end 109.116622 -227.943664)
		(width 0.1143)
		(layer "In4.Cu")
		(net "P5E_CPU1_G1_RX_DP<2>")
	)
	(segment
		(start 109.1438 -227.959412)
		(end 109.145324 -227.960428)
		(width 0.1143)
		(layer "In4.Cu")
		(net "P5E_CPU1_G1_RX_DP<2>")
	)
	(segment
		(start 109.149134 -226.986592)
		(end 109.147102 -226.987608)
		(width 0.1143)
		(layer "In4.Cu")
		(net "P5E_CPU1_G1_RX_DP<2>")
	)
	(segment
		(start 151.656796 -135.993124)
		(end 151.65451 -135.999728)
		(width 0.14224)
		(layer "In4.Cu")
		(net "P5E_CPU1_G1_RX_DP<2>")
	)
	(segment
		(start 108.239814 -224.740216)
		(end 108.241592 -224.741486)
		(width 0.1143)
		(layer "In4.Cu")
		(net "P5E_CPU1_G1_RX_DP<2>")
	)
	(segment
		(start 109.147102 -227.961444)
		(end 109.159548 -227.968556)
		(width 0.1143)
		(layer "In4.Cu")
		(net "P5E_CPU1_G1_RX_DP<2>")
	)
	(segment
		(start 60.278264 -53.648864)
		(end 61.181996 -54.460902)
		(width 0.14224)
		(layer "In4.Cu")
		(net "P5E_CPU1_G1_RX_DP<2>")
	)
	(segment
		(start 108.788962 -232.334308)
		(end 108.49102 -232.334308)
		(width 0.1143)
		(layer "In4.Cu")
		(net "P5E_CPU1_G1_RX_DP<2>")
	)
	(segment
		(start 109.138466 -228.6127)
		(end 109.109002 -228.629972)
		(width 0.1143)
		(layer "In4.Cu")
		(net "P5E_CPU1_G1_RX_DP<2>")
	)
	(segment
		(start 108.208064 -224.721928)
		(end 108.208826 -224.722436)
		(width 0.1143)
		(layer "In4.Cu")
		(net "P5E_CPU1_G1_RX_DP<2>")
	)
	(segment
		(start 109.145578 -230.228394)
		(end 109.144562 -230.228902)
		(width 0.1143)
		(layer "In4.Cu")
		(net "P5E_CPU1_G1_RX_DP<2>")
	)
	(segment
		(start 109.106716 -231.177592)
		(end 109.10697 -231.177592)
		(width 0.1143)
		(layer "In4.Cu")
		(net "P5E_CPU1_G1_RX_DP<2>")
	)
	(segment
		(start 151.437848 -135.539988)
		(end 151.656796 -135.993124)
		(width 0.14224)
		(layer "In4.Cu")
		(net "P5E_CPU1_G1_RX_DP<2>")
	)
	(segment
		(start 108.239814 -222.108776)
		(end 108.210096 -222.125794)
		(width 0.1143)
		(layer "In4.Cu")
		(net "P5E_CPU1_G1_RX_DP<2>")
	)
	(segment
		(start 62.472062 -55.54091)
		(end 151.437848 -135.539988)
		(width 0.14224)
		(layer "In4.Cu")
		(net "P5E_CPU1_G1_RX_DP<2>")
	)
	(segment
		(start 51.423824 -17.682972)
		(end 51.369468 -17.815052)
		(width 0.14224)
		(layer "In4.Cu")
		(net "P5E_CPU1_G1_RX_DP<2>")
	)
	(segment
		(start 109.13364 -227.95357)
		(end 109.135164 -227.954586)
		(width 0.1143)
		(layer "In4.Cu")
		(net "P5E_CPU1_G1_RX_DP<2>")
	)
	(segment
		(start 157.111954 -164.571172)
		(end 155.031694 -170.679364)
		(width 0.14224)
		(layer "In4.Cu")
		(net "P5E_CPU1_G1_RX_DP<2>")
	)
	(segment
		(start 109.149896 -230.225854)
		(end 109.147102 -230.227378)
		(width 0.1143)
		(layer "In4.Cu")
		(net "P5E_CPU1_G1_RX_DP<2>")
	)
	(segment
		(start 108.390944 -221.378526)
		(end 108.390944 -221.637352)
		(width 0.1143)
		(layer "In4.Cu")
		(net "P5E_CPU1_G1_RX_DP<2>")
	)
	(segment
		(start 51.369468 -17.815052)
		(end 51.14417 -18.23593)
		(width 0.14224)
		(layer "In4.Cu")
		(net "P5E_CPU1_G1_RX_DP<2>")
	)
	(segment
		(start 154.881326 -171.157646)
		(end 154.678126 -171.755308)
		(width 0.14224)
		(layer "In4.Cu")
		(net "P5E_CPU1_G1_RX_DP<2>")
	)
	(segment
		(start 108.345224 -221.332806)
		(end 108.390944 -221.378526)
		(width 0.1143)
		(layer "In4.Cu")
		(net "P5E_CPU1_G1_RX_DP<2>")
	)
	(segment
		(start 108.390944 -221.637352)
		(end 108.396024 -221.642432)
		(width 0.1143)
		(layer "In4.Cu")
		(net "P5E_CPU1_G1_RX_DP<2>")
	)
	(segment
		(start 109.144816 -226.339908)
		(end 109.149388 -226.342448)
		(width 0.1143)
		(layer "In4.Cu")
		(net "P5E_CPU1_G1_RX_DP<2>")
	)
	(segment
		(start 156.218382 -145.437352)
		(end 157.111954 -159.73679)
		(width 0.14224)
		(layer "In4.Cu")
		(net "P5E_CPU1_G1_RX_DP<2>")
	)
	(segment
		(start 109.117384 -227.944172)
		(end 109.13364 -227.95357)
		(width 0.1143)
		(layer "In4.Cu")
		(net "P5E_CPU1_G1_RX_DP<2>")
	)
	(segment
		(start 109.13999 -228.611684)
		(end 109.138466 -228.6127)
		(width 0.1143)
		(layer "In4.Cu")
		(net "P5E_CPU1_G1_RX_DP<2>")
	)
	(segment
		(start 109.10697 -231.177592)
		(end 109.147356 -231.201214)
		(width 0.1143)
		(layer "In4.Cu")
		(net "P5E_CPU1_G1_RX_DP<2>")
	)
	(segment
		(start 50.692558 -19.026124)
		(end 50.729134 -19.811746)
		(width 0.14224)
		(layer "In4.Cu")
		(net "P5E_CPU1_G1_RX_DP<2>")
	)
	(segment
		(start 108.240068 -223.728788)
		(end 108.166408 -223.770952)
		(width 0.1143)
		(layer "In4.Cu")
		(net "P5E_CPU1_G1_RX_DP<2>")
	)
	(segment
		(start 108.39577 -225.042476)
		(end 108.39577 -225.044508)
		(width 0.1143)
		(layer "In4.Cu")
		(net "P5E_CPU1_G1_RX_DP<2>")
	)
	(segment
		(start 151.65451 -135.999728)
		(end 156.218382 -145.437352)
		(width 0.14224)
		(layer "In4.Cu")
		(net "P5E_CPU1_G1_RX_DP<2>")
	)
	(segment
		(start 109.144054 -226.3394)
		(end 109.144816 -226.339908)
		(width 0.1143)
		(layer "In4.Cu")
		(net "P5E_CPU1_G1_RX_DP<2>")
	)
	(segment
		(start 52.23129 -13.624306)
		(end 51.423824 -17.682972)
		(width 0.14224)
		(layer "In4.Cu")
		(net "P5E_CPU1_G1_RX_DP<2>")
	)
	(segment
		(start 151.080216 -176.814734)
		(end 112.628934 -208.343246)
		(width 0.14224)
		(layer "In4.Cu")
		(net "P5E_CPU1_G1_RX_DP<2>")
	)
	(segment
		(start 108.205778 -224.720658)
		(end 108.208064 -224.721928)
		(width 0.1143)
		(layer "In4.Cu")
		(net "P5E_CPU1_G1_RX_DP<2>")
	)
	(segment
		(start 61.181996 -54.460902)
		(end 62.472062 -55.54091)
		(width 0.14224)
		(layer "In4.Cu")
		(net "P5E_CPU1_G1_RX_DP<2>")
	)
	(segment
		(start 109.14634 -227.960936)
		(end 109.147102 -227.961444)
		(width 0.1143)
		(layer "In4.Cu")
		(net "P5E_CPU1_G1_RX_DP<2>")
	)
	(segment
		(start 108.207048 -222.127572)
		(end 108.16717 -222.150686)
		(width 0.1143)
		(layer "In4.Cu")
		(net "P5E_CPU1_G1_RX_DP<2>")
	)
	(segment
		(start 109.147102 -230.227378)
		(end 109.145578 -230.228394)
		(width 0.1143)
		(layer "In4.Cu")
		(net "P5E_CPU1_G1_RX_DP<2>")
	)
	(segment
		(start 108.208826 -224.722436)
		(end 108.239814 -224.740216)
		(width 0.1143)
		(layer "In4.Cu")
		(net "P5E_CPU1_G1_RX_DP<2>")
	)
	(segment
		(start 108.156248 -223.069912)
		(end 108.16717 -223.078294)
		(width 0.1143)
		(layer "In4.Cu")
		(net "P5E_CPU1_G1_RX_DP<2>")
	)
	(segment
		(start 108.16717 -223.078294)
		(end 108.241338 -223.12122)
		(width 0.1143)
		(layer "In4.Cu")
		(net "P5E_CPU1_G1_RX_DP<2>")
	)
	(segment
		(start 51.14417 -18.23593)
		(end 50.823622 -18.769584)
		(width 0.14224)
		(layer "In4.Cu")
		(net "P5E_CPU1_G1_RX_DP<2>")
	)
	(segment
		(start 52.23129 -5.254244)
		(end 52.23129 -13.624306)
		(width 0.14224)
		(layer "In4.Cu")
		(net "P5E_CPU1_G1_RX_DP<2>")
	)
	(segment
		(start 109.147102 -226.987608)
		(end 109.109002 -227.00996)
		(width 0.1143)
		(layer "In4.Cu")
		(net "P5E_CPU1_G1_RX_DP<2>")
	)
	(segment
		(start 108.208064 -222.127064)
		(end 108.207048 -222.127572)
		(width 0.1143)
		(layer "In4.Cu")
		(net "P5E_CPU1_G1_RX_DP<2>")
	)
	(segment
		(start 109.142784 -226.338638)
		(end 109.143546 -226.339146)
		(width 0.1143)
		(layer "In4.Cu")
		(net "P5E_CPU1_G1_RX_DP<2>")
	)
	(segment
		(start 108.876084 -232.228898)
		(end 108.875322 -232.228898)
		(width 0.1143)
		(layer "In4.Cu")
		(net "P5E_CPU1_G1_RX_DP<2>")
	)
	(segment
		(start 109.116114 -230.245412)
		(end 109.111542 -230.248206)
		(width 0.1143)
		(layer "In4.Cu")
		(net "P5E_CPU1_G1_RX_DP<2>")
	)
	(segment
		(start 108.166408 -223.770952)
		(end 108.15447 -223.78035)
		(width 0.1143)
		(layer "In4.Cu")
		(net "P5E_CPU1_G1_RX_DP<2>")
	)
	(segment
		(start 59.093608 -52.676044)
		(end 60.278264 -53.648864)
		(width 0.14224)
		(layer "In4.Cu")
		(net "P5E_CPU1_G1_RX_DP<2>")
	)
	(segment
		(start 108.208826 -222.126556)
		(end 108.208064 -222.127064)
		(width 0.1143)
		(layer "In4.Cu")
		(net "P5E_CPU1_G1_RX_DP<2>")
	)
	(segment
		(start 109.116622 -227.943664)
		(end 109.117384 -227.944172)
		(width 0.1143)
		(layer "In4.Cu")
		(net "P5E_CPU1_G1_RX_DP<2>")
	)
	(segment
		(start 108.396024 -221.804738)
		(end 108.39577 -221.804484)
		(width 0.1143)
		(layer "In4.Cu")
		(net "P5E_CPU1_G1_RX_DP<2>")
	)
	(segment
		(start 50.758852 -20.029424)
		(end 56.952642 -48.982122)
		(width 0.14224)
		(layer "In4.Cu")
		(net "P5E_CPU1_G1_RX_DP<2>")
	)
	(segment
		(start 109.143546 -228.609652)
		(end 109.142784 -228.61016)
		(width 0.1143)
		(layer "In4.Cu")
		(net "P5E_CPU1_G1_RX_DP<2>")
	)
	(segment
		(start 109.145324 -227.960428)
		(end 109.14634 -227.960936)
		(width 0.1143)
		(layer "In4.Cu")
		(net "P5E_CPU1_G1_RX_DP<2>")
	)
	(segment
		(start 108.210096 -222.125794)
		(end 108.208826 -222.126556)
		(width 0.1143)
		(layer "In4.Cu")
		(net "P5E_CPU1_G1_RX_DP<2>")
	)
	(segment
		(start 108.345224 -215.558116)
		(end 108.345224 -221.304358)
		(width 0.14224)
		(layer "In4.Cu")
		(net "P5E_CPU1_G1_RX_DP<2>")
	)
	(segment
		(start 108.639102 -225.509074)
		(end 108.708698 -225.549714)
		(width 0.1143)
		(layer "In4.Cu")
		(net "P5E_CPU1_G1_RX_DP<2>")
	)
	(segment
		(start 109.159548 -228.600508)
		(end 109.143546 -228.609652)
		(width 0.1143)
		(layer "In4.Cu")
		(net "P5E_CPU1_G1_RX_DP<2>")
	)
	(segment
		(start 109.148118 -231.201722)
		(end 109.148626 -231.201722)
		(width 0.1143)
		(layer "In4.Cu")
		(net "P5E_CPU1_G1_RX_DP<2>")
	)
	(segment
		(start 108.16717 -222.150686)
		(end 108.156248 -222.159068)
		(width 0.1143)
		(layer "In4.Cu")
		(net "P5E_CPU1_G1_RX_DP<2>")
	)
	(segment
		(start 109.109764 -226.319588)
		(end 109.142784 -226.338638)
		(width 0.1143)
		(layer "In4.Cu")
		(net "P5E_CPU1_G1_RX_DP<2>")
	)
	(segment
		(start 109.135164 -227.954586)
		(end 109.1438 -227.959412)
		(width 0.1143)
		(layer "In4.Cu")
		(net "P5E_CPU1_G1_RX_DP<2>")
	)
	(segment
		(start 109.144562 -230.228902)
		(end 109.116114 -230.245412)
		(width 0.1143)
		(layer "In4.Cu")
		(net "P5E_CPU1_G1_RX_DP<2>")
	)
	(arc
		(start 109.109002 -226.31908)
		(mid 109.109383 -226.319334)
		(end 109.109764 -226.319588)
		(width 0.1143)
		(layer "In4.Cu")
		(net "P5E_CPU1_G1_RX_DP<2>")
	)
	(arc
		(start 108.32973 -222.016828)
		(mid 108.288747 -222.06669)
		(end 108.239814 -222.108776)
		(width 0.1143)
		(layer "In4.Cu")
		(net "P5E_CPU1_G1_RX_DP<2>")
	)
	(arc
		(start 109.148626 -231.201722)
		(mid 109.334264 -231.524302)
		(end 109.148626 -231.846882)
		(width 0.1143)
		(layer "In4.Cu")
		(net "P5E_CPU1_G1_RX_DP<2>")
	)
	(arc
		(start 109.109002 -228.629972)
		(mid 108.865675 -229.094538)
		(end 109.109002 -229.559104)
		(width 0.1143)
		(layer "In4.Cu")
		(net "P5E_CPU1_G1_RX_DP<2>")
	)
	(arc
		(start 107.92587 -224.234502)
		(mid 108.00085 -224.514986)
		(end 108.205778 -224.720658)
		(width 0.1143)
		(layer "In4.Cu")
		(net "P5E_CPU1_G1_RX_DP<2>")
	)
	(arc
		(start 108.156248 -222.159068)
		(mid 107.923917 -222.61449)
		(end 108.156248 -223.069912)
		(width 0.1143)
		(layer "In4.Cu")
		(net "P5E_CPU1_G1_RX_DP<2>")
	)
	(arc
		(start 108.39577 -221.804484)
		(mid 108.392812 -221.851983)
		(end 108.383832 -221.898718)
		(width 0.1143)
		(layer "In4.Cu")
		(net "P5E_CPU1_G1_RX_DP<2>")
	)
	(arc
		(start 109.109002 -227.00996)
		(mid 108.865675 -227.474526)
		(end 109.109002 -227.939092)
		(width 0.1143)
		(layer "In4.Cu")
		(net "P5E_CPU1_G1_RX_DP<2>")
	)
	(arc
		(start 109.149388 -226.342448)
		(mid 109.334713 -226.66463)
		(end 109.149134 -226.986592)
		(width 0.1143)
		(layer "In4.Cu")
		(net "P5E_CPU1_G1_RX_DP<2>")
	)
	(arc
		(start 108.241592 -224.741486)
		(mid 108.354997 -224.873381)
		(end 108.39577 -225.042476)
		(width 0.1143)
		(layer "In4.Cu")
		(net "P5E_CPU1_G1_RX_DP<2>")
	)
	(arc
		(start 108.39577 -225.044508)
		(mid 108.460285 -225.306727)
		(end 108.639102 -225.509074)
		(width 0.1143)
		(layer "In4.Cu")
		(net "P5E_CPU1_G1_RX_DP<2>")
	)
	(arc
		(start 108.383832 -221.898718)
		(mid 108.361954 -221.960144)
		(end 108.32973 -222.016828)
		(width 0.1143)
		(layer "In4.Cu")
		(net "P5E_CPU1_G1_RX_DP<2>")
	)
	(arc
		(start 109.109764 -231.869234)
		(mid 108.957434 -232.026019)
		(end 108.876084 -232.228898)
		(width 0.1143)
		(layer "In4.Cu")
		(net "P5E_CPU1_G1_RX_DP<2>")
	)
	(arc
		(start 109.335824 -229.90429)
		(mid 109.286001 -230.09002)
		(end 109.149896 -230.225854)
		(width 0.1143)
		(layer "In4.Cu")
		(net "P5E_CPU1_G1_RX_DP<2>")
	)
	(arc
		(start 109.181646 -229.601522)
		(mid 109.295053 -229.734411)
		(end 109.335824 -229.90429)
		(width 0.1143)
		(layer "In4.Cu")
		(net "P5E_CPU1_G1_RX_DP<2>")
	)
	(arc
		(start 107.92587 -224.226628)
		(mid 107.925855 -224.230565)
		(end 107.92587 -224.234502)
		(width 0.1143)
		(layer "In4.Cu")
		(net "P5E_CPU1_G1_RX_DP<2>")
	)
	(arc
		(start 108.241338 -223.12122)
		(mid 108.395915 -223.425308)
		(end 108.240068 -223.728788)
		(width 0.1143)
		(layer "In4.Cu")
		(net "P5E_CPU1_G1_RX_DP<2>")
	)
	(arc
		(start 108.15447 -223.78035)
		(mid 107.991272 -223.978434)
		(end 107.92587 -224.226628)
		(width 0.1143)
		(layer "In4.Cu")
		(net "P5E_CPU1_G1_RX_DP<2>")
	)
	(arc
		(start 108.875322 -232.228898)
		(mid 108.873432 -232.240183)
		(end 108.871766 -232.251504)
		(width 0.1143)
		(layer "In4.Cu")
		(net "P5E_CPU1_G1_RX_DP<2>")
	)
	(arc
		(start 109.159548 -227.968556)
		(mid 109.334498 -228.284532)
		(end 109.159548 -228.600508)
		(width 0.1143)
		(layer "In4.Cu")
		(net "P5E_CPU1_G1_RX_DP<2>")
	)
	(arc
		(start 108.708698 -225.549714)
		(mid 108.824125 -225.68309)
		(end 108.86567 -225.854514)
		(width 0.1143)
		(layer "In4.Cu")
		(net "P5E_CPU1_G1_RX_DP<2>")
	)
	(arc
		(start 108.86567 -225.854514)
		(mid 108.930185 -226.116733)
		(end 109.109002 -226.31908)
		(width 0.1143)
		(layer "In4.Cu")
		(net "P5E_CPU1_G1_RX_DP<2>")
	)
	(arc
		(start 109.111542 -230.248206)
		(mid 108.865659 -230.711626)
		(end 109.106716 -231.177592)
		(width 0.1143)
		(layer "In4.Cu")
		(net "P5E_CPU1_G1_RX_DP<2>")
	)
	(arc
		(start 109.109002 -227.939092)
		(mid 109.109383 -227.939346)
		(end 109.109764 -227.9396)
		(width 0.1143)
		(layer "In4.Cu")
		(net "P5E_CPU1_G1_RX_DP<2>")
	)
	(segment
		(start 106.607864 -235.030264)
		(end 106.141012 -234.764326)
		(width 0.12954)
		(layer "F.Cu")
		(net "P5E_CPU1_G1_RX_DP<3>")
	)
	(segment
		(start 50.267108 -8.320024)
		(end 50.267108 -7.709154)
		(width 0.12954)
		(layer "F.Cu")
		(net "P5E_CPU1_G1_RX_DP<3>")
	)
	(segment
		(start 50.405792 -6.99516)
		(end 50.13579 -6.725158)
		(width 0.12954)
		(layer "F.Cu")
		(net "P5E_CPU1_G1_RX_DP<3>")
	)
	(segment
		(start 50.405792 -7.57047)
		(end 50.405792 -6.99516)
		(width 0.12954)
		(layer "F.Cu")
		(net "P5E_CPU1_G1_RX_DP<3>")
	)
	(segment
		(start 50.267108 -7.709154)
		(end 50.405792 -7.57047)
		(width 0.12954)
		(layer "F.Cu")
		(net "P5E_CPU1_G1_RX_DP<3>")
	)
	(segment
		(start 155.269184 -145.619978)
		(end 156.153358 -159.767016)
		(width 0.14224)
		(layer "In4.Cu")
		(net "P5E_CPU1_G1_RX_DP<3>")
	)
	(segment
		(start 107.455716 -221.804738)
		(end 107.455462 -221.804484)
		(width 0.1143)
		(layer "In4.Cu")
		(net "P5E_CPU1_G1_RX_DP<3>")
	)
	(segment
		(start 108.208064 -231.201976)
		(end 108.241592 -231.221534)
		(width 0.1143)
		(layer "In4.Cu")
		(net "P5E_CPU1_G1_RX_DP<3>")
	)
	(segment
		(start 107.268264 -223.747076)
		(end 107.267248 -223.747584)
		(width 0.1143)
		(layer "In4.Cu")
		(net "P5E_CPU1_G1_RX_DP<3>")
	)
	(segment
		(start 108.207048 -228.60762)
		(end 108.205778 -228.608382)
		(width 0.1143)
		(layer "In4.Cu")
		(net "P5E_CPU1_G1_RX_DP<3>")
	)
	(segment
		(start 108.239814 -226.968812)
		(end 108.210096 -226.98583)
		(width 0.1143)
		(layer "In4.Cu")
		(net "P5E_CPU1_G1_RX_DP<3>")
	)
	(segment
		(start 107.25912 -233.472482)
		(end 107.257342 -233.473752)
		(width 0.1143)
		(layer "In4.Cu")
		(net "P5E_CPU1_G1_RX_DP<3>")
	)
	(segment
		(start 108.203492 -228.609906)
		(end 108.168948 -228.629972)
		(width 0.1143)
		(layer "In4.Cu")
		(net "P5E_CPU1_G1_RX_DP<3>")
	)
	(segment
		(start 107.455716 -221.64675)
		(end 107.455716 -221.804738)
		(width 0.1143)
		(layer "In4.Cu")
		(net "P5E_CPU1_G1_RX_DP<3>")
	)
	(segment
		(start 108.205778 -228.608382)
		(end 108.203492 -228.609906)
		(width 0.1143)
		(layer "In4.Cu")
		(net "P5E_CPU1_G1_RX_DP<3>")
	)
	(segment
		(start 108.212382 -227.964492)
		(end 108.213398 -227.965)
		(width 0.1143)
		(layer "In4.Cu")
		(net "P5E_CPU1_G1_RX_DP<3>")
	)
	(segment
		(start 108.239814 -230.208582)
		(end 108.21162 -230.224838)
		(width 0.1143)
		(layer "In4.Cu")
		(net "P5E_CPU1_G1_RX_DP<3>")
	)
	(segment
		(start 50.42662 -7.015988)
		(end 50.42662 -12.346178)
		(width 0.14224)
		(layer "In4.Cu")
		(net "P5E_CPU1_G1_RX_DP<3>")
	)
	(segment
		(start 108.204508 -227.95992)
		(end 108.205524 -227.960428)
		(width 0.1143)
		(layer "In4.Cu")
		(net "P5E_CPU1_G1_RX_DP<3>")
	)
	(segment
		(start 108.208064 -231.846882)
		(end 108.207048 -231.84739)
		(width 0.1143)
		(layer "In4.Cu")
		(net "P5E_CPU1_G1_RX_DP<3>")
	)
	(segment
		(start 107.259628 -222.14459)
		(end 107.176062 -222.19285)
		(width 0.1143)
		(layer "In4.Cu")
		(net "P5E_CPU1_G1_RX_DP<3>")
	)
	(segment
		(start 107.768644 -232.639108)
		(end 107.738164 -232.656888)
		(width 0.1143)
		(layer "In4.Cu")
		(net "P5E_CPU1_G1_RX_DP<3>")
	)
	(segment
		(start 108.205016 -230.228648)
		(end 108.202984 -230.229918)
		(width 0.1143)
		(layer "In4.Cu")
		(net "P5E_CPU1_G1_RX_DP<3>")
	)
	(segment
		(start 106.985816 -224.234502)
		(end 106.98607 -224.234502)
		(width 0.1143)
		(layer "In4.Cu")
		(net "P5E_CPU1_G1_RX_DP<3>")
	)
	(segment
		(start 108.198158 -227.95611)
		(end 108.199682 -227.957126)
		(width 0.1143)
		(layer "In4.Cu")
		(net "P5E_CPU1_G1_RX_DP<3>")
	)
	(segment
		(start 108.21162 -230.224838)
		(end 108.210096 -230.2256)
		(width 0.1143)
		(layer "In4.Cu")
		(net "P5E_CPU1_G1_RX_DP<3>")
	)
	(segment
		(start 108.198158 -226.336098)
		(end 108.199682 -226.337114)
		(width 0.1143)
		(layer "In4.Cu")
		(net "P5E_CPU1_G1_RX_DP<3>")
	)
	(segment
		(start 151.049482 -136.89076)
		(end 151.04872 -136.892284)
		(width 0.14224)
		(layer "In4.Cu")
		(net "P5E_CPU1_G1_RX_DP<3>")
	)
	(segment
		(start 59.670442 -54.356254)
		(end 60.570872 -55.165244)
		(width 0.14224)
		(layer "In4.Cu")
		(net "P5E_CPU1_G1_RX_DP<3>")
	)
	(segment
		(start 107.300014 -223.120204)
		(end 107.32008 -223.134682)
		(width 0.1143)
		(layer "In4.Cu")
		(net "P5E_CPU1_G1_RX_DP<3>")
	)
	(segment
		(start 108.205778 -226.98837)
		(end 108.203492 -226.989894)
		(width 0.1143)
		(layer "In4.Cu")
		(net "P5E_CPU1_G1_RX_DP<3>")
	)
	(segment
		(start 107.237784 -223.08439)
		(end 107.300014 -223.120204)
		(width 0.1143)
		(layer "In4.Cu")
		(net "P5E_CPU1_G1_RX_DP<3>")
	)
	(segment
		(start 49.0474 -20.333462)
		(end 55.687468 -48.870108)
		(width 0.14224)
		(layer "In4.Cu")
		(net "P5E_CPU1_G1_RX_DP<3>")
	)
	(segment
		(start 153.899108 -171.050712)
		(end 153.782268 -171.368974)
		(width 0.14224)
		(layer "In4.Cu")
		(net "P5E_CPU1_G1_RX_DP<3>")
	)
	(segment
		(start 108.168948 -226.31908)
		(end 108.198158 -226.336098)
		(width 0.1143)
		(layer "In4.Cu")
		(net "P5E_CPU1_G1_RX_DP<3>")
	)
	(segment
		(start 108.212382 -226.34448)
		(end 108.213398 -226.344988)
		(width 0.1143)
		(layer "In4.Cu")
		(net "P5E_CPU1_G1_RX_DP<3>")
	)
	(segment
		(start 107.267248 -223.747584)
		(end 107.229148 -223.769936)
		(width 0.1143)
		(layer "In4.Cu")
		(net "P5E_CPU1_G1_RX_DP<3>")
	)
	(segment
		(start 107.26166 -233.470958)
		(end 107.25912 -233.472482)
		(width 0.1143)
		(layer "In4.Cu")
		(net "P5E_CPU1_G1_RX_DP<3>")
	)
	(segment
		(start 48.207422 -18.375122)
		(end 48.215042 -18.386552)
		(width 0.14224)
		(layer "In4.Cu")
		(net "P5E_CPU1_G1_RX_DP<3>")
	)
	(segment
		(start 108.207048 -230.227378)
		(end 108.205778 -230.22814)
		(width 0.1143)
		(layer "In4.Cu")
		(net "P5E_CPU1_G1_RX_DP<3>")
	)
	(segment
		(start 108.204508 -226.339908)
		(end 108.205524 -226.340416)
		(width 0.1143)
		(layer "In4.Cu")
		(net "P5E_CPU1_G1_RX_DP<3>")
	)
	(segment
		(start 108.208064 -226.34194)
		(end 108.208826 -226.342448)
		(width 0.1143)
		(layer "In4.Cu")
		(net "P5E_CPU1_G1_RX_DP<3>")
	)
	(segment
		(start 108.21162 -227.963984)
		(end 108.212382 -227.964492)
		(width 0.1143)
		(layer "In4.Cu")
		(net "P5E_CPU1_G1_RX_DP<3>")
	)
	(segment
		(start 47.972218 -17.935702)
		(end 48.207422 -18.375122)
		(width 0.14224)
		(layer "In4.Cu")
		(net "P5E_CPU1_G1_RX_DP<3>")
	)
	(segment
		(start 108.21416 -226.345496)
		(end 108.2167 -226.346766)
		(width 0.1143)
		(layer "In4.Cu")
		(net "P5E_CPU1_G1_RX_DP<3>")
	)
	(segment
		(start 153.899362 -171.04995)
		(end 153.899108 -171.050712)
		(width 0.14224)
		(layer "In4.Cu")
		(net "P5E_CPU1_G1_RX_DP<3>")
	)
	(segment
		(start 107.32008 -223.71431)
		(end 107.300014 -223.728788)
		(width 0.1143)
		(layer "In4.Cu")
		(net "P5E_CPU1_G1_RX_DP<3>")
	)
	(segment
		(start 108.208064 -230.22687)
		(end 108.207048 -230.227378)
		(width 0.1143)
		(layer "In4.Cu")
		(net "P5E_CPU1_G1_RX_DP<3>")
	)
	(segment
		(start 108.205524 -227.960428)
		(end 108.207048 -227.961444)
		(width 0.1143)
		(layer "In4.Cu")
		(net "P5E_CPU1_G1_RX_DP<3>")
	)
	(segment
		(start 108.208064 -228.607112)
		(end 108.207048 -228.60762)
		(width 0.1143)
		(layer "In4.Cu")
		(net "P5E_CPU1_G1_RX_DP<3>")
	)
	(segment
		(start 107.229402 -224.699068)
		(end 107.268518 -224.721928)
		(width 0.1143)
		(layer "In4.Cu")
		(net "P5E_CPU1_G1_RX_DP<3>")
	)
	(segment
		(start 108.208064 -226.9871)
		(end 108.207048 -226.987608)
		(width 0.1143)
		(layer "In4.Cu")
		(net "P5E_CPU1_G1_RX_DP<3>")
	)
	(segment
		(start 107.400598 -221.304358)
		(end 107.400598 -221.332806)
		(width 0.1143)
		(layer "In4.Cu")
		(net "P5E_CPU1_G1_RX_DP<3>")
	)
	(segment
		(start 60.570872 -55.165244)
		(end 61.860938 -56.245252)
		(width 0.14224)
		(layer "In4.Cu")
		(net "P5E_CPU1_G1_RX_DP<3>")
	)
	(segment
		(start 107.272074 -223.74479)
		(end 107.270296 -223.745806)
		(width 0.1143)
		(layer "In4.Cu")
		(net "P5E_CPU1_G1_RX_DP<3>")
	)
	(segment
		(start 151.04872 -136.892284)
		(end 155.269184 -145.619978)
		(width 0.14224)
		(layer "In4.Cu")
		(net "P5E_CPU1_G1_RX_DP<3>")
	)
	(segment
		(start 108.2167 -226.346766)
		(end 108.239814 -226.360228)
		(width 0.1143)
		(layer "In4.Cu")
		(net "P5E_CPU1_G1_RX_DP<3>")
	)
	(segment
		(start 108.207048 -226.987608)
		(end 108.205778 -226.98837)
		(width 0.1143)
		(layer "In4.Cu")
		(net "P5E_CPU1_G1_RX_DP<3>")
	)
	(segment
		(start 108.202984 -230.229918)
		(end 108.171488 -230.248206)
		(width 0.1143)
		(layer "In4.Cu")
		(net "P5E_CPU1_G1_RX_DP<3>")
	)
	(segment
		(start 108.168948 -229.559104)
		(end 108.208064 -229.581964)
		(width 0.1143)
		(layer "In4.Cu")
		(net "P5E_CPU1_G1_RX_DP<3>")
	)
	(segment
		(start 108.208826 -231.846374)
		(end 108.208064 -231.846882)
		(width 0.1143)
		(layer "In4.Cu")
		(net "P5E_CPU1_G1_RX_DP<3>")
	)
	(segment
		(start 107.701842 -225.510852)
		(end 107.738164 -225.531934)
		(width 0.1143)
		(layer "In4.Cu")
		(net "P5E_CPU1_G1_RX_DP<3>")
	)
	(segment
		(start 108.205778 -231.848152)
		(end 108.203492 -231.849676)
		(width 0.1143)
		(layer "In4.Cu")
		(net "P5E_CPU1_G1_RX_DP<3>")
	)
	(segment
		(start 150.334218 -176.219612)
		(end 111.924592 -207.700626)
		(width 0.14224)
		(layer "In4.Cu")
		(net "P5E_CPU1_G1_RX_DP<3>")
	)
	(segment
		(start 61.860938 -56.245252)
		(end 150.668482 -136.10209)
		(width 0.14224)
		(layer "In4.Cu")
		(net "P5E_CPU1_G1_RX_DP<3>")
	)
	(segment
		(start 156.153358 -164.457126)
		(end 154.016202 -170.731688)
		(width 0.14224)
		(layer "In4.Cu")
		(net "P5E_CPU1_G1_RX_DP<3>")
	)
	(segment
		(start 108.210096 -228.605842)
		(end 108.208826 -228.606604)
		(width 0.1143)
		(layer "In4.Cu")
		(net "P5E_CPU1_G1_RX_DP<3>")
	)
	(segment
		(start 107.270042 -233.465624)
		(end 107.268772 -233.466386)
		(width 0.1143)
		(layer "In4.Cu")
		(net "P5E_CPU1_G1_RX_DP<3>")
	)
	(segment
		(start 108.208826 -228.606604)
		(end 108.208064 -228.607112)
		(width 0.1143)
		(layer "In4.Cu")
		(net "P5E_CPU1_G1_RX_DP<3>")
	)
	(segment
		(start 108.208826 -227.96246)
		(end 108.21162 -227.963984)
		(width 0.1143)
		(layer "In4.Cu")
		(net "P5E_CPU1_G1_RX_DP<3>")
	)
	(segment
		(start 107.446318 -221.637352)
		(end 107.455716 -221.64675)
		(width 0.1143)
		(layer "In4.Cu")
		(net "P5E_CPU1_G1_RX_DP<3>")
	)
	(segment
		(start 107.446318 -221.378526)
		(end 107.446318 -221.637352)
		(width 0.1143)
		(layer "In4.Cu")
		(net "P5E_CPU1_G1_RX_DP<3>")
	)
	(segment
		(start 108.239814 -228.588824)
		(end 108.210096 -228.605842)
		(width 0.1143)
		(layer "In4.Cu")
		(net "P5E_CPU1_G1_RX_DP<3>")
	)
	(segment
		(start 107.738164 -225.531934)
		(end 107.768644 -225.549714)
		(width 0.1143)
		(layer "In4.Cu")
		(net "P5E_CPU1_G1_RX_DP<3>")
	)
	(segment
		(start 55.687468 -48.870108)
		(end 58.230262 -53.17363)
		(width 0.14224)
		(layer "In4.Cu")
		(net "P5E_CPU1_G1_RX_DP<3>")
	)
	(segment
		(start 108.207048 -226.341432)
		(end 108.208064 -226.34194)
		(width 0.1143)
		(layer "In4.Cu")
		(net "P5E_CPU1_G1_RX_DP<3>")
	)
	(segment
		(start 48.496728 -16.426942)
		(end 47.952914 -17.240504)
		(width 0.14224)
		(layer "In4.Cu")
		(net "P5E_CPU1_G1_RX_DP<3>")
	)
	(segment
		(start 107.230418 -223.080072)
		(end 107.237022 -223.083882)
		(width 0.1143)
		(layer "In4.Cu")
		(net "P5E_CPU1_G1_RX_DP<3>")
	)
	(segment
		(start 108.205524 -226.340416)
		(end 108.207048 -226.341432)
		(width 0.1143)
		(layer "In4.Cu")
		(net "P5E_CPU1_G1_RX_DP<3>")
	)
	(segment
		(start 108.199682 -226.337114)
		(end 108.204508 -226.339908)
		(width 0.1143)
		(layer "In4.Cu")
		(net "P5E_CPU1_G1_RX_DP<3>")
	)
	(segment
		(start 50.42662 -12.346178)
		(end 48.496728 -16.426942)
		(width 0.14224)
		(layer "In4.Cu")
		(net "P5E_CPU1_G1_RX_DP<3>")
	)
	(segment
		(start 107.400598 -221.332806)
		(end 107.446318 -221.378526)
		(width 0.1143)
		(layer "In4.Cu")
		(net "P5E_CPU1_G1_RX_DP<3>")
	)
	(segment
		(start 108.2167 -227.966778)
		(end 108.239814 -227.98024)
		(width 0.1143)
		(layer "In4.Cu")
		(net "P5E_CPU1_G1_RX_DP<3>")
	)
	(segment
		(start 108.21416 -227.965508)
		(end 108.2167 -227.966778)
		(width 0.1143)
		(layer "In4.Cu")
		(net "P5E_CPU1_G1_RX_DP<3>")
	)
	(segment
		(start 107.300014 -223.728788)
		(end 107.272836 -223.744282)
		(width 0.1143)
		(layer "In4.Cu")
		(net "P5E_CPU1_G1_RX_DP<3>")
	)
	(segment
		(start 108.203492 -226.989894)
		(end 108.168948 -227.00996)
		(width 0.1143)
		(layer "In4.Cu")
		(net "P5E_CPU1_G1_RX_DP<3>")
	)
	(segment
		(start 107.237022 -223.083882)
		(end 107.237784 -223.08439)
		(width 0.1143)
		(layer "In4.Cu")
		(net "P5E_CPU1_G1_RX_DP<3>")
	)
	(segment
		(start 47.901606 -17.765014)
		(end 47.972218 -17.935702)
		(width 0.14224)
		(layer "In4.Cu")
		(net "P5E_CPU1_G1_RX_DP<3>")
	)
	(segment
		(start 48.215296 -18.386552)
		(end 48.564546 -18.909538)
		(width 0.14224)
		(layer "In4.Cu")
		(net "P5E_CPU1_G1_RX_DP<3>")
	)
	(segment
		(start 108.208826 -226.986592)
		(end 108.208064 -226.9871)
		(width 0.1143)
		(layer "In4.Cu")
		(net "P5E_CPU1_G1_RX_DP<3>")
	)
	(segment
		(start 108.208064 -227.961952)
		(end 108.208826 -227.96246)
		(width 0.1143)
		(layer "In4.Cu")
		(net "P5E_CPU1_G1_RX_DP<3>")
	)
	(segment
		(start 156.153358 -159.767016)
		(end 156.153358 -164.457126)
		(width 0.14224)
		(layer "In4.Cu")
		(net "P5E_CPU1_G1_RX_DP<3>")
	)
	(segment
		(start 50.13579 -6.725158)
		(end 50.42662 -7.015988)
		(width 0.14224)
		(layer "In4.Cu")
		(net "P5E_CPU1_G1_RX_DP<3>")
	)
	(segment
		(start 107.738164 -232.656888)
		(end 107.699048 -232.679748)
		(width 0.1143)
		(layer "In4.Cu")
		(net "P5E_CPU1_G1_RX_DP<3>")
	)
	(segment
		(start 107.29976 -233.448606)
		(end 107.270042 -233.465624)
		(width 0.1143)
		(layer "In4.Cu")
		(net "P5E_CPU1_G1_RX_DP<3>")
	)
	(segment
		(start 107.272836 -223.744282)
		(end 107.272074 -223.74479)
		(width 0.1143)
		(layer "In4.Cu")
		(net "P5E_CPU1_G1_RX_DP<3>")
	)
	(segment
		(start 106.438954 -234.764326)
		(end 106.141012 -234.764326)
		(width 0.1143)
		(layer "In4.Cu")
		(net "P5E_CPU1_G1_RX_DP<3>")
	)
	(segment
		(start 106.521758 -234.681522)
		(end 106.438954 -234.764326)
		(width 0.1143)
		(layer "In4.Cu")
		(net "P5E_CPU1_G1_RX_DP<3>")
	)
	(segment
		(start 107.400598 -215.319864)
		(end 107.400598 -221.304358)
		(width 0.14224)
		(layer "In4.Cu")
		(net "P5E_CPU1_G1_RX_DP<3>")
	)
	(segment
		(start 48.564546 -18.909538)
		(end 49.0474 -20.333462)
		(width 0.14224)
		(layer "In4.Cu")
		(net "P5E_CPU1_G1_RX_DP<3>")
	)
	(segment
		(start 108.210096 -231.845612)
		(end 108.208826 -231.846374)
		(width 0.1143)
		(layer "In4.Cu")
		(net "P5E_CPU1_G1_RX_DP<3>")
	)
	(segment
		(start 108.207048 -227.961444)
		(end 108.208064 -227.961952)
		(width 0.1143)
		(layer "In4.Cu")
		(net "P5E_CPU1_G1_RX_DP<3>")
	)
	(segment
		(start 108.239814 -231.828594)
		(end 108.210096 -231.845612)
		(width 0.1143)
		(layer "In4.Cu")
		(net "P5E_CPU1_G1_RX_DP<3>")
	)
	(segment
		(start 108.208826 -226.342448)
		(end 108.21162 -226.343972)
		(width 0.1143)
		(layer "In4.Cu")
		(net "P5E_CPU1_G1_RX_DP<3>")
	)
	(segment
		(start 47.901606 -17.410176)
		(end 47.901606 -17.765014)
		(width 0.14224)
		(layer "In4.Cu")
		(net "P5E_CPU1_G1_RX_DP<3>")
	)
	(segment
		(start 108.203492 -231.849676)
		(end 108.168948 -231.869742)
		(width 0.1143)
		(layer "In4.Cu")
		(net "P5E_CPU1_G1_RX_DP<3>")
	)
	(segment
		(start 107.268518 -224.721928)
		(end 107.298998 -224.739708)
		(width 0.1143)
		(layer "In4.Cu")
		(net "P5E_CPU1_G1_RX_DP<3>")
	)
	(segment
		(start 107.270296 -223.745806)
		(end 107.269026 -223.746568)
		(width 0.1143)
		(layer "In4.Cu")
		(net "P5E_CPU1_G1_RX_DP<3>")
	)
	(segment
		(start 106.82478 -234.261406)
		(end 106.758994 -234.299506)
		(width 0.1143)
		(layer "In4.Cu")
		(net "P5E_CPU1_G1_RX_DP<3>")
	)
	(segment
		(start 154.016202 -170.731688)
		(end 153.899362 -171.04995)
		(width 0.14224)
		(layer "In4.Cu")
		(net "P5E_CPU1_G1_RX_DP<3>")
	)
	(segment
		(start 108.210096 -230.2256)
		(end 108.208826 -230.226362)
		(width 0.1143)
		(layer "In4.Cu")
		(net "P5E_CPU1_G1_RX_DP<3>")
	)
	(segment
		(start 108.208826 -230.226362)
		(end 108.208064 -230.22687)
		(width 0.1143)
		(layer "In4.Cu")
		(net "P5E_CPU1_G1_RX_DP<3>")
	)
	(segment
		(start 108.208064 -229.581964)
		(end 108.241592 -229.601522)
		(width 0.1143)
		(layer "In4.Cu")
		(net "P5E_CPU1_G1_RX_DP<3>")
	)
	(segment
		(start 111.924592 -207.700626)
		(end 107.400598 -215.319864)
		(width 0.14224)
		(layer "In4.Cu")
		(net "P5E_CPU1_G1_RX_DP<3>")
	)
	(segment
		(start 108.21162 -226.343972)
		(end 108.212382 -226.34448)
		(width 0.1143)
		(layer "In4.Cu")
		(net "P5E_CPU1_G1_RX_DP<3>")
	)
	(segment
		(start 106.98607 -224.234502)
		(end 106.987594 -224.25914)
		(width 0.1143)
		(layer "In4.Cu")
		(net "P5E_CPU1_G1_RX_DP<3>")
	)
	(segment
		(start 108.168948 -227.939092)
		(end 108.198158 -227.95611)
		(width 0.1143)
		(layer "In4.Cu")
		(net "P5E_CPU1_G1_RX_DP<3>")
	)
	(segment
		(start 108.213398 -226.344988)
		(end 108.21416 -226.345496)
		(width 0.1143)
		(layer "In4.Cu")
		(net "P5E_CPU1_G1_RX_DP<3>")
	)
	(segment
		(start 48.215042 -18.386552)
		(end 48.215296 -18.386552)
		(width 0.14224)
		(layer "In4.Cu")
		(net "P5E_CPU1_G1_RX_DP<3>")
	)
	(segment
		(start 153.782268 -171.368974)
		(end 150.334218 -176.219612)
		(width 0.14224)
		(layer "In4.Cu")
		(net "P5E_CPU1_G1_RX_DP<3>")
	)
	(segment
		(start 108.207048 -231.84739)
		(end 108.205778 -231.848152)
		(width 0.1143)
		(layer "In4.Cu")
		(net "P5E_CPU1_G1_RX_DP<3>")
	)
	(segment
		(start 107.268772 -233.466386)
		(end 107.26166 -233.470958)
		(width 0.1143)
		(layer "In4.Cu")
		(net "P5E_CPU1_G1_RX_DP<3>")
	)
	(segment
		(start 108.199682 -227.957126)
		(end 108.204508 -227.95992)
		(width 0.1143)
		(layer "In4.Cu")
		(net "P5E_CPU1_G1_RX_DP<3>")
	)
	(segment
		(start 58.230262 -53.17363)
		(end 59.670442 -54.356254)
		(width 0.14224)
		(layer "In4.Cu")
		(net "P5E_CPU1_G1_RX_DP<3>")
	)
	(segment
		(start 107.269026 -223.746568)
		(end 107.268264 -223.747076)
		(width 0.1143)
		(layer "In4.Cu")
		(net "P5E_CPU1_G1_RX_DP<3>")
	)
	(segment
		(start 108.205778 -230.22814)
		(end 108.205016 -230.228648)
		(width 0.1143)
		(layer "In4.Cu")
		(net "P5E_CPU1_G1_RX_DP<3>")
	)
	(segment
		(start 108.210096 -226.98583)
		(end 108.208826 -226.986592)
		(width 0.1143)
		(layer "In4.Cu")
		(net "P5E_CPU1_G1_RX_DP<3>")
	)
	(segment
		(start 108.213398 -227.965)
		(end 108.21416 -227.965508)
		(width 0.1143)
		(layer "In4.Cu")
		(net "P5E_CPU1_G1_RX_DP<3>")
	)
	(segment
		(start 150.668482 -136.10209)
		(end 151.049482 -136.89076)
		(width 0.14224)
		(layer "In4.Cu")
		(net "P5E_CPU1_G1_RX_DP<3>")
	)
	(segment
		(start 47.952914 -17.240504)
		(end 47.901606 -17.410176)
		(width 0.14224)
		(layer "In4.Cu")
		(net "P5E_CPU1_G1_RX_DP<3>")
	)
	(segment
		(start 108.168948 -231.179116)
		(end 108.208064 -231.201976)
		(width 0.1143)
		(layer "In4.Cu")
		(net "P5E_CPU1_G1_RX_DP<3>")
	)
	(arc
		(start 108.241592 -229.601522)
		(mid 108.354999 -229.734411)
		(end 108.39577 -229.90429)
		(width 0.1143)
		(layer "In4.Cu")
		(net "P5E_CPU1_G1_RX_DP<3>")
	)
	(arc
		(start 107.199938 -224.675954)
		(mid 107.208756 -224.683156)
		(end 107.217718 -224.690178)
		(width 0.1143)
		(layer "In4.Cu")
		(net "P5E_CPU1_G1_RX_DP<3>")
	)
	(arc
		(start 107.768644 -225.549714)
		(mid 107.884071 -225.68309)
		(end 107.925616 -225.854514)
		(width 0.1143)
		(layer "In4.Cu")
		(net "P5E_CPU1_G1_RX_DP<3>")
	)
	(arc
		(start 108.168948 -228.629972)
		(mid 107.925621 -229.094538)
		(end 108.168948 -229.559104)
		(width 0.1143)
		(layer "In4.Cu")
		(net "P5E_CPU1_G1_RX_DP<3>")
	)
	(arc
		(start 106.526076 -234.658916)
		(mid 106.523801 -234.670197)
		(end 106.521758 -234.681522)
		(width 0.1143)
		(layer "In4.Cu")
		(net "P5E_CPU1_G1_RX_DP<3>")
	)
	(arc
		(start 107.257342 -233.473752)
		(mid 107.064964 -233.680216)
		(end 106.985562 -233.951018)
		(width 0.1143)
		(layer "In4.Cu")
		(net "P5E_CPU1_G1_RX_DP<3>")
	)
	(arc
		(start 107.217718 -224.690178)
		(mid 107.22353 -224.694662)
		(end 107.229402 -224.699068)
		(width 0.1143)
		(layer "In4.Cu")
		(net "P5E_CPU1_G1_RX_DP<3>")
	)
	(arc
		(start 106.758994 -234.299506)
		(mid 106.607158 -234.456291)
		(end 106.526076 -234.658916)
		(width 0.1143)
		(layer "In4.Cu")
		(net "P5E_CPU1_G1_RX_DP<3>")
	)
	(arc
		(start 107.699048 -232.679748)
		(mid 107.520235 -232.882098)
		(end 107.455716 -233.144314)
		(width 0.1143)
		(layer "In4.Cu")
		(net "P5E_CPU1_G1_RX_DP<3>")
	)
	(arc
		(start 107.925616 -230.71455)
		(mid 107.990131 -230.976769)
		(end 108.168948 -231.179116)
		(width 0.1143)
		(layer "In4.Cu")
		(net "P5E_CPU1_G1_RX_DP<3>")
	)
	(arc
		(start 107.455462 -221.804484)
		(mid 107.403074 -222.000763)
		(end 107.259628 -222.14459)
		(width 0.1143)
		(layer "In4.Cu")
		(net "P5E_CPU1_G1_RX_DP<3>")
	)
	(arc
		(start 107.176062 -222.19285)
		(mid 107.165781 -222.202632)
		(end 107.155742 -222.212662)
		(width 0.1143)
		(layer "In4.Cu")
		(net "P5E_CPU1_G1_RX_DP<3>")
	)
	(arc
		(start 107.32008 -223.134682)
		(mid 107.468587 -223.424496)
		(end 107.32008 -223.71431)
		(width 0.1143)
		(layer "In4.Cu")
		(net "P5E_CPU1_G1_RX_DP<3>")
	)
	(arc
		(start 107.925616 -232.334308)
		(mid 107.884067 -232.50573)
		(end 107.768644 -232.639108)
		(width 0.1143)
		(layer "In4.Cu")
		(net "P5E_CPU1_G1_RX_DP<3>")
	)
	(arc
		(start 107.925616 -225.854514)
		(mid 107.990131 -226.116733)
		(end 108.168948 -226.31908)
		(width 0.1143)
		(layer "In4.Cu")
		(net "P5E_CPU1_G1_RX_DP<3>")
	)
	(arc
		(start 106.985562 -233.951018)
		(mid 106.938671 -234.123566)
		(end 106.82478 -234.261406)
		(width 0.1143)
		(layer "In4.Cu")
		(net "P5E_CPU1_G1_RX_DP<3>")
	)
	(arc
		(start 108.239814 -226.360228)
		(mid 108.395742 -226.66452)
		(end 108.239814 -226.968812)
		(width 0.1143)
		(layer "In4.Cu")
		(net "P5E_CPU1_G1_RX_DP<3>")
	)
	(arc
		(start 108.241592 -231.221534)
		(mid 108.354999 -231.354423)
		(end 108.39577 -231.524302)
		(width 0.1143)
		(layer "In4.Cu")
		(net "P5E_CPU1_G1_RX_DP<3>")
	)
	(arc
		(start 108.171488 -230.248206)
		(mid 107.990836 -230.450951)
		(end 107.925616 -230.71455)
		(width 0.1143)
		(layer "In4.Cu")
		(net "P5E_CPU1_G1_RX_DP<3>")
	)
	(arc
		(start 108.39577 -229.90429)
		(mid 108.354515 -230.075261)
		(end 108.239814 -230.208582)
		(width 0.1143)
		(layer "In4.Cu")
		(net "P5E_CPU1_G1_RX_DP<3>")
	)
	(arc
		(start 108.239814 -227.98024)
		(mid 108.395742 -228.284532)
		(end 108.239814 -228.588824)
		(width 0.1143)
		(layer "In4.Cu")
		(net "P5E_CPU1_G1_RX_DP<3>")
	)
	(arc
		(start 106.987594 -224.25914)
		(mid 106.988214 -224.263714)
		(end 106.988864 -224.268284)
		(width 0.1143)
		(layer "In4.Cu")
		(net "P5E_CPU1_G1_RX_DP<3>")
	)
	(arc
		(start 106.988864 -224.268284)
		(mid 107.060025 -224.489915)
		(end 107.199938 -224.675954)
		(width 0.1143)
		(layer "In4.Cu")
		(net "P5E_CPU1_G1_RX_DP<3>")
	)
	(arc
		(start 107.45597 -225.044508)
		(mid 107.521206 -225.308099)
		(end 107.701842 -225.510852)
		(width 0.1143)
		(layer "In4.Cu")
		(net "P5E_CPU1_G1_RX_DP<3>")
	)
	(arc
		(start 108.168948 -227.00996)
		(mid 107.925621 -227.474526)
		(end 108.168948 -227.939092)
		(width 0.1143)
		(layer "In4.Cu")
		(net "P5E_CPU1_G1_RX_DP<3>")
	)
	(arc
		(start 107.298998 -224.739708)
		(mid 107.414425 -224.873084)
		(end 107.45597 -225.044508)
		(width 0.1143)
		(layer "In4.Cu")
		(net "P5E_CPU1_G1_RX_DP<3>")
	)
	(arc
		(start 108.168948 -231.869742)
		(mid 107.990135 -232.072092)
		(end 107.925616 -232.334308)
		(width 0.1143)
		(layer "In4.Cu")
		(net "P5E_CPU1_G1_RX_DP<3>")
	)
	(arc
		(start 107.216448 -223.070166)
		(mid 107.223395 -223.075172)
		(end 107.230418 -223.080072)
		(width 0.1143)
		(layer "In4.Cu")
		(net "P5E_CPU1_G1_RX_DP<3>")
	)
	(arc
		(start 107.455716 -233.144314)
		(mid 107.414461 -233.315285)
		(end 107.29976 -233.448606)
		(width 0.1143)
		(layer "In4.Cu")
		(net "P5E_CPU1_G1_RX_DP<3>")
	)
	(arc
		(start 107.229148 -223.769936)
		(mid 107.050335 -223.972286)
		(end 106.985816 -224.234502)
		(width 0.1143)
		(layer "In4.Cu")
		(net "P5E_CPU1_G1_RX_DP<3>")
	)
	(arc
		(start 107.155742 -222.212662)
		(mid 106.99287 -222.655058)
		(end 107.216448 -223.070166)
		(width 0.1143)
		(layer "In4.Cu")
		(net "P5E_CPU1_G1_RX_DP<3>")
	)
	(arc
		(start 108.39577 -231.524302)
		(mid 108.354515 -231.695273)
		(end 108.239814 -231.828594)
		(width 0.1143)
		(layer "In4.Cu")
		(net "P5E_CPU1_G1_RX_DP<3>")
	)
	(segment
		(start 106.607864 -231.79024)
		(end 106.141012 -231.524302)
		(width 0.12954)
		(layer "F.Cu")
		(net "P5E_CPU1_G1_RX_DP<4>")
	)
	(segment
		(start 44.330366 -4.963414)
		(end 44.595796 -5.228844)
		(width 0.12954)
		(layer "F.Cu")
		(net "P5E_CPU1_G1_RX_DP<4>")
	)
	(segment
		(start 44.595796 -7.57047)
		(end 44.457112 -7.709154)
		(width 0.12954)
		(layer "F.Cu")
		(net "P5E_CPU1_G1_RX_DP<4>")
	)
	(segment
		(start 44.595796 -5.228844)
		(end 44.595796 -7.57047)
		(width 0.12954)
		(layer "F.Cu")
		(net "P5E_CPU1_G1_RX_DP<4>")
	)
	(segment
		(start 44.457112 -7.709154)
		(end 44.457112 -8.320024)
		(width 0.12954)
		(layer "F.Cu")
		(net "P5E_CPU1_G1_RX_DP<4>")
	)
	(segment
		(start 106.289094 -224.699068)
		(end 106.32821 -224.721928)
		(width 0.1143)
		(layer "In4.Cu")
		(net "P5E_CPU1_G1_RX_DP<4>")
	)
	(segment
		(start 107.268264 -228.607112)
		(end 107.229148 -228.629972)
		(width 0.1143)
		(layer "In4.Cu")
		(net "P5E_CPU1_G1_RX_DP<4>")
	)
	(segment
		(start 44.621196 -5.254244)
		(end 44.621196 -11.435588)
		(width 0.14224)
		(layer "In4.Cu")
		(net "P5E_CPU1_G1_RX_DP<4>")
	)
	(segment
		(start 106.758994 -225.509074)
		(end 106.79557 -225.53041)
		(width 0.1143)
		(layer "In4.Cu")
		(net "P5E_CPU1_G1_RX_DP<4>")
	)
	(segment
		(start 149.625812 -175.593756)
		(end 111.213392 -207.07223)
		(width 0.14224)
		(layer "In4.Cu")
		(net "P5E_CPU1_G1_RX_DP<4>")
	)
	(segment
		(start 107.229148 -226.31908)
		(end 107.268264 -226.34194)
		(width 0.1143)
		(layer "In4.Cu")
		(net "P5E_CPU1_G1_RX_DP<4>")
	)
	(segment
		(start 149.884892 -136.651746)
		(end 154.342084 -145.855436)
		(width 0.14224)
		(layer "In4.Cu")
		(net "P5E_CPU1_G1_RX_DP<4>")
	)
	(segment
		(start 45.107606 -19.23923)
		(end 45.136816 -19.34718)
		(width 0.14224)
		(layer "In4.Cu")
		(net "P5E_CPU1_G1_RX_DP<4>")
	)
	(segment
		(start 106.831638 -231.017318)
		(end 106.79811 -231.036876)
		(width 0.1143)
		(layer "In4.Cu")
		(net "P5E_CPU1_G1_RX_DP<4>")
	)
	(segment
		(start 106.798872 -225.532442)
		(end 106.82986 -225.550222)
		(width 0.1143)
		(layer "In4.Cu")
		(net "P5E_CPU1_G1_RX_DP<4>")
	)
	(segment
		(start 45.126148 -18.966942)
		(end 45.107606 -19.06016)
		(width 0.14224)
		(layer "In4.Cu")
		(net "P5E_CPU1_G1_RX_DP<4>")
	)
	(segment
		(start 154.082242 -167.599868)
		(end 154.081988 -167.599868)
		(width 0.14224)
		(layer "In4.Cu")
		(net "P5E_CPU1_G1_RX_DP<4>")
	)
	(segment
		(start 45.136054 -18.91665)
		(end 45.126148 -18.965926)
		(width 0.14224)
		(layer "In4.Cu")
		(net "P5E_CPU1_G1_RX_DP<4>")
	)
	(segment
		(start 106.32694 -222.127572)
		(end 106.28884 -222.149924)
		(width 0.1143)
		(layer "In4.Cu")
		(net "P5E_CPU1_G1_RX_DP<4>")
	)
	(segment
		(start 106.438954 -231.524302)
		(end 106.141012 -231.524302)
		(width 0.1143)
		(layer "In4.Cu")
		(net "P5E_CPU1_G1_RX_DP<4>")
	)
	(segment
		(start 106.045508 -222.61449)
		(end 106.045762 -222.61449)
		(width 0.1143)
		(layer "In4.Cu")
		(net "P5E_CPU1_G1_RX_DP<4>")
	)
	(segment
		(start 152.951434 -170.915584)
		(end 149.625812 -175.593756)
		(width 0.14224)
		(layer "In4.Cu")
		(net "P5E_CPU1_G1_RX_DP<4>")
	)
	(segment
		(start 45.194474 -18.77568)
		(end 45.136054 -18.91665)
		(width 0.14224)
		(layer "In4.Cu")
		(net "P5E_CPU1_G1_RX_DP<4>")
	)
	(segment
		(start 106.359706 -222.108776)
		(end 106.334306 -222.123508)
		(width 0.1143)
		(layer "In4.Cu")
		(net "P5E_CPU1_G1_RX_DP<4>")
	)
	(segment
		(start 106.79811 -225.531934)
		(end 106.798872 -225.532442)
		(width 0.1143)
		(layer "In4.Cu")
		(net "P5E_CPU1_G1_RX_DP<4>")
	)
	(segment
		(start 106.327956 -222.127064)
		(end 106.32694 -222.127572)
		(width 0.1143)
		(layer "In4.Cu")
		(net "P5E_CPU1_G1_RX_DP<4>")
	)
	(segment
		(start 45.781468 -17.815052)
		(end 45.559472 -18.229834)
		(width 0.14224)
		(layer "In4.Cu")
		(net "P5E_CPU1_G1_RX_DP<4>")
	)
	(segment
		(start 106.501692 -221.378526)
		(end 106.501692 -221.637352)
		(width 0.1143)
		(layer "In4.Cu")
		(net "P5E_CPU1_G1_RX_DP<4>")
	)
	(segment
		(start 106.328718 -222.126556)
		(end 106.327956 -222.127064)
		(width 0.1143)
		(layer "In4.Cu")
		(net "P5E_CPU1_G1_RX_DP<4>")
	)
	(segment
		(start 107.229148 -229.559104)
		(end 107.268264 -229.581964)
		(width 0.1143)
		(layer "In4.Cu")
		(net "P5E_CPU1_G1_RX_DP<4>")
	)
	(segment
		(start 45.136816 -19.34718)
		(end 45.149008 -19.386042)
		(width 0.14224)
		(layer "In4.Cu")
		(net "P5E_CPU1_G1_RX_DP<4>")
	)
	(segment
		(start 107.229148 -227.939092)
		(end 107.268264 -227.961952)
		(width 0.1143)
		(layer "In4.Cu")
		(net "P5E_CPU1_G1_RX_DP<4>")
	)
	(segment
		(start 59.959748 -55.869586)
		(end 61.249814 -56.949594)
		(width 0.14224)
		(layer "In4.Cu")
		(net "P5E_CPU1_G1_RX_DP<4>")
	)
	(segment
		(start 106.334306 -222.123508)
		(end 106.332274 -222.124524)
		(width 0.1143)
		(layer "In4.Cu")
		(net "P5E_CPU1_G1_RX_DP<4>")
	)
	(segment
		(start 107.298744 -230.20909)
		(end 107.231688 -230.248206)
		(width 0.1143)
		(layer "In4.Cu")
		(net "P5E_CPU1_G1_RX_DP<4>")
	)
	(segment
		(start 106.35869 -223.729296)
		(end 106.32821 -223.747076)
		(width 0.1143)
		(layer "In4.Cu")
		(net "P5E_CPU1_G1_RX_DP<4>")
	)
	(segment
		(start 106.515916 -221.651576)
		(end 106.515916 -221.804738)
		(width 0.1143)
		(layer "In4.Cu")
		(net "P5E_CPU1_G1_RX_DP<4>")
	)
	(segment
		(start 107.298744 -228.589332)
		(end 107.268264 -228.607112)
		(width 0.1143)
		(layer "In4.Cu")
		(net "P5E_CPU1_G1_RX_DP<4>")
	)
	(segment
		(start 106.455972 -221.304358)
		(end 106.455972 -221.332806)
		(width 0.1143)
		(layer "In4.Cu")
		(net "P5E_CPU1_G1_RX_DP<4>")
	)
	(segment
		(start 106.32821 -223.101916)
		(end 106.35869 -223.119696)
		(width 0.1143)
		(layer "In4.Cu")
		(net "P5E_CPU1_G1_RX_DP<4>")
	)
	(segment
		(start 155.213304 -159.796734)
		(end 155.213304 -164.28339)
		(width 0.14224)
		(layer "In4.Cu")
		(net "P5E_CPU1_G1_RX_DP<4>")
	)
	(segment
		(start 106.515916 -221.804738)
		(end 106.515662 -221.804484)
		(width 0.1143)
		(layer "In4.Cu")
		(net "P5E_CPU1_G1_RX_DP<4>")
	)
	(segment
		(start 45.82541 -17.708626)
		(end 45.781468 -17.815052)
		(width 0.14224)
		(layer "In4.Cu")
		(net "P5E_CPU1_G1_RX_DP<4>")
	)
	(segment
		(start 107.268264 -229.581964)
		(end 107.300776 -229.60076)
		(width 0.1143)
		(layer "In4.Cu")
		(net "P5E_CPU1_G1_RX_DP<4>")
	)
	(segment
		(start 45.82541 -17.489932)
		(end 45.82541 -17.708626)
		(width 0.14224)
		(layer "In4.Cu")
		(net "P5E_CPU1_G1_RX_DP<4>")
	)
	(segment
		(start 106.332274 -222.124524)
		(end 106.331512 -222.125032)
		(width 0.1143)
		(layer "In4.Cu")
		(net "P5E_CPU1_G1_RX_DP<4>")
	)
	(segment
		(start 45.126148 -18.965926)
		(end 45.126148 -18.966942)
		(width 0.14224)
		(layer "In4.Cu")
		(net "P5E_CPU1_G1_RX_DP<4>")
	)
	(segment
		(start 47.582836 -26.692352)
		(end 54.186836 -48.332644)
		(width 0.14224)
		(layer "In4.Cu")
		(net "P5E_CPU1_G1_RX_DP<4>")
	)
	(segment
		(start 45.148754 -19.386042)
		(end 47.582836 -26.692352)
		(width 0.14224)
		(layer "In4.Cu")
		(net "P5E_CPU1_G1_RX_DP<4>")
	)
	(segment
		(start 106.455972 -221.332806)
		(end 106.501692 -221.378526)
		(width 0.1143)
		(layer "In4.Cu")
		(net "P5E_CPU1_G1_RX_DP<4>")
	)
	(segment
		(start 106.32821 -224.721928)
		(end 106.35869 -224.739708)
		(width 0.1143)
		(layer "In4.Cu")
		(net "P5E_CPU1_G1_RX_DP<4>")
	)
	(segment
		(start 107.268264 -226.9871)
		(end 107.229148 -227.00996)
		(width 0.1143)
		(layer "In4.Cu")
		(net "P5E_CPU1_G1_RX_DP<4>")
	)
	(segment
		(start 154.081988 -167.599868)
		(end 152.951434 -170.915584)
		(width 0.14224)
		(layer "In4.Cu")
		(net "P5E_CPU1_G1_RX_DP<4>")
	)
	(segment
		(start 106.79811 -231.036876)
		(end 106.758994 -231.059736)
		(width 0.1143)
		(layer "In4.Cu")
		(net "P5E_CPU1_G1_RX_DP<4>")
	)
	(segment
		(start 59.06262 -55.06339)
		(end 59.959748 -55.869586)
		(width 0.14224)
		(layer "In4.Cu")
		(net "P5E_CPU1_G1_RX_DP<4>")
	)
	(segment
		(start 44.330366 -4.963414)
		(end 44.621196 -5.254244)
		(width 0.14224)
		(layer "In4.Cu")
		(net "P5E_CPU1_G1_RX_DP<4>")
	)
	(segment
		(start 106.797094 -225.531426)
		(end 106.79811 -225.531934)
		(width 0.1143)
		(layer "In4.Cu")
		(net "P5E_CPU1_G1_RX_DP<4>")
	)
	(segment
		(start 111.213392 -207.07223)
		(end 106.455972 -215.084406)
		(width 0.14224)
		(layer "In4.Cu")
		(net "P5E_CPU1_G1_RX_DP<4>")
	)
	(segment
		(start 155.213304 -164.28339)
		(end 154.082242 -167.599868)
		(width 0.14224)
		(layer "In4.Cu")
		(net "P5E_CPU1_G1_RX_DP<4>")
	)
	(segment
		(start 45.559472 -18.229834)
		(end 45.194474 -18.77568)
		(width 0.14224)
		(layer "In4.Cu")
		(net "P5E_CPU1_G1_RX_DP<4>")
	)
	(segment
		(start 107.268264 -226.34194)
		(end 107.298744 -226.35972)
		(width 0.1143)
		(layer "In4.Cu")
		(net "P5E_CPU1_G1_RX_DP<4>")
	)
	(segment
		(start 106.521758 -231.441498)
		(end 106.438954 -231.524302)
		(width 0.1143)
		(layer "In4.Cu")
		(net "P5E_CPU1_G1_RX_DP<4>")
	)
	(segment
		(start 107.298744 -226.96932)
		(end 107.268264 -226.9871)
		(width 0.1143)
		(layer "In4.Cu")
		(net "P5E_CPU1_G1_RX_DP<4>")
	)
	(segment
		(start 54.186836 -48.332644)
		(end 56.780684 -53.184298)
		(width 0.14224)
		(layer "In4.Cu")
		(net "P5E_CPU1_G1_RX_DP<4>")
	)
	(segment
		(start 149.884638 -136.651746)
		(end 149.884892 -136.651746)
		(width 0.14224)
		(layer "In4.Cu")
		(net "P5E_CPU1_G1_RX_DP<4>")
	)
	(segment
		(start 106.455972 -215.084406)
		(end 106.455972 -221.304358)
		(width 0.14224)
		(layer "In4.Cu")
		(net "P5E_CPU1_G1_RX_DP<4>")
	)
	(segment
		(start 44.621196 -11.435588)
		(end 45.82541 -17.489932)
		(width 0.14224)
		(layer "In4.Cu")
		(net "P5E_CPU1_G1_RX_DP<4>")
	)
	(segment
		(start 45.107606 -19.06016)
		(end 45.107606 -19.23923)
		(width 0.14224)
		(layer "In4.Cu")
		(net "P5E_CPU1_G1_RX_DP<4>")
	)
	(segment
		(start 61.249814 -56.949594)
		(end 149.884638 -136.651746)
		(width 0.14224)
		(layer "In4.Cu")
		(net "P5E_CPU1_G1_RX_DP<4>")
	)
	(segment
		(start 107.268264 -227.961952)
		(end 107.298744 -227.979732)
		(width 0.1143)
		(layer "In4.Cu")
		(net "P5E_CPU1_G1_RX_DP<4>")
	)
	(segment
		(start 106.289094 -223.079056)
		(end 106.32821 -223.101916)
		(width 0.1143)
		(layer "In4.Cu")
		(net "P5E_CPU1_G1_RX_DP<4>")
	)
	(segment
		(start 106.79557 -225.53041)
		(end 106.797094 -225.531426)
		(width 0.1143)
		(layer "In4.Cu")
		(net "P5E_CPU1_G1_RX_DP<4>")
	)
	(segment
		(start 106.501692 -221.637352)
		(end 106.515916 -221.651576)
		(width 0.1143)
		(layer "In4.Cu")
		(net "P5E_CPU1_G1_RX_DP<4>")
	)
	(segment
		(start 154.342084 -145.855436)
		(end 155.213304 -159.796734)
		(width 0.14224)
		(layer "In4.Cu")
		(net "P5E_CPU1_G1_RX_DP<4>")
	)
	(segment
		(start 106.32821 -223.747076)
		(end 106.289094 -223.769936)
		(width 0.1143)
		(layer "In4.Cu")
		(net "P5E_CPU1_G1_RX_DP<4>")
	)
	(segment
		(start 106.331512 -222.125032)
		(end 106.328718 -222.126556)
		(width 0.1143)
		(layer "In4.Cu")
		(net "P5E_CPU1_G1_RX_DP<4>")
	)
	(segment
		(start 56.839104 -53.237638)
		(end 59.06262 -55.06339)
		(width 0.14224)
		(layer "In4.Cu")
		(net "P5E_CPU1_G1_RX_DP<4>")
	)
	(segment
		(start 45.149008 -19.386042)
		(end 45.148754 -19.386042)
		(width 0.14224)
		(layer "In4.Cu")
		(net "P5E_CPU1_G1_RX_DP<4>")
	)
	(segment
		(start 56.780684 -53.184298)
		(end 56.839104 -53.237638)
		(width 0.14224)
		(layer "In4.Cu")
		(net "P5E_CPU1_G1_RX_DP<4>")
	)
	(arc
		(start 107.229148 -228.629972)
		(mid 106.985821 -229.094538)
		(end 107.229148 -229.559104)
		(width 0.1143)
		(layer "In4.Cu")
		(net "P5E_CPU1_G1_RX_DP<4>")
	)
	(arc
		(start 107.298744 -226.35972)
		(mid 107.455721 -226.66452)
		(end 107.298744 -226.96932)
		(width 0.1143)
		(layer "In4.Cu")
		(net "P5E_CPU1_G1_RX_DP<4>")
	)
	(arc
		(start 106.503724 -221.898718)
		(mid 106.481846 -221.960144)
		(end 106.449622 -222.016828)
		(width 0.1143)
		(layer "In4.Cu")
		(net "P5E_CPU1_G1_RX_DP<4>")
	)
	(arc
		(start 106.985816 -225.854514)
		(mid 107.050331 -226.116733)
		(end 107.229148 -226.31908)
		(width 0.1143)
		(layer "In4.Cu")
		(net "P5E_CPU1_G1_RX_DP<4>")
	)
	(arc
		(start 107.300776 -229.60076)
		(mid 107.414705 -229.733907)
		(end 107.455716 -229.90429)
		(width 0.1143)
		(layer "In4.Cu")
		(net "P5E_CPU1_G1_RX_DP<4>")
	)
	(arc
		(start 106.35869 -224.739708)
		(mid 106.474117 -224.873084)
		(end 106.515662 -225.044508)
		(width 0.1143)
		(layer "In4.Cu")
		(net "P5E_CPU1_G1_RX_DP<4>")
	)
	(arc
		(start 107.455716 -229.90429)
		(mid 107.414167 -230.075712)
		(end 107.298744 -230.20909)
		(width 0.1143)
		(layer "In4.Cu")
		(net "P5E_CPU1_G1_RX_DP<4>")
	)
	(arc
		(start 107.298744 -227.979732)
		(mid 107.455721 -228.284532)
		(end 107.298744 -228.589332)
		(width 0.1143)
		(layer "In4.Cu")
		(net "P5E_CPU1_G1_RX_DP<4>")
	)
	(arc
		(start 106.289094 -223.769936)
		(mid 106.045767 -224.234502)
		(end 106.289094 -224.699068)
		(width 0.1143)
		(layer "In4.Cu")
		(net "P5E_CPU1_G1_RX_DP<4>")
	)
	(arc
		(start 106.525568 -231.418638)
		(mid 106.523545 -231.430048)
		(end 106.521758 -231.441498)
		(width 0.1143)
		(layer "In4.Cu")
		(net "P5E_CPU1_G1_RX_DP<4>")
	)
	(arc
		(start 106.045762 -222.61449)
		(mid 106.110277 -222.876709)
		(end 106.289094 -223.079056)
		(width 0.1143)
		(layer "In4.Cu")
		(net "P5E_CPU1_G1_RX_DP<4>")
	)
	(arc
		(start 106.985816 -230.71455)
		(mid 106.945054 -230.884434)
		(end 106.831638 -231.017318)
		(width 0.1143)
		(layer "In4.Cu")
		(net "P5E_CPU1_G1_RX_DP<4>")
	)
	(arc
		(start 106.515662 -221.804484)
		(mid 106.512704 -221.851983)
		(end 106.503724 -221.898718)
		(width 0.1143)
		(layer "In4.Cu")
		(net "P5E_CPU1_G1_RX_DP<4>")
	)
	(arc
		(start 106.82986 -225.550222)
		(mid 106.944536 -225.683556)
		(end 106.985816 -225.854514)
		(width 0.1143)
		(layer "In4.Cu")
		(net "P5E_CPU1_G1_RX_DP<4>")
	)
	(arc
		(start 107.231688 -230.248206)
		(mid 107.051036 -230.450951)
		(end 106.985816 -230.71455)
		(width 0.1143)
		(layer "In4.Cu")
		(net "P5E_CPU1_G1_RX_DP<4>")
	)
	(arc
		(start 106.758994 -231.059736)
		(mid 106.607007 -231.216244)
		(end 106.525568 -231.418638)
		(width 0.1143)
		(layer "In4.Cu")
		(net "P5E_CPU1_G1_RX_DP<4>")
	)
	(arc
		(start 106.35869 -223.119696)
		(mid 106.515667 -223.424496)
		(end 106.35869 -223.729296)
		(width 0.1143)
		(layer "In4.Cu")
		(net "P5E_CPU1_G1_RX_DP<4>")
	)
	(arc
		(start 106.28884 -222.149924)
		(mid 106.110027 -222.352274)
		(end 106.045508 -222.61449)
		(width 0.1143)
		(layer "In4.Cu")
		(net "P5E_CPU1_G1_RX_DP<4>")
	)
	(arc
		(start 106.515662 -225.044508)
		(mid 106.580177 -225.306727)
		(end 106.758994 -225.509074)
		(width 0.1143)
		(layer "In4.Cu")
		(net "P5E_CPU1_G1_RX_DP<4>")
	)
	(arc
		(start 107.229148 -227.00996)
		(mid 106.985821 -227.474526)
		(end 107.229148 -227.939092)
		(width 0.1143)
		(layer "In4.Cu")
		(net "P5E_CPU1_G1_RX_DP<4>")
	)
	(arc
		(start 106.449622 -222.016828)
		(mid 106.408639 -222.06669)
		(end 106.359706 -222.108776)
		(width 0.1143)
		(layer "In4.Cu")
		(net "P5E_CPU1_G1_RX_DP<4>")
	)
	(segment
		(start 106.607864 -233.410252)
		(end 106.141012 -233.144314)
		(width 0.12954)
		(layer "F.Cu")
		(net "P5E_CPU1_G1_RX_DP<5>")
	)
	(segment
		(start 42.657014 -8.320024)
		(end 42.657014 -7.709154)
		(width 0.12954)
		(layer "F.Cu")
		(net "P5E_CPU1_G1_RX_DP<5>")
	)
	(segment
		(start 42.795698 -7.57047)
		(end 42.795698 -6.99516)
		(width 0.12954)
		(layer "F.Cu")
		(net "P5E_CPU1_G1_RX_DP<5>")
	)
	(segment
		(start 42.657014 -7.709154)
		(end 42.795698 -7.57047)
		(width 0.12954)
		(layer "F.Cu")
		(net "P5E_CPU1_G1_RX_DP<5>")
	)
	(segment
		(start 42.795698 -6.99516)
		(end 42.525696 -6.725158)
		(width 0.12954)
		(layer "F.Cu")
		(net "P5E_CPU1_G1_RX_DP<5>")
	)
	(segment
		(start 106.328718 -226.342448)
		(end 106.359706 -226.360228)
		(width 0.1143)
		(layer "In4.Cu")
		(net "P5E_CPU1_G1_RX_DP<5>")
	)
	(segment
		(start 43.750992 -20.115276)
		(end 46.08957 -26.703274)
		(width 0.14224)
		(layer "In4.Cu")
		(net "P5E_CPU1_G1_RX_DP<5>")
	)
	(segment
		(start 154.271726 -164.116512)
		(end 153.815542 -165.455854)
		(width 0.14224)
		(layer "In4.Cu")
		(net "P5E_CPU1_G1_RX_DP<5>")
	)
	(segment
		(start 110.480094 -206.467202)
		(end 105.510584 -214.837772)
		(width 0.14224)
		(layer "In4.Cu")
		(net "P5E_CPU1_G1_RX_DP<5>")
	)
	(segment
		(start 106.32948 -230.229156)
		(end 106.324908 -230.23195)
		(width 0.1143)
		(layer "In4.Cu")
		(net "P5E_CPU1_G1_RX_DP<5>")
	)
	(segment
		(start 105.575862 -221.65691)
		(end 105.575862 -221.804484)
		(width 0.1143)
		(layer "In4.Cu")
		(net "P5E_CPU1_G1_RX_DP<5>")
	)
	(segment
		(start 105.858056 -225.531934)
		(end 105.85958 -225.53295)
		(width 0.1143)
		(layer "In4.Cu")
		(net "P5E_CPU1_G1_RX_DP<5>")
	)
	(segment
		(start 52.920646 -48.31334)
		(end 55.712614 -53.471826)
		(width 0.14224)
		(layer "In4.Cu")
		(net "P5E_CPU1_G1_RX_DP<5>")
	)
	(segment
		(start 105.887774 -231.019858)
		(end 105.81894 -231.059736)
		(width 0.1143)
		(layer "In4.Cu")
		(net "P5E_CPU1_G1_RX_DP<5>")
	)
	(segment
		(start 105.819702 -231.989376)
		(end 105.858564 -232.011982)
		(width 0.1143)
		(layer "In4.Cu")
		(net "P5E_CPU1_G1_RX_DP<5>")
	)
	(segment
		(start 105.862374 -225.534474)
		(end 105.863644 -225.535236)
		(width 0.1143)
		(layer "In4.Cu")
		(net "P5E_CPU1_G1_RX_DP<5>")
	)
	(segment
		(start 105.575608 -225.044508)
		(end 105.575862 -225.044508)
		(width 0.1143)
		(layer "In4.Cu")
		(net "P5E_CPU1_G1_RX_DP<5>")
	)
	(segment
		(start 105.388156 -223.747076)
		(end 105.34904 -223.769936)
		(width 0.1143)
		(layer "In4.Cu")
		(net "P5E_CPU1_G1_RX_DP<5>")
	)
	(segment
		(start 105.418636 -223.729296)
		(end 105.388156 -223.747076)
		(width 0.1143)
		(layer "In4.Cu")
		(net "P5E_CPU1_G1_RX_DP<5>")
	)
	(segment
		(start 106.291634 -229.560882)
		(end 106.359452 -229.599998)
		(width 0.1143)
		(layer "In4.Cu")
		(net "P5E_CPU1_G1_RX_DP<5>")
	)
	(segment
		(start 46.118018 -26.783284)
		(end 52.920646 -48.31334)
		(width 0.14224)
		(layer "In4.Cu")
		(net "P5E_CPU1_G1_RX_DP<5>")
	)
	(segment
		(start 106.359706 -226.968812)
		(end 106.329988 -226.98583)
		(width 0.1143)
		(layer "In4.Cu")
		(net "P5E_CPU1_G1_RX_DP<5>")
	)
	(segment
		(start 106.328718 -227.96246)
		(end 106.359706 -227.98024)
		(width 0.1143)
		(layer "In4.Cu")
		(net "P5E_CPU1_G1_RX_DP<5>")
	)
	(segment
		(start 106.327194 -232.821226)
		(end 106.328718 -232.822242)
		(width 0.1143)
		(layer "In4.Cu")
		(net "P5E_CPU1_G1_RX_DP<5>")
	)
	(segment
		(start 105.556304 -221.637352)
		(end 105.575862 -221.65691)
		(width 0.1143)
		(layer "In4.Cu")
		(net "P5E_CPU1_G1_RX_DP<5>")
	)
	(segment
		(start 60.63869 -57.653936)
		(end 149.12467 -137.222738)
		(width 0.14224)
		(layer "In4.Cu")
		(net "P5E_CPU1_G1_RX_DP<5>")
	)
	(segment
		(start 148.72843 -175.123094)
		(end 110.480094 -206.467202)
		(width 0.14224)
		(layer "In4.Cu")
		(net "P5E_CPU1_G1_RX_DP<5>")
	)
	(segment
		(start 59.348624 -56.573928)
		(end 60.63869 -57.653936)
		(width 0.14224)
		(layer "In4.Cu")
		(net "P5E_CPU1_G1_RX_DP<5>")
	)
	(segment
		(start 42.313606 -17.57553)
		(end 42.313606 -17.765014)
		(width 0.14224)
		(layer "In4.Cu")
		(net "P5E_CPU1_G1_RX_DP<5>")
	)
	(segment
		(start 106.327956 -228.607112)
		(end 106.291634 -228.628194)
		(width 0.1143)
		(layer "In4.Cu")
		(net "P5E_CPU1_G1_RX_DP<5>")
	)
	(segment
		(start 106.327956 -226.9871)
		(end 106.291634 -227.008182)
		(width 0.1143)
		(layer "In4.Cu")
		(net "P5E_CPU1_G1_RX_DP<5>")
	)
	(segment
		(start 106.359706 -228.588824)
		(end 106.329988 -228.605842)
		(width 0.1143)
		(layer "In4.Cu")
		(net "P5E_CPU1_G1_RX_DP<5>")
	)
	(segment
		(start 106.329988 -226.98583)
		(end 106.328718 -226.986592)
		(width 0.1143)
		(layer "In4.Cu")
		(net "P5E_CPU1_G1_RX_DP<5>")
	)
	(segment
		(start 55.743348 -53.505608)
		(end 56.23179 -53.945282)
		(width 0.14224)
		(layer "In4.Cu")
		(net "P5E_CPU1_G1_RX_DP<5>")
	)
	(segment
		(start 43.662854 -19.93392)
		(end 43.750992 -20.115276)
		(width 0.14224)
		(layer "In4.Cu")
		(net "P5E_CPU1_G1_RX_DP<5>")
	)
	(segment
		(start 56.23179 -53.945282)
		(end 58.454798 -55.770526)
		(width 0.14224)
		(layer "In4.Cu")
		(net "P5E_CPU1_G1_RX_DP<5>")
	)
	(segment
		(start 105.857548 -225.531426)
		(end 105.858056 -225.531934)
		(width 0.1143)
		(layer "In4.Cu")
		(net "P5E_CPU1_G1_RX_DP<5>")
	)
	(segment
		(start 55.712614 -53.471826)
		(end 55.743348 -53.505608)
		(width 0.14224)
		(layer "In4.Cu")
		(net "P5E_CPU1_G1_RX_DP<5>")
	)
	(segment
		(start 105.510584 -221.332806)
		(end 105.556304 -221.378526)
		(width 0.1143)
		(layer "In4.Cu")
		(net "P5E_CPU1_G1_RX_DP<5>")
	)
	(segment
		(start 43.660822 -19.933158)
		(end 43.662092 -19.93265)
		(width 0.14224)
		(layer "In4.Cu")
		(net "P5E_CPU1_G1_RX_DP<5>")
	)
	(segment
		(start 106.327956 -227.961952)
		(end 106.328718 -227.96246)
		(width 0.1143)
		(layer "In4.Cu")
		(net "P5E_CPU1_G1_RX_DP<5>")
	)
	(segment
		(start 153.815542 -165.455854)
		(end 152.447244 -169.474134)
		(width 0.14224)
		(layer "In4.Cu")
		(net "P5E_CPU1_G1_RX_DP<5>")
	)
	(segment
		(start 42.384218 -17.935702)
		(end 42.619422 -18.375122)
		(width 0.14224)
		(layer "In4.Cu")
		(net "P5E_CPU1_G1_RX_DP<5>")
	)
	(segment
		(start 106.324654 -232.819956)
		(end 106.327194 -232.821226)
		(width 0.1143)
		(layer "In4.Cu")
		(net "P5E_CPU1_G1_RX_DP<5>")
	)
	(segment
		(start 105.510584 -214.837772)
		(end 105.510584 -221.304358)
		(width 0.14224)
		(layer "In4.Cu")
		(net "P5E_CPU1_G1_RX_DP<5>")
	)
	(segment
		(start 106.27868 -226.31146)
		(end 106.289094 -226.319334)
		(width 0.1143)
		(layer "In4.Cu")
		(net "P5E_CPU1_G1_RX_DP<5>")
	)
	(segment
		(start 58.454798 -55.770526)
		(end 59.348624 -56.573928)
		(width 0.14224)
		(layer "In4.Cu")
		(net "P5E_CPU1_G1_RX_DP<5>")
	)
	(segment
		(start 105.861612 -225.533966)
		(end 105.862374 -225.534474)
		(width 0.1143)
		(layer "In4.Cu")
		(net "P5E_CPU1_G1_RX_DP<5>")
	)
	(segment
		(start 105.556304 -221.378526)
		(end 105.556304 -221.637352)
		(width 0.1143)
		(layer "In4.Cu")
		(net "P5E_CPU1_G1_RX_DP<5>")
	)
	(segment
		(start 46.091856 -26.710132)
		(end 46.118018 -26.783284)
		(width 0.14224)
		(layer "In4.Cu")
		(net "P5E_CPU1_G1_RX_DP<5>")
	)
	(segment
		(start 106.327956 -226.34194)
		(end 106.328718 -226.342448)
		(width 0.1143)
		(layer "In4.Cu")
		(net "P5E_CPU1_G1_RX_DP<5>")
	)
	(segment
		(start 105.34904 -224.699068)
		(end 105.388156 -224.721928)
		(width 0.1143)
		(layer "In4.Cu")
		(net "P5E_CPU1_G1_RX_DP<5>")
	)
	(segment
		(start 106.289094 -226.319334)
		(end 106.325162 -226.340162)
		(width 0.1143)
		(layer "In4.Cu")
		(net "P5E_CPU1_G1_RX_DP<5>")
	)
	(segment
		(start 149.12467 -137.222738)
		(end 153.411936 -146.076162)
		(width 0.14224)
		(layer "In4.Cu")
		(net "P5E_CPU1_G1_RX_DP<5>")
	)
	(segment
		(start 42.816526 -7.015988)
		(end 42.816526 -12.468352)
		(width 0.14224)
		(layer "In4.Cu")
		(net "P5E_CPU1_G1_RX_DP<5>")
	)
	(segment
		(start 105.863644 -225.535236)
		(end 105.88752 -225.548952)
		(width 0.1143)
		(layer "In4.Cu")
		(net "P5E_CPU1_G1_RX_DP<5>")
	)
	(segment
		(start 106.508804 -233.074464)
		(end 106.438954 -233.144314)
		(width 0.1143)
		(layer "In4.Cu")
		(net "P5E_CPU1_G1_RX_DP<5>")
	)
	(segment
		(start 153.411936 -146.076162)
		(end 154.271726 -159.826452)
		(width 0.14224)
		(layer "In4.Cu")
		(net "P5E_CPU1_G1_RX_DP<5>")
	)
	(segment
		(start 105.350564 -223.080072)
		(end 105.418636 -223.119696)
		(width 0.1143)
		(layer "In4.Cu")
		(net "P5E_CPU1_G1_RX_DP<5>")
	)
	(segment
		(start 154.271726 -159.826452)
		(end 154.271726 -164.116512)
		(width 0.14224)
		(layer "In4.Cu")
		(net "P5E_CPU1_G1_RX_DP<5>")
	)
	(segment
		(start 43.66006 -19.931888)
		(end 43.660822 -19.933158)
		(width 0.14224)
		(layer "In4.Cu")
		(net "P5E_CPU1_G1_RX_DP<5>")
	)
	(segment
		(start 106.328718 -228.606604)
		(end 106.327956 -228.607112)
		(width 0.1143)
		(layer "In4.Cu")
		(net "P5E_CPU1_G1_RX_DP<5>")
	)
	(segment
		(start 106.291634 -227.94087)
		(end 106.327956 -227.961952)
		(width 0.1143)
		(layer "In4.Cu")
		(net "P5E_CPU1_G1_RX_DP<5>")
	)
	(segment
		(start 43.662092 -19.93265)
		(end 43.662854 -19.93392)
		(width 0.14224)
		(layer "In4.Cu")
		(net "P5E_CPU1_G1_RX_DP<5>")
	)
	(segment
		(start 152.070816 -170.470068)
		(end 148.72843 -175.123094)
		(width 0.14224)
		(layer "In4.Cu")
		(net "P5E_CPU1_G1_RX_DP<5>")
	)
	(segment
		(start 106.359452 -229.599998)
		(end 106.359706 -229.600252)
		(width 0.1143)
		(layer "In4.Cu")
		(net "P5E_CPU1_G1_RX_DP<5>")
	)
	(segment
		(start 42.619422 -18.375122)
		(end 43.66006 -19.931888)
		(width 0.14224)
		(layer "In4.Cu")
		(net "P5E_CPU1_G1_RX_DP<5>")
	)
	(segment
		(start 105.510584 -221.304358)
		(end 105.510584 -221.332806)
		(width 0.1143)
		(layer "In4.Cu")
		(net "P5E_CPU1_G1_RX_DP<5>")
	)
	(segment
		(start 42.816526 -12.468352)
		(end 42.313606 -17.57553)
		(width 0.14224)
		(layer "In4.Cu")
		(net "P5E_CPU1_G1_RX_DP<5>")
	)
	(segment
		(start 106.329988 -228.605842)
		(end 106.328718 -228.606604)
		(width 0.1143)
		(layer "In4.Cu")
		(net "P5E_CPU1_G1_RX_DP<5>")
	)
	(segment
		(start 106.438954 -233.144314)
		(end 106.141012 -233.144314)
		(width 0.1143)
		(layer "In4.Cu")
		(net "P5E_CPU1_G1_RX_DP<5>")
	)
	(segment
		(start 106.045762 -225.854514)
		(end 106.045762 -225.861626)
		(width 0.1143)
		(layer "In4.Cu")
		(net "P5E_CPU1_G1_RX_DP<5>")
	)
	(segment
		(start 46.08957 -26.703274)
		(end 46.091856 -26.710132)
		(width 0.14224)
		(layer "In4.Cu")
		(net "P5E_CPU1_G1_RX_DP<5>")
	)
	(segment
		(start 105.388156 -224.721928)
		(end 105.418636 -224.739708)
		(width 0.1143)
		(layer "In4.Cu")
		(net "P5E_CPU1_G1_RX_DP<5>")
	)
	(segment
		(start 42.525696 -6.725158)
		(end 42.816526 -7.015988)
		(width 0.14224)
		(layer "In4.Cu")
		(net "P5E_CPU1_G1_RX_DP<5>")
	)
	(segment
		(start 105.391712 -222.128334)
		(end 105.388918 -222.129858)
		(width 0.1143)
		(layer "In4.Cu")
		(net "P5E_CPU1_G1_RX_DP<5>")
	)
	(segment
		(start 106.040174 -232.327196)
		(end 106.040174 -232.329736)
		(width 0.1143)
		(layer "In4.Cu")
		(net "P5E_CPU1_G1_RX_DP<5>")
	)
	(segment
		(start 105.85958 -225.53295)
		(end 105.861612 -225.533966)
		(width 0.1143)
		(layer "In4.Cu")
		(net "P5E_CPU1_G1_RX_DP<5>")
	)
	(segment
		(start 106.328718 -232.822242)
		(end 106.359706 -232.840022)
		(width 0.1143)
		(layer "In4.Cu")
		(net "P5E_CPU1_G1_RX_DP<5>")
	)
	(segment
		(start 42.313606 -17.765014)
		(end 42.384218 -17.935702)
		(width 0.14224)
		(layer "In4.Cu")
		(net "P5E_CPU1_G1_RX_DP<5>")
	)
	(segment
		(start 106.328718 -226.986592)
		(end 106.327956 -226.9871)
		(width 0.1143)
		(layer "In4.Cu")
		(net "P5E_CPU1_G1_RX_DP<5>")
	)
	(segment
		(start 152.447244 -169.474134)
		(end 152.070816 -170.470068)
		(width 0.14224)
		(layer "In4.Cu")
		(net "P5E_CPU1_G1_RX_DP<5>")
	)
	(segment
		(start 106.325162 -226.340162)
		(end 106.327956 -226.34194)
		(width 0.1143)
		(layer "In4.Cu")
		(net "P5E_CPU1_G1_RX_DP<5>")
	)
	(arc
		(start 106.291634 -228.628194)
		(mid 106.283456 -228.633837)
		(end 106.275378 -228.639624)
		(width 0.1143)
		(layer "In4.Cu")
		(net "P5E_CPU1_G1_RX_DP<5>")
	)
	(arc
		(start 105.858564 -232.011982)
		(mid 105.991484 -232.145329)
		(end 106.040174 -232.327196)
		(width 0.1143)
		(layer "In4.Cu")
		(net "P5E_CPU1_G1_RX_DP<5>")
	)
	(arc
		(start 106.27741 -227.930964)
		(mid 106.284483 -227.935973)
		(end 106.291634 -227.94087)
		(width 0.1143)
		(layer "In4.Cu")
		(net "P5E_CPU1_G1_RX_DP<5>")
	)
	(arc
		(start 106.291634 -227.008182)
		(mid 106.284484 -227.01308)
		(end 106.27741 -227.018088)
		(width 0.1143)
		(layer "In4.Cu")
		(net "P5E_CPU1_G1_RX_DP<5>")
	)
	(arc
		(start 105.418636 -224.739708)
		(mid 105.534063 -224.873084)
		(end 105.575608 -225.044508)
		(width 0.1143)
		(layer "In4.Cu")
		(net "P5E_CPU1_G1_RX_DP<5>")
	)
	(arc
		(start 106.275378 -228.639624)
		(mid 106.110711 -228.838231)
		(end 106.045762 -229.087934)
		(width 0.1143)
		(layer "In4.Cu")
		(net "P5E_CPU1_G1_RX_DP<5>")
	)
	(arc
		(start 106.27741 -227.018088)
		(mid 106.050027 -227.474526)
		(end 106.27741 -227.930964)
		(width 0.1143)
		(layer "In4.Cu")
		(net "P5E_CPU1_G1_RX_DP<5>")
	)
	(arc
		(start 105.81894 -231.059736)
		(mid 105.575613 -231.524302)
		(end 105.81894 -231.988868)
		(width 0.1143)
		(layer "In4.Cu")
		(net "P5E_CPU1_G1_RX_DP<5>")
	)
	(arc
		(start 106.045762 -229.094538)
		(mid 106.110998 -229.358129)
		(end 106.291634 -229.560882)
		(width 0.1143)
		(layer "In4.Cu")
		(net "P5E_CPU1_G1_RX_DP<5>")
	)
	(arc
		(start 106.359706 -226.360228)
		(mid 106.515634 -226.66452)
		(end 106.359706 -226.968812)
		(width 0.1143)
		(layer "In4.Cu")
		(net "P5E_CPU1_G1_RX_DP<5>")
	)
	(arc
		(start 106.324908 -230.23195)
		(mid 106.120584 -230.435795)
		(end 106.045762 -230.71455)
		(width 0.1143)
		(layer "In4.Cu")
		(net "P5E_CPU1_G1_RX_DP<5>")
	)
	(arc
		(start 105.388918 -222.129858)
		(mid 105.107424 -222.594374)
		(end 105.350564 -223.080072)
		(width 0.1143)
		(layer "In4.Cu")
		(net "P5E_CPU1_G1_RX_DP<5>")
	)
	(arc
		(start 106.359706 -229.600252)
		(mid 106.474549 -229.7334)
		(end 106.515916 -229.90429)
		(width 0.1143)
		(layer "In4.Cu")
		(net "P5E_CPU1_G1_RX_DP<5>")
	)
	(arc
		(start 105.575862 -225.044508)
		(mid 105.651364 -225.32576)
		(end 105.857548 -225.531426)
		(width 0.1143)
		(layer "In4.Cu")
		(net "P5E_CPU1_G1_RX_DP<5>")
	)
	(arc
		(start 105.88752 -225.548952)
		(mid 106.003793 -225.682492)
		(end 106.045762 -225.854514)
		(width 0.1143)
		(layer "In4.Cu")
		(net "P5E_CPU1_G1_RX_DP<5>")
	)
	(arc
		(start 105.575862 -221.804484)
		(mid 105.526613 -221.990768)
		(end 105.391712 -222.128334)
		(width 0.1143)
		(layer "In4.Cu")
		(net "P5E_CPU1_G1_RX_DP<5>")
	)
	(arc
		(start 105.418636 -223.119696)
		(mid 105.575613 -223.424496)
		(end 105.418636 -223.729296)
		(width 0.1143)
		(layer "In4.Cu")
		(net "P5E_CPU1_G1_RX_DP<5>")
	)
	(arc
		(start 106.359706 -227.98024)
		(mid 106.515634 -228.284532)
		(end 106.359706 -228.588824)
		(width 0.1143)
		(layer "In4.Cu")
		(net "P5E_CPU1_G1_RX_DP<5>")
	)
	(arc
		(start 106.045762 -225.861626)
		(mid 106.111964 -226.112559)
		(end 106.27868 -226.31146)
		(width 0.1143)
		(layer "In4.Cu")
		(net "P5E_CPU1_G1_RX_DP<5>")
	)
	(arc
		(start 106.040174 -232.329736)
		(mid 106.11639 -232.613157)
		(end 106.324654 -232.819956)
		(width 0.1143)
		(layer "In4.Cu")
		(net "P5E_CPU1_G1_RX_DP<5>")
	)
	(arc
		(start 105.34904 -223.769936)
		(mid 105.105713 -224.234502)
		(end 105.34904 -224.699068)
		(width 0.1143)
		(layer "In4.Cu")
		(net "P5E_CPU1_G1_RX_DP<5>")
	)
	(arc
		(start 106.045762 -230.71455)
		(mid 106.003883 -230.886419)
		(end 105.887774 -231.019858)
		(width 0.1143)
		(layer "In4.Cu")
		(net "P5E_CPU1_G1_RX_DP<5>")
	)
	(arc
		(start 106.045762 -229.087934)
		(mid 106.045752 -229.091236)
		(end 106.045762 -229.094538)
		(width 0.1143)
		(layer "In4.Cu")
		(net "P5E_CPU1_G1_RX_DP<5>")
	)
	(arc
		(start 106.515916 -229.90429)
		(mid 106.465988 -230.09156)
		(end 106.32948 -230.229156)
		(width 0.1143)
		(layer "In4.Cu")
		(net "P5E_CPU1_G1_RX_DP<5>")
	)
	(arc
		(start 106.359706 -232.840022)
		(mid 106.456841 -232.942891)
		(end 106.508804 -233.074464)
		(width 0.1143)
		(layer "In4.Cu")
		(net "P5E_CPU1_G1_RX_DP<5>")
	)
	(arc
		(start 105.81894 -231.988868)
		(mid 105.819321 -231.989122)
		(end 105.819702 -231.989376)
		(width 0.1143)
		(layer "In4.Cu")
		(net "P5E_CPU1_G1_RX_DP<5>")
	)
	(segment
		(start 19.147028 -7.709154)
		(end 19.285712 -7.57047)
		(width 0.12954)
		(layer "F.Cu")
		(net "P5E_CPU1_G1_RX_DP<15>")
	)
	(segment
		(start 19.285712 -6.99516)
		(end 19.01571 -6.725158)
		(width 0.12954)
		(layer "F.Cu")
		(net "P5E_CPU1_G1_RX_DP<15>")
	)
	(segment
		(start 19.147028 -8.320024)
		(end 19.147028 -7.709154)
		(width 0.12954)
		(layer "F.Cu")
		(net "P5E_CPU1_G1_RX_DP<15>")
	)
	(segment
		(start 19.285712 -7.57047)
		(end 19.285712 -6.99516)
		(width 0.12954)
		(layer "F.Cu")
		(net "P5E_CPU1_G1_RX_DP<15>")
	)
	(segment
		(start 98.147886 -235.030264)
		(end 97.681034 -234.764326)
		(width 0.12954)
		(layer "F.Cu")
		(net "P5E_CPU1_G1_RX_DP<15>")
	)
	(segment
		(start 49.286922 -60.62726)
		(end 54.199282 -64.646048)
		(width 0.14224)
		(layer "In4.Cu")
		(net "P5E_CPU1_G1_RX_DP<15>")
	)
	(segment
		(start 96.454468 -225.529902)
		(end 96.457008 -225.531426)
		(width 0.1143)
		(layer "In4.Cu")
		(net "P5E_CPU1_G1_RX_DP<15>")
	)
	(segment
		(start 19.30654 -11.855196)
		(end 18.93189 -12.759944)
		(width 0.14224)
		(layer "In4.Cu")
		(net "P5E_CPU1_G1_RX_DP<15>")
	)
	(segment
		(start 95.480632 -222.27032)
		(end 95.481648 -222.270828)
		(width 0.1143)
		(layer "In4.Cu")
		(net "P5E_CPU1_G1_RX_DP<15>")
	)
	(segment
		(start 14.456664 -16.432784)
		(end 14.06779 -17.37106)
		(width 0.14224)
		(layer "In4.Cu")
		(net "P5E_CPU1_G1_RX_DP<15>")
	)
	(segment
		(start 96.928178 -226.34194)
		(end 96.958658 -226.35972)
		(width 0.1143)
		(layer "In4.Cu")
		(net "P5E_CPU1_G1_RX_DP<15>")
	)
	(segment
		(start 96.457008 -232.01122)
		(end 96.458024 -232.011728)
		(width 0.1143)
		(layer "In4.Cu")
		(net "P5E_CPU1_G1_RX_DP<15>")
	)
	(segment
		(start 96.889062 -226.31908)
		(end 96.928178 -226.34194)
		(width 0.1143)
		(layer "In4.Cu")
		(net "P5E_CPU1_G1_RX_DP<15>")
	)
	(segment
		(start 96.460056 -225.533204)
		(end 96.489774 -225.550222)
		(width 0.1143)
		(layer "In4.Cu")
		(net "P5E_CPU1_G1_RX_DP<15>")
	)
	(segment
		(start 96.418908 -225.509074)
		(end 96.425766 -225.513138)
		(width 0.1143)
		(layer "In4.Cu")
		(net "P5E_CPU1_G1_RX_DP<15>")
	)
	(segment
		(start 95.988124 -223.101916)
		(end 96.018604 -223.119696)
		(width 0.1143)
		(layer "In4.Cu")
		(net "P5E_CPU1_G1_RX_DP<15>")
	)
	(segment
		(start 96.457008 -225.531426)
		(end 96.458024 -225.531934)
		(width 0.1143)
		(layer "In4.Cu")
		(net "P5E_CPU1_G1_RX_DP<15>")
	)
	(segment
		(start 97.87001 -234.443016)
		(end 97.899728 -234.460034)
		(width 0.1143)
		(layer "In4.Cu")
		(net "P5E_CPU1_G1_RX_DP<15>")
	)
	(segment
		(start 18.93189 -12.759944)
		(end 14.456664 -16.432784)
		(width 0.14224)
		(layer "In4.Cu")
		(net "P5E_CPU1_G1_RX_DP<15>")
	)
	(segment
		(start 96.958658 -230.20909)
		(end 96.891602 -230.248206)
		(width 0.1143)
		(layer "In4.Cu")
		(net "P5E_CPU1_G1_RX_DP<15>")
	)
	(segment
		(start 95.949008 -223.079056)
		(end 95.988124 -223.101916)
		(width 0.1143)
		(layer "In4.Cu")
		(net "P5E_CPU1_G1_RX_DP<15>")
	)
	(segment
		(start 143.952468 -147.96643)
		(end 144.71523 -160.127696)
		(width 0.14224)
		(layer "In4.Cu")
		(net "P5E_CPU1_G1_RX_DP<15>")
	)
	(segment
		(start 98.048826 -234.694476)
		(end 97.978976 -234.764326)
		(width 0.1143)
		(layer "In4.Cu")
		(net "P5E_CPU1_G1_RX_DP<15>")
	)
	(segment
		(start 96.491552 -231.017318)
		(end 96.458024 -231.036876)
		(width 0.1143)
		(layer "In4.Cu")
		(net "P5E_CPU1_G1_RX_DP<15>")
	)
	(segment
		(start 96.418908 -231.988868)
		(end 96.425766 -231.992932)
		(width 0.1143)
		(layer "In4.Cu")
		(net "P5E_CPU1_G1_RX_DP<15>")
	)
	(segment
		(start 96.426528 -231.99344)
		(end 96.453706 -232.009188)
		(width 0.1143)
		(layer "In4.Cu")
		(net "P5E_CPU1_G1_RX_DP<15>")
	)
	(segment
		(start 14.06779 -17.686528)
		(end 14.164564 -17.973548)
		(width 0.14224)
		(layer "In4.Cu")
		(net "P5E_CPU1_G1_RX_DP<15>")
	)
	(segment
		(start 96.453706 -232.009188)
		(end 96.454468 -232.009696)
		(width 0.1143)
		(layer "In4.Cu")
		(net "P5E_CPU1_G1_RX_DP<15>")
	)
	(segment
		(start 19.30654 -7.015988)
		(end 19.30654 -11.855196)
		(width 0.14224)
		(layer "In4.Cu")
		(net "P5E_CPU1_G1_RX_DP<15>")
	)
	(segment
		(start 95.988124 -223.747076)
		(end 95.949008 -223.769936)
		(width 0.1143)
		(layer "In4.Cu")
		(net "P5E_CPU1_G1_RX_DP<15>")
	)
	(segment
		(start 19.01571 -6.725158)
		(end 19.30654 -7.015988)
		(width 0.14224)
		(layer "In4.Cu")
		(net "P5E_CPU1_G1_RX_DP<15>")
	)
	(segment
		(start 102.804722 -200.674986)
		(end 95.125032 -213.673944)
		(width 0.14224)
		(layer "In4.Cu")
		(net "P5E_CPU1_G1_RX_DP<15>")
	)
	(segment
		(start 96.928178 -227.961952)
		(end 96.958658 -227.979732)
		(width 0.1143)
		(layer "In4.Cu")
		(net "P5E_CPU1_G1_RX_DP<15>")
	)
	(segment
		(start 96.928178 -228.607112)
		(end 96.889062 -228.629972)
		(width 0.1143)
		(layer "In4.Cu")
		(net "P5E_CPU1_G1_RX_DP<15>")
	)
	(segment
		(start 96.889062 -232.798874)
		(end 96.928178 -232.821734)
		(width 0.1143)
		(layer "In4.Cu")
		(net "P5E_CPU1_G1_RX_DP<15>")
	)
	(segment
		(start 96.958658 -226.96932)
		(end 96.928178 -226.9871)
		(width 0.1143)
		(layer "In4.Cu")
		(net "P5E_CPU1_G1_RX_DP<15>")
	)
	(segment
		(start 97.978976 -234.764326)
		(end 97.681034 -234.764326)
		(width 0.1143)
		(layer "In4.Cu")
		(net "P5E_CPU1_G1_RX_DP<15>")
	)
	(segment
		(start 54.199282 -64.646048)
		(end 141.719554 -143.349472)
		(width 0.14224)
		(layer "In4.Cu")
		(net "P5E_CPU1_G1_RX_DP<15>")
	)
	(segment
		(start 96.889062 -229.559104)
		(end 96.928178 -229.581964)
		(width 0.1143)
		(layer "In4.Cu")
		(net "P5E_CPU1_G1_RX_DP<15>")
	)
	(segment
		(start 14.06779 -17.37106)
		(end 14.06779 -17.686528)
		(width 0.14224)
		(layer "In4.Cu")
		(net "P5E_CPU1_G1_RX_DP<15>")
	)
	(segment
		(start 97.598484 -233.963972)
		(end 97.598484 -233.973624)
		(width 0.1143)
		(layer "In4.Cu")
		(net "P5E_CPU1_G1_RX_DP<15>")
	)
	(segment
		(start 14.164564 -17.973548)
		(end 34.01949 -44.713398)
		(width 0.14224)
		(layer "In4.Cu")
		(net "P5E_CPU1_G1_RX_DP<15>")
	)
	(segment
		(start 95.481648 -222.270828)
		(end 95.54972 -222.310198)
		(width 0.1143)
		(layer "In4.Cu")
		(net "P5E_CPU1_G1_RX_DP<15>")
	)
	(segment
		(start 95.949008 -224.699068)
		(end 95.988124 -224.721928)
		(width 0.1143)
		(layer "In4.Cu")
		(net "P5E_CPU1_G1_RX_DP<15>")
	)
	(segment
		(start 143.887952 -164.50945)
		(end 140.225272 -170.026838)
		(width 0.14224)
		(layer "In4.Cu")
		(net "P5E_CPU1_G1_RX_DP<15>")
	)
	(segment
		(start 96.425766 -231.992932)
		(end 96.426528 -231.99344)
		(width 0.1143)
		(layer "In4.Cu")
		(net "P5E_CPU1_G1_RX_DP<15>")
	)
	(segment
		(start 96.928178 -229.581964)
		(end 96.96069 -229.60076)
		(width 0.1143)
		(layer "In4.Cu")
		(net "P5E_CPU1_G1_RX_DP<15>")
	)
	(segment
		(start 97.86874 -234.442254)
		(end 97.87001 -234.443016)
		(width 0.1143)
		(layer "In4.Cu")
		(net "P5E_CPU1_G1_RX_DP<15>")
	)
	(segment
		(start 95.170752 -221.334076)
		(end 95.170752 -221.592902)
		(width 0.1143)
		(layer "In4.Cu")
		(net "P5E_CPU1_G1_RX_DP<15>")
	)
	(segment
		(start 96.458024 -231.036876)
		(end 96.418908 -231.059736)
		(width 0.1143)
		(layer "In4.Cu")
		(net "P5E_CPU1_G1_RX_DP<15>")
	)
	(segment
		(start 96.889062 -227.939092)
		(end 96.928178 -227.961952)
		(width 0.1143)
		(layer "In4.Cu")
		(net "P5E_CPU1_G1_RX_DP<15>")
	)
	(segment
		(start 144.71523 -162.079432)
		(end 143.887952 -164.50945)
		(width 0.14224)
		(layer "In4.Cu")
		(net "P5E_CPU1_G1_RX_DP<15>")
	)
	(segment
		(start 97.358962 -233.60888)
		(end 97.410778 -233.639106)
		(width 0.1143)
		(layer "In4.Cu")
		(net "P5E_CPU1_G1_RX_DP<15>")
	)
	(segment
		(start 96.928178 -226.9871)
		(end 96.889062 -227.00996)
		(width 0.1143)
		(layer "In4.Cu")
		(net "P5E_CPU1_G1_RX_DP<15>")
	)
	(segment
		(start 96.458024 -232.011728)
		(end 96.458786 -232.012236)
		(width 0.1143)
		(layer "In4.Cu")
		(net "P5E_CPU1_G1_RX_DP<15>")
	)
	(segment
		(start 95.125032 -221.288356)
		(end 95.170752 -221.334076)
		(width 0.1143)
		(layer "In4.Cu")
		(net "P5E_CPU1_G1_RX_DP<15>")
	)
	(segment
		(start 96.458786 -225.532442)
		(end 96.460056 -225.533204)
		(width 0.1143)
		(layer "In4.Cu")
		(net "P5E_CPU1_G1_RX_DP<15>")
	)
	(segment
		(start 96.458786 -232.012236)
		(end 96.460056 -232.012998)
		(width 0.1143)
		(layer "In4.Cu")
		(net "P5E_CPU1_G1_RX_DP<15>")
	)
	(segment
		(start 34.01949 -44.713398)
		(end 49.286922 -60.62726)
		(width 0.14224)
		(layer "In4.Cu")
		(net "P5E_CPU1_G1_RX_DP<15>")
	)
	(segment
		(start 96.458024 -225.531934)
		(end 96.458786 -225.532442)
		(width 0.1143)
		(layer "In4.Cu")
		(net "P5E_CPU1_G1_RX_DP<15>")
	)
	(segment
		(start 96.018604 -223.729296)
		(end 95.988124 -223.747076)
		(width 0.1143)
		(layer "In4.Cu")
		(net "P5E_CPU1_G1_RX_DP<15>")
	)
	(segment
		(start 141.719554 -143.349472)
		(end 143.952468 -147.96643)
		(width 0.14224)
		(layer "In4.Cu")
		(net "P5E_CPU1_G1_RX_DP<15>")
	)
	(segment
		(start 96.928178 -232.821734)
		(end 96.958658 -232.839514)
		(width 0.1143)
		(layer "In4.Cu")
		(net "P5E_CPU1_G1_RX_DP<15>")
	)
	(segment
		(start 96.958658 -228.589332)
		(end 96.928178 -228.607112)
		(width 0.1143)
		(layer "In4.Cu")
		(net "P5E_CPU1_G1_RX_DP<15>")
	)
	(segment
		(start 144.71523 -160.127696)
		(end 144.71523 -162.079432)
		(width 0.14224)
		(layer "In4.Cu")
		(net "P5E_CPU1_G1_RX_DP<15>")
	)
	(segment
		(start 96.426528 -225.513646)
		(end 96.453706 -225.529394)
		(width 0.1143)
		(layer "In4.Cu")
		(net "P5E_CPU1_G1_RX_DP<15>")
	)
	(segment
		(start 95.125032 -221.259908)
		(end 95.125032 -221.288356)
		(width 0.1143)
		(layer "In4.Cu")
		(net "P5E_CPU1_G1_RX_DP<15>")
	)
	(segment
		(start 95.988124 -224.721928)
		(end 96.018604 -224.739708)
		(width 0.1143)
		(layer "In4.Cu")
		(net "P5E_CPU1_G1_RX_DP<15>")
	)
	(segment
		(start 96.460056 -232.012998)
		(end 96.489774 -232.030016)
		(width 0.1143)
		(layer "In4.Cu")
		(net "P5E_CPU1_G1_RX_DP<15>")
	)
	(segment
		(start 96.453706 -225.529394)
		(end 96.454468 -225.529902)
		(width 0.1143)
		(layer "In4.Cu")
		(net "P5E_CPU1_G1_RX_DP<15>")
	)
	(segment
		(start 95.125032 -213.673944)
		(end 95.125032 -221.259908)
		(width 0.14224)
		(layer "In4.Cu")
		(net "P5E_CPU1_G1_RX_DP<15>")
	)
	(segment
		(start 95.479616 -222.269558)
		(end 95.480632 -222.27032)
		(width 0.1143)
		(layer "In4.Cu")
		(net "P5E_CPU1_G1_RX_DP<15>")
	)
	(segment
		(start 140.225272 -170.026838)
		(end 102.804722 -200.674986)
		(width 0.14224)
		(layer "In4.Cu")
		(net "P5E_CPU1_G1_RX_DP<15>")
	)
	(segment
		(start 96.425766 -225.513138)
		(end 96.426528 -225.513646)
		(width 0.1143)
		(layer "In4.Cu")
		(net "P5E_CPU1_G1_RX_DP<15>")
	)
	(segment
		(start 95.170752 -221.592902)
		(end 95.235776 -221.657926)
		(width 0.1143)
		(layer "In4.Cu")
		(net "P5E_CPU1_G1_RX_DP<15>")
	)
	(segment
		(start 96.454468 -232.009696)
		(end 96.457008 -232.01122)
		(width 0.1143)
		(layer "In4.Cu")
		(net "P5E_CPU1_G1_RX_DP<15>")
	)
	(segment
		(start 97.867978 -234.441746)
		(end 97.86874 -234.442254)
		(width 0.1143)
		(layer "In4.Cu")
		(net "P5E_CPU1_G1_RX_DP<15>")
	)
	(segment
		(start 95.235776 -221.657926)
		(end 95.235776 -221.804484)
		(width 0.1143)
		(layer "In4.Cu")
		(net "P5E_CPU1_G1_RX_DP<15>")
	)
	(arc
		(start 95.949008 -223.769936)
		(mid 95.705681 -224.234502)
		(end 95.949008 -224.699068)
		(width 0.1143)
		(layer "In4.Cu")
		(net "P5E_CPU1_G1_RX_DP<15>")
	)
	(arc
		(start 97.598484 -233.973624)
		(mid 97.670674 -234.243695)
		(end 97.867978 -234.441746)
		(width 0.1143)
		(layer "In4.Cu")
		(net "P5E_CPU1_G1_RX_DP<15>")
	)
	(arc
		(start 96.489774 -232.030016)
		(mid 96.60445 -232.16335)
		(end 96.64573 -232.334308)
		(width 0.1143)
		(layer "In4.Cu")
		(net "P5E_CPU1_G1_RX_DP<15>")
	)
	(arc
		(start 96.418908 -231.059736)
		(mid 96.175581 -231.524302)
		(end 96.418908 -231.988868)
		(width 0.1143)
		(layer "In4.Cu")
		(net "P5E_CPU1_G1_RX_DP<15>")
	)
	(arc
		(start 95.54972 -222.310198)
		(mid 95.664396 -222.443532)
		(end 95.705676 -222.61449)
		(width 0.1143)
		(layer "In4.Cu")
		(net "P5E_CPU1_G1_RX_DP<15>")
	)
	(arc
		(start 96.018604 -224.739708)
		(mid 96.134031 -224.873084)
		(end 96.175576 -225.044508)
		(width 0.1143)
		(layer "In4.Cu")
		(net "P5E_CPU1_G1_RX_DP<15>")
	)
	(arc
		(start 96.889062 -227.00996)
		(mid 96.645735 -227.474526)
		(end 96.889062 -227.939092)
		(width 0.1143)
		(layer "In4.Cu")
		(net "P5E_CPU1_G1_RX_DP<15>")
	)
	(arc
		(start 96.958658 -227.979732)
		(mid 97.115635 -228.284532)
		(end 96.958658 -228.589332)
		(width 0.1143)
		(layer "In4.Cu")
		(net "P5E_CPU1_G1_RX_DP<15>")
	)
	(arc
		(start 96.958658 -232.839514)
		(mid 97.074085 -232.97289)
		(end 97.11563 -233.144314)
		(width 0.1143)
		(layer "In4.Cu")
		(net "P5E_CPU1_G1_RX_DP<15>")
	)
	(arc
		(start 96.489774 -225.550222)
		(mid 96.60445 -225.683556)
		(end 96.64573 -225.854514)
		(width 0.1143)
		(layer "In4.Cu")
		(net "P5E_CPU1_G1_RX_DP<15>")
	)
	(arc
		(start 96.889062 -228.629972)
		(mid 96.645735 -229.094538)
		(end 96.889062 -229.559104)
		(width 0.1143)
		(layer "In4.Cu")
		(net "P5E_CPU1_G1_RX_DP<15>")
	)
	(arc
		(start 96.64573 -230.71455)
		(mid 96.604968 -230.884434)
		(end 96.491552 -231.017318)
		(width 0.1143)
		(layer "In4.Cu")
		(net "P5E_CPU1_G1_RX_DP<15>")
	)
	(arc
		(start 97.11563 -233.144314)
		(mid 97.180145 -233.406533)
		(end 97.358962 -233.60888)
		(width 0.1143)
		(layer "In4.Cu")
		(net "P5E_CPU1_G1_RX_DP<15>")
	)
	(arc
		(start 95.705676 -222.61449)
		(mid 95.770191 -222.876709)
		(end 95.949008 -223.079056)
		(width 0.1143)
		(layer "In4.Cu")
		(net "P5E_CPU1_G1_RX_DP<15>")
	)
	(arc
		(start 97.410778 -233.639106)
		(mid 97.54821 -233.776365)
		(end 97.598484 -233.963972)
		(width 0.1143)
		(layer "In4.Cu")
		(net "P5E_CPU1_G1_RX_DP<15>")
	)
	(arc
		(start 96.018604 -223.119696)
		(mid 96.175581 -223.424496)
		(end 96.018604 -223.729296)
		(width 0.1143)
		(layer "In4.Cu")
		(net "P5E_CPU1_G1_RX_DP<15>")
	)
	(arc
		(start 97.11563 -229.90429)
		(mid 97.074081 -230.075712)
		(end 96.958658 -230.20909)
		(width 0.1143)
		(layer "In4.Cu")
		(net "P5E_CPU1_G1_RX_DP<15>")
	)
	(arc
		(start 96.175576 -225.044508)
		(mid 96.240091 -225.306727)
		(end 96.418908 -225.509074)
		(width 0.1143)
		(layer "In4.Cu")
		(net "P5E_CPU1_G1_RX_DP<15>")
	)
	(arc
		(start 95.235776 -221.804484)
		(mid 95.300435 -222.067041)
		(end 95.479616 -222.269558)
		(width 0.1143)
		(layer "In4.Cu")
		(net "P5E_CPU1_G1_RX_DP<15>")
	)
	(arc
		(start 96.64573 -232.334308)
		(mid 96.710245 -232.596527)
		(end 96.889062 -232.798874)
		(width 0.1143)
		(layer "In4.Cu")
		(net "P5E_CPU1_G1_RX_DP<15>")
	)
	(arc
		(start 97.899728 -234.460034)
		(mid 97.996863 -234.562903)
		(end 98.048826 -234.694476)
		(width 0.1143)
		(layer "In4.Cu")
		(net "P5E_CPU1_G1_RX_DP<15>")
	)
	(arc
		(start 96.96069 -229.60076)
		(mid 97.074619 -229.733907)
		(end 97.11563 -229.90429)
		(width 0.1143)
		(layer "In4.Cu")
		(net "P5E_CPU1_G1_RX_DP<15>")
	)
	(arc
		(start 96.891602 -230.248206)
		(mid 96.71095 -230.450951)
		(end 96.64573 -230.71455)
		(width 0.1143)
		(layer "In4.Cu")
		(net "P5E_CPU1_G1_RX_DP<15>")
	)
	(arc
		(start 96.958658 -226.35972)
		(mid 97.115635 -226.66452)
		(end 96.958658 -226.96932)
		(width 0.1143)
		(layer "In4.Cu")
		(net "P5E_CPU1_G1_RX_DP<15>")
	)
	(arc
		(start 96.64573 -225.854514)
		(mid 96.710245 -226.116733)
		(end 96.889062 -226.31908)
		(width 0.1143)
		(layer "In4.Cu")
		(net "P5E_CPU1_G1_RX_DP<15>")
	)
	(segment
		(start 41.31818 -5.239258)
		(end 41.31818 -7.57047)
		(width 0.12954)
		(layer "F.Cu")
		(net "P5E_CPU1_G1_RX_DN<6>")
	)
	(segment
		(start 41.594024 -4.963414)
		(end 41.31818 -5.239258)
		(width 0.12954)
		(layer "F.Cu")
		(net "P5E_CPU1_G1_RX_DN<6>")
	)
	(segment
		(start 41.31818 -7.57047)
		(end 41.456864 -7.709154)
		(width 0.12954)
		(layer "F.Cu")
		(net "P5E_CPU1_G1_RX_DN<6>")
	)
	(segment
		(start 104.72801 -235.030264)
		(end 104.261158 -234.764326)
		(width 0.12954)
		(layer "F.Cu")
		(net "P5E_CPU1_G1_RX_DN<6>")
	)
	(segment
		(start 41.456864 -7.709154)
		(end 41.456864 -8.320024)
		(width 0.12954)
		(layer "F.Cu")
		(net "P5E_CPU1_G1_RX_DN<6>")
	)
	(segment
		(start 105.013252 -232.821988)
		(end 105.010458 -232.823512)
		(width 0.1143)
		(layer "In4.Cu")
		(net "P5E_CPU1_G1_RX_DN<6>")
	)
	(segment
		(start 41.303194 -5.254244)
		(end 41.303194 -12.323826)
		(width 0.14224)
		(layer "In4.Cu")
		(net "P5E_CPU1_G1_RX_DN<6>")
	)
	(segment
		(start 105.016554 -232.82021)
		(end 105.01503 -232.821226)
		(width 0.1143)
		(layer "In4.Cu")
		(net "P5E_CPU1_G1_RX_DN<6>")
	)
	(segment
		(start 105.01503 -232.821226)
		(end 105.014014 -232.821734)
		(width 0.1143)
		(layer "In4.Cu")
		(net "P5E_CPU1_G1_RX_DN<6>")
	)
	(segment
		(start 104.583484 -222.26905)
		(end 104.512364 -222.310198)
		(width 0.1143)
		(layer "In4.Cu")
		(net "P5E_CPU1_G1_RX_DN<6>")
	)
	(segment
		(start 41.303194 -12.323826)
		(end 40.22852 -17.73047)
		(width 0.14224)
		(layer "In4.Cu")
		(net "P5E_CPU1_G1_RX_DN<6>")
	)
	(segment
		(start 105.046272 -225.385884)
		(end 105.05313 -225.389948)
		(width 0.1143)
		(layer "In4.Cu")
		(net "P5E_CPU1_G1_RX_DN<6>")
	)
	(segment
		(start 151.70785 -169.590212)
		(end 151.706072 -169.595038)
		(width 0.14224)
		(layer "In4.Cu")
		(net "P5E_CPU1_G1_RX_DN<6>")
	)
	(segment
		(start 105.483914 -226.177094)
		(end 105.52303 -226.199954)
		(width 0.1143)
		(layer "In4.Cu")
		(net "P5E_CPU1_G1_RX_DN<6>")
	)
	(segment
		(start 39.97325 -19.998944)
		(end 42.903902 -26.475944)
		(width 0.14224)
		(layer "In4.Cu")
		(net "P5E_CPU1_G1_RX_DN<6>")
	)
	(segment
		(start 43.001692 -26.692352)
		(end 52.421282 -50.147728)
		(width 0.14224)
		(layer "In4.Cu")
		(net "P5E_CPU1_G1_RX_DN<6>")
	)
	(segment
		(start 104.847644 -221.332806)
		(end 104.801924 -221.378526)
		(width 0.1143)
		(layer "In4.Cu")
		(net "P5E_CPU1_G1_RX_DN<6>")
	)
	(segment
		(start 105.022142 -232.816908)
		(end 105.018332 -232.819194)
		(width 0.1143)
		(layer "In4.Cu")
		(net "P5E_CPU1_G1_RX_DN<6>")
	)
	(segment
		(start 104.113076 -234.418886)
		(end 104.07396 -234.441746)
		(width 0.1143)
		(layer "In4.Cu")
		(net "P5E_CPU1_G1_RX_DN<6>")
	)
	(segment
		(start 104.512364 -222.918782)
		(end 104.542082 -222.9358)
		(width 0.1143)
		(layer "In4.Cu")
		(net "P5E_CPU1_G1_RX_DN<6>")
	)
	(segment
		(start 105.014014 -225.367088)
		(end 105.04551 -225.385376)
		(width 0.1143)
		(layer "In4.Cu")
		(net "P5E_CPU1_G1_RX_DN<6>")
	)
	(segment
		(start 40.22852 -17.73047)
		(end 39.842186 -18.66392)
		(width 0.14224)
		(layer "In4.Cu")
		(net "P5E_CPU1_G1_RX_DN<6>")
	)
	(segment
		(start 109.979206 -206.036418)
		(end 104.847644 -214.680546)
		(width 0.14224)
		(layer "In4.Cu")
		(net "P5E_CPU1_G1_RX_DN<6>")
	)
	(segment
		(start 54.786784 -53.421788)
		(end 55.285894 -53.969158)
		(width 0.14224)
		(layer "In4.Cu")
		(net "P5E_CPU1_G1_RX_DN<6>")
	)
	(segment
		(start 55.807864 -54.43855)
		(end 58.030872 -56.263794)
		(width 0.14224)
		(layer "In4.Cu")
		(net "P5E_CPU1_G1_RX_DN<6>")
	)
	(segment
		(start 151.705056 -169.598086)
		(end 151.511508 -170.109896)
		(width 0.14224)
		(layer "In4.Cu")
		(net "P5E_CPU1_G1_RX_DN<6>")
	)
	(segment
		(start 105.453434 -226.159314)
		(end 105.483914 -226.177094)
		(width 0.1143)
		(layer "In4.Cu")
		(net "P5E_CPU1_G1_RX_DN<6>")
	)
	(segment
		(start 52.421282 -50.147728)
		(end 54.786784 -53.421788)
		(width 0.14224)
		(layer "In4.Cu")
		(net "P5E_CPU1_G1_RX_DN<6>")
	)
	(segment
		(start 105.010458 -232.823512)
		(end 105.009188 -232.824274)
		(width 0.1143)
		(layer "In4.Cu")
		(net "P5E_CPU1_G1_RX_DN<6>")
	)
	(segment
		(start 105.52303 -227.129086)
		(end 105.483914 -227.151946)
		(width 0.1143)
		(layer "In4.Cu")
		(net "P5E_CPU1_G1_RX_DN<6>")
	)
	(segment
		(start 104.07396 -234.441746)
		(end 104.04348 -234.459526)
		(width 0.1143)
		(layer "In4.Cu")
		(net "P5E_CPU1_G1_RX_DN<6>")
	)
	(segment
		(start 105.012998 -231.846374)
		(end 105.014014 -231.846882)
		(width 0.1143)
		(layer "In4.Cu")
		(net "P5E_CPU1_G1_RX_DN<6>")
	)
	(segment
		(start 55.285894 -53.969158)
		(end 55.807864 -54.43855)
		(width 0.14224)
		(layer "In4.Cu")
		(net "P5E_CPU1_G1_RX_DN<6>")
	)
	(segment
		(start 151.706072 -169.595038)
		(end 151.705056 -169.598086)
		(width 0.14224)
		(layer "In4.Cu")
		(net "P5E_CPU1_G1_RX_DN<6>")
	)
	(segment
		(start 151.511508 -170.109896)
		(end 148.209 -174.70755)
		(width 0.14224)
		(layer "In4.Cu")
		(net "P5E_CPU1_G1_RX_DN<6>")
	)
	(segment
		(start 104.544114 -222.93707)
		(end 104.57561 -222.955358)
		(width 0.1143)
		(layer "In4.Cu")
		(net "P5E_CPU1_G1_RX_DN<6>")
	)
	(segment
		(start 105.009188 -232.824274)
		(end 105.006902 -232.825544)
		(width 0.1143)
		(layer "In4.Cu")
		(net "P5E_CPU1_G1_RX_DN<6>")
	)
	(segment
		(start 148.209 -174.70755)
		(end 109.979206 -206.036418)
		(width 0.14224)
		(layer "In4.Cu")
		(net "P5E_CPU1_G1_RX_DN<6>")
	)
	(segment
		(start 105.00487 -232.826814)
		(end 105.000298 -232.829354)
		(width 0.1143)
		(layer "In4.Cu")
		(net "P5E_CPU1_G1_RX_DN<6>")
	)
	(segment
		(start 104.58323 -223.889062)
		(end 104.546654 -223.910398)
		(width 0.1143)
		(layer "In4.Cu")
		(net "P5E_CPU1_G1_RX_DN<6>")
	)
	(segment
		(start 104.543352 -222.936562)
		(end 104.544114 -222.93707)
		(width 0.1143)
		(layer "In4.Cu")
		(net "P5E_CPU1_G1_RX_DN<6>")
	)
	(segment
		(start 105.453434 -227.779326)
		(end 105.483914 -227.797106)
		(width 0.1143)
		(layer "In4.Cu")
		(net "P5E_CPU1_G1_RX_DN<6>")
	)
	(segment
		(start 153.61412 -163.990528)
		(end 151.70785 -169.590212)
		(width 0.14224)
		(layer "In4.Cu")
		(net "P5E_CPU1_G1_RX_DN<6>")
	)
	(segment
		(start 153.61412 -159.84728)
		(end 153.61412 -163.990528)
		(width 0.14224)
		(layer "In4.Cu")
		(net "P5E_CPU1_G1_RX_DN<6>")
	)
	(segment
		(start 104.546654 -223.910398)
		(end 104.54513 -223.911414)
		(width 0.1143)
		(layer "In4.Cu")
		(net "P5E_CPU1_G1_RX_DN<6>")
	)
	(segment
		(start 105.01757 -232.819702)
		(end 105.016554 -232.82021)
		(width 0.1143)
		(layer "In4.Cu")
		(net "P5E_CPU1_G1_RX_DN<6>")
	)
	(segment
		(start 41.594024 -4.963414)
		(end 41.303194 -5.254244)
		(width 0.14224)
		(layer "In4.Cu")
		(net "P5E_CPU1_G1_RX_DN<6>")
	)
	(segment
		(start 105.52049 -230.370634)
		(end 105.453434 -230.40975)
		(width 0.1143)
		(layer "In4.Cu")
		(net "P5E_CPU1_G1_RX_DN<6>")
	)
	(segment
		(start 104.54386 -233.63174)
		(end 104.51211 -233.650282)
		(width 0.1143)
		(layer "In4.Cu")
		(net "P5E_CPU1_G1_RX_DN<6>")
	)
	(segment
		(start 105.52303 -228.749098)
		(end 105.483914 -228.771958)
		(width 0.1143)
		(layer "In4.Cu")
		(net "P5E_CPU1_G1_RX_DN<6>")
	)
	(segment
		(start 104.356154 -233.95432)
		(end 104.356408 -233.95432)
		(width 0.1143)
		(layer "In4.Cu")
		(net "P5E_CPU1_G1_RX_DN<6>")
	)
	(segment
		(start 104.801924 -221.378526)
		(end 104.801924 -221.558358)
		(width 0.1143)
		(layer "In4.Cu")
		(net "P5E_CPU1_G1_RX_DN<6>")
	)
	(segment
		(start 104.544114 -223.911922)
		(end 104.543352 -223.91243)
		(width 0.1143)
		(layer "In4.Cu")
		(net "P5E_CPU1_G1_RX_DN<6>")
	)
	(segment
		(start 105.014014 -232.821734)
		(end 105.013252 -232.821988)
		(width 0.1143)
		(layer "In4.Cu")
		(net "P5E_CPU1_G1_RX_DN<6>")
	)
	(segment
		(start 104.847644 -214.680546)
		(end 104.847644 -221.304358)
		(width 0.14224)
		(layer "In4.Cu")
		(net "P5E_CPU1_G1_RX_DN<6>")
	)
	(segment
		(start 58.030872 -56.263794)
		(end 58.922412 -57.065164)
		(width 0.14224)
		(layer "In4.Cu")
		(net "P5E_CPU1_G1_RX_DN<6>")
	)
	(segment
		(start 103.963216 -234.764326)
		(end 104.261158 -234.764326)
		(width 0.1143)
		(layer "In4.Cu")
		(net "P5E_CPU1_G1_RX_DN<6>")
	)
	(segment
		(start 42.951654 -26.581608)
		(end 43.001692 -26.692352)
		(width 0.14224)
		(layer "In4.Cu")
		(net "P5E_CPU1_G1_RX_DN<6>")
	)
	(segment
		(start 104.801924 -221.558358)
		(end 104.826308 -221.582742)
		(width 0.1143)
		(layer "In4.Cu")
		(net "P5E_CPU1_G1_RX_DN<6>")
	)
	(segment
		(start 104.542082 -222.9358)
		(end 104.543352 -222.936562)
		(width 0.1143)
		(layer "In4.Cu")
		(net "P5E_CPU1_G1_RX_DN<6>")
	)
	(segment
		(start 152.762712 -146.229324)
		(end 153.61412 -159.84728)
		(width 0.14224)
		(layer "In4.Cu")
		(net "P5E_CPU1_G1_RX_DN<6>")
	)
	(segment
		(start 104.576372 -222.955866)
		(end 104.58323 -222.95993)
		(width 0.1143)
		(layer "In4.Cu")
		(net "P5E_CPU1_G1_RX_DN<6>")
	)
	(segment
		(start 105.05313 -231.179116)
		(end 104.984296 -231.218994)
		(width 0.1143)
		(layer "In4.Cu")
		(net "P5E_CPU1_G1_RX_DN<6>")
	)
	(segment
		(start 103.893366 -234.694476)
		(end 103.963216 -234.764326)
		(width 0.1143)
		(layer "In4.Cu")
		(net "P5E_CPU1_G1_RX_DN<6>")
	)
	(segment
		(start 104.835198 -225.05162)
		(end 104.835198 -225.05924)
		(width 0.1143)
		(layer "In4.Cu")
		(net "P5E_CPU1_G1_RX_DN<6>")
	)
	(segment
		(start 105.483914 -227.797106)
		(end 105.52303 -227.819966)
		(width 0.1143)
		(layer "In4.Cu")
		(net "P5E_CPU1_G1_RX_DN<6>")
	)
	(segment
		(start 42.903902 -26.475944)
		(end 42.910252 -26.478738)
		(width 0.14224)
		(layer "In4.Cu")
		(net "P5E_CPU1_G1_RX_DN<6>")
	)
	(segment
		(start 104.57561 -222.955358)
		(end 104.576372 -222.955866)
		(width 0.1143)
		(layer "In4.Cu")
		(net "P5E_CPU1_G1_RX_DN<6>")
	)
	(segment
		(start 104.512364 -224.538794)
		(end 104.553766 -224.56267)
		(width 0.1143)
		(layer "In4.Cu")
		(net "P5E_CPU1_G1_RX_DN<6>")
	)
	(segment
		(start 104.61625 -222.245428)
		(end 104.583484 -222.26905)
		(width 0.1143)
		(layer "In4.Cu")
		(net "P5E_CPU1_G1_RX_DN<6>")
	)
	(segment
		(start 39.842186 -18.66392)
		(end 39.808658 -19.10588)
		(width 0.14224)
		(layer "In4.Cu")
		(net "P5E_CPU1_G1_RX_DN<6>")
	)
	(segment
		(start 148.594826 -137.62101)
		(end 152.762712 -146.229324)
		(width 0.14224)
		(layer "In4.Cu")
		(net "P5E_CPU1_G1_RX_DN<6>")
	)
	(segment
		(start 104.826308 -221.582742)
		(end 104.826308 -221.834964)
		(width 0.1143)
		(layer "In4.Cu")
		(net "P5E_CPU1_G1_RX_DN<6>")
	)
	(segment
		(start 58.922412 -57.065164)
		(end 60.212478 -58.145172)
		(width 0.14224)
		(layer "In4.Cu")
		(net "P5E_CPU1_G1_RX_DN<6>")
	)
	(segment
		(start 105.483914 -227.151946)
		(end 105.453434 -227.169726)
		(width 0.1143)
		(layer "In4.Cu")
		(net "P5E_CPU1_G1_RX_DN<6>")
	)
	(segment
		(start 105.005886 -232.826306)
		(end 105.00487 -232.826814)
		(width 0.1143)
		(layer "In4.Cu")
		(net "P5E_CPU1_G1_RX_DN<6>")
	)
	(segment
		(start 104.539542 -223.914462)
		(end 104.512364 -223.93021)
		(width 0.1143)
		(layer "In4.Cu")
		(net "P5E_CPU1_G1_RX_DN<6>")
	)
	(segment
		(start 105.483914 -229.416864)
		(end 105.52303 -229.439724)
		(width 0.1143)
		(layer "In4.Cu")
		(net "P5E_CPU1_G1_RX_DN<6>")
	)
	(segment
		(start 104.847644 -221.304358)
		(end 104.847644 -221.332806)
		(width 0.1143)
		(layer "In4.Cu")
		(net "P5E_CPU1_G1_RX_DN<6>")
	)
	(segment
		(start 39.808658 -19.10588)
		(end 39.97325 -19.998944)
		(width 0.14224)
		(layer "In4.Cu")
		(net "P5E_CPU1_G1_RX_DN<6>")
	)
	(segment
		(start 105.483914 -228.771958)
		(end 105.453434 -228.789738)
		(width 0.1143)
		(layer "In4.Cu")
		(net "P5E_CPU1_G1_RX_DN<6>")
	)
	(segment
		(start 105.013252 -225.36658)
		(end 105.014014 -225.367088)
		(width 0.1143)
		(layer "In4.Cu")
		(net "P5E_CPU1_G1_RX_DN<6>")
	)
	(segment
		(start 104.54513 -223.911414)
		(end 104.544114 -223.911922)
		(width 0.1143)
		(layer "In4.Cu")
		(net "P5E_CPU1_G1_RX_DN<6>")
	)
	(segment
		(start 105.031032 -232.811828)
		(end 105.022142 -232.816908)
		(width 0.1143)
		(layer "In4.Cu")
		(net "P5E_CPU1_G1_RX_DN<6>")
	)
	(segment
		(start 104.543352 -223.91243)
		(end 104.542082 -223.913192)
		(width 0.1143)
		(layer "In4.Cu")
		(net "P5E_CPU1_G1_RX_DN<6>")
	)
	(segment
		(start 105.04551 -225.385376)
		(end 105.046272 -225.385884)
		(width 0.1143)
		(layer "In4.Cu")
		(net "P5E_CPU1_G1_RX_DN<6>")
	)
	(segment
		(start 104.542082 -223.913192)
		(end 104.539542 -223.914462)
		(width 0.1143)
		(layer "In4.Cu")
		(net "P5E_CPU1_G1_RX_DN<6>")
	)
	(segment
		(start 105.451402 -229.398068)
		(end 105.483914 -229.416864)
		(width 0.1143)
		(layer "In4.Cu")
		(net "P5E_CPU1_G1_RX_DN<6>")
	)
	(segment
		(start 104.813862 -233.153458)
		(end 104.813862 -233.163618)
		(width 0.1143)
		(layer "In4.Cu")
		(net "P5E_CPU1_G1_RX_DN<6>")
	)
	(segment
		(start 42.910252 -26.478738)
		(end 42.951654 -26.581608)
		(width 0.14224)
		(layer "In4.Cu")
		(net "P5E_CPU1_G1_RX_DN<6>")
	)
	(segment
		(start 60.212478 -58.145172)
		(end 148.594826 -137.62101)
		(width 0.14224)
		(layer "In4.Cu")
		(net "P5E_CPU1_G1_RX_DN<6>")
	)
	(segment
		(start 105.018332 -232.819194)
		(end 105.01757 -232.819702)
		(width 0.1143)
		(layer "In4.Cu")
		(net "P5E_CPU1_G1_RX_DN<6>")
	)
	(segment
		(start 105.014014 -231.846882)
		(end 105.014268 -231.846882)
		(width 0.1143)
		(layer "In4.Cu")
		(net "P5E_CPU1_G1_RX_DN<6>")
	)
	(segment
		(start 105.006902 -232.825544)
		(end 105.005886 -232.826306)
		(width 0.1143)
		(layer "In4.Cu")
		(net "P5E_CPU1_G1_RX_DN<6>")
	)
	(arc
		(start 105.014268 -231.846882)
		(mid 105.042851 -231.863315)
		(end 105.070402 -231.881426)
		(width 0.1143)
		(layer "In4.Cu")
		(net "P5E_CPU1_G1_RX_DN<6>")
	)
	(arc
		(start 105.070402 -231.881426)
		(mid 105.304966 -232.357414)
		(end 105.031032 -232.811828)
		(width 0.1143)
		(layer "In4.Cu")
		(net "P5E_CPU1_G1_RX_DN<6>")
	)
	(arc
		(start 105.296462 -225.854514)
		(mid 105.338011 -226.025936)
		(end 105.453434 -226.159314)
		(width 0.1143)
		(layer "In4.Cu")
		(net "P5E_CPU1_G1_RX_DN<6>")
	)
	(arc
		(start 105.296462 -229.094538)
		(mid 105.337428 -229.264944)
		(end 105.451402 -229.398068)
		(width 0.1143)
		(layer "In4.Cu")
		(net "P5E_CPU1_G1_RX_DN<6>")
	)
	(arc
		(start 104.512364 -223.93021)
		(mid 104.356436 -224.234502)
		(end 104.512364 -224.538794)
		(width 0.1143)
		(layer "In4.Cu")
		(net "P5E_CPU1_G1_RX_DN<6>")
	)
	(arc
		(start 105.52303 -229.439724)
		(mid 105.701843 -229.642074)
		(end 105.766362 -229.90429)
		(width 0.1143)
		(layer "In4.Cu")
		(net "P5E_CPU1_G1_RX_DN<6>")
	)
	(arc
		(start 104.51211 -233.650282)
		(mid 104.397434 -233.783473)
		(end 104.356154 -233.95432)
		(width 0.1143)
		(layer "In4.Cu")
		(net "P5E_CPU1_G1_RX_DN<6>")
	)
	(arc
		(start 104.813862 -233.163618)
		(mid 104.74152 -233.433816)
		(end 104.54386 -233.63174)
		(width 0.1143)
		(layer "In4.Cu")
		(net "P5E_CPU1_G1_RX_DN<6>")
	)
	(arc
		(start 105.000298 -232.829354)
		(mid 104.863786 -232.966504)
		(end 104.813862 -233.153458)
		(width 0.1143)
		(layer "In4.Cu")
		(net "P5E_CPU1_G1_RX_DN<6>")
	)
	(arc
		(start 105.52303 -227.819966)
		(mid 105.766357 -228.284532)
		(end 105.52303 -228.749098)
		(width 0.1143)
		(layer "In4.Cu")
		(net "P5E_CPU1_G1_RX_DN<6>")
	)
	(arc
		(start 105.52303 -226.199954)
		(mid 105.766357 -226.66452)
		(end 105.52303 -227.129086)
		(width 0.1143)
		(layer "In4.Cu")
		(net "P5E_CPU1_G1_RX_DN<6>")
	)
	(arc
		(start 104.826308 -221.834964)
		(mid 104.770862 -222.065578)
		(end 104.61625 -222.245428)
		(width 0.1143)
		(layer "In4.Cu")
		(net "P5E_CPU1_G1_RX_DN<6>")
	)
	(arc
		(start 104.04348 -234.459526)
		(mid 103.945715 -234.562502)
		(end 103.893366 -234.694476)
		(width 0.1143)
		(layer "In4.Cu")
		(net "P5E_CPU1_G1_RX_DN<6>")
	)
	(arc
		(start 105.766362 -229.90429)
		(mid 105.701126 -230.167881)
		(end 105.52049 -230.370634)
		(width 0.1143)
		(layer "In4.Cu")
		(net "P5E_CPU1_G1_RX_DN<6>")
	)
	(arc
		(start 104.984296 -231.218994)
		(mid 104.82738 -231.54056)
		(end 105.012998 -231.846374)
		(width 0.1143)
		(layer "In4.Cu")
		(net "P5E_CPU1_G1_RX_DN<6>")
	)
	(arc
		(start 105.453434 -230.40975)
		(mid 105.338007 -230.543126)
		(end 105.296462 -230.71455)
		(width 0.1143)
		(layer "In4.Cu")
		(net "P5E_CPU1_G1_RX_DN<6>")
	)
	(arc
		(start 105.453434 -227.169726)
		(mid 105.296457 -227.474526)
		(end 105.453434 -227.779326)
		(width 0.1143)
		(layer "In4.Cu")
		(net "P5E_CPU1_G1_RX_DN<6>")
	)
	(arc
		(start 105.453434 -228.789738)
		(mid 105.338007 -228.923114)
		(end 105.296462 -229.094538)
		(width 0.1143)
		(layer "In4.Cu")
		(net "P5E_CPU1_G1_RX_DN<6>")
	)
	(arc
		(start 104.553766 -224.56267)
		(mid 104.759834 -224.769533)
		(end 104.835198 -225.05162)
		(width 0.1143)
		(layer "In4.Cu")
		(net "P5E_CPU1_G1_RX_DN<6>")
	)
	(arc
		(start 104.835198 -225.05924)
		(mid 104.882922 -225.236842)
		(end 105.013252 -225.36658)
		(width 0.1143)
		(layer "In4.Cu")
		(net "P5E_CPU1_G1_RX_DN<6>")
	)
	(arc
		(start 104.58323 -222.95993)
		(mid 104.826557 -223.424496)
		(end 104.58323 -223.889062)
		(width 0.1143)
		(layer "In4.Cu")
		(net "P5E_CPU1_G1_RX_DN<6>")
	)
	(arc
		(start 105.05313 -225.389948)
		(mid 105.231943 -225.592298)
		(end 105.296462 -225.854514)
		(width 0.1143)
		(layer "In4.Cu")
		(net "P5E_CPU1_G1_RX_DN<6>")
	)
	(arc
		(start 104.512364 -222.310198)
		(mid 104.356436 -222.61449)
		(end 104.512364 -222.918782)
		(width 0.1143)
		(layer "In4.Cu")
		(net "P5E_CPU1_G1_RX_DN<6>")
	)
	(arc
		(start 104.356408 -233.95432)
		(mid 104.291893 -234.216539)
		(end 104.113076 -234.418886)
		(width 0.1143)
		(layer "In4.Cu")
		(net "P5E_CPU1_G1_RX_DN<6>")
	)
	(arc
		(start 105.296462 -230.71455)
		(mid 105.231947 -230.976769)
		(end 105.05313 -231.179116)
		(width 0.1143)
		(layer "In4.Cu")
		(net "P5E_CPU1_G1_RX_DN<6>")
	)
	(segment
		(start 39.518336 -7.57047)
		(end 39.518336 -6.996176)
		(width 0.12954)
		(layer "F.Cu")
		(net "P5E_CPU1_G1_RX_DN<7>")
	)
	(segment
		(start 39.65702 -7.709154)
		(end 39.518336 -7.57047)
		(width 0.12954)
		(layer "F.Cu")
		(net "P5E_CPU1_G1_RX_DN<7>")
	)
	(segment
		(start 39.518336 -6.996176)
		(end 39.789354 -6.725158)
		(width 0.12954)
		(layer "F.Cu")
		(net "P5E_CPU1_G1_RX_DN<7>")
	)
	(segment
		(start 39.65702 -8.320024)
		(end 39.65702 -7.709154)
		(width 0.12954)
		(layer "F.Cu")
		(net "P5E_CPU1_G1_RX_DN<7>")
	)
	(segment
		(start 104.72801 -231.79024)
		(end 104.261158 -231.524302)
		(width 0.12954)
		(layer "F.Cu")
		(net "P5E_CPU1_G1_RX_DN<7>")
	)
	(segment
		(start 103.89743 -221.332806)
		(end 103.85171 -221.378526)
		(width 0.1143)
		(layer "In4.Cu")
		(net "P5E_CPU1_G1_RX_DN<7>")
	)
	(segment
		(start 104.513634 -226.159314)
		(end 104.544114 -226.177094)
		(width 0.1143)
		(layer "In4.Cu")
		(net "P5E_CPU1_G1_RX_DN<7>")
	)
	(segment
		(start 104.58069 -230.370634)
		(end 104.513634 -230.40975)
		(width 0.1143)
		(layer "In4.Cu")
		(net "P5E_CPU1_G1_RX_DN<7>")
	)
	(segment
		(start 104.073452 -225.36658)
		(end 104.074214 -225.367088)
		(width 0.1143)
		(layer "In4.Cu")
		(net "P5E_CPU1_G1_RX_DN<7>")
	)
	(segment
		(start 103.550212 -222.245936)
		(end 103.550212 -222.800164)
		(width 0.1143)
		(layer "In4.Cu")
		(net "P5E_CPU1_G1_RX_DN<7>")
	)
	(segment
		(start 103.963216 -231.524302)
		(end 104.261158 -231.524302)
		(width 0.1143)
		(layer "In4.Cu")
		(net "P5E_CPU1_G1_RX_DN<7>")
	)
	(segment
		(start 103.85171 -221.517972)
		(end 103.550212 -222.245936)
		(width 0.1143)
		(layer "In4.Cu")
		(net "P5E_CPU1_G1_RX_DN<7>")
	)
	(segment
		(start 104.042464 -225.3488)
		(end 104.042464 -225.348546)
		(width 0.1143)
		(layer "In4.Cu")
		(net "P5E_CPU1_G1_RX_DN<7>")
	)
	(segment
		(start 104.544114 -228.771958)
		(end 104.513634 -228.789738)
		(width 0.1143)
		(layer "In4.Cu")
		(net "P5E_CPU1_G1_RX_DN<7>")
	)
	(segment
		(start 104.513634 -227.779326)
		(end 104.544114 -227.797106)
		(width 0.1143)
		(layer "In4.Cu")
		(net "P5E_CPU1_G1_RX_DN<7>")
	)
	(segment
		(start 54.628288 -54.631844)
		(end 55.200042 -55.145686)
		(width 0.14224)
		(layer "In4.Cu")
		(net "P5E_CPU1_G1_RX_DN<7>")
	)
	(segment
		(start 36.745672 -17.815052)
		(end 36.967668 -18.229834)
		(width 0.14224)
		(layer "In4.Cu")
		(net "P5E_CPU1_G1_RX_DN<7>")
	)
	(segment
		(start 104.065578 -225.362008)
		(end 104.06634 -225.362516)
		(width 0.1143)
		(layer "In4.Cu")
		(net "P5E_CPU1_G1_RX_DN<7>")
	)
	(segment
		(start 104.106472 -225.385884)
		(end 104.11333 -225.389948)
		(width 0.1143)
		(layer "In4.Cu")
		(net "P5E_CPU1_G1_RX_DN<7>")
	)
	(segment
		(start 104.06634 -225.362516)
		(end 104.067864 -225.363278)
		(width 0.1143)
		(layer "In4.Cu")
		(net "P5E_CPU1_G1_RX_DN<7>")
	)
	(segment
		(start 104.042464 -225.348546)
		(end 104.060752 -225.359214)
		(width 0.1143)
		(layer "In4.Cu")
		(net "P5E_CPU1_G1_RX_DN<7>")
	)
	(segment
		(start 104.58323 -227.129086)
		(end 104.544114 -227.151946)
		(width 0.1143)
		(layer "In4.Cu")
		(net "P5E_CPU1_G1_RX_DN<7>")
	)
	(segment
		(start 37.022786 -16.484346)
		(end 36.70173 -17.542256)
		(width 0.14224)
		(layer "In4.Cu")
		(net "P5E_CPU1_G1_RX_DN<7>")
	)
	(segment
		(start 104.58323 -228.749098)
		(end 104.544114 -228.771958)
		(width 0.1143)
		(layer "In4.Cu")
		(net "P5E_CPU1_G1_RX_DN<7>")
	)
	(segment
		(start 104.11333 -231.179116)
		(end 104.074214 -231.201976)
		(width 0.1143)
		(layer "In4.Cu")
		(net "P5E_CPU1_G1_RX_DN<7>")
	)
	(segment
		(start 109.261402 -205.418944)
		(end 103.89743 -214.453724)
		(width 0.14224)
		(layer "In4.Cu")
		(net "P5E_CPU1_G1_RX_DN<7>")
	)
	(segment
		(start 103.57358 -224.539302)
		(end 103.60406 -224.557082)
		(width 0.1143)
		(layer "In4.Cu")
		(net "P5E_CPU1_G1_RX_DN<7>")
	)
	(segment
		(start 104.060752 -225.359214)
		(end 104.064308 -225.361246)
		(width 0.1143)
		(layer "In4.Cu")
		(net "P5E_CPU1_G1_RX_DN<7>")
	)
	(segment
		(start 58.311288 -57.769506)
		(end 59.601354 -58.849514)
		(width 0.14224)
		(layer "In4.Cu")
		(net "P5E_CPU1_G1_RX_DN<7>")
	)
	(segment
		(start 103.60406 -223.911922)
		(end 103.57358 -223.929702)
		(width 0.1143)
		(layer "In4.Cu")
		(net "P5E_CPU1_G1_RX_DN<7>")
	)
	(segment
		(start 55.200042 -55.145686)
		(end 57.42305 -56.97093)
		(width 0.14224)
		(layer "In4.Cu")
		(net "P5E_CPU1_G1_RX_DN<7>")
	)
	(segment
		(start 36.967668 -18.229834)
		(end 37.570918 -19.131534)
		(width 0.14224)
		(layer "In4.Cu")
		(net "P5E_CPU1_G1_RX_DN<7>")
	)
	(segment
		(start 51.431952 -50.794412)
		(end 54.078378 -54.029356)
		(width 0.14224)
		(layer "In4.Cu")
		(net "P5E_CPU1_G1_RX_DN<7>")
	)
	(segment
		(start 104.068626 -225.363786)
		(end 104.072182 -225.365818)
		(width 0.1143)
		(layer "In4.Cu")
		(net "P5E_CPU1_G1_RX_DN<7>")
	)
	(segment
		(start 57.42305 -56.97093)
		(end 58.311288 -57.769506)
		(width 0.14224)
		(layer "In4.Cu")
		(net "P5E_CPU1_G1_RX_DN<7>")
	)
	(segment
		(start 39.789354 -6.725158)
		(end 39.498524 -7.015988)
		(width 0.14224)
		(layer "In4.Cu")
		(net "P5E_CPU1_G1_RX_DN<7>")
	)
	(segment
		(start 104.544114 -229.416864)
		(end 104.58323 -229.439724)
		(width 0.1143)
		(layer "In4.Cu")
		(net "P5E_CPU1_G1_RX_DN<7>")
	)
	(segment
		(start 103.597456 -222.913956)
		(end 103.597456 -222.91421)
		(width 0.1143)
		(layer "In4.Cu")
		(net "P5E_CPU1_G1_RX_DN<7>")
	)
	(segment
		(start 103.550212 -222.800164)
		(end 103.597456 -222.913956)
		(width 0.1143)
		(layer "In4.Cu")
		(net "P5E_CPU1_G1_RX_DN<7>")
	)
	(segment
		(start 103.597456 -222.91421)
		(end 103.642922 -222.959422)
		(width 0.1143)
		(layer "In4.Cu")
		(net "P5E_CPU1_G1_RX_DN<7>")
	)
	(segment
		(start 103.89743 -221.304358)
		(end 103.89743 -221.332806)
		(width 0.1143)
		(layer "In4.Cu")
		(net "P5E_CPU1_G1_RX_DN<7>")
	)
	(segment
		(start 104.544114 -227.797106)
		(end 104.58323 -227.819966)
		(width 0.1143)
		(layer "In4.Cu")
		(net "P5E_CPU1_G1_RX_DN<7>")
	)
	(segment
		(start 104.072182 -225.365818)
		(end 104.073452 -225.36658)
		(width 0.1143)
		(layer "In4.Cu")
		(net "P5E_CPU1_G1_RX_DN<7>")
	)
	(segment
		(start 103.89743 -214.453724)
		(end 103.89743 -221.304358)
		(width 0.14224)
		(layer "In4.Cu")
		(net "P5E_CPU1_G1_RX_DN<7>")
	)
	(segment
		(start 104.544114 -226.177094)
		(end 104.58323 -226.199954)
		(width 0.1143)
		(layer "In4.Cu")
		(net "P5E_CPU1_G1_RX_DN<7>")
	)
	(segment
		(start 152.66924 -159.876998)
		(end 152.66924 -163.769548)
		(width 0.14224)
		(layer "In4.Cu")
		(net "P5E_CPU1_G1_RX_DN<7>")
	)
	(segment
		(start 39.389558 -22.911816)
		(end 41.207944 -26.692352)
		(width 0.14224)
		(layer "In4.Cu")
		(net "P5E_CPU1_G1_RX_DN<7>")
	)
	(segment
		(start 104.074214 -231.201976)
		(end 104.040686 -231.221534)
		(width 0.1143)
		(layer "In4.Cu")
		(net "P5E_CPU1_G1_RX_DN<7>")
	)
	(segment
		(start 36.70173 -17.70888)
		(end 36.745672 -17.815052)
		(width 0.14224)
		(layer "In4.Cu")
		(net "P5E_CPU1_G1_RX_DN<7>")
	)
	(segment
		(start 104.10571 -225.385376)
		(end 104.106472 -225.385884)
		(width 0.1143)
		(layer "In4.Cu")
		(net "P5E_CPU1_G1_RX_DN<7>")
	)
	(segment
		(start 104.067864 -225.363278)
		(end 104.068626 -225.363786)
		(width 0.1143)
		(layer "In4.Cu")
		(net "P5E_CPU1_G1_RX_DN<7>")
	)
	(segment
		(start 54.078378 -54.029356)
		(end 54.628288 -54.631844)
		(width 0.14224)
		(layer "In4.Cu")
		(net "P5E_CPU1_G1_RX_DN<7>")
	)
	(segment
		(start 147.835112 -138.192002)
		(end 151.829262 -146.443446)
		(width 0.14224)
		(layer "In4.Cu")
		(net "P5E_CPU1_G1_RX_DN<7>")
	)
	(segment
		(start 103.85171 -221.378526)
		(end 103.85171 -221.517972)
		(width 0.1143)
		(layer "In4.Cu")
		(net "P5E_CPU1_G1_RX_DN<7>")
	)
	(segment
		(start 59.601354 -58.849514)
		(end 147.835112 -138.192002)
		(width 0.14224)
		(layer "In4.Cu")
		(net "P5E_CPU1_G1_RX_DN<7>")
	)
	(segment
		(start 38.986714 -13.544804)
		(end 37.022786 -16.484346)
		(width 0.14224)
		(layer "In4.Cu")
		(net "P5E_CPU1_G1_RX_DN<7>")
	)
	(segment
		(start 36.70173 -17.542256)
		(end 36.70173 -17.70888)
		(width 0.14224)
		(layer "In4.Cu")
		(net "P5E_CPU1_G1_RX_DN<7>")
	)
	(segment
		(start 150.752556 -169.398696)
		(end 147.228052 -174.305722)
		(width 0.14224)
		(layer "In4.Cu")
		(net "P5E_CPU1_G1_RX_DN<7>")
	)
	(segment
		(start 39.224458 -12.97051)
		(end 38.986714 -13.544804)
		(width 0.14224)
		(layer "In4.Cu")
		(net "P5E_CPU1_G1_RX_DN<7>")
	)
	(segment
		(start 104.511602 -229.398068)
		(end 104.544114 -229.416864)
		(width 0.1143)
		(layer "In4.Cu")
		(net "P5E_CPU1_G1_RX_DN<7>")
	)
	(segment
		(start 39.498524 -11.593068)
		(end 39.224458 -12.97051)
		(width 0.14224)
		(layer "In4.Cu")
		(net "P5E_CPU1_G1_RX_DN<7>")
	)
	(segment
		(start 103.893366 -231.454452)
		(end 103.963216 -231.524302)
		(width 0.1143)
		(layer "In4.Cu")
		(net "P5E_CPU1_G1_RX_DN<7>")
	)
	(segment
		(start 103.60406 -224.557082)
		(end 103.643176 -224.579942)
		(width 0.1143)
		(layer "In4.Cu")
		(net "P5E_CPU1_G1_RX_DN<7>")
	)
	(segment
		(start 152.66924 -163.769548)
		(end 150.752556 -169.398696)
		(width 0.14224)
		(layer "In4.Cu")
		(net "P5E_CPU1_G1_RX_DN<7>")
	)
	(segment
		(start 37.570918 -19.131534)
		(end 39.389558 -22.911816)
		(width 0.14224)
		(layer "In4.Cu")
		(net "P5E_CPU1_G1_RX_DN<7>")
	)
	(segment
		(start 103.642922 -222.959422)
		(end 103.64343 -222.960184)
		(width 0.1143)
		(layer "In4.Cu")
		(net "P5E_CPU1_G1_RX_DN<7>")
	)
	(segment
		(start 104.544114 -227.151946)
		(end 104.513634 -227.169726)
		(width 0.1143)
		(layer "In4.Cu")
		(net "P5E_CPU1_G1_RX_DN<7>")
	)
	(segment
		(start 103.643176 -223.889062)
		(end 103.60406 -223.911922)
		(width 0.1143)
		(layer "In4.Cu")
		(net "P5E_CPU1_G1_RX_DN<7>")
	)
	(segment
		(start 104.064308 -225.361246)
		(end 104.065578 -225.362008)
		(width 0.1143)
		(layer "In4.Cu")
		(net "P5E_CPU1_G1_RX_DN<7>")
	)
	(segment
		(start 104.074214 -225.367088)
		(end 104.10571 -225.385376)
		(width 0.1143)
		(layer "In4.Cu")
		(net "P5E_CPU1_G1_RX_DN<7>")
	)
	(segment
		(start 151.829262 -146.443446)
		(end 152.66924 -159.876998)
		(width 0.14224)
		(layer "In4.Cu")
		(net "P5E_CPU1_G1_RX_DN<7>")
	)
	(segment
		(start 147.228052 -174.305722)
		(end 109.261402 -205.418944)
		(width 0.14224)
		(layer "In4.Cu")
		(net "P5E_CPU1_G1_RX_DN<7>")
	)
	(segment
		(start 39.498524 -7.015988)
		(end 39.498524 -11.593068)
		(width 0.14224)
		(layer "In4.Cu")
		(net "P5E_CPU1_G1_RX_DN<7>")
	)
	(segment
		(start 41.207944 -26.692352)
		(end 51.431952 -50.794412)
		(width 0.14224)
		(layer "In4.Cu")
		(net "P5E_CPU1_G1_RX_DN<7>")
	)
	(arc
		(start 104.11333 -225.389948)
		(mid 104.292143 -225.592298)
		(end 104.356662 -225.854514)
		(width 0.1143)
		(layer "In4.Cu")
		(net "P5E_CPU1_G1_RX_DN<7>")
	)
	(arc
		(start 104.58323 -229.439724)
		(mid 104.762043 -229.642074)
		(end 104.826562 -229.90429)
		(width 0.1143)
		(layer "In4.Cu")
		(net "P5E_CPU1_G1_RX_DN<7>")
	)
	(arc
		(start 103.643176 -224.579942)
		(mid 103.821989 -224.782292)
		(end 103.886508 -225.044508)
		(width 0.1143)
		(layer "In4.Cu")
		(net "P5E_CPU1_G1_RX_DN<7>")
	)
	(arc
		(start 104.356662 -225.854514)
		(mid 104.398211 -226.025936)
		(end 104.513634 -226.159314)
		(width 0.1143)
		(layer "In4.Cu")
		(net "P5E_CPU1_G1_RX_DN<7>")
	)
	(arc
		(start 104.826562 -229.90429)
		(mid 104.761326 -230.167881)
		(end 104.58069 -230.370634)
		(width 0.1143)
		(layer "In4.Cu")
		(net "P5E_CPU1_G1_RX_DN<7>")
	)
	(arc
		(start 103.64343 -222.960184)
		(mid 103.886439 -223.424673)
		(end 103.643176 -223.889062)
		(width 0.1143)
		(layer "In4.Cu")
		(net "P5E_CPU1_G1_RX_DN<7>")
	)
	(arc
		(start 104.513634 -230.40975)
		(mid 104.398207 -230.543126)
		(end 104.356662 -230.71455)
		(width 0.1143)
		(layer "In4.Cu")
		(net "P5E_CPU1_G1_RX_DN<7>")
	)
	(arc
		(start 103.57358 -223.929702)
		(mid 103.416603 -224.234502)
		(end 103.57358 -224.539302)
		(width 0.1143)
		(layer "In4.Cu")
		(net "P5E_CPU1_G1_RX_DN<7>")
	)
	(arc
		(start 103.886508 -225.044508)
		(mid 103.927763 -225.215479)
		(end 104.042464 -225.3488)
		(width 0.1143)
		(layer "In4.Cu")
		(net "P5E_CPU1_G1_RX_DN<7>")
	)
	(arc
		(start 104.513634 -227.169726)
		(mid 104.356657 -227.474526)
		(end 104.513634 -227.779326)
		(width 0.1143)
		(layer "In4.Cu")
		(net "P5E_CPU1_G1_RX_DN<7>")
	)
	(arc
		(start 104.58323 -227.819966)
		(mid 104.826557 -228.284532)
		(end 104.58323 -228.749098)
		(width 0.1143)
		(layer "In4.Cu")
		(net "P5E_CPU1_G1_RX_DN<7>")
	)
	(arc
		(start 104.58323 -226.199954)
		(mid 104.826557 -226.66452)
		(end 104.58323 -227.129086)
		(width 0.1143)
		(layer "In4.Cu")
		(net "P5E_CPU1_G1_RX_DN<7>")
	)
	(arc
		(start 104.356662 -230.71455)
		(mid 104.292147 -230.976769)
		(end 104.11333 -231.179116)
		(width 0.1143)
		(layer "In4.Cu")
		(net "P5E_CPU1_G1_RX_DN<7>")
	)
	(arc
		(start 104.513634 -228.789738)
		(mid 104.398207 -228.923114)
		(end 104.356662 -229.094538)
		(width 0.1143)
		(layer "In4.Cu")
		(net "P5E_CPU1_G1_RX_DN<7>")
	)
	(arc
		(start 104.356662 -229.094538)
		(mid 104.397628 -229.264944)
		(end 104.511602 -229.398068)
		(width 0.1143)
		(layer "In4.Cu")
		(net "P5E_CPU1_G1_RX_DN<7>")
	)
	(arc
		(start 104.040686 -231.221534)
		(mid 103.944798 -231.323942)
		(end 103.893366 -231.454452)
		(width 0.1143)
		(layer "In4.Cu")
		(net "P5E_CPU1_G1_RX_DN<7>")
	)
	(segment
		(start 104.72801 -233.410252)
		(end 104.261158 -233.144314)
		(width 0.12954)
		(layer "F.Cu")
		(net "P5E_CPU1_G1_RX_DN<8>")
	)
	(segment
		(start 32.48406 -4.963414)
		(end 32.209232 -5.238242)
		(width 0.12954)
		(layer "F.Cu")
		(net "P5E_CPU1_G1_RX_DN<8>")
	)
	(segment
		(start 32.209232 -5.238242)
		(end 32.209232 -7.571486)
		(width 0.12954)
		(layer "F.Cu")
		(net "P5E_CPU1_G1_RX_DN<8>")
	)
	(segment
		(start 32.3469 -7.709154)
		(end 32.3469 -8.320024)
		(width 0.12954)
		(layer "F.Cu")
		(net "P5E_CPU1_G1_RX_DN<8>")
	)
	(segment
		(start 32.209232 -7.571486)
		(end 32.3469 -7.709154)
		(width 0.12954)
		(layer "F.Cu")
		(net "P5E_CPU1_G1_RX_DN<8>")
	)
	(segment
		(start 51.936904 -52.885086)
		(end 53.368448 -54.6354)
		(width 0.14224)
		(layer "In4.Cu")
		(net "P5E_CPU1_G1_RX_DN<8>")
	)
	(segment
		(start 102.664006 -223.911922)
		(end 102.633526 -223.929702)
		(width 0.1143)
		(layer "In4.Cu")
		(net "P5E_CPU1_G1_RX_DN<8>")
	)
	(segment
		(start 53.970936 -55.29453)
		(end 54.59222 -55.852822)
		(width 0.14224)
		(layer "In4.Cu")
		(net "P5E_CPU1_G1_RX_DN<8>")
	)
	(segment
		(start 102.05212 -215.735154)
		(end 102.05212 -221.259908)
		(width 0.14224)
		(layer "In4.Cu")
		(net "P5E_CPU1_G1_RX_DN<8>")
	)
	(segment
		(start 102.703122 -223.889062)
		(end 102.664006 -223.911922)
		(width 0.1143)
		(layer "In4.Cu")
		(net "P5E_CPU1_G1_RX_DN<8>")
	)
	(segment
		(start 151.729948 -159.906716)
		(end 151.729948 -163.547806)
		(width 0.14224)
		(layer "In4.Cu")
		(net "P5E_CPU1_G1_RX_DN<8>")
	)
	(segment
		(start 103.6066 -227.150422)
		(end 103.605076 -227.151438)
		(width 0.1143)
		(layer "In4.Cu")
		(net "P5E_CPU1_G1_RX_DN<8>")
	)
	(segment
		(start 103.635556 -232.675176)
		(end 103.636318 -232.675684)
		(width 0.1143)
		(layer "In4.Cu")
		(net "P5E_CPU1_G1_RX_DN<8>")
	)
	(segment
		(start 103.603298 -232.65638)
		(end 103.60406 -232.656888)
		(width 0.1143)
		(layer "In4.Cu")
		(net "P5E_CPU1_G1_RX_DN<8>")
	)
	(segment
		(start 102.664006 -224.557082)
		(end 102.703122 -224.579942)
		(width 0.1143)
		(layer "In4.Cu")
		(net "P5E_CPU1_G1_RX_DN<8>")
	)
	(segment
		(start 33.944052 -19.319748)
		(end 33.946592 -19.324828)
		(width 0.14224)
		(layer "In4.Cu")
		(net "P5E_CPU1_G1_RX_DN<8>")
	)
	(segment
		(start 58.99023 -59.553856)
		(end 147.075398 -138.762994)
		(width 0.14224)
		(layer "In4.Cu")
		(net "P5E_CPU1_G1_RX_DN<8>")
	)
	(segment
		(start 103.603298 -226.176586)
		(end 103.60406 -226.177094)
		(width 0.1143)
		(layer "In4.Cu")
		(net "P5E_CPU1_G1_RX_DN<8>")
	)
	(segment
		(start 149.937978 -168.890442)
		(end 149.91842 -168.948608)
		(width 0.14224)
		(layer "In4.Cu")
		(net "P5E_CPU1_G1_RX_DN<8>")
	)
	(segment
		(start 102.633526 -222.91929)
		(end 102.664006 -222.93707)
		(width 0.1143)
		(layer "In4.Cu")
		(net "P5E_CPU1_G1_RX_DN<8>")
	)
	(segment
		(start 102.052628 -215.734392)
		(end 102.05212 -215.735154)
		(width 0.14224)
		(layer "In4.Cu")
		(net "P5E_CPU1_G1_RX_DN<8>")
	)
	(segment
		(start 149.91842 -168.948608)
		(end 146.519646 -173.680374)
		(width 0.14224)
		(layer "In4.Cu")
		(net "P5E_CPU1_G1_RX_DN<8>")
	)
	(segment
		(start 103.170482 -231.180894)
		(end 103.100632 -231.221534)
		(width 0.1143)
		(layer "In4.Cu")
		(net "P5E_CPU1_G1_RX_DN<8>")
	)
	(segment
		(start 33.941258 -19.31289)
		(end 33.941766 -19.314414)
		(width 0.14224)
		(layer "In4.Cu")
		(net "P5E_CPU1_G1_RX_DN<8>")
	)
	(segment
		(start 103.60406 -228.771958)
		(end 103.603298 -228.772466)
		(width 0.1143)
		(layer "In4.Cu")
		(net "P5E_CPU1_G1_RX_DN<8>")
	)
	(segment
		(start 103.603298 -228.772466)
		(end 103.57231 -228.790246)
		(width 0.1143)
		(layer "In4.Cu")
		(net "P5E_CPU1_G1_RX_DN<8>")
	)
	(segment
		(start 103.603298 -227.796598)
		(end 103.60406 -227.797106)
		(width 0.1143)
		(layer "In4.Cu")
		(net "P5E_CPU1_G1_RX_DN<8>")
	)
	(segment
		(start 103.636318 -226.19589)
		(end 103.643176 -226.199954)
		(width 0.1143)
		(layer "In4.Cu")
		(net "P5E_CPU1_G1_RX_DN<8>")
	)
	(segment
		(start 33.92551 -18.998692)
		(end 33.90773 -19.0881)
		(width 0.14224)
		(layer "In4.Cu")
		(net "P5E_CPU1_G1_RX_DN<8>")
	)
	(segment
		(start 103.880412 -233.06151)
		(end 103.963216 -233.144314)
		(width 0.1143)
		(layer "In4.Cu")
		(net "P5E_CPU1_G1_RX_DN<8>")
	)
	(segment
		(start 146.519646 -173.680374)
		(end 108.54309 -204.801978)
		(width 0.14224)
		(layer "In4.Cu")
		(net "P5E_CPU1_G1_RX_DN<8>")
	)
	(segment
		(start 103.963216 -233.144314)
		(end 104.261158 -233.144314)
		(width 0.1143)
		(layer "In4.Cu")
		(net "P5E_CPU1_G1_RX_DN<8>")
	)
	(segment
		(start 102.193344 -222.126556)
		(end 102.194106 -222.127064)
		(width 0.1143)
		(layer "In4.Cu")
		(net "P5E_CPU1_G1_RX_DN<8>")
	)
	(segment
		(start 103.598218 -232.653586)
		(end 103.603298 -232.65638)
		(width 0.1143)
		(layer "In4.Cu")
		(net "P5E_CPU1_G1_RX_DN<8>")
	)
	(segment
		(start 103.6066 -228.770434)
		(end 103.605076 -228.77145)
		(width 0.1143)
		(layer "In4.Cu")
		(net "P5E_CPU1_G1_RX_DN<8>")
	)
	(segment
		(start 33.90773 -19.0881)
		(end 33.90773 -19.223482)
		(width 0.14224)
		(layer "In4.Cu")
		(net "P5E_CPU1_G1_RX_DN<8>")
	)
	(segment
		(start 103.643176 -228.749098)
		(end 103.6066 -228.770434)
		(width 0.1143)
		(layer "In4.Cu")
		(net "P5E_CPU1_G1_RX_DN<8>")
	)
	(segment
		(start 103.57231 -227.778818)
		(end 103.603298 -227.796598)
		(width 0.1143)
		(layer "In4.Cu")
		(net "P5E_CPU1_G1_RX_DN<8>")
	)
	(segment
		(start 56.815228 -57.678066)
		(end 57.700164 -58.473848)
		(width 0.14224)
		(layer "In4.Cu")
		(net "P5E_CPU1_G1_RX_DN<8>")
	)
	(segment
		(start 103.132382 -225.366072)
		(end 103.134668 -225.367342)
		(width 0.1143)
		(layer "In4.Cu")
		(net "P5E_CPU1_G1_RX_DN<8>")
	)
	(segment
		(start 102.185978 -222.122492)
		(end 102.193344 -222.126556)
		(width 0.1143)
		(layer "In4.Cu")
		(net "P5E_CPU1_G1_RX_DN<8>")
	)
	(segment
		(start 103.605076 -228.77145)
		(end 103.60406 -228.771958)
		(width 0.1143)
		(layer "In4.Cu")
		(net "P5E_CPU1_G1_RX_DN<8>")
	)
	(segment
		(start 103.10241 -231.828594)
		(end 103.13416 -231.846882)
		(width 0.1143)
		(layer "In4.Cu")
		(net "P5E_CPU1_G1_RX_DN<8>")
	)
	(segment
		(start 150.894034 -166.022782)
		(end 150.073868 -168.451022)
		(width 0.14224)
		(layer "In4.Cu")
		(net "P5E_CPU1_G1_RX_DN<8>")
	)
	(segment
		(start 102.162356 -222.108776)
		(end 102.185978 -222.122492)
		(width 0.1143)
		(layer "In4.Cu")
		(net "P5E_CPU1_G1_RX_DN<8>")
	)
	(segment
		(start 103.60406 -227.797106)
		(end 103.635556 -227.815394)
		(width 0.1143)
		(layer "In4.Cu")
		(net "P5E_CPU1_G1_RX_DN<8>")
	)
	(segment
		(start 108.54309 -204.801978)
		(end 102.052628 -215.734392)
		(width 0.14224)
		(layer "In4.Cu")
		(net "P5E_CPU1_G1_RX_DN<8>")
	)
	(segment
		(start 103.60406 -226.177094)
		(end 103.635556 -226.195382)
		(width 0.1143)
		(layer "In4.Cu")
		(net "P5E_CPU1_G1_RX_DN<8>")
	)
	(segment
		(start 103.410766 -232.327196)
		(end 103.410766 -232.329736)
		(width 0.1143)
		(layer "In4.Cu")
		(net "P5E_CPU1_G1_RX_DN<8>")
	)
	(segment
		(start 103.134668 -225.367342)
		(end 103.135684 -225.36785)
		(width 0.1143)
		(layer "In4.Cu")
		(net "P5E_CPU1_G1_RX_DN<8>")
	)
	(segment
		(start 103.605076 -227.151438)
		(end 103.60406 -227.151946)
		(width 0.1143)
		(layer "In4.Cu")
		(net "P5E_CPU1_G1_RX_DN<8>")
	)
	(segment
		(start 102.194106 -222.127064)
		(end 102.195122 -222.127572)
		(width 0.1143)
		(layer "In4.Cu")
		(net "P5E_CPU1_G1_RX_DN<8>")
	)
	(segment
		(start 103.603298 -227.152454)
		(end 103.57231 -227.170234)
		(width 0.1143)
		(layer "In4.Cu")
		(net "P5E_CPU1_G1_RX_DN<8>")
	)
	(segment
		(start 32.19323 -11.530838)
		(end 32.501332 -12.546584)
		(width 0.14224)
		(layer "In4.Cu")
		(net "P5E_CPU1_G1_RX_DN<8>")
	)
	(segment
		(start 53.368448 -54.6354)
		(end 53.970936 -55.29453)
		(width 0.14224)
		(layer "In4.Cu")
		(net "P5E_CPU1_G1_RX_DN<8>")
	)
	(segment
		(start 102.05212 -221.259908)
		(end 102.05212 -221.288356)
		(width 0.1143)
		(layer "In4.Cu")
		(net "P5E_CPU1_G1_RX_DN<8>")
	)
	(segment
		(start 34.554922 -17.935702)
		(end 34.319718 -18.375122)
		(width 0.14224)
		(layer "In4.Cu")
		(net "P5E_CPU1_G1_RX_DN<8>")
	)
	(segment
		(start 33.940242 -19.310604)
		(end 33.94075 -19.31162)
		(width 0.14224)
		(layer "In4.Cu")
		(net "P5E_CPU1_G1_RX_DN<8>")
	)
	(segment
		(start 102.633526 -224.539302)
		(end 102.664006 -224.557082)
		(width 0.1143)
		(layer "In4.Cu")
		(net "P5E_CPU1_G1_RX_DN<8>")
	)
	(segment
		(start 38.071806 -26.692352)
		(end 49.513744 -49.922176)
		(width 0.14224)
		(layer "In4.Cu")
		(net "P5E_CPU1_G1_RX_DN<8>")
	)
	(segment
		(start 33.962594 -18.909284)
		(end 33.92551 -18.998692)
		(width 0.14224)
		(layer "In4.Cu")
		(net "P5E_CPU1_G1_RX_DN<8>")
	)
	(segment
		(start 33.946592 -19.324828)
		(end 33.9471 -19.326098)
		(width 0.14224)
		(layer "In4.Cu")
		(net "P5E_CPU1_G1_RX_DN<8>")
	)
	(segment
		(start 102.195122 -222.127572)
		(end 102.233222 -222.149924)
		(width 0.1143)
		(layer "In4.Cu")
		(net "P5E_CPU1_G1_RX_DN<8>")
	)
	(segment
		(start 33.90773 -19.223482)
		(end 33.940242 -19.310604)
		(width 0.14224)
		(layer "In4.Cu")
		(net "P5E_CPU1_G1_RX_DN<8>")
	)
	(segment
		(start 33.9471 -19.326098)
		(end 38.071806 -26.692352)
		(width 0.14224)
		(layer "In4.Cu")
		(net "P5E_CPU1_G1_RX_DN<8>")
	)
	(segment
		(start 103.636318 -232.675684)
		(end 103.643176 -232.679748)
		(width 0.1143)
		(layer "In4.Cu")
		(net "P5E_CPU1_G1_RX_DN<8>")
	)
	(segment
		(start 150.901654 -146.667474)
		(end 151.729948 -159.906716)
		(width 0.14224)
		(layer "In4.Cu")
		(net "P5E_CPU1_G1_RX_DN<8>")
	)
	(segment
		(start 33.226248 -14.078712)
		(end 34.625534 -17.46123)
		(width 0.14224)
		(layer "In4.Cu")
		(net "P5E_CPU1_G1_RX_DN<8>")
	)
	(segment
		(start 102.05212 -221.288356)
		(end 102.0064 -221.334076)
		(width 0.1143)
		(layer "In4.Cu")
		(net "P5E_CPU1_G1_RX_DN<8>")
	)
	(segment
		(start 103.605076 -230.394256)
		(end 103.599742 -230.397304)
		(width 0.1143)
		(layer "In4.Cu")
		(net "P5E_CPU1_G1_RX_DN<8>")
	)
	(segment
		(start 102.0064 -221.334076)
		(end 102.0064 -221.804738)
		(width 0.1143)
		(layer "In4.Cu")
		(net "P5E_CPU1_G1_RX_DN<8>")
	)
	(segment
		(start 103.636318 -227.815902)
		(end 103.643176 -227.819966)
		(width 0.1143)
		(layer "In4.Cu")
		(net "P5E_CPU1_G1_RX_DN<8>")
	)
	(segment
		(start 103.635556 -227.815394)
		(end 103.636318 -227.815902)
		(width 0.1143)
		(layer "In4.Cu")
		(net "P5E_CPU1_G1_RX_DN<8>")
	)
	(segment
		(start 50.725324 -51.403504)
		(end 51.936904 -52.885086)
		(width 0.14224)
		(layer "In4.Cu")
		(net "P5E_CPU1_G1_RX_DN<8>")
	)
	(segment
		(start 49.513744 -49.922176)
		(end 50.725324 -51.403504)
		(width 0.14224)
		(layer "In4.Cu")
		(net "P5E_CPU1_G1_RX_DN<8>")
	)
	(segment
		(start 32.501332 -12.546584)
		(end 33.226248 -14.078712)
		(width 0.14224)
		(layer "In4.Cu")
		(net "P5E_CPU1_G1_RX_DN<8>")
	)
	(segment
		(start 103.135684 -225.36785)
		(end 103.13797 -225.36912)
		(width 0.1143)
		(layer "In4.Cu")
		(net "P5E_CPU1_G1_RX_DN<8>")
	)
	(segment
		(start 147.075398 -138.762994)
		(end 150.901654 -146.667474)
		(width 0.14224)
		(layer "In4.Cu")
		(net "P5E_CPU1_G1_RX_DN<8>")
	)
	(segment
		(start 57.700164 -58.473848)
		(end 58.99023 -59.553856)
		(width 0.14224)
		(layer "In4.Cu")
		(net "P5E_CPU1_G1_RX_DN<8>")
	)
	(segment
		(start 33.941766 -19.314414)
		(end 33.944052 -19.319748)
		(width 0.14224)
		(layer "In4.Cu")
		(net "P5E_CPU1_G1_RX_DN<8>")
	)
	(segment
		(start 103.635556 -226.195382)
		(end 103.636318 -226.19589)
		(width 0.1143)
		(layer "In4.Cu")
		(net "P5E_CPU1_G1_RX_DN<8>")
	)
	(segment
		(start 103.13797 -225.36912)
		(end 103.138986 -225.369628)
		(width 0.1143)
		(layer "In4.Cu")
		(net "P5E_CPU1_G1_RX_DN<8>")
	)
	(segment
		(start 33.94075 -19.31162)
		(end 33.941258 -19.31289)
		(width 0.14224)
		(layer "In4.Cu")
		(net "P5E_CPU1_G1_RX_DN<8>")
	)
	(segment
		(start 103.570532 -229.397306)
		(end 103.643176 -229.439724)
		(width 0.1143)
		(layer "In4.Cu")
		(net "P5E_CPU1_G1_RX_DN<8>")
	)
	(segment
		(start 32.19323 -5.254244)
		(end 32.19323 -11.530838)
		(width 0.14224)
		(layer "In4.Cu")
		(net "P5E_CPU1_G1_RX_DN<8>")
	)
	(segment
		(start 103.60406 -232.656888)
		(end 103.635556 -232.675176)
		(width 0.1143)
		(layer "In4.Cu")
		(net "P5E_CPU1_G1_RX_DN<8>")
	)
	(segment
		(start 32.48406 -4.963414)
		(end 32.19323 -5.254244)
		(width 0.14224)
		(layer "In4.Cu")
		(net "P5E_CPU1_G1_RX_DN<8>")
	)
	(segment
		(start 151.729948 -163.547806)
		(end 150.894034 -166.022782)
		(width 0.14224)
		(layer "In4.Cu")
		(net "P5E_CPU1_G1_RX_DN<8>")
	)
	(segment
		(start 103.574596 -226.160076)
		(end 103.603298 -226.176586)
		(width 0.1143)
		(layer "In4.Cu")
		(net "P5E_CPU1_G1_RX_DN<8>")
	)
	(segment
		(start 103.643176 -227.129086)
		(end 103.6066 -227.150422)
		(width 0.1143)
		(layer "In4.Cu")
		(net "P5E_CPU1_G1_RX_DN<8>")
	)
	(segment
		(start 103.60406 -227.151946)
		(end 103.603298 -227.152454)
		(width 0.1143)
		(layer "In4.Cu")
		(net "P5E_CPU1_G1_RX_DN<8>")
	)
	(segment
		(start 54.59222 -55.852822)
		(end 56.815228 -57.678066)
		(width 0.14224)
		(layer "In4.Cu")
		(net "P5E_CPU1_G1_RX_DN<8>")
	)
	(segment
		(start 34.625534 -17.46123)
		(end 34.625534 -17.76476)
		(width 0.14224)
		(layer "In4.Cu")
		(net "P5E_CPU1_G1_RX_DN<8>")
	)
	(segment
		(start 34.625534 -17.76476)
		(end 34.554922 -17.935702)
		(width 0.14224)
		(layer "In4.Cu")
		(net "P5E_CPU1_G1_RX_DN<8>")
	)
	(segment
		(start 150.073868 -168.451022)
		(end 149.937978 -168.890442)
		(width 0.14224)
		(layer "In4.Cu")
		(net "P5E_CPU1_G1_RX_DN<8>")
	)
	(segment
		(start 103.138986 -225.369628)
		(end 103.170482 -225.38817)
		(width 0.1143)
		(layer "In4.Cu")
		(net "P5E_CPU1_G1_RX_DN<8>")
	)
	(segment
		(start 34.319718 -18.375122)
		(end 33.962594 -18.909284)
		(width 0.14224)
		(layer "In4.Cu")
		(net "P5E_CPU1_G1_RX_DN<8>")
	)
	(segment
		(start 102.664006 -222.93707)
		(end 102.703122 -222.95993)
		(width 0.1143)
		(layer "In4.Cu")
		(net "P5E_CPU1_G1_RX_DN<8>")
	)
	(arc
		(start 103.410766 -232.329736)
		(mid 103.461016 -232.516818)
		(end 103.598218 -232.653586)
		(width 0.1143)
		(layer "In4.Cu")
		(net "P5E_CPU1_G1_RX_DN<8>")
	)
	(arc
		(start 103.416354 -229.094538)
		(mid 103.457116 -229.264422)
		(end 103.570532 -229.397306)
		(width 0.1143)
		(layer "In4.Cu")
		(net "P5E_CPU1_G1_RX_DN<8>")
	)
	(arc
		(start 102.703122 -224.579942)
		(mid 102.881935 -224.782292)
		(end 102.946454 -225.044508)
		(width 0.1143)
		(layer "In4.Cu")
		(net "P5E_CPU1_G1_RX_DN<8>")
	)
	(arc
		(start 102.233222 -222.149924)
		(mid 102.412035 -222.352274)
		(end 102.476554 -222.61449)
		(width 0.1143)
		(layer "In4.Cu")
		(net "P5E_CPU1_G1_RX_DN<8>")
	)
	(arc
		(start 103.876602 -233.03865)
		(mid 103.878625 -233.05006)
		(end 103.880412 -233.06151)
		(width 0.1143)
		(layer "In4.Cu")
		(net "P5E_CPU1_G1_RX_DN<8>")
	)
	(arc
		(start 102.946454 -225.044508)
		(mid 102.996277 -225.230238)
		(end 103.132382 -225.366072)
		(width 0.1143)
		(layer "In4.Cu")
		(net "P5E_CPU1_G1_RX_DN<8>")
	)
	(arc
		(start 103.57231 -227.170234)
		(mid 103.420721 -227.474526)
		(end 103.57231 -227.778818)
		(width 0.1143)
		(layer "In4.Cu")
		(net "P5E_CPU1_G1_RX_DN<8>")
	)
	(arc
		(start 103.13416 -231.846882)
		(mid 103.3367 -232.050052)
		(end 103.410766 -232.327196)
		(width 0.1143)
		(layer "In4.Cu")
		(net "P5E_CPU1_G1_RX_DN<8>")
	)
	(arc
		(start 103.57231 -228.790246)
		(mid 103.460513 -228.925047)
		(end 103.416354 -229.094538)
		(width 0.1143)
		(layer "In4.Cu")
		(net "P5E_CPU1_G1_RX_DN<8>")
	)
	(arc
		(start 103.599742 -230.397304)
		(mid 103.46547 -230.531321)
		(end 103.416354 -230.71455)
		(width 0.1143)
		(layer "In4.Cu")
		(net "P5E_CPU1_G1_RX_DN<8>")
	)
	(arc
		(start 103.170482 -225.38817)
		(mid 103.351134 -225.590915)
		(end 103.416354 -225.854514)
		(width 0.1143)
		(layer "In4.Cu")
		(net "P5E_CPU1_G1_RX_DN<8>")
	)
	(arc
		(start 102.0064 -221.804738)
		(mid 102.047713 -221.975568)
		(end 102.162356 -222.108776)
		(width 0.1143)
		(layer "In4.Cu")
		(net "P5E_CPU1_G1_RX_DN<8>")
	)
	(arc
		(start 103.886508 -229.90429)
		(mid 103.81114 -230.186805)
		(end 103.605076 -230.394256)
		(width 0.1143)
		(layer "In4.Cu")
		(net "P5E_CPU1_G1_RX_DN<8>")
	)
	(arc
		(start 103.416354 -230.71455)
		(mid 103.351118 -230.978141)
		(end 103.170482 -231.180894)
		(width 0.1143)
		(layer "In4.Cu")
		(net "P5E_CPU1_G1_RX_DN<8>")
	)
	(arc
		(start 103.643176 -232.679748)
		(mid 103.795163 -232.836256)
		(end 103.876602 -233.03865)
		(width 0.1143)
		(layer "In4.Cu")
		(net "P5E_CPU1_G1_RX_DN<8>")
	)
	(arc
		(start 103.643176 -229.439724)
		(mid 103.821989 -229.642074)
		(end 103.886508 -229.90429)
		(width 0.1143)
		(layer "In4.Cu")
		(net "P5E_CPU1_G1_RX_DN<8>")
	)
	(arc
		(start 102.946454 -231.524302)
		(mid 102.987709 -231.695273)
		(end 103.10241 -231.828594)
		(width 0.1143)
		(layer "In4.Cu")
		(net "P5E_CPU1_G1_RX_DN<8>")
	)
	(arc
		(start 103.643176 -227.819966)
		(mid 103.886503 -228.284532)
		(end 103.643176 -228.749098)
		(width 0.1143)
		(layer "In4.Cu")
		(net "P5E_CPU1_G1_RX_DN<8>")
	)
	(arc
		(start 102.633526 -223.929702)
		(mid 102.476549 -224.234502)
		(end 102.633526 -224.539302)
		(width 0.1143)
		(layer "In4.Cu")
		(net "P5E_CPU1_G1_RX_DN<8>")
	)
	(arc
		(start 103.643176 -226.199954)
		(mid 103.886503 -226.66452)
		(end 103.643176 -227.129086)
		(width 0.1143)
		(layer "In4.Cu")
		(net "P5E_CPU1_G1_RX_DN<8>")
	)
	(arc
		(start 102.476554 -222.61449)
		(mid 102.518103 -222.785912)
		(end 102.633526 -222.91929)
		(width 0.1143)
		(layer "In4.Cu")
		(net "P5E_CPU1_G1_RX_DN<8>")
	)
	(arc
		(start 103.100632 -231.221534)
		(mid 102.987225 -231.354423)
		(end 102.946454 -231.524302)
		(width 0.1143)
		(layer "In4.Cu")
		(net "P5E_CPU1_G1_RX_DN<8>")
	)
	(arc
		(start 103.416354 -225.854514)
		(mid 103.461365 -226.02495)
		(end 103.574596 -226.160076)
		(width 0.1143)
		(layer "In4.Cu")
		(net "P5E_CPU1_G1_RX_DN<8>")
	)
	(arc
		(start 102.703122 -222.95993)
		(mid 102.946449 -223.424496)
		(end 102.703122 -223.889062)
		(width 0.1143)
		(layer "In4.Cu")
		(net "P5E_CPU1_G1_RX_DN<8>")
	)
	(segment
		(start 101.907848 -236.650276)
		(end 101.440996 -236.384338)
		(width 0.12954)
		(layer "F.Cu")
		(net "P5E_CPU1_G1_RX_DN<9>")
	)
	(segment
		(start 30.547056 -7.709154)
		(end 30.408372 -7.57047)
		(width 0.12954)
		(layer "F.Cu")
		(net "P5E_CPU1_G1_RX_DN<9>")
	)
	(segment
		(start 30.408372 -7.57047)
		(end 30.408372 -6.996176)
		(width 0.12954)
		(layer "F.Cu")
		(net "P5E_CPU1_G1_RX_DN<9>")
	)
	(segment
		(start 30.408372 -6.996176)
		(end 30.67939 -6.725158)
		(width 0.12954)
		(layer "F.Cu")
		(net "P5E_CPU1_G1_RX_DN<9>")
	)
	(segment
		(start 30.547056 -8.320024)
		(end 30.547056 -7.709154)
		(width 0.12954)
		(layer "F.Cu")
		(net "P5E_CPU1_G1_RX_DN<9>")
	)
	(segment
		(start 101.247702 -236.065314)
		(end 101.222302 -236.080046)
		(width 0.1143)
		(layer "In4.Cu")
		(net "P5E_CPU1_G1_RX_DN<9>")
	)
	(segment
		(start 53.984144 -56.560466)
		(end 56.207406 -58.385456)
		(width 0.14224)
		(layer "In4.Cu")
		(net "P5E_CPU1_G1_RX_DN<9>")
	)
	(segment
		(start 150.778718 -159.936688)
		(end 150.778718 -163.40963)
		(width 0.14224)
		(layer "In4.Cu")
		(net "P5E_CPU1_G1_RX_DN<9>")
	)
	(segment
		(start 102.70236 -228.749606)
		(end 102.66553 -228.770942)
		(width 0.1143)
		(layer "In4.Cu")
		(net "P5E_CPU1_G1_RX_DN<9>")
	)
	(segment
		(start 102.162356 -231.828594)
		(end 102.188772 -231.843834)
		(width 0.1143)
		(layer "In4.Cu")
		(net "P5E_CPU1_G1_RX_DN<9>")
	)
	(segment
		(start 101.222302 -222.108776)
		(end 101.254052 -222.127064)
		(width 0.1143)
		(layer "In4.Cu")
		(net "P5E_CPU1_G1_RX_DN<9>")
	)
	(segment
		(start 102.632256 -232.6386)
		(end 102.663244 -232.65638)
		(width 0.1143)
		(layer "In4.Cu")
		(net "P5E_CPU1_G1_RX_DN<9>")
	)
	(segment
		(start 101.066346 -221.544896)
		(end 101.066346 -221.804484)
		(width 0.1143)
		(layer "In4.Cu")
		(net "P5E_CPU1_G1_RX_DN<9>")
	)
	(segment
		(start 102.193344 -231.846374)
		(end 102.194106 -231.846882)
		(width 0.1143)
		(layer "In4.Cu")
		(net "P5E_CPU1_G1_RX_DN<9>")
	)
	(segment
		(start 145.695924 -173.147736)
		(end 107.71759 -204.272896)
		(width 0.14224)
		(layer "In4.Cu")
		(net "P5E_CPU1_G1_RX_DN<9>")
	)
	(segment
		(start 102.19055 -231.84485)
		(end 102.192074 -231.845612)
		(width 0.1143)
		(layer "In4.Cu")
		(net "P5E_CPU1_G1_RX_DN<9>")
	)
	(segment
		(start 101.073204 -236.314488)
		(end 101.143054 -236.384338)
		(width 0.1143)
		(layer "In4.Cu")
		(net "P5E_CPU1_G1_RX_DN<9>")
	)
	(segment
		(start 101.723952 -222.93707)
		(end 101.763068 -222.95993)
		(width 0.1143)
		(layer "In4.Cu")
		(net "P5E_CPU1_G1_RX_DN<9>")
	)
	(segment
		(start 102.196392 -234.440222)
		(end 102.194106 -234.441746)
		(width 0.1143)
		(layer "In4.Cu")
		(net "P5E_CPU1_G1_RX_DN<9>")
	)
	(segment
		(start 31.142686 -17.78762)
		(end 31.379668 -18.229834)
		(width 0.14224)
		(layer "In4.Cu")
		(net "P5E_CPU1_G1_RX_DN<9>")
	)
	(segment
		(start 57.08904 -59.17819)
		(end 58.379106 -60.258198)
		(width 0.14224)
		(layer "In4.Cu")
		(net "P5E_CPU1_G1_RX_DN<9>")
	)
	(segment
		(start 102.193344 -225.36658)
		(end 102.194106 -225.367088)
		(width 0.1143)
		(layer "In4.Cu")
		(net "P5E_CPU1_G1_RX_DN<9>")
	)
	(segment
		(start 101.723952 -224.557082)
		(end 101.763068 -224.579942)
		(width 0.1143)
		(layer "In4.Cu")
		(net "P5E_CPU1_G1_RX_DN<9>")
	)
	(segment
		(start 150.778718 -163.40963)
		(end 149.1742 -168.122092)
		(width 0.14224)
		(layer "In4.Cu")
		(net "P5E_CPU1_G1_RX_DN<9>")
	)
	(segment
		(start 30.38856 -11.77925)
		(end 31.12008 -17.697958)
		(width 0.14224)
		(layer "In4.Cu")
		(net "P5E_CPU1_G1_RX_DN<9>")
	)
	(segment
		(start 149.1615 -168.15943)
		(end 145.695924 -173.147736)
		(width 0.14224)
		(layer "In4.Cu")
		(net "P5E_CPU1_G1_RX_DN<9>")
	)
	(segment
		(start 101.763068 -235.228892)
		(end 101.723952 -235.251752)
		(width 0.1143)
		(layer "In4.Cu")
		(net "P5E_CPU1_G1_RX_DN<9>")
	)
	(segment
		(start 102.703122 -227.129086)
		(end 102.634288 -227.169218)
		(width 0.1143)
		(layer "In4.Cu")
		(net "P5E_CPU1_G1_RX_DN<9>")
	)
	(segment
		(start 102.680516 -233.622088)
		(end 102.66553 -233.630978)
		(width 0.1143)
		(layer "In4.Cu")
		(net "P5E_CPU1_G1_RX_DN<9>")
	)
	(segment
		(start 102.664514 -233.631486)
		(end 102.659942 -233.634026)
		(width 0.1143)
		(layer "In4.Cu")
		(net "P5E_CPU1_G1_RX_DN<9>")
	)
	(segment
		(start 31.12008 -17.697958)
		(end 31.142686 -17.78762)
		(width 0.14224)
		(layer "In4.Cu")
		(net "P5E_CPU1_G1_RX_DN<9>")
	)
	(segment
		(start 102.664006 -230.39197)
		(end 102.632256 -230.410258)
		(width 0.1143)
		(layer "In4.Cu")
		(net "P5E_CPU1_G1_RX_DN<9>")
	)
	(segment
		(start 36.611052 -26.692352)
		(end 47.222156 -48.592994)
		(width 0.14224)
		(layer "In4.Cu")
		(net "P5E_CPU1_G1_RX_DN<9>")
	)
	(segment
		(start 102.204266 -234.43565)
		(end 102.196392 -234.440222)
		(width 0.1143)
		(layer "In4.Cu")
		(net "P5E_CPU1_G1_RX_DN<9>")
	)
	(segment
		(start 102.665784 -232.657904)
		(end 102.702106 -232.678986)
		(width 0.1143)
		(layer "In4.Cu")
		(net "P5E_CPU1_G1_RX_DN<9>")
	)
	(segment
		(start 102.66553 -233.630978)
		(end 102.664514 -233.631486)
		(width 0.1143)
		(layer "In4.Cu")
		(net "P5E_CPU1_G1_RX_DN<9>")
	)
	(segment
		(start 47.222156 -48.592994)
		(end 52.658518 -55.240936)
		(width 0.14224)
		(layer "In4.Cu")
		(net "P5E_CPU1_G1_RX_DN<9>")
	)
	(segment
		(start 102.664006 -232.656888)
		(end 102.665022 -232.657396)
		(width 0.1143)
		(layer "In4.Cu")
		(net "P5E_CPU1_G1_RX_DN<9>")
	)
	(segment
		(start 102.632256 -226.158806)
		(end 102.703122 -226.199954)
		(width 0.1143)
		(layer "In4.Cu")
		(net "P5E_CPU1_G1_RX_DN<9>")
	)
	(segment
		(start 101.723952 -223.911922)
		(end 101.693472 -223.929702)
		(width 0.1143)
		(layer "In4.Cu")
		(net "P5E_CPU1_G1_RX_DN<9>")
	)
	(segment
		(start 58.379106 -60.258198)
		(end 146.315684 -139.333986)
		(width 0.14224)
		(layer "In4.Cu")
		(net "P5E_CPU1_G1_RX_DN<9>")
	)
	(segment
		(start 101.693472 -222.91929)
		(end 101.723952 -222.93707)
		(width 0.1143)
		(layer "In4.Cu")
		(net "P5E_CPU1_G1_RX_DN<9>")
	)
	(segment
		(start 31.379668 -18.229834)
		(end 34.449766 -22.816312)
		(width 0.14224)
		(layer "In4.Cu")
		(net "P5E_CPU1_G1_RX_DN<9>")
	)
	(segment
		(start 102.194106 -234.441746)
		(end 102.162356 -234.460034)
		(width 0.1143)
		(layer "In4.Cu")
		(net "P5E_CPU1_G1_RX_DN<9>")
	)
	(segment
		(start 102.663498 -228.771958)
		(end 102.63759 -228.787198)
		(width 0.1143)
		(layer "In4.Cu")
		(net "P5E_CPU1_G1_RX_DN<9>")
	)
	(segment
		(start 102.230428 -231.180894)
		(end 102.160578 -231.221534)
		(width 0.1143)
		(layer "In4.Cu")
		(net "P5E_CPU1_G1_RX_DN<9>")
	)
	(segment
		(start 101.081332 -215.516206)
		(end 101.081078 -215.51646)
		(width 0.14224)
		(layer "In4.Cu")
		(net "P5E_CPU1_G1_RX_DN<9>")
	)
	(segment
		(start 149.1742 -168.122092)
		(end 149.1742 -168.122346)
		(width 0.14224)
		(layer "In4.Cu")
		(net "P5E_CPU1_G1_RX_DN<9>")
	)
	(segment
		(start 52.658518 -55.240936)
		(end 53.313584 -55.95747)
		(width 0.14224)
		(layer "In4.Cu")
		(net "P5E_CPU1_G1_RX_DN<9>")
	)
	(segment
		(start 30.67939 -6.725158)
		(end 30.38856 -7.015988)
		(width 0.14224)
		(layer "In4.Cu")
		(net "P5E_CPU1_G1_RX_DN<9>")
	)
	(segment
		(start 101.254052 -222.127064)
		(end 101.293168 -222.149924)
		(width 0.1143)
		(layer "In4.Cu")
		(net "P5E_CPU1_G1_RX_DN<9>")
	)
	(segment
		(start 107.71759 -204.272896)
		(end 101.081332 -215.516206)
		(width 0.14224)
		(layer "In4.Cu")
		(net "P5E_CPU1_G1_RX_DN<9>")
	)
	(segment
		(start 101.249734 -236.064298)
		(end 101.247702 -236.065314)
		(width 0.1143)
		(layer "In4.Cu")
		(net "P5E_CPU1_G1_RX_DN<9>")
	)
	(segment
		(start 102.162356 -225.3488)
		(end 102.188772 -225.36404)
		(width 0.1143)
		(layer "In4.Cu")
		(net "P5E_CPU1_G1_RX_DN<9>")
	)
	(segment
		(start 102.188772 -231.843834)
		(end 102.189788 -231.844342)
		(width 0.1143)
		(layer "In4.Cu")
		(net "P5E_CPU1_G1_RX_DN<9>")
	)
	(segment
		(start 102.63759 -228.787198)
		(end 102.636828 -228.787706)
		(width 0.1143)
		(layer "In4.Cu")
		(net "P5E_CPU1_G1_RX_DN<9>")
	)
	(segment
		(start 102.189788 -231.844342)
		(end 102.19055 -231.84485)
		(width 0.1143)
		(layer "In4.Cu")
		(net "P5E_CPU1_G1_RX_DN<9>")
	)
	(segment
		(start 101.693472 -224.539302)
		(end 101.723952 -224.557082)
		(width 0.1143)
		(layer "In4.Cu")
		(net "P5E_CPU1_G1_RX_DN<9>")
	)
	(segment
		(start 149.1742 -168.122346)
		(end 149.1615 -168.15943)
		(width 0.14224)
		(layer "In4.Cu")
		(net "P5E_CPU1_G1_RX_DN<9>")
	)
	(segment
		(start 101.763068 -223.889062)
		(end 101.723952 -223.911922)
		(width 0.1143)
		(layer "In4.Cu")
		(net "P5E_CPU1_G1_RX_DN<9>")
	)
	(segment
		(start 101.293168 -236.038898)
		(end 101.256592 -236.060234)
		(width 0.1143)
		(layer "In4.Cu")
		(net "P5E_CPU1_G1_RX_DN<9>")
	)
	(segment
		(start 34.449766 -22.816312)
		(end 36.611052 -26.692352)
		(width 0.14224)
		(layer "In4.Cu")
		(net "P5E_CPU1_G1_RX_DN<9>")
	)
	(segment
		(start 102.702106 -232.678986)
		(end 102.726236 -232.696004)
		(width 0.1143)
		(layer "In4.Cu")
		(net "P5E_CPU1_G1_RX_DN<9>")
	)
	(segment
		(start 102.4763 -230.546656)
		(end 102.4763 -230.71455)
		(width 0.1143)
		(layer "In4.Cu")
		(net "P5E_CPU1_G1_RX_DN<9>")
	)
	(segment
		(start 102.726236 -233.592624)
		(end 102.703122 -233.609134)
		(width 0.1143)
		(layer "In4.Cu")
		(net "P5E_CPU1_G1_RX_DN<9>")
	)
	(segment
		(start 101.081078 -221.259908)
		(end 101.081078 -221.288356)
		(width 0.1143)
		(layer "In4.Cu")
		(net "P5E_CPU1_G1_RX_DN<9>")
	)
	(segment
		(start 56.207406 -58.385456)
		(end 57.08904 -59.17819)
		(width 0.14224)
		(layer "In4.Cu")
		(net "P5E_CPU1_G1_RX_DN<9>")
	)
	(segment
		(start 102.194106 -225.367088)
		(end 102.196392 -225.368358)
		(width 0.1143)
		(layer "In4.Cu")
		(net "P5E_CPU1_G1_RX_DN<9>")
	)
	(segment
		(start 101.081078 -221.288356)
		(end 101.035358 -221.334076)
		(width 0.1143)
		(layer "In4.Cu")
		(net "P5E_CPU1_G1_RX_DN<9>")
	)
	(segment
		(start 101.254052 -236.061758)
		(end 101.25329 -236.062266)
		(width 0.1143)
		(layer "In4.Cu")
		(net "P5E_CPU1_G1_RX_DN<9>")
	)
	(segment
		(start 102.663244 -232.65638)
		(end 102.664006 -232.656888)
		(width 0.1143)
		(layer "In4.Cu")
		(net "P5E_CPU1_G1_RX_DN<9>")
	)
	(segment
		(start 102.664006 -228.771958)
		(end 102.663498 -228.771958)
		(width 0.1143)
		(layer "In4.Cu")
		(net "P5E_CPU1_G1_RX_DN<9>")
	)
	(segment
		(start 101.723952 -235.251752)
		(end 101.693472 -235.269532)
		(width 0.1143)
		(layer "In4.Cu")
		(net "P5E_CPU1_G1_RX_DN<9>")
	)
	(segment
		(start 102.632256 -230.410258)
		(end 102.495858 -230.508556)
		(width 0.1143)
		(layer "In4.Cu")
		(net "P5E_CPU1_G1_RX_DN<9>")
	)
	(segment
		(start 149.960838 -146.863816)
		(end 150.778718 -159.936688)
		(width 0.14224)
		(layer "In4.Cu")
		(net "P5E_CPU1_G1_RX_DN<9>")
	)
	(segment
		(start 53.313584 -55.95747)
		(end 53.984144 -56.560466)
		(width 0.14224)
		(layer "In4.Cu")
		(net "P5E_CPU1_G1_RX_DN<9>")
	)
	(segment
		(start 102.665022 -232.657396)
		(end 102.665784 -232.657904)
		(width 0.1143)
		(layer "In4.Cu")
		(net "P5E_CPU1_G1_RX_DN<9>")
	)
	(segment
		(start 101.035358 -221.334076)
		(end 101.035358 -221.513908)
		(width 0.1143)
		(layer "In4.Cu")
		(net "P5E_CPU1_G1_RX_DN<9>")
	)
	(segment
		(start 30.38856 -7.015988)
		(end 30.38856 -11.77925)
		(width 0.14224)
		(layer "In4.Cu")
		(net "P5E_CPU1_G1_RX_DN<9>")
	)
	(segment
		(start 102.192074 -231.845612)
		(end 102.193344 -231.846374)
		(width 0.1143)
		(layer "In4.Cu")
		(net "P5E_CPU1_G1_RX_DN<9>")
	)
	(segment
		(start 102.188772 -225.36404)
		(end 102.189788 -225.364548)
		(width 0.1143)
		(layer "In4.Cu")
		(net "P5E_CPU1_G1_RX_DN<9>")
	)
	(segment
		(start 102.664006 -229.416864)
		(end 102.703122 -229.439724)
		(width 0.1143)
		(layer "In4.Cu")
		(net "P5E_CPU1_G1_RX_DN<9>")
	)
	(segment
		(start 102.66553 -228.770942)
		(end 102.664006 -228.771958)
		(width 0.1143)
		(layer "In4.Cu")
		(net "P5E_CPU1_G1_RX_DN<9>")
	)
	(segment
		(start 102.194106 -231.846882)
		(end 102.196392 -231.848152)
		(width 0.1143)
		(layer "In4.Cu")
		(net "P5E_CPU1_G1_RX_DN<9>")
	)
	(segment
		(start 101.256592 -236.060234)
		(end 101.255068 -236.06125)
		(width 0.1143)
		(layer "In4.Cu")
		(net "P5E_CPU1_G1_RX_DN<9>")
	)
	(segment
		(start 101.250496 -236.06379)
		(end 101.249734 -236.064298)
		(width 0.1143)
		(layer "In4.Cu")
		(net "P5E_CPU1_G1_RX_DN<9>")
	)
	(segment
		(start 102.189788 -225.364548)
		(end 102.19055 -225.365056)
		(width 0.1143)
		(layer "In4.Cu")
		(net "P5E_CPU1_G1_RX_DN<9>")
	)
	(segment
		(start 102.630478 -229.397306)
		(end 102.664006 -229.416864)
		(width 0.1143)
		(layer "In4.Cu")
		(net "P5E_CPU1_G1_RX_DN<9>")
	)
	(segment
		(start 101.081078 -215.51646)
		(end 101.081078 -221.259908)
		(width 0.14224)
		(layer "In4.Cu")
		(net "P5E_CPU1_G1_RX_DN<9>")
	)
	(segment
		(start 102.703122 -233.609134)
		(end 102.680516 -233.622088)
		(width 0.1143)
		(layer "In4.Cu")
		(net "P5E_CPU1_G1_RX_DN<9>")
	)
	(segment
		(start 102.19055 -225.365056)
		(end 102.192074 -225.365818)
		(width 0.1143)
		(layer "In4.Cu")
		(net "P5E_CPU1_G1_RX_DN<9>")
	)
	(segment
		(start 102.700582 -230.370634)
		(end 102.664006 -230.39197)
		(width 0.1143)
		(layer "In4.Cu")
		(net "P5E_CPU1_G1_RX_DN<9>")
	)
	(segment
		(start 101.25329 -236.062266)
		(end 101.25202 -236.063028)
		(width 0.1143)
		(layer "In4.Cu")
		(net "P5E_CPU1_G1_RX_DN<9>")
	)
	(segment
		(start 101.143054 -236.384338)
		(end 101.440996 -236.384338)
		(width 0.1143)
		(layer "In4.Cu")
		(net "P5E_CPU1_G1_RX_DN<9>")
	)
	(segment
		(start 101.035358 -221.513908)
		(end 101.066346 -221.544896)
		(width 0.1143)
		(layer "In4.Cu")
		(net "P5E_CPU1_G1_RX_DN<9>")
	)
	(segment
		(start 102.192074 -225.365818)
		(end 102.193344 -225.36658)
		(width 0.1143)
		(layer "In4.Cu")
		(net "P5E_CPU1_G1_RX_DN<9>")
	)
	(segment
		(start 101.255068 -236.06125)
		(end 101.254052 -236.061758)
		(width 0.1143)
		(layer "In4.Cu")
		(net "P5E_CPU1_G1_RX_DN<9>")
	)
	(segment
		(start 101.25202 -236.063028)
		(end 101.250496 -236.06379)
		(width 0.1143)
		(layer "In4.Cu")
		(net "P5E_CPU1_G1_RX_DN<9>")
	)
	(segment
		(start 146.315684 -139.333986)
		(end 149.960838 -146.863816)
		(width 0.14224)
		(layer "In4.Cu")
		(net "P5E_CPU1_G1_RX_DN<9>")
	)
	(arc
		(start 102.196392 -231.848152)
		(mid 102.401337 -232.053814)
		(end 102.4763 -232.334308)
		(width 0.1143)
		(layer "In4.Cu")
		(net "P5E_CPU1_G1_RX_DN<9>")
	)
	(arc
		(start 102.0064 -231.524302)
		(mid 102.047655 -231.695273)
		(end 102.162356 -231.828594)
		(width 0.1143)
		(layer "In4.Cu")
		(net "P5E_CPU1_G1_RX_DN<9>")
	)
	(arc
		(start 102.0064 -234.764326)
		(mid 101.941885 -235.026545)
		(end 101.763068 -235.228892)
		(width 0.1143)
		(layer "In4.Cu")
		(net "P5E_CPU1_G1_RX_DN<9>")
	)
	(arc
		(start 101.293168 -222.149924)
		(mid 101.471981 -222.352274)
		(end 101.5365 -222.61449)
		(width 0.1143)
		(layer "In4.Cu")
		(net "P5E_CPU1_G1_RX_DN<9>")
	)
	(arc
		(start 102.726236 -232.696004)
		(mid 102.956066 -233.144314)
		(end 102.726236 -233.592624)
		(width 0.1143)
		(layer "In4.Cu")
		(net "P5E_CPU1_G1_RX_DN<9>")
	)
	(arc
		(start 101.763068 -224.579942)
		(mid 101.941881 -224.782292)
		(end 102.0064 -225.044508)
		(width 0.1143)
		(layer "In4.Cu")
		(net "P5E_CPU1_G1_RX_DN<9>")
	)
	(arc
		(start 102.658926 -227.796598)
		(mid 102.944521 -228.261018)
		(end 102.70236 -228.749606)
		(width 0.1143)
		(layer "In4.Cu")
		(net "P5E_CPU1_G1_RX_DN<9>")
	)
	(arc
		(start 101.5365 -222.61449)
		(mid 101.578049 -222.785912)
		(end 101.693472 -222.91929)
		(width 0.1143)
		(layer "In4.Cu")
		(net "P5E_CPU1_G1_RX_DN<9>")
	)
	(arc
		(start 102.636828 -228.787706)
		(mid 102.632228 -228.791227)
		(end 102.627684 -228.794818)
		(width 0.1143)
		(layer "In4.Cu")
		(net "P5E_CPU1_G1_RX_DN<9>")
	)
	(arc
		(start 101.5365 -235.574332)
		(mid 101.471985 -235.836551)
		(end 101.293168 -236.038898)
		(width 0.1143)
		(layer "In4.Cu")
		(net "P5E_CPU1_G1_RX_DN<9>")
	)
	(arc
		(start 102.0064 -225.044508)
		(mid 102.047655 -225.215479)
		(end 102.162356 -225.3488)
		(width 0.1143)
		(layer "In4.Cu")
		(net "P5E_CPU1_G1_RX_DN<9>")
	)
	(arc
		(start 102.659942 -233.634026)
		(mid 102.527306 -233.769072)
		(end 102.47884 -233.952034)
		(width 0.1143)
		(layer "In4.Cu")
		(net "P5E_CPU1_G1_RX_DN<9>")
	)
	(arc
		(start 101.763068 -222.95993)
		(mid 102.006395 -223.424496)
		(end 101.763068 -223.889062)
		(width 0.1143)
		(layer "In4.Cu")
		(net "P5E_CPU1_G1_RX_DN<9>")
	)
	(arc
		(start 101.222302 -236.080046)
		(mid 101.125167 -236.182915)
		(end 101.073204 -236.314488)
		(width 0.1143)
		(layer "In4.Cu")
		(net "P5E_CPU1_G1_RX_DN<9>")
	)
	(arc
		(start 102.4763 -232.334308)
		(mid 102.520371 -232.503844)
		(end 102.632256 -232.6386)
		(width 0.1143)
		(layer "In4.Cu")
		(net "P5E_CPU1_G1_RX_DN<9>")
	)
	(arc
		(start 102.4763 -225.854514)
		(mid 102.517555 -226.025485)
		(end 102.632256 -226.158806)
		(width 0.1143)
		(layer "In4.Cu")
		(net "P5E_CPU1_G1_RX_DN<9>")
	)
	(arc
		(start 101.066346 -221.804484)
		(mid 101.107601 -221.975455)
		(end 101.222302 -222.108776)
		(width 0.1143)
		(layer "In4.Cu")
		(net "P5E_CPU1_G1_RX_DN<9>")
	)
	(arc
		(start 102.627684 -228.794818)
		(mid 102.52733 -228.93223)
		(end 102.4763 -229.094538)
		(width 0.1143)
		(layer "In4.Cu")
		(net "P5E_CPU1_G1_RX_DN<9>")
	)
	(arc
		(start 102.4763 -230.71455)
		(mid 102.411064 -230.978141)
		(end 102.230428 -231.180894)
		(width 0.1143)
		(layer "In4.Cu")
		(net "P5E_CPU1_G1_RX_DN<9>")
	)
	(arc
		(start 102.703122 -226.199954)
		(mid 102.946449 -226.66452)
		(end 102.703122 -227.129086)
		(width 0.1143)
		(layer "In4.Cu")
		(net "P5E_CPU1_G1_RX_DN<9>")
	)
	(arc
		(start 102.634288 -227.169218)
		(mid 102.476767 -227.489536)
		(end 102.658926 -227.796598)
		(width 0.1143)
		(layer "In4.Cu")
		(net "P5E_CPU1_G1_RX_DN<9>")
	)
	(arc
		(start 102.703122 -229.439724)
		(mid 102.881935 -229.642074)
		(end 102.946454 -229.90429)
		(width 0.1143)
		(layer "In4.Cu")
		(net "P5E_CPU1_G1_RX_DN<9>")
	)
	(arc
		(start 102.495858 -230.508556)
		(mid 102.481505 -230.525252)
		(end 102.4763 -230.546656)
		(width 0.1143)
		(layer "In4.Cu")
		(net "P5E_CPU1_G1_RX_DN<9>")
	)
	(arc
		(start 102.47884 -233.952034)
		(mid 102.405478 -234.230144)
		(end 102.204266 -234.43565)
		(width 0.1143)
		(layer "In4.Cu")
		(net "P5E_CPU1_G1_RX_DN<9>")
	)
	(arc
		(start 102.196392 -225.368358)
		(mid 102.401337 -225.57402)
		(end 102.4763 -225.854514)
		(width 0.1143)
		(layer "In4.Cu")
		(net "P5E_CPU1_G1_RX_DN<9>")
	)
	(arc
		(start 102.160578 -231.221534)
		(mid 102.047171 -231.354423)
		(end 102.0064 -231.524302)
		(width 0.1143)
		(layer "In4.Cu")
		(net "P5E_CPU1_G1_RX_DN<9>")
	)
	(arc
		(start 102.162356 -234.460034)
		(mid 102.04768 -234.593368)
		(end 102.0064 -234.764326)
		(width 0.1143)
		(layer "In4.Cu")
		(net "P5E_CPU1_G1_RX_DN<9>")
	)
	(arc
		(start 102.946454 -229.90429)
		(mid 102.881218 -230.167881)
		(end 102.700582 -230.370634)
		(width 0.1143)
		(layer "In4.Cu")
		(net "P5E_CPU1_G1_RX_DN<9>")
	)
	(arc
		(start 102.4763 -229.094538)
		(mid 102.517062 -229.264422)
		(end 102.630478 -229.397306)
		(width 0.1143)
		(layer "In4.Cu")
		(net "P5E_CPU1_G1_RX_DN<9>")
	)
	(arc
		(start 101.693472 -235.269532)
		(mid 101.578045 -235.402908)
		(end 101.5365 -235.574332)
		(width 0.1143)
		(layer "In4.Cu")
		(net "P5E_CPU1_G1_RX_DN<9>")
	)
	(arc
		(start 101.693472 -223.929702)
		(mid 101.536495 -224.234502)
		(end 101.693472 -224.539302)
		(width 0.1143)
		(layer "In4.Cu")
		(net "P5E_CPU1_G1_RX_DN<9>")
	)
	(segment
		(start 28.747212 -7.709408)
		(end 28.746958 -7.709662)
		(width 0.12954)
		(layer "F.Cu")
		(net "P5E_CPU1_G1_RX_DN<10>")
	)
	(segment
		(start 28.608274 -7.57047)
		(end 28.747212 -7.709408)
		(width 0.12954)
		(layer "F.Cu")
		(net "P5E_CPU1_G1_RX_DN<10>")
	)
	(segment
		(start 28.746958 -7.709662)
		(end 28.746958 -8.320024)
		(width 0.12954)
		(layer "F.Cu")
		(net "P5E_CPU1_G1_RX_DN<10>")
	)
	(segment
		(start 101.907848 -231.79024)
		(end 101.440996 -231.524302)
		(width 0.12954)
		(layer "F.Cu")
		(net "P5E_CPU1_G1_RX_DN<10>")
	)
	(segment
		(start 28.883864 -4.963414)
		(end 28.608274 -5.239004)
		(width 0.12954)
		(layer "F.Cu")
		(net "P5E_CPU1_G1_RX_DN<10>")
	)
	(segment
		(start 28.608274 -5.239004)
		(end 28.608274 -7.57047)
		(width 0.12954)
		(layer "F.Cu")
		(net "P5E_CPU1_G1_RX_DN<10>")
	)
	(segment
		(start 101.661976 -100.433632)
		(end 145.55597 -139.904978)
		(width 0.14224)
		(layer "In4.Cu")
		(net "P5E_CPU1_G1_RX_DN<10>")
	)
	(segment
		(start 100.136198 -215.105488)
		(end 100.136198 -221.259908)
		(width 0.14224)
		(layer "In4.Cu")
		(net "P5E_CPU1_G1_RX_DN<10>")
	)
	(segment
		(start 47.42688 -50.707036)
		(end 50.132996 -53.861462)
		(width 0.14224)
		(layer "In4.Cu")
		(net "P5E_CPU1_G1_RX_DN<10>")
	)
	(segment
		(start 28.883864 -4.963414)
		(end 28.593034 -5.254244)
		(width 0.14224)
		(layer "In4.Cu")
		(net "P5E_CPU1_G1_RX_DN<10>")
	)
	(segment
		(start 101.723952 -229.416864)
		(end 101.763068 -229.439724)
		(width 0.1143)
		(layer "In4.Cu")
		(net "P5E_CPU1_G1_RX_DN<10>")
	)
	(segment
		(start 106.876088 -203.754482)
		(end 100.136198 -215.105488)
		(width 0.14224)
		(layer "In4.Cu")
		(net "P5E_CPU1_G1_RX_DN<10>")
	)
	(segment
		(start 52.656232 -56.62041)
		(end 53.376068 -57.267856)
		(width 0.14224)
		(layer "In4.Cu")
		(net "P5E_CPU1_G1_RX_DN<10>")
	)
	(segment
		(start 50.132996 -53.861462)
		(end 52.656232 -56.62041)
		(width 0.14224)
		(layer "In4.Cu")
		(net "P5E_CPU1_G1_RX_DN<10>")
	)
	(segment
		(start 28.967176 -17.935448)
		(end 28.960318 -17.948402)
		(width 0.14224)
		(layer "In4.Cu")
		(net "P5E_CPU1_G1_RX_DN<10>")
	)
	(segment
		(start 101.25329 -225.36658)
		(end 101.254052 -225.367088)
		(width 0.1143)
		(layer "In4.Cu")
		(net "P5E_CPU1_G1_RX_DN<10>")
	)
	(segment
		(start 145.55597 -139.904978)
		(end 149.034754 -147.097242)
		(width 0.14224)
		(layer "In4.Cu")
		(net "P5E_CPU1_G1_RX_DN<10>")
	)
	(segment
		(start 101.723952 -228.771958)
		(end 101.693472 -228.789738)
		(width 0.1143)
		(layer "In4.Cu")
		(net "P5E_CPU1_G1_RX_DN<10>")
	)
	(segment
		(start 28.214066 -19.27352)
		(end 31.653988 -25.112218)
		(width 0.14224)
		(layer "In4.Cu")
		(net "P5E_CPU1_G1_RX_DN<10>")
	)
	(segment
		(start 56.477916 -59.882532)
		(end 57.767982 -60.96254)
		(width 0.14224)
		(layer "In4.Cu")
		(net "P5E_CPU1_G1_RX_DN<10>")
	)
	(segment
		(start 101.254052 -231.201976)
		(end 101.220524 -231.221534)
		(width 0.1143)
		(layer "In4.Cu")
		(net "P5E_CPU1_G1_RX_DN<10>")
	)
	(segment
		(start 100.136198 -221.259908)
		(end 100.136198 -221.288356)
		(width 0.1143)
		(layer "In4.Cu")
		(net "P5E_CPU1_G1_RX_DN<10>")
	)
	(segment
		(start 100.282248 -222.108776)
		(end 100.313998 -222.127064)
		(width 0.1143)
		(layer "In4.Cu")
		(net "P5E_CPU1_G1_RX_DN<10>")
	)
	(segment
		(start 101.249734 -225.364548)
		(end 101.250496 -225.365056)
		(width 0.1143)
		(layer "In4.Cu")
		(net "P5E_CPU1_G1_RX_DN<10>")
	)
	(segment
		(start 101.723952 -227.797106)
		(end 101.763068 -227.819966)
		(width 0.1143)
		(layer "In4.Cu")
		(net "P5E_CPU1_G1_RX_DN<10>")
	)
	(segment
		(start 101.250496 -225.365056)
		(end 101.25202 -225.365818)
		(width 0.1143)
		(layer "In4.Cu")
		(net "P5E_CPU1_G1_RX_DN<10>")
	)
	(segment
		(start 100.823014 -223.889062)
		(end 100.783898 -223.911922)
		(width 0.1143)
		(layer "In4.Cu")
		(net "P5E_CPU1_G1_RX_DN<10>")
	)
	(segment
		(start 100.090478 -221.334076)
		(end 100.090478 -221.513908)
		(width 0.1143)
		(layer "In4.Cu")
		(net "P5E_CPU1_G1_RX_DN<10>")
	)
	(segment
		(start 100.136198 -221.288356)
		(end 100.090478 -221.334076)
		(width 0.1143)
		(layer "In4.Cu")
		(net "P5E_CPU1_G1_RX_DN<10>")
	)
	(segment
		(start 101.285548 -225.385376)
		(end 101.28631 -225.385884)
		(width 0.1143)
		(layer "In4.Cu")
		(net "P5E_CPU1_G1_RX_DN<10>")
	)
	(segment
		(start 28.960064 -17.948402)
		(end 28.731718 -18.375122)
		(width 0.14224)
		(layer "In4.Cu")
		(net "P5E_CPU1_G1_RX_DN<10>")
	)
	(segment
		(start 57.767982 -60.96254)
		(end 101.661976 -100.433632)
		(width 0.14224)
		(layer "In4.Cu")
		(net "P5E_CPU1_G1_RX_DN<10>")
	)
	(segment
		(start 101.293168 -231.179116)
		(end 101.254052 -231.201976)
		(width 0.1143)
		(layer "In4.Cu")
		(net "P5E_CPU1_G1_RX_DN<10>")
	)
	(segment
		(start 101.763068 -228.749098)
		(end 101.723952 -228.771958)
		(width 0.1143)
		(layer "In4.Cu")
		(net "P5E_CPU1_G1_RX_DN<10>")
	)
	(segment
		(start 32.695896 -26.59761)
		(end 32.69615 -26.597864)
		(width 0.14224)
		(layer "In4.Cu")
		(net "P5E_CPU1_G1_RX_DN<10>")
	)
	(segment
		(start 29.037534 -16.322548)
		(end 29.037534 -17.76476)
		(width 0.14224)
		(layer "In4.Cu")
		(net "P5E_CPU1_G1_RX_DN<10>")
	)
	(segment
		(start 100.783898 -222.93707)
		(end 100.823014 -222.95993)
		(width 0.1143)
		(layer "In4.Cu")
		(net "P5E_CPU1_G1_RX_DN<10>")
	)
	(segment
		(start 28.993846 -17.871186)
		(end 28.993592 -17.871186)
		(width 0.14224)
		(layer "In4.Cu")
		(net "P5E_CPU1_G1_RX_DN<10>")
	)
	(segment
		(start 101.723952 -226.177094)
		(end 101.763068 -226.199954)
		(width 0.1143)
		(layer "In4.Cu")
		(net "P5E_CPU1_G1_RX_DN<10>")
	)
	(segment
		(start 100.783898 -223.911922)
		(end 100.753418 -223.929702)
		(width 0.1143)
		(layer "In4.Cu")
		(net "P5E_CPU1_G1_RX_DN<10>")
	)
	(segment
		(start 53.376068 -57.267856)
		(end 55.599584 -59.092846)
		(width 0.14224)
		(layer "In4.Cu")
		(net "P5E_CPU1_G1_RX_DN<10>")
	)
	(segment
		(start 149.839934 -159.966152)
		(end 149.839934 -163.234878)
		(width 0.14224)
		(layer "In4.Cu")
		(net "P5E_CPU1_G1_RX_DN<10>")
	)
	(segment
		(start 100.313998 -222.127064)
		(end 100.353114 -222.149924)
		(width 0.1143)
		(layer "In4.Cu")
		(net "P5E_CPU1_G1_RX_DN<10>")
	)
	(segment
		(start 101.693472 -226.159314)
		(end 101.723952 -226.177094)
		(width 0.1143)
		(layer "In4.Cu")
		(net "P5E_CPU1_G1_RX_DN<10>")
	)
	(segment
		(start 28.960318 -17.948402)
		(end 28.960064 -17.948402)
		(width 0.14224)
		(layer "In4.Cu")
		(net "P5E_CPU1_G1_RX_DN<10>")
	)
	(segment
		(start 144.94256 -172.559472)
		(end 106.876088 -203.754482)
		(width 0.14224)
		(layer "In4.Cu")
		(net "P5E_CPU1_G1_RX_DN<10>")
	)
	(segment
		(start 32.725868 -26.628598)
		(end 44.72051 -47.552356)
		(width 0.14224)
		(layer "In4.Cu")
		(net "P5E_CPU1_G1_RX_DN<10>")
	)
	(segment
		(start 55.599584 -59.092846)
		(end 56.477916 -59.882532)
		(width 0.14224)
		(layer "In4.Cu")
		(net "P5E_CPU1_G1_RX_DN<10>")
	)
	(segment
		(start 44.72051 -47.552356)
		(end 47.42688 -50.707036)
		(width 0.14224)
		(layer "In4.Cu")
		(net "P5E_CPU1_G1_RX_DN<10>")
	)
	(segment
		(start 101.073204 -231.454452)
		(end 101.143054 -231.524302)
		(width 0.1143)
		(layer "In4.Cu")
		(net "P5E_CPU1_G1_RX_DN<10>")
	)
	(segment
		(start 31.653988 -25.112218)
		(end 32.025336 -25.641554)
		(width 0.14224)
		(layer "In4.Cu")
		(net "P5E_CPU1_G1_RX_DN<10>")
	)
	(segment
		(start 32.710374 -26.601928)
		(end 32.725614 -26.628344)
		(width 0.14224)
		(layer "In4.Cu")
		(net "P5E_CPU1_G1_RX_DN<10>")
	)
	(segment
		(start 149.839934 -163.234878)
		(end 148.321268 -167.69588)
		(width 0.14224)
		(layer "In4.Cu")
		(net "P5E_CPU1_G1_RX_DN<10>")
	)
	(segment
		(start 32.025336 -25.641554)
		(end 32.695896 -26.59761)
		(width 0.14224)
		(layer "In4.Cu")
		(net "P5E_CPU1_G1_RX_DN<10>")
	)
	(segment
		(start 148.321268 -167.69588)
		(end 144.94256 -172.559472)
		(width 0.14224)
		(layer "In4.Cu")
		(net "P5E_CPU1_G1_RX_DN<10>")
	)
	(segment
		(start 28.593034 -11.808714)
		(end 29.037534 -16.322548)
		(width 0.14224)
		(layer "In4.Cu")
		(net "P5E_CPU1_G1_RX_DN<10>")
	)
	(segment
		(start 100.090478 -221.513908)
		(end 100.126292 -221.549722)
		(width 0.1143)
		(layer "In4.Cu")
		(net "P5E_CPU1_G1_RX_DN<10>")
	)
	(segment
		(start 29.037534 -17.76476)
		(end 28.993846 -17.871186)
		(width 0.14224)
		(layer "In4.Cu")
		(net "P5E_CPU1_G1_RX_DN<10>")
	)
	(segment
		(start 101.254052 -225.367088)
		(end 101.285548 -225.385376)
		(width 0.1143)
		(layer "In4.Cu")
		(net "P5E_CPU1_G1_RX_DN<10>")
	)
	(segment
		(start 100.753418 -222.91929)
		(end 100.783898 -222.93707)
		(width 0.1143)
		(layer "In4.Cu")
		(net "P5E_CPU1_G1_RX_DN<10>")
	)
	(segment
		(start 101.693472 -227.779326)
		(end 101.723952 -227.797106)
		(width 0.1143)
		(layer "In4.Cu")
		(net "P5E_CPU1_G1_RX_DN<10>")
	)
	(segment
		(start 100.753418 -224.539302)
		(end 100.783898 -224.557082)
		(width 0.1143)
		(layer "In4.Cu")
		(net "P5E_CPU1_G1_RX_DN<10>")
	)
	(segment
		(start 32.725614 -26.628344)
		(end 32.725868 -26.628598)
		(width 0.14224)
		(layer "In4.Cu")
		(net "P5E_CPU1_G1_RX_DN<10>")
	)
	(segment
		(start 28.593034 -5.254244)
		(end 28.593034 -11.808714)
		(width 0.14224)
		(layer "In4.Cu")
		(net "P5E_CPU1_G1_RX_DN<10>")
	)
	(segment
		(start 101.25202 -225.365818)
		(end 101.25329 -225.36658)
		(width 0.1143)
		(layer "In4.Cu")
		(net "P5E_CPU1_G1_RX_DN<10>")
	)
	(segment
		(start 101.763068 -227.129086)
		(end 101.723952 -227.151946)
		(width 0.1143)
		(layer "In4.Cu")
		(net "P5E_CPU1_G1_RX_DN<10>")
	)
	(segment
		(start 101.28631 -225.385884)
		(end 101.293168 -225.389948)
		(width 0.1143)
		(layer "In4.Cu")
		(net "P5E_CPU1_G1_RX_DN<10>")
	)
	(segment
		(start 100.783898 -224.557082)
		(end 100.823014 -224.579942)
		(width 0.1143)
		(layer "In4.Cu")
		(net "P5E_CPU1_G1_RX_DN<10>")
	)
	(segment
		(start 28.21686 -19.145504)
		(end 28.214066 -19.27352)
		(width 0.14224)
		(layer "In4.Cu")
		(net "P5E_CPU1_G1_RX_DN<10>")
	)
	(segment
		(start 32.69615 -26.597864)
		(end 32.710374 -26.601928)
		(width 0.14224)
		(layer "In4.Cu")
		(net "P5E_CPU1_G1_RX_DN<10>")
	)
	(segment
		(start 100.126292 -221.549722)
		(end 100.126292 -221.804484)
		(width 0.1143)
		(layer "In4.Cu")
		(net "P5E_CPU1_G1_RX_DN<10>")
	)
	(segment
		(start 101.760528 -230.370634)
		(end 101.693472 -230.40975)
		(width 0.1143)
		(layer "In4.Cu")
		(net "P5E_CPU1_G1_RX_DN<10>")
	)
	(segment
		(start 28.731718 -18.375122)
		(end 28.21686 -19.145504)
		(width 0.14224)
		(layer "In4.Cu")
		(net "P5E_CPU1_G1_RX_DN<10>")
	)
	(segment
		(start 101.143054 -231.524302)
		(end 101.440996 -231.524302)
		(width 0.1143)
		(layer "In4.Cu")
		(net "P5E_CPU1_G1_RX_DN<10>")
	)
	(segment
		(start 101.248718 -225.36404)
		(end 101.249734 -225.364548)
		(width 0.1143)
		(layer "In4.Cu")
		(net "P5E_CPU1_G1_RX_DN<10>")
	)
	(segment
		(start 101.222302 -225.3488)
		(end 101.248718 -225.36404)
		(width 0.1143)
		(layer "In4.Cu")
		(net "P5E_CPU1_G1_RX_DN<10>")
	)
	(segment
		(start 101.723952 -227.151946)
		(end 101.693472 -227.169726)
		(width 0.1143)
		(layer "In4.Cu")
		(net "P5E_CPU1_G1_RX_DN<10>")
	)
	(segment
		(start 28.993592 -17.871186)
		(end 28.967176 -17.935448)
		(width 0.14224)
		(layer "In4.Cu")
		(net "P5E_CPU1_G1_RX_DN<10>")
	)
	(segment
		(start 101.69144 -229.398068)
		(end 101.723952 -229.416864)
		(width 0.1143)
		(layer "In4.Cu")
		(net "P5E_CPU1_G1_RX_DN<10>")
	)
	(segment
		(start 149.034754 -147.097242)
		(end 149.839934 -159.966152)
		(width 0.14224)
		(layer "In4.Cu")
		(net "P5E_CPU1_G1_RX_DN<10>")
	)
	(arc
		(start 101.5365 -230.71455)
		(mid 101.471985 -230.976769)
		(end 101.293168 -231.179116)
		(width 0.1143)
		(layer "In4.Cu")
		(net "P5E_CPU1_G1_RX_DN<10>")
	)
	(arc
		(start 101.763068 -229.439724)
		(mid 101.941881 -229.642074)
		(end 102.0064 -229.90429)
		(width 0.1143)
		(layer "In4.Cu")
		(net "P5E_CPU1_G1_RX_DN<10>")
	)
	(arc
		(start 102.0064 -229.90429)
		(mid 101.941164 -230.167881)
		(end 101.760528 -230.370634)
		(width 0.1143)
		(layer "In4.Cu")
		(net "P5E_CPU1_G1_RX_DN<10>")
	)
	(arc
		(start 100.126292 -221.804484)
		(mid 100.167547 -221.975455)
		(end 100.282248 -222.108776)
		(width 0.1143)
		(layer "In4.Cu")
		(net "P5E_CPU1_G1_RX_DN<10>")
	)
	(arc
		(start 101.066346 -225.044508)
		(mid 101.107601 -225.215479)
		(end 101.222302 -225.3488)
		(width 0.1143)
		(layer "In4.Cu")
		(net "P5E_CPU1_G1_RX_DN<10>")
	)
	(arc
		(start 100.353114 -222.149924)
		(mid 100.531927 -222.352274)
		(end 100.596446 -222.61449)
		(width 0.1143)
		(layer "In4.Cu")
		(net "P5E_CPU1_G1_RX_DN<10>")
	)
	(arc
		(start 100.823014 -222.95993)
		(mid 101.066341 -223.424496)
		(end 100.823014 -223.889062)
		(width 0.1143)
		(layer "In4.Cu")
		(net "P5E_CPU1_G1_RX_DN<10>")
	)
	(arc
		(start 101.693472 -227.169726)
		(mid 101.536495 -227.474526)
		(end 101.693472 -227.779326)
		(width 0.1143)
		(layer "In4.Cu")
		(net "P5E_CPU1_G1_RX_DN<10>")
	)
	(arc
		(start 100.823014 -224.579942)
		(mid 101.001827 -224.782292)
		(end 101.066346 -225.044508)
		(width 0.1143)
		(layer "In4.Cu")
		(net "P5E_CPU1_G1_RX_DN<10>")
	)
	(arc
		(start 101.5365 -229.094538)
		(mid 101.577466 -229.264944)
		(end 101.69144 -229.398068)
		(width 0.1143)
		(layer "In4.Cu")
		(net "P5E_CPU1_G1_RX_DN<10>")
	)
	(arc
		(start 100.596446 -222.61449)
		(mid 100.637995 -222.785912)
		(end 100.753418 -222.91929)
		(width 0.1143)
		(layer "In4.Cu")
		(net "P5E_CPU1_G1_RX_DN<10>")
	)
	(arc
		(start 101.693472 -230.40975)
		(mid 101.578045 -230.543126)
		(end 101.5365 -230.71455)
		(width 0.1143)
		(layer "In4.Cu")
		(net "P5E_CPU1_G1_RX_DN<10>")
	)
	(arc
		(start 101.293168 -225.389948)
		(mid 101.471981 -225.592298)
		(end 101.5365 -225.854514)
		(width 0.1143)
		(layer "In4.Cu")
		(net "P5E_CPU1_G1_RX_DN<10>")
	)
	(arc
		(start 101.220524 -231.221534)
		(mid 101.124636 -231.323942)
		(end 101.073204 -231.454452)
		(width 0.1143)
		(layer "In4.Cu")
		(net "P5E_CPU1_G1_RX_DN<10>")
	)
	(arc
		(start 101.5365 -225.854514)
		(mid 101.578049 -226.025936)
		(end 101.693472 -226.159314)
		(width 0.1143)
		(layer "In4.Cu")
		(net "P5E_CPU1_G1_RX_DN<10>")
	)
	(arc
		(start 101.763068 -226.199954)
		(mid 102.006395 -226.66452)
		(end 101.763068 -227.129086)
		(width 0.1143)
		(layer "In4.Cu")
		(net "P5E_CPU1_G1_RX_DN<10>")
	)
	(arc
		(start 100.753418 -223.929702)
		(mid 100.596441 -224.234502)
		(end 100.753418 -224.539302)
		(width 0.1143)
		(layer "In4.Cu")
		(net "P5E_CPU1_G1_RX_DN<10>")
	)
	(arc
		(start 101.693472 -228.789738)
		(mid 101.578045 -228.923114)
		(end 101.5365 -229.094538)
		(width 0.1143)
		(layer "In4.Cu")
		(net "P5E_CPU1_G1_RX_DN<10>")
	)
	(arc
		(start 101.763068 -227.819966)
		(mid 102.006395 -228.284532)
		(end 101.763068 -228.749098)
		(width 0.1143)
		(layer "In4.Cu")
		(net "P5E_CPU1_G1_RX_DN<10>")
	)
	(segment
		(start 26.94686 -7.709154)
		(end 26.808176 -7.57047)
		(width 0.12954)
		(layer "F.Cu")
		(net "P5E_CPU1_G1_RX_DN<11>")
	)
	(segment
		(start 26.94686 -8.320024)
		(end 26.94686 -7.709154)
		(width 0.12954)
		(layer "F.Cu")
		(net "P5E_CPU1_G1_RX_DN<11>")
	)
	(segment
		(start 101.907848 -233.410252)
		(end 101.440996 -233.144314)
		(width 0.12954)
		(layer "F.Cu")
		(net "P5E_CPU1_G1_RX_DN<11>")
	)
	(segment
		(start 26.808176 -7.57047)
		(end 26.808176 -6.996176)
		(width 0.12954)
		(layer "F.Cu")
		(net "P5E_CPU1_G1_RX_DN<11>")
	)
	(segment
		(start 26.808176 -6.996176)
		(end 27.079194 -6.725158)
		(width 0.12954)
		(layer "F.Cu")
		(net "P5E_CPU1_G1_RX_DN<11>")
	)
	(segment
		(start 100.315522 -225.36785)
		(end 100.317808 -225.36912)
		(width 0.1143)
		(layer "In4.Cu")
		(net "P5E_CPU1_G1_RX_DN<11>")
	)
	(segment
		(start 100.784914 -230.394256)
		(end 100.77958 -230.397304)
		(width 0.1143)
		(layer "In4.Cu")
		(net "P5E_CPU1_G1_RX_DN<11>")
	)
	(segment
		(start 99.813364 -222.91929)
		(end 99.843844 -222.93707)
		(width 0.1143)
		(layer "In4.Cu")
		(net "P5E_CPU1_G1_RX_DN<11>")
	)
	(segment
		(start 100.778056 -232.653586)
		(end 100.783136 -232.65638)
		(width 0.1143)
		(layer "In4.Cu")
		(net "P5E_CPU1_G1_RX_DN<11>")
	)
	(segment
		(start 144.23009 -171.936664)
		(end 106.16819 -203.119736)
		(width 0.14224)
		(layer "In4.Cu")
		(net "P5E_CPU1_G1_RX_DN<11>")
	)
	(segment
		(start 100.783136 -227.796598)
		(end 100.783898 -227.797106)
		(width 0.1143)
		(layer "In4.Cu")
		(net "P5E_CPU1_G1_RX_DN<11>")
	)
	(segment
		(start 100.752148 -227.778818)
		(end 100.783136 -227.796598)
		(width 0.1143)
		(layer "In4.Cu")
		(net "P5E_CPU1_G1_RX_DN<11>")
	)
	(segment
		(start 26.782522 -19.210528)
		(end 31.002478 -26.692352)
		(width 0.14224)
		(layer "In4.Cu")
		(net "P5E_CPU1_G1_RX_DN<11>")
	)
	(segment
		(start 100.783898 -227.151946)
		(end 100.783136 -227.152454)
		(width 0.1143)
		(layer "In4.Cu")
		(net "P5E_CPU1_G1_RX_DN<11>")
	)
	(segment
		(start 100.786438 -228.770434)
		(end 100.784914 -228.77145)
		(width 0.1143)
		(layer "In4.Cu")
		(net "P5E_CPU1_G1_RX_DN<11>")
	)
	(segment
		(start 100.823014 -228.749098)
		(end 100.786438 -228.770434)
		(width 0.1143)
		(layer "In4.Cu")
		(net "P5E_CPU1_G1_RX_DN<11>")
	)
	(segment
		(start 100.815394 -232.675176)
		(end 100.816156 -232.675684)
		(width 0.1143)
		(layer "In4.Cu")
		(net "P5E_CPU1_G1_RX_DN<11>")
	)
	(segment
		(start 99.186238 -221.559374)
		(end 99.186238 -221.804484)
		(width 0.1143)
		(layer "In4.Cu")
		(net "P5E_CPU1_G1_RX_DN<11>")
	)
	(segment
		(start 100.783898 -226.177094)
		(end 100.815394 -226.195382)
		(width 0.1143)
		(layer "In4.Cu")
		(net "P5E_CPU1_G1_RX_DN<11>")
	)
	(segment
		(start 145.005044 -140.920724)
		(end 145.009108 -140.924788)
		(width 0.14224)
		(layer "In4.Cu")
		(net "P5E_CPU1_G1_RX_DN<11>")
	)
	(segment
		(start 100.783136 -226.176586)
		(end 100.783898 -226.177094)
		(width 0.1143)
		(layer "In4.Cu")
		(net "P5E_CPU1_G1_RX_DN<11>")
	)
	(segment
		(start 101.143054 -233.144314)
		(end 101.440996 -233.144314)
		(width 0.1143)
		(layer "In4.Cu")
		(net "P5E_CPU1_G1_RX_DN<11>")
	)
	(segment
		(start 99.843844 -222.93707)
		(end 99.88296 -222.95993)
		(width 0.1143)
		(layer "In4.Cu")
		(net "P5E_CPU1_G1_RX_DN<11>")
	)
	(segment
		(start 52.768246 -57.975246)
		(end 54.991508 -59.800236)
		(width 0.14224)
		(layer "In4.Cu")
		(net "P5E_CPU1_G1_RX_DN<11>")
	)
	(segment
		(start 99.813364 -224.539302)
		(end 99.843844 -224.557082)
		(width 0.1143)
		(layer "In4.Cu")
		(net "P5E_CPU1_G1_RX_DN<11>")
	)
	(segment
		(start 25.68956 -18.102834)
		(end 26.763472 -19.176746)
		(width 0.14224)
		(layer "In4.Cu")
		(net "P5E_CPU1_G1_RX_DN<11>")
	)
	(segment
		(start 51.30292 -56.657748)
		(end 52.768246 -57.975246)
		(width 0.14224)
		(layer "In4.Cu")
		(net "P5E_CPU1_G1_RX_DN<11>")
	)
	(segment
		(start 100.784914 -227.151438)
		(end 100.783898 -227.151946)
		(width 0.1143)
		(layer "In4.Cu")
		(net "P5E_CPU1_G1_RX_DN<11>")
	)
	(segment
		(start 26.788364 -7.015988)
		(end 26.788364 -11.141202)
		(width 0.14224)
		(layer "In4.Cu")
		(net "P5E_CPU1_G1_RX_DN<11>")
	)
	(segment
		(start 100.317808 -225.36912)
		(end 100.318824 -225.369628)
		(width 0.1143)
		(layer "In4.Cu")
		(net "P5E_CPU1_G1_RX_DN<11>")
	)
	(segment
		(start 100.31222 -225.366072)
		(end 100.314506 -225.367342)
		(width 0.1143)
		(layer "In4.Cu")
		(net "P5E_CPU1_G1_RX_DN<11>")
	)
	(segment
		(start 100.282248 -231.828594)
		(end 100.313998 -231.846882)
		(width 0.1143)
		(layer "In4.Cu")
		(net "P5E_CPU1_G1_RX_DN<11>")
	)
	(segment
		(start 106.16819 -203.119736)
		(end 99.186492 -214.878666)
		(width 0.14224)
		(layer "In4.Cu")
		(net "P5E_CPU1_G1_RX_DN<11>")
	)
	(segment
		(start 99.140772 -221.513908)
		(end 99.186238 -221.559374)
		(width 0.1143)
		(layer "In4.Cu")
		(net "P5E_CPU1_G1_RX_DN<11>")
	)
	(segment
		(start 99.186492 -214.878666)
		(end 99.186492 -221.259908)
		(width 0.14224)
		(layer "In4.Cu")
		(net "P5E_CPU1_G1_RX_DN<11>")
	)
	(segment
		(start 26.763472 -19.176746)
		(end 26.782522 -19.210274)
		(width 0.14224)
		(layer "In4.Cu")
		(net "P5E_CPU1_G1_RX_DN<11>")
	)
	(segment
		(start 100.816156 -227.815902)
		(end 100.823014 -227.819966)
		(width 0.1143)
		(layer "In4.Cu")
		(net "P5E_CPU1_G1_RX_DN<11>")
	)
	(segment
		(start 147.539456 -166.80688)
		(end 144.23009 -171.936664)
		(width 0.14224)
		(layer "In4.Cu")
		(net "P5E_CPU1_G1_RX_DN<11>")
	)
	(segment
		(start 100.783898 -228.771958)
		(end 100.783136 -228.772466)
		(width 0.1143)
		(layer "In4.Cu")
		(net "P5E_CPU1_G1_RX_DN<11>")
	)
	(segment
		(start 99.140772 -221.334076)
		(end 99.140772 -221.513908)
		(width 0.1143)
		(layer "In4.Cu")
		(net "P5E_CPU1_G1_RX_DN<11>")
	)
	(segment
		(start 148.9075 -159.995616)
		(end 148.9075 -162.788346)
		(width 0.14224)
		(layer "In4.Cu")
		(net "P5E_CPU1_G1_RX_DN<11>")
	)
	(segment
		(start 100.754434 -226.160076)
		(end 100.783136 -226.176586)
		(width 0.1143)
		(layer "In4.Cu")
		(net "P5E_CPU1_G1_RX_DN<11>")
	)
	(segment
		(start 101.06025 -233.06151)
		(end 101.143054 -233.144314)
		(width 0.1143)
		(layer "In4.Cu")
		(net "P5E_CPU1_G1_RX_DN<11>")
	)
	(segment
		(start 100.816156 -226.19589)
		(end 100.823014 -226.199954)
		(width 0.1143)
		(layer "In4.Cu")
		(net "P5E_CPU1_G1_RX_DN<11>")
	)
	(segment
		(start 99.186492 -221.259908)
		(end 99.186492 -221.288356)
		(width 0.1143)
		(layer "In4.Cu")
		(net "P5E_CPU1_G1_RX_DN<11>")
	)
	(segment
		(start 100.815394 -227.815394)
		(end 100.816156 -227.815902)
		(width 0.1143)
		(layer "In4.Cu")
		(net "P5E_CPU1_G1_RX_DN<11>")
	)
	(segment
		(start 144.85493 -140.61059)
		(end 145.005044 -140.920724)
		(width 0.14224)
		(layer "In4.Cu")
		(net "P5E_CPU1_G1_RX_DN<11>")
	)
	(segment
		(start 99.37496 -222.127572)
		(end 99.41306 -222.149924)
		(width 0.1143)
		(layer "In4.Cu")
		(net "P5E_CPU1_G1_RX_DN<11>")
	)
	(segment
		(start 99.843844 -224.557082)
		(end 99.88296 -224.579942)
		(width 0.1143)
		(layer "In4.Cu")
		(net "P5E_CPU1_G1_RX_DN<11>")
	)
	(segment
		(start 100.784914 -228.77145)
		(end 100.783898 -228.771958)
		(width 0.1143)
		(layer "In4.Cu")
		(net "P5E_CPU1_G1_RX_DN<11>")
	)
	(segment
		(start 100.786438 -227.150422)
		(end 100.784914 -227.151438)
		(width 0.1143)
		(layer "In4.Cu")
		(net "P5E_CPU1_G1_RX_DN<11>")
	)
	(segment
		(start 99.843844 -223.911922)
		(end 99.813364 -223.929702)
		(width 0.1143)
		(layer "In4.Cu")
		(net "P5E_CPU1_G1_RX_DN<11>")
	)
	(segment
		(start 100.816156 -232.675684)
		(end 100.823014 -232.679748)
		(width 0.1143)
		(layer "In4.Cu")
		(net "P5E_CPU1_G1_RX_DN<11>")
	)
	(segment
		(start 100.318824 -225.369628)
		(end 100.35032 -225.38817)
		(width 0.1143)
		(layer "In4.Cu")
		(net "P5E_CPU1_G1_RX_DN<11>")
	)
	(segment
		(start 26.788364 -11.141202)
		(end 25.550622 -17.363694)
		(width 0.14224)
		(layer "In4.Cu")
		(net "P5E_CPU1_G1_RX_DN<11>")
	)
	(segment
		(start 26.782522 -19.210274)
		(end 26.782522 -19.210528)
		(width 0.14224)
		(layer "In4.Cu")
		(net "P5E_CPU1_G1_RX_DN<11>")
	)
	(segment
		(start 54.991508 -59.800236)
		(end 144.85493 -140.61059)
		(width 0.14224)
		(layer "In4.Cu")
		(net "P5E_CPU1_G1_RX_DN<11>")
	)
	(segment
		(start 100.783136 -232.65638)
		(end 100.783898 -232.656888)
		(width 0.1143)
		(layer "In4.Cu")
		(net "P5E_CPU1_G1_RX_DN<11>")
	)
	(segment
		(start 99.88296 -223.889062)
		(end 99.843844 -223.911922)
		(width 0.1143)
		(layer "In4.Cu")
		(net "P5E_CPU1_G1_RX_DN<11>")
	)
	(segment
		(start 148.116036 -147.348702)
		(end 148.9075 -159.995616)
		(width 0.14224)
		(layer "In4.Cu")
		(net "P5E_CPU1_G1_RX_DN<11>")
	)
	(segment
		(start 100.783898 -227.797106)
		(end 100.815394 -227.815394)
		(width 0.1143)
		(layer "In4.Cu")
		(net "P5E_CPU1_G1_RX_DN<11>")
	)
	(segment
		(start 25.550622 -17.41043)
		(end 25.546558 -17.414494)
		(width 0.14224)
		(layer "In4.Cu")
		(net "P5E_CPU1_G1_RX_DN<11>")
	)
	(segment
		(start 145.009108 -140.924788)
		(end 148.116036 -147.348702)
		(width 0.14224)
		(layer "In4.Cu")
		(net "P5E_CPU1_G1_RX_DN<11>")
	)
	(segment
		(start 25.546558 -17.414494)
		(end 25.546558 -17.757648)
		(width 0.14224)
		(layer "In4.Cu")
		(net "P5E_CPU1_G1_RX_DN<11>")
	)
	(segment
		(start 99.373182 -222.126556)
		(end 99.373944 -222.127064)
		(width 0.1143)
		(layer "In4.Cu")
		(net "P5E_CPU1_G1_RX_DN<11>")
	)
	(segment
		(start 100.590604 -232.327196)
		(end 100.590604 -232.329736)
		(width 0.1143)
		(layer "In4.Cu")
		(net "P5E_CPU1_G1_RX_DN<11>")
	)
	(segment
		(start 100.75037 -229.397306)
		(end 100.823014 -229.439724)
		(width 0.1143)
		(layer "In4.Cu")
		(net "P5E_CPU1_G1_RX_DN<11>")
	)
	(segment
		(start 27.079194 -6.725158)
		(end 26.788364 -7.015988)
		(width 0.14224)
		(layer "In4.Cu")
		(net "P5E_CPU1_G1_RX_DN<11>")
	)
	(segment
		(start 42.843958 -46.797722)
		(end 47.073566 -51.727608)
		(width 0.14224)
		(layer "In4.Cu")
		(net "P5E_CPU1_G1_RX_DN<11>")
	)
	(segment
		(start 25.550622 -17.363694)
		(end 25.550622 -17.41043)
		(width 0.14224)
		(layer "In4.Cu")
		(net "P5E_CPU1_G1_RX_DN<11>")
	)
	(segment
		(start 99.373944 -222.127064)
		(end 99.37496 -222.127572)
		(width 0.1143)
		(layer "In4.Cu")
		(net "P5E_CPU1_G1_RX_DN<11>")
	)
	(segment
		(start 100.783136 -228.772466)
		(end 100.752148 -228.790246)
		(width 0.1143)
		(layer "In4.Cu")
		(net "P5E_CPU1_G1_RX_DN<11>")
	)
	(segment
		(start 100.783136 -227.152454)
		(end 100.752148 -227.170234)
		(width 0.1143)
		(layer "In4.Cu")
		(net "P5E_CPU1_G1_RX_DN<11>")
	)
	(segment
		(start 100.815394 -226.195382)
		(end 100.816156 -226.19589)
		(width 0.1143)
		(layer "In4.Cu")
		(net "P5E_CPU1_G1_RX_DN<11>")
	)
	(segment
		(start 100.783898 -232.656888)
		(end 100.815394 -232.675176)
		(width 0.1143)
		(layer "In4.Cu")
		(net "P5E_CPU1_G1_RX_DN<11>")
	)
	(segment
		(start 47.073566 -51.727608)
		(end 51.30292 -56.657748)
		(width 0.14224)
		(layer "In4.Cu")
		(net "P5E_CPU1_G1_RX_DN<11>")
	)
	(segment
		(start 99.365816 -222.122492)
		(end 99.373182 -222.126556)
		(width 0.1143)
		(layer "In4.Cu")
		(net "P5E_CPU1_G1_RX_DN<11>")
	)
	(segment
		(start 31.002478 -26.692352)
		(end 42.843958 -46.797722)
		(width 0.14224)
		(layer "In4.Cu")
		(net "P5E_CPU1_G1_RX_DN<11>")
	)
	(segment
		(start 100.823014 -227.129086)
		(end 100.786438 -227.150422)
		(width 0.1143)
		(layer "In4.Cu")
		(net "P5E_CPU1_G1_RX_DN<11>")
	)
	(segment
		(start 25.546558 -17.757648)
		(end 25.68956 -18.102834)
		(width 0.14224)
		(layer "In4.Cu")
		(net "P5E_CPU1_G1_RX_DN<11>")
	)
	(segment
		(start 99.342194 -222.108776)
		(end 99.365816 -222.122492)
		(width 0.1143)
		(layer "In4.Cu")
		(net "P5E_CPU1_G1_RX_DN<11>")
	)
	(segment
		(start 148.9075 -162.788346)
		(end 147.539456 -166.80688)
		(width 0.14224)
		(layer "In4.Cu")
		(net "P5E_CPU1_G1_RX_DN<11>")
	)
	(segment
		(start 99.186492 -221.288356)
		(end 99.140772 -221.334076)
		(width 0.1143)
		(layer "In4.Cu")
		(net "P5E_CPU1_G1_RX_DN<11>")
	)
	(segment
		(start 100.314506 -225.367342)
		(end 100.315522 -225.36785)
		(width 0.1143)
		(layer "In4.Cu")
		(net "P5E_CPU1_G1_RX_DN<11>")
	)
	(segment
		(start 100.35032 -231.180894)
		(end 100.28047 -231.221534)
		(width 0.1143)
		(layer "In4.Cu")
		(net "P5E_CPU1_G1_RX_DN<11>")
	)
	(arc
		(start 100.823014 -229.439724)
		(mid 101.001827 -229.642074)
		(end 101.066346 -229.90429)
		(width 0.1143)
		(layer "In4.Cu")
		(net "P5E_CPU1_G1_RX_DN<11>")
	)
	(arc
		(start 100.823014 -227.819966)
		(mid 101.066341 -228.284532)
		(end 100.823014 -228.749098)
		(width 0.1143)
		(layer "In4.Cu")
		(net "P5E_CPU1_G1_RX_DN<11>")
	)
	(arc
		(start 100.590604 -232.329736)
		(mid 100.640854 -232.516818)
		(end 100.778056 -232.653586)
		(width 0.1143)
		(layer "In4.Cu")
		(net "P5E_CPU1_G1_RX_DN<11>")
	)
	(arc
		(start 100.823014 -232.679748)
		(mid 100.975001 -232.836256)
		(end 101.05644 -233.03865)
		(width 0.1143)
		(layer "In4.Cu")
		(net "P5E_CPU1_G1_RX_DN<11>")
	)
	(arc
		(start 100.752148 -227.170234)
		(mid 100.600559 -227.474526)
		(end 100.752148 -227.778818)
		(width 0.1143)
		(layer "In4.Cu")
		(net "P5E_CPU1_G1_RX_DN<11>")
	)
	(arc
		(start 100.28047 -231.221534)
		(mid 100.167063 -231.354423)
		(end 100.126292 -231.524302)
		(width 0.1143)
		(layer "In4.Cu")
		(net "P5E_CPU1_G1_RX_DN<11>")
	)
	(arc
		(start 99.813364 -223.929702)
		(mid 99.656387 -224.234502)
		(end 99.813364 -224.539302)
		(width 0.1143)
		(layer "In4.Cu")
		(net "P5E_CPU1_G1_RX_DN<11>")
	)
	(arc
		(start 101.066346 -229.90429)
		(mid 100.990978 -230.186805)
		(end 100.784914 -230.394256)
		(width 0.1143)
		(layer "In4.Cu")
		(net "P5E_CPU1_G1_RX_DN<11>")
	)
	(arc
		(start 100.126292 -231.524302)
		(mid 100.167547 -231.695273)
		(end 100.282248 -231.828594)
		(width 0.1143)
		(layer "In4.Cu")
		(net "P5E_CPU1_G1_RX_DN<11>")
	)
	(arc
		(start 99.41306 -222.149924)
		(mid 99.591873 -222.352274)
		(end 99.656392 -222.61449)
		(width 0.1143)
		(layer "In4.Cu")
		(net "P5E_CPU1_G1_RX_DN<11>")
	)
	(arc
		(start 101.05644 -233.03865)
		(mid 101.058463 -233.05006)
		(end 101.06025 -233.06151)
		(width 0.1143)
		(layer "In4.Cu")
		(net "P5E_CPU1_G1_RX_DN<11>")
	)
	(arc
		(start 100.35032 -225.38817)
		(mid 100.530972 -225.590915)
		(end 100.596192 -225.854514)
		(width 0.1143)
		(layer "In4.Cu")
		(net "P5E_CPU1_G1_RX_DN<11>")
	)
	(arc
		(start 99.186238 -221.804484)
		(mid 99.227493 -221.975455)
		(end 99.342194 -222.108776)
		(width 0.1143)
		(layer "In4.Cu")
		(net "P5E_CPU1_G1_RX_DN<11>")
	)
	(arc
		(start 100.77958 -230.397304)
		(mid 100.645308 -230.531321)
		(end 100.596192 -230.71455)
		(width 0.1143)
		(layer "In4.Cu")
		(net "P5E_CPU1_G1_RX_DN<11>")
	)
	(arc
		(start 100.823014 -226.199954)
		(mid 101.066341 -226.66452)
		(end 100.823014 -227.129086)
		(width 0.1143)
		(layer "In4.Cu")
		(net "P5E_CPU1_G1_RX_DN<11>")
	)
	(arc
		(start 99.88296 -222.95993)
		(mid 100.126287 -223.424496)
		(end 99.88296 -223.889062)
		(width 0.1143)
		(layer "In4.Cu")
		(net "P5E_CPU1_G1_RX_DN<11>")
	)
	(arc
		(start 100.596192 -230.71455)
		(mid 100.530956 -230.978141)
		(end 100.35032 -231.180894)
		(width 0.1143)
		(layer "In4.Cu")
		(net "P5E_CPU1_G1_RX_DN<11>")
	)
	(arc
		(start 99.656392 -222.61449)
		(mid 99.697941 -222.785912)
		(end 99.813364 -222.91929)
		(width 0.1143)
		(layer "In4.Cu")
		(net "P5E_CPU1_G1_RX_DN<11>")
	)
	(arc
		(start 100.752148 -228.790246)
		(mid 100.640351 -228.925047)
		(end 100.596192 -229.094538)
		(width 0.1143)
		(layer "In4.Cu")
		(net "P5E_CPU1_G1_RX_DN<11>")
	)
	(arc
		(start 100.313998 -231.846882)
		(mid 100.516538 -232.050052)
		(end 100.590604 -232.327196)
		(width 0.1143)
		(layer "In4.Cu")
		(net "P5E_CPU1_G1_RX_DN<11>")
	)
	(arc
		(start 99.88296 -224.579942)
		(mid 100.061773 -224.782292)
		(end 100.126292 -225.044508)
		(width 0.1143)
		(layer "In4.Cu")
		(net "P5E_CPU1_G1_RX_DN<11>")
	)
	(arc
		(start 100.126292 -225.044508)
		(mid 100.176115 -225.230238)
		(end 100.31222 -225.366072)
		(width 0.1143)
		(layer "In4.Cu")
		(net "P5E_CPU1_G1_RX_DN<11>")
	)
	(arc
		(start 100.596192 -225.854514)
		(mid 100.641203 -226.02495)
		(end 100.754434 -226.160076)
		(width 0.1143)
		(layer "In4.Cu")
		(net "P5E_CPU1_G1_RX_DN<11>")
	)
	(arc
		(start 100.596192 -229.094538)
		(mid 100.636954 -229.264422)
		(end 100.75037 -229.397306)
		(width 0.1143)
		(layer "In4.Cu")
		(net "P5E_CPU1_G1_RX_DN<11>")
	)
	(segment
		(start 25.14727 -7.709408)
		(end 25.147016 -7.709662)
		(width 0.12954)
		(layer "F.Cu")
		(net "P5E_CPU1_G1_RX_DN<12>")
	)
	(segment
		(start 25.008332 -7.57047)
		(end 25.14727 -7.709408)
		(width 0.12954)
		(layer "F.Cu")
		(net "P5E_CPU1_G1_RX_DN<12>")
	)
	(segment
		(start 25.283922 -4.963414)
		(end 25.008332 -5.239004)
		(width 0.12954)
		(layer "F.Cu")
		(net "P5E_CPU1_G1_RX_DN<12>")
	)
	(segment
		(start 101.907848 -235.030264)
		(end 101.440996 -234.764326)
		(width 0.12954)
		(layer "F.Cu")
		(net "P5E_CPU1_G1_RX_DN<12>")
	)
	(segment
		(start 25.008332 -5.239004)
		(end 25.008332 -7.57047)
		(width 0.12954)
		(layer "F.Cu")
		(net "P5E_CPU1_G1_RX_DN<12>")
	)
	(segment
		(start 25.147016 -7.709662)
		(end 25.147016 -8.320024)
		(width 0.12954)
		(layer "F.Cu")
		(net "P5E_CPU1_G1_RX_DN<12>")
	)
	(segment
		(start 99.373182 -231.846374)
		(end 99.373944 -231.846882)
		(width 0.1143)
		(layer "In4.Cu")
		(net "P5E_CPU1_G1_RX_DN<12>")
	)
	(segment
		(start 24.993092 -11.247374)
		(end 23.924768 -16.617696)
		(width 0.14224)
		(layer "In4.Cu")
		(net "P5E_CPU1_G1_RX_DN<12>")
	)
	(segment
		(start 27.951176 -26.692606)
		(end 27.951684 -26.693622)
		(width 0.14224)
		(layer "In4.Cu")
		(net "P5E_CPU1_G1_RX_DN<12>")
	)
	(segment
		(start 99.371912 -225.365818)
		(end 99.373182 -225.36658)
		(width 0.1143)
		(layer "In4.Cu")
		(net "P5E_CPU1_G1_RX_DN<12>")
	)
	(segment
		(start 99.811332 -229.398068)
		(end 99.843844 -229.416864)
		(width 0.1143)
		(layer "In4.Cu")
		(net "P5E_CPU1_G1_RX_DN<12>")
	)
	(segment
		(start 99.41306 -231.179116)
		(end 99.373944 -231.201976)
		(width 0.1143)
		(layer "In4.Cu")
		(net "P5E_CPU1_G1_RX_DN<12>")
	)
	(segment
		(start 144.069308 -141.173454)
		(end 144.102328 -141.203172)
		(width 0.14224)
		(layer "In4.Cu")
		(net "P5E_CPU1_G1_RX_DN<12>")
	)
	(segment
		(start 100.786438 -234.278424)
		(end 100.823014 -234.29976)
		(width 0.1143)
		(layer "In4.Cu")
		(net "P5E_CPU1_G1_RX_DN<12>")
	)
	(segment
		(start 99.376484 -231.848406)
		(end 99.41306 -231.869742)
		(width 0.1143)
		(layer "In4.Cu")
		(net "P5E_CPU1_G1_RX_DN<12>")
	)
	(segment
		(start 105.281222 -202.62723)
		(end 98.241612 -214.546434)
		(width 0.14224)
		(layer "In4.Cu")
		(net "P5E_CPU1_G1_RX_DN<12>")
	)
	(segment
		(start 98.90379 -224.557082)
		(end 98.942906 -224.579942)
		(width 0.1143)
		(layer "In4.Cu")
		(net "P5E_CPU1_G1_RX_DN<12>")
	)
	(segment
		(start 98.241612 -221.288356)
		(end 98.195892 -221.334076)
		(width 0.1143)
		(layer "In4.Cu")
		(net "P5E_CPU1_G1_RX_DN<12>")
	)
	(segment
		(start 100.310442 -233.463084)
		(end 100.311966 -233.463846)
		(width 0.1143)
		(layer "In4.Cu")
		(net "P5E_CPU1_G1_RX_DN<12>")
	)
	(segment
		(start 22.73173 -19.0881)
		(end 22.73173 -19.191732)
		(width 0.14224)
		(layer "In4.Cu")
		(net "P5E_CPU1_G1_RX_DN<12>")
	)
	(segment
		(start 99.88296 -228.749098)
		(end 99.843844 -228.771958)
		(width 0.1143)
		(layer "In4.Cu")
		(net "P5E_CPU1_G1_RX_DN<12>")
	)
	(segment
		(start 147.127214 -147.457668)
		(end 147.91436 -160.026858)
		(width 0.14224)
		(layer "In4.Cu")
		(net "P5E_CPU1_G1_RX_DN<12>")
	)
	(segment
		(start 27.94635 -26.684986)
		(end 27.949906 -26.690574)
		(width 0.14224)
		(layer "In4.Cu")
		(net "P5E_CPU1_G1_RX_DN<12>")
	)
	(segment
		(start 22.786594 -18.909284)
		(end 22.74951 -18.998692)
		(width 0.14224)
		(layer "In4.Cu")
		(net "P5E_CPU1_G1_RX_DN<12>")
	)
	(segment
		(start 99.370388 -231.84485)
		(end 99.371912 -231.845612)
		(width 0.1143)
		(layer "In4.Cu")
		(net "P5E_CPU1_G1_RX_DN<12>")
	)
	(segment
		(start 100.783898 -234.2769)
		(end 100.784914 -234.277408)
		(width 0.1143)
		(layer "In4.Cu")
		(net "P5E_CPU1_G1_RX_DN<12>")
	)
	(segment
		(start 98.195892 -221.513908)
		(end 98.246184 -221.5642)
		(width 0.1143)
		(layer "In4.Cu")
		(net "P5E_CPU1_G1_RX_DN<12>")
	)
	(segment
		(start 22.73173 -19.191732)
		(end 22.868382 -19.791172)
		(width 0.14224)
		(layer "In4.Cu")
		(net "P5E_CPU1_G1_RX_DN<12>")
	)
	(segment
		(start 147.914614 -161.505392)
		(end 147.914614 -162.733736)
		(width 0.14224)
		(layer "In4.Cu")
		(net "P5E_CPU1_G1_RX_DN<12>")
	)
	(segment
		(start 98.241612 -214.546434)
		(end 98.241612 -221.259908)
		(width 0.14224)
		(layer "In4.Cu")
		(net "P5E_CPU1_G1_RX_DN<12>")
	)
	(segment
		(start 22.868382 -19.791172)
		(end 24.40686 -21.953728)
		(width 0.14224)
		(layer "In4.Cu")
		(net "P5E_CPU1_G1_RX_DN<12>")
	)
	(segment
		(start 27.826208 -26.510488)
		(end 27.845258 -26.529538)
		(width 0.14224)
		(layer "In4.Cu")
		(net "P5E_CPU1_G1_RX_DN<12>")
	)
	(segment
		(start 27.845258 -26.529538)
		(end 27.94635 -26.684986)
		(width 0.14224)
		(layer "In4.Cu")
		(net "P5E_CPU1_G1_RX_DN<12>")
	)
	(segment
		(start 98.241612 -221.259908)
		(end 98.241612 -221.288356)
		(width 0.1143)
		(layer "In4.Cu")
		(net "P5E_CPU1_G1_RX_DN<12>")
	)
	(segment
		(start 100.784914 -234.277408)
		(end 100.786438 -234.278424)
		(width 0.1143)
		(layer "In4.Cu")
		(net "P5E_CPU1_G1_RX_DN<12>")
	)
	(segment
		(start 100.314506 -233.46537)
		(end 100.31476 -233.46537)
		(width 0.1143)
		(layer "In4.Cu")
		(net "P5E_CPU1_G1_RX_DN<12>")
	)
	(segment
		(start 99.370388 -225.365056)
		(end 99.371912 -225.365818)
		(width 0.1143)
		(layer "In4.Cu")
		(net "P5E_CPU1_G1_RX_DN<12>")
	)
	(segment
		(start 40.670734 -46.277276)
		(end 48.175164 -54.667912)
		(width 0.14224)
		(layer "In4.Cu")
		(net "P5E_CPU1_G1_RX_DN<12>")
	)
	(segment
		(start 100.360988 -233.495342)
		(end 100.360734 -233.495596)
		(width 0.1143)
		(layer "In4.Cu")
		(net "P5E_CPU1_G1_RX_DN<12>")
	)
	(segment
		(start 100.608892 -233.963972)
		(end 100.608892 -233.973624)
		(width 0.1143)
		(layer "In4.Cu")
		(net "P5E_CPU1_G1_RX_DN<12>")
	)
	(segment
		(start 146.617436 -166.499794)
		(end 143.476472 -171.347384)
		(width 0.14224)
		(layer "In4.Cu")
		(net "P5E_CPU1_G1_RX_DN<12>")
	)
	(segment
		(start 99.813364 -232.639108)
		(end 99.843844 -232.656888)
		(width 0.1143)
		(layer "In4.Cu")
		(net "P5E_CPU1_G1_RX_DN<12>")
	)
	(segment
		(start 100.311966 -233.463846)
		(end 100.314506 -233.46537)
		(width 0.1143)
		(layer "In4.Cu")
		(net "P5E_CPU1_G1_RX_DN<12>")
	)
	(segment
		(start 27.949906 -26.690574)
		(end 27.950922 -26.692352)
		(width 0.14224)
		(layer "In4.Cu")
		(net "P5E_CPU1_G1_RX_DN<12>")
	)
	(segment
		(start 99.373182 -225.36658)
		(end 99.373944 -225.367088)
		(width 0.1143)
		(layer "In4.Cu")
		(net "P5E_CPU1_G1_RX_DN<12>")
	)
	(segment
		(start 147.914614 -162.733736)
		(end 147.878546 -162.769804)
		(width 0.14224)
		(layer "In4.Cu")
		(net "P5E_CPU1_G1_RX_DN<12>")
	)
	(segment
		(start 101.143054 -234.764326)
		(end 101.440996 -234.764326)
		(width 0.1143)
		(layer "In4.Cu")
		(net "P5E_CPU1_G1_RX_DN<12>")
	)
	(segment
		(start 23.143718 -18.375122)
		(end 22.786594 -18.909284)
		(width 0.14224)
		(layer "In4.Cu")
		(net "P5E_CPU1_G1_RX_DN<12>")
	)
	(segment
		(start 144.056354 -141.147038)
		(end 144.069308 -141.173454)
		(width 0.14224)
		(layer "In4.Cu")
		(net "P5E_CPU1_G1_RX_DN<12>")
	)
	(segment
		(start 99.373944 -231.201976)
		(end 99.340416 -231.221534)
		(width 0.1143)
		(layer "In4.Cu")
		(net "P5E_CPU1_G1_RX_DN<12>")
	)
	(segment
		(start 99.88042 -230.370634)
		(end 99.813364 -230.40975)
		(width 0.1143)
		(layer "In4.Cu")
		(net "P5E_CPU1_G1_RX_DN<12>")
	)
	(segment
		(start 99.813364 -227.779326)
		(end 99.843844 -227.797106)
		(width 0.1143)
		(layer "In4.Cu")
		(net "P5E_CPU1_G1_RX_DN<12>")
	)
	(segment
		(start 99.813364 -226.159314)
		(end 99.843844 -226.177094)
		(width 0.1143)
		(layer "In4.Cu")
		(net "P5E_CPU1_G1_RX_DN<12>")
	)
	(segment
		(start 48.175164 -54.667912)
		(end 50.67681 -57.46496)
		(width 0.14224)
		(layer "In4.Cu")
		(net "P5E_CPU1_G1_RX_DN<12>")
	)
	(segment
		(start 99.843844 -232.656888)
		(end 99.88296 -232.679748)
		(width 0.1143)
		(layer "In4.Cu")
		(net "P5E_CPU1_G1_RX_DN<12>")
	)
	(segment
		(start 99.36861 -225.36404)
		(end 99.369626 -225.364548)
		(width 0.1143)
		(layer "In4.Cu")
		(net "P5E_CPU1_G1_RX_DN<12>")
	)
	(segment
		(start 50.67681 -57.46496)
		(end 54.383432 -60.507626)
		(width 0.14224)
		(layer "In4.Cu")
		(net "P5E_CPU1_G1_RX_DN<12>")
	)
	(segment
		(start 27.951684 -26.693622)
		(end 40.670734 -46.277276)
		(width 0.14224)
		(layer "In4.Cu")
		(net "P5E_CPU1_G1_RX_DN<12>")
	)
	(segment
		(start 147.91436 -160.026858)
		(end 147.91436 -161.505138)
		(width 0.14224)
		(layer "In4.Cu")
		(net "P5E_CPU1_G1_RX_DN<12>")
	)
	(segment
		(start 99.373944 -231.846882)
		(end 99.37496 -231.84739)
		(width 0.1143)
		(layer "In4.Cu")
		(net "P5E_CPU1_G1_RX_DN<12>")
	)
	(segment
		(start 98.942906 -223.889062)
		(end 98.90379 -223.911922)
		(width 0.1143)
		(layer "In4.Cu")
		(net "P5E_CPU1_G1_RX_DN<12>")
	)
	(segment
		(start 23.924768 -16.617696)
		(end 23.378922 -17.935702)
		(width 0.14224)
		(layer "In4.Cu")
		(net "P5E_CPU1_G1_RX_DN<12>")
	)
	(segment
		(start 98.87331 -224.539302)
		(end 98.90379 -224.557082)
		(width 0.1143)
		(layer "In4.Cu")
		(net "P5E_CPU1_G1_RX_DN<12>")
	)
	(segment
		(start 99.37496 -225.367596)
		(end 99.376484 -225.368612)
		(width 0.1143)
		(layer "In4.Cu")
		(net "P5E_CPU1_G1_RX_DN<12>")
	)
	(segment
		(start 99.36861 -231.843834)
		(end 99.369626 -231.844342)
		(width 0.1143)
		(layer "In4.Cu")
		(net "P5E_CPU1_G1_RX_DN<12>")
	)
	(segment
		(start 147.91436 -161.505138)
		(end 147.914614 -161.505392)
		(width 0.14224)
		(layer "In4.Cu")
		(net "P5E_CPU1_G1_RX_DN<12>")
	)
	(segment
		(start 99.371912 -231.845612)
		(end 99.373182 -231.846374)
		(width 0.1143)
		(layer "In4.Cu")
		(net "P5E_CPU1_G1_RX_DN<12>")
	)
	(segment
		(start 54.383432 -60.507626)
		(end 144.056354 -141.147038)
		(width 0.14224)
		(layer "In4.Cu")
		(net "P5E_CPU1_G1_RX_DN<12>")
	)
	(segment
		(start 25.283922 -4.963414)
		(end 24.993092 -5.254244)
		(width 0.14224)
		(layer "In4.Cu")
		(net "P5E_CPU1_G1_RX_DN<12>")
	)
	(segment
		(start 24.40686 -21.953728)
		(end 26.867866 -25.112726)
		(width 0.14224)
		(layer "In4.Cu")
		(net "P5E_CPU1_G1_RX_DN<12>")
	)
	(segment
		(start 24.993092 -5.254244)
		(end 24.993092 -11.247374)
		(width 0.14224)
		(layer "In4.Cu")
		(net "P5E_CPU1_G1_RX_DN<12>")
	)
	(segment
		(start 147.878546 -162.769804)
		(end 146.617436 -166.499794)
		(width 0.14224)
		(layer "In4.Cu")
		(net "P5E_CPU1_G1_RX_DN<12>")
	)
	(segment
		(start 99.88296 -227.129086)
		(end 99.843844 -227.151946)
		(width 0.1143)
		(layer "In4.Cu")
		(net "P5E_CPU1_G1_RX_DN<12>")
	)
	(segment
		(start 27.950922 -26.692352)
		(end 27.951176 -26.692606)
		(width 0.14224)
		(layer "In4.Cu")
		(net "P5E_CPU1_G1_RX_DN<12>")
	)
	(segment
		(start 99.843844 -229.416864)
		(end 99.88296 -229.439724)
		(width 0.1143)
		(layer "In4.Cu")
		(net "P5E_CPU1_G1_RX_DN<12>")
	)
	(segment
		(start 98.90379 -223.911922)
		(end 98.87331 -223.929702)
		(width 0.1143)
		(layer "In4.Cu")
		(net "P5E_CPU1_G1_RX_DN<12>")
	)
	(segment
		(start 98.40214 -222.108776)
		(end 98.43389 -222.127064)
		(width 0.1143)
		(layer "In4.Cu")
		(net "P5E_CPU1_G1_RX_DN<12>")
	)
	(segment
		(start 98.43389 -222.127064)
		(end 98.473006 -222.149924)
		(width 0.1143)
		(layer "In4.Cu")
		(net "P5E_CPU1_G1_RX_DN<12>")
	)
	(segment
		(start 99.369626 -231.844342)
		(end 99.370388 -231.84485)
		(width 0.1143)
		(layer "In4.Cu")
		(net "P5E_CPU1_G1_RX_DN<12>")
	)
	(segment
		(start 99.37496 -231.84739)
		(end 99.376484 -231.848406)
		(width 0.1143)
		(layer "In4.Cu")
		(net "P5E_CPU1_G1_RX_DN<12>")
	)
	(segment
		(start 99.342194 -225.3488)
		(end 99.36861 -225.36404)
		(width 0.1143)
		(layer "In4.Cu")
		(net "P5E_CPU1_G1_RX_DN<12>")
	)
	(segment
		(start 101.06025 -234.681522)
		(end 101.143054 -234.764326)
		(width 0.1143)
		(layer "In4.Cu")
		(net "P5E_CPU1_G1_RX_DN<12>")
	)
	(segment
		(start 23.378922 -17.935702)
		(end 23.143718 -18.375122)
		(width 0.14224)
		(layer "In4.Cu")
		(net "P5E_CPU1_G1_RX_DN<12>")
	)
	(segment
		(start 99.843844 -227.797106)
		(end 99.88296 -227.819966)
		(width 0.1143)
		(layer "In4.Cu")
		(net "P5E_CPU1_G1_RX_DN<12>")
	)
	(segment
		(start 143.476472 -171.347384)
		(end 105.281222 -202.62723)
		(width 0.14224)
		(layer "In4.Cu")
		(net "P5E_CPU1_G1_RX_DN<12>")
	)
	(segment
		(start 99.843844 -226.177094)
		(end 99.88296 -226.199954)
		(width 0.1143)
		(layer "In4.Cu")
		(net "P5E_CPU1_G1_RX_DN<12>")
	)
	(segment
		(start 99.369626 -225.364548)
		(end 99.370388 -225.365056)
		(width 0.1143)
		(layer "In4.Cu")
		(net "P5E_CPU1_G1_RX_DN<12>")
	)
	(segment
		(start 22.74951 -18.998692)
		(end 22.73173 -19.0881)
		(width 0.14224)
		(layer "In4.Cu")
		(net "P5E_CPU1_G1_RX_DN<12>")
	)
	(segment
		(start 98.87331 -222.91929)
		(end 98.90379 -222.93707)
		(width 0.1143)
		(layer "In4.Cu")
		(net "P5E_CPU1_G1_RX_DN<12>")
	)
	(segment
		(start 98.195892 -221.334076)
		(end 98.195892 -221.513908)
		(width 0.1143)
		(layer "In4.Cu")
		(net "P5E_CPU1_G1_RX_DN<12>")
	)
	(segment
		(start 26.867866 -25.112726)
		(end 27.826208 -26.510488)
		(width 0.14224)
		(layer "In4.Cu")
		(net "P5E_CPU1_G1_RX_DN<12>")
	)
	(segment
		(start 99.373944 -225.367088)
		(end 99.37496 -225.367596)
		(width 0.1143)
		(layer "In4.Cu")
		(net "P5E_CPU1_G1_RX_DN<12>")
	)
	(segment
		(start 99.843844 -227.151946)
		(end 99.813364 -227.169726)
		(width 0.1143)
		(layer "In4.Cu")
		(net "P5E_CPU1_G1_RX_DN<12>")
	)
	(segment
		(start 98.90379 -222.93707)
		(end 98.942906 -222.95993)
		(width 0.1143)
		(layer "In4.Cu")
		(net "P5E_CPU1_G1_RX_DN<12>")
	)
	(segment
		(start 144.102328 -141.203172)
		(end 147.127214 -147.457668)
		(width 0.14224)
		(layer "In4.Cu")
		(net "P5E_CPU1_G1_RX_DN<12>")
	)
	(segment
		(start 100.78339 -234.2769)
		(end 100.783898 -234.2769)
		(width 0.1143)
		(layer "In4.Cu")
		(net "P5E_CPU1_G1_RX_DN<12>")
	)
	(segment
		(start 98.246184 -221.5642)
		(end 98.246184 -221.804484)
		(width 0.1143)
		(layer "In4.Cu")
		(net "P5E_CPU1_G1_RX_DN<12>")
	)
	(segment
		(start 99.376484 -225.368612)
		(end 99.41306 -225.389948)
		(width 0.1143)
		(layer "In4.Cu")
		(net "P5E_CPU1_G1_RX_DN<12>")
	)
	(segment
		(start 99.342194 -231.828594)
		(end 99.36861 -231.843834)
		(width 0.1143)
		(layer "In4.Cu")
		(net "P5E_CPU1_G1_RX_DN<12>")
	)
	(segment
		(start 99.843844 -228.771958)
		(end 99.813364 -228.789738)
		(width 0.1143)
		(layer "In4.Cu")
		(net "P5E_CPU1_G1_RX_DN<12>")
	)
	(arc
		(start 99.88296 -226.199954)
		(mid 100.126287 -226.66452)
		(end 99.88296 -227.129086)
		(width 0.1143)
		(layer "In4.Cu")
		(net "P5E_CPU1_G1_RX_DN<12>")
	)
	(arc
		(start 99.656392 -225.854514)
		(mid 99.697941 -226.025936)
		(end 99.813364 -226.159314)
		(width 0.1143)
		(layer "In4.Cu")
		(net "P5E_CPU1_G1_RX_DN<12>")
	)
	(arc
		(start 99.186238 -225.044508)
		(mid 99.227493 -225.215479)
		(end 99.342194 -225.3488)
		(width 0.1143)
		(layer "In4.Cu")
		(net "P5E_CPU1_G1_RX_DN<12>")
	)
	(arc
		(start 100.360734 -233.495596)
		(mid 100.54306 -233.69892)
		(end 100.608892 -233.963972)
		(width 0.1143)
		(layer "In4.Cu")
		(net "P5E_CPU1_G1_RX_DN<12>")
	)
	(arc
		(start 99.88296 -232.679748)
		(mid 100.061773 -232.882098)
		(end 100.126292 -233.144314)
		(width 0.1143)
		(layer "In4.Cu")
		(net "P5E_CPU1_G1_RX_DN<12>")
	)
	(arc
		(start 99.813364 -230.40975)
		(mid 99.697937 -230.543126)
		(end 99.656392 -230.71455)
		(width 0.1143)
		(layer "In4.Cu")
		(net "P5E_CPU1_G1_RX_DN<12>")
	)
	(arc
		(start 98.716338 -222.61449)
		(mid 98.757887 -222.785912)
		(end 98.87331 -222.91929)
		(width 0.1143)
		(layer "In4.Cu")
		(net "P5E_CPU1_G1_RX_DN<12>")
	)
	(arc
		(start 99.340416 -231.221534)
		(mid 99.227009 -231.354423)
		(end 99.186238 -231.524302)
		(width 0.1143)
		(layer "In4.Cu")
		(net "P5E_CPU1_G1_RX_DN<12>")
	)
	(arc
		(start 99.813364 -228.789738)
		(mid 99.697937 -228.923114)
		(end 99.656392 -229.094538)
		(width 0.1143)
		(layer "In4.Cu")
		(net "P5E_CPU1_G1_RX_DN<12>")
	)
	(arc
		(start 98.246184 -221.804484)
		(mid 98.287439 -221.975455)
		(end 98.40214 -222.108776)
		(width 0.1143)
		(layer "In4.Cu")
		(net "P5E_CPU1_G1_RX_DN<12>")
	)
	(arc
		(start 99.186238 -231.524302)
		(mid 99.227493 -231.695273)
		(end 99.342194 -231.828594)
		(width 0.1143)
		(layer "In4.Cu")
		(net "P5E_CPU1_G1_RX_DN<12>")
	)
	(arc
		(start 100.823014 -234.29976)
		(mid 100.975001 -234.456268)
		(end 101.05644 -234.658662)
		(width 0.1143)
		(layer "In4.Cu")
		(net "P5E_CPU1_G1_RX_DN<12>")
	)
	(arc
		(start 99.656392 -229.094538)
		(mid 99.697358 -229.264944)
		(end 99.811332 -229.398068)
		(width 0.1143)
		(layer "In4.Cu")
		(net "P5E_CPU1_G1_RX_DN<12>")
	)
	(arc
		(start 99.88296 -227.819966)
		(mid 100.126287 -228.284532)
		(end 99.88296 -228.749098)
		(width 0.1143)
		(layer "In4.Cu")
		(net "P5E_CPU1_G1_RX_DN<12>")
	)
	(arc
		(start 100.126292 -233.144314)
		(mid 100.175632 -233.328392)
		(end 100.310442 -233.463084)
		(width 0.1143)
		(layer "In4.Cu")
		(net "P5E_CPU1_G1_RX_DN<12>")
	)
	(arc
		(start 99.41306 -225.389948)
		(mid 99.591873 -225.592298)
		(end 99.656392 -225.854514)
		(width 0.1143)
		(layer "In4.Cu")
		(net "P5E_CPU1_G1_RX_DN<12>")
	)
	(arc
		(start 100.31476 -233.46537)
		(mid 100.338238 -233.479794)
		(end 100.360988 -233.495342)
		(width 0.1143)
		(layer "In4.Cu")
		(net "P5E_CPU1_G1_RX_DN<12>")
	)
	(arc
		(start 99.88296 -229.439724)
		(mid 100.061773 -229.642074)
		(end 100.126292 -229.90429)
		(width 0.1143)
		(layer "In4.Cu")
		(net "P5E_CPU1_G1_RX_DN<12>")
	)
	(arc
		(start 98.473006 -222.149924)
		(mid 98.651819 -222.352274)
		(end 98.716338 -222.61449)
		(width 0.1143)
		(layer "In4.Cu")
		(net "P5E_CPU1_G1_RX_DN<12>")
	)
	(arc
		(start 99.656392 -230.71455)
		(mid 99.591877 -230.976769)
		(end 99.41306 -231.179116)
		(width 0.1143)
		(layer "In4.Cu")
		(net "P5E_CPU1_G1_RX_DN<12>")
	)
	(arc
		(start 99.656392 -232.334308)
		(mid 99.697941 -232.50573)
		(end 99.813364 -232.639108)
		(width 0.1143)
		(layer "In4.Cu")
		(net "P5E_CPU1_G1_RX_DN<12>")
	)
	(arc
		(start 98.942906 -224.579942)
		(mid 99.121719 -224.782292)
		(end 99.186238 -225.044508)
		(width 0.1143)
		(layer "In4.Cu")
		(net "P5E_CPU1_G1_RX_DN<12>")
	)
	(arc
		(start 99.813364 -227.169726)
		(mid 99.656387 -227.474526)
		(end 99.813364 -227.779326)
		(width 0.1143)
		(layer "In4.Cu")
		(net "P5E_CPU1_G1_RX_DN<12>")
	)
	(arc
		(start 98.87331 -223.929702)
		(mid 98.716333 -224.234502)
		(end 98.87331 -224.539302)
		(width 0.1143)
		(layer "In4.Cu")
		(net "P5E_CPU1_G1_RX_DN<12>")
	)
	(arc
		(start 99.41306 -231.869742)
		(mid 99.591873 -232.072092)
		(end 99.656392 -232.334308)
		(width 0.1143)
		(layer "In4.Cu")
		(net "P5E_CPU1_G1_RX_DN<12>")
	)
	(arc
		(start 101.05644 -234.658662)
		(mid 101.058463 -234.670072)
		(end 101.06025 -234.681522)
		(width 0.1143)
		(layer "In4.Cu")
		(net "P5E_CPU1_G1_RX_DN<12>")
	)
	(arc
		(start 100.126292 -229.90429)
		(mid 100.061056 -230.167881)
		(end 99.88042 -230.370634)
		(width 0.1143)
		(layer "In4.Cu")
		(net "P5E_CPU1_G1_RX_DN<12>")
	)
	(arc
		(start 98.942906 -222.95993)
		(mid 99.186233 -223.424496)
		(end 98.942906 -223.889062)
		(width 0.1143)
		(layer "In4.Cu")
		(net "P5E_CPU1_G1_RX_DN<12>")
	)
	(arc
		(start 100.608892 -233.973624)
		(mid 100.655632 -234.148569)
		(end 100.78339 -234.2769)
		(width 0.1143)
		(layer "In4.Cu")
		(net "P5E_CPU1_G1_RX_DN<12>")
	)
	(segment
		(start 23.346918 -8.320024)
		(end 23.346918 -7.709154)
		(width 0.12954)
		(layer "F.Cu")
		(net "P5E_CPU1_G1_RX_DN<13>")
	)
	(segment
		(start 23.208234 -7.57047)
		(end 23.208234 -6.996176)
		(width 0.12954)
		(layer "F.Cu")
		(net "P5E_CPU1_G1_RX_DN<13>")
	)
	(segment
		(start 23.208234 -6.996176)
		(end 23.479252 -6.725158)
		(width 0.12954)
		(layer "F.Cu")
		(net "P5E_CPU1_G1_RX_DN<13>")
	)
	(segment
		(start 23.346918 -7.709154)
		(end 23.208234 -7.57047)
		(width 0.12954)
		(layer "F.Cu")
		(net "P5E_CPU1_G1_RX_DN<13>")
	)
	(segment
		(start 99.08794 -236.650276)
		(end 98.621088 -236.384338)
		(width 0.12954)
		(layer "F.Cu")
		(net "P5E_CPU1_G1_RX_DN<13>")
	)
	(segment
		(start 98.914458 -228.765862)
		(end 98.912426 -228.767132)
		(width 0.1143)
		(layer "In4.Cu")
		(net "P5E_CPU1_G1_RX_DN<13>")
	)
	(segment
		(start 123.420632 -186.565794)
		(end 104.50703 -202.055984)
		(width 0.14224)
		(layer "In4.Cu")
		(net "P5E_CPU1_G1_RX_DN<13>")
	)
	(segment
		(start 98.90887 -235.248958)
		(end 98.9076 -235.24972)
		(width 0.1143)
		(layer "In4.Cu")
		(net "P5E_CPU1_G1_RX_DN<13>")
	)
	(segment
		(start 97.96399 -222.93707)
		(end 97.995486 -222.955358)
		(width 0.1143)
		(layer "In4.Cu")
		(net "P5E_CPU1_G1_RX_DN<13>")
	)
	(segment
		(start 98.904044 -234.2769)
		(end 98.93554 -234.295188)
		(width 0.1143)
		(layer "In4.Cu")
		(net "P5E_CPU1_G1_RX_DN<13>")
	)
	(segment
		(start 98.323146 -236.384338)
		(end 98.621088 -236.384338)
		(width 0.1143)
		(layer "In4.Cu")
		(net "P5E_CPU1_G1_RX_DN<13>")
	)
	(segment
		(start 21.918676 -20.368768)
		(end 38.929818 -45.903642)
		(width 0.14224)
		(layer "In4.Cu")
		(net "P5E_CPU1_G1_RX_DN<13>")
	)
	(segment
		(start 98.904044 -233.63174)
		(end 98.903282 -233.632248)
		(width 0.1143)
		(layer "In4.Cu")
		(net "P5E_CPU1_G1_RX_DN<13>")
	)
	(segment
		(start 98.914458 -235.245656)
		(end 98.912426 -235.246926)
		(width 0.1143)
		(layer "In4.Cu")
		(net "P5E_CPU1_G1_RX_DN<13>")
	)
	(segment
		(start 98.906584 -235.250228)
		(end 98.90506 -235.251244)
		(width 0.1143)
		(layer "In4.Cu")
		(net "P5E_CPU1_G1_RX_DN<13>")
	)
	(segment
		(start 97.306384 -221.56928)
		(end 97.306384 -221.804484)
		(width 0.1143)
		(layer "In4.Cu")
		(net "P5E_CPU1_G1_RX_DN<13>")
	)
	(segment
		(start 98.43389 -236.061758)
		(end 98.40341 -236.079538)
		(width 0.1143)
		(layer "In4.Cu")
		(net "P5E_CPU1_G1_RX_DN<13>")
	)
	(segment
		(start 50.090324 -58.246518)
		(end 54.383432 -61.77661)
		(width 0.14224)
		(layer "In4.Cu")
		(net "P5E_CPU1_G1_RX_DN<13>")
	)
	(segment
		(start 98.909632 -235.24845)
		(end 98.90887 -235.248958)
		(width 0.1143)
		(layer "In4.Cu")
		(net "P5E_CPU1_G1_RX_DN<13>")
	)
	(segment
		(start 98.43389 -225.367088)
		(end 98.473006 -225.389948)
		(width 0.1143)
		(layer "In4.Cu")
		(net "P5E_CPU1_G1_RX_DN<13>")
	)
	(segment
		(start 98.909632 -227.148644)
		(end 98.90887 -227.149152)
		(width 0.1143)
		(layer "In4.Cu")
		(net "P5E_CPU1_G1_RX_DN<13>")
	)
	(segment
		(start 146.5834 -153.864564)
		(end 146.971258 -160.056576)
		(width 0.14224)
		(layer "In4.Cu")
		(net "P5E_CPU1_G1_RX_DN<13>")
	)
	(segment
		(start 98.895916 -232.652316)
		(end 98.903282 -232.65638)
		(width 0.1143)
		(layer "In4.Cu")
		(net "P5E_CPU1_G1_RX_DN<13>")
	)
	(segment
		(start 97.296732 -221.288356)
		(end 97.251012 -221.334076)
		(width 0.1143)
		(layer "In4.Cu")
		(net "P5E_CPU1_G1_RX_DN<13>")
	)
	(segment
		(start 97.974404 -223.905826)
		(end 97.972372 -223.907096)
		(width 0.1143)
		(layer "In4.Cu")
		(net "P5E_CPU1_G1_RX_DN<13>")
	)
	(segment
		(start 23.479252 -6.725158)
		(end 23.188422 -7.015988)
		(width 0.14224)
		(layer "In4.Cu")
		(net "P5E_CPU1_G1_RX_DN<13>")
	)
	(segment
		(start 98.90506 -227.151438)
		(end 98.904044 -227.151946)
		(width 0.1143)
		(layer "In4.Cu")
		(net "P5E_CPU1_G1_RX_DN<13>")
	)
	(segment
		(start 98.870516 -229.397306)
		(end 98.904044 -229.416864)
		(width 0.1143)
		(layer "In4.Cu")
		(net "P5E_CPU1_G1_RX_DN<13>")
	)
	(segment
		(start 98.90887 -233.628946)
		(end 98.9076 -233.629708)
		(width 0.1143)
		(layer "In4.Cu")
		(net "P5E_CPU1_G1_RX_DN<13>")
	)
	(segment
		(start 98.903282 -234.276392)
		(end 98.904044 -234.2769)
		(width 0.1143)
		(layer "In4.Cu")
		(net "P5E_CPU1_G1_RX_DN<13>")
	)
	(segment
		(start 98.900488 -227.153978)
		(end 98.872294 -227.170234)
		(width 0.1143)
		(layer "In4.Cu")
		(net "P5E_CPU1_G1_RX_DN<13>")
	)
	(segment
		(start 98.904044 -227.797106)
		(end 98.93554 -227.815394)
		(width 0.1143)
		(layer "In4.Cu")
		(net "P5E_CPU1_G1_RX_DN<13>")
	)
	(segment
		(start 98.94316 -235.228892)
		(end 98.916236 -235.24464)
		(width 0.1143)
		(layer "In4.Cu")
		(net "P5E_CPU1_G1_RX_DN<13>")
	)
	(segment
		(start 97.976182 -223.90481)
		(end 97.97542 -223.905318)
		(width 0.1143)
		(layer "In4.Cu")
		(net "P5E_CPU1_G1_RX_DN<13>")
	)
	(segment
		(start 54.383432 -61.77661)
		(end 143.34236 -141.773656)
		(width 0.14224)
		(layer "In4.Cu")
		(net "P5E_CPU1_G1_RX_DN<13>")
	)
	(segment
		(start 19.992086 -17.3863)
		(end 19.929856 -17.536414)
		(width 0.14224)
		(layer "In4.Cu")
		(net "P5E_CPU1_G1_RX_DN<13>")
	)
	(segment
		(start 98.916236 -227.144834)
		(end 98.915474 -227.145342)
		(width 0.1143)
		(layer "In4.Cu")
		(net "P5E_CPU1_G1_RX_DN<13>")
	)
	(segment
		(start 98.903282 -235.25226)
		(end 98.902012 -235.253022)
		(width 0.1143)
		(layer "In4.Cu")
		(net "P5E_CPU1_G1_RX_DN<13>")
	)
	(segment
		(start 98.872294 -234.258612)
		(end 98.895916 -234.272328)
		(width 0.1143)
		(layer "In4.Cu")
		(net "P5E_CPU1_G1_RX_DN<13>")
	)
	(segment
		(start 97.96399 -223.911922)
		(end 97.963228 -223.91243)
		(width 0.1143)
		(layer "In4.Cu")
		(net "P5E_CPU1_G1_RX_DN<13>")
	)
	(segment
		(start 22.816058 -13.160248)
		(end 19.992086 -17.3863)
		(width 0.14224)
		(layer "In4.Cu")
		(net "P5E_CPU1_G1_RX_DN<13>")
	)
	(segment
		(start 98.90506 -235.251244)
		(end 98.904044 -235.251752)
		(width 0.1143)
		(layer "In4.Cu")
		(net "P5E_CPU1_G1_RX_DN<13>")
	)
	(segment
		(start 97.96653 -223.910398)
		(end 97.965006 -223.911414)
		(width 0.1143)
		(layer "In4.Cu")
		(net "P5E_CPU1_G1_RX_DN<13>")
	)
	(segment
		(start 98.904044 -230.39197)
		(end 98.872294 -230.410258)
		(width 0.1143)
		(layer "In4.Cu")
		(net "P5E_CPU1_G1_RX_DN<13>")
	)
	(segment
		(start 98.902012 -233.63301)
		(end 98.900488 -233.633772)
		(width 0.1143)
		(layer "In4.Cu")
		(net "P5E_CPU1_G1_RX_DN<13>")
	)
	(segment
		(start 98.40341 -225.349308)
		(end 98.43389 -225.367088)
		(width 0.1143)
		(layer "In4.Cu")
		(net "P5E_CPU1_G1_RX_DN<13>")
	)
	(segment
		(start 19.929856 -17.737074)
		(end 20.6883 -18.871184)
		(width 0.14224)
		(layer "In4.Cu")
		(net "P5E_CPU1_G1_RX_DN<13>")
	)
	(segment
		(start 97.96399 -224.557082)
		(end 97.995486 -224.57537)
		(width 0.1143)
		(layer "In4.Cu")
		(net "P5E_CPU1_G1_RX_DN<13>")
	)
	(segment
		(start 97.251012 -221.513908)
		(end 97.306384 -221.56928)
		(width 0.1143)
		(layer "In4.Cu")
		(net "P5E_CPU1_G1_RX_DN<13>")
	)
	(segment
		(start 146.195542 -147.672806)
		(end 146.5834 -153.864564)
		(width 0.14224)
		(layer "In4.Cu")
		(net "P5E_CPU1_G1_RX_DN<13>")
	)
	(segment
		(start 98.94316 -227.129086)
		(end 98.916236 -227.144834)
		(width 0.1143)
		(layer "In4.Cu")
		(net "P5E_CPU1_G1_RX_DN<13>")
	)
	(segment
		(start 97.296732 -214.2617)
		(end 97.296732 -221.259908)
		(width 0.14224)
		(layer "In4.Cu")
		(net "P5E_CPU1_G1_RX_DN<13>")
	)
	(segment
		(start 98.912426 -233.626914)
		(end 98.909632 -233.628438)
		(width 0.1143)
		(layer "In4.Cu")
		(net "P5E_CPU1_G1_RX_DN<13>")
	)
	(segment
		(start 98.903282 -232.65638)
		(end 98.904044 -232.656888)
		(width 0.1143)
		(layer "In4.Cu")
		(net "P5E_CPU1_G1_RX_DN<13>")
	)
	(segment
		(start 97.996248 -222.955866)
		(end 98.003106 -222.95993)
		(width 0.1143)
		(layer "In4.Cu")
		(net "P5E_CPU1_G1_RX_DN<13>")
	)
	(segment
		(start 98.93554 -227.815394)
		(end 98.936302 -227.815902)
		(width 0.1143)
		(layer "In4.Cu")
		(net "P5E_CPU1_G1_RX_DN<13>")
	)
	(segment
		(start 98.904044 -226.177094)
		(end 98.93554 -226.195382)
		(width 0.1143)
		(layer "In4.Cu")
		(net "P5E_CPU1_G1_RX_DN<13>")
	)
	(segment
		(start 98.914458 -227.14585)
		(end 98.912426 -227.14712)
		(width 0.1143)
		(layer "In4.Cu")
		(net "P5E_CPU1_G1_RX_DN<13>")
	)
	(segment
		(start 98.93554 -232.675176)
		(end 98.936302 -232.675684)
		(width 0.1143)
		(layer "In4.Cu")
		(net "P5E_CPU1_G1_RX_DN<13>")
	)
	(segment
		(start 98.904044 -235.251752)
		(end 98.903282 -235.25226)
		(width 0.1143)
		(layer "In4.Cu")
		(net "P5E_CPU1_G1_RX_DN<13>")
	)
	(segment
		(start 98.43389 -231.846882)
		(end 98.473006 -231.869742)
		(width 0.1143)
		(layer "In4.Cu")
		(net "P5E_CPU1_G1_RX_DN<13>")
	)
	(segment
		(start 19.929856 -17.536414)
		(end 19.929856 -17.737074)
		(width 0.14224)
		(layer "In4.Cu")
		(net "P5E_CPU1_G1_RX_DN<13>")
	)
	(segment
		(start 23.188422 -11.93292)
		(end 22.816058 -13.160248)
		(width 0.14224)
		(layer "In4.Cu")
		(net "P5E_CPU1_G1_RX_DN<13>")
	)
	(segment
		(start 98.915474 -235.245148)
		(end 98.914458 -235.245656)
		(width 0.1143)
		(layer "In4.Cu")
		(net "P5E_CPU1_G1_RX_DN<13>")
	)
	(segment
		(start 98.936302 -234.295696)
		(end 98.94316 -234.29976)
		(width 0.1143)
		(layer "In4.Cu")
		(net "P5E_CPU1_G1_RX_DN<13>")
	)
	(segment
		(start 98.904044 -232.656888)
		(end 98.93554 -232.675176)
		(width 0.1143)
		(layer "In4.Cu")
		(net "P5E_CPU1_G1_RX_DN<13>")
	)
	(segment
		(start 97.97542 -223.905318)
		(end 97.974404 -223.905826)
		(width 0.1143)
		(layer "In4.Cu")
		(net "P5E_CPU1_G1_RX_DN<13>")
	)
	(segment
		(start 98.916236 -228.764846)
		(end 98.915474 -228.765354)
		(width 0.1143)
		(layer "In4.Cu")
		(net "P5E_CPU1_G1_RX_DN<13>")
	)
	(segment
		(start 98.915474 -227.145342)
		(end 98.914458 -227.14585)
		(width 0.1143)
		(layer "In4.Cu")
		(net "P5E_CPU1_G1_RX_DN<13>")
	)
	(segment
		(start 146.971258 -160.056576)
		(end 146.971258 -162.433508)
		(width 0.14224)
		(layer "In4.Cu")
		(net "P5E_CPU1_G1_RX_DN<13>")
	)
	(segment
		(start 145.74266 -166.04234)
		(end 145.70075 -166.104062)
		(width 0.14224)
		(layer "In4.Cu")
		(net "P5E_CPU1_G1_RX_DN<13>")
	)
	(segment
		(start 98.895916 -234.272328)
		(end 98.903282 -234.276392)
		(width 0.1143)
		(layer "In4.Cu")
		(net "P5E_CPU1_G1_RX_DN<13>")
	)
	(segment
		(start 98.872294 -227.778818)
		(end 98.895916 -227.792534)
		(width 0.1143)
		(layer "In4.Cu")
		(net "P5E_CPU1_G1_RX_DN<13>")
	)
	(segment
		(start 98.94316 -228.749098)
		(end 98.916236 -228.764846)
		(width 0.1143)
		(layer "In4.Cu")
		(net "P5E_CPU1_G1_RX_DN<13>")
	)
	(segment
		(start 104.50703 -202.055984)
		(end 97.296732 -214.2617)
		(width 0.14224)
		(layer "In4.Cu")
		(net "P5E_CPU1_G1_RX_DN<13>")
	)
	(segment
		(start 97.251012 -221.334076)
		(end 97.251012 -221.513908)
		(width 0.1143)
		(layer "In4.Cu")
		(net "P5E_CPU1_G1_RX_DN<13>")
	)
	(segment
		(start 98.904044 -228.771958)
		(end 98.903282 -228.772466)
		(width 0.1143)
		(layer "In4.Cu")
		(net "P5E_CPU1_G1_RX_DN<13>")
	)
	(segment
		(start 98.900488 -233.633772)
		(end 98.872294 -233.650028)
		(width 0.1143)
		(layer "In4.Cu")
		(net "P5E_CPU1_G1_RX_DN<13>")
	)
	(segment
		(start 98.906584 -227.150422)
		(end 98.90506 -227.151438)
		(width 0.1143)
		(layer "In4.Cu")
		(net "P5E_CPU1_G1_RX_DN<13>")
	)
	(segment
		(start 98.902012 -228.773228)
		(end 98.900488 -228.77399)
		(width 0.1143)
		(layer "In4.Cu")
		(net "P5E_CPU1_G1_RX_DN<13>")
	)
	(segment
		(start 98.936302 -226.19589)
		(end 98.94316 -226.199954)
		(width 0.1143)
		(layer "In4.Cu")
		(net "P5E_CPU1_G1_RX_DN<13>")
	)
	(segment
		(start 98.93554 -234.295188)
		(end 98.936302 -234.295696)
		(width 0.1143)
		(layer "In4.Cu")
		(net "P5E_CPU1_G1_RX_DN<13>")
	)
	(segment
		(start 98.909632 -233.628438)
		(end 98.90887 -233.628946)
		(width 0.1143)
		(layer "In4.Cu")
		(net "P5E_CPU1_G1_RX_DN<13>")
	)
	(segment
		(start 97.967546 -223.90989)
		(end 97.96653 -223.910398)
		(width 0.1143)
		(layer "In4.Cu")
		(net "P5E_CPU1_G1_RX_DN<13>")
	)
	(segment
		(start 98.936302 -227.815902)
		(end 98.94316 -227.819966)
		(width 0.1143)
		(layer "In4.Cu")
		(net "P5E_CPU1_G1_RX_DN<13>")
	)
	(segment
		(start 97.968816 -223.909128)
		(end 97.967546 -223.90989)
		(width 0.1143)
		(layer "In4.Cu")
		(net "P5E_CPU1_G1_RX_DN<13>")
	)
	(segment
		(start 146.971258 -162.433508)
		(end 145.74266 -166.04234)
		(width 0.14224)
		(layer "In4.Cu")
		(net "P5E_CPU1_G1_RX_DN<13>")
	)
	(segment
		(start 98.9076 -227.149914)
		(end 98.906584 -227.150422)
		(width 0.1143)
		(layer "In4.Cu")
		(net "P5E_CPU1_G1_RX_DN<13>")
	)
	(segment
		(start 98.912426 -235.246926)
		(end 98.909632 -235.24845)
		(width 0.1143)
		(layer "In4.Cu")
		(net "P5E_CPU1_G1_RX_DN<13>")
	)
	(segment
		(start 98.902012 -227.153216)
		(end 98.900488 -227.153978)
		(width 0.1143)
		(layer "In4.Cu")
		(net "P5E_CPU1_G1_RX_DN<13>")
	)
	(segment
		(start 98.253296 -236.314488)
		(end 98.323146 -236.384338)
		(width 0.1143)
		(layer "In4.Cu")
		(net "P5E_CPU1_G1_RX_DN<13>")
	)
	(segment
		(start 98.90506 -228.77145)
		(end 98.904044 -228.771958)
		(width 0.1143)
		(layer "In4.Cu")
		(net "P5E_CPU1_G1_RX_DN<13>")
	)
	(segment
		(start 98.916236 -233.624628)
		(end 98.915474 -233.625136)
		(width 0.1143)
		(layer "In4.Cu")
		(net "P5E_CPU1_G1_RX_DN<13>")
	)
	(segment
		(start 97.963228 -224.556574)
		(end 97.96399 -224.557082)
		(width 0.1143)
		(layer "In4.Cu")
		(net "P5E_CPU1_G1_RX_DN<13>")
	)
	(segment
		(start 98.895916 -226.172522)
		(end 98.903282 -226.176586)
		(width 0.1143)
		(layer "In4.Cu")
		(net "P5E_CPU1_G1_RX_DN<13>")
	)
	(segment
		(start 98.90887 -228.769164)
		(end 98.9076 -228.769926)
		(width 0.1143)
		(layer "In4.Cu")
		(net "P5E_CPU1_G1_RX_DN<13>")
	)
	(segment
		(start 97.995486 -224.57537)
		(end 97.996248 -224.575878)
		(width 0.1143)
		(layer "In4.Cu")
		(net "P5E_CPU1_G1_RX_DN<13>")
	)
	(segment
		(start 98.906584 -228.770434)
		(end 98.90506 -228.77145)
		(width 0.1143)
		(layer "In4.Cu")
		(net "P5E_CPU1_G1_RX_DN<13>")
	)
	(segment
		(start 97.996248 -224.575878)
		(end 98.003106 -224.579942)
		(width 0.1143)
		(layer "In4.Cu")
		(net "P5E_CPU1_G1_RX_DN<13>")
	)
	(segment
		(start 98.93554 -226.195382)
		(end 98.936302 -226.19589)
		(width 0.1143)
		(layer "In4.Cu")
		(net "P5E_CPU1_G1_RX_DN<13>")
	)
	(segment
		(start 98.872294 -226.158806)
		(end 98.895916 -226.172522)
		(width 0.1143)
		(layer "In4.Cu")
		(net "P5E_CPU1_G1_RX_DN<13>")
	)
	(segment
		(start 98.915474 -228.765354)
		(end 98.914458 -228.765862)
		(width 0.1143)
		(layer "In4.Cu")
		(net "P5E_CPU1_G1_RX_DN<13>")
	)
	(segment
		(start 97.965006 -223.911414)
		(end 97.96399 -223.911922)
		(width 0.1143)
		(layer "In4.Cu")
		(net "P5E_CPU1_G1_RX_DN<13>")
	)
	(segment
		(start 98.902012 -235.253022)
		(end 98.900488 -235.253784)
		(width 0.1143)
		(layer "In4.Cu")
		(net "P5E_CPU1_G1_RX_DN<13>")
	)
	(segment
		(start 98.473006 -236.038898)
		(end 98.43389 -236.061758)
		(width 0.1143)
		(layer "In4.Cu")
		(net "P5E_CPU1_G1_RX_DN<13>")
	)
	(segment
		(start 98.914458 -233.625644)
		(end 98.912426 -233.626914)
		(width 0.1143)
		(layer "In4.Cu")
		(net "P5E_CPU1_G1_RX_DN<13>")
	)
	(segment
		(start 97.296732 -221.259908)
		(end 97.296732 -221.288356)
		(width 0.1143)
		(layer "In4.Cu")
		(net "P5E_CPU1_G1_RX_DN<13>")
	)
	(segment
		(start 98.40341 -231.829102)
		(end 98.43389 -231.846882)
		(width 0.1143)
		(layer "In4.Cu")
		(net "P5E_CPU1_G1_RX_DN<13>")
	)
	(segment
		(start 23.188422 -7.015988)
		(end 23.188422 -11.93292)
		(width 0.14224)
		(layer "In4.Cu")
		(net "P5E_CPU1_G1_RX_DN<13>")
	)
	(segment
		(start 98.9076 -235.24972)
		(end 98.906584 -235.250228)
		(width 0.1143)
		(layer "In4.Cu")
		(net "P5E_CPU1_G1_RX_DN<13>")
	)
	(segment
		(start 97.93224 -224.538794)
		(end 97.963228 -224.556574)
		(width 0.1143)
		(layer "In4.Cu")
		(net "P5E_CPU1_G1_RX_DN<13>")
	)
	(segment
		(start 98.904044 -229.416864)
		(end 98.94316 -229.439724)
		(width 0.1143)
		(layer "In4.Cu")
		(net "P5E_CPU1_G1_RX_DN<13>")
	)
	(segment
		(start 97.995486 -222.955358)
		(end 97.996248 -222.955866)
		(width 0.1143)
		(layer "In4.Cu")
		(net "P5E_CPU1_G1_RX_DN<13>")
	)
	(segment
		(start 98.916236 -235.24464)
		(end 98.915474 -235.245148)
		(width 0.1143)
		(layer "In4.Cu")
		(net "P5E_CPU1_G1_RX_DN<13>")
	)
	(segment
		(start 98.912426 -227.14712)
		(end 98.909632 -227.148644)
		(width 0.1143)
		(layer "In4.Cu")
		(net "P5E_CPU1_G1_RX_DN<13>")
	)
	(segment
		(start 98.94316 -233.60888)
		(end 98.916236 -233.624628)
		(width 0.1143)
		(layer "In4.Cu")
		(net "P5E_CPU1_G1_RX_DN<13>")
	)
	(segment
		(start 98.90887 -227.149152)
		(end 98.9076 -227.149914)
		(width 0.1143)
		(layer "In4.Cu")
		(net "P5E_CPU1_G1_RX_DN<13>")
	)
	(segment
		(start 98.903282 -227.152454)
		(end 98.902012 -227.153216)
		(width 0.1143)
		(layer "In4.Cu")
		(net "P5E_CPU1_G1_RX_DN<13>")
	)
	(segment
		(start 97.963228 -222.936562)
		(end 97.96399 -222.93707)
		(width 0.1143)
		(layer "In4.Cu")
		(net "P5E_CPU1_G1_RX_DN<13>")
	)
	(segment
		(start 20.6883 -18.871184)
		(end 21.918676 -20.368768)
		(width 0.14224)
		(layer "In4.Cu")
		(net "P5E_CPU1_G1_RX_DN<13>")
	)
	(segment
		(start 98.912426 -228.767132)
		(end 98.909632 -228.768656)
		(width 0.1143)
		(layer "In4.Cu")
		(net "P5E_CPU1_G1_RX_DN<13>")
	)
	(segment
		(start 98.903282 -233.632248)
		(end 98.902012 -233.63301)
		(width 0.1143)
		(layer "In4.Cu")
		(net "P5E_CPU1_G1_RX_DN<13>")
	)
	(segment
		(start 145.70075 -166.104062)
		(end 142.334234 -171.07535)
		(width 0.14224)
		(layer "In4.Cu")
		(net "P5E_CPU1_G1_RX_DN<13>")
	)
	(segment
		(start 98.903282 -228.772466)
		(end 98.902012 -228.773228)
		(width 0.1143)
		(layer "In4.Cu")
		(net "P5E_CPU1_G1_RX_DN<13>")
	)
	(segment
		(start 98.903282 -226.176586)
		(end 98.904044 -226.177094)
		(width 0.1143)
		(layer "In4.Cu")
		(net "P5E_CPU1_G1_RX_DN<13>")
	)
	(segment
		(start 98.473006 -231.179116)
		(end 98.43389 -231.201976)
		(width 0.1143)
		(layer "In4.Cu")
		(net "P5E_CPU1_G1_RX_DN<13>")
	)
	(segment
		(start 142.334234 -171.07535)
		(end 123.420632 -186.565794)
		(width 0.14224)
		(layer "In4.Cu")
		(net "P5E_CPU1_G1_RX_DN<13>")
	)
	(segment
		(start 97.963228 -223.91243)
		(end 97.93224 -223.93021)
		(width 0.1143)
		(layer "In4.Cu")
		(net "P5E_CPU1_G1_RX_DN<13>")
	)
	(segment
		(start 98.936302 -232.675684)
		(end 98.94316 -232.679748)
		(width 0.1143)
		(layer "In4.Cu")
		(net "P5E_CPU1_G1_RX_DN<13>")
	)
	(segment
		(start 98.9076 -228.769926)
		(end 98.906584 -228.770434)
		(width 0.1143)
		(layer "In4.Cu")
		(net "P5E_CPU1_G1_RX_DN<13>")
	)
	(segment
		(start 97.969578 -223.90862)
		(end 97.968816 -223.909128)
		(width 0.1143)
		(layer "In4.Cu")
		(net "P5E_CPU1_G1_RX_DN<13>")
	)
	(segment
		(start 98.906584 -233.630216)
		(end 98.90506 -233.631232)
		(width 0.1143)
		(layer "In4.Cu")
		(net "P5E_CPU1_G1_RX_DN<13>")
	)
	(segment
		(start 97.972372 -223.907096)
		(end 97.969578 -223.90862)
		(width 0.1143)
		(layer "In4.Cu")
		(net "P5E_CPU1_G1_RX_DN<13>")
	)
	(segment
		(start 98.9076 -233.629708)
		(end 98.906584 -233.630216)
		(width 0.1143)
		(layer "In4.Cu")
		(net "P5E_CPU1_G1_RX_DN<13>")
	)
	(segment
		(start 98.903282 -227.796598)
		(end 98.904044 -227.797106)
		(width 0.1143)
		(layer "In4.Cu")
		(net "P5E_CPU1_G1_RX_DN<13>")
	)
	(segment
		(start 97.46234 -222.108776)
		(end 97.496376 -222.128334)
		(width 0.1143)
		(layer "In4.Cu")
		(net "P5E_CPU1_G1_RX_DN<13>")
	)
	(segment
		(start 98.43389 -231.201976)
		(end 98.401378 -231.220772)
		(width 0.1143)
		(layer "In4.Cu")
		(net "P5E_CPU1_G1_RX_DN<13>")
	)
	(segment
		(start 98.900488 -235.253784)
		(end 98.872294 -235.27004)
		(width 0.1143)
		(layer "In4.Cu")
		(net "P5E_CPU1_G1_RX_DN<13>")
	)
	(segment
		(start 98.003106 -223.889062)
		(end 97.976182 -223.90481)
		(width 0.1143)
		(layer "In4.Cu")
		(net "P5E_CPU1_G1_RX_DN<13>")
	)
	(segment
		(start 98.909632 -228.768656)
		(end 98.90887 -228.769164)
		(width 0.1143)
		(layer "In4.Cu")
		(net "P5E_CPU1_G1_RX_DN<13>")
	)
	(segment
		(start 98.94062 -230.370634)
		(end 98.904044 -230.39197)
		(width 0.1143)
		(layer "In4.Cu")
		(net "P5E_CPU1_G1_RX_DN<13>")
	)
	(segment
		(start 98.895916 -227.792534)
		(end 98.903282 -227.796598)
		(width 0.1143)
		(layer "In4.Cu")
		(net "P5E_CPU1_G1_RX_DN<13>")
	)
	(segment
		(start 143.34236 -141.773656)
		(end 146.195542 -147.672806)
		(width 0.14224)
		(layer "In4.Cu")
		(net "P5E_CPU1_G1_RX_DN<13>")
	)
	(segment
		(start 38.929818 -45.903642)
		(end 50.090324 -58.246518)
		(width 0.14224)
		(layer "In4.Cu")
		(net "P5E_CPU1_G1_RX_DN<13>")
	)
	(segment
		(start 98.915474 -233.625136)
		(end 98.914458 -233.625644)
		(width 0.1143)
		(layer "In4.Cu")
		(net "P5E_CPU1_G1_RX_DN<13>")
	)
	(segment
		(start 98.900488 -228.77399)
		(end 98.872294 -228.790246)
		(width 0.1143)
		(layer "In4.Cu")
		(net "P5E_CPU1_G1_RX_DN<13>")
	)
	(segment
		(start 98.872294 -232.6386)
		(end 98.895916 -232.652316)
		(width 0.1143)
		(layer "In4.Cu")
		(net "P5E_CPU1_G1_RX_DN<13>")
	)
	(segment
		(start 98.90506 -233.631232)
		(end 98.904044 -233.63174)
		(width 0.1143)
		(layer "In4.Cu")
		(net "P5E_CPU1_G1_RX_DN<13>")
	)
	(segment
		(start 98.904044 -227.151946)
		(end 98.903282 -227.152454)
		(width 0.1143)
		(layer "In4.Cu")
		(net "P5E_CPU1_G1_RX_DN<13>")
	)
	(segment
		(start 97.96272 -222.936308)
		(end 97.963228 -222.936562)
		(width 0.1143)
		(layer "In4.Cu")
		(net "P5E_CPU1_G1_RX_DN<13>")
	)
	(arc
		(start 97.93224 -223.93021)
		(mid 97.781855 -224.234502)
		(end 97.93224 -224.538794)
		(width 0.1143)
		(layer "In4.Cu")
		(net "P5E_CPU1_G1_RX_DN<13>")
	)
	(arc
		(start 98.246438 -231.524302)
		(mid 98.287987 -231.695724)
		(end 98.40341 -231.829102)
		(width 0.1143)
		(layer "In4.Cu")
		(net "P5E_CPU1_G1_RX_DN<13>")
	)
	(arc
		(start 97.496376 -222.128334)
		(mid 97.701321 -222.333996)
		(end 97.776284 -222.61449)
		(width 0.1143)
		(layer "In4.Cu")
		(net "P5E_CPU1_G1_RX_DN<13>")
	)
	(arc
		(start 98.716338 -235.574332)
		(mid 98.651823 -235.836551)
		(end 98.473006 -236.038898)
		(width 0.1143)
		(layer "In4.Cu")
		(net "P5E_CPU1_G1_RX_DN<13>")
	)
	(arc
		(start 98.872294 -227.170234)
		(mid 98.716366 -227.474526)
		(end 98.872294 -227.778818)
		(width 0.1143)
		(layer "In4.Cu")
		(net "P5E_CPU1_G1_RX_DN<13>")
	)
	(arc
		(start 98.94316 -232.679748)
		(mid 99.186487 -233.144314)
		(end 98.94316 -233.60888)
		(width 0.1143)
		(layer "In4.Cu")
		(net "P5E_CPU1_G1_RX_DN<13>")
	)
	(arc
		(start 98.716338 -232.334308)
		(mid 98.757593 -232.505279)
		(end 98.872294 -232.6386)
		(width 0.1143)
		(layer "In4.Cu")
		(net "P5E_CPU1_G1_RX_DN<13>")
	)
	(arc
		(start 98.246438 -225.044508)
		(mid 98.287987 -225.21593)
		(end 98.40341 -225.349308)
		(width 0.1143)
		(layer "In4.Cu")
		(net "P5E_CPU1_G1_RX_DN<13>")
	)
	(arc
		(start 98.716338 -230.71455)
		(mid 98.651823 -230.976769)
		(end 98.473006 -231.179116)
		(width 0.1143)
		(layer "In4.Cu")
		(net "P5E_CPU1_G1_RX_DN<13>")
	)
	(arc
		(start 98.473006 -225.389948)
		(mid 98.651819 -225.592298)
		(end 98.716338 -225.854514)
		(width 0.1143)
		(layer "In4.Cu")
		(net "P5E_CPU1_G1_RX_DN<13>")
	)
	(arc
		(start 98.003106 -222.95993)
		(mid 98.246433 -223.424496)
		(end 98.003106 -223.889062)
		(width 0.1143)
		(layer "In4.Cu")
		(net "P5E_CPU1_G1_RX_DN<13>")
	)
	(arc
		(start 98.401378 -231.220772)
		(mid 98.287449 -231.353919)
		(end 98.246438 -231.524302)
		(width 0.1143)
		(layer "In4.Cu")
		(net "P5E_CPU1_G1_RX_DN<13>")
	)
	(arc
		(start 98.40341 -236.079538)
		(mid 98.305645 -236.182514)
		(end 98.253296 -236.314488)
		(width 0.1143)
		(layer "In4.Cu")
		(net "P5E_CPU1_G1_RX_DN<13>")
	)
	(arc
		(start 98.716338 -229.094538)
		(mid 98.7571 -229.264422)
		(end 98.870516 -229.397306)
		(width 0.1143)
		(layer "In4.Cu")
		(net "P5E_CPU1_G1_RX_DN<13>")
	)
	(arc
		(start 97.776284 -222.61449)
		(mid 97.826249 -222.800466)
		(end 97.96272 -222.936308)
		(width 0.1143)
		(layer "In4.Cu")
		(net "P5E_CPU1_G1_RX_DN<13>")
	)
	(arc
		(start 98.003106 -224.579942)
		(mid 98.181919 -224.782292)
		(end 98.246438 -225.044508)
		(width 0.1143)
		(layer "In4.Cu")
		(net "P5E_CPU1_G1_RX_DN<13>")
	)
	(arc
		(start 98.716338 -225.854514)
		(mid 98.757593 -226.025485)
		(end 98.872294 -226.158806)
		(width 0.1143)
		(layer "In4.Cu")
		(net "P5E_CPU1_G1_RX_DN<13>")
	)
	(arc
		(start 99.186492 -229.90429)
		(mid 99.121256 -230.167881)
		(end 98.94062 -230.370634)
		(width 0.1143)
		(layer "In4.Cu")
		(net "P5E_CPU1_G1_RX_DN<13>")
	)
	(arc
		(start 98.94316 -227.819966)
		(mid 99.186487 -228.284532)
		(end 98.94316 -228.749098)
		(width 0.1143)
		(layer "In4.Cu")
		(net "P5E_CPU1_G1_RX_DN<13>")
	)
	(arc
		(start 98.872294 -228.790246)
		(mid 98.757618 -228.92358)
		(end 98.716338 -229.094538)
		(width 0.1143)
		(layer "In4.Cu")
		(net "P5E_CPU1_G1_RX_DN<13>")
	)
	(arc
		(start 98.94316 -234.29976)
		(mid 99.186487 -234.764326)
		(end 98.94316 -235.228892)
		(width 0.1143)
		(layer "In4.Cu")
		(net "P5E_CPU1_G1_RX_DN<13>")
	)
	(arc
		(start 98.94316 -229.439724)
		(mid 99.121973 -229.642074)
		(end 99.186492 -229.90429)
		(width 0.1143)
		(layer "In4.Cu")
		(net "P5E_CPU1_G1_RX_DN<13>")
	)
	(arc
		(start 97.306384 -221.804484)
		(mid 97.347639 -221.975455)
		(end 97.46234 -222.108776)
		(width 0.1143)
		(layer "In4.Cu")
		(net "P5E_CPU1_G1_RX_DN<13>")
	)
	(arc
		(start 98.94316 -226.199954)
		(mid 99.186487 -226.66452)
		(end 98.94316 -227.129086)
		(width 0.1143)
		(layer "In4.Cu")
		(net "P5E_CPU1_G1_RX_DN<13>")
	)
	(arc
		(start 98.872294 -235.27004)
		(mid 98.757618 -235.403374)
		(end 98.716338 -235.574332)
		(width 0.1143)
		(layer "In4.Cu")
		(net "P5E_CPU1_G1_RX_DN<13>")
	)
	(arc
		(start 98.872294 -233.650028)
		(mid 98.716366 -233.95432)
		(end 98.872294 -234.258612)
		(width 0.1143)
		(layer "In4.Cu")
		(net "P5E_CPU1_G1_RX_DN<13>")
	)
	(arc
		(start 98.473006 -231.869742)
		(mid 98.651819 -232.072092)
		(end 98.716338 -232.334308)
		(width 0.1143)
		(layer "In4.Cu")
		(net "P5E_CPU1_G1_RX_DN<13>")
	)
	(arc
		(start 98.872294 -230.410258)
		(mid 98.757618 -230.543592)
		(end 98.716338 -230.71455)
		(width 0.1143)
		(layer "In4.Cu")
		(net "P5E_CPU1_G1_RX_DN<13>")
	)
	(segment
		(start 21.547074 -7.709408)
		(end 21.547074 -8.320024)
		(width 0.12954)
		(layer "F.Cu")
		(net "P5E_CPU1_G1_RX_DN<14>")
	)
	(segment
		(start 21.408136 -7.57047)
		(end 21.547074 -7.709408)
		(width 0.12954)
		(layer "F.Cu")
		(net "P5E_CPU1_G1_RX_DN<14>")
	)
	(segment
		(start 21.68398 -4.963414)
		(end 21.408136 -5.239258)
		(width 0.12954)
		(layer "F.Cu")
		(net "P5E_CPU1_G1_RX_DN<14>")
	)
	(segment
		(start 99.08794 -233.410252)
		(end 98.621088 -233.144314)
		(width 0.12954)
		(layer "F.Cu")
		(net "P5E_CPU1_G1_RX_DN<14>")
	)
	(segment
		(start 21.408136 -5.239258)
		(end 21.408136 -7.57047)
		(width 0.12954)
		(layer "F.Cu")
		(net "P5E_CPU1_G1_RX_DN<14>")
	)
	(segment
		(start 96.553274 -222.126556)
		(end 96.554036 -222.127064)
		(width 0.1143)
		(layer "In4.Cu")
		(net "P5E_CPU1_G1_RX_DN<14>")
	)
	(segment
		(start 20.955508 -23.942802)
		(end 20.956778 -23.94458)
		(width 0.14224)
		(layer "In4.Cu")
		(net "P5E_CPU1_G1_RX_DN<14>")
	)
	(segment
		(start 20.960842 -23.949914)
		(end 20.960842 -23.950168)
		(width 0.14224)
		(layer "In4.Cu")
		(net "P5E_CPU1_G1_RX_DN<14>")
	)
	(segment
		(start 96.351852 -221.259908)
		(end 96.351852 -221.288356)
		(width 0.1143)
		(layer "In4.Cu")
		(net "P5E_CPU1_G1_RX_DN<14>")
	)
	(segment
		(start 32.576516 -39.889684)
		(end 32.577532 -39.891208)
		(width 0.14224)
		(layer "In4.Cu")
		(net "P5E_CPU1_G1_RX_DN<14>")
	)
	(segment
		(start 96.554036 -222.127064)
		(end 96.555052 -222.127572)
		(width 0.1143)
		(layer "In4.Cu")
		(net "P5E_CPU1_G1_RX_DN<14>")
	)
	(segment
		(start 21.39315 -5.254244)
		(end 21.39315 -12.033758)
		(width 0.14224)
		(layer "In4.Cu")
		(net "P5E_CPU1_G1_RX_DN<14>")
	)
	(segment
		(start 17.764252 -17.985486)
		(end 17.555718 -18.375122)
		(width 0.14224)
		(layer "In4.Cu")
		(net "P5E_CPU1_G1_RX_DN<14>")
	)
	(segment
		(start 96.306132 -221.513908)
		(end 96.36633 -221.574106)
		(width 0.1143)
		(layer "In4.Cu")
		(net "P5E_CPU1_G1_RX_DN<14>")
	)
	(segment
		(start 17.727168 -20.214336)
		(end 20.938998 -23.920704)
		(width 0.14224)
		(layer "In4.Cu")
		(net "P5E_CPU1_G1_RX_DN<14>")
	)
	(segment
		(start 97.023936 -224.557082)
		(end 97.063052 -224.579942)
		(width 0.1143)
		(layer "In4.Cu")
		(net "P5E_CPU1_G1_RX_DN<14>")
	)
	(segment
		(start 97.063052 -223.889062)
		(end 97.023936 -223.911922)
		(width 0.1143)
		(layer "In4.Cu")
		(net "P5E_CPU1_G1_RX_DN<14>")
	)
	(segment
		(start 17.198594 -18.909284)
		(end 17.16151 -18.998692)
		(width 0.14224)
		(layer "In4.Cu")
		(net "P5E_CPU1_G1_RX_DN<14>")
	)
	(segment
		(start 97.96399 -232.656888)
		(end 97.995486 -232.675176)
		(width 0.1143)
		(layer "In4.Cu")
		(net "P5E_CPU1_G1_RX_DN<14>")
	)
	(segment
		(start 20.956778 -23.94458)
		(end 20.95754 -23.945596)
		(width 0.14224)
		(layer "In4.Cu")
		(net "P5E_CPU1_G1_RX_DN<14>")
	)
	(segment
		(start 20.958556 -23.946866)
		(end 20.960842 -23.949914)
		(width 0.14224)
		(layer "In4.Cu")
		(net "P5E_CPU1_G1_RX_DN<14>")
	)
	(segment
		(start 97.46234 -231.828594)
		(end 97.49409 -231.846882)
		(width 0.1143)
		(layer "In4.Cu")
		(net "P5E_CPU1_G1_RX_DN<14>")
	)
	(segment
		(start 145.964656 -160.088326)
		(end 145.964656 -162.191192)
		(width 0.14224)
		(layer "In4.Cu")
		(net "P5E_CPU1_G1_RX_DN<14>")
	)
	(segment
		(start 17.555718 -18.375122)
		(end 17.198594 -18.909284)
		(width 0.14224)
		(layer "In4.Cu")
		(net "P5E_CPU1_G1_RX_DN<14>")
	)
	(segment
		(start 97.996248 -232.675684)
		(end 98.003106 -232.679748)
		(width 0.1143)
		(layer "In4.Cu")
		(net "P5E_CPU1_G1_RX_DN<14>")
	)
	(segment
		(start 54.726078 -63.438786)
		(end 142.668498 -142.52194)
		(width 0.14224)
		(layer "In4.Cu")
		(net "P5E_CPU1_G1_RX_DN<14>")
	)
	(segment
		(start 97.96399 -227.797106)
		(end 97.995486 -227.815394)
		(width 0.1143)
		(layer "In4.Cu")
		(net "P5E_CPU1_G1_RX_DN<14>")
	)
	(segment
		(start 50.018442 -59.55538)
		(end 54.726078 -63.438786)
		(width 0.14224)
		(layer "In4.Cu")
		(net "P5E_CPU1_G1_RX_DN<14>")
	)
	(segment
		(start 20.939506 -23.921466)
		(end 20.945602 -23.929594)
		(width 0.14224)
		(layer "In4.Cu")
		(net "P5E_CPU1_G1_RX_DN<14>")
	)
	(segment
		(start 17.131792 -19.25447)
		(end 17.727168 -20.214336)
		(width 0.14224)
		(layer "In4.Cu")
		(net "P5E_CPU1_G1_RX_DN<14>")
	)
	(segment
		(start 20.952714 -23.939246)
		(end 20.955508 -23.942802)
		(width 0.14224)
		(layer "In4.Cu")
		(net "P5E_CPU1_G1_RX_DN<14>")
	)
	(segment
		(start 21.68398 -4.963414)
		(end 21.39315 -5.254244)
		(width 0.14224)
		(layer "In4.Cu")
		(net "P5E_CPU1_G1_RX_DN<14>")
	)
	(segment
		(start 20.960842 -23.950168)
		(end 32.574992 -39.887652)
		(width 0.14224)
		(layer "In4.Cu")
		(net "P5E_CPU1_G1_RX_DN<14>")
	)
	(segment
		(start 97.96399 -227.151946)
		(end 97.963228 -227.152454)
		(width 0.1143)
		(layer "In4.Cu")
		(net "P5E_CPU1_G1_RX_DN<14>")
	)
	(segment
		(start 96.545908 -222.122492)
		(end 96.553274 -222.126556)
		(width 0.1143)
		(layer "In4.Cu")
		(net "P5E_CPU1_G1_RX_DN<14>")
	)
	(segment
		(start 97.96653 -228.770434)
		(end 97.965006 -228.77145)
		(width 0.1143)
		(layer "In4.Cu")
		(net "P5E_CPU1_G1_RX_DN<14>")
	)
	(segment
		(start 142.668498 -142.52194)
		(end 145.190464 -147.736306)
		(width 0.14224)
		(layer "In4.Cu")
		(net "P5E_CPU1_G1_RX_DN<14>")
	)
	(segment
		(start 17.121632 -19.199352)
		(end 17.131792 -19.25447)
		(width 0.14224)
		(layer "In4.Cu")
		(net "P5E_CPU1_G1_RX_DN<14>")
	)
	(segment
		(start 97.996248 -227.815902)
		(end 98.003106 -227.819966)
		(width 0.1143)
		(layer "In4.Cu")
		(net "P5E_CPU1_G1_RX_DN<14>")
	)
	(segment
		(start 32.579056 -39.89324)
		(end 32.580072 -39.89451)
		(width 0.14224)
		(layer "In4.Cu")
		(net "P5E_CPU1_G1_RX_DN<14>")
	)
	(segment
		(start 97.96399 -226.177094)
		(end 97.995486 -226.195382)
		(width 0.1143)
		(layer "In4.Cu")
		(net "P5E_CPU1_G1_RX_DN<14>")
	)
	(segment
		(start 97.995486 -227.815394)
		(end 97.996248 -227.815902)
		(width 0.1143)
		(layer "In4.Cu")
		(net "P5E_CPU1_G1_RX_DN<14>")
	)
	(segment
		(start 32.578548 -39.892478)
		(end 32.579056 -39.89324)
		(width 0.14224)
		(layer "In4.Cu")
		(net "P5E_CPU1_G1_RX_DN<14>")
	)
	(segment
		(start 97.770696 -232.327196)
		(end 97.770696 -232.329736)
		(width 0.1143)
		(layer "In4.Cu")
		(net "P5E_CPU1_G1_RX_DN<14>")
	)
	(segment
		(start 97.965006 -228.77145)
		(end 97.96399 -228.771958)
		(width 0.1143)
		(layer "In4.Cu")
		(net "P5E_CPU1_G1_RX_DN<14>")
	)
	(segment
		(start 97.93224 -227.778818)
		(end 97.963228 -227.796598)
		(width 0.1143)
		(layer "In4.Cu")
		(net "P5E_CPU1_G1_RX_DN<14>")
	)
	(segment
		(start 98.003106 -227.129086)
		(end 97.96653 -227.150422)
		(width 0.1143)
		(layer "In4.Cu")
		(net "P5E_CPU1_G1_RX_DN<14>")
	)
	(segment
		(start 97.495614 -225.36785)
		(end 97.4979 -225.36912)
		(width 0.1143)
		(layer "In4.Cu")
		(net "P5E_CPU1_G1_RX_DN<14>")
	)
	(segment
		(start 21.39315 -12.033758)
		(end 21.10359 -12.987782)
		(width 0.14224)
		(layer "In4.Cu")
		(net "P5E_CPU1_G1_RX_DN<14>")
	)
	(segment
		(start 97.530412 -231.180894)
		(end 97.460562 -231.221534)
		(width 0.1143)
		(layer "In4.Cu")
		(net "P5E_CPU1_G1_RX_DN<14>")
	)
	(segment
		(start 97.965006 -227.151438)
		(end 97.96399 -227.151946)
		(width 0.1143)
		(layer "In4.Cu")
		(net "P5E_CPU1_G1_RX_DN<14>")
	)
	(segment
		(start 96.351852 -213.990936)
		(end 96.351852 -221.259908)
		(width 0.14224)
		(layer "In4.Cu")
		(net "P5E_CPU1_G1_RX_DN<14>")
	)
	(segment
		(start 98.240342 -233.06151)
		(end 98.323146 -233.144314)
		(width 0.1143)
		(layer "In4.Cu")
		(net "P5E_CPU1_G1_RX_DN<14>")
	)
	(segment
		(start 96.993456 -224.539302)
		(end 97.023936 -224.557082)
		(width 0.1143)
		(layer "In4.Cu")
		(net "P5E_CPU1_G1_RX_DN<14>")
	)
	(segment
		(start 97.494598 -225.367342)
		(end 97.495614 -225.36785)
		(width 0.1143)
		(layer "In4.Cu")
		(net "P5E_CPU1_G1_RX_DN<14>")
	)
	(segment
		(start 21.10359 -12.987782)
		(end 17.764252 -17.985486)
		(width 0.14224)
		(layer "In4.Cu")
		(net "P5E_CPU1_G1_RX_DN<14>")
	)
	(segment
		(start 32.577532 -39.891208)
		(end 32.578548 -39.892478)
		(width 0.14224)
		(layer "In4.Cu")
		(net "P5E_CPU1_G1_RX_DN<14>")
	)
	(segment
		(start 144.995646 -165.067488)
		(end 141.499844 -170.552872)
		(width 0.14224)
		(layer "In4.Cu")
		(net "P5E_CPU1_G1_RX_DN<14>")
	)
	(segment
		(start 97.023936 -222.93707)
		(end 97.063052 -222.95993)
		(width 0.1143)
		(layer "In4.Cu")
		(net "P5E_CPU1_G1_RX_DN<14>")
	)
	(segment
		(start 145.190464 -147.736306)
		(end 145.964656 -160.088326)
		(width 0.14224)
		(layer "In4.Cu")
		(net "P5E_CPU1_G1_RX_DN<14>")
	)
	(segment
		(start 145.964656 -162.191192)
		(end 144.995646 -165.067488)
		(width 0.14224)
		(layer "In4.Cu")
		(net "P5E_CPU1_G1_RX_DN<14>")
	)
	(segment
		(start 32.582104 -39.897558)
		(end 36.265104 -44.951396)
		(width 0.14224)
		(layer "In4.Cu")
		(net "P5E_CPU1_G1_RX_DN<14>")
	)
	(segment
		(start 32.580072 -39.89451)
		(end 32.582104 -39.897558)
		(width 0.14224)
		(layer "In4.Cu")
		(net "P5E_CPU1_G1_RX_DN<14>")
	)
	(segment
		(start 32.574992 -39.887652)
		(end 32.576516 -39.889684)
		(width 0.14224)
		(layer "In4.Cu")
		(net "P5E_CPU1_G1_RX_DN<14>")
	)
	(segment
		(start 17.16151 -18.998692)
		(end 17.121632 -19.199352)
		(width 0.14224)
		(layer "In4.Cu")
		(net "P5E_CPU1_G1_RX_DN<14>")
	)
	(segment
		(start 97.963228 -232.65638)
		(end 97.96399 -232.656888)
		(width 0.1143)
		(layer "In4.Cu")
		(net "P5E_CPU1_G1_RX_DN<14>")
	)
	(segment
		(start 36.265104 -44.951396)
		(end 50.018442 -59.55538)
		(width 0.14224)
		(layer "In4.Cu")
		(net "P5E_CPU1_G1_RX_DN<14>")
	)
	(segment
		(start 96.555052 -222.127572)
		(end 96.593152 -222.149924)
		(width 0.1143)
		(layer "In4.Cu")
		(net "P5E_CPU1_G1_RX_DN<14>")
	)
	(segment
		(start 97.995486 -226.195382)
		(end 97.996248 -226.19589)
		(width 0.1143)
		(layer "In4.Cu")
		(net "P5E_CPU1_G1_RX_DN<14>")
	)
	(segment
		(start 96.351852 -221.288356)
		(end 96.306132 -221.334076)
		(width 0.1143)
		(layer "In4.Cu")
		(net "P5E_CPU1_G1_RX_DN<14>")
	)
	(segment
		(start 98.323146 -233.144314)
		(end 98.621088 -233.144314)
		(width 0.1143)
		(layer "In4.Cu")
		(net "P5E_CPU1_G1_RX_DN<14>")
	)
	(segment
		(start 97.963228 -227.796598)
		(end 97.96399 -227.797106)
		(width 0.1143)
		(layer "In4.Cu")
		(net "P5E_CPU1_G1_RX_DN<14>")
	)
	(segment
		(start 97.996248 -226.19589)
		(end 98.003106 -226.199954)
		(width 0.1143)
		(layer "In4.Cu")
		(net "P5E_CPU1_G1_RX_DN<14>")
	)
	(segment
		(start 20.94611 -23.930356)
		(end 20.952206 -23.938484)
		(width 0.14224)
		(layer "In4.Cu")
		(net "P5E_CPU1_G1_RX_DN<14>")
	)
	(segment
		(start 97.965006 -230.394256)
		(end 97.959672 -230.397304)
		(width 0.1143)
		(layer "In4.Cu")
		(net "P5E_CPU1_G1_RX_DN<14>")
	)
	(segment
		(start 97.4979 -225.36912)
		(end 97.498916 -225.369628)
		(width 0.1143)
		(layer "In4.Cu")
		(net "P5E_CPU1_G1_RX_DN<14>")
	)
	(segment
		(start 97.023936 -223.911922)
		(end 96.993456 -223.929702)
		(width 0.1143)
		(layer "In4.Cu")
		(net "P5E_CPU1_G1_RX_DN<14>")
	)
	(segment
		(start 97.958148 -232.653586)
		(end 97.963228 -232.65638)
		(width 0.1143)
		(layer "In4.Cu")
		(net "P5E_CPU1_G1_RX_DN<14>")
	)
	(segment
		(start 20.945602 -23.929594)
		(end 20.94611 -23.930356)
		(width 0.14224)
		(layer "In4.Cu")
		(net "P5E_CPU1_G1_RX_DN<14>")
	)
	(segment
		(start 97.498916 -225.369628)
		(end 97.530412 -225.38817)
		(width 0.1143)
		(layer "In4.Cu")
		(net "P5E_CPU1_G1_RX_DN<14>")
	)
	(segment
		(start 20.938998 -23.920704)
		(end 20.939506 -23.921466)
		(width 0.14224)
		(layer "In4.Cu")
		(net "P5E_CPU1_G1_RX_DN<14>")
	)
	(segment
		(start 97.934526 -226.160076)
		(end 97.963228 -226.176586)
		(width 0.1143)
		(layer "In4.Cu")
		(net "P5E_CPU1_G1_RX_DN<14>")
	)
	(segment
		(start 20.952206 -23.938484)
		(end 20.952714 -23.939246)
		(width 0.14224)
		(layer "In4.Cu")
		(net "P5E_CPU1_G1_RX_DN<14>")
	)
	(segment
		(start 96.306132 -221.334076)
		(end 96.306132 -221.513908)
		(width 0.1143)
		(layer "In4.Cu")
		(net "P5E_CPU1_G1_RX_DN<14>")
	)
	(segment
		(start 96.36633 -221.574106)
		(end 96.36633 -221.804484)
		(width 0.1143)
		(layer "In4.Cu")
		(net "P5E_CPU1_G1_RX_DN<14>")
	)
	(segment
		(start 96.993456 -222.91929)
		(end 97.023936 -222.93707)
		(width 0.1143)
		(layer "In4.Cu")
		(net "P5E_CPU1_G1_RX_DN<14>")
	)
	(segment
		(start 97.963228 -226.176586)
		(end 97.96399 -226.177094)
		(width 0.1143)
		(layer "In4.Cu")
		(net "P5E_CPU1_G1_RX_DN<14>")
	)
	(segment
		(start 103.788464 -201.439272)
		(end 96.351852 -213.990936)
		(width 0.14224)
		(layer "In4.Cu")
		(net "P5E_CPU1_G1_RX_DN<14>")
	)
	(segment
		(start 96.522286 -222.108776)
		(end 96.545908 -222.122492)
		(width 0.1143)
		(layer "In4.Cu")
		(net "P5E_CPU1_G1_RX_DN<14>")
	)
	(segment
		(start 141.499844 -170.552872)
		(end 103.788464 -201.439272)
		(width 0.14224)
		(layer "In4.Cu")
		(net "P5E_CPU1_G1_RX_DN<14>")
	)
	(segment
		(start 97.492312 -225.366072)
		(end 97.494598 -225.367342)
		(width 0.1143)
		(layer "In4.Cu")
		(net "P5E_CPU1_G1_RX_DN<14>")
	)
	(segment
		(start 97.995486 -232.675176)
		(end 97.996248 -232.675684)
		(width 0.1143)
		(layer "In4.Cu")
		(net "P5E_CPU1_G1_RX_DN<14>")
	)
	(segment
		(start 97.930462 -229.397306)
		(end 98.003106 -229.439724)
		(width 0.1143)
		(layer "In4.Cu")
		(net "P5E_CPU1_G1_RX_DN<14>")
	)
	(segment
		(start 98.003106 -228.749098)
		(end 97.96653 -228.770434)
		(width 0.1143)
		(layer "In4.Cu")
		(net "P5E_CPU1_G1_RX_DN<14>")
	)
	(segment
		(start 20.95754 -23.945596)
		(end 20.958556 -23.946866)
		(width 0.14224)
		(layer "In4.Cu")
		(net "P5E_CPU1_G1_RX_DN<14>")
	)
	(segment
		(start 97.963228 -227.152454)
		(end 97.93224 -227.170234)
		(width 0.1143)
		(layer "In4.Cu")
		(net "P5E_CPU1_G1_RX_DN<14>")
	)
	(segment
		(start 97.96653 -227.150422)
		(end 97.965006 -227.151438)
		(width 0.1143)
		(layer "In4.Cu")
		(net "P5E_CPU1_G1_RX_DN<14>")
	)
	(segment
		(start 97.963228 -228.772466)
		(end 97.93224 -228.790246)
		(width 0.1143)
		(layer "In4.Cu")
		(net "P5E_CPU1_G1_RX_DN<14>")
	)
	(segment
		(start 97.96399 -228.771958)
		(end 97.963228 -228.772466)
		(width 0.1143)
		(layer "In4.Cu")
		(net "P5E_CPU1_G1_RX_DN<14>")
	)
	(arc
		(start 97.306384 -225.044508)
		(mid 97.356207 -225.230238)
		(end 97.492312 -225.366072)
		(width 0.1143)
		(layer "In4.Cu")
		(net "P5E_CPU1_G1_RX_DN<14>")
	)
	(arc
		(start 96.36633 -221.804484)
		(mid 96.407585 -221.975455)
		(end 96.522286 -222.108776)
		(width 0.1143)
		(layer "In4.Cu")
		(net "P5E_CPU1_G1_RX_DN<14>")
	)
	(arc
		(start 97.530412 -225.38817)
		(mid 97.711064 -225.590915)
		(end 97.776284 -225.854514)
		(width 0.1143)
		(layer "In4.Cu")
		(net "P5E_CPU1_G1_RX_DN<14>")
	)
	(arc
		(start 96.593152 -222.149924)
		(mid 96.771965 -222.352274)
		(end 96.836484 -222.61449)
		(width 0.1143)
		(layer "In4.Cu")
		(net "P5E_CPU1_G1_RX_DN<14>")
	)
	(arc
		(start 98.246438 -229.90429)
		(mid 98.17107 -230.186805)
		(end 97.965006 -230.394256)
		(width 0.1143)
		(layer "In4.Cu")
		(net "P5E_CPU1_G1_RX_DN<14>")
	)
	(arc
		(start 98.003106 -227.819966)
		(mid 98.246433 -228.284532)
		(end 98.003106 -228.749098)
		(width 0.1143)
		(layer "In4.Cu")
		(net "P5E_CPU1_G1_RX_DN<14>")
	)
	(arc
		(start 97.93224 -227.170234)
		(mid 97.780651 -227.474526)
		(end 97.93224 -227.778818)
		(width 0.1143)
		(layer "In4.Cu")
		(net "P5E_CPU1_G1_RX_DN<14>")
	)
	(arc
		(start 96.836484 -222.61449)
		(mid 96.878033 -222.785912)
		(end 96.993456 -222.91929)
		(width 0.1143)
		(layer "In4.Cu")
		(net "P5E_CPU1_G1_RX_DN<14>")
	)
	(arc
		(start 97.460562 -231.221534)
		(mid 97.347155 -231.354423)
		(end 97.306384 -231.524302)
		(width 0.1143)
		(layer "In4.Cu")
		(net "P5E_CPU1_G1_RX_DN<14>")
	)
	(arc
		(start 97.776284 -229.094538)
		(mid 97.817046 -229.264422)
		(end 97.930462 -229.397306)
		(width 0.1143)
		(layer "In4.Cu")
		(net "P5E_CPU1_G1_RX_DN<14>")
	)
	(arc
		(start 97.770696 -232.329736)
		(mid 97.820946 -232.516818)
		(end 97.958148 -232.653586)
		(width 0.1143)
		(layer "In4.Cu")
		(net "P5E_CPU1_G1_RX_DN<14>")
	)
	(arc
		(start 97.776284 -230.71455)
		(mid 97.711048 -230.978141)
		(end 97.530412 -231.180894)
		(width 0.1143)
		(layer "In4.Cu")
		(net "P5E_CPU1_G1_RX_DN<14>")
	)
	(arc
		(start 97.49409 -231.846882)
		(mid 97.69663 -232.050052)
		(end 97.770696 -232.327196)
		(width 0.1143)
		(layer "In4.Cu")
		(net "P5E_CPU1_G1_RX_DN<14>")
	)
	(arc
		(start 96.993456 -223.929702)
		(mid 96.836479 -224.234502)
		(end 96.993456 -224.539302)
		(width 0.1143)
		(layer "In4.Cu")
		(net "P5E_CPU1_G1_RX_DN<14>")
	)
	(arc
		(start 98.003106 -232.679748)
		(mid 98.155093 -232.836256)
		(end 98.236532 -233.03865)
		(width 0.1143)
		(layer "In4.Cu")
		(net "P5E_CPU1_G1_RX_DN<14>")
	)
	(arc
		(start 97.959672 -230.397304)
		(mid 97.8254 -230.531321)
		(end 97.776284 -230.71455)
		(width 0.1143)
		(layer "In4.Cu")
		(net "P5E_CPU1_G1_RX_DN<14>")
	)
	(arc
		(start 97.776284 -225.854514)
		(mid 97.821295 -226.02495)
		(end 97.934526 -226.160076)
		(width 0.1143)
		(layer "In4.Cu")
		(net "P5E_CPU1_G1_RX_DN<14>")
	)
	(arc
		(start 98.003106 -229.439724)
		(mid 98.181919 -229.642074)
		(end 98.246438 -229.90429)
		(width 0.1143)
		(layer "In4.Cu")
		(net "P5E_CPU1_G1_RX_DN<14>")
	)
	(arc
		(start 97.93224 -228.790246)
		(mid 97.820443 -228.925047)
		(end 97.776284 -229.094538)
		(width 0.1143)
		(layer "In4.Cu")
		(net "P5E_CPU1_G1_RX_DN<14>")
	)
	(arc
		(start 98.003106 -226.199954)
		(mid 98.246433 -226.66452)
		(end 98.003106 -227.129086)
		(width 0.1143)
		(layer "In4.Cu")
		(net "P5E_CPU1_G1_RX_DN<14>")
	)
	(arc
		(start 97.306384 -231.524302)
		(mid 97.347639 -231.695273)
		(end 97.46234 -231.828594)
		(width 0.1143)
		(layer "In4.Cu")
		(net "P5E_CPU1_G1_RX_DN<14>")
	)
	(arc
		(start 97.063052 -224.579942)
		(mid 97.241865 -224.782292)
		(end 97.306384 -225.044508)
		(width 0.1143)
		(layer "In4.Cu")
		(net "P5E_CPU1_G1_RX_DN<14>")
	)
	(arc
		(start 98.236532 -233.03865)
		(mid 98.238555 -233.05006)
		(end 98.240342 -233.06151)
		(width 0.1143)
		(layer "In4.Cu")
		(net "P5E_CPU1_G1_RX_DN<14>")
	)
	(arc
		(start 97.063052 -222.95993)
		(mid 97.306379 -223.424496)
		(end 97.063052 -223.889062)
		(width 0.1143)
		(layer "In4.Cu")
		(net "P5E_CPU1_G1_RX_DN<14>")
	)
	(segment
		(start 56.128412 -7.57047)
		(end 56.26735 -7.709408)
		(width 0.12954)
		(layer "F.Cu")
		(net "P5E_CPU1_G1_RX_DN<0>")
	)
	(segment
		(start 56.404002 -4.963414)
		(end 56.128412 -5.239004)
		(width 0.12954)
		(layer "F.Cu")
		(net "P5E_CPU1_G1_RX_DN<0>")
	)
	(segment
		(start 109.897926 -235.84027)
		(end 109.431074 -235.574332)
		(width 0.12954)
		(layer "F.Cu")
		(net "P5E_CPU1_G1_RX_DN<0>")
	)
	(segment
		(start 56.267096 -7.709662)
		(end 56.267096 -8.320024)
		(width 0.12954)
		(layer "F.Cu")
		(net "P5E_CPU1_G1_RX_DN<0>")
	)
	(segment
		(start 56.128412 -5.239004)
		(end 56.128412 -7.57047)
		(width 0.12954)
		(layer "F.Cu")
		(net "P5E_CPU1_G1_RX_DN<0>")
	)
	(segment
		(start 56.26735 -7.709408)
		(end 56.267096 -7.709662)
		(width 0.12954)
		(layer "F.Cu")
		(net "P5E_CPU1_G1_RX_DN<0>")
	)
	(segment
		(start 56.654446 -18.909284)
		(end 56.617108 -18.999708)
		(width 0.14224)
		(layer "In4.Cu")
		(net "P5E_CPU1_G1_RX_DN<0>")
	)
	(segment
		(start 156.830776 -172.13326)
		(end 156.492702 -173.052994)
		(width 0.14224)
		(layer "In4.Cu")
		(net "P5E_CPU1_G1_RX_DN<0>")
	)
	(segment
		(start 109.063282 -235.504482)
		(end 109.133132 -235.574332)
		(width 0.1143)
		(layer "In4.Cu")
		(net "P5E_CPU1_G1_RX_DN<0>")
	)
	(segment
		(start 153.147268 -134.054342)
		(end 158.340044 -144.882362)
		(width 0.14224)
		(layer "In4.Cu")
		(net "P5E_CPU1_G1_RX_DN<0>")
	)
	(segment
		(start 109.717586 -234.439714)
		(end 109.71657 -234.440222)
		(width 0.1143)
		(layer "In4.Cu")
		(net "P5E_CPU1_G1_RX_DN<0>")
	)
	(segment
		(start 56.617108 -18.999708)
		(end 56.60009 -19.082512)
		(width 0.14224)
		(layer "In4.Cu")
		(net "P5E_CPU1_G1_RX_DN<0>")
	)
	(segment
		(start 56.113172 -5.254244)
		(end 56.113172 -11.02614)
		(width 0.14224)
		(layer "In4.Cu")
		(net "P5E_CPU1_G1_RX_DN<0>")
	)
	(segment
		(start 110.645194 -221.393512)
		(end 111.105188 -222.504508)
		(width 0.14224)
		(layer "In4.Cu")
		(net "P5E_CPU1_G1_RX_DN<0>")
	)
	(segment
		(start 110.785148 -233.122216)
		(end 110.765082 -233.142282)
		(width 0.1143)
		(layer "In4.Cu")
		(net "P5E_CPU1_G1_RX_DN<0>")
	)
	(segment
		(start 109.753146 -234.418886)
		(end 109.725968 -234.434888)
		(width 0.1143)
		(layer "In4.Cu")
		(net "P5E_CPU1_G1_RX_DN<0>")
	)
	(segment
		(start 109.71403 -234.441746)
		(end 109.713268 -234.442254)
		(width 0.1143)
		(layer "In4.Cu")
		(net "P5E_CPU1_G1_RX_DN<0>")
	)
	(segment
		(start 57.01157 -18.375122)
		(end 56.654446 -18.909284)
		(width 0.14224)
		(layer "In4.Cu")
		(net "P5E_CPU1_G1_RX_DN<0>")
	)
	(segment
		(start 109.71657 -234.440222)
		(end 109.715046 -234.441238)
		(width 0.1143)
		(layer "In4.Cu")
		(net "P5E_CPU1_G1_RX_DN<0>")
	)
	(segment
		(start 156.479748 -173.0883)
		(end 152.939496 -178.066446)
		(width 0.14224)
		(layer "In4.Cu")
		(net "P5E_CPU1_G1_RX_DN<0>")
	)
	(segment
		(start 159.26435 -164.989764)
		(end 156.830776 -172.13326)
		(width 0.14224)
		(layer "In4.Cu")
		(net "P5E_CPU1_G1_RX_DN<0>")
	)
	(segment
		(start 156.492702 -173.053248)
		(end 156.479748 -173.0883)
		(width 0.14224)
		(layer "In4.Cu")
		(net "P5E_CPU1_G1_RX_DN<0>")
	)
	(segment
		(start 109.721904 -234.437174)
		(end 109.719872 -234.438444)
		(width 0.1143)
		(layer "In4.Cu")
		(net "P5E_CPU1_G1_RX_DN<0>")
	)
	(segment
		(start 109.715046 -234.441238)
		(end 109.71403 -234.441746)
		(width 0.1143)
		(layer "In4.Cu")
		(net "P5E_CPU1_G1_RX_DN<0>")
	)
	(segment
		(start 109.317282 -235.209334)
		(end 109.21238 -235.27004)
		(width 0.1143)
		(layer "In4.Cu")
		(net "P5E_CPU1_G1_RX_DN<0>")
	)
	(segment
		(start 111.105188 -232.802176)
		(end 110.785148 -233.122216)
		(width 0.14224)
		(layer "In4.Cu")
		(net "P5E_CPU1_G1_RX_DN<0>")
	)
	(segment
		(start 109.725968 -234.434888)
		(end 109.721904 -234.437174)
		(width 0.1143)
		(layer "In4.Cu")
		(net "P5E_CPU1_G1_RX_DN<0>")
	)
	(segment
		(start 159.26435 -159.687514)
		(end 159.26435 -164.989764)
		(width 0.14224)
		(layer "In4.Cu")
		(net "P5E_CPU1_G1_RX_DN<0>")
	)
	(segment
		(start 60.536836 -50.776378)
		(end 153.147268 -134.054342)
		(width 0.14224)
		(layer "In4.Cu")
		(net "P5E_CPU1_G1_RX_DN<0>")
	)
	(segment
		(start 59.563508 -48.876712)
		(end 60.536836 -50.776378)
		(width 0.14224)
		(layer "In4.Cu")
		(net "P5E_CPU1_G1_RX_DN<0>")
	)
	(segment
		(start 57.317386 -17.080484)
		(end 57.317386 -17.765014)
		(width 0.14224)
		(layer "In4.Cu")
		(net "P5E_CPU1_G1_RX_DN<0>")
	)
	(segment
		(start 110.700058 -233.142282)
		(end 110.2995 -233.54284)
		(width 0.1143)
		(layer "In4.Cu")
		(net "P5E_CPU1_G1_RX_DN<0>")
	)
	(segment
		(start 152.939496 -178.066446)
		(end 114.431318 -209.641948)
		(width 0.14224)
		(layer "In4.Cu")
		(net "P5E_CPU1_G1_RX_DN<0>")
	)
	(segment
		(start 110.765082 -233.142282)
		(end 110.700058 -233.142282)
		(width 0.1143)
		(layer "In4.Cu")
		(net "P5E_CPU1_G1_RX_DN<0>")
	)
	(segment
		(start 57.246774 -17.935702)
		(end 57.01157 -18.375122)
		(width 0.14224)
		(layer "In4.Cu")
		(net "P5E_CPU1_G1_RX_DN<0>")
	)
	(segment
		(start 110.645194 -216.018618)
		(end 110.645194 -221.393512)
		(width 0.14224)
		(layer "In4.Cu")
		(net "P5E_CPU1_G1_RX_DN<0>")
	)
	(segment
		(start 156.492702 -173.052994)
		(end 156.492702 -173.053248)
		(width 0.14224)
		(layer "In4.Cu")
		(net "P5E_CPU1_G1_RX_DN<0>")
	)
	(segment
		(start 57.317386 -17.765014)
		(end 57.246774 -17.935702)
		(width 0.14224)
		(layer "In4.Cu")
		(net "P5E_CPU1_G1_RX_DN<0>")
	)
	(segment
		(start 56.470042 -20.62099)
		(end 59.563508 -48.876712)
		(width 0.14224)
		(layer "In4.Cu")
		(net "P5E_CPU1_G1_RX_DN<0>")
	)
	(segment
		(start 158.340044 -144.882362)
		(end 159.26435 -159.687514)
		(width 0.14224)
		(layer "In4.Cu")
		(net "P5E_CPU1_G1_RX_DN<0>")
	)
	(segment
		(start 109.719872 -234.438444)
		(end 109.718856 -234.438952)
		(width 0.1143)
		(layer "In4.Cu")
		(net "P5E_CPU1_G1_RX_DN<0>")
	)
	(segment
		(start 56.113172 -11.02614)
		(end 57.317386 -17.080484)
		(width 0.14224)
		(layer "In4.Cu")
		(net "P5E_CPU1_G1_RX_DN<0>")
	)
	(segment
		(start 109.539024 -234.743244)
		(end 109.539024 -234.82427)
		(width 0.1143)
		(layer "In4.Cu")
		(net "P5E_CPU1_G1_RX_DN<0>")
	)
	(segment
		(start 109.718856 -234.438952)
		(end 109.717586 -234.439714)
		(width 0.1143)
		(layer "In4.Cu")
		(net "P5E_CPU1_G1_RX_DN<0>")
	)
	(segment
		(start 109.133132 -235.574332)
		(end 109.431074 -235.574332)
		(width 0.1143)
		(layer "In4.Cu")
		(net "P5E_CPU1_G1_RX_DN<0>")
	)
	(segment
		(start 111.105188 -222.504508)
		(end 111.105188 -232.802176)
		(width 0.14224)
		(layer "In4.Cu")
		(net "P5E_CPU1_G1_RX_DN<0>")
	)
	(segment
		(start 114.431318 -209.641948)
		(end 110.645194 -216.018618)
		(width 0.14224)
		(layer "In4.Cu")
		(net "P5E_CPU1_G1_RX_DN<0>")
	)
	(segment
		(start 56.404002 -4.963414)
		(end 56.113172 -5.254244)
		(width 0.14224)
		(layer "In4.Cu")
		(net "P5E_CPU1_G1_RX_DN<0>")
	)
	(segment
		(start 110.18393 -233.63174)
		(end 110.15345 -233.64952)
		(width 0.1143)
		(layer "In4.Cu")
		(net "P5E_CPU1_G1_RX_DN<0>")
	)
	(segment
		(start 56.60009 -19.082512)
		(end 56.470042 -20.62099)
		(width 0.14224)
		(layer "In4.Cu")
		(net "P5E_CPU1_G1_RX_DN<0>")
	)
	(arc
		(start 109.996478 -233.95432)
		(mid 109.931963 -234.216539)
		(end 109.753146 -234.418886)
		(width 0.1143)
		(layer "In4.Cu")
		(net "P5E_CPU1_G1_RX_DN<0>")
	)
	(arc
		(start 110.15345 -233.64952)
		(mid 110.038023 -233.782896)
		(end 109.996478 -233.95432)
		(width 0.1143)
		(layer "In4.Cu")
		(net "P5E_CPU1_G1_RX_DN<0>")
	)
	(arc
		(start 109.21238 -235.27004)
		(mid 109.115245 -235.372909)
		(end 109.063282 -235.504482)
		(width 0.1143)
		(layer "In4.Cu")
		(net "P5E_CPU1_G1_RX_DN<0>")
	)
	(arc
		(start 109.539024 -234.82427)
		(mid 109.47963 -235.04645)
		(end 109.317282 -235.209334)
		(width 0.1143)
		(layer "In4.Cu")
		(net "P5E_CPU1_G1_RX_DN<0>")
	)
	(arc
		(start 110.2995 -233.54284)
		(mid 110.244601 -233.591042)
		(end 110.18393 -233.63174)
		(width 0.1143)
		(layer "In4.Cu")
		(net "P5E_CPU1_G1_RX_DN<0>")
	)
	(arc
		(start 109.713268 -234.442254)
		(mid 109.585684 -234.569335)
		(end 109.539024 -234.743244)
		(width 0.1143)
		(layer "In4.Cu")
		(net "P5E_CPU1_G1_RX_DN<0>")
	)
	(segment
		(start 54.328314 -6.996176)
		(end 54.599332 -6.725158)
		(width 0.12954)
		(layer "F.Cu")
		(net "P5E_CPU1_G1_RX_DN<1>")
	)
	(segment
		(start 54.466998 -7.709154)
		(end 54.328314 -7.57047)
		(width 0.12954)
		(layer "F.Cu")
		(net "P5E_CPU1_G1_RX_DN<1>")
	)
	(segment
		(start 54.466998 -8.320024)
		(end 54.466998 -7.709154)
		(width 0.12954)
		(layer "F.Cu")
		(net "P5E_CPU1_G1_RX_DN<1>")
	)
	(segment
		(start 54.328314 -7.57047)
		(end 54.328314 -6.996176)
		(width 0.12954)
		(layer "F.Cu")
		(net "P5E_CPU1_G1_RX_DN<1>")
	)
	(segment
		(start 109.897926 -234.220258)
		(end 109.431074 -233.95432)
		(width 0.12954)
		(layer "F.Cu")
		(net "P5E_CPU1_G1_RX_DN<1>")
	)
	(segment
		(start 109.522006 -233.131868)
		(end 109.521752 -233.131614)
		(width 0.1143)
		(layer "In4.Cu")
		(net "P5E_CPU1_G1_RX_DN<1>")
	)
	(segment
		(start 109.526324 -221.378526)
		(end 109.526324 -221.558358)
		(width 0.1143)
		(layer "In4.Cu")
		(net "P5E_CPU1_G1_RX_DN<1>")
	)
	(segment
		(start 109.275626 -224.57537)
		(end 109.276388 -224.575878)
		(width 0.1143)
		(layer "In4.Cu")
		(net "P5E_CPU1_G1_RX_DN<1>")
	)
	(segment
		(start 110.180374 -231.037638)
		(end 110.187232 -231.041702)
		(width 0.1143)
		(layer "In4.Cu")
		(net "P5E_CPU1_G1_RX_DN<1>")
	)
	(segment
		(start 109.24413 -224.557082)
		(end 109.275626 -224.57537)
		(width 0.1143)
		(layer "In4.Cu")
		(net "P5E_CPU1_G1_RX_DN<1>")
	)
	(segment
		(start 109.693202 -232.835958)
		(end 109.693202 -232.835704)
		(width 0.1143)
		(layer "In4.Cu")
		(net "P5E_CPU1_G1_RX_DN<1>")
	)
	(segment
		(start 110.15345 -226.159314)
		(end 110.18393 -226.177094)
		(width 0.1143)
		(layer "In4.Cu")
		(net "P5E_CPU1_G1_RX_DN<1>")
	)
	(segment
		(start 110.217458 -230.372412)
		(end 110.184184 -230.391716)
		(width 0.1143)
		(layer "In4.Cu")
		(net "P5E_CPU1_G1_RX_DN<1>")
	)
	(segment
		(start 109.712506 -232.824528)
		(end 109.694472 -232.834942)
		(width 0.1143)
		(layer "In4.Cu")
		(net "P5E_CPU1_G1_RX_DN<1>")
	)
	(segment
		(start 54.599332 -6.725158)
		(end 54.308502 -7.015988)
		(width 0.14224)
		(layer "In4.Cu")
		(net "P5E_CPU1_G1_RX_DN<1>")
	)
	(segment
		(start 54.436518 -18.77568)
		(end 54.494938 -18.916396)
		(width 0.14224)
		(layer "In4.Cu")
		(net "P5E_CPU1_G1_RX_DN<1>")
	)
	(segment
		(start 110.18393 -226.177094)
		(end 110.220252 -226.198176)
		(width 0.1143)
		(layer "In4.Cu")
		(net "P5E_CPU1_G1_RX_DN<1>")
	)
	(segment
		(start 53.849524 -17.815052)
		(end 54.07152 -18.229834)
		(width 0.14224)
		(layer "In4.Cu")
		(net "P5E_CPU1_G1_RX_DN<1>")
	)
	(segment
		(start 158.3309 -164.797994)
		(end 155.771088 -172.3136)
		(width 0.14224)
		(layer "In4.Cu")
		(net "P5E_CPU1_G1_RX_DN<1>")
	)
	(segment
		(start 158.3309 -159.698436)
		(end 158.3309 -164.797994)
		(width 0.14224)
		(layer "In4.Cu")
		(net "P5E_CPU1_G1_RX_DN<1>")
	)
	(segment
		(start 110.18393 -227.797106)
		(end 110.220252 -227.818188)
		(width 0.1143)
		(layer "In4.Cu")
		(net "P5E_CPU1_G1_RX_DN<1>")
	)
	(segment
		(start 109.21238 -224.538794)
		(end 109.23651 -224.552764)
		(width 0.1143)
		(layer "In4.Cu")
		(net "P5E_CPU1_G1_RX_DN<1>")
	)
	(segment
		(start 110.151418 -229.398068)
		(end 110.195106 -229.423214)
		(width 0.1143)
		(layer "In4.Cu")
		(net "P5E_CPU1_G1_RX_DN<1>")
	)
	(segment
		(start 155.667964 -172.593254)
		(end 152.206198 -177.461926)
		(width 0.14224)
		(layer "In4.Cu")
		(net "P5E_CPU1_G1_RX_DN<1>")
	)
	(segment
		(start 110.466124 -231.524302)
		(end 110.466378 -231.524302)
		(width 0.1143)
		(layer "In4.Cu")
		(net "P5E_CPU1_G1_RX_DN<1>")
	)
	(segment
		(start 152.31237 -134.558024)
		(end 157.42031 -145.121884)
		(width 0.14224)
		(layer "In4.Cu")
		(net "P5E_CPU1_G1_RX_DN<1>")
	)
	(segment
		(start 109.239812 -224.554542)
		(end 109.240574 -224.55505)
		(width 0.1143)
		(layer "In4.Cu")
		(net "P5E_CPU1_G1_RX_DN<1>")
	)
	(segment
		(start 59.717686 -51.293776)
		(end 152.31237 -134.558024)
		(width 0.14224)
		(layer "In4.Cu")
		(net "P5E_CPU1_G1_RX_DN<1>")
	)
	(segment
		(start 157.42031 -145.121884)
		(end 158.3309 -159.698436)
		(width 0.14224)
		(layer "In4.Cu")
		(net "P5E_CPU1_G1_RX_DN<1>")
	)
	(segment
		(start 109.526578 -221.558612)
		(end 109.526578 -223.423734)
		(width 0.1143)
		(layer "In4.Cu")
		(net "P5E_CPU1_G1_RX_DN<1>")
	)
	(segment
		(start 53.805582 -17.70888)
		(end 53.849524 -17.815052)
		(width 0.14224)
		(layer "In4.Cu")
		(net "P5E_CPU1_G1_RX_DN<1>")
	)
	(segment
		(start 54.07152 -18.229834)
		(end 54.436518 -18.77568)
		(width 0.14224)
		(layer "In4.Cu")
		(net "P5E_CPU1_G1_RX_DN<1>")
	)
	(segment
		(start 109.243368 -224.556574)
		(end 109.24413 -224.557082)
		(width 0.1143)
		(layer "In4.Cu")
		(net "P5E_CPU1_G1_RX_DN<1>")
	)
	(segment
		(start 54.51094 -18.997422)
		(end 54.526688 -19.07667)
		(width 0.14224)
		(layer "In4.Cu")
		(net "P5E_CPU1_G1_RX_DN<1>")
	)
	(segment
		(start 110.1852 -232.014268)
		(end 110.179104 -232.017824)
		(width 0.1143)
		(layer "In4.Cu")
		(net "P5E_CPU1_G1_RX_DN<1>")
	)
	(segment
		(start 110.18393 -227.151946)
		(end 110.15345 -227.169726)
		(width 0.1143)
		(layer "In4.Cu")
		(net "P5E_CPU1_G1_RX_DN<1>")
	)
	(segment
		(start 109.240574 -224.55505)
		(end 109.243368 -224.556574)
		(width 0.1143)
		(layer "In4.Cu")
		(net "P5E_CPU1_G1_RX_DN<1>")
	)
	(segment
		(start 110.15345 -227.779326)
		(end 110.18393 -227.797106)
		(width 0.1143)
		(layer "In4.Cu")
		(net "P5E_CPU1_G1_RX_DN<1>")
	)
	(segment
		(start 155.771088 -172.3136)
		(end 155.770834 -172.3136)
		(width 0.14224)
		(layer "In4.Cu")
		(net "P5E_CPU1_G1_RX_DN<1>")
	)
	(segment
		(start 110.18393 -228.771958)
		(end 110.15345 -228.789738)
		(width 0.1143)
		(layer "In4.Cu")
		(net "P5E_CPU1_G1_RX_DN<1>")
	)
	(segment
		(start 54.526688 -19.07667)
		(end 54.526688 -19.277838)
		(width 0.14224)
		(layer "In4.Cu")
		(net "P5E_CPU1_G1_RX_DN<1>")
	)
	(segment
		(start 109.526324 -221.558358)
		(end 109.526578 -221.558612)
		(width 0.1143)
		(layer "In4.Cu")
		(net "P5E_CPU1_G1_RX_DN<1>")
	)
	(segment
		(start 109.23651 -224.552764)
		(end 109.237526 -224.553272)
		(width 0.1143)
		(layer "In4.Cu")
		(net "P5E_CPU1_G1_RX_DN<1>")
	)
	(segment
		(start 109.230414 -233.639868)
		(end 109.21238 -233.650028)
		(width 0.1143)
		(layer "In4.Cu")
		(net "P5E_CPU1_G1_RX_DN<1>")
	)
	(segment
		(start 109.572044 -221.332806)
		(end 109.526324 -221.378526)
		(width 0.1143)
		(layer "In4.Cu")
		(net "P5E_CPU1_G1_RX_DN<1>")
	)
	(segment
		(start 54.51094 -18.99666)
		(end 54.51094 -18.997422)
		(width 0.14224)
		(layer "In4.Cu")
		(net "P5E_CPU1_G1_RX_DN<1>")
	)
	(segment
		(start 53.805582 -17.5895)
		(end 53.805582 -17.70888)
		(width 0.14224)
		(layer "In4.Cu")
		(net "P5E_CPU1_G1_RX_DN<1>")
	)
	(segment
		(start 58.50509 -48.996854)
		(end 59.717686 -51.293776)
		(width 0.14224)
		(layer "In4.Cu")
		(net "P5E_CPU1_G1_RX_DN<1>")
	)
	(segment
		(start 109.68355 -225.349308)
		(end 109.71403 -225.367088)
		(width 0.1143)
		(layer "In4.Cu")
		(net "P5E_CPU1_G1_RX_DN<1>")
	)
	(segment
		(start 54.308502 -12.526518)
		(end 54.299866 -12.569952)
		(width 0.14224)
		(layer "In4.Cu")
		(net "P5E_CPU1_G1_RX_DN<1>")
	)
	(segment
		(start 109.694472 -232.834942)
		(end 109.693202 -232.835958)
		(width 0.1143)
		(layer "In4.Cu")
		(net "P5E_CPU1_G1_RX_DN<1>")
	)
	(segment
		(start 110.220252 -227.130864)
		(end 110.18393 -227.151946)
		(width 0.1143)
		(layer "In4.Cu")
		(net "P5E_CPU1_G1_RX_DN<1>")
	)
	(segment
		(start 54.299866 -12.569952)
		(end 53.805582 -17.5895)
		(width 0.14224)
		(layer "In4.Cu")
		(net "P5E_CPU1_G1_RX_DN<1>")
	)
	(segment
		(start 113.671604 -209.058764)
		(end 109.572044 -215.963754)
		(width 0.14224)
		(layer "In4.Cu")
		(net "P5E_CPU1_G1_RX_DN<1>")
	)
	(segment
		(start 155.770834 -172.3136)
		(end 155.667964 -172.593254)
		(width 0.14224)
		(layer "In4.Cu")
		(net "P5E_CPU1_G1_RX_DN<1>")
	)
	(segment
		(start 109.063282 -233.88447)
		(end 109.133132 -233.95432)
		(width 0.1143)
		(layer "In4.Cu")
		(net "P5E_CPU1_G1_RX_DN<1>")
	)
	(segment
		(start 110.184184 -230.391716)
		(end 110.154212 -230.408988)
		(width 0.1143)
		(layer "In4.Cu")
		(net "P5E_CPU1_G1_RX_DN<1>")
	)
	(segment
		(start 54.526688 -19.277838)
		(end 58.50509 -48.996854)
		(width 0.14224)
		(layer "In4.Cu")
		(net "P5E_CPU1_G1_RX_DN<1>")
	)
	(segment
		(start 54.308502 -7.015988)
		(end 54.308502 -12.526518)
		(width 0.14224)
		(layer "In4.Cu")
		(net "P5E_CPU1_G1_RX_DN<1>")
	)
	(segment
		(start 152.206198 -177.461926)
		(end 113.671604 -209.058764)
		(width 0.14224)
		(layer "In4.Cu")
		(net "P5E_CPU1_G1_RX_DN<1>")
	)
	(segment
		(start 109.238288 -224.55378)
		(end 109.239812 -224.554542)
		(width 0.1143)
		(layer "In4.Cu")
		(net "P5E_CPU1_G1_RX_DN<1>")
	)
	(segment
		(start 109.572044 -215.963754)
		(end 109.572044 -221.304358)
		(width 0.14224)
		(layer "In4.Cu")
		(net "P5E_CPU1_G1_RX_DN<1>")
	)
	(segment
		(start 109.276388 -224.575878)
		(end 109.283246 -224.579942)
		(width 0.1143)
		(layer "In4.Cu")
		(net "P5E_CPU1_G1_RX_DN<1>")
	)
	(segment
		(start 54.494938 -18.916396)
		(end 54.51094 -18.99666)
		(width 0.14224)
		(layer "In4.Cu")
		(net "P5E_CPU1_G1_RX_DN<1>")
	)
	(segment
		(start 109.71403 -225.367088)
		(end 109.753146 -225.389948)
		(width 0.1143)
		(layer "In4.Cu")
		(net "P5E_CPU1_G1_RX_DN<1>")
	)
	(segment
		(start 109.237526 -224.553272)
		(end 109.238288 -224.55378)
		(width 0.1143)
		(layer "In4.Cu")
		(net "P5E_CPU1_G1_RX_DN<1>")
	)
	(segment
		(start 109.572044 -221.304358)
		(end 109.572044 -221.332806)
		(width 0.1143)
		(layer "In4.Cu")
		(net "P5E_CPU1_G1_RX_DN<1>")
	)
	(segment
		(start 109.693202 -232.835704)
		(end 109.66323 -232.85577)
		(width 0.1143)
		(layer "In4.Cu")
		(net "P5E_CPU1_G1_RX_DN<1>")
	)
	(segment
		(start 109.282738 -223.88957)
		(end 109.210856 -223.93148)
		(width 0.1143)
		(layer "In4.Cu")
		(net "P5E_CPU1_G1_RX_DN<1>")
	)
	(segment
		(start 109.521752 -233.131614)
		(end 109.521752 -233.132122)
		(width 0.1143)
		(layer "In4.Cu")
		(net "P5E_CPU1_G1_RX_DN<1>")
	)
	(segment
		(start 109.133132 -233.95432)
		(end 109.431074 -233.95432)
		(width 0.1143)
		(layer "In4.Cu")
		(net "P5E_CPU1_G1_RX_DN<1>")
	)
	(segment
		(start 110.220252 -228.750876)
		(end 110.18393 -228.771958)
		(width 0.1143)
		(layer "In4.Cu")
		(net "P5E_CPU1_G1_RX_DN<1>")
	)
	(arc
		(start 109.66323 -232.85577)
		(mid 109.559336 -232.97679)
		(end 109.522006 -233.131868)
		(width 0.1143)
		(layer "In4.Cu")
		(net "P5E_CPU1_G1_RX_DN<1>")
	)
	(arc
		(start 109.526578 -223.423734)
		(mid 109.464544 -223.682046)
		(end 109.291374 -223.883474)
		(width 0.1143)
		(layer "In4.Cu")
		(net "P5E_CPU1_G1_RX_DN<1>")
	)
	(arc
		(start 110.388654 -231.811322)
		(mid 110.29998 -231.925879)
		(end 110.1852 -232.014268)
		(width 0.1143)
		(layer "In4.Cu")
		(net "P5E_CPU1_G1_RX_DN<1>")
	)
	(arc
		(start 110.466124 -229.91064)
		(mid 110.400837 -230.161581)
		(end 110.234476 -230.360474)
		(width 0.1143)
		(layer "In4.Cu")
		(net "P5E_CPU1_G1_RX_DN<1>")
	)
	(arc
		(start 110.466378 -231.524302)
		(mid 110.446622 -231.672982)
		(end 110.388654 -231.811322)
		(width 0.1143)
		(layer "In4.Cu")
		(net "P5E_CPU1_G1_RX_DN<1>")
	)
	(arc
		(start 109.521752 -233.132122)
		(mid 109.443809 -233.424861)
		(end 109.230414 -233.639868)
		(width 0.1143)
		(layer "In4.Cu")
		(net "P5E_CPU1_G1_RX_DN<1>")
	)
	(arc
		(start 110.187232 -231.041702)
		(mid 110.391378 -231.24561)
		(end 110.466124 -231.524302)
		(width 0.1143)
		(layer "In4.Cu")
		(net "P5E_CPU1_G1_RX_DN<1>")
	)
	(arc
		(start 110.154212 -230.408988)
		(mid 110.038031 -230.542547)
		(end 109.996224 -230.71455)
		(width 0.1143)
		(layer "In4.Cu")
		(net "P5E_CPU1_G1_RX_DN<1>")
	)
	(arc
		(start 109.291374 -223.883474)
		(mid 109.28707 -223.886542)
		(end 109.282738 -223.88957)
		(width 0.1143)
		(layer "In4.Cu")
		(net "P5E_CPU1_G1_RX_DN<1>")
	)
	(arc
		(start 109.996478 -229.094538)
		(mid 110.037444 -229.264944)
		(end 110.151418 -229.398068)
		(width 0.1143)
		(layer "In4.Cu")
		(net "P5E_CPU1_G1_RX_DN<1>")
	)
	(arc
		(start 110.15345 -227.169726)
		(mid 109.996473 -227.474526)
		(end 110.15345 -227.779326)
		(width 0.1143)
		(layer "In4.Cu")
		(net "P5E_CPU1_G1_RX_DN<1>")
	)
	(arc
		(start 109.996478 -225.854514)
		(mid 110.038027 -226.025936)
		(end 110.15345 -226.159314)
		(width 0.1143)
		(layer "In4.Cu")
		(net "P5E_CPU1_G1_RX_DN<1>")
	)
	(arc
		(start 110.220252 -227.818188)
		(mid 110.466142 -228.284532)
		(end 110.220252 -228.750876)
		(width 0.1143)
		(layer "In4.Cu")
		(net "P5E_CPU1_G1_RX_DN<1>")
	)
	(arc
		(start 109.283246 -224.579942)
		(mid 109.462059 -224.782292)
		(end 109.526578 -225.044508)
		(width 0.1143)
		(layer "In4.Cu")
		(net "P5E_CPU1_G1_RX_DN<1>")
	)
	(arc
		(start 109.753146 -225.389948)
		(mid 109.931959 -225.592298)
		(end 109.996478 -225.854514)
		(width 0.1143)
		(layer "In4.Cu")
		(net "P5E_CPU1_G1_RX_DN<1>")
	)
	(arc
		(start 109.996224 -230.71455)
		(mid 110.045554 -230.900455)
		(end 110.180374 -231.037638)
		(width 0.1143)
		(layer "In4.Cu")
		(net "P5E_CPU1_G1_RX_DN<1>")
	)
	(arc
		(start 109.21238 -233.650028)
		(mid 109.115245 -233.752897)
		(end 109.063282 -233.88447)
		(width 0.1143)
		(layer "In4.Cu")
		(net "P5E_CPU1_G1_RX_DN<1>")
	)
	(arc
		(start 110.179104 -232.017824)
		(mid 110.04587 -232.151889)
		(end 109.996478 -232.334308)
		(width 0.1143)
		(layer "In4.Cu")
		(net "P5E_CPU1_G1_RX_DN<1>")
	)
	(arc
		(start 110.234476 -230.360474)
		(mid 110.226023 -230.366523)
		(end 110.217458 -230.372412)
		(width 0.1143)
		(layer "In4.Cu")
		(net "P5E_CPU1_G1_RX_DN<1>")
	)
	(arc
		(start 110.220252 -226.198176)
		(mid 110.466142 -226.66452)
		(end 110.220252 -227.130864)
		(width 0.1143)
		(layer "In4.Cu")
		(net "P5E_CPU1_G1_RX_DN<1>")
	)
	(arc
		(start 110.195106 -229.423214)
		(mid 110.398282 -229.6293)
		(end 110.466124 -229.91064)
		(width 0.1143)
		(layer "In4.Cu")
		(net "P5E_CPU1_G1_RX_DN<1>")
	)
	(arc
		(start 109.996478 -232.334308)
		(mid 109.919613 -232.617154)
		(end 109.712506 -232.824528)
		(width 0.1143)
		(layer "In4.Cu")
		(net "P5E_CPU1_G1_RX_DN<1>")
	)
	(arc
		(start 110.15345 -228.789738)
		(mid 110.038023 -228.923114)
		(end 109.996478 -229.094538)
		(width 0.1143)
		(layer "In4.Cu")
		(net "P5E_CPU1_G1_RX_DN<1>")
	)
	(arc
		(start 109.210856 -223.93148)
		(mid 109.056589 -224.235491)
		(end 109.21238 -224.538794)
		(width 0.1143)
		(layer "In4.Cu")
		(net "P5E_CPU1_G1_RX_DN<1>")
	)
	(arc
		(start 109.526578 -225.044508)
		(mid 109.568127 -225.21593)
		(end 109.68355 -225.349308)
		(width 0.1143)
		(layer "In4.Cu")
		(net "P5E_CPU1_G1_RX_DN<1>")
	)
	(segment
		(start 109.897926 -232.600246)
		(end 109.431074 -232.334308)
		(width 0.12954)
		(layer "F.Cu")
		(net "P5E_CPU1_G1_RX_DN<2>")
	)
	(segment
		(start 52.80406 -4.963414)
		(end 52.528216 -5.239258)
		(width 0.12954)
		(layer "F.Cu")
		(net "P5E_CPU1_G1_RX_DN<2>")
	)
	(segment
		(start 52.6669 -7.709662)
		(end 52.6669 -8.320024)
		(width 0.12954)
		(layer "F.Cu")
		(net "P5E_CPU1_G1_RX_DN<2>")
	)
	(segment
		(start 52.667154 -7.709408)
		(end 52.6669 -7.709662)
		(width 0.12954)
		(layer "F.Cu")
		(net "P5E_CPU1_G1_RX_DN<2>")
	)
	(segment
		(start 52.528216 -5.239258)
		(end 52.528216 -7.57047)
		(width 0.12954)
		(layer "F.Cu")
		(net "P5E_CPU1_G1_RX_DN<2>")
	)
	(segment
		(start 52.528216 -7.57047)
		(end 52.667154 -7.709408)
		(width 0.12954)
		(layer "F.Cu")
		(net "P5E_CPU1_G1_RX_DN<2>")
	)
	(segment
		(start 151.288242 -177.00879)
		(end 112.846104 -208.529936)
		(width 0.14224)
		(layer "In4.Cu")
		(net "P5E_CPU1_G1_RX_DN<2>")
	)
	(segment
		(start 108.627164 -221.304358)
		(end 108.627164 -221.332806)
		(width 0.1143)
		(layer "In4.Cu")
		(net "P5E_CPU1_G1_RX_DN<2>")
	)
	(segment
		(start 108.74248 -225.348546)
		(end 108.813092 -225.389948)
		(width 0.1143)
		(layer "In4.Cu")
		(net "P5E_CPU1_G1_RX_DN<2>")
	)
	(segment
		(start 108.305092 -222.291402)
		(end 108.304076 -222.29191)
		(width 0.1143)
		(layer "In4.Cu")
		(net "P5E_CPU1_G1_RX_DN<2>")
	)
	(segment
		(start 108.344462 -223.8883)
		(end 108.344462 -223.888554)
		(width 0.1143)
		(layer "In4.Cu")
		(net "P5E_CPU1_G1_RX_DN<2>")
	)
	(segment
		(start 109.238796 -228.775006)
		(end 109.238034 -228.775514)
		(width 0.1143)
		(layer "In4.Cu")
		(net "P5E_CPU1_G1_RX_DN<2>")
	)
	(segment
		(start 108.272326 -222.310198)
		(end 108.269278 -222.312484)
		(width 0.1143)
		(layer "In4.Cu")
		(net "P5E_CPU1_G1_RX_DN<2>")
	)
	(segment
		(start 109.240574 -230.394002)
		(end 109.21238 -230.410258)
		(width 0.1143)
		(layer "In4.Cu")
		(net "P5E_CPU1_G1_RX_DN<2>")
	)
	(segment
		(start 109.231938 -227.789994)
		(end 109.2327 -227.790502)
		(width 0.1143)
		(layer "In4.Cu")
		(net "P5E_CPU1_G1_RX_DN<2>")
	)
	(segment
		(start 157.393894 -164.617908)
		(end 155.304236 -170.75404)
		(width 0.14224)
		(layer "In4.Cu")
		(net "P5E_CPU1_G1_RX_DN<2>")
	)
	(segment
		(start 109.24159 -227.795582)
		(end 109.242352 -227.79609)
		(width 0.1143)
		(layer "In4.Cu")
		(net "P5E_CPU1_G1_RX_DN<2>")
	)
	(segment
		(start 155.14955 -171.24553)
		(end 155.046934 -171.547282)
		(width 0.14224)
		(layer "In4.Cu")
		(net "P5E_CPU1_G1_RX_DN<2>")
	)
	(segment
		(start 108.269278 -222.916496)
		(end 108.272326 -222.918782)
		(width 0.1143)
		(layer "In4.Cu")
		(net "P5E_CPU1_G1_RX_DN<2>")
	)
	(segment
		(start 109.239812 -228.774498)
		(end 109.238796 -228.775006)
		(width 0.1143)
		(layer "In4.Cu")
		(net "P5E_CPU1_G1_RX_DN<2>")
	)
	(segment
		(start 109.24413 -232.011728)
		(end 109.21238 -232.030016)
		(width 0.1143)
		(layer "In4.Cu")
		(net "P5E_CPU1_G1_RX_DN<2>")
	)
	(segment
		(start 151.667718 -135.367268)
		(end 151.961596 -135.975344)
		(width 0.14224)
		(layer "In4.Cu")
		(net "P5E_CPU1_G1_RX_DN<2>")
	)
	(segment
		(start 59.312048 -52.49037)
		(end 60.46216 -53.434996)
		(width 0.14224)
		(layer "In4.Cu")
		(net "P5E_CPU1_G1_RX_DN<2>")
	)
	(segment
		(start 155.046934 -171.547282)
		(end 155.04668 -171.547282)
		(width 0.14224)
		(layer "In4.Cu")
		(net "P5E_CPU1_G1_RX_DN<2>")
	)
	(segment
		(start 109.238542 -227.793804)
		(end 109.24032 -227.79482)
		(width 0.1143)
		(layer "In4.Cu")
		(net "P5E_CPU1_G1_RX_DN<2>")
	)
	(segment
		(start 109.244892 -227.151438)
		(end 109.24413 -227.151946)
		(width 0.1143)
		(layer "In4.Cu")
		(net "P5E_CPU1_G1_RX_DN<2>")
	)
	(segment
		(start 109.237526 -227.793296)
		(end 109.238542 -227.793804)
		(width 0.1143)
		(layer "In4.Cu")
		(net "P5E_CPU1_G1_RX_DN<2>")
	)
	(segment
		(start 108.304076 -222.93707)
		(end 108.344462 -222.960692)
		(width 0.1143)
		(layer "In4.Cu")
		(net "P5E_CPU1_G1_RX_DN<2>")
	)
	(segment
		(start 155.04668 -171.547282)
		(end 154.931872 -171.885102)
		(width 0.14224)
		(layer "In4.Cu")
		(net "P5E_CPU1_G1_RX_DN<2>")
	)
	(segment
		(start 51.69535 -17.764252)
		(end 51.69535 -17.76476)
		(width 0.14224)
		(layer "In4.Cu")
		(net "P5E_CPU1_G1_RX_DN<2>")
	)
	(segment
		(start 108.303314 -224.556574)
		(end 108.3056 -224.558098)
		(width 0.1143)
		(layer "In4.Cu")
		(net "P5E_CPU1_G1_RX_DN<2>")
	)
	(segment
		(start 108.581444 -221.558358)
		(end 108.586524 -221.563438)
		(width 0.1143)
		(layer "In4.Cu")
		(net "P5E_CPU1_G1_RX_DN<2>")
	)
	(segment
		(start 51.010566 -19.788378)
		(end 51.036982 -19.980656)
		(width 0.14224)
		(layer "In4.Cu")
		(net "P5E_CPU1_G1_RX_DN<2>")
	)
	(segment
		(start 109.244638 -230.391208)
		(end 109.243876 -230.391716)
		(width 0.1143)
		(layer "In4.Cu")
		(net "P5E_CPU1_G1_RX_DN<2>")
	)
	(segment
		(start 109.242352 -227.79609)
		(end 109.243368 -227.796598)
		(width 0.1143)
		(layer "In4.Cu")
		(net "P5E_CPU1_G1_RX_DN<2>")
	)
	(segment
		(start 109.243876 -230.391716)
		(end 109.24413 -230.39197)
		(width 0.1143)
		(layer "In4.Cu")
		(net "P5E_CPU1_G1_RX_DN<2>")
	)
	(segment
		(start 108.3056 -224.558098)
		(end 108.342938 -224.579688)
		(width 0.1143)
		(layer "In4.Cu")
		(net "P5E_CPU1_G1_RX_DN<2>")
	)
	(segment
		(start 109.21238 -226.158806)
		(end 109.237526 -226.173284)
		(width 0.1143)
		(layer "In4.Cu")
		(net "P5E_CPU1_G1_RX_DN<2>")
	)
	(segment
		(start 51.07051 -18.90649)
		(end 50.9778 -19.087846)
		(width 0.14224)
		(layer "In4.Cu")
		(net "P5E_CPU1_G1_RX_DN<2>")
	)
	(segment
		(start 109.239304 -226.1743)
		(end 109.24413 -226.177094)
		(width 0.1143)
		(layer "In4.Cu")
		(net "P5E_CPU1_G1_RX_DN<2>")
	)
	(segment
		(start 109.24159 -228.773482)
		(end 109.240574 -228.77399)
		(width 0.1143)
		(layer "In4.Cu")
		(net "P5E_CPU1_G1_RX_DN<2>")
	)
	(segment
		(start 109.234478 -228.777292)
		(end 109.21238 -228.790246)
		(width 0.1143)
		(layer "In4.Cu")
		(net "P5E_CPU1_G1_RX_DN<2>")
	)
	(segment
		(start 109.24413 -229.416864)
		(end 109.280452 -229.437946)
		(width 0.1143)
		(layer "In4.Cu")
		(net "P5E_CPU1_G1_RX_DN<2>")
	)
	(segment
		(start 108.581444 -221.378526)
		(end 108.581444 -221.558358)
		(width 0.1143)
		(layer "In4.Cu")
		(net "P5E_CPU1_G1_RX_DN<2>")
	)
	(segment
		(start 109.210602 -229.397306)
		(end 109.24413 -229.416864)
		(width 0.1143)
		(layer "In4.Cu")
		(net "P5E_CPU1_G1_RX_DN<2>")
	)
	(segment
		(start 52.80406 -4.963414)
		(end 52.51323 -5.254244)
		(width 0.14224)
		(layer "In4.Cu")
		(net "P5E_CPU1_G1_RX_DN<2>")
	)
	(segment
		(start 109.24413 -228.771958)
		(end 109.243368 -228.772466)
		(width 0.1143)
		(layer "In4.Cu")
		(net "P5E_CPU1_G1_RX_DN<2>")
	)
	(segment
		(start 154.931872 -171.885102)
		(end 151.288242 -177.00879)
		(width 0.14224)
		(layer "In4.Cu")
		(net "P5E_CPU1_G1_RX_DN<2>")
	)
	(segment
		(start 109.228636 -227.788216)
		(end 109.229652 -227.788724)
		(width 0.1143)
		(layer "In4.Cu")
		(net "P5E_CPU1_G1_RX_DN<2>")
	)
	(segment
		(start 108.306616 -222.290386)
		(end 108.305092 -222.291402)
		(width 0.1143)
		(layer "In4.Cu")
		(net "P5E_CPU1_G1_RX_DN<2>")
	)
	(segment
		(start 109.210602 -231.017318)
		(end 109.243368 -231.036368)
		(width 0.1143)
		(layer "In4.Cu")
		(net "P5E_CPU1_G1_RX_DN<2>")
	)
	(segment
		(start 108.274104 -223.929194)
		(end 108.272326 -223.930464)
		(width 0.1143)
		(layer "In4.Cu")
		(net "P5E_CPU1_G1_RX_DN<2>")
	)
	(segment
		(start 51.010312 -19.779488)
		(end 51.010566 -19.788378)
		(width 0.14224)
		(layer "In4.Cu")
		(net "P5E_CPU1_G1_RX_DN<2>")
	)
	(segment
		(start 108.58627 -225.042476)
		(end 108.58627 -225.044508)
		(width 0.1143)
		(layer "In4.Cu")
		(net "P5E_CPU1_G1_RX_DN<2>")
	)
	(segment
		(start 109.24413 -227.797106)
		(end 109.244638 -227.797106)
		(width 0.1143)
		(layer "In4.Cu")
		(net "P5E_CPU1_G1_RX_DN<2>")
	)
	(segment
		(start 61.366908 -54.247796)
		(end 62.656974 -55.327804)
		(width 0.14224)
		(layer "In4.Cu")
		(net "P5E_CPU1_G1_RX_DN<2>")
	)
	(segment
		(start 112.846104 -208.529936)
		(end 108.627164 -215.635586)
		(width 0.14224)
		(layer "In4.Cu")
		(net "P5E_CPU1_G1_RX_DN<2>")
	)
	(segment
		(start 156.496512 -145.364454)
		(end 157.393894 -159.7279)
		(width 0.14224)
		(layer "In4.Cu")
		(net "P5E_CPU1_G1_RX_DN<2>")
	)
	(segment
		(start 51.389534 -18.375122)
		(end 51.07051 -18.90649)
		(width 0.14224)
		(layer "In4.Cu")
		(net "P5E_CPU1_G1_RX_DN<2>")
	)
	(segment
		(start 109.229652 -227.788724)
		(end 109.230922 -227.789486)
		(width 0.1143)
		(layer "In4.Cu")
		(net "P5E_CPU1_G1_RX_DN<2>")
	)
	(segment
		(start 62.656974 -55.327804)
		(end 151.667718 -135.367268)
		(width 0.14224)
		(layer "In4.Cu")
		(net "P5E_CPU1_G1_RX_DN<2>")
	)
	(segment
		(start 108.342938 -224.579688)
		(end 108.35259 -224.586546)
		(width 0.1143)
		(layer "In4.Cu")
		(net "P5E_CPU1_G1_RX_DN<2>")
	)
	(segment
		(start 109.238542 -226.173792)
		(end 109.239304 -226.1743)
		(width 0.1143)
		(layer "In4.Cu")
		(net "P5E_CPU1_G1_RX_DN<2>")
	)
	(segment
		(start 109.234986 -227.791772)
		(end 109.236764 -227.792788)
		(width 0.1143)
		(layer "In4.Cu")
		(net "P5E_CPU1_G1_RX_DN<2>")
	)
	(segment
		(start 108.627164 -221.332806)
		(end 108.581444 -221.378526)
		(width 0.1143)
		(layer "In4.Cu")
		(net "P5E_CPU1_G1_RX_DN<2>")
	)
	(segment
		(start 109.21238 -227.778818)
		(end 109.228636 -227.788216)
		(width 0.1143)
		(layer "In4.Cu")
		(net "P5E_CPU1_G1_RX_DN<2>")
	)
	(segment
		(start 155.304236 -170.75404)
		(end 155.14955 -171.24553)
		(width 0.14224)
		(layer "In4.Cu")
		(net "P5E_CPU1_G1_RX_DN<2>")
	)
	(segment
		(start 51.69535 -17.76476)
		(end 51.624738 -17.935702)
		(width 0.14224)
		(layer "In4.Cu")
		(net "P5E_CPU1_G1_RX_DN<2>")
	)
	(segment
		(start 109.2327 -227.790502)
		(end 109.234224 -227.791264)
		(width 0.1143)
		(layer "In4.Cu")
		(net "P5E_CPU1_G1_RX_DN<2>")
	)
	(segment
		(start 50.9778 -19.087846)
		(end 50.991516 -19.3802)
		(width 0.14224)
		(layer "In4.Cu")
		(net "P5E_CPU1_G1_RX_DN<2>")
	)
	(segment
		(start 51.036982 -19.980656)
		(end 57.219088 -48.879506)
		(width 0.14224)
		(layer "In4.Cu")
		(net "P5E_CPU1_G1_RX_DN<2>")
	)
	(segment
		(start 50.991516 -19.3802)
		(end 51.010312 -19.779488)
		(width 0.14224)
		(layer "In4.Cu")
		(net "P5E_CPU1_G1_RX_DN<2>")
	)
	(segment
		(start 109.24413 -227.151946)
		(end 109.21238 -227.170234)
		(width 0.1143)
		(layer "In4.Cu")
		(net "P5E_CPU1_G1_RX_DN<2>")
	)
	(segment
		(start 108.30052 -224.555304)
		(end 108.303314 -224.556574)
		(width 0.1143)
		(layer "In4.Cu")
		(net "P5E_CPU1_G1_RX_DN<2>")
	)
	(segment
		(start 109.244638 -228.771958)
		(end 109.24413 -228.771958)
		(width 0.1143)
		(layer "In4.Cu")
		(net "P5E_CPU1_G1_RX_DN<2>")
	)
	(segment
		(start 109.238034 -228.775514)
		(end 109.234478 -228.777292)
		(width 0.1143)
		(layer "In4.Cu")
		(net "P5E_CPU1_G1_RX_DN<2>")
	)
	(segment
		(start 108.34243 -223.889824)
		(end 108.274104 -223.929194)
		(width 0.1143)
		(layer "In4.Cu")
		(net "P5E_CPU1_G1_RX_DN<2>")
	)
	(segment
		(start 108.272326 -222.918782)
		(end 108.304076 -222.93707)
		(width 0.1143)
		(layer "In4.Cu")
		(net "P5E_CPU1_G1_RX_DN<2>")
	)
	(segment
		(start 109.237526 -226.173284)
		(end 109.238542 -226.173792)
		(width 0.1143)
		(layer "In4.Cu")
		(net "P5E_CPU1_G1_RX_DN<2>")
	)
	(segment
		(start 108.116624 -224.2312)
		(end 108.11637 -224.233232)
		(width 0.1143)
		(layer "In4.Cu")
		(net "P5E_CPU1_G1_RX_DN<2>")
	)
	(segment
		(start 108.586524 -221.563438)
		(end 108.586524 -221.804484)
		(width 0.1143)
		(layer "In4.Cu")
		(net "P5E_CPU1_G1_RX_DN<2>")
	)
	(segment
		(start 108.343192 -222.26905)
		(end 108.306616 -222.290386)
		(width 0.1143)
		(layer "In4.Cu")
		(net "P5E_CPU1_G1_RX_DN<2>")
	)
	(segment
		(start 109.243368 -231.036368)
		(end 109.24413 -231.036876)
		(width 0.1143)
		(layer "In4.Cu")
		(net "P5E_CPU1_G1_RX_DN<2>")
	)
	(segment
		(start 108.11637 -224.233232)
		(end 108.11637 -224.234502)
		(width 0.1143)
		(layer "In4.Cu")
		(net "P5E_CPU1_G1_RX_DN<2>")
	)
	(segment
		(start 151.961596 -135.975344)
		(end 151.95931 -135.981948)
		(width 0.14224)
		(layer "In4.Cu")
		(net "P5E_CPU1_G1_RX_DN<2>")
	)
	(segment
		(start 109.063282 -232.264458)
		(end 109.133132 -232.334308)
		(width 0.1143)
		(layer "In4.Cu")
		(net "P5E_CPU1_G1_RX_DN<2>")
	)
	(segment
		(start 109.243368 -230.392478)
		(end 109.242098 -230.39324)
		(width 0.1143)
		(layer "In4.Cu")
		(net "P5E_CPU1_G1_RX_DN<2>")
	)
	(segment
		(start 57.219088 -48.879506)
		(end 59.312048 -52.49037)
		(width 0.14224)
		(layer "In4.Cu")
		(net "P5E_CPU1_G1_RX_DN<2>")
	)
	(segment
		(start 109.242352 -228.772974)
		(end 109.24159 -228.773482)
		(width 0.1143)
		(layer "In4.Cu")
		(net "P5E_CPU1_G1_RX_DN<2>")
	)
	(segment
		(start 109.243368 -228.772466)
		(end 109.242352 -228.772974)
		(width 0.1143)
		(layer "In4.Cu")
		(net "P5E_CPU1_G1_RX_DN<2>")
	)
	(segment
		(start 52.51323 -5.254244)
		(end 52.51323 -13.652246)
		(width 0.14224)
		(layer "In4.Cu")
		(net "P5E_CPU1_G1_RX_DN<2>")
	)
	(segment
		(start 109.242098 -230.39324)
		(end 109.240574 -230.394002)
		(width 0.1143)
		(layer "In4.Cu")
		(net "P5E_CPU1_G1_RX_DN<2>")
	)
	(segment
		(start 52.51323 -13.652246)
		(end 51.69535 -17.764252)
		(width 0.14224)
		(layer "In4.Cu")
		(net "P5E_CPU1_G1_RX_DN<2>")
	)
	(segment
		(start 109.240574 -228.77399)
		(end 109.239812 -228.774498)
		(width 0.1143)
		(layer "In4.Cu")
		(net "P5E_CPU1_G1_RX_DN<2>")
	)
	(segment
		(start 109.236764 -227.792788)
		(end 109.237526 -227.793296)
		(width 0.1143)
		(layer "In4.Cu")
		(net "P5E_CPU1_G1_RX_DN<2>")
	)
	(segment
		(start 109.230922 -227.789486)
		(end 109.231938 -227.789994)
		(width 0.1143)
		(layer "In4.Cu")
		(net "P5E_CPU1_G1_RX_DN<2>")
	)
	(segment
		(start 109.243368 -227.796598)
		(end 109.24413 -227.797106)
		(width 0.1143)
		(layer "In4.Cu")
		(net "P5E_CPU1_G1_RX_DN<2>")
	)
	(segment
		(start 109.24032 -227.79482)
		(end 109.24159 -227.795582)
		(width 0.1143)
		(layer "In4.Cu")
		(net "P5E_CPU1_G1_RX_DN<2>")
	)
	(segment
		(start 157.393894 -159.7279)
		(end 157.393894 -164.617908)
		(width 0.14224)
		(layer "In4.Cu")
		(net "P5E_CPU1_G1_RX_DN<2>")
	)
	(segment
		(start 60.46216 -53.434996)
		(end 61.366908 -54.247796)
		(width 0.14224)
		(layer "In4.Cu")
		(net "P5E_CPU1_G1_RX_DN<2>")
	)
	(segment
		(start 108.300012 -224.55505)
		(end 108.30052 -224.555304)
		(width 0.1143)
		(layer "In4.Cu")
		(net "P5E_CPU1_G1_RX_DN<2>")
	)
	(segment
		(start 51.624738 -17.935702)
		(end 51.389534 -18.375122)
		(width 0.14224)
		(layer "In4.Cu")
		(net "P5E_CPU1_G1_RX_DN<2>")
	)
	(segment
		(start 109.234224 -227.791264)
		(end 109.234986 -227.791772)
		(width 0.1143)
		(layer "In4.Cu")
		(net "P5E_CPU1_G1_RX_DN<2>")
	)
	(segment
		(start 151.95931 -135.981948)
		(end 156.496512 -145.364454)
		(width 0.14224)
		(layer "In4.Cu")
		(net "P5E_CPU1_G1_RX_DN<2>")
	)
	(segment
		(start 109.133132 -232.334308)
		(end 109.431074 -232.334308)
		(width 0.1143)
		(layer "In4.Cu")
		(net "P5E_CPU1_G1_RX_DN<2>")
	)
	(segment
		(start 109.24413 -230.39197)
		(end 109.243368 -230.392478)
		(width 0.1143)
		(layer "In4.Cu")
		(net "P5E_CPU1_G1_RX_DN<2>")
	)
	(segment
		(start 108.627164 -215.635586)
		(end 108.627164 -221.304358)
		(width 0.14224)
		(layer "In4.Cu")
		(net "P5E_CPU1_G1_RX_DN<2>")
	)
	(segment
		(start 108.304076 -222.29191)
		(end 108.272326 -222.310198)
		(width 0.1143)
		(layer "In4.Cu")
		(net "P5E_CPU1_G1_RX_DN<2>")
	)
	(segment
		(start 109.24413 -226.177094)
		(end 109.244892 -226.177602)
		(width 0.1143)
		(layer "In4.Cu")
		(net "P5E_CPU1_G1_RX_DN<2>")
	)
	(arc
		(start 109.056424 -225.854514)
		(mid 109.097679 -226.025485)
		(end 109.21238 -226.158806)
		(width 0.1143)
		(layer "In4.Cu")
		(net "P5E_CPU1_G1_RX_DN<2>")
	)
	(arc
		(start 109.526324 -229.90429)
		(mid 109.450822 -230.185542)
		(end 109.244638 -230.391208)
		(width 0.1143)
		(layer "In4.Cu")
		(net "P5E_CPU1_G1_RX_DN<2>")
	)
	(arc
		(start 108.56849 -221.946724)
		(mid 108.484749 -222.128084)
		(end 108.343192 -222.26905)
		(width 0.1143)
		(layer "In4.Cu")
		(net "P5E_CPU1_G1_RX_DN<2>")
	)
	(arc
		(start 109.280452 -229.437946)
		(mid 109.461104 -229.640691)
		(end 109.526324 -229.90429)
		(width 0.1143)
		(layer "In4.Cu")
		(net "P5E_CPU1_G1_RX_DN<2>")
	)
	(arc
		(start 108.58627 -225.044508)
		(mid 108.627668 -225.215382)
		(end 108.74248 -225.348546)
		(width 0.1143)
		(layer "In4.Cu")
		(net "P5E_CPU1_G1_RX_DN<2>")
	)
	(arc
		(start 108.35259 -224.586546)
		(mid 108.524455 -224.78631)
		(end 108.58627 -225.042476)
		(width 0.1143)
		(layer "In4.Cu")
		(net "P5E_CPU1_G1_RX_DN<2>")
	)
	(arc
		(start 108.586524 -221.804484)
		(mid 108.582023 -221.876176)
		(end 108.56849 -221.946724)
		(width 0.1143)
		(layer "In4.Cu")
		(net "P5E_CPU1_G1_RX_DN<2>")
	)
	(arc
		(start 108.813092 -225.389948)
		(mid 108.991905 -225.592298)
		(end 109.056424 -225.854514)
		(width 0.1143)
		(layer "In4.Cu")
		(net "P5E_CPU1_G1_RX_DN<2>")
	)
	(arc
		(start 109.24413 -231.036876)
		(mid 109.524777 -231.524302)
		(end 109.24413 -232.011728)
		(width 0.1143)
		(layer "In4.Cu")
		(net "P5E_CPU1_G1_RX_DN<2>")
	)
	(arc
		(start 109.244638 -227.797106)
		(mid 109.525285 -228.284532)
		(end 109.244638 -228.771958)
		(width 0.1143)
		(layer "In4.Cu")
		(net "P5E_CPU1_G1_RX_DN<2>")
	)
	(arc
		(start 109.21238 -232.030016)
		(mid 109.115245 -232.132885)
		(end 109.063282 -232.264458)
		(width 0.1143)
		(layer "In4.Cu")
		(net "P5E_CPU1_G1_RX_DN<2>")
	)
	(arc
		(start 108.344462 -222.960692)
		(mid 108.522527 -223.162869)
		(end 108.586778 -223.424496)
		(width 0.1143)
		(layer "In4.Cu")
		(net "P5E_CPU1_G1_RX_DN<2>")
	)
	(arc
		(start 109.21238 -228.790246)
		(mid 109.097704 -228.92358)
		(end 109.056424 -229.094538)
		(width 0.1143)
		(layer "In4.Cu")
		(net "P5E_CPU1_G1_RX_DN<2>")
	)
	(arc
		(start 108.272326 -223.930464)
		(mid 108.161821 -224.06393)
		(end 108.116624 -224.2312)
		(width 0.1143)
		(layer "In4.Cu")
		(net "P5E_CPU1_G1_RX_DN<2>")
	)
	(arc
		(start 109.056424 -230.71455)
		(mid 109.097186 -230.884434)
		(end 109.210602 -231.017318)
		(width 0.1143)
		(layer "In4.Cu")
		(net "P5E_CPU1_G1_RX_DN<2>")
	)
	(arc
		(start 109.21238 -230.410258)
		(mid 109.097704 -230.543592)
		(end 109.056424 -230.71455)
		(width 0.1143)
		(layer "In4.Cu")
		(net "P5E_CPU1_G1_RX_DN<2>")
	)
	(arc
		(start 108.586778 -223.424496)
		(mid 108.522485 -223.686101)
		(end 108.344462 -223.8883)
		(width 0.1143)
		(layer "In4.Cu")
		(net "P5E_CPU1_G1_RX_DN<2>")
	)
	(arc
		(start 109.244892 -226.177602)
		(mid 109.525226 -226.66452)
		(end 109.244892 -227.151438)
		(width 0.1143)
		(layer "In4.Cu")
		(net "P5E_CPU1_G1_RX_DN<2>")
	)
	(arc
		(start 108.11637 -224.234502)
		(mid 108.165531 -224.419218)
		(end 108.300012 -224.55505)
		(width 0.1143)
		(layer "In4.Cu")
		(net "P5E_CPU1_G1_RX_DN<2>")
	)
	(arc
		(start 108.344462 -223.888554)
		(mid 108.343447 -223.88919)
		(end 108.34243 -223.889824)
		(width 0.1143)
		(layer "In4.Cu")
		(net "P5E_CPU1_G1_RX_DN<2>")
	)
	(arc
		(start 108.269278 -222.312484)
		(mid 108.114466 -222.61449)
		(end 108.269278 -222.916496)
		(width 0.1143)
		(layer "In4.Cu")
		(net "P5E_CPU1_G1_RX_DN<2>")
	)
	(arc
		(start 109.21238 -227.170234)
		(mid 109.056452 -227.474526)
		(end 109.21238 -227.778818)
		(width 0.1143)
		(layer "In4.Cu")
		(net "P5E_CPU1_G1_RX_DN<2>")
	)
	(arc
		(start 109.056424 -229.094538)
		(mid 109.097186 -229.264422)
		(end 109.210602 -229.397306)
		(width 0.1143)
		(layer "In4.Cu")
		(net "P5E_CPU1_G1_RX_DN<2>")
	)
	(segment
		(start 50.728372 -7.57047)
		(end 50.728372 -6.996176)
		(width 0.12954)
		(layer "F.Cu")
		(net "P5E_CPU1_G1_RX_DN<3>")
	)
	(segment
		(start 50.867056 -7.709154)
		(end 50.728372 -7.57047)
		(width 0.12954)
		(layer "F.Cu")
		(net "P5E_CPU1_G1_RX_DN<3>")
	)
	(segment
		(start 50.728372 -6.996176)
		(end 50.99939 -6.725158)
		(width 0.12954)
		(layer "F.Cu")
		(net "P5E_CPU1_G1_RX_DN<3>")
	)
	(segment
		(start 50.867056 -8.320024)
		(end 50.867056 -7.709154)
		(width 0.12954)
		(layer "F.Cu")
		(net "P5E_CPU1_G1_RX_DN<3>")
	)
	(segment
		(start 107.547918 -235.030264)
		(end 107.081066 -234.764326)
		(width 0.12954)
		(layer "F.Cu")
		(net "P5E_CPU1_G1_RX_DN<3>")
	)
	(segment
		(start 108.340652 -230.370634)
		(end 108.33608 -230.373428)
		(width 0.1143)
		(layer "In4.Cu")
		(net "P5E_CPU1_G1_RX_DN<3>")
	)
	(segment
		(start 108.303314 -227.152454)
		(end 108.302044 -227.153216)
		(width 0.1143)
		(layer "In4.Cu")
		(net "P5E_CPU1_G1_RX_DN<3>")
	)
	(segment
		(start 108.272326 -226.158806)
		(end 108.293662 -226.171252)
		(width 0.1143)
		(layer "In4.Cu")
		(net "P5E_CPU1_G1_RX_DN<3>")
	)
	(segment
		(start 108.305092 -228.77145)
		(end 108.304076 -228.771958)
		(width 0.1143)
		(layer "In4.Cu")
		(net "P5E_CPU1_G1_RX_DN<3>")
	)
	(segment
		(start 108.298234 -226.173792)
		(end 108.299758 -226.174554)
		(width 0.1143)
		(layer "In4.Cu")
		(net "P5E_CPU1_G1_RX_DN<3>")
	)
	(segment
		(start 108.299758 -226.174554)
		(end 108.30052 -226.175062)
		(width 0.1143)
		(layer "In4.Cu")
		(net "P5E_CPU1_G1_RX_DN<3>")
	)
	(segment
		(start 107.682538 -215.397334)
		(end 107.682538 -221.304358)
		(width 0.14224)
		(layer "In4.Cu")
		(net "P5E_CPU1_G1_RX_DN<3>")
	)
	(segment
		(start 106.783124 -234.764326)
		(end 107.081066 -234.764326)
		(width 0.1143)
		(layer "In4.Cu")
		(net "P5E_CPU1_G1_RX_DN<3>")
	)
	(segment
		(start 108.31068 -227.800916)
		(end 108.312204 -227.801932)
		(width 0.1143)
		(layer "In4.Cu")
		(net "P5E_CPU1_G1_RX_DN<3>")
	)
	(segment
		(start 108.306616 -230.390446)
		(end 108.305092 -230.391462)
		(width 0.1143)
		(layer "In4.Cu")
		(net "P5E_CPU1_G1_RX_DN<3>")
	)
	(segment
		(start 108.33608 -230.373428)
		(end 108.307632 -230.389938)
		(width 0.1143)
		(layer "In4.Cu")
		(net "P5E_CPU1_G1_RX_DN<3>")
	)
	(segment
		(start 108.303314 -226.176586)
		(end 108.304076 -226.177094)
		(width 0.1143)
		(layer "In4.Cu")
		(net "P5E_CPU1_G1_RX_DN<3>")
	)
	(segment
		(start 108.303314 -230.392478)
		(end 108.300012 -230.394256)
		(width 0.1143)
		(layer "In4.Cu")
		(net "P5E_CPU1_G1_RX_DN<3>")
	)
	(segment
		(start 108.303314 -228.772466)
		(end 108.302044 -228.773228)
		(width 0.1143)
		(layer "In4.Cu")
		(net "P5E_CPU1_G1_RX_DN<3>")
	)
	(segment
		(start 108.305092 -232.01122)
		(end 108.304076 -232.011728)
		(width 0.1143)
		(layer "In4.Cu")
		(net "P5E_CPU1_G1_RX_DN<3>")
	)
	(segment
		(start 108.305092 -226.177602)
		(end 108.306616 -226.178618)
		(width 0.1143)
		(layer "In4.Cu")
		(net "P5E_CPU1_G1_RX_DN<3>")
	)
	(segment
		(start 108.298234 -227.793804)
		(end 108.299758 -227.794566)
		(width 0.1143)
		(layer "In4.Cu")
		(net "P5E_CPU1_G1_RX_DN<3>")
	)
	(segment
		(start 108.293662 -227.791264)
		(end 108.296202 -227.792534)
		(width 0.1143)
		(layer "In4.Cu")
		(net "P5E_CPU1_G1_RX_DN<3>")
	)
	(segment
		(start 107.176824 -224.22612)
		(end 107.177586 -224.241106)
		(width 0.1143)
		(layer "In4.Cu")
		(net "P5E_CPU1_G1_RX_DN<3>")
	)
	(segment
		(start 108.296202 -227.792534)
		(end 108.297472 -227.793296)
		(width 0.1143)
		(layer "In4.Cu")
		(net "P5E_CPU1_G1_RX_DN<3>")
	)
	(segment
		(start 106.713274 -234.694476)
		(end 106.783124 -234.764326)
		(width 0.1143)
		(layer "In4.Cu")
		(net "P5E_CPU1_G1_RX_DN<3>")
	)
	(segment
		(start 108.307632 -230.389938)
		(end 108.306616 -230.390446)
		(width 0.1143)
		(layer "In4.Cu")
		(net "P5E_CPU1_G1_RX_DN<3>")
	)
	(segment
		(start 154.28214 -170.825668)
		(end 154.16403 -171.147232)
		(width 0.14224)
		(layer "In4.Cu")
		(net "P5E_CPU1_G1_RX_DN<3>")
	)
	(segment
		(start 108.272326 -227.778818)
		(end 108.293662 -227.791264)
		(width 0.1143)
		(layer "In4.Cu")
		(net "P5E_CPU1_G1_RX_DN<3>")
	)
	(segment
		(start 108.296202 -226.172522)
		(end 108.297472 -226.173284)
		(width 0.1143)
		(layer "In4.Cu")
		(net "P5E_CPU1_G1_RX_DN<3>")
	)
	(segment
		(start 49.318926 -20.255992)
		(end 55.95239 -48.763936)
		(width 0.14224)
		(layer "In4.Cu")
		(net "P5E_CPU1_G1_RX_DN<3>")
	)
	(segment
		(start 108.299504 -227.154486)
		(end 108.272326 -227.170234)
		(width 0.1143)
		(layer "In4.Cu")
		(net "P5E_CPU1_G1_RX_DN<3>")
	)
	(segment
		(start 108.304076 -230.39197)
		(end 108.303314 -230.392478)
		(width 0.1143)
		(layer "In4.Cu")
		(net "P5E_CPU1_G1_RX_DN<3>")
	)
	(segment
		(start 108.304076 -231.036876)
		(end 108.343192 -231.059736)
		(width 0.1143)
		(layer "In4.Cu")
		(net "P5E_CPU1_G1_RX_DN<3>")
	)
	(segment
		(start 108.306616 -226.178618)
		(end 108.30941 -226.180142)
		(width 0.1143)
		(layer "In4.Cu")
		(net "P5E_CPU1_G1_RX_DN<3>")
	)
	(segment
		(start 107.365038 -233.631232)
		(end 107.364022 -233.63174)
		(width 0.1143)
		(layer "In4.Cu")
		(net "P5E_CPU1_G1_RX_DN<3>")
	)
	(segment
		(start 48.183546 -17.70888)
		(end 48.227488 -17.815052)
		(width 0.14224)
		(layer "In4.Cu")
		(net "P5E_CPU1_G1_RX_DN<3>")
	)
	(segment
		(start 154.033982 -171.501562)
		(end 150.542244 -176.413668)
		(width 0.14224)
		(layer "In4.Cu")
		(net "P5E_CPU1_G1_RX_DN<3>")
	)
	(segment
		(start 107.366562 -233.630216)
		(end 107.365038 -233.631232)
		(width 0.1143)
		(layer "In4.Cu")
		(net "P5E_CPU1_G1_RX_DN<3>")
	)
	(segment
		(start 58.44794 -52.987194)
		(end 59.854338 -54.142386)
		(width 0.14224)
		(layer "In4.Cu")
		(net "P5E_CPU1_G1_RX_DN<3>")
	)
	(segment
		(start 108.303314 -232.012236)
		(end 108.302044 -232.012998)
		(width 0.1143)
		(layer "In4.Cu")
		(net "P5E_CPU1_G1_RX_DN<3>")
	)
	(segment
		(start 112.141762 -207.887316)
		(end 109.912404 -211.641944)
		(width 0.14224)
		(layer "In4.Cu")
		(net "P5E_CPU1_G1_RX_DN<3>")
	)
	(segment
		(start 109.91215 -211.642198)
		(end 107.682538 -215.397334)
		(width 0.14224)
		(layer "In4.Cu")
		(net "P5E_CPU1_G1_RX_DN<3>")
	)
	(segment
		(start 107.4039 -222.960184)
		(end 107.431586 -222.979996)
		(width 0.1143)
		(layer "In4.Cu")
		(net "P5E_CPU1_G1_RX_DN<3>")
	)
	(segment
		(start 109.912404 -211.641944)
		(end 109.91215 -211.642198)
		(width 0.14224)
		(layer "In4.Cu")
		(net "P5E_CPU1_G1_RX_DN<3>")
	)
	(segment
		(start 108.343192 -231.988868)
		(end 108.306616 -232.010204)
		(width 0.1143)
		(layer "In4.Cu")
		(net "P5E_CPU1_G1_RX_DN<3>")
	)
	(segment
		(start 106.930444 -234.420664)
		(end 106.920284 -234.426252)
		(width 0.1143)
		(layer "In4.Cu")
		(net "P5E_CPU1_G1_RX_DN<3>")
	)
	(segment
		(start 108.302044 -228.773228)
		(end 108.299504 -228.774498)
		(width 0.1143)
		(layer "In4.Cu")
		(net "P5E_CPU1_G1_RX_DN<3>")
	)
	(segment
		(start 108.29925 -230.394764)
		(end 108.298234 -230.395272)
		(width 0.1143)
		(layer "In4.Cu")
		(net "P5E_CPU1_G1_RX_DN<3>")
	)
	(segment
		(start 108.312204 -227.801932)
		(end 108.343192 -227.819966)
		(width 0.1143)
		(layer "In4.Cu")
		(net "P5E_CPU1_G1_RX_DN<3>")
	)
	(segment
		(start 108.300012 -230.394256)
		(end 108.29925 -230.394764)
		(width 0.1143)
		(layer "In4.Cu")
		(net "P5E_CPU1_G1_RX_DN<3>")
	)
	(segment
		(start 108.293662 -226.171252)
		(end 108.296202 -226.172522)
		(width 0.1143)
		(layer "In4.Cu")
		(net "P5E_CPU1_G1_RX_DN<3>")
	)
	(segment
		(start 108.302044 -232.012998)
		(end 108.299504 -232.014268)
		(width 0.1143)
		(layer "In4.Cu")
		(net "P5E_CPU1_G1_RX_DN<3>")
	)
	(segment
		(start 107.803442 -225.349308)
		(end 107.833922 -225.367088)
		(width 0.1143)
		(layer "In4.Cu")
		(net "P5E_CPU1_G1_RX_DN<3>")
	)
	(segment
		(start 108.31068 -226.180904)
		(end 108.312204 -226.18192)
		(width 0.1143)
		(layer "In4.Cu")
		(net "P5E_CPU1_G1_RX_DN<3>")
	)
	(segment
		(start 107.682538 -221.304358)
		(end 107.682538 -221.332806)
		(width 0.1143)
		(layer "In4.Cu")
		(net "P5E_CPU1_G1_RX_DN<3>")
	)
	(segment
		(start 107.682538 -221.332806)
		(end 107.636818 -221.378526)
		(width 0.1143)
		(layer "In4.Cu")
		(net "P5E_CPU1_G1_RX_DN<3>")
	)
	(segment
		(start 108.343192 -228.749098)
		(end 108.306616 -228.770434)
		(width 0.1143)
		(layer "In4.Cu")
		(net "P5E_CPU1_G1_RX_DN<3>")
	)
	(segment
		(start 107.334812 -224.53981)
		(end 107.400598 -224.578164)
		(width 0.1143)
		(layer "In4.Cu")
		(net "P5E_CPU1_G1_RX_DN<3>")
	)
	(segment
		(start 107.402376 -223.889824)
		(end 107.367578 -223.90989)
		(width 0.1143)
		(layer "In4.Cu")
		(net "P5E_CPU1_G1_RX_DN<3>")
	)
	(segment
		(start 50.70856 -12.409678)
		(end 48.742854 -16.566388)
		(width 0.14224)
		(layer "In4.Cu")
		(net "P5E_CPU1_G1_RX_DN<3>")
	)
	(segment
		(start 108.304076 -227.797106)
		(end 108.305092 -227.797614)
		(width 0.1143)
		(layer "In4.Cu")
		(net "P5E_CPU1_G1_RX_DN<3>")
	)
	(segment
		(start 107.636818 -221.558358)
		(end 107.646216 -221.567756)
		(width 0.1143)
		(layer "In4.Cu")
		(net "P5E_CPU1_G1_RX_DN<3>")
	)
	(segment
		(start 155.88615 -166.116254)
		(end 154.28214 -170.825668)
		(width 0.14224)
		(layer "In4.Cu")
		(net "P5E_CPU1_G1_RX_DN<3>")
	)
	(segment
		(start 108.312204 -226.18192)
		(end 108.343192 -226.199954)
		(width 0.1143)
		(layer "In4.Cu")
		(net "P5E_CPU1_G1_RX_DN<3>")
	)
	(segment
		(start 108.305092 -227.797614)
		(end 108.306616 -227.79863)
		(width 0.1143)
		(layer "In4.Cu")
		(net "P5E_CPU1_G1_RX_DN<3>")
	)
	(segment
		(start 108.305092 -227.151438)
		(end 108.304076 -227.151946)
		(width 0.1143)
		(layer "In4.Cu")
		(net "P5E_CPU1_G1_RX_DN<3>")
	)
	(segment
		(start 156.435298 -164.503862)
		(end 155.88615 -166.116762)
		(width 0.14224)
		(layer "In4.Cu")
		(net "P5E_CPU1_G1_RX_DN<3>")
	)
	(segment
		(start 108.30941 -226.180142)
		(end 108.31068 -226.180904)
		(width 0.1143)
		(layer "In4.Cu")
		(net "P5E_CPU1_G1_RX_DN<3>")
	)
	(segment
		(start 108.270548 -229.397306)
		(end 108.304076 -229.416864)
		(width 0.1143)
		(layer "In4.Cu")
		(net "P5E_CPU1_G1_RX_DN<3>")
	)
	(segment
		(start 106.920284 -234.426252)
		(end 106.862372 -234.460034)
		(width 0.1143)
		(layer "In4.Cu")
		(net "P5E_CPU1_G1_RX_DN<3>")
	)
	(segment
		(start 108.270548 -231.017318)
		(end 108.304076 -231.036876)
		(width 0.1143)
		(layer "In4.Cu")
		(net "P5E_CPU1_G1_RX_DN<3>")
	)
	(segment
		(start 107.367578 -223.90989)
		(end 107.365292 -223.911414)
		(width 0.1143)
		(layer "In4.Cu")
		(net "P5E_CPU1_G1_RX_DN<3>")
	)
	(segment
		(start 48.227488 -17.815052)
		(end 48.449738 -18.229834)
		(width 0.14224)
		(layer "In4.Cu")
		(net "P5E_CPU1_G1_RX_DN<3>")
	)
	(segment
		(start 155.88615 -166.116762)
		(end 155.88615 -166.116254)
		(width 0.14224)
		(layer "In4.Cu")
		(net "P5E_CPU1_G1_RX_DN<3>")
	)
	(segment
		(start 107.833922 -232.821734)
		(end 107.803442 -232.839514)
		(width 0.1143)
		(layer "In4.Cu")
		(net "P5E_CPU1_G1_RX_DN<3>")
	)
	(segment
		(start 107.333034 -222.919036)
		(end 107.4039 -222.960184)
		(width 0.1143)
		(layer "In4.Cu")
		(net "P5E_CPU1_G1_RX_DN<3>")
	)
	(segment
		(start 108.306616 -227.150422)
		(end 108.305092 -227.151438)
		(width 0.1143)
		(layer "In4.Cu")
		(net "P5E_CPU1_G1_RX_DN<3>")
	)
	(segment
		(start 151.352758 -136.872726)
		(end 151.486362 -137.14857)
		(width 0.14224)
		(layer "In4.Cu")
		(net "P5E_CPU1_G1_RX_DN<3>")
	)
	(segment
		(start 108.302044 -227.153216)
		(end 108.299504 -227.154486)
		(width 0.1143)
		(layer "In4.Cu")
		(net "P5E_CPU1_G1_RX_DN<3>")
	)
	(segment
		(start 156.435298 -159.758126)
		(end 156.435298 -164.503862)
		(width 0.14224)
		(layer "In4.Cu")
		(net "P5E_CPU1_G1_RX_DN<3>")
	)
	(segment
		(start 107.873038 -232.798874)
		(end 107.833922 -232.821734)
		(width 0.1143)
		(layer "In4.Cu")
		(net "P5E_CPU1_G1_RX_DN<3>")
	)
	(segment
		(start 154.16403 -171.147232)
		(end 154.16403 -171.147486)
		(width 0.14224)
		(layer "In4.Cu")
		(net "P5E_CPU1_G1_RX_DN<3>")
	)
	(segment
		(start 108.304076 -229.416864)
		(end 108.343192 -229.439724)
		(width 0.1143)
		(layer "In4.Cu")
		(net "P5E_CPU1_G1_RX_DN<3>")
	)
	(segment
		(start 155.547314 -145.54708)
		(end 156.435298 -159.758126)
		(width 0.14224)
		(layer "In4.Cu")
		(net "P5E_CPU1_G1_RX_DN<3>")
	)
	(segment
		(start 154.163776 -171.148248)
		(end 154.033982 -171.501562)
		(width 0.14224)
		(layer "In4.Cu")
		(net "P5E_CPU1_G1_RX_DN<3>")
	)
	(segment
		(start 48.210724 -17.362678)
		(end 48.183546 -17.452086)
		(width 0.14224)
		(layer "In4.Cu")
		(net "P5E_CPU1_G1_RX_DN<3>")
	)
	(segment
		(start 107.833922 -225.367088)
		(end 107.873038 -225.389948)
		(width 0.1143)
		(layer "In4.Cu")
		(net "P5E_CPU1_G1_RX_DN<3>")
	)
	(segment
		(start 108.297472 -226.173284)
		(end 108.298234 -226.173792)
		(width 0.1143)
		(layer "In4.Cu")
		(net "P5E_CPU1_G1_RX_DN<3>")
	)
	(segment
		(start 151.353266 -136.871202)
		(end 151.352758 -136.872726)
		(width 0.14224)
		(layer "In4.Cu")
		(net "P5E_CPU1_G1_RX_DN<3>")
	)
	(segment
		(start 108.304076 -232.011728)
		(end 108.303314 -232.012236)
		(width 0.1143)
		(layer "In4.Cu")
		(net "P5E_CPU1_G1_RX_DN<3>")
	)
	(segment
		(start 107.355132 -222.30969)
		(end 107.291632 -222.346266)
		(width 0.1143)
		(layer "In4.Cu")
		(net "P5E_CPU1_G1_RX_DN<3>")
	)
	(segment
		(start 107.431586 -223.868996)
		(end 107.402376 -223.889824)
		(width 0.1143)
		(layer "In4.Cu")
		(net "P5E_CPU1_G1_RX_DN<3>")
	)
	(segment
		(start 150.542244 -176.413668)
		(end 112.141762 -207.887316)
		(width 0.14224)
		(layer "In4.Cu")
		(net "P5E_CPU1_G1_RX_DN<3>")
	)
	(segment
		(start 107.636818 -221.378526)
		(end 107.636818 -221.558358)
		(width 0.1143)
		(layer "In4.Cu")
		(net "P5E_CPU1_G1_RX_DN<3>")
	)
	(segment
		(start 108.303314 -227.796598)
		(end 108.304076 -227.797106)
		(width 0.1143)
		(layer "In4.Cu")
		(net "P5E_CPU1_G1_RX_DN<3>")
	)
	(segment
		(start 108.306616 -227.79863)
		(end 108.30941 -227.800154)
		(width 0.1143)
		(layer "In4.Cu")
		(net "P5E_CPU1_G1_RX_DN<3>")
	)
	(segment
		(start 151.486362 -137.14857)
		(end 155.547314 -145.54708)
		(width 0.14224)
		(layer "In4.Cu")
		(net "P5E_CPU1_G1_RX_DN<3>")
	)
	(segment
		(start 107.364022 -233.63174)
		(end 107.36326 -233.632248)
		(width 0.1143)
		(layer "In4.Cu")
		(net "P5E_CPU1_G1_RX_DN<3>")
	)
	(segment
		(start 107.646216 -221.567756)
		(end 107.646216 -221.804484)
		(width 0.1143)
		(layer "In4.Cu")
		(net "P5E_CPU1_G1_RX_DN<3>")
	)
	(segment
		(start 108.343192 -227.129086)
		(end 108.306616 -227.150422)
		(width 0.1143)
		(layer "In4.Cu")
		(net "P5E_CPU1_G1_RX_DN<3>")
	)
	(segment
		(start 50.70856 -7.015988)
		(end 50.70856 -12.409678)
		(width 0.14224)
		(layer "In4.Cu")
		(net "P5E_CPU1_G1_RX_DN<3>")
	)
	(segment
		(start 108.30941 -227.800154)
		(end 108.31068 -227.800916)
		(width 0.1143)
		(layer "In4.Cu")
		(net "P5E_CPU1_G1_RX_DN<3>")
	)
	(segment
		(start 48.449738 -18.229834)
		(end 48.819816 -18.783808)
		(width 0.14224)
		(layer "In4.Cu")
		(net "P5E_CPU1_G1_RX_DN<3>")
	)
	(segment
		(start 48.819816 -18.783808)
		(end 49.318926 -20.255992)
		(width 0.14224)
		(layer "In4.Cu")
		(net "P5E_CPU1_G1_RX_DN<3>")
	)
	(segment
		(start 154.16403 -171.147486)
		(end 154.163776 -171.148248)
		(width 0.14224)
		(layer "In4.Cu")
		(net "P5E_CPU1_G1_RX_DN<3>")
	)
	(segment
		(start 108.304076 -226.177094)
		(end 108.305092 -226.177602)
		(width 0.1143)
		(layer "In4.Cu")
		(net "P5E_CPU1_G1_RX_DN<3>")
	)
	(segment
		(start 150.898352 -135.929624)
		(end 151.353266 -136.871202)
		(width 0.14224)
		(layer "In4.Cu")
		(net "P5E_CPU1_G1_RX_DN<3>")
	)
	(segment
		(start 107.403138 -233.60888)
		(end 107.366562 -233.630216)
		(width 0.1143)
		(layer "In4.Cu")
		(net "P5E_CPU1_G1_RX_DN<3>")
	)
	(segment
		(start 108.304076 -227.151946)
		(end 108.303314 -227.152454)
		(width 0.1143)
		(layer "In4.Cu")
		(net "P5E_CPU1_G1_RX_DN<3>")
	)
	(segment
		(start 108.304076 -228.771958)
		(end 108.303314 -228.772466)
		(width 0.1143)
		(layer "In4.Cu")
		(net "P5E_CPU1_G1_RX_DN<3>")
	)
	(segment
		(start 107.332272 -222.918528)
		(end 107.333034 -222.919036)
		(width 0.1143)
		(layer "In4.Cu")
		(net "P5E_CPU1_G1_RX_DN<3>")
	)
	(segment
		(start 60.755784 -54.952138)
		(end 62.04585 -56.032146)
		(width 0.14224)
		(layer "In4.Cu")
		(net "P5E_CPU1_G1_RX_DN<3>")
	)
	(segment
		(start 107.364276 -223.911922)
		(end 107.332526 -223.93021)
		(width 0.1143)
		(layer "In4.Cu")
		(net "P5E_CPU1_G1_RX_DN<3>")
	)
	(segment
		(start 55.95239 -48.763936)
		(end 58.44794 -52.987194)
		(width 0.14224)
		(layer "In4.Cu")
		(net "P5E_CPU1_G1_RX_DN<3>")
	)
	(segment
		(start 107.332272 -222.918782)
		(end 107.332272 -222.918528)
		(width 0.1143)
		(layer "In4.Cu")
		(net "P5E_CPU1_G1_RX_DN<3>")
	)
	(segment
		(start 108.297472 -227.793296)
		(end 108.298234 -227.793804)
		(width 0.1143)
		(layer "In4.Cu")
		(net "P5E_CPU1_G1_RX_DN<3>")
	)
	(segment
		(start 62.04585 -56.032146)
		(end 150.898352 -135.929624)
		(width 0.14224)
		(layer "In4.Cu")
		(net "P5E_CPU1_G1_RX_DN<3>")
	)
	(segment
		(start 108.30052 -227.795074)
		(end 108.303314 -227.796598)
		(width 0.1143)
		(layer "In4.Cu")
		(net "P5E_CPU1_G1_RX_DN<3>")
	)
	(segment
		(start 48.183546 -17.452086)
		(end 48.183546 -17.70888)
		(width 0.14224)
		(layer "In4.Cu")
		(net "P5E_CPU1_G1_RX_DN<3>")
	)
	(segment
		(start 108.305092 -230.391462)
		(end 108.304076 -230.39197)
		(width 0.1143)
		(layer "In4.Cu")
		(net "P5E_CPU1_G1_RX_DN<3>")
	)
	(segment
		(start 107.365292 -223.911414)
		(end 107.364276 -223.911922)
		(width 0.1143)
		(layer "In4.Cu")
		(net "P5E_CPU1_G1_RX_DN<3>")
	)
	(segment
		(start 108.299504 -232.014268)
		(end 108.272326 -232.030016)
		(width 0.1143)
		(layer "In4.Cu")
		(net "P5E_CPU1_G1_RX_DN<3>")
	)
	(segment
		(start 108.30052 -226.175062)
		(end 108.303314 -226.176586)
		(width 0.1143)
		(layer "In4.Cu")
		(net "P5E_CPU1_G1_RX_DN<3>")
	)
	(segment
		(start 108.298234 -230.395272)
		(end 108.272326 -230.410258)
		(width 0.1143)
		(layer "In4.Cu")
		(net "P5E_CPU1_G1_RX_DN<3>")
	)
	(segment
		(start 108.299504 -228.774498)
		(end 108.272326 -228.790246)
		(width 0.1143)
		(layer "In4.Cu")
		(net "P5E_CPU1_G1_RX_DN<3>")
	)
	(segment
		(start 108.306616 -232.010204)
		(end 108.305092 -232.01122)
		(width 0.1143)
		(layer "In4.Cu")
		(net "P5E_CPU1_G1_RX_DN<3>")
	)
	(segment
		(start 48.742854 -16.566388)
		(end 48.210724 -17.362678)
		(width 0.14224)
		(layer "In4.Cu")
		(net "P5E_CPU1_G1_RX_DN<3>")
	)
	(segment
		(start 50.99939 -6.725158)
		(end 50.70856 -7.015988)
		(width 0.14224)
		(layer "In4.Cu")
		(net "P5E_CPU1_G1_RX_DN<3>")
	)
	(segment
		(start 108.299758 -227.794566)
		(end 108.30052 -227.795074)
		(width 0.1143)
		(layer "In4.Cu")
		(net "P5E_CPU1_G1_RX_DN<3>")
	)
	(segment
		(start 59.854338 -54.142386)
		(end 60.755784 -54.952138)
		(width 0.14224)
		(layer "In4.Cu")
		(net "P5E_CPU1_G1_RX_DN<3>")
	)
	(segment
		(start 108.306616 -228.770434)
		(end 108.305092 -228.77145)
		(width 0.1143)
		(layer "In4.Cu")
		(net "P5E_CPU1_G1_RX_DN<3>")
	)
	(arc
		(start 107.646216 -221.804484)
		(mid 107.568312 -222.096071)
		(end 107.355132 -222.30969)
		(width 0.1143)
		(layer "In4.Cu")
		(net "P5E_CPU1_G1_RX_DN<3>")
	)
	(arc
		(start 108.11637 -230.71455)
		(mid 108.157132 -230.884434)
		(end 108.270548 -231.017318)
		(width 0.1143)
		(layer "In4.Cu")
		(net "P5E_CPU1_G1_RX_DN<3>")
	)
	(arc
		(start 108.343192 -227.819966)
		(mid 108.586519 -228.284532)
		(end 108.343192 -228.749098)
		(width 0.1143)
		(layer "In4.Cu")
		(net "P5E_CPU1_G1_RX_DN<3>")
	)
	(arc
		(start 108.272326 -228.790246)
		(mid 108.15765 -228.92358)
		(end 108.11637 -229.094538)
		(width 0.1143)
		(layer "In4.Cu")
		(net "P5E_CPU1_G1_RX_DN<3>")
	)
	(arc
		(start 107.291632 -222.346266)
		(mid 107.183038 -222.641655)
		(end 107.332272 -222.918782)
		(width 0.1143)
		(layer "In4.Cu")
		(net "P5E_CPU1_G1_RX_DN<3>")
	)
	(arc
		(start 107.64647 -233.144314)
		(mid 107.581955 -233.406533)
		(end 107.403138 -233.60888)
		(width 0.1143)
		(layer "In4.Cu")
		(net "P5E_CPU1_G1_RX_DN<3>")
	)
	(arc
		(start 107.332526 -223.93021)
		(mid 107.219872 -224.059843)
		(end 107.176824 -224.22612)
		(width 0.1143)
		(layer "In4.Cu")
		(net "P5E_CPU1_G1_RX_DN<3>")
	)
	(arc
		(start 107.873038 -225.389948)
		(mid 108.051851 -225.592298)
		(end 108.11637 -225.854514)
		(width 0.1143)
		(layer "In4.Cu")
		(net "P5E_CPU1_G1_RX_DN<3>")
	)
	(arc
		(start 108.272326 -227.170234)
		(mid 108.116398 -227.474526)
		(end 108.272326 -227.778818)
		(width 0.1143)
		(layer "In4.Cu")
		(net "P5E_CPU1_G1_RX_DN<3>")
	)
	(arc
		(start 108.343192 -229.439724)
		(mid 108.522005 -229.642074)
		(end 108.586524 -229.90429)
		(width 0.1143)
		(layer "In4.Cu")
		(net "P5E_CPU1_G1_RX_DN<3>")
	)
	(arc
		(start 108.272326 -230.410258)
		(mid 108.15765 -230.543592)
		(end 108.11637 -230.71455)
		(width 0.1143)
		(layer "In4.Cu")
		(net "P5E_CPU1_G1_RX_DN<3>")
	)
	(arc
		(start 107.177586 -224.241106)
		(mid 107.228101 -224.399832)
		(end 107.327192 -224.533714)
		(width 0.1143)
		(layer "In4.Cu")
		(net "P5E_CPU1_G1_RX_DN<3>")
	)
	(arc
		(start 108.11637 -225.854514)
		(mid 108.157625 -226.025485)
		(end 108.272326 -226.158806)
		(width 0.1143)
		(layer "In4.Cu")
		(net "P5E_CPU1_G1_RX_DN<3>")
	)
	(arc
		(start 107.36326 -233.632248)
		(mid 107.230634 -233.774519)
		(end 107.176062 -233.961178)
		(width 0.1143)
		(layer "In4.Cu")
		(net "P5E_CPU1_G1_RX_DN<3>")
	)
	(arc
		(start 107.176062 -233.961178)
		(mid 107.104401 -234.218275)
		(end 106.930444 -234.420664)
		(width 0.1143)
		(layer "In4.Cu")
		(net "P5E_CPU1_G1_RX_DN<3>")
	)
	(arc
		(start 108.11637 -229.094538)
		(mid 108.157132 -229.264422)
		(end 108.270548 -229.397306)
		(width 0.1143)
		(layer "In4.Cu")
		(net "P5E_CPU1_G1_RX_DN<3>")
	)
	(arc
		(start 108.343192 -226.199954)
		(mid 108.586519 -226.66452)
		(end 108.343192 -227.129086)
		(width 0.1143)
		(layer "In4.Cu")
		(net "P5E_CPU1_G1_RX_DN<3>")
	)
	(arc
		(start 107.64647 -225.044508)
		(mid 107.688019 -225.21593)
		(end 107.803442 -225.349308)
		(width 0.1143)
		(layer "In4.Cu")
		(net "P5E_CPU1_G1_RX_DN<3>")
	)
	(arc
		(start 106.862372 -234.460034)
		(mid 106.765237 -234.562903)
		(end 106.713274 -234.694476)
		(width 0.1143)
		(layer "In4.Cu")
		(net "P5E_CPU1_G1_RX_DN<3>")
	)
	(arc
		(start 108.343192 -231.059736)
		(mid 108.586519 -231.524302)
		(end 108.343192 -231.988868)
		(width 0.1143)
		(layer "In4.Cu")
		(net "P5E_CPU1_G1_RX_DN<3>")
	)
	(arc
		(start 107.431586 -222.979996)
		(mid 107.659274 -223.424496)
		(end 107.431586 -223.868996)
		(width 0.1143)
		(layer "In4.Cu")
		(net "P5E_CPU1_G1_RX_DN<3>")
	)
	(arc
		(start 108.272326 -232.030016)
		(mid 108.15765 -232.16335)
		(end 108.11637 -232.334308)
		(width 0.1143)
		(layer "In4.Cu")
		(net "P5E_CPU1_G1_RX_DN<3>")
	)
	(arc
		(start 107.400598 -224.578164)
		(mid 107.58125 -224.780909)
		(end 107.64647 -225.044508)
		(width 0.1143)
		(layer "In4.Cu")
		(net "P5E_CPU1_G1_RX_DN<3>")
	)
	(arc
		(start 108.586524 -229.90429)
		(mid 108.521288 -230.167881)
		(end 108.340652 -230.370634)
		(width 0.1143)
		(layer "In4.Cu")
		(net "P5E_CPU1_G1_RX_DN<3>")
	)
	(arc
		(start 107.803442 -232.839514)
		(mid 107.688015 -232.97289)
		(end 107.64647 -233.144314)
		(width 0.1143)
		(layer "In4.Cu")
		(net "P5E_CPU1_G1_RX_DN<3>")
	)
	(arc
		(start 108.11637 -232.334308)
		(mid 108.051855 -232.596527)
		(end 107.873038 -232.798874)
		(width 0.1143)
		(layer "In4.Cu")
		(net "P5E_CPU1_G1_RX_DN<3>")
	)
	(arc
		(start 107.327192 -224.533714)
		(mid 107.330982 -224.536786)
		(end 107.334812 -224.53981)
		(width 0.1143)
		(layer "In4.Cu")
		(net "P5E_CPU1_G1_RX_DN<3>")
	)
	(segment
		(start 45.05706 -7.709662)
		(end 45.05706 -8.320024)
		(width 0.12954)
		(layer "F.Cu")
		(net "P5E_CPU1_G1_RX_DN<4>")
	)
	(segment
		(start 107.547918 -231.79024)
		(end 107.081066 -231.524302)
		(width 0.12954)
		(layer "F.Cu")
		(net "P5E_CPU1_G1_RX_DN<4>")
	)
	(segment
		(start 45.193966 -4.963414)
		(end 44.918376 -5.239004)
		(width 0.12954)
		(layer "F.Cu")
		(net "P5E_CPU1_G1_RX_DN<4>")
	)
	(segment
		(start 44.918376 -7.57047)
		(end 45.057314 -7.709408)
		(width 0.12954)
		(layer "F.Cu")
		(net "P5E_CPU1_G1_RX_DN<4>")
	)
	(segment
		(start 45.057314 -7.709408)
		(end 45.05706 -7.709662)
		(width 0.12954)
		(layer "F.Cu")
		(net "P5E_CPU1_G1_RX_DN<4>")
	)
	(segment
		(start 44.918376 -5.239004)
		(end 44.918376 -7.57047)
		(width 0.12954)
		(layer "F.Cu")
		(net "P5E_CPU1_G1_RX_DN<4>")
	)
	(segment
		(start 106.463084 -222.26905)
		(end 106.426508 -222.290386)
		(width 0.1143)
		(layer "In4.Cu")
		(net "P5E_CPU1_G1_RX_DN<4>")
	)
	(segment
		(start 106.933238 -231.179116)
		(end 106.894122 -231.201976)
		(width 0.1143)
		(layer "In4.Cu")
		(net "P5E_CPU1_G1_RX_DN<4>")
	)
	(segment
		(start 106.894122 -225.367088)
		(end 106.925618 -225.385376)
		(width 0.1143)
		(layer "In4.Cu")
		(net "P5E_CPU1_G1_RX_DN<4>")
	)
	(segment
		(start 106.426508 -222.290386)
		(end 106.424984 -222.291402)
		(width 0.1143)
		(layer "In4.Cu")
		(net "P5E_CPU1_G1_RX_DN<4>")
	)
	(segment
		(start 155.495244 -159.787844)
		(end 155.495244 -164.33038)
		(width 0.14224)
		(layer "In4.Cu")
		(net "P5E_CPU1_G1_RX_DN<4>")
	)
	(segment
		(start 106.894122 -231.201976)
		(end 106.860594 -231.221534)
		(width 0.1143)
		(layer "In4.Cu")
		(net "P5E_CPU1_G1_RX_DN<4>")
	)
	(segment
		(start 154.620214 -145.782538)
		(end 155.495244 -159.787844)
		(width 0.14224)
		(layer "In4.Cu")
		(net "P5E_CPU1_G1_RX_DN<4>")
	)
	(segment
		(start 106.393488 -224.539302)
		(end 106.423968 -224.557082)
		(width 0.1143)
		(layer "In4.Cu")
		(net "P5E_CPU1_G1_RX_DN<4>")
	)
	(segment
		(start 107.403138 -227.129086)
		(end 107.364022 -227.151946)
		(width 0.1143)
		(layer "In4.Cu")
		(net "P5E_CPU1_G1_RX_DN<4>")
	)
	(segment
		(start 106.925618 -225.385376)
		(end 106.92638 -225.385884)
		(width 0.1143)
		(layer "In4.Cu")
		(net "P5E_CPU1_G1_RX_DN<4>")
	)
	(segment
		(start 107.403138 -228.749098)
		(end 107.364022 -228.771958)
		(width 0.1143)
		(layer "In4.Cu")
		(net "P5E_CPU1_G1_RX_DN<4>")
	)
	(segment
		(start 46.036738 -17.935702)
		(end 45.801534 -18.375122)
		(width 0.14224)
		(layer "In4.Cu")
		(net "P5E_CPU1_G1_RX_DN<4>")
	)
	(segment
		(start 106.862372 -225.3488)
		(end 106.89209 -225.365818)
		(width 0.1143)
		(layer "In4.Cu")
		(net "P5E_CPU1_G1_RX_DN<4>")
	)
	(segment
		(start 130.6322 -191.52362)
		(end 111.430562 -207.25892)
		(width 0.14224)
		(layer "In4.Cu")
		(net "P5E_CPU1_G1_RX_DN<4>")
	)
	(segment
		(start 107.364022 -227.151946)
		(end 107.333542 -227.169726)
		(width 0.1143)
		(layer "In4.Cu")
		(net "P5E_CPU1_G1_RX_DN<4>")
	)
	(segment
		(start 46.10735 -17.461992)
		(end 46.10735 -17.76476)
		(width 0.14224)
		(layer "In4.Cu")
		(net "P5E_CPU1_G1_RX_DN<4>")
	)
	(segment
		(start 106.236262 -222.61449)
		(end 106.236516 -222.61449)
		(width 0.1143)
		(layer "In4.Cu")
		(net "P5E_CPU1_G1_RX_DN<4>")
	)
	(segment
		(start 106.737912 -221.332806)
		(end 106.692192 -221.378526)
		(width 0.1143)
		(layer "In4.Cu")
		(net "P5E_CPU1_G1_RX_DN<4>")
	)
	(segment
		(start 106.423968 -222.29191)
		(end 106.392218 -222.310198)
		(width 0.1143)
		(layer "In4.Cu")
		(net "P5E_CPU1_G1_RX_DN<4>")
	)
	(segment
		(start 45.417486 -19.299682)
		(end 47.851568 -26.606754)
		(width 0.14224)
		(layer "In4.Cu")
		(net "P5E_CPU1_G1_RX_DN<4>")
	)
	(segment
		(start 106.393488 -222.91929)
		(end 106.423968 -222.93707)
		(width 0.1143)
		(layer "In4.Cu")
		(net "P5E_CPU1_G1_RX_DN<4>")
	)
	(segment
		(start 45.389546 -19.0881)
		(end 45.389546 -19.201638)
		(width 0.14224)
		(layer "In4.Cu")
		(net "P5E_CPU1_G1_RX_DN<4>")
	)
	(segment
		(start 106.423968 -224.557082)
		(end 106.463084 -224.579942)
		(width 0.1143)
		(layer "In4.Cu")
		(net "P5E_CPU1_G1_RX_DN<4>")
	)
	(segment
		(start 45.44441 -18.909284)
		(end 45.407326 -18.998692)
		(width 0.14224)
		(layer "In4.Cu")
		(net "P5E_CPU1_G1_RX_DN<4>")
	)
	(segment
		(start 59.246516 -54.849522)
		(end 60.14466 -55.65648)
		(width 0.14224)
		(layer "In4.Cu")
		(net "P5E_CPU1_G1_RX_DN<4>")
	)
	(segment
		(start 60.14466 -55.65648)
		(end 61.434726 -56.736488)
		(width 0.14224)
		(layer "In4.Cu")
		(net "P5E_CPU1_G1_RX_DN<4>")
	)
	(segment
		(start 111.430562 -207.25892)
		(end 106.737912 -215.161876)
		(width 0.14224)
		(layer "In4.Cu")
		(net "P5E_CPU1_G1_RX_DN<4>")
	)
	(segment
		(start 130.6322 -191.523366)
		(end 130.6322 -191.52362)
		(width 0.14224)
		(layer "In4.Cu")
		(net "P5E_CPU1_G1_RX_DN<4>")
	)
	(segment
		(start 45.193966 -4.963414)
		(end 44.903136 -5.254244)
		(width 0.14224)
		(layer "In4.Cu")
		(net "P5E_CPU1_G1_RX_DN<4>")
	)
	(segment
		(start 57.023762 -53.024278)
		(end 59.246516 -54.849522)
		(width 0.14224)
		(layer "In4.Cu")
		(net "P5E_CPU1_G1_RX_DN<4>")
	)
	(segment
		(start 106.737912 -215.161876)
		(end 106.737912 -221.304358)
		(width 0.14224)
		(layer "In4.Cu")
		(net "P5E_CPU1_G1_RX_DN<4>")
	)
	(segment
		(start 107.364022 -227.797106)
		(end 107.403138 -227.819966)
		(width 0.1143)
		(layer "In4.Cu")
		(net "P5E_CPU1_G1_RX_DN<4>")
	)
	(segment
		(start 45.389546 -19.201638)
		(end 45.417486 -19.299682)
		(width 0.14224)
		(layer "In4.Cu")
		(net "P5E_CPU1_G1_RX_DN<4>")
	)
	(segment
		(start 107.333542 -226.159314)
		(end 107.364022 -226.177094)
		(width 0.1143)
		(layer "In4.Cu")
		(net "P5E_CPU1_G1_RX_DN<4>")
	)
	(segment
		(start 107.33151 -229.398068)
		(end 107.364022 -229.416864)
		(width 0.1143)
		(layer "In4.Cu")
		(net "P5E_CPU1_G1_RX_DN<4>")
	)
	(segment
		(start 155.495244 -164.33038)
		(end 153.20518 -171.045632)
		(width 0.14224)
		(layer "In4.Cu")
		(net "P5E_CPU1_G1_RX_DN<4>")
	)
	(segment
		(start 46.10735 -17.76476)
		(end 46.036738 -17.935702)
		(width 0.14224)
		(layer "In4.Cu")
		(net "P5E_CPU1_G1_RX_DN<4>")
	)
	(segment
		(start 106.783124 -231.524302)
		(end 107.081066 -231.524302)
		(width 0.1143)
		(layer "In4.Cu")
		(net "P5E_CPU1_G1_RX_DN<4>")
	)
	(segment
		(start 106.706416 -221.572582)
		(end 106.706416 -221.804484)
		(width 0.1143)
		(layer "In4.Cu")
		(net "P5E_CPU1_G1_RX_DN<4>")
	)
	(segment
		(start 44.903136 -11.407648)
		(end 46.10735 -17.461992)
		(width 0.14224)
		(layer "In4.Cu")
		(net "P5E_CPU1_G1_RX_DN<4>")
	)
	(segment
		(start 106.424984 -222.291402)
		(end 106.423968 -222.29191)
		(width 0.1143)
		(layer "In4.Cu")
		(net "P5E_CPU1_G1_RX_DN<4>")
	)
	(segment
		(start 45.801534 -18.375122)
		(end 45.44441 -18.909284)
		(width 0.14224)
		(layer "In4.Cu")
		(net "P5E_CPU1_G1_RX_DN<4>")
	)
	(segment
		(start 106.692192 -221.558358)
		(end 106.706416 -221.572582)
		(width 0.1143)
		(layer "In4.Cu")
		(net "P5E_CPU1_G1_RX_DN<4>")
	)
	(segment
		(start 106.713274 -231.454452)
		(end 106.783124 -231.524302)
		(width 0.1143)
		(layer "In4.Cu")
		(net "P5E_CPU1_G1_RX_DN<4>")
	)
	(segment
		(start 106.423968 -222.93707)
		(end 106.463084 -222.95993)
		(width 0.1143)
		(layer "In4.Cu")
		(net "P5E_CPU1_G1_RX_DN<4>")
	)
	(segment
		(start 106.463084 -223.889062)
		(end 106.423968 -223.911922)
		(width 0.1143)
		(layer "In4.Cu")
		(net "P5E_CPU1_G1_RX_DN<4>")
	)
	(segment
		(start 107.333542 -227.779326)
		(end 107.364022 -227.797106)
		(width 0.1143)
		(layer "In4.Cu")
		(net "P5E_CPU1_G1_RX_DN<4>")
	)
	(segment
		(start 107.364022 -228.771958)
		(end 107.333542 -228.789738)
		(width 0.1143)
		(layer "In4.Cu")
		(net "P5E_CPU1_G1_RX_DN<4>")
	)
	(segment
		(start 150.114508 -136.479026)
		(end 154.620214 -145.782538)
		(width 0.14224)
		(layer "In4.Cu")
		(net "P5E_CPU1_G1_RX_DN<4>")
	)
	(segment
		(start 149.833838 -175.787812)
		(end 130.6322 -191.523366)
		(width 0.14224)
		(layer "In4.Cu")
		(net "P5E_CPU1_G1_RX_DN<4>")
	)
	(segment
		(start 107.364022 -229.416864)
		(end 107.403138 -229.439724)
		(width 0.1143)
		(layer "In4.Cu")
		(net "P5E_CPU1_G1_RX_DN<4>")
	)
	(segment
		(start 45.407326 -18.998692)
		(end 45.389546 -19.0881)
		(width 0.14224)
		(layer "In4.Cu")
		(net "P5E_CPU1_G1_RX_DN<4>")
	)
	(segment
		(start 106.89209 -225.365818)
		(end 106.89336 -225.36658)
		(width 0.1143)
		(layer "In4.Cu")
		(net "P5E_CPU1_G1_RX_DN<4>")
	)
	(segment
		(start 106.92638 -225.385884)
		(end 106.933238 -225.389948)
		(width 0.1143)
		(layer "In4.Cu")
		(net "P5E_CPU1_G1_RX_DN<4>")
	)
	(segment
		(start 106.737912 -221.304358)
		(end 106.737912 -221.332806)
		(width 0.1143)
		(layer "In4.Cu")
		(net "P5E_CPU1_G1_RX_DN<4>")
	)
	(segment
		(start 107.364022 -226.177094)
		(end 107.403138 -226.199954)
		(width 0.1143)
		(layer "In4.Cu")
		(net "P5E_CPU1_G1_RX_DN<4>")
	)
	(segment
		(start 106.692192 -221.378526)
		(end 106.692192 -221.558358)
		(width 0.1143)
		(layer "In4.Cu")
		(net "P5E_CPU1_G1_RX_DN<4>")
	)
	(segment
		(start 57.00649 -53.00853)
		(end 57.023762 -53.024278)
		(width 0.14224)
		(layer "In4.Cu")
		(net "P5E_CPU1_G1_RX_DN<4>")
	)
	(segment
		(start 54.448456 -48.223932)
		(end 57.00649 -53.00853)
		(width 0.14224)
		(layer "In4.Cu")
		(net "P5E_CPU1_G1_RX_DN<4>")
	)
	(segment
		(start 107.400598 -230.370634)
		(end 107.333542 -230.40975)
		(width 0.1143)
		(layer "In4.Cu")
		(net "P5E_CPU1_G1_RX_DN<4>")
	)
	(segment
		(start 106.423968 -223.911922)
		(end 106.393488 -223.929702)
		(width 0.1143)
		(layer "In4.Cu")
		(net "P5E_CPU1_G1_RX_DN<4>")
	)
	(segment
		(start 61.434726 -56.736488)
		(end 150.114508 -136.479026)
		(width 0.14224)
		(layer "In4.Cu")
		(net "P5E_CPU1_G1_RX_DN<4>")
	)
	(segment
		(start 153.20518 -171.045632)
		(end 149.833838 -175.787812)
		(width 0.14224)
		(layer "In4.Cu")
		(net "P5E_CPU1_G1_RX_DN<4>")
	)
	(segment
		(start 44.903136 -5.254244)
		(end 44.903136 -11.407648)
		(width 0.14224)
		(layer "In4.Cu")
		(net "P5E_CPU1_G1_RX_DN<4>")
	)
	(segment
		(start 106.89336 -225.36658)
		(end 106.894122 -225.367088)
		(width 0.1143)
		(layer "In4.Cu")
		(net "P5E_CPU1_G1_RX_DN<4>")
	)
	(segment
		(start 47.851568 -26.606754)
		(end 54.448456 -48.223932)
		(width 0.14224)
		(layer "In4.Cu")
		(net "P5E_CPU1_G1_RX_DN<4>")
	)
	(arc
		(start 106.706416 -221.804484)
		(mid 106.701915 -221.876176)
		(end 106.688382 -221.946724)
		(width 0.1143)
		(layer "In4.Cu")
		(net "P5E_CPU1_G1_RX_DN<4>")
	)
	(arc
		(start 106.393488 -223.929702)
		(mid 106.236511 -224.234502)
		(end 106.393488 -224.539302)
		(width 0.1143)
		(layer "In4.Cu")
		(net "P5E_CPU1_G1_RX_DN<4>")
	)
	(arc
		(start 107.64647 -229.90429)
		(mid 107.581234 -230.167881)
		(end 107.400598 -230.370634)
		(width 0.1143)
		(layer "In4.Cu")
		(net "P5E_CPU1_G1_RX_DN<4>")
	)
	(arc
		(start 107.333542 -228.789738)
		(mid 107.218115 -228.923114)
		(end 107.17657 -229.094538)
		(width 0.1143)
		(layer "In4.Cu")
		(net "P5E_CPU1_G1_RX_DN<4>")
	)
	(arc
		(start 107.333542 -227.169726)
		(mid 107.176565 -227.474526)
		(end 107.333542 -227.779326)
		(width 0.1143)
		(layer "In4.Cu")
		(net "P5E_CPU1_G1_RX_DN<4>")
	)
	(arc
		(start 107.17657 -229.094538)
		(mid 107.217536 -229.264944)
		(end 107.33151 -229.398068)
		(width 0.1143)
		(layer "In4.Cu")
		(net "P5E_CPU1_G1_RX_DN<4>")
	)
	(arc
		(start 106.860594 -231.221534)
		(mid 106.764706 -231.323942)
		(end 106.713274 -231.454452)
		(width 0.1143)
		(layer "In4.Cu")
		(net "P5E_CPU1_G1_RX_DN<4>")
	)
	(arc
		(start 106.688382 -221.946724)
		(mid 106.604701 -222.128141)
		(end 106.463084 -222.26905)
		(width 0.1143)
		(layer "In4.Cu")
		(net "P5E_CPU1_G1_RX_DN<4>")
	)
	(arc
		(start 106.236516 -222.61449)
		(mid 106.278065 -222.785912)
		(end 106.393488 -222.91929)
		(width 0.1143)
		(layer "In4.Cu")
		(net "P5E_CPU1_G1_RX_DN<4>")
	)
	(arc
		(start 106.463084 -222.95993)
		(mid 106.706411 -223.424496)
		(end 106.463084 -223.889062)
		(width 0.1143)
		(layer "In4.Cu")
		(net "P5E_CPU1_G1_RX_DN<4>")
	)
	(arc
		(start 107.403138 -227.819966)
		(mid 107.646465 -228.284532)
		(end 107.403138 -228.749098)
		(width 0.1143)
		(layer "In4.Cu")
		(net "P5E_CPU1_G1_RX_DN<4>")
	)
	(arc
		(start 106.463084 -224.579942)
		(mid 106.641897 -224.782292)
		(end 106.706416 -225.044508)
		(width 0.1143)
		(layer "In4.Cu")
		(net "P5E_CPU1_G1_RX_DN<4>")
	)
	(arc
		(start 107.333542 -230.40975)
		(mid 107.218115 -230.543126)
		(end 107.17657 -230.71455)
		(width 0.1143)
		(layer "In4.Cu")
		(net "P5E_CPU1_G1_RX_DN<4>")
	)
	(arc
		(start 106.392218 -222.310198)
		(mid 106.277542 -222.443532)
		(end 106.236262 -222.61449)
		(width 0.1143)
		(layer "In4.Cu")
		(net "P5E_CPU1_G1_RX_DN<4>")
	)
	(arc
		(start 106.706416 -225.044508)
		(mid 106.747671 -225.215479)
		(end 106.862372 -225.3488)
		(width 0.1143)
		(layer "In4.Cu")
		(net "P5E_CPU1_G1_RX_DN<4>")
	)
	(arc
		(start 107.17657 -225.854514)
		(mid 107.218119 -226.025936)
		(end 107.333542 -226.159314)
		(width 0.1143)
		(layer "In4.Cu")
		(net "P5E_CPU1_G1_RX_DN<4>")
	)
	(arc
		(start 107.403138 -226.199954)
		(mid 107.646465 -226.66452)
		(end 107.403138 -227.129086)
		(width 0.1143)
		(layer "In4.Cu")
		(net "P5E_CPU1_G1_RX_DN<4>")
	)
	(arc
		(start 107.403138 -229.439724)
		(mid 107.581951 -229.642074)
		(end 107.64647 -229.90429)
		(width 0.1143)
		(layer "In4.Cu")
		(net "P5E_CPU1_G1_RX_DN<4>")
	)
	(arc
		(start 106.933238 -225.389948)
		(mid 107.112051 -225.592298)
		(end 107.17657 -225.854514)
		(width 0.1143)
		(layer "In4.Cu")
		(net "P5E_CPU1_G1_RX_DN<4>")
	)
	(arc
		(start 107.17657 -230.71455)
		(mid 107.112055 -230.976769)
		(end 106.933238 -231.179116)
		(width 0.1143)
		(layer "In4.Cu")
		(net "P5E_CPU1_G1_RX_DN<4>")
	)
	(segment
		(start 43.256962 -8.320024)
		(end 43.256962 -7.709154)
		(width 0.12954)
		(layer "F.Cu")
		(net "P5E_CPU1_G1_RX_DN<5>")
	)
	(segment
		(start 107.547918 -233.410252)
		(end 107.081066 -233.144314)
		(width 0.12954)
		(layer "F.Cu")
		(net "P5E_CPU1_G1_RX_DN<5>")
	)
	(segment
		(start 43.118278 -7.57047)
		(end 43.118278 -6.996176)
		(width 0.12954)
		(layer "F.Cu")
		(net "P5E_CPU1_G1_RX_DN<5>")
	)
	(segment
		(start 43.118278 -6.996176)
		(end 43.389296 -6.725158)
		(width 0.12954)
		(layer "F.Cu")
		(net "P5E_CPU1_G1_RX_DN<5>")
	)
	(segment
		(start 43.256962 -7.709154)
		(end 43.118278 -7.57047)
		(width 0.12954)
		(layer "F.Cu")
		(net "P5E_CPU1_G1_RX_DN<5>")
	)
	(segment
		(start 153.626566 -166.885874)
		(end 152.712674 -169.569384)
		(width 0.14224)
		(layer "In4.Cu")
		(net "P5E_CPU1_G1_RX_DN<5>")
	)
	(segment
		(start 42.595546 -17.70888)
		(end 42.639488 -17.815052)
		(width 0.14224)
		(layer "In4.Cu")
		(net "P5E_CPU1_G1_RX_DN<5>")
	)
	(segment
		(start 55.944008 -53.306726)
		(end 56.415686 -53.731414)
		(width 0.14224)
		(layer "In4.Cu")
		(net "P5E_CPU1_G1_RX_DN<5>")
	)
	(segment
		(start 58.638694 -55.556658)
		(end 59.533536 -56.360822)
		(width 0.14224)
		(layer "In4.Cu")
		(net "P5E_CPU1_G1_RX_DN<5>")
	)
	(segment
		(start 46.385226 -26.692352)
		(end 46.38548 -26.693622)
		(width 0.14224)
		(layer "In4.Cu")
		(net "P5E_CPU1_G1_RX_DN<5>")
	)
	(segment
		(start 106.456226 -227.815902)
		(end 106.463084 -227.819966)
		(width 0.1143)
		(layer "In4.Cu")
		(net "P5E_CPU1_G1_RX_DN<5>")
	)
	(segment
		(start 106.423968 -228.771958)
		(end 106.423206 -228.772466)
		(width 0.1143)
		(layer "In4.Cu")
		(net "P5E_CPU1_G1_RX_DN<5>")
	)
	(segment
		(start 105.99039 -231.180894)
		(end 105.92054 -231.221534)
		(width 0.1143)
		(layer "In4.Cu")
		(net "P5E_CPU1_G1_RX_DN<5>")
	)
	(segment
		(start 106.423206 -227.796598)
		(end 106.423968 -227.797106)
		(width 0.1143)
		(layer "In4.Cu")
		(net "P5E_CPU1_G1_RX_DN<5>")
	)
	(segment
		(start 106.394504 -226.160076)
		(end 106.423206 -226.176586)
		(width 0.1143)
		(layer "In4.Cu")
		(net "P5E_CPU1_G1_RX_DN<5>")
	)
	(segment
		(start 149.354286 -137.050018)
		(end 153.690066 -146.003264)
		(width 0.14224)
		(layer "In4.Cu")
		(net "P5E_CPU1_G1_RX_DN<5>")
	)
	(segment
		(start 153.690066 -146.003264)
		(end 154.553666 -159.817562)
		(width 0.14224)
		(layer "In4.Cu")
		(net "P5E_CPU1_G1_RX_DN<5>")
	)
	(segment
		(start 106.418126 -232.653586)
		(end 106.423206 -232.65638)
		(width 0.1143)
		(layer "In4.Cu")
		(net "P5E_CPU1_G1_RX_DN<5>")
	)
	(segment
		(start 106.455464 -226.195382)
		(end 106.456226 -226.19589)
		(width 0.1143)
		(layer "In4.Cu")
		(net "P5E_CPU1_G1_RX_DN<5>")
	)
	(segment
		(start 60.823602 -57.44083)
		(end 149.35454 -137.050018)
		(width 0.14224)
		(layer "In4.Cu")
		(net "P5E_CPU1_G1_RX_DN<5>")
	)
	(segment
		(start 44.011596 -20.005802)
		(end 46.330362 -26.53792)
		(width 0.14224)
		(layer "In4.Cu")
		(net "P5E_CPU1_G1_RX_DN<5>")
	)
	(segment
		(start 105.922318 -231.828594)
		(end 105.954068 -231.846882)
		(width 0.1143)
		(layer "In4.Cu")
		(net "P5E_CPU1_G1_RX_DN<5>")
	)
	(segment
		(start 105.958894 -225.369628)
		(end 105.99039 -225.38817)
		(width 0.1143)
		(layer "In4.Cu")
		(net "P5E_CPU1_G1_RX_DN<5>")
	)
	(segment
		(start 106.423968 -232.656888)
		(end 106.455464 -232.675176)
		(width 0.1143)
		(layer "In4.Cu")
		(net "P5E_CPU1_G1_RX_DN<5>")
	)
	(segment
		(start 105.792524 -221.304358)
		(end 105.792524 -221.332806)
		(width 0.1143)
		(layer "In4.Cu")
		(net "P5E_CPU1_G1_RX_DN<5>")
	)
	(segment
		(start 105.453434 -224.539302)
		(end 105.483914 -224.557082)
		(width 0.1143)
		(layer "In4.Cu")
		(net "P5E_CPU1_G1_RX_DN<5>")
	)
	(segment
		(start 105.52303 -223.889062)
		(end 105.483914 -223.911922)
		(width 0.1143)
		(layer "In4.Cu")
		(net "P5E_CPU1_G1_RX_DN<5>")
	)
	(segment
		(start 154.553666 -159.817562)
		(end 154.553666 -164.163248)
		(width 0.14224)
		(layer "In4.Cu")
		(net "P5E_CPU1_G1_RX_DN<5>")
	)
	(segment
		(start 46.358302 -26.616406)
		(end 46.385226 -26.692352)
		(width 0.14224)
		(layer "In4.Cu")
		(net "P5E_CPU1_G1_RX_DN<5>")
	)
	(segment
		(start 46.330362 -26.53792)
		(end 46.367954 -26.575512)
		(width 0.14224)
		(layer "In4.Cu")
		(net "P5E_CPU1_G1_RX_DN<5>")
	)
	(segment
		(start 43.916092 -19.807428)
		(end 43.915838 -19.809206)
		(width 0.14224)
		(layer "In4.Cu")
		(net "P5E_CPU1_G1_RX_DN<5>")
	)
	(segment
		(start 106.455464 -232.675176)
		(end 106.456226 -232.675684)
		(width 0.1143)
		(layer "In4.Cu")
		(net "P5E_CPU1_G1_RX_DN<5>")
	)
	(segment
		(start 105.792524 -214.915242)
		(end 105.792524 -221.304358)
		(width 0.14224)
		(layer "In4.Cu")
		(net "P5E_CPU1_G1_RX_DN<5>")
	)
	(segment
		(start 46.357286 -26.613612)
		(end 46.358048 -26.615644)
		(width 0.14224)
		(layer "In4.Cu")
		(net "P5E_CPU1_G1_RX_DN<5>")
	)
	(segment
		(start 43.098466 -7.015988)
		(end 43.098466 -12.482322)
		(width 0.14224)
		(layer "In4.Cu")
		(net "P5E_CPU1_G1_RX_DN<5>")
	)
	(segment
		(start 105.453434 -222.91929)
		(end 105.483914 -222.93707)
		(width 0.1143)
		(layer "In4.Cu")
		(net "P5E_CPU1_G1_RX_DN<5>")
	)
	(segment
		(start 154.553666 -164.163248)
		(end 153.626566 -166.886128)
		(width 0.14224)
		(layer "In4.Cu")
		(net "P5E_CPU1_G1_RX_DN<5>")
	)
	(segment
		(start 106.426508 -228.770434)
		(end 106.424984 -228.77145)
		(width 0.1143)
		(layer "In4.Cu")
		(net "P5E_CPU1_G1_RX_DN<5>")
	)
	(segment
		(start 152.321514 -170.604434)
		(end 148.935948 -175.317912)
		(width 0.14224)
		(layer "In4.Cu")
		(net "P5E_CPU1_G1_RX_DN<5>")
	)
	(segment
		(start 105.954576 -225.367342)
		(end 105.955592 -225.36785)
		(width 0.1143)
		(layer "In4.Cu")
		(net "P5E_CPU1_G1_RX_DN<5>")
	)
	(segment
		(start 149.35454 -137.050018)
		(end 149.354286 -137.050018)
		(width 0.14224)
		(layer "In4.Cu")
		(net "P5E_CPU1_G1_RX_DN<5>")
	)
	(segment
		(start 46.38548 -26.693622)
		(end 46.38548 -26.693368)
		(width 0.14224)
		(layer "In4.Cu")
		(net "P5E_CPU1_G1_RX_DN<5>")
	)
	(segment
		(start 46.358048 -26.615644)
		(end 46.358302 -26.616406)
		(width 0.14224)
		(layer "In4.Cu")
		(net "P5E_CPU1_G1_RX_DN<5>")
	)
	(segment
		(start 148.935948 -175.317912)
		(end 110.697264 -206.653892)
		(width 0.14224)
		(layer "In4.Cu")
		(net "P5E_CPU1_G1_RX_DN<5>")
	)
	(segment
		(start 42.595546 -17.5895)
		(end 42.595546 -17.70888)
		(width 0.14224)
		(layer "In4.Cu")
		(net "P5E_CPU1_G1_RX_DN<5>")
	)
	(segment
		(start 106.424984 -230.394256)
		(end 106.41965 -230.397304)
		(width 0.1143)
		(layer "In4.Cu")
		(net "P5E_CPU1_G1_RX_DN<5>")
	)
	(segment
		(start 106.392218 -227.778818)
		(end 106.423206 -227.796598)
		(width 0.1143)
		(layer "In4.Cu")
		(net "P5E_CPU1_G1_RX_DN<5>")
	)
	(segment
		(start 105.766362 -221.577916)
		(end 105.766362 -221.804484)
		(width 0.1143)
		(layer "In4.Cu")
		(net "P5E_CPU1_G1_RX_DN<5>")
	)
	(segment
		(start 43.098466 -12.482322)
		(end 42.595546 -17.5895)
		(width 0.14224)
		(layer "In4.Cu")
		(net "P5E_CPU1_G1_RX_DN<5>")
	)
	(segment
		(start 106.423206 -228.772466)
		(end 106.392218 -228.790246)
		(width 0.1143)
		(layer "In4.Cu")
		(net "P5E_CPU1_G1_RX_DN<5>")
	)
	(segment
		(start 105.95229 -225.366072)
		(end 105.954576 -225.367342)
		(width 0.1143)
		(layer "In4.Cu")
		(net "P5E_CPU1_G1_RX_DN<5>")
	)
	(segment
		(start 46.355762 -26.609294)
		(end 46.356524 -26.611326)
		(width 0.14224)
		(layer "In4.Cu")
		(net "P5E_CPU1_G1_RX_DN<5>")
	)
	(segment
		(start 53.181504 -48.202596)
		(end 55.944008 -53.306726)
		(width 0.14224)
		(layer "In4.Cu")
		(net "P5E_CPU1_G1_RX_DN<5>")
	)
	(segment
		(start 105.957878 -225.36912)
		(end 105.958894 -225.369628)
		(width 0.1143)
		(layer "In4.Cu")
		(net "P5E_CPU1_G1_RX_DN<5>")
	)
	(segment
		(start 105.483914 -223.911922)
		(end 105.453434 -223.929702)
		(width 0.1143)
		(layer "In4.Cu")
		(net "P5E_CPU1_G1_RX_DN<5>")
	)
	(segment
		(start 106.423206 -227.152454)
		(end 106.392218 -227.170234)
		(width 0.1143)
		(layer "In4.Cu")
		(net "P5E_CPU1_G1_RX_DN<5>")
	)
	(segment
		(start 106.424984 -227.151438)
		(end 106.423968 -227.151946)
		(width 0.1143)
		(layer "In4.Cu")
		(net "P5E_CPU1_G1_RX_DN<5>")
	)
	(segment
		(start 53.181504 -48.20285)
		(end 53.181504 -48.202596)
		(width 0.14224)
		(layer "In4.Cu")
		(net "P5E_CPU1_G1_RX_DN<5>")
	)
	(segment
		(start 46.367954 -26.575512)
		(end 46.355 -26.607008)
		(width 0.14224)
		(layer "In4.Cu")
		(net "P5E_CPU1_G1_RX_DN<5>")
	)
	(segment
		(start 106.423206 -232.65638)
		(end 106.423968 -232.656888)
		(width 0.1143)
		(layer "In4.Cu")
		(net "P5E_CPU1_G1_RX_DN<5>")
	)
	(segment
		(start 46.38548 -26.693368)
		(end 53.181504 -48.20285)
		(width 0.14224)
		(layer "In4.Cu")
		(net "P5E_CPU1_G1_RX_DN<5>")
	)
	(segment
		(start 152.712674 -169.569384)
		(end 152.321514 -170.604434)
		(width 0.14224)
		(layer "In4.Cu")
		(net "P5E_CPU1_G1_RX_DN<5>")
	)
	(segment
		(start 105.746804 -221.378526)
		(end 105.746804 -221.558358)
		(width 0.1143)
		(layer "In4.Cu")
		(net "P5E_CPU1_G1_RX_DN<5>")
	)
	(segment
		(start 106.423206 -226.176586)
		(end 106.423968 -226.177094)
		(width 0.1143)
		(layer "In4.Cu")
		(net "P5E_CPU1_G1_RX_DN<5>")
	)
	(segment
		(start 110.697264 -206.653892)
		(end 105.792524 -214.915242)
		(width 0.14224)
		(layer "In4.Cu")
		(net "P5E_CPU1_G1_RX_DN<5>")
	)
	(segment
		(start 106.455464 -227.815394)
		(end 106.456226 -227.815902)
		(width 0.1143)
		(layer "In4.Cu")
		(net "P5E_CPU1_G1_RX_DN<5>")
	)
	(segment
		(start 43.389296 -6.725158)
		(end 43.098466 -7.015988)
		(width 0.14224)
		(layer "In4.Cu")
		(net "P5E_CPU1_G1_RX_DN<5>")
	)
	(segment
		(start 105.483914 -224.557082)
		(end 105.52303 -224.579942)
		(width 0.1143)
		(layer "In4.Cu")
		(net "P5E_CPU1_G1_RX_DN<5>")
	)
	(segment
		(start 56.415686 -53.731414)
		(end 58.638694 -55.556658)
		(width 0.14224)
		(layer "In4.Cu")
		(net "P5E_CPU1_G1_RX_DN<5>")
	)
	(segment
		(start 105.792524 -221.332806)
		(end 105.746804 -221.378526)
		(width 0.1143)
		(layer "In4.Cu")
		(net "P5E_CPU1_G1_RX_DN<5>")
	)
	(segment
		(start 105.485184 -222.29445)
		(end 105.481882 -222.296228)
		(width 0.1143)
		(layer "In4.Cu")
		(net "P5E_CPU1_G1_RX_DN<5>")
	)
	(segment
		(start 42.639488 -17.815052)
		(end 42.861484 -18.229834)
		(width 0.14224)
		(layer "In4.Cu")
		(net "P5E_CPU1_G1_RX_DN<5>")
	)
	(segment
		(start 46.356524 -26.611326)
		(end 46.357286 -26.613612)
		(width 0.14224)
		(layer "In4.Cu")
		(net "P5E_CPU1_G1_RX_DN<5>")
	)
	(segment
		(start 59.533536 -56.360822)
		(end 60.823602 -57.44083)
		(width 0.14224)
		(layer "In4.Cu")
		(net "P5E_CPU1_G1_RX_DN<5>")
	)
	(segment
		(start 105.955592 -225.36785)
		(end 105.957878 -225.36912)
		(width 0.1143)
		(layer "In4.Cu")
		(net "P5E_CPU1_G1_RX_DN<5>")
	)
	(segment
		(start 106.70032 -233.06151)
		(end 106.783124 -233.144314)
		(width 0.1143)
		(layer "In4.Cu")
		(net "P5E_CPU1_G1_RX_DN<5>")
	)
	(segment
		(start 106.783124 -233.144314)
		(end 107.081066 -233.144314)
		(width 0.1143)
		(layer "In4.Cu")
		(net "P5E_CPU1_G1_RX_DN<5>")
	)
	(segment
		(start 106.423968 -226.177094)
		(end 106.455464 -226.195382)
		(width 0.1143)
		(layer "In4.Cu")
		(net "P5E_CPU1_G1_RX_DN<5>")
	)
	(segment
		(start 42.861484 -18.229834)
		(end 43.916092 -19.807428)
		(width 0.14224)
		(layer "In4.Cu")
		(net "P5E_CPU1_G1_RX_DN<5>")
	)
	(segment
		(start 43.9166 -19.810476)
		(end 44.011596 -20.005802)
		(width 0.14224)
		(layer "In4.Cu")
		(net "P5E_CPU1_G1_RX_DN<5>")
	)
	(segment
		(start 106.230674 -232.327196)
		(end 106.230674 -232.329736)
		(width 0.1143)
		(layer "In4.Cu")
		(net "P5E_CPU1_G1_RX_DN<5>")
	)
	(segment
		(start 106.456226 -232.675684)
		(end 106.463084 -232.679748)
		(width 0.1143)
		(layer "In4.Cu")
		(net "P5E_CPU1_G1_RX_DN<5>")
	)
	(segment
		(start 105.746804 -221.558358)
		(end 105.766362 -221.577916)
		(width 0.1143)
		(layer "In4.Cu")
		(net "P5E_CPU1_G1_RX_DN<5>")
	)
	(segment
		(start 106.426508 -227.150422)
		(end 106.424984 -227.151438)
		(width 0.1143)
		(layer "In4.Cu")
		(net "P5E_CPU1_G1_RX_DN<5>")
	)
	(segment
		(start 106.456226 -226.19589)
		(end 106.463084 -226.199954)
		(width 0.1143)
		(layer "In4.Cu")
		(net "P5E_CPU1_G1_RX_DN<5>")
	)
	(segment
		(start 153.626566 -166.886128)
		(end 153.626566 -166.885874)
		(width 0.14224)
		(layer "In4.Cu")
		(net "P5E_CPU1_G1_RX_DN<5>")
	)
	(segment
		(start 106.39044 -229.397306)
		(end 106.463084 -229.439724)
		(width 0.1143)
		(layer "In4.Cu")
		(net "P5E_CPU1_G1_RX_DN<5>")
	)
	(segment
		(start 43.915838 -19.809206)
		(end 43.9166 -19.810476)
		(width 0.14224)
		(layer "In4.Cu")
		(net "P5E_CPU1_G1_RX_DN<5>")
	)
	(segment
		(start 106.424984 -228.77145)
		(end 106.423968 -228.771958)
		(width 0.1143)
		(layer "In4.Cu")
		(net "P5E_CPU1_G1_RX_DN<5>")
	)
	(segment
		(start 106.463084 -228.749098)
		(end 106.426508 -228.770434)
		(width 0.1143)
		(layer "In4.Cu")
		(net "P5E_CPU1_G1_RX_DN<5>")
	)
	(segment
		(start 106.463084 -227.129086)
		(end 106.426508 -227.150422)
		(width 0.1143)
		(layer "In4.Cu")
		(net "P5E_CPU1_G1_RX_DN<5>")
	)
	(segment
		(start 105.483914 -222.93707)
		(end 105.52303 -222.95993)
		(width 0.1143)
		(layer "In4.Cu")
		(net "P5E_CPU1_G1_RX_DN<5>")
	)
	(segment
		(start 106.423968 -227.151946)
		(end 106.423206 -227.152454)
		(width 0.1143)
		(layer "In4.Cu")
		(net "P5E_CPU1_G1_RX_DN<5>")
	)
	(segment
		(start 106.423968 -227.797106)
		(end 106.455464 -227.815394)
		(width 0.1143)
		(layer "In4.Cu")
		(net "P5E_CPU1_G1_RX_DN<5>")
	)
	(segment
		(start 46.355 -26.607008)
		(end 46.355762 -26.609294)
		(width 0.14224)
		(layer "In4.Cu")
		(net "P5E_CPU1_G1_RX_DN<5>")
	)
	(arc
		(start 105.92054 -231.221534)
		(mid 105.807133 -231.354423)
		(end 105.766362 -231.524302)
		(width 0.1143)
		(layer "In4.Cu")
		(net "P5E_CPU1_G1_RX_DN<5>")
	)
	(arc
		(start 106.392218 -228.790246)
		(mid 106.280421 -228.925047)
		(end 106.236262 -229.094538)
		(width 0.1143)
		(layer "In4.Cu")
		(net "P5E_CPU1_G1_RX_DN<5>")
	)
	(arc
		(start 106.706416 -229.90429)
		(mid 106.631048 -230.186805)
		(end 106.424984 -230.394256)
		(width 0.1143)
		(layer "In4.Cu")
		(net "P5E_CPU1_G1_RX_DN<5>")
	)
	(arc
		(start 105.766362 -221.804484)
		(mid 105.691069 -222.086935)
		(end 105.485184 -222.29445)
		(width 0.1143)
		(layer "In4.Cu")
		(net "P5E_CPU1_G1_RX_DN<5>")
	)
	(arc
		(start 106.230674 -232.329736)
		(mid 106.280924 -232.516818)
		(end 106.418126 -232.653586)
		(width 0.1143)
		(layer "In4.Cu")
		(net "P5E_CPU1_G1_RX_DN<5>")
	)
	(arc
		(start 105.766362 -231.524302)
		(mid 105.807617 -231.695273)
		(end 105.922318 -231.828594)
		(width 0.1143)
		(layer "In4.Cu")
		(net "P5E_CPU1_G1_RX_DN<5>")
	)
	(arc
		(start 106.69651 -233.03865)
		(mid 106.698533 -233.05006)
		(end 106.70032 -233.06151)
		(width 0.1143)
		(layer "In4.Cu")
		(net "P5E_CPU1_G1_RX_DN<5>")
	)
	(arc
		(start 106.463084 -229.439724)
		(mid 106.641897 -229.642074)
		(end 106.706416 -229.90429)
		(width 0.1143)
		(layer "In4.Cu")
		(net "P5E_CPU1_G1_RX_DN<5>")
	)
	(arc
		(start 106.463084 -227.819966)
		(mid 106.706411 -228.284532)
		(end 106.463084 -228.749098)
		(width 0.1143)
		(layer "In4.Cu")
		(net "P5E_CPU1_G1_RX_DN<5>")
	)
	(arc
		(start 105.52303 -222.95993)
		(mid 105.766357 -223.424496)
		(end 105.52303 -223.889062)
		(width 0.1143)
		(layer "In4.Cu")
		(net "P5E_CPU1_G1_RX_DN<5>")
	)
	(arc
		(start 106.392218 -227.170234)
		(mid 106.240629 -227.474526)
		(end 106.392218 -227.778818)
		(width 0.1143)
		(layer "In4.Cu")
		(net "P5E_CPU1_G1_RX_DN<5>")
	)
	(arc
		(start 106.41965 -230.397304)
		(mid 106.285378 -230.531321)
		(end 106.236262 -230.71455)
		(width 0.1143)
		(layer "In4.Cu")
		(net "P5E_CPU1_G1_RX_DN<5>")
	)
	(arc
		(start 106.463084 -226.199954)
		(mid 106.706411 -226.66452)
		(end 106.463084 -227.129086)
		(width 0.1143)
		(layer "In4.Cu")
		(net "P5E_CPU1_G1_RX_DN<5>")
	)
	(arc
		(start 105.766362 -225.044508)
		(mid 105.816185 -225.230238)
		(end 105.95229 -225.366072)
		(width 0.1143)
		(layer "In4.Cu")
		(net "P5E_CPU1_G1_RX_DN<5>")
	)
	(arc
		(start 105.481882 -222.296228)
		(mid 105.298043 -222.600049)
		(end 105.453434 -222.91929)
		(width 0.1143)
		(layer "In4.Cu")
		(net "P5E_CPU1_G1_RX_DN<5>")
	)
	(arc
		(start 106.463084 -232.679748)
		(mid 106.615071 -232.836256)
		(end 106.69651 -233.03865)
		(width 0.1143)
		(layer "In4.Cu")
		(net "P5E_CPU1_G1_RX_DN<5>")
	)
	(arc
		(start 106.236262 -229.094538)
		(mid 106.277024 -229.264422)
		(end 106.39044 -229.397306)
		(width 0.1143)
		(layer "In4.Cu")
		(net "P5E_CPU1_G1_RX_DN<5>")
	)
	(arc
		(start 105.453434 -223.929702)
		(mid 105.296457 -224.234502)
		(end 105.453434 -224.539302)
		(width 0.1143)
		(layer "In4.Cu")
		(net "P5E_CPU1_G1_RX_DN<5>")
	)
	(arc
		(start 106.236262 -225.854514)
		(mid 106.281273 -226.02495)
		(end 106.394504 -226.160076)
		(width 0.1143)
		(layer "In4.Cu")
		(net "P5E_CPU1_G1_RX_DN<5>")
	)
	(arc
		(start 105.954068 -231.846882)
		(mid 106.156608 -232.050052)
		(end 106.230674 -232.327196)
		(width 0.1143)
		(layer "In4.Cu")
		(net "P5E_CPU1_G1_RX_DN<5>")
	)
	(arc
		(start 106.236262 -230.71455)
		(mid 106.171026 -230.978141)
		(end 105.99039 -231.180894)
		(width 0.1143)
		(layer "In4.Cu")
		(net "P5E_CPU1_G1_RX_DN<5>")
	)
	(arc
		(start 105.99039 -225.38817)
		(mid 106.171042 -225.590915)
		(end 106.236262 -225.854514)
		(width 0.1143)
		(layer "In4.Cu")
		(net "P5E_CPU1_G1_RX_DN<5>")
	)
	(arc
		(start 105.52303 -224.579942)
		(mid 105.701843 -224.782292)
		(end 105.766362 -225.044508)
		(width 0.1143)
		(layer "In4.Cu")
		(net "P5E_CPU1_G1_RX_DN<5>")
	)
	(segment
		(start 19.608292 -7.57047)
		(end 19.608292 -6.996176)
		(width 0.12954)
		(layer "F.Cu")
		(net "P5E_CPU1_G1_RX_DN<15>")
	)
	(segment
		(start 99.08794 -235.030264)
		(end 98.621088 -234.764326)
		(width 0.12954)
		(layer "F.Cu")
		(net "P5E_CPU1_G1_RX_DN<15>")
	)
	(segment
		(start 19.746976 -7.709154)
		(end 19.608292 -7.57047)
		(width 0.12954)
		(layer "F.Cu")
		(net "P5E_CPU1_G1_RX_DN<15>")
	)
	(segment
		(start 19.746976 -8.320024)
		(end 19.746976 -7.709154)
		(width 0.12954)
		(layer "F.Cu")
		(net "P5E_CPU1_G1_RX_DN<15>")
	)
	(segment
		(start 19.608292 -6.996176)
		(end 19.87931 -6.725158)
		(width 0.12954)
		(layer "F.Cu")
		(net "P5E_CPU1_G1_RX_DN<15>")
	)
	(segment
		(start 34.23539 -44.530772)
		(end 49.478692 -60.419742)
		(width 0.14224)
		(layer "In4.Cu")
		(net "P5E_CPU1_G1_RX_DN<15>")
	)
	(segment
		(start 95.361252 -221.334076)
		(end 95.361252 -221.513908)
		(width 0.1143)
		(layer "In4.Cu")
		(net "P5E_CPU1_G1_RX_DN<15>")
	)
	(segment
		(start 95.426276 -221.578932)
		(end 95.426276 -221.804484)
		(width 0.1143)
		(layer "In4.Cu")
		(net "P5E_CPU1_G1_RX_DN<15>")
	)
	(segment
		(start 97.063052 -228.749098)
		(end 97.023936 -228.771958)
		(width 0.1143)
		(layer "In4.Cu")
		(net "P5E_CPU1_G1_RX_DN<15>")
	)
	(segment
		(start 97.023936 -227.151946)
		(end 96.993456 -227.169726)
		(width 0.1143)
		(layer "In4.Cu")
		(net "P5E_CPU1_G1_RX_DN<15>")
	)
	(segment
		(start 96.991424 -229.398068)
		(end 97.023936 -229.416864)
		(width 0.1143)
		(layer "In4.Cu")
		(net "P5E_CPU1_G1_RX_DN<15>")
	)
	(segment
		(start 144.143222 -164.634926)
		(end 140.436854 -170.218354)
		(width 0.14224)
		(layer "In4.Cu")
		(net "P5E_CPU1_G1_RX_DN<15>")
	)
	(segment
		(start 97.023936 -228.771958)
		(end 96.993456 -228.789738)
		(width 0.1143)
		(layer "In4.Cu")
		(net "P5E_CPU1_G1_RX_DN<15>")
	)
	(segment
		(start 97.023936 -227.797106)
		(end 97.063052 -227.819966)
		(width 0.1143)
		(layer "In4.Cu")
		(net "P5E_CPU1_G1_RX_DN<15>")
	)
	(segment
		(start 96.554036 -225.367088)
		(end 96.555052 -225.367596)
		(width 0.1143)
		(layer "In4.Cu")
		(net "P5E_CPU1_G1_RX_DN<15>")
	)
	(segment
		(start 97.963482 -234.2769)
		(end 97.96399 -234.2769)
		(width 0.1143)
		(layer "In4.Cu")
		(net "P5E_CPU1_G1_RX_DN<15>")
	)
	(segment
		(start 97.490534 -233.463084)
		(end 97.492058 -233.463846)
		(width 0.1143)
		(layer "In4.Cu")
		(net "P5E_CPU1_G1_RX_DN<15>")
	)
	(segment
		(start 96.552004 -231.845612)
		(end 96.553274 -231.846374)
		(width 0.1143)
		(layer "In4.Cu")
		(net "P5E_CPU1_G1_RX_DN<15>")
	)
	(segment
		(start 97.060512 -230.370634)
		(end 96.993456 -230.40975)
		(width 0.1143)
		(layer "In4.Cu")
		(net "P5E_CPU1_G1_RX_DN<15>")
	)
	(segment
		(start 96.553274 -231.846374)
		(end 96.554036 -231.846882)
		(width 0.1143)
		(layer "In4.Cu")
		(net "P5E_CPU1_G1_RX_DN<15>")
	)
	(segment
		(start 96.993456 -232.639108)
		(end 97.023936 -232.656888)
		(width 0.1143)
		(layer "In4.Cu")
		(net "P5E_CPU1_G1_RX_DN<15>")
	)
	(segment
		(start 97.96399 -234.2769)
		(end 97.965006 -234.277408)
		(width 0.1143)
		(layer "In4.Cu")
		(net "P5E_CPU1_G1_RX_DN<15>")
	)
	(segment
		(start 96.593152 -231.179116)
		(end 96.554036 -231.201976)
		(width 0.1143)
		(layer "In4.Cu")
		(net "P5E_CPU1_G1_RX_DN<15>")
	)
	(segment
		(start 96.083882 -222.93707)
		(end 96.122998 -222.95993)
		(width 0.1143)
		(layer "In4.Cu")
		(net "P5E_CPU1_G1_RX_DN<15>")
	)
	(segment
		(start 141.949424 -143.176752)
		(end 144.230598 -147.893532)
		(width 0.14224)
		(layer "In4.Cu")
		(net "P5E_CPU1_G1_RX_DN<15>")
	)
	(segment
		(start 96.522286 -231.828594)
		(end 96.548702 -231.843834)
		(width 0.1143)
		(layer "In4.Cu")
		(net "P5E_CPU1_G1_RX_DN<15>")
	)
	(segment
		(start 98.323146 -234.764326)
		(end 98.621088 -234.764326)
		(width 0.1143)
		(layer "In4.Cu")
		(net "P5E_CPU1_G1_RX_DN<15>")
	)
	(segment
		(start 96.083882 -223.911922)
		(end 96.053402 -223.929702)
		(width 0.1143)
		(layer "In4.Cu")
		(net "P5E_CPU1_G1_RX_DN<15>")
	)
	(segment
		(start 19.165316 -12.933172)
		(end 14.69009 -16.606012)
		(width 0.14224)
		(layer "In4.Cu")
		(net "P5E_CPU1_G1_RX_DN<15>")
	)
	(segment
		(start 97.023936 -232.656888)
		(end 97.063052 -232.679748)
		(width 0.1143)
		(layer "In4.Cu")
		(net "P5E_CPU1_G1_RX_DN<15>")
	)
	(segment
		(start 144.230598 -147.893532)
		(end 144.99717 -160.118806)
		(width 0.14224)
		(layer "In4.Cu")
		(net "P5E_CPU1_G1_RX_DN<15>")
	)
	(segment
		(start 54.382924 -64.431926)
		(end 141.949424 -143.176752)
		(width 0.14224)
		(layer "In4.Cu")
		(net "P5E_CPU1_G1_RX_DN<15>")
	)
	(segment
		(start 95.406972 -221.288356)
		(end 95.361252 -221.334076)
		(width 0.1143)
		(layer "In4.Cu")
		(net "P5E_CPU1_G1_RX_DN<15>")
	)
	(segment
		(start 96.556576 -231.848406)
		(end 96.593152 -231.869742)
		(width 0.1143)
		(layer "In4.Cu")
		(net "P5E_CPU1_G1_RX_DN<15>")
	)
	(segment
		(start 96.555052 -225.367596)
		(end 96.556576 -225.368612)
		(width 0.1143)
		(layer "In4.Cu")
		(net "P5E_CPU1_G1_RX_DN<15>")
	)
	(segment
		(start 95.582232 -222.108776)
		(end 95.613982 -222.127064)
		(width 0.1143)
		(layer "In4.Cu")
		(net "P5E_CPU1_G1_RX_DN<15>")
	)
	(segment
		(start 97.965006 -234.277408)
		(end 97.96653 -234.278424)
		(width 0.1143)
		(layer "In4.Cu")
		(net "P5E_CPU1_G1_RX_DN<15>")
	)
	(segment
		(start 144.99717 -162.126168)
		(end 144.143222 -164.634926)
		(width 0.14224)
		(layer "In4.Cu")
		(net "P5E_CPU1_G1_RX_DN<15>")
	)
	(segment
		(start 96.522286 -225.3488)
		(end 96.548702 -225.36404)
		(width 0.1143)
		(layer "In4.Cu")
		(net "P5E_CPU1_G1_RX_DN<15>")
	)
	(segment
		(start 96.554036 -231.201976)
		(end 96.520508 -231.221534)
		(width 0.1143)
		(layer "In4.Cu")
		(net "P5E_CPU1_G1_RX_DN<15>")
	)
	(segment
		(start 14.417548 -17.841214)
		(end 34.23539 -44.530772)
		(width 0.14224)
		(layer "In4.Cu")
		(net "P5E_CPU1_G1_RX_DN<15>")
	)
	(segment
		(start 96.555052 -231.84739)
		(end 96.556576 -231.848406)
		(width 0.1143)
		(layer "In4.Cu")
		(net "P5E_CPU1_G1_RX_DN<15>")
	)
	(segment
		(start 95.613982 -222.127064)
		(end 95.653098 -222.149924)
		(width 0.1143)
		(layer "In4.Cu")
		(net "P5E_CPU1_G1_RX_DN<15>")
	)
	(segment
		(start 96.122998 -223.889062)
		(end 96.083882 -223.911922)
		(width 0.1143)
		(layer "In4.Cu")
		(net "P5E_CPU1_G1_RX_DN<15>")
	)
	(segment
		(start 96.556576 -225.368612)
		(end 96.593152 -225.389948)
		(width 0.1143)
		(layer "In4.Cu")
		(net "P5E_CPU1_G1_RX_DN<15>")
	)
	(segment
		(start 96.55048 -231.84485)
		(end 96.552004 -231.845612)
		(width 0.1143)
		(layer "In4.Cu")
		(net "P5E_CPU1_G1_RX_DN<15>")
	)
	(segment
		(start 49.478692 -60.419742)
		(end 54.382924 -64.431926)
		(width 0.14224)
		(layer "In4.Cu")
		(net "P5E_CPU1_G1_RX_DN<15>")
	)
	(segment
		(start 96.549718 -225.364548)
		(end 96.55048 -225.365056)
		(width 0.1143)
		(layer "In4.Cu")
		(net "P5E_CPU1_G1_RX_DN<15>")
	)
	(segment
		(start 96.552004 -225.365818)
		(end 96.553274 -225.36658)
		(width 0.1143)
		(layer "In4.Cu")
		(net "P5E_CPU1_G1_RX_DN<15>")
	)
	(segment
		(start 97.96653 -234.278424)
		(end 98.003106 -234.29976)
		(width 0.1143)
		(layer "In4.Cu")
		(net "P5E_CPU1_G1_RX_DN<15>")
	)
	(segment
		(start 96.053402 -222.91929)
		(end 96.083882 -222.93707)
		(width 0.1143)
		(layer "In4.Cu")
		(net "P5E_CPU1_G1_RX_DN<15>")
	)
	(segment
		(start 96.548702 -225.36404)
		(end 96.549718 -225.364548)
		(width 0.1143)
		(layer "In4.Cu")
		(net "P5E_CPU1_G1_RX_DN<15>")
	)
	(segment
		(start 98.240342 -234.681522)
		(end 98.323146 -234.764326)
		(width 0.1143)
		(layer "In4.Cu")
		(net "P5E_CPU1_G1_RX_DN<15>")
	)
	(segment
		(start 96.554036 -231.846882)
		(end 96.555052 -231.84739)
		(width 0.1143)
		(layer "In4.Cu")
		(net "P5E_CPU1_G1_RX_DN<15>")
	)
	(segment
		(start 96.993456 -226.159314)
		(end 97.023936 -226.177094)
		(width 0.1143)
		(layer "In4.Cu")
		(net "P5E_CPU1_G1_RX_DN<15>")
	)
	(segment
		(start 14.34973 -17.640046)
		(end 14.417548 -17.841214)
		(width 0.14224)
		(layer "In4.Cu")
		(net "P5E_CPU1_G1_RX_DN<15>")
	)
	(segment
		(start 96.548702 -231.843834)
		(end 96.549718 -231.844342)
		(width 0.1143)
		(layer "In4.Cu")
		(net "P5E_CPU1_G1_RX_DN<15>")
	)
	(segment
		(start 97.54108 -233.495342)
		(end 97.540826 -233.495596)
		(width 0.1143)
		(layer "In4.Cu")
		(net "P5E_CPU1_G1_RX_DN<15>")
	)
	(segment
		(start 97.492058 -233.463846)
		(end 97.494598 -233.46537)
		(width 0.1143)
		(layer "In4.Cu")
		(net "P5E_CPU1_G1_RX_DN<15>")
	)
	(segment
		(start 97.023936 -229.416864)
		(end 97.063052 -229.439724)
		(width 0.1143)
		(layer "In4.Cu")
		(net "P5E_CPU1_G1_RX_DN<15>")
	)
	(segment
		(start 97.063052 -227.129086)
		(end 97.023936 -227.151946)
		(width 0.1143)
		(layer "In4.Cu")
		(net "P5E_CPU1_G1_RX_DN<15>")
	)
	(segment
		(start 96.053402 -224.539302)
		(end 96.083882 -224.557082)
		(width 0.1143)
		(layer "In4.Cu")
		(net "P5E_CPU1_G1_RX_DN<15>")
	)
	(segment
		(start 19.58848 -11.911584)
		(end 19.165316 -12.933172)
		(width 0.14224)
		(layer "In4.Cu")
		(net "P5E_CPU1_G1_RX_DN<15>")
	)
	(segment
		(start 97.023936 -226.177094)
		(end 97.063052 -226.199954)
		(width 0.1143)
		(layer "In4.Cu")
		(net "P5E_CPU1_G1_RX_DN<15>")
	)
	(segment
		(start 96.993456 -227.779326)
		(end 97.023936 -227.797106)
		(width 0.1143)
		(layer "In4.Cu")
		(net "P5E_CPU1_G1_RX_DN<15>")
	)
	(segment
		(start 96.553274 -225.36658)
		(end 96.554036 -225.367088)
		(width 0.1143)
		(layer "In4.Cu")
		(net "P5E_CPU1_G1_RX_DN<15>")
	)
	(segment
		(start 96.55048 -225.365056)
		(end 96.552004 -225.365818)
		(width 0.1143)
		(layer "In4.Cu")
		(net "P5E_CPU1_G1_RX_DN<15>")
	)
	(segment
		(start 19.58848 -7.015988)
		(end 19.58848 -11.911584)
		(width 0.14224)
		(layer "In4.Cu")
		(net "P5E_CPU1_G1_RX_DN<15>")
	)
	(segment
		(start 97.788984 -233.963972)
		(end 97.788984 -233.973624)
		(width 0.1143)
		(layer "In4.Cu")
		(net "P5E_CPU1_G1_RX_DN<15>")
	)
	(segment
		(start 144.99717 -160.118806)
		(end 144.99717 -162.126168)
		(width 0.14224)
		(layer "In4.Cu")
		(net "P5E_CPU1_G1_RX_DN<15>")
	)
	(segment
		(start 96.549718 -231.844342)
		(end 96.55048 -231.84485)
		(width 0.1143)
		(layer "In4.Cu")
		(net "P5E_CPU1_G1_RX_DN<15>")
	)
	(segment
		(start 140.436854 -170.218354)
		(end 103.022146 -200.861422)
		(width 0.14224)
		(layer "In4.Cu")
		(net "P5E_CPU1_G1_RX_DN<15>")
	)
	(segment
		(start 103.022146 -200.861422)
		(end 95.406972 -213.75116)
		(width 0.14224)
		(layer "In4.Cu")
		(net "P5E_CPU1_G1_RX_DN<15>")
	)
	(segment
		(start 95.361252 -221.513908)
		(end 95.426276 -221.578932)
		(width 0.1143)
		(layer "In4.Cu")
		(net "P5E_CPU1_G1_RX_DN<15>")
	)
	(segment
		(start 95.406972 -213.75116)
		(end 95.406972 -221.259908)
		(width 0.14224)
		(layer "In4.Cu")
		(net "P5E_CPU1_G1_RX_DN<15>")
	)
	(segment
		(start 95.406972 -221.259908)
		(end 95.406972 -221.288356)
		(width 0.1143)
		(layer "In4.Cu")
		(net "P5E_CPU1_G1_RX_DN<15>")
	)
	(segment
		(start 19.87931 -6.725158)
		(end 19.58848 -7.015988)
		(width 0.14224)
		(layer "In4.Cu")
		(net "P5E_CPU1_G1_RX_DN<15>")
	)
	(segment
		(start 97.494598 -233.46537)
		(end 97.494852 -233.46537)
		(width 0.1143)
		(layer "In4.Cu")
		(net "P5E_CPU1_G1_RX_DN<15>")
	)
	(segment
		(start 14.69009 -16.606012)
		(end 14.34973 -17.427194)
		(width 0.14224)
		(layer "In4.Cu")
		(net "P5E_CPU1_G1_RX_DN<15>")
	)
	(segment
		(start 14.34973 -17.427194)
		(end 14.34973 -17.640046)
		(width 0.14224)
		(layer "In4.Cu")
		(net "P5E_CPU1_G1_RX_DN<15>")
	)
	(segment
		(start 96.083882 -224.557082)
		(end 96.122998 -224.579942)
		(width 0.1143)
		(layer "In4.Cu")
		(net "P5E_CPU1_G1_RX_DN<15>")
	)
	(arc
		(start 96.993456 -227.169726)
		(mid 96.836479 -227.474526)
		(end 96.993456 -227.779326)
		(width 0.1143)
		(layer "In4.Cu")
		(net "P5E_CPU1_G1_RX_DN<15>")
	)
	(arc
		(start 96.836484 -230.71455)
		(mid 96.771969 -230.976769)
		(end 96.593152 -231.179116)
		(width 0.1143)
		(layer "In4.Cu")
		(net "P5E_CPU1_G1_RX_DN<15>")
	)
	(arc
		(start 96.122998 -224.579942)
		(mid 96.301811 -224.782292)
		(end 96.36633 -225.044508)
		(width 0.1143)
		(layer "In4.Cu")
		(net "P5E_CPU1_G1_RX_DN<15>")
	)
	(arc
		(start 96.836484 -225.854514)
		(mid 96.878033 -226.025936)
		(end 96.993456 -226.159314)
		(width 0.1143)
		(layer "In4.Cu")
		(net "P5E_CPU1_G1_RX_DN<15>")
	)
	(arc
		(start 96.36633 -225.044508)
		(mid 96.407585 -225.215479)
		(end 96.522286 -225.3488)
		(width 0.1143)
		(layer "In4.Cu")
		(net "P5E_CPU1_G1_RX_DN<15>")
	)
	(arc
		(start 97.063052 -227.819966)
		(mid 97.306379 -228.284532)
		(end 97.063052 -228.749098)
		(width 0.1143)
		(layer "In4.Cu")
		(net "P5E_CPU1_G1_RX_DN<15>")
	)
	(arc
		(start 96.836484 -229.094538)
		(mid 96.87745 -229.264944)
		(end 96.991424 -229.398068)
		(width 0.1143)
		(layer "In4.Cu")
		(net "P5E_CPU1_G1_RX_DN<15>")
	)
	(arc
		(start 96.053402 -223.929702)
		(mid 95.896425 -224.234502)
		(end 96.053402 -224.539302)
		(width 0.1143)
		(layer "In4.Cu")
		(net "P5E_CPU1_G1_RX_DN<15>")
	)
	(arc
		(start 97.063052 -229.439724)
		(mid 97.241865 -229.642074)
		(end 97.306384 -229.90429)
		(width 0.1143)
		(layer "In4.Cu")
		(net "P5E_CPU1_G1_RX_DN<15>")
	)
	(arc
		(start 96.36633 -231.524302)
		(mid 96.407585 -231.695273)
		(end 96.522286 -231.828594)
		(width 0.1143)
		(layer "In4.Cu")
		(net "P5E_CPU1_G1_RX_DN<15>")
	)
	(arc
		(start 97.063052 -232.679748)
		(mid 97.241865 -232.882098)
		(end 97.306384 -233.144314)
		(width 0.1143)
		(layer "In4.Cu")
		(net "P5E_CPU1_G1_RX_DN<15>")
	)
	(arc
		(start 96.593152 -225.389948)
		(mid 96.771965 -225.592298)
		(end 96.836484 -225.854514)
		(width 0.1143)
		(layer "In4.Cu")
		(net "P5E_CPU1_G1_RX_DN<15>")
	)
	(arc
		(start 96.520508 -231.221534)
		(mid 96.407101 -231.354423)
		(end 96.36633 -231.524302)
		(width 0.1143)
		(layer "In4.Cu")
		(net "P5E_CPU1_G1_RX_DN<15>")
	)
	(arc
		(start 97.306384 -233.144314)
		(mid 97.355724 -233.328392)
		(end 97.490534 -233.463084)
		(width 0.1143)
		(layer "In4.Cu")
		(net "P5E_CPU1_G1_RX_DN<15>")
	)
	(arc
		(start 97.494852 -233.46537)
		(mid 97.51833 -233.479794)
		(end 97.54108 -233.495342)
		(width 0.1143)
		(layer "In4.Cu")
		(net "P5E_CPU1_G1_RX_DN<15>")
	)
	(arc
		(start 95.89643 -222.61449)
		(mid 95.937979 -222.785912)
		(end 96.053402 -222.91929)
		(width 0.1143)
		(layer "In4.Cu")
		(net "P5E_CPU1_G1_RX_DN<15>")
	)
	(arc
		(start 96.122998 -222.95993)
		(mid 96.366325 -223.424496)
		(end 96.122998 -223.889062)
		(width 0.1143)
		(layer "In4.Cu")
		(net "P5E_CPU1_G1_RX_DN<15>")
	)
	(arc
		(start 95.653098 -222.149924)
		(mid 95.831911 -222.352274)
		(end 95.89643 -222.61449)
		(width 0.1143)
		(layer "In4.Cu")
		(net "P5E_CPU1_G1_RX_DN<15>")
	)
	(arc
		(start 96.593152 -231.869742)
		(mid 96.771965 -232.072092)
		(end 96.836484 -232.334308)
		(width 0.1143)
		(layer "In4.Cu")
		(net "P5E_CPU1_G1_RX_DN<15>")
	)
	(arc
		(start 97.063052 -226.199954)
		(mid 97.306379 -226.66452)
		(end 97.063052 -227.129086)
		(width 0.1143)
		(layer "In4.Cu")
		(net "P5E_CPU1_G1_RX_DN<15>")
	)
	(arc
		(start 96.993456 -230.40975)
		(mid 96.878029 -230.543126)
		(end 96.836484 -230.71455)
		(width 0.1143)
		(layer "In4.Cu")
		(net "P5E_CPU1_G1_RX_DN<15>")
	)
	(arc
		(start 97.306384 -229.90429)
		(mid 97.241148 -230.167881)
		(end 97.060512 -230.370634)
		(width 0.1143)
		(layer "In4.Cu")
		(net "P5E_CPU1_G1_RX_DN<15>")
	)
	(arc
		(start 96.993456 -228.789738)
		(mid 96.878029 -228.923114)
		(end 96.836484 -229.094538)
		(width 0.1143)
		(layer "In4.Cu")
		(net "P5E_CPU1_G1_RX_DN<15>")
	)
	(arc
		(start 97.540826 -233.495596)
		(mid 97.723152 -233.69892)
		(end 97.788984 -233.963972)
		(width 0.1143)
		(layer "In4.Cu")
		(net "P5E_CPU1_G1_RX_DN<15>")
	)
	(arc
		(start 98.003106 -234.29976)
		(mid 98.155093 -234.456268)
		(end 98.236532 -234.658662)
		(width 0.1143)
		(layer "In4.Cu")
		(net "P5E_CPU1_G1_RX_DN<15>")
	)
	(arc
		(start 96.836484 -232.334308)
		(mid 96.878033 -232.50573)
		(end 96.993456 -232.639108)
		(width 0.1143)
		(layer "In4.Cu")
		(net "P5E_CPU1_G1_RX_DN<15>")
	)
	(arc
		(start 97.788984 -233.973624)
		(mid 97.835724 -234.148569)
		(end 97.963482 -234.2769)
		(width 0.1143)
		(layer "In4.Cu")
		(net "P5E_CPU1_G1_RX_DN<15>")
	)
	(arc
		(start 98.236532 -234.658662)
		(mid 98.238555 -234.670072)
		(end 98.240342 -234.681522)
		(width 0.1143)
		(layer "In4.Cu")
		(net "P5E_CPU1_G1_RX_DN<15>")
	)
	(arc
		(start 95.426276 -221.804484)
		(mid 95.467531 -221.975455)
		(end 95.582232 -222.108776)
		(width 0.1143)
		(layer "In4.Cu")
		(net "P5E_CPU1_G1_RX_DN<15>")
	)
	(segment
		(start 103.787956 -230.170228)
		(end 103.321104 -229.90429)
		(width 0.12954)
		(layer "F.Cu")
		(net "GMI_CPU0_G2_CPU1_G0_TX_DP<9>")
	)
	(segment
		(start 367.707926 -230.169974)
		(end 368.174778 -229.904036)
		(width 0.12954)
		(layer "F.Cu")
		(net "GMI_CPU0_G2_CPU1_G0_TX_DP<9>")
	)
	(segment
		(start 103.619046 -229.90429)
		(end 103.70185 -229.821486)
		(width 0.1143)
		(layer "In2.Cu")
		(net "GMI_CPU0_G2_CPU1_G0_TX_DP<9>")
	)
	(segment
		(start 366.107726 -225.366834)
		(end 366.139222 -225.385122)
		(width 0.1143)
		(layer "In2.Cu")
		(net "GMI_CPU0_G2_CPU1_G0_TX_DP<9>")
	)
	(segment
		(start 105.388918 -224.722436)
		(end 105.388156 -224.721928)
		(width 0.1143)
		(layer "In2.Cu")
		(net "GMI_CPU0_G2_CPU1_G0_TX_DP<9>")
	)
	(segment
		(start 366.099852 -222.122238)
		(end 366.101122 -222.123)
		(width 0.1143)
		(layer "In2.Cu")
		(net "GMI_CPU0_G2_CPU1_G0_TX_DP<9>")
	)
	(segment
		(start 104.408986 -228.629972)
		(end 104.441752 -228.610922)
		(width 0.1143)
		(layer "In2.Cu")
		(net "GMI_CPU0_G2_CPU1_G0_TX_DP<9>")
	)
	(segment
		(start 360.375454 -213.097618)
		(end 364.927388 -217.06586)
		(width 0.14224)
		(layer "In2.Cu")
		(net "GMI_CPU0_G2_CPU1_G0_TX_DP<9>")
	)
	(segment
		(start 366.106964 -226.342194)
		(end 366.075976 -226.359974)
		(width 0.1143)
		(layer "In2.Cu")
		(net "GMI_CPU0_G2_CPU1_G0_TX_DP<9>")
	)
	(segment
		(start 104.448102 -228.607112)
		(end 104.448864 -228.606604)
		(width 0.1143)
		(layer "In2.Cu")
		(net "GMI_CPU0_G2_CPU1_G0_TX_DP<9>")
	)
	(segment
		(start 105.35666 -224.70364)
		(end 105.355898 -224.703132)
		(width 0.1143)
		(layer "In2.Cu")
		(net "GMI_CPU0_G2_CPU1_G0_TX_DP<9>")
	)
	(segment
		(start 104.918256 -227.797106)
		(end 104.948736 -227.779326)
		(width 0.1143)
		(layer "In2.Cu")
		(net "GMI_CPU0_G2_CPU1_G0_TX_DP<9>")
	)
	(segment
		(start 105.38714 -224.72142)
		(end 105.35666 -224.70364)
		(width 0.1143)
		(layer "In2.Cu")
		(net "GMI_CPU0_G2_CPU1_G0_TX_DP<9>")
	)
	(segment
		(start 105.381806 -225.370898)
		(end 105.382568 -225.37039)
		(width 0.1143)
		(layer "In2.Cu")
		(net "GMI_CPU0_G2_CPU1_G0_TX_DP<9>")
	)
	(segment
		(start 308.181756 -183.540654)
		(end 309.686452 -184.11444)
		(width 0.14224)
		(layer "In2.Cu")
		(net "GMI_CPU0_G2_CPU1_G0_TX_DP<9>")
	)
	(segment
		(start 105.383838 -226.98964)
		(end 105.385616 -226.988624)
		(width 0.1143)
		(layer "In2.Cu")
		(net "GMI_CPU0_G2_CPU1_G0_TX_DP<9>")
	)
	(segment
		(start 366.146842 -226.318826)
		(end 366.110266 -226.340162)
		(width 0.1143)
		(layer "In2.Cu")
		(net "GMI_CPU0_G2_CPU1_G0_TX_DP<9>")
	)
	(segment
		(start 366.075976 -225.348546)
		(end 366.105694 -225.365564)
		(width 0.1143)
		(layer "In2.Cu")
		(net "GMI_CPU0_G2_CPU1_G0_TX_DP<9>")
	)
	(segment
		(start 105.382568 -223.750378)
		(end 105.383838 -223.749616)
		(width 0.1143)
		(layer "In2.Cu")
		(net "GMI_CPU0_G2_CPU1_G0_TX_DP<9>")
	)
	(segment
		(start 110.955836 -210.425284)
		(end 110.95609 -210.425284)
		(width 0.14224)
		(layer "In2.Cu")
		(net "GMI_CPU0_G2_CPU1_G0_TX_DP<9>")
	)
	(segment
		(start 367.794032 -229.821232)
		(end 367.876836 -229.904036)
		(width 0.1143)
		(layer "In2.Cu")
		(net "GMI_CPU0_G2_CPU1_G0_TX_DP<9>")
	)
	(segment
		(start 105.35666 -223.083628)
		(end 105.355898 -223.08312)
		(width 0.1143)
		(layer "In2.Cu")
		(net "GMI_CPU0_G2_CPU1_G0_TX_DP<9>")
	)
	(segment
		(start 105.388918 -223.102424)
		(end 105.388156 -223.101916)
		(width 0.1143)
		(layer "In2.Cu")
		(net "GMI_CPU0_G2_CPU1_G0_TX_DP<9>")
	)
	(segment
		(start 105.383838 -223.749616)
		(end 105.385616 -223.7486)
		(width 0.1143)
		(layer "In2.Cu")
		(net "GMI_CPU0_G2_CPU1_G0_TX_DP<9>")
	)
	(segment
		(start 366.106964 -224.722182)
		(end 366.075976 -224.739962)
		(width 0.1143)
		(layer "In2.Cu")
		(net "GMI_CPU0_G2_CPU1_G0_TX_DP<9>")
	)
	(segment
		(start 104.65435 -221.248732)
		(end 104.60863 -221.203012)
		(width 0.1143)
		(layer "In2.Cu")
		(net "GMI_CPU0_G2_CPU1_G0_TX_DP<9>")
	)
	(segment
		(start 366.107726 -224.721674)
		(end 366.106964 -224.722182)
		(width 0.1143)
		(layer "In2.Cu")
		(net "GMI_CPU0_G2_CPU1_G0_TX_DP<9>")
	)
	(segment
		(start 366.135158 -227.002594)
		(end 366.13846 -227.004626)
		(width 0.1143)
		(layer "In2.Cu")
		(net "GMI_CPU0_G2_CPU1_G0_TX_DP<9>")
	)
	(segment
		(start 103.939086 -229.439724)
		(end 103.978202 -229.416864)
		(width 0.1143)
		(layer "In2.Cu")
		(net "GMI_CPU0_G2_CPU1_G0_TX_DP<9>")
	)
	(segment
		(start 103.978202 -229.416864)
		(end 104.010714 -229.398068)
		(width 0.1143)
		(layer "In2.Cu")
		(net "GMI_CPU0_G2_CPU1_G0_TX_DP<9>")
	)
	(segment
		(start 366.108742 -226.341178)
		(end 366.107726 -226.341686)
		(width 0.1143)
		(layer "In2.Cu")
		(net "GMI_CPU0_G2_CPU1_G0_TX_DP<9>")
	)
	(segment
		(start 104.637332 -221.83344)
		(end 104.637332 -221.469966)
		(width 0.1143)
		(layer "In2.Cu")
		(net "GMI_CPU0_G2_CPU1_G0_TX_DP<9>")
	)
	(segment
		(start 104.948736 -222.30969)
		(end 104.918256 -222.29191)
		(width 0.1143)
		(layer "In2.Cu")
		(net "GMI_CPU0_G2_CPU1_G0_TX_DP<9>")
	)
	(segment
		(start 104.60863 -221.203012)
		(end 104.60863 -221.174564)
		(width 0.1143)
		(layer "In2.Cu")
		(net "GMI_CPU0_G2_CPU1_G0_TX_DP<9>")
	)
	(segment
		(start 365.876078 -221.34703)
		(end 365.92002 -221.390972)
		(width 0.1143)
		(layer "In2.Cu")
		(net "GMI_CPU0_G2_CPU1_G0_TX_DP<9>")
	)
	(segment
		(start 105.34904 -223.769936)
		(end 105.381806 -223.750886)
		(width 0.1143)
		(layer "In2.Cu")
		(net "GMI_CPU0_G2_CPU1_G0_TX_DP<9>")
	)
	(segment
		(start 366.101122 -222.123)
		(end 366.101884 -222.123508)
		(width 0.1143)
		(layer "In2.Cu")
		(net "GMI_CPU0_G2_CPU1_G0_TX_DP<9>")
	)
	(segment
		(start 105.419906 -223.120204)
		(end 105.388918 -223.102424)
		(width 0.1143)
		(layer "In2.Cu")
		(net "GMI_CPU0_G2_CPU1_G0_TX_DP<9>")
	)
	(segment
		(start 105.385616 -226.988624)
		(end 105.38714 -226.987608)
		(width 0.1143)
		(layer "In2.Cu")
		(net "GMI_CPU0_G2_CPU1_G0_TX_DP<9>")
	)
	(segment
		(start 104.65435 -221.452948)
		(end 104.65435 -221.248732)
		(width 0.1143)
		(layer "In2.Cu")
		(net "GMI_CPU0_G2_CPU1_G0_TX_DP<9>")
	)
	(segment
		(start 366.10417 -222.124778)
		(end 366.106964 -222.126302)
		(width 0.1143)
		(layer "In2.Cu")
		(net "GMI_CPU0_G2_CPU1_G0_TX_DP<9>")
	)
	(segment
		(start 105.388156 -226.9871)
		(end 105.388918 -226.986592)
		(width 0.1143)
		(layer "In2.Cu")
		(net "GMI_CPU0_G2_CPU1_G0_TX_DP<9>")
	)
	(segment
		(start 366.101884 -222.123508)
		(end 366.103408 -222.12427)
		(width 0.1143)
		(layer "In2.Cu")
		(net "GMI_CPU0_G2_CPU1_G0_TX_DP<9>")
	)
	(segment
		(start 366.85982 -228.282754)
		(end 366.85982 -228.284024)
		(width 0.1143)
		(layer "In2.Cu")
		(net "GMI_CPU0_G2_CPU1_G0_TX_DP<9>")
	)
	(segment
		(start 366.139222 -225.385122)
		(end 366.139984 -225.38563)
		(width 0.1143)
		(layer "In2.Cu")
		(net "GMI_CPU0_G2_CPU1_G0_TX_DP<9>")
	)
	(segment
		(start 366.146842 -224.698814)
		(end 366.110266 -224.72015)
		(width 0.1143)
		(layer "In2.Cu")
		(net "GMI_CPU0_G2_CPU1_G0_TX_DP<9>")
	)
	(segment
		(start 367.057178 -228.612446)
		(end 367.08588 -228.628956)
		(width 0.1143)
		(layer "In2.Cu")
		(net "GMI_CPU0_G2_CPU1_G0_TX_DP<9>")
	)
	(segment
		(start 366.139984 -225.38563)
		(end 366.146842 -225.389694)
		(width 0.1143)
		(layer "In2.Cu")
		(net "GMI_CPU0_G2_CPU1_G0_TX_DP<9>")
	)
	(segment
		(start 365.92002 -221.390972)
		(end 365.92002 -221.80423)
		(width 0.1143)
		(layer "In2.Cu")
		(net "GMI_CPU0_G2_CPU1_G0_TX_DP<9>")
	)
	(segment
		(start 366.106964 -225.366326)
		(end 366.107726 -225.366834)
		(width 0.1143)
		(layer "In2.Cu")
		(net "GMI_CPU0_G2_CPU1_G0_TX_DP<9>")
	)
	(segment
		(start 366.105694 -223.745552)
		(end 366.106964 -223.746314)
		(width 0.1143)
		(layer "In2.Cu")
		(net "GMI_CPU0_G2_CPU1_G0_TX_DP<9>")
	)
	(segment
		(start 105.419906 -225.3488)
		(end 105.439718 -225.334576)
		(width 0.1143)
		(layer "In2.Cu")
		(net "GMI_CPU0_G2_CPU1_G0_TX_DP<9>")
	)
	(segment
		(start 366.139222 -223.76511)
		(end 366.139984 -223.765618)
		(width 0.1143)
		(layer "In2.Cu")
		(net "GMI_CPU0_G2_CPU1_G0_TX_DP<9>")
	)
	(segment
		(start 367.51768 -229.41661)
		(end 367.556796 -229.43947)
		(width 0.1143)
		(layer "In2.Cu")
		(net "GMI_CPU0_G2_CPU1_G0_TX_DP<9>")
	)
	(segment
		(start 105.385616 -223.7486)
		(end 105.38714 -223.747584)
		(width 0.1143)
		(layer "In2.Cu")
		(net "GMI_CPU0_G2_CPU1_G0_TX_DP<9>")
	)
	(segment
		(start 104.87914 -227.819966)
		(end 104.918256 -227.797106)
		(width 0.1143)
		(layer "In2.Cu")
		(net "GMI_CPU0_G2_CPU1_G0_TX_DP<9>")
	)
	(segment
		(start 366.106964 -226.986338)
		(end 366.107726 -226.986846)
		(width 0.1143)
		(layer "In2.Cu")
		(net "GMI_CPU0_G2_CPU1_G0_TX_DP<9>")
	)
	(segment
		(start 105.38714 -223.101408)
		(end 105.35666 -223.083628)
		(width 0.1143)
		(layer "In2.Cu")
		(net "GMI_CPU0_G2_CPU1_G0_TX_DP<9>")
	)
	(segment
		(start 104.448864 -228.606604)
		(end 104.451658 -228.60508)
		(width 0.1143)
		(layer "In2.Cu")
		(net "GMI_CPU0_G2_CPU1_G0_TX_DP<9>")
	)
	(segment
		(start 105.383838 -225.369628)
		(end 105.385616 -225.368612)
		(width 0.1143)
		(layer "In2.Cu")
		(net "GMI_CPU0_G2_CPU1_G0_TX_DP<9>")
	)
	(segment
		(start 105.388918 -223.746568)
		(end 105.419906 -223.728788)
		(width 0.1143)
		(layer "In2.Cu")
		(net "GMI_CPU0_G2_CPU1_G0_TX_DP<9>")
	)
	(segment
		(start 322.559172 -190.326518)
		(end 356.094538 -210.19643)
		(width 0.14224)
		(layer "In2.Cu")
		(net "GMI_CPU0_G2_CPU1_G0_TX_DP<9>")
	)
	(segment
		(start 366.110266 -224.72015)
		(end 366.108742 -224.721166)
		(width 0.1143)
		(layer "In2.Cu")
		(net "GMI_CPU0_G2_CPU1_G0_TX_DP<9>")
	)
	(segment
		(start 105.381806 -223.750886)
		(end 105.382568 -223.750378)
		(width 0.1143)
		(layer "In2.Cu")
		(net "GMI_CPU0_G2_CPU1_G0_TX_DP<9>")
	)
	(segment
		(start 236.613192 -180.624988)
		(end 306.278534 -183.045608)
		(width 0.14224)
		(layer "In2.Cu")
		(net "GMI_CPU0_G2_CPU1_G0_TX_DP<9>")
	)
	(segment
		(start 366.106964 -223.10217)
		(end 366.075976 -223.11995)
		(width 0.1143)
		(layer "In2.Cu")
		(net "GMI_CPU0_G2_CPU1_G0_TX_DP<9>")
	)
	(segment
		(start 367.484152 -229.397052)
		(end 367.51768 -229.41661)
		(width 0.1143)
		(layer "In2.Cu")
		(net "GMI_CPU0_G2_CPU1_G0_TX_DP<9>")
	)
	(segment
		(start 366.105694 -225.365564)
		(end 366.106964 -225.366326)
		(width 0.1143)
		(layer "In2.Cu")
		(net "GMI_CPU0_G2_CPU1_G0_TX_DP<9>")
	)
	(segment
		(start 110.95609 -210.425284)
		(end 111.574834 -209.80654)
		(width 0.14224)
		(layer "In2.Cu")
		(net "GMI_CPU0_G2_CPU1_G0_TX_DP<9>")
	)
	(segment
		(start 105.38714 -226.341432)
		(end 105.35666 -226.323652)
		(width 0.1143)
		(layer "In2.Cu")
		(net "GMI_CPU0_G2_CPU1_G0_TX_DP<9>")
	)
	(segment
		(start 356.094538 -210.19643)
		(end 360.375454 -213.097618)
		(width 0.14224)
		(layer "In2.Cu")
		(net "GMI_CPU0_G2_CPU1_G0_TX_DP<9>")
	)
	(segment
		(start 366.075976 -223.728534)
		(end 366.105694 -223.745552)
		(width 0.1143)
		(layer "In2.Cu")
		(net "GMI_CPU0_G2_CPU1_G0_TX_DP<9>")
	)
	(segment
		(start 105.439718 -224.75444)
		(end 105.419906 -224.740216)
		(width 0.1143)
		(layer "In2.Cu")
		(net "GMI_CPU0_G2_CPU1_G0_TX_DP<9>")
	)
	(segment
		(start 104.443784 -228.609652)
		(end 104.445562 -228.608636)
		(width 0.1143)
		(layer "In2.Cu")
		(net "GMI_CPU0_G2_CPU1_G0_TX_DP<9>")
	)
	(segment
		(start 104.637332 -221.469966)
		(end 104.65435 -221.452948)
		(width 0.1143)
		(layer "In2.Cu")
		(net "GMI_CPU0_G2_CPU1_G0_TX_DP<9>")
	)
	(segment
		(start 103.321104 -229.90429)
		(end 103.619046 -229.90429)
		(width 0.1143)
		(layer "In2.Cu")
		(net "GMI_CPU0_G2_CPU1_G0_TX_DP<9>")
	)
	(segment
		(start 366.134142 -227.002086)
		(end 366.135158 -227.002594)
		(width 0.1143)
		(layer "In2.Cu")
		(net "GMI_CPU0_G2_CPU1_G0_TX_DP<9>")
	)
	(segment
		(start 105.355898 -226.323144)
		(end 105.34904 -226.31908)
		(width 0.1143)
		(layer "In2.Cu")
		(net "GMI_CPU0_G2_CPU1_G0_TX_DP<9>")
	)
	(segment
		(start 105.419906 -224.740216)
		(end 105.388918 -224.722436)
		(width 0.1143)
		(layer "In2.Cu")
		(net "GMI_CPU0_G2_CPU1_G0_TX_DP<9>")
	)
	(segment
		(start 104.451658 -228.60508)
		(end 104.45242 -228.604572)
		(width 0.1143)
		(layer "In2.Cu")
		(net "GMI_CPU0_G2_CPU1_G0_TX_DP<9>")
	)
	(segment
		(start 366.107726 -226.986846)
		(end 366.134142 -227.002086)
		(width 0.1143)
		(layer "In2.Cu")
		(net "GMI_CPU0_G2_CPU1_G0_TX_DP<9>")
	)
	(segment
		(start 105.388918 -226.342448)
		(end 105.388156 -226.34194)
		(width 0.1143)
		(layer "In2.Cu")
		(net "GMI_CPU0_G2_CPU1_G0_TX_DP<9>")
	)
	(segment
		(start 105.38714 -225.367596)
		(end 105.388156 -225.367088)
		(width 0.1143)
		(layer "In2.Cu")
		(net "GMI_CPU0_G2_CPU1_G0_TX_DP<9>")
	)
	(segment
		(start 366.107726 -222.12681)
		(end 366.108742 -222.127318)
		(width 0.1143)
		(layer "In2.Cu")
		(net "GMI_CPU0_G2_CPU1_G0_TX_DP<9>")
	)
	(segment
		(start 104.447086 -228.60762)
		(end 104.448102 -228.607112)
		(width 0.1143)
		(layer "In2.Cu")
		(net "GMI_CPU0_G2_CPU1_G0_TX_DP<9>")
	)
	(segment
		(start 366.146842 -223.078802)
		(end 366.110266 -223.100138)
		(width 0.1143)
		(layer "In2.Cu")
		(net "GMI_CPU0_G2_CPU1_G0_TX_DP<9>")
	)
	(segment
		(start 366.105694 -226.985576)
		(end 366.106964 -226.986338)
		(width 0.1143)
		(layer "In2.Cu")
		(net "GMI_CPU0_G2_CPU1_G0_TX_DP<9>")
	)
	(segment
		(start 104.60863 -221.174564)
		(end 104.60863 -216.77249)
		(width 0.14224)
		(layer "In2.Cu")
		(net "GMI_CPU0_G2_CPU1_G0_TX_DP<9>")
	)
	(segment
		(start 105.34904 -225.389948)
		(end 105.381806 -225.370898)
		(width 0.1143)
		(layer "In2.Cu")
		(net "GMI_CPU0_G2_CPU1_G0_TX_DP<9>")
	)
	(segment
		(start 365.921798 -221.083124)
		(end 365.876078 -221.128844)
		(width 0.1143)
		(layer "In2.Cu")
		(net "GMI_CPU0_G2_CPU1_G0_TX_DP<9>")
	)
	(segment
		(start 104.445562 -228.608636)
		(end 104.447086 -228.60762)
		(width 0.1143)
		(layer "In2.Cu")
		(net "GMI_CPU0_G2_CPU1_G0_TX_DP<9>")
	)
	(segment
		(start 366.106964 -223.746314)
		(end 366.107726 -223.746822)
		(width 0.1143)
		(layer "In2.Cu")
		(net "GMI_CPU0_G2_CPU1_G0_TX_DP<9>")
	)
	(segment
		(start 366.110266 -223.100138)
		(end 366.108742 -223.101154)
		(width 0.1143)
		(layer "In2.Cu")
		(net "GMI_CPU0_G2_CPU1_G0_TX_DP<9>")
	)
	(segment
		(start 105.382568 -225.37039)
		(end 105.383838 -225.369628)
		(width 0.1143)
		(layer "In2.Cu")
		(net "GMI_CPU0_G2_CPU1_G0_TX_DP<9>")
	)
	(segment
		(start 105.388156 -223.101916)
		(end 105.38714 -223.101408)
		(width 0.1143)
		(layer "In2.Cu")
		(net "GMI_CPU0_G2_CPU1_G0_TX_DP<9>")
	)
	(segment
		(start 309.686452 -184.11444)
		(end 322.559172 -190.326518)
		(width 0.14224)
		(layer "In2.Cu")
		(net "GMI_CPU0_G2_CPU1_G0_TX_DP<9>")
	)
	(segment
		(start 104.918256 -222.29191)
		(end 104.881934 -222.270828)
		(width 0.1143)
		(layer "In2.Cu")
		(net "GMI_CPU0_G2_CPU1_G0_TX_DP<9>")
	)
	(segment
		(start 105.388918 -226.986592)
		(end 105.419906 -226.968812)
		(width 0.1143)
		(layer "In2.Cu")
		(net "GMI_CPU0_G2_CPU1_G0_TX_DP<9>")
	)
	(segment
		(start 164.962332 -183.07177)
		(end 166.330122 -182.712614)
		(width 0.14224)
		(layer "In2.Cu")
		(net "GMI_CPU0_G2_CPU1_G0_TX_DP<9>")
	)
	(segment
		(start 104.442514 -228.610414)
		(end 104.443784 -228.609652)
		(width 0.1143)
		(layer "In2.Cu")
		(net "GMI_CPU0_G2_CPU1_G0_TX_DP<9>")
	)
	(segment
		(start 104.441752 -228.610922)
		(end 104.442514 -228.610414)
		(width 0.1143)
		(layer "In2.Cu")
		(net "GMI_CPU0_G2_CPU1_G0_TX_DP<9>")
	)
	(segment
		(start 105.439718 -223.134428)
		(end 105.419906 -223.120204)
		(width 0.1143)
		(layer "In2.Cu")
		(net "GMI_CPU0_G2_CPU1_G0_TX_DP<9>")
	)
	(segment
		(start 105.385616 -225.368612)
		(end 105.38714 -225.367596)
		(width 0.1143)
		(layer "In2.Cu")
		(net "GMI_CPU0_G2_CPU1_G0_TX_DP<9>")
	)
	(segment
		(start 366.55883 -227.798122)
		(end 366.59058 -227.816918)
		(width 0.1143)
		(layer "In2.Cu")
		(net "GMI_CPU0_G2_CPU1_G0_TX_DP<9>")
	)
	(segment
		(start 155.32608 -186.81319)
		(end 164.962332 -183.07177)
		(width 0.14224)
		(layer "In2.Cu")
		(net "GMI_CPU0_G2_CPU1_G0_TX_DP<9>")
	)
	(segment
		(start 105.388156 -224.721928)
		(end 105.38714 -224.72142)
		(width 0.1143)
		(layer "In2.Cu")
		(net "GMI_CPU0_G2_CPU1_G0_TX_DP<9>")
	)
	(segment
		(start 105.419906 -226.360228)
		(end 105.388918 -226.342448)
		(width 0.1143)
		(layer "In2.Cu")
		(net "GMI_CPU0_G2_CPU1_G0_TX_DP<9>")
	)
	(segment
		(start 105.34904 -227.00996)
		(end 105.381806 -226.99091)
		(width 0.1143)
		(layer "In2.Cu")
		(net "GMI_CPU0_G2_CPU1_G0_TX_DP<9>")
	)
	(segment
		(start 105.388156 -226.34194)
		(end 105.38714 -226.341432)
		(width 0.1143)
		(layer "In2.Cu")
		(net "GMI_CPU0_G2_CPU1_G0_TX_DP<9>")
	)
	(segment
		(start 105.381806 -226.99091)
		(end 105.382568 -226.990402)
		(width 0.1143)
		(layer "In2.Cu")
		(net "GMI_CPU0_G2_CPU1_G0_TX_DP<9>")
	)
	(segment
		(start 366.103408 -222.12427)
		(end 366.10417 -222.124778)
		(width 0.1143)
		(layer "In2.Cu")
		(net "GMI_CPU0_G2_CPU1_G0_TX_DP<9>")
	)
	(segment
		(start 306.278534 -183.045608)
		(end 308.181756 -183.540654)
		(width 0.14224)
		(layer "In2.Cu")
		(net "GMI_CPU0_G2_CPU1_G0_TX_DP<9>")
	)
	(segment
		(start 166.330122 -182.712614)
		(end 236.613192 -180.624988)
		(width 0.14224)
		(layer "In2.Cu")
		(net "GMI_CPU0_G2_CPU1_G0_TX_DP<9>")
	)
	(segment
		(start 366.139984 -223.765618)
		(end 366.146842 -223.769682)
		(width 0.1143)
		(layer "In2.Cu")
		(net "GMI_CPU0_G2_CPU1_G0_TX_DP<9>")
	)
	(segment
		(start 365.876078 -221.128844)
		(end 365.876078 -221.34703)
		(width 0.1143)
		(layer "In2.Cu")
		(net "GMI_CPU0_G2_CPU1_G0_TX_DP<9>")
	)
	(segment
		(start 366.075976 -226.968558)
		(end 366.105694 -226.985576)
		(width 0.1143)
		(layer "In2.Cu")
		(net "GMI_CPU0_G2_CPU1_G0_TX_DP<9>")
	)
	(segment
		(start 365.921798 -219.252292)
		(end 365.921798 -221.083124)
		(width 0.14224)
		(layer "In2.Cu")
		(net "GMI_CPU0_G2_CPU1_G0_TX_DP<9>")
	)
	(segment
		(start 366.108742 -222.127318)
		(end 366.146842 -222.14967)
		(width 0.1143)
		(layer "In2.Cu")
		(net "GMI_CPU0_G2_CPU1_G0_TX_DP<9>")
	)
	(segment
		(start 367.876836 -229.904036)
		(end 368.174778 -229.904036)
		(width 0.1143)
		(layer "In2.Cu")
		(net "GMI_CPU0_G2_CPU1_G0_TX_DP<9>")
	)
	(segment
		(start 105.38714 -223.747584)
		(end 105.388156 -223.747076)
		(width 0.1143)
		(layer "In2.Cu")
		(net "GMI_CPU0_G2_CPU1_G0_TX_DP<9>")
	)
	(segment
		(start 105.388156 -223.747076)
		(end 105.388918 -223.746568)
		(width 0.1143)
		(layer "In2.Cu")
		(net "GMI_CPU0_G2_CPU1_G0_TX_DP<9>")
	)
	(segment
		(start 105.382568 -226.990402)
		(end 105.383838 -226.98964)
		(width 0.1143)
		(layer "In2.Cu")
		(net "GMI_CPU0_G2_CPU1_G0_TX_DP<9>")
	)
	(segment
		(start 366.402874 -227.466906)
		(end 366.402874 -227.494084)
		(width 0.1143)
		(layer "In2.Cu")
		(net "GMI_CPU0_G2_CPU1_G0_TX_DP<9>")
	)
	(segment
		(start 104.45242 -228.604572)
		(end 104.479852 -228.588824)
		(width 0.1143)
		(layer "In2.Cu")
		(net "GMI_CPU0_G2_CPU1_G0_TX_DP<9>")
	)
	(segment
		(start 366.097312 -222.120968)
		(end 366.099852 -222.122238)
		(width 0.1143)
		(layer "In2.Cu")
		(net "GMI_CPU0_G2_CPU1_G0_TX_DP<9>")
	)
	(segment
		(start 105.355898 -224.703132)
		(end 105.34904 -224.699068)
		(width 0.1143)
		(layer "In2.Cu")
		(net "GMI_CPU0_G2_CPU1_G0_TX_DP<9>")
	)
	(segment
		(start 364.927388 -217.06586)
		(end 365.921798 -219.252292)
		(width 0.14224)
		(layer "In2.Cu")
		(net "GMI_CPU0_G2_CPU1_G0_TX_DP<9>")
	)
	(segment
		(start 366.108742 -224.721166)
		(end 366.107726 -224.721674)
		(width 0.1143)
		(layer "In2.Cu")
		(net "GMI_CPU0_G2_CPU1_G0_TX_DP<9>")
	)
	(segment
		(start 105.388156 -225.367088)
		(end 105.388918 -225.36658)
		(width 0.1143)
		(layer "In2.Cu")
		(net "GMI_CPU0_G2_CPU1_G0_TX_DP<9>")
	)
	(segment
		(start 366.075976 -222.108522)
		(end 366.097312 -222.120968)
		(width 0.1143)
		(layer "In2.Cu")
		(net "GMI_CPU0_G2_CPU1_G0_TX_DP<9>")
	)
	(segment
		(start 111.574834 -209.80654)
		(end 155.32608 -186.81319)
		(width 0.14224)
		(layer "In2.Cu")
		(net "GMI_CPU0_G2_CPU1_G0_TX_DP<9>")
	)
	(segment
		(start 105.419906 -223.728788)
		(end 105.439718 -223.714564)
		(width 0.1143)
		(layer "In2.Cu")
		(net "GMI_CPU0_G2_CPU1_G0_TX_DP<9>")
	)
	(segment
		(start 366.108742 -223.101154)
		(end 366.107726 -223.101662)
		(width 0.1143)
		(layer "In2.Cu")
		(net "GMI_CPU0_G2_CPU1_G0_TX_DP<9>")
	)
	(segment
		(start 366.107726 -226.341686)
		(end 366.106964 -226.342194)
		(width 0.1143)
		(layer "In2.Cu")
		(net "GMI_CPU0_G2_CPU1_G0_TX_DP<9>")
	)
	(segment
		(start 366.107726 -223.746822)
		(end 366.139222 -223.76511)
		(width 0.1143)
		(layer "In2.Cu")
		(net "GMI_CPU0_G2_CPU1_G0_TX_DP<9>")
	)
	(segment
		(start 366.106964 -222.126302)
		(end 366.107726 -222.12681)
		(width 0.1143)
		(layer "In2.Cu")
		(net "GMI_CPU0_G2_CPU1_G0_TX_DP<9>")
	)
	(segment
		(start 366.110266 -226.340162)
		(end 366.108742 -226.341178)
		(width 0.1143)
		(layer "In2.Cu")
		(net "GMI_CPU0_G2_CPU1_G0_TX_DP<9>")
	)
	(segment
		(start 366.107726 -223.101662)
		(end 366.106964 -223.10217)
		(width 0.1143)
		(layer "In2.Cu")
		(net "GMI_CPU0_G2_CPU1_G0_TX_DP<9>")
	)
	(segment
		(start 105.38714 -226.987608)
		(end 105.388156 -226.9871)
		(width 0.1143)
		(layer "In2.Cu")
		(net "GMI_CPU0_G2_CPU1_G0_TX_DP<9>")
	)
	(segment
		(start 105.35666 -226.323652)
		(end 105.355898 -226.323144)
		(width 0.1143)
		(layer "In2.Cu")
		(net "GMI_CPU0_G2_CPU1_G0_TX_DP<9>")
	)
	(segment
		(start 104.60863 -216.77249)
		(end 110.955836 -210.425284)
		(width 0.14224)
		(layer "In2.Cu")
		(net "GMI_CPU0_G2_CPU1_G0_TX_DP<9>")
	)
	(segment
		(start 366.13846 -227.004626)
		(end 366.139984 -227.005642)
		(width 0.1143)
		(layer "In2.Cu")
		(net "GMI_CPU0_G2_CPU1_G0_TX_DP<9>")
	)
	(segment
		(start 105.355898 -223.08312)
		(end 105.34904 -223.079056)
		(width 0.1143)
		(layer "In2.Cu")
		(net "GMI_CPU0_G2_CPU1_G0_TX_DP<9>")
	)
	(segment
		(start 105.388918 -225.36658)
		(end 105.419906 -225.3488)
		(width 0.1143)
		(layer "In2.Cu")
		(net "GMI_CPU0_G2_CPU1_G0_TX_DP<9>")
	)
	(segment
		(start 104.636824 -221.833948)
		(end 104.637332 -221.83344)
		(width 0.1143)
		(layer "In2.Cu")
		(net "GMI_CPU0_G2_CPU1_G0_TX_DP<9>")
	)
	(arc
		(start 103.70566 -229.798626)
		(mid 103.787093 -229.596228)
		(end 103.939086 -229.439724)
		(width 0.1143)
		(layer "In2.Cu")
		(net "GMI_CPU0_G2_CPU1_G0_TX_DP<9>")
	)
	(arc
		(start 104.165654 -229.094538)
		(mid 104.230169 -228.832319)
		(end 104.408986 -228.629972)
		(width 0.1143)
		(layer "In2.Cu")
		(net "GMI_CPU0_G2_CPU1_G0_TX_DP<9>")
	)
	(arc
		(start 367.329974 -229.094284)
		(mid 367.370736 -229.264168)
		(end 367.484152 -229.397052)
		(width 0.1143)
		(layer "In2.Cu")
		(net "GMI_CPU0_G2_CPU1_G0_TX_DP<9>")
	)
	(arc
		(start 366.59058 -227.816918)
		(mid 366.78708 -228.014083)
		(end 366.85982 -228.282754)
		(width 0.1143)
		(layer "In2.Cu")
		(net "GMI_CPU0_G2_CPU1_G0_TX_DP<9>")
	)
	(arc
		(start 367.08588 -228.628956)
		(mid 367.265225 -228.831559)
		(end 367.329974 -229.094284)
		(width 0.1143)
		(layer "In2.Cu")
		(net "GMI_CPU0_G2_CPU1_G0_TX_DP<9>")
	)
	(arc
		(start 366.85982 -228.284024)
		(mid 366.903677 -228.459474)
		(end 367.025174 -228.593396)
		(width 0.1143)
		(layer "In2.Cu")
		(net "GMI_CPU0_G2_CPU1_G0_TX_DP<9>")
	)
	(arc
		(start 105.439718 -223.714564)
		(mid 105.588432 -223.424496)
		(end 105.439718 -223.134428)
		(width 0.1143)
		(layer "In2.Cu")
		(net "GMI_CPU0_G2_CPU1_G0_TX_DP<9>")
	)
	(arc
		(start 104.948736 -227.779326)
		(mid 105.064163 -227.64595)
		(end 105.105708 -227.474526)
		(width 0.1143)
		(layer "In2.Cu")
		(net "GMI_CPU0_G2_CPU1_G0_TX_DP<9>")
	)
	(arc
		(start 366.075976 -226.359974)
		(mid 365.920048 -226.664266)
		(end 366.075976 -226.968558)
		(width 0.1143)
		(layer "In2.Cu")
		(net "GMI_CPU0_G2_CPU1_G0_TX_DP<9>")
	)
	(arc
		(start 105.34904 -226.31908)
		(mid 105.105713 -225.854514)
		(end 105.34904 -225.389948)
		(width 0.1143)
		(layer "In2.Cu")
		(net "GMI_CPU0_G2_CPU1_G0_TX_DP<9>")
	)
	(arc
		(start 366.075976 -223.11995)
		(mid 365.920048 -223.424242)
		(end 366.075976 -223.728534)
		(width 0.1143)
		(layer "In2.Cu")
		(net "GMI_CPU0_G2_CPU1_G0_TX_DP<9>")
	)
	(arc
		(start 104.881934 -222.270828)
		(mid 104.708325 -222.08103)
		(end 104.636824 -221.833948)
		(width 0.1143)
		(layer "In2.Cu")
		(net "GMI_CPU0_G2_CPU1_G0_TX_DP<9>")
	)
	(arc
		(start 366.402874 -227.494084)
		(mid 366.444133 -227.664941)
		(end 366.55883 -227.798122)
		(width 0.1143)
		(layer "In2.Cu")
		(net "GMI_CPU0_G2_CPU1_G0_TX_DP<9>")
	)
	(arc
		(start 366.146842 -222.14967)
		(mid 366.390169 -222.614236)
		(end 366.146842 -223.078802)
		(width 0.1143)
		(layer "In2.Cu")
		(net "GMI_CPU0_G2_CPU1_G0_TX_DP<9>")
	)
	(arc
		(start 105.105708 -227.474526)
		(mid 105.170223 -227.212307)
		(end 105.34904 -227.00996)
		(width 0.1143)
		(layer "In2.Cu")
		(net "GMI_CPU0_G2_CPU1_G0_TX_DP<9>")
	)
	(arc
		(start 104.010714 -229.398068)
		(mid 104.124643 -229.264921)
		(end 104.165654 -229.094538)
		(width 0.1143)
		(layer "In2.Cu")
		(net "GMI_CPU0_G2_CPU1_G0_TX_DP<9>")
	)
	(arc
		(start 366.075976 -224.739962)
		(mid 365.920048 -225.044254)
		(end 366.075976 -225.348546)
		(width 0.1143)
		(layer "In2.Cu")
		(net "GMI_CPU0_G2_CPU1_G0_TX_DP<9>")
	)
	(arc
		(start 366.146842 -223.769682)
		(mid 366.390169 -224.234248)
		(end 366.146842 -224.698814)
		(width 0.1143)
		(layer "In2.Cu")
		(net "GMI_CPU0_G2_CPU1_G0_TX_DP<9>")
	)
	(arc
		(start 105.419906 -226.968812)
		(mid 105.571495 -226.66452)
		(end 105.419906 -226.360228)
		(width 0.1143)
		(layer "In2.Cu")
		(net "GMI_CPU0_G2_CPU1_G0_TX_DP<9>")
	)
	(arc
		(start 366.139984 -227.005642)
		(mid 366.332508 -227.201456)
		(end 366.402874 -227.466906)
		(width 0.1143)
		(layer "In2.Cu")
		(net "GMI_CPU0_G2_CPU1_G0_TX_DP<9>")
	)
	(arc
		(start 365.92002 -221.80423)
		(mid 365.961275 -221.975201)
		(end 366.075976 -222.108522)
		(width 0.1143)
		(layer "In2.Cu")
		(net "GMI_CPU0_G2_CPU1_G0_TX_DP<9>")
	)
	(arc
		(start 105.34904 -223.079056)
		(mid 105.170227 -222.876706)
		(end 105.105708 -222.61449)
		(width 0.1143)
		(layer "In2.Cu")
		(net "GMI_CPU0_G2_CPU1_G0_TX_DP<9>")
	)
	(arc
		(start 105.34904 -224.699068)
		(mid 105.105713 -224.234502)
		(end 105.34904 -223.769936)
		(width 0.1143)
		(layer "In2.Cu")
		(net "GMI_CPU0_G2_CPU1_G0_TX_DP<9>")
	)
	(arc
		(start 104.479852 -228.588824)
		(mid 104.594528 -228.45549)
		(end 104.635808 -228.284532)
		(width 0.1143)
		(layer "In2.Cu")
		(net "GMI_CPU0_G2_CPU1_G0_TX_DP<9>")
	)
	(arc
		(start 105.439718 -225.334576)
		(mid 105.588432 -225.044508)
		(end 105.439718 -224.75444)
		(width 0.1143)
		(layer "In2.Cu")
		(net "GMI_CPU0_G2_CPU1_G0_TX_DP<9>")
	)
	(arc
		(start 366.146842 -225.389694)
		(mid 366.390169 -225.85426)
		(end 366.146842 -226.318826)
		(width 0.1143)
		(layer "In2.Cu")
		(net "GMI_CPU0_G2_CPU1_G0_TX_DP<9>")
	)
	(arc
		(start 103.70185 -229.821486)
		(mid 103.703638 -229.810037)
		(end 103.70566 -229.798626)
		(width 0.1143)
		(layer "In2.Cu")
		(net "GMI_CPU0_G2_CPU1_G0_TX_DP<9>")
	)
	(arc
		(start 367.025174 -228.593396)
		(mid 367.040937 -228.603323)
		(end 367.057178 -228.612446)
		(width 0.1143)
		(layer "In2.Cu")
		(net "GMI_CPU0_G2_CPU1_G0_TX_DP<9>")
	)
	(arc
		(start 367.556796 -229.43947)
		(mid 367.715001 -229.605757)
		(end 367.794032 -229.821232)
		(width 0.1143)
		(layer "In2.Cu")
		(net "GMI_CPU0_G2_CPU1_G0_TX_DP<9>")
	)
	(arc
		(start 104.635808 -228.284532)
		(mid 104.700323 -228.022313)
		(end 104.87914 -227.819966)
		(width 0.1143)
		(layer "In2.Cu")
		(net "GMI_CPU0_G2_CPU1_G0_TX_DP<9>")
	)
	(arc
		(start 105.105708 -222.61449)
		(mid 105.064159 -222.443068)
		(end 104.948736 -222.30969)
		(width 0.1143)
		(layer "In2.Cu")
		(net "GMI_CPU0_G2_CPU1_G0_TX_DP<9>")
	)
	(segment
		(start 103.787956 -226.930458)
		(end 103.321104 -226.66452)
		(width 0.12954)
		(layer "F.Cu")
		(net "GMI_CPU0_G2_CPU1_G0_TX_DP<8>")
	)
	(segment
		(start 367.707926 -226.930204)
		(end 368.174778 -226.664266)
		(width 0.12954)
		(layer "F.Cu")
		(net "GMI_CPU0_G2_CPU1_G0_TX_DP<8>")
	)
	(segment
		(start 367.765838 -221.34703)
		(end 367.765838 -221.128844)
		(width 0.1143)
		(layer "In2.Cu")
		(net "GMI_CPU0_G2_CPU1_G0_TX_DP<8>")
	)
	(segment
		(start 103.508048 -226.34194)
		(end 103.539798 -226.360228)
		(width 0.1143)
		(layer "In2.Cu")
		(net "GMI_CPU0_G2_CPU1_G0_TX_DP<8>")
	)
	(segment
		(start 102.71887 -221.203012)
		(end 102.76459 -221.248732)
		(width 0.1143)
		(layer "In2.Cu")
		(net "GMI_CPU0_G2_CPU1_G0_TX_DP<8>")
	)
	(segment
		(start 102.999032 -222.26905)
		(end 103.048562 -222.298006)
		(width 0.1143)
		(layer "In2.Cu")
		(net "GMI_CPU0_G2_CPU1_G0_TX_DP<8>")
	)
	(segment
		(start 310.227726 -182.272178)
		(end 308.826154 -181.738016)
		(width 0.14224)
		(layer "In2.Cu")
		(net "GMI_CPU0_G2_CPU1_G0_TX_DP<8>")
	)
	(segment
		(start 103.508048 -225.367088)
		(end 103.471726 -225.38817)
		(width 0.1143)
		(layer "In2.Cu")
		(net "GMI_CPU0_G2_CPU1_G0_TX_DP<8>")
	)
	(segment
		(start 368.026696 -222.14967)
		(end 367.98758 -222.12681)
		(width 0.1143)
		(layer "In2.Cu")
		(net "GMI_CPU0_G2_CPU1_G0_TX_DP<8>")
	)
	(segment
		(start 103.619046 -226.66452)
		(end 103.321104 -226.66452)
		(width 0.1143)
		(layer "In2.Cu")
		(net "GMI_CPU0_G2_CPU1_G0_TX_DP<8>")
	)
	(segment
		(start 367.98758 -223.101662)
		(end 368.026696 -223.078802)
		(width 0.1143)
		(layer "In2.Cu")
		(net "GMI_CPU0_G2_CPU1_G0_TX_DP<8>")
	)
	(segment
		(start 163.1569 -181.492652)
		(end 153.375106 -185.543444)
		(width 0.14224)
		(layer "In2.Cu")
		(net "GMI_CPU0_G2_CPU1_G0_TX_DP<8>")
	)
	(segment
		(start 103.471726 -224.700846)
		(end 103.508048 -224.721928)
		(width 0.1143)
		(layer "In2.Cu")
		(net "GMI_CPU0_G2_CPU1_G0_TX_DP<8>")
	)
	(segment
		(start 367.9571 -226.359466)
		(end 367.98758 -226.341686)
		(width 0.1143)
		(layer "In2.Cu")
		(net "GMI_CPU0_G2_CPU1_G0_TX_DP<8>")
	)
	(segment
		(start 367.800128 -221.38132)
		(end 367.765838 -221.34703)
		(width 0.1143)
		(layer "In2.Cu")
		(net "GMI_CPU0_G2_CPU1_G0_TX_DP<8>")
	)
	(segment
		(start 357.031544 -208.492852)
		(end 323.968618 -188.900816)
		(width 0.14224)
		(layer "In2.Cu")
		(net "GMI_CPU0_G2_CPU1_G0_TX_DP<8>")
	)
	(segment
		(start 367.9571 -224.739454)
		(end 367.98758 -224.721674)
		(width 0.1143)
		(layer "In2.Cu")
		(net "GMI_CPU0_G2_CPU1_G0_TX_DP<8>")
	)
	(segment
		(start 103.471726 -226.320858)
		(end 103.508048 -226.34194)
		(width 0.1143)
		(layer "In2.Cu")
		(net "GMI_CPU0_G2_CPU1_G0_TX_DP<8>")
	)
	(segment
		(start 103.539798 -225.3488)
		(end 103.508048 -225.367088)
		(width 0.1143)
		(layer "In2.Cu")
		(net "GMI_CPU0_G2_CPU1_G0_TX_DP<8>")
	)
	(segment
		(start 367.800128 -221.80423)
		(end 367.800128 -221.38132)
		(width 0.1143)
		(layer "In2.Cu")
		(net "GMI_CPU0_G2_CPU1_G0_TX_DP<8>")
	)
	(segment
		(start 362.000546 -211.860638)
		(end 357.031544 -208.492852)
		(width 0.14224)
		(layer "In2.Cu")
		(net "GMI_CPU0_G2_CPU1_G0_TX_DP<8>")
	)
	(segment
		(start 165.532562 -180.827172)
		(end 163.1569 -181.492652)
		(width 0.14224)
		(layer "In2.Cu")
		(net "GMI_CPU0_G2_CPU1_G0_TX_DP<8>")
	)
	(segment
		(start 103.508048 -223.747076)
		(end 103.471726 -223.768158)
		(width 0.1143)
		(layer "In2.Cu")
		(net "GMI_CPU0_G2_CPU1_G0_TX_DP<8>")
	)
	(segment
		(start 102.755954 -221.80423)
		(end 102.7557 -221.804484)
		(width 0.1143)
		(layer "In2.Cu")
		(net "GMI_CPU0_G2_CPU1_G0_TX_DP<8>")
	)
	(segment
		(start 367.811558 -218.837256)
		(end 366.371886 -215.671654)
		(width 0.14224)
		(layer "In2.Cu")
		(net "GMI_CPU0_G2_CPU1_G0_TX_DP<8>")
	)
	(segment
		(start 103.508048 -224.721928)
		(end 103.539798 -224.740216)
		(width 0.1143)
		(layer "In2.Cu")
		(net "GMI_CPU0_G2_CPU1_G0_TX_DP<8>")
	)
	(segment
		(start 367.98758 -223.746822)
		(end 367.9571 -223.729042)
		(width 0.1143)
		(layer "In2.Cu")
		(net "GMI_CPU0_G2_CPU1_G0_TX_DP<8>")
	)
	(segment
		(start 110.15091 -208.159858)
		(end 102.71887 -215.591898)
		(width 0.14224)
		(layer "In2.Cu")
		(net "GMI_CPU0_G2_CPU1_G0_TX_DP<8>")
	)
	(segment
		(start 102.755954 -221.566486)
		(end 102.755954 -221.80423)
		(width 0.1143)
		(layer "In2.Cu")
		(net "GMI_CPU0_G2_CPU1_G0_TX_DP<8>")
	)
	(segment
		(start 306.26558 -181.073298)
		(end 231.662986 -178.559968)
		(width 0.14224)
		(layer "In2.Cu")
		(net "GMI_CPU0_G2_CPU1_G0_TX_DP<8>")
	)
	(segment
		(start 231.662986 -178.559968)
		(end 165.532562 -180.827172)
		(width 0.14224)
		(layer "In2.Cu")
		(net "GMI_CPU0_G2_CPU1_G0_TX_DP<8>")
	)
	(segment
		(start 368.174778 -226.664266)
		(end 367.876836 -226.664266)
		(width 0.1143)
		(layer "In2.Cu")
		(net "GMI_CPU0_G2_CPU1_G0_TX_DP<8>")
	)
	(segment
		(start 368.026696 -223.769682)
		(end 367.98758 -223.746822)
		(width 0.1143)
		(layer "In2.Cu")
		(net "GMI_CPU0_G2_CPU1_G0_TX_DP<8>")
	)
	(segment
		(start 367.765838 -221.128844)
		(end 367.811558 -221.083124)
		(width 0.1143)
		(layer "In2.Cu")
		(net "GMI_CPU0_G2_CPU1_G0_TX_DP<8>")
	)
	(segment
		(start 366.371886 -215.671654)
		(end 362.000546 -211.860638)
		(width 0.14224)
		(layer "In2.Cu")
		(net "GMI_CPU0_G2_CPU1_G0_TX_DP<8>")
	)
	(segment
		(start 367.876836 -226.664266)
		(end 367.806986 -226.594416)
		(width 0.1143)
		(layer "In2.Cu")
		(net "GMI_CPU0_G2_CPU1_G0_TX_DP<8>")
	)
	(segment
		(start 103.236268 -222.622872)
		(end 103.236268 -222.629984)
		(width 0.1143)
		(layer "In2.Cu")
		(net "GMI_CPU0_G2_CPU1_G0_TX_DP<8>")
	)
	(segment
		(start 323.968618 -188.900816)
		(end 310.227726 -182.272178)
		(width 0.14224)
		(layer "In2.Cu")
		(net "GMI_CPU0_G2_CPU1_G0_TX_DP<8>")
	)
	(segment
		(start 103.508048 -223.101916)
		(end 103.539798 -223.120204)
		(width 0.1143)
		(layer "In2.Cu")
		(net "GMI_CPU0_G2_CPU1_G0_TX_DP<8>")
	)
	(segment
		(start 153.375106 -185.543444)
		(end 110.15091 -208.159858)
		(width 0.14224)
		(layer "In2.Cu")
		(net "GMI_CPU0_G2_CPU1_G0_TX_DP<8>")
	)
	(segment
		(start 367.98758 -222.12681)
		(end 367.9571 -222.10903)
		(width 0.1143)
		(layer "In2.Cu")
		(net "GMI_CPU0_G2_CPU1_G0_TX_DP<8>")
	)
	(segment
		(start 102.71887 -221.174564)
		(end 102.71887 -221.203012)
		(width 0.1143)
		(layer "In2.Cu")
		(net "GMI_CPU0_G2_CPU1_G0_TX_DP<8>")
	)
	(segment
		(start 102.71887 -215.591898)
		(end 102.71887 -221.174564)
		(width 0.14224)
		(layer "In2.Cu")
		(net "GMI_CPU0_G2_CPU1_G0_TX_DP<8>")
	)
	(segment
		(start 103.688896 -226.59467)
		(end 103.619046 -226.66452)
		(width 0.1143)
		(layer "In2.Cu")
		(net "GMI_CPU0_G2_CPU1_G0_TX_DP<8>")
	)
	(segment
		(start 367.9571 -223.119442)
		(end 367.98758 -223.101662)
		(width 0.1143)
		(layer "In2.Cu")
		(net "GMI_CPU0_G2_CPU1_G0_TX_DP<8>")
	)
	(segment
		(start 102.76459 -221.248732)
		(end 102.76459 -221.55785)
		(width 0.1143)
		(layer "In2.Cu")
		(net "GMI_CPU0_G2_CPU1_G0_TX_DP<8>")
	)
	(segment
		(start 103.539798 -223.728788)
		(end 103.508048 -223.747076)
		(width 0.1143)
		(layer "In2.Cu")
		(net "GMI_CPU0_G2_CPU1_G0_TX_DP<8>")
	)
	(segment
		(start 102.76459 -221.55785)
		(end 102.755954 -221.566486)
		(width 0.1143)
		(layer "In2.Cu")
		(net "GMI_CPU0_G2_CPU1_G0_TX_DP<8>")
	)
	(segment
		(start 367.98758 -225.366834)
		(end 367.9571 -225.349054)
		(width 0.1143)
		(layer "In2.Cu")
		(net "GMI_CPU0_G2_CPU1_G0_TX_DP<8>")
	)
	(segment
		(start 308.826154 -181.738016)
		(end 306.26558 -181.073298)
		(width 0.14224)
		(layer "In2.Cu")
		(net "GMI_CPU0_G2_CPU1_G0_TX_DP<8>")
	)
	(segment
		(start 367.98758 -224.721674)
		(end 368.026696 -224.698814)
		(width 0.1143)
		(layer "In2.Cu")
		(net "GMI_CPU0_G2_CPU1_G0_TX_DP<8>")
	)
	(segment
		(start 367.811558 -221.083124)
		(end 367.811558 -218.837256)
		(width 0.14224)
		(layer "In2.Cu")
		(net "GMI_CPU0_G2_CPU1_G0_TX_DP<8>")
	)
	(segment
		(start 367.98758 -226.341686)
		(end 368.026696 -226.318826)
		(width 0.1143)
		(layer "In2.Cu")
		(net "GMI_CPU0_G2_CPU1_G0_TX_DP<8>")
	)
	(segment
		(start 368.026696 -225.389694)
		(end 367.98758 -225.366834)
		(width 0.1143)
		(layer "In2.Cu")
		(net "GMI_CPU0_G2_CPU1_G0_TX_DP<8>")
	)
	(arc
		(start 367.9571 -222.10903)
		(mid 367.841673 -221.975654)
		(end 367.800128 -221.80423)
		(width 0.1143)
		(layer "In2.Cu")
		(net "GMI_CPU0_G2_CPU1_G0_TX_DP<8>")
	)
	(arc
		(start 367.9571 -223.729042)
		(mid 367.800123 -223.424242)
		(end 367.9571 -223.119442)
		(width 0.1143)
		(layer "In2.Cu")
		(net "GMI_CPU0_G2_CPU1_G0_TX_DP<8>")
	)
	(arc
		(start 368.026696 -224.698814)
		(mid 368.270023 -224.234248)
		(end 368.026696 -223.769682)
		(width 0.1143)
		(layer "In2.Cu")
		(net "GMI_CPU0_G2_CPU1_G0_TX_DP<8>")
	)
	(arc
		(start 103.471726 -223.768158)
		(mid 103.464062 -223.773429)
		(end 103.456486 -223.778826)
		(width 0.1143)
		(layer "In2.Cu")
		(net "GMI_CPU0_G2_CPU1_G0_TX_DP<8>")
	)
	(arc
		(start 102.7557 -221.804484)
		(mid 102.820215 -222.066703)
		(end 102.999032 -222.26905)
		(width 0.1143)
		(layer "In2.Cu")
		(net "GMI_CPU0_G2_CPU1_G0_TX_DP<8>")
	)
	(arc
		(start 103.45547 -226.309428)
		(mid 103.463548 -226.315214)
		(end 103.471726 -226.320858)
		(width 0.1143)
		(layer "In2.Cu")
		(net "GMI_CPU0_G2_CPU1_G0_TX_DP<8>")
	)
	(arc
		(start 367.9571 -225.349054)
		(mid 367.800123 -225.044254)
		(end 367.9571 -224.739454)
		(width 0.1143)
		(layer "In2.Cu")
		(net "GMI_CPU0_G2_CPU1_G0_TX_DP<8>")
	)
	(arc
		(start 103.471726 -225.38817)
		(mid 103.463548 -225.393813)
		(end 103.45547 -225.3996)
		(width 0.1143)
		(layer "In2.Cu")
		(net "GMI_CPU0_G2_CPU1_G0_TX_DP<8>")
	)
	(arc
		(start 103.236268 -222.629984)
		(mid 103.309073 -222.902277)
		(end 103.508048 -223.101916)
		(width 0.1143)
		(layer "In2.Cu")
		(net "GMI_CPU0_G2_CPU1_G0_TX_DP<8>")
	)
	(arc
		(start 368.026696 -223.078802)
		(mid 368.270023 -222.614236)
		(end 368.026696 -222.14967)
		(width 0.1143)
		(layer "In2.Cu")
		(net "GMI_CPU0_G2_CPU1_G0_TX_DP<8>")
	)
	(arc
		(start 103.048562 -222.298006)
		(mid 103.185994 -222.435265)
		(end 103.236268 -222.622872)
		(width 0.1143)
		(layer "In2.Cu")
		(net "GMI_CPU0_G2_CPU1_G0_TX_DP<8>")
	)
	(arc
		(start 103.456486 -224.690178)
		(mid 103.464062 -224.695574)
		(end 103.471726 -224.700846)
		(width 0.1143)
		(layer "In2.Cu")
		(net "GMI_CPU0_G2_CPU1_G0_TX_DP<8>")
	)
	(arc
		(start 103.539798 -223.120204)
		(mid 103.695726 -223.424496)
		(end 103.539798 -223.728788)
		(width 0.1143)
		(layer "In2.Cu")
		(net "GMI_CPU0_G2_CPU1_G0_TX_DP<8>")
	)
	(arc
		(start 103.539798 -224.740216)
		(mid 103.695726 -225.044508)
		(end 103.539798 -225.3488)
		(width 0.1143)
		(layer "In2.Cu")
		(net "GMI_CPU0_G2_CPU1_G0_TX_DP<8>")
	)
	(arc
		(start 103.456486 -223.778826)
		(mid 103.231315 -224.234502)
		(end 103.456486 -224.690178)
		(width 0.1143)
		(layer "In2.Cu")
		(net "GMI_CPU0_G2_CPU1_G0_TX_DP<8>")
	)
	(arc
		(start 367.806986 -226.594416)
		(mid 367.859403 -226.462485)
		(end 367.9571 -226.359466)
		(width 0.1143)
		(layer "In2.Cu")
		(net "GMI_CPU0_G2_CPU1_G0_TX_DP<8>")
	)
	(arc
		(start 103.45547 -225.3996)
		(mid 103.232586 -225.854514)
		(end 103.45547 -226.309428)
		(width 0.1143)
		(layer "In2.Cu")
		(net "GMI_CPU0_G2_CPU1_G0_TX_DP<8>")
	)
	(arc
		(start 368.026696 -226.318826)
		(mid 368.270023 -225.85426)
		(end 368.026696 -225.389694)
		(width 0.1143)
		(layer "In2.Cu")
		(net "GMI_CPU0_G2_CPU1_G0_TX_DP<8>")
	)
	(arc
		(start 103.539798 -226.360228)
		(mid 103.636933 -226.463097)
		(end 103.688896 -226.59467)
		(width 0.1143)
		(layer "In2.Cu")
		(net "GMI_CPU0_G2_CPU1_G0_TX_DP<8>")
	)
	(segment
		(start 367.707926 -228.550216)
		(end 368.174778 -228.284278)
		(width 0.12954)
		(layer "F.Cu")
		(net "GMI_CPU0_G2_CPU1_G0_TX_DP<7>")
	)
	(segment
		(start 103.787956 -228.55047)
		(end 103.321104 -228.284532)
		(width 0.12954)
		(layer "F.Cu")
		(net "GMI_CPU0_G2_CPU1_G0_TX_DP<7>")
	)
	(segment
		(start 367.51768 -227.796852)
		(end 367.516918 -227.796344)
		(width 0.1143)
		(layer "In2.Cu")
		(net "GMI_CPU0_G2_CPU1_G0_TX_DP<7>")
	)
	(segment
		(start 308.892448 -182.761128)
		(end 306.362862 -182.103268)
		(width 0.14224)
		(layer "In2.Cu")
		(net "GMI_CPU0_G2_CPU1_G0_TX_DP<7>")
	)
	(segment
		(start 104.451658 -223.103948)
		(end 104.45242 -223.104456)
		(width 0.1143)
		(layer "In2.Cu")
		(net "GMI_CPU0_G2_CPU1_G0_TX_DP<7>")
	)
	(segment
		(start 367.518696 -227.79736)
		(end 367.51768 -227.796852)
		(width 0.1143)
		(layer "In2.Cu")
		(net "GMI_CPU0_G2_CPU1_G0_TX_DP<7>")
	)
	(segment
		(start 104.447086 -226.987608)
		(end 104.408986 -227.00996)
		(width 0.1143)
		(layer "In2.Cu")
		(net "GMI_CPU0_G2_CPU1_G0_TX_DP<7>")
	)
	(segment
		(start 104.45242 -223.744536)
		(end 104.451658 -223.745044)
		(width 0.1143)
		(layer "In2.Cu")
		(net "GMI_CPU0_G2_CPU1_G0_TX_DP<7>")
	)
	(segment
		(start 104.451658 -224.72396)
		(end 104.45242 -224.724468)
		(width 0.1143)
		(layer "In2.Cu")
		(net "GMI_CPU0_G2_CPU1_G0_TX_DP<7>")
	)
	(segment
		(start 361.455462 -212.672676)
		(end 356.753414 -209.486246)
		(width 0.14224)
		(layer "In2.Cu")
		(net "GMI_CPU0_G2_CPU1_G0_TX_DP<7>")
	)
	(segment
		(start 104.453436 -224.724976)
		(end 104.454198 -224.725484)
		(width 0.1143)
		(layer "In2.Cu")
		(net "GMI_CPU0_G2_CPU1_G0_TX_DP<7>")
	)
	(segment
		(start 103.66375 -221.203012)
		(end 103.70947 -221.248732)
		(width 0.1143)
		(layer "In2.Cu")
		(net "GMI_CPU0_G2_CPU1_G0_TX_DP<7>")
	)
	(segment
		(start 104.479852 -226.968812)
		(end 104.450134 -226.98583)
		(width 0.1143)
		(layer "In2.Cu")
		(net "GMI_CPU0_G2_CPU1_G0_TX_DP<7>")
	)
	(segment
		(start 104.451658 -226.343972)
		(end 104.45242 -226.34448)
		(width 0.1143)
		(layer "In2.Cu")
		(net "GMI_CPU0_G2_CPU1_G0_TX_DP<7>")
	)
	(segment
		(start 103.696008 -221.54896)
		(end 103.696008 -221.804484)
		(width 0.1143)
		(layer "In2.Cu")
		(net "GMI_CPU0_G2_CPU1_G0_TX_DP<7>")
	)
	(segment
		(start 322.992242 -189.483238)
		(end 309.702708 -183.070246)
		(width 0.14224)
		(layer "In2.Cu")
		(net "GMI_CPU0_G2_CPU1_G0_TX_DP<7>")
	)
	(segment
		(start 104.447086 -224.72142)
		(end 104.448102 -224.721928)
		(width 0.1143)
		(layer "In2.Cu")
		(net "GMI_CPU0_G2_CPU1_G0_TX_DP<7>")
	)
	(segment
		(start 104.448864 -226.986592)
		(end 104.448102 -226.9871)
		(width 0.1143)
		(layer "In2.Cu")
		(net "GMI_CPU0_G2_CPU1_G0_TX_DP<7>")
	)
	(segment
		(start 104.457754 -226.347274)
		(end 104.479852 -226.360228)
		(width 0.1143)
		(layer "In2.Cu")
		(net "GMI_CPU0_G2_CPU1_G0_TX_DP<7>")
	)
	(segment
		(start 104.448864 -225.36658)
		(end 104.448102 -225.367088)
		(width 0.1143)
		(layer "In2.Cu")
		(net "GMI_CPU0_G2_CPU1_G0_TX_DP<7>")
	)
	(segment
		(start 104.408986 -224.699068)
		(end 104.415844 -224.703132)
		(width 0.1143)
		(layer "In2.Cu")
		(net "GMI_CPU0_G2_CPU1_G0_TX_DP<7>")
	)
	(segment
		(start 367.514124 -227.795074)
		(end 367.513616 -227.79482)
		(width 0.1143)
		(layer "In2.Cu")
		(net "GMI_CPU0_G2_CPU1_G0_TX_DP<7>")
	)
	(segment
		(start 104.479852 -223.728788)
		(end 104.454452 -223.74352)
		(width 0.1143)
		(layer "In2.Cu")
		(net "GMI_CPU0_G2_CPU1_G0_TX_DP<7>")
	)
	(segment
		(start 103.70947 -221.535498)
		(end 103.696008 -221.54896)
		(width 0.1143)
		(layer "In2.Cu")
		(net "GMI_CPU0_G2_CPU1_G0_TX_DP<7>")
	)
	(segment
		(start 367.549176 -227.81514)
		(end 367.518696 -227.79736)
		(width 0.1143)
		(layer "In2.Cu")
		(net "GMI_CPU0_G2_CPU1_G0_TX_DP<7>")
	)
	(segment
		(start 367.084102 -222.147892)
		(end 367.04778 -222.12681)
		(width 0.1143)
		(layer "In2.Cu")
		(net "GMI_CPU0_G2_CPU1_G0_TX_DP<7>")
	)
	(segment
		(start 104.450134 -226.98583)
		(end 104.448864 -226.986592)
		(width 0.1143)
		(layer "In2.Cu")
		(net "GMI_CPU0_G2_CPU1_G0_TX_DP<7>")
	)
	(segment
		(start 104.416606 -226.323652)
		(end 104.447086 -226.341432)
		(width 0.1143)
		(layer "In2.Cu")
		(net "GMI_CPU0_G2_CPU1_G0_TX_DP<7>")
	)
	(segment
		(start 104.445562 -223.7486)
		(end 104.408986 -223.769936)
		(width 0.1143)
		(layer "In2.Cu")
		(net "GMI_CPU0_G2_CPU1_G0_TX_DP<7>")
	)
	(segment
		(start 104.415844 -223.08312)
		(end 104.416606 -223.083628)
		(width 0.1143)
		(layer "In2.Cu")
		(net "GMI_CPU0_G2_CPU1_G0_TX_DP<7>")
	)
	(segment
		(start 103.66375 -221.174564)
		(end 103.66375 -221.203012)
		(width 0.1143)
		(layer "In2.Cu")
		(net "GMI_CPU0_G2_CPU1_G0_TX_DP<7>")
	)
	(segment
		(start 366.820958 -221.34703)
		(end 366.820958 -221.128844)
		(width 0.1143)
		(layer "In2.Cu")
		(net "GMI_CPU0_G2_CPU1_G0_TX_DP<7>")
	)
	(segment
		(start 367.01603 -226.359974)
		(end 367.04778 -226.341686)
		(width 0.1143)
		(layer "In2.Cu")
		(net "GMI_CPU0_G2_CPU1_G0_TX_DP<7>")
	)
	(segment
		(start 154.224482 -186.21883)
		(end 111.074454 -208.764886)
		(width 0.14224)
		(layer "In2.Cu")
		(net "GMI_CPU0_G2_CPU1_G0_TX_DP<7>")
	)
	(segment
		(start 367.876836 -228.284278)
		(end 367.794032 -228.201474)
		(width 0.1143)
		(layer "In2.Cu")
		(net "GMI_CPU0_G2_CPU1_G0_TX_DP<7>")
	)
	(segment
		(start 104.448864 -223.746568)
		(end 104.448102 -223.747076)
		(width 0.1143)
		(layer "In2.Cu")
		(net "GMI_CPU0_G2_CPU1_G0_TX_DP<7>")
	)
	(segment
		(start 104.454198 -226.345496)
		(end 104.457754 -226.347274)
		(width 0.1143)
		(layer "In2.Cu")
		(net "GMI_CPU0_G2_CPU1_G0_TX_DP<7>")
	)
	(segment
		(start 104.416606 -224.70364)
		(end 104.447086 -224.72142)
		(width 0.1143)
		(layer "In2.Cu")
		(net "GMI_CPU0_G2_CPU1_G0_TX_DP<7>")
	)
	(segment
		(start 104.45242 -223.104456)
		(end 104.453436 -223.104964)
		(width 0.1143)
		(layer "In2.Cu")
		(net "GMI_CPU0_G2_CPU1_G0_TX_DP<7>")
	)
	(segment
		(start 103.70185 -228.201728)
		(end 103.619046 -228.284532)
		(width 0.1143)
		(layer "In2.Cu")
		(net "GMI_CPU0_G2_CPU1_G0_TX_DP<7>")
	)
	(segment
		(start 104.45242 -224.724468)
		(end 104.453436 -224.724976)
		(width 0.1143)
		(layer "In2.Cu")
		(net "GMI_CPU0_G2_CPU1_G0_TX_DP<7>")
	)
	(segment
		(start 309.702708 -183.070246)
		(end 308.892448 -182.761128)
		(width 0.14224)
		(layer "In2.Cu")
		(net "GMI_CPU0_G2_CPU1_G0_TX_DP<7>")
	)
	(segment
		(start 367.342674 -227.49637)
		(end 367.342674 -227.483924)
		(width 0.1143)
		(layer "In2.Cu")
		(net "GMI_CPU0_G2_CPU1_G0_TX_DP<7>")
	)
	(segment
		(start 366.860074 -221.80423)
		(end 366.860074 -221.386146)
		(width 0.1143)
		(layer "In2.Cu")
		(net "GMI_CPU0_G2_CPU1_G0_TX_DP<7>")
	)
	(segment
		(start 236.615732 -179.679346)
		(end 166.231824 -181.77002)
		(width 0.14224)
		(layer "In2.Cu")
		(net "GMI_CPU0_G2_CPU1_G0_TX_DP<7>")
	)
	(segment
		(start 104.447086 -223.747584)
		(end 104.445562 -223.7486)
		(width 0.1143)
		(layer "In2.Cu")
		(net "GMI_CPU0_G2_CPU1_G0_TX_DP<7>")
	)
	(segment
		(start 367.01603 -223.11995)
		(end 367.04778 -223.101662)
		(width 0.1143)
		(layer "In2.Cu")
		(net "GMI_CPU0_G2_CPU1_G0_TX_DP<7>")
	)
	(segment
		(start 367.04778 -223.101662)
		(end 367.084102 -223.08058)
		(width 0.1143)
		(layer "In2.Cu")
		(net "GMI_CPU0_G2_CPU1_G0_TX_DP<7>")
	)
	(segment
		(start 327.22058 -191.988694)
		(end 327.22058 -191.98844)
		(width 0.14224)
		(layer "In2.Cu")
		(net "GMI_CPU0_G2_CPU1_G0_TX_DP<7>")
	)
	(segment
		(start 103.94061 -222.270066)
		(end 103.978202 -222.29191)
		(width 0.1143)
		(layer "In2.Cu")
		(net "GMI_CPU0_G2_CPU1_G0_TX_DP<7>")
	)
	(segment
		(start 367.01603 -223.72828)
		(end 367.01603 -223.728534)
		(width 0.1143)
		(layer "In2.Cu")
		(net "GMI_CPU0_G2_CPU1_G0_TX_DP<7>")
	)
	(segment
		(start 368.174778 -228.284278)
		(end 367.876836 -228.284278)
		(width 0.1143)
		(layer "In2.Cu")
		(net "GMI_CPU0_G2_CPU1_G0_TX_DP<7>")
	)
	(segment
		(start 367.04778 -225.366834)
		(end 367.01603 -225.348546)
		(width 0.1143)
		(layer "In2.Cu")
		(net "GMI_CPU0_G2_CPU1_G0_TX_DP<7>")
	)
	(segment
		(start 367.032032 -223.737424)
		(end 367.01603 -223.72828)
		(width 0.1143)
		(layer "In2.Cu")
		(net "GMI_CPU0_G2_CPU1_G0_TX_DP<7>")
	)
	(segment
		(start 306.362862 -182.103268)
		(end 236.615732 -179.679346)
		(width 0.14224)
		(layer "In2.Cu")
		(net "GMI_CPU0_G2_CPU1_G0_TX_DP<7>")
	)
	(segment
		(start 367.086896 -224.699068)
		(end 367.114582 -224.679002)
		(width 0.1143)
		(layer "In2.Cu")
		(net "GMI_CPU0_G2_CPU1_G0_TX_DP<7>")
	)
	(segment
		(start 367.01603 -224.739962)
		(end 367.086896 -224.699068)
		(width 0.1143)
		(layer "In2.Cu")
		(net "GMI_CPU0_G2_CPU1_G0_TX_DP<7>")
	)
	(segment
		(start 367.086896 -223.769428)
		(end 367.048034 -223.747076)
		(width 0.1143)
		(layer "In2.Cu")
		(net "GMI_CPU0_G2_CPU1_G0_TX_DP<7>")
	)
	(segment
		(start 366.866678 -221.083124)
		(end 366.866678 -219.076524)
		(width 0.14224)
		(layer "In2.Cu")
		(net "GMI_CPU0_G2_CPU1_G0_TX_DP<7>")
	)
	(segment
		(start 104.457754 -224.727262)
		(end 104.479852 -224.740216)
		(width 0.1143)
		(layer "In2.Cu")
		(net "GMI_CPU0_G2_CPU1_G0_TX_DP<7>")
	)
	(segment
		(start 104.008682 -227.779326)
		(end 103.978202 -227.797106)
		(width 0.1143)
		(layer "In2.Cu")
		(net "GMI_CPU0_G2_CPU1_G0_TX_DP<7>")
	)
	(segment
		(start 104.448864 -226.342448)
		(end 104.451658 -226.343972)
		(width 0.1143)
		(layer "In2.Cu")
		(net "GMI_CPU0_G2_CPU1_G0_TX_DP<7>")
	)
	(segment
		(start 104.453436 -223.104964)
		(end 104.454198 -223.105472)
		(width 0.1143)
		(layer "In2.Cu")
		(net "GMI_CPU0_G2_CPU1_G0_TX_DP<7>")
	)
	(segment
		(start 104.45242 -226.34448)
		(end 104.453436 -226.344988)
		(width 0.1143)
		(layer "In2.Cu")
		(net "GMI_CPU0_G2_CPU1_G0_TX_DP<7>")
	)
	(segment
		(start 367.556796 -227.819712)
		(end 367.549938 -227.815648)
		(width 0.1143)
		(layer "In2.Cu")
		(net "GMI_CPU0_G2_CPU1_G0_TX_DP<7>")
	)
	(segment
		(start 356.753414 -209.486246)
		(end 327.22058 -191.988694)
		(width 0.14224)
		(layer "In2.Cu")
		(net "GMI_CPU0_G2_CPU1_G0_TX_DP<7>")
	)
	(segment
		(start 104.479852 -225.3488)
		(end 104.450134 -225.365818)
		(width 0.1143)
		(layer "In2.Cu")
		(net "GMI_CPU0_G2_CPU1_G0_TX_DP<7>")
	)
	(segment
		(start 367.059972 -226.994212)
		(end 367.01603 -226.968304)
		(width 0.1143)
		(layer "In2.Cu")
		(net "GMI_CPU0_G2_CPU1_G0_TX_DP<7>")
	)
	(segment
		(start 367.114582 -223.789494)
		(end 367.086896 -223.769428)
		(width 0.1143)
		(layer "In2.Cu")
		(net "GMI_CPU0_G2_CPU1_G0_TX_DP<7>")
	)
	(segment
		(start 367.048034 -223.747076)
		(end 367.032032 -223.737424)
		(width 0.1143)
		(layer "In2.Cu")
		(net "GMI_CPU0_G2_CPU1_G0_TX_DP<7>")
	)
	(segment
		(start 367.04778 -222.12681)
		(end 367.01603 -222.108522)
		(width 0.1143)
		(layer "In2.Cu")
		(net "GMI_CPU0_G2_CPU1_G0_TX_DP<7>")
	)
	(segment
		(start 104.448102 -225.367088)
		(end 104.447086 -225.367596)
		(width 0.1143)
		(layer "In2.Cu")
		(net "GMI_CPU0_G2_CPU1_G0_TX_DP<7>")
	)
	(segment
		(start 104.448102 -226.9871)
		(end 104.447086 -226.987608)
		(width 0.1143)
		(layer "In2.Cu")
		(net "GMI_CPU0_G2_CPU1_G0_TX_DP<7>")
	)
	(segment
		(start 367.084102 -225.387916)
		(end 367.04778 -225.366834)
		(width 0.1143)
		(layer "In2.Cu")
		(net "GMI_CPU0_G2_CPU1_G0_TX_DP<7>")
	)
	(segment
		(start 367.516918 -227.796344)
		(end 367.514124 -227.795074)
		(width 0.1143)
		(layer "In2.Cu")
		(net "GMI_CPU0_G2_CPU1_G0_TX_DP<7>")
	)
	(segment
		(start 365.595662 -216.28227)
		(end 361.455462 -212.672676)
		(width 0.14224)
		(layer "In2.Cu")
		(net "GMI_CPU0_G2_CPU1_G0_TX_DP<7>")
	)
	(segment
		(start 104.448864 -224.722436)
		(end 104.451658 -224.72396)
		(width 0.1143)
		(layer "In2.Cu")
		(net "GMI_CPU0_G2_CPU1_G0_TX_DP<7>")
	)
	(segment
		(start 366.860074 -221.386146)
		(end 366.820958 -221.34703)
		(width 0.1143)
		(layer "In2.Cu")
		(net "GMI_CPU0_G2_CPU1_G0_TX_DP<7>")
	)
	(segment
		(start 103.978202 -222.29191)
		(end 104.008682 -222.30969)
		(width 0.1143)
		(layer "In2.Cu")
		(net "GMI_CPU0_G2_CPU1_G0_TX_DP<7>")
	)
	(segment
		(start 103.70947 -221.248732)
		(end 103.70947 -221.535498)
		(width 0.1143)
		(layer "In2.Cu")
		(net "GMI_CPU0_G2_CPU1_G0_TX_DP<7>")
	)
	(segment
		(start 104.454198 -224.725484)
		(end 104.457754 -224.727262)
		(width 0.1143)
		(layer "In2.Cu")
		(net "GMI_CPU0_G2_CPU1_G0_TX_DP<7>")
	)
	(segment
		(start 104.447086 -223.101408)
		(end 104.448102 -223.101916)
		(width 0.1143)
		(layer "In2.Cu")
		(net "GMI_CPU0_G2_CPU1_G0_TX_DP<7>")
	)
	(segment
		(start 104.448102 -226.34194)
		(end 104.448864 -226.342448)
		(width 0.1143)
		(layer "In2.Cu")
		(net "GMI_CPU0_G2_CPU1_G0_TX_DP<7>")
	)
	(segment
		(start 164.724588 -182.16372)
		(end 154.224482 -186.21883)
		(width 0.14224)
		(layer "In2.Cu")
		(net "GMI_CPU0_G2_CPU1_G0_TX_DP<7>")
	)
	(segment
		(start 103.978202 -227.797106)
		(end 103.939086 -227.819966)
		(width 0.1143)
		(layer "In2.Cu")
		(net "GMI_CPU0_G2_CPU1_G0_TX_DP<7>")
	)
	(segment
		(start 104.447086 -226.341432)
		(end 104.448102 -226.34194)
		(width 0.1143)
		(layer "In2.Cu")
		(net "GMI_CPU0_G2_CPU1_G0_TX_DP<7>")
	)
	(segment
		(start 104.408986 -226.31908)
		(end 104.415844 -226.323144)
		(width 0.1143)
		(layer "In2.Cu")
		(net "GMI_CPU0_G2_CPU1_G0_TX_DP<7>")
	)
	(segment
		(start 367.04778 -226.341686)
		(end 367.084102 -226.320604)
		(width 0.1143)
		(layer "In2.Cu")
		(net "GMI_CPU0_G2_CPU1_G0_TX_DP<7>")
	)
	(segment
		(start 104.448102 -224.721928)
		(end 104.448864 -224.722436)
		(width 0.1143)
		(layer "In2.Cu")
		(net "GMI_CPU0_G2_CPU1_G0_TX_DP<7>")
	)
	(segment
		(start 104.448102 -223.747076)
		(end 104.447086 -223.747584)
		(width 0.1143)
		(layer "In2.Cu")
		(net "GMI_CPU0_G2_CPU1_G0_TX_DP<7>")
	)
	(segment
		(start 366.866678 -219.076524)
		(end 365.595662 -216.28227)
		(width 0.14224)
		(layer "In2.Cu")
		(net "GMI_CPU0_G2_CPU1_G0_TX_DP<7>")
	)
	(segment
		(start 166.231824 -181.77002)
		(end 164.724588 -182.16372)
		(width 0.14224)
		(layer "In2.Cu")
		(net "GMI_CPU0_G2_CPU1_G0_TX_DP<7>")
	)
	(segment
		(start 104.454452 -223.74352)
		(end 104.45242 -223.744536)
		(width 0.1143)
		(layer "In2.Cu")
		(net "GMI_CPU0_G2_CPU1_G0_TX_DP<7>")
	)
	(segment
		(start 104.448102 -223.101916)
		(end 104.448864 -223.102424)
		(width 0.1143)
		(layer "In2.Cu")
		(net "GMI_CPU0_G2_CPU1_G0_TX_DP<7>")
	)
	(segment
		(start 104.415844 -224.703132)
		(end 104.416606 -224.70364)
		(width 0.1143)
		(layer "In2.Cu")
		(net "GMI_CPU0_G2_CPU1_G0_TX_DP<7>")
	)
	(segment
		(start 103.619046 -228.284532)
		(end 103.321104 -228.284532)
		(width 0.1143)
		(layer "In2.Cu")
		(net "GMI_CPU0_G2_CPU1_G0_TX_DP<7>")
	)
	(segment
		(start 103.66375 -216.17559)
		(end 103.66375 -221.174564)
		(width 0.14224)
		(layer "In2.Cu")
		(net "GMI_CPU0_G2_CPU1_G0_TX_DP<7>")
	)
	(segment
		(start 367.549938 -227.815648)
		(end 367.549176 -227.81514)
		(width 0.1143)
		(layer "In2.Cu")
		(net "GMI_CPU0_G2_CPU1_G0_TX_DP<7>")
	)
	(segment
		(start 104.416606 -223.083628)
		(end 104.447086 -223.101408)
		(width 0.1143)
		(layer "In2.Cu")
		(net "GMI_CPU0_G2_CPU1_G0_TX_DP<7>")
	)
	(segment
		(start 104.447086 -225.367596)
		(end 104.408986 -225.389948)
		(width 0.1143)
		(layer "In2.Cu")
		(net "GMI_CPU0_G2_CPU1_G0_TX_DP<7>")
	)
	(segment
		(start 104.457754 -223.10725)
		(end 104.479852 -223.120204)
		(width 0.1143)
		(layer "In2.Cu")
		(net "GMI_CPU0_G2_CPU1_G0_TX_DP<7>")
	)
	(segment
		(start 104.408986 -223.079056)
		(end 104.415844 -223.08312)
		(width 0.1143)
		(layer "In2.Cu")
		(net "GMI_CPU0_G2_CPU1_G0_TX_DP<7>")
	)
	(segment
		(start 104.415844 -226.323144)
		(end 104.416606 -226.323652)
		(width 0.1143)
		(layer "In2.Cu")
		(net "GMI_CPU0_G2_CPU1_G0_TX_DP<7>")
	)
	(segment
		(start 104.454198 -223.105472)
		(end 104.457754 -223.10725)
		(width 0.1143)
		(layer "In2.Cu")
		(net "GMI_CPU0_G2_CPU1_G0_TX_DP<7>")
	)
	(segment
		(start 104.451658 -223.745044)
		(end 104.448864 -223.746568)
		(width 0.1143)
		(layer "In2.Cu")
		(net "GMI_CPU0_G2_CPU1_G0_TX_DP<7>")
	)
	(segment
		(start 104.453436 -226.344988)
		(end 104.454198 -226.345496)
		(width 0.1143)
		(layer "In2.Cu")
		(net "GMI_CPU0_G2_CPU1_G0_TX_DP<7>")
	)
	(segment
		(start 366.820958 -221.128844)
		(end 366.866678 -221.083124)
		(width 0.1143)
		(layer "In2.Cu")
		(net "GMI_CPU0_G2_CPU1_G0_TX_DP<7>")
	)
	(segment
		(start 104.448864 -223.102424)
		(end 104.451658 -223.103948)
		(width 0.1143)
		(layer "In2.Cu")
		(net "GMI_CPU0_G2_CPU1_G0_TX_DP<7>")
	)
	(segment
		(start 327.22058 -191.98844)
		(end 322.992242 -189.483238)
		(width 0.14224)
		(layer "In2.Cu")
		(net "GMI_CPU0_G2_CPU1_G0_TX_DP<7>")
	)
	(segment
		(start 104.450134 -225.365818)
		(end 104.448864 -225.36658)
		(width 0.1143)
		(layer "In2.Cu")
		(net "GMI_CPU0_G2_CPU1_G0_TX_DP<7>")
	)
	(segment
		(start 111.074454 -208.764886)
		(end 103.66375 -216.17559)
		(width 0.14224)
		(layer "In2.Cu")
		(net "GMI_CPU0_G2_CPU1_G0_TX_DP<7>")
	)
	(arc
		(start 104.165654 -222.61449)
		(mid 104.230169 -222.876709)
		(end 104.408986 -223.079056)
		(width 0.1143)
		(layer "In2.Cu")
		(net "GMI_CPU0_G2_CPU1_G0_TX_DP<7>")
	)
	(arc
		(start 367.098326 -225.397822)
		(mid 367.091252 -225.392815)
		(end 367.084102 -225.387916)
		(width 0.1143)
		(layer "In2.Cu")
		(net "GMI_CPU0_G2_CPU1_G0_TX_DP<7>")
	)
	(arc
		(start 367.01603 -223.728534)
		(mid 366.860102 -223.424242)
		(end 367.01603 -223.11995)
		(width 0.1143)
		(layer "In2.Cu")
		(net "GMI_CPU0_G2_CPU1_G0_TX_DP<7>")
	)
	(arc
		(start 367.794032 -228.201474)
		(mid 367.714953 -227.986029)
		(end 367.556796 -227.819712)
		(width 0.1143)
		(layer "In2.Cu")
		(net "GMI_CPU0_G2_CPU1_G0_TX_DP<7>")
	)
	(arc
		(start 367.098326 -222.157798)
		(mid 367.091252 -222.152791)
		(end 367.084102 -222.147892)
		(width 0.1143)
		(layer "In2.Cu")
		(net "GMI_CPU0_G2_CPU1_G0_TX_DP<7>")
	)
	(arc
		(start 367.084102 -223.08058)
		(mid 367.091251 -223.07568)
		(end 367.098326 -223.070674)
		(width 0.1143)
		(layer "In2.Cu")
		(net "GMI_CPU0_G2_CPU1_G0_TX_DP<7>")
	)
	(arc
		(start 104.479852 -223.120204)
		(mid 104.63578 -223.424496)
		(end 104.479852 -223.728788)
		(width 0.1143)
		(layer "In2.Cu")
		(net "GMI_CPU0_G2_CPU1_G0_TX_DP<7>")
	)
	(arc
		(start 367.513616 -227.79482)
		(mid 367.388416 -227.668346)
		(end 367.342674 -227.49637)
		(width 0.1143)
		(layer "In2.Cu")
		(net "GMI_CPU0_G2_CPU1_G0_TX_DP<7>")
	)
	(arc
		(start 367.01603 -226.968304)
		(mid 366.934049 -226.887654)
		(end 366.880394 -226.785932)
		(width 0.1143)
		(layer "In2.Cu")
		(net "GMI_CPU0_G2_CPU1_G0_TX_DP<7>")
	)
	(arc
		(start 367.098326 -223.070674)
		(mid 367.325709 -222.614236)
		(end 367.098326 -222.157798)
		(width 0.1143)
		(layer "In2.Cu")
		(net "GMI_CPU0_G2_CPU1_G0_TX_DP<7>")
	)
	(arc
		(start 104.008682 -222.30969)
		(mid 104.124109 -222.443066)
		(end 104.165654 -222.61449)
		(width 0.1143)
		(layer "In2.Cu")
		(net "GMI_CPU0_G2_CPU1_G0_TX_DP<7>")
	)
	(arc
		(start 104.165654 -227.474526)
		(mid 104.124105 -227.645948)
		(end 104.008682 -227.779326)
		(width 0.1143)
		(layer "In2.Cu")
		(net "GMI_CPU0_G2_CPU1_G0_TX_DP<7>")
	)
	(arc
		(start 367.01603 -225.348546)
		(mid 366.860102 -225.044254)
		(end 367.01603 -224.739962)
		(width 0.1143)
		(layer "In2.Cu")
		(net "GMI_CPU0_G2_CPU1_G0_TX_DP<7>")
	)
	(arc
		(start 103.696008 -221.804484)
		(mid 103.76088 -222.067447)
		(end 103.94061 -222.270066)
		(width 0.1143)
		(layer "In2.Cu")
		(net "GMI_CPU0_G2_CPU1_G0_TX_DP<7>")
	)
	(arc
		(start 104.408986 -227.00996)
		(mid 104.230173 -227.21231)
		(end 104.165654 -227.474526)
		(width 0.1143)
		(layer "In2.Cu")
		(net "GMI_CPU0_G2_CPU1_G0_TX_DP<7>")
	)
	(arc
		(start 103.70566 -228.178868)
		(mid 103.703637 -228.190278)
		(end 103.70185 -228.201728)
		(width 0.1143)
		(layer "In2.Cu")
		(net "GMI_CPU0_G2_CPU1_G0_TX_DP<7>")
	)
	(arc
		(start 367.084102 -226.320604)
		(mid 367.091251 -226.315704)
		(end 367.098326 -226.310698)
		(width 0.1143)
		(layer "In2.Cu")
		(net "GMI_CPU0_G2_CPU1_G0_TX_DP<7>")
	)
	(arc
		(start 103.939086 -227.819966)
		(mid 103.787099 -227.976474)
		(end 103.70566 -228.178868)
		(width 0.1143)
		(layer "In2.Cu")
		(net "GMI_CPU0_G2_CPU1_G0_TX_DP<7>")
	)
	(arc
		(start 366.880394 -226.785932)
		(mid 366.877773 -226.550523)
		(end 367.01603 -226.359974)
		(width 0.1143)
		(layer "In2.Cu")
		(net "GMI_CPU0_G2_CPU1_G0_TX_DP<7>")
	)
	(arc
		(start 104.479852 -226.360228)
		(mid 104.63578 -226.66452)
		(end 104.479852 -226.968812)
		(width 0.1143)
		(layer "In2.Cu")
		(net "GMI_CPU0_G2_CPU1_G0_TX_DP<7>")
	)
	(arc
		(start 367.01603 -222.108522)
		(mid 366.901354 -221.975188)
		(end 366.860074 -221.80423)
		(width 0.1143)
		(layer "In2.Cu")
		(net "GMI_CPU0_G2_CPU1_G0_TX_DP<7>")
	)
	(arc
		(start 367.114582 -224.679002)
		(mid 367.342582 -224.234248)
		(end 367.114582 -223.789494)
		(width 0.1143)
		(layer "In2.Cu")
		(net "GMI_CPU0_G2_CPU1_G0_TX_DP<7>")
	)
	(arc
		(start 104.479852 -224.740216)
		(mid 104.63578 -225.044508)
		(end 104.479852 -225.3488)
		(width 0.1143)
		(layer "In2.Cu")
		(net "GMI_CPU0_G2_CPU1_G0_TX_DP<7>")
	)
	(arc
		(start 367.342674 -227.483924)
		(mid 367.266917 -227.201209)
		(end 367.059972 -226.994212)
		(width 0.1143)
		(layer "In2.Cu")
		(net "GMI_CPU0_G2_CPU1_G0_TX_DP<7>")
	)
	(arc
		(start 104.408986 -225.389948)
		(mid 104.165659 -225.854514)
		(end 104.408986 -226.31908)
		(width 0.1143)
		(layer "In2.Cu")
		(net "GMI_CPU0_G2_CPU1_G0_TX_DP<7>")
	)
	(arc
		(start 104.408986 -223.769936)
		(mid 104.165659 -224.234502)
		(end 104.408986 -224.699068)
		(width 0.1143)
		(layer "In2.Cu")
		(net "GMI_CPU0_G2_CPU1_G0_TX_DP<7>")
	)
	(arc
		(start 367.098326 -226.310698)
		(mid 367.325709 -225.85426)
		(end 367.098326 -225.397822)
		(width 0.1143)
		(layer "In2.Cu")
		(net "GMI_CPU0_G2_CPU1_G0_TX_DP<7>")
	)
	(segment
		(start 100.967794 -230.170228)
		(end 100.500942 -229.90429)
		(width 0.12954)
		(layer "F.Cu")
		(net "GMI_CPU0_G2_CPU1_G0_TX_DP<6>")
	)
	(segment
		(start 370.527834 -230.169974)
		(end 370.994686 -229.904036)
		(width 0.12954)
		(layer "F.Cu")
		(net "GMI_CPU0_G2_CPU1_G0_TX_DP<6>")
	)
	(segment
		(start 101.62159 -228.610922)
		(end 101.588824 -228.629972)
		(width 0.1143)
		(layer "In2.Cu")
		(net "GMI_CPU0_G2_CPU1_G0_TX_DP<6>")
	)
	(segment
		(start 369.398804 -227.79736)
		(end 369.397788 -227.796852)
		(width 0.1143)
		(layer "In2.Cu")
		(net "GMI_CPU0_G2_CPU1_G0_TX_DP<6>")
	)
	(segment
		(start 370.994686 -229.904036)
		(end 370.696998 -229.904036)
		(width 0.1143)
		(layer "In2.Cu")
		(net "GMI_CPU0_G2_CPU1_G0_TX_DP<6>")
	)
	(segment
		(start 368.96675 -225.389694)
		(end 368.927634 -225.366834)
		(width 0.1143)
		(layer "In2.Cu")
		(net "GMI_CPU0_G2_CPU1_G0_TX_DP<6>")
	)
	(segment
		(start 102.60838 -225.34245)
		(end 102.57282 -225.360484)
		(width 0.1143)
		(layer "In2.Cu")
		(net "GMI_CPU0_G2_CPU1_G0_TX_DP<6>")
	)
	(segment
		(start 370.337842 -229.41661)
		(end 370.304314 -229.397052)
		(width 0.1143)
		(layer "In2.Cu")
		(net "GMI_CPU0_G2_CPU1_G0_TX_DP<6>")
	)
	(segment
		(start 368.927634 -225.366834)
		(end 368.897154 -225.349054)
		(width 0.1143)
		(layer "In2.Cu")
		(net "GMI_CPU0_G2_CPU1_G0_TX_DP<6>")
	)
	(segment
		(start 102.565454 -226.340162)
		(end 102.5652 -226.340416)
		(width 0.1143)
		(layer "In2.Cu")
		(net "GMI_CPU0_G2_CPU1_G0_TX_DP<6>")
	)
	(segment
		(start 369.397788 -227.796852)
		(end 369.397026 -227.796344)
		(width 0.1143)
		(layer "In2.Cu")
		(net "GMI_CPU0_G2_CPU1_G0_TX_DP<6>")
	)
	(segment
		(start 368.927634 -223.101662)
		(end 368.96675 -223.078802)
		(width 0.1143)
		(layer "In2.Cu")
		(net "GMI_CPU0_G2_CPU1_G0_TX_DP<6>")
	)
	(segment
		(start 368.96675 -222.14967)
		(end 368.947192 -222.13824)
		(width 0.1143)
		(layer "In2.Cu")
		(net "GMI_CPU0_G2_CPU1_G0_TX_DP<6>")
	)
	(segment
		(start 368.897154 -224.739454)
		(end 368.927634 -224.721674)
		(width 0.1143)
		(layer "In2.Cu")
		(net "GMI_CPU0_G2_CPU1_G0_TX_DP<6>")
	)
	(segment
		(start 102.529894 -226.319842)
		(end 102.56266 -226.338638)
		(width 0.1143)
		(layer "In2.Cu")
		(net "GMI_CPU0_G2_CPU1_G0_TX_DP<6>")
	)
	(segment
		(start 101.631496 -228.60508)
		(end 101.628702 -228.606604)
		(width 0.1143)
		(layer "In2.Cu")
		(net "GMI_CPU0_G2_CPU1_G0_TX_DP<6>")
	)
	(segment
		(start 102.561644 -223.750886)
		(end 102.528878 -223.769936)
		(width 0.1143)
		(layer "In2.Cu")
		(net "GMI_CPU0_G2_CPU1_G0_TX_DP<6>")
	)
	(segment
		(start 101.626924 -228.60762)
		(end 101.6254 -228.608636)
		(width 0.1143)
		(layer "In2.Cu")
		(net "GMI_CPU0_G2_CPU1_G0_TX_DP<6>")
	)
	(segment
		(start 368.710718 -221.365318)
		(end 368.710718 -221.128844)
		(width 0.1143)
		(layer "In2.Cu")
		(net "GMI_CPU0_G2_CPU1_G0_TX_DP<6>")
	)
	(segment
		(start 102.061772 -222.270828)
		(end 102.128574 -222.30969)
		(width 0.1143)
		(layer "In2.Cu")
		(net "GMI_CPU0_G2_CPU1_G0_TX_DP<6>")
	)
	(segment
		(start 369.39347 -227.794312)
		(end 369.391946 -227.79355)
		(width 0.1143)
		(layer "In2.Cu")
		(net "GMI_CPU0_G2_CPU1_G0_TX_DP<6>")
	)
	(segment
		(start 102.568756 -226.342448)
		(end 102.599744 -226.360228)
		(width 0.1143)
		(layer "In2.Cu")
		(net "GMI_CPU0_G2_CPU1_G0_TX_DP<6>")
	)
	(segment
		(start 101.65969 -228.588824)
		(end 101.634544 -228.603302)
		(width 0.1143)
		(layer "In2.Cu")
		(net "GMI_CPU0_G2_CPU1_G0_TX_DP<6>")
	)
	(segment
		(start 101.623622 -228.609652)
		(end 101.62159 -228.610922)
		(width 0.1143)
		(layer "In2.Cu")
		(net "GMI_CPU0_G2_CPU1_G0_TX_DP<6>")
	)
	(segment
		(start 102.619556 -225.334576)
		(end 102.60838 -225.34245)
		(width 0.1143)
		(layer "In2.Cu")
		(net "GMI_CPU0_G2_CPU1_G0_TX_DP<6>")
	)
	(segment
		(start 102.565454 -226.988624)
		(end 102.563676 -226.98964)
		(width 0.1143)
		(layer "In2.Cu")
		(net "GMI_CPU0_G2_CPU1_G0_TX_DP<6>")
	)
	(segment
		(start 102.528878 -224.699068)
		(end 102.599744 -224.740216)
		(width 0.1143)
		(layer "In2.Cu")
		(net "GMI_CPU0_G2_CPU1_G0_TX_DP<6>")
	)
	(segment
		(start 368.96675 -227.009706)
		(end 368.927634 -226.986846)
		(width 0.1143)
		(layer "In2.Cu")
		(net "GMI_CPU0_G2_CPU1_G0_TX_DP<6>")
	)
	(segment
		(start 362.801662 -211.264754)
		(end 357.48087 -207.658716)
		(width 0.14224)
		(layer "In2.Cu")
		(net "GMI_CPU0_G2_CPU1_G0_TX_DP<6>")
	)
	(segment
		(start 101.816154 -221.248732)
		(end 101.816154 -221.545912)
		(width 0.1143)
		(layer "In2.Cu")
		(net "GMI_CPU0_G2_CPU1_G0_TX_DP<6>")
	)
	(segment
		(start 309.170832 -180.835046)
		(end 305.371246 -179.848764)
		(width 0.14224)
		(layer "In2.Cu")
		(net "GMI_CPU0_G2_CPU1_G0_TX_DP<6>")
	)
	(segment
		(start 369.906804 -228.629718)
		(end 369.867688 -228.606858)
		(width 0.1143)
		(layer "In2.Cu")
		(net "GMI_CPU0_G2_CPU1_G0_TX_DP<6>")
	)
	(segment
		(start 152.942798 -184.696608)
		(end 109.38637 -207.395318)
		(width 0.14224)
		(layer "In2.Cu")
		(net "GMI_CPU0_G2_CPU1_G0_TX_DP<6>")
	)
	(segment
		(start 102.568756 -226.986592)
		(end 102.566978 -226.987608)
		(width 0.1143)
		(layer "In2.Cu")
		(net "GMI_CPU0_G2_CPU1_G0_TX_DP<6>")
	)
	(segment
		(start 101.628702 -228.606604)
		(end 101.626924 -228.60762)
		(width 0.1143)
		(layer "In2.Cu")
		(net "GMI_CPU0_G2_CPU1_G0_TX_DP<6>")
	)
	(segment
		(start 368.897154 -226.359466)
		(end 368.927634 -226.341686)
		(width 0.1143)
		(layer "In2.Cu")
		(net "GMI_CPU0_G2_CPU1_G0_TX_DP<6>")
	)
	(segment
		(start 102.561644 -226.99091)
		(end 102.528878 -227.00996)
		(width 0.1143)
		(layer "In2.Cu")
		(net "GMI_CPU0_G2_CPU1_G0_TX_DP<6>")
	)
	(segment
		(start 100.798884 -229.90429)
		(end 100.500942 -229.90429)
		(width 0.1143)
		(layer "In2.Cu")
		(net "GMI_CPU0_G2_CPU1_G0_TX_DP<6>")
	)
	(segment
		(start 368.740436 -221.80423)
		(end 368.740182 -221.804484)
		(width 0.1143)
		(layer "In2.Cu")
		(net "GMI_CPU0_G2_CPU1_G0_TX_DP<6>")
	)
	(segment
		(start 369.397026 -227.796344)
		(end 369.395756 -227.795582)
		(width 0.1143)
		(layer "In2.Cu")
		(net "GMI_CPU0_G2_CPU1_G0_TX_DP<6>")
	)
	(segment
		(start 369.387374 -227.79101)
		(end 369.366038 -227.778564)
		(width 0.1143)
		(layer "In2.Cu")
		(net "GMI_CPU0_G2_CPU1_G0_TX_DP<6>")
	)
	(segment
		(start 102.565454 -223.7486)
		(end 102.563676 -223.749616)
		(width 0.1143)
		(layer "In2.Cu")
		(net "GMI_CPU0_G2_CPU1_G0_TX_DP<6>")
	)
	(segment
		(start 102.528878 -223.079056)
		(end 102.599744 -223.120204)
		(width 0.1143)
		(layer "In2.Cu")
		(net "GMI_CPU0_G2_CPU1_G0_TX_DP<6>")
	)
	(segment
		(start 101.634544 -228.603302)
		(end 101.633782 -228.60381)
		(width 0.1143)
		(layer "In2.Cu")
		(net "GMI_CPU0_G2_CPU1_G0_TX_DP<6>")
	)
	(segment
		(start 324.36181 -188.03366)
		(end 310.455056 -181.324504)
		(width 0.14224)
		(layer "In2.Cu")
		(net "GMI_CPU0_G2_CPU1_G0_TX_DP<6>")
	)
	(segment
		(start 101.816154 -221.545912)
		(end 101.8159 -221.546166)
		(width 0.1143)
		(layer "In2.Cu")
		(net "GMI_CPU0_G2_CPU1_G0_TX_DP<6>")
	)
	(segment
		(start 162.980116 -180.539644)
		(end 152.942798 -184.696608)
		(width 0.14224)
		(layer "In2.Cu")
		(net "GMI_CPU0_G2_CPU1_G0_TX_DP<6>")
	)
	(segment
		(start 102.536752 -225.384868)
		(end 102.53472 -225.385884)
		(width 0.1143)
		(layer "In2.Cu")
		(net "GMI_CPU0_G2_CPU1_G0_TX_DP<6>")
	)
	(segment
		(start 102.57282 -225.360484)
		(end 102.539546 -225.382836)
		(width 0.1143)
		(layer "In2.Cu")
		(net "GMI_CPU0_G2_CPU1_G0_TX_DP<6>")
	)
	(segment
		(start 368.927634 -226.341686)
		(end 368.96675 -226.318826)
		(width 0.1143)
		(layer "In2.Cu")
		(net "GMI_CPU0_G2_CPU1_G0_TX_DP<6>")
	)
	(segment
		(start 101.770434 -221.174564)
		(end 101.770434 -221.203012)
		(width 0.1143)
		(layer "In2.Cu")
		(net "GMI_CPU0_G2_CPU1_G0_TX_DP<6>")
	)
	(segment
		(start 368.927634 -223.746822)
		(end 368.897154 -223.729042)
		(width 0.1143)
		(layer "In2.Cu")
		(net "GMI_CPU0_G2_CPU1_G0_TX_DP<6>")
	)
	(segment
		(start 369.391184 -227.793042)
		(end 369.389914 -227.79228)
		(width 0.1143)
		(layer "In2.Cu")
		(net "GMI_CPU0_G2_CPU1_G0_TX_DP<6>")
	)
	(segment
		(start 101.77399 -219.547948)
		(end 101.770434 -219.547948)
		(width 0.14224)
		(layer "In2.Cu")
		(net "GMI_CPU0_G2_CPU1_G0_TX_DP<6>")
	)
	(segment
		(start 102.599744 -223.120204)
		(end 102.619556 -223.134428)
		(width 0.1143)
		(layer "In2.Cu")
		(net "GMI_CPU0_G2_CPU1_G0_TX_DP<6>")
	)
	(segment
		(start 368.756438 -221.083124)
		(end 368.756438 -218.638882)
		(width 0.14224)
		(layer "In2.Cu")
		(net "GMI_CPU0_G2_CPU1_G0_TX_DP<6>")
	)
	(segment
		(start 368.756438 -218.638882)
		(end 367.111534 -215.022684)
		(width 0.14224)
		(layer "In2.Cu")
		(net "GMI_CPU0_G2_CPU1_G0_TX_DP<6>")
	)
	(segment
		(start 368.710718 -221.128844)
		(end 368.756438 -221.083124)
		(width 0.1143)
		(layer "In2.Cu")
		(net "GMI_CPU0_G2_CPU1_G0_TX_DP<6>")
	)
	(segment
		(start 102.566978 -226.987608)
		(end 102.565454 -226.988624)
		(width 0.1143)
		(layer "In2.Cu")
		(net "GMI_CPU0_G2_CPU1_G0_TX_DP<6>")
	)
	(segment
		(start 102.566978 -226.341432)
		(end 102.568756 -226.342448)
		(width 0.1143)
		(layer "In2.Cu")
		(net "GMI_CPU0_G2_CPU1_G0_TX_DP<6>")
	)
	(segment
		(start 101.190552 -229.398068)
		(end 101.118924 -229.439724)
		(width 0.1143)
		(layer "In2.Cu")
		(net "GMI_CPU0_G2_CPU1_G0_TX_DP<6>")
	)
	(segment
		(start 369.436904 -227.819712)
		(end 369.398804 -227.79736)
		(width 0.1143)
		(layer "In2.Cu")
		(net "GMI_CPU0_G2_CPU1_G0_TX_DP<6>")
	)
	(segment
		(start 368.96675 -223.769682)
		(end 368.927634 -223.746822)
		(width 0.1143)
		(layer "In2.Cu")
		(net "GMI_CPU0_G2_CPU1_G0_TX_DP<6>")
	)
	(segment
		(start 101.633782 -228.60381)
		(end 101.632258 -228.604572)
		(width 0.1143)
		(layer "In2.Cu")
		(net "GMI_CPU0_G2_CPU1_G0_TX_DP<6>")
	)
	(segment
		(start 368.740182 -221.804484)
		(end 368.740182 -221.394782)
		(width 0.1143)
		(layer "In2.Cu")
		(net "GMI_CPU0_G2_CPU1_G0_TX_DP<6>")
	)
	(segment
		(start 102.563676 -226.98964)
		(end 102.561644 -226.99091)
		(width 0.1143)
		(layer "In2.Cu")
		(net "GMI_CPU0_G2_CPU1_G0_TX_DP<6>")
	)
	(segment
		(start 305.371246 -179.848764)
		(end 235.328714 -177.488596)
		(width 0.14224)
		(layer "In2.Cu")
		(net "GMI_CPU0_G2_CPU1_G0_TX_DP<6>")
	)
	(segment
		(start 101.6254 -228.608636)
		(end 101.623622 -228.609652)
		(width 0.1143)
		(layer "In2.Cu")
		(net "GMI_CPU0_G2_CPU1_G0_TX_DP<6>")
	)
	(segment
		(start 102.563676 -223.749616)
		(end 102.561644 -223.750886)
		(width 0.1143)
		(layer "In2.Cu")
		(net "GMI_CPU0_G2_CPU1_G0_TX_DP<6>")
	)
	(segment
		(start 368.947192 -222.13824)
		(end 368.896138 -222.108268)
		(width 0.1143)
		(layer "In2.Cu")
		(net "GMI_CPU0_G2_CPU1_G0_TX_DP<6>")
	)
	(segment
		(start 101.8159 -221.546166)
		(end 101.8159 -221.804484)
		(width 0.1143)
		(layer "In2.Cu")
		(net "GMI_CPU0_G2_CPU1_G0_TX_DP<6>")
	)
	(segment
		(start 109.38637 -207.395318)
		(end 101.77399 -215.007698)
		(width 0.14224)
		(layer "In2.Cu")
		(net "GMI_CPU0_G2_CPU1_G0_TX_DP<6>")
	)
	(segment
		(start 102.56266 -226.338638)
		(end 102.565454 -226.340162)
		(width 0.1143)
		(layer "In2.Cu")
		(net "GMI_CPU0_G2_CPU1_G0_TX_DP<6>")
	)
	(segment
		(start 368.927634 -224.721674)
		(end 368.96675 -224.698814)
		(width 0.1143)
		(layer "In2.Cu")
		(net "GMI_CPU0_G2_CPU1_G0_TX_DP<6>")
	)
	(segment
		(start 102.619556 -223.714564)
		(end 102.599744 -223.728788)
		(width 0.1143)
		(layer "In2.Cu")
		(net "GMI_CPU0_G2_CPU1_G0_TX_DP<6>")
	)
	(segment
		(start 357.48087 -207.658716)
		(end 324.36181 -188.03366)
		(width 0.14224)
		(layer "In2.Cu")
		(net "GMI_CPU0_G2_CPU1_G0_TX_DP<6>")
	)
	(segment
		(start 102.539546 -225.382836)
		(end 102.53853 -225.383598)
		(width 0.1143)
		(layer "In2.Cu")
		(net "GMI_CPU0_G2_CPU1_G0_TX_DP<6>")
	)
	(segment
		(start 101.770434 -221.203012)
		(end 101.816154 -221.248732)
		(width 0.1143)
		(layer "In2.Cu")
		(net "GMI_CPU0_G2_CPU1_G0_TX_DP<6>")
	)
	(segment
		(start 102.599744 -226.968812)
		(end 102.568756 -226.986592)
		(width 0.1143)
		(layer "In2.Cu")
		(net "GMI_CPU0_G2_CPU1_G0_TX_DP<6>")
	)
	(segment
		(start 367.111534 -215.022684)
		(end 362.801662 -211.264754)
		(width 0.14224)
		(layer "In2.Cu")
		(net "GMI_CPU0_G2_CPU1_G0_TX_DP<6>")
	)
	(segment
		(start 370.696998 -229.904036)
		(end 370.614194 -229.821232)
		(width 0.1143)
		(layer "In2.Cu")
		(net "GMI_CPU0_G2_CPU1_G0_TX_DP<6>")
	)
	(segment
		(start 368.927634 -226.986846)
		(end 368.897154 -226.969066)
		(width 0.1143)
		(layer "In2.Cu")
		(net "GMI_CPU0_G2_CPU1_G0_TX_DP<6>")
	)
	(segment
		(start 100.881688 -229.821486)
		(end 100.798884 -229.90429)
		(width 0.1143)
		(layer "In2.Cu")
		(net "GMI_CPU0_G2_CPU1_G0_TX_DP<6>")
	)
	(segment
		(start 369.389914 -227.79228)
		(end 369.387374 -227.79101)
		(width 0.1143)
		(layer "In2.Cu")
		(net "GMI_CPU0_G2_CPU1_G0_TX_DP<6>")
	)
	(segment
		(start 310.455056 -181.324504)
		(end 309.170832 -180.835046)
		(width 0.14224)
		(layer "In2.Cu")
		(net "GMI_CPU0_G2_CPU1_G0_TX_DP<6>")
	)
	(segment
		(start 102.5652 -226.340416)
		(end 102.565708 -226.34067)
		(width 0.1143)
		(layer "In2.Cu")
		(net "GMI_CPU0_G2_CPU1_G0_TX_DP<6>")
	)
	(segment
		(start 165.301168 -179.889658)
		(end 162.980116 -180.539644)
		(width 0.14224)
		(layer "In2.Cu")
		(net "GMI_CPU0_G2_CPU1_G0_TX_DP<6>")
	)
	(segment
		(start 101.632258 -228.604572)
		(end 101.631496 -228.60508)
		(width 0.1143)
		(layer "In2.Cu")
		(net "GMI_CPU0_G2_CPU1_G0_TX_DP<6>")
	)
	(segment
		(start 101.770434 -219.547948)
		(end 101.770434 -221.174564)
		(width 0.14224)
		(layer "In2.Cu")
		(net "GMI_CPU0_G2_CPU1_G0_TX_DP<6>")
	)
	(segment
		(start 102.565708 -226.34067)
		(end 102.566978 -226.341432)
		(width 0.1143)
		(layer "In2.Cu")
		(net "GMI_CPU0_G2_CPU1_G0_TX_DP<6>")
	)
	(segment
		(start 102.128574 -227.779326)
		(end 102.058978 -227.819966)
		(width 0.1143)
		(layer "In2.Cu")
		(net "GMI_CPU0_G2_CPU1_G0_TX_DP<6>")
	)
	(segment
		(start 101.77399 -215.007698)
		(end 101.77399 -219.547948)
		(width 0.14224)
		(layer "In2.Cu")
		(net "GMI_CPU0_G2_CPU1_G0_TX_DP<6>")
	)
	(segment
		(start 369.391946 -227.79355)
		(end 369.391184 -227.793042)
		(width 0.1143)
		(layer "In2.Cu")
		(net "GMI_CPU0_G2_CPU1_G0_TX_DP<6>")
	)
	(segment
		(start 102.599744 -224.740216)
		(end 102.619556 -224.75444)
		(width 0.1143)
		(layer "In2.Cu")
		(net "GMI_CPU0_G2_CPU1_G0_TX_DP<6>")
	)
	(segment
		(start 102.53853 -225.383598)
		(end 102.536752 -225.384868)
		(width 0.1143)
		(layer "In2.Cu")
		(net "GMI_CPU0_G2_CPU1_G0_TX_DP<6>")
	)
	(segment
		(start 369.867688 -228.606858)
		(end 369.837208 -228.589078)
		(width 0.1143)
		(layer "In2.Cu")
		(net "GMI_CPU0_G2_CPU1_G0_TX_DP<6>")
	)
	(segment
		(start 369.394232 -227.79482)
		(end 369.39347 -227.794312)
		(width 0.1143)
		(layer "In2.Cu")
		(net "GMI_CPU0_G2_CPU1_G0_TX_DP<6>")
	)
	(segment
		(start 235.328714 -177.488596)
		(end 165.301168 -179.889658)
		(width 0.14224)
		(layer "In2.Cu")
		(net "GMI_CPU0_G2_CPU1_G0_TX_DP<6>")
	)
	(segment
		(start 102.599744 -223.728788)
		(end 102.566978 -223.747584)
		(width 0.1143)
		(layer "In2.Cu")
		(net "GMI_CPU0_G2_CPU1_G0_TX_DP<6>")
	)
	(segment
		(start 370.376958 -229.43947)
		(end 370.337842 -229.41661)
		(width 0.1143)
		(layer "In2.Cu")
		(net "GMI_CPU0_G2_CPU1_G0_TX_DP<6>")
	)
	(segment
		(start 102.566978 -223.747584)
		(end 102.565454 -223.7486)
		(width 0.1143)
		(layer "In2.Cu")
		(net "GMI_CPU0_G2_CPU1_G0_TX_DP<6>")
	)
	(segment
		(start 368.740182 -221.394782)
		(end 368.710718 -221.365318)
		(width 0.1143)
		(layer "In2.Cu")
		(net "GMI_CPU0_G2_CPU1_G0_TX_DP<6>")
	)
	(segment
		(start 368.897154 -223.119442)
		(end 368.927634 -223.101662)
		(width 0.1143)
		(layer "In2.Cu")
		(net "GMI_CPU0_G2_CPU1_G0_TX_DP<6>")
	)
	(segment
		(start 369.395756 -227.795582)
		(end 369.394232 -227.79482)
		(width 0.1143)
		(layer "In2.Cu")
		(net "GMI_CPU0_G2_CPU1_G0_TX_DP<6>")
	)
	(arc
		(start 102.285546 -227.474526)
		(mid 102.243997 -227.645948)
		(end 102.128574 -227.779326)
		(width 0.1143)
		(layer "In2.Cu")
		(net "GMI_CPU0_G2_CPU1_G0_TX_DP<6>")
	)
	(arc
		(start 101.345492 -229.094538)
		(mid 101.304526 -229.264944)
		(end 101.190552 -229.398068)
		(width 0.1143)
		(layer "In2.Cu")
		(net "GMI_CPU0_G2_CPU1_G0_TX_DP<6>")
	)
	(arc
		(start 370.304314 -229.397052)
		(mid 370.190907 -229.264163)
		(end 370.150136 -229.094284)
		(width 0.1143)
		(layer "In2.Cu")
		(net "GMI_CPU0_G2_CPU1_G0_TX_DP<6>")
	)
	(arc
		(start 101.8159 -221.804484)
		(mid 101.881136 -222.068075)
		(end 102.061772 -222.270828)
		(width 0.1143)
		(layer "In2.Cu")
		(net "GMI_CPU0_G2_CPU1_G0_TX_DP<6>")
	)
	(arc
		(start 101.118924 -229.439724)
		(mid 100.966937 -229.596232)
		(end 100.885498 -229.798626)
		(width 0.1143)
		(layer "In2.Cu")
		(net "GMI_CPU0_G2_CPU1_G0_TX_DP<6>")
	)
	(arc
		(start 368.897154 -226.969066)
		(mid 368.740177 -226.664266)
		(end 368.897154 -226.359466)
		(width 0.1143)
		(layer "In2.Cu")
		(net "GMI_CPU0_G2_CPU1_G0_TX_DP<6>")
	)
	(arc
		(start 102.128574 -222.30969)
		(mid 102.244001 -222.443066)
		(end 102.285546 -222.61449)
		(width 0.1143)
		(layer "In2.Cu")
		(net "GMI_CPU0_G2_CPU1_G0_TX_DP<6>")
	)
	(arc
		(start 368.897154 -225.349054)
		(mid 368.740177 -225.044254)
		(end 368.897154 -224.739454)
		(width 0.1143)
		(layer "In2.Cu")
		(net "GMI_CPU0_G2_CPU1_G0_TX_DP<6>")
	)
	(arc
		(start 102.528878 -227.00996)
		(mid 102.350065 -227.21231)
		(end 102.285546 -227.474526)
		(width 0.1143)
		(layer "In2.Cu")
		(net "GMI_CPU0_G2_CPU1_G0_TX_DP<6>")
	)
	(arc
		(start 101.588824 -228.629972)
		(mid 101.410011 -228.832322)
		(end 101.345492 -229.094538)
		(width 0.1143)
		(layer "In2.Cu")
		(net "GMI_CPU0_G2_CPU1_G0_TX_DP<6>")
	)
	(arc
		(start 102.058978 -227.819966)
		(mid 101.880165 -228.022316)
		(end 101.815646 -228.284532)
		(width 0.1143)
		(layer "In2.Cu")
		(net "GMI_CPU0_G2_CPU1_G0_TX_DP<6>")
	)
	(arc
		(start 370.150136 -229.094284)
		(mid 370.085621 -228.832065)
		(end 369.906804 -228.629718)
		(width 0.1143)
		(layer "In2.Cu")
		(net "GMI_CPU0_G2_CPU1_G0_TX_DP<6>")
	)
	(arc
		(start 369.680236 -228.284278)
		(mid 369.615721 -228.022059)
		(end 369.436904 -227.819712)
		(width 0.1143)
		(layer "In2.Cu")
		(net "GMI_CPU0_G2_CPU1_G0_TX_DP<6>")
	)
	(arc
		(start 369.366038 -227.778564)
		(mid 369.251362 -227.64523)
		(end 369.210082 -227.474272)
		(width 0.1143)
		(layer "In2.Cu")
		(net "GMI_CPU0_G2_CPU1_G0_TX_DP<6>")
	)
	(arc
		(start 102.53472 -225.385884)
		(mid 102.285612 -225.85159)
		(end 102.529894 -226.319842)
		(width 0.1143)
		(layer "In2.Cu")
		(net "GMI_CPU0_G2_CPU1_G0_TX_DP<6>")
	)
	(arc
		(start 102.285546 -222.61449)
		(mid 102.350061 -222.876709)
		(end 102.528878 -223.079056)
		(width 0.1143)
		(layer "In2.Cu")
		(net "GMI_CPU0_G2_CPU1_G0_TX_DP<6>")
	)
	(arc
		(start 102.619556 -224.75444)
		(mid 102.76827 -225.044508)
		(end 102.619556 -225.334576)
		(width 0.1143)
		(layer "In2.Cu")
		(net "GMI_CPU0_G2_CPU1_G0_TX_DP<6>")
	)
	(arc
		(start 370.614194 -229.821232)
		(mid 370.535115 -229.605787)
		(end 370.376958 -229.43947)
		(width 0.1143)
		(layer "In2.Cu")
		(net "GMI_CPU0_G2_CPU1_G0_TX_DP<6>")
	)
	(arc
		(start 368.96675 -224.698814)
		(mid 369.210077 -224.234248)
		(end 368.96675 -223.769682)
		(width 0.1143)
		(layer "In2.Cu")
		(net "GMI_CPU0_G2_CPU1_G0_TX_DP<6>")
	)
	(arc
		(start 100.885498 -229.798626)
		(mid 100.883475 -229.810036)
		(end 100.881688 -229.821486)
		(width 0.1143)
		(layer "In2.Cu")
		(net "GMI_CPU0_G2_CPU1_G0_TX_DP<6>")
	)
	(arc
		(start 102.599744 -226.360228)
		(mid 102.751333 -226.66452)
		(end 102.599744 -226.968812)
		(width 0.1143)
		(layer "In2.Cu")
		(net "GMI_CPU0_G2_CPU1_G0_TX_DP<6>")
	)
	(arc
		(start 102.619556 -223.134428)
		(mid 102.76827 -223.424496)
		(end 102.619556 -223.714564)
		(width 0.1143)
		(layer "In2.Cu")
		(net "GMI_CPU0_G2_CPU1_G0_TX_DP<6>")
	)
	(arc
		(start 368.896138 -222.108268)
		(mid 368.781628 -221.975033)
		(end 368.740436 -221.80423)
		(width 0.1143)
		(layer "In2.Cu")
		(net "GMI_CPU0_G2_CPU1_G0_TX_DP<6>")
	)
	(arc
		(start 369.210082 -227.474272)
		(mid 369.145567 -227.212053)
		(end 368.96675 -227.009706)
		(width 0.1143)
		(layer "In2.Cu")
		(net "GMI_CPU0_G2_CPU1_G0_TX_DP<6>")
	)
	(arc
		(start 101.815646 -228.284532)
		(mid 101.774391 -228.455503)
		(end 101.65969 -228.588824)
		(width 0.1143)
		(layer "In2.Cu")
		(net "GMI_CPU0_G2_CPU1_G0_TX_DP<6>")
	)
	(arc
		(start 368.96675 -223.078802)
		(mid 369.210077 -222.614236)
		(end 368.96675 -222.14967)
		(width 0.1143)
		(layer "In2.Cu")
		(net "GMI_CPU0_G2_CPU1_G0_TX_DP<6>")
	)
	(arc
		(start 368.897154 -223.729042)
		(mid 368.740177 -223.424242)
		(end 368.897154 -223.119442)
		(width 0.1143)
		(layer "In2.Cu")
		(net "GMI_CPU0_G2_CPU1_G0_TX_DP<6>")
	)
	(arc
		(start 102.528878 -223.769936)
		(mid 102.285551 -224.234502)
		(end 102.528878 -224.699068)
		(width 0.1143)
		(layer "In2.Cu")
		(net "GMI_CPU0_G2_CPU1_G0_TX_DP<6>")
	)
	(arc
		(start 368.96675 -226.318826)
		(mid 369.210077 -225.85426)
		(end 368.96675 -225.389694)
		(width 0.1143)
		(layer "In2.Cu")
		(net "GMI_CPU0_G2_CPU1_G0_TX_DP<6>")
	)
	(arc
		(start 369.837208 -228.589078)
		(mid 369.721781 -228.455702)
		(end 369.680236 -228.284278)
		(width 0.1143)
		(layer "In2.Cu")
		(net "GMI_CPU0_G2_CPU1_G0_TX_DP<6>")
	)
	(segment
		(start 100.967794 -226.930458)
		(end 100.500942 -226.66452)
		(width 0.12954)
		(layer "F.Cu")
		(net "GMI_CPU0_G2_CPU1_G0_TX_DP<5>")
	)
	(segment
		(start 370.527834 -226.930204)
		(end 370.994686 -226.664266)
		(width 0.12954)
		(layer "F.Cu")
		(net "GMI_CPU0_G2_CPU1_G0_TX_DP<5>")
	)
	(segment
		(start 164.897054 -178.011836)
		(end 162.238944 -178.75631)
		(width 0.14224)
		(layer "In2.Cu")
		(net "GMI_CPU0_G2_CPU1_G0_TX_DP<5>")
	)
	(segment
		(start 235.30941 -175.598074)
		(end 164.897054 -178.011836)
		(width 0.14224)
		(layer "In2.Cu")
		(net "GMI_CPU0_G2_CPU1_G0_TX_DP<5>")
	)
	(segment
		(start 370.777262 -223.119442)
		(end 370.807742 -223.101662)
		(width 0.1143)
		(layer "In2.Cu")
		(net "GMI_CPU0_G2_CPU1_G0_TX_DP<5>")
	)
	(segment
		(start 99.890072 -221.174564)
		(end 99.890072 -221.203012)
		(width 0.1143)
		(layer "In2.Cu")
		(net "GMI_CPU0_G2_CPU1_G0_TX_DP<5>")
	)
	(segment
		(start 370.646198 -218.1225)
		(end 368.703098 -213.85022)
		(width 0.14224)
		(layer "In2.Cu")
		(net "GMI_CPU0_G2_CPU1_G0_TX_DP<5>")
	)
	(segment
		(start 370.846858 -225.389694)
		(end 370.807742 -225.366834)
		(width 0.1143)
		(layer "In2.Cu")
		(net "GMI_CPU0_G2_CPU1_G0_TX_DP<5>")
	)
	(segment
		(start 370.600478 -221.128844)
		(end 370.646198 -221.083124)
		(width 0.1143)
		(layer "In2.Cu")
		(net "GMI_CPU0_G2_CPU1_G0_TX_DP<5>")
	)
	(segment
		(start 325.49211 -186.468258)
		(end 311.392316 -179.666138)
		(width 0.14224)
		(layer "In2.Cu")
		(net "GMI_CPU0_G2_CPU1_G0_TX_DP<5>")
	)
	(segment
		(start 370.600478 -221.34703)
		(end 370.600478 -221.128844)
		(width 0.1143)
		(layer "In2.Cu")
		(net "GMI_CPU0_G2_CPU1_G0_TX_DP<5>")
	)
	(segment
		(start 370.62029 -221.366842)
		(end 370.600478 -221.34703)
		(width 0.1143)
		(layer "In2.Cu")
		(net "GMI_CPU0_G2_CPU1_G0_TX_DP<5>")
	)
	(segment
		(start 305.807364 -177.97399)
		(end 235.30941 -175.598074)
		(width 0.14224)
		(layer "In2.Cu")
		(net "GMI_CPU0_G2_CPU1_G0_TX_DP<5>")
	)
	(segment
		(start 99.890072 -213.775544)
		(end 99.890072 -221.174564)
		(width 0.14224)
		(layer "In2.Cu")
		(net "GMI_CPU0_G2_CPU1_G0_TX_DP<5>")
	)
	(segment
		(start 99.935792 -221.248732)
		(end 99.935792 -221.80423)
		(width 0.1143)
		(layer "In2.Cu")
		(net "GMI_CPU0_G2_CPU1_G0_TX_DP<5>")
	)
	(segment
		(start 100.868734 -226.59467)
		(end 100.798884 -226.66452)
		(width 0.1143)
		(layer "In2.Cu")
		(net "GMI_CPU0_G2_CPU1_G0_TX_DP<5>")
	)
	(segment
		(start 370.62029 -221.80423)
		(end 370.62029 -221.366842)
		(width 0.1143)
		(layer "In2.Cu")
		(net "GMI_CPU0_G2_CPU1_G0_TX_DP<5>")
	)
	(segment
		(start 370.807742 -224.721674)
		(end 370.846858 -224.698814)
		(width 0.1143)
		(layer "In2.Cu")
		(net "GMI_CPU0_G2_CPU1_G0_TX_DP<5>")
	)
	(segment
		(start 361.157012 -207.858868)
		(end 358.138984 -205.813406)
		(width 0.14224)
		(layer "In2.Cu")
		(net "GMI_CPU0_G2_CPU1_G0_TX_DP<5>")
	)
	(segment
		(start 370.807742 -223.101662)
		(end 370.846858 -223.078802)
		(width 0.1143)
		(layer "In2.Cu")
		(net "GMI_CPU0_G2_CPU1_G0_TX_DP<5>")
	)
	(segment
		(start 364.182152 -209.909156)
		(end 361.157012 -207.858614)
		(width 0.14224)
		(layer "In2.Cu")
		(net "GMI_CPU0_G2_CPU1_G0_TX_DP<5>")
	)
	(segment
		(start 370.994686 -226.664266)
		(end 370.696998 -226.664266)
		(width 0.1143)
		(layer "In2.Cu")
		(net "GMI_CPU0_G2_CPU1_G0_TX_DP<5>")
	)
	(segment
		(start 100.687886 -223.101916)
		(end 100.719636 -223.120204)
		(width 0.1143)
		(layer "In2.Cu")
		(net "GMI_CPU0_G2_CPU1_G0_TX_DP<5>")
	)
	(segment
		(start 99.935792 -221.80423)
		(end 99.935538 -221.804484)
		(width 0.1143)
		(layer "In2.Cu")
		(net "GMI_CPU0_G2_CPU1_G0_TX_DP<5>")
	)
	(segment
		(start 309.396638 -178.905408)
		(end 305.807364 -177.97399)
		(width 0.14224)
		(layer "In2.Cu")
		(net "GMI_CPU0_G2_CPU1_G0_TX_DP<5>")
	)
	(segment
		(start 358.138984 -205.813406)
		(end 325.49211 -186.468258)
		(width 0.14224)
		(layer "In2.Cu")
		(net "GMI_CPU0_G2_CPU1_G0_TX_DP<5>")
	)
	(segment
		(start 361.157012 -207.858614)
		(end 361.157012 -207.858868)
		(width 0.14224)
		(layer "In2.Cu")
		(net "GMI_CPU0_G2_CPU1_G0_TX_DP<5>")
	)
	(segment
		(start 100.687886 -224.721928)
		(end 100.719636 -224.740216)
		(width 0.1143)
		(layer "In2.Cu")
		(net "GMI_CPU0_G2_CPU1_G0_TX_DP<5>")
	)
	(segment
		(start 99.890072 -221.203012)
		(end 99.935792 -221.248732)
		(width 0.1143)
		(layer "In2.Cu")
		(net "GMI_CPU0_G2_CPU1_G0_TX_DP<5>")
	)
	(segment
		(start 370.807742 -223.746822)
		(end 370.777262 -223.729042)
		(width 0.1143)
		(layer "In2.Cu")
		(net "GMI_CPU0_G2_CPU1_G0_TX_DP<5>")
	)
	(segment
		(start 370.646198 -221.083124)
		(end 370.646198 -218.1225)
		(width 0.14224)
		(layer "In2.Cu")
		(net "GMI_CPU0_G2_CPU1_G0_TX_DP<5>")
	)
	(segment
		(start 370.807742 -225.366834)
		(end 370.777262 -225.349054)
		(width 0.1143)
		(layer "In2.Cu")
		(net "GMI_CPU0_G2_CPU1_G0_TX_DP<5>")
	)
	(segment
		(start 311.392316 -179.666138)
		(end 309.396638 -178.905408)
		(width 0.14224)
		(layer "In2.Cu")
		(net "GMI_CPU0_G2_CPU1_G0_TX_DP<5>")
	)
	(segment
		(start 100.687886 -226.34194)
		(end 100.719636 -226.360228)
		(width 0.1143)
		(layer "In2.Cu")
		(net "GMI_CPU0_G2_CPU1_G0_TX_DP<5>")
	)
	(segment
		(start 370.846858 -223.769682)
		(end 370.807742 -223.746822)
		(width 0.1143)
		(layer "In2.Cu")
		(net "GMI_CPU0_G2_CPU1_G0_TX_DP<5>")
	)
	(segment
		(start 108.027216 -205.6384)
		(end 99.890072 -213.775544)
		(width 0.14224)
		(layer "In2.Cu")
		(net "GMI_CPU0_G2_CPU1_G0_TX_DP<5>")
	)
	(segment
		(start 368.703098 -213.85022)
		(end 364.182152 -209.909156)
		(width 0.14224)
		(layer "In2.Cu")
		(net "GMI_CPU0_G2_CPU1_G0_TX_DP<5>")
	)
	(segment
		(start 370.777262 -226.359466)
		(end 370.807742 -226.341686)
		(width 0.1143)
		(layer "In2.Cu")
		(net "GMI_CPU0_G2_CPU1_G0_TX_DP<5>")
	)
	(segment
		(start 100.651564 -224.700846)
		(end 100.687886 -224.721928)
		(width 0.1143)
		(layer "In2.Cu")
		(net "GMI_CPU0_G2_CPU1_G0_TX_DP<5>")
	)
	(segment
		(start 100.17887 -222.26905)
		(end 100.2284 -222.298006)
		(width 0.1143)
		(layer "In2.Cu")
		(net "GMI_CPU0_G2_CPU1_G0_TX_DP<5>")
	)
	(segment
		(start 370.807742 -222.12681)
		(end 370.777262 -222.10903)
		(width 0.1143)
		(layer "In2.Cu")
		(net "GMI_CPU0_G2_CPU1_G0_TX_DP<5>")
	)
	(segment
		(start 100.719636 -223.728788)
		(end 100.687886 -223.747076)
		(width 0.1143)
		(layer "In2.Cu")
		(net "GMI_CPU0_G2_CPU1_G0_TX_DP<5>")
	)
	(segment
		(start 152.357836 -182.849012)
		(end 108.027216 -205.6384)
		(width 0.14224)
		(layer "In2.Cu")
		(net "GMI_CPU0_G2_CPU1_G0_TX_DP<5>")
	)
	(segment
		(start 100.798884 -226.66452)
		(end 100.500942 -226.66452)
		(width 0.1143)
		(layer "In2.Cu")
		(net "GMI_CPU0_G2_CPU1_G0_TX_DP<5>")
	)
	(segment
		(start 100.651564 -226.320858)
		(end 100.687886 -226.34194)
		(width 0.1143)
		(layer "In2.Cu")
		(net "GMI_CPU0_G2_CPU1_G0_TX_DP<5>")
	)
	(segment
		(start 370.777262 -224.739454)
		(end 370.807742 -224.721674)
		(width 0.1143)
		(layer "In2.Cu")
		(net "GMI_CPU0_G2_CPU1_G0_TX_DP<5>")
	)
	(segment
		(start 370.807742 -226.341686)
		(end 370.846858 -226.318826)
		(width 0.1143)
		(layer "In2.Cu")
		(net "GMI_CPU0_G2_CPU1_G0_TX_DP<5>")
	)
	(segment
		(start 162.238944 -178.75631)
		(end 152.357836 -182.849012)
		(width 0.14224)
		(layer "In2.Cu")
		(net "GMI_CPU0_G2_CPU1_G0_TX_DP<5>")
	)
	(segment
		(start 100.416106 -222.622872)
		(end 100.416106 -222.629984)
		(width 0.1143)
		(layer "In2.Cu")
		(net "GMI_CPU0_G2_CPU1_G0_TX_DP<5>")
	)
	(segment
		(start 100.687886 -225.367088)
		(end 100.651564 -225.38817)
		(width 0.1143)
		(layer "In2.Cu")
		(net "GMI_CPU0_G2_CPU1_G0_TX_DP<5>")
	)
	(segment
		(start 370.846858 -222.14967)
		(end 370.807742 -222.12681)
		(width 0.1143)
		(layer "In2.Cu")
		(net "GMI_CPU0_G2_CPU1_G0_TX_DP<5>")
	)
	(segment
		(start 100.687886 -223.747076)
		(end 100.651564 -223.768158)
		(width 0.1143)
		(layer "In2.Cu")
		(net "GMI_CPU0_G2_CPU1_G0_TX_DP<5>")
	)
	(segment
		(start 370.696998 -226.664266)
		(end 370.627148 -226.594416)
		(width 0.1143)
		(layer "In2.Cu")
		(net "GMI_CPU0_G2_CPU1_G0_TX_DP<5>")
	)
	(segment
		(start 100.719636 -225.3488)
		(end 100.687886 -225.367088)
		(width 0.1143)
		(layer "In2.Cu")
		(net "GMI_CPU0_G2_CPU1_G0_TX_DP<5>")
	)
	(arc
		(start 370.846858 -224.698814)
		(mid 371.090185 -224.234248)
		(end 370.846858 -223.769682)
		(width 0.1143)
		(layer "In2.Cu")
		(net "GMI_CPU0_G2_CPU1_G0_TX_DP<5>")
	)
	(arc
		(start 100.636324 -223.778826)
		(mid 100.411153 -224.234502)
		(end 100.636324 -224.690178)
		(width 0.1143)
		(layer "In2.Cu")
		(net "GMI_CPU0_G2_CPU1_G0_TX_DP<5>")
	)
	(arc
		(start 100.651564 -223.768158)
		(mid 100.6439 -223.773429)
		(end 100.636324 -223.778826)
		(width 0.1143)
		(layer "In2.Cu")
		(net "GMI_CPU0_G2_CPU1_G0_TX_DP<5>")
	)
	(arc
		(start 100.651564 -225.38817)
		(mid 100.643386 -225.393813)
		(end 100.635308 -225.3996)
		(width 0.1143)
		(layer "In2.Cu")
		(net "GMI_CPU0_G2_CPU1_G0_TX_DP<5>")
	)
	(arc
		(start 100.635308 -226.309428)
		(mid 100.643386 -226.315214)
		(end 100.651564 -226.320858)
		(width 0.1143)
		(layer "In2.Cu")
		(net "GMI_CPU0_G2_CPU1_G0_TX_DP<5>")
	)
	(arc
		(start 100.636324 -224.690178)
		(mid 100.6439 -224.695574)
		(end 100.651564 -224.700846)
		(width 0.1143)
		(layer "In2.Cu")
		(net "GMI_CPU0_G2_CPU1_G0_TX_DP<5>")
	)
	(arc
		(start 370.846858 -223.078802)
		(mid 371.090185 -222.614236)
		(end 370.846858 -222.14967)
		(width 0.1143)
		(layer "In2.Cu")
		(net "GMI_CPU0_G2_CPU1_G0_TX_DP<5>")
	)
	(arc
		(start 370.777262 -222.10903)
		(mid 370.661835 -221.975654)
		(end 370.62029 -221.80423)
		(width 0.1143)
		(layer "In2.Cu")
		(net "GMI_CPU0_G2_CPU1_G0_TX_DP<5>")
	)
	(arc
		(start 100.719636 -224.740216)
		(mid 100.875564 -225.044508)
		(end 100.719636 -225.3488)
		(width 0.1143)
		(layer "In2.Cu")
		(net "GMI_CPU0_G2_CPU1_G0_TX_DP<5>")
	)
	(arc
		(start 99.935538 -221.804484)
		(mid 100.000053 -222.066703)
		(end 100.17887 -222.26905)
		(width 0.1143)
		(layer "In2.Cu")
		(net "GMI_CPU0_G2_CPU1_G0_TX_DP<5>")
	)
	(arc
		(start 370.627148 -226.594416)
		(mid 370.679565 -226.462485)
		(end 370.777262 -226.359466)
		(width 0.1143)
		(layer "In2.Cu")
		(net "GMI_CPU0_G2_CPU1_G0_TX_DP<5>")
	)
	(arc
		(start 370.846858 -226.318826)
		(mid 371.090185 -225.85426)
		(end 370.846858 -225.389694)
		(width 0.1143)
		(layer "In2.Cu")
		(net "GMI_CPU0_G2_CPU1_G0_TX_DP<5>")
	)
	(arc
		(start 370.777262 -225.349054)
		(mid 370.620285 -225.044254)
		(end 370.777262 -224.739454)
		(width 0.1143)
		(layer "In2.Cu")
		(net "GMI_CPU0_G2_CPU1_G0_TX_DP<5>")
	)
	(arc
		(start 100.719636 -223.120204)
		(mid 100.875564 -223.424496)
		(end 100.719636 -223.728788)
		(width 0.1143)
		(layer "In2.Cu")
		(net "GMI_CPU0_G2_CPU1_G0_TX_DP<5>")
	)
	(arc
		(start 100.416106 -222.629984)
		(mid 100.488911 -222.902277)
		(end 100.687886 -223.101916)
		(width 0.1143)
		(layer "In2.Cu")
		(net "GMI_CPU0_G2_CPU1_G0_TX_DP<5>")
	)
	(arc
		(start 100.2284 -222.298006)
		(mid 100.365832 -222.435265)
		(end 100.416106 -222.622872)
		(width 0.1143)
		(layer "In2.Cu")
		(net "GMI_CPU0_G2_CPU1_G0_TX_DP<5>")
	)
	(arc
		(start 100.635308 -225.3996)
		(mid 100.412424 -225.854514)
		(end 100.635308 -226.309428)
		(width 0.1143)
		(layer "In2.Cu")
		(net "GMI_CPU0_G2_CPU1_G0_TX_DP<5>")
	)
	(arc
		(start 370.777262 -223.729042)
		(mid 370.620285 -223.424242)
		(end 370.777262 -223.119442)
		(width 0.1143)
		(layer "In2.Cu")
		(net "GMI_CPU0_G2_CPU1_G0_TX_DP<5>")
	)
	(arc
		(start 100.719636 -226.360228)
		(mid 100.816771 -226.463097)
		(end 100.868734 -226.59467)
		(width 0.1143)
		(layer "In2.Cu")
		(net "GMI_CPU0_G2_CPU1_G0_TX_DP<5>")
	)
	(segment
		(start 100.967794 -228.55047)
		(end 100.500942 -228.284532)
		(width 0.12954)
		(layer "F.Cu")
		(net "GMI_CPU0_G2_CPU1_G0_TX_DP<4>")
	)
	(segment
		(start 370.527834 -228.550216)
		(end 370.994686 -228.284278)
		(width 0.12954)
		(layer "F.Cu")
		(net "GMI_CPU0_G2_CPU1_G0_TX_DP<4>")
	)
	(segment
		(start 369.680236 -221.80423)
		(end 369.680236 -221.371668)
		(width 0.1143)
		(layer "In2.Cu")
		(net "GMI_CPU0_G2_CPU1_G0_TX_DP<4>")
	)
	(segment
		(start 165.182296 -178.947826)
		(end 162.35426 -179.740052)
		(width 0.14224)
		(layer "In2.Cu")
		(net "GMI_CPU0_G2_CPU1_G0_TX_DP<4>")
	)
	(segment
		(start 108.815886 -206.42707)
		(end 100.82911 -214.413846)
		(width 0.14224)
		(layer "In2.Cu")
		(net "GMI_CPU0_G2_CPU1_G0_TX_DP<4>")
	)
	(segment
		(start 370.696998 -228.284278)
		(end 370.614194 -228.201474)
		(width 0.1143)
		(layer "In2.Cu")
		(net "GMI_CPU0_G2_CPU1_G0_TX_DP<4>")
	)
	(segment
		(start 101.626924 -224.72142)
		(end 101.62794 -224.721928)
		(width 0.1143)
		(layer "In2.Cu")
		(net "GMI_CPU0_G2_CPU1_G0_TX_DP<4>")
	)
	(segment
		(start 369.836192 -223.11995)
		(end 369.867942 -223.101662)
		(width 0.1143)
		(layer "In2.Cu")
		(net "GMI_CPU0_G2_CPU1_G0_TX_DP<4>")
	)
	(segment
		(start 101.15804 -227.797106)
		(end 101.118924 -227.819966)
		(width 0.1143)
		(layer "In2.Cu")
		(net "GMI_CPU0_G2_CPU1_G0_TX_DP<4>")
	)
	(segment
		(start 370.334286 -227.795074)
		(end 370.333778 -227.79482)
		(width 0.1143)
		(layer "In2.Cu")
		(net "GMI_CPU0_G2_CPU1_G0_TX_DP<4>")
	)
	(segment
		(start 101.628702 -225.36658)
		(end 101.62794 -225.367088)
		(width 0.1143)
		(layer "In2.Cu")
		(net "GMI_CPU0_G2_CPU1_G0_TX_DP<4>")
	)
	(segment
		(start 101.625146 -224.720404)
		(end 101.626924 -224.72142)
		(width 0.1143)
		(layer "In2.Cu")
		(net "GMI_CPU0_G2_CPU1_G0_TX_DP<4>")
	)
	(segment
		(start 101.588824 -223.079056)
		(end 101.595682 -223.08312)
		(width 0.1143)
		(layer "In2.Cu")
		(net "GMI_CPU0_G2_CPU1_G0_TX_DP<4>")
	)
	(segment
		(start 101.629972 -225.365818)
		(end 101.628702 -225.36658)
		(width 0.1143)
		(layer "In2.Cu")
		(net "GMI_CPU0_G2_CPU1_G0_TX_DP<4>")
	)
	(segment
		(start 369.852194 -223.737424)
		(end 369.836192 -223.72828)
		(width 0.1143)
		(layer "In2.Cu")
		(net "GMI_CPU0_G2_CPU1_G0_TX_DP<4>")
	)
	(segment
		(start 101.634036 -223.105472)
		(end 101.636068 -223.106742)
		(width 0.1143)
		(layer "In2.Cu")
		(net "GMI_CPU0_G2_CPU1_G0_TX_DP<4>")
	)
	(segment
		(start 100.82911 -221.203012)
		(end 100.87483 -221.248732)
		(width 0.1143)
		(layer "In2.Cu")
		(net "GMI_CPU0_G2_CPU1_G0_TX_DP<4>")
	)
	(segment
		(start 369.880134 -226.994212)
		(end 369.836192 -226.968304)
		(width 0.1143)
		(layer "In2.Cu")
		(net "GMI_CPU0_G2_CPU1_G0_TX_DP<4>")
	)
	(segment
		(start 101.596444 -224.70364)
		(end 101.621082 -224.717864)
		(width 0.1143)
		(layer "In2.Cu")
		(net "GMI_CPU0_G2_CPU1_G0_TX_DP<4>")
	)
	(segment
		(start 369.868196 -223.747076)
		(end 369.852194 -223.737424)
		(width 0.1143)
		(layer "In2.Cu")
		(net "GMI_CPU0_G2_CPU1_G0_TX_DP<4>")
	)
	(segment
		(start 311.144666 -180.589174)
		(end 309.105808 -179.812442)
		(width 0.14224)
		(layer "In2.Cu")
		(net "GMI_CPU0_G2_CPU1_G0_TX_DP<4>")
	)
	(segment
		(start 101.638354 -224.728024)
		(end 101.65969 -224.740216)
		(width 0.1143)
		(layer "In2.Cu")
		(net "GMI_CPU0_G2_CPU1_G0_TX_DP<4>")
	)
	(segment
		(start 101.628702 -223.746568)
		(end 101.62794 -223.747076)
		(width 0.1143)
		(layer "In2.Cu")
		(net "GMI_CPU0_G2_CPU1_G0_TX_DP<4>")
	)
	(segment
		(start 370.994686 -228.284278)
		(end 370.696998 -228.284278)
		(width 0.1143)
		(layer "In2.Cu")
		(net "GMI_CPU0_G2_CPU1_G0_TX_DP<4>")
	)
	(segment
		(start 101.636068 -226.346766)
		(end 101.637084 -226.347274)
		(width 0.1143)
		(layer "In2.Cu")
		(net "GMI_CPU0_G2_CPU1_G0_TX_DP<4>")
	)
	(segment
		(start 101.628702 -224.722436)
		(end 101.631496 -224.72396)
		(width 0.1143)
		(layer "In2.Cu")
		(net "GMI_CPU0_G2_CPU1_G0_TX_DP<4>")
	)
	(segment
		(start 101.62794 -224.721928)
		(end 101.628702 -224.722436)
		(width 0.1143)
		(layer "In2.Cu")
		(net "GMI_CPU0_G2_CPU1_G0_TX_DP<4>")
	)
	(segment
		(start 101.621082 -224.717864)
		(end 101.622606 -224.71888)
		(width 0.1143)
		(layer "In2.Cu")
		(net "GMI_CPU0_G2_CPU1_G0_TX_DP<4>")
	)
	(segment
		(start 100.87483 -221.83217)
		(end 100.876608 -221.833948)
		(width 0.1143)
		(layer "In2.Cu")
		(net "GMI_CPU0_G2_CPU1_G0_TX_DP<4>")
	)
	(segment
		(start 101.622606 -223.098868)
		(end 101.623622 -223.099376)
		(width 0.1143)
		(layer "In2.Cu")
		(net "GMI_CPU0_G2_CPU1_G0_TX_DP<4>")
	)
	(segment
		(start 101.625146 -226.340416)
		(end 101.626924 -226.341432)
		(width 0.1143)
		(layer "In2.Cu")
		(net "GMI_CPU0_G2_CPU1_G0_TX_DP<4>")
	)
	(segment
		(start 369.867942 -226.341686)
		(end 369.904264 -226.320604)
		(width 0.1143)
		(layer "In2.Cu")
		(net "GMI_CPU0_G2_CPU1_G0_TX_DP<4>")
	)
	(segment
		(start 370.338858 -227.79736)
		(end 370.337842 -227.796852)
		(width 0.1143)
		(layer "In2.Cu")
		(net "GMI_CPU0_G2_CPU1_G0_TX_DP<4>")
	)
	(segment
		(start 100.87483 -221.248732)
		(end 100.87483 -221.83217)
		(width 0.1143)
		(layer "In2.Cu")
		(net "GMI_CPU0_G2_CPU1_G0_TX_DP<4>")
	)
	(segment
		(start 369.867942 -223.101662)
		(end 369.904264 -223.08058)
		(width 0.1143)
		(layer "In2.Cu")
		(net "GMI_CPU0_G2_CPU1_G0_TX_DP<4>")
	)
	(segment
		(start 370.376958 -227.819712)
		(end 370.3701 -227.815648)
		(width 0.1143)
		(layer "In2.Cu")
		(net "GMI_CPU0_G2_CPU1_G0_TX_DP<4>")
	)
	(segment
		(start 369.680236 -221.371668)
		(end 369.655598 -221.34703)
		(width 0.1143)
		(layer "In2.Cu")
		(net "GMI_CPU0_G2_CPU1_G0_TX_DP<4>")
	)
	(segment
		(start 101.6254 -223.7486)
		(end 101.620828 -223.75114)
		(width 0.1143)
		(layer "In2.Cu")
		(net "GMI_CPU0_G2_CPU1_G0_TX_DP<4>")
	)
	(segment
		(start 370.33708 -227.796344)
		(end 370.334286 -227.795074)
		(width 0.1143)
		(layer "In2.Cu")
		(net "GMI_CPU0_G2_CPU1_G0_TX_DP<4>")
	)
	(segment
		(start 101.588824 -226.31908)
		(end 101.595682 -226.323144)
		(width 0.1143)
		(layer "In2.Cu")
		(net "GMI_CPU0_G2_CPU1_G0_TX_DP<4>")
	)
	(segment
		(start 101.632258 -223.104456)
		(end 101.633274 -223.104964)
		(width 0.1143)
		(layer "In2.Cu")
		(net "GMI_CPU0_G2_CPU1_G0_TX_DP<4>")
	)
	(segment
		(start 369.934744 -223.789494)
		(end 369.907058 -223.769428)
		(width 0.1143)
		(layer "In2.Cu")
		(net "GMI_CPU0_G2_CPU1_G0_TX_DP<4>")
	)
	(segment
		(start 101.18852 -227.779326)
		(end 101.15804 -227.797106)
		(width 0.1143)
		(layer "In2.Cu")
		(net "GMI_CPU0_G2_CPU1_G0_TX_DP<4>")
	)
	(segment
		(start 370.337842 -227.796852)
		(end 370.33708 -227.796344)
		(width 0.1143)
		(layer "In2.Cu")
		(net "GMI_CPU0_G2_CPU1_G0_TX_DP<4>")
	)
	(segment
		(start 101.626924 -225.367596)
		(end 101.588824 -225.389948)
		(width 0.1143)
		(layer "In2.Cu")
		(net "GMI_CPU0_G2_CPU1_G0_TX_DP<4>")
	)
	(segment
		(start 369.907058 -223.769428)
		(end 369.868196 -223.747076)
		(width 0.1143)
		(layer "In2.Cu")
		(net "GMI_CPU0_G2_CPU1_G0_TX_DP<4>")
	)
	(segment
		(start 101.622606 -224.71888)
		(end 101.623622 -224.719388)
		(width 0.1143)
		(layer "In2.Cu")
		(net "GMI_CPU0_G2_CPU1_G0_TX_DP<4>")
	)
	(segment
		(start 101.631496 -224.72396)
		(end 101.632258 -224.724468)
		(width 0.1143)
		(layer "In2.Cu")
		(net "GMI_CPU0_G2_CPU1_G0_TX_DP<4>")
	)
	(segment
		(start 101.636068 -223.106742)
		(end 101.637084 -223.10725)
		(width 0.1143)
		(layer "In2.Cu")
		(net "GMI_CPU0_G2_CPU1_G0_TX_DP<4>")
	)
	(segment
		(start 101.621082 -226.337876)
		(end 101.622606 -226.338892)
		(width 0.1143)
		(layer "In2.Cu")
		(net "GMI_CPU0_G2_CPU1_G0_TX_DP<4>")
	)
	(segment
		(start 101.63429 -223.74352)
		(end 101.632258 -223.744536)
		(width 0.1143)
		(layer "In2.Cu")
		(net "GMI_CPU0_G2_CPU1_G0_TX_DP<4>")
	)
	(segment
		(start 369.655598 -221.128844)
		(end 369.701318 -221.083124)
		(width 0.1143)
		(layer "In2.Cu")
		(net "GMI_CPU0_G2_CPU1_G0_TX_DP<4>")
	)
	(segment
		(start 369.904264 -225.387916)
		(end 369.867942 -225.366834)
		(width 0.1143)
		(layer "In2.Cu")
		(net "GMI_CPU0_G2_CPU1_G0_TX_DP<4>")
	)
	(segment
		(start 100.881688 -228.201728)
		(end 100.798884 -228.284532)
		(width 0.1143)
		(layer "In2.Cu")
		(net "GMI_CPU0_G2_CPU1_G0_TX_DP<4>")
	)
	(segment
		(start 101.638354 -226.348036)
		(end 101.65969 -226.360228)
		(width 0.1143)
		(layer "In2.Cu")
		(net "GMI_CPU0_G2_CPU1_G0_TX_DP<4>")
	)
	(segment
		(start 235.32465 -176.543208)
		(end 165.182296 -178.947826)
		(width 0.14224)
		(layer "In2.Cu")
		(net "GMI_CPU0_G2_CPU1_G0_TX_DP<4>")
	)
	(segment
		(start 369.701318 -218.37904)
		(end 367.9063 -214.432642)
		(width 0.14224)
		(layer "In2.Cu")
		(net "GMI_CPU0_G2_CPU1_G0_TX_DP<4>")
	)
	(segment
		(start 100.798884 -228.284532)
		(end 100.500942 -228.284532)
		(width 0.1143)
		(layer "In2.Cu")
		(net "GMI_CPU0_G2_CPU1_G0_TX_DP<4>")
	)
	(segment
		(start 101.62794 -223.101916)
		(end 101.628702 -223.102424)
		(width 0.1143)
		(layer "In2.Cu")
		(net "GMI_CPU0_G2_CPU1_G0_TX_DP<4>")
	)
	(segment
		(start 101.626924 -226.987608)
		(end 101.588824 -227.00996)
		(width 0.1143)
		(layer "In2.Cu")
		(net "GMI_CPU0_G2_CPU1_G0_TX_DP<4>")
	)
	(segment
		(start 369.907058 -224.699068)
		(end 369.934744 -224.679002)
		(width 0.1143)
		(layer "In2.Cu")
		(net "GMI_CPU0_G2_CPU1_G0_TX_DP<4>")
	)
	(segment
		(start 100.82911 -221.174564)
		(end 100.82911 -221.203012)
		(width 0.1143)
		(layer "In2.Cu")
		(net "GMI_CPU0_G2_CPU1_G0_TX_DP<4>")
	)
	(segment
		(start 369.836192 -226.359974)
		(end 369.867942 -226.341686)
		(width 0.1143)
		(layer "In2.Cu")
		(net "GMI_CPU0_G2_CPU1_G0_TX_DP<4>")
	)
	(segment
		(start 369.867942 -222.12681)
		(end 369.836192 -222.108522)
		(width 0.1143)
		(layer "In2.Cu")
		(net "GMI_CPU0_G2_CPU1_G0_TX_DP<4>")
	)
	(segment
		(start 101.634036 -226.345496)
		(end 101.636068 -226.346766)
		(width 0.1143)
		(layer "In2.Cu")
		(net "GMI_CPU0_G2_CPU1_G0_TX_DP<4>")
	)
	(segment
		(start 101.632258 -223.744536)
		(end 101.631496 -223.745044)
		(width 0.1143)
		(layer "In2.Cu")
		(net "GMI_CPU0_G2_CPU1_G0_TX_DP<4>")
	)
	(segment
		(start 369.867942 -225.366834)
		(end 369.836192 -225.348546)
		(width 0.1143)
		(layer "In2.Cu")
		(net "GMI_CPU0_G2_CPU1_G0_TX_DP<4>")
	)
	(segment
		(start 101.622606 -226.338892)
		(end 101.623622 -226.3394)
		(width 0.1143)
		(layer "In2.Cu")
		(net "GMI_CPU0_G2_CPU1_G0_TX_DP<4>")
	)
	(segment
		(start 370.369338 -227.81514)
		(end 370.338858 -227.79736)
		(width 0.1143)
		(layer "In2.Cu")
		(net "GMI_CPU0_G2_CPU1_G0_TX_DP<4>")
	)
	(segment
		(start 101.596444 -223.083628)
		(end 101.621082 -223.097852)
		(width 0.1143)
		(layer "In2.Cu")
		(net "GMI_CPU0_G2_CPU1_G0_TX_DP<4>")
	)
	(segment
		(start 101.629972 -226.98583)
		(end 101.628702 -226.986592)
		(width 0.1143)
		(layer "In2.Cu")
		(net "GMI_CPU0_G2_CPU1_G0_TX_DP<4>")
	)
	(segment
		(start 101.62794 -226.34194)
		(end 101.628702 -226.342448)
		(width 0.1143)
		(layer "In2.Cu")
		(net "GMI_CPU0_G2_CPU1_G0_TX_DP<4>")
	)
	(segment
		(start 101.637084 -226.347274)
		(end 101.638354 -226.348036)
		(width 0.1143)
		(layer "In2.Cu")
		(net "GMI_CPU0_G2_CPU1_G0_TX_DP<4>")
	)
	(segment
		(start 101.636068 -224.726754)
		(end 101.637084 -224.727262)
		(width 0.1143)
		(layer "In2.Cu")
		(net "GMI_CPU0_G2_CPU1_G0_TX_DP<4>")
	)
	(segment
		(start 369.701318 -221.083124)
		(end 369.701318 -218.37904)
		(width 0.14224)
		(layer "In2.Cu")
		(net "GMI_CPU0_G2_CPU1_G0_TX_DP<4>")
	)
	(segment
		(start 369.836192 -224.739962)
		(end 369.907058 -224.699068)
		(width 0.1143)
		(layer "In2.Cu")
		(net "GMI_CPU0_G2_CPU1_G0_TX_DP<4>")
	)
	(segment
		(start 101.626924 -223.101408)
		(end 101.62794 -223.101916)
		(width 0.1143)
		(layer "In2.Cu")
		(net "GMI_CPU0_G2_CPU1_G0_TX_DP<4>")
	)
	(segment
		(start 101.633274 -226.344988)
		(end 101.634036 -226.345496)
		(width 0.1143)
		(layer "In2.Cu")
		(net "GMI_CPU0_G2_CPU1_G0_TX_DP<4>")
	)
	(segment
		(start 101.62794 -226.9871)
		(end 101.626924 -226.987608)
		(width 0.1143)
		(layer "In2.Cu")
		(net "GMI_CPU0_G2_CPU1_G0_TX_DP<4>")
	)
	(segment
		(start 101.626924 -226.341432)
		(end 101.62794 -226.34194)
		(width 0.1143)
		(layer "In2.Cu")
		(net "GMI_CPU0_G2_CPU1_G0_TX_DP<4>")
	)
	(segment
		(start 101.620828 -223.75114)
		(end 101.588824 -223.769936)
		(width 0.1143)
		(layer "In2.Cu")
		(net "GMI_CPU0_G2_CPU1_G0_TX_DP<4>")
	)
	(segment
		(start 367.9063 -214.432642)
		(end 363.48924 -210.581494)
		(width 0.14224)
		(layer "In2.Cu")
		(net "GMI_CPU0_G2_CPU1_G0_TX_DP<4>")
	)
	(segment
		(start 101.632258 -224.724468)
		(end 101.633274 -224.724976)
		(width 0.1143)
		(layer "In2.Cu")
		(net "GMI_CPU0_G2_CPU1_G0_TX_DP<4>")
	)
	(segment
		(start 101.62794 -225.367088)
		(end 101.626924 -225.367596)
		(width 0.1143)
		(layer "In2.Cu")
		(net "GMI_CPU0_G2_CPU1_G0_TX_DP<4>")
	)
	(segment
		(start 101.631496 -223.745044)
		(end 101.628702 -223.746568)
		(width 0.1143)
		(layer "In2.Cu")
		(net "GMI_CPU0_G2_CPU1_G0_TX_DP<4>")
	)
	(segment
		(start 101.62794 -223.747076)
		(end 101.626924 -223.747584)
		(width 0.1143)
		(layer "In2.Cu")
		(net "GMI_CPU0_G2_CPU1_G0_TX_DP<4>")
	)
	(segment
		(start 101.595682 -224.703132)
		(end 101.596444 -224.70364)
		(width 0.1143)
		(layer "In2.Cu")
		(net "GMI_CPU0_G2_CPU1_G0_TX_DP<4>")
	)
	(segment
		(start 101.633274 -223.104964)
		(end 101.634036 -223.105472)
		(width 0.1143)
		(layer "In2.Cu")
		(net "GMI_CPU0_G2_CPU1_G0_TX_DP<4>")
	)
	(segment
		(start 101.637084 -224.727262)
		(end 101.638354 -224.728024)
		(width 0.1143)
		(layer "In2.Cu")
		(net "GMI_CPU0_G2_CPU1_G0_TX_DP<4>")
	)
	(segment
		(start 152.759918 -183.713374)
		(end 108.815886 -206.42707)
		(width 0.14224)
		(layer "In2.Cu")
		(net "GMI_CPU0_G2_CPU1_G0_TX_DP<4>")
	)
	(segment
		(start 100.82911 -214.413846)
		(end 100.82911 -221.174564)
		(width 0.14224)
		(layer "In2.Cu")
		(net "GMI_CPU0_G2_CPU1_G0_TX_DP<4>")
	)
	(segment
		(start 101.65969 -225.3488)
		(end 101.629972 -225.365818)
		(width 0.1143)
		(layer "In2.Cu")
		(net "GMI_CPU0_G2_CPU1_G0_TX_DP<4>")
	)
	(segment
		(start 309.105808 -179.812442)
		(end 305.6382 -178.91252)
		(width 0.14224)
		(layer "In2.Cu")
		(net "GMI_CPU0_G2_CPU1_G0_TX_DP<4>")
	)
	(segment
		(start 370.162836 -227.49637)
		(end 370.162836 -227.483924)
		(width 0.1143)
		(layer "In2.Cu")
		(net "GMI_CPU0_G2_CPU1_G0_TX_DP<4>")
	)
	(segment
		(start 101.623622 -226.3394)
		(end 101.625146 -226.340416)
		(width 0.1143)
		(layer "In2.Cu")
		(net "GMI_CPU0_G2_CPU1_G0_TX_DP<4>")
	)
	(segment
		(start 305.6382 -178.91252)
		(end 235.32465 -176.543208)
		(width 0.14224)
		(layer "In2.Cu")
		(net "GMI_CPU0_G2_CPU1_G0_TX_DP<4>")
	)
	(segment
		(start 101.621082 -223.097852)
		(end 101.622606 -223.098868)
		(width 0.1143)
		(layer "In2.Cu")
		(net "GMI_CPU0_G2_CPU1_G0_TX_DP<4>")
	)
	(segment
		(start 101.634036 -224.725484)
		(end 101.636068 -224.726754)
		(width 0.1143)
		(layer "In2.Cu")
		(net "GMI_CPU0_G2_CPU1_G0_TX_DP<4>")
	)
	(segment
		(start 363.48924 -210.581494)
		(end 357.466646 -206.499714)
		(width 0.14224)
		(layer "In2.Cu")
		(net "GMI_CPU0_G2_CPU1_G0_TX_DP<4>")
	)
	(segment
		(start 162.35426 -179.740052)
		(end 152.759918 -183.713374)
		(width 0.14224)
		(layer "In2.Cu")
		(net "GMI_CPU0_G2_CPU1_G0_TX_DP<4>")
	)
	(segment
		(start 101.632258 -226.34448)
		(end 101.633274 -226.344988)
		(width 0.1143)
		(layer "In2.Cu")
		(net "GMI_CPU0_G2_CPU1_G0_TX_DP<4>")
	)
	(segment
		(start 101.623622 -224.719388)
		(end 101.625146 -224.720404)
		(width 0.1143)
		(layer "In2.Cu")
		(net "GMI_CPU0_G2_CPU1_G0_TX_DP<4>")
	)
	(segment
		(start 369.655598 -221.34703)
		(end 369.655598 -221.128844)
		(width 0.1143)
		(layer "In2.Cu")
		(net "GMI_CPU0_G2_CPU1_G0_TX_DP<4>")
	)
	(segment
		(start 101.120448 -222.270066)
		(end 101.15804 -222.29191)
		(width 0.1143)
		(layer "In2.Cu")
		(net "GMI_CPU0_G2_CPU1_G0_TX_DP<4>")
	)
	(segment
		(start 369.904264 -222.147892)
		(end 369.867942 -222.12681)
		(width 0.1143)
		(layer "In2.Cu")
		(net "GMI_CPU0_G2_CPU1_G0_TX_DP<4>")
	)
	(segment
		(start 101.15804 -222.29191)
		(end 101.18852 -222.30969)
		(width 0.1143)
		(layer "In2.Cu")
		(net "GMI_CPU0_G2_CPU1_G0_TX_DP<4>")
	)
	(segment
		(start 101.638354 -223.108012)
		(end 101.65969 -223.120204)
		(width 0.1143)
		(layer "In2.Cu")
		(net "GMI_CPU0_G2_CPU1_G0_TX_DP<4>")
	)
	(segment
		(start 369.836192 -223.72828)
		(end 369.836192 -223.728534)
		(width 0.1143)
		(layer "In2.Cu")
		(net "GMI_CPU0_G2_CPU1_G0_TX_DP<4>")
	)
	(segment
		(start 101.628702 -226.986592)
		(end 101.62794 -226.9871)
		(width 0.1143)
		(layer "In2.Cu")
		(net "GMI_CPU0_G2_CPU1_G0_TX_DP<4>")
	)
	(segment
		(start 101.633274 -224.724976)
		(end 101.634036 -224.725484)
		(width 0.1143)
		(layer "In2.Cu")
		(net "GMI_CPU0_G2_CPU1_G0_TX_DP<4>")
	)
	(segment
		(start 325.10984 -187.326778)
		(end 311.144666 -180.589174)
		(width 0.14224)
		(layer "In2.Cu")
		(net "GMI_CPU0_G2_CPU1_G0_TX_DP<4>")
	)
	(segment
		(start 101.625146 -223.100392)
		(end 101.626924 -223.101408)
		(width 0.1143)
		(layer "In2.Cu")
		(net "GMI_CPU0_G2_CPU1_G0_TX_DP<4>")
	)
	(segment
		(start 101.588824 -224.699068)
		(end 101.595682 -224.703132)
		(width 0.1143)
		(layer "In2.Cu")
		(net "GMI_CPU0_G2_CPU1_G0_TX_DP<4>")
	)
	(segment
		(start 101.631496 -226.343972)
		(end 101.632258 -226.34448)
		(width 0.1143)
		(layer "In2.Cu")
		(net "GMI_CPU0_G2_CPU1_G0_TX_DP<4>")
	)
	(segment
		(start 101.65969 -226.968812)
		(end 101.629972 -226.98583)
		(width 0.1143)
		(layer "In2.Cu")
		(net "GMI_CPU0_G2_CPU1_G0_TX_DP<4>")
	)
	(segment
		(start 101.596444 -226.323652)
		(end 101.621082 -226.337876)
		(width 0.1143)
		(layer "In2.Cu")
		(net "GMI_CPU0_G2_CPU1_G0_TX_DP<4>")
	)
	(segment
		(start 101.628702 -226.342448)
		(end 101.631496 -226.343972)
		(width 0.1143)
		(layer "In2.Cu")
		(net "GMI_CPU0_G2_CPU1_G0_TX_DP<4>")
	)
	(segment
		(start 101.65969 -223.728788)
		(end 101.63429 -223.74352)
		(width 0.1143)
		(layer "In2.Cu")
		(net "GMI_CPU0_G2_CPU1_G0_TX_DP<4>")
	)
	(segment
		(start 101.628702 -223.102424)
		(end 101.631496 -223.103948)
		(width 0.1143)
		(layer "In2.Cu")
		(net "GMI_CPU0_G2_CPU1_G0_TX_DP<4>")
	)
	(segment
		(start 101.631496 -223.103948)
		(end 101.632258 -223.104456)
		(width 0.1143)
		(layer "In2.Cu")
		(net "GMI_CPU0_G2_CPU1_G0_TX_DP<4>")
	)
	(segment
		(start 101.637084 -223.10725)
		(end 101.638354 -223.108012)
		(width 0.1143)
		(layer "In2.Cu")
		(net "GMI_CPU0_G2_CPU1_G0_TX_DP<4>")
	)
	(segment
		(start 101.623622 -223.099376)
		(end 101.625146 -223.100392)
		(width 0.1143)
		(layer "In2.Cu")
		(net "GMI_CPU0_G2_CPU1_G0_TX_DP<4>")
	)
	(segment
		(start 101.626924 -223.747584)
		(end 101.6254 -223.7486)
		(width 0.1143)
		(layer "In2.Cu")
		(net "GMI_CPU0_G2_CPU1_G0_TX_DP<4>")
	)
	(segment
		(start 370.3701 -227.815648)
		(end 370.369338 -227.81514)
		(width 0.1143)
		(layer "In2.Cu")
		(net "GMI_CPU0_G2_CPU1_G0_TX_DP<4>")
	)
	(segment
		(start 357.466646 -206.499714)
		(end 325.10984 -187.326778)
		(width 0.14224)
		(layer "In2.Cu")
		(net "GMI_CPU0_G2_CPU1_G0_TX_DP<4>")
	)
	(segment
		(start 101.595682 -226.323144)
		(end 101.596444 -226.323652)
		(width 0.1143)
		(layer "In2.Cu")
		(net "GMI_CPU0_G2_CPU1_G0_TX_DP<4>")
	)
	(segment
		(start 101.595682 -223.08312)
		(end 101.596444 -223.083628)
		(width 0.1143)
		(layer "In2.Cu")
		(net "GMI_CPU0_G2_CPU1_G0_TX_DP<4>")
	)
	(arc
		(start 369.836192 -225.348546)
		(mid 369.680264 -225.044254)
		(end 369.836192 -224.739962)
		(width 0.1143)
		(layer "In2.Cu")
		(net "GMI_CPU0_G2_CPU1_G0_TX_DP<4>")
	)
	(arc
		(start 369.904264 -223.08058)
		(mid 369.911413 -223.07568)
		(end 369.918488 -223.070674)
		(width 0.1143)
		(layer "In2.Cu")
		(net "GMI_CPU0_G2_CPU1_G0_TX_DP<4>")
	)
	(arc
		(start 369.836192 -223.728534)
		(mid 369.680264 -223.424242)
		(end 369.836192 -223.11995)
		(width 0.1143)
		(layer "In2.Cu")
		(net "GMI_CPU0_G2_CPU1_G0_TX_DP<4>")
	)
	(arc
		(start 101.65969 -224.740216)
		(mid 101.815618 -225.044508)
		(end 101.65969 -225.3488)
		(width 0.1143)
		(layer "In2.Cu")
		(net "GMI_CPU0_G2_CPU1_G0_TX_DP<4>")
	)
	(arc
		(start 369.836192 -226.968304)
		(mid 369.754211 -226.887654)
		(end 369.700556 -226.785932)
		(width 0.1143)
		(layer "In2.Cu")
		(net "GMI_CPU0_G2_CPU1_G0_TX_DP<4>")
	)
	(arc
		(start 369.904264 -226.320604)
		(mid 369.911413 -226.315704)
		(end 369.918488 -226.310698)
		(width 0.1143)
		(layer "In2.Cu")
		(net "GMI_CPU0_G2_CPU1_G0_TX_DP<4>")
	)
	(arc
		(start 100.885498 -228.178868)
		(mid 100.883475 -228.190278)
		(end 100.881688 -228.201728)
		(width 0.1143)
		(layer "In2.Cu")
		(net "GMI_CPU0_G2_CPU1_G0_TX_DP<4>")
	)
	(arc
		(start 369.918488 -226.310698)
		(mid 370.145871 -225.85426)
		(end 369.918488 -225.397822)
		(width 0.1143)
		(layer "In2.Cu")
		(net "GMI_CPU0_G2_CPU1_G0_TX_DP<4>")
	)
	(arc
		(start 369.918488 -225.397822)
		(mid 369.911414 -225.392815)
		(end 369.904264 -225.387916)
		(width 0.1143)
		(layer "In2.Cu")
		(net "GMI_CPU0_G2_CPU1_G0_TX_DP<4>")
	)
	(arc
		(start 101.65969 -226.360228)
		(mid 101.815618 -226.66452)
		(end 101.65969 -226.968812)
		(width 0.1143)
		(layer "In2.Cu")
		(net "GMI_CPU0_G2_CPU1_G0_TX_DP<4>")
	)
	(arc
		(start 101.588824 -223.769936)
		(mid 101.345497 -224.234502)
		(end 101.588824 -224.699068)
		(width 0.1143)
		(layer "In2.Cu")
		(net "GMI_CPU0_G2_CPU1_G0_TX_DP<4>")
	)
	(arc
		(start 370.614194 -228.201474)
		(mid 370.535115 -227.986029)
		(end 370.376958 -227.819712)
		(width 0.1143)
		(layer "In2.Cu")
		(net "GMI_CPU0_G2_CPU1_G0_TX_DP<4>")
	)
	(arc
		(start 101.588824 -225.389948)
		(mid 101.345497 -225.854514)
		(end 101.588824 -226.31908)
		(width 0.1143)
		(layer "In2.Cu")
		(net "GMI_CPU0_G2_CPU1_G0_TX_DP<4>")
	)
	(arc
		(start 100.876608 -221.833948)
		(mid 100.947736 -222.080406)
		(end 101.120448 -222.270066)
		(width 0.1143)
		(layer "In2.Cu")
		(net "GMI_CPU0_G2_CPU1_G0_TX_DP<4>")
	)
	(arc
		(start 101.65969 -223.120204)
		(mid 101.815618 -223.424496)
		(end 101.65969 -223.728788)
		(width 0.1143)
		(layer "In2.Cu")
		(net "GMI_CPU0_G2_CPU1_G0_TX_DP<4>")
	)
	(arc
		(start 101.18852 -222.30969)
		(mid 101.303947 -222.443066)
		(end 101.345492 -222.61449)
		(width 0.1143)
		(layer "In2.Cu")
		(net "GMI_CPU0_G2_CPU1_G0_TX_DP<4>")
	)
	(arc
		(start 101.588824 -227.00996)
		(mid 101.410011 -227.21231)
		(end 101.345492 -227.474526)
		(width 0.1143)
		(layer "In2.Cu")
		(net "GMI_CPU0_G2_CPU1_G0_TX_DP<4>")
	)
	(arc
		(start 369.918488 -223.070674)
		(mid 370.145871 -222.614236)
		(end 369.918488 -222.157798)
		(width 0.1143)
		(layer "In2.Cu")
		(net "GMI_CPU0_G2_CPU1_G0_TX_DP<4>")
	)
	(arc
		(start 370.162836 -227.483924)
		(mid 370.087079 -227.201209)
		(end 369.880134 -226.994212)
		(width 0.1143)
		(layer "In2.Cu")
		(net "GMI_CPU0_G2_CPU1_G0_TX_DP<4>")
	)
	(arc
		(start 370.333778 -227.79482)
		(mid 370.208578 -227.668346)
		(end 370.162836 -227.49637)
		(width 0.1143)
		(layer "In2.Cu")
		(net "GMI_CPU0_G2_CPU1_G0_TX_DP<4>")
	)
	(arc
		(start 369.700556 -226.785932)
		(mid 369.697935 -226.550523)
		(end 369.836192 -226.359974)
		(width 0.1143)
		(layer "In2.Cu")
		(net "GMI_CPU0_G2_CPU1_G0_TX_DP<4>")
	)
	(arc
		(start 101.345492 -222.61449)
		(mid 101.410007 -222.876709)
		(end 101.588824 -223.079056)
		(width 0.1143)
		(layer "In2.Cu")
		(net "GMI_CPU0_G2_CPU1_G0_TX_DP<4>")
	)
	(arc
		(start 369.836192 -222.108522)
		(mid 369.721516 -221.975188)
		(end 369.680236 -221.80423)
		(width 0.1143)
		(layer "In2.Cu")
		(net "GMI_CPU0_G2_CPU1_G0_TX_DP<4>")
	)
	(arc
		(start 369.918488 -222.157798)
		(mid 369.911414 -222.152791)
		(end 369.904264 -222.147892)
		(width 0.1143)
		(layer "In2.Cu")
		(net "GMI_CPU0_G2_CPU1_G0_TX_DP<4>")
	)
	(arc
		(start 101.118924 -227.819966)
		(mid 100.966937 -227.976474)
		(end 100.885498 -228.178868)
		(width 0.1143)
		(layer "In2.Cu")
		(net "GMI_CPU0_G2_CPU1_G0_TX_DP<4>")
	)
	(arc
		(start 369.934744 -224.679002)
		(mid 370.162744 -224.234248)
		(end 369.934744 -223.789494)
		(width 0.1143)
		(layer "In2.Cu")
		(net "GMI_CPU0_G2_CPU1_G0_TX_DP<4>")
	)
	(arc
		(start 101.345492 -227.474526)
		(mid 101.303943 -227.645948)
		(end 101.18852 -227.779326)
		(width 0.1143)
		(layer "In2.Cu")
		(net "GMI_CPU0_G2_CPU1_G0_TX_DP<4>")
	)
	(segment
		(start 373.347996 -230.169974)
		(end 373.814848 -229.904036)
		(width 0.12954)
		(layer "F.Cu")
		(net "GMI_CPU0_G2_CPU1_G0_TX_DP<3>")
	)
	(segment
		(start 98.147886 -230.170228)
		(end 97.681034 -229.90429)
		(width 0.12954)
		(layer "F.Cu")
		(net "GMI_CPU0_G2_CPU1_G0_TX_DP<3>")
	)
	(segment
		(start 99.779836 -223.728788)
		(end 99.799648 -223.714564)
		(width 0.1143)
		(layer "In2.Cu")
		(net "GMI_CPU0_G2_CPU1_G0_TX_DP<3>")
	)
	(segment
		(start 99.748086 -225.367088)
		(end 99.748848 -225.36658)
		(width 0.1143)
		(layer "In2.Cu")
		(net "GMI_CPU0_G2_CPU1_G0_TX_DP<3>")
	)
	(segment
		(start 371.605556 -221.17431)
		(end 371.605556 -221.202758)
		(width 0.1143)
		(layer "In2.Cu")
		(net "GMI_CPU0_G2_CPU1_G0_TX_DP<3>")
	)
	(segment
		(start 98.811588 -228.60508)
		(end 98.81235 -228.604572)
		(width 0.1143)
		(layer "In2.Cu")
		(net "GMI_CPU0_G2_CPU1_G0_TX_DP<3>")
	)
	(segment
		(start 99.799648 -224.75444)
		(end 99.779836 -224.740216)
		(width 0.1143)
		(layer "In2.Cu")
		(net "GMI_CPU0_G2_CPU1_G0_TX_DP<3>")
	)
	(segment
		(start 107.248198 -204.859382)
		(end 152.144476 -181.890924)
		(width 0.14224)
		(layer "In2.Cu")
		(net "GMI_CPU0_G2_CPU1_G0_TX_DP<3>")
	)
	(segment
		(start 371.775228 -227.002594)
		(end 371.77853 -227.004626)
		(width 0.1143)
		(layer "In2.Cu")
		(net "GMI_CPU0_G2_CPU1_G0_TX_DP<3>")
	)
	(segment
		(start 371.747034 -223.746314)
		(end 371.747796 -223.746822)
		(width 0.1143)
		(layer "In2.Cu")
		(net "GMI_CPU0_G2_CPU1_G0_TX_DP<3>")
	)
	(segment
		(start 371.748812 -224.721166)
		(end 371.747796 -224.721674)
		(width 0.1143)
		(layer "In2.Cu")
		(net "GMI_CPU0_G2_CPU1_G0_TX_DP<3>")
	)
	(segment
		(start 371.747034 -225.366326)
		(end 371.747796 -225.366834)
		(width 0.1143)
		(layer "In2.Cu")
		(net "GMI_CPU0_G2_CPU1_G0_TX_DP<3>")
	)
	(segment
		(start 371.739922 -222.122238)
		(end 371.741192 -222.123)
		(width 0.1143)
		(layer "In2.Cu")
		(net "GMI_CPU0_G2_CPU1_G0_TX_DP<3>")
	)
	(segment
		(start 311.264554 -178.555396)
		(end 326.30999 -185.802016)
		(width 0.14224)
		(layer "In2.Cu")
		(net "GMI_CPU0_G2_CPU1_G0_TX_DP<3>")
	)
	(segment
		(start 152.144476 -181.890924)
		(end 161.296604 -178.030378)
		(width 0.14224)
		(layer "In2.Cu")
		(net "GMI_CPU0_G2_CPU1_G0_TX_DP<3>")
	)
	(segment
		(start 371.747796 -223.746822)
		(end 371.779292 -223.76511)
		(width 0.1143)
		(layer "In2.Cu")
		(net "GMI_CPU0_G2_CPU1_G0_TX_DP<3>")
	)
	(segment
		(start 371.747034 -223.10217)
		(end 371.716046 -223.11995)
		(width 0.1143)
		(layer "In2.Cu")
		(net "GMI_CPU0_G2_CPU1_G0_TX_DP<3>")
	)
	(segment
		(start 371.748812 -222.127318)
		(end 371.786912 -222.14967)
		(width 0.1143)
		(layer "In2.Cu")
		(net "GMI_CPU0_G2_CPU1_G0_TX_DP<3>")
	)
	(segment
		(start 305.922426 -177.000916)
		(end 309.87365 -178.02606)
		(width 0.14224)
		(layer "In2.Cu")
		(net "GMI_CPU0_G2_CPU1_G0_TX_DP<3>")
	)
	(segment
		(start 371.741954 -222.123508)
		(end 371.743478 -222.12427)
		(width 0.1143)
		(layer "In2.Cu")
		(net "GMI_CPU0_G2_CPU1_G0_TX_DP<3>")
	)
	(segment
		(start 371.748812 -223.101154)
		(end 371.747796 -223.101662)
		(width 0.1143)
		(layer "In2.Cu")
		(net "GMI_CPU0_G2_CPU1_G0_TX_DP<3>")
	)
	(segment
		(start 99.743768 -226.98964)
		(end 99.745546 -226.988624)
		(width 0.1143)
		(layer "In2.Cu")
		(net "GMI_CPU0_G2_CPU1_G0_TX_DP<3>")
	)
	(segment
		(start 371.743478 -222.12427)
		(end 371.74424 -222.124778)
		(width 0.1143)
		(layer "In2.Cu")
		(net "GMI_CPU0_G2_CPU1_G0_TX_DP<3>")
	)
	(segment
		(start 372.49989 -228.282754)
		(end 372.49989 -228.284024)
		(width 0.1143)
		(layer "In2.Cu")
		(net "GMI_CPU0_G2_CPU1_G0_TX_DP<3>")
	)
	(segment
		(start 371.774212 -227.002086)
		(end 371.775228 -227.002594)
		(width 0.1143)
		(layer "In2.Cu")
		(net "GMI_CPU0_G2_CPU1_G0_TX_DP<3>")
	)
	(segment
		(start 97.681034 -229.90429)
		(end 97.978976 -229.90429)
		(width 0.1143)
		(layer "In2.Cu")
		(net "GMI_CPU0_G2_CPU1_G0_TX_DP<3>")
	)
	(segment
		(start 371.786912 -226.318826)
		(end 371.750336 -226.340162)
		(width 0.1143)
		(layer "In2.Cu")
		(net "GMI_CPU0_G2_CPU1_G0_TX_DP<3>")
	)
	(segment
		(start 369.438682 -213.208108)
		(end 371.605556 -217.969846)
		(width 0.14224)
		(layer "In2.Cu")
		(net "GMI_CPU0_G2_CPU1_G0_TX_DP<3>")
	)
	(segment
		(start 371.747796 -226.986846)
		(end 371.774212 -227.002086)
		(width 0.1143)
		(layer "In2.Cu")
		(net "GMI_CPU0_G2_CPU1_G0_TX_DP<3>")
	)
	(segment
		(start 99.748086 -223.747076)
		(end 99.748848 -223.746568)
		(width 0.1143)
		(layer "In2.Cu")
		(net "GMI_CPU0_G2_CPU1_G0_TX_DP<3>")
	)
	(segment
		(start 371.716046 -225.348546)
		(end 371.745764 -225.365564)
		(width 0.1143)
		(layer "In2.Cu")
		(net "GMI_CPU0_G2_CPU1_G0_TX_DP<3>")
	)
	(segment
		(start 99.748086 -223.101916)
		(end 99.74707 -223.101408)
		(width 0.1143)
		(layer "In2.Cu")
		(net "GMI_CPU0_G2_CPU1_G0_TX_DP<3>")
	)
	(segment
		(start 98.768916 -228.629972)
		(end 98.801682 -228.610922)
		(width 0.1143)
		(layer "In2.Cu")
		(net "GMI_CPU0_G2_CPU1_G0_TX_DP<3>")
	)
	(segment
		(start 371.780054 -223.765618)
		(end 371.786912 -223.769682)
		(width 0.1143)
		(layer "In2.Cu")
		(net "GMI_CPU0_G2_CPU1_G0_TX_DP<3>")
	)
	(segment
		(start 98.808794 -228.606604)
		(end 98.811588 -228.60508)
		(width 0.1143)
		(layer "In2.Cu")
		(net "GMI_CPU0_G2_CPU1_G0_TX_DP<3>")
	)
	(segment
		(start 371.559836 -221.545658)
		(end 371.56009 -221.545912)
		(width 0.1143)
		(layer "In2.Cu")
		(net "GMI_CPU0_G2_CPU1_G0_TX_DP<3>")
	)
	(segment
		(start 99.70897 -223.769936)
		(end 99.741736 -223.750886)
		(width 0.1143)
		(layer "In2.Cu")
		(net "GMI_CPU0_G2_CPU1_G0_TX_DP<3>")
	)
	(segment
		(start 164.706554 -177.057304)
		(end 234.680506 -174.5488)
		(width 0.14224)
		(layer "In2.Cu")
		(net "GMI_CPU0_G2_CPU1_G0_TX_DP<3>")
	)
	(segment
		(start 98.950526 -221.203012)
		(end 98.950526 -221.174564)
		(width 0.1143)
		(layer "In2.Cu")
		(net "GMI_CPU0_G2_CPU1_G0_TX_DP<3>")
	)
	(segment
		(start 371.559836 -221.248478)
		(end 371.559836 -221.545658)
		(width 0.1143)
		(layer "In2.Cu")
		(net "GMI_CPU0_G2_CPU1_G0_TX_DP<3>")
	)
	(segment
		(start 99.748848 -226.342448)
		(end 99.748086 -226.34194)
		(width 0.1143)
		(layer "In2.Cu")
		(net "GMI_CPU0_G2_CPU1_G0_TX_DP<3>")
	)
	(segment
		(start 371.745764 -225.365564)
		(end 371.747034 -225.366326)
		(width 0.1143)
		(layer "In2.Cu")
		(net "GMI_CPU0_G2_CPU1_G0_TX_DP<3>")
	)
	(segment
		(start 99.308666 -222.30969)
		(end 99.278186 -222.29191)
		(width 0.1143)
		(layer "In2.Cu")
		(net "GMI_CPU0_G2_CPU1_G0_TX_DP<3>")
	)
	(segment
		(start 98.995992 -221.546166)
		(end 98.996246 -221.545912)
		(width 0.1143)
		(layer "In2.Cu")
		(net "GMI_CPU0_G2_CPU1_G0_TX_DP<3>")
	)
	(segment
		(start 371.779292 -223.76511)
		(end 371.780054 -223.765618)
		(width 0.1143)
		(layer "In2.Cu")
		(net "GMI_CPU0_G2_CPU1_G0_TX_DP<3>")
	)
	(segment
		(start 99.71659 -226.323652)
		(end 99.715828 -226.323144)
		(width 0.1143)
		(layer "In2.Cu")
		(net "GMI_CPU0_G2_CPU1_G0_TX_DP<3>")
	)
	(segment
		(start 98.81235 -228.604572)
		(end 98.839782 -228.588824)
		(width 0.1143)
		(layer "In2.Cu")
		(net "GMI_CPU0_G2_CPU1_G0_TX_DP<3>")
	)
	(segment
		(start 373.124222 -229.397052)
		(end 373.15775 -229.41661)
		(width 0.1143)
		(layer "In2.Cu")
		(net "GMI_CPU0_G2_CPU1_G0_TX_DP<3>")
	)
	(segment
		(start 234.680506 -174.5488)
		(end 305.922426 -177.000916)
		(width 0.14224)
		(layer "In2.Cu")
		(net "GMI_CPU0_G2_CPU1_G0_TX_DP<3>")
	)
	(segment
		(start 371.747796 -222.12681)
		(end 371.748812 -222.127318)
		(width 0.1143)
		(layer "In2.Cu")
		(net "GMI_CPU0_G2_CPU1_G0_TX_DP<3>")
	)
	(segment
		(start 99.748848 -223.746568)
		(end 99.779836 -223.728788)
		(width 0.1143)
		(layer "In2.Cu")
		(net "GMI_CPU0_G2_CPU1_G0_TX_DP<3>")
	)
	(segment
		(start 371.605556 -217.969846)
		(end 371.605556 -221.17431)
		(width 0.14224)
		(layer "In2.Cu")
		(net "GMI_CPU0_G2_CPU1_G0_TX_DP<3>")
	)
	(segment
		(start 99.748848 -225.36658)
		(end 99.779836 -225.3488)
		(width 0.1143)
		(layer "In2.Cu")
		(net "GMI_CPU0_G2_CPU1_G0_TX_DP<3>")
	)
	(segment
		(start 371.741192 -222.123)
		(end 371.741954 -222.123508)
		(width 0.1143)
		(layer "In2.Cu")
		(net "GMI_CPU0_G2_CPU1_G0_TX_DP<3>")
	)
	(segment
		(start 99.748848 -226.986592)
		(end 99.779836 -226.968812)
		(width 0.1143)
		(layer "In2.Cu")
		(net "GMI_CPU0_G2_CPU1_G0_TX_DP<3>")
	)
	(segment
		(start 98.299016 -229.439724)
		(end 98.338132 -229.416864)
		(width 0.1143)
		(layer "In2.Cu")
		(net "GMI_CPU0_G2_CPU1_G0_TX_DP<3>")
	)
	(segment
		(start 372.697248 -228.612446)
		(end 372.72595 -228.628956)
		(width 0.1143)
		(layer "In2.Cu")
		(net "GMI_CPU0_G2_CPU1_G0_TX_DP<3>")
	)
	(segment
		(start 97.978976 -229.90429)
		(end 98.06178 -229.821486)
		(width 0.1143)
		(layer "In2.Cu")
		(net "GMI_CPU0_G2_CPU1_G0_TX_DP<3>")
	)
	(segment
		(start 371.747796 -224.721674)
		(end 371.747034 -224.722182)
		(width 0.1143)
		(layer "In2.Cu")
		(net "GMI_CPU0_G2_CPU1_G0_TX_DP<3>")
	)
	(segment
		(start 99.74707 -225.367596)
		(end 99.748086 -225.367088)
		(width 0.1143)
		(layer "In2.Cu")
		(net "GMI_CPU0_G2_CPU1_G0_TX_DP<3>")
	)
	(segment
		(start 98.950526 -221.174564)
		(end 98.950526 -213.157054)
		(width 0.14224)
		(layer "In2.Cu")
		(net "GMI_CPU0_G2_CPU1_G0_TX_DP<3>")
	)
	(segment
		(start 161.296604 -178.030378)
		(end 164.706554 -177.057304)
		(width 0.14224)
		(layer "In2.Cu")
		(net "GMI_CPU0_G2_CPU1_G0_TX_DP<3>")
	)
	(segment
		(start 99.799648 -223.134428)
		(end 99.779836 -223.120204)
		(width 0.1143)
		(layer "In2.Cu")
		(net "GMI_CPU0_G2_CPU1_G0_TX_DP<3>")
	)
	(segment
		(start 99.779836 -223.120204)
		(end 99.748848 -223.102424)
		(width 0.1143)
		(layer "In2.Cu")
		(net "GMI_CPU0_G2_CPU1_G0_TX_DP<3>")
	)
	(segment
		(start 99.741736 -225.370898)
		(end 99.743768 -225.369628)
		(width 0.1143)
		(layer "In2.Cu")
		(net "GMI_CPU0_G2_CPU1_G0_TX_DP<3>")
	)
	(segment
		(start 371.74424 -222.124778)
		(end 371.747034 -222.126302)
		(width 0.1143)
		(layer "In2.Cu")
		(net "GMI_CPU0_G2_CPU1_G0_TX_DP<3>")
	)
	(segment
		(start 99.74707 -224.72142)
		(end 99.71659 -224.70364)
		(width 0.1143)
		(layer "In2.Cu")
		(net "GMI_CPU0_G2_CPU1_G0_TX_DP<3>")
	)
	(segment
		(start 99.23907 -227.819966)
		(end 99.278186 -227.797106)
		(width 0.1143)
		(layer "In2.Cu")
		(net "GMI_CPU0_G2_CPU1_G0_TX_DP<3>")
	)
	(segment
		(start 99.74707 -226.341432)
		(end 99.71659 -226.323652)
		(width 0.1143)
		(layer "In2.Cu")
		(net "GMI_CPU0_G2_CPU1_G0_TX_DP<3>")
	)
	(segment
		(start 98.996246 -221.248732)
		(end 98.950526 -221.203012)
		(width 0.1143)
		(layer "In2.Cu")
		(net "GMI_CPU0_G2_CPU1_G0_TX_DP<3>")
	)
	(segment
		(start 371.77853 -227.004626)
		(end 371.780054 -227.005642)
		(width 0.1143)
		(layer "In2.Cu")
		(net "GMI_CPU0_G2_CPU1_G0_TX_DP<3>")
	)
	(segment
		(start 98.808032 -228.607112)
		(end 98.808794 -228.606604)
		(width 0.1143)
		(layer "In2.Cu")
		(net "GMI_CPU0_G2_CPU1_G0_TX_DP<3>")
	)
	(segment
		(start 98.995992 -221.804484)
		(end 98.995992 -221.546166)
		(width 0.1143)
		(layer "In2.Cu")
		(net "GMI_CPU0_G2_CPU1_G0_TX_DP<3>")
	)
	(segment
		(start 371.747796 -225.366834)
		(end 371.779292 -225.385122)
		(width 0.1143)
		(layer "In2.Cu")
		(net "GMI_CPU0_G2_CPU1_G0_TX_DP<3>")
	)
	(segment
		(start 371.747796 -226.341686)
		(end 371.747034 -226.342194)
		(width 0.1143)
		(layer "In2.Cu")
		(net "GMI_CPU0_G2_CPU1_G0_TX_DP<3>")
	)
	(segment
		(start 371.750336 -224.72015)
		(end 371.748812 -224.721166)
		(width 0.1143)
		(layer "In2.Cu")
		(net "GMI_CPU0_G2_CPU1_G0_TX_DP<3>")
	)
	(segment
		(start 371.747034 -222.126302)
		(end 371.747796 -222.12681)
		(width 0.1143)
		(layer "In2.Cu")
		(net "GMI_CPU0_G2_CPU1_G0_TX_DP<3>")
	)
	(segment
		(start 371.716046 -223.728534)
		(end 371.745764 -223.745552)
		(width 0.1143)
		(layer "In2.Cu")
		(net "GMI_CPU0_G2_CPU1_G0_TX_DP<3>")
	)
	(segment
		(start 357.807006 -204.4319)
		(end 360.147616 -206.015844)
		(width 0.14224)
		(layer "In2.Cu")
		(net "GMI_CPU0_G2_CPU1_G0_TX_DP<3>")
	)
	(segment
		(start 371.786912 -223.078802)
		(end 371.750336 -223.100138)
		(width 0.1143)
		(layer "In2.Cu")
		(net "GMI_CPU0_G2_CPU1_G0_TX_DP<3>")
	)
	(segment
		(start 371.737382 -222.120968)
		(end 371.739922 -222.122238)
		(width 0.1143)
		(layer "In2.Cu")
		(net "GMI_CPU0_G2_CPU1_G0_TX_DP<3>")
	)
	(segment
		(start 99.278186 -227.797106)
		(end 99.308666 -227.779326)
		(width 0.1143)
		(layer "In2.Cu")
		(net "GMI_CPU0_G2_CPU1_G0_TX_DP<3>")
	)
	(segment
		(start 99.741736 -223.750886)
		(end 99.743768 -223.749616)
		(width 0.1143)
		(layer "In2.Cu")
		(net "GMI_CPU0_G2_CPU1_G0_TX_DP<3>")
	)
	(segment
		(start 99.70897 -227.00996)
		(end 99.741736 -226.99091)
		(width 0.1143)
		(layer "In2.Cu")
		(net "GMI_CPU0_G2_CPU1_G0_TX_DP<3>")
	)
	(segment
		(start 98.807016 -228.60762)
		(end 98.808032 -228.607112)
		(width 0.1143)
		(layer "In2.Cu")
		(net "GMI_CPU0_G2_CPU1_G0_TX_DP<3>")
	)
	(segment
		(start 99.715828 -224.703132)
		(end 99.70897 -224.699068)
		(width 0.1143)
		(layer "In2.Cu")
		(net "GMI_CPU0_G2_CPU1_G0_TX_DP<3>")
	)
	(segment
		(start 371.56009 -221.545912)
		(end 371.56009 -221.80423)
		(width 0.1143)
		(layer "In2.Cu")
		(net "GMI_CPU0_G2_CPU1_G0_TX_DP<3>")
	)
	(segment
		(start 98.801682 -228.610922)
		(end 98.803714 -228.609652)
		(width 0.1143)
		(layer "In2.Cu")
		(net "GMI_CPU0_G2_CPU1_G0_TX_DP<3>")
	)
	(segment
		(start 99.748848 -224.722436)
		(end 99.748086 -224.721928)
		(width 0.1143)
		(layer "In2.Cu")
		(net "GMI_CPU0_G2_CPU1_G0_TX_DP<3>")
	)
	(segment
		(start 99.741736 -226.99091)
		(end 99.743768 -226.98964)
		(width 0.1143)
		(layer "In2.Cu")
		(net "GMI_CPU0_G2_CPU1_G0_TX_DP<3>")
	)
	(segment
		(start 371.747796 -223.101662)
		(end 371.747034 -223.10217)
		(width 0.1143)
		(layer "In2.Cu")
		(net "GMI_CPU0_G2_CPU1_G0_TX_DP<3>")
	)
	(segment
		(start 99.748086 -226.9871)
		(end 99.748848 -226.986592)
		(width 0.1143)
		(layer "In2.Cu")
		(net "GMI_CPU0_G2_CPU1_G0_TX_DP<3>")
	)
	(segment
		(start 371.745764 -223.745552)
		(end 371.747034 -223.746314)
		(width 0.1143)
		(layer "In2.Cu")
		(net "GMI_CPU0_G2_CPU1_G0_TX_DP<3>")
	)
	(segment
		(start 371.750336 -226.340162)
		(end 371.748812 -226.341178)
		(width 0.1143)
		(layer "In2.Cu")
		(net "GMI_CPU0_G2_CPU1_G0_TX_DP<3>")
	)
	(segment
		(start 372.1989 -227.798122)
		(end 372.23065 -227.816918)
		(width 0.1143)
		(layer "In2.Cu")
		(net "GMI_CPU0_G2_CPU1_G0_TX_DP<3>")
	)
	(segment
		(start 99.743768 -223.749616)
		(end 99.745546 -223.7486)
		(width 0.1143)
		(layer "In2.Cu")
		(net "GMI_CPU0_G2_CPU1_G0_TX_DP<3>")
	)
	(segment
		(start 98.803714 -228.609652)
		(end 98.805492 -228.608636)
		(width 0.1143)
		(layer "In2.Cu")
		(net "GMI_CPU0_G2_CPU1_G0_TX_DP<3>")
	)
	(segment
		(start 99.715828 -226.323144)
		(end 99.70897 -226.31908)
		(width 0.1143)
		(layer "In2.Cu")
		(net "GMI_CPU0_G2_CPU1_G0_TX_DP<3>")
	)
	(segment
		(start 326.30999 -185.802016)
		(end 357.807006 -204.4319)
		(width 0.14224)
		(layer "In2.Cu")
		(net "GMI_CPU0_G2_CPU1_G0_TX_DP<3>")
	)
	(segment
		(start 371.745764 -226.985576)
		(end 371.747034 -226.986338)
		(width 0.1143)
		(layer "In2.Cu")
		(net "GMI_CPU0_G2_CPU1_G0_TX_DP<3>")
	)
	(segment
		(start 98.805492 -228.608636)
		(end 98.807016 -228.60762)
		(width 0.1143)
		(layer "In2.Cu")
		(net "GMI_CPU0_G2_CPU1_G0_TX_DP<3>")
	)
	(segment
		(start 373.15775 -229.41661)
		(end 373.196866 -229.43947)
		(width 0.1143)
		(layer "In2.Cu")
		(net "GMI_CPU0_G2_CPU1_G0_TX_DP<3>")
	)
	(segment
		(start 99.278186 -222.29191)
		(end 99.241864 -222.270828)
		(width 0.1143)
		(layer "In2.Cu")
		(net "GMI_CPU0_G2_CPU1_G0_TX_DP<3>")
	)
	(segment
		(start 360.14787 -206.016098)
		(end 364.790228 -209.158078)
		(width 0.14224)
		(layer "In2.Cu")
		(net "GMI_CPU0_G2_CPU1_G0_TX_DP<3>")
	)
	(segment
		(start 99.748848 -223.102424)
		(end 99.748086 -223.101916)
		(width 0.1143)
		(layer "In2.Cu")
		(net "GMI_CPU0_G2_CPU1_G0_TX_DP<3>")
	)
	(segment
		(start 98.338132 -229.416864)
		(end 98.370644 -229.398068)
		(width 0.1143)
		(layer "In2.Cu")
		(net "GMI_CPU0_G2_CPU1_G0_TX_DP<3>")
	)
	(segment
		(start 371.747034 -226.986338)
		(end 371.747796 -226.986846)
		(width 0.1143)
		(layer "In2.Cu")
		(net "GMI_CPU0_G2_CPU1_G0_TX_DP<3>")
	)
	(segment
		(start 373.434102 -229.821232)
		(end 373.516906 -229.904036)
		(width 0.1143)
		(layer "In2.Cu")
		(net "GMI_CPU0_G2_CPU1_G0_TX_DP<3>")
	)
	(segment
		(start 371.605556 -221.202758)
		(end 371.559836 -221.248478)
		(width 0.1143)
		(layer "In2.Cu")
		(net "GMI_CPU0_G2_CPU1_G0_TX_DP<3>")
	)
	(segment
		(start 99.745546 -223.7486)
		(end 99.74707 -223.747584)
		(width 0.1143)
		(layer "In2.Cu")
		(net "GMI_CPU0_G2_CPU1_G0_TX_DP<3>")
	)
	(segment
		(start 371.780054 -225.38563)
		(end 371.786912 -225.389694)
		(width 0.1143)
		(layer "In2.Cu")
		(net "GMI_CPU0_G2_CPU1_G0_TX_DP<3>")
	)
	(segment
		(start 99.74707 -226.987608)
		(end 99.748086 -226.9871)
		(width 0.1143)
		(layer "In2.Cu")
		(net "GMI_CPU0_G2_CPU1_G0_TX_DP<3>")
	)
	(segment
		(start 99.779836 -224.740216)
		(end 99.748848 -224.722436)
		(width 0.1143)
		(layer "In2.Cu")
		(net "GMI_CPU0_G2_CPU1_G0_TX_DP<3>")
	)
	(segment
		(start 99.74707 -223.101408)
		(end 99.71659 -223.083628)
		(width 0.1143)
		(layer "In2.Cu")
		(net "GMI_CPU0_G2_CPU1_G0_TX_DP<3>")
	)
	(segment
		(start 99.70897 -225.389948)
		(end 99.741736 -225.370898)
		(width 0.1143)
		(layer "In2.Cu")
		(net "GMI_CPU0_G2_CPU1_G0_TX_DP<3>")
	)
	(segment
		(start 371.747034 -224.722182)
		(end 371.716046 -224.739962)
		(width 0.1143)
		(layer "In2.Cu")
		(net "GMI_CPU0_G2_CPU1_G0_TX_DP<3>")
	)
	(segment
		(start 99.71659 -224.70364)
		(end 99.715828 -224.703132)
		(width 0.1143)
		(layer "In2.Cu")
		(net "GMI_CPU0_G2_CPU1_G0_TX_DP<3>")
	)
	(segment
		(start 371.779292 -225.385122)
		(end 371.780054 -225.38563)
		(width 0.1143)
		(layer "In2.Cu")
		(net "GMI_CPU0_G2_CPU1_G0_TX_DP<3>")
	)
	(segment
		(start 364.790228 -209.158078)
		(end 369.438682 -213.208108)
		(width 0.14224)
		(layer "In2.Cu")
		(net "GMI_CPU0_G2_CPU1_G0_TX_DP<3>")
	)
	(segment
		(start 98.996246 -221.545912)
		(end 98.996246 -221.248732)
		(width 0.1143)
		(layer "In2.Cu")
		(net "GMI_CPU0_G2_CPU1_G0_TX_DP<3>")
	)
	(segment
		(start 309.87365 -178.02606)
		(end 311.264554 -178.555396)
		(width 0.14224)
		(layer "In2.Cu")
		(net "GMI_CPU0_G2_CPU1_G0_TX_DP<3>")
	)
	(segment
		(start 360.147616 -206.015844)
		(end 360.14787 -206.016098)
		(width 0.14224)
		(layer "In2.Cu")
		(net "GMI_CPU0_G2_CPU1_G0_TX_DP<3>")
	)
	(segment
		(start 371.716046 -226.968558)
		(end 371.745764 -226.985576)
		(width 0.1143)
		(layer "In2.Cu")
		(net "GMI_CPU0_G2_CPU1_G0_TX_DP<3>")
	)
	(segment
		(start 99.745546 -226.988624)
		(end 99.74707 -226.987608)
		(width 0.1143)
		(layer "In2.Cu")
		(net "GMI_CPU0_G2_CPU1_G0_TX_DP<3>")
	)
	(segment
		(start 99.715828 -223.08312)
		(end 99.70897 -223.079056)
		(width 0.1143)
		(layer "In2.Cu")
		(net "GMI_CPU0_G2_CPU1_G0_TX_DP<3>")
	)
	(segment
		(start 99.748086 -226.34194)
		(end 99.74707 -226.341432)
		(width 0.1143)
		(layer "In2.Cu")
		(net "GMI_CPU0_G2_CPU1_G0_TX_DP<3>")
	)
	(segment
		(start 371.786912 -224.698814)
		(end 371.750336 -224.72015)
		(width 0.1143)
		(layer "In2.Cu")
		(net "GMI_CPU0_G2_CPU1_G0_TX_DP<3>")
	)
	(segment
		(start 371.716046 -222.108522)
		(end 371.737382 -222.120968)
		(width 0.1143)
		(layer "In2.Cu")
		(net "GMI_CPU0_G2_CPU1_G0_TX_DP<3>")
	)
	(segment
		(start 98.950526 -213.157054)
		(end 107.248198 -204.859382)
		(width 0.14224)
		(layer "In2.Cu")
		(net "GMI_CPU0_G2_CPU1_G0_TX_DP<3>")
	)
	(segment
		(start 371.747034 -226.342194)
		(end 371.716046 -226.359974)
		(width 0.1143)
		(layer "In2.Cu")
		(net "GMI_CPU0_G2_CPU1_G0_TX_DP<3>")
	)
	(segment
		(start 99.748086 -224.721928)
		(end 99.74707 -224.72142)
		(width 0.1143)
		(layer "In2.Cu")
		(net "GMI_CPU0_G2_CPU1_G0_TX_DP<3>")
	)
	(segment
		(start 99.743768 -225.369628)
		(end 99.745546 -225.368612)
		(width 0.1143)
		(layer "In2.Cu")
		(net "GMI_CPU0_G2_CPU1_G0_TX_DP<3>")
	)
	(segment
		(start 99.779836 -226.360228)
		(end 99.748848 -226.342448)
		(width 0.1143)
		(layer "In2.Cu")
		(net "GMI_CPU0_G2_CPU1_G0_TX_DP<3>")
	)
	(segment
		(start 99.71659 -223.083628)
		(end 99.715828 -223.08312)
		(width 0.1143)
		(layer "In2.Cu")
		(net "GMI_CPU0_G2_CPU1_G0_TX_DP<3>")
	)
	(segment
		(start 99.779836 -225.3488)
		(end 99.799648 -225.334576)
		(width 0.1143)
		(layer "In2.Cu")
		(net "GMI_CPU0_G2_CPU1_G0_TX_DP<3>")
	)
	(segment
		(start 99.74707 -223.747584)
		(end 99.748086 -223.747076)
		(width 0.1143)
		(layer "In2.Cu")
		(net "GMI_CPU0_G2_CPU1_G0_TX_DP<3>")
	)
	(segment
		(start 371.750336 -223.100138)
		(end 371.748812 -223.101154)
		(width 0.1143)
		(layer "In2.Cu")
		(net "GMI_CPU0_G2_CPU1_G0_TX_DP<3>")
	)
	(segment
		(start 373.516906 -229.904036)
		(end 373.814848 -229.904036)
		(width 0.1143)
		(layer "In2.Cu")
		(net "GMI_CPU0_G2_CPU1_G0_TX_DP<3>")
	)
	(segment
		(start 99.745546 -225.368612)
		(end 99.74707 -225.367596)
		(width 0.1143)
		(layer "In2.Cu")
		(net "GMI_CPU0_G2_CPU1_G0_TX_DP<3>")
	)
	(segment
		(start 371.748812 -226.341178)
		(end 371.747796 -226.341686)
		(width 0.1143)
		(layer "In2.Cu")
		(net "GMI_CPU0_G2_CPU1_G0_TX_DP<3>")
	)
	(segment
		(start 372.042944 -227.466906)
		(end 372.042944 -227.494084)
		(width 0.1143)
		(layer "In2.Cu")
		(net "GMI_CPU0_G2_CPU1_G0_TX_DP<3>")
	)
	(arc
		(start 99.799648 -223.714564)
		(mid 99.948362 -223.424496)
		(end 99.799648 -223.134428)
		(width 0.1143)
		(layer "In2.Cu")
		(net "GMI_CPU0_G2_CPU1_G0_TX_DP<3>")
	)
	(arc
		(start 99.779836 -226.968812)
		(mid 99.931425 -226.66452)
		(end 99.779836 -226.360228)
		(width 0.1143)
		(layer "In2.Cu")
		(net "GMI_CPU0_G2_CPU1_G0_TX_DP<3>")
	)
	(arc
		(start 371.716046 -226.359974)
		(mid 371.560118 -226.664266)
		(end 371.716046 -226.968558)
		(width 0.1143)
		(layer "In2.Cu")
		(net "GMI_CPU0_G2_CPU1_G0_TX_DP<3>")
	)
	(arc
		(start 98.839782 -228.588824)
		(mid 98.954458 -228.45549)
		(end 98.995738 -228.284532)
		(width 0.1143)
		(layer "In2.Cu")
		(net "GMI_CPU0_G2_CPU1_G0_TX_DP<3>")
	)
	(arc
		(start 99.70897 -226.31908)
		(mid 99.465643 -225.854514)
		(end 99.70897 -225.389948)
		(width 0.1143)
		(layer "In2.Cu")
		(net "GMI_CPU0_G2_CPU1_G0_TX_DP<3>")
	)
	(arc
		(start 99.70897 -224.699068)
		(mid 99.465643 -224.234502)
		(end 99.70897 -223.769936)
		(width 0.1143)
		(layer "In2.Cu")
		(net "GMI_CPU0_G2_CPU1_G0_TX_DP<3>")
	)
	(arc
		(start 373.196866 -229.43947)
		(mid 373.355071 -229.605757)
		(end 373.434102 -229.821232)
		(width 0.1143)
		(layer "In2.Cu")
		(net "GMI_CPU0_G2_CPU1_G0_TX_DP<3>")
	)
	(arc
		(start 372.970044 -229.094284)
		(mid 373.010806 -229.264168)
		(end 373.124222 -229.397052)
		(width 0.1143)
		(layer "In2.Cu")
		(net "GMI_CPU0_G2_CPU1_G0_TX_DP<3>")
	)
	(arc
		(start 99.308666 -227.779326)
		(mid 99.424093 -227.64595)
		(end 99.465638 -227.474526)
		(width 0.1143)
		(layer "In2.Cu")
		(net "GMI_CPU0_G2_CPU1_G0_TX_DP<3>")
	)
	(arc
		(start 99.465638 -222.61449)
		(mid 99.424089 -222.443068)
		(end 99.308666 -222.30969)
		(width 0.1143)
		(layer "In2.Cu")
		(net "GMI_CPU0_G2_CPU1_G0_TX_DP<3>")
	)
	(arc
		(start 99.241864 -222.270828)
		(mid 99.061212 -222.068083)
		(end 98.995992 -221.804484)
		(width 0.1143)
		(layer "In2.Cu")
		(net "GMI_CPU0_G2_CPU1_G0_TX_DP<3>")
	)
	(arc
		(start 99.799648 -225.334576)
		(mid 99.948362 -225.044508)
		(end 99.799648 -224.75444)
		(width 0.1143)
		(layer "In2.Cu")
		(net "GMI_CPU0_G2_CPU1_G0_TX_DP<3>")
	)
	(arc
		(start 371.786912 -225.389694)
		(mid 372.030239 -225.85426)
		(end 371.786912 -226.318826)
		(width 0.1143)
		(layer "In2.Cu")
		(net "GMI_CPU0_G2_CPU1_G0_TX_DP<3>")
	)
	(arc
		(start 372.49989 -228.284024)
		(mid 372.543747 -228.459474)
		(end 372.665244 -228.593396)
		(width 0.1143)
		(layer "In2.Cu")
		(net "GMI_CPU0_G2_CPU1_G0_TX_DP<3>")
	)
	(arc
		(start 372.72595 -228.628956)
		(mid 372.905295 -228.831559)
		(end 372.970044 -229.094284)
		(width 0.1143)
		(layer "In2.Cu")
		(net "GMI_CPU0_G2_CPU1_G0_TX_DP<3>")
	)
	(arc
		(start 98.525584 -229.094538)
		(mid 98.590099 -228.832319)
		(end 98.768916 -228.629972)
		(width 0.1143)
		(layer "In2.Cu")
		(net "GMI_CPU0_G2_CPU1_G0_TX_DP<3>")
	)
	(arc
		(start 98.370644 -229.398068)
		(mid 98.484573 -229.264921)
		(end 98.525584 -229.094538)
		(width 0.1143)
		(layer "In2.Cu")
		(net "GMI_CPU0_G2_CPU1_G0_TX_DP<3>")
	)
	(arc
		(start 371.716046 -224.739962)
		(mid 371.560118 -225.044254)
		(end 371.716046 -225.348546)
		(width 0.1143)
		(layer "In2.Cu")
		(net "GMI_CPU0_G2_CPU1_G0_TX_DP<3>")
	)
	(arc
		(start 99.70897 -223.079056)
		(mid 99.530157 -222.876706)
		(end 99.465638 -222.61449)
		(width 0.1143)
		(layer "In2.Cu")
		(net "GMI_CPU0_G2_CPU1_G0_TX_DP<3>")
	)
	(arc
		(start 372.665244 -228.593396)
		(mid 372.681007 -228.603323)
		(end 372.697248 -228.612446)
		(width 0.1143)
		(layer "In2.Cu")
		(net "GMI_CPU0_G2_CPU1_G0_TX_DP<3>")
	)
	(arc
		(start 98.06178 -229.821486)
		(mid 98.063568 -229.810037)
		(end 98.06559 -229.798626)
		(width 0.1143)
		(layer "In2.Cu")
		(net "GMI_CPU0_G2_CPU1_G0_TX_DP<3>")
	)
	(arc
		(start 98.995738 -228.284532)
		(mid 99.060253 -228.022313)
		(end 99.23907 -227.819966)
		(width 0.1143)
		(layer "In2.Cu")
		(net "GMI_CPU0_G2_CPU1_G0_TX_DP<3>")
	)
	(arc
		(start 372.23065 -227.816918)
		(mid 372.42715 -228.014083)
		(end 372.49989 -228.282754)
		(width 0.1143)
		(layer "In2.Cu")
		(net "GMI_CPU0_G2_CPU1_G0_TX_DP<3>")
	)
	(arc
		(start 372.042944 -227.494084)
		(mid 372.084203 -227.664941)
		(end 372.1989 -227.798122)
		(width 0.1143)
		(layer "In2.Cu")
		(net "GMI_CPU0_G2_CPU1_G0_TX_DP<3>")
	)
	(arc
		(start 371.716046 -223.11995)
		(mid 371.560118 -223.424242)
		(end 371.716046 -223.728534)
		(width 0.1143)
		(layer "In2.Cu")
		(net "GMI_CPU0_G2_CPU1_G0_TX_DP<3>")
	)
	(arc
		(start 371.780054 -227.005642)
		(mid 371.972578 -227.201456)
		(end 372.042944 -227.466906)
		(width 0.1143)
		(layer "In2.Cu")
		(net "GMI_CPU0_G2_CPU1_G0_TX_DP<3>")
	)
	(arc
		(start 98.06559 -229.798626)
		(mid 98.147023 -229.596228)
		(end 98.299016 -229.439724)
		(width 0.1143)
		(layer "In2.Cu")
		(net "GMI_CPU0_G2_CPU1_G0_TX_DP<3>")
	)
	(arc
		(start 371.56009 -221.80423)
		(mid 371.601345 -221.975201)
		(end 371.716046 -222.108522)
		(width 0.1143)
		(layer "In2.Cu")
		(net "GMI_CPU0_G2_CPU1_G0_TX_DP<3>")
	)
	(arc
		(start 371.786912 -223.769682)
		(mid 372.030239 -224.234248)
		(end 371.786912 -224.698814)
		(width 0.1143)
		(layer "In2.Cu")
		(net "GMI_CPU0_G2_CPU1_G0_TX_DP<3>")
	)
	(arc
		(start 371.786912 -222.14967)
		(mid 372.030239 -222.614236)
		(end 371.786912 -223.078802)
		(width 0.1143)
		(layer "In2.Cu")
		(net "GMI_CPU0_G2_CPU1_G0_TX_DP<3>")
	)
	(arc
		(start 99.465638 -227.474526)
		(mid 99.530153 -227.212307)
		(end 99.70897 -227.00996)
		(width 0.1143)
		(layer "In2.Cu")
		(net "GMI_CPU0_G2_CPU1_G0_TX_DP<3>")
	)
	(segment
		(start 98.147886 -226.930458)
		(end 97.681034 -226.66452)
		(width 0.12954)
		(layer "F.Cu")
		(net "GMI_CPU0_G2_CPU1_G0_TX_DP<2>")
	)
	(segment
		(start 373.347996 -226.930204)
		(end 373.814848 -226.664266)
		(width 0.12954)
		(layer "F.Cu")
		(net "GMI_CPU0_G2_CPU1_G0_TX_DP<2>")
	)
	(segment
		(start 97.899728 -224.740216)
		(end 97.867978 -224.721928)
		(width 0.1143)
		(layer "In2.Cu")
		(net "GMI_CPU0_G2_CPU1_G0_TX_DP<2>")
	)
	(segment
		(start 373.485664 -221.17431)
		(end 373.485664 -221.202758)
		(width 0.1143)
		(layer "In2.Cu")
		(net "GMI_CPU0_G2_CPU1_G0_TX_DP<2>")
	)
	(segment
		(start 160.968436 -176.14138)
		(end 164.341556 -175.17872)
		(width 0.14224)
		(layer "In2.Cu")
		(net "GMI_CPU0_G2_CPU1_G0_TX_DP<2>")
	)
	(segment
		(start 373.59717 -222.10903)
		(end 373.62765 -222.12681)
		(width 0.1143)
		(layer "In2.Cu")
		(net "GMI_CPU0_G2_CPU1_G0_TX_DP<2>")
	)
	(segment
		(start 312.712862 -177.07229)
		(end 318.867028 -179.809902)
		(width 0.14224)
		(layer "In2.Cu")
		(net "GMI_CPU0_G2_CPU1_G0_TX_DP<2>")
	)
	(segment
		(start 97.09531 -221.248732)
		(end 97.04959 -221.203012)
		(width 0.1143)
		(layer "In2.Cu")
		(net "GMI_CPU0_G2_CPU1_G0_TX_DP<2>")
	)
	(segment
		(start 97.04959 -221.203012)
		(end 97.04959 -221.174564)
		(width 0.1143)
		(layer "In2.Cu")
		(net "GMI_CPU0_G2_CPU1_G0_TX_DP<2>")
	)
	(segment
		(start 373.59717 -223.729042)
		(end 373.62765 -223.746822)
		(width 0.1143)
		(layer "In2.Cu")
		(net "GMI_CPU0_G2_CPU1_G0_TX_DP<2>")
	)
	(segment
		(start 373.62765 -222.12681)
		(end 373.666766 -222.14967)
		(width 0.1143)
		(layer "In2.Cu")
		(net "GMI_CPU0_G2_CPU1_G0_TX_DP<2>")
	)
	(segment
		(start 97.867978 -223.747076)
		(end 97.899728 -223.728788)
		(width 0.1143)
		(layer "In2.Cu")
		(net "GMI_CPU0_G2_CPU1_G0_TX_DP<2>")
	)
	(segment
		(start 97.899728 -223.120204)
		(end 97.867978 -223.101916)
		(width 0.1143)
		(layer "In2.Cu")
		(net "GMI_CPU0_G2_CPU1_G0_TX_DP<2>")
	)
	(segment
		(start 373.516906 -226.664266)
		(end 373.814848 -226.664266)
		(width 0.1143)
		(layer "In2.Cu")
		(net "GMI_CPU0_G2_CPU1_G0_TX_DP<2>")
	)
	(segment
		(start 373.62765 -223.746822)
		(end 373.666766 -223.769682)
		(width 0.1143)
		(layer "In2.Cu")
		(net "GMI_CPU0_G2_CPU1_G0_TX_DP<2>")
	)
	(segment
		(start 97.899728 -226.360228)
		(end 97.867978 -226.34194)
		(width 0.1143)
		(layer "In2.Cu")
		(net "GMI_CPU0_G2_CPU1_G0_TX_DP<2>")
	)
	(segment
		(start 306.35575 -175.109886)
		(end 310.12892 -176.088802)
		(width 0.14224)
		(layer "In2.Cu")
		(net "GMI_CPU0_G2_CPU1_G0_TX_DP<2>")
	)
	(segment
		(start 97.04959 -221.174564)
		(end 97.04959 -211.98078)
		(width 0.14224)
		(layer "In2.Cu")
		(net "GMI_CPU0_G2_CPU1_G0_TX_DP<2>")
	)
	(segment
		(start 373.439944 -221.248478)
		(end 373.439944 -221.545658)
		(width 0.1143)
		(layer "In2.Cu")
		(net "GMI_CPU0_G2_CPU1_G0_TX_DP<2>")
	)
	(segment
		(start 373.62765 -223.101662)
		(end 373.59717 -223.119442)
		(width 0.1143)
		(layer "In2.Cu")
		(net "GMI_CPU0_G2_CPU1_G0_TX_DP<2>")
	)
	(segment
		(start 97.596198 -222.629984)
		(end 97.596198 -222.622872)
		(width 0.1143)
		(layer "In2.Cu")
		(net "GMI_CPU0_G2_CPU1_G0_TX_DP<2>")
	)
	(segment
		(start 97.09531 -221.545912)
		(end 97.09531 -221.248732)
		(width 0.1143)
		(layer "In2.Cu")
		(net "GMI_CPU0_G2_CPU1_G0_TX_DP<2>")
	)
	(segment
		(start 97.115884 -221.566486)
		(end 97.09531 -221.545912)
		(width 0.1143)
		(layer "In2.Cu")
		(net "GMI_CPU0_G2_CPU1_G0_TX_DP<2>")
	)
	(segment
		(start 318.874394 -179.81295)
		(end 323.001132 -181.941978)
		(width 0.14224)
		(layer "In2.Cu")
		(net "GMI_CPU0_G2_CPU1_G0_TX_DP<2>")
	)
	(segment
		(start 97.867978 -224.721928)
		(end 97.831656 -224.700846)
		(width 0.1143)
		(layer "In2.Cu")
		(net "GMI_CPU0_G2_CPU1_G0_TX_DP<2>")
	)
	(segment
		(start 97.867978 -226.34194)
		(end 97.831656 -226.320858)
		(width 0.1143)
		(layer "In2.Cu")
		(net "GMI_CPU0_G2_CPU1_G0_TX_DP<2>")
	)
	(segment
		(start 97.04959 -211.98078)
		(end 105.605326 -203.425044)
		(width 0.14224)
		(layer "In2.Cu")
		(net "GMI_CPU0_G2_CPU1_G0_TX_DP<2>")
	)
	(segment
		(start 373.62765 -226.341686)
		(end 373.59717 -226.359466)
		(width 0.1143)
		(layer "In2.Cu")
		(net "GMI_CPU0_G2_CPU1_G0_TX_DP<2>")
	)
	(segment
		(start 359.032556 -202.942444)
		(end 365.925862 -207.607916)
		(width 0.14224)
		(layer "In2.Cu")
		(net "GMI_CPU0_G2_CPU1_G0_TX_DP<2>")
	)
	(segment
		(start 370.953792 -211.9884)
		(end 373.485664 -217.551762)
		(width 0.14224)
		(layer "In2.Cu")
		(net "GMI_CPU0_G2_CPU1_G0_TX_DP<2>")
	)
	(segment
		(start 318.867028 -179.809902)
		(end 318.874394 -179.81295)
		(width 0.14224)
		(layer "In2.Cu")
		(net "GMI_CPU0_G2_CPU1_G0_TX_DP<2>")
	)
	(segment
		(start 373.666766 -223.078802)
		(end 373.62765 -223.101662)
		(width 0.1143)
		(layer "In2.Cu")
		(net "GMI_CPU0_G2_CPU1_G0_TX_DP<2>")
	)
	(segment
		(start 373.59717 -225.349054)
		(end 373.62765 -225.366834)
		(width 0.1143)
		(layer "In2.Cu")
		(net "GMI_CPU0_G2_CPU1_G0_TX_DP<2>")
	)
	(segment
		(start 97.115884 -221.80423)
		(end 97.115884 -221.566486)
		(width 0.1143)
		(layer "In2.Cu")
		(net "GMI_CPU0_G2_CPU1_G0_TX_DP<2>")
	)
	(segment
		(start 373.485664 -217.551762)
		(end 373.485664 -221.17431)
		(width 0.14224)
		(layer "In2.Cu")
		(net "GMI_CPU0_G2_CPU1_G0_TX_DP<2>")
	)
	(segment
		(start 323.001132 -181.942232)
		(end 327.128378 -184.071514)
		(width 0.14224)
		(layer "In2.Cu")
		(net "GMI_CPU0_G2_CPU1_G0_TX_DP<2>")
	)
	(segment
		(start 323.001132 -181.941978)
		(end 323.001132 -181.942232)
		(width 0.14224)
		(layer "In2.Cu")
		(net "GMI_CPU0_G2_CPU1_G0_TX_DP<2>")
	)
	(segment
		(start 97.831656 -223.768158)
		(end 97.867978 -223.747076)
		(width 0.1143)
		(layer "In2.Cu")
		(net "GMI_CPU0_G2_CPU1_G0_TX_DP<2>")
	)
	(segment
		(start 373.62765 -224.721674)
		(end 373.59717 -224.739454)
		(width 0.1143)
		(layer "In2.Cu")
		(net "GMI_CPU0_G2_CPU1_G0_TX_DP<2>")
	)
	(segment
		(start 373.62765 -225.366834)
		(end 373.666766 -225.389694)
		(width 0.1143)
		(layer "In2.Cu")
		(net "GMI_CPU0_G2_CPU1_G0_TX_DP<2>")
	)
	(segment
		(start 105.605326 -203.425044)
		(end 150.996396 -180.348382)
		(width 0.14224)
		(layer "In2.Cu")
		(net "GMI_CPU0_G2_CPU1_G0_TX_DP<2>")
	)
	(segment
		(start 150.996396 -180.348382)
		(end 160.968436 -176.14138)
		(width 0.14224)
		(layer "In2.Cu")
		(net "GMI_CPU0_G2_CPU1_G0_TX_DP<2>")
	)
	(segment
		(start 327.128378 -184.071514)
		(end 359.032556 -202.942444)
		(width 0.14224)
		(layer "In2.Cu")
		(net "GMI_CPU0_G2_CPU1_G0_TX_DP<2>")
	)
	(segment
		(start 373.666766 -226.318826)
		(end 373.62765 -226.341686)
		(width 0.1143)
		(layer "In2.Cu")
		(net "GMI_CPU0_G2_CPU1_G0_TX_DP<2>")
	)
	(segment
		(start 373.439944 -221.545658)
		(end 373.440198 -221.545912)
		(width 0.1143)
		(layer "In2.Cu")
		(net "GMI_CPU0_G2_CPU1_G0_TX_DP<2>")
	)
	(segment
		(start 373.666766 -224.698814)
		(end 373.62765 -224.721674)
		(width 0.1143)
		(layer "In2.Cu")
		(net "GMI_CPU0_G2_CPU1_G0_TX_DP<2>")
	)
	(segment
		(start 373.440198 -221.545912)
		(end 373.440198 -221.80423)
		(width 0.1143)
		(layer "In2.Cu")
		(net "GMI_CPU0_G2_CPU1_G0_TX_DP<2>")
	)
	(segment
		(start 310.12892 -176.088802)
		(end 312.712862 -177.07229)
		(width 0.14224)
		(layer "In2.Cu")
		(net "GMI_CPU0_G2_CPU1_G0_TX_DP<2>")
	)
	(segment
		(start 97.978976 -226.66452)
		(end 98.048826 -226.59467)
		(width 0.1143)
		(layer "In2.Cu")
		(net "GMI_CPU0_G2_CPU1_G0_TX_DP<2>")
	)
	(segment
		(start 373.485664 -221.202758)
		(end 373.439944 -221.248478)
		(width 0.1143)
		(layer "In2.Cu")
		(net "GMI_CPU0_G2_CPU1_G0_TX_DP<2>")
	)
	(segment
		(start 97.681034 -226.66452)
		(end 97.978976 -226.66452)
		(width 0.1143)
		(layer "In2.Cu")
		(net "GMI_CPU0_G2_CPU1_G0_TX_DP<2>")
	)
	(segment
		(start 164.341556 -175.17872)
		(end 234.888786 -172.649896)
		(width 0.14224)
		(layer "In2.Cu")
		(net "GMI_CPU0_G2_CPU1_G0_TX_DP<2>")
	)
	(segment
		(start 373.447056 -226.594416)
		(end 373.516906 -226.664266)
		(width 0.1143)
		(layer "In2.Cu")
		(net "GMI_CPU0_G2_CPU1_G0_TX_DP<2>")
	)
	(segment
		(start 365.925862 -207.607916)
		(end 370.953792 -211.9884)
		(width 0.14224)
		(layer "In2.Cu")
		(net "GMI_CPU0_G2_CPU1_G0_TX_DP<2>")
	)
	(segment
		(start 234.888786 -172.649896)
		(end 306.35575 -175.109886)
		(width 0.14224)
		(layer "In2.Cu")
		(net "GMI_CPU0_G2_CPU1_G0_TX_DP<2>")
	)
	(segment
		(start 97.867978 -225.367088)
		(end 97.899728 -225.3488)
		(width 0.1143)
		(layer "In2.Cu")
		(net "GMI_CPU0_G2_CPU1_G0_TX_DP<2>")
	)
	(segment
		(start 97.11563 -221.804484)
		(end 97.115884 -221.80423)
		(width 0.1143)
		(layer "In2.Cu")
		(net "GMI_CPU0_G2_CPU1_G0_TX_DP<2>")
	)
	(segment
		(start 97.831656 -225.38817)
		(end 97.867978 -225.367088)
		(width 0.1143)
		(layer "In2.Cu")
		(net "GMI_CPU0_G2_CPU1_G0_TX_DP<2>")
	)
	(segment
		(start 97.408492 -222.298006)
		(end 97.358962 -222.26905)
		(width 0.1143)
		(layer "In2.Cu")
		(net "GMI_CPU0_G2_CPU1_G0_TX_DP<2>")
	)
	(arc
		(start 373.666766 -223.769682)
		(mid 373.910093 -224.234248)
		(end 373.666766 -224.698814)
		(width 0.1143)
		(layer "In2.Cu")
		(net "GMI_CPU0_G2_CPU1_G0_TX_DP<2>")
	)
	(arc
		(start 373.440198 -221.80423)
		(mid 373.481747 -221.975652)
		(end 373.59717 -222.10903)
		(width 0.1143)
		(layer "In2.Cu")
		(net "GMI_CPU0_G2_CPU1_G0_TX_DP<2>")
	)
	(arc
		(start 373.59717 -223.119442)
		(mid 373.440193 -223.424242)
		(end 373.59717 -223.729042)
		(width 0.1143)
		(layer "In2.Cu")
		(net "GMI_CPU0_G2_CPU1_G0_TX_DP<2>")
	)
	(arc
		(start 97.8154 -225.3996)
		(mid 97.823478 -225.393814)
		(end 97.831656 -225.38817)
		(width 0.1143)
		(layer "In2.Cu")
		(net "GMI_CPU0_G2_CPU1_G0_TX_DP<2>")
	)
	(arc
		(start 97.867978 -223.101916)
		(mid 97.668986 -222.902287)
		(end 97.596198 -222.629984)
		(width 0.1143)
		(layer "In2.Cu")
		(net "GMI_CPU0_G2_CPU1_G0_TX_DP<2>")
	)
	(arc
		(start 373.666766 -222.14967)
		(mid 373.910093 -222.614236)
		(end 373.666766 -223.078802)
		(width 0.1143)
		(layer "In2.Cu")
		(net "GMI_CPU0_G2_CPU1_G0_TX_DP<2>")
	)
	(arc
		(start 373.666766 -225.389694)
		(mid 373.910093 -225.85426)
		(end 373.666766 -226.318826)
		(width 0.1143)
		(layer "In2.Cu")
		(net "GMI_CPU0_G2_CPU1_G0_TX_DP<2>")
	)
	(arc
		(start 97.899728 -225.3488)
		(mid 98.055656 -225.044508)
		(end 97.899728 -224.740216)
		(width 0.1143)
		(layer "In2.Cu")
		(net "GMI_CPU0_G2_CPU1_G0_TX_DP<2>")
	)
	(arc
		(start 373.59717 -224.739454)
		(mid 373.440193 -225.044254)
		(end 373.59717 -225.349054)
		(width 0.1143)
		(layer "In2.Cu")
		(net "GMI_CPU0_G2_CPU1_G0_TX_DP<2>")
	)
	(arc
		(start 97.358962 -222.26905)
		(mid 97.180149 -222.0667)
		(end 97.11563 -221.804484)
		(width 0.1143)
		(layer "In2.Cu")
		(net "GMI_CPU0_G2_CPU1_G0_TX_DP<2>")
	)
	(arc
		(start 97.596198 -222.622872)
		(mid 97.545892 -222.435284)
		(end 97.408492 -222.298006)
		(width 0.1143)
		(layer "In2.Cu")
		(net "GMI_CPU0_G2_CPU1_G0_TX_DP<2>")
	)
	(arc
		(start 373.59717 -226.359466)
		(mid 373.499405 -226.462442)
		(end 373.447056 -226.594416)
		(width 0.1143)
		(layer "In2.Cu")
		(net "GMI_CPU0_G2_CPU1_G0_TX_DP<2>")
	)
	(arc
		(start 97.831656 -226.320858)
		(mid 97.823478 -226.315215)
		(end 97.8154 -226.309428)
		(width 0.1143)
		(layer "In2.Cu")
		(net "GMI_CPU0_G2_CPU1_G0_TX_DP<2>")
	)
	(arc
		(start 97.816416 -223.778826)
		(mid 97.823992 -223.77343)
		(end 97.831656 -223.768158)
		(width 0.1143)
		(layer "In2.Cu")
		(net "GMI_CPU0_G2_CPU1_G0_TX_DP<2>")
	)
	(arc
		(start 97.899728 -223.728788)
		(mid 98.055656 -223.424496)
		(end 97.899728 -223.120204)
		(width 0.1143)
		(layer "In2.Cu")
		(net "GMI_CPU0_G2_CPU1_G0_TX_DP<2>")
	)
	(arc
		(start 97.816416 -224.690178)
		(mid 97.591245 -224.234502)
		(end 97.816416 -223.778826)
		(width 0.1143)
		(layer "In2.Cu")
		(net "GMI_CPU0_G2_CPU1_G0_TX_DP<2>")
	)
	(arc
		(start 97.8154 -226.309428)
		(mid 97.592516 -225.854514)
		(end 97.8154 -225.3996)
		(width 0.1143)
		(layer "In2.Cu")
		(net "GMI_CPU0_G2_CPU1_G0_TX_DP<2>")
	)
	(arc
		(start 97.831656 -224.700846)
		(mid 97.823992 -224.695575)
		(end 97.816416 -224.690178)
		(width 0.1143)
		(layer "In2.Cu")
		(net "GMI_CPU0_G2_CPU1_G0_TX_DP<2>")
	)
	(arc
		(start 98.048826 -226.59467)
		(mid 97.996777 -226.463151)
		(end 97.899728 -226.360228)
		(width 0.1143)
		(layer "In2.Cu")
		(net "GMI_CPU0_G2_CPU1_G0_TX_DP<2>")
	)
	(segment
		(start 98.147886 -228.55047)
		(end 97.681034 -228.284532)
		(width 0.12954)
		(layer "F.Cu")
		(net "GMI_CPU0_G2_CPU1_G0_TX_DP<1>")
	)
	(segment
		(start 373.347996 -228.550216)
		(end 373.814848 -228.284278)
		(width 0.12954)
		(layer "F.Cu")
		(net "GMI_CPU0_G2_CPU1_G0_TX_DP<1>")
	)
	(segment
		(start 98.768916 -225.389948)
		(end 98.807016 -225.367596)
		(width 0.1143)
		(layer "In2.Cu")
		(net "GMI_CPU0_G2_CPU1_G0_TX_DP<1>")
	)
	(segment
		(start 98.807016 -226.987608)
		(end 98.808032 -226.9871)
		(width 0.1143)
		(layer "In2.Cu")
		(net "GMI_CPU0_G2_CPU1_G0_TX_DP<1>")
	)
	(segment
		(start 98.814636 -223.105726)
		(end 98.813874 -223.105218)
		(width 0.1143)
		(layer "In2.Cu")
		(net "GMI_CPU0_G2_CPU1_G0_TX_DP<1>")
	)
	(segment
		(start 373.190008 -227.815648)
		(end 373.196866 -227.819712)
		(width 0.1143)
		(layer "In2.Cu")
		(net "GMI_CPU0_G2_CPU1_G0_TX_DP<1>")
	)
	(segment
		(start 98.807016 -224.72142)
		(end 98.776536 -224.70364)
		(width 0.1143)
		(layer "In2.Cu")
		(net "GMI_CPU0_G2_CPU1_G0_TX_DP<1>")
	)
	(segment
		(start 161.21888 -177.04816)
		(end 164.471858 -176.11979)
		(width 0.14224)
		(layer "In2.Cu")
		(net "GMI_CPU0_G2_CPU1_G0_TX_DP<1>")
	)
	(segment
		(start 372.754652 -224.679002)
		(end 372.726966 -224.699068)
		(width 0.1143)
		(layer "In2.Cu")
		(net "GMI_CPU0_G2_CPU1_G0_TX_DP<1>")
	)
	(segment
		(start 98.055938 -221.706948)
		(end 98.04019 -221.6912)
		(width 0.1143)
		(layer "In2.Cu")
		(net "GMI_CPU0_G2_CPU1_G0_TX_DP<1>")
	)
	(segment
		(start 372.500144 -221.545912)
		(end 372.500144 -221.80423)
		(width 0.1143)
		(layer "In2.Cu")
		(net "GMI_CPU0_G2_CPU1_G0_TX_DP<1>")
	)
	(segment
		(start 97.681034 -228.284532)
		(end 97.978976 -228.284532)
		(width 0.1143)
		(layer "In2.Cu")
		(net "GMI_CPU0_G2_CPU1_G0_TX_DP<1>")
	)
	(segment
		(start 98.775774 -224.703132)
		(end 98.768916 -224.699068)
		(width 0.1143)
		(layer "In2.Cu")
		(net "GMI_CPU0_G2_CPU1_G0_TX_DP<1>")
	)
	(segment
		(start 98.808032 -226.9871)
		(end 98.808794 -226.986592)
		(width 0.1143)
		(layer "In2.Cu")
		(net "GMI_CPU0_G2_CPU1_G0_TX_DP<1>")
	)
	(segment
		(start 98.839782 -226.360228)
		(end 98.818446 -226.347782)
		(width 0.1143)
		(layer "In2.Cu")
		(net "GMI_CPU0_G2_CPU1_G0_TX_DP<1>")
	)
	(segment
		(start 106.36504 -204.184758)
		(end 151.591772 -181.10962)
		(width 0.14224)
		(layer "In2.Cu")
		(net "GMI_CPU0_G2_CPU1_G0_TX_DP<1>")
	)
	(segment
		(start 98.813874 -223.105218)
		(end 98.81235 -223.104456)
		(width 0.1143)
		(layer "In2.Cu")
		(net "GMI_CPU0_G2_CPU1_G0_TX_DP<1>")
	)
	(segment
		(start 372.49989 -221.545658)
		(end 372.500144 -221.545912)
		(width 0.1143)
		(layer "In2.Cu")
		(net "GMI_CPU0_G2_CPU1_G0_TX_DP<1>")
	)
	(segment
		(start 373.156988 -227.796344)
		(end 373.15775 -227.796852)
		(width 0.1143)
		(layer "In2.Cu")
		(net "GMI_CPU0_G2_CPU1_G0_TX_DP<1>")
	)
	(segment
		(start 372.54561 -217.78341)
		(end 372.54561 -221.17431)
		(width 0.14224)
		(layer "In2.Cu")
		(net "GMI_CPU0_G2_CPU1_G0_TX_DP<1>")
	)
	(segment
		(start 98.807016 -225.367596)
		(end 98.808032 -225.367088)
		(width 0.1143)
		(layer "In2.Cu")
		(net "GMI_CPU0_G2_CPU1_G0_TX_DP<1>")
	)
	(segment
		(start 98.811588 -224.72396)
		(end 98.810064 -224.723198)
		(width 0.1143)
		(layer "In2.Cu")
		(net "GMI_CPU0_G2_CPU1_G0_TX_DP<1>")
	)
	(segment
		(start 98.338132 -227.797106)
		(end 98.368612 -227.779326)
		(width 0.1143)
		(layer "In2.Cu")
		(net "GMI_CPU0_G2_CPU1_G0_TX_DP<1>")
	)
	(segment
		(start 98.775774 -226.323144)
		(end 98.768916 -226.31908)
		(width 0.1143)
		(layer "In2.Cu")
		(net "GMI_CPU0_G2_CPU1_G0_TX_DP<1>")
	)
	(segment
		(start 97.99447 -212.555328)
		(end 106.36504 -204.184758)
		(width 0.14224)
		(layer "In2.Cu")
		(net "GMI_CPU0_G2_CPU1_G0_TX_DP<1>")
	)
	(segment
		(start 98.808794 -226.986592)
		(end 98.810064 -226.98583)
		(width 0.1143)
		(layer "In2.Cu")
		(net "GMI_CPU0_G2_CPU1_G0_TX_DP<1>")
	)
	(segment
		(start 372.68785 -223.101662)
		(end 372.6561 -223.11995)
		(width 0.1143)
		(layer "In2.Cu")
		(net "GMI_CPU0_G2_CPU1_G0_TX_DP<1>")
	)
	(segment
		(start 98.808032 -223.101916)
		(end 98.807016 -223.101408)
		(width 0.1143)
		(layer "In2.Cu")
		(net "GMI_CPU0_G2_CPU1_G0_TX_DP<1>")
	)
	(segment
		(start 373.158766 -227.79736)
		(end 373.189246 -227.81514)
		(width 0.1143)
		(layer "In2.Cu")
		(net "GMI_CPU0_G2_CPU1_G0_TX_DP<1>")
	)
	(segment
		(start 372.982744 -227.483924)
		(end 372.982744 -227.49637)
		(width 0.1143)
		(layer "In2.Cu")
		(net "GMI_CPU0_G2_CPU1_G0_TX_DP<1>")
	)
	(segment
		(start 98.04019 -221.6912)
		(end 98.04019 -221.248732)
		(width 0.1143)
		(layer "In2.Cu")
		(net "GMI_CPU0_G2_CPU1_G0_TX_DP<1>")
	)
	(segment
		(start 98.808032 -225.367088)
		(end 98.808794 -225.36658)
		(width 0.1143)
		(layer "In2.Cu")
		(net "GMI_CPU0_G2_CPU1_G0_TX_DP<1>")
	)
	(segment
		(start 97.99447 -221.174564)
		(end 97.99447 -212.555328)
		(width 0.14224)
		(layer "In2.Cu")
		(net "GMI_CPU0_G2_CPU1_G0_TX_DP<1>")
	)
	(segment
		(start 98.055938 -221.804484)
		(end 98.055938 -221.706948)
		(width 0.1143)
		(layer "In2.Cu")
		(net "GMI_CPU0_G2_CPU1_G0_TX_DP<1>")
	)
	(segment
		(start 309.89397 -177.035968)
		(end 312.174382 -177.903886)
		(width 0.14224)
		(layer "In2.Cu")
		(net "GMI_CPU0_G2_CPU1_G0_TX_DP<1>")
	)
	(segment
		(start 98.81235 -223.744536)
		(end 98.839782 -223.728788)
		(width 0.1143)
		(layer "In2.Cu")
		(net "GMI_CPU0_G2_CPU1_G0_TX_DP<1>")
	)
	(segment
		(start 97.978976 -228.284532)
		(end 98.06178 -228.201728)
		(width 0.1143)
		(layer "In2.Cu")
		(net "GMI_CPU0_G2_CPU1_G0_TX_DP<1>")
	)
	(segment
		(start 98.818446 -226.347782)
		(end 98.815906 -226.346512)
		(width 0.1143)
		(layer "In2.Cu")
		(net "GMI_CPU0_G2_CPU1_G0_TX_DP<1>")
	)
	(segment
		(start 98.808032 -223.747076)
		(end 98.808794 -223.746568)
		(width 0.1143)
		(layer "In2.Cu")
		(net "GMI_CPU0_G2_CPU1_G0_TX_DP<1>")
	)
	(segment
		(start 373.189246 -227.81514)
		(end 373.190008 -227.815648)
		(width 0.1143)
		(layer "In2.Cu")
		(net "GMI_CPU0_G2_CPU1_G0_TX_DP<1>")
	)
	(segment
		(start 98.808032 -224.721928)
		(end 98.807016 -224.72142)
		(width 0.1143)
		(layer "In2.Cu")
		(net "GMI_CPU0_G2_CPU1_G0_TX_DP<1>")
	)
	(segment
		(start 98.808794 -224.722436)
		(end 98.808032 -224.721928)
		(width 0.1143)
		(layer "In2.Cu")
		(net "GMI_CPU0_G2_CPU1_G0_TX_DP<1>")
	)
	(segment
		(start 98.813874 -226.345242)
		(end 98.81235 -226.34448)
		(width 0.1143)
		(layer "In2.Cu")
		(net "GMI_CPU0_G2_CPU1_G0_TX_DP<1>")
	)
	(segment
		(start 98.810064 -224.723198)
		(end 98.808794 -224.722436)
		(width 0.1143)
		(layer "In2.Cu")
		(net "GMI_CPU0_G2_CPU1_G0_TX_DP<1>")
	)
	(segment
		(start 370.194332 -212.61578)
		(end 372.54561 -217.78341)
		(width 0.14224)
		(layer "In2.Cu")
		(net "GMI_CPU0_G2_CPU1_G0_TX_DP<1>")
	)
	(segment
		(start 98.768916 -227.00996)
		(end 98.807016 -226.987608)
		(width 0.1143)
		(layer "In2.Cu")
		(net "GMI_CPU0_G2_CPU1_G0_TX_DP<1>")
	)
	(segment
		(start 98.807016 -226.341432)
		(end 98.776536 -226.323652)
		(width 0.1143)
		(layer "In2.Cu")
		(net "GMI_CPU0_G2_CPU1_G0_TX_DP<1>")
	)
	(segment
		(start 98.807016 -223.747584)
		(end 98.808032 -223.747076)
		(width 0.1143)
		(layer "In2.Cu")
		(net "GMI_CPU0_G2_CPU1_G0_TX_DP<1>")
	)
	(segment
		(start 98.839782 -224.740216)
		(end 98.818446 -224.72777)
		(width 0.1143)
		(layer "In2.Cu")
		(net "GMI_CPU0_G2_CPU1_G0_TX_DP<1>")
	)
	(segment
		(start 98.808032 -226.34194)
		(end 98.807016 -226.341432)
		(width 0.1143)
		(layer "In2.Cu")
		(net "GMI_CPU0_G2_CPU1_G0_TX_DP<1>")
	)
	(segment
		(start 98.813874 -224.72523)
		(end 98.81235 -224.724468)
		(width 0.1143)
		(layer "In2.Cu")
		(net "GMI_CPU0_G2_CPU1_G0_TX_DP<1>")
	)
	(segment
		(start 98.81235 -226.34448)
		(end 98.811588 -226.343972)
		(width 0.1143)
		(layer "In2.Cu")
		(net "GMI_CPU0_G2_CPU1_G0_TX_DP<1>")
	)
	(segment
		(start 372.688104 -223.747076)
		(end 372.726966 -223.769428)
		(width 0.1143)
		(layer "In2.Cu")
		(net "GMI_CPU0_G2_CPU1_G0_TX_DP<1>")
	)
	(segment
		(start 373.15775 -227.796852)
		(end 373.158766 -227.79736)
		(width 0.1143)
		(layer "In2.Cu")
		(net "GMI_CPU0_G2_CPU1_G0_TX_DP<1>")
	)
	(segment
		(start 98.815906 -223.106488)
		(end 98.814636 -223.105726)
		(width 0.1143)
		(layer "In2.Cu")
		(net "GMI_CPU0_G2_CPU1_G0_TX_DP<1>")
	)
	(segment
		(start 372.6561 -222.108522)
		(end 372.68785 -222.12681)
		(width 0.1143)
		(layer "In2.Cu")
		(net "GMI_CPU0_G2_CPU1_G0_TX_DP<1>")
	)
	(segment
		(start 98.808794 -225.36658)
		(end 98.810064 -225.365818)
		(width 0.1143)
		(layer "In2.Cu")
		(net "GMI_CPU0_G2_CPU1_G0_TX_DP<1>")
	)
	(segment
		(start 372.724172 -223.08058)
		(end 372.68785 -223.101662)
		(width 0.1143)
		(layer "In2.Cu")
		(net "GMI_CPU0_G2_CPU1_G0_TX_DP<1>")
	)
	(segment
		(start 98.808794 -223.102424)
		(end 98.808032 -223.101916)
		(width 0.1143)
		(layer "In2.Cu")
		(net "GMI_CPU0_G2_CPU1_G0_TX_DP<1>")
	)
	(segment
		(start 164.471858 -176.11979)
		(end 234.961938 -173.592998)
		(width 0.14224)
		(layer "In2.Cu")
		(net "GMI_CPU0_G2_CPU1_G0_TX_DP<1>")
	)
	(segment
		(start 373.153686 -227.79482)
		(end 373.154194 -227.795074)
		(width 0.1143)
		(layer "In2.Cu")
		(net "GMI_CPU0_G2_CPU1_G0_TX_DP<1>")
	)
	(segment
		(start 358.371394 -203.666598)
		(end 365.319564 -208.3689)
		(width 0.14224)
		(layer "In2.Cu")
		(net "GMI_CPU0_G2_CPU1_G0_TX_DP<1>")
	)
	(segment
		(start 373.434102 -228.201474)
		(end 373.516906 -228.284278)
		(width 0.1143)
		(layer "In2.Cu")
		(net "GMI_CPU0_G2_CPU1_G0_TX_DP<1>")
	)
	(segment
		(start 98.81235 -223.104456)
		(end 98.811588 -223.103948)
		(width 0.1143)
		(layer "In2.Cu")
		(net "GMI_CPU0_G2_CPU1_G0_TX_DP<1>")
	)
	(segment
		(start 97.99447 -221.203012)
		(end 97.99447 -221.174564)
		(width 0.1143)
		(layer "In2.Cu")
		(net "GMI_CPU0_G2_CPU1_G0_TX_DP<1>")
	)
	(segment
		(start 98.810064 -226.34321)
		(end 98.808794 -226.342448)
		(width 0.1143)
		(layer "In2.Cu")
		(net "GMI_CPU0_G2_CPU1_G0_TX_DP<1>")
	)
	(segment
		(start 98.368612 -222.30969)
		(end 98.338132 -222.29191)
		(width 0.1143)
		(layer "In2.Cu")
		(net "GMI_CPU0_G2_CPU1_G0_TX_DP<1>")
	)
	(segment
		(start 98.814636 -226.34575)
		(end 98.813874 -226.345242)
		(width 0.1143)
		(layer "In2.Cu")
		(net "GMI_CPU0_G2_CPU1_G0_TX_DP<1>")
	)
	(segment
		(start 326.39127 -184.751218)
		(end 358.371394 -203.666598)
		(width 0.14224)
		(layer "In2.Cu")
		(net "GMI_CPU0_G2_CPU1_G0_TX_DP<1>")
	)
	(segment
		(start 373.516906 -228.284278)
		(end 373.814848 -228.284278)
		(width 0.1143)
		(layer "In2.Cu")
		(net "GMI_CPU0_G2_CPU1_G0_TX_DP<1>")
	)
	(segment
		(start 372.54561 -221.202758)
		(end 372.49989 -221.248478)
		(width 0.1143)
		(layer "In2.Cu")
		(net "GMI_CPU0_G2_CPU1_G0_TX_DP<1>")
	)
	(segment
		(start 372.6561 -223.72828)
		(end 372.672102 -223.737424)
		(width 0.1143)
		(layer "In2.Cu")
		(net "GMI_CPU0_G2_CPU1_G0_TX_DP<1>")
	)
	(segment
		(start 98.807016 -223.101408)
		(end 98.776536 -223.083628)
		(width 0.1143)
		(layer "In2.Cu")
		(net "GMI_CPU0_G2_CPU1_G0_TX_DP<1>")
	)
	(segment
		(start 372.54561 -221.17431)
		(end 372.54561 -221.202758)
		(width 0.1143)
		(layer "In2.Cu")
		(net "GMI_CPU0_G2_CPU1_G0_TX_DP<1>")
	)
	(segment
		(start 373.154194 -227.795074)
		(end 373.156988 -227.796344)
		(width 0.1143)
		(layer "In2.Cu")
		(net "GMI_CPU0_G2_CPU1_G0_TX_DP<1>")
	)
	(segment
		(start 234.961938 -173.592998)
		(end 306.05603 -176.040288)
		(width 0.14224)
		(layer "In2.Cu")
		(net "GMI_CPU0_G2_CPU1_G0_TX_DP<1>")
	)
	(segment
		(start 98.810064 -225.365818)
		(end 98.839782 -225.3488)
		(width 0.1143)
		(layer "In2.Cu")
		(net "GMI_CPU0_G2_CPU1_G0_TX_DP<1>")
	)
	(segment
		(start 372.6561 -223.728534)
		(end 372.6561 -223.72828)
		(width 0.1143)
		(layer "In2.Cu")
		(net "GMI_CPU0_G2_CPU1_G0_TX_DP<1>")
	)
	(segment
		(start 98.810064 -223.103186)
		(end 98.808794 -223.102424)
		(width 0.1143)
		(layer "In2.Cu")
		(net "GMI_CPU0_G2_CPU1_G0_TX_DP<1>")
	)
	(segment
		(start 98.811588 -223.745044)
		(end 98.81235 -223.744536)
		(width 0.1143)
		(layer "In2.Cu")
		(net "GMI_CPU0_G2_CPU1_G0_TX_DP<1>")
	)
	(segment
		(start 98.810064 -226.98583)
		(end 98.839782 -226.968812)
		(width 0.1143)
		(layer "In2.Cu")
		(net "GMI_CPU0_G2_CPU1_G0_TX_DP<1>")
	)
	(segment
		(start 98.81235 -224.724468)
		(end 98.811588 -224.72396)
		(width 0.1143)
		(layer "In2.Cu")
		(net "GMI_CPU0_G2_CPU1_G0_TX_DP<1>")
	)
	(segment
		(start 372.68785 -226.341686)
		(end 372.6561 -226.359974)
		(width 0.1143)
		(layer "In2.Cu")
		(net "GMI_CPU0_G2_CPU1_G0_TX_DP<1>")
	)
	(segment
		(start 98.808794 -226.342448)
		(end 98.808032 -226.34194)
		(width 0.1143)
		(layer "In2.Cu")
		(net "GMI_CPU0_G2_CPU1_G0_TX_DP<1>")
	)
	(segment
		(start 372.68785 -222.12681)
		(end 372.724172 -222.147892)
		(width 0.1143)
		(layer "In2.Cu")
		(net "GMI_CPU0_G2_CPU1_G0_TX_DP<1>")
	)
	(segment
		(start 98.815906 -226.346512)
		(end 98.814636 -226.34575)
		(width 0.1143)
		(layer "In2.Cu")
		(net "GMI_CPU0_G2_CPU1_G0_TX_DP<1>")
	)
	(segment
		(start 98.776536 -223.083628)
		(end 98.775774 -223.08312)
		(width 0.1143)
		(layer "In2.Cu")
		(net "GMI_CPU0_G2_CPU1_G0_TX_DP<1>")
	)
	(segment
		(start 98.839782 -223.120204)
		(end 98.818446 -223.107758)
		(width 0.1143)
		(layer "In2.Cu")
		(net "GMI_CPU0_G2_CPU1_G0_TX_DP<1>")
	)
	(segment
		(start 98.814636 -224.725738)
		(end 98.813874 -224.72523)
		(width 0.1143)
		(layer "In2.Cu")
		(net "GMI_CPU0_G2_CPU1_G0_TX_DP<1>")
	)
	(segment
		(start 372.672102 -223.737424)
		(end 372.688104 -223.747076)
		(width 0.1143)
		(layer "In2.Cu")
		(net "GMI_CPU0_G2_CPU1_G0_TX_DP<1>")
	)
	(segment
		(start 372.726966 -224.699068)
		(end 372.6561 -224.739962)
		(width 0.1143)
		(layer "In2.Cu")
		(net "GMI_CPU0_G2_CPU1_G0_TX_DP<1>")
	)
	(segment
		(start 98.776536 -224.70364)
		(end 98.775774 -224.703132)
		(width 0.1143)
		(layer "In2.Cu")
		(net "GMI_CPU0_G2_CPU1_G0_TX_DP<1>")
	)
	(segment
		(start 98.818446 -224.72777)
		(end 98.815906 -224.7265)
		(width 0.1143)
		(layer "In2.Cu")
		(net "GMI_CPU0_G2_CPU1_G0_TX_DP<1>")
	)
	(segment
		(start 312.174382 -177.903886)
		(end 326.39127 -184.751218)
		(width 0.14224)
		(layer "In2.Cu")
		(net "GMI_CPU0_G2_CPU1_G0_TX_DP<1>")
	)
	(segment
		(start 98.776536 -226.323652)
		(end 98.775774 -226.323144)
		(width 0.1143)
		(layer "In2.Cu")
		(net "GMI_CPU0_G2_CPU1_G0_TX_DP<1>")
	)
	(segment
		(start 98.818446 -223.107758)
		(end 98.815906 -223.106488)
		(width 0.1143)
		(layer "In2.Cu")
		(net "GMI_CPU0_G2_CPU1_G0_TX_DP<1>")
	)
	(segment
		(start 98.775774 -223.08312)
		(end 98.768916 -223.079056)
		(width 0.1143)
		(layer "In2.Cu")
		(net "GMI_CPU0_G2_CPU1_G0_TX_DP<1>")
	)
	(segment
		(start 372.6561 -226.968304)
		(end 372.700042 -226.994212)
		(width 0.1143)
		(layer "In2.Cu")
		(net "GMI_CPU0_G2_CPU1_G0_TX_DP<1>")
	)
	(segment
		(start 306.05603 -176.040288)
		(end 309.89397 -177.035968)
		(width 0.14224)
		(layer "In2.Cu")
		(net "GMI_CPU0_G2_CPU1_G0_TX_DP<1>")
	)
	(segment
		(start 98.04019 -221.248732)
		(end 97.99447 -221.203012)
		(width 0.1143)
		(layer "In2.Cu")
		(net "GMI_CPU0_G2_CPU1_G0_TX_DP<1>")
	)
	(segment
		(start 98.338132 -222.29191)
		(end 98.30054 -222.270066)
		(width 0.1143)
		(layer "In2.Cu")
		(net "GMI_CPU0_G2_CPU1_G0_TX_DP<1>")
	)
	(segment
		(start 372.68785 -225.366834)
		(end 372.724172 -225.387916)
		(width 0.1143)
		(layer "In2.Cu")
		(net "GMI_CPU0_G2_CPU1_G0_TX_DP<1>")
	)
	(segment
		(start 98.299016 -227.819966)
		(end 98.338132 -227.797106)
		(width 0.1143)
		(layer "In2.Cu")
		(net "GMI_CPU0_G2_CPU1_G0_TX_DP<1>")
	)
	(segment
		(start 372.49989 -221.248478)
		(end 372.49989 -221.545658)
		(width 0.1143)
		(layer "In2.Cu")
		(net "GMI_CPU0_G2_CPU1_G0_TX_DP<1>")
	)
	(segment
		(start 151.591772 -181.10962)
		(end 161.21888 -177.04816)
		(width 0.14224)
		(layer "In2.Cu")
		(net "GMI_CPU0_G2_CPU1_G0_TX_DP<1>")
	)
	(segment
		(start 98.811588 -226.343972)
		(end 98.810064 -226.34321)
		(width 0.1143)
		(layer "In2.Cu")
		(net "GMI_CPU0_G2_CPU1_G0_TX_DP<1>")
	)
	(segment
		(start 98.768916 -223.769936)
		(end 98.805492 -223.7486)
		(width 0.1143)
		(layer "In2.Cu")
		(net "GMI_CPU0_G2_CPU1_G0_TX_DP<1>")
	)
	(segment
		(start 372.724172 -226.320604)
		(end 372.68785 -226.341686)
		(width 0.1143)
		(layer "In2.Cu")
		(net "GMI_CPU0_G2_CPU1_G0_TX_DP<1>")
	)
	(segment
		(start 98.811588 -223.103948)
		(end 98.810064 -223.103186)
		(width 0.1143)
		(layer "In2.Cu")
		(net "GMI_CPU0_G2_CPU1_G0_TX_DP<1>")
	)
	(segment
		(start 365.319564 -208.3689)
		(end 370.194332 -212.61578)
		(width 0.14224)
		(layer "In2.Cu")
		(net "GMI_CPU0_G2_CPU1_G0_TX_DP<1>")
	)
	(segment
		(start 372.726966 -223.769428)
		(end 372.754652 -223.789494)
		(width 0.1143)
		(layer "In2.Cu")
		(net "GMI_CPU0_G2_CPU1_G0_TX_DP<1>")
	)
	(segment
		(start 372.6561 -225.348546)
		(end 372.68785 -225.366834)
		(width 0.1143)
		(layer "In2.Cu")
		(net "GMI_CPU0_G2_CPU1_G0_TX_DP<1>")
	)
	(segment
		(start 98.815906 -224.7265)
		(end 98.814636 -224.725738)
		(width 0.1143)
		(layer "In2.Cu")
		(net "GMI_CPU0_G2_CPU1_G0_TX_DP<1>")
	)
	(segment
		(start 98.805492 -223.7486)
		(end 98.807016 -223.747584)
		(width 0.1143)
		(layer "In2.Cu")
		(net "GMI_CPU0_G2_CPU1_G0_TX_DP<1>")
	)
	(segment
		(start 98.808794 -223.746568)
		(end 98.811588 -223.745044)
		(width 0.1143)
		(layer "In2.Cu")
		(net "GMI_CPU0_G2_CPU1_G0_TX_DP<1>")
	)
	(arc
		(start 98.839782 -226.968812)
		(mid 98.99571 -226.66452)
		(end 98.839782 -226.360228)
		(width 0.1143)
		(layer "In2.Cu")
		(net "GMI_CPU0_G2_CPU1_G0_TX_DP<1>")
	)
	(arc
		(start 372.500144 -221.80423)
		(mid 372.541399 -221.975201)
		(end 372.6561 -222.108522)
		(width 0.1143)
		(layer "In2.Cu")
		(net "GMI_CPU0_G2_CPU1_G0_TX_DP<1>")
	)
	(arc
		(start 372.6561 -223.11995)
		(mid 372.500172 -223.424242)
		(end 372.6561 -223.728534)
		(width 0.1143)
		(layer "In2.Cu")
		(net "GMI_CPU0_G2_CPU1_G0_TX_DP<1>")
	)
	(arc
		(start 98.768916 -223.079056)
		(mid 98.590103 -222.876706)
		(end 98.525584 -222.61449)
		(width 0.1143)
		(layer "In2.Cu")
		(net "GMI_CPU0_G2_CPU1_G0_TX_DP<1>")
	)
	(arc
		(start 372.724172 -222.147892)
		(mid 372.731322 -222.15279)
		(end 372.738396 -222.157798)
		(width 0.1143)
		(layer "In2.Cu")
		(net "GMI_CPU0_G2_CPU1_G0_TX_DP<1>")
	)
	(arc
		(start 98.525584 -222.61449)
		(mid 98.484035 -222.443068)
		(end 98.368612 -222.30969)
		(width 0.1143)
		(layer "In2.Cu")
		(net "GMI_CPU0_G2_CPU1_G0_TX_DP<1>")
	)
	(arc
		(start 373.196866 -227.819712)
		(mid 373.355071 -227.985999)
		(end 373.434102 -228.201474)
		(width 0.1143)
		(layer "In2.Cu")
		(net "GMI_CPU0_G2_CPU1_G0_TX_DP<1>")
	)
	(arc
		(start 372.520464 -226.785932)
		(mid 372.5741 -226.887668)
		(end 372.6561 -226.968304)
		(width 0.1143)
		(layer "In2.Cu")
		(net "GMI_CPU0_G2_CPU1_G0_TX_DP<1>")
	)
	(arc
		(start 98.839782 -225.3488)
		(mid 98.99571 -225.044508)
		(end 98.839782 -224.740216)
		(width 0.1143)
		(layer "In2.Cu")
		(net "GMI_CPU0_G2_CPU1_G0_TX_DP<1>")
	)
	(arc
		(start 372.738396 -223.070674)
		(mid 372.731323 -223.075683)
		(end 372.724172 -223.08058)
		(width 0.1143)
		(layer "In2.Cu")
		(net "GMI_CPU0_G2_CPU1_G0_TX_DP<1>")
	)
	(arc
		(start 372.724172 -225.387916)
		(mid 372.731322 -225.392814)
		(end 372.738396 -225.397822)
		(width 0.1143)
		(layer "In2.Cu")
		(net "GMI_CPU0_G2_CPU1_G0_TX_DP<1>")
	)
	(arc
		(start 98.839782 -223.728788)
		(mid 98.99571 -223.424496)
		(end 98.839782 -223.120204)
		(width 0.1143)
		(layer "In2.Cu")
		(net "GMI_CPU0_G2_CPU1_G0_TX_DP<1>")
	)
	(arc
		(start 98.368612 -227.779326)
		(mid 98.484039 -227.64595)
		(end 98.525584 -227.474526)
		(width 0.1143)
		(layer "In2.Cu")
		(net "GMI_CPU0_G2_CPU1_G0_TX_DP<1>")
	)
	(arc
		(start 98.06178 -228.201728)
		(mid 98.063568 -228.190279)
		(end 98.06559 -228.178868)
		(width 0.1143)
		(layer "In2.Cu")
		(net "GMI_CPU0_G2_CPU1_G0_TX_DP<1>")
	)
	(arc
		(start 98.525584 -227.474526)
		(mid 98.590099 -227.212307)
		(end 98.768916 -227.00996)
		(width 0.1143)
		(layer "In2.Cu")
		(net "GMI_CPU0_G2_CPU1_G0_TX_DP<1>")
	)
	(arc
		(start 372.6561 -226.359974)
		(mid 372.517844 -226.550524)
		(end 372.520464 -226.785932)
		(width 0.1143)
		(layer "In2.Cu")
		(net "GMI_CPU0_G2_CPU1_G0_TX_DP<1>")
	)
	(arc
		(start 372.738396 -225.397822)
		(mid 372.965779 -225.85426)
		(end 372.738396 -226.310698)
		(width 0.1143)
		(layer "In2.Cu")
		(net "GMI_CPU0_G2_CPU1_G0_TX_DP<1>")
	)
	(arc
		(start 98.768916 -226.31908)
		(mid 98.525589 -225.854514)
		(end 98.768916 -225.389948)
		(width 0.1143)
		(layer "In2.Cu")
		(net "GMI_CPU0_G2_CPU1_G0_TX_DP<1>")
	)
	(arc
		(start 372.982744 -227.49637)
		(mid 373.02851 -227.668332)
		(end 373.153686 -227.79482)
		(width 0.1143)
		(layer "In2.Cu")
		(net "GMI_CPU0_G2_CPU1_G0_TX_DP<1>")
	)
	(arc
		(start 98.30054 -222.270066)
		(mid 98.120811 -222.067446)
		(end 98.055938 -221.804484)
		(width 0.1143)
		(layer "In2.Cu")
		(net "GMI_CPU0_G2_CPU1_G0_TX_DP<1>")
	)
	(arc
		(start 98.768916 -224.699068)
		(mid 98.525589 -224.234502)
		(end 98.768916 -223.769936)
		(width 0.1143)
		(layer "In2.Cu")
		(net "GMI_CPU0_G2_CPU1_G0_TX_DP<1>")
	)
	(arc
		(start 372.700042 -226.994212)
		(mid 372.90703 -227.201184)
		(end 372.982744 -227.483924)
		(width 0.1143)
		(layer "In2.Cu")
		(net "GMI_CPU0_G2_CPU1_G0_TX_DP<1>")
	)
	(arc
		(start 372.738396 -222.157798)
		(mid 372.965779 -222.614236)
		(end 372.738396 -223.070674)
		(width 0.1143)
		(layer "In2.Cu")
		(net "GMI_CPU0_G2_CPU1_G0_TX_DP<1>")
	)
	(arc
		(start 98.06559 -228.178868)
		(mid 98.147023 -227.97647)
		(end 98.299016 -227.819966)
		(width 0.1143)
		(layer "In2.Cu")
		(net "GMI_CPU0_G2_CPU1_G0_TX_DP<1>")
	)
	(arc
		(start 372.754652 -223.789494)
		(mid 372.982652 -224.234248)
		(end 372.754652 -224.679002)
		(width 0.1143)
		(layer "In2.Cu")
		(net "GMI_CPU0_G2_CPU1_G0_TX_DP<1>")
	)
	(arc
		(start 372.6561 -224.739962)
		(mid 372.500172 -225.044254)
		(end 372.6561 -225.348546)
		(width 0.1143)
		(layer "In2.Cu")
		(net "GMI_CPU0_G2_CPU1_G0_TX_DP<1>")
	)
	(arc
		(start 372.738396 -226.310698)
		(mid 372.731323 -226.315707)
		(end 372.724172 -226.320604)
		(width 0.1143)
		(layer "In2.Cu")
		(net "GMI_CPU0_G2_CPU1_G0_TX_DP<1>")
	)
	(segment
		(start 362.53801 -230.97998)
		(end 363.004862 -230.714296)
		(width 0.12954)
		(layer "F.Cu")
		(net "GMI_CPU0_G2_CPU1_G0_TX_DP<15>")
	)
	(segment
		(start 108.957872 -230.980234)
		(end 108.49102 -230.71455)
		(width 0.12954)
		(layer "F.Cu")
		(net "GMI_CPU0_G2_CPU1_G0_TX_DP<15>")
	)
	(segment
		(start 110.066074 -228.620066)
		(end 110.049056 -228.629972)
		(width 0.1143)
		(layer "In2.Cu")
		(net "GMI_CPU0_G2_CPU1_G0_TX_DP<15>")
	)
	(segment
		(start 362.347764 -230.226616)
		(end 362.347256 -230.226362)
		(width 0.1143)
		(layer "In2.Cu")
		(net "GMI_CPU0_G2_CPU1_G0_TX_DP<15>")
	)
	(segment
		(start 110.998508 -223.084898)
		(end 111.027972 -223.101916)
		(width 0.1143)
		(layer "In2.Cu")
		(net "GMI_CPU0_G2_CPU1_G0_TX_DP<15>")
	)
	(segment
		(start 110.27791 -221.227396)
		(end 110.32363 -221.273116)
		(width 0.1143)
		(layer "In2.Cu")
		(net "GMI_CPU0_G2_CPU1_G0_TX_DP<15>")
	)
	(segment
		(start 361.40771 -228.606858)
		(end 361.37723 -228.589078)
		(width 0.1143)
		(layer "In2.Cu")
		(net "GMI_CPU0_G2_CPU1_G0_TX_DP<15>")
	)
	(segment
		(start 363.004862 -230.714296)
		(end 362.70692 -230.714296)
		(width 0.1143)
		(layer "In2.Cu")
		(net "GMI_CPU0_G2_CPU1_G0_TX_DP<15>")
	)
	(segment
		(start 111.114332 -223.261936)
		(end 111.114332 -227.44811)
		(width 0.1143)
		(layer "In2.Cu")
		(net "GMI_CPU0_G2_CPU1_G0_TX_DP<15>")
	)
	(segment
		(start 360.148378 -226.07397)
		(end 360.148378 -223.066864)
		(width 0.14224)
		(layer "In2.Cu")
		(net "GMI_CPU0_G2_CPU1_G0_TX_DP<15>")
	)
	(segment
		(start 360.148378 -223.066864)
		(end 359.012236 -220.323918)
		(width 0.14224)
		(layer "In2.Cu")
		(net "GMI_CPU0_G2_CPU1_G0_TX_DP<15>")
	)
	(segment
		(start 110.586266 -228.12629)
		(end 110.16488 -228.54793)
		(width 0.1143)
		(layer "In2.Cu")
		(net "GMI_CPU0_G2_CPU1_G0_TX_DP<15>")
	)
	(segment
		(start 360.880152 -227.756212)
		(end 360.513376 -227.38969)
		(width 0.1143)
		(layer "In2.Cu")
		(net "GMI_CPU0_G2_CPU1_G0_TX_DP<15>")
	)
	(segment
		(start 361.881674 -229.418896)
		(end 361.877102 -229.416102)
		(width 0.1143)
		(layer "In2.Cu")
		(net "GMI_CPU0_G2_CPU1_G0_TX_DP<15>")
	)
	(segment
		(start 109.323124 -229.913688)
		(end 109.323124 -229.924102)
		(width 0.1143)
		(layer "In2.Cu")
		(net "GMI_CPU0_G2_CPU1_G0_TX_DP<15>")
	)
	(segment
		(start 362.70692 -230.714296)
		(end 362.624116 -230.631492)
		(width 0.1143)
		(layer "In2.Cu")
		(net "GMI_CPU0_G2_CPU1_G0_TX_DP<15>")
	)
	(segment
		(start 307.170836 -190.72352)
		(end 264.955528 -191.224662)
		(width 0.14224)
		(layer "In2.Cu")
		(net "GMI_CPU0_G2_CPU1_G0_TX_DP<15>")
	)
	(segment
		(start 110.27537 -221.501208)
		(end 110.27537 -221.804484)
		(width 0.1143)
		(layer "In2.Cu")
		(net "GMI_CPU0_G2_CPU1_G0_TX_DP<15>")
	)
	(segment
		(start 208.314798 -190.64732)
		(end 163.326318 -190.780162)
		(width 0.14224)
		(layer "In2.Cu")
		(net "GMI_CPU0_G2_CPU1_G0_TX_DP<15>")
	)
	(segment
		(start 110.32363 -221.452948)
		(end 110.27537 -221.501208)
		(width 0.1143)
		(layer "In2.Cu")
		(net "GMI_CPU0_G2_CPU1_G0_TX_DP<15>")
	)
	(segment
		(start 310.106822 -191.241172)
		(end 307.170836 -190.72352)
		(width 0.14224)
		(layer "In2.Cu")
		(net "GMI_CPU0_G2_CPU1_G0_TX_DP<15>")
	)
	(segment
		(start 109.148118 -230.22687)
		(end 109.111542 -230.248206)
		(width 0.1143)
		(layer "In2.Cu")
		(net "GMI_CPU0_G2_CPU1_G0_TX_DP<15>")
	)
	(segment
		(start 110.27791 -221.198948)
		(end 110.27791 -221.227396)
		(width 0.1143)
		(layer "In2.Cu")
		(net "GMI_CPU0_G2_CPU1_G0_TX_DP<15>")
	)
	(segment
		(start 360.102658 -226.398074)
		(end 360.102658 -226.148138)
		(width 0.1143)
		(layer "In2.Cu")
		(net "GMI_CPU0_G2_CPU1_G0_TX_DP<15>")
	)
	(segment
		(start 111.02848 -223.10217)
		(end 111.062008 -223.135698)
		(width 0.1143)
		(layer "In2.Cu")
		(net "GMI_CPU0_G2_CPU1_G0_TX_DP<15>")
	)
	(segment
		(start 110.995714 -223.08312)
		(end 110.996476 -223.083628)
		(width 0.1143)
		(layer "In2.Cu")
		(net "GMI_CPU0_G2_CPU1_G0_TX_DP<15>")
	)
	(segment
		(start 360.513376 -227.38969)
		(end 360.102658 -226.398074)
		(width 0.1143)
		(layer "In2.Cu")
		(net "GMI_CPU0_G2_CPU1_G0_TX_DP<15>")
	)
	(segment
		(start 111.027972 -223.101916)
		(end 111.02848 -223.10217)
		(width 0.1143)
		(layer "In2.Cu")
		(net "GMI_CPU0_G2_CPU1_G0_TX_DP<15>")
	)
	(segment
		(start 111.114078 -223.26219)
		(end 111.114332 -223.261936)
		(width 0.1143)
		(layer "In2.Cu")
		(net "GMI_CPU0_G2_CPU1_G0_TX_DP<15>")
	)
	(segment
		(start 360.148378 -226.102418)
		(end 360.148378 -226.07397)
		(width 0.1143)
		(layer "In2.Cu")
		(net "GMI_CPU0_G2_CPU1_G0_TX_DP<15>")
	)
	(segment
		(start 110.32363 -221.273116)
		(end 110.32363 -221.452948)
		(width 0.1143)
		(layer "In2.Cu")
		(net "GMI_CPU0_G2_CPU1_G0_TX_DP<15>")
	)
	(segment
		(start 110.066836 -228.619304)
		(end 110.066074 -228.620066)
		(width 0.1143)
		(layer "In2.Cu")
		(net "GMI_CPU0_G2_CPU1_G0_TX_DP<15>")
	)
	(segment
		(start 110.996476 -223.083628)
		(end 110.998508 -223.084898)
		(width 0.1143)
		(layer "In2.Cu")
		(net "GMI_CPU0_G2_CPU1_G0_TX_DP<15>")
	)
	(segment
		(start 110.593886 -222.314262)
		(end 110.596934 -222.31731)
		(width 0.1143)
		(layer "In2.Cu")
		(net "GMI_CPU0_G2_CPU1_G0_TX_DP<15>")
	)
	(segment
		(start 110.088172 -228.606858)
		(end 110.066836 -228.619304)
		(width 0.1143)
		(layer "In2.Cu")
		(net "GMI_CPU0_G2_CPU1_G0_TX_DP<15>")
	)
	(segment
		(start 110.739936 -222.582486)
		(end 110.740952 -222.587058)
		(width 0.1143)
		(layer "In2.Cu")
		(net "GMI_CPU0_G2_CPU1_G0_TX_DP<15>")
	)
	(segment
		(start 362.38434 -230.247952)
		(end 362.347764 -230.226616)
		(width 0.1143)
		(layer "In2.Cu")
		(net "GMI_CPU0_G2_CPU1_G0_TX_DP<15>")
	)
	(segment
		(start 110.586774 -222.308674)
		(end 110.587536 -222.309182)
		(width 0.1143)
		(layer "In2.Cu")
		(net "GMI_CPU0_G2_CPU1_G0_TX_DP<15>")
	)
	(segment
		(start 111.007906 -227.704904)
		(end 110.586266 -228.126544)
		(width 0.1143)
		(layer "In2.Cu")
		(net "GMI_CPU0_G2_CPU1_G0_TX_DP<15>")
	)
	(segment
		(start 361.877102 -229.416102)
		(end 361.844336 -229.397052)
		(width 0.1143)
		(layer "In2.Cu")
		(net "GMI_CPU0_G2_CPU1_G0_TX_DP<15>")
	)
	(segment
		(start 264.955528 -191.224662)
		(end 236.44479 -186.348116)
		(width 0.14224)
		(layer "In2.Cu")
		(net "GMI_CPU0_G2_CPU1_G0_TX_DP<15>")
	)
	(segment
		(start 163.326318 -190.780162)
		(end 114.889026 -215.781382)
		(width 0.14224)
		(layer "In2.Cu")
		(net "GMI_CPU0_G2_CPU1_G0_TX_DP<15>")
	)
	(segment
		(start 114.889026 -215.781382)
		(end 110.27791 -220.392498)
		(width 0.14224)
		(layer "In2.Cu")
		(net "GMI_CPU0_G2_CPU1_G0_TX_DP<15>")
	)
	(segment
		(start 110.517432 -222.268288)
		(end 110.52048 -222.270574)
		(width 0.1143)
		(layer "In2.Cu")
		(net "GMI_CPU0_G2_CPU1_G0_TX_DP<15>")
	)
	(segment
		(start 110.52048 -222.270574)
		(end 110.586774 -222.308674)
		(width 0.1143)
		(layer "In2.Cu")
		(net "GMI_CPU0_G2_CPU1_G0_TX_DP<15>")
	)
	(segment
		(start 108.871766 -230.631746)
		(end 108.788962 -230.71455)
		(width 0.1143)
		(layer "In2.Cu")
		(net "GMI_CPU0_G2_CPU1_G0_TX_DP<15>")
	)
	(segment
		(start 108.788962 -230.71455)
		(end 108.49102 -230.71455)
		(width 0.1143)
		(layer "In2.Cu")
		(net "GMI_CPU0_G2_CPU1_G0_TX_DP<15>")
	)
	(segment
		(start 111.114332 -227.44811)
		(end 111.114078 -227.447856)
		(width 0.1143)
		(layer "In2.Cu")
		(net "GMI_CPU0_G2_CPU1_G0_TX_DP<15>")
	)
	(segment
		(start 355.708966 -217.020648)
		(end 310.106822 -191.241172)
		(width 0.14224)
		(layer "In2.Cu")
		(net "GMI_CPU0_G2_CPU1_G0_TX_DP<15>")
	)
	(segment
		(start 110.586266 -228.126544)
		(end 110.586266 -228.12629)
		(width 0.1143)
		(layer "In2.Cu")
		(net "GMI_CPU0_G2_CPU1_G0_TX_DP<15>")
	)
	(segment
		(start 359.012236 -220.323918)
		(end 355.708966 -217.020648)
		(width 0.14224)
		(layer "In2.Cu")
		(net "GMI_CPU0_G2_CPU1_G0_TX_DP<15>")
	)
	(segment
		(start 109.651546 -229.397306)
		(end 109.604556 -229.424738)
		(width 0.1143)
		(layer "In2.Cu")
		(net "GMI_CPU0_G2_CPU1_G0_TX_DP<15>")
	)
	(segment
		(start 361.446826 -228.629718)
		(end 361.40771 -228.606858)
		(width 0.1143)
		(layer "In2.Cu")
		(net "GMI_CPU0_G2_CPU1_G0_TX_DP<15>")
	)
	(segment
		(start 110.27791 -220.392498)
		(end 110.27791 -221.198948)
		(width 0.14224)
		(layer "In2.Cu")
		(net "GMI_CPU0_G2_CPU1_G0_TX_DP<15>")
	)
	(segment
		(start 236.44479 -186.348116)
		(end 208.314798 -190.64732)
		(width 0.14224)
		(layer "In2.Cu")
		(net "GMI_CPU0_G2_CPU1_G0_TX_DP<15>")
	)
	(segment
		(start 360.102658 -226.148138)
		(end 360.148378 -226.102418)
		(width 0.1143)
		(layer "In2.Cu")
		(net "GMI_CPU0_G2_CPU1_G0_TX_DP<15>")
	)
	(segment
		(start 110.988856 -223.079056)
		(end 110.995714 -223.08312)
		(width 0.1143)
		(layer "In2.Cu")
		(net "GMI_CPU0_G2_CPU1_G0_TX_DP<15>")
	)
	(arc
		(start 109.323124 -229.924102)
		(mid 109.276233 -230.098968)
		(end 109.148118 -230.22687)
		(width 0.1143)
		(layer "In2.Cu")
		(net "GMI_CPU0_G2_CPU1_G0_TX_DP<15>")
	)
	(arc
		(start 361.844336 -229.397052)
		(mid 361.730929 -229.264163)
		(end 361.690158 -229.094284)
		(width 0.1143)
		(layer "In2.Cu")
		(net "GMI_CPU0_G2_CPU1_G0_TX_DP<15>")
	)
	(arc
		(start 110.740952 -222.587058)
		(mid 110.74414 -222.60868)
		(end 110.745524 -222.630492)
		(width 0.1143)
		(layer "In2.Cu")
		(net "GMI_CPU0_G2_CPU1_G0_TX_DP<15>")
	)
	(arc
		(start 361.123484 -228.08946)
		(mid 361.014776 -227.913372)
		(end 360.880152 -227.756212)
		(width 0.1143)
		(layer "In2.Cu")
		(net "GMI_CPU0_G2_CPU1_G0_TX_DP<15>")
	)
	(arc
		(start 110.745524 -222.630492)
		(mid 110.811558 -222.87977)
		(end 110.98149 -223.073722)
		(width 0.1143)
		(layer "In2.Cu")
		(net "GMI_CPU0_G2_CPU1_G0_TX_DP<15>")
	)
	(arc
		(start 110.16488 -228.54793)
		(mid 110.128452 -228.579903)
		(end 110.088172 -228.606858)
		(width 0.1143)
		(layer "In2.Cu")
		(net "GMI_CPU0_G2_CPU1_G0_TX_DP<15>")
	)
	(arc
		(start 110.98149 -223.073722)
		(mid 110.985162 -223.076404)
		(end 110.988856 -223.079056)
		(width 0.1143)
		(layer "In2.Cu")
		(net "GMI_CPU0_G2_CPU1_G0_TX_DP<15>")
	)
	(arc
		(start 362.620306 -230.608632)
		(mid 362.538026 -230.404936)
		(end 362.38434 -230.247952)
		(width 0.1143)
		(layer "In2.Cu")
		(net "GMI_CPU0_G2_CPU1_G0_TX_DP<15>")
	)
	(arc
		(start 361.225846 -228.349302)
		(mid 361.207065 -228.271457)
		(end 361.17784 -228.196902)
		(width 0.1143)
		(layer "In2.Cu")
		(net "GMI_CPU0_G2_CPU1_G0_TX_DP<15>")
	)
	(arc
		(start 362.624116 -230.631492)
		(mid 362.622328 -230.620043)
		(end 362.620306 -230.608632)
		(width 0.1143)
		(layer "In2.Cu")
		(net "GMI_CPU0_G2_CPU1_G0_TX_DP<15>")
	)
	(arc
		(start 110.596934 -222.31731)
		(mid 110.688445 -222.439106)
		(end 110.739936 -222.582486)
		(width 0.1143)
		(layer "In2.Cu")
		(net "GMI_CPU0_G2_CPU1_G0_TX_DP<15>")
	)
	(arc
		(start 111.062008 -223.135698)
		(mid 111.100596 -223.193776)
		(end 111.114078 -223.26219)
		(width 0.1143)
		(layer "In2.Cu")
		(net "GMI_CPU0_G2_CPU1_G0_TX_DP<15>")
	)
	(arc
		(start 108.875576 -230.608886)
		(mid 108.873553 -230.620296)
		(end 108.871766 -230.631746)
		(width 0.1143)
		(layer "In2.Cu")
		(net "GMI_CPU0_G2_CPU1_G0_TX_DP<15>")
	)
	(arc
		(start 110.587536 -222.309182)
		(mid 110.590724 -222.311705)
		(end 110.593886 -222.314262)
		(width 0.1143)
		(layer "In2.Cu")
		(net "GMI_CPU0_G2_CPU1_G0_TX_DP<15>")
	)
	(arc
		(start 361.690158 -229.094284)
		(mid 361.625643 -228.832065)
		(end 361.446826 -228.629718)
		(width 0.1143)
		(layer "In2.Cu")
		(net "GMI_CPU0_G2_CPU1_G0_TX_DP<15>")
	)
	(arc
		(start 361.37723 -228.589078)
		(mid 361.277939 -228.484081)
		(end 361.225846 -228.349302)
		(width 0.1143)
		(layer "In2.Cu")
		(net "GMI_CPU0_G2_CPU1_G0_TX_DP<15>")
	)
	(arc
		(start 110.27537 -221.804484)
		(mid 110.329888 -222.046972)
		(end 110.483142 -222.242634)
		(width 0.1143)
		(layer "In2.Cu")
		(net "GMI_CPU0_G2_CPU1_G0_TX_DP<15>")
	)
	(arc
		(start 109.604556 -229.424738)
		(mid 109.398488 -229.631601)
		(end 109.323124 -229.913688)
		(width 0.1143)
		(layer "In2.Cu")
		(net "GMI_CPU0_G2_CPU1_G0_TX_DP<15>")
	)
	(arc
		(start 109.111542 -230.248206)
		(mid 108.957842 -230.405181)
		(end 108.875576 -230.608886)
		(width 0.1143)
		(layer "In2.Cu")
		(net "GMI_CPU0_G2_CPU1_G0_TX_DP<15>")
	)
	(arc
		(start 110.049056 -228.629972)
		(mid 109.870243 -228.832322)
		(end 109.805724 -229.094538)
		(width 0.1143)
		(layer "In2.Cu")
		(net "GMI_CPU0_G2_CPU1_G0_TX_DP<15>")
	)
	(arc
		(start 361.17784 -228.196902)
		(mid 361.150855 -228.143083)
		(end 361.123484 -228.08946)
		(width 0.1143)
		(layer "In2.Cu")
		(net "GMI_CPU0_G2_CPU1_G0_TX_DP<15>")
	)
	(arc
		(start 111.114078 -227.447856)
		(mid 111.086527 -227.586922)
		(end 111.007906 -227.704904)
		(width 0.1143)
		(layer "In2.Cu")
		(net "GMI_CPU0_G2_CPU1_G0_TX_DP<15>")
	)
	(arc
		(start 362.161328 -229.904544)
		(mid 362.086424 -229.624329)
		(end 361.881674 -229.418896)
		(width 0.1143)
		(layer "In2.Cu")
		(net "GMI_CPU0_G2_CPU1_G0_TX_DP<15>")
	)
	(arc
		(start 362.347256 -230.226362)
		(mid 362.211195 -230.090362)
		(end 362.161328 -229.904544)
		(width 0.1143)
		(layer "In2.Cu")
		(net "GMI_CPU0_G2_CPU1_G0_TX_DP<15>")
	)
	(arc
		(start 109.805724 -229.094538)
		(mid 109.764962 -229.264422)
		(end 109.651546 -229.397306)
		(width 0.1143)
		(layer "In2.Cu")
		(net "GMI_CPU0_G2_CPU1_G0_TX_DP<15>")
	)
	(arc
		(start 110.483142 -222.242634)
		(mid 110.500046 -222.255784)
		(end 110.517432 -222.268288)
		(width 0.1143)
		(layer "In2.Cu")
		(net "GMI_CPU0_G2_CPU1_G0_TX_DP<15>")
	)
	(segment
		(start 108.957872 -229.360476)
		(end 108.49102 -229.094538)
		(width 0.12954)
		(layer "F.Cu")
		(net "GMI_CPU0_G2_CPU1_G0_TX_DP<14>")
	)
	(segment
		(start 362.53801 -229.360222)
		(end 363.004862 -229.094284)
		(width 0.12954)
		(layer "F.Cu")
		(net "GMI_CPU0_G2_CPU1_G0_TX_DP<14>")
	)
	(segment
		(start 110.118652 -226.96932)
		(end 110.049056 -227.00996)
		(width 0.1143)
		(layer "In2.Cu")
		(net "GMI_CPU0_G2_CPU1_G0_TX_DP<14>")
	)
	(segment
		(start 361.446826 -227.009706)
		(end 361.40771 -226.986846)
		(width 0.1143)
		(layer "In2.Cu")
		(net "GMI_CPU0_G2_CPU1_G0_TX_DP<14>")
	)
	(segment
		(start 361.404408 -224.723452)
		(end 361.40771 -224.721674)
		(width 0.1143)
		(layer "In2.Cu")
		(net "GMI_CPU0_G2_CPU1_G0_TX_DP<14>")
	)
	(segment
		(start 361.197398 -221.083124)
		(end 361.197398 -220.799914)
		(width 0.14224)
		(layer "In2.Cu")
		(net "GMI_CPU0_G2_CPU1_G0_TX_DP<14>")
	)
	(segment
		(start 109.179868 -228.588824)
		(end 109.14888 -228.606604)
		(width 0.1143)
		(layer "In2.Cu")
		(net "GMI_CPU0_G2_CPU1_G0_TX_DP<14>")
	)
	(segment
		(start 109.302042 -228.50094)
		(end 109.179868 -228.588824)
		(width 0.1143)
		(layer "In2.Cu")
		(net "GMI_CPU0_G2_CPU1_G0_TX_DP<14>")
	)
	(segment
		(start 361.197398 -221.097602)
		(end 361.197398 -221.083124)
		(width 0.1143)
		(layer "In2.Cu")
		(net "GMI_CPU0_G2_CPU1_G0_TX_DP<14>")
	)
	(segment
		(start 110.088934 -225.36658)
		(end 110.088172 -225.367088)
		(width 0.1143)
		(layer "In2.Cu")
		(net "GMI_CPU0_G2_CPU1_G0_TX_DP<14>")
	)
	(segment
		(start 109.33303 -219.7735)
		(end 109.33303 -221.174564)
		(width 0.14224)
		(layer "In2.Cu")
		(net "GMI_CPU0_G2_CPU1_G0_TX_DP<14>")
	)
	(segment
		(start 109.649768 -227.778818)
		(end 109.581696 -227.818188)
		(width 0.1143)
		(layer "In2.Cu")
		(net "GMI_CPU0_G2_CPU1_G0_TX_DP<14>")
	)
	(segment
		(start 362.347764 -228.606858)
		(end 362.316014 -228.58857)
		(width 0.1143)
		(layer "In2.Cu")
		(net "GMI_CPU0_G2_CPU1_G0_TX_DP<14>")
	)
	(segment
		(start 361.877864 -227.796852)
		(end 361.846114 -227.778564)
		(width 0.1143)
		(layer "In2.Cu")
		(net "GMI_CPU0_G2_CPU1_G0_TX_DP<14>")
	)
	(segment
		(start 110.0963 -225.362516)
		(end 110.094268 -225.363532)
		(width 0.1143)
		(layer "In2.Cu")
		(net "GMI_CPU0_G2_CPU1_G0_TX_DP<14>")
	)
	(segment
		(start 110.094268 -225.363532)
		(end 110.093506 -225.36404)
		(width 0.1143)
		(layer "In2.Cu")
		(net "GMI_CPU0_G2_CPU1_G0_TX_DP<14>")
	)
	(segment
		(start 361.40771 -224.721674)
		(end 361.41025 -224.72015)
		(width 0.1143)
		(layer "In2.Cu")
		(net "GMI_CPU0_G2_CPU1_G0_TX_DP<14>")
	)
	(segment
		(start 208.242154 -189.70244)
		(end 162.344862 -189.837822)
		(width 0.14224)
		(layer "In2.Cu")
		(net "GMI_CPU0_G2_CPU1_G0_TX_DP<14>")
	)
	(segment
		(start 361.399074 -222.121476)
		(end 361.37596 -222.108522)
		(width 0.1143)
		(layer "In2.Cu")
		(net "GMI_CPU0_G2_CPU1_G0_TX_DP<14>")
	)
	(segment
		(start 109.37875 -221.45752)
		(end 109.335316 -221.500954)
		(width 0.1143)
		(layer "In2.Cu")
		(net "GMI_CPU0_G2_CPU1_G0_TX_DP<14>")
	)
	(segment
		(start 110.119922 -225.3488)
		(end 110.0963 -225.362516)
		(width 0.1143)
		(layer "In2.Cu")
		(net "GMI_CPU0_G2_CPU1_G0_TX_DP<14>")
	)
	(segment
		(start 310.432958 -190.35141)
		(end 307.181504 -189.778132)
		(width 0.14224)
		(layer "In2.Cu")
		(net "GMI_CPU0_G2_CPU1_G0_TX_DP<14>")
	)
	(segment
		(start 362.38688 -228.629718)
		(end 362.384086 -228.627686)
		(width 0.1143)
		(layer "In2.Cu")
		(net "GMI_CPU0_G2_CPU1_G0_TX_DP<14>")
	)
	(segment
		(start 109.145578 -228.608636)
		(end 109.109002 -228.629972)
		(width 0.1143)
		(layer "In2.Cu")
		(net "GMI_CPU0_G2_CPU1_G0_TX_DP<14>")
	)
	(segment
		(start 356.333298 -216.294716)
		(end 310.432958 -190.35141)
		(width 0.14224)
		(layer "In2.Cu")
		(net "GMI_CPU0_G2_CPU1_G0_TX_DP<14>")
	)
	(segment
		(start 360.919522 -220.198442)
		(end 356.333298 -216.294716)
		(width 0.14224)
		(layer "In2.Cu")
		(net "GMI_CPU0_G2_CPU1_G0_TX_DP<14>")
	)
	(segment
		(start 110.091728 -225.365056)
		(end 110.088934 -225.36658)
		(width 0.1143)
		(layer "In2.Cu")
		(net "GMI_CPU0_G2_CPU1_G0_TX_DP<14>")
	)
	(segment
		(start 109.147102 -228.60762)
		(end 109.145578 -228.608636)
		(width 0.1143)
		(layer "In2.Cu")
		(net "GMI_CPU0_G2_CPU1_G0_TX_DP<14>")
	)
	(segment
		(start 109.14888 -228.606604)
		(end 109.148118 -228.607112)
		(width 0.1143)
		(layer "In2.Cu")
		(net "GMI_CPU0_G2_CPU1_G0_TX_DP<14>")
	)
	(segment
		(start 307.181504 -189.778132)
		(end 265.030204 -190.278512)
		(width 0.14224)
		(layer "In2.Cu")
		(net "GMI_CPU0_G2_CPU1_G0_TX_DP<14>")
	)
	(segment
		(start 109.33303 -221.174564)
		(end 109.33303 -221.203012)
		(width 0.1143)
		(layer "In2.Cu")
		(net "GMI_CPU0_G2_CPU1_G0_TX_DP<14>")
	)
	(segment
		(start 361.406948 -222.126302)
		(end 361.403138 -222.124016)
		(width 0.1143)
		(layer "In2.Cu")
		(net "GMI_CPU0_G2_CPU1_G0_TX_DP<14>")
	)
	(segment
		(start 361.220004 -221.49435)
		(end 361.151678 -221.426024)
		(width 0.1143)
		(layer "In2.Cu")
		(net "GMI_CPU0_G2_CPU1_G0_TX_DP<14>")
	)
	(segment
		(start 361.220258 -225.044254)
		(end 361.220004 -225.044254)
		(width 0.1143)
		(layer "In2.Cu")
		(net "GMI_CPU0_G2_CPU1_G0_TX_DP<14>")
	)
	(segment
		(start 361.446826 -223.769682)
		(end 361.40771 -223.746822)
		(width 0.1143)
		(layer "In2.Cu")
		(net "GMI_CPU0_G2_CPU1_G0_TX_DP<14>")
	)
	(segment
		(start 108.871766 -229.011734)
		(end 108.788962 -229.094538)
		(width 0.1143)
		(layer "In2.Cu")
		(net "GMI_CPU0_G2_CPU1_G0_TX_DP<14>")
	)
	(segment
		(start 362.70692 -229.094284)
		(end 362.624116 -229.01148)
		(width 0.1143)
		(layer "In2.Cu")
		(net "GMI_CPU0_G2_CPU1_G0_TX_DP<14>")
	)
	(segment
		(start 110.276132 -223.424496)
		(end 110.276132 -225.044508)
		(width 0.1143)
		(layer "In2.Cu")
		(net "GMI_CPU0_G2_CPU1_G0_TX_DP<14>")
	)
	(segment
		(start 363.004862 -229.094284)
		(end 362.70692 -229.094284)
		(width 0.1143)
		(layer "In2.Cu")
		(net "GMI_CPU0_G2_CPU1_G0_TX_DP<14>")
	)
	(segment
		(start 110.106968 -223.112838)
		(end 110.123732 -223.122744)
		(width 0.1143)
		(layer "In2.Cu")
		(net "GMI_CPU0_G2_CPU1_G0_TX_DP<14>")
	)
	(segment
		(start 215.278716 -188.62675)
		(end 208.242154 -189.70244)
		(width 0.14224)
		(layer "In2.Cu")
		(net "GMI_CPU0_G2_CPU1_G0_TX_DP<14>")
	)
	(segment
		(start 110.049056 -226.31908)
		(end 110.112048 -226.35591)
		(width 0.1143)
		(layer "In2.Cu")
		(net "GMI_CPU0_G2_CPU1_G0_TX_DP<14>")
	)
	(segment
		(start 361.40771 -223.746822)
		(end 361.37723 -223.729042)
		(width 0.1143)
		(layer "In2.Cu")
		(net "GMI_CPU0_G2_CPU1_G0_TX_DP<14>")
	)
	(segment
		(start 114.65179 -214.45474)
		(end 109.33303 -219.7735)
		(width 0.14224)
		(layer "In2.Cu")
		(net "GMI_CPU0_G2_CPU1_G0_TX_DP<14>")
	)
	(segment
		(start 109.335316 -221.500954)
		(end 109.335316 -221.804484)
		(width 0.1143)
		(layer "In2.Cu")
		(net "GMI_CPU0_G2_CPU1_G0_TX_DP<14>")
	)
	(segment
		(start 265.030204 -190.278512)
		(end 236.453172 -185.39079)
		(width 0.14224)
		(layer "In2.Cu")
		(net "GMI_CPU0_G2_CPU1_G0_TX_DP<14>")
	)
	(segment
		(start 361.151678 -221.426024)
		(end 361.151678 -221.143322)
		(width 0.1143)
		(layer "In2.Cu")
		(net "GMI_CPU0_G2_CPU1_G0_TX_DP<14>")
	)
	(segment
		(start 361.151678 -221.143322)
		(end 361.197398 -221.097602)
		(width 0.1143)
		(layer "In2.Cu")
		(net "GMI_CPU0_G2_CPU1_G0_TX_DP<14>")
	)
	(segment
		(start 236.453172 -185.39079)
		(end 215.278716 -188.627004)
		(width 0.14224)
		(layer "In2.Cu")
		(net "GMI_CPU0_G2_CPU1_G0_TX_DP<14>")
	)
	(segment
		(start 361.197398 -220.799914)
		(end 360.919522 -220.198442)
		(width 0.14224)
		(layer "In2.Cu")
		(net "GMI_CPU0_G2_CPU1_G0_TX_DP<14>")
	)
	(segment
		(start 110.093506 -225.36404)
		(end 110.09249 -225.364548)
		(width 0.1143)
		(layer "In2.Cu")
		(net "GMI_CPU0_G2_CPU1_G0_TX_DP<14>")
	)
	(segment
		(start 361.3785 -226.358704)
		(end 361.446826 -226.318826)
		(width 0.1143)
		(layer "In2.Cu")
		(net "GMI_CPU0_G2_CPU1_G0_TX_DP<14>")
	)
	(segment
		(start 361.380786 -223.11741)
		(end 361.446826 -223.078802)
		(width 0.1143)
		(layer "In2.Cu")
		(net "GMI_CPU0_G2_CPU1_G0_TX_DP<14>")
	)
	(segment
		(start 215.278716 -188.627004)
		(end 215.278716 -188.62675)
		(width 0.14224)
		(layer "In2.Cu")
		(net "GMI_CPU0_G2_CPU1_G0_TX_DP<14>")
	)
	(segment
		(start 109.37875 -221.248732)
		(end 109.37875 -221.45752)
		(width 0.1143)
		(layer "In2.Cu")
		(net "GMI_CPU0_G2_CPU1_G0_TX_DP<14>")
	)
	(segment
		(start 110.087156 -225.367596)
		(end 110.049056 -225.389948)
		(width 0.1143)
		(layer "In2.Cu")
		(net "GMI_CPU0_G2_CPU1_G0_TX_DP<14>")
	)
	(segment
		(start 109.33303 -221.203012)
		(end 109.37875 -221.248732)
		(width 0.1143)
		(layer "In2.Cu")
		(net "GMI_CPU0_G2_CPU1_G0_TX_DP<14>")
	)
	(segment
		(start 361.446826 -222.14967)
		(end 361.408726 -222.127318)
		(width 0.1143)
		(layer "In2.Cu")
		(net "GMI_CPU0_G2_CPU1_G0_TX_DP<14>")
	)
	(segment
		(start 109.148118 -228.607112)
		(end 109.147102 -228.60762)
		(width 0.1143)
		(layer "In2.Cu")
		(net "GMI_CPU0_G2_CPU1_G0_TX_DP<14>")
	)
	(segment
		(start 110.088172 -225.367088)
		(end 110.087156 -225.367596)
		(width 0.1143)
		(layer "In2.Cu")
		(net "GMI_CPU0_G2_CPU1_G0_TX_DP<14>")
	)
	(segment
		(start 108.788962 -229.094538)
		(end 108.49102 -229.094538)
		(width 0.1143)
		(layer "In2.Cu")
		(net "GMI_CPU0_G2_CPU1_G0_TX_DP<14>")
	)
	(segment
		(start 109.335824 -228.284532)
		(end 109.335824 -228.4349)
		(width 0.1143)
		(layer "In2.Cu")
		(net "GMI_CPU0_G2_CPU1_G0_TX_DP<14>")
	)
	(segment
		(start 361.408726 -222.127318)
		(end 361.40771 -222.12681)
		(width 0.1143)
		(layer "In2.Cu")
		(net "GMI_CPU0_G2_CPU1_G0_TX_DP<14>")
	)
	(segment
		(start 361.220004 -221.80423)
		(end 361.220004 -221.49435)
		(width 0.1143)
		(layer "In2.Cu")
		(net "GMI_CPU0_G2_CPU1_G0_TX_DP<14>")
	)
	(segment
		(start 361.40771 -226.986846)
		(end 361.37723 -226.969066)
		(width 0.1143)
		(layer "In2.Cu")
		(net "GMI_CPU0_G2_CPU1_G0_TX_DP<14>")
	)
	(segment
		(start 110.09249 -225.364548)
		(end 110.091728 -225.365056)
		(width 0.1143)
		(layer "In2.Cu")
		(net "GMI_CPU0_G2_CPU1_G0_TX_DP<14>")
	)
	(segment
		(start 361.914186 -227.817934)
		(end 361.877864 -227.796852)
		(width 0.1143)
		(layer "In2.Cu")
		(net "GMI_CPU0_G2_CPU1_G0_TX_DP<14>")
	)
	(segment
		(start 109.579918 -222.270066)
		(end 109.644434 -222.307404)
		(width 0.1143)
		(layer "In2.Cu")
		(net "GMI_CPU0_G2_CPU1_G0_TX_DP<14>")
	)
	(segment
		(start 162.344862 -189.837822)
		(end 114.65179 -214.45474)
		(width 0.14224)
		(layer "In2.Cu")
		(net "GMI_CPU0_G2_CPU1_G0_TX_DP<14>")
	)
	(segment
		(start 361.40771 -222.12681)
		(end 361.406948 -222.126302)
		(width 0.1143)
		(layer "In2.Cu")
		(net "GMI_CPU0_G2_CPU1_G0_TX_DP<14>")
	)
	(segment
		(start 362.384086 -228.627686)
		(end 362.347764 -228.606858)
		(width 0.1143)
		(layer "In2.Cu")
		(net "GMI_CPU0_G2_CPU1_G0_TX_DP<14>")
	)
	(segment
		(start 361.403138 -222.124016)
		(end 361.399074 -222.121476)
		(width 0.1143)
		(layer "In2.Cu")
		(net "GMI_CPU0_G2_CPU1_G0_TX_DP<14>")
	)
	(arc
		(start 361.37596 -222.108522)
		(mid 361.261284 -221.975188)
		(end 361.220004 -221.80423)
		(width 0.1143)
		(layer "In2.Cu")
		(net "GMI_CPU0_G2_CPU1_G0_TX_DP<14>")
	)
	(arc
		(start 361.446826 -226.318826)
		(mid 361.689421 -225.850395)
		(end 361.437936 -225.386646)
		(width 0.1143)
		(layer "In2.Cu")
		(net "GMI_CPU0_G2_CPU1_G0_TX_DP<14>")
	)
	(arc
		(start 109.335316 -221.804484)
		(mid 109.399975 -222.067041)
		(end 109.579156 -222.269558)
		(width 0.1143)
		(layer "In2.Cu")
		(net "GMI_CPU0_G2_CPU1_G0_TX_DP<14>")
	)
	(arc
		(start 361.37723 -223.729042)
		(mid 361.262552 -223.596751)
		(end 361.220512 -223.426782)
		(width 0.1143)
		(layer "In2.Cu")
		(net "GMI_CPU0_G2_CPU1_G0_TX_DP<14>")
	)
	(arc
		(start 110.27537 -226.671632)
		(mid 110.273147 -226.707382)
		(end 110.267496 -226.742752)
		(width 0.1143)
		(layer "In2.Cu")
		(net "GMI_CPU0_G2_CPU1_G0_TX_DP<14>")
	)
	(arc
		(start 362.620306 -228.98862)
		(mid 362.538873 -228.786222)
		(end 362.38688 -228.629718)
		(width 0.1143)
		(layer "In2.Cu")
		(net "GMI_CPU0_G2_CPU1_G0_TX_DP<14>")
	)
	(arc
		(start 361.846114 -227.778564)
		(mid 361.731438 -227.64523)
		(end 361.690158 -227.474272)
		(width 0.1143)
		(layer "In2.Cu")
		(net "GMI_CPU0_G2_CPU1_G0_TX_DP<14>")
	)
	(arc
		(start 109.579156 -222.269558)
		(mid 109.579537 -222.269812)
		(end 109.579918 -222.270066)
		(width 0.1143)
		(layer "In2.Cu")
		(net "GMI_CPU0_G2_CPU1_G0_TX_DP<14>")
	)
	(arc
		(start 109.644434 -222.307404)
		(mid 109.757922 -222.450485)
		(end 109.805978 -222.626682)
		(width 0.1143)
		(layer "In2.Cu")
		(net "GMI_CPU0_G2_CPU1_G0_TX_DP<14>")
	)
	(arc
		(start 109.335824 -228.4349)
		(mid 109.326895 -228.471998)
		(end 109.302042 -228.50094)
		(width 0.1143)
		(layer "In2.Cu")
		(net "GMI_CPU0_G2_CPU1_G0_TX_DP<14>")
	)
	(arc
		(start 361.350306 -225.312986)
		(mid 361.30652 -225.262654)
		(end 361.26674 -225.2091)
		(width 0.1143)
		(layer "In2.Cu")
		(net "GMI_CPU0_G2_CPU1_G0_TX_DP<14>")
	)
	(arc
		(start 361.220512 -223.422972)
		(mid 361.269667 -223.253949)
		(end 361.380786 -223.11741)
		(width 0.1143)
		(layer "In2.Cu")
		(net "GMI_CPU0_G2_CPU1_G0_TX_DP<14>")
	)
	(arc
		(start 361.690158 -227.474272)
		(mid 361.625643 -227.212053)
		(end 361.446826 -227.009706)
		(width 0.1143)
		(layer "In2.Cu")
		(net "GMI_CPU0_G2_CPU1_G0_TX_DP<14>")
	)
	(arc
		(start 361.220512 -223.426782)
		(mid 361.220508 -223.424877)
		(end 361.220512 -223.422972)
		(width 0.1143)
		(layer "In2.Cu")
		(net "GMI_CPU0_G2_CPU1_G0_TX_DP<14>")
	)
	(arc
		(start 361.446826 -223.078802)
		(mid 361.690153 -222.614236)
		(end 361.446826 -222.14967)
		(width 0.1143)
		(layer "In2.Cu")
		(net "GMI_CPU0_G2_CPU1_G0_TX_DP<14>")
	)
	(arc
		(start 362.316014 -228.58857)
		(mid 362.204217 -228.453769)
		(end 362.160058 -228.284278)
		(width 0.1143)
		(layer "In2.Cu")
		(net "GMI_CPU0_G2_CPU1_G0_TX_DP<14>")
	)
	(arc
		(start 108.875576 -228.988874)
		(mid 108.873553 -229.000284)
		(end 108.871766 -229.011734)
		(width 0.1143)
		(layer "In2.Cu")
		(net "GMI_CPU0_G2_CPU1_G0_TX_DP<14>")
	)
	(arc
		(start 361.41025 -224.72015)
		(mid 361.689283 -224.254935)
		(end 361.446826 -223.769682)
		(width 0.1143)
		(layer "In2.Cu")
		(net "GMI_CPU0_G2_CPU1_G0_TX_DP<14>")
	)
	(arc
		(start 110.049056 -227.00996)
		(mid 109.870243 -227.21231)
		(end 109.805724 -227.474526)
		(width 0.1143)
		(layer "In2.Cu")
		(net "GMI_CPU0_G2_CPU1_G0_TX_DP<14>")
	)
	(arc
		(start 110.049056 -225.389948)
		(mid 109.805729 -225.854514)
		(end 110.049056 -226.31908)
		(width 0.1143)
		(layer "In2.Cu")
		(net "GMI_CPU0_G2_CPU1_G0_TX_DP<14>")
	)
	(arc
		(start 361.220258 -226.664266)
		(mid 361.265562 -226.493964)
		(end 361.3785 -226.358704)
		(width 0.1143)
		(layer "In2.Cu")
		(net "GMI_CPU0_G2_CPU1_G0_TX_DP<14>")
	)
	(arc
		(start 110.276132 -225.044508)
		(mid 110.259082 -225.155699)
		(end 110.209838 -225.256852)
		(width 0.1143)
		(layer "In2.Cu")
		(net "GMI_CPU0_G2_CPU1_G0_TX_DP<14>")
	)
	(arc
		(start 361.224576 -225.102928)
		(mid 361.221261 -225.073676)
		(end 361.220258 -225.044254)
		(width 0.1143)
		(layer "In2.Cu")
		(net "GMI_CPU0_G2_CPU1_G0_TX_DP<14>")
	)
	(arc
		(start 109.109002 -228.629972)
		(mid 108.957015 -228.78648)
		(end 108.875576 -228.988874)
		(width 0.1143)
		(layer "In2.Cu")
		(net "GMI_CPU0_G2_CPU1_G0_TX_DP<14>")
	)
	(arc
		(start 362.160058 -228.284278)
		(mid 362.087052 -228.024789)
		(end 361.914186 -227.817934)
		(width 0.1143)
		(layer "In2.Cu")
		(net "GMI_CPU0_G2_CPU1_G0_TX_DP<14>")
	)
	(arc
		(start 361.26674 -225.2091)
		(mid 361.239734 -225.158362)
		(end 361.224576 -225.102928)
		(width 0.1143)
		(layer "In2.Cu")
		(net "GMI_CPU0_G2_CPU1_G0_TX_DP<14>")
	)
	(arc
		(start 109.805978 -222.626682)
		(mid 109.895604 -222.90745)
		(end 110.106968 -223.112838)
		(width 0.1143)
		(layer "In2.Cu")
		(net "GMI_CPU0_G2_CPU1_G0_TX_DP<14>")
	)
	(arc
		(start 362.624116 -229.01148)
		(mid 362.622328 -229.000031)
		(end 362.620306 -228.98862)
		(width 0.1143)
		(layer "In2.Cu")
		(net "GMI_CPU0_G2_CPU1_G0_TX_DP<14>")
	)
	(arc
		(start 109.805724 -227.474526)
		(mid 109.764469 -227.645497)
		(end 109.649768 -227.778818)
		(width 0.1143)
		(layer "In2.Cu")
		(net "GMI_CPU0_G2_CPU1_G0_TX_DP<14>")
	)
	(arc
		(start 361.37723 -226.969066)
		(mid 361.261803 -226.83569)
		(end 361.220258 -226.664266)
		(width 0.1143)
		(layer "In2.Cu")
		(net "GMI_CPU0_G2_CPU1_G0_TX_DP<14>")
	)
	(arc
		(start 110.123732 -223.122744)
		(mid 110.235879 -223.255467)
		(end 110.276132 -223.424496)
		(width 0.1143)
		(layer "In2.Cu")
		(net "GMI_CPU0_G2_CPU1_G0_TX_DP<14>")
	)
	(arc
		(start 110.112048 -226.35591)
		(mid 110.222796 -226.498717)
		(end 110.27537 -226.671632)
		(width 0.1143)
		(layer "In2.Cu")
		(net "GMI_CPU0_G2_CPU1_G0_TX_DP<14>")
	)
	(arc
		(start 110.267496 -226.742752)
		(mid 110.214279 -226.869964)
		(end 110.118652 -226.96932)
		(width 0.1143)
		(layer "In2.Cu")
		(net "GMI_CPU0_G2_CPU1_G0_TX_DP<14>")
	)
	(arc
		(start 109.581696 -227.818188)
		(mid 109.401044 -228.020933)
		(end 109.335824 -228.284532)
		(width 0.1143)
		(layer "In2.Cu")
		(net "GMI_CPU0_G2_CPU1_G0_TX_DP<14>")
	)
	(arc
		(start 361.220004 -225.044254)
		(mid 361.269381 -224.859229)
		(end 361.404408 -224.723452)
		(width 0.1143)
		(layer "In2.Cu")
		(net "GMI_CPU0_G2_CPU1_G0_TX_DP<14>")
	)
	(arc
		(start 361.437936 -225.386646)
		(mid 361.391989 -225.352353)
		(end 361.350306 -225.312986)
		(width 0.1143)
		(layer "In2.Cu")
		(net "GMI_CPU0_G2_CPU1_G0_TX_DP<14>")
	)
	(arc
		(start 110.209838 -225.256852)
		(mid 110.168855 -225.306714)
		(end 110.119922 -225.3488)
		(width 0.1143)
		(layer "In2.Cu")
		(net "GMI_CPU0_G2_CPU1_G0_TX_DP<14>")
	)
	(segment
		(start 362.53801 -227.74021)
		(end 363.004862 -227.474272)
		(width 0.12954)
		(layer "F.Cu")
		(net "GMI_CPU0_G2_CPU1_G0_TX_DP<13>")
	)
	(segment
		(start 108.957872 -227.740464)
		(end 108.49102 -227.474526)
		(width 0.12954)
		(layer "F.Cu")
		(net "GMI_CPU0_G2_CPU1_G0_TX_DP<13>")
	)
	(segment
		(start 114.046254 -213.508082)
		(end 111.602774 -215.951562)
		(width 0.14224)
		(layer "In2.Cu")
		(net "GMI_CPU0_G2_CPU1_G0_TX_DP<13>")
	)
	(segment
		(start 109.11586 -226.323144)
		(end 109.116622 -226.323652)
		(width 0.1143)
		(layer "In2.Cu")
		(net "GMI_CPU0_G2_CPU1_G0_TX_DP<13>")
	)
	(segment
		(start 362.316014 -226.359974)
		(end 362.347002 -226.342194)
		(width 0.1143)
		(layer "In2.Cu")
		(net "GMI_CPU0_G2_CPU1_G0_TX_DP<13>")
	)
	(segment
		(start 362.347764 -223.746822)
		(end 362.347002 -223.746314)
		(width 0.1143)
		(layer "In2.Cu")
		(net "GMI_CPU0_G2_CPU1_G0_TX_DP<13>")
	)
	(segment
		(start 109.116622 -226.323652)
		(end 109.147102 -226.341432)
		(width 0.1143)
		(layer "In2.Cu")
		(net "GMI_CPU0_G2_CPU1_G0_TX_DP<13>")
	)
	(segment
		(start 109.148118 -226.9871)
		(end 109.147102 -226.987608)
		(width 0.1143)
		(layer "In2.Cu")
		(net "GMI_CPU0_G2_CPU1_G0_TX_DP<13>")
	)
	(segment
		(start 362.347002 -226.986338)
		(end 362.316014 -226.968558)
		(width 0.1143)
		(layer "In2.Cu")
		(net "GMI_CPU0_G2_CPU1_G0_TX_DP<13>")
	)
	(segment
		(start 362.316014 -225.348546)
		(end 362.297218 -225.33483)
		(width 0.1143)
		(layer "In2.Cu")
		(net "GMI_CPU0_G2_CPU1_G0_TX_DP<13>")
	)
	(segment
		(start 362.316014 -223.728534)
		(end 362.296202 -223.71431)
		(width 0.1143)
		(layer "In2.Cu")
		(net "GMI_CPU0_G2_CPU1_G0_TX_DP<13>")
	)
	(segment
		(start 362.347764 -226.986846)
		(end 362.347002 -226.986338)
		(width 0.1143)
		(layer "In2.Cu")
		(net "GMI_CPU0_G2_CPU1_G0_TX_DP<13>")
	)
	(segment
		(start 362.297218 -224.753678)
		(end 362.316014 -224.739962)
		(width 0.1143)
		(layer "In2.Cu")
		(net "GMI_CPU0_G2_CPU1_G0_TX_DP<13>")
	)
	(segment
		(start 109.152436 -225.364548)
		(end 109.151674 -225.365056)
		(width 0.1143)
		(layer "In2.Cu")
		(net "GMI_CPU0_G2_CPU1_G0_TX_DP<13>")
	)
	(segment
		(start 362.296202 -223.134174)
		(end 362.316014 -223.11995)
		(width 0.1143)
		(layer "In2.Cu")
		(net "GMI_CPU0_G2_CPU1_G0_TX_DP<13>")
	)
	(segment
		(start 362.34878 -225.367342)
		(end 362.347764 -225.366834)
		(width 0.1143)
		(layer "In2.Cu")
		(net "GMI_CPU0_G2_CPU1_G0_TX_DP<13>")
	)
	(segment
		(start 108.395516 -221.584266)
		(end 108.395516 -221.804484)
		(width 0.1143)
		(layer "In2.Cu")
		(net "GMI_CPU0_G2_CPU1_G0_TX_DP<13>")
	)
	(segment
		(start 362.38688 -227.009706)
		(end 362.380022 -227.005642)
		(width 0.1143)
		(layer "In2.Cu")
		(net "GMI_CPU0_G2_CPU1_G0_TX_DP<13>")
	)
	(segment
		(start 109.109002 -224.699068)
		(end 109.11586 -224.703132)
		(width 0.1143)
		(layer "In2.Cu")
		(net "GMI_CPU0_G2_CPU1_G0_TX_DP<13>")
	)
	(segment
		(start 362.347764 -225.366834)
		(end 362.347002 -225.366326)
		(width 0.1143)
		(layer "In2.Cu")
		(net "GMI_CPU0_G2_CPU1_G0_TX_DP<13>")
	)
	(segment
		(start 362.380022 -227.005642)
		(end 362.37926 -227.005134)
		(width 0.1143)
		(layer "In2.Cu")
		(net "GMI_CPU0_G2_CPU1_G0_TX_DP<13>")
	)
	(segment
		(start 362.160058 -221.41053)
		(end 362.096558 -221.34703)
		(width 0.1143)
		(layer "In2.Cu")
		(net "GMI_CPU0_G2_CPU1_G0_TX_DP<13>")
	)
	(segment
		(start 363.004862 -227.474272)
		(end 362.70692 -227.474272)
		(width 0.1143)
		(layer "In2.Cu")
		(net "GMI_CPU0_G2_CPU1_G0_TX_DP<13>")
	)
	(segment
		(start 108.788962 -227.474526)
		(end 108.49102 -227.474526)
		(width 0.1143)
		(layer "In2.Cu")
		(net "GMI_CPU0_G2_CPU1_G0_TX_DP<13>")
	)
	(segment
		(start 362.316014 -223.11995)
		(end 362.347002 -223.10217)
		(width 0.1143)
		(layer "In2.Cu")
		(net "GMI_CPU0_G2_CPU1_G0_TX_DP<13>")
	)
	(segment
		(start 109.179868 -225.3488)
		(end 109.152436 -225.364548)
		(width 0.1143)
		(layer "In2.Cu")
		(net "GMI_CPU0_G2_CPU1_G0_TX_DP<13>")
	)
	(segment
		(start 108.38815 -221.174564)
		(end 108.38815 -221.203012)
		(width 0.1143)
		(layer "In2.Cu")
		(net "GMI_CPU0_G2_CPU1_G0_TX_DP<13>")
	)
	(segment
		(start 111.602774 -215.951562)
		(end 110.03661 -217.51798)
		(width 0.14224)
		(layer "In2.Cu")
		(net "GMI_CPU0_G2_CPU1_G0_TX_DP<13>")
	)
	(segment
		(start 109.147102 -225.367596)
		(end 109.145578 -225.368612)
		(width 0.1143)
		(layer "In2.Cu")
		(net "GMI_CPU0_G2_CPU1_G0_TX_DP<13>")
	)
	(segment
		(start 362.34878 -226.341178)
		(end 362.350304 -226.340162)
		(width 0.1143)
		(layer "In2.Cu")
		(net "GMI_CPU0_G2_CPU1_G0_TX_DP<13>")
	)
	(segment
		(start 108.871766 -227.391722)
		(end 108.788962 -227.474526)
		(width 0.1143)
		(layer "In2.Cu")
		(net "GMI_CPU0_G2_CPU1_G0_TX_DP<13>")
	)
	(segment
		(start 109.148118 -226.987354)
		(end 109.148118 -226.9871)
		(width 0.1143)
		(layer "In2.Cu")
		(net "GMI_CPU0_G2_CPU1_G0_TX_DP<13>")
	)
	(segment
		(start 109.148118 -223.747076)
		(end 109.109002 -223.769936)
		(width 0.1143)
		(layer "In2.Cu")
		(net "GMI_CPU0_G2_CPU1_G0_TX_DP<13>")
	)
	(segment
		(start 362.347002 -225.366326)
		(end 362.316014 -225.348546)
		(width 0.1143)
		(layer "In2.Cu")
		(net "GMI_CPU0_G2_CPU1_G0_TX_DP<13>")
	)
	(segment
		(start 307.25872 -188.831982)
		(end 265.10615 -189.332616)
		(width 0.14224)
		(layer "In2.Cu")
		(net "GMI_CPU0_G2_CPU1_G0_TX_DP<13>")
	)
	(segment
		(start 362.37926 -223.76511)
		(end 362.347764 -223.746822)
		(width 0.1143)
		(layer "In2.Cu")
		(net "GMI_CPU0_G2_CPU1_G0_TX_DP<13>")
	)
	(segment
		(start 361.714034 -219.570808)
		(end 356.443026 -215.082882)
		(width 0.14224)
		(layer "In2.Cu")
		(net "GMI_CPU0_G2_CPU1_G0_TX_DP<13>")
	)
	(segment
		(start 109.116622 -224.70364)
		(end 109.147102 -224.72142)
		(width 0.1143)
		(layer "In2.Cu")
		(net "GMI_CPU0_G2_CPU1_G0_TX_DP<13>")
	)
	(segment
		(start 362.34878 -223.101154)
		(end 362.350304 -223.100138)
		(width 0.1143)
		(layer "In2.Cu")
		(net "GMI_CPU0_G2_CPU1_G0_TX_DP<13>")
	)
	(segment
		(start 109.148118 -226.34194)
		(end 109.148118 -226.341686)
		(width 0.1143)
		(layer "In2.Cu")
		(net "GMI_CPU0_G2_CPU1_G0_TX_DP<13>")
	)
	(segment
		(start 108.38815 -221.203012)
		(end 108.43387 -221.248732)
		(width 0.1143)
		(layer "In2.Cu")
		(net "GMI_CPU0_G2_CPU1_G0_TX_DP<13>")
	)
	(segment
		(start 109.148118 -224.721928)
		(end 109.14888 -224.722436)
		(width 0.1143)
		(layer "In2.Cu")
		(net "GMI_CPU0_G2_CPU1_G0_TX_DP<13>")
	)
	(segment
		(start 109.147102 -224.72142)
		(end 109.148118 -224.721928)
		(width 0.1143)
		(layer "In2.Cu")
		(net "GMI_CPU0_G2_CPU1_G0_TX_DP<13>")
	)
	(segment
		(start 362.142278 -220.49867)
		(end 361.714034 -219.570808)
		(width 0.14224)
		(layer "In2.Cu")
		(net "GMI_CPU0_G2_CPU1_G0_TX_DP<13>")
	)
	(segment
		(start 109.145578 -226.988624)
		(end 109.109002 -227.00996)
		(width 0.1143)
		(layer "In2.Cu")
		(net "GMI_CPU0_G2_CPU1_G0_TX_DP<13>")
	)
	(segment
		(start 362.142278 -221.083124)
		(end 362.142278 -220.49867)
		(width 0.14224)
		(layer "In2.Cu")
		(net "GMI_CPU0_G2_CPU1_G0_TX_DP<13>")
	)
	(segment
		(start 362.380022 -223.765618)
		(end 362.37926 -223.76511)
		(width 0.1143)
		(layer "In2.Cu")
		(net "GMI_CPU0_G2_CPU1_G0_TX_DP<13>")
	)
	(segment
		(start 109.109002 -226.31908)
		(end 109.11586 -226.323144)
		(width 0.1143)
		(layer "In2.Cu")
		(net "GMI_CPU0_G2_CPU1_G0_TX_DP<13>")
	)
	(segment
		(start 161.732722 -188.894212)
		(end 114.046254 -213.508082)
		(width 0.14224)
		(layer "In2.Cu")
		(net "GMI_CPU0_G2_CPU1_G0_TX_DP<13>")
	)
	(segment
		(start 362.096558 -221.143322)
		(end 362.142278 -221.097602)
		(width 0.1143)
		(layer "In2.Cu")
		(net "GMI_CPU0_G2_CPU1_G0_TX_DP<13>")
	)
	(segment
		(start 362.38688 -223.769682)
		(end 362.380022 -223.765618)
		(width 0.1143)
		(layer "In2.Cu")
		(net "GMI_CPU0_G2_CPU1_G0_TX_DP<13>")
	)
	(segment
		(start 362.347002 -226.342194)
		(end 362.347764 -226.341686)
		(width 0.1143)
		(layer "In2.Cu")
		(net "GMI_CPU0_G2_CPU1_G0_TX_DP<13>")
	)
	(segment
		(start 109.148626 -226.9871)
		(end 109.148118 -226.987354)
		(width 0.1143)
		(layer "In2.Cu")
		(net "GMI_CPU0_G2_CPU1_G0_TX_DP<13>")
	)
	(segment
		(start 109.145578 -225.368612)
		(end 109.109002 -225.389948)
		(width 0.1143)
		(layer "In2.Cu")
		(net "GMI_CPU0_G2_CPU1_G0_TX_DP<13>")
	)
	(segment
		(start 108.38815 -219.166948)
		(end 108.38815 -221.174564)
		(width 0.14224)
		(layer "In2.Cu")
		(net "GMI_CPU0_G2_CPU1_G0_TX_DP<13>")
	)
	(segment
		(start 312.398918 -190.252858)
		(end 312.398918 -190.253112)
		(width 0.14224)
		(layer "In2.Cu")
		(net "GMI_CPU0_G2_CPU1_G0_TX_DP<13>")
	)
	(segment
		(start 108.43387 -221.545912)
		(end 108.395516 -221.584266)
		(width 0.1143)
		(layer "In2.Cu")
		(net "GMI_CPU0_G2_CPU1_G0_TX_DP<13>")
	)
	(segment
		(start 362.350304 -226.340162)
		(end 362.38688 -226.318826)
		(width 0.1143)
		(layer "In2.Cu")
		(net "GMI_CPU0_G2_CPU1_G0_TX_DP<13>")
	)
	(segment
		(start 265.10615 -189.332616)
		(end 236.461554 -184.433464)
		(width 0.14224)
		(layer "In2.Cu")
		(net "GMI_CPU0_G2_CPU1_G0_TX_DP<13>")
	)
	(segment
		(start 362.37926 -227.005134)
		(end 362.347764 -226.986846)
		(width 0.1143)
		(layer "In2.Cu")
		(net "GMI_CPU0_G2_CPU1_G0_TX_DP<13>")
	)
	(segment
		(start 362.347002 -224.722182)
		(end 362.347764 -224.721674)
		(width 0.1143)
		(layer "In2.Cu")
		(net "GMI_CPU0_G2_CPU1_G0_TX_DP<13>")
	)
	(segment
		(start 362.142278 -221.097602)
		(end 362.142278 -221.083124)
		(width 0.1143)
		(layer "In2.Cu")
		(net "GMI_CPU0_G2_CPU1_G0_TX_DP<13>")
	)
	(segment
		(start 236.461554 -184.433464)
		(end 208.169002 -188.75756)
		(width 0.14224)
		(layer "In2.Cu")
		(net "GMI_CPU0_G2_CPU1_G0_TX_DP<13>")
	)
	(segment
		(start 109.11586 -224.703132)
		(end 109.116622 -224.70364)
		(width 0.1143)
		(layer "In2.Cu")
		(net "GMI_CPU0_G2_CPU1_G0_TX_DP<13>")
	)
	(segment
		(start 311.580276 -189.856618)
		(end 310.726582 -189.44336)
		(width 0.14224)
		(layer "In2.Cu")
		(net "GMI_CPU0_G2_CPU1_G0_TX_DP<13>")
	)
	(segment
		(start 355.702362 -214.599774)
		(end 314.044076 -191.049656)
		(width 0.14224)
		(layer "In2.Cu")
		(net "GMI_CPU0_G2_CPU1_G0_TX_DP<13>")
	)
	(segment
		(start 362.350304 -224.72015)
		(end 362.38688 -224.698814)
		(width 0.1143)
		(layer "In2.Cu")
		(net "GMI_CPU0_G2_CPU1_G0_TX_DP<13>")
	)
	(segment
		(start 109.14888 -224.722436)
		(end 109.15015 -224.723198)
		(width 0.1143)
		(layer "In2.Cu")
		(net "GMI_CPU0_G2_CPU1_G0_TX_DP<13>")
	)
	(segment
		(start 362.347764 -222.12681)
		(end 362.316014 -222.108522)
		(width 0.1143)
		(layer "In2.Cu")
		(net "GMI_CPU0_G2_CPU1_G0_TX_DP<13>")
	)
	(segment
		(start 109.147102 -226.987608)
		(end 109.145578 -226.988624)
		(width 0.1143)
		(layer "In2.Cu")
		(net "GMI_CPU0_G2_CPU1_G0_TX_DP<13>")
	)
	(segment
		(start 109.178598 -223.729296)
		(end 109.148118 -223.747076)
		(width 0.1143)
		(layer "In2.Cu")
		(net "GMI_CPU0_G2_CPU1_G0_TX_DP<13>")
	)
	(segment
		(start 362.160058 -221.80423)
		(end 362.160058 -221.41053)
		(width 0.1143)
		(layer "In2.Cu")
		(net "GMI_CPU0_G2_CPU1_G0_TX_DP<13>")
	)
	(segment
		(start 314.044076 -191.049656)
		(end 312.398918 -190.252858)
		(width 0.14224)
		(layer "In2.Cu")
		(net "GMI_CPU0_G2_CPU1_G0_TX_DP<13>")
	)
	(segment
		(start 110.03661 -217.51798)
		(end 108.38815 -219.166948)
		(width 0.14224)
		(layer "In2.Cu")
		(net "GMI_CPU0_G2_CPU1_G0_TX_DP<13>")
	)
	(segment
		(start 356.443026 -215.082882)
		(end 355.702362 -214.599774)
		(width 0.14224)
		(layer "In2.Cu")
		(net "GMI_CPU0_G2_CPU1_G0_TX_DP<13>")
	)
	(segment
		(start 109.14761 -223.101916)
		(end 109.147864 -223.101916)
		(width 0.1143)
		(layer "In2.Cu")
		(net "GMI_CPU0_G2_CPU1_G0_TX_DP<13>")
	)
	(segment
		(start 109.14888 -225.36658)
		(end 109.148118 -225.367088)
		(width 0.1143)
		(layer "In2.Cu")
		(net "GMI_CPU0_G2_CPU1_G0_TX_DP<13>")
	)
	(segment
		(start 362.347764 -226.341686)
		(end 362.34878 -226.341178)
		(width 0.1143)
		(layer "In2.Cu")
		(net "GMI_CPU0_G2_CPU1_G0_TX_DP<13>")
	)
	(segment
		(start 312.398918 -190.253112)
		(end 311.580276 -189.856618)
		(width 0.14224)
		(layer "In2.Cu")
		(net "GMI_CPU0_G2_CPU1_G0_TX_DP<13>")
	)
	(segment
		(start 362.347002 -223.10217)
		(end 362.347764 -223.101662)
		(width 0.1143)
		(layer "In2.Cu")
		(net "GMI_CPU0_G2_CPU1_G0_TX_DP<13>")
	)
	(segment
		(start 362.38688 -222.14967)
		(end 362.347764 -222.12681)
		(width 0.1143)
		(layer "In2.Cu")
		(net "GMI_CPU0_G2_CPU1_G0_TX_DP<13>")
	)
	(segment
		(start 362.347764 -224.721674)
		(end 362.34878 -224.721166)
		(width 0.1143)
		(layer "In2.Cu")
		(net "GMI_CPU0_G2_CPU1_G0_TX_DP<13>")
	)
	(segment
		(start 109.148118 -226.341686)
		(end 109.148626 -226.34194)
		(width 0.1143)
		(layer "In2.Cu")
		(net "GMI_CPU0_G2_CPU1_G0_TX_DP<13>")
	)
	(segment
		(start 109.148118 -225.367088)
		(end 109.147102 -225.367596)
		(width 0.1143)
		(layer "In2.Cu")
		(net "GMI_CPU0_G2_CPU1_G0_TX_DP<13>")
	)
	(segment
		(start 362.350304 -223.100138)
		(end 362.38688 -223.078802)
		(width 0.1143)
		(layer "In2.Cu")
		(net "GMI_CPU0_G2_CPU1_G0_TX_DP<13>")
	)
	(segment
		(start 362.70692 -227.474272)
		(end 362.624116 -227.391468)
		(width 0.1143)
		(layer "In2.Cu")
		(net "GMI_CPU0_G2_CPU1_G0_TX_DP<13>")
	)
	(segment
		(start 109.151674 -225.365056)
		(end 109.14888 -225.36658)
		(width 0.1143)
		(layer "In2.Cu")
		(net "GMI_CPU0_G2_CPU1_G0_TX_DP<13>")
	)
	(segment
		(start 362.096558 -221.34703)
		(end 362.096558 -221.143322)
		(width 0.1143)
		(layer "In2.Cu")
		(net "GMI_CPU0_G2_CPU1_G0_TX_DP<13>")
	)
	(segment
		(start 362.316014 -224.739962)
		(end 362.347002 -224.722182)
		(width 0.1143)
		(layer "In2.Cu")
		(net "GMI_CPU0_G2_CPU1_G0_TX_DP<13>")
	)
	(segment
		(start 362.34878 -224.721166)
		(end 362.350304 -224.72015)
		(width 0.1143)
		(layer "In2.Cu")
		(net "GMI_CPU0_G2_CPU1_G0_TX_DP<13>")
	)
	(segment
		(start 109.15015 -224.723198)
		(end 109.179868 -224.740216)
		(width 0.1143)
		(layer "In2.Cu")
		(net "GMI_CPU0_G2_CPU1_G0_TX_DP<13>")
	)
	(segment
		(start 108.43387 -221.248732)
		(end 108.43387 -221.545912)
		(width 0.1143)
		(layer "In2.Cu")
		(net "GMI_CPU0_G2_CPU1_G0_TX_DP<13>")
	)
	(segment
		(start 362.347764 -223.101662)
		(end 362.34878 -223.101154)
		(width 0.1143)
		(layer "In2.Cu")
		(net "GMI_CPU0_G2_CPU1_G0_TX_DP<13>")
	)
	(segment
		(start 109.147102 -226.341432)
		(end 109.148118 -226.34194)
		(width 0.1143)
		(layer "In2.Cu")
		(net "GMI_CPU0_G2_CPU1_G0_TX_DP<13>")
	)
	(segment
		(start 108.640118 -222.270066)
		(end 108.682028 -222.294196)
		(width 0.1143)
		(layer "In2.Cu")
		(net "GMI_CPU0_G2_CPU1_G0_TX_DP<13>")
	)
	(segment
		(start 109.147864 -223.101916)
		(end 109.179614 -223.120204)
		(width 0.1143)
		(layer "In2.Cu")
		(net "GMI_CPU0_G2_CPU1_G0_TX_DP<13>")
	)
	(segment
		(start 362.38688 -225.389694)
		(end 362.34878 -225.367342)
		(width 0.1143)
		(layer "In2.Cu")
		(net "GMI_CPU0_G2_CPU1_G0_TX_DP<13>")
	)
	(segment
		(start 208.169002 -188.75756)
		(end 161.732722 -188.894212)
		(width 0.14224)
		(layer "In2.Cu")
		(net "GMI_CPU0_G2_CPU1_G0_TX_DP<13>")
	)
	(segment
		(start 310.726582 -189.44336)
		(end 307.25872 -188.831982)
		(width 0.14224)
		(layer "In2.Cu")
		(net "GMI_CPU0_G2_CPU1_G0_TX_DP<13>")
	)
	(segment
		(start 362.347002 -223.746314)
		(end 362.316014 -223.728534)
		(width 0.1143)
		(layer "In2.Cu")
		(net "GMI_CPU0_G2_CPU1_G0_TX_DP<13>")
	)
	(arc
		(start 109.179868 -224.740216)
		(mid 109.335796 -225.044508)
		(end 109.179868 -225.3488)
		(width 0.1143)
		(layer "In2.Cu")
		(net "GMI_CPU0_G2_CPU1_G0_TX_DP<13>")
	)
	(arc
		(start 109.109002 -227.00996)
		(mid 108.957015 -227.166468)
		(end 108.875576 -227.368862)
		(width 0.1143)
		(layer "In2.Cu")
		(net "GMI_CPU0_G2_CPU1_G0_TX_DP<13>")
	)
	(arc
		(start 362.38688 -226.318826)
		(mid 362.630207 -225.85426)
		(end 362.38688 -225.389694)
		(width 0.1143)
		(layer "In2.Cu")
		(net "GMI_CPU0_G2_CPU1_G0_TX_DP<13>")
	)
	(arc
		(start 109.109002 -225.389948)
		(mid 108.865675 -225.854514)
		(end 109.109002 -226.31908)
		(width 0.1143)
		(layer "In2.Cu")
		(net "GMI_CPU0_G2_CPU1_G0_TX_DP<13>")
	)
	(arc
		(start 362.316014 -222.108522)
		(mid 362.201338 -221.975188)
		(end 362.160058 -221.80423)
		(width 0.1143)
		(layer "In2.Cu")
		(net "GMI_CPU0_G2_CPU1_G0_TX_DP<13>")
	)
	(arc
		(start 362.38688 -224.698814)
		(mid 362.630207 -224.234248)
		(end 362.38688 -223.769682)
		(width 0.1143)
		(layer "In2.Cu")
		(net "GMI_CPU0_G2_CPU1_G0_TX_DP<13>")
	)
	(arc
		(start 108.869734 -222.619062)
		(mid 108.944155 -222.897624)
		(end 109.14761 -223.101916)
		(width 0.1143)
		(layer "In2.Cu")
		(net "GMI_CPU0_G2_CPU1_G0_TX_DP<13>")
	)
	(arc
		(start 109.33557 -223.424496)
		(mid 109.294021 -223.595918)
		(end 109.178598 -223.729296)
		(width 0.1143)
		(layer "In2.Cu")
		(net "GMI_CPU0_G2_CPU1_G0_TX_DP<13>")
	)
	(arc
		(start 109.148626 -226.34194)
		(mid 109.334264 -226.66452)
		(end 109.148626 -226.9871)
		(width 0.1143)
		(layer "In2.Cu")
		(net "GMI_CPU0_G2_CPU1_G0_TX_DP<13>")
	)
	(arc
		(start 108.395516 -221.804484)
		(mid 108.460388 -222.067447)
		(end 108.640118 -222.270066)
		(width 0.1143)
		(layer "In2.Cu")
		(net "GMI_CPU0_G2_CPU1_G0_TX_DP<13>")
	)
	(arc
		(start 362.38688 -223.078802)
		(mid 362.630207 -222.614236)
		(end 362.38688 -222.14967)
		(width 0.1143)
		(layer "In2.Cu")
		(net "GMI_CPU0_G2_CPU1_G0_TX_DP<13>")
	)
	(arc
		(start 362.620306 -227.368608)
		(mid 362.538873 -227.16621)
		(end 362.38688 -227.009706)
		(width 0.1143)
		(layer "In2.Cu")
		(net "GMI_CPU0_G2_CPU1_G0_TX_DP<13>")
	)
	(arc
		(start 362.297218 -225.33483)
		(mid 362.148303 -225.044254)
		(end 362.297218 -224.753678)
		(width 0.1143)
		(layer "In2.Cu")
		(net "GMI_CPU0_G2_CPU1_G0_TX_DP<13>")
	)
	(arc
		(start 362.296202 -223.71431)
		(mid 362.147488 -223.424242)
		(end 362.296202 -223.134174)
		(width 0.1143)
		(layer "In2.Cu")
		(net "GMI_CPU0_G2_CPU1_G0_TX_DP<13>")
	)
	(arc
		(start 108.875576 -227.368862)
		(mid 108.873553 -227.380272)
		(end 108.871766 -227.391722)
		(width 0.1143)
		(layer "In2.Cu")
		(net "GMI_CPU0_G2_CPU1_G0_TX_DP<13>")
	)
	(arc
		(start 109.179614 -223.120204)
		(mid 109.29429 -223.253538)
		(end 109.33557 -223.424496)
		(width 0.1143)
		(layer "In2.Cu")
		(net "GMI_CPU0_G2_CPU1_G0_TX_DP<13>")
	)
	(arc
		(start 108.682028 -222.294196)
		(mid 108.81946 -222.431455)
		(end 108.869734 -222.619062)
		(width 0.1143)
		(layer "In2.Cu")
		(net "GMI_CPU0_G2_CPU1_G0_TX_DP<13>")
	)
	(arc
		(start 362.316014 -226.968558)
		(mid 362.166917 -226.664266)
		(end 362.316014 -226.359974)
		(width 0.1143)
		(layer "In2.Cu")
		(net "GMI_CPU0_G2_CPU1_G0_TX_DP<13>")
	)
	(arc
		(start 109.109002 -223.769936)
		(mid 108.865675 -224.234502)
		(end 109.109002 -224.699068)
		(width 0.1143)
		(layer "In2.Cu")
		(net "GMI_CPU0_G2_CPU1_G0_TX_DP<13>")
	)
	(arc
		(start 362.624116 -227.391468)
		(mid 362.622328 -227.380019)
		(end 362.620306 -227.368608)
		(width 0.1143)
		(layer "In2.Cu")
		(net "GMI_CPU0_G2_CPU1_G0_TX_DP<13>")
	)
	(segment
		(start 364.888018 -230.169974)
		(end 365.35487 -229.904036)
		(width 0.12954)
		(layer "F.Cu")
		(net "GMI_CPU0_G2_CPU1_G0_TX_DP<12>")
	)
	(segment
		(start 106.607864 -230.170228)
		(end 106.141012 -229.90429)
		(width 0.12954)
		(layer "F.Cu")
		(net "GMI_CPU0_G2_CPU1_G0_TX_DP<12>")
	)
	(segment
		(start 363.041438 -221.34703)
		(end 363.041438 -221.143322)
		(width 0.1143)
		(layer "In2.Cu")
		(net "GMI_CPU0_G2_CPU1_G0_TX_DP<12>")
	)
	(segment
		(start 363.281214 -222.123)
		(end 363.279944 -222.122238)
		(width 0.1143)
		(layer "In2.Cu")
		(net "GMI_CPU0_G2_CPU1_G0_TX_DP<12>")
	)
	(segment
		(start 363.041438 -221.143322)
		(end 363.087158 -221.097602)
		(width 0.1143)
		(layer "In2.Cu")
		(net "GMI_CPU0_G2_CPU1_G0_TX_DP<12>")
	)
	(segment
		(start 363.290358 -223.100138)
		(end 363.326934 -223.078802)
		(width 0.1143)
		(layer "In2.Cu")
		(net "GMI_CPU0_G2_CPU1_G0_TX_DP<12>")
	)
	(segment
		(start 108.208826 -226.986592)
		(end 108.208064 -226.9871)
		(width 0.1143)
		(layer "In2.Cu")
		(net "GMI_CPU0_G2_CPU1_G0_TX_DP<12>")
	)
	(segment
		(start 363.320076 -225.38563)
		(end 363.319314 -225.385122)
		(width 0.1143)
		(layer "In2.Cu")
		(net "GMI_CPU0_G2_CPU1_G0_TX_DP<12>")
	)
	(segment
		(start 208.09585 -187.81268)
		(end 161.195258 -187.950602)
		(width 0.14224)
		(layer "In2.Cu")
		(net "GMI_CPU0_G2_CPU1_G0_TX_DP<12>")
	)
	(segment
		(start 107.456224 -221.545912)
		(end 107.456224 -221.805246)
		(width 0.1143)
		(layer "In2.Cu")
		(net "GMI_CPU0_G2_CPU1_G0_TX_DP<12>")
	)
	(segment
		(start 365.35487 -229.904036)
		(end 365.056928 -229.904036)
		(width 0.1143)
		(layer "In2.Cu")
		(net "GMI_CPU0_G2_CPU1_G0_TX_DP<12>")
	)
	(segment
		(start 107.29976 -228.588824)
		(end 107.272328 -228.604572)
		(width 0.1143)
		(layer "In2.Cu")
		(net "GMI_CPU0_G2_CPU1_G0_TX_DP<12>")
	)
	(segment
		(start 363.290358 -226.340162)
		(end 363.326934 -226.318826)
		(width 0.1143)
		(layer "In2.Cu")
		(net "GMI_CPU0_G2_CPU1_G0_TX_DP<12>")
	)
	(segment
		(start 106.521758 -229.821486)
		(end 106.438954 -229.90429)
		(width 0.1143)
		(layer "In2.Cu")
		(net "GMI_CPU0_G2_CPU1_G0_TX_DP<12>")
	)
	(segment
		(start 363.2835 -222.12427)
		(end 363.281976 -222.123508)
		(width 0.1143)
		(layer "In2.Cu")
		(net "GMI_CPU0_G2_CPU1_G0_TX_DP<12>")
	)
	(segment
		(start 161.195258 -187.950602)
		(end 113.36528 -212.638386)
		(width 0.14224)
		(layer "In2.Cu")
		(net "GMI_CPU0_G2_CPU1_G0_TX_DP<12>")
	)
	(segment
		(start 108.203746 -223.749616)
		(end 108.202476 -223.750378)
		(width 0.1143)
		(layer "In2.Cu")
		(net "GMI_CPU0_G2_CPU1_G0_TX_DP<12>")
	)
	(segment
		(start 108.202476 -226.990402)
		(end 108.201714 -226.99091)
		(width 0.1143)
		(layer "In2.Cu")
		(net "GMI_CPU0_G2_CPU1_G0_TX_DP<12>")
	)
	(segment
		(start 363.287056 -224.722182)
		(end 363.287818 -224.721674)
		(width 0.1143)
		(layer "In2.Cu")
		(net "GMI_CPU0_G2_CPU1_G0_TX_DP<12>")
	)
	(segment
		(start 108.202476 -223.750378)
		(end 108.201714 -223.750886)
		(width 0.1143)
		(layer "In2.Cu")
		(net "GMI_CPU0_G2_CPU1_G0_TX_DP<12>")
	)
	(segment
		(start 107.48899 -221.248732)
		(end 107.48899 -221.513146)
		(width 0.1143)
		(layer "In2.Cu")
		(net "GMI_CPU0_G2_CPU1_G0_TX_DP<12>")
	)
	(segment
		(start 108.208826 -224.722436)
		(end 108.239814 -224.740216)
		(width 0.1143)
		(layer "In2.Cu")
		(net "GMI_CPU0_G2_CPU1_G0_TX_DP<12>")
	)
	(segment
		(start 108.208064 -224.721928)
		(end 108.208826 -224.722436)
		(width 0.1143)
		(layer "In2.Cu")
		(net "GMI_CPU0_G2_CPU1_G0_TX_DP<12>")
	)
	(segment
		(start 363.287818 -223.746822)
		(end 363.287056 -223.746314)
		(width 0.1143)
		(layer "In2.Cu")
		(net "GMI_CPU0_G2_CPU1_G0_TX_DP<12>")
	)
	(segment
		(start 364.736888 -229.43947)
		(end 364.697772 -229.41661)
		(width 0.1143)
		(layer "In2.Cu")
		(net "GMI_CPU0_G2_CPU1_G0_TX_DP<12>")
	)
	(segment
		(start 108.175806 -226.323144)
		(end 108.176568 -226.323652)
		(width 0.1143)
		(layer "In2.Cu")
		(net "GMI_CPU0_G2_CPU1_G0_TX_DP<12>")
	)
	(segment
		(start 108.207048 -224.72142)
		(end 108.208064 -224.721928)
		(width 0.1143)
		(layer "In2.Cu")
		(net "GMI_CPU0_G2_CPU1_G0_TX_DP<12>")
	)
	(segment
		(start 108.176568 -223.083628)
		(end 108.207048 -223.101408)
		(width 0.1143)
		(layer "In2.Cu")
		(net "GMI_CPU0_G2_CPU1_G0_TX_DP<12>")
	)
	(segment
		(start 108.168948 -223.079056)
		(end 108.175806 -223.08312)
		(width 0.1143)
		(layer "In2.Cu")
		(net "GMI_CPU0_G2_CPU1_G0_TX_DP<12>")
	)
	(segment
		(start 106.79811 -229.416864)
		(end 106.758994 -229.439724)
		(width 0.1143)
		(layer "In2.Cu")
		(net "GMI_CPU0_G2_CPU1_G0_TX_DP<12>")
	)
	(segment
		(start 107.262422 -228.610414)
		(end 107.26166 -228.610922)
		(width 0.1143)
		(layer "In2.Cu")
		(net "GMI_CPU0_G2_CPU1_G0_TX_DP<12>")
	)
	(segment
		(start 363.287818 -225.366834)
		(end 363.287056 -225.366326)
		(width 0.1143)
		(layer "In2.Cu")
		(net "GMI_CPU0_G2_CPU1_G0_TX_DP<12>")
	)
	(segment
		(start 107.271566 -228.60508)
		(end 107.268772 -228.606604)
		(width 0.1143)
		(layer "In2.Cu")
		(net "GMI_CPU0_G2_CPU1_G0_TX_DP<12>")
	)
	(segment
		(start 108.201714 -226.99091)
		(end 108.168948 -227.00996)
		(width 0.1143)
		(layer "In2.Cu")
		(net "GMI_CPU0_G2_CPU1_G0_TX_DP<12>")
	)
	(segment
		(start 363.287818 -224.721674)
		(end 363.288834 -224.721166)
		(width 0.1143)
		(layer "In2.Cu")
		(net "GMI_CPU0_G2_CPU1_G0_TX_DP<12>")
	)
	(segment
		(start 107.44327 -221.174564)
		(end 107.44327 -221.203012)
		(width 0.1143)
		(layer "In2.Cu")
		(net "GMI_CPU0_G2_CPU1_G0_TX_DP<12>")
	)
	(segment
		(start 108.259626 -223.714564)
		(end 108.239814 -223.728788)
		(width 0.1143)
		(layer "In2.Cu")
		(net "GMI_CPU0_G2_CPU1_G0_TX_DP<12>")
	)
	(segment
		(start 363.287056 -223.746314)
		(end 363.285786 -223.745552)
		(width 0.1143)
		(layer "In2.Cu")
		(net "GMI_CPU0_G2_CPU1_G0_TX_DP<12>")
	)
	(segment
		(start 108.259626 -225.334576)
		(end 108.239814 -225.3488)
		(width 0.1143)
		(layer "In2.Cu")
		(net "GMI_CPU0_G2_CPU1_G0_TX_DP<12>")
	)
	(segment
		(start 108.207048 -223.747584)
		(end 108.205524 -223.7486)
		(width 0.1143)
		(layer "In2.Cu")
		(net "GMI_CPU0_G2_CPU1_G0_TX_DP<12>")
	)
	(segment
		(start 113.007394 -212.996272)
		(end 113.007394 -212.996526)
		(width 0.14224)
		(layer "In2.Cu")
		(net "GMI_CPU0_G2_CPU1_G0_TX_DP<12>")
	)
	(segment
		(start 363.288834 -224.721166)
		(end 363.290358 -224.72015)
		(width 0.1143)
		(layer "In2.Cu")
		(net "GMI_CPU0_G2_CPU1_G0_TX_DP<12>")
	)
	(segment
		(start 363.285786 -225.365564)
		(end 363.256068 -225.348546)
		(width 0.1143)
		(layer "In2.Cu")
		(net "GMI_CPU0_G2_CPU1_G0_TX_DP<12>")
	)
	(segment
		(start 363.287818 -226.341686)
		(end 363.288834 -226.341178)
		(width 0.1143)
		(layer "In2.Cu")
		(net "GMI_CPU0_G2_CPU1_G0_TX_DP<12>")
	)
	(segment
		(start 108.175806 -224.703132)
		(end 108.176568 -224.70364)
		(width 0.1143)
		(layer "In2.Cu")
		(net "GMI_CPU0_G2_CPU1_G0_TX_DP<12>")
	)
	(segment
		(start 363.284262 -222.124778)
		(end 363.2835 -222.12427)
		(width 0.1143)
		(layer "In2.Cu")
		(net "GMI_CPU0_G2_CPU1_G0_TX_DP<12>")
	)
	(segment
		(start 107.263692 -228.609652)
		(end 107.262422 -228.610414)
		(width 0.1143)
		(layer "In2.Cu")
		(net "GMI_CPU0_G2_CPU1_G0_TX_DP<12>")
	)
	(segment
		(start 363.288834 -222.127318)
		(end 363.287818 -222.12681)
		(width 0.1143)
		(layer "In2.Cu")
		(net "GMI_CPU0_G2_CPU1_G0_TX_DP<12>")
	)
	(segment
		(start 311.020206 -188.53531)
		(end 307.36159 -187.890404)
		(width 0.14224)
		(layer "In2.Cu")
		(net "GMI_CPU0_G2_CPU1_G0_TX_DP<12>")
	)
	(segment
		(start 107.268772 -228.606604)
		(end 107.26801 -228.607112)
		(width 0.1143)
		(layer "In2.Cu")
		(net "GMI_CPU0_G2_CPU1_G0_TX_DP<12>")
	)
	(segment
		(start 108.203746 -225.369628)
		(end 108.202476 -225.37039)
		(width 0.1143)
		(layer "In2.Cu")
		(net "GMI_CPU0_G2_CPU1_G0_TX_DP<12>")
	)
	(segment
		(start 107.44327 -218.561666)
		(end 107.44327 -221.174564)
		(width 0.14224)
		(layer "In2.Cu")
		(net "GMI_CPU0_G2_CPU1_G0_TX_DP<12>")
	)
	(segment
		(start 363.287056 -225.366326)
		(end 363.285786 -225.365564)
		(width 0.1143)
		(layer "In2.Cu")
		(net "GMI_CPU0_G2_CPU1_G0_TX_DP<12>")
	)
	(segment
		(start 108.208826 -226.342448)
		(end 108.239814 -226.360228)
		(width 0.1143)
		(layer "In2.Cu")
		(net "GMI_CPU0_G2_CPU1_G0_TX_DP<12>")
	)
	(segment
		(start 363.100112 -221.405704)
		(end 363.041438 -221.34703)
		(width 0.1143)
		(layer "In2.Cu")
		(net "GMI_CPU0_G2_CPU1_G0_TX_DP<12>")
	)
	(segment
		(start 107.768644 -227.779326)
		(end 107.738164 -227.797106)
		(width 0.1143)
		(layer "In2.Cu")
		(net "GMI_CPU0_G2_CPU1_G0_TX_DP<12>")
	)
	(segment
		(start 108.207048 -223.101408)
		(end 108.208064 -223.101916)
		(width 0.1143)
		(layer "In2.Cu")
		(net "GMI_CPU0_G2_CPU1_G0_TX_DP<12>")
	)
	(segment
		(start 108.207048 -226.987608)
		(end 108.205524 -226.988624)
		(width 0.1143)
		(layer "In2.Cu")
		(net "GMI_CPU0_G2_CPU1_G0_TX_DP<12>")
	)
	(segment
		(start 108.205524 -225.368612)
		(end 108.203746 -225.369628)
		(width 0.1143)
		(layer "In2.Cu")
		(net "GMI_CPU0_G2_CPU1_G0_TX_DP<12>")
	)
	(segment
		(start 364.265972 -228.628956)
		(end 364.23727 -228.612446)
		(width 0.1143)
		(layer "In2.Cu")
		(net "GMI_CPU0_G2_CPU1_G0_TX_DP<12>")
	)
	(segment
		(start 108.208064 -225.367088)
		(end 108.207048 -225.367596)
		(width 0.1143)
		(layer "In2.Cu")
		(net "GMI_CPU0_G2_CPU1_G0_TX_DP<12>")
	)
	(segment
		(start 363.285786 -226.985576)
		(end 363.256068 -226.968558)
		(width 0.1143)
		(layer "In2.Cu")
		(net "GMI_CPU0_G2_CPU1_G0_TX_DP<12>")
	)
	(segment
		(start 108.203746 -226.98964)
		(end 108.202476 -226.990402)
		(width 0.1143)
		(layer "In2.Cu")
		(net "GMI_CPU0_G2_CPU1_G0_TX_DP<12>")
	)
	(segment
		(start 108.176568 -224.70364)
		(end 108.207048 -224.72142)
		(width 0.1143)
		(layer "In2.Cu")
		(net "GMI_CPU0_G2_CPU1_G0_TX_DP<12>")
	)
	(segment
		(start 107.700572 -222.270066)
		(end 107.768644 -222.309944)
		(width 0.1143)
		(layer "In2.Cu")
		(net "GMI_CPU0_G2_CPU1_G0_TX_DP<12>")
	)
	(segment
		(start 363.582966 -227.494084)
		(end 363.582966 -227.466906)
		(width 0.1143)
		(layer "In2.Cu")
		(net "GMI_CPU0_G2_CPU1_G0_TX_DP<12>")
	)
	(segment
		(start 363.287818 -222.12681)
		(end 363.287056 -222.126302)
		(width 0.1143)
		(layer "In2.Cu")
		(net "GMI_CPU0_G2_CPU1_G0_TX_DP<12>")
	)
	(segment
		(start 108.205524 -223.7486)
		(end 108.203746 -223.749616)
		(width 0.1143)
		(layer "In2.Cu")
		(net "GMI_CPU0_G2_CPU1_G0_TX_DP<12>")
	)
	(segment
		(start 108.208826 -225.36658)
		(end 108.208064 -225.367088)
		(width 0.1143)
		(layer "In2.Cu")
		(net "GMI_CPU0_G2_CPU1_G0_TX_DP<12>")
	)
	(segment
		(start 108.208064 -223.101916)
		(end 108.208826 -223.102424)
		(width 0.1143)
		(layer "In2.Cu")
		(net "GMI_CPU0_G2_CPU1_G0_TX_DP<12>")
	)
	(segment
		(start 108.201714 -225.370898)
		(end 108.168948 -225.389948)
		(width 0.1143)
		(layer "In2.Cu")
		(net "GMI_CPU0_G2_CPU1_G0_TX_DP<12>")
	)
	(segment
		(start 363.319314 -225.385122)
		(end 363.287818 -225.366834)
		(width 0.1143)
		(layer "In2.Cu")
		(net "GMI_CPU0_G2_CPU1_G0_TX_DP<12>")
	)
	(segment
		(start 107.44327 -221.203012)
		(end 107.48899 -221.248732)
		(width 0.1143)
		(layer "In2.Cu")
		(net "GMI_CPU0_G2_CPU1_G0_TX_DP<12>")
	)
	(segment
		(start 307.36159 -187.89015)
		(end 307.335936 -187.885832)
		(width 0.14224)
		(layer "In2.Cu")
		(net "GMI_CPU0_G2_CPU1_G0_TX_DP<12>")
	)
	(segment
		(start 108.208064 -226.9871)
		(end 108.207048 -226.987608)
		(width 0.1143)
		(layer "In2.Cu")
		(net "GMI_CPU0_G2_CPU1_G0_TX_DP<12>")
	)
	(segment
		(start 236.469936 -183.476138)
		(end 208.09585 -187.81268)
		(width 0.14224)
		(layer "In2.Cu")
		(net "GMI_CPU0_G2_CPU1_G0_TX_DP<12>")
	)
	(segment
		(start 107.26801 -228.607112)
		(end 107.266994 -228.60762)
		(width 0.1143)
		(layer "In2.Cu")
		(net "GMI_CPU0_G2_CPU1_G0_TX_DP<12>")
	)
	(segment
		(start 363.285786 -223.745552)
		(end 363.256068 -223.728534)
		(width 0.1143)
		(layer "In2.Cu")
		(net "GMI_CPU0_G2_CPU1_G0_TX_DP<12>")
	)
	(segment
		(start 307.36159 -187.890404)
		(end 307.36159 -187.89015)
		(width 0.14224)
		(layer "In2.Cu")
		(net "GMI_CPU0_G2_CPU1_G0_TX_DP<12>")
	)
	(segment
		(start 363.281976 -222.123508)
		(end 363.281214 -222.123)
		(width 0.1143)
		(layer "In2.Cu")
		(net "GMI_CPU0_G2_CPU1_G0_TX_DP<12>")
	)
	(segment
		(start 363.287056 -226.986338)
		(end 363.285786 -226.985576)
		(width 0.1143)
		(layer "In2.Cu")
		(net "GMI_CPU0_G2_CPU1_G0_TX_DP<12>")
	)
	(segment
		(start 363.277404 -222.120968)
		(end 363.256068 -222.108522)
		(width 0.1143)
		(layer "In2.Cu")
		(net "GMI_CPU0_G2_CPU1_G0_TX_DP<12>")
	)
	(segment
		(start 363.279944 -222.122238)
		(end 363.277404 -222.120968)
		(width 0.1143)
		(layer "In2.Cu")
		(net "GMI_CPU0_G2_CPU1_G0_TX_DP<12>")
	)
	(segment
		(start 362.548678 -218.962986)
		(end 357.46817 -214.63762)
		(width 0.14224)
		(layer "In2.Cu")
		(net "GMI_CPU0_G2_CPU1_G0_TX_DP<12>")
	)
	(segment
		(start 363.326934 -223.769682)
		(end 363.320076 -223.765618)
		(width 0.1143)
		(layer "In2.Cu")
		(net "GMI_CPU0_G2_CPU1_G0_TX_DP<12>")
	)
	(segment
		(start 365.056928 -229.904036)
		(end 364.974124 -229.821232)
		(width 0.1143)
		(layer "In2.Cu")
		(net "GMI_CPU0_G2_CPU1_G0_TX_DP<12>")
	)
	(segment
		(start 107.768644 -222.309944)
		(end 107.768644 -222.30969)
		(width 0.1143)
		(layer "In2.Cu")
		(net "GMI_CPU0_G2_CPU1_G0_TX_DP<12>")
	)
	(segment
		(start 108.207048 -226.341432)
		(end 108.208064 -226.34194)
		(width 0.1143)
		(layer "In2.Cu")
		(net "GMI_CPU0_G2_CPU1_G0_TX_DP<12>")
	)
	(segment
		(start 363.320076 -227.005642)
		(end 363.318552 -227.004626)
		(width 0.1143)
		(layer "In2.Cu")
		(net "GMI_CPU0_G2_CPU1_G0_TX_DP<12>")
	)
	(segment
		(start 108.239814 -223.728788)
		(end 108.208826 -223.746568)
		(width 0.1143)
		(layer "In2.Cu")
		(net "GMI_CPU0_G2_CPU1_G0_TX_DP<12>")
	)
	(segment
		(start 113.007394 -212.996526)
		(end 107.44327 -218.561666)
		(width 0.14224)
		(layer "In2.Cu")
		(net "GMI_CPU0_G2_CPU1_G0_TX_DP<12>")
	)
	(segment
		(start 363.314234 -227.002086)
		(end 363.287818 -226.986846)
		(width 0.1143)
		(layer "In2.Cu")
		(net "GMI_CPU0_G2_CPU1_G0_TX_DP<12>")
	)
	(segment
		(start 108.239814 -226.968812)
		(end 108.208826 -226.986592)
		(width 0.1143)
		(layer "In2.Cu")
		(net "GMI_CPU0_G2_CPU1_G0_TX_DP<12>")
	)
	(segment
		(start 364.039912 -228.284024)
		(end 364.039912 -228.282754)
		(width 0.1143)
		(layer "In2.Cu")
		(net "GMI_CPU0_G2_CPU1_G0_TX_DP<12>")
	)
	(segment
		(start 355.839014 -213.57463)
		(end 314.6171 -190.27648)
		(width 0.14224)
		(layer "In2.Cu")
		(net "GMI_CPU0_G2_CPU1_G0_TX_DP<12>")
	)
	(segment
		(start 363.288834 -223.101154)
		(end 363.290358 -223.100138)
		(width 0.1143)
		(layer "In2.Cu")
		(net "GMI_CPU0_G2_CPU1_G0_TX_DP<12>")
	)
	(segment
		(start 363.287056 -223.10217)
		(end 363.287818 -223.101662)
		(width 0.1143)
		(layer "In2.Cu")
		(net "GMI_CPU0_G2_CPU1_G0_TX_DP<12>")
	)
	(segment
		(start 363.326934 -222.14967)
		(end 363.288834 -222.127318)
		(width 0.1143)
		(layer "In2.Cu")
		(net "GMI_CPU0_G2_CPU1_G0_TX_DP<12>")
	)
	(segment
		(start 108.239814 -224.740216)
		(end 108.259626 -224.75444)
		(width 0.1143)
		(layer "In2.Cu")
		(net "GMI_CPU0_G2_CPU1_G0_TX_DP<12>")
	)
	(segment
		(start 363.256068 -224.739962)
		(end 363.287056 -224.722182)
		(width 0.1143)
		(layer "In2.Cu")
		(net "GMI_CPU0_G2_CPU1_G0_TX_DP<12>")
	)
	(segment
		(start 363.288834 -226.341178)
		(end 363.290358 -226.340162)
		(width 0.1143)
		(layer "In2.Cu")
		(net "GMI_CPU0_G2_CPU1_G0_TX_DP<12>")
	)
	(segment
		(start 108.201714 -223.750886)
		(end 108.168948 -223.769936)
		(width 0.1143)
		(layer "In2.Cu")
		(net "GMI_CPU0_G2_CPU1_G0_TX_DP<12>")
	)
	(segment
		(start 363.326934 -225.389694)
		(end 363.320076 -225.38563)
		(width 0.1143)
		(layer "In2.Cu")
		(net "GMI_CPU0_G2_CPU1_G0_TX_DP<12>")
	)
	(segment
		(start 363.256068 -223.11995)
		(end 363.287056 -223.10217)
		(width 0.1143)
		(layer "In2.Cu")
		(net "GMI_CPU0_G2_CPU1_G0_TX_DP<12>")
	)
	(segment
		(start 108.239814 -223.120204)
		(end 108.259626 -223.134428)
		(width 0.1143)
		(layer "In2.Cu")
		(net "GMI_CPU0_G2_CPU1_G0_TX_DP<12>")
	)
	(segment
		(start 314.6171 -190.27648)
		(end 311.020206 -188.53531)
		(width 0.14224)
		(layer "In2.Cu")
		(net "GMI_CPU0_G2_CPU1_G0_TX_DP<12>")
	)
	(segment
		(start 107.26547 -228.608636)
		(end 107.263692 -228.609652)
		(width 0.1143)
		(layer "In2.Cu")
		(net "GMI_CPU0_G2_CPU1_G0_TX_DP<12>")
	)
	(segment
		(start 108.168948 -226.31908)
		(end 108.175806 -226.323144)
		(width 0.1143)
		(layer "In2.Cu")
		(net "GMI_CPU0_G2_CPU1_G0_TX_DP<12>")
	)
	(segment
		(start 307.335936 -187.885832)
		(end 265.179556 -188.386212)
		(width 0.14224)
		(layer "In2.Cu")
		(net "GMI_CPU0_G2_CPU1_G0_TX_DP<12>")
	)
	(segment
		(start 363.770672 -227.816918)
		(end 363.738922 -227.798122)
		(width 0.1143)
		(layer "In2.Cu")
		(net "GMI_CPU0_G2_CPU1_G0_TX_DP<12>")
	)
	(segment
		(start 106.438954 -229.90429)
		(end 106.141012 -229.90429)
		(width 0.1143)
		(layer "In2.Cu")
		(net "GMI_CPU0_G2_CPU1_G0_TX_DP<12>")
	)
	(segment
		(start 363.31525 -227.002594)
		(end 363.314234 -227.002086)
		(width 0.1143)
		(layer "In2.Cu")
		(net "GMI_CPU0_G2_CPU1_G0_TX_DP<12>")
	)
	(segment
		(start 363.290358 -224.72015)
		(end 363.326934 -224.698814)
		(width 0.1143)
		(layer "In2.Cu")
		(net "GMI_CPU0_G2_CPU1_G0_TX_DP<12>")
	)
	(segment
		(start 363.318552 -227.004626)
		(end 363.31525 -227.002594)
		(width 0.1143)
		(layer "In2.Cu")
		(net "GMI_CPU0_G2_CPU1_G0_TX_DP<12>")
	)
	(segment
		(start 108.208826 -223.102424)
		(end 108.239814 -223.120204)
		(width 0.1143)
		(layer "In2.Cu")
		(net "GMI_CPU0_G2_CPU1_G0_TX_DP<12>")
	)
	(segment
		(start 113.36528 -212.638386)
		(end 113.007394 -212.996272)
		(width 0.14224)
		(layer "In2.Cu")
		(net "GMI_CPU0_G2_CPU1_G0_TX_DP<12>")
	)
	(segment
		(start 363.087158 -221.097602)
		(end 363.087158 -221.083124)
		(width 0.1143)
		(layer "In2.Cu")
		(net "GMI_CPU0_G2_CPU1_G0_TX_DP<12>")
	)
	(segment
		(start 108.239814 -225.3488)
		(end 108.208826 -225.36658)
		(width 0.1143)
		(layer "In2.Cu")
		(net "GMI_CPU0_G2_CPU1_G0_TX_DP<12>")
	)
	(segment
		(start 357.46817 -214.63762)
		(end 355.839014 -213.57463)
		(width 0.14224)
		(layer "In2.Cu")
		(net "GMI_CPU0_G2_CPU1_G0_TX_DP<12>")
	)
	(segment
		(start 364.697772 -229.41661)
		(end 364.664244 -229.397052)
		(width 0.1143)
		(layer "In2.Cu")
		(net "GMI_CPU0_G2_CPU1_G0_TX_DP<12>")
	)
	(segment
		(start 108.208064 -223.747076)
		(end 108.207048 -223.747584)
		(width 0.1143)
		(layer "In2.Cu")
		(net "GMI_CPU0_G2_CPU1_G0_TX_DP<12>")
	)
	(segment
		(start 363.256068 -226.359974)
		(end 363.287056 -226.342194)
		(width 0.1143)
		(layer "In2.Cu")
		(net "GMI_CPU0_G2_CPU1_G0_TX_DP<12>")
	)
	(segment
		(start 107.48899 -221.513146)
		(end 107.456224 -221.545912)
		(width 0.1143)
		(layer "In2.Cu")
		(net "GMI_CPU0_G2_CPU1_G0_TX_DP<12>")
	)
	(segment
		(start 363.320076 -223.765618)
		(end 363.319314 -223.76511)
		(width 0.1143)
		(layer "In2.Cu")
		(net "GMI_CPU0_G2_CPU1_G0_TX_DP<12>")
	)
	(segment
		(start 108.207048 -225.367596)
		(end 108.205524 -225.368612)
		(width 0.1143)
		(layer "In2.Cu")
		(net "GMI_CPU0_G2_CPU1_G0_TX_DP<12>")
	)
	(segment
		(start 108.205524 -226.988624)
		(end 108.203746 -226.98964)
		(width 0.1143)
		(layer "In2.Cu")
		(net "GMI_CPU0_G2_CPU1_G0_TX_DP<12>")
	)
	(segment
		(start 108.168948 -224.699068)
		(end 108.175806 -224.703132)
		(width 0.1143)
		(layer "In2.Cu")
		(net "GMI_CPU0_G2_CPU1_G0_TX_DP<12>")
	)
	(segment
		(start 107.266994 -228.60762)
		(end 107.26547 -228.608636)
		(width 0.1143)
		(layer "In2.Cu")
		(net "GMI_CPU0_G2_CPU1_G0_TX_DP<12>")
	)
	(segment
		(start 363.287818 -223.101662)
		(end 363.288834 -223.101154)
		(width 0.1143)
		(layer "In2.Cu")
		(net "GMI_CPU0_G2_CPU1_G0_TX_DP<12>")
	)
	(segment
		(start 108.176568 -226.323652)
		(end 108.207048 -226.341432)
		(width 0.1143)
		(layer "In2.Cu")
		(net "GMI_CPU0_G2_CPU1_G0_TX_DP<12>")
	)
	(segment
		(start 265.179556 -188.386212)
		(end 236.469936 -183.476138)
		(width 0.14224)
		(layer "In2.Cu")
		(net "GMI_CPU0_G2_CPU1_G0_TX_DP<12>")
	)
	(segment
		(start 108.208826 -223.746568)
		(end 108.208064 -223.747076)
		(width 0.1143)
		(layer "In2.Cu")
		(net "GMI_CPU0_G2_CPU1_G0_TX_DP<12>")
	)
	(segment
		(start 108.202476 -225.37039)
		(end 108.201714 -225.370898)
		(width 0.1143)
		(layer "In2.Cu")
		(net "GMI_CPU0_G2_CPU1_G0_TX_DP<12>")
	)
	(segment
		(start 363.087158 -220.129608)
		(end 362.548678 -218.962986)
		(width 0.14224)
		(layer "In2.Cu")
		(net "GMI_CPU0_G2_CPU1_G0_TX_DP<12>")
	)
	(segment
		(start 363.287056 -222.126302)
		(end 363.284262 -222.124778)
		(width 0.1143)
		(layer "In2.Cu")
		(net "GMI_CPU0_G2_CPU1_G0_TX_DP<12>")
	)
	(segment
		(start 363.287818 -226.986846)
		(end 363.287056 -226.986338)
		(width 0.1143)
		(layer "In2.Cu")
		(net "GMI_CPU0_G2_CPU1_G0_TX_DP<12>")
	)
	(segment
		(start 363.287056 -226.342194)
		(end 363.287818 -226.341686)
		(width 0.1143)
		(layer "In2.Cu")
		(net "GMI_CPU0_G2_CPU1_G0_TX_DP<12>")
	)
	(segment
		(start 107.272328 -228.604572)
		(end 107.271566 -228.60508)
		(width 0.1143)
		(layer "In2.Cu")
		(net "GMI_CPU0_G2_CPU1_G0_TX_DP<12>")
	)
	(segment
		(start 108.208064 -226.34194)
		(end 108.208826 -226.342448)
		(width 0.1143)
		(layer "In2.Cu")
		(net "GMI_CPU0_G2_CPU1_G0_TX_DP<12>")
	)
	(segment
		(start 108.175806 -223.08312)
		(end 108.176568 -223.083628)
		(width 0.1143)
		(layer "In2.Cu")
		(net "GMI_CPU0_G2_CPU1_G0_TX_DP<12>")
	)
	(segment
		(start 106.830622 -229.398068)
		(end 106.79811 -229.416864)
		(width 0.1143)
		(layer "In2.Cu")
		(net "GMI_CPU0_G2_CPU1_G0_TX_DP<12>")
	)
	(segment
		(start 363.319314 -223.76511)
		(end 363.287818 -223.746822)
		(width 0.1143)
		(layer "In2.Cu")
		(net "GMI_CPU0_G2_CPU1_G0_TX_DP<12>")
	)
	(segment
		(start 363.087158 -221.083124)
		(end 363.087158 -220.129608)
		(width 0.14224)
		(layer "In2.Cu")
		(net "GMI_CPU0_G2_CPU1_G0_TX_DP<12>")
	)
	(segment
		(start 363.100112 -221.80423)
		(end 363.100112 -221.405704)
		(width 0.1143)
		(layer "In2.Cu")
		(net "GMI_CPU0_G2_CPU1_G0_TX_DP<12>")
	)
	(segment
		(start 107.738164 -227.797106)
		(end 107.699048 -227.819966)
		(width 0.1143)
		(layer "In2.Cu")
		(net "GMI_CPU0_G2_CPU1_G0_TX_DP<12>")
	)
	(segment
		(start 107.26166 -228.610922)
		(end 107.228894 -228.629972)
		(width 0.1143)
		(layer "In2.Cu")
		(net "GMI_CPU0_G2_CPU1_G0_TX_DP<12>")
	)
	(arc
		(start 364.23727 -228.612446)
		(mid 364.22103 -228.603321)
		(end 364.205266 -228.593396)
		(width 0.1143)
		(layer "In2.Cu")
		(net "GMI_CPU0_G2_CPU1_G0_TX_DP<12>")
	)
	(arc
		(start 108.168948 -225.389948)
		(mid 107.925621 -225.854514)
		(end 108.168948 -226.31908)
		(width 0.1143)
		(layer "In2.Cu")
		(net "GMI_CPU0_G2_CPU1_G0_TX_DP<12>")
	)
	(arc
		(start 363.582966 -227.466906)
		(mid 363.512636 -227.201436)
		(end 363.320076 -227.005642)
		(width 0.1143)
		(layer "In2.Cu")
		(net "GMI_CPU0_G2_CPU1_G0_TX_DP<12>")
	)
	(arc
		(start 108.259626 -223.134428)
		(mid 108.40834 -223.424496)
		(end 108.259626 -223.714564)
		(width 0.1143)
		(layer "In2.Cu")
		(net "GMI_CPU0_G2_CPU1_G0_TX_DP<12>")
	)
	(arc
		(start 107.456224 -221.805246)
		(mid 107.521025 -222.067822)
		(end 107.700572 -222.270066)
		(width 0.1143)
		(layer "In2.Cu")
		(net "GMI_CPU0_G2_CPU1_G0_TX_DP<12>")
	)
	(arc
		(start 363.738922 -227.798122)
		(mid 363.624246 -227.664931)
		(end 363.582966 -227.494084)
		(width 0.1143)
		(layer "In2.Cu")
		(net "GMI_CPU0_G2_CPU1_G0_TX_DP<12>")
	)
	(arc
		(start 363.256068 -223.728534)
		(mid 363.10014 -223.424242)
		(end 363.256068 -223.11995)
		(width 0.1143)
		(layer "In2.Cu")
		(net "GMI_CPU0_G2_CPU1_G0_TX_DP<12>")
	)
	(arc
		(start 363.326934 -226.318826)
		(mid 363.570261 -225.85426)
		(end 363.326934 -225.389694)
		(width 0.1143)
		(layer "In2.Cu")
		(net "GMI_CPU0_G2_CPU1_G0_TX_DP<12>")
	)
	(arc
		(start 363.326934 -224.698814)
		(mid 363.570261 -224.234248)
		(end 363.326934 -223.769682)
		(width 0.1143)
		(layer "In2.Cu")
		(net "GMI_CPU0_G2_CPU1_G0_TX_DP<12>")
	)
	(arc
		(start 107.699048 -227.819966)
		(mid 107.520235 -228.022316)
		(end 107.455716 -228.284532)
		(width 0.1143)
		(layer "In2.Cu")
		(net "GMI_CPU0_G2_CPU1_G0_TX_DP<12>")
	)
	(arc
		(start 363.326934 -223.078802)
		(mid 363.570261 -222.614236)
		(end 363.326934 -222.14967)
		(width 0.1143)
		(layer "In2.Cu")
		(net "GMI_CPU0_G2_CPU1_G0_TX_DP<12>")
	)
	(arc
		(start 364.039912 -228.282754)
		(mid 363.967105 -228.014122)
		(end 363.770672 -227.816918)
		(width 0.1143)
		(layer "In2.Cu")
		(net "GMI_CPU0_G2_CPU1_G0_TX_DP<12>")
	)
	(arc
		(start 364.974124 -229.821232)
		(mid 364.895045 -229.605787)
		(end 364.736888 -229.43947)
		(width 0.1143)
		(layer "In2.Cu")
		(net "GMI_CPU0_G2_CPU1_G0_TX_DP<12>")
	)
	(arc
		(start 364.664244 -229.397052)
		(mid 364.550837 -229.264163)
		(end 364.510066 -229.094284)
		(width 0.1143)
		(layer "In2.Cu")
		(net "GMI_CPU0_G2_CPU1_G0_TX_DP<12>")
	)
	(arc
		(start 108.259626 -224.75444)
		(mid 108.40834 -225.044508)
		(end 108.259626 -225.334576)
		(width 0.1143)
		(layer "In2.Cu")
		(net "GMI_CPU0_G2_CPU1_G0_TX_DP<12>")
	)
	(arc
		(start 107.228894 -228.629972)
		(mid 107.050081 -228.832322)
		(end 106.985562 -229.094538)
		(width 0.1143)
		(layer "In2.Cu")
		(net "GMI_CPU0_G2_CPU1_G0_TX_DP<12>")
	)
	(arc
		(start 363.256068 -226.968558)
		(mid 363.10014 -226.664266)
		(end 363.256068 -226.359974)
		(width 0.1143)
		(layer "In2.Cu")
		(net "GMI_CPU0_G2_CPU1_G0_TX_DP<12>")
	)
	(arc
		(start 363.256068 -222.108522)
		(mid 363.141392 -221.975188)
		(end 363.100112 -221.80423)
		(width 0.1143)
		(layer "In2.Cu")
		(net "GMI_CPU0_G2_CPU1_G0_TX_DP<12>")
	)
	(arc
		(start 106.985562 -229.094538)
		(mid 106.944596 -229.264944)
		(end 106.830622 -229.398068)
		(width 0.1143)
		(layer "In2.Cu")
		(net "GMI_CPU0_G2_CPU1_G0_TX_DP<12>")
	)
	(arc
		(start 364.205266 -228.593396)
		(mid 364.083864 -228.459423)
		(end 364.039912 -228.284024)
		(width 0.1143)
		(layer "In2.Cu")
		(net "GMI_CPU0_G2_CPU1_G0_TX_DP<12>")
	)
	(arc
		(start 106.758994 -229.439724)
		(mid 106.607007 -229.596232)
		(end 106.525568 -229.798626)
		(width 0.1143)
		(layer "In2.Cu")
		(net "GMI_CPU0_G2_CPU1_G0_TX_DP<12>")
	)
	(arc
		(start 108.239814 -226.360228)
		(mid 108.391403 -226.66452)
		(end 108.239814 -226.968812)
		(width 0.1143)
		(layer "In2.Cu")
		(net "GMI_CPU0_G2_CPU1_G0_TX_DP<12>")
	)
	(arc
		(start 108.168948 -227.00996)
		(mid 107.990135 -227.21231)
		(end 107.925616 -227.474526)
		(width 0.1143)
		(layer "In2.Cu")
		(net "GMI_CPU0_G2_CPU1_G0_TX_DP<12>")
	)
	(arc
		(start 108.168948 -223.769936)
		(mid 107.925621 -224.234502)
		(end 108.168948 -224.699068)
		(width 0.1143)
		(layer "In2.Cu")
		(net "GMI_CPU0_G2_CPU1_G0_TX_DP<12>")
	)
	(arc
		(start 107.925616 -227.474526)
		(mid 107.884067 -227.645948)
		(end 107.768644 -227.779326)
		(width 0.1143)
		(layer "In2.Cu")
		(net "GMI_CPU0_G2_CPU1_G0_TX_DP<12>")
	)
	(arc
		(start 363.256068 -225.348546)
		(mid 363.10014 -225.044254)
		(end 363.256068 -224.739962)
		(width 0.1143)
		(layer "In2.Cu")
		(net "GMI_CPU0_G2_CPU1_G0_TX_DP<12>")
	)
	(arc
		(start 106.525568 -229.798626)
		(mid 106.523545 -229.810036)
		(end 106.521758 -229.821486)
		(width 0.1143)
		(layer "In2.Cu")
		(net "GMI_CPU0_G2_CPU1_G0_TX_DP<12>")
	)
	(arc
		(start 107.925616 -222.61449)
		(mid 107.990131 -222.876709)
		(end 108.168948 -223.079056)
		(width 0.1143)
		(layer "In2.Cu")
		(net "GMI_CPU0_G2_CPU1_G0_TX_DP<12>")
	)
	(arc
		(start 364.510066 -229.094284)
		(mid 364.445344 -228.831545)
		(end 364.265972 -228.628956)
		(width 0.1143)
		(layer "In2.Cu")
		(net "GMI_CPU0_G2_CPU1_G0_TX_DP<12>")
	)
	(arc
		(start 107.768644 -222.30969)
		(mid 107.884071 -222.443066)
		(end 107.925616 -222.61449)
		(width 0.1143)
		(layer "In2.Cu")
		(net "GMI_CPU0_G2_CPU1_G0_TX_DP<12>")
	)
	(arc
		(start 107.455716 -228.284532)
		(mid 107.414461 -228.455503)
		(end 107.29976 -228.588824)
		(width 0.1143)
		(layer "In2.Cu")
		(net "GMI_CPU0_G2_CPU1_G0_TX_DP<12>")
	)
	(segment
		(start 106.607864 -226.930458)
		(end 106.141012 -226.66452)
		(width 0.12954)
		(layer "F.Cu")
		(net "GMI_CPU0_G2_CPU1_G0_TX_DP<11>")
	)
	(segment
		(start 364.888018 -226.930204)
		(end 365.35487 -226.664266)
		(width 0.12954)
		(layer "F.Cu")
		(net "GMI_CPU0_G2_CPU1_G0_TX_DP<11>")
	)
	(segment
		(start 365.167672 -222.12681)
		(end 365.137192 -222.10903)
		(width 0.1143)
		(layer "In2.Cu")
		(net "GMI_CPU0_G2_CPU1_G0_TX_DP<11>")
	)
	(segment
		(start 356.73792 -211.802218)
		(end 321.291966 -190.800482)
		(width 0.14224)
		(layer "In2.Cu")
		(net "GMI_CPU0_G2_CPU1_G0_TX_DP<11>")
	)
	(segment
		(start 364.22584 -217.841322)
		(end 359.259632 -213.51113)
		(width 0.14224)
		(layer "In2.Cu")
		(net "GMI_CPU0_G2_CPU1_G0_TX_DP<11>")
	)
	(segment
		(start 364.98022 -221.396052)
		(end 364.931198 -221.34703)
		(width 0.1143)
		(layer "In2.Cu")
		(net "GMI_CPU0_G2_CPU1_G0_TX_DP<11>")
	)
	(segment
		(start 105.55351 -221.174564)
		(end 105.55351 -221.203012)
		(width 0.1143)
		(layer "In2.Cu")
		(net "GMI_CPU0_G2_CPU1_G0_TX_DP<11>")
	)
	(segment
		(start 166.452042 -183.654446)
		(end 165.257226 -183.969152)
		(width 0.14224)
		(layer "In2.Cu")
		(net "GMI_CPU0_G2_CPU1_G0_TX_DP<11>")
	)
	(segment
		(start 309.040276 -184.888124)
		(end 307.768752 -184.403238)
		(width 0.14224)
		(layer "In2.Cu")
		(net "GMI_CPU0_G2_CPU1_G0_TX_DP<11>")
	)
	(segment
		(start 112.339374 -210.573366)
		(end 105.55351 -217.35923)
		(width 0.14224)
		(layer "In2.Cu")
		(net "GMI_CPU0_G2_CPU1_G0_TX_DP<11>")
	)
	(segment
		(start 321.291966 -190.800482)
		(end 309.040276 -184.888124)
		(width 0.14224)
		(layer "In2.Cu")
		(net "GMI_CPU0_G2_CPU1_G0_TX_DP<11>")
	)
	(segment
		(start 106.327956 -223.101916)
		(end 106.359706 -223.120204)
		(width 0.1143)
		(layer "In2.Cu")
		(net "GMI_CPU0_G2_CPU1_G0_TX_DP<11>")
	)
	(segment
		(start 365.137192 -226.359466)
		(end 365.167672 -226.341686)
		(width 0.1143)
		(layer "In2.Cu")
		(net "GMI_CPU0_G2_CPU1_G0_TX_DP<11>")
	)
	(segment
		(start 106.508804 -226.59467)
		(end 106.438954 -226.66452)
		(width 0.1143)
		(layer "In2.Cu")
		(net "GMI_CPU0_G2_CPU1_G0_TX_DP<11>")
	)
	(segment
		(start 105.575862 -221.80423)
		(end 105.575608 -221.804484)
		(width 0.1143)
		(layer "In2.Cu")
		(net "GMI_CPU0_G2_CPU1_G0_TX_DP<11>")
	)
	(segment
		(start 365.167672 -223.101662)
		(end 365.206788 -223.078802)
		(width 0.1143)
		(layer "In2.Cu")
		(net "GMI_CPU0_G2_CPU1_G0_TX_DP<11>")
	)
	(segment
		(start 155.766262 -187.666376)
		(end 112.339374 -210.573366)
		(width 0.14224)
		(layer "In2.Cu")
		(net "GMI_CPU0_G2_CPU1_G0_TX_DP<11>")
	)
	(segment
		(start 106.359706 -225.3488)
		(end 106.327956 -225.367088)
		(width 0.1143)
		(layer "In2.Cu")
		(net "GMI_CPU0_G2_CPU1_G0_TX_DP<11>")
	)
	(segment
		(start 365.206788 -225.389694)
		(end 365.167672 -225.366834)
		(width 0.1143)
		(layer "In2.Cu")
		(net "GMI_CPU0_G2_CPU1_G0_TX_DP<11>")
	)
	(segment
		(start 364.98022 -221.80423)
		(end 364.98022 -221.396052)
		(width 0.1143)
		(layer "In2.Cu")
		(net "GMI_CPU0_G2_CPU1_G0_TX_DP<11>")
	)
	(segment
		(start 105.55351 -221.203012)
		(end 105.59923 -221.248732)
		(width 0.1143)
		(layer "In2.Cu")
		(net "GMI_CPU0_G2_CPU1_G0_TX_DP<11>")
	)
	(segment
		(start 365.137192 -224.739454)
		(end 365.167672 -224.721674)
		(width 0.1143)
		(layer "In2.Cu")
		(net "GMI_CPU0_G2_CPU1_G0_TX_DP<11>")
	)
	(segment
		(start 106.359706 -223.728788)
		(end 106.327956 -223.747076)
		(width 0.1143)
		(layer "In2.Cu")
		(net "GMI_CPU0_G2_CPU1_G0_TX_DP<11>")
	)
	(segment
		(start 364.976918 -219.492322)
		(end 364.22584 -217.841322)
		(width 0.14224)
		(layer "In2.Cu")
		(net "GMI_CPU0_G2_CPU1_G0_TX_DP<11>")
	)
	(segment
		(start 165.257226 -183.969152)
		(end 155.766262 -187.666376)
		(width 0.14224)
		(layer "In2.Cu")
		(net "GMI_CPU0_G2_CPU1_G0_TX_DP<11>")
	)
	(segment
		(start 365.167672 -224.721674)
		(end 365.206788 -224.698814)
		(width 0.1143)
		(layer "In2.Cu")
		(net "GMI_CPU0_G2_CPU1_G0_TX_DP<11>")
	)
	(segment
		(start 364.931198 -221.34703)
		(end 364.931198 -221.128844)
		(width 0.1143)
		(layer "In2.Cu")
		(net "GMI_CPU0_G2_CPU1_G0_TX_DP<11>")
	)
	(segment
		(start 106.327956 -226.34194)
		(end 106.359706 -226.360228)
		(width 0.1143)
		(layer "In2.Cu")
		(net "GMI_CPU0_G2_CPU1_G0_TX_DP<11>")
	)
	(segment
		(start 106.327956 -223.747076)
		(end 106.291634 -223.768158)
		(width 0.1143)
		(layer "In2.Cu")
		(net "GMI_CPU0_G2_CPU1_G0_TX_DP<11>")
	)
	(segment
		(start 365.167672 -223.746822)
		(end 365.137192 -223.729042)
		(width 0.1143)
		(layer "In2.Cu")
		(net "GMI_CPU0_G2_CPU1_G0_TX_DP<11>")
	)
	(segment
		(start 105.55351 -217.35923)
		(end 105.55351 -221.174564)
		(width 0.14224)
		(layer "In2.Cu")
		(net "GMI_CPU0_G2_CPU1_G0_TX_DP<11>")
	)
	(segment
		(start 365.167672 -226.341686)
		(end 365.206788 -226.318826)
		(width 0.1143)
		(layer "In2.Cu")
		(net "GMI_CPU0_G2_CPU1_G0_TX_DP<11>")
	)
	(segment
		(start 106.327956 -225.367088)
		(end 106.291634 -225.38817)
		(width 0.1143)
		(layer "In2.Cu")
		(net "GMI_CPU0_G2_CPU1_G0_TX_DP<11>")
	)
	(segment
		(start 106.291634 -226.320858)
		(end 106.327956 -226.34194)
		(width 0.1143)
		(layer "In2.Cu")
		(net "GMI_CPU0_G2_CPU1_G0_TX_DP<11>")
	)
	(segment
		(start 106.327956 -224.721928)
		(end 106.359706 -224.740216)
		(width 0.1143)
		(layer "In2.Cu")
		(net "GMI_CPU0_G2_CPU1_G0_TX_DP<11>")
	)
	(segment
		(start 365.206788 -223.769682)
		(end 365.167672 -223.746822)
		(width 0.1143)
		(layer "In2.Cu")
		(net "GMI_CPU0_G2_CPU1_G0_TX_DP<11>")
	)
	(segment
		(start 307.768752 -184.403238)
		(end 306.172616 -183.987948)
		(width 0.14224)
		(layer "In2.Cu")
		(net "GMI_CPU0_G2_CPU1_G0_TX_DP<11>")
	)
	(segment
		(start 105.59923 -221.543118)
		(end 105.575862 -221.566486)
		(width 0.1143)
		(layer "In2.Cu")
		(net "GMI_CPU0_G2_CPU1_G0_TX_DP<11>")
	)
	(segment
		(start 106.056176 -222.622872)
		(end 106.056176 -222.629984)
		(width 0.1143)
		(layer "In2.Cu")
		(net "GMI_CPU0_G2_CPU1_G0_TX_DP<11>")
	)
	(segment
		(start 236.610652 -181.57063)
		(end 166.452042 -183.654446)
		(width 0.14224)
		(layer "In2.Cu")
		(net "GMI_CPU0_G2_CPU1_G0_TX_DP<11>")
	)
	(segment
		(start 105.59923 -221.248732)
		(end 105.59923 -221.543118)
		(width 0.1143)
		(layer "In2.Cu")
		(net "GMI_CPU0_G2_CPU1_G0_TX_DP<11>")
	)
	(segment
		(start 365.206788 -222.14967)
		(end 365.167672 -222.12681)
		(width 0.1143)
		(layer "In2.Cu")
		(net "GMI_CPU0_G2_CPU1_G0_TX_DP<11>")
	)
	(segment
		(start 365.056928 -226.664266)
		(end 364.987078 -226.594416)
		(width 0.1143)
		(layer "In2.Cu")
		(net "GMI_CPU0_G2_CPU1_G0_TX_DP<11>")
	)
	(segment
		(start 106.438954 -226.66452)
		(end 106.141012 -226.66452)
		(width 0.1143)
		(layer "In2.Cu")
		(net "GMI_CPU0_G2_CPU1_G0_TX_DP<11>")
	)
	(segment
		(start 364.976918 -221.083124)
		(end 364.976918 -219.492322)
		(width 0.14224)
		(layer "In2.Cu")
		(net "GMI_CPU0_G2_CPU1_G0_TX_DP<11>")
	)
	(segment
		(start 106.291634 -224.700846)
		(end 106.327956 -224.721928)
		(width 0.1143)
		(layer "In2.Cu")
		(net "GMI_CPU0_G2_CPU1_G0_TX_DP<11>")
	)
	(segment
		(start 359.259632 -213.51113)
		(end 356.73792 -211.802218)
		(width 0.14224)
		(layer "In2.Cu")
		(net "GMI_CPU0_G2_CPU1_G0_TX_DP<11>")
	)
	(segment
		(start 306.172616 -183.987948)
		(end 236.610652 -181.57063)
		(width 0.14224)
		(layer "In2.Cu")
		(net "GMI_CPU0_G2_CPU1_G0_TX_DP<11>")
	)
	(segment
		(start 105.575862 -221.566486)
		(end 105.575862 -221.80423)
		(width 0.1143)
		(layer "In2.Cu")
		(net "GMI_CPU0_G2_CPU1_G0_TX_DP<11>")
	)
	(segment
		(start 365.35487 -226.664266)
		(end 365.056928 -226.664266)
		(width 0.1143)
		(layer "In2.Cu")
		(net "GMI_CPU0_G2_CPU1_G0_TX_DP<11>")
	)
	(segment
		(start 105.81894 -222.26905)
		(end 105.86847 -222.298006)
		(width 0.1143)
		(layer "In2.Cu")
		(net "GMI_CPU0_G2_CPU1_G0_TX_DP<11>")
	)
	(segment
		(start 365.137192 -223.119442)
		(end 365.167672 -223.101662)
		(width 0.1143)
		(layer "In2.Cu")
		(net "GMI_CPU0_G2_CPU1_G0_TX_DP<11>")
	)
	(segment
		(start 364.931198 -221.128844)
		(end 364.976918 -221.083124)
		(width 0.1143)
		(layer "In2.Cu")
		(net "GMI_CPU0_G2_CPU1_G0_TX_DP<11>")
	)
	(segment
		(start 365.167672 -225.366834)
		(end 365.137192 -225.349054)
		(width 0.1143)
		(layer "In2.Cu")
		(net "GMI_CPU0_G2_CPU1_G0_TX_DP<11>")
	)
	(arc
		(start 365.137192 -222.10903)
		(mid 365.021765 -221.975654)
		(end 364.98022 -221.80423)
		(width 0.1143)
		(layer "In2.Cu")
		(net "GMI_CPU0_G2_CPU1_G0_TX_DP<11>")
	)
	(arc
		(start 106.275378 -226.309428)
		(mid 106.283456 -226.315214)
		(end 106.291634 -226.320858)
		(width 0.1143)
		(layer "In2.Cu")
		(net "GMI_CPU0_G2_CPU1_G0_TX_DP<11>")
	)
	(arc
		(start 106.056176 -222.629984)
		(mid 106.128981 -222.902277)
		(end 106.327956 -223.101916)
		(width 0.1143)
		(layer "In2.Cu")
		(net "GMI_CPU0_G2_CPU1_G0_TX_DP<11>")
	)
	(arc
		(start 106.359706 -226.360228)
		(mid 106.456841 -226.463097)
		(end 106.508804 -226.59467)
		(width 0.1143)
		(layer "In2.Cu")
		(net "GMI_CPU0_G2_CPU1_G0_TX_DP<11>")
	)
	(arc
		(start 105.86847 -222.298006)
		(mid 106.005902 -222.435265)
		(end 106.056176 -222.622872)
		(width 0.1143)
		(layer "In2.Cu")
		(net "GMI_CPU0_G2_CPU1_G0_TX_DP<11>")
	)
	(arc
		(start 106.359706 -223.120204)
		(mid 106.515634 -223.424496)
		(end 106.359706 -223.728788)
		(width 0.1143)
		(layer "In2.Cu")
		(net "GMI_CPU0_G2_CPU1_G0_TX_DP<11>")
	)
	(arc
		(start 106.291634 -223.768158)
		(mid 106.28397 -223.773429)
		(end 106.276394 -223.778826)
		(width 0.1143)
		(layer "In2.Cu")
		(net "GMI_CPU0_G2_CPU1_G0_TX_DP<11>")
	)
	(arc
		(start 106.359706 -224.740216)
		(mid 106.515634 -225.044508)
		(end 106.359706 -225.3488)
		(width 0.1143)
		(layer "In2.Cu")
		(net "GMI_CPU0_G2_CPU1_G0_TX_DP<11>")
	)
	(arc
		(start 365.137192 -225.349054)
		(mid 364.980215 -225.044254)
		(end 365.137192 -224.739454)
		(width 0.1143)
		(layer "In2.Cu")
		(net "GMI_CPU0_G2_CPU1_G0_TX_DP<11>")
	)
	(arc
		(start 106.275378 -225.3996)
		(mid 106.052494 -225.854514)
		(end 106.275378 -226.309428)
		(width 0.1143)
		(layer "In2.Cu")
		(net "GMI_CPU0_G2_CPU1_G0_TX_DP<11>")
	)
	(arc
		(start 106.276394 -224.690178)
		(mid 106.28397 -224.695574)
		(end 106.291634 -224.700846)
		(width 0.1143)
		(layer "In2.Cu")
		(net "GMI_CPU0_G2_CPU1_G0_TX_DP<11>")
	)
	(arc
		(start 364.987078 -226.594416)
		(mid 365.039495 -226.462485)
		(end 365.137192 -226.359466)
		(width 0.1143)
		(layer "In2.Cu")
		(net "GMI_CPU0_G2_CPU1_G0_TX_DP<11>")
	)
	(arc
		(start 105.575608 -221.804484)
		(mid 105.640123 -222.066703)
		(end 105.81894 -222.26905)
		(width 0.1143)
		(layer "In2.Cu")
		(net "GMI_CPU0_G2_CPU1_G0_TX_DP<11>")
	)
	(arc
		(start 365.206788 -226.318826)
		(mid 365.450115 -225.85426)
		(end 365.206788 -225.389694)
		(width 0.1143)
		(layer "In2.Cu")
		(net "GMI_CPU0_G2_CPU1_G0_TX_DP<11>")
	)
	(arc
		(start 106.276394 -223.778826)
		(mid 106.051223 -224.234502)
		(end 106.276394 -224.690178)
		(width 0.1143)
		(layer "In2.Cu")
		(net "GMI_CPU0_G2_CPU1_G0_TX_DP<11>")
	)
	(arc
		(start 365.137192 -223.729042)
		(mid 364.980215 -223.424242)
		(end 365.137192 -223.119442)
		(width 0.1143)
		(layer "In2.Cu")
		(net "GMI_CPU0_G2_CPU1_G0_TX_DP<11>")
	)
	(arc
		(start 365.206788 -223.078802)
		(mid 365.450115 -222.614236)
		(end 365.206788 -222.14967)
		(width 0.1143)
		(layer "In2.Cu")
		(net "GMI_CPU0_G2_CPU1_G0_TX_DP<11>")
	)
	(arc
		(start 106.291634 -225.38817)
		(mid 106.283456 -225.393813)
		(end 106.275378 -225.3996)
		(width 0.1143)
		(layer "In2.Cu")
		(net "GMI_CPU0_G2_CPU1_G0_TX_DP<11>")
	)
	(arc
		(start 365.206788 -224.698814)
		(mid 365.450115 -224.234248)
		(end 365.206788 -223.769682)
		(width 0.1143)
		(layer "In2.Cu")
		(net "GMI_CPU0_G2_CPU1_G0_TX_DP<11>")
	)
	(segment
		(start 364.888018 -228.550216)
		(end 365.35487 -228.284278)
		(width 0.12954)
		(layer "F.Cu")
		(net "GMI_CPU0_G2_CPU1_G0_TX_DP<10>")
	)
	(segment
		(start 106.607864 -228.55047)
		(end 106.141012 -228.284532)
		(width 0.12954)
		(layer "F.Cu")
		(net "GMI_CPU0_G2_CPU1_G0_TX_DP<10>")
	)
	(segment
		(start 365.35487 -228.284278)
		(end 365.056928 -228.284278)
		(width 0.1143)
		(layer "In2.Cu")
		(net "GMI_CPU0_G2_CPU1_G0_TX_DP<10>")
	)
	(segment
		(start 107.26801 -223.101916)
		(end 107.268772 -223.102424)
		(width 0.1143)
		(layer "In2.Cu")
		(net "GMI_CPU0_G2_CPU1_G0_TX_DP<10>")
	)
	(segment
		(start 107.271566 -224.72396)
		(end 107.272328 -224.724468)
		(width 0.1143)
		(layer "In2.Cu")
		(net "GMI_CPU0_G2_CPU1_G0_TX_DP<10>")
	)
	(segment
		(start 364.032038 -221.097602)
		(end 364.032038 -221.083124)
		(width 0.1143)
		(layer "In2.Cu")
		(net "GMI_CPU0_G2_CPU1_G0_TX_DP<10>")
	)
	(segment
		(start 106.521758 -228.201728)
		(end 106.438954 -228.284532)
		(width 0.1143)
		(layer "In2.Cu")
		(net "GMI_CPU0_G2_CPU1_G0_TX_DP<10>")
	)
	(segment
		(start 106.82859 -227.779326)
		(end 106.79811 -227.797106)
		(width 0.1143)
		(layer "In2.Cu")
		(net "GMI_CPU0_G2_CPU1_G0_TX_DP<10>")
	)
	(segment
		(start 306.09286 -184.930796)
		(end 236.608112 -182.516272)
		(width 0.14224)
		(layer "In2.Cu")
		(net "GMI_CPU0_G2_CPU1_G0_TX_DP<10>")
	)
	(segment
		(start 106.49839 -221.174564)
		(end 106.49839 -221.203012)
		(width 0.1143)
		(layer "In2.Cu")
		(net "GMI_CPU0_G2_CPU1_G0_TX_DP<10>")
	)
	(segment
		(start 107.266994 -226.987608)
		(end 107.228894 -227.00996)
		(width 0.1143)
		(layer "In2.Cu")
		(net "GMI_CPU0_G2_CPU1_G0_TX_DP<10>")
	)
	(segment
		(start 321.515232 -192.066164)
		(end 307.474874 -185.290206)
		(width 0.14224)
		(layer "In2.Cu")
		(net "GMI_CPU0_G2_CPU1_G0_TX_DP<10>")
	)
	(segment
		(start 364.266988 -224.699068)
		(end 364.294674 -224.679002)
		(width 0.1143)
		(layer "In2.Cu")
		(net "GMI_CPU0_G2_CPU1_G0_TX_DP<10>")
	)
	(segment
		(start 114.134138 -210.824826)
		(end 114.134138 -210.82508)
		(width 0.14224)
		(layer "In2.Cu")
		(net "GMI_CPU0_G2_CPU1_G0_TX_DP<10>")
	)
	(segment
		(start 364.522766 -227.49637)
		(end 364.522766 -227.483924)
		(width 0.1143)
		(layer "In2.Cu")
		(net "GMI_CPU0_G2_CPU1_G0_TX_DP<10>")
	)
	(segment
		(start 236.608112 -182.516272)
		(end 166.651686 -184.594246)
		(width 0.14224)
		(layer "In2.Cu")
		(net "GMI_CPU0_G2_CPU1_G0_TX_DP<10>")
	)
	(segment
		(start 364.266988 -223.769428)
		(end 364.228126 -223.747076)
		(width 0.1143)
		(layer "In2.Cu")
		(net "GMI_CPU0_G2_CPU1_G0_TX_DP<10>")
	)
	(segment
		(start 166.651686 -184.594246)
		(end 165.549326 -184.885584)
		(width 0.14224)
		(layer "In2.Cu")
		(net "GMI_CPU0_G2_CPU1_G0_TX_DP<10>")
	)
	(segment
		(start 107.266994 -226.341432)
		(end 107.26801 -226.34194)
		(width 0.1143)
		(layer "In2.Cu")
		(net "GMI_CPU0_G2_CPU1_G0_TX_DP<10>")
	)
	(segment
		(start 107.270042 -226.98583)
		(end 107.268772 -226.986592)
		(width 0.1143)
		(layer "In2.Cu")
		(net "GMI_CPU0_G2_CPU1_G0_TX_DP<10>")
	)
	(segment
		(start 364.227872 -226.341686)
		(end 364.264194 -226.320604)
		(width 0.1143)
		(layer "In2.Cu")
		(net "GMI_CPU0_G2_CPU1_G0_TX_DP<10>")
	)
	(segment
		(start 107.273344 -223.104964)
		(end 107.274106 -223.105472)
		(width 0.1143)
		(layer "In2.Cu")
		(net "GMI_CPU0_G2_CPU1_G0_TX_DP<10>")
	)
	(segment
		(start 106.49839 -221.203012)
		(end 106.54411 -221.248732)
		(width 0.1143)
		(layer "In2.Cu")
		(net "GMI_CPU0_G2_CPU1_G0_TX_DP<10>")
	)
	(segment
		(start 107.272328 -223.744536)
		(end 107.271566 -223.745044)
		(width 0.1143)
		(layer "In2.Cu")
		(net "GMI_CPU0_G2_CPU1_G0_TX_DP<10>")
	)
	(segment
		(start 107.29976 -225.3488)
		(end 107.270042 -225.365818)
		(width 0.1143)
		(layer "In2.Cu")
		(net "GMI_CPU0_G2_CPU1_G0_TX_DP<10>")
	)
	(segment
		(start 364.196122 -223.72828)
		(end 364.196122 -223.728534)
		(width 0.1143)
		(layer "In2.Cu")
		(net "GMI_CPU0_G2_CPU1_G0_TX_DP<10>")
	)
	(segment
		(start 113.058956 -211.394548)
		(end 106.49839 -217.955114)
		(width 0.14224)
		(layer "In2.Cu")
		(net "GMI_CPU0_G2_CPU1_G0_TX_DP<10>")
	)
	(segment
		(start 107.236514 -226.323652)
		(end 107.266994 -226.341432)
		(width 0.1143)
		(layer "In2.Cu")
		(net "GMI_CPU0_G2_CPU1_G0_TX_DP<10>")
	)
	(segment
		(start 364.264194 -225.387916)
		(end 364.227872 -225.366834)
		(width 0.1143)
		(layer "In2.Cu")
		(net "GMI_CPU0_G2_CPU1_G0_TX_DP<10>")
	)
	(segment
		(start 107.26801 -223.747076)
		(end 107.266994 -223.747584)
		(width 0.1143)
		(layer "In2.Cu")
		(net "GMI_CPU0_G2_CPU1_G0_TX_DP<10>")
	)
	(segment
		(start 307.474874 -185.290206)
		(end 306.09286 -184.930796)
		(width 0.14224)
		(layer "In2.Cu")
		(net "GMI_CPU0_G2_CPU1_G0_TX_DP<10>")
	)
	(segment
		(start 107.271566 -223.103948)
		(end 107.272328 -223.104456)
		(width 0.1143)
		(layer "In2.Cu")
		(net "GMI_CPU0_G2_CPU1_G0_TX_DP<10>")
	)
	(segment
		(start 107.235752 -226.323144)
		(end 107.236514 -226.323652)
		(width 0.1143)
		(layer "In2.Cu")
		(net "GMI_CPU0_G2_CPU1_G0_TX_DP<10>")
	)
	(segment
		(start 107.29976 -223.728788)
		(end 107.27436 -223.74352)
		(width 0.1143)
		(layer "In2.Cu")
		(net "GMI_CPU0_G2_CPU1_G0_TX_DP<10>")
	)
	(segment
		(start 107.271566 -223.745044)
		(end 107.268772 -223.746568)
		(width 0.1143)
		(layer "In2.Cu")
		(net "GMI_CPU0_G2_CPU1_G0_TX_DP<10>")
	)
	(segment
		(start 106.54411 -221.520766)
		(end 106.515916 -221.54896)
		(width 0.1143)
		(layer "In2.Cu")
		(net "GMI_CPU0_G2_CPU1_G0_TX_DP<10>")
	)
	(segment
		(start 107.275122 -226.346004)
		(end 107.29976 -226.360228)
		(width 0.1143)
		(layer "In2.Cu")
		(net "GMI_CPU0_G2_CPU1_G0_TX_DP<10>")
	)
	(segment
		(start 107.272328 -226.34448)
		(end 107.273344 -226.344988)
		(width 0.1143)
		(layer "In2.Cu")
		(net "GMI_CPU0_G2_CPU1_G0_TX_DP<10>")
	)
	(segment
		(start 106.79811 -227.797106)
		(end 106.758994 -227.819966)
		(width 0.1143)
		(layer "In2.Cu")
		(net "GMI_CPU0_G2_CPU1_G0_TX_DP<10>")
	)
	(segment
		(start 107.270042 -225.365818)
		(end 107.268772 -225.36658)
		(width 0.1143)
		(layer "In2.Cu")
		(net "GMI_CPU0_G2_CPU1_G0_TX_DP<10>")
	)
	(segment
		(start 107.266994 -225.367596)
		(end 107.228894 -225.389948)
		(width 0.1143)
		(layer "In2.Cu")
		(net "GMI_CPU0_G2_CPU1_G0_TX_DP<10>")
	)
	(segment
		(start 107.268772 -223.102424)
		(end 107.271566 -223.103948)
		(width 0.1143)
		(layer "In2.Cu")
		(net "GMI_CPU0_G2_CPU1_G0_TX_DP<10>")
	)
	(segment
		(start 107.268772 -226.986592)
		(end 107.26801 -226.9871)
		(width 0.1143)
		(layer "In2.Cu")
		(net "GMI_CPU0_G2_CPU1_G0_TX_DP<10>")
	)
	(segment
		(start 107.272328 -223.104456)
		(end 107.273344 -223.104964)
		(width 0.1143)
		(layer "In2.Cu")
		(net "GMI_CPU0_G2_CPU1_G0_TX_DP<10>")
	)
	(segment
		(start 106.515916 -221.54896)
		(end 106.515916 -221.804484)
		(width 0.1143)
		(layer "In2.Cu")
		(net "GMI_CPU0_G2_CPU1_G0_TX_DP<10>")
	)
	(segment
		(start 107.26801 -225.367088)
		(end 107.266994 -225.367596)
		(width 0.1143)
		(layer "In2.Cu")
		(net "GMI_CPU0_G2_CPU1_G0_TX_DP<10>")
	)
	(segment
		(start 363.986318 -221.34703)
		(end 363.986318 -221.143322)
		(width 0.1143)
		(layer "In2.Cu")
		(net "GMI_CPU0_G2_CPU1_G0_TX_DP<10>")
	)
	(segment
		(start 107.26801 -224.721928)
		(end 107.268772 -224.722436)
		(width 0.1143)
		(layer "In2.Cu")
		(net "GMI_CPU0_G2_CPU1_G0_TX_DP<10>")
	)
	(segment
		(start 106.760518 -222.270066)
		(end 106.79811 -222.29191)
		(width 0.1143)
		(layer "In2.Cu")
		(net "GMI_CPU0_G2_CPU1_G0_TX_DP<10>")
	)
	(segment
		(start 364.032038 -219.720414)
		(end 363.459014 -218.460574)
		(width 0.14224)
		(layer "In2.Cu")
		(net "GMI_CPU0_G2_CPU1_G0_TX_DP<10>")
	)
	(segment
		(start 107.273344 -226.344988)
		(end 107.274106 -226.345496)
		(width 0.1143)
		(layer "In2.Cu")
		(net "GMI_CPU0_G2_CPU1_G0_TX_DP<10>")
	)
	(segment
		(start 364.227872 -223.101662)
		(end 364.264194 -223.08058)
		(width 0.1143)
		(layer "In2.Cu")
		(net "GMI_CPU0_G2_CPU1_G0_TX_DP<10>")
	)
	(segment
		(start 107.274106 -223.105472)
		(end 107.275122 -223.10598)
		(width 0.1143)
		(layer "In2.Cu")
		(net "GMI_CPU0_G2_CPU1_G0_TX_DP<10>")
	)
	(segment
		(start 156.24937 -188.521848)
		(end 114.134138 -210.824826)
		(width 0.14224)
		(layer "In2.Cu")
		(net "GMI_CPU0_G2_CPU1_G0_TX_DP<10>")
	)
	(segment
		(start 107.273344 -224.724976)
		(end 107.274106 -224.725484)
		(width 0.1143)
		(layer "In2.Cu")
		(net "GMI_CPU0_G2_CPU1_G0_TX_DP<10>")
	)
	(segment
		(start 364.697772 -227.796852)
		(end 364.69701 -227.796344)
		(width 0.1143)
		(layer "In2.Cu")
		(net "GMI_CPU0_G2_CPU1_G0_TX_DP<10>")
	)
	(segment
		(start 106.49839 -217.955114)
		(end 106.49839 -221.174564)
		(width 0.14224)
		(layer "In2.Cu")
		(net "GMI_CPU0_G2_CPU1_G0_TX_DP<10>")
	)
	(segment
		(start 364.032038 -221.083124)
		(end 364.032038 -219.720414)
		(width 0.14224)
		(layer "In2.Cu")
		(net "GMI_CPU0_G2_CPU1_G0_TX_DP<10>")
	)
	(segment
		(start 364.228126 -223.747076)
		(end 364.212124 -223.737424)
		(width 0.1143)
		(layer "In2.Cu")
		(net "GMI_CPU0_G2_CPU1_G0_TX_DP<10>")
	)
	(segment
		(start 364.69701 -227.796344)
		(end 364.694216 -227.795074)
		(width 0.1143)
		(layer "In2.Cu")
		(net "GMI_CPU0_G2_CPU1_G0_TX_DP<10>")
	)
	(segment
		(start 364.240064 -226.994212)
		(end 364.196122 -226.968304)
		(width 0.1143)
		(layer "In2.Cu")
		(net "GMI_CPU0_G2_CPU1_G0_TX_DP<10>")
	)
	(segment
		(start 364.040166 -221.80423)
		(end 364.040166 -221.400878)
		(width 0.1143)
		(layer "In2.Cu")
		(net "GMI_CPU0_G2_CPU1_G0_TX_DP<10>")
	)
	(segment
		(start 107.235752 -223.08312)
		(end 107.236514 -223.083628)
		(width 0.1143)
		(layer "In2.Cu")
		(net "GMI_CPU0_G2_CPU1_G0_TX_DP<10>")
	)
	(segment
		(start 364.040166 -221.400878)
		(end 363.986318 -221.34703)
		(width 0.1143)
		(layer "In2.Cu")
		(net "GMI_CPU0_G2_CPU1_G0_TX_DP<10>")
	)
	(segment
		(start 107.266994 -223.101408)
		(end 107.26801 -223.101916)
		(width 0.1143)
		(layer "In2.Cu")
		(net "GMI_CPU0_G2_CPU1_G0_TX_DP<10>")
	)
	(segment
		(start 364.736888 -227.819712)
		(end 364.697772 -227.796852)
		(width 0.1143)
		(layer "In2.Cu")
		(net "GMI_CPU0_G2_CPU1_G0_TX_DP<10>")
	)
	(segment
		(start 107.275122 -223.10598)
		(end 107.29976 -223.120204)
		(width 0.1143)
		(layer "In2.Cu")
		(net "GMI_CPU0_G2_CPU1_G0_TX_DP<10>")
	)
	(segment
		(start 107.274106 -224.725484)
		(end 107.275122 -224.725992)
		(width 0.1143)
		(layer "In2.Cu")
		(net "GMI_CPU0_G2_CPU1_G0_TX_DP<10>")
	)
	(segment
		(start 363.459014 -218.460574)
		(end 358.48163 -214.121746)
		(width 0.14224)
		(layer "In2.Cu")
		(net "GMI_CPU0_G2_CPU1_G0_TX_DP<10>")
	)
	(segment
		(start 356.689152 -212.906864)
		(end 321.515232 -192.066164)
		(width 0.14224)
		(layer "In2.Cu")
		(net "GMI_CPU0_G2_CPU1_G0_TX_DP<10>")
	)
	(segment
		(start 107.228894 -223.079056)
		(end 107.235752 -223.08312)
		(width 0.1143)
		(layer "In2.Cu")
		(net "GMI_CPU0_G2_CPU1_G0_TX_DP<10>")
	)
	(segment
		(start 107.268772 -224.722436)
		(end 107.271566 -224.72396)
		(width 0.1143)
		(layer "In2.Cu")
		(net "GMI_CPU0_G2_CPU1_G0_TX_DP<10>")
	)
	(segment
		(start 107.274106 -226.345496)
		(end 107.275122 -226.346004)
		(width 0.1143)
		(layer "In2.Cu")
		(net "GMI_CPU0_G2_CPU1_G0_TX_DP<10>")
	)
	(segment
		(start 107.268772 -223.746568)
		(end 107.26801 -223.747076)
		(width 0.1143)
		(layer "In2.Cu")
		(net "GMI_CPU0_G2_CPU1_G0_TX_DP<10>")
	)
	(segment
		(start 114.134138 -210.82508)
		(end 113.058956 -211.394548)
		(width 0.14224)
		(layer "In2.Cu")
		(net "GMI_CPU0_G2_CPU1_G0_TX_DP<10>")
	)
	(segment
		(start 364.694216 -227.795074)
		(end 364.693708 -227.79482)
		(width 0.1143)
		(layer "In2.Cu")
		(net "GMI_CPU0_G2_CPU1_G0_TX_DP<10>")
	)
	(segment
		(start 107.235752 -224.703132)
		(end 107.236514 -224.70364)
		(width 0.1143)
		(layer "In2.Cu")
		(net "GMI_CPU0_G2_CPU1_G0_TX_DP<10>")
	)
	(segment
		(start 107.271566 -226.343972)
		(end 107.272328 -226.34448)
		(width 0.1143)
		(layer "In2.Cu")
		(net "GMI_CPU0_G2_CPU1_G0_TX_DP<10>")
	)
	(segment
		(start 107.29976 -226.968812)
		(end 107.270042 -226.98583)
		(width 0.1143)
		(layer "In2.Cu")
		(net "GMI_CPU0_G2_CPU1_G0_TX_DP<10>")
	)
	(segment
		(start 107.26547 -223.7486)
		(end 107.228894 -223.769936)
		(width 0.1143)
		(layer "In2.Cu")
		(net "GMI_CPU0_G2_CPU1_G0_TX_DP<10>")
	)
	(segment
		(start 107.26801 -226.9871)
		(end 107.266994 -226.987608)
		(width 0.1143)
		(layer "In2.Cu")
		(net "GMI_CPU0_G2_CPU1_G0_TX_DP<10>")
	)
	(segment
		(start 106.438954 -228.284532)
		(end 106.141012 -228.284532)
		(width 0.1143)
		(layer "In2.Cu")
		(net "GMI_CPU0_G2_CPU1_G0_TX_DP<10>")
	)
	(segment
		(start 364.294674 -223.789494)
		(end 364.266988 -223.769428)
		(width 0.1143)
		(layer "In2.Cu")
		(net "GMI_CPU0_G2_CPU1_G0_TX_DP<10>")
	)
	(segment
		(start 107.236514 -224.70364)
		(end 107.266994 -224.72142)
		(width 0.1143)
		(layer "In2.Cu")
		(net "GMI_CPU0_G2_CPU1_G0_TX_DP<10>")
	)
	(segment
		(start 107.266994 -223.747584)
		(end 107.26547 -223.7486)
		(width 0.1143)
		(layer "In2.Cu")
		(net "GMI_CPU0_G2_CPU1_G0_TX_DP<10>")
	)
	(segment
		(start 107.27436 -223.74352)
		(end 107.272328 -223.744536)
		(width 0.1143)
		(layer "In2.Cu")
		(net "GMI_CPU0_G2_CPU1_G0_TX_DP<10>")
	)
	(segment
		(start 106.79811 -222.29191)
		(end 106.82859 -222.30969)
		(width 0.1143)
		(layer "In2.Cu")
		(net "GMI_CPU0_G2_CPU1_G0_TX_DP<10>")
	)
	(segment
		(start 364.227872 -225.366834)
		(end 364.196122 -225.348546)
		(width 0.1143)
		(layer "In2.Cu")
		(net "GMI_CPU0_G2_CPU1_G0_TX_DP<10>")
	)
	(segment
		(start 165.549326 -184.885584)
		(end 156.24937 -188.521848)
		(width 0.14224)
		(layer "In2.Cu")
		(net "GMI_CPU0_G2_CPU1_G0_TX_DP<10>")
	)
	(segment
		(start 364.196122 -226.359974)
		(end 364.227872 -226.341686)
		(width 0.1143)
		(layer "In2.Cu")
		(net "GMI_CPU0_G2_CPU1_G0_TX_DP<10>")
	)
	(segment
		(start 107.266994 -224.72142)
		(end 107.26801 -224.721928)
		(width 0.1143)
		(layer "In2.Cu")
		(net "GMI_CPU0_G2_CPU1_G0_TX_DP<10>")
	)
	(segment
		(start 107.26801 -226.34194)
		(end 107.268772 -226.342448)
		(width 0.1143)
		(layer "In2.Cu")
		(net "GMI_CPU0_G2_CPU1_G0_TX_DP<10>")
	)
	(segment
		(start 106.54411 -221.248732)
		(end 106.54411 -221.520766)
		(width 0.1143)
		(layer "In2.Cu")
		(net "GMI_CPU0_G2_CPU1_G0_TX_DP<10>")
	)
	(segment
		(start 364.264194 -222.147892)
		(end 364.227872 -222.12681)
		(width 0.1143)
		(layer "In2.Cu")
		(net "GMI_CPU0_G2_CPU1_G0_TX_DP<10>")
	)
	(segment
		(start 365.056928 -228.284278)
		(end 364.974124 -228.201474)
		(width 0.1143)
		(layer "In2.Cu")
		(net "GMI_CPU0_G2_CPU1_G0_TX_DP<10>")
	)
	(segment
		(start 364.212124 -223.737424)
		(end 364.196122 -223.72828)
		(width 0.1143)
		(layer "In2.Cu")
		(net "GMI_CPU0_G2_CPU1_G0_TX_DP<10>")
	)
	(segment
		(start 107.236514 -223.083628)
		(end 107.266994 -223.101408)
		(width 0.1143)
		(layer "In2.Cu")
		(net "GMI_CPU0_G2_CPU1_G0_TX_DP<10>")
	)
	(segment
		(start 107.268772 -226.342448)
		(end 107.271566 -226.343972)
		(width 0.1143)
		(layer "In2.Cu")
		(net "GMI_CPU0_G2_CPU1_G0_TX_DP<10>")
	)
	(segment
		(start 358.48163 -214.121746)
		(end 356.689152 -212.906864)
		(width 0.14224)
		(layer "In2.Cu")
		(net "GMI_CPU0_G2_CPU1_G0_TX_DP<10>")
	)
	(segment
		(start 107.228894 -226.31908)
		(end 107.235752 -226.323144)
		(width 0.1143)
		(layer "In2.Cu")
		(net "GMI_CPU0_G2_CPU1_G0_TX_DP<10>")
	)
	(segment
		(start 364.227872 -222.12681)
		(end 364.196122 -222.108522)
		(width 0.1143)
		(layer "In2.Cu")
		(net "GMI_CPU0_G2_CPU1_G0_TX_DP<10>")
	)
	(segment
		(start 363.986318 -221.143322)
		(end 364.032038 -221.097602)
		(width 0.1143)
		(layer "In2.Cu")
		(net "GMI_CPU0_G2_CPU1_G0_TX_DP<10>")
	)
	(segment
		(start 107.275122 -224.725992)
		(end 107.29976 -224.740216)
		(width 0.1143)
		(layer "In2.Cu")
		(net "GMI_CPU0_G2_CPU1_G0_TX_DP<10>")
	)
	(segment
		(start 364.196122 -224.739962)
		(end 364.266988 -224.699068)
		(width 0.1143)
		(layer "In2.Cu")
		(net "GMI_CPU0_G2_CPU1_G0_TX_DP<10>")
	)
	(segment
		(start 364.196122 -223.11995)
		(end 364.227872 -223.101662)
		(width 0.1143)
		(layer "In2.Cu")
		(net "GMI_CPU0_G2_CPU1_G0_TX_DP<10>")
	)
	(segment
		(start 107.228894 -224.699068)
		(end 107.235752 -224.703132)
		(width 0.1143)
		(layer "In2.Cu")
		(net "GMI_CPU0_G2_CPU1_G0_TX_DP<10>")
	)
	(segment
		(start 107.272328 -224.724468)
		(end 107.273344 -224.724976)
		(width 0.1143)
		(layer "In2.Cu")
		(net "GMI_CPU0_G2_CPU1_G0_TX_DP<10>")
	)
	(segment
		(start 107.268772 -225.36658)
		(end 107.26801 -225.367088)
		(width 0.1143)
		(layer "In2.Cu")
		(net "GMI_CPU0_G2_CPU1_G0_TX_DP<10>")
	)
	(arc
		(start 364.060486 -226.785932)
		(mid 364.057865 -226.550523)
		(end 364.196122 -226.359974)
		(width 0.1143)
		(layer "In2.Cu")
		(net "GMI_CPU0_G2_CPU1_G0_TX_DP<10>")
	)
	(arc
		(start 364.278418 -223.070674)
		(mid 364.505801 -222.614236)
		(end 364.278418 -222.157798)
		(width 0.1143)
		(layer "In2.Cu")
		(net "GMI_CPU0_G2_CPU1_G0_TX_DP<10>")
	)
	(arc
		(start 364.278418 -225.397822)
		(mid 364.271344 -225.392815)
		(end 364.264194 -225.387916)
		(width 0.1143)
		(layer "In2.Cu")
		(net "GMI_CPU0_G2_CPU1_G0_TX_DP<10>")
	)
	(arc
		(start 107.228894 -223.769936)
		(mid 106.985567 -224.234502)
		(end 107.228894 -224.699068)
		(width 0.1143)
		(layer "In2.Cu")
		(net "GMI_CPU0_G2_CPU1_G0_TX_DP<10>")
	)
	(arc
		(start 364.522766 -227.483924)
		(mid 364.447009 -227.201209)
		(end 364.240064 -226.994212)
		(width 0.1143)
		(layer "In2.Cu")
		(net "GMI_CPU0_G2_CPU1_G0_TX_DP<10>")
	)
	(arc
		(start 364.196122 -226.968304)
		(mid 364.114141 -226.887654)
		(end 364.060486 -226.785932)
		(width 0.1143)
		(layer "In2.Cu")
		(net "GMI_CPU0_G2_CPU1_G0_TX_DP<10>")
	)
	(arc
		(start 107.29976 -226.360228)
		(mid 107.455688 -226.66452)
		(end 107.29976 -226.968812)
		(width 0.1143)
		(layer "In2.Cu")
		(net "GMI_CPU0_G2_CPU1_G0_TX_DP<10>")
	)
	(arc
		(start 107.29976 -223.120204)
		(mid 107.455688 -223.424496)
		(end 107.29976 -223.728788)
		(width 0.1143)
		(layer "In2.Cu")
		(net "GMI_CPU0_G2_CPU1_G0_TX_DP<10>")
	)
	(arc
		(start 364.974124 -228.201474)
		(mid 364.895045 -227.986029)
		(end 364.736888 -227.819712)
		(width 0.1143)
		(layer "In2.Cu")
		(net "GMI_CPU0_G2_CPU1_G0_TX_DP<10>")
	)
	(arc
		(start 364.278418 -226.310698)
		(mid 364.505801 -225.85426)
		(end 364.278418 -225.397822)
		(width 0.1143)
		(layer "In2.Cu")
		(net "GMI_CPU0_G2_CPU1_G0_TX_DP<10>")
	)
	(arc
		(start 106.82859 -222.30969)
		(mid 106.944017 -222.443066)
		(end 106.985562 -222.61449)
		(width 0.1143)
		(layer "In2.Cu")
		(net "GMI_CPU0_G2_CPU1_G0_TX_DP<10>")
	)
	(arc
		(start 364.264194 -223.08058)
		(mid 364.271343 -223.07568)
		(end 364.278418 -223.070674)
		(width 0.1143)
		(layer "In2.Cu")
		(net "GMI_CPU0_G2_CPU1_G0_TX_DP<10>")
	)
	(arc
		(start 107.29976 -224.740216)
		(mid 107.455688 -225.044508)
		(end 107.29976 -225.3488)
		(width 0.1143)
		(layer "In2.Cu")
		(net "GMI_CPU0_G2_CPU1_G0_TX_DP<10>")
	)
	(arc
		(start 364.264194 -226.320604)
		(mid 364.271343 -226.315704)
		(end 364.278418 -226.310698)
		(width 0.1143)
		(layer "In2.Cu")
		(net "GMI_CPU0_G2_CPU1_G0_TX_DP<10>")
	)
	(arc
		(start 106.985562 -222.61449)
		(mid 107.050077 -222.876709)
		(end 107.228894 -223.079056)
		(width 0.1143)
		(layer "In2.Cu")
		(net "GMI_CPU0_G2_CPU1_G0_TX_DP<10>")
	)
	(arc
		(start 364.278418 -222.157798)
		(mid 364.271344 -222.152791)
		(end 364.264194 -222.147892)
		(width 0.1143)
		(layer "In2.Cu")
		(net "GMI_CPU0_G2_CPU1_G0_TX_DP<10>")
	)
	(arc
		(start 107.228894 -225.389948)
		(mid 106.985567 -225.854514)
		(end 107.228894 -226.31908)
		(width 0.1143)
		(layer "In2.Cu")
		(net "GMI_CPU0_G2_CPU1_G0_TX_DP<10>")
	)
	(arc
		(start 364.196122 -222.108522)
		(mid 364.081446 -221.975188)
		(end 364.040166 -221.80423)
		(width 0.1143)
		(layer "In2.Cu")
		(net "GMI_CPU0_G2_CPU1_G0_TX_DP<10>")
	)
	(arc
		(start 364.196122 -225.348546)
		(mid 364.040194 -225.044254)
		(end 364.196122 -224.739962)
		(width 0.1143)
		(layer "In2.Cu")
		(net "GMI_CPU0_G2_CPU1_G0_TX_DP<10>")
	)
	(arc
		(start 364.693708 -227.79482)
		(mid 364.568508 -227.668346)
		(end 364.522766 -227.49637)
		(width 0.1143)
		(layer "In2.Cu")
		(net "GMI_CPU0_G2_CPU1_G0_TX_DP<10>")
	)
	(arc
		(start 364.196122 -223.728534)
		(mid 364.040194 -223.424242)
		(end 364.196122 -223.11995)
		(width 0.1143)
		(layer "In2.Cu")
		(net "GMI_CPU0_G2_CPU1_G0_TX_DP<10>")
	)
	(arc
		(start 364.294674 -224.679002)
		(mid 364.522674 -224.234248)
		(end 364.294674 -223.789494)
		(width 0.1143)
		(layer "In2.Cu")
		(net "GMI_CPU0_G2_CPU1_G0_TX_DP<10>")
	)
	(arc
		(start 106.985562 -227.474526)
		(mid 106.944013 -227.645948)
		(end 106.82859 -227.779326)
		(width 0.1143)
		(layer "In2.Cu")
		(net "GMI_CPU0_G2_CPU1_G0_TX_DP<10>")
	)
	(arc
		(start 107.228894 -227.00996)
		(mid 107.050081 -227.21231)
		(end 106.985562 -227.474526)
		(width 0.1143)
		(layer "In2.Cu")
		(net "GMI_CPU0_G2_CPU1_G0_TX_DP<10>")
	)
	(arc
		(start 106.758994 -227.819966)
		(mid 106.607007 -227.976474)
		(end 106.525568 -228.178868)
		(width 0.1143)
		(layer "In2.Cu")
		(net "GMI_CPU0_G2_CPU1_G0_TX_DP<10>")
	)
	(arc
		(start 106.525568 -228.178868)
		(mid 106.523545 -228.190278)
		(end 106.521758 -228.201728)
		(width 0.1143)
		(layer "In2.Cu")
		(net "GMI_CPU0_G2_CPU1_G0_TX_DP<10>")
	)
	(arc
		(start 106.515916 -221.804484)
		(mid 106.580788 -222.067447)
		(end 106.760518 -222.270066)
		(width 0.1143)
		(layer "In2.Cu")
		(net "GMI_CPU0_G2_CPU1_G0_TX_DP<10>")
	)
	(segment
		(start 98.147886 -231.79024)
		(end 97.681034 -231.524302)
		(width 0.12954)
		(layer "F.Cu")
		(net "GMI_CPU0_G2_CPU1_G0_TX_DP<0>")
	)
	(segment
		(start 373.347996 -231.789986)
		(end 373.814848 -231.524048)
		(width 0.12954)
		(layer "F.Cu")
		(net "GMI_CPU0_G2_CPU1_G0_TX_DP<0>")
	)
	(segment
		(start 374.60682 -227.009706)
		(end 374.567704 -226.986846)
		(width 0.1143)
		(layer "In2.Cu")
		(net "GMI_CPU0_G2_CPU1_G0_TX_DP<0>")
	)
	(segment
		(start 97.978976 -231.524302)
		(end 97.681034 -231.524302)
		(width 0.1143)
		(layer "In2.Cu")
		(net "GMI_CPU0_G2_CPU1_G0_TX_DP<0>")
	)
	(segment
		(start 96.115378 -221.624906)
		(end 96.17583 -221.685358)
		(width 0.1143)
		(layer "In2.Cu")
		(net "GMI_CPU0_G2_CPU1_G0_TX_DP<0>")
	)
	(segment
		(start 96.928178 -223.747076)
		(end 96.889062 -223.769936)
		(width 0.1143)
		(layer "In2.Cu")
		(net "GMI_CPU0_G2_CPU1_G0_TX_DP<0>")
	)
	(segment
		(start 98.048826 -231.454452)
		(end 97.978976 -231.524302)
		(width 0.1143)
		(layer "In2.Cu")
		(net "GMI_CPU0_G2_CPU1_G0_TX_DP<0>")
	)
	(segment
		(start 96.958658 -226.96932)
		(end 96.928178 -226.9871)
		(width 0.1143)
		(layer "In2.Cu")
		(net "GMI_CPU0_G2_CPU1_G0_TX_DP<0>")
	)
	(segment
		(start 374.537224 -223.119442)
		(end 374.567704 -223.101662)
		(width 0.1143)
		(layer "In2.Cu")
		(net "GMI_CPU0_G2_CPU1_G0_TX_DP<0>")
	)
	(segment
		(start 373.62765 -231.201722)
		(end 373.666766 -231.178862)
		(width 0.1143)
		(layer "In2.Cu")
		(net "GMI_CPU0_G2_CPU1_G0_TX_DP<0>")
	)
	(segment
		(start 97.361502 -230.370634)
		(end 97.398078 -230.39197)
		(width 0.1143)
		(layer "In2.Cu")
		(net "GMI_CPU0_G2_CPU1_G0_TX_DP<0>")
	)
	(segment
		(start 374.535192 -229.600506)
		(end 374.567704 -229.58171)
		(width 0.1143)
		(layer "In2.Cu")
		(net "GMI_CPU0_G2_CPU1_G0_TX_DP<0>")
	)
	(segment
		(start 96.889062 -223.079056)
		(end 96.928178 -223.101916)
		(width 0.1143)
		(layer "In2.Cu")
		(net "GMI_CPU0_G2_CPU1_G0_TX_DP<0>")
	)
	(segment
		(start 374.567704 -228.606858)
		(end 374.537224 -228.589078)
		(width 0.1143)
		(layer "In2.Cu")
		(net "GMI_CPU0_G2_CPU1_G0_TX_DP<0>")
	)
	(segment
		(start 97.398078 -230.39197)
		(end 97.398332 -230.39197)
		(width 0.1143)
		(layer "In2.Cu")
		(net "GMI_CPU0_G2_CPU1_G0_TX_DP<0>")
	)
	(segment
		(start 150.16226 -179.671218)
		(end 104.84104 -202.660758)
		(width 0.14224)
		(layer "In2.Cu")
		(net "GMI_CPU0_G2_CPU1_G0_TX_DP<0>")
	)
	(segment
		(start 160.64611 -175.248316)
		(end 150.16226 -179.671218)
		(width 0.14224)
		(layer "In2.Cu")
		(net "GMI_CPU0_G2_CPU1_G0_TX_DP<0>")
	)
	(segment
		(start 96.889062 -226.31908)
		(end 96.928178 -226.34194)
		(width 0.1143)
		(layer "In2.Cu")
		(net "GMI_CPU0_G2_CPU1_G0_TX_DP<0>")
	)
	(segment
		(start 358.98074 -201.7776)
		(end 325.367904 -181.896258)
		(width 0.14224)
		(layer "In2.Cu")
		(net "GMI_CPU0_G2_CPU1_G0_TX_DP<0>")
	)
	(segment
		(start 234.616752 -171.679108)
		(end 164.324284 -174.198534)
		(width 0.14224)
		(layer "In2.Cu")
		(net "GMI_CPU0_G2_CPU1_G0_TX_DP<0>")
	)
	(segment
		(start 306.615338 -174.157132)
		(end 234.616752 -171.679108)
		(width 0.14224)
		(layer "In2.Cu")
		(net "GMI_CPU0_G2_CPU1_G0_TX_DP<0>")
	)
	(segment
		(start 374.567704 -226.341686)
		(end 374.60682 -226.318826)
		(width 0.1143)
		(layer "In2.Cu")
		(net "GMI_CPU0_G2_CPU1_G0_TX_DP<0>")
	)
	(segment
		(start 374.380252 -221.80423)
		(end 374.380252 -221.467172)
		(width 0.1143)
		(layer "In2.Cu")
		(net "GMI_CPU0_G2_CPU1_G0_TX_DP<0>")
	)
	(segment
		(start 374.567704 -226.986846)
		(end 374.537224 -226.969066)
		(width 0.1143)
		(layer "In2.Cu")
		(net "GMI_CPU0_G2_CPU1_G0_TX_DP<0>")
	)
	(segment
		(start 362.733336 -204.317346)
		(end 358.98074 -201.7776)
		(width 0.14224)
		(layer "In2.Cu")
		(net "GMI_CPU0_G2_CPU1_G0_TX_DP<0>")
	)
	(segment
		(start 96.889062 -227.939092)
		(end 96.928178 -227.961952)
		(width 0.1143)
		(layer "In2.Cu")
		(net "GMI_CPU0_G2_CPU1_G0_TX_DP<0>")
	)
	(segment
		(start 374.60682 -222.14967)
		(end 374.537224 -222.10903)
		(width 0.1143)
		(layer "In2.Cu")
		(net "GMI_CPU0_G2_CPU1_G0_TX_DP<0>")
	)
	(segment
		(start 374.537224 -226.359466)
		(end 374.567704 -226.341686)
		(width 0.1143)
		(layer "In2.Cu")
		(net "GMI_CPU0_G2_CPU1_G0_TX_DP<0>")
	)
	(segment
		(start 315.158374 -176.979072)
		(end 310.158384 -175.076358)
		(width 0.14224)
		(layer "In2.Cu")
		(net "GMI_CPU0_G2_CPU1_G0_TX_DP<0>")
	)
	(segment
		(start 374.60682 -225.389694)
		(end 374.567704 -225.366834)
		(width 0.1143)
		(layer "In2.Cu")
		(net "GMI_CPU0_G2_CPU1_G0_TX_DP<0>")
	)
	(segment
		(start 96.418908 -222.26905)
		(end 96.425766 -222.273114)
		(width 0.1143)
		(layer "In2.Cu")
		(net "GMI_CPU0_G2_CPU1_G0_TX_DP<0>")
	)
	(segment
		(start 374.066054 -230.410004)
		(end 374.097804 -230.391716)
		(width 0.1143)
		(layer "In2.Cu")
		(net "GMI_CPU0_G2_CPU1_G0_TX_DP<0>")
	)
	(segment
		(start 96.958658 -225.349308)
		(end 96.928178 -225.367088)
		(width 0.1143)
		(layer "In2.Cu")
		(net "GMI_CPU0_G2_CPU1_G0_TX_DP<0>")
	)
	(segment
		(start 374.567704 -225.366834)
		(end 374.537224 -225.349054)
		(width 0.1143)
		(layer "In2.Cu")
		(net "GMI_CPU0_G2_CPU1_G0_TX_DP<0>")
	)
	(segment
		(start 374.567704 -223.746822)
		(end 374.537224 -223.729042)
		(width 0.1143)
		(layer "In2.Cu")
		(net "GMI_CPU0_G2_CPU1_G0_TX_DP<0>")
	)
	(segment
		(start 96.928178 -226.9871)
		(end 96.889062 -227.00996)
		(width 0.1143)
		(layer "In2.Cu")
		(net "GMI_CPU0_G2_CPU1_G0_TX_DP<0>")
	)
	(segment
		(start 373.516906 -231.524048)
		(end 373.447056 -231.454198)
		(width 0.1143)
		(layer "In2.Cu")
		(net "GMI_CPU0_G2_CPU1_G0_TX_DP<0>")
	)
	(segment
		(start 104.84104 -202.660758)
		(end 96.069658 -211.43214)
		(width 0.14224)
		(layer "In2.Cu")
		(net "GMI_CPU0_G2_CPU1_G0_TX_DP<0>")
	)
	(segment
		(start 310.158384 -175.076358)
		(end 306.615338 -174.157132)
		(width 0.14224)
		(layer "In2.Cu")
		(net "GMI_CPU0_G2_CPU1_G0_TX_DP<0>")
	)
	(segment
		(start 374.379744 -221.248478)
		(end 374.425464 -221.202758)
		(width 0.1143)
		(layer "In2.Cu")
		(net "GMI_CPU0_G2_CPU1_G0_TX_DP<0>")
	)
	(segment
		(start 374.567704 -223.101662)
		(end 374.60682 -223.078802)
		(width 0.1143)
		(layer "In2.Cu")
		(net "GMI_CPU0_G2_CPU1_G0_TX_DP<0>")
	)
	(segment
		(start 96.928178 -229.581964)
		(end 96.96069 -229.60076)
		(width 0.1143)
		(layer "In2.Cu")
		(net "GMI_CPU0_G2_CPU1_G0_TX_DP<0>")
	)
	(segment
		(start 96.425766 -222.273114)
		(end 96.426528 -222.273622)
		(width 0.1143)
		(layer "In2.Cu")
		(net "GMI_CPU0_G2_CPU1_G0_TX_DP<0>")
	)
	(segment
		(start 164.324284 -174.198534)
		(end 160.64611 -175.248316)
		(width 0.14224)
		(layer "In2.Cu")
		(net "GMI_CPU0_G2_CPU1_G0_TX_DP<0>")
	)
	(segment
		(start 96.928178 -225.367088)
		(end 96.889062 -225.389948)
		(width 0.1143)
		(layer "In2.Cu")
		(net "GMI_CPU0_G2_CPU1_G0_TX_DP<0>")
	)
	(segment
		(start 362.73359 -204.3176)
		(end 362.733336 -204.317346)
		(width 0.14224)
		(layer "In2.Cu")
		(net "GMI_CPU0_G2_CPU1_G0_TX_DP<0>")
	)
	(segment
		(start 374.60682 -223.769682)
		(end 374.567704 -223.746822)
		(width 0.1143)
		(layer "In2.Cu")
		(net "GMI_CPU0_G2_CPU1_G0_TX_DP<0>")
	)
	(segment
		(start 373.595138 -231.220518)
		(end 373.62765 -231.201722)
		(width 0.1143)
		(layer "In2.Cu")
		(net "GMI_CPU0_G2_CPU1_G0_TX_DP<0>")
	)
	(segment
		(start 96.426528 -222.273622)
		(end 96.457008 -222.291402)
		(width 0.1143)
		(layer "In2.Cu")
		(net "GMI_CPU0_G2_CPU1_G0_TX_DP<0>")
	)
	(segment
		(start 374.425464 -221.202758)
		(end 374.425464 -221.17431)
		(width 0.1143)
		(layer "In2.Cu")
		(net "GMI_CPU0_G2_CPU1_G0_TX_DP<0>")
	)
	(segment
		(start 96.889062 -229.559104)
		(end 96.928178 -229.581964)
		(width 0.1143)
		(layer "In2.Cu")
		(net "GMI_CPU0_G2_CPU1_G0_TX_DP<0>")
	)
	(segment
		(start 374.425464 -221.17431)
		(end 374.425464 -217.208608)
		(width 0.14224)
		(layer "In2.Cu")
		(net "GMI_CPU0_G2_CPU1_G0_TX_DP<0>")
	)
	(segment
		(start 374.425464 -217.208608)
		(end 371.83441 -211.514436)
		(width 0.14224)
		(layer "In2.Cu")
		(net "GMI_CPU0_G2_CPU1_G0_TX_DP<0>")
	)
	(segment
		(start 96.928178 -228.607112)
		(end 96.889062 -228.629972)
		(width 0.1143)
		(layer "In2.Cu")
		(net "GMI_CPU0_G2_CPU1_G0_TX_DP<0>")
	)
	(segment
		(start 374.097804 -230.391716)
		(end 374.13438 -230.37038)
		(width 0.1143)
		(layer "In2.Cu")
		(net "GMI_CPU0_G2_CPU1_G0_TX_DP<0>")
	)
	(segment
		(start 374.567704 -229.58171)
		(end 374.60682 -229.55885)
		(width 0.1143)
		(layer "In2.Cu")
		(net "GMI_CPU0_G2_CPU1_G0_TX_DP<0>")
	)
	(segment
		(start 374.537224 -227.979478)
		(end 374.567704 -227.961698)
		(width 0.1143)
		(layer "In2.Cu")
		(net "GMI_CPU0_G2_CPU1_G0_TX_DP<0>")
	)
	(segment
		(start 96.458024 -222.29191)
		(end 96.489774 -222.310198)
		(width 0.1143)
		(layer "In2.Cu")
		(net "GMI_CPU0_G2_CPU1_G0_TX_DP<0>")
	)
	(segment
		(start 96.889062 -224.699068)
		(end 96.928178 -224.721928)
		(width 0.1143)
		(layer "In2.Cu")
		(net "GMI_CPU0_G2_CPU1_G0_TX_DP<0>")
	)
	(segment
		(start 96.928178 -223.101916)
		(end 96.958658 -223.119696)
		(width 0.1143)
		(layer "In2.Cu")
		(net "GMI_CPU0_G2_CPU1_G0_TX_DP<0>")
	)
	(segment
		(start 374.379744 -221.466664)
		(end 374.379744 -221.248478)
		(width 0.1143)
		(layer "In2.Cu")
		(net "GMI_CPU0_G2_CPU1_G0_TX_DP<0>")
	)
	(segment
		(start 96.115378 -221.248732)
		(end 96.115378 -221.624906)
		(width 0.1143)
		(layer "In2.Cu")
		(net "GMI_CPU0_G2_CPU1_G0_TX_DP<0>")
	)
	(segment
		(start 96.069658 -221.174564)
		(end 96.069658 -221.203012)
		(width 0.1143)
		(layer "In2.Cu")
		(net "GMI_CPU0_G2_CPU1_G0_TX_DP<0>")
	)
	(segment
		(start 96.928178 -227.961952)
		(end 96.958658 -227.979732)
		(width 0.1143)
		(layer "In2.Cu")
		(net "GMI_CPU0_G2_CPU1_G0_TX_DP<0>")
	)
	(segment
		(start 366.493806 -206.862426)
		(end 362.73359 -204.3176)
		(width 0.14224)
		(layer "In2.Cu")
		(net "GMI_CPU0_G2_CPU1_G0_TX_DP<0>")
	)
	(segment
		(start 96.928178 -226.34194)
		(end 96.958658 -226.35972)
		(width 0.1143)
		(layer "In2.Cu")
		(net "GMI_CPU0_G2_CPU1_G0_TX_DP<0>")
	)
	(segment
		(start 96.928178 -224.721928)
		(end 96.958658 -224.739708)
		(width 0.1143)
		(layer "In2.Cu")
		(net "GMI_CPU0_G2_CPU1_G0_TX_DP<0>")
	)
	(segment
		(start 373.814848 -231.524048)
		(end 373.516906 -231.524048)
		(width 0.1143)
		(layer "In2.Cu")
		(net "GMI_CPU0_G2_CPU1_G0_TX_DP<0>")
	)
	(segment
		(start 374.567704 -227.961698)
		(end 374.60682 -227.938838)
		(width 0.1143)
		(layer "In2.Cu")
		(net "GMI_CPU0_G2_CPU1_G0_TX_DP<0>")
	)
	(segment
		(start 96.958658 -228.589332)
		(end 96.928178 -228.607112)
		(width 0.1143)
		(layer "In2.Cu")
		(net "GMI_CPU0_G2_CPU1_G0_TX_DP<0>")
	)
	(segment
		(start 371.83441 -211.514436)
		(end 366.493806 -206.862426)
		(width 0.14224)
		(layer "In2.Cu")
		(net "GMI_CPU0_G2_CPU1_G0_TX_DP<0>")
	)
	(segment
		(start 96.069658 -221.203012)
		(end 96.115378 -221.248732)
		(width 0.1143)
		(layer "In2.Cu")
		(net "GMI_CPU0_G2_CPU1_G0_TX_DP<0>")
	)
	(segment
		(start 97.863914 -231.19969)
		(end 97.901506 -231.221534)
		(width 0.1143)
		(layer "In2.Cu")
		(net "GMI_CPU0_G2_CPU1_G0_TX_DP<0>")
	)
	(segment
		(start 374.380252 -221.467172)
		(end 374.379744 -221.466664)
		(width 0.1143)
		(layer "In2.Cu")
		(net "GMI_CPU0_G2_CPU1_G0_TX_DP<0>")
	)
	(segment
		(start 96.457008 -222.291402)
		(end 96.458024 -222.29191)
		(width 0.1143)
		(layer "In2.Cu")
		(net "GMI_CPU0_G2_CPU1_G0_TX_DP<0>")
	)
	(segment
		(start 96.958658 -223.729296)
		(end 96.928178 -223.747076)
		(width 0.1143)
		(layer "In2.Cu")
		(net "GMI_CPU0_G2_CPU1_G0_TX_DP<0>")
	)
	(segment
		(start 374.60682 -228.629718)
		(end 374.567704 -228.606858)
		(width 0.1143)
		(layer "In2.Cu")
		(net "GMI_CPU0_G2_CPU1_G0_TX_DP<0>")
	)
	(segment
		(start 374.537224 -224.739454)
		(end 374.567704 -224.721674)
		(width 0.1143)
		(layer "In2.Cu")
		(net "GMI_CPU0_G2_CPU1_G0_TX_DP<0>")
	)
	(segment
		(start 96.17583 -221.685358)
		(end 96.175576 -221.685612)
		(width 0.1143)
		(layer "In2.Cu")
		(net "GMI_CPU0_G2_CPU1_G0_TX_DP<0>")
	)
	(segment
		(start 325.367904 -181.896258)
		(end 315.158374 -176.979072)
		(width 0.14224)
		(layer "In2.Cu")
		(net "GMI_CPU0_G2_CPU1_G0_TX_DP<0>")
	)
	(segment
		(start 96.175576 -221.685612)
		(end 96.175576 -221.804484)
		(width 0.1143)
		(layer "In2.Cu")
		(net "GMI_CPU0_G2_CPU1_G0_TX_DP<0>")
	)
	(segment
		(start 374.567704 -224.721674)
		(end 374.60682 -224.698814)
		(width 0.1143)
		(layer "In2.Cu")
		(net "GMI_CPU0_G2_CPU1_G0_TX_DP<0>")
	)
	(segment
		(start 96.069658 -211.43214)
		(end 96.069658 -221.174564)
		(width 0.14224)
		(layer "In2.Cu")
		(net "GMI_CPU0_G2_CPU1_G0_TX_DP<0>")
	)
	(arc
		(start 96.958658 -224.739708)
		(mid 97.115635 -225.044508)
		(end 96.958658 -225.349308)
		(width 0.1143)
		(layer "In2.Cu")
		(net "GMI_CPU0_G2_CPU1_G0_TX_DP<0>")
	)
	(arc
		(start 374.537224 -225.349054)
		(mid 374.380247 -225.044254)
		(end 374.537224 -224.739454)
		(width 0.1143)
		(layer "In2.Cu")
		(net "GMI_CPU0_G2_CPU1_G0_TX_DP<0>")
	)
	(arc
		(start 96.958658 -227.979732)
		(mid 97.115635 -228.284532)
		(end 96.958658 -228.589332)
		(width 0.1143)
		(layer "In2.Cu")
		(net "GMI_CPU0_G2_CPU1_G0_TX_DP<0>")
	)
	(arc
		(start 96.889062 -223.769936)
		(mid 96.645735 -224.234502)
		(end 96.889062 -224.699068)
		(width 0.1143)
		(layer "In2.Cu")
		(net "GMI_CPU0_G2_CPU1_G0_TX_DP<0>")
	)
	(arc
		(start 373.666766 -231.178862)
		(mid 373.845579 -230.976512)
		(end 373.910098 -230.714296)
		(width 0.1143)
		(layer "In2.Cu")
		(net "GMI_CPU0_G2_CPU1_G0_TX_DP<0>")
	)
	(arc
		(start 96.889062 -227.00996)
		(mid 96.645735 -227.474526)
		(end 96.889062 -227.939092)
		(width 0.1143)
		(layer "In2.Cu")
		(net "GMI_CPU0_G2_CPU1_G0_TX_DP<0>")
	)
	(arc
		(start 374.13438 -230.37038)
		(mid 374.315032 -230.167635)
		(end 374.380252 -229.904036)
		(width 0.1143)
		(layer "In2.Cu")
		(net "GMI_CPU0_G2_CPU1_G0_TX_DP<0>")
	)
	(arc
		(start 374.537224 -226.969066)
		(mid 374.380247 -226.664266)
		(end 374.537224 -226.359466)
		(width 0.1143)
		(layer "In2.Cu")
		(net "GMI_CPU0_G2_CPU1_G0_TX_DP<0>")
	)
	(arc
		(start 96.958658 -226.35972)
		(mid 97.115635 -226.66452)
		(end 96.958658 -226.96932)
		(width 0.1143)
		(layer "In2.Cu")
		(net "GMI_CPU0_G2_CPU1_G0_TX_DP<0>")
	)
	(arc
		(start 374.380252 -229.904036)
		(mid 374.421218 -229.73363)
		(end 374.535192 -229.600506)
		(width 0.1143)
		(layer "In2.Cu")
		(net "GMI_CPU0_G2_CPU1_G0_TX_DP<0>")
	)
	(arc
		(start 373.447056 -231.454198)
		(mid 373.498764 -231.323215)
		(end 373.595138 -231.220518)
		(width 0.1143)
		(layer "In2.Cu")
		(net "GMI_CPU0_G2_CPU1_G0_TX_DP<0>")
	)
	(arc
		(start 374.537224 -223.729042)
		(mid 374.380247 -223.424242)
		(end 374.537224 -223.119442)
		(width 0.1143)
		(layer "In2.Cu")
		(net "GMI_CPU0_G2_CPU1_G0_TX_DP<0>")
	)
	(arc
		(start 97.398332 -230.39197)
		(mid 97.535377 -230.52893)
		(end 97.58553 -230.716074)
		(width 0.1143)
		(layer "In2.Cu")
		(net "GMI_CPU0_G2_CPU1_G0_TX_DP<0>")
	)
	(arc
		(start 373.910098 -230.714296)
		(mid 373.951353 -230.543325)
		(end 374.066054 -230.410004)
		(width 0.1143)
		(layer "In2.Cu")
		(net "GMI_CPU0_G2_CPU1_G0_TX_DP<0>")
	)
	(arc
		(start 374.60682 -224.698814)
		(mid 374.850147 -224.234248)
		(end 374.60682 -223.769682)
		(width 0.1143)
		(layer "In2.Cu")
		(net "GMI_CPU0_G2_CPU1_G0_TX_DP<0>")
	)
	(arc
		(start 97.11563 -229.90429)
		(mid 97.180866 -230.167881)
		(end 97.361502 -230.370634)
		(width 0.1143)
		(layer "In2.Cu")
		(net "GMI_CPU0_G2_CPU1_G0_TX_DP<0>")
	)
	(arc
		(start 374.60682 -229.55885)
		(mid 374.850147 -229.094284)
		(end 374.60682 -228.629718)
		(width 0.1143)
		(layer "In2.Cu")
		(net "GMI_CPU0_G2_CPU1_G0_TX_DP<0>")
	)
	(arc
		(start 374.537224 -228.589078)
		(mid 374.380247 -228.284278)
		(end 374.537224 -227.979478)
		(width 0.1143)
		(layer "In2.Cu")
		(net "GMI_CPU0_G2_CPU1_G0_TX_DP<0>")
	)
	(arc
		(start 96.175576 -221.804484)
		(mid 96.240091 -222.066703)
		(end 96.418908 -222.26905)
		(width 0.1143)
		(layer "In2.Cu")
		(net "GMI_CPU0_G2_CPU1_G0_TX_DP<0>")
	)
	(arc
		(start 374.60682 -227.938838)
		(mid 374.850147 -227.474272)
		(end 374.60682 -227.009706)
		(width 0.1143)
		(layer "In2.Cu")
		(net "GMI_CPU0_G2_CPU1_G0_TX_DP<0>")
	)
	(arc
		(start 96.889062 -228.629972)
		(mid 96.645735 -229.094538)
		(end 96.889062 -229.559104)
		(width 0.1143)
		(layer "In2.Cu")
		(net "GMI_CPU0_G2_CPU1_G0_TX_DP<0>")
	)
	(arc
		(start 96.64573 -222.61449)
		(mid 96.710245 -222.876709)
		(end 96.889062 -223.079056)
		(width 0.1143)
		(layer "In2.Cu")
		(net "GMI_CPU0_G2_CPU1_G0_TX_DP<0>")
	)
	(arc
		(start 96.958658 -223.119696)
		(mid 97.115635 -223.424496)
		(end 96.958658 -223.729296)
		(width 0.1143)
		(layer "In2.Cu")
		(net "GMI_CPU0_G2_CPU1_G0_TX_DP<0>")
	)
	(arc
		(start 97.901506 -231.221534)
		(mid 97.997394 -231.323942)
		(end 98.048826 -231.454452)
		(width 0.1143)
		(layer "In2.Cu")
		(net "GMI_CPU0_G2_CPU1_G0_TX_DP<0>")
	)
	(arc
		(start 97.58553 -230.716074)
		(mid 97.660094 -230.995087)
		(end 97.863914 -231.19969)
		(width 0.1143)
		(layer "In2.Cu")
		(net "GMI_CPU0_G2_CPU1_G0_TX_DP<0>")
	)
	(arc
		(start 374.60682 -223.078802)
		(mid 374.850147 -222.614236)
		(end 374.60682 -222.14967)
		(width 0.1143)
		(layer "In2.Cu")
		(net "GMI_CPU0_G2_CPU1_G0_TX_DP<0>")
	)
	(arc
		(start 96.489774 -222.310198)
		(mid 96.60445 -222.443532)
		(end 96.64573 -222.61449)
		(width 0.1143)
		(layer "In2.Cu")
		(net "GMI_CPU0_G2_CPU1_G0_TX_DP<0>")
	)
	(arc
		(start 374.537224 -222.10903)
		(mid 374.421797 -221.975654)
		(end 374.380252 -221.80423)
		(width 0.1143)
		(layer "In2.Cu")
		(net "GMI_CPU0_G2_CPU1_G0_TX_DP<0>")
	)
	(arc
		(start 96.96069 -229.60076)
		(mid 97.074619 -229.733907)
		(end 97.11563 -229.90429)
		(width 0.1143)
		(layer "In2.Cu")
		(net "GMI_CPU0_G2_CPU1_G0_TX_DP<0>")
	)
	(arc
		(start 96.889062 -225.389948)
		(mid 96.645735 -225.854514)
		(end 96.889062 -226.31908)
		(width 0.1143)
		(layer "In2.Cu")
		(net "GMI_CPU0_G2_CPU1_G0_TX_DP<0>")
	)
	(arc
		(start 374.60682 -226.318826)
		(mid 374.850147 -225.85426)
		(end 374.60682 -225.389694)
		(width 0.1143)
		(layer "In2.Cu")
		(net "GMI_CPU0_G2_CPU1_G0_TX_DP<0>")
	)
	(segment
		(start 104.72801 -230.170228)
		(end 104.261158 -229.90429)
		(width 0.12954)
		(layer "F.Cu")
		(net "GMI_CPU0_G2_CPU1_G0_TX_DN<9>")
	)
	(segment
		(start 366.767872 -230.169974)
		(end 367.234724 -229.904036)
		(width 0.12954)
		(layer "F.Cu")
		(net "GMI_CPU0_G2_CPU1_G0_TX_DN<9>")
	)
	(segment
		(start 105.480612 -226.175062)
		(end 105.47985 -226.174554)
		(width 0.1143)
		(layer "In2.Cu")
		(net "GMI_CPU0_G2_CPU1_G0_TX_DN<9>")
	)
	(segment
		(start 107.24007 -214.540084)
		(end 107.536234 -214.24392)
		(width 0.14224)
		(layer "In2.Cu")
		(net "GMI_CPU0_G2_CPU1_G0_TX_DN<9>")
	)
	(segment
		(start 366.952022 -228.772974)
		(end 366.953292 -228.77272)
		(width 0.1143)
		(layer "In2.Cu")
		(net "GMI_CPU0_G2_CPU1_G0_TX_DN<9>")
	)
	(segment
		(start 366.953292 -228.77272)
		(end 366.983518 -228.789992)
		(width 0.1143)
		(layer "In2.Cu")
		(net "GMI_CPU0_G2_CPU1_G0_TX_DN<9>")
	)
	(segment
		(start 105.47985 -225.534474)
		(end 105.480612 -225.533966)
		(width 0.1143)
		(layer "In2.Cu")
		(net "GMI_CPU0_G2_CPU1_G0_TX_DN<9>")
	)
	(segment
		(start 111.743998 -210.036156)
		(end 155.443174 -187.070238)
		(width 0.14224)
		(layer "In2.Cu")
		(net "GMI_CPU0_G2_CPU1_G0_TX_DN<9>")
	)
	(segment
		(start 322.425568 -190.575438)
		(end 355.943408 -210.434682)
		(width 0.14224)
		(layer "In2.Cu")
		(net "GMI_CPU0_G2_CPU1_G0_TX_DN<9>")
	)
	(segment
		(start 105.52303 -223.889316)
		(end 105.55097 -223.86925)
		(width 0.1143)
		(layer "In2.Cu")
		(net "GMI_CPU0_G2_CPU1_G0_TX_DN<9>")
	)
	(segment
		(start 105.97007 -215.810084)
		(end 106.16057 -215.810084)
		(width 0.14224)
		(layer "In2.Cu")
		(net "GMI_CPU0_G2_CPU1_G0_TX_DN<9>")
	)
	(segment
		(start 104.542082 -228.773228)
		(end 104.543352 -228.772466)
		(width 0.1143)
		(layer "In2.Cu")
		(net "GMI_CPU0_G2_CPU1_G0_TX_DN<9>")
	)
	(segment
		(start 111.15548 -210.81492)
		(end 111.15548 -210.624674)
		(width 0.14224)
		(layer "In2.Cu")
		(net "GMI_CPU0_G2_CPU1_G0_TX_DN<9>")
	)
	(segment
		(start 366.013746 -226.17557)
		(end 366.012476 -226.176332)
		(width 0.1143)
		(layer "In2.Cu")
		(net "GMI_CPU0_G2_CPU1_G0_TX_DN<9>")
	)
	(segment
		(start 366.011714 -226.17684)
		(end 365.972598 -226.1997)
		(width 0.1143)
		(layer "In2.Cu")
		(net "GMI_CPU0_G2_CPU1_G0_TX_DN<9>")
	)
	(segment
		(start 366.009174 -227.150168)
		(end 366.010698 -227.151184)
		(width 0.1143)
		(layer "In2.Cu")
		(net "GMI_CPU0_G2_CPU1_G0_TX_DN<9>")
	)
	(segment
		(start 104.89057 -221.174564)
		(end 104.89057 -216.88933)
		(width 0.14224)
		(layer "In2.Cu")
		(net "GMI_CPU0_G2_CPU1_G0_TX_DN<9>")
	)
	(segment
		(start 367.385346 -229.560628)
		(end 367.421668 -229.58171)
		(width 0.1143)
		(layer "In2.Cu")
		(net "GMI_CPU0_G2_CPU1_G0_TX_DN<9>")
	)
	(segment
		(start 105.478834 -225.534982)
		(end 105.47985 -225.534474)
		(width 0.1143)
		(layer "In2.Cu")
		(net "GMI_CPU0_G2_CPU1_G0_TX_DN<9>")
	)
	(segment
		(start 105.452418 -225.550222)
		(end 105.478834 -225.534982)
		(width 0.1143)
		(layer "In2.Cu")
		(net "GMI_CPU0_G2_CPU1_G0_TX_DN<9>")
	)
	(segment
		(start 105.486962 -222.938848)
		(end 105.484168 -222.93707)
		(width 0.1143)
		(layer "In2.Cu")
		(net "GMI_CPU0_G2_CPU1_G0_TX_DN<9>")
	)
	(segment
		(start 105.014014 -222.127064)
		(end 104.983534 -222.109284)
		(width 0.1143)
		(layer "In2.Cu")
		(net "GMI_CPU0_G2_CPU1_G0_TX_DN<9>")
	)
	(segment
		(start 107.536234 -214.24392)
		(end 107.726734 -214.24392)
		(width 0.14224)
		(layer "In2.Cu")
		(net "GMI_CPU0_G2_CPU1_G0_TX_DN<9>")
	)
	(segment
		(start 365.685578 -221.426024)
		(end 365.72952 -221.469966)
		(width 0.1143)
		(layer "In2.Cu")
		(net "GMI_CPU0_G2_CPU1_G0_TX_DN<9>")
	)
	(segment
		(start 365.972598 -223.888808)
		(end 366.009174 -223.910144)
		(width 0.1143)
		(layer "In2.Cu")
		(net "GMI_CPU0_G2_CPU1_G0_TX_DN<9>")
	)
	(segment
		(start 104.84485 -221.248732)
		(end 104.89057 -221.203012)
		(width 0.1143)
		(layer "In2.Cu")
		(net "GMI_CPU0_G2_CPU1_G0_TX_DN<9>")
	)
	(segment
		(start 366.011714 -222.291656)
		(end 366.043464 -222.309944)
		(width 0.1143)
		(layer "In2.Cu")
		(net "GMI_CPU0_G2_CPU1_G0_TX_DN<9>")
	)
	(segment
		(start 107.726734 -214.24392)
		(end 108.023152 -213.947248)
		(width 0.14224)
		(layer "In2.Cu")
		(net "GMI_CPU0_G2_CPU1_G0_TX_DN<9>")
	)
	(segment
		(start 105.484168 -227.151946)
		(end 105.52049 -227.130864)
		(width 0.1143)
		(layer "In2.Cu")
		(net "GMI_CPU0_G2_CPU1_G0_TX_DN<9>")
	)
	(segment
		(start 309.574692 -184.373774)
		(end 322.425568 -190.575438)
		(width 0.14224)
		(layer "In2.Cu")
		(net "GMI_CPU0_G2_CPU1_G0_TX_DN<9>")
	)
	(segment
		(start 109.589316 -212.190838)
		(end 109.88548 -211.894674)
		(width 0.14224)
		(layer "In2.Cu")
		(net "GMI_CPU0_G2_CPU1_G0_TX_DN<9>")
	)
	(segment
		(start 105.52303 -225.509328)
		(end 105.55097 -225.489262)
		(width 0.1143)
		(layer "In2.Cu")
		(net "GMI_CPU0_G2_CPU1_G0_TX_DN<9>")
	)
	(segment
		(start 366.043464 -226.158552)
		(end 366.013746 -226.17557)
		(width 0.1143)
		(layer "In2.Cu")
		(net "GMI_CPU0_G2_CPU1_G0_TX_DN<9>")
	)
	(segment
		(start 366.212374 -227.46716)
		(end 366.212374 -227.494338)
		(width 0.1143)
		(layer "In2.Cu")
		(net "GMI_CPU0_G2_CPU1_G0_TX_DN<9>")
	)
	(segment
		(start 109.589316 -212.381084)
		(end 109.589316 -212.190838)
		(width 0.14224)
		(layer "In2.Cu")
		(net "GMI_CPU0_G2_CPU1_G0_TX_DN<9>")
	)
	(segment
		(start 104.54513 -228.77145)
		(end 104.546654 -228.770434)
		(width 0.1143)
		(layer "In2.Cu")
		(net "GMI_CPU0_G2_CPU1_G0_TX_DN<9>")
	)
	(segment
		(start 105.482136 -226.175824)
		(end 105.480612 -226.175062)
		(width 0.1143)
		(layer "In2.Cu")
		(net "GMI_CPU0_G2_CPU1_G0_TX_DN<9>")
	)
	(segment
		(start 109.102398 -212.677756)
		(end 109.292898 -212.677756)
		(width 0.14224)
		(layer "In2.Cu")
		(net "GMI_CPU0_G2_CPU1_G0_TX_DN<9>")
	)
	(segment
		(start 105.47985 -227.154486)
		(end 105.480612 -227.153978)
		(width 0.1143)
		(layer "In2.Cu")
		(net "GMI_CPU0_G2_CPU1_G0_TX_DN<9>")
	)
	(segment
		(start 105.452418 -227.170234)
		(end 105.478834 -227.154994)
		(width 0.1143)
		(layer "In2.Cu")
		(net "GMI_CPU0_G2_CPU1_G0_TX_DN<9>")
	)
	(segment
		(start 105.483406 -225.532442)
		(end 105.483914 -225.532442)
		(width 0.1143)
		(layer "In2.Cu")
		(net "GMI_CPU0_G2_CPU1_G0_TX_DN<9>")
	)
	(segment
		(start 366.010698 -223.91116)
		(end 366.011714 -223.911668)
		(width 0.1143)
		(layer "In2.Cu")
		(net "GMI_CPU0_G2_CPU1_G0_TX_DN<9>")
	)
	(segment
		(start 105.484168 -224.557082)
		(end 105.483406 -224.556574)
		(width 0.1143)
		(layer "In2.Cu")
		(net "GMI_CPU0_G2_CPU1_G0_TX_DN<9>")
	)
	(segment
		(start 106.456988 -215.513412)
		(end 106.456988 -215.323166)
		(width 0.14224)
		(layer "In2.Cu")
		(net "GMI_CPU0_G2_CPU1_G0_TX_DN<9>")
	)
	(segment
		(start 366.041686 -227.169218)
		(end 366.042702 -227.169726)
		(width 0.1143)
		(layer "In2.Cu")
		(net "GMI_CPU0_G2_CPU1_G0_TX_DN<9>")
	)
	(segment
		(start 105.478834 -223.91497)
		(end 105.47985 -223.914462)
		(width 0.1143)
		(layer "In2.Cu")
		(net "GMI_CPU0_G2_CPU1_G0_TX_DN<9>")
	)
	(segment
		(start 105.47985 -224.554542)
		(end 105.452418 -224.538794)
		(width 0.1143)
		(layer "In2.Cu")
		(net "GMI_CPU0_G2_CPU1_G0_TX_DN<9>")
	)
	(segment
		(start 105.483406 -222.936562)
		(end 105.482136 -222.9358)
		(width 0.1143)
		(layer "In2.Cu")
		(net "GMI_CPU0_G2_CPU1_G0_TX_DN<9>")
	)
	(segment
		(start 366.012476 -227.1522)
		(end 366.037368 -227.166678)
		(width 0.1143)
		(layer "In2.Cu")
		(net "GMI_CPU0_G2_CPU1_G0_TX_DN<9>")
	)
	(segment
		(start 110.372398 -211.407756)
		(end 110.668562 -211.111592)
		(width 0.14224)
		(layer "In2.Cu")
		(net "GMI_CPU0_G2_CPU1_G0_TX_DN<9>")
	)
	(segment
		(start 366.038384 -227.167186)
		(end 366.041686 -227.169218)
		(width 0.1143)
		(layer "In2.Cu")
		(net "GMI_CPU0_G2_CPU1_G0_TX_DN<9>")
	)
	(segment
		(start 366.455198 -227.958396)
		(end 366.49406 -227.981256)
		(width 0.1143)
		(layer "In2.Cu")
		(net "GMI_CPU0_G2_CPU1_G0_TX_DN<9>")
	)
	(segment
		(start 365.972598 -227.128832)
		(end 366.009174 -227.150168)
		(width 0.1143)
		(layer "In2.Cu")
		(net "GMI_CPU0_G2_CPU1_G0_TX_DN<9>")
	)
	(segment
		(start 366.043464 -224.53854)
		(end 366.013746 -224.555558)
		(width 0.1143)
		(layer "In2.Cu")
		(net "GMI_CPU0_G2_CPU1_G0_TX_DN<9>")
	)
	(segment
		(start 367.602516 -229.834186)
		(end 367.532666 -229.904036)
		(width 0.1143)
		(layer "In2.Cu")
		(net "GMI_CPU0_G2_CPU1_G0_TX_DN<9>")
	)
	(segment
		(start 355.943408 -210.434682)
		(end 360.202988 -213.321392)
		(width 0.14224)
		(layer "In2.Cu")
		(net "GMI_CPU0_G2_CPU1_G0_TX_DN<9>")
	)
	(segment
		(start 366.013746 -222.935546)
		(end 366.012476 -222.936308)
		(width 0.1143)
		(layer "In2.Cu")
		(net "GMI_CPU0_G2_CPU1_G0_TX_DN<9>")
	)
	(segment
		(start 105.482136 -225.533204)
		(end 105.483406 -225.532442)
		(width 0.1143)
		(layer "In2.Cu")
		(net "GMI_CPU0_G2_CPU1_G0_TX_DN<9>")
	)
	(segment
		(start 365.972598 -222.268796)
		(end 366.008158 -222.289624)
		(width 0.1143)
		(layer "In2.Cu")
		(net "GMI_CPU0_G2_CPU1_G0_TX_DN<9>")
	)
	(segment
		(start 366.010698 -227.151184)
		(end 366.011714 -227.151692)
		(width 0.1143)
		(layer "In2.Cu")
		(net "GMI_CPU0_G2_CPU1_G0_TX_DN<9>")
	)
	(segment
		(start 104.983534 -227.979732)
		(end 105.014014 -227.961952)
		(width 0.1143)
		(layer "In2.Cu")
		(net "GMI_CPU0_G2_CPU1_G0_TX_DN<9>")
	)
	(segment
		(start 105.52049 -226.198176)
		(end 105.484168 -226.177094)
		(width 0.1143)
		(layer "In2.Cu")
		(net "GMI_CPU0_G2_CPU1_G0_TX_DN<9>")
	)
	(segment
		(start 364.695994 -217.238326)
		(end 365.639858 -219.313506)
		(width 0.14224)
		(layer "In2.Cu")
		(net "GMI_CPU0_G2_CPU1_G0_TX_DN<9>")
	)
	(segment
		(start 366.010698 -222.291148)
		(end 366.011714 -222.291656)
		(width 0.1143)
		(layer "In2.Cu")
		(net "GMI_CPU0_G2_CPU1_G0_TX_DN<9>")
	)
	(segment
		(start 365.639858 -219.313506)
		(end 365.639858 -221.083124)
		(width 0.14224)
		(layer "In2.Cu")
		(net "GMI_CPU0_G2_CPU1_G0_TX_DN<9>")
	)
	(segment
		(start 105.55097 -224.599754)
		(end 105.52303 -224.579688)
		(width 0.1143)
		(layer "In2.Cu")
		(net "GMI_CPU0_G2_CPU1_G0_TX_DN<9>")
	)
	(segment
		(start 105.47985 -226.174554)
		(end 105.452418 -226.158806)
		(width 0.1143)
		(layer "In2.Cu")
		(net "GMI_CPU0_G2_CPU1_G0_TX_DN<9>")
	)
	(segment
		(start 106.16057 -215.810084)
		(end 106.456988 -215.513412)
		(width 0.14224)
		(layer "In2.Cu")
		(net "GMI_CPU0_G2_CPU1_G0_TX_DN<9>")
	)
	(segment
		(start 104.53878 -228.775006)
		(end 104.539796 -228.774498)
		(width 0.1143)
		(layer "In2.Cu")
		(net "GMI_CPU0_G2_CPU1_G0_TX_DN<9>")
	)
	(segment
		(start 366.919256 -228.751892)
		(end 366.951006 -228.772466)
		(width 0.1143)
		(layer "In2.Cu")
		(net "GMI_CPU0_G2_CPU1_G0_TX_DN<9>")
	)
	(segment
		(start 105.480612 -223.913954)
		(end 105.482136 -223.913192)
		(width 0.1143)
		(layer "In2.Cu")
		(net "GMI_CPU0_G2_CPU1_G0_TX_DN<9>")
	)
	(segment
		(start 104.827832 -221.54896)
		(end 104.84485 -221.531942)
		(width 0.1143)
		(layer "In2.Cu")
		(net "GMI_CPU0_G2_CPU1_G0_TX_DN<9>")
	)
	(segment
		(start 166.370508 -182.993538)
		(end 236.61243 -180.907182)
		(width 0.14224)
		(layer "In2.Cu")
		(net "GMI_CPU0_G2_CPU1_G0_TX_DN<9>")
	)
	(segment
		(start 366.011714 -224.556828)
		(end 365.972598 -224.579688)
		(width 0.1143)
		(layer "In2.Cu")
		(net "GMI_CPU0_G2_CPU1_G0_TX_DN<9>")
	)
	(segment
		(start 104.261158 -229.90429)
		(end 103.963216 -229.90429)
		(width 0.1143)
		(layer "In2.Cu")
		(net "GMI_CPU0_G2_CPU1_G0_TX_DN<9>")
	)
	(segment
		(start 366.011714 -223.911668)
		(end 366.012476 -223.912176)
		(width 0.1143)
		(layer "In2.Cu")
		(net "GMI_CPU0_G2_CPU1_G0_TX_DN<9>")
	)
	(segment
		(start 105.478834 -227.154994)
		(end 105.47985 -227.154486)
		(width 0.1143)
		(layer "In2.Cu")
		(net "GMI_CPU0_G2_CPU1_G0_TX_DN<9>")
	)
	(segment
		(start 104.539796 -228.774498)
		(end 104.540558 -228.77399)
		(width 0.1143)
		(layer "In2.Cu")
		(net "GMI_CPU0_G2_CPU1_G0_TX_DN<9>")
	)
	(segment
		(start 367.532666 -229.904036)
		(end 367.234724 -229.904036)
		(width 0.1143)
		(layer "In2.Cu")
		(net "GMI_CPU0_G2_CPU1_G0_TX_DN<9>")
	)
	(segment
		(start 236.61243 -180.907182)
		(end 306.23764 -183.326532)
		(width 0.14224)
		(layer "In2.Cu")
		(net "GMI_CPU0_G2_CPU1_G0_TX_DN<9>")
	)
	(segment
		(start 105.47985 -223.914462)
		(end 105.480612 -223.913954)
		(width 0.1143)
		(layer "In2.Cu")
		(net "GMI_CPU0_G2_CPU1_G0_TX_DN<9>")
	)
	(segment
		(start 110.859062 -211.111592)
		(end 111.15548 -210.81492)
		(width 0.14224)
		(layer "In2.Cu")
		(net "GMI_CPU0_G2_CPU1_G0_TX_DN<9>")
	)
	(segment
		(start 367.421668 -229.58171)
		(end 367.455196 -229.601268)
		(width 0.1143)
		(layer "In2.Cu")
		(net "GMI_CPU0_G2_CPU1_G0_TX_DN<9>")
	)
	(segment
		(start 366.012476 -222.936308)
		(end 366.011714 -222.936816)
		(width 0.1143)
		(layer "In2.Cu")
		(net "GMI_CPU0_G2_CPU1_G0_TX_DN<9>")
	)
	(segment
		(start 105.47985 -222.93453)
		(end 105.452418 -222.918782)
		(width 0.1143)
		(layer "In2.Cu")
		(net "GMI_CPU0_G2_CPU1_G0_TX_DN<9>")
	)
	(segment
		(start 108.806234 -213.164166)
		(end 108.806234 -212.97392)
		(width 0.14224)
		(layer "In2.Cu")
		(net "GMI_CPU0_G2_CPU1_G0_TX_DN<9>")
	)
	(segment
		(start 105.501694 -225.523552)
		(end 105.505758 -225.519234)
		(width 0.1143)
		(layer "In2.Cu")
		(net "GMI_CPU0_G2_CPU1_G0_TX_DN<9>")
	)
	(segment
		(start 105.484168 -222.93707)
		(end 105.483406 -222.936562)
		(width 0.1143)
		(layer "In2.Cu")
		(net "GMI_CPU0_G2_CPU1_G0_TX_DN<9>")
	)
	(segment
		(start 108.806234 -212.97392)
		(end 109.102398 -212.677756)
		(width 0.14224)
		(layer "In2.Cu")
		(net "GMI_CPU0_G2_CPU1_G0_TX_DN<9>")
	)
	(segment
		(start 109.88548 -211.894674)
		(end 110.07598 -211.894674)
		(width 0.14224)
		(layer "In2.Cu")
		(net "GMI_CPU0_G2_CPU1_G0_TX_DN<9>")
	)
	(segment
		(start 110.372398 -211.598002)
		(end 110.372398 -211.407756)
		(width 0.14224)
		(layer "In2.Cu")
		(net "GMI_CPU0_G2_CPU1_G0_TX_DN<9>")
	)
	(segment
		(start 107.24007 -214.73033)
		(end 107.24007 -214.540084)
		(width 0.14224)
		(layer "In2.Cu")
		(net "GMI_CPU0_G2_CPU1_G0_TX_DN<9>")
	)
	(segment
		(start 104.827832 -221.833948)
		(end 104.827832 -221.54896)
		(width 0.1143)
		(layer "In2.Cu")
		(net "GMI_CPU0_G2_CPU1_G0_TX_DN<9>")
	)
	(segment
		(start 105.014014 -227.961952)
		(end 105.05313 -227.939092)
		(width 0.1143)
		(layer "In2.Cu")
		(net "GMI_CPU0_G2_CPU1_G0_TX_DN<9>")
	)
	(segment
		(start 365.685578 -221.128844)
		(end 365.685578 -221.426024)
		(width 0.1143)
		(layer "In2.Cu")
		(net "GMI_CPU0_G2_CPU1_G0_TX_DN<9>")
	)
	(segment
		(start 366.951006 -228.772466)
		(end 366.952022 -228.772974)
		(width 0.1143)
		(layer "In2.Cu")
		(net "GMI_CPU0_G2_CPU1_G0_TX_DN<9>")
	)
	(segment
		(start 105.482136 -227.153216)
		(end 105.483406 -227.152454)
		(width 0.1143)
		(layer "In2.Cu")
		(net "GMI_CPU0_G2_CPU1_G0_TX_DN<9>")
	)
	(segment
		(start 366.011714 -222.936816)
		(end 365.975392 -222.957644)
		(width 0.1143)
		(layer "In2.Cu")
		(net "GMI_CPU0_G2_CPU1_G0_TX_DN<9>")
	)
	(segment
		(start 106.456988 -215.323166)
		(end 106.753152 -215.027002)
		(width 0.14224)
		(layer "In2.Cu")
		(net "GMI_CPU0_G2_CPU1_G0_TX_DN<9>")
	)
	(segment
		(start 366.009174 -222.290132)
		(end 366.010698 -222.291148)
		(width 0.1143)
		(layer "In2.Cu")
		(net "GMI_CPU0_G2_CPU1_G0_TX_DN<9>")
	)
	(segment
		(start 105.480612 -224.55505)
		(end 105.47985 -224.554542)
		(width 0.1143)
		(layer "In2.Cu")
		(net "GMI_CPU0_G2_CPU1_G0_TX_DN<9>")
	)
	(segment
		(start 365.639858 -221.083124)
		(end 365.685578 -221.128844)
		(width 0.1143)
		(layer "In2.Cu")
		(net "GMI_CPU0_G2_CPU1_G0_TX_DN<9>")
	)
	(segment
		(start 105.377234 -216.593166)
		(end 105.673906 -216.296494)
		(width 0.14224)
		(layer "In2.Cu")
		(net "GMI_CPU0_G2_CPU1_G0_TX_DN<9>")
	)
	(segment
		(start 110.668562 -211.111592)
		(end 110.859062 -211.111592)
		(width 0.14224)
		(layer "In2.Cu")
		(net "GMI_CPU0_G2_CPU1_G0_TX_DN<9>")
	)
	(segment
		(start 106.753152 -215.027002)
		(end 106.943652 -215.027002)
		(width 0.14224)
		(layer "In2.Cu")
		(net "GMI_CPU0_G2_CPU1_G0_TX_DN<9>")
	)
	(segment
		(start 105.483406 -223.91243)
		(end 105.485692 -223.910906)
		(width 0.1143)
		(layer "In2.Cu")
		(net "GMI_CPU0_G2_CPU1_G0_TX_DN<9>")
	)
	(segment
		(start 366.012476 -223.912176)
		(end 366.043464 -223.929956)
		(width 0.1143)
		(layer "In2.Cu")
		(net "GMI_CPU0_G2_CPU1_G0_TX_DN<9>")
	)
	(segment
		(start 104.512364 -228.790246)
		(end 104.53878 -228.775006)
		(width 0.1143)
		(layer "In2.Cu")
		(net "GMI_CPU0_G2_CPU1_G0_TX_DN<9>")
	)
	(segment
		(start 105.485692 -223.910906)
		(end 105.52303 -223.889316)
		(width 0.1143)
		(layer "In2.Cu")
		(net "GMI_CPU0_G2_CPU1_G0_TX_DN<9>")
	)
	(segment
		(start 108.023152 -213.947248)
		(end 108.023152 -213.757002)
		(width 0.14224)
		(layer "In2.Cu")
		(net "GMI_CPU0_G2_CPU1_G0_TX_DN<9>")
	)
	(segment
		(start 105.52303 -224.579688)
		(end 105.486962 -224.55886)
		(width 0.1143)
		(layer "In2.Cu")
		(net "GMI_CPU0_G2_CPU1_G0_TX_DN<9>")
	)
	(segment
		(start 105.483406 -227.152454)
		(end 105.484168 -227.151946)
		(width 0.1143)
		(layer "In2.Cu")
		(net "GMI_CPU0_G2_CPU1_G0_TX_DN<9>")
	)
	(segment
		(start 165.049454 -183.340502)
		(end 166.370508 -182.993538)
		(width 0.14224)
		(layer "In2.Cu")
		(net "GMI_CPU0_G2_CPU1_G0_TX_DN<9>")
	)
	(segment
		(start 105.673906 -216.296494)
		(end 105.673906 -216.106248)
		(width 0.14224)
		(layer "In2.Cu")
		(net "GMI_CPU0_G2_CPU1_G0_TX_DN<9>")
	)
	(segment
		(start 105.482136 -224.555812)
		(end 105.480612 -224.55505)
		(width 0.1143)
		(layer "In2.Cu")
		(net "GMI_CPU0_G2_CPU1_G0_TX_DN<9>")
	)
	(segment
		(start 366.009174 -223.910144)
		(end 366.010698 -223.91116)
		(width 0.1143)
		(layer "In2.Cu")
		(net "GMI_CPU0_G2_CPU1_G0_TX_DN<9>")
	)
	(segment
		(start 104.540558 -228.77399)
		(end 104.542082 -228.773228)
		(width 0.1143)
		(layer "In2.Cu")
		(net "GMI_CPU0_G2_CPU1_G0_TX_DN<9>")
	)
	(segment
		(start 366.013746 -224.555558)
		(end 366.012476 -224.55632)
		(width 0.1143)
		(layer "In2.Cu")
		(net "GMI_CPU0_G2_CPU1_G0_TX_DN<9>")
	)
	(segment
		(start 104.84485 -221.531942)
		(end 104.84485 -221.248732)
		(width 0.1143)
		(layer "In2.Cu")
		(net "GMI_CPU0_G2_CPU1_G0_TX_DN<9>")
	)
	(segment
		(start 366.012476 -225.532188)
		(end 366.043464 -225.549968)
		(width 0.1143)
		(layer "In2.Cu")
		(net "GMI_CPU0_G2_CPU1_G0_TX_DN<9>")
	)
	(segment
		(start 105.480612 -225.533966)
		(end 105.482136 -225.533204)
		(width 0.1143)
		(layer "In2.Cu")
		(net "GMI_CPU0_G2_CPU1_G0_TX_DN<9>")
	)
	(segment
		(start 105.55097 -222.979742)
		(end 105.52303 -222.959676)
		(width 0.1143)
		(layer "In2.Cu")
		(net "GMI_CPU0_G2_CPU1_G0_TX_DN<9>")
	)
	(segment
		(start 366.010698 -225.531172)
		(end 366.011714 -225.53168)
		(width 0.1143)
		(layer "In2.Cu")
		(net "GMI_CPU0_G2_CPU1_G0_TX_DN<9>")
	)
	(segment
		(start 104.543352 -228.772466)
		(end 104.544114 -228.771958)
		(width 0.1143)
		(layer "In2.Cu")
		(net "GMI_CPU0_G2_CPU1_G0_TX_DN<9>")
	)
	(segment
		(start 366.49406 -227.981256)
		(end 366.494568 -227.98151)
		(width 0.1143)
		(layer "In2.Cu")
		(net "GMI_CPU0_G2_CPU1_G0_TX_DN<9>")
	)
	(segment
		(start 106.943652 -215.027002)
		(end 107.24007 -214.73033)
		(width 0.14224)
		(layer "In2.Cu")
		(net "GMI_CPU0_G2_CPU1_G0_TX_DN<9>")
	)
	(segment
		(start 366.011714 -225.53168)
		(end 366.012476 -225.532188)
		(width 0.1143)
		(layer "In2.Cu")
		(net "GMI_CPU0_G2_CPU1_G0_TX_DN<9>")
	)
	(segment
		(start 366.009174 -225.530156)
		(end 366.010698 -225.531172)
		(width 0.1143)
		(layer "In2.Cu")
		(net "GMI_CPU0_G2_CPU1_G0_TX_DN<9>")
	)
	(segment
		(start 105.673906 -216.106248)
		(end 105.97007 -215.810084)
		(width 0.14224)
		(layer "In2.Cu")
		(net "GMI_CPU0_G2_CPU1_G0_TX_DN<9>")
	)
	(segment
		(start 103.963216 -229.90429)
		(end 103.893366 -229.83444)
		(width 0.1143)
		(layer "In2.Cu")
		(net "GMI_CPU0_G2_CPU1_G0_TX_DN<9>")
	)
	(segment
		(start 164.97935 -183.36768)
		(end 165.049454 -183.340502)
		(width 0.14224)
		(layer "In2.Cu")
		(net "GMI_CPU0_G2_CPU1_G0_TX_DN<9>")
	)
	(segment
		(start 105.186734 -216.593166)
		(end 105.377234 -216.593166)
		(width 0.14224)
		(layer "In2.Cu")
		(net "GMI_CPU0_G2_CPU1_G0_TX_DN<9>")
	)
	(segment
		(start 104.89057 -216.88933)
		(end 105.186734 -216.593166)
		(width 0.14224)
		(layer "In2.Cu")
		(net "GMI_CPU0_G2_CPU1_G0_TX_DN<9>")
	)
	(segment
		(start 105.480612 -222.935038)
		(end 105.47985 -222.93453)
		(width 0.1143)
		(layer "In2.Cu")
		(net "GMI_CPU0_G2_CPU1_G0_TX_DN<9>")
	)
	(segment
		(start 105.452418 -223.93021)
		(end 105.478834 -223.91497)
		(width 0.1143)
		(layer "In2.Cu")
		(net "GMI_CPU0_G2_CPU1_G0_TX_DN<9>")
	)
	(segment
		(start 360.202988 -213.321392)
		(end 364.695994 -217.238326)
		(width 0.14224)
		(layer "In2.Cu")
		(net "GMI_CPU0_G2_CPU1_G0_TX_DN<9>")
	)
	(segment
		(start 104.546654 -228.770434)
		(end 104.58323 -228.749098)
		(width 0.1143)
		(layer "In2.Cu")
		(net "GMI_CPU0_G2_CPU1_G0_TX_DN<9>")
	)
	(segment
		(start 111.15548 -210.624674)
		(end 111.743998 -210.036156)
		(width 0.14224)
		(layer "In2.Cu")
		(net "GMI_CPU0_G2_CPU1_G0_TX_DN<9>")
	)
	(segment
		(start 105.505758 -225.519234)
		(end 105.52303 -225.509328)
		(width 0.1143)
		(layer "In2.Cu")
		(net "GMI_CPU0_G2_CPU1_G0_TX_DN<9>")
	)
	(segment
		(start 108.509816 -213.460838)
		(end 108.806234 -213.164166)
		(width 0.14224)
		(layer "In2.Cu")
		(net "GMI_CPU0_G2_CPU1_G0_TX_DN<9>")
	)
	(segment
		(start 366.043464 -222.918528)
		(end 366.013746 -222.935546)
		(width 0.1143)
		(layer "In2.Cu")
		(net "GMI_CPU0_G2_CPU1_G0_TX_DN<9>")
	)
	(segment
		(start 366.008158 -222.289624)
		(end 366.009174 -222.290132)
		(width 0.1143)
		(layer "In2.Cu")
		(net "GMI_CPU0_G2_CPU1_G0_TX_DN<9>")
	)
	(segment
		(start 105.483406 -226.176586)
		(end 105.482136 -226.175824)
		(width 0.1143)
		(layer "In2.Cu")
		(net "GMI_CPU0_G2_CPU1_G0_TX_DN<9>")
	)
	(segment
		(start 108.023152 -213.757002)
		(end 108.319316 -213.460838)
		(width 0.14224)
		(layer "In2.Cu")
		(net "GMI_CPU0_G2_CPU1_G0_TX_DN<9>")
	)
	(segment
		(start 109.292898 -212.677756)
		(end 109.589316 -212.381084)
		(width 0.14224)
		(layer "In2.Cu")
		(net "GMI_CPU0_G2_CPU1_G0_TX_DN<9>")
	)
	(segment
		(start 104.89057 -221.203012)
		(end 104.89057 -221.174564)
		(width 0.1143)
		(layer "In2.Cu")
		(net "GMI_CPU0_G2_CPU1_G0_TX_DN<9>")
	)
	(segment
		(start 366.012476 -226.176332)
		(end 366.011714 -226.17684)
		(width 0.1143)
		(layer "In2.Cu")
		(net "GMI_CPU0_G2_CPU1_G0_TX_DN<9>")
	)
	(segment
		(start 105.52303 -222.959676)
		(end 105.486962 -222.938848)
		(width 0.1143)
		(layer "In2.Cu")
		(net "GMI_CPU0_G2_CPU1_G0_TX_DN<9>")
	)
	(segment
		(start 366.012476 -224.55632)
		(end 366.011714 -224.556828)
		(width 0.1143)
		(layer "In2.Cu")
		(net "GMI_CPU0_G2_CPU1_G0_TX_DN<9>")
	)
	(segment
		(start 110.07598 -211.894674)
		(end 110.372398 -211.598002)
		(width 0.14224)
		(layer "In2.Cu")
		(net "GMI_CPU0_G2_CPU1_G0_TX_DN<9>")
	)
	(segment
		(start 105.482136 -223.913192)
		(end 105.483406 -223.91243)
		(width 0.1143)
		(layer "In2.Cu")
		(net "GMI_CPU0_G2_CPU1_G0_TX_DN<9>")
	)
	(segment
		(start 306.23764 -183.326532)
		(end 308.09565 -183.809894)
		(width 0.14224)
		(layer "In2.Cu")
		(net "GMI_CPU0_G2_CPU1_G0_TX_DN<9>")
	)
	(segment
		(start 366.037368 -227.166678)
		(end 366.038384 -227.167186)
		(width 0.1143)
		(layer "In2.Cu")
		(net "GMI_CPU0_G2_CPU1_G0_TX_DN<9>")
	)
	(segment
		(start 365.72952 -221.469966)
		(end 365.72952 -221.80423)
		(width 0.1143)
		(layer "In2.Cu")
		(net "GMI_CPU0_G2_CPU1_G0_TX_DN<9>")
	)
	(segment
		(start 105.05313 -222.149924)
		(end 105.014014 -222.127064)
		(width 0.1143)
		(layer "In2.Cu")
		(net "GMI_CPU0_G2_CPU1_G0_TX_DN<9>")
	)
	(segment
		(start 308.09565 -183.809894)
		(end 309.574692 -184.373774)
		(width 0.14224)
		(layer "In2.Cu")
		(net "GMI_CPU0_G2_CPU1_G0_TX_DN<9>")
	)
	(segment
		(start 108.319316 -213.460838)
		(end 108.509816 -213.460838)
		(width 0.14224)
		(layer "In2.Cu")
		(net "GMI_CPU0_G2_CPU1_G0_TX_DN<9>")
	)
	(segment
		(start 105.484168 -226.177094)
		(end 105.483406 -226.176586)
		(width 0.1143)
		(layer "In2.Cu")
		(net "GMI_CPU0_G2_CPU1_G0_TX_DN<9>")
	)
	(segment
		(start 365.972598 -225.50882)
		(end 366.009174 -225.530156)
		(width 0.1143)
		(layer "In2.Cu")
		(net "GMI_CPU0_G2_CPU1_G0_TX_DN<9>")
	)
	(segment
		(start 366.011714 -227.151692)
		(end 366.012476 -227.1522)
		(width 0.1143)
		(layer "In2.Cu")
		(net "GMI_CPU0_G2_CPU1_G0_TX_DN<9>")
	)
	(segment
		(start 105.483406 -224.556574)
		(end 105.482136 -224.555812)
		(width 0.1143)
		(layer "In2.Cu")
		(net "GMI_CPU0_G2_CPU1_G0_TX_DN<9>")
	)
	(segment
		(start 365.975392 -222.957644)
		(end 365.972598 -222.959676)
		(width 0.1143)
		(layer "In2.Cu")
		(net "GMI_CPU0_G2_CPU1_G0_TX_DN<9>")
	)
	(segment
		(start 104.041448 -229.60076)
		(end 104.07396 -229.581964)
		(width 0.1143)
		(layer "In2.Cu")
		(net "GMI_CPU0_G2_CPU1_G0_TX_DN<9>")
	)
	(segment
		(start 105.486962 -224.55886)
		(end 105.484168 -224.557082)
		(width 0.1143)
		(layer "In2.Cu")
		(net "GMI_CPU0_G2_CPU1_G0_TX_DN<9>")
	)
	(segment
		(start 105.482136 -222.9358)
		(end 105.480612 -222.935038)
		(width 0.1143)
		(layer "In2.Cu")
		(net "GMI_CPU0_G2_CPU1_G0_TX_DN<9>")
	)
	(segment
		(start 366.66932 -228.283516)
		(end 366.66932 -228.284024)
		(width 0.1143)
		(layer "In2.Cu")
		(net "GMI_CPU0_G2_CPU1_G0_TX_DN<9>")
	)
	(segment
		(start 105.480612 -227.153978)
		(end 105.482136 -227.153216)
		(width 0.1143)
		(layer "In2.Cu")
		(net "GMI_CPU0_G2_CPU1_G0_TX_DN<9>")
	)
	(segment
		(start 155.443174 -187.070238)
		(end 164.97935 -183.36768)
		(width 0.14224)
		(layer "In2.Cu")
		(net "GMI_CPU0_G2_CPU1_G0_TX_DN<9>")
	)
	(segment
		(start 104.544114 -228.771958)
		(end 104.54513 -228.77145)
		(width 0.1143)
		(layer "In2.Cu")
		(net "GMI_CPU0_G2_CPU1_G0_TX_DN<9>")
	)
	(segment
		(start 104.07396 -229.581964)
		(end 104.113076 -229.559104)
		(width 0.1143)
		(layer "In2.Cu")
		(net "GMI_CPU0_G2_CPU1_G0_TX_DN<9>")
	)
	(segment
		(start 105.483914 -225.532442)
		(end 105.501694 -225.523552)
		(width 0.1143)
		(layer "In2.Cu")
		(net "GMI_CPU0_G2_CPU1_G0_TX_DN<9>")
	)
	(arc
		(start 366.212374 -227.494338)
		(mid 366.276725 -227.756244)
		(end 366.455198 -227.958396)
		(width 0.1143)
		(layer "In2.Cu")
		(net "GMI_CPU0_G2_CPU1_G0_TX_DN<9>")
	)
	(arc
		(start 105.452418 -226.158806)
		(mid 105.29649 -225.854514)
		(end 105.452418 -225.550222)
		(width 0.1143)
		(layer "In2.Cu")
		(net "GMI_CPU0_G2_CPU1_G0_TX_DN<9>")
	)
	(arc
		(start 367.139474 -229.094284)
		(mid 367.20471 -229.357875)
		(end 367.385346 -229.560628)
		(width 0.1143)
		(layer "In2.Cu")
		(net "GMI_CPU0_G2_CPU1_G0_TX_DN<9>")
	)
	(arc
		(start 365.972598 -226.1997)
		(mid 365.729271 -226.664266)
		(end 365.972598 -227.128832)
		(width 0.1143)
		(layer "In2.Cu")
		(net "GMI_CPU0_G2_CPU1_G0_TX_DN<9>")
	)
	(arc
		(start 105.296462 -222.61449)
		(mid 105.231947 -222.352271)
		(end 105.05313 -222.149924)
		(width 0.1143)
		(layer "In2.Cu")
		(net "GMI_CPU0_G2_CPU1_G0_TX_DN<9>")
	)
	(arc
		(start 366.043464 -225.549968)
		(mid 366.199392 -225.85426)
		(end 366.043464 -226.158552)
		(width 0.1143)
		(layer "In2.Cu")
		(net "GMI_CPU0_G2_CPU1_G0_TX_DN<9>")
	)
	(arc
		(start 104.113076 -229.559104)
		(mid 104.291889 -229.356754)
		(end 104.356408 -229.094538)
		(width 0.1143)
		(layer "In2.Cu")
		(net "GMI_CPU0_G2_CPU1_G0_TX_DN<9>")
	)
	(arc
		(start 365.972598 -224.579688)
		(mid 365.729271 -225.044254)
		(end 365.972598 -225.50882)
		(width 0.1143)
		(layer "In2.Cu")
		(net "GMI_CPU0_G2_CPU1_G0_TX_DN<9>")
	)
	(arc
		(start 367.455196 -229.601268)
		(mid 367.551084 -229.703676)
		(end 367.602516 -229.834186)
		(width 0.1143)
		(layer "In2.Cu")
		(net "GMI_CPU0_G2_CPU1_G0_TX_DN<9>")
	)
	(arc
		(start 104.58323 -228.749098)
		(mid 104.762043 -228.546748)
		(end 104.826562 -228.284532)
		(width 0.1143)
		(layer "In2.Cu")
		(net "GMI_CPU0_G2_CPU1_G0_TX_DN<9>")
	)
	(arc
		(start 105.534714 -227.120958)
		(mid 105.762097 -226.66452)
		(end 105.534714 -226.208082)
		(width 0.1143)
		(layer "In2.Cu")
		(net "GMI_CPU0_G2_CPU1_G0_TX_DN<9>")
	)
	(arc
		(start 365.72952 -221.80423)
		(mid 365.757436 -221.980206)
		(end 365.83874 -222.138748)
		(width 0.1143)
		(layer "In2.Cu")
		(net "GMI_CPU0_G2_CPU1_G0_TX_DN<9>")
	)
	(arc
		(start 105.52049 -227.130864)
		(mid 105.52764 -227.125966)
		(end 105.534714 -227.120958)
		(width 0.1143)
		(layer "In2.Cu")
		(net "GMI_CPU0_G2_CPU1_G0_TX_DN<9>")
	)
	(arc
		(start 366.66932 -228.284024)
		(mid 366.735668 -228.54927)
		(end 366.919256 -228.751892)
		(width 0.1143)
		(layer "In2.Cu")
		(net "GMI_CPU0_G2_CPU1_G0_TX_DN<9>")
	)
	(arc
		(start 366.983518 -228.789992)
		(mid 367.098194 -228.923326)
		(end 367.139474 -229.094284)
		(width 0.1143)
		(layer "In2.Cu")
		(net "GMI_CPU0_G2_CPU1_G0_TX_DN<9>")
	)
	(arc
		(start 105.55097 -225.489262)
		(mid 105.77897 -225.044508)
		(end 105.55097 -224.599754)
		(width 0.1143)
		(layer "In2.Cu")
		(net "GMI_CPU0_G2_CPU1_G0_TX_DN<9>")
	)
	(arc
		(start 105.55097 -223.86925)
		(mid 105.77897 -223.424496)
		(end 105.55097 -222.979742)
		(width 0.1143)
		(layer "In2.Cu")
		(net "GMI_CPU0_G2_CPU1_G0_TX_DN<9>")
	)
	(arc
		(start 105.296462 -227.474526)
		(mid 105.337717 -227.303555)
		(end 105.452418 -227.170234)
		(width 0.1143)
		(layer "In2.Cu")
		(net "GMI_CPU0_G2_CPU1_G0_TX_DN<9>")
	)
	(arc
		(start 366.042702 -227.169726)
		(mid 366.167006 -227.295935)
		(end 366.212374 -227.46716)
		(width 0.1143)
		(layer "In2.Cu")
		(net "GMI_CPU0_G2_CPU1_G0_TX_DN<9>")
	)
	(arc
		(start 104.356408 -229.094538)
		(mid 104.397663 -228.923567)
		(end 104.512364 -228.790246)
		(width 0.1143)
		(layer "In2.Cu")
		(net "GMI_CPU0_G2_CPU1_G0_TX_DN<9>")
	)
	(arc
		(start 366.043464 -222.309944)
		(mid 366.199392 -222.614236)
		(end 366.043464 -222.918528)
		(width 0.1143)
		(layer "In2.Cu")
		(net "GMI_CPU0_G2_CPU1_G0_TX_DN<9>")
	)
	(arc
		(start 366.494568 -227.98151)
		(mid 366.622037 -228.109318)
		(end 366.66932 -228.283516)
		(width 0.1143)
		(layer "In2.Cu")
		(net "GMI_CPU0_G2_CPU1_G0_TX_DN<9>")
	)
	(arc
		(start 103.893366 -229.83444)
		(mid 103.945074 -229.703457)
		(end 104.041448 -229.60076)
		(width 0.1143)
		(layer "In2.Cu")
		(net "GMI_CPU0_G2_CPU1_G0_TX_DN<9>")
	)
	(arc
		(start 104.983534 -222.109284)
		(mid 104.875117 -221.988886)
		(end 104.827832 -221.833948)
		(width 0.1143)
		(layer "In2.Cu")
		(net "GMI_CPU0_G2_CPU1_G0_TX_DN<9>")
	)
	(arc
		(start 365.83874 -222.138748)
		(mid 365.900259 -222.209342)
		(end 365.972598 -222.268796)
		(width 0.1143)
		(layer "In2.Cu")
		(net "GMI_CPU0_G2_CPU1_G0_TX_DN<9>")
	)
	(arc
		(start 105.452418 -224.538794)
		(mid 105.29649 -224.234502)
		(end 105.452418 -223.93021)
		(width 0.1143)
		(layer "In2.Cu")
		(net "GMI_CPU0_G2_CPU1_G0_TX_DN<9>")
	)
	(arc
		(start 105.05313 -227.939092)
		(mid 105.231943 -227.736742)
		(end 105.296462 -227.474526)
		(width 0.1143)
		(layer "In2.Cu")
		(net "GMI_CPU0_G2_CPU1_G0_TX_DN<9>")
	)
	(arc
		(start 366.043464 -223.929956)
		(mid 366.199392 -224.234248)
		(end 366.043464 -224.53854)
		(width 0.1143)
		(layer "In2.Cu")
		(net "GMI_CPU0_G2_CPU1_G0_TX_DN<9>")
	)
	(arc
		(start 105.534714 -226.208082)
		(mid 105.527641 -226.203073)
		(end 105.52049 -226.198176)
		(width 0.1143)
		(layer "In2.Cu")
		(net "GMI_CPU0_G2_CPU1_G0_TX_DN<9>")
	)
	(arc
		(start 104.826562 -228.284532)
		(mid 104.868111 -228.11311)
		(end 104.983534 -227.979732)
		(width 0.1143)
		(layer "In2.Cu")
		(net "GMI_CPU0_G2_CPU1_G0_TX_DN<9>")
	)
	(arc
		(start 105.452418 -222.918782)
		(mid 105.337742 -222.785448)
		(end 105.296462 -222.61449)
		(width 0.1143)
		(layer "In2.Cu")
		(net "GMI_CPU0_G2_CPU1_G0_TX_DN<9>")
	)
	(arc
		(start 365.972598 -222.959676)
		(mid 365.729271 -223.424242)
		(end 365.972598 -223.888808)
		(width 0.1143)
		(layer "In2.Cu")
		(net "GMI_CPU0_G2_CPU1_G0_TX_DN<9>")
	)
	(segment
		(start 366.767872 -226.930204)
		(end 367.234724 -226.664266)
		(width 0.12954)
		(layer "F.Cu")
		(net "GMI_CPU0_G2_CPU1_G0_TX_DN<8>")
	)
	(segment
		(start 104.72801 -226.930458)
		(end 104.261158 -226.66452)
		(width 0.12954)
		(layer "F.Cu")
		(net "GMI_CPU0_G2_CPU1_G0_TX_DN<8>")
	)
	(segment
		(start 367.529618 -218.89847)
		(end 366.140492 -215.84412)
		(width 0.14224)
		(layer "In2.Cu")
		(net "GMI_CPU0_G2_CPU1_G0_TX_DN<8>")
	)
	(segment
		(start 165.575996 -181.107842)
		(end 163.249356 -181.75986)
		(width 0.14224)
		(layer "In2.Cu")
		(net "GMI_CPU0_G2_CPU1_G0_TX_DN<8>")
	)
	(segment
		(start 106.133138 -212.766656)
		(end 105.83672 -213.063328)
		(width 0.14224)
		(layer "In2.Cu")
		(net "GMI_CPU0_G2_CPU1_G0_TX_DN<8>")
	)
	(segment
		(start 103.57231 -226.158806)
		(end 103.60406 -226.177094)
		(width 0.1143)
		(layer "In2.Cu")
		(net "GMI_CPU0_G2_CPU1_G0_TX_DN<8>")
	)
	(segment
		(start 367.609628 -221.460314)
		(end 367.575338 -221.426024)
		(width 0.1143)
		(layer "In2.Cu")
		(net "GMI_CPU0_G2_CPU1_G0_TX_DN<8>")
	)
	(segment
		(start 367.575338 -221.128844)
		(end 367.529618 -221.083124)
		(width 0.1143)
		(layer "In2.Cu")
		(net "GMI_CPU0_G2_CPU1_G0_TX_DN<8>")
	)
	(segment
		(start 367.852706 -224.579688)
		(end 367.891822 -224.556828)
		(width 0.1143)
		(layer "In2.Cu")
		(net "GMI_CPU0_G2_CPU1_G0_TX_DN<8>")
	)
	(segment
		(start 104.863138 -213.84641)
		(end 104.566974 -214.142574)
		(width 0.14224)
		(layer "In2.Cu")
		(net "GMI_CPU0_G2_CPU1_G0_TX_DN<8>")
	)
	(segment
		(start 103.00081 -221.174564)
		(end 103.00081 -221.203012)
		(width 0.1143)
		(layer "In2.Cu")
		(net "GMI_CPU0_G2_CPU1_G0_TX_DN<8>")
	)
	(segment
		(start 367.852706 -222.959676)
		(end 367.891822 -222.936816)
		(width 0.1143)
		(layer "In2.Cu")
		(net "GMI_CPU0_G2_CPU1_G0_TX_DN<8>")
	)
	(segment
		(start 367.891822 -226.17684)
		(end 367.922302 -226.15906)
		(width 0.1143)
		(layer "In2.Cu")
		(net "GMI_CPU0_G2_CPU1_G0_TX_DN<8>")
	)
	(segment
		(start 103.880412 -226.581716)
		(end 103.963216 -226.66452)
		(width 0.1143)
		(layer "In2.Cu")
		(net "GMI_CPU0_G2_CPU1_G0_TX_DN<8>")
	)
	(segment
		(start 104.270556 -214.629492)
		(end 104.080056 -214.629492)
		(width 0.14224)
		(layer "In2.Cu")
		(net "GMI_CPU0_G2_CPU1_G0_TX_DN<8>")
	)
	(segment
		(start 103.605076 -224.55759)
		(end 103.643176 -224.579942)
		(width 0.1143)
		(layer "In2.Cu")
		(net "GMI_CPU0_G2_CPU1_G0_TX_DN<8>")
	)
	(segment
		(start 367.575338 -221.426024)
		(end 367.575338 -221.128844)
		(width 0.1143)
		(layer "In2.Cu")
		(net "GMI_CPU0_G2_CPU1_G0_TX_DN<8>")
	)
	(segment
		(start 103.426768 -222.622872)
		(end 103.426768 -222.629984)
		(width 0.1143)
		(layer "In2.Cu")
		(net "GMI_CPU0_G2_CPU1_G0_TX_DN<8>")
	)
	(segment
		(start 103.60406 -225.531934)
		(end 103.57231 -225.550222)
		(width 0.1143)
		(layer "In2.Cu")
		(net "GMI_CPU0_G2_CPU1_G0_TX_DN<8>")
	)
	(segment
		(start 367.234724 -226.664266)
		(end 367.532666 -226.664266)
		(width 0.1143)
		(layer "In2.Cu")
		(net "GMI_CPU0_G2_CPU1_G0_TX_DN<8>")
	)
	(segment
		(start 367.529618 -221.083124)
		(end 367.529618 -218.89847)
		(width 0.14224)
		(layer "In2.Cu")
		(net "GMI_CPU0_G2_CPU1_G0_TX_DN<8>")
	)
	(segment
		(start 109.265466 -209.444082)
		(end 109.265466 -209.634328)
		(width 0.14224)
		(layer "In2.Cu")
		(net "GMI_CPU0_G2_CPU1_G0_TX_DN<8>")
	)
	(segment
		(start 367.922302 -222.309436)
		(end 367.852706 -222.268796)
		(width 0.1143)
		(layer "In2.Cu")
		(net "GMI_CPU0_G2_CPU1_G0_TX_DN<8>")
	)
	(segment
		(start 106.133138 -212.57641)
		(end 106.133138 -212.766656)
		(width 0.14224)
		(layer "In2.Cu")
		(net "GMI_CPU0_G2_CPU1_G0_TX_DN<8>")
	)
	(segment
		(start 103.783892 -214.925656)
		(end 103.783892 -215.115902)
		(width 0.14224)
		(layer "In2.Cu")
		(net "GMI_CPU0_G2_CPU1_G0_TX_DN<8>")
	)
	(segment
		(start 102.946454 -221.645734)
		(end 102.946454 -221.804484)
		(width 0.1143)
		(layer "In2.Cu")
		(net "GMI_CPU0_G2_CPU1_G0_TX_DN<8>")
	)
	(segment
		(start 163.249356 -181.75986)
		(end 153.49474 -185.799222)
		(width 0.14224)
		(layer "In2.Cu")
		(net "GMI_CPU0_G2_CPU1_G0_TX_DN<8>")
	)
	(segment
		(start 103.603298 -222.936816)
		(end 103.60406 -222.93707)
		(width 0.1143)
		(layer "In2.Cu")
		(net "GMI_CPU0_G2_CPU1_G0_TX_DN<8>")
	)
	(segment
		(start 103.57231 -224.538794)
		(end 103.603298 -224.556574)
		(width 0.1143)
		(layer "In2.Cu")
		(net "GMI_CPU0_G2_CPU1_G0_TX_DN<8>")
	)
	(segment
		(start 102.95509 -221.637098)
		(end 102.946454 -221.645734)
		(width 0.1143)
		(layer "In2.Cu")
		(net "GMI_CPU0_G2_CPU1_G0_TX_DN<8>")
	)
	(segment
		(start 106.429302 -212.280246)
		(end 106.133138 -212.57641)
		(width 0.14224)
		(layer "In2.Cu")
		(net "GMI_CPU0_G2_CPU1_G0_TX_DN<8>")
	)
	(segment
		(start 104.566974 -214.33282)
		(end 104.270556 -214.629492)
		(width 0.14224)
		(layer "In2.Cu")
		(net "GMI_CPU0_G2_CPU1_G0_TX_DN<8>")
	)
	(segment
		(start 106.619802 -212.280246)
		(end 106.429302 -212.280246)
		(width 0.14224)
		(layer "In2.Cu")
		(net "GMI_CPU0_G2_CPU1_G0_TX_DN<8>")
	)
	(segment
		(start 108.185966 -210.714082)
		(end 107.995466 -210.714082)
		(width 0.14224)
		(layer "In2.Cu")
		(net "GMI_CPU0_G2_CPU1_G0_TX_DN<8>")
	)
	(segment
		(start 105.350056 -213.359492)
		(end 105.350056 -213.549738)
		(width 0.14224)
		(layer "In2.Cu")
		(net "GMI_CPU0_G2_CPU1_G0_TX_DN<8>")
	)
	(segment
		(start 366.140492 -215.84412)
		(end 361.82808 -212.084412)
		(width 0.14224)
		(layer "In2.Cu")
		(net "GMI_CPU0_G2_CPU1_G0_TX_DN<8>")
	)
	(segment
		(start 103.296974 -215.412574)
		(end 103.00081 -215.708738)
		(width 0.14224)
		(layer "In2.Cu")
		(net "GMI_CPU0_G2_CPU1_G0_TX_DN<8>")
	)
	(segment
		(start 105.83672 -213.063328)
		(end 105.64622 -213.063328)
		(width 0.14224)
		(layer "In2.Cu")
		(net "GMI_CPU0_G2_CPU1_G0_TX_DN<8>")
	)
	(segment
		(start 105.64622 -213.063328)
		(end 105.350056 -213.359492)
		(width 0.14224)
		(layer "In2.Cu")
		(net "GMI_CPU0_G2_CPU1_G0_TX_DN<8>")
	)
	(segment
		(start 103.00081 -221.203012)
		(end 102.95509 -221.248732)
		(width 0.1143)
		(layer "In2.Cu")
		(net "GMI_CPU0_G2_CPU1_G0_TX_DN<8>")
	)
	(segment
		(start 103.487474 -215.412574)
		(end 103.296974 -215.412574)
		(width 0.14224)
		(layer "In2.Cu")
		(net "GMI_CPU0_G2_CPU1_G0_TX_DN<8>")
	)
	(segment
		(start 103.603298 -224.556574)
		(end 103.60406 -224.557082)
		(width 0.1143)
		(layer "In2.Cu")
		(net "GMI_CPU0_G2_CPU1_G0_TX_DN<8>")
	)
	(segment
		(start 367.891822 -223.911668)
		(end 367.852706 -223.888808)
		(width 0.1143)
		(layer "In2.Cu")
		(net "GMI_CPU0_G2_CPU1_G0_TX_DN<8>")
	)
	(segment
		(start 310.115966 -182.531512)
		(end 308.740302 -182.007256)
		(width 0.14224)
		(layer "In2.Cu")
		(net "GMI_CPU0_G2_CPU1_G0_TX_DN<8>")
	)
	(segment
		(start 103.60406 -223.911922)
		(end 103.57231 -223.93021)
		(width 0.1143)
		(layer "In2.Cu")
		(net "GMI_CPU0_G2_CPU1_G0_TX_DN<8>")
	)
	(segment
		(start 104.566974 -214.142574)
		(end 104.566974 -214.33282)
		(width 0.14224)
		(layer "In2.Cu")
		(net "GMI_CPU0_G2_CPU1_G0_TX_DN<8>")
	)
	(segment
		(start 107.212384 -211.497164)
		(end 106.91622 -211.793328)
		(width 0.14224)
		(layer "In2.Cu")
		(net "GMI_CPU0_G2_CPU1_G0_TX_DN<8>")
	)
	(segment
		(start 103.60406 -226.177094)
		(end 103.643176 -226.199954)
		(width 0.1143)
		(layer "In2.Cu")
		(net "GMI_CPU0_G2_CPU1_G0_TX_DN<8>")
	)
	(segment
		(start 306.22494 -181.354222)
		(end 231.662986 -178.842162)
		(width 0.14224)
		(layer "In2.Cu")
		(net "GMI_CPU0_G2_CPU1_G0_TX_DN<8>")
	)
	(segment
		(start 104.080056 -214.629492)
		(end 103.783892 -214.925656)
		(width 0.14224)
		(layer "In2.Cu")
		(net "GMI_CPU0_G2_CPU1_G0_TX_DN<8>")
	)
	(segment
		(start 109.265466 -209.634328)
		(end 108.969048 -209.931)
		(width 0.14224)
		(layer "In2.Cu")
		(net "GMI_CPU0_G2_CPU1_G0_TX_DN<8>")
	)
	(segment
		(start 367.852706 -226.1997)
		(end 367.891822 -226.17684)
		(width 0.1143)
		(layer "In2.Cu")
		(net "GMI_CPU0_G2_CPU1_G0_TX_DN<8>")
	)
	(segment
		(start 105.053638 -213.84641)
		(end 104.863138 -213.84641)
		(width 0.14224)
		(layer "In2.Cu")
		(net "GMI_CPU0_G2_CPU1_G0_TX_DN<8>")
	)
	(segment
		(start 103.102156 -222.108522)
		(end 103.144574 -222.13316)
		(width 0.1143)
		(layer "In2.Cu")
		(net "GMI_CPU0_G2_CPU1_G0_TX_DN<8>")
	)
	(segment
		(start 231.662986 -178.842162)
		(end 165.575996 -181.107842)
		(width 0.14224)
		(layer "In2.Cu")
		(net "GMI_CPU0_G2_CPU1_G0_TX_DN<8>")
	)
	(segment
		(start 361.82808 -212.084412)
		(end 356.880414 -208.731104)
		(width 0.14224)
		(layer "In2.Cu")
		(net "GMI_CPU0_G2_CPU1_G0_TX_DN<8>")
	)
	(segment
		(start 106.91622 -211.793328)
		(end 106.91622 -211.983574)
		(width 0.14224)
		(layer "In2.Cu")
		(net "GMI_CPU0_G2_CPU1_G0_TX_DN<8>")
	)
	(segment
		(start 103.605076 -222.937578)
		(end 103.643176 -222.95993)
		(width 0.1143)
		(layer "In2.Cu")
		(net "GMI_CPU0_G2_CPU1_G0_TX_DN<8>")
	)
	(segment
		(start 108.482384 -210.41741)
		(end 108.185966 -210.714082)
		(width 0.14224)
		(layer "In2.Cu")
		(net "GMI_CPU0_G2_CPU1_G0_TX_DN<8>")
	)
	(segment
		(start 367.609628 -221.80423)
		(end 367.609628 -221.460314)
		(width 0.1143)
		(layer "In2.Cu")
		(net "GMI_CPU0_G2_CPU1_G0_TX_DN<8>")
	)
	(segment
		(start 107.699302 -211.010246)
		(end 107.699302 -211.200492)
		(width 0.14224)
		(layer "In2.Cu")
		(net "GMI_CPU0_G2_CPU1_G0_TX_DN<8>")
	)
	(segment
		(start 105.350056 -213.549738)
		(end 105.053638 -213.84641)
		(width 0.14224)
		(layer "In2.Cu")
		(net "GMI_CPU0_G2_CPU1_G0_TX_DN<8>")
	)
	(segment
		(start 103.00081 -215.708738)
		(end 103.00081 -221.174564)
		(width 0.14224)
		(layer "In2.Cu")
		(net "GMI_CPU0_G2_CPU1_G0_TX_DN<8>")
	)
	(segment
		(start 103.783892 -215.115902)
		(end 103.487474 -215.412574)
		(width 0.14224)
		(layer "In2.Cu")
		(net "GMI_CPU0_G2_CPU1_G0_TX_DN<8>")
	)
	(segment
		(start 107.995466 -210.714082)
		(end 107.699302 -211.010246)
		(width 0.14224)
		(layer "In2.Cu")
		(net "GMI_CPU0_G2_CPU1_G0_TX_DN<8>")
	)
	(segment
		(start 108.482384 -210.227164)
		(end 108.482384 -210.41741)
		(width 0.14224)
		(layer "In2.Cu")
		(net "GMI_CPU0_G2_CPU1_G0_TX_DN<8>")
	)
	(segment
		(start 108.969048 -209.931)
		(end 108.778548 -209.931)
		(width 0.14224)
		(layer "In2.Cu")
		(net "GMI_CPU0_G2_CPU1_G0_TX_DN<8>")
	)
	(segment
		(start 367.891822 -222.936816)
		(end 367.922302 -222.919036)
		(width 0.1143)
		(layer "In2.Cu")
		(net "GMI_CPU0_G2_CPU1_G0_TX_DN<8>")
	)
	(segment
		(start 102.95509 -221.248732)
		(end 102.95509 -221.637098)
		(width 0.1143)
		(layer "In2.Cu")
		(net "GMI_CPU0_G2_CPU1_G0_TX_DN<8>")
	)
	(segment
		(start 367.891822 -225.53168)
		(end 367.852706 -225.50882)
		(width 0.1143)
		(layer "In2.Cu")
		(net "GMI_CPU0_G2_CPU1_G0_TX_DN<8>")
	)
	(segment
		(start 367.891822 -224.556828)
		(end 367.922302 -224.539048)
		(width 0.1143)
		(layer "In2.Cu")
		(net "GMI_CPU0_G2_CPU1_G0_TX_DN<8>")
	)
	(segment
		(start 110.31982 -208.389728)
		(end 109.265466 -209.444082)
		(width 0.14224)
		(layer "In2.Cu")
		(net "GMI_CPU0_G2_CPU1_G0_TX_DN<8>")
	)
	(segment
		(start 367.532666 -226.664266)
		(end 367.61547 -226.581462)
		(width 0.1143)
		(layer "In2.Cu")
		(net "GMI_CPU0_G2_CPU1_G0_TX_DN<8>")
	)
	(segment
		(start 103.643176 -223.889062)
		(end 103.60406 -223.911922)
		(width 0.1143)
		(layer "In2.Cu")
		(net "GMI_CPU0_G2_CPU1_G0_TX_DN<8>")
	)
	(segment
		(start 103.60406 -222.93707)
		(end 103.605076 -222.937578)
		(width 0.1143)
		(layer "In2.Cu")
		(net "GMI_CPU0_G2_CPU1_G0_TX_DN<8>")
	)
	(segment
		(start 153.49474 -185.799222)
		(end 110.31982 -208.389728)
		(width 0.14224)
		(layer "In2.Cu")
		(net "GMI_CPU0_G2_CPU1_G0_TX_DN<8>")
	)
	(segment
		(start 108.778548 -209.931)
		(end 108.482384 -210.227164)
		(width 0.14224)
		(layer "In2.Cu")
		(net "GMI_CPU0_G2_CPU1_G0_TX_DN<8>")
	)
	(segment
		(start 367.922302 -225.54946)
		(end 367.891822 -225.53168)
		(width 0.1143)
		(layer "In2.Cu")
		(net "GMI_CPU0_G2_CPU1_G0_TX_DN<8>")
	)
	(segment
		(start 107.699302 -211.200492)
		(end 107.402884 -211.497164)
		(width 0.14224)
		(layer "In2.Cu")
		(net "GMI_CPU0_G2_CPU1_G0_TX_DN<8>")
	)
	(segment
		(start 107.402884 -211.497164)
		(end 107.212384 -211.497164)
		(width 0.14224)
		(layer "In2.Cu")
		(net "GMI_CPU0_G2_CPU1_G0_TX_DN<8>")
	)
	(segment
		(start 103.60406 -224.557082)
		(end 103.605076 -224.55759)
		(width 0.1143)
		(layer "In2.Cu")
		(net "GMI_CPU0_G2_CPU1_G0_TX_DN<8>")
	)
	(segment
		(start 323.835014 -189.149736)
		(end 310.115966 -182.531512)
		(width 0.14224)
		(layer "In2.Cu")
		(net "GMI_CPU0_G2_CPU1_G0_TX_DN<8>")
	)
	(segment
		(start 367.922302 -223.929448)
		(end 367.891822 -223.911668)
		(width 0.1143)
		(layer "In2.Cu")
		(net "GMI_CPU0_G2_CPU1_G0_TX_DN<8>")
	)
	(segment
		(start 103.963216 -226.66452)
		(end 104.261158 -226.66452)
		(width 0.1143)
		(layer "In2.Cu")
		(net "GMI_CPU0_G2_CPU1_G0_TX_DN<8>")
	)
	(segment
		(start 356.880414 -208.731104)
		(end 323.835014 -189.149736)
		(width 0.14224)
		(layer "In2.Cu")
		(net "GMI_CPU0_G2_CPU1_G0_TX_DN<8>")
	)
	(segment
		(start 103.643176 -225.509074)
		(end 103.60406 -225.531934)
		(width 0.1143)
		(layer "In2.Cu")
		(net "GMI_CPU0_G2_CPU1_G0_TX_DN<8>")
	)
	(segment
		(start 106.91622 -211.983574)
		(end 106.619802 -212.280246)
		(width 0.14224)
		(layer "In2.Cu")
		(net "GMI_CPU0_G2_CPU1_G0_TX_DN<8>")
	)
	(segment
		(start 308.740302 -182.007256)
		(end 306.22494 -181.354222)
		(width 0.14224)
		(layer "In2.Cu")
		(net "GMI_CPU0_G2_CPU1_G0_TX_DN<8>")
	)
	(arc
		(start 103.643176 -226.199954)
		(mid 103.795163 -226.356462)
		(end 103.876602 -226.558856)
		(width 0.1143)
		(layer "In2.Cu")
		(net "GMI_CPU0_G2_CPU1_G0_TX_DN<8>")
	)
	(arc
		(start 103.876602 -226.558856)
		(mid 103.878625 -226.570266)
		(end 103.880412 -226.581716)
		(width 0.1143)
		(layer "In2.Cu")
		(net "GMI_CPU0_G2_CPU1_G0_TX_DN<8>")
	)
	(arc
		(start 367.852706 -223.888808)
		(mid 367.609379 -223.424242)
		(end 367.852706 -222.959676)
		(width 0.1143)
		(layer "In2.Cu")
		(net "GMI_CPU0_G2_CPU1_G0_TX_DN<8>")
	)
	(arc
		(start 102.946454 -221.804484)
		(mid 102.987647 -221.975273)
		(end 103.102156 -222.108522)
		(width 0.1143)
		(layer "In2.Cu")
		(net "GMI_CPU0_G2_CPU1_G0_TX_DN<8>")
	)
	(arc
		(start 367.852706 -225.50882)
		(mid 367.609379 -225.044254)
		(end 367.852706 -224.579688)
		(width 0.1143)
		(layer "In2.Cu")
		(net "GMI_CPU0_G2_CPU1_G0_TX_DN<8>")
	)
	(arc
		(start 103.426768 -222.629984)
		(mid 103.474057 -222.806968)
		(end 103.603298 -222.936816)
		(width 0.1143)
		(layer "In2.Cu")
		(net "GMI_CPU0_G2_CPU1_G0_TX_DN<8>")
	)
	(arc
		(start 103.144574 -222.13316)
		(mid 103.3512 -222.340249)
		(end 103.426768 -222.622872)
		(width 0.1143)
		(layer "In2.Cu")
		(net "GMI_CPU0_G2_CPU1_G0_TX_DN<8>")
	)
	(arc
		(start 103.643176 -222.95993)
		(mid 103.886503 -223.424496)
		(end 103.643176 -223.889062)
		(width 0.1143)
		(layer "In2.Cu")
		(net "GMI_CPU0_G2_CPU1_G0_TX_DN<8>")
	)
	(arc
		(start 367.922302 -224.539048)
		(mid 368.079279 -224.234248)
		(end 367.922302 -223.929448)
		(width 0.1143)
		(layer "In2.Cu")
		(net "GMI_CPU0_G2_CPU1_G0_TX_DN<8>")
	)
	(arc
		(start 367.922302 -226.15906)
		(mid 368.079279 -225.85426)
		(end 367.922302 -225.54946)
		(width 0.1143)
		(layer "In2.Cu")
		(net "GMI_CPU0_G2_CPU1_G0_TX_DN<8>")
	)
	(arc
		(start 367.922302 -222.919036)
		(mid 368.079279 -222.614236)
		(end 367.922302 -222.309436)
		(width 0.1143)
		(layer "In2.Cu")
		(net "GMI_CPU0_G2_CPU1_G0_TX_DN<8>")
	)
	(arc
		(start 103.57231 -223.93021)
		(mid 103.421925 -224.234502)
		(end 103.57231 -224.538794)
		(width 0.1143)
		(layer "In2.Cu")
		(net "GMI_CPU0_G2_CPU1_G0_TX_DN<8>")
	)
	(arc
		(start 367.852706 -222.268796)
		(mid 367.674063 -222.066401)
		(end 367.609628 -221.80423)
		(width 0.1143)
		(layer "In2.Cu")
		(net "GMI_CPU0_G2_CPU1_G0_TX_DN<8>")
	)
	(arc
		(start 367.61928 -226.558602)
		(mid 367.700713 -226.356204)
		(end 367.852706 -226.1997)
		(width 0.1143)
		(layer "In2.Cu")
		(net "GMI_CPU0_G2_CPU1_G0_TX_DN<8>")
	)
	(arc
		(start 367.61547 -226.581462)
		(mid 367.617258 -226.570013)
		(end 367.61928 -226.558602)
		(width 0.1143)
		(layer "In2.Cu")
		(net "GMI_CPU0_G2_CPU1_G0_TX_DN<8>")
	)
	(arc
		(start 103.643176 -224.579942)
		(mid 103.886503 -225.044508)
		(end 103.643176 -225.509074)
		(width 0.1143)
		(layer "In2.Cu")
		(net "GMI_CPU0_G2_CPU1_G0_TX_DN<8>")
	)
	(arc
		(start 103.57231 -225.550222)
		(mid 103.423213 -225.854514)
		(end 103.57231 -226.158806)
		(width 0.1143)
		(layer "In2.Cu")
		(net "GMI_CPU0_G2_CPU1_G0_TX_DN<8>")
	)
	(segment
		(start 366.767872 -228.550216)
		(end 367.234724 -228.284278)
		(width 0.12954)
		(layer "F.Cu")
		(net "GMI_CPU0_G2_CPU1_G0_TX_DN<7>")
	)
	(segment
		(start 104.72801 -228.55047)
		(end 104.261158 -228.284532)
		(width 0.12954)
		(layer "F.Cu")
		(net "GMI_CPU0_G2_CPU1_G0_TX_DN<7>")
	)
	(segment
		(start 361.282996 -212.89645)
		(end 356.602284 -209.724498)
		(width 0.14224)
		(layer "In2.Cu")
		(net "GMI_CPU0_G2_CPU1_G0_TX_DN<7>")
	)
	(segment
		(start 104.540558 -222.935038)
		(end 104.542082 -222.9358)
		(width 0.1143)
		(layer "In2.Cu")
		(net "GMI_CPU0_G2_CPU1_G0_TX_DN<7>")
	)
	(segment
		(start 107.078018 -213.350348)
		(end 106.7816 -213.64702)
		(width 0.14224)
		(layer "In2.Cu")
		(net "GMI_CPU0_G2_CPU1_G0_TX_DN<7>")
	)
	(segment
		(start 104.54513 -223.911414)
		(end 104.544114 -223.911922)
		(width 0.1143)
		(layer "In2.Cu")
		(net "GMI_CPU0_G2_CPU1_G0_TX_DN<7>")
	)
	(segment
		(start 367.152174 -227.49637)
		(end 367.152174 -227.483924)
		(width 0.1143)
		(layer "In2.Cu")
		(net "GMI_CPU0_G2_CPU1_G0_TX_DN<7>")
	)
	(segment
		(start 104.546654 -227.150422)
		(end 104.54513 -227.151438)
		(width 0.1143)
		(layer "In2.Cu")
		(net "GMI_CPU0_G2_CPU1_G0_TX_DN<7>")
	)
	(segment
		(start 366.584738 -221.083124)
		(end 366.584738 -219.137738)
		(width 0.14224)
		(layer "In2.Cu")
		(net "GMI_CPU0_G2_CPU1_G0_TX_DN<7>")
	)
	(segment
		(start 104.54513 -227.151438)
		(end 104.544114 -227.151946)
		(width 0.1143)
		(layer "In2.Cu")
		(net "GMI_CPU0_G2_CPU1_G0_TX_DN<7>")
	)
	(segment
		(start 366.669574 -221.46514)
		(end 366.630458 -221.426024)
		(width 0.1143)
		(layer "In2.Cu")
		(net "GMI_CPU0_G2_CPU1_G0_TX_DN<7>")
	)
	(segment
		(start 109.427264 -211.001102)
		(end 109.130846 -211.297774)
		(width 0.14224)
		(layer "In2.Cu")
		(net "GMI_CPU0_G2_CPU1_G0_TX_DN<7>")
	)
	(segment
		(start 104.542082 -226.175824)
		(end 104.543352 -226.176586)
		(width 0.1143)
		(layer "In2.Cu")
		(net "GMI_CPU0_G2_CPU1_G0_TX_DN<7>")
	)
	(segment
		(start 366.983518 -225.549968)
		(end 366.951768 -225.53168)
		(width 0.1143)
		(layer "In2.Cu")
		(net "GMI_CPU0_G2_CPU1_G0_TX_DN<7>")
	)
	(segment
		(start 104.544114 -225.531934)
		(end 104.512364 -225.550222)
		(width 0.1143)
		(layer "In2.Cu")
		(net "GMI_CPU0_G2_CPU1_G0_TX_DN<7>")
	)
	(segment
		(start 322.858638 -189.732158)
		(end 309.590948 -183.32958)
		(width 0.14224)
		(layer "In2.Cu")
		(net "GMI_CPU0_G2_CPU1_G0_TX_DN<7>")
	)
	(segment
		(start 104.543352 -223.91243)
		(end 104.542082 -223.913192)
		(width 0.1143)
		(layer "In2.Cu")
		(net "GMI_CPU0_G2_CPU1_G0_TX_DN<7>")
	)
	(segment
		(start 109.913928 -210.514692)
		(end 109.723428 -210.514692)
		(width 0.14224)
		(layer "In2.Cu")
		(net "GMI_CPU0_G2_CPU1_G0_TX_DN<7>")
	)
	(segment
		(start 236.61497 -179.96154)
		(end 166.27221 -182.050944)
		(width 0.14224)
		(layer "In2.Cu")
		(net "GMI_CPU0_G2_CPU1_G0_TX_DN<7>")
	)
	(segment
		(start 107.8611 -212.567266)
		(end 107.564682 -212.863938)
		(width 0.14224)
		(layer "In2.Cu")
		(net "GMI_CPU0_G2_CPU1_G0_TX_DN<7>")
	)
	(segment
		(start 104.54513 -226.177602)
		(end 104.546654 -226.178618)
		(width 0.1143)
		(layer "In2.Cu")
		(net "GMI_CPU0_G2_CPU1_G0_TX_DN<7>")
	)
	(segment
		(start 109.723428 -210.514692)
		(end 109.427264 -210.810856)
		(width 0.14224)
		(layer "In2.Cu")
		(net "GMI_CPU0_G2_CPU1_G0_TX_DN<7>")
	)
	(segment
		(start 366.630458 -221.128844)
		(end 366.584738 -221.083124)
		(width 0.1143)
		(layer "In2.Cu")
		(net "GMI_CPU0_G2_CPU1_G0_TX_DN<7>")
	)
	(segment
		(start 104.553766 -226.182682)
		(end 104.58323 -226.199954)
		(width 0.1143)
		(layer "In2.Cu")
		(net "GMI_CPU0_G2_CPU1_G0_TX_DN<7>")
	)
	(segment
		(start 103.893366 -228.214682)
		(end 103.963216 -228.284532)
		(width 0.1143)
		(layer "In2.Cu")
		(net "GMI_CPU0_G2_CPU1_G0_TX_DN<7>")
	)
	(segment
		(start 367.532666 -228.284278)
		(end 367.602516 -228.214428)
		(width 0.1143)
		(layer "In2.Cu")
		(net "GMI_CPU0_G2_CPU1_G0_TX_DN<7>")
	)
	(segment
		(start 104.546654 -222.938594)
		(end 104.552242 -222.941642)
		(width 0.1143)
		(layer "In2.Cu")
		(net "GMI_CPU0_G2_CPU1_G0_TX_DN<7>")
	)
	(segment
		(start 367.421668 -227.961698)
		(end 367.419382 -227.960428)
		(width 0.1143)
		(layer "In2.Cu")
		(net "GMI_CPU0_G2_CPU1_G0_TX_DN<7>")
	)
	(segment
		(start 104.54513 -225.531426)
		(end 104.544114 -225.531934)
		(width 0.1143)
		(layer "In2.Cu")
		(net "GMI_CPU0_G2_CPU1_G0_TX_DN<7>")
	)
	(segment
		(start 103.89997 -221.614492)
		(end 103.886508 -221.627954)
		(width 0.1143)
		(layer "In2.Cu")
		(net "GMI_CPU0_G2_CPU1_G0_TX_DN<7>")
	)
	(segment
		(start 104.544114 -227.151946)
		(end 104.512364 -227.170234)
		(width 0.1143)
		(layer "In2.Cu")
		(net "GMI_CPU0_G2_CPU1_G0_TX_DN<7>")
	)
	(segment
		(start 105.998518 -214.430102)
		(end 105.808018 -214.430102)
		(width 0.14224)
		(layer "In2.Cu")
		(net "GMI_CPU0_G2_CPU1_G0_TX_DN<7>")
	)
	(segment
		(start 104.041448 -222.108014)
		(end 104.111806 -222.148908)
		(width 0.1143)
		(layer "In2.Cu")
		(net "GMI_CPU0_G2_CPU1_G0_TX_DN<7>")
	)
	(segment
		(start 104.543352 -222.936562)
		(end 104.544114 -222.93707)
		(width 0.1143)
		(layer "In2.Cu")
		(net "GMI_CPU0_G2_CPU1_G0_TX_DN<7>")
	)
	(segment
		(start 104.58323 -225.509074)
		(end 104.546654 -225.53041)
		(width 0.1143)
		(layer "In2.Cu")
		(net "GMI_CPU0_G2_CPU1_G0_TX_DN<7>")
	)
	(segment
		(start 106.294936 -214.13343)
		(end 105.998518 -214.430102)
		(width 0.14224)
		(layer "In2.Cu")
		(net "GMI_CPU0_G2_CPU1_G0_TX_DN<7>")
	)
	(segment
		(start 103.963216 -228.284532)
		(end 104.261158 -228.284532)
		(width 0.1143)
		(layer "In2.Cu")
		(net "GMI_CPU0_G2_CPU1_G0_TX_DN<7>")
	)
	(segment
		(start 104.728772 -215.699594)
		(end 104.432354 -215.996266)
		(width 0.14224)
		(layer "In2.Cu")
		(net "GMI_CPU0_G2_CPU1_G0_TX_DN<7>")
	)
	(segment
		(start 104.58323 -227.129086)
		(end 104.546654 -227.150422)
		(width 0.1143)
		(layer "In2.Cu")
		(net "GMI_CPU0_G2_CPU1_G0_TX_DN<7>")
	)
	(segment
		(start 107.374182 -212.863938)
		(end 107.078018 -213.160102)
		(width 0.14224)
		(layer "In2.Cu")
		(net "GMI_CPU0_G2_CPU1_G0_TX_DN<7>")
	)
	(segment
		(start 104.241854 -215.996266)
		(end 103.94569 -216.29243)
		(width 0.14224)
		(layer "In2.Cu")
		(net "GMI_CPU0_G2_CPU1_G0_TX_DN<7>")
	)
	(segment
		(start 103.94569 -216.29243)
		(end 103.94569 -221.174564)
		(width 0.14224)
		(layer "In2.Cu")
		(net "GMI_CPU0_G2_CPU1_G0_TX_DN<7>")
	)
	(segment
		(start 366.983518 -224.53854)
		(end 367.00333 -224.524316)
		(width 0.1143)
		(layer "In2.Cu")
		(net "GMI_CPU0_G2_CPU1_G0_TX_DN<7>")
	)
	(segment
		(start 104.58323 -223.889062)
		(end 104.546654 -223.910398)
		(width 0.1143)
		(layer "In2.Cu")
		(net "GMI_CPU0_G2_CPU1_G0_TX_DN<7>")
	)
	(segment
		(start 110.210346 -210.21802)
		(end 109.913928 -210.514692)
		(width 0.14224)
		(layer "In2.Cu")
		(net "GMI_CPU0_G2_CPU1_G0_TX_DN<7>")
	)
	(segment
		(start 109.130846 -211.297774)
		(end 108.940346 -211.297774)
		(width 0.14224)
		(layer "In2.Cu")
		(net "GMI_CPU0_G2_CPU1_G0_TX_DN<7>")
	)
	(segment
		(start 104.512364 -226.158806)
		(end 104.540558 -226.175062)
		(width 0.1143)
		(layer "In2.Cu")
		(net "GMI_CPU0_G2_CPU1_G0_TX_DN<7>")
	)
	(segment
		(start 104.54513 -224.55759)
		(end 104.546654 -224.558606)
		(width 0.1143)
		(layer "In2.Cu")
		(net "GMI_CPU0_G2_CPU1_G0_TX_DN<7>")
	)
	(segment
		(start 105.808018 -214.430102)
		(end 105.511854 -214.726266)
		(width 0.14224)
		(layer "In2.Cu")
		(net "GMI_CPU0_G2_CPU1_G0_TX_DN<7>")
	)
	(segment
		(start 103.89997 -221.248732)
		(end 103.89997 -221.614492)
		(width 0.1143)
		(layer "In2.Cu")
		(net "GMI_CPU0_G2_CPU1_G0_TX_DN<7>")
	)
	(segment
		(start 367.00333 -223.94418)
		(end 366.983518 -223.929956)
		(width 0.1143)
		(layer "In2.Cu")
		(net "GMI_CPU0_G2_CPU1_G0_TX_DN<7>")
	)
	(segment
		(start 104.544114 -222.93707)
		(end 104.54513 -222.937578)
		(width 0.1143)
		(layer "In2.Cu")
		(net "GMI_CPU0_G2_CPU1_G0_TX_DN<7>")
	)
	(segment
		(start 104.544114 -223.911922)
		(end 104.543352 -223.91243)
		(width 0.1143)
		(layer "In2.Cu")
		(net "GMI_CPU0_G2_CPU1_G0_TX_DN<7>")
	)
	(segment
		(start 366.964468 -227.159058)
		(end 366.912652 -227.128832)
		(width 0.1143)
		(layer "In2.Cu")
		(net "GMI_CPU0_G2_CPU1_G0_TX_DN<7>")
	)
	(segment
		(start 366.951768 -225.53168)
		(end 366.912652 -225.50882)
		(width 0.1143)
		(layer "In2.Cu")
		(net "GMI_CPU0_G2_CPU1_G0_TX_DN<7>")
	)
	(segment
		(start 104.546654 -225.53041)
		(end 104.54513 -225.531426)
		(width 0.1143)
		(layer "In2.Cu")
		(net "GMI_CPU0_G2_CPU1_G0_TX_DN<7>")
	)
	(segment
		(start 105.511854 -214.916512)
		(end 105.215436 -215.213184)
		(width 0.14224)
		(layer "In2.Cu")
		(net "GMI_CPU0_G2_CPU1_G0_TX_DN<7>")
	)
	(segment
		(start 104.542082 -223.913192)
		(end 104.512364 -223.93021)
		(width 0.1143)
		(layer "In2.Cu")
		(net "GMI_CPU0_G2_CPU1_G0_TX_DN<7>")
	)
	(segment
		(start 308.806342 -183.030368)
		(end 306.321968 -182.384192)
		(width 0.14224)
		(layer "In2.Cu")
		(net "GMI_CPU0_G2_CPU1_G0_TX_DN<7>")
	)
	(segment
		(start 104.512364 -222.918782)
		(end 104.540558 -222.935038)
		(width 0.1143)
		(layer "In2.Cu")
		(net "GMI_CPU0_G2_CPU1_G0_TX_DN<7>")
	)
	(segment
		(start 366.584738 -219.137738)
		(end 365.364268 -216.454736)
		(width 0.14224)
		(layer "In2.Cu")
		(net "GMI_CPU0_G2_CPU1_G0_TX_DN<7>")
	)
	(segment
		(start 109.427264 -210.810856)
		(end 109.427264 -211.001102)
		(width 0.14224)
		(layer "In2.Cu")
		(net "GMI_CPU0_G2_CPU1_G0_TX_DN<7>")
	)
	(segment
		(start 366.951768 -226.17684)
		(end 366.983518 -226.158552)
		(width 0.1143)
		(layer "In2.Cu")
		(net "GMI_CPU0_G2_CPU1_G0_TX_DN<7>")
	)
	(segment
		(start 105.024936 -215.213184)
		(end 104.728772 -215.509348)
		(width 0.14224)
		(layer "In2.Cu")
		(net "GMI_CPU0_G2_CPU1_G0_TX_DN<7>")
	)
	(segment
		(start 104.540558 -224.55505)
		(end 104.542082 -224.555812)
		(width 0.1143)
		(layer "In2.Cu")
		(net "GMI_CPU0_G2_CPU1_G0_TX_DN<7>")
	)
	(segment
		(start 104.543352 -226.176586)
		(end 104.544114 -226.177094)
		(width 0.1143)
		(layer "In2.Cu")
		(net "GMI_CPU0_G2_CPU1_G0_TX_DN<7>")
	)
	(segment
		(start 166.27221 -182.050944)
		(end 164.811456 -182.432706)
		(width 0.14224)
		(layer "In2.Cu")
		(net "GMI_CPU0_G2_CPU1_G0_TX_DN<7>")
	)
	(segment
		(start 103.886508 -221.627954)
		(end 103.886508 -221.804484)
		(width 0.1143)
		(layer "In2.Cu")
		(net "GMI_CPU0_G2_CPU1_G0_TX_DN<7>")
	)
	(segment
		(start 108.644182 -211.593938)
		(end 108.644182 -211.784184)
		(width 0.14224)
		(layer "In2.Cu")
		(net "GMI_CPU0_G2_CPU1_G0_TX_DN<7>")
	)
	(segment
		(start 104.546654 -224.558606)
		(end 104.552242 -224.561654)
		(width 0.1143)
		(layer "In2.Cu")
		(net "GMI_CPU0_G2_CPU1_G0_TX_DN<7>")
	)
	(segment
		(start 306.321968 -182.384192)
		(end 236.61497 -179.96154)
		(width 0.14224)
		(layer "In2.Cu")
		(net "GMI_CPU0_G2_CPU1_G0_TX_DN<7>")
	)
	(segment
		(start 104.553766 -222.942658)
		(end 104.58323 -222.95993)
		(width 0.1143)
		(layer "In2.Cu")
		(net "GMI_CPU0_G2_CPU1_G0_TX_DN<7>")
	)
	(segment
		(start 110.210346 -210.027774)
		(end 110.210346 -210.21802)
		(width 0.14224)
		(layer "In2.Cu")
		(net "GMI_CPU0_G2_CPU1_G0_TX_DN<7>")
	)
	(segment
		(start 104.728772 -215.509348)
		(end 104.728772 -215.699594)
		(width 0.14224)
		(layer "In2.Cu")
		(net "GMI_CPU0_G2_CPU1_G0_TX_DN<7>")
	)
	(segment
		(start 104.542082 -224.555812)
		(end 104.543352 -224.556574)
		(width 0.1143)
		(layer "In2.Cu")
		(net "GMI_CPU0_G2_CPU1_G0_TX_DN<7>")
	)
	(segment
		(start 103.94569 -221.203012)
		(end 103.89997 -221.248732)
		(width 0.1143)
		(layer "In2.Cu")
		(net "GMI_CPU0_G2_CPU1_G0_TX_DN<7>")
	)
	(segment
		(start 104.540558 -226.175062)
		(end 104.542082 -226.175824)
		(width 0.1143)
		(layer "In2.Cu")
		(net "GMI_CPU0_G2_CPU1_G0_TX_DN<7>")
	)
	(segment
		(start 106.294936 -213.943184)
		(end 106.294936 -214.13343)
		(width 0.14224)
		(layer "In2.Cu")
		(net "GMI_CPU0_G2_CPU1_G0_TX_DN<7>")
	)
	(segment
		(start 104.544114 -226.177094)
		(end 104.54513 -226.177602)
		(width 0.1143)
		(layer "In2.Cu")
		(net "GMI_CPU0_G2_CPU1_G0_TX_DN<7>")
	)
	(segment
		(start 106.7816 -213.64702)
		(end 106.5911 -213.64702)
		(width 0.14224)
		(layer "In2.Cu")
		(net "GMI_CPU0_G2_CPU1_G0_TX_DN<7>")
	)
	(segment
		(start 366.983518 -222.309944)
		(end 366.912652 -222.268796)
		(width 0.1143)
		(layer "In2.Cu")
		(net "GMI_CPU0_G2_CPU1_G0_TX_DN<7>")
	)
	(segment
		(start 105.215436 -215.213184)
		(end 105.024936 -215.213184)
		(width 0.14224)
		(layer "In2.Cu")
		(net "GMI_CPU0_G2_CPU1_G0_TX_DN<7>")
	)
	(segment
		(start 365.364268 -216.454736)
		(end 361.282996 -212.89645)
		(width 0.14224)
		(layer "In2.Cu")
		(net "GMI_CPU0_G2_CPU1_G0_TX_DN<7>")
	)
	(segment
		(start 366.669574 -221.80423)
		(end 366.669574 -221.46514)
		(width 0.1143)
		(layer "In2.Cu")
		(net "GMI_CPU0_G2_CPU1_G0_TX_DN<7>")
	)
	(segment
		(start 104.113076 -227.939092)
		(end 104.07396 -227.961952)
		(width 0.1143)
		(layer "In2.Cu")
		(net "GMI_CPU0_G2_CPU1_G0_TX_DN<7>")
	)
	(segment
		(start 367.234724 -228.284278)
		(end 367.532666 -228.284278)
		(width 0.1143)
		(layer "In2.Cu")
		(net "GMI_CPU0_G2_CPU1_G0_TX_DN<7>")
	)
	(segment
		(start 366.983518 -223.929956)
		(end 366.912652 -223.888808)
		(width 0.1143)
		(layer "In2.Cu")
		(net "GMI_CPU0_G2_CPU1_G0_TX_DN<7>")
	)
	(segment
		(start 104.543352 -224.556574)
		(end 104.544114 -224.557082)
		(width 0.1143)
		(layer "In2.Cu")
		(net "GMI_CPU0_G2_CPU1_G0_TX_DN<7>")
	)
	(segment
		(start 367.42243 -227.962206)
		(end 367.421668 -227.961698)
		(width 0.1143)
		(layer "In2.Cu")
		(net "GMI_CPU0_G2_CPU1_G0_TX_DN<7>")
	)
	(segment
		(start 104.544114 -224.557082)
		(end 104.54513 -224.55759)
		(width 0.1143)
		(layer "In2.Cu")
		(net "GMI_CPU0_G2_CPU1_G0_TX_DN<7>")
	)
	(segment
		(start 108.940346 -211.297774)
		(end 108.644182 -211.593938)
		(width 0.14224)
		(layer "In2.Cu")
		(net "GMI_CPU0_G2_CPU1_G0_TX_DN<7>")
	)
	(segment
		(start 108.347764 -212.080856)
		(end 108.157264 -212.080856)
		(width 0.14224)
		(layer "In2.Cu")
		(net "GMI_CPU0_G2_CPU1_G0_TX_DN<7>")
	)
	(segment
		(start 366.951768 -222.936816)
		(end 366.983518 -222.918528)
		(width 0.1143)
		(layer "In2.Cu")
		(net "GMI_CPU0_G2_CPU1_G0_TX_DN<7>")
	)
	(segment
		(start 366.630458 -221.426024)
		(end 366.630458 -221.128844)
		(width 0.1143)
		(layer "In2.Cu")
		(net "GMI_CPU0_G2_CPU1_G0_TX_DN<7>")
	)
	(segment
		(start 111.243364 -208.994756)
		(end 110.210346 -210.027774)
		(width 0.14224)
		(layer "In2.Cu")
		(net "GMI_CPU0_G2_CPU1_G0_TX_DN<7>")
	)
	(segment
		(start 107.8611 -212.37702)
		(end 107.8611 -212.567266)
		(width 0.14224)
		(layer "In2.Cu")
		(net "GMI_CPU0_G2_CPU1_G0_TX_DN<7>")
	)
	(segment
		(start 104.552242 -224.561654)
		(end 104.553766 -224.56267)
		(width 0.1143)
		(layer "In2.Cu")
		(net "GMI_CPU0_G2_CPU1_G0_TX_DN<7>")
	)
	(segment
		(start 107.564682 -212.863938)
		(end 107.374182 -212.863938)
		(width 0.14224)
		(layer "In2.Cu")
		(net "GMI_CPU0_G2_CPU1_G0_TX_DN<7>")
	)
	(segment
		(start 104.546654 -226.178618)
		(end 104.552242 -226.181666)
		(width 0.1143)
		(layer "In2.Cu")
		(net "GMI_CPU0_G2_CPU1_G0_TX_DN<7>")
	)
	(segment
		(start 106.5911 -213.64702)
		(end 106.294936 -213.943184)
		(width 0.14224)
		(layer "In2.Cu")
		(net "GMI_CPU0_G2_CPU1_G0_TX_DN<7>")
	)
	(segment
		(start 164.811456 -182.432706)
		(end 154.341068 -186.476386)
		(width 0.14224)
		(layer "In2.Cu")
		(net "GMI_CPU0_G2_CPU1_G0_TX_DN<7>")
	)
	(segment
		(start 104.552242 -222.941642)
		(end 104.553766 -222.942658)
		(width 0.1143)
		(layer "In2.Cu")
		(net "GMI_CPU0_G2_CPU1_G0_TX_DN<7>")
	)
	(segment
		(start 104.54513 -222.937578)
		(end 104.546654 -222.938594)
		(width 0.1143)
		(layer "In2.Cu")
		(net "GMI_CPU0_G2_CPU1_G0_TX_DN<7>")
	)
	(segment
		(start 366.912652 -224.579688)
		(end 366.951768 -224.556828)
		(width 0.1143)
		(layer "In2.Cu")
		(net "GMI_CPU0_G2_CPU1_G0_TX_DN<7>")
	)
	(segment
		(start 309.590948 -183.32958)
		(end 308.806342 -183.030368)
		(width 0.14224)
		(layer "In2.Cu")
		(net "GMI_CPU0_G2_CPU1_G0_TX_DN<7>")
	)
	(segment
		(start 366.951768 -224.556828)
		(end 366.983518 -224.53854)
		(width 0.1143)
		(layer "In2.Cu")
		(net "GMI_CPU0_G2_CPU1_G0_TX_DN<7>")
	)
	(segment
		(start 105.511854 -214.726266)
		(end 105.511854 -214.916512)
		(width 0.14224)
		(layer "In2.Cu")
		(net "GMI_CPU0_G2_CPU1_G0_TX_DN<7>")
	)
	(segment
		(start 104.546654 -223.910398)
		(end 104.54513 -223.911414)
		(width 0.1143)
		(layer "In2.Cu")
		(net "GMI_CPU0_G2_CPU1_G0_TX_DN<7>")
	)
	(segment
		(start 104.552242 -226.181666)
		(end 104.553766 -226.182682)
		(width 0.1143)
		(layer "In2.Cu")
		(net "GMI_CPU0_G2_CPU1_G0_TX_DN<7>")
	)
	(segment
		(start 104.553766 -224.56267)
		(end 104.58323 -224.579942)
		(width 0.1143)
		(layer "In2.Cu")
		(net "GMI_CPU0_G2_CPU1_G0_TX_DN<7>")
	)
	(segment
		(start 154.341068 -186.476386)
		(end 111.243364 -208.994756)
		(width 0.14224)
		(layer "In2.Cu")
		(net "GMI_CPU0_G2_CPU1_G0_TX_DN<7>")
	)
	(segment
		(start 366.912652 -226.1997)
		(end 366.951768 -226.17684)
		(width 0.1143)
		(layer "In2.Cu")
		(net "GMI_CPU0_G2_CPU1_G0_TX_DN<7>")
	)
	(segment
		(start 108.644182 -211.784184)
		(end 108.347764 -212.080856)
		(width 0.14224)
		(layer "In2.Cu")
		(net "GMI_CPU0_G2_CPU1_G0_TX_DN<7>")
	)
	(segment
		(start 104.542082 -222.9358)
		(end 104.543352 -222.936562)
		(width 0.1143)
		(layer "In2.Cu")
		(net "GMI_CPU0_G2_CPU1_G0_TX_DN<7>")
	)
	(segment
		(start 356.602284 -209.724498)
		(end 322.858638 -189.732158)
		(width 0.14224)
		(layer "In2.Cu")
		(net "GMI_CPU0_G2_CPU1_G0_TX_DN<7>")
	)
	(segment
		(start 104.512364 -224.538794)
		(end 104.540558 -224.55505)
		(width 0.1143)
		(layer "In2.Cu")
		(net "GMI_CPU0_G2_CPU1_G0_TX_DN<7>")
	)
	(segment
		(start 103.94569 -221.174564)
		(end 103.94569 -221.203012)
		(width 0.1143)
		(layer "In2.Cu")
		(net "GMI_CPU0_G2_CPU1_G0_TX_DN<7>")
	)
	(segment
		(start 366.912652 -222.959676)
		(end 366.951768 -222.936816)
		(width 0.1143)
		(layer "In2.Cu")
		(net "GMI_CPU0_G2_CPU1_G0_TX_DN<7>")
	)
	(segment
		(start 104.07396 -227.961952)
		(end 104.04348 -227.979732)
		(width 0.1143)
		(layer "In2.Cu")
		(net "GMI_CPU0_G2_CPU1_G0_TX_DN<7>")
	)
	(segment
		(start 367.453418 -227.979986)
		(end 367.42243 -227.962206)
		(width 0.1143)
		(layer "In2.Cu")
		(net "GMI_CPU0_G2_CPU1_G0_TX_DN<7>")
	)
	(segment
		(start 108.157264 -212.080856)
		(end 107.8611 -212.37702)
		(width 0.14224)
		(layer "In2.Cu")
		(net "GMI_CPU0_G2_CPU1_G0_TX_DN<7>")
	)
	(segment
		(start 104.432354 -215.996266)
		(end 104.241854 -215.996266)
		(width 0.14224)
		(layer "In2.Cu")
		(net "GMI_CPU0_G2_CPU1_G0_TX_DN<7>")
	)
	(segment
		(start 107.078018 -213.160102)
		(end 107.078018 -213.350348)
		(width 0.14224)
		(layer "In2.Cu")
		(net "GMI_CPU0_G2_CPU1_G0_TX_DN<7>")
	)
	(arc
		(start 366.912652 -227.128832)
		(mid 366.669325 -226.664266)
		(end 366.912652 -226.1997)
		(width 0.1143)
		(layer "In2.Cu")
		(net "GMI_CPU0_G2_CPU1_G0_TX_DN<7>")
	)
	(arc
		(start 104.512364 -227.170234)
		(mid 104.397688 -227.303568)
		(end 104.356408 -227.474526)
		(width 0.1143)
		(layer "In2.Cu")
		(net "GMI_CPU0_G2_CPU1_G0_TX_DN<7>")
	)
	(arc
		(start 104.58323 -226.199954)
		(mid 104.826557 -226.66452)
		(end 104.58323 -227.129086)
		(width 0.1143)
		(layer "In2.Cu")
		(net "GMI_CPU0_G2_CPU1_G0_TX_DN<7>")
	)
	(arc
		(start 367.419382 -227.960428)
		(mid 367.223708 -227.76413)
		(end 367.152174 -227.49637)
		(width 0.1143)
		(layer "In2.Cu")
		(net "GMI_CPU0_G2_CPU1_G0_TX_DN<7>")
	)
	(arc
		(start 104.58323 -224.579942)
		(mid 104.826557 -225.044508)
		(end 104.58323 -225.509074)
		(width 0.1143)
		(layer "In2.Cu")
		(net "GMI_CPU0_G2_CPU1_G0_TX_DN<7>")
	)
	(arc
		(start 367.152174 -227.483924)
		(mid 367.101868 -227.296336)
		(end 366.964468 -227.159058)
		(width 0.1143)
		(layer "In2.Cu")
		(net "GMI_CPU0_G2_CPU1_G0_TX_DN<7>")
	)
	(arc
		(start 367.602516 -228.214428)
		(mid 367.550467 -228.082909)
		(end 367.453418 -227.979986)
		(width 0.1143)
		(layer "In2.Cu")
		(net "GMI_CPU0_G2_CPU1_G0_TX_DN<7>")
	)
	(arc
		(start 366.912652 -223.888808)
		(mid 366.669325 -223.424242)
		(end 366.912652 -222.959676)
		(width 0.1143)
		(layer "In2.Cu")
		(net "GMI_CPU0_G2_CPU1_G0_TX_DN<7>")
	)
	(arc
		(start 366.983518 -226.158552)
		(mid 367.135107 -225.85426)
		(end 366.983518 -225.549968)
		(width 0.1143)
		(layer "In2.Cu")
		(net "GMI_CPU0_G2_CPU1_G0_TX_DN<7>")
	)
	(arc
		(start 103.886508 -221.804484)
		(mid 103.927474 -221.97489)
		(end 104.041448 -222.108014)
		(width 0.1143)
		(layer "In2.Cu")
		(net "GMI_CPU0_G2_CPU1_G0_TX_DN<7>")
	)
	(arc
		(start 104.111806 -222.148908)
		(mid 104.291535 -222.351528)
		(end 104.356408 -222.61449)
		(width 0.1143)
		(layer "In2.Cu")
		(net "GMI_CPU0_G2_CPU1_G0_TX_DN<7>")
	)
	(arc
		(start 104.512364 -223.93021)
		(mid 104.356436 -224.234502)
		(end 104.512364 -224.538794)
		(width 0.1143)
		(layer "In2.Cu")
		(net "GMI_CPU0_G2_CPU1_G0_TX_DN<7>")
	)
	(arc
		(start 104.04348 -227.979732)
		(mid 103.945715 -228.082708)
		(end 103.893366 -228.214682)
		(width 0.1143)
		(layer "In2.Cu")
		(net "GMI_CPU0_G2_CPU1_G0_TX_DN<7>")
	)
	(arc
		(start 104.512364 -225.550222)
		(mid 104.356436 -225.854514)
		(end 104.512364 -226.158806)
		(width 0.1143)
		(layer "In2.Cu")
		(net "GMI_CPU0_G2_CPU1_G0_TX_DN<7>")
	)
	(arc
		(start 104.356408 -222.61449)
		(mid 104.397663 -222.785461)
		(end 104.512364 -222.918782)
		(width 0.1143)
		(layer "In2.Cu")
		(net "GMI_CPU0_G2_CPU1_G0_TX_DN<7>")
	)
	(arc
		(start 366.983518 -222.918528)
		(mid 367.135107 -222.614236)
		(end 366.983518 -222.309944)
		(width 0.1143)
		(layer "In2.Cu")
		(net "GMI_CPU0_G2_CPU1_G0_TX_DN<7>")
	)
	(arc
		(start 366.912652 -222.268796)
		(mid 366.733994 -222.066396)
		(end 366.669574 -221.80423)
		(width 0.1143)
		(layer "In2.Cu")
		(net "GMI_CPU0_G2_CPU1_G0_TX_DN<7>")
	)
	(arc
		(start 104.58323 -222.95993)
		(mid 104.826557 -223.424496)
		(end 104.58323 -223.889062)
		(width 0.1143)
		(layer "In2.Cu")
		(net "GMI_CPU0_G2_CPU1_G0_TX_DN<7>")
	)
	(arc
		(start 104.356408 -227.474526)
		(mid 104.291893 -227.736745)
		(end 104.113076 -227.939092)
		(width 0.1143)
		(layer "In2.Cu")
		(net "GMI_CPU0_G2_CPU1_G0_TX_DN<7>")
	)
	(arc
		(start 366.912652 -225.50882)
		(mid 366.669325 -225.044254)
		(end 366.912652 -224.579688)
		(width 0.1143)
		(layer "In2.Cu")
		(net "GMI_CPU0_G2_CPU1_G0_TX_DN<7>")
	)
	(arc
		(start 367.00333 -224.524316)
		(mid 367.152044 -224.234248)
		(end 367.00333 -223.94418)
		(width 0.1143)
		(layer "In2.Cu")
		(net "GMI_CPU0_G2_CPU1_G0_TX_DN<7>")
	)
	(segment
		(start 369.588034 -230.169974)
		(end 370.054886 -229.904036)
		(width 0.12954)
		(layer "F.Cu")
		(net "GMI_CPU0_G2_CPU1_G0_TX_DN<6>")
	)
	(segment
		(start 101.907848 -230.170228)
		(end 101.440996 -229.90429)
		(width 0.12954)
		(layer "F.Cu")
		(net "GMI_CPU0_G2_CPU1_G0_TX_DN<6>")
	)
	(segment
		(start 102.643178 -225.543364)
		(end 102.643178 -225.54311)
		(width 0.1143)
		(layer "In2.Cu")
		(net "GMI_CPU0_G2_CPU1_G0_TX_DN<6>")
	)
	(segment
		(start 102.633272 -225.549714)
		(end 102.632256 -225.550222)
		(width 0.1143)
		(layer "In2.Cu")
		(net "GMI_CPU0_G2_CPU1_G0_TX_DN<6>")
	)
	(segment
		(start 103.622094 -213.558374)
		(end 103.622094 -213.74862)
		(width 0.14224)
		(layer "In2.Cu")
		(net "GMI_CPU0_G2_CPU1_G0_TX_DN<6>")
	)
	(segment
		(start 101.72319 -228.772466)
		(end 101.72192 -228.773228)
		(width 0.1143)
		(layer "In2.Cu")
		(net "GMI_CPU0_G2_CPU1_G0_TX_DN<6>")
	)
	(segment
		(start 102.657656 -227.155502)
		(end 102.632256 -227.170234)
		(width 0.1143)
		(layer "In2.Cu")
		(net "GMI_CPU0_G2_CPU1_G0_TX_DN<6>")
	)
	(segment
		(start 104.108758 -213.26221)
		(end 103.918258 -213.26221)
		(width 0.14224)
		(layer "In2.Cu")
		(net "GMI_CPU0_G2_CPU1_G0_TX_DN<6>")
	)
	(segment
		(start 102.006654 -221.624906)
		(end 102.0064 -221.62516)
		(width 0.1143)
		(layer "In2.Cu")
		(net "GMI_CPU0_G2_CPU1_G0_TX_DN<6>")
	)
	(segment
		(start 102.839012 -214.341456)
		(end 102.839012 -214.531702)
		(width 0.14224)
		(layer "In2.Cu")
		(net "GMI_CPU0_G2_CPU1_G0_TX_DN<6>")
	)
	(segment
		(start 102.730046 -225.48977)
		(end 102.706678 -225.50628)
		(width 0.1143)
		(layer "In2.Cu")
		(net "GMI_CPU0_G2_CPU1_G0_TX_DN<6>")
	)
	(segment
		(start 102.659688 -223.914462)
		(end 102.657656 -223.915478)
		(width 0.1143)
		(layer "In2.Cu")
		(net "GMI_CPU0_G2_CPU1_G0_TX_DN<6>")
	)
	(segment
		(start 105.484422 -211.696046)
		(end 105.188258 -211.99221)
		(width 0.14224)
		(layer "In2.Cu")
		(net "GMI_CPU0_G2_CPU1_G0_TX_DN<6>")
	)
	(segment
		(start 368.549682 -221.80423)
		(end 368.549682 -221.473776)
		(width 0.1143)
		(layer "In2.Cu")
		(net "GMI_CPU0_G2_CPU1_G0_TX_DN<6>")
	)
	(segment
		(start 106.754422 -210.426046)
		(end 106.754422 -210.616292)
		(width 0.14224)
		(layer "In2.Cu")
		(net "GMI_CPU0_G2_CPU1_G0_TX_DN<6>")
	)
	(segment
		(start 368.474498 -221.083124)
		(end 368.474498 -218.700096)
		(width 0.14224)
		(layer "In2.Cu")
		(net "GMI_CPU0_G2_CPU1_G0_TX_DN<6>")
	)
	(segment
		(start 153.062178 -184.952386)
		(end 109.555026 -207.625442)
		(width 0.14224)
		(layer "In2.Cu")
		(net "GMI_CPU0_G2_CPU1_G0_TX_DN<6>")
	)
	(segment
		(start 370.24183 -229.58171)
		(end 370.205508 -229.560628)
		(width 0.1143)
		(layer "In2.Cu")
		(net "GMI_CPU0_G2_CPU1_G0_TX_DN<6>")
	)
	(segment
		(start 368.831876 -222.936816)
		(end 368.862356 -222.919036)
		(width 0.1143)
		(layer "In2.Cu")
		(net "GMI_CPU0_G2_CPU1_G0_TX_DN<6>")
	)
	(segment
		(start 106.754422 -210.616292)
		(end 106.458004 -210.912964)
		(width 0.14224)
		(layer "In2.Cu")
		(net "GMI_CPU0_G2_CPU1_G0_TX_DN<6>")
	)
	(segment
		(start 101.719634 -228.774498)
		(end 101.717602 -228.775514)
		(width 0.1143)
		(layer "In2.Cu")
		(net "GMI_CPU0_G2_CPU1_G0_TX_DN<6>")
	)
	(segment
		(start 368.549682 -221.473776)
		(end 368.520218 -221.444312)
		(width 0.1143)
		(layer "In2.Cu")
		(net "GMI_CPU0_G2_CPU1_G0_TX_DN<6>")
	)
	(segment
		(start 101.72192 -228.773228)
		(end 101.720396 -228.77399)
		(width 0.1143)
		(layer "In2.Cu")
		(net "GMI_CPU0_G2_CPU1_G0_TX_DN<6>")
	)
	(segment
		(start 102.663244 -227.152454)
		(end 102.661974 -227.153216)
		(width 0.1143)
		(layer "In2.Cu")
		(net "GMI_CPU0_G2_CPU1_G0_TX_DN<6>")
	)
	(segment
		(start 102.839012 -214.531702)
		(end 102.542594 -214.828374)
		(width 0.14224)
		(layer "In2.Cu")
		(net "GMI_CPU0_G2_CPU1_G0_TX_DN<6>")
	)
	(segment
		(start 105.188258 -211.99221)
		(end 105.188258 -212.182456)
		(width 0.14224)
		(layer "In2.Cu")
		(net "GMI_CPU0_G2_CPU1_G0_TX_DN<6>")
	)
	(segment
		(start 102.6668 -224.55886)
		(end 102.702868 -224.579688)
		(width 0.1143)
		(layer "In2.Cu")
		(net "GMI_CPU0_G2_CPU1_G0_TX_DN<6>")
	)
	(segment
		(start 101.292914 -229.559104)
		(end 101.253798 -229.581964)
		(width 0.1143)
		(layer "In2.Cu")
		(net "GMI_CPU0_G2_CPU1_G0_TX_DN<6>")
	)
	(segment
		(start 102.660958 -222.935292)
		(end 102.661974 -222.9358)
		(width 0.1143)
		(layer "In2.Cu")
		(net "GMI_CPU0_G2_CPU1_G0_TX_DN<6>")
	)
	(segment
		(start 105.674922 -211.696046)
		(end 105.484422 -211.696046)
		(width 0.14224)
		(layer "In2.Cu")
		(net "GMI_CPU0_G2_CPU1_G0_TX_DN<6>")
	)
	(segment
		(start 368.862356 -223.929448)
		(end 368.831876 -223.911668)
		(width 0.1143)
		(layer "In2.Cu")
		(net "GMI_CPU0_G2_CPU1_G0_TX_DN<6>")
	)
	(segment
		(start 102.663244 -223.91243)
		(end 102.661974 -223.913192)
		(width 0.1143)
		(layer "In2.Cu")
		(net "GMI_CPU0_G2_CPU1_G0_TX_DN<6>")
	)
	(segment
		(start 104.405176 -212.775292)
		(end 104.405176 -212.965538)
		(width 0.14224)
		(layer "In2.Cu")
		(net "GMI_CPU0_G2_CPU1_G0_TX_DN<6>")
	)
	(segment
		(start 102.702868 -222.959676)
		(end 102.730808 -222.979742)
		(width 0.1143)
		(layer "In2.Cu")
		(net "GMI_CPU0_G2_CPU1_G0_TX_DN<6>")
	)
	(segment
		(start 106.267504 -210.912964)
		(end 105.97134 -211.209128)
		(width 0.14224)
		(layer "In2.Cu")
		(net "GMI_CPU0_G2_CPU1_G0_TX_DN<6>")
	)
	(segment
		(start 368.862356 -225.54946)
		(end 368.831876 -225.53168)
		(width 0.1143)
		(layer "In2.Cu")
		(net "GMI_CPU0_G2_CPU1_G0_TX_DN<6>")
	)
	(segment
		(start 102.193852 -227.961952)
		(end 102.163372 -227.979732)
		(width 0.1143)
		(layer "In2.Cu")
		(net "GMI_CPU0_G2_CPU1_G0_TX_DN<6>")
	)
	(segment
		(start 324.228206 -188.28258)
		(end 310.343296 -181.583838)
		(width 0.14224)
		(layer "In2.Cu")
		(net "GMI_CPU0_G2_CPU1_G0_TX_DN<6>")
	)
	(segment
		(start 101.720396 -228.77399)
		(end 101.719634 -228.774498)
		(width 0.1143)
		(layer "In2.Cu")
		(net "GMI_CPU0_G2_CPU1_G0_TX_DN<6>")
	)
	(segment
		(start 102.632256 -222.918782)
		(end 102.660196 -222.934784)
		(width 0.1143)
		(layer "In2.Cu")
		(net "GMI_CPU0_G2_CPU1_G0_TX_DN<6>")
	)
	(segment
		(start 104.405176 -212.965538)
		(end 104.108758 -213.26221)
		(width 0.14224)
		(layer "In2.Cu")
		(net "GMI_CPU0_G2_CPU1_G0_TX_DN<6>")
	)
	(segment
		(start 368.831876 -223.911668)
		(end 368.79276 -223.888808)
		(width 0.1143)
		(layer "In2.Cu")
		(net "GMI_CPU0_G2_CPU1_G0_TX_DN<6>")
	)
	(segment
		(start 102.661974 -224.555812)
		(end 102.663244 -224.556574)
		(width 0.1143)
		(layer "In2.Cu")
		(net "GMI_CPU0_G2_CPU1_G0_TX_DN<6>")
	)
	(segment
		(start 101.717602 -228.775514)
		(end 101.692202 -228.790246)
		(width 0.1143)
		(layer "In2.Cu")
		(net "GMI_CPU0_G2_CPU1_G0_TX_DN<6>")
	)
	(segment
		(start 102.661974 -226.175824)
		(end 102.663244 -226.176586)
		(width 0.1143)
		(layer "In2.Cu")
		(net "GMI_CPU0_G2_CPU1_G0_TX_DN<6>")
	)
	(segment
		(start 369.301776 -227.961698)
		(end 369.30076 -227.96119)
		(width 0.1143)
		(layer "In2.Cu")
		(net "GMI_CPU0_G2_CPU1_G0_TX_DN<6>")
	)
	(segment
		(start 101.727508 -228.769926)
		(end 101.726492 -228.770434)
		(width 0.1143)
		(layer "In2.Cu")
		(net "GMI_CPU0_G2_CPU1_G0_TX_DN<6>")
	)
	(segment
		(start 102.66553 -223.910906)
		(end 102.663244 -223.91243)
		(width 0.1143)
		(layer "In2.Cu")
		(net "GMI_CPU0_G2_CPU1_G0_TX_DN<6>")
	)
	(segment
		(start 368.831876 -225.53168)
		(end 368.79276 -225.50882)
		(width 0.1143)
		(layer "In2.Cu")
		(net "GMI_CPU0_G2_CPU1_G0_TX_DN<6>")
	)
	(segment
		(start 102.663244 -222.936562)
		(end 102.664006 -222.93707)
		(width 0.1143)
		(layer "In2.Cu")
		(net "GMI_CPU0_G2_CPU1_G0_TX_DN<6>")
	)
	(segment
		(start 309.08498 -181.104286)
		(end 305.330606 -180.129688)
		(width 0.14224)
		(layer "In2.Cu")
		(net "GMI_CPU0_G2_CPU1_G0_TX_DN<6>")
	)
	(segment
		(start 369.30076 -227.96119)
		(end 369.299236 -227.960174)
		(width 0.1143)
		(layer "In2.Cu")
		(net "GMI_CPU0_G2_CPU1_G0_TX_DN<6>")
	)
	(segment
		(start 369.29822 -227.959666)
		(end 369.26266 -227.938838)
		(width 0.1143)
		(layer "In2.Cu")
		(net "GMI_CPU0_G2_CPU1_G0_TX_DN<6>")
	)
	(segment
		(start 101.143054 -229.90429)
		(end 101.440996 -229.90429)
		(width 0.1143)
		(layer "In2.Cu")
		(net "GMI_CPU0_G2_CPU1_G0_TX_DN<6>")
	)
	(segment
		(start 102.669594 -225.525076)
		(end 102.645464 -225.54184)
		(width 0.1143)
		(layer "In2.Cu")
		(net "GMI_CPU0_G2_CPU1_G0_TX_DN<6>")
	)
	(segment
		(start 101.724968 -228.77145)
		(end 101.723952 -228.771958)
		(width 0.1143)
		(layer "In2.Cu")
		(net "GMI_CPU0_G2_CPU1_G0_TX_DN<6>")
	)
	(segment
		(start 101.253798 -229.581964)
		(end 101.221286 -229.60076)
		(width 0.1143)
		(layer "In2.Cu")
		(net "GMI_CPU0_G2_CPU1_G0_TX_DN<6>")
	)
	(segment
		(start 102.664006 -227.151946)
		(end 102.663244 -227.152454)
		(width 0.1143)
		(layer "In2.Cu")
		(net "GMI_CPU0_G2_CPU1_G0_TX_DN<6>")
	)
	(segment
		(start 101.726492 -228.770434)
		(end 101.724968 -228.77145)
		(width 0.1143)
		(layer "In2.Cu")
		(net "GMI_CPU0_G2_CPU1_G0_TX_DN<6>")
	)
	(segment
		(start 370.275358 -229.601268)
		(end 370.24183 -229.58171)
		(width 0.1143)
		(layer "In2.Cu")
		(net "GMI_CPU0_G2_CPU1_G0_TX_DN<6>")
	)
	(segment
		(start 103.918258 -213.26221)
		(end 103.622094 -213.558374)
		(width 0.14224)
		(layer "In2.Cu")
		(net "GMI_CPU0_G2_CPU1_G0_TX_DN<6>")
	)
	(segment
		(start 102.193852 -222.127064)
		(end 102.232968 -222.149924)
		(width 0.1143)
		(layer "In2.Cu")
		(net "GMI_CPU0_G2_CPU1_G0_TX_DN<6>")
	)
	(segment
		(start 102.352094 -214.828374)
		(end 102.05593 -215.124538)
		(width 0.14224)
		(layer "In2.Cu")
		(net "GMI_CPU0_G2_CPU1_G0_TX_DN<6>")
	)
	(segment
		(start 106.458004 -210.912964)
		(end 106.267504 -210.912964)
		(width 0.14224)
		(layer "In2.Cu")
		(net "GMI_CPU0_G2_CPU1_G0_TX_DN<6>")
	)
	(segment
		(start 368.79276 -226.1997)
		(end 368.831876 -226.17684)
		(width 0.1143)
		(layer "In2.Cu")
		(net "GMI_CPU0_G2_CPU1_G0_TX_DN<6>")
	)
	(segment
		(start 368.831876 -227.151692)
		(end 368.79276 -227.128832)
		(width 0.1143)
		(layer "In2.Cu")
		(net "GMI_CPU0_G2_CPU1_G0_TX_DN<6>")
	)
	(segment
		(start 369.959636 -229.094284)
		(end 369.959382 -229.094284)
		(width 0.1143)
		(layer "In2.Cu")
		(net "GMI_CPU0_G2_CPU1_G0_TX_DN<6>")
	)
	(segment
		(start 107.537504 -209.642964)
		(end 107.537504 -209.83321)
		(width 0.14224)
		(layer "In2.Cu")
		(net "GMI_CPU0_G2_CPU1_G0_TX_DN<6>")
	)
	(segment
		(start 107.537504 -209.83321)
		(end 107.241086 -210.129882)
		(width 0.14224)
		(layer "In2.Cu")
		(net "GMI_CPU0_G2_CPU1_G0_TX_DN<6>")
	)
	(segment
		(start 370.352828 -229.904036)
		(end 370.422678 -229.834186)
		(width 0.1143)
		(layer "In2.Cu")
		(net "GMI_CPU0_G2_CPU1_G0_TX_DN<6>")
	)
	(segment
		(start 102.660196 -224.554796)
		(end 102.660958 -224.555304)
		(width 0.1143)
		(layer "In2.Cu")
		(net "GMI_CPU0_G2_CPU1_G0_TX_DN<6>")
	)
	(segment
		(start 102.661974 -227.153216)
		(end 102.66045 -227.153978)
		(width 0.1143)
		(layer "In2.Cu")
		(net "GMI_CPU0_G2_CPU1_G0_TX_DN<6>")
	)
	(segment
		(start 101.723952 -228.771958)
		(end 101.72319 -228.772466)
		(width 0.1143)
		(layer "In2.Cu")
		(net "GMI_CPU0_G2_CPU1_G0_TX_DN<6>")
	)
	(segment
		(start 102.730808 -223.86925)
		(end 102.702868 -223.889316)
		(width 0.1143)
		(layer "In2.Cu")
		(net "GMI_CPU0_G2_CPU1_G0_TX_DN<6>")
	)
	(segment
		(start 102.632256 -226.158806)
		(end 102.661974 -226.175824)
		(width 0.1143)
		(layer "In2.Cu")
		(net "GMI_CPU0_G2_CPU1_G0_TX_DN<6>")
	)
	(segment
		(start 102.702868 -223.889316)
		(end 102.66553 -223.910906)
		(width 0.1143)
		(layer "In2.Cu")
		(net "GMI_CPU0_G2_CPU1_G0_TX_DN<6>")
	)
	(segment
		(start 103.325676 -214.045292)
		(end 103.135176 -214.045292)
		(width 0.14224)
		(layer "In2.Cu")
		(net "GMI_CPU0_G2_CPU1_G0_TX_DN<6>")
	)
	(segment
		(start 102.657656 -223.915478)
		(end 102.632256 -223.93021)
		(width 0.1143)
		(layer "In2.Cu")
		(net "GMI_CPU0_G2_CPU1_G0_TX_DN<6>")
	)
	(segment
		(start 107.241086 -210.129882)
		(end 107.050586 -210.129882)
		(width 0.14224)
		(layer "In2.Cu")
		(net "GMI_CPU0_G2_CPU1_G0_TX_DN<6>")
	)
	(segment
		(start 369.77193 -228.771704)
		(end 369.732814 -228.748844)
		(width 0.1143)
		(layer "In2.Cu")
		(net "GMI_CPU0_G2_CPU1_G0_TX_DN<6>")
	)
	(segment
		(start 102.163372 -222.109284)
		(end 102.193852 -222.127064)
		(width 0.1143)
		(layer "In2.Cu")
		(net "GMI_CPU0_G2_CPU1_G0_TX_DN<6>")
	)
	(segment
		(start 310.343296 -181.583838)
		(end 309.08498 -181.104286)
		(width 0.14224)
		(layer "In2.Cu")
		(net "GMI_CPU0_G2_CPU1_G0_TX_DN<6>")
	)
	(segment
		(start 369.80241 -228.789484)
		(end 369.77193 -228.771704)
		(width 0.1143)
		(layer "In2.Cu")
		(net "GMI_CPU0_G2_CPU1_G0_TX_DN<6>")
	)
	(segment
		(start 368.862356 -222.309436)
		(end 368.79276 -222.268796)
		(width 0.1143)
		(layer "In2.Cu")
		(net "GMI_CPU0_G2_CPU1_G0_TX_DN<6>")
	)
	(segment
		(start 368.79276 -224.579688)
		(end 368.831876 -224.556828)
		(width 0.1143)
		(layer "In2.Cu")
		(net "GMI_CPU0_G2_CPU1_G0_TX_DN<6>")
	)
	(segment
		(start 102.706678 -225.50628)
		(end 102.669594 -225.525076)
		(width 0.1143)
		(layer "In2.Cu")
		(net "GMI_CPU0_G2_CPU1_G0_TX_DN<6>")
	)
	(segment
		(start 366.88014 -215.19515)
		(end 362.629196 -211.488528)
		(width 0.14224)
		(layer "In2.Cu")
		(net "GMI_CPU0_G2_CPU1_G0_TX_DN<6>")
	)
	(segment
		(start 105.97134 -211.399374)
		(end 105.674922 -211.696046)
		(width 0.14224)
		(layer "In2.Cu")
		(net "GMI_CPU0_G2_CPU1_G0_TX_DN<6>")
	)
	(segment
		(start 102.66045 -223.913954)
		(end 102.659688 -223.914462)
		(width 0.1143)
		(layer "In2.Cu")
		(net "GMI_CPU0_G2_CPU1_G0_TX_DN<6>")
	)
	(segment
		(start 163.072572 -180.806852)
		(end 153.062178 -184.952386)
		(width 0.14224)
		(layer "In2.Cu")
		(net "GMI_CPU0_G2_CPU1_G0_TX_DN<6>")
	)
	(segment
		(start 108.320586 -208.859882)
		(end 108.320586 -209.050128)
		(width 0.14224)
		(layer "In2.Cu")
		(net "GMI_CPU0_G2_CPU1_G0_TX_DN<6>")
	)
	(segment
		(start 104.89184 -212.479128)
		(end 104.70134 -212.479128)
		(width 0.14224)
		(layer "In2.Cu")
		(net "GMI_CPU0_G2_CPU1_G0_TX_DN<6>")
	)
	(segment
		(start 370.054886 -229.904036)
		(end 370.352828 -229.904036)
		(width 0.1143)
		(layer "In2.Cu")
		(net "GMI_CPU0_G2_CPU1_G0_TX_DN<6>")
	)
	(segment
		(start 102.660196 -222.934784)
		(end 102.660958 -222.935292)
		(width 0.1143)
		(layer "In2.Cu")
		(net "GMI_CPU0_G2_CPU1_G0_TX_DN<6>")
	)
	(segment
		(start 102.663244 -224.556574)
		(end 102.664006 -224.557082)
		(width 0.1143)
		(layer "In2.Cu")
		(net "GMI_CPU0_G2_CPU1_G0_TX_DN<6>")
	)
	(segment
		(start 369.299236 -227.960174)
		(end 369.29822 -227.959666)
		(width 0.1143)
		(layer "In2.Cu")
		(net "GMI_CPU0_G2_CPU1_G0_TX_DN<6>")
	)
	(segment
		(start 102.052374 -219.551504)
		(end 102.052374 -221.174564)
		(width 0.14224)
		(layer "In2.Cu")
		(net "GMI_CPU0_G2_CPU1_G0_TX_DN<6>")
	)
	(segment
		(start 369.333526 -227.979986)
		(end 369.301776 -227.961698)
		(width 0.1143)
		(layer "In2.Cu")
		(net "GMI_CPU0_G2_CPU1_G0_TX_DN<6>")
	)
	(segment
		(start 368.520218 -221.444312)
		(end 368.520218 -221.128844)
		(width 0.1143)
		(layer "In2.Cu")
		(net "GMI_CPU0_G2_CPU1_G0_TX_DN<6>")
	)
	(segment
		(start 165.344602 -180.170328)
		(end 163.072572 -180.806852)
		(width 0.14224)
		(layer "In2.Cu")
		(net "GMI_CPU0_G2_CPU1_G0_TX_DN<6>")
	)
	(segment
		(start 102.702868 -224.579688)
		(end 102.730808 -224.599754)
		(width 0.1143)
		(layer "In2.Cu")
		(net "GMI_CPU0_G2_CPU1_G0_TX_DN<6>")
	)
	(segment
		(start 102.632256 -224.538794)
		(end 102.660196 -224.554796)
		(width 0.1143)
		(layer "In2.Cu")
		(net "GMI_CPU0_G2_CPU1_G0_TX_DN<6>")
	)
	(segment
		(start 103.135176 -214.045292)
		(end 102.839012 -214.341456)
		(width 0.14224)
		(layer "In2.Cu")
		(net "GMI_CPU0_G2_CPU1_G0_TX_DN<6>")
	)
	(segment
		(start 105.188258 -212.182456)
		(end 104.89184 -212.479128)
		(width 0.14224)
		(layer "In2.Cu")
		(net "GMI_CPU0_G2_CPU1_G0_TX_DN<6>")
	)
	(segment
		(start 108.024168 -209.3468)
		(end 107.833668 -209.3468)
		(width 0.14224)
		(layer "In2.Cu")
		(net "GMI_CPU0_G2_CPU1_G0_TX_DN<6>")
	)
	(segment
		(start 102.05593 -215.124538)
		(end 102.05593 -219.547948)
		(width 0.14224)
		(layer "In2.Cu")
		(net "GMI_CPU0_G2_CPU1_G0_TX_DN<6>")
	)
	(segment
		(start 108.320586 -209.050128)
		(end 108.024168 -209.3468)
		(width 0.14224)
		(layer "In2.Cu")
		(net "GMI_CPU0_G2_CPU1_G0_TX_DN<6>")
	)
	(segment
		(start 109.555026 -207.625442)
		(end 108.320586 -208.859882)
		(width 0.14224)
		(layer "In2.Cu")
		(net "GMI_CPU0_G2_CPU1_G0_TX_DN<6>")
	)
	(segment
		(start 107.833668 -209.3468)
		(end 107.537504 -209.642964)
		(width 0.14224)
		(layer "In2.Cu")
		(net "GMI_CPU0_G2_CPU1_G0_TX_DN<6>")
	)
	(segment
		(start 104.70134 -212.479128)
		(end 104.405176 -212.775292)
		(width 0.14224)
		(layer "In2.Cu")
		(net "GMI_CPU0_G2_CPU1_G0_TX_DN<6>")
	)
	(segment
		(start 102.542594 -214.828374)
		(end 102.352094 -214.828374)
		(width 0.14224)
		(layer "In2.Cu")
		(net "GMI_CPU0_G2_CPU1_G0_TX_DN<6>")
	)
	(segment
		(start 102.052374 -221.203012)
		(end 102.006654 -221.248732)
		(width 0.1143)
		(layer "In2.Cu")
		(net "GMI_CPU0_G2_CPU1_G0_TX_DN<6>")
	)
	(segment
		(start 102.6668 -222.938848)
		(end 102.702868 -222.959676)
		(width 0.1143)
		(layer "In2.Cu")
		(net "GMI_CPU0_G2_CPU1_G0_TX_DN<6>")
	)
	(segment
		(start 235.328714 -177.77079)
		(end 165.344602 -180.170328)
		(width 0.14224)
		(layer "In2.Cu")
		(net "GMI_CPU0_G2_CPU1_G0_TX_DN<6>")
	)
	(segment
		(start 102.660958 -224.555304)
		(end 102.661974 -224.555812)
		(width 0.1143)
		(layer "In2.Cu")
		(net "GMI_CPU0_G2_CPU1_G0_TX_DN<6>")
	)
	(segment
		(start 102.645464 -225.54184)
		(end 102.644448 -225.542602)
		(width 0.1143)
		(layer "In2.Cu")
		(net "GMI_CPU0_G2_CPU1_G0_TX_DN<6>")
	)
	(segment
		(start 103.622094 -213.74862)
		(end 103.325676 -214.045292)
		(width 0.14224)
		(layer "In2.Cu")
		(net "GMI_CPU0_G2_CPU1_G0_TX_DN<6>")
	)
	(segment
		(start 102.05593 -219.547948)
		(end 102.052374 -219.551504)
		(width 0.14224)
		(layer "In2.Cu")
		(net "GMI_CPU0_G2_CPU1_G0_TX_DN<6>")
	)
	(segment
		(start 368.520218 -221.128844)
		(end 368.474498 -221.083124)
		(width 0.1143)
		(layer "In2.Cu")
		(net "GMI_CPU0_G2_CPU1_G0_TX_DN<6>")
	)
	(segment
		(start 102.661974 -223.913192)
		(end 102.66045 -223.913954)
		(width 0.1143)
		(layer "In2.Cu")
		(net "GMI_CPU0_G2_CPU1_G0_TX_DN<6>")
	)
	(segment
		(start 368.831876 -226.17684)
		(end 368.862356 -226.15906)
		(width 0.1143)
		(layer "In2.Cu")
		(net "GMI_CPU0_G2_CPU1_G0_TX_DN<6>")
	)
	(segment
		(start 357.32974 -207.896968)
		(end 324.228206 -188.28258)
		(width 0.14224)
		(layer "In2.Cu")
		(net "GMI_CPU0_G2_CPU1_G0_TX_DN<6>")
	)
	(segment
		(start 368.862356 -227.169472)
		(end 368.831876 -227.151692)
		(width 0.1143)
		(layer "In2.Cu")
		(net "GMI_CPU0_G2_CPU1_G0_TX_DN<6>")
	)
	(segment
		(start 102.644448 -225.542602)
		(end 102.643178 -225.543364)
		(width 0.1143)
		(layer "In2.Cu")
		(net "GMI_CPU0_G2_CPU1_G0_TX_DN<6>")
	)
	(segment
		(start 101.763068 -228.749098)
		(end 101.727508 -228.769926)
		(width 0.1143)
		(layer "In2.Cu")
		(net "GMI_CPU0_G2_CPU1_G0_TX_DN<6>")
	)
	(segment
		(start 102.006654 -221.248732)
		(end 102.006654 -221.624906)
		(width 0.1143)
		(layer "In2.Cu")
		(net "GMI_CPU0_G2_CPU1_G0_TX_DN<6>")
	)
	(segment
		(start 102.661974 -222.9358)
		(end 102.663244 -222.936562)
		(width 0.1143)
		(layer "In2.Cu")
		(net "GMI_CPU0_G2_CPU1_G0_TX_DN<6>")
	)
	(segment
		(start 102.66045 -227.153978)
		(end 102.659688 -227.154486)
		(width 0.1143)
		(layer "In2.Cu")
		(net "GMI_CPU0_G2_CPU1_G0_TX_DN<6>")
	)
	(segment
		(start 368.831876 -224.556828)
		(end 368.862356 -224.539048)
		(width 0.1143)
		(layer "In2.Cu")
		(net "GMI_CPU0_G2_CPU1_G0_TX_DN<6>")
	)
	(segment
		(start 105.97134 -211.209128)
		(end 105.97134 -211.399374)
		(width 0.14224)
		(layer "In2.Cu")
		(net "GMI_CPU0_G2_CPU1_G0_TX_DN<6>")
	)
	(segment
		(start 102.664006 -226.177094)
		(end 102.700328 -226.198176)
		(width 0.1143)
		(layer "In2.Cu")
		(net "GMI_CPU0_G2_CPU1_G0_TX_DN<6>")
	)
	(segment
		(start 102.663244 -226.176586)
		(end 102.664006 -226.177094)
		(width 0.1143)
		(layer "In2.Cu")
		(net "GMI_CPU0_G2_CPU1_G0_TX_DN<6>")
	)
	(segment
		(start 102.664006 -224.557082)
		(end 102.6668 -224.55886)
		(width 0.1143)
		(layer "In2.Cu")
		(net "GMI_CPU0_G2_CPU1_G0_TX_DN<6>")
	)
	(segment
		(start 102.232968 -227.939092)
		(end 102.193852 -227.961952)
		(width 0.1143)
		(layer "In2.Cu")
		(net "GMI_CPU0_G2_CPU1_G0_TX_DN<6>")
	)
	(segment
		(start 102.659688 -227.154486)
		(end 102.657656 -227.155502)
		(width 0.1143)
		(layer "In2.Cu")
		(net "GMI_CPU0_G2_CPU1_G0_TX_DN<6>")
	)
	(segment
		(start 362.629196 -211.488528)
		(end 357.32974 -207.896968)
		(width 0.14224)
		(layer "In2.Cu")
		(net "GMI_CPU0_G2_CPU1_G0_TX_DN<6>")
	)
	(segment
		(start 305.330606 -180.129688)
		(end 235.328714 -177.77079)
		(width 0.14224)
		(layer "In2.Cu")
		(net "GMI_CPU0_G2_CPU1_G0_TX_DN<6>")
	)
	(segment
		(start 102.0064 -221.62516)
		(end 102.0064 -221.804484)
		(width 0.1143)
		(layer "In2.Cu")
		(net "GMI_CPU0_G2_CPU1_G0_TX_DN<6>")
	)
	(segment
		(start 107.050586 -210.129882)
		(end 106.754422 -210.426046)
		(width 0.14224)
		(layer "In2.Cu")
		(net "GMI_CPU0_G2_CPU1_G0_TX_DN<6>")
	)
	(segment
		(start 102.700328 -227.130864)
		(end 102.664006 -227.151946)
		(width 0.1143)
		(layer "In2.Cu")
		(net "GMI_CPU0_G2_CPU1_G0_TX_DN<6>")
	)
	(segment
		(start 102.643178 -225.54311)
		(end 102.633272 -225.549714)
		(width 0.1143)
		(layer "In2.Cu")
		(net "GMI_CPU0_G2_CPU1_G0_TX_DN<6>")
	)
	(segment
		(start 368.474498 -218.700096)
		(end 366.88014 -215.19515)
		(width 0.14224)
		(layer "In2.Cu")
		(net "GMI_CPU0_G2_CPU1_G0_TX_DN<6>")
	)
	(segment
		(start 101.073204 -229.83444)
		(end 101.143054 -229.90429)
		(width 0.1143)
		(layer "In2.Cu")
		(net "GMI_CPU0_G2_CPU1_G0_TX_DN<6>")
	)
	(segment
		(start 102.664006 -222.93707)
		(end 102.6668 -222.938848)
		(width 0.1143)
		(layer "In2.Cu")
		(net "GMI_CPU0_G2_CPU1_G0_TX_DN<6>")
	)
	(segment
		(start 102.052374 -221.174564)
		(end 102.052374 -221.203012)
		(width 0.1143)
		(layer "In2.Cu")
		(net "GMI_CPU0_G2_CPU1_G0_TX_DN<6>")
	)
	(segment
		(start 368.79276 -222.959676)
		(end 368.831876 -222.936816)
		(width 0.1143)
		(layer "In2.Cu")
		(net "GMI_CPU0_G2_CPU1_G0_TX_DN<6>")
	)
	(arc
		(start 369.26266 -227.938838)
		(mid 369.083847 -227.736488)
		(end 369.019328 -227.474272)
		(width 0.1143)
		(layer "In2.Cu")
		(net "GMI_CPU0_G2_CPU1_G0_TX_DN<6>")
	)
	(arc
		(start 368.862356 -224.539048)
		(mid 369.019333 -224.234248)
		(end 368.862356 -223.929448)
		(width 0.1143)
		(layer "In2.Cu")
		(net "GMI_CPU0_G2_CPU1_G0_TX_DN<6>")
	)
	(arc
		(start 102.0064 -221.804484)
		(mid 102.047949 -221.975906)
		(end 102.163372 -222.109284)
		(width 0.1143)
		(layer "In2.Cu")
		(net "GMI_CPU0_G2_CPU1_G0_TX_DN<6>")
	)
	(arc
		(start 368.79276 -227.128832)
		(mid 368.549433 -226.664266)
		(end 368.79276 -226.1997)
		(width 0.1143)
		(layer "In2.Cu")
		(net "GMI_CPU0_G2_CPU1_G0_TX_DN<6>")
	)
	(arc
		(start 369.732814 -228.748844)
		(mid 369.554001 -228.546494)
		(end 369.489482 -228.284278)
		(width 0.1143)
		(layer "In2.Cu")
		(net "GMI_CPU0_G2_CPU1_G0_TX_DN<6>")
	)
	(arc
		(start 102.0064 -228.284532)
		(mid 101.941885 -228.546751)
		(end 101.763068 -228.749098)
		(width 0.1143)
		(layer "In2.Cu")
		(net "GMI_CPU0_G2_CPU1_G0_TX_DN<6>")
	)
	(arc
		(start 102.730808 -224.599754)
		(mid 102.958808 -225.044966)
		(end 102.730046 -225.48977)
		(width 0.1143)
		(layer "In2.Cu")
		(net "GMI_CPU0_G2_CPU1_G0_TX_DN<6>")
	)
	(arc
		(start 368.862356 -222.919036)
		(mid 369.019333 -222.614236)
		(end 368.862356 -222.309436)
		(width 0.1143)
		(layer "In2.Cu")
		(net "GMI_CPU0_G2_CPU1_G0_TX_DN<6>")
	)
	(arc
		(start 102.700328 -226.198176)
		(mid 102.707477 -226.203076)
		(end 102.714552 -226.208082)
		(width 0.1143)
		(layer "In2.Cu")
		(net "GMI_CPU0_G2_CPU1_G0_TX_DN<6>")
	)
	(arc
		(start 368.79276 -223.888808)
		(mid 368.549433 -223.424242)
		(end 368.79276 -222.959676)
		(width 0.1143)
		(layer "In2.Cu")
		(net "GMI_CPU0_G2_CPU1_G0_TX_DN<6>")
	)
	(arc
		(start 368.862356 -226.15906)
		(mid 369.019333 -225.85426)
		(end 368.862356 -225.54946)
		(width 0.1143)
		(layer "In2.Cu")
		(net "GMI_CPU0_G2_CPU1_G0_TX_DN<6>")
	)
	(arc
		(start 102.632256 -223.93021)
		(mid 102.476328 -224.234502)
		(end 102.632256 -224.538794)
		(width 0.1143)
		(layer "In2.Cu")
		(net "GMI_CPU0_G2_CPU1_G0_TX_DN<6>")
	)
	(arc
		(start 369.959382 -229.094284)
		(mid 369.917833 -228.922862)
		(end 369.80241 -228.789484)
		(width 0.1143)
		(layer "In2.Cu")
		(net "GMI_CPU0_G2_CPU1_G0_TX_DN<6>")
	)
	(arc
		(start 101.221286 -229.60076)
		(mid 101.124846 -229.703415)
		(end 101.073204 -229.83444)
		(width 0.1143)
		(layer "In2.Cu")
		(net "GMI_CPU0_G2_CPU1_G0_TX_DN<6>")
	)
	(arc
		(start 102.4763 -227.474526)
		(mid 102.411785 -227.736745)
		(end 102.232968 -227.939092)
		(width 0.1143)
		(layer "In2.Cu")
		(net "GMI_CPU0_G2_CPU1_G0_TX_DN<6>")
	)
	(arc
		(start 102.163372 -227.979732)
		(mid 102.047945 -228.113108)
		(end 102.0064 -228.284532)
		(width 0.1143)
		(layer "In2.Cu")
		(net "GMI_CPU0_G2_CPU1_G0_TX_DN<6>")
	)
	(arc
		(start 101.692202 -228.790246)
		(mid 101.577526 -228.92358)
		(end 101.536246 -229.094538)
		(width 0.1143)
		(layer "In2.Cu")
		(net "GMI_CPU0_G2_CPU1_G0_TX_DN<6>")
	)
	(arc
		(start 368.79276 -222.268796)
		(mid 368.614117 -222.066401)
		(end 368.549682 -221.80423)
		(width 0.1143)
		(layer "In2.Cu")
		(net "GMI_CPU0_G2_CPU1_G0_TX_DN<6>")
	)
	(arc
		(start 102.632256 -225.550222)
		(mid 102.476328 -225.854514)
		(end 102.632256 -226.158806)
		(width 0.1143)
		(layer "In2.Cu")
		(net "GMI_CPU0_G2_CPU1_G0_TX_DN<6>")
	)
	(arc
		(start 369.019328 -227.474272)
		(mid 368.977779 -227.30285)
		(end 368.862356 -227.169472)
		(width 0.1143)
		(layer "In2.Cu")
		(net "GMI_CPU0_G2_CPU1_G0_TX_DN<6>")
	)
	(arc
		(start 102.632256 -227.170234)
		(mid 102.51758 -227.303568)
		(end 102.4763 -227.474526)
		(width 0.1143)
		(layer "In2.Cu")
		(net "GMI_CPU0_G2_CPU1_G0_TX_DN<6>")
	)
	(arc
		(start 102.730808 -222.979742)
		(mid 102.958808 -223.424496)
		(end 102.730808 -223.86925)
		(width 0.1143)
		(layer "In2.Cu")
		(net "GMI_CPU0_G2_CPU1_G0_TX_DN<6>")
	)
	(arc
		(start 370.205508 -229.560628)
		(mid 370.024856 -229.357883)
		(end 369.959636 -229.094284)
		(width 0.1143)
		(layer "In2.Cu")
		(net "GMI_CPU0_G2_CPU1_G0_TX_DN<6>")
	)
	(arc
		(start 102.232968 -222.149924)
		(mid 102.411781 -222.352274)
		(end 102.4763 -222.61449)
		(width 0.1143)
		(layer "In2.Cu")
		(net "GMI_CPU0_G2_CPU1_G0_TX_DN<6>")
	)
	(arc
		(start 101.536246 -229.094538)
		(mid 101.471731 -229.356757)
		(end 101.292914 -229.559104)
		(width 0.1143)
		(layer "In2.Cu")
		(net "GMI_CPU0_G2_CPU1_G0_TX_DN<6>")
	)
	(arc
		(start 368.79276 -225.50882)
		(mid 368.549433 -225.044254)
		(end 368.79276 -224.579688)
		(width 0.1143)
		(layer "In2.Cu")
		(net "GMI_CPU0_G2_CPU1_G0_TX_DN<6>")
	)
	(arc
		(start 369.489482 -228.284278)
		(mid 369.448227 -228.113307)
		(end 369.333526 -227.979986)
		(width 0.1143)
		(layer "In2.Cu")
		(net "GMI_CPU0_G2_CPU1_G0_TX_DN<6>")
	)
	(arc
		(start 370.422678 -229.834186)
		(mid 370.371188 -229.703713)
		(end 370.275358 -229.601268)
		(width 0.1143)
		(layer "In2.Cu")
		(net "GMI_CPU0_G2_CPU1_G0_TX_DN<6>")
	)
	(arc
		(start 102.714552 -227.120958)
		(mid 102.707478 -227.125965)
		(end 102.700328 -227.130864)
		(width 0.1143)
		(layer "In2.Cu")
		(net "GMI_CPU0_G2_CPU1_G0_TX_DN<6>")
	)
	(arc
		(start 102.714552 -226.208082)
		(mid 102.941935 -226.66452)
		(end 102.714552 -227.120958)
		(width 0.1143)
		(layer "In2.Cu")
		(net "GMI_CPU0_G2_CPU1_G0_TX_DN<6>")
	)
	(arc
		(start 102.4763 -222.61449)
		(mid 102.517555 -222.785461)
		(end 102.632256 -222.918782)
		(width 0.1143)
		(layer "In2.Cu")
		(net "GMI_CPU0_G2_CPU1_G0_TX_DN<6>")
	)
	(segment
		(start 101.907848 -226.930458)
		(end 101.440996 -226.66452)
		(width 0.12954)
		(layer "F.Cu")
		(net "GMI_CPU0_G2_CPU1_G0_TX_DN<5>")
	)
	(segment
		(start 369.588034 -226.930204)
		(end 370.054886 -226.664266)
		(width 0.12954)
		(layer "F.Cu")
		(net "GMI_CPU0_G2_CPU1_G0_TX_DN<5>")
	)
	(segment
		(start 311.280556 -179.925472)
		(end 309.310786 -179.174648)
		(width 0.14224)
		(layer "In2.Cu")
		(net "GMI_CPU0_G2_CPU1_G0_TX_DN<5>")
	)
	(segment
		(start 370.352828 -226.664266)
		(end 370.435632 -226.581462)
		(width 0.1143)
		(layer "In2.Cu")
		(net "GMI_CPU0_G2_CPU1_G0_TX_DN<5>")
	)
	(segment
		(start 100.652834 -213.602062)
		(end 100.462334 -213.602062)
		(width 0.14224)
		(layer "In2.Cu")
		(net "GMI_CPU0_G2_CPU1_G0_TX_DN<5>")
	)
	(segment
		(start 100.783136 -222.936816)
		(end 100.783898 -222.93707)
		(width 0.1143)
		(layer "In2.Cu")
		(net "GMI_CPU0_G2_CPU1_G0_TX_DN<5>")
	)
	(segment
		(start 235.30941 -175.880268)
		(end 164.940488 -178.292506)
		(width 0.14224)
		(layer "In2.Cu")
		(net "GMI_CPU0_G2_CPU1_G0_TX_DN<5>")
	)
	(segment
		(start 100.281994 -222.108522)
		(end 100.324412 -222.13316)
		(width 0.1143)
		(layer "In2.Cu")
		(net "GMI_CPU0_G2_CPU1_G0_TX_DN<5>")
	)
	(segment
		(start 164.940488 -178.292506)
		(end 162.3314 -179.023518)
		(width 0.14224)
		(layer "In2.Cu")
		(net "GMI_CPU0_G2_CPU1_G0_TX_DN<5>")
	)
	(segment
		(start 102.515416 -211.739226)
		(end 102.218998 -212.035898)
		(width 0.14224)
		(layer "In2.Cu")
		(net "GMI_CPU0_G2_CPU1_G0_TX_DN<5>")
	)
	(segment
		(start 368.471704 -214.022686)
		(end 364.009686 -210.13293)
		(width 0.14224)
		(layer "In2.Cu")
		(net "GMI_CPU0_G2_CPU1_G0_TX_DN<5>")
	)
	(segment
		(start 100.783898 -224.557082)
		(end 100.784914 -224.55759)
		(width 0.1143)
		(layer "In2.Cu")
		(net "GMI_CPU0_G2_CPU1_G0_TX_DN<5>")
	)
	(segment
		(start 104.568244 -209.686652)
		(end 104.377744 -209.686652)
		(width 0.14224)
		(layer "In2.Cu")
		(net "GMI_CPU0_G2_CPU1_G0_TX_DN<5>")
	)
	(segment
		(start 102.028498 -212.035898)
		(end 101.732334 -212.332062)
		(width 0.14224)
		(layer "In2.Cu")
		(net "GMI_CPU0_G2_CPU1_G0_TX_DN<5>")
	)
	(segment
		(start 370.742464 -223.929448)
		(end 370.711984 -223.911668)
		(width 0.1143)
		(layer "In2.Cu")
		(net "GMI_CPU0_G2_CPU1_G0_TX_DN<5>")
	)
	(segment
		(start 325.358506 -186.717178)
		(end 311.280556 -179.925472)
		(width 0.14224)
		(layer "In2.Cu")
		(net "GMI_CPU0_G2_CPU1_G0_TX_DN<5>")
	)
	(segment
		(start 100.172012 -221.203012)
		(end 100.126292 -221.248732)
		(width 0.1143)
		(layer "In2.Cu")
		(net "GMI_CPU0_G2_CPU1_G0_TX_DN<5>")
	)
	(segment
		(start 370.742464 -222.309436)
		(end 370.672868 -222.268796)
		(width 0.1143)
		(layer "In2.Cu")
		(net "GMI_CPU0_G2_CPU1_G0_TX_DN<5>")
	)
	(segment
		(start 101.732334 -212.522308)
		(end 101.435916 -212.81898)
		(width 0.14224)
		(layer "In2.Cu")
		(net "GMI_CPU0_G2_CPU1_G0_TX_DN<5>")
	)
	(segment
		(start 100.126292 -221.248732)
		(end 100.126292 -221.804484)
		(width 0.1143)
		(layer "In2.Cu")
		(net "GMI_CPU0_G2_CPU1_G0_TX_DN<5>")
	)
	(segment
		(start 100.172012 -221.174564)
		(end 100.172012 -221.203012)
		(width 0.1143)
		(layer "In2.Cu")
		(net "GMI_CPU0_G2_CPU1_G0_TX_DN<5>")
	)
	(segment
		(start 101.435916 -212.81898)
		(end 101.245416 -212.81898)
		(width 0.14224)
		(layer "In2.Cu")
		(net "GMI_CPU0_G2_CPU1_G0_TX_DN<5>")
	)
	(segment
		(start 100.784914 -222.937578)
		(end 100.823014 -222.95993)
		(width 0.1143)
		(layer "In2.Cu")
		(net "GMI_CPU0_G2_CPU1_G0_TX_DN<5>")
	)
	(segment
		(start 103.298498 -210.765898)
		(end 103.298498 -210.956144)
		(width 0.14224)
		(layer "In2.Cu")
		(net "GMI_CPU0_G2_CPU1_G0_TX_DN<5>")
	)
	(segment
		(start 101.245416 -212.81898)
		(end 100.949252 -213.115144)
		(width 0.14224)
		(layer "In2.Cu")
		(net "GMI_CPU0_G2_CPU1_G0_TX_DN<5>")
	)
	(segment
		(start 370.672868 -222.959676)
		(end 370.711984 -222.936816)
		(width 0.1143)
		(layer "In2.Cu")
		(net "GMI_CPU0_G2_CPU1_G0_TX_DN<5>")
	)
	(segment
		(start 104.377744 -209.686652)
		(end 104.08158 -209.982816)
		(width 0.14224)
		(layer "In2.Cu")
		(net "GMI_CPU0_G2_CPU1_G0_TX_DN<5>")
	)
	(segment
		(start 105.647744 -208.416652)
		(end 105.647744 -208.606898)
		(width 0.14224)
		(layer "In2.Cu")
		(net "GMI_CPU0_G2_CPU1_G0_TX_DN<5>")
	)
	(segment
		(start 100.462334 -213.602062)
		(end 100.172012 -213.892384)
		(width 0.14224)
		(layer "In2.Cu")
		(net "GMI_CPU0_G2_CPU1_G0_TX_DN<5>")
	)
	(segment
		(start 102.81158 -211.252816)
		(end 102.515416 -211.54898)
		(width 0.14224)
		(layer "In2.Cu")
		(net "GMI_CPU0_G2_CPU1_G0_TX_DN<5>")
	)
	(segment
		(start 370.409978 -221.128844)
		(end 370.364258 -221.083124)
		(width 0.1143)
		(layer "In2.Cu")
		(net "GMI_CPU0_G2_CPU1_G0_TX_DN<5>")
	)
	(segment
		(start 370.42979 -221.445836)
		(end 370.409978 -221.426024)
		(width 0.1143)
		(layer "In2.Cu")
		(net "GMI_CPU0_G2_CPU1_G0_TX_DN<5>")
	)
	(segment
		(start 100.783898 -225.531934)
		(end 100.752148 -225.550222)
		(width 0.1143)
		(layer "In2.Cu")
		(net "GMI_CPU0_G2_CPU1_G0_TX_DN<5>")
	)
	(segment
		(start 100.783898 -226.177094)
		(end 100.823014 -226.199954)
		(width 0.1143)
		(layer "In2.Cu")
		(net "GMI_CPU0_G2_CPU1_G0_TX_DN<5>")
	)
	(segment
		(start 309.310786 -179.174648)
		(end 305.766724 -178.254914)
		(width 0.14224)
		(layer "In2.Cu")
		(net "GMI_CPU0_G2_CPU1_G0_TX_DN<5>")
	)
	(segment
		(start 370.364258 -221.083124)
		(end 370.364258 -218.183714)
		(width 0.14224)
		(layer "In2.Cu")
		(net "GMI_CPU0_G2_CPU1_G0_TX_DN<5>")
	)
	(segment
		(start 370.711984 -223.911668)
		(end 370.672868 -223.888808)
		(width 0.1143)
		(layer "In2.Cu")
		(net "GMI_CPU0_G2_CPU1_G0_TX_DN<5>")
	)
	(segment
		(start 100.783898 -223.911922)
		(end 100.752148 -223.93021)
		(width 0.1143)
		(layer "In2.Cu")
		(net "GMI_CPU0_G2_CPU1_G0_TX_DN<5>")
	)
	(segment
		(start 100.784914 -224.55759)
		(end 100.823014 -224.579942)
		(width 0.1143)
		(layer "In2.Cu")
		(net "GMI_CPU0_G2_CPU1_G0_TX_DN<5>")
	)
	(segment
		(start 102.515416 -211.54898)
		(end 102.515416 -211.739226)
		(width 0.14224)
		(layer "In2.Cu")
		(net "GMI_CPU0_G2_CPU1_G0_TX_DN<5>")
	)
	(segment
		(start 104.08158 -209.982816)
		(end 104.08158 -210.173062)
		(width 0.14224)
		(layer "In2.Cu")
		(net "GMI_CPU0_G2_CPU1_G0_TX_DN<5>")
	)
	(segment
		(start 364.009686 -210.13293)
		(end 357.987854 -206.051658)
		(width 0.14224)
		(layer "In2.Cu")
		(net "GMI_CPU0_G2_CPU1_G0_TX_DN<5>")
	)
	(segment
		(start 100.823014 -225.509074)
		(end 100.783898 -225.531934)
		(width 0.1143)
		(layer "In2.Cu")
		(net "GMI_CPU0_G2_CPU1_G0_TX_DN<5>")
	)
	(segment
		(start 100.949252 -213.115144)
		(end 100.949252 -213.30539)
		(width 0.14224)
		(layer "In2.Cu")
		(net "GMI_CPU0_G2_CPU1_G0_TX_DN<5>")
	)
	(segment
		(start 100.783136 -224.556574)
		(end 100.783898 -224.557082)
		(width 0.1143)
		(layer "In2.Cu")
		(net "GMI_CPU0_G2_CPU1_G0_TX_DN<5>")
	)
	(segment
		(start 104.864662 -209.38998)
		(end 104.568244 -209.686652)
		(width 0.14224)
		(layer "In2.Cu")
		(net "GMI_CPU0_G2_CPU1_G0_TX_DN<5>")
	)
	(segment
		(start 108.195364 -205.869032)
		(end 106.430826 -207.63357)
		(width 0.14224)
		(layer "In2.Cu")
		(net "GMI_CPU0_G2_CPU1_G0_TX_DN<5>")
	)
	(segment
		(start 357.987854 -206.051658)
		(end 325.358506 -186.717178)
		(width 0.14224)
		(layer "In2.Cu")
		(net "GMI_CPU0_G2_CPU1_G0_TX_DN<5>")
	)
	(segment
		(start 370.672868 -224.579688)
		(end 370.711984 -224.556828)
		(width 0.1143)
		(layer "In2.Cu")
		(net "GMI_CPU0_G2_CPU1_G0_TX_DN<5>")
	)
	(segment
		(start 104.08158 -210.173062)
		(end 103.785162 -210.469734)
		(width 0.14224)
		(layer "In2.Cu")
		(net "GMI_CPU0_G2_CPU1_G0_TX_DN<5>")
	)
	(segment
		(start 370.364258 -218.183714)
		(end 368.471704 -214.022686)
		(width 0.14224)
		(layer "In2.Cu")
		(net "GMI_CPU0_G2_CPU1_G0_TX_DN<5>")
	)
	(segment
		(start 370.409978 -221.426024)
		(end 370.409978 -221.128844)
		(width 0.1143)
		(layer "In2.Cu")
		(net "GMI_CPU0_G2_CPU1_G0_TX_DN<5>")
	)
	(segment
		(start 100.949252 -213.30539)
		(end 100.652834 -213.602062)
		(width 0.14224)
		(layer "In2.Cu")
		(net "GMI_CPU0_G2_CPU1_G0_TX_DN<5>")
	)
	(segment
		(start 105.647744 -208.606898)
		(end 105.351326 -208.90357)
		(width 0.14224)
		(layer "In2.Cu")
		(net "GMI_CPU0_G2_CPU1_G0_TX_DN<5>")
	)
	(segment
		(start 106.430826 -207.63357)
		(end 106.430826 -207.823816)
		(width 0.14224)
		(layer "In2.Cu")
		(net "GMI_CPU0_G2_CPU1_G0_TX_DN<5>")
	)
	(segment
		(start 152.476454 -183.105298)
		(end 108.195364 -205.869032)
		(width 0.14224)
		(layer "In2.Cu")
		(net "GMI_CPU0_G2_CPU1_G0_TX_DN<5>")
	)
	(segment
		(start 305.766724 -178.254914)
		(end 235.30941 -175.880268)
		(width 0.14224)
		(layer "In2.Cu")
		(net "GMI_CPU0_G2_CPU1_G0_TX_DN<5>")
	)
	(segment
		(start 370.42979 -221.80423)
		(end 370.42979 -221.445836)
		(width 0.1143)
		(layer "In2.Cu")
		(net "GMI_CPU0_G2_CPU1_G0_TX_DN<5>")
	)
	(segment
		(start 101.732334 -212.332062)
		(end 101.732334 -212.522308)
		(width 0.14224)
		(layer "In2.Cu")
		(net "GMI_CPU0_G2_CPU1_G0_TX_DN<5>")
	)
	(segment
		(start 100.752148 -224.538794)
		(end 100.783136 -224.556574)
		(width 0.1143)
		(layer "In2.Cu")
		(net "GMI_CPU0_G2_CPU1_G0_TX_DN<5>")
	)
	(segment
		(start 100.606606 -222.622872)
		(end 100.606606 -222.629984)
		(width 0.1143)
		(layer "In2.Cu")
		(net "GMI_CPU0_G2_CPU1_G0_TX_DN<5>")
	)
	(segment
		(start 105.351326 -208.90357)
		(end 105.160826 -208.90357)
		(width 0.14224)
		(layer "In2.Cu")
		(net "GMI_CPU0_G2_CPU1_G0_TX_DN<5>")
	)
	(segment
		(start 370.742464 -225.54946)
		(end 370.711984 -225.53168)
		(width 0.1143)
		(layer "In2.Cu")
		(net "GMI_CPU0_G2_CPU1_G0_TX_DN<5>")
	)
	(segment
		(start 370.711984 -226.17684)
		(end 370.742464 -226.15906)
		(width 0.1143)
		(layer "In2.Cu")
		(net "GMI_CPU0_G2_CPU1_G0_TX_DN<5>")
	)
	(segment
		(start 100.172012 -213.892384)
		(end 100.172012 -221.174564)
		(width 0.14224)
		(layer "In2.Cu")
		(net "GMI_CPU0_G2_CPU1_G0_TX_DN<5>")
	)
	(segment
		(start 101.143054 -226.66452)
		(end 101.440996 -226.66452)
		(width 0.1143)
		(layer "In2.Cu")
		(net "GMI_CPU0_G2_CPU1_G0_TX_DN<5>")
	)
	(segment
		(start 100.823014 -223.889062)
		(end 100.783898 -223.911922)
		(width 0.1143)
		(layer "In2.Cu")
		(net "GMI_CPU0_G2_CPU1_G0_TX_DN<5>")
	)
	(segment
		(start 100.783898 -222.93707)
		(end 100.784914 -222.937578)
		(width 0.1143)
		(layer "In2.Cu")
		(net "GMI_CPU0_G2_CPU1_G0_TX_DN<5>")
	)
	(segment
		(start 370.711984 -225.53168)
		(end 370.672868 -225.50882)
		(width 0.1143)
		(layer "In2.Cu")
		(net "GMI_CPU0_G2_CPU1_G0_TX_DN<5>")
	)
	(segment
		(start 106.430826 -207.823816)
		(end 106.134408 -208.120488)
		(width 0.14224)
		(layer "In2.Cu")
		(net "GMI_CPU0_G2_CPU1_G0_TX_DN<5>")
	)
	(segment
		(start 370.054886 -226.664266)
		(end 370.352828 -226.664266)
		(width 0.1143)
		(layer "In2.Cu")
		(net "GMI_CPU0_G2_CPU1_G0_TX_DN<5>")
	)
	(segment
		(start 101.06025 -226.581716)
		(end 101.143054 -226.66452)
		(width 0.1143)
		(layer "In2.Cu")
		(net "GMI_CPU0_G2_CPU1_G0_TX_DN<5>")
	)
	(segment
		(start 162.3314 -179.023518)
		(end 152.476454 -183.105298)
		(width 0.14224)
		(layer "In2.Cu")
		(net "GMI_CPU0_G2_CPU1_G0_TX_DN<5>")
	)
	(segment
		(start 370.711984 -222.936816)
		(end 370.742464 -222.919036)
		(width 0.1143)
		(layer "In2.Cu")
		(net "GMI_CPU0_G2_CPU1_G0_TX_DN<5>")
	)
	(segment
		(start 100.752148 -226.158806)
		(end 100.783898 -226.177094)
		(width 0.1143)
		(layer "In2.Cu")
		(net "GMI_CPU0_G2_CPU1_G0_TX_DN<5>")
	)
	(segment
		(start 103.594662 -210.469734)
		(end 103.298498 -210.765898)
		(width 0.14224)
		(layer "In2.Cu")
		(net "GMI_CPU0_G2_CPU1_G0_TX_DN<5>")
	)
	(segment
		(start 105.943908 -208.120488)
		(end 105.647744 -208.416652)
		(width 0.14224)
		(layer "In2.Cu")
		(net "GMI_CPU0_G2_CPU1_G0_TX_DN<5>")
	)
	(segment
		(start 370.711984 -224.556828)
		(end 370.742464 -224.539048)
		(width 0.1143)
		(layer "In2.Cu")
		(net "GMI_CPU0_G2_CPU1_G0_TX_DN<5>")
	)
	(segment
		(start 106.134408 -208.120488)
		(end 105.943908 -208.120488)
		(width 0.14224)
		(layer "In2.Cu")
		(net "GMI_CPU0_G2_CPU1_G0_TX_DN<5>")
	)
	(segment
		(start 105.160826 -208.90357)
		(end 104.864662 -209.199734)
		(width 0.14224)
		(layer "In2.Cu")
		(net "GMI_CPU0_G2_CPU1_G0_TX_DN<5>")
	)
	(segment
		(start 104.864662 -209.199734)
		(end 104.864662 -209.38998)
		(width 0.14224)
		(layer "In2.Cu")
		(net "GMI_CPU0_G2_CPU1_G0_TX_DN<5>")
	)
	(segment
		(start 103.298498 -210.956144)
		(end 103.00208 -211.252816)
		(width 0.14224)
		(layer "In2.Cu")
		(net "GMI_CPU0_G2_CPU1_G0_TX_DN<5>")
	)
	(segment
		(start 370.672868 -226.1997)
		(end 370.711984 -226.17684)
		(width 0.1143)
		(layer "In2.Cu")
		(net "GMI_CPU0_G2_CPU1_G0_TX_DN<5>")
	)
	(segment
		(start 102.218998 -212.035898)
		(end 102.028498 -212.035898)
		(width 0.14224)
		(layer "In2.Cu")
		(net "GMI_CPU0_G2_CPU1_G0_TX_DN<5>")
	)
	(segment
		(start 103.00208 -211.252816)
		(end 102.81158 -211.252816)
		(width 0.14224)
		(layer "In2.Cu")
		(net "GMI_CPU0_G2_CPU1_G0_TX_DN<5>")
	)
	(segment
		(start 103.785162 -210.469734)
		(end 103.594662 -210.469734)
		(width 0.14224)
		(layer "In2.Cu")
		(net "GMI_CPU0_G2_CPU1_G0_TX_DN<5>")
	)
	(arc
		(start 370.742464 -222.919036)
		(mid 370.899441 -222.614236)
		(end 370.742464 -222.309436)
		(width 0.1143)
		(layer "In2.Cu")
		(net "GMI_CPU0_G2_CPU1_G0_TX_DN<5>")
	)
	(arc
		(start 100.752148 -225.550222)
		(mid 100.603051 -225.854514)
		(end 100.752148 -226.158806)
		(width 0.1143)
		(layer "In2.Cu")
		(net "GMI_CPU0_G2_CPU1_G0_TX_DN<5>")
	)
	(arc
		(start 370.672868 -223.888808)
		(mid 370.429541 -223.424242)
		(end 370.672868 -222.959676)
		(width 0.1143)
		(layer "In2.Cu")
		(net "GMI_CPU0_G2_CPU1_G0_TX_DN<5>")
	)
	(arc
		(start 100.752148 -223.93021)
		(mid 100.601763 -224.234502)
		(end 100.752148 -224.538794)
		(width 0.1143)
		(layer "In2.Cu")
		(net "GMI_CPU0_G2_CPU1_G0_TX_DN<5>")
	)
	(arc
		(start 100.606606 -222.629984)
		(mid 100.653895 -222.806968)
		(end 100.783136 -222.936816)
		(width 0.1143)
		(layer "In2.Cu")
		(net "GMI_CPU0_G2_CPU1_G0_TX_DN<5>")
	)
	(arc
		(start 100.823014 -226.199954)
		(mid 100.975001 -226.356462)
		(end 101.05644 -226.558856)
		(width 0.1143)
		(layer "In2.Cu")
		(net "GMI_CPU0_G2_CPU1_G0_TX_DN<5>")
	)
	(arc
		(start 370.742464 -224.539048)
		(mid 370.899441 -224.234248)
		(end 370.742464 -223.929448)
		(width 0.1143)
		(layer "In2.Cu")
		(net "GMI_CPU0_G2_CPU1_G0_TX_DN<5>")
	)
	(arc
		(start 370.435632 -226.581462)
		(mid 370.43742 -226.570013)
		(end 370.439442 -226.558602)
		(width 0.1143)
		(layer "In2.Cu")
		(net "GMI_CPU0_G2_CPU1_G0_TX_DN<5>")
	)
	(arc
		(start 370.672868 -222.268796)
		(mid 370.494225 -222.066401)
		(end 370.42979 -221.80423)
		(width 0.1143)
		(layer "In2.Cu")
		(net "GMI_CPU0_G2_CPU1_G0_TX_DN<5>")
	)
	(arc
		(start 100.823014 -222.95993)
		(mid 101.066341 -223.424496)
		(end 100.823014 -223.889062)
		(width 0.1143)
		(layer "In2.Cu")
		(net "GMI_CPU0_G2_CPU1_G0_TX_DN<5>")
	)
	(arc
		(start 370.672868 -225.50882)
		(mid 370.429541 -225.044254)
		(end 370.672868 -224.579688)
		(width 0.1143)
		(layer "In2.Cu")
		(net "GMI_CPU0_G2_CPU1_G0_TX_DN<5>")
	)
	(arc
		(start 370.742464 -226.15906)
		(mid 370.899441 -225.85426)
		(end 370.742464 -225.54946)
		(width 0.1143)
		(layer "In2.Cu")
		(net "GMI_CPU0_G2_CPU1_G0_TX_DN<5>")
	)
	(arc
		(start 100.324412 -222.13316)
		(mid 100.531038 -222.340249)
		(end 100.606606 -222.622872)
		(width 0.1143)
		(layer "In2.Cu")
		(net "GMI_CPU0_G2_CPU1_G0_TX_DN<5>")
	)
	(arc
		(start 100.823014 -224.579942)
		(mid 101.066341 -225.044508)
		(end 100.823014 -225.509074)
		(width 0.1143)
		(layer "In2.Cu")
		(net "GMI_CPU0_G2_CPU1_G0_TX_DN<5>")
	)
	(arc
		(start 100.126292 -221.804484)
		(mid 100.167485 -221.975273)
		(end 100.281994 -222.108522)
		(width 0.1143)
		(layer "In2.Cu")
		(net "GMI_CPU0_G2_CPU1_G0_TX_DN<5>")
	)
	(arc
		(start 101.05644 -226.558856)
		(mid 101.058463 -226.570266)
		(end 101.06025 -226.581716)
		(width 0.1143)
		(layer "In2.Cu")
		(net "GMI_CPU0_G2_CPU1_G0_TX_DN<5>")
	)
	(arc
		(start 370.439442 -226.558602)
		(mid 370.520875 -226.356204)
		(end 370.672868 -226.1997)
		(width 0.1143)
		(layer "In2.Cu")
		(net "GMI_CPU0_G2_CPU1_G0_TX_DN<5>")
	)
	(segment
		(start 101.907848 -228.55047)
		(end 101.440996 -228.284532)
		(width 0.12954)
		(layer "F.Cu")
		(net "GMI_CPU0_G2_CPU1_G0_TX_DN<4>")
	)
	(segment
		(start 369.588034 -228.550216)
		(end 370.054886 -228.284278)
		(width 0.12954)
		(layer "F.Cu")
		(net "GMI_CPU0_G2_CPU1_G0_TX_DN<4>")
	)
	(segment
		(start 101.073204 -228.214682)
		(end 101.143054 -228.284532)
		(width 0.1143)
		(layer "In2.Cu")
		(net "GMI_CPU0_G2_CPU1_G0_TX_DN<4>")
	)
	(segment
		(start 101.692202 -226.158806)
		(end 101.717856 -226.173538)
		(width 0.1143)
		(layer "In2.Cu")
		(net "GMI_CPU0_G2_CPU1_G0_TX_DN<4>")
	)
	(segment
		(start 101.726492 -222.938594)
		(end 101.730556 -222.94088)
		(width 0.1143)
		(layer "In2.Cu")
		(net "GMI_CPU0_G2_CPU1_G0_TX_DN<4>")
	)
	(segment
		(start 101.726492 -223.910398)
		(end 101.724968 -223.911414)
		(width 0.1143)
		(layer "In2.Cu")
		(net "GMI_CPU0_G2_CPU1_G0_TX_DN<4>")
	)
	(segment
		(start 102.380796 -213.45144)
		(end 102.190296 -213.45144)
		(width 0.14224)
		(layer "In2.Cu")
		(net "GMI_CPU0_G2_CPU1_G0_TX_DN<4>")
	)
	(segment
		(start 369.419378 -218.440254)
		(end 367.674906 -214.605108)
		(width 0.14224)
		(layer "In2.Cu")
		(net "GMI_CPU0_G2_CPU1_G0_TX_DN<4>")
	)
	(segment
		(start 369.77193 -225.53168)
		(end 369.732814 -225.50882)
		(width 0.1143)
		(layer "In2.Cu")
		(net "GMI_CPU0_G2_CPU1_G0_TX_DN<4>")
	)
	(segment
		(start 107.079288 -208.752948)
		(end 106.888788 -208.752948)
		(width 0.14224)
		(layer "In2.Cu")
		(net "GMI_CPU0_G2_CPU1_G0_TX_DN<4>")
	)
	(segment
		(start 103.75646 -211.885276)
		(end 103.460296 -212.18144)
		(width 0.14224)
		(layer "In2.Cu")
		(net "GMI_CPU0_G2_CPU1_G0_TX_DN<4>")
	)
	(segment
		(start 101.720396 -223.913954)
		(end 101.719634 -223.914462)
		(width 0.1143)
		(layer "In2.Cu")
		(net "GMI_CPU0_G2_CPU1_G0_TX_DN<4>")
	)
	(segment
		(start 369.80368 -223.929956)
		(end 369.732814 -223.888808)
		(width 0.1143)
		(layer "In2.Cu")
		(net "GMI_CPU0_G2_CPU1_G0_TX_DN<4>")
	)
	(segment
		(start 101.730556 -226.180904)
		(end 101.73208 -226.18192)
		(width 0.1143)
		(layer "In2.Cu")
		(net "GMI_CPU0_G2_CPU1_G0_TX_DN<4>")
	)
	(segment
		(start 101.253798 -227.961952)
		(end 101.223318 -227.979732)
		(width 0.1143)
		(layer "In2.Cu")
		(net "GMI_CPU0_G2_CPU1_G0_TX_DN<4>")
	)
	(segment
		(start 101.717856 -223.915478)
		(end 101.71684 -223.915986)
		(width 0.1143)
		(layer "In2.Cu")
		(net "GMI_CPU0_G2_CPU1_G0_TX_DN<4>")
	)
	(segment
		(start 369.972336 -227.49637)
		(end 369.972336 -227.483924)
		(width 0.1143)
		(layer "In2.Cu")
		(net "GMI_CPU0_G2_CPU1_G0_TX_DN<4>")
	)
	(segment
		(start 101.71938 -224.554542)
		(end 101.72192 -224.555812)
		(width 0.1143)
		(layer "In2.Cu")
		(net "GMI_CPU0_G2_CPU1_G0_TX_DN<4>")
	)
	(segment
		(start 101.726492 -224.558606)
		(end 101.730556 -224.560892)
		(width 0.1143)
		(layer "In2.Cu")
		(net "GMI_CPU0_G2_CPU1_G0_TX_DN<4>")
	)
	(segment
		(start 101.730556 -224.560892)
		(end 101.73208 -224.561908)
		(width 0.1143)
		(layer "In2.Cu")
		(net "GMI_CPU0_G2_CPU1_G0_TX_DN<4>")
	)
	(segment
		(start 165.22573 -179.228496)
		(end 162.446716 -180.00726)
		(width 0.14224)
		(layer "In2.Cu")
		(net "GMI_CPU0_G2_CPU1_G0_TX_DN<4>")
	)
	(segment
		(start 101.724968 -227.151438)
		(end 101.723952 -227.151946)
		(width 0.1143)
		(layer "In2.Cu")
		(net "GMI_CPU0_G2_CPU1_G0_TX_DN<4>")
	)
	(segment
		(start 101.723952 -222.93707)
		(end 101.724968 -222.937578)
		(width 0.1143)
		(layer "In2.Cu")
		(net "GMI_CPU0_G2_CPU1_G0_TX_DN<4>")
	)
	(segment
		(start 369.80368 -224.53854)
		(end 369.823492 -224.524316)
		(width 0.1143)
		(layer "In2.Cu")
		(net "GMI_CPU0_G2_CPU1_G0_TX_DN<4>")
	)
	(segment
		(start 369.80368 -225.549968)
		(end 369.77193 -225.53168)
		(width 0.1143)
		(layer "In2.Cu")
		(net "GMI_CPU0_G2_CPU1_G0_TX_DN<4>")
	)
	(segment
		(start 152.87879 -183.969406)
		(end 108.984288 -206.657448)
		(width 0.14224)
		(layer "In2.Cu")
		(net "GMI_CPU0_G2_CPU1_G0_TX_DN<4>")
	)
	(segment
		(start 101.894132 -213.747604)
		(end 101.894132 -213.93785)
		(width 0.14224)
		(layer "In2.Cu")
		(net "GMI_CPU0_G2_CPU1_G0_TX_DN<4>")
	)
	(segment
		(start 369.77193 -226.17684)
		(end 369.80368 -226.158552)
		(width 0.1143)
		(layer "In2.Cu")
		(net "GMI_CPU0_G2_CPU1_G0_TX_DN<4>")
	)
	(segment
		(start 101.723952 -226.177094)
		(end 101.724968 -226.177602)
		(width 0.1143)
		(layer "In2.Cu")
		(net "GMI_CPU0_G2_CPU1_G0_TX_DN<4>")
	)
	(segment
		(start 101.71684 -223.915986)
		(end 101.692202 -223.93021)
		(width 0.1143)
		(layer "In2.Cu")
		(net "GMI_CPU0_G2_CPU1_G0_TX_DN<4>")
	)
	(segment
		(start 311.032906 -180.848508)
		(end 309.019956 -180.081682)
		(width 0.14224)
		(layer "In2.Cu")
		(net "GMI_CPU0_G2_CPU1_G0_TX_DN<4>")
	)
	(segment
		(start 101.723952 -223.911922)
		(end 101.72319 -223.91243)
		(width 0.1143)
		(layer "In2.Cu")
		(net "GMI_CPU0_G2_CPU1_G0_TX_DN<4>")
	)
	(segment
		(start 101.724968 -226.177602)
		(end 101.726492 -226.178618)
		(width 0.1143)
		(layer "In2.Cu")
		(net "GMI_CPU0_G2_CPU1_G0_TX_DN<4>")
	)
	(segment
		(start 101.733096 -224.562416)
		(end 101.73462 -224.563432)
		(width 0.1143)
		(layer "In2.Cu")
		(net "GMI_CPU0_G2_CPU1_G0_TX_DN<4>")
	)
	(segment
		(start 101.73208 -226.18192)
		(end 101.733096 -226.182428)
		(width 0.1143)
		(layer "In2.Cu")
		(net "GMI_CPU0_G2_CPU1_G0_TX_DN<4>")
	)
	(segment
		(start 103.94696 -211.885276)
		(end 103.75646 -211.885276)
		(width 0.14224)
		(layer "In2.Cu")
		(net "GMI_CPU0_G2_CPU1_G0_TX_DN<4>")
	)
	(segment
		(start 101.730556 -222.94088)
		(end 101.73208 -222.941896)
		(width 0.1143)
		(layer "In2.Cu")
		(net "GMI_CPU0_G2_CPU1_G0_TX_DN<4>")
	)
	(segment
		(start 105.809542 -209.832194)
		(end 105.809542 -210.02244)
		(width 0.14224)
		(layer "In2.Cu")
		(net "GMI_CPU0_G2_CPU1_G0_TX_DN<4>")
	)
	(segment
		(start 101.724968 -222.937578)
		(end 101.726492 -222.938594)
		(width 0.1143)
		(layer "In2.Cu")
		(net "GMI_CPU0_G2_CPU1_G0_TX_DN<4>")
	)
	(segment
		(start 101.726492 -225.53041)
		(end 101.724968 -225.531426)
		(width 0.1143)
		(layer "In2.Cu")
		(net "GMI_CPU0_G2_CPU1_G0_TX_DN<4>")
	)
	(segment
		(start 324.976236 -187.575698)
		(end 311.032906 -180.848508)
		(width 0.14224)
		(layer "In2.Cu")
		(net "GMI_CPU0_G2_CPU1_G0_TX_DN<4>")
	)
	(segment
		(start 370.352828 -228.284278)
		(end 370.422678 -228.214428)
		(width 0.1143)
		(layer "In2.Cu")
		(net "GMI_CPU0_G2_CPU1_G0_TX_DN<4>")
	)
	(segment
		(start 106.105706 -209.53603)
		(end 105.809542 -209.832194)
		(width 0.14224)
		(layer "In2.Cu")
		(net "GMI_CPU0_G2_CPU1_G0_TX_DN<4>")
	)
	(segment
		(start 101.717856 -224.553526)
		(end 101.71938 -224.554542)
		(width 0.1143)
		(layer "In2.Cu")
		(net "GMI_CPU0_G2_CPU1_G0_TX_DN<4>")
	)
	(segment
		(start 101.719634 -223.914462)
		(end 101.718618 -223.91497)
		(width 0.1143)
		(layer "In2.Cu")
		(net "GMI_CPU0_G2_CPU1_G0_TX_DN<4>")
	)
	(segment
		(start 370.054886 -228.284278)
		(end 370.352828 -228.284278)
		(width 0.1143)
		(layer "In2.Cu")
		(net "GMI_CPU0_G2_CPU1_G0_TX_DN<4>")
	)
	(segment
		(start 101.11105 -214.530686)
		(end 101.11105 -221.174564)
		(width 0.14224)
		(layer "In2.Cu")
		(net "GMI_CPU0_G2_CPU1_G0_TX_DN<4>")
	)
	(segment
		(start 370.27358 -227.979986)
		(end 370.242592 -227.962206)
		(width 0.1143)
		(layer "In2.Cu")
		(net "GMI_CPU0_G2_CPU1_G0_TX_DN<4>")
	)
	(segment
		(start 105.322624 -210.319112)
		(end 105.02646 -210.615276)
		(width 0.14224)
		(layer "In2.Cu")
		(net "GMI_CPU0_G2_CPU1_G0_TX_DN<4>")
	)
	(segment
		(start 305.59756 -179.193444)
		(end 235.32465 -176.825402)
		(width 0.14224)
		(layer "In2.Cu")
		(net "GMI_CPU0_G2_CPU1_G0_TX_DN<4>")
	)
	(segment
		(start 101.72319 -222.936562)
		(end 101.723952 -222.93707)
		(width 0.1143)
		(layer "In2.Cu")
		(net "GMI_CPU0_G2_CPU1_G0_TX_DN<4>")
	)
	(segment
		(start 106.592624 -209.049112)
		(end 106.592624 -209.239358)
		(width 0.14224)
		(layer "In2.Cu")
		(net "GMI_CPU0_G2_CPU1_G0_TX_DN<4>")
	)
	(segment
		(start 101.11105 -221.174564)
		(end 101.11105 -221.203012)
		(width 0.1143)
		(layer "In2.Cu")
		(net "GMI_CPU0_G2_CPU1_G0_TX_DN<4>")
	)
	(segment
		(start 101.726492 -226.178618)
		(end 101.730556 -226.180904)
		(width 0.1143)
		(layer "In2.Cu")
		(net "GMI_CPU0_G2_CPU1_G0_TX_DN<4>")
	)
	(segment
		(start 102.677214 -213.154768)
		(end 102.380796 -213.45144)
		(width 0.14224)
		(layer "In2.Cu")
		(net "GMI_CPU0_G2_CPU1_G0_TX_DN<4>")
	)
	(segment
		(start 108.984288 -206.657448)
		(end 107.375706 -208.26603)
		(width 0.14224)
		(layer "In2.Cu")
		(net "GMI_CPU0_G2_CPU1_G0_TX_DN<4>")
	)
	(segment
		(start 101.73462 -226.183444)
		(end 101.763068 -226.199954)
		(width 0.1143)
		(layer "In2.Cu")
		(net "GMI_CPU0_G2_CPU1_G0_TX_DN<4>")
	)
	(segment
		(start 101.724968 -223.911414)
		(end 101.723952 -223.911922)
		(width 0.1143)
		(layer "In2.Cu")
		(net "GMI_CPU0_G2_CPU1_G0_TX_DN<4>")
	)
	(segment
		(start 101.73208 -224.561908)
		(end 101.733096 -224.562416)
		(width 0.1143)
		(layer "In2.Cu")
		(net "GMI_CPU0_G2_CPU1_G0_TX_DN<4>")
	)
	(segment
		(start 101.71938 -222.93453)
		(end 101.72192 -222.9358)
		(width 0.1143)
		(layer "In2.Cu")
		(net "GMI_CPU0_G2_CPU1_G0_TX_DN<4>")
	)
	(segment
		(start 101.72319 -224.556574)
		(end 101.723952 -224.557082)
		(width 0.1143)
		(layer "In2.Cu")
		(net "GMI_CPU0_G2_CPU1_G0_TX_DN<4>")
	)
	(segment
		(start 357.315516 -206.737966)
		(end 324.976236 -187.575698)
		(width 0.14224)
		(layer "In2.Cu")
		(net "GMI_CPU0_G2_CPU1_G0_TX_DN<4>")
	)
	(segment
		(start 369.77193 -222.936816)
		(end 369.80368 -222.918528)
		(width 0.1143)
		(layer "In2.Cu")
		(net "GMI_CPU0_G2_CPU1_G0_TX_DN<4>")
	)
	(segment
		(start 101.763068 -225.509074)
		(end 101.726492 -225.53041)
		(width 0.1143)
		(layer "In2.Cu")
		(net "GMI_CPU0_G2_CPU1_G0_TX_DN<4>")
	)
	(segment
		(start 162.446716 -180.00726)
		(end 152.87879 -183.969406)
		(width 0.14224)
		(layer "In2.Cu")
		(net "GMI_CPU0_G2_CPU1_G0_TX_DN<4>")
	)
	(segment
		(start 106.592624 -209.239358)
		(end 106.296206 -209.53603)
		(width 0.14224)
		(layer "In2.Cu")
		(net "GMI_CPU0_G2_CPU1_G0_TX_DN<4>")
	)
	(segment
		(start 369.732814 -224.579688)
		(end 369.77193 -224.556828)
		(width 0.1143)
		(layer "In2.Cu")
		(net "GMI_CPU0_G2_CPU1_G0_TX_DN<4>")
	)
	(segment
		(start 104.539542 -211.102194)
		(end 104.243378 -211.398358)
		(width 0.14224)
		(layer "In2.Cu")
		(net "GMI_CPU0_G2_CPU1_G0_TX_DN<4>")
	)
	(segment
		(start 101.72319 -226.176586)
		(end 101.723952 -226.177094)
		(width 0.1143)
		(layer "In2.Cu")
		(net "GMI_CPU0_G2_CPU1_G0_TX_DN<4>")
	)
	(segment
		(start 369.823492 -223.94418)
		(end 369.80368 -223.929956)
		(width 0.1143)
		(layer "In2.Cu")
		(net "GMI_CPU0_G2_CPU1_G0_TX_DN<4>")
	)
	(segment
		(start 369.78463 -227.159058)
		(end 369.732814 -227.128832)
		(width 0.1143)
		(layer "In2.Cu")
		(net "GMI_CPU0_G2_CPU1_G0_TX_DN<4>")
	)
	(segment
		(start 101.692202 -224.538794)
		(end 101.717856 -224.553526)
		(width 0.1143)
		(layer "In2.Cu")
		(net "GMI_CPU0_G2_CPU1_G0_TX_DN<4>")
	)
	(segment
		(start 101.726492 -227.150422)
		(end 101.724968 -227.151438)
		(width 0.1143)
		(layer "In2.Cu")
		(net "GMI_CPU0_G2_CPU1_G0_TX_DN<4>")
	)
	(segment
		(start 235.32465 -176.825402)
		(end 165.22573 -179.228496)
		(width 0.14224)
		(layer "In2.Cu")
		(net "GMI_CPU0_G2_CPU1_G0_TX_DN<4>")
	)
	(segment
		(start 369.489736 -221.450662)
		(end 369.465098 -221.426024)
		(width 0.1143)
		(layer "In2.Cu")
		(net "GMI_CPU0_G2_CPU1_G0_TX_DN<4>")
	)
	(segment
		(start 103.163878 -212.668358)
		(end 102.973378 -212.668358)
		(width 0.14224)
		(layer "In2.Cu")
		(net "GMI_CPU0_G2_CPU1_G0_TX_DN<4>")
	)
	(segment
		(start 107.375706 -208.26603)
		(end 107.375706 -208.456276)
		(width 0.14224)
		(layer "In2.Cu")
		(net "GMI_CPU0_G2_CPU1_G0_TX_DN<4>")
	)
	(segment
		(start 101.733096 -226.182428)
		(end 101.73462 -226.183444)
		(width 0.1143)
		(layer "In2.Cu")
		(net "GMI_CPU0_G2_CPU1_G0_TX_DN<4>")
	)
	(segment
		(start 369.732814 -226.1997)
		(end 369.77193 -226.17684)
		(width 0.1143)
		(layer "In2.Cu")
		(net "GMI_CPU0_G2_CPU1_G0_TX_DN<4>")
	)
	(segment
		(start 101.723952 -224.557082)
		(end 101.724968 -224.55759)
		(width 0.1143)
		(layer "In2.Cu")
		(net "GMI_CPU0_G2_CPU1_G0_TX_DN<4>")
	)
	(segment
		(start 101.718618 -223.91497)
		(end 101.717856 -223.915478)
		(width 0.1143)
		(layer "In2.Cu")
		(net "GMI_CPU0_G2_CPU1_G0_TX_DN<4>")
	)
	(segment
		(start 101.72319 -223.91243)
		(end 101.720396 -223.913954)
		(width 0.1143)
		(layer "In2.Cu")
		(net "GMI_CPU0_G2_CPU1_G0_TX_DN<4>")
	)
	(segment
		(start 101.73462 -224.563432)
		(end 101.763068 -224.579942)
		(width 0.1143)
		(layer "In2.Cu")
		(net "GMI_CPU0_G2_CPU1_G0_TX_DN<4>")
	)
	(segment
		(start 101.73462 -222.94342)
		(end 101.763068 -222.95993)
		(width 0.1143)
		(layer "In2.Cu")
		(net "GMI_CPU0_G2_CPU1_G0_TX_DN<4>")
	)
	(segment
		(start 104.243378 -211.588604)
		(end 103.94696 -211.885276)
		(width 0.14224)
		(layer "In2.Cu")
		(net "GMI_CPU0_G2_CPU1_G0_TX_DN<4>")
	)
	(segment
		(start 369.465098 -221.128844)
		(end 369.419378 -221.083124)
		(width 0.1143)
		(layer "In2.Cu")
		(net "GMI_CPU0_G2_CPU1_G0_TX_DN<4>")
	)
	(segment
		(start 101.292914 -227.939092)
		(end 101.253798 -227.961952)
		(width 0.1143)
		(layer "In2.Cu")
		(net "GMI_CPU0_G2_CPU1_G0_TX_DN<4>")
	)
	(segment
		(start 105.02646 -210.805522)
		(end 104.730042 -211.102194)
		(width 0.14224)
		(layer "In2.Cu")
		(net "GMI_CPU0_G2_CPU1_G0_TX_DN<4>")
	)
	(segment
		(start 363.316774 -210.805268)
		(end 357.315516 -206.737966)
		(width 0.14224)
		(layer "In2.Cu")
		(net "GMI_CPU0_G2_CPU1_G0_TX_DN<4>")
	)
	(segment
		(start 107.375706 -208.456276)
		(end 107.079288 -208.752948)
		(width 0.14224)
		(layer "In2.Cu")
		(net "GMI_CPU0_G2_CPU1_G0_TX_DN<4>")
	)
	(segment
		(start 101.894132 -213.93785)
		(end 101.597714 -214.234522)
		(width 0.14224)
		(layer "In2.Cu")
		(net "GMI_CPU0_G2_CPU1_G0_TX_DN<4>")
	)
	(segment
		(start 101.733096 -222.942404)
		(end 101.73462 -222.94342)
		(width 0.1143)
		(layer "In2.Cu")
		(net "GMI_CPU0_G2_CPU1_G0_TX_DN<4>")
	)
	(segment
		(start 105.513124 -210.319112)
		(end 105.322624 -210.319112)
		(width 0.14224)
		(layer "In2.Cu")
		(net "GMI_CPU0_G2_CPU1_G0_TX_DN<4>")
	)
	(segment
		(start 101.06533 -221.794832)
		(end 101.066854 -221.824042)
		(width 0.1143)
		(layer "In2.Cu")
		(net "GMI_CPU0_G2_CPU1_G0_TX_DN<4>")
	)
	(segment
		(start 101.763068 -227.129086)
		(end 101.726492 -227.150422)
		(width 0.1143)
		(layer "In2.Cu")
		(net "GMI_CPU0_G2_CPU1_G0_TX_DN<4>")
	)
	(segment
		(start 101.72192 -224.555812)
		(end 101.72319 -224.556574)
		(width 0.1143)
		(layer "In2.Cu")
		(net "GMI_CPU0_G2_CPU1_G0_TX_DN<4>")
	)
	(segment
		(start 105.809542 -210.02244)
		(end 105.513124 -210.319112)
		(width 0.14224)
		(layer "In2.Cu")
		(net "GMI_CPU0_G2_CPU1_G0_TX_DN<4>")
	)
	(segment
		(start 101.221286 -222.108014)
		(end 101.291644 -222.148908)
		(width 0.1143)
		(layer "In2.Cu")
		(net "GMI_CPU0_G2_CPU1_G0_TX_DN<4>")
	)
	(segment
		(start 369.77193 -224.556828)
		(end 369.80368 -224.53854)
		(width 0.1143)
		(layer "In2.Cu")
		(net "GMI_CPU0_G2_CPU1_G0_TX_DN<4>")
	)
	(segment
		(start 369.419378 -221.083124)
		(end 369.419378 -218.440254)
		(width 0.14224)
		(layer "In2.Cu")
		(net "GMI_CPU0_G2_CPU1_G0_TX_DN<4>")
	)
	(segment
		(start 101.692202 -222.918782)
		(end 101.717856 -222.933514)
		(width 0.1143)
		(layer "In2.Cu")
		(net "GMI_CPU0_G2_CPU1_G0_TX_DN<4>")
	)
	(segment
		(start 104.243378 -211.398358)
		(end 104.243378 -211.588604)
		(width 0.14224)
		(layer "In2.Cu")
		(net "GMI_CPU0_G2_CPU1_G0_TX_DN<4>")
	)
	(segment
		(start 101.407214 -214.234522)
		(end 101.11105 -214.530686)
		(width 0.14224)
		(layer "In2.Cu")
		(net "GMI_CPU0_G2_CPU1_G0_TX_DN<4>")
	)
	(segment
		(start 369.489736 -221.80423)
		(end 369.489736 -221.450662)
		(width 0.1143)
		(layer "In2.Cu")
		(net "GMI_CPU0_G2_CPU1_G0_TX_DN<4>")
	)
	(segment
		(start 105.02646 -210.615276)
		(end 105.02646 -210.805522)
		(width 0.14224)
		(layer "In2.Cu")
		(net "GMI_CPU0_G2_CPU1_G0_TX_DN<4>")
	)
	(segment
		(start 101.06533 -221.248732)
		(end 101.06533 -221.794832)
		(width 0.1143)
		(layer "In2.Cu")
		(net "GMI_CPU0_G2_CPU1_G0_TX_DN<4>")
	)
	(segment
		(start 369.465098 -221.426024)
		(end 369.465098 -221.128844)
		(width 0.1143)
		(layer "In2.Cu")
		(net "GMI_CPU0_G2_CPU1_G0_TX_DN<4>")
	)
	(segment
		(start 101.723952 -225.531934)
		(end 101.692202 -225.550222)
		(width 0.1143)
		(layer "In2.Cu")
		(net "GMI_CPU0_G2_CPU1_G0_TX_DN<4>")
	)
	(segment
		(start 104.730042 -211.102194)
		(end 104.539542 -211.102194)
		(width 0.14224)
		(layer "In2.Cu")
		(net "GMI_CPU0_G2_CPU1_G0_TX_DN<4>")
	)
	(segment
		(start 101.717856 -222.933514)
		(end 101.71938 -222.93453)
		(width 0.1143)
		(layer "In2.Cu")
		(net "GMI_CPU0_G2_CPU1_G0_TX_DN<4>")
	)
	(segment
		(start 101.724968 -224.55759)
		(end 101.726492 -224.558606)
		(width 0.1143)
		(layer "In2.Cu")
		(net "GMI_CPU0_G2_CPU1_G0_TX_DN<4>")
	)
	(segment
		(start 370.24183 -227.961698)
		(end 370.239544 -227.960428)
		(width 0.1143)
		(layer "In2.Cu")
		(net "GMI_CPU0_G2_CPU1_G0_TX_DN<4>")
	)
	(segment
		(start 101.72192 -226.175824)
		(end 101.72319 -226.176586)
		(width 0.1143)
		(layer "In2.Cu")
		(net "GMI_CPU0_G2_CPU1_G0_TX_DN<4>")
	)
	(segment
		(start 101.11105 -221.203012)
		(end 101.06533 -221.248732)
		(width 0.1143)
		(layer "In2.Cu")
		(net "GMI_CPU0_G2_CPU1_G0_TX_DN<4>")
	)
	(segment
		(start 102.973378 -212.668358)
		(end 102.677214 -212.964522)
		(width 0.14224)
		(layer "In2.Cu")
		(net "GMI_CPU0_G2_CPU1_G0_TX_DN<4>")
	)
	(segment
		(start 101.724968 -225.531426)
		(end 101.723952 -225.531934)
		(width 0.1143)
		(layer "In2.Cu")
		(net "GMI_CPU0_G2_CPU1_G0_TX_DN<4>")
	)
	(segment
		(start 106.296206 -209.53603)
		(end 106.105706 -209.53603)
		(width 0.14224)
		(layer "In2.Cu")
		(net "GMI_CPU0_G2_CPU1_G0_TX_DN<4>")
	)
	(segment
		(start 102.190296 -213.45144)
		(end 101.894132 -213.747604)
		(width 0.14224)
		(layer "In2.Cu")
		(net "GMI_CPU0_G2_CPU1_G0_TX_DN<4>")
	)
	(segment
		(start 369.732814 -222.959676)
		(end 369.77193 -222.936816)
		(width 0.1143)
		(layer "In2.Cu")
		(net "GMI_CPU0_G2_CPU1_G0_TX_DN<4>")
	)
	(segment
		(start 101.73208 -222.941896)
		(end 101.733096 -222.942404)
		(width 0.1143)
		(layer "In2.Cu")
		(net "GMI_CPU0_G2_CPU1_G0_TX_DN<4>")
	)
	(segment
		(start 369.80368 -222.309944)
		(end 369.732814 -222.268796)
		(width 0.1143)
		(layer "In2.Cu")
		(net "GMI_CPU0_G2_CPU1_G0_TX_DN<4>")
	)
	(segment
		(start 101.763068 -223.889062)
		(end 101.726492 -223.910398)
		(width 0.1143)
		(layer "In2.Cu")
		(net "GMI_CPU0_G2_CPU1_G0_TX_DN<4>")
	)
	(segment
		(start 370.242592 -227.962206)
		(end 370.24183 -227.961698)
		(width 0.1143)
		(layer "In2.Cu")
		(net "GMI_CPU0_G2_CPU1_G0_TX_DN<4>")
	)
	(segment
		(start 367.674906 -214.605108)
		(end 363.316774 -210.805268)
		(width 0.14224)
		(layer "In2.Cu")
		(net "GMI_CPU0_G2_CPU1_G0_TX_DN<4>")
	)
	(segment
		(start 101.71938 -226.174554)
		(end 101.72192 -226.175824)
		(width 0.1143)
		(layer "In2.Cu")
		(net "GMI_CPU0_G2_CPU1_G0_TX_DN<4>")
	)
	(segment
		(start 101.597714 -214.234522)
		(end 101.407214 -214.234522)
		(width 0.14224)
		(layer "In2.Cu")
		(net "GMI_CPU0_G2_CPU1_G0_TX_DN<4>")
	)
	(segment
		(start 103.460296 -212.371686)
		(end 103.163878 -212.668358)
		(width 0.14224)
		(layer "In2.Cu")
		(net "GMI_CPU0_G2_CPU1_G0_TX_DN<4>")
	)
	(segment
		(start 103.460296 -212.18144)
		(end 103.460296 -212.371686)
		(width 0.14224)
		(layer "In2.Cu")
		(net "GMI_CPU0_G2_CPU1_G0_TX_DN<4>")
	)
	(segment
		(start 309.019956 -180.081682)
		(end 305.59756 -179.193444)
		(width 0.14224)
		(layer "In2.Cu")
		(net "GMI_CPU0_G2_CPU1_G0_TX_DN<4>")
	)
	(segment
		(start 101.143054 -228.284532)
		(end 101.440996 -228.284532)
		(width 0.1143)
		(layer "In2.Cu")
		(net "GMI_CPU0_G2_CPU1_G0_TX_DN<4>")
	)
	(segment
		(start 101.723952 -227.151946)
		(end 101.692202 -227.170234)
		(width 0.1143)
		(layer "In2.Cu")
		(net "GMI_CPU0_G2_CPU1_G0_TX_DN<4>")
	)
	(segment
		(start 101.72192 -222.9358)
		(end 101.72319 -222.936562)
		(width 0.1143)
		(layer "In2.Cu")
		(net "GMI_CPU0_G2_CPU1_G0_TX_DN<4>")
	)
	(segment
		(start 106.888788 -208.752948)
		(end 106.592624 -209.049112)
		(width 0.14224)
		(layer "In2.Cu")
		(net "GMI_CPU0_G2_CPU1_G0_TX_DN<4>")
	)
	(segment
		(start 101.717856 -226.173538)
		(end 101.71938 -226.174554)
		(width 0.1143)
		(layer "In2.Cu")
		(net "GMI_CPU0_G2_CPU1_G0_TX_DN<4>")
	)
	(segment
		(start 102.677214 -212.964522)
		(end 102.677214 -213.154768)
		(width 0.14224)
		(layer "In2.Cu")
		(net "GMI_CPU0_G2_CPU1_G0_TX_DN<4>")
	)
	(arc
		(start 101.291644 -222.148908)
		(mid 101.471373 -222.351528)
		(end 101.536246 -222.61449)
		(width 0.1143)
		(layer "In2.Cu")
		(net "GMI_CPU0_G2_CPU1_G0_TX_DN<4>")
	)
	(arc
		(start 101.536246 -222.61449)
		(mid 101.577501 -222.785461)
		(end 101.692202 -222.918782)
		(width 0.1143)
		(layer "In2.Cu")
		(net "GMI_CPU0_G2_CPU1_G0_TX_DN<4>")
	)
	(arc
		(start 369.80368 -226.158552)
		(mid 369.955269 -225.85426)
		(end 369.80368 -225.549968)
		(width 0.1143)
		(layer "In2.Cu")
		(net "GMI_CPU0_G2_CPU1_G0_TX_DN<4>")
	)
	(arc
		(start 101.692202 -225.550222)
		(mid 101.536274 -225.854514)
		(end 101.692202 -226.158806)
		(width 0.1143)
		(layer "In2.Cu")
		(net "GMI_CPU0_G2_CPU1_G0_TX_DN<4>")
	)
	(arc
		(start 370.239544 -227.960428)
		(mid 370.04387 -227.76413)
		(end 369.972336 -227.49637)
		(width 0.1143)
		(layer "In2.Cu")
		(net "GMI_CPU0_G2_CPU1_G0_TX_DN<4>")
	)
	(arc
		(start 369.732814 -222.268796)
		(mid 369.554156 -222.066396)
		(end 369.489736 -221.80423)
		(width 0.1143)
		(layer "In2.Cu")
		(net "GMI_CPU0_G2_CPU1_G0_TX_DN<4>")
	)
	(arc
		(start 369.732814 -227.128832)
		(mid 369.489487 -226.664266)
		(end 369.732814 -226.1997)
		(width 0.1143)
		(layer "In2.Cu")
		(net "GMI_CPU0_G2_CPU1_G0_TX_DN<4>")
	)
	(arc
		(start 370.422678 -228.214428)
		(mid 370.370629 -228.082909)
		(end 370.27358 -227.979986)
		(width 0.1143)
		(layer "In2.Cu")
		(net "GMI_CPU0_G2_CPU1_G0_TX_DN<4>")
	)
	(arc
		(start 369.80368 -222.918528)
		(mid 369.955269 -222.614236)
		(end 369.80368 -222.309944)
		(width 0.1143)
		(layer "In2.Cu")
		(net "GMI_CPU0_G2_CPU1_G0_TX_DN<4>")
	)
	(arc
		(start 369.732814 -223.888808)
		(mid 369.489487 -223.424242)
		(end 369.732814 -222.959676)
		(width 0.1143)
		(layer "In2.Cu")
		(net "GMI_CPU0_G2_CPU1_G0_TX_DN<4>")
	)
	(arc
		(start 369.823492 -224.524316)
		(mid 369.972206 -224.234248)
		(end 369.823492 -223.94418)
		(width 0.1143)
		(layer "In2.Cu")
		(net "GMI_CPU0_G2_CPU1_G0_TX_DN<4>")
	)
	(arc
		(start 369.972336 -227.483924)
		(mid 369.92203 -227.296336)
		(end 369.78463 -227.159058)
		(width 0.1143)
		(layer "In2.Cu")
		(net "GMI_CPU0_G2_CPU1_G0_TX_DN<4>")
	)
	(arc
		(start 101.536246 -227.474526)
		(mid 101.471731 -227.736745)
		(end 101.292914 -227.939092)
		(width 0.1143)
		(layer "In2.Cu")
		(net "GMI_CPU0_G2_CPU1_G0_TX_DN<4>")
	)
	(arc
		(start 101.763068 -226.199954)
		(mid 102.006395 -226.66452)
		(end 101.763068 -227.129086)
		(width 0.1143)
		(layer "In2.Cu")
		(net "GMI_CPU0_G2_CPU1_G0_TX_DN<4>")
	)
	(arc
		(start 101.763068 -222.95993)
		(mid 102.006395 -223.424496)
		(end 101.763068 -223.889062)
		(width 0.1143)
		(layer "In2.Cu")
		(net "GMI_CPU0_G2_CPU1_G0_TX_DN<4>")
	)
	(arc
		(start 101.692202 -223.93021)
		(mid 101.536274 -224.234502)
		(end 101.692202 -224.538794)
		(width 0.1143)
		(layer "In2.Cu")
		(net "GMI_CPU0_G2_CPU1_G0_TX_DN<4>")
	)
	(arc
		(start 369.732814 -225.50882)
		(mid 369.489487 -225.044254)
		(end 369.732814 -224.579688)
		(width 0.1143)
		(layer "In2.Cu")
		(net "GMI_CPU0_G2_CPU1_G0_TX_DN<4>")
	)
	(arc
		(start 101.763068 -224.579942)
		(mid 102.006395 -225.044508)
		(end 101.763068 -225.509074)
		(width 0.1143)
		(layer "In2.Cu")
		(net "GMI_CPU0_G2_CPU1_G0_TX_DN<4>")
	)
	(arc
		(start 101.692202 -227.170234)
		(mid 101.577526 -227.303568)
		(end 101.536246 -227.474526)
		(width 0.1143)
		(layer "In2.Cu")
		(net "GMI_CPU0_G2_CPU1_G0_TX_DN<4>")
	)
	(arc
		(start 101.066854 -221.824042)
		(mid 101.07589 -221.88816)
		(end 101.09581 -221.949772)
		(width 0.1143)
		(layer "In2.Cu")
		(net "GMI_CPU0_G2_CPU1_G0_TX_DN<4>")
	)
	(arc
		(start 101.09581 -221.949772)
		(mid 101.147683 -222.037509)
		(end 101.221286 -222.108014)
		(width 0.1143)
		(layer "In2.Cu")
		(net "GMI_CPU0_G2_CPU1_G0_TX_DN<4>")
	)
	(arc
		(start 101.223318 -227.979732)
		(mid 101.125553 -228.082708)
		(end 101.073204 -228.214682)
		(width 0.1143)
		(layer "In2.Cu")
		(net "GMI_CPU0_G2_CPU1_G0_TX_DN<4>")
	)
	(segment
		(start 372.407942 -230.169974)
		(end 372.874794 -229.904036)
		(width 0.12954)
		(layer "F.Cu")
		(net "GMI_CPU0_G2_CPU1_G0_TX_DN<3>")
	)
	(segment
		(start 99.08794 -230.170228)
		(end 98.621088 -229.90429)
		(width 0.12954)
		(layer "F.Cu")
		(net "GMI_CPU0_G2_CPU1_G0_TX_DN<3>")
	)
	(segment
		(start 99.41306 -227.939092)
		(end 99.373944 -227.961952)
		(width 0.1143)
		(layer "In2.Cu")
		(net "GMI_CPU0_G2_CPU1_G0_TX_DN<3>")
	)
	(segment
		(start 371.678454 -227.167186)
		(end 371.677438 -227.166678)
		(width 0.1143)
		(layer "In2.Cu")
		(net "GMI_CPU0_G2_CPU1_G0_TX_DN<3>")
	)
	(segment
		(start 104.999028 -207.507332)
		(end 104.702864 -207.803496)
		(width 0.14224)
		(layer "In2.Cu")
		(net "GMI_CPU0_G2_CPU1_G0_TX_DN<3>")
	)
	(segment
		(start 100.787454 -211.909152)
		(end 100.491036 -212.205824)
		(width 0.14224)
		(layer "In2.Cu")
		(net "GMI_CPU0_G2_CPU1_G0_TX_DN<3>")
	)
	(segment
		(start 101.570536 -210.935824)
		(end 101.570536 -211.12607)
		(width 0.14224)
		(layer "In2.Cu")
		(net "GMI_CPU0_G2_CPU1_G0_TX_DN<3>")
	)
	(segment
		(start 99.83978 -223.914462)
		(end 99.837748 -223.915478)
		(width 0.1143)
		(layer "In2.Cu")
		(net "GMI_CPU0_G2_CPU1_G0_TX_DN<3>")
	)
	(segment
		(start 99.865688 -225.519234)
		(end 99.861624 -225.523552)
		(width 0.1143)
		(layer "In2.Cu")
		(net "GMI_CPU0_G2_CPU1_G0_TX_DN<3>")
	)
	(segment
		(start 371.369336 -221.248478)
		(end 371.323616 -221.202758)
		(width 0.1143)
		(layer "In2.Cu")
		(net "GMI_CPU0_G2_CPU1_G0_TX_DN<3>")
	)
	(segment
		(start 372.13413 -227.981256)
		(end 372.095268 -227.958396)
		(width 0.1143)
		(layer "In2.Cu")
		(net "GMI_CPU0_G2_CPU1_G0_TX_DN<3>")
	)
	(segment
		(start 371.652546 -225.532188)
		(end 371.651784 -225.53168)
		(width 0.1143)
		(layer "In2.Cu")
		(net "GMI_CPU0_G2_CPU1_G0_TX_DN<3>")
	)
	(segment
		(start 98.94316 -228.749098)
		(end 98.906584 -228.770434)
		(width 0.1143)
		(layer "In2.Cu")
		(net "GMI_CPU0_G2_CPU1_G0_TX_DN<3>")
	)
	(segment
		(start 371.323616 -221.17431)
		(end 371.323616 -218.03106)
		(width 0.14224)
		(layer "In2.Cu")
		(net "GMI_CPU0_G2_CPU1_G0_TX_DN<3>")
	)
	(segment
		(start 103.1367 -209.559906)
		(end 102.840282 -209.856578)
		(width 0.14224)
		(layer "In2.Cu")
		(net "GMI_CPU0_G2_CPU1_G0_TX_DN<3>")
	)
	(segment
		(start 371.36959 -221.80423)
		(end 371.36959 -221.624906)
		(width 0.1143)
		(layer "In2.Cu")
		(net "GMI_CPU0_G2_CPU1_G0_TX_DN<3>")
	)
	(segment
		(start 99.846892 -222.938848)
		(end 99.88296 -222.959676)
		(width 0.1143)
		(layer "In2.Cu")
		(net "GMI_CPU0_G2_CPU1_G0_TX_DN<3>")
	)
	(segment
		(start 103.623364 -209.073496)
		(end 103.432864 -209.073496)
		(width 0.14224)
		(layer "In2.Cu")
		(net "GMI_CPU0_G2_CPU1_G0_TX_DN<3>")
	)
	(segment
		(start 371.681756 -227.169218)
		(end 371.678454 -227.167186)
		(width 0.1143)
		(layer "In2.Cu")
		(net "GMI_CPU0_G2_CPU1_G0_TX_DN<3>")
	)
	(segment
		(start 371.649244 -227.150168)
		(end 371.612668 -227.128832)
		(width 0.1143)
		(layer "In2.Cu")
		(net "GMI_CPU0_G2_CPU1_G0_TX_DN<3>")
	)
	(segment
		(start 100.300536 -212.205824)
		(end 100.004372 -212.501988)
		(width 0.14224)
		(layer "In2.Cu")
		(net "GMI_CPU0_G2_CPU1_G0_TX_DN<3>")
	)
	(segment
		(start 234.68076 -174.830994)
		(end 164.751004 -177.337974)
		(width 0.14224)
		(layer "In2.Cu")
		(net "GMI_CPU0_G2_CPU1_G0_TX_DN<3>")
	)
	(segment
		(start 371.615462 -222.957644)
		(end 371.651784 -222.936816)
		(width 0.1143)
		(layer "In2.Cu")
		(net "GMI_CPU0_G2_CPU1_G0_TX_DN<3>")
	)
	(segment
		(start 372.30939 -228.284024)
		(end 372.30939 -228.283516)
		(width 0.1143)
		(layer "In2.Cu")
		(net "GMI_CPU0_G2_CPU1_G0_TX_DN<3>")
	)
	(segment
		(start 104.702864 -207.993742)
		(end 104.406446 -208.290414)
		(width 0.14224)
		(layer "In2.Cu")
		(net "GMI_CPU0_G2_CPU1_G0_TX_DN<3>")
	)
	(segment
		(start 371.683534 -225.549968)
		(end 371.652546 -225.532188)
		(width 0.1143)
		(layer "In2.Cu")
		(net "GMI_CPU0_G2_CPU1_G0_TX_DN<3>")
	)
	(segment
		(start 99.844098 -226.177094)
		(end 99.88042 -226.198176)
		(width 0.1143)
		(layer "In2.Cu")
		(net "GMI_CPU0_G2_CPU1_G0_TX_DN<3>")
	)
	(segment
		(start 371.682772 -227.169726)
		(end 371.681756 -227.169218)
		(width 0.1143)
		(layer "In2.Cu")
		(net "GMI_CPU0_G2_CPU1_G0_TX_DN<3>")
	)
	(segment
		(start 371.651784 -222.936816)
		(end 371.652546 -222.936308)
		(width 0.1143)
		(layer "In2.Cu")
		(net "GMI_CPU0_G2_CPU1_G0_TX_DN<3>")
	)
	(segment
		(start 371.652546 -222.936308)
		(end 371.653816 -222.935546)
		(width 0.1143)
		(layer "In2.Cu")
		(net "GMI_CPU0_G2_CPU1_G0_TX_DN<3>")
	)
	(segment
		(start 98.253296 -229.83444)
		(end 98.323146 -229.90429)
		(width 0.1143)
		(layer "In2.Cu")
		(net "GMI_CPU0_G2_CPU1_G0_TX_DN<3>")
	)
	(segment
		(start 364.617762 -209.382106)
		(end 357.655876 -204.670406)
		(width 0.14224)
		(layer "In2.Cu")
		(net "GMI_CPU0_G2_CPU1_G0_TX_DN<3>")
	)
	(segment
		(start 103.432864 -209.073496)
		(end 103.1367 -209.36966)
		(width 0.14224)
		(layer "In2.Cu")
		(net "GMI_CPU0_G2_CPU1_G0_TX_DN<3>")
	)
	(segment
		(start 99.186746 -221.248732)
		(end 99.186746 -221.624906)
		(width 0.1143)
		(layer "In2.Cu")
		(net "GMI_CPU0_G2_CPU1_G0_TX_DN<3>")
	)
	(segment
		(start 99.83978 -227.154486)
		(end 99.837748 -227.155502)
		(width 0.1143)
		(layer "In2.Cu")
		(net "GMI_CPU0_G2_CPU1_G0_TX_DN<3>")
	)
	(segment
		(start 99.843336 -225.532442)
		(end 99.842066 -225.533204)
		(width 0.1143)
		(layer "In2.Cu")
		(net "GMI_CPU0_G2_CPU1_G0_TX_DN<3>")
	)
	(segment
		(start 371.612668 -224.579688)
		(end 371.651784 -224.556828)
		(width 0.1143)
		(layer "In2.Cu")
		(net "GMI_CPU0_G2_CPU1_G0_TX_DN<3>")
	)
	(segment
		(start 99.812348 -226.158806)
		(end 99.842066 -226.175824)
		(width 0.1143)
		(layer "In2.Cu")
		(net "GMI_CPU0_G2_CPU1_G0_TX_DN<3>")
	)
	(segment
		(start 99.843336 -222.936562)
		(end 99.844098 -222.93707)
		(width 0.1143)
		(layer "In2.Cu")
		(net "GMI_CPU0_G2_CPU1_G0_TX_DN<3>")
	)
	(segment
		(start 371.683534 -223.929956)
		(end 371.652546 -223.912176)
		(width 0.1143)
		(layer "In2.Cu")
		(net "GMI_CPU0_G2_CPU1_G0_TX_DN<3>")
	)
	(segment
		(start 373.095266 -229.601268)
		(end 373.061738 -229.58171)
		(width 0.1143)
		(layer "In2.Cu")
		(net "GMI_CPU0_G2_CPU1_G0_TX_DN<3>")
	)
	(segment
		(start 357.655876 -204.670406)
		(end 326.17664 -186.050936)
		(width 0.14224)
		(layer "In2.Cu")
		(net "GMI_CPU0_G2_CPU1_G0_TX_DN<3>")
	)
	(segment
		(start 371.651784 -224.556828)
		(end 371.652546 -224.55632)
		(width 0.1143)
		(layer "In2.Cu")
		(net "GMI_CPU0_G2_CPU1_G0_TX_DN<3>")
	)
	(segment
		(start 99.83978 -225.534474)
		(end 99.837748 -225.53549)
		(width 0.1143)
		(layer "In2.Cu")
		(net "GMI_CPU0_G2_CPU1_G0_TX_DN<3>")
	)
	(segment
		(start 99.840542 -227.153978)
		(end 99.83978 -227.154486)
		(width 0.1143)
		(layer "In2.Cu")
		(net "GMI_CPU0_G2_CPU1_G0_TX_DN<3>")
	)
	(segment
		(start 371.652546 -227.1522)
		(end 371.651784 -227.151692)
		(width 0.1143)
		(layer "In2.Cu")
		(net "GMI_CPU0_G2_CPU1_G0_TX_DN<3>")
	)
	(segment
		(start 98.90506 -228.77145)
		(end 98.904044 -228.771958)
		(width 0.1143)
		(layer "In2.Cu")
		(net "GMI_CPU0_G2_CPU1_G0_TX_DN<3>")
	)
	(segment
		(start 371.653816 -224.555558)
		(end 371.683534 -224.53854)
		(width 0.1143)
		(layer "In2.Cu")
		(net "GMI_CPU0_G2_CPU1_G0_TX_DN<3>")
	)
	(segment
		(start 99.844098 -224.557082)
		(end 99.846892 -224.55886)
		(width 0.1143)
		(layer "In2.Cu")
		(net "GMI_CPU0_G2_CPU1_G0_TX_DN<3>")
	)
	(segment
		(start 371.652546 -223.912176)
		(end 371.651784 -223.911668)
		(width 0.1143)
		(layer "In2.Cu")
		(net "GMI_CPU0_G2_CPU1_G0_TX_DN<3>")
	)
	(segment
		(start 371.651784 -225.53168)
		(end 371.650768 -225.531172)
		(width 0.1143)
		(layer "In2.Cu")
		(net "GMI_CPU0_G2_CPU1_G0_TX_DN<3>")
	)
	(segment
		(start 98.904044 -228.771958)
		(end 98.903282 -228.772466)
		(width 0.1143)
		(layer "In2.Cu")
		(net "GMI_CPU0_G2_CPU1_G0_TX_DN<3>")
	)
	(segment
		(start 309.787798 -178.2953)
		(end 305.881532 -177.28184)
		(width 0.14224)
		(layer "In2.Cu")
		(net "GMI_CPU0_G2_CPU1_G0_TX_DN<3>")
	)
	(segment
		(start 101.8667 -210.63966)
		(end 101.570536 -210.935824)
		(width 0.14224)
		(layer "In2.Cu")
		(net "GMI_CPU0_G2_CPU1_G0_TX_DN<3>")
	)
	(segment
		(start 371.653816 -222.935546)
		(end 371.683534 -222.918528)
		(width 0.1143)
		(layer "In2.Cu")
		(net "GMI_CPU0_G2_CPU1_G0_TX_DN<3>")
	)
	(segment
		(start 103.1367 -209.36966)
		(end 103.1367 -209.559906)
		(width 0.14224)
		(layer "In2.Cu")
		(net "GMI_CPU0_G2_CPU1_G0_TX_DN<3>")
	)
	(segment
		(start 371.651784 -227.151692)
		(end 371.650768 -227.151184)
		(width 0.1143)
		(layer "In2.Cu")
		(net "GMI_CPU0_G2_CPU1_G0_TX_DN<3>")
	)
	(segment
		(start 99.843336 -223.91243)
		(end 99.842066 -223.913192)
		(width 0.1143)
		(layer "In2.Cu")
		(net "GMI_CPU0_G2_CPU1_G0_TX_DN<3>")
	)
	(segment
		(start 371.650768 -225.531172)
		(end 371.649244 -225.530156)
		(width 0.1143)
		(layer "In2.Cu")
		(net "GMI_CPU0_G2_CPU1_G0_TX_DN<3>")
	)
	(segment
		(start 99.845622 -223.910906)
		(end 99.843336 -223.91243)
		(width 0.1143)
		(layer "In2.Cu")
		(net "GMI_CPU0_G2_CPU1_G0_TX_DN<3>")
	)
	(segment
		(start 99.812348 -222.918782)
		(end 99.842066 -222.9358)
		(width 0.1143)
		(layer "In2.Cu")
		(net "GMI_CPU0_G2_CPU1_G0_TX_DN<3>")
	)
	(segment
		(start 99.232466 -221.203012)
		(end 99.186746 -221.248732)
		(width 0.1143)
		(layer "In2.Cu")
		(net "GMI_CPU0_G2_CPU1_G0_TX_DN<3>")
	)
	(segment
		(start 105.485946 -207.21066)
		(end 105.189528 -207.507332)
		(width 0.14224)
		(layer "In2.Cu")
		(net "GMI_CPU0_G2_CPU1_G0_TX_DN<3>")
	)
	(segment
		(start 371.612668 -222.959676)
		(end 371.615462 -222.957644)
		(width 0.1143)
		(layer "In2.Cu")
		(net "GMI_CPU0_G2_CPU1_G0_TX_DN<3>")
	)
	(segment
		(start 98.903282 -228.772466)
		(end 98.902012 -228.773228)
		(width 0.1143)
		(layer "In2.Cu")
		(net "GMI_CPU0_G2_CPU1_G0_TX_DN<3>")
	)
	(segment
		(start 98.473006 -229.559104)
		(end 98.43389 -229.581964)
		(width 0.1143)
		(layer "In2.Cu")
		(net "GMI_CPU0_G2_CPU1_G0_TX_DN<3>")
	)
	(segment
		(start 99.842066 -223.913192)
		(end 99.840542 -223.913954)
		(width 0.1143)
		(layer "In2.Cu")
		(net "GMI_CPU0_G2_CPU1_G0_TX_DN<3>")
	)
	(segment
		(start 99.842066 -224.555812)
		(end 99.843336 -224.556574)
		(width 0.1143)
		(layer "In2.Cu")
		(net "GMI_CPU0_G2_CPU1_G0_TX_DN<3>")
	)
	(segment
		(start 99.88042 -227.130864)
		(end 99.844098 -227.151946)
		(width 0.1143)
		(layer "In2.Cu")
		(net "GMI_CPU0_G2_CPU1_G0_TX_DN<3>")
	)
	(segment
		(start 99.843844 -225.532442)
		(end 99.843336 -225.532442)
		(width 0.1143)
		(layer "In2.Cu")
		(net "GMI_CPU0_G2_CPU1_G0_TX_DN<3>")
	)
	(segment
		(start 100.004372 -212.501988)
		(end 100.004372 -212.692234)
		(width 0.14224)
		(layer "In2.Cu")
		(net "GMI_CPU0_G2_CPU1_G0_TX_DN<3>")
	)
	(segment
		(start 98.43389 -229.581964)
		(end 98.401378 -229.60076)
		(width 0.1143)
		(layer "In2.Cu")
		(net "GMI_CPU0_G2_CPU1_G0_TX_DN<3>")
	)
	(segment
		(start 98.323146 -229.90429)
		(end 98.621088 -229.90429)
		(width 0.1143)
		(layer "In2.Cu")
		(net "GMI_CPU0_G2_CPU1_G0_TX_DN<3>")
	)
	(segment
		(start 371.852444 -227.494338)
		(end 371.852444 -227.46716)
		(width 0.1143)
		(layer "In2.Cu")
		(net "GMI_CPU0_G2_CPU1_G0_TX_DN<3>")
	)
	(segment
		(start 105.189528 -207.507332)
		(end 104.999028 -207.507332)
		(width 0.14224)
		(layer "In2.Cu")
		(net "GMI_CPU0_G2_CPU1_G0_TX_DN<3>")
	)
	(segment
		(start 372.593362 -228.77272)
		(end 372.592092 -228.772974)
		(width 0.1143)
		(layer "In2.Cu")
		(net "GMI_CPU0_G2_CPU1_G0_TX_DN<3>")
	)
	(segment
		(start 99.88296 -222.959676)
		(end 99.9109 -222.979742)
		(width 0.1143)
		(layer "In2.Cu")
		(net "GMI_CPU0_G2_CPU1_G0_TX_DN<3>")
	)
	(segment
		(start 99.373944 -222.127064)
		(end 99.41306 -222.149924)
		(width 0.1143)
		(layer "In2.Cu")
		(net "GMI_CPU0_G2_CPU1_G0_TX_DN<3>")
	)
	(segment
		(start 104.702864 -207.803496)
		(end 104.702864 -207.993742)
		(width 0.14224)
		(layer "In2.Cu")
		(net "GMI_CPU0_G2_CPU1_G0_TX_DN<3>")
	)
	(segment
		(start 371.650768 -223.91116)
		(end 371.649244 -223.910144)
		(width 0.1143)
		(layer "In2.Cu")
		(net "GMI_CPU0_G2_CPU1_G0_TX_DN<3>")
	)
	(segment
		(start 99.88296 -224.579688)
		(end 99.9109 -224.599754)
		(width 0.1143)
		(layer "In2.Cu")
		(net "GMI_CPU0_G2_CPU1_G0_TX_DN<3>")
	)
	(segment
		(start 103.919782 -208.586578)
		(end 103.919782 -208.776824)
		(width 0.14224)
		(layer "In2.Cu")
		(net "GMI_CPU0_G2_CPU1_G0_TX_DN<3>")
	)
	(segment
		(start 371.652546 -226.176332)
		(end 371.653816 -226.17557)
		(width 0.1143)
		(layer "In2.Cu")
		(net "GMI_CPU0_G2_CPU1_G0_TX_DN<3>")
	)
	(segment
		(start 371.651784 -223.911668)
		(end 371.650768 -223.91116)
		(width 0.1143)
		(layer "In2.Cu")
		(net "GMI_CPU0_G2_CPU1_G0_TX_DN<3>")
	)
	(segment
		(start 99.232466 -213.273894)
		(end 99.232466 -221.174564)
		(width 0.14224)
		(layer "In2.Cu")
		(net "GMI_CPU0_G2_CPU1_G0_TX_DN<3>")
	)
	(segment
		(start 99.843336 -227.152454)
		(end 99.842066 -227.153216)
		(width 0.1143)
		(layer "In2.Cu")
		(net "GMI_CPU0_G2_CPU1_G0_TX_DN<3>")
	)
	(segment
		(start 99.88296 -225.509328)
		(end 99.865688 -225.519234)
		(width 0.1143)
		(layer "In2.Cu")
		(net "GMI_CPU0_G2_CPU1_G0_TX_DN<3>")
	)
	(segment
		(start 102.840282 -209.856578)
		(end 102.649782 -209.856578)
		(width 0.14224)
		(layer "In2.Cu")
		(net "GMI_CPU0_G2_CPU1_G0_TX_DN<3>")
	)
	(segment
		(start 371.649244 -225.530156)
		(end 371.612668 -225.50882)
		(width 0.1143)
		(layer "In2.Cu")
		(net "GMI_CPU0_G2_CPU1_G0_TX_DN<3>")
	)
	(segment
		(start 371.36959 -221.624906)
		(end 371.369336 -221.624652)
		(width 0.1143)
		(layer "In2.Cu")
		(net "GMI_CPU0_G2_CPU1_G0_TX_DN<3>")
	)
	(segment
		(start 99.9109 -223.86925)
		(end 99.88296 -223.889316)
		(width 0.1143)
		(layer "In2.Cu")
		(net "GMI_CPU0_G2_CPU1_G0_TX_DN<3>")
	)
	(segment
		(start 98.899726 -228.774498)
		(end 98.897694 -228.775514)
		(width 0.1143)
		(layer "In2.Cu")
		(net "GMI_CPU0_G2_CPU1_G0_TX_DN<3>")
	)
	(segment
		(start 373.172736 -229.904036)
		(end 373.242586 -229.834186)
		(width 0.1143)
		(layer "In2.Cu")
		(net "GMI_CPU0_G2_CPU1_G0_TX_DN<3>")
	)
	(segment
		(start 99.861624 -225.523552)
		(end 99.843844 -225.532442)
		(width 0.1143)
		(layer "In2.Cu")
		(net "GMI_CPU0_G2_CPU1_G0_TX_DN<3>")
	)
	(segment
		(start 371.369336 -221.624652)
		(end 371.369336 -221.248478)
		(width 0.1143)
		(layer "In2.Cu")
		(net "GMI_CPU0_G2_CPU1_G0_TX_DN<3>")
	)
	(segment
		(start 105.485946 -207.020414)
		(end 105.485946 -207.21066)
		(width 0.14224)
		(layer "In2.Cu")
		(net "GMI_CPU0_G2_CPU1_G0_TX_DN<3>")
	)
	(segment
		(start 99.840542 -223.913954)
		(end 99.83978 -223.914462)
		(width 0.1143)
		(layer "In2.Cu")
		(net "GMI_CPU0_G2_CPU1_G0_TX_DN<3>")
	)
	(segment
		(start 101.570536 -211.12607)
		(end 101.274118 -211.422742)
		(width 0.14224)
		(layer "In2.Cu")
		(net "GMI_CPU0_G2_CPU1_G0_TX_DN<3>")
	)
	(segment
		(start 371.651784 -226.17684)
		(end 371.652546 -226.176332)
		(width 0.1143)
		(layer "In2.Cu")
		(net "GMI_CPU0_G2_CPU1_G0_TX_DN<3>")
	)
	(segment
		(start 99.88296 -223.889316)
		(end 99.845622 -223.910906)
		(width 0.1143)
		(layer "In2.Cu")
		(net "GMI_CPU0_G2_CPU1_G0_TX_DN<3>")
	)
	(segment
		(start 99.844098 -227.151946)
		(end 99.843336 -227.152454)
		(width 0.1143)
		(layer "In2.Cu")
		(net "GMI_CPU0_G2_CPU1_G0_TX_DN<3>")
	)
	(segment
		(start 103.919782 -208.776824)
		(end 103.623364 -209.073496)
		(width 0.14224)
		(layer "In2.Cu")
		(net "GMI_CPU0_G2_CPU1_G0_TX_DN<3>")
	)
	(segment
		(start 99.842066 -226.175824)
		(end 99.843336 -226.176586)
		(width 0.1143)
		(layer "In2.Cu")
		(net "GMI_CPU0_G2_CPU1_G0_TX_DN<3>")
	)
	(segment
		(start 98.897694 -228.775514)
		(end 98.872294 -228.790246)
		(width 0.1143)
		(layer "In2.Cu")
		(net "GMI_CPU0_G2_CPU1_G0_TX_DN<3>")
	)
	(segment
		(start 98.900488 -228.77399)
		(end 98.899726 -228.774498)
		(width 0.1143)
		(layer "In2.Cu")
		(net "GMI_CPU0_G2_CPU1_G0_TX_DN<3>")
	)
	(segment
		(start 101.274118 -211.422742)
		(end 101.083618 -211.422742)
		(width 0.14224)
		(layer "In2.Cu")
		(net "GMI_CPU0_G2_CPU1_G0_TX_DN<3>")
	)
	(segment
		(start 305.881532 -177.28184)
		(end 234.68076 -174.830994)
		(width 0.14224)
		(layer "In2.Cu")
		(net "GMI_CPU0_G2_CPU1_G0_TX_DN<3>")
	)
	(segment
		(start 99.843336 -226.176586)
		(end 99.844098 -226.177094)
		(width 0.1143)
		(layer "In2.Cu")
		(net "GMI_CPU0_G2_CPU1_G0_TX_DN<3>")
	)
	(segment
		(start 99.837748 -223.915478)
		(end 99.812348 -223.93021)
		(width 0.1143)
		(layer "In2.Cu")
		(net "GMI_CPU0_G2_CPU1_G0_TX_DN<3>")
	)
	(segment
		(start 371.677438 -227.166678)
		(end 371.652546 -227.1522)
		(width 0.1143)
		(layer "In2.Cu")
		(net "GMI_CPU0_G2_CPU1_G0_TX_DN<3>")
	)
	(segment
		(start 101.083618 -211.422742)
		(end 100.787454 -211.718906)
		(width 0.14224)
		(layer "In2.Cu")
		(net "GMI_CPU0_G2_CPU1_G0_TX_DN<3>")
	)
	(segment
		(start 99.842066 -227.153216)
		(end 99.840542 -227.153978)
		(width 0.1143)
		(layer "In2.Cu")
		(net "GMI_CPU0_G2_CPU1_G0_TX_DN<3>")
	)
	(segment
		(start 372.591076 -228.772466)
		(end 372.559326 -228.751892)
		(width 0.1143)
		(layer "In2.Cu")
		(net "GMI_CPU0_G2_CPU1_G0_TX_DN<3>")
	)
	(segment
		(start 371.649244 -223.910144)
		(end 371.612668 -223.888808)
		(width 0.1143)
		(layer "In2.Cu")
		(net "GMI_CPU0_G2_CPU1_G0_TX_DN<3>")
	)
	(segment
		(start 100.491036 -212.205824)
		(end 100.300536 -212.205824)
		(width 0.14224)
		(layer "In2.Cu")
		(net "GMI_CPU0_G2_CPU1_G0_TX_DN<3>")
	)
	(segment
		(start 99.343464 -222.109284)
		(end 99.373944 -222.127064)
		(width 0.1143)
		(layer "In2.Cu")
		(net "GMI_CPU0_G2_CPU1_G0_TX_DN<3>")
	)
	(segment
		(start 371.650768 -222.291148)
		(end 371.649244 -222.290132)
		(width 0.1143)
		(layer "In2.Cu")
		(net "GMI_CPU0_G2_CPU1_G0_TX_DN<3>")
	)
	(segment
		(start 104.215946 -208.290414)
		(end 103.919782 -208.586578)
		(width 0.14224)
		(layer "In2.Cu")
		(net "GMI_CPU0_G2_CPU1_G0_TX_DN<3>")
	)
	(segment
		(start 371.651784 -222.291656)
		(end 371.650768 -222.291148)
		(width 0.1143)
		(layer "In2.Cu")
		(net "GMI_CPU0_G2_CPU1_G0_TX_DN<3>")
	)
	(segment
		(start 371.323616 -221.202758)
		(end 371.323616 -221.17431)
		(width 0.1143)
		(layer "In2.Cu")
		(net "GMI_CPU0_G2_CPU1_G0_TX_DN<3>")
	)
	(segment
		(start 99.837748 -225.53549)
		(end 99.812348 -225.550222)
		(width 0.1143)
		(layer "In2.Cu")
		(net "GMI_CPU0_G2_CPU1_G0_TX_DN<3>")
	)
	(segment
		(start 99.837748 -227.155502)
		(end 99.812348 -227.170234)
		(width 0.1143)
		(layer "In2.Cu")
		(net "GMI_CPU0_G2_CPU1_G0_TX_DN<3>")
	)
	(segment
		(start 100.004372 -212.692234)
		(end 99.707954 -212.988906)
		(width 0.14224)
		(layer "In2.Cu")
		(net "GMI_CPU0_G2_CPU1_G0_TX_DN<3>")
	)
	(segment
		(start 99.844098 -222.93707)
		(end 99.846892 -222.938848)
		(width 0.1143)
		(layer "In2.Cu")
		(net "GMI_CPU0_G2_CPU1_G0_TX_DN<3>")
	)
	(segment
		(start 371.649244 -222.290132)
		(end 371.648228 -222.289624)
		(width 0.1143)
		(layer "In2.Cu")
		(net "GMI_CPU0_G2_CPU1_G0_TX_DN<3>")
	)
	(segment
		(start 99.846892 -224.55886)
		(end 99.88296 -224.579688)
		(width 0.1143)
		(layer "In2.Cu")
		(net "GMI_CPU0_G2_CPU1_G0_TX_DN<3>")
	)
	(segment
		(start 371.653816 -226.17557)
		(end 371.683534 -226.158552)
		(width 0.1143)
		(layer "In2.Cu")
		(net "GMI_CPU0_G2_CPU1_G0_TX_DN<3>")
	)
	(segment
		(start 98.902012 -228.773228)
		(end 98.900488 -228.77399)
		(width 0.1143)
		(layer "In2.Cu")
		(net "GMI_CPU0_G2_CPU1_G0_TX_DN<3>")
	)
	(segment
		(start 369.207288 -213.380574)
		(end 364.617762 -209.382106)
		(width 0.14224)
		(layer "In2.Cu")
		(net "GMI_CPU0_G2_CPU1_G0_TX_DN<3>")
	)
	(segment
		(start 99.843336 -224.556574)
		(end 99.844098 -224.557082)
		(width 0.1143)
		(layer "In2.Cu")
		(net "GMI_CPU0_G2_CPU1_G0_TX_DN<3>")
	)
	(segment
		(start 107.416092 -205.090268)
		(end 105.485946 -207.020414)
		(width 0.14224)
		(layer "In2.Cu")
		(net "GMI_CPU0_G2_CPU1_G0_TX_DN<3>")
	)
	(segment
		(start 152.263602 -182.146702)
		(end 107.416092 -205.090268)
		(width 0.14224)
		(layer "In2.Cu")
		(net "GMI_CPU0_G2_CPU1_G0_TX_DN<3>")
	)
	(segment
		(start 371.650768 -227.151184)
		(end 371.649244 -227.150168)
		(width 0.1143)
		(layer "In2.Cu")
		(net "GMI_CPU0_G2_CPU1_G0_TX_DN<3>")
	)
	(segment
		(start 372.623588 -228.789992)
		(end 372.593362 -228.77272)
		(width 0.1143)
		(layer "In2.Cu")
		(net "GMI_CPU0_G2_CPU1_G0_TX_DN<3>")
	)
	(segment
		(start 372.592092 -228.772974)
		(end 372.591076 -228.772466)
		(width 0.1143)
		(layer "In2.Cu")
		(net "GMI_CPU0_G2_CPU1_G0_TX_DN<3>")
	)
	(segment
		(start 161.390584 -178.297078)
		(end 152.263602 -182.146702)
		(width 0.14224)
		(layer "In2.Cu")
		(net "GMI_CPU0_G2_CPU1_G0_TX_DN<3>")
	)
	(segment
		(start 371.652546 -224.55632)
		(end 371.653816 -224.555558)
		(width 0.1143)
		(layer "In2.Cu")
		(net "GMI_CPU0_G2_CPU1_G0_TX_DN<3>")
	)
	(segment
		(start 104.406446 -208.290414)
		(end 104.215946 -208.290414)
		(width 0.14224)
		(layer "In2.Cu")
		(net "GMI_CPU0_G2_CPU1_G0_TX_DN<3>")
	)
	(segment
		(start 99.9109 -225.489262)
		(end 99.88296 -225.509328)
		(width 0.1143)
		(layer "In2.Cu")
		(net "GMI_CPU0_G2_CPU1_G0_TX_DN<3>")
	)
	(segment
		(start 99.517454 -212.988906)
		(end 99.232466 -213.273894)
		(width 0.14224)
		(layer "In2.Cu")
		(net "GMI_CPU0_G2_CPU1_G0_TX_DN<3>")
	)
	(segment
		(start 371.683534 -222.309944)
		(end 371.651784 -222.291656)
		(width 0.1143)
		(layer "In2.Cu")
		(net "GMI_CPU0_G2_CPU1_G0_TX_DN<3>")
	)
	(segment
		(start 99.842066 -222.9358)
		(end 99.843336 -222.936562)
		(width 0.1143)
		(layer "In2.Cu")
		(net "GMI_CPU0_G2_CPU1_G0_TX_DN<3>")
	)
	(segment
		(start 371.612668 -226.1997)
		(end 371.651784 -226.17684)
		(width 0.1143)
		(layer "In2.Cu")
		(net "GMI_CPU0_G2_CPU1_G0_TX_DN<3>")
	)
	(segment
		(start 99.842066 -225.533204)
		(end 99.840542 -225.533966)
		(width 0.1143)
		(layer "In2.Cu")
		(net "GMI_CPU0_G2_CPU1_G0_TX_DN<3>")
	)
	(segment
		(start 102.353618 -210.342988)
		(end 102.0572 -210.63966)
		(width 0.14224)
		(layer "In2.Cu")
		(net "GMI_CPU0_G2_CPU1_G0_TX_DN<3>")
	)
	(segment
		(start 372.134638 -227.98151)
		(end 372.13413 -227.981256)
		(width 0.1143)
		(layer "In2.Cu")
		(net "GMI_CPU0_G2_CPU1_G0_TX_DN<3>")
	)
	(segment
		(start 100.787454 -211.718906)
		(end 100.787454 -211.909152)
		(width 0.14224)
		(layer "In2.Cu")
		(net "GMI_CPU0_G2_CPU1_G0_TX_DN<3>")
	)
	(segment
		(start 102.0572 -210.63966)
		(end 101.8667 -210.63966)
		(width 0.14224)
		(layer "In2.Cu")
		(net "GMI_CPU0_G2_CPU1_G0_TX_DN<3>")
	)
	(segment
		(start 99.186746 -221.624906)
		(end 99.186492 -221.62516)
		(width 0.1143)
		(layer "In2.Cu")
		(net "GMI_CPU0_G2_CPU1_G0_TX_DN<3>")
	)
	(segment
		(start 371.323616 -218.03106)
		(end 369.207288 -213.380574)
		(width 0.14224)
		(layer "In2.Cu")
		(net "GMI_CPU0_G2_CPU1_G0_TX_DN<3>")
	)
	(segment
		(start 102.353618 -210.152742)
		(end 102.353618 -210.342988)
		(width 0.14224)
		(layer "In2.Cu")
		(net "GMI_CPU0_G2_CPU1_G0_TX_DN<3>")
	)
	(segment
		(start 99.186492 -221.62516)
		(end 99.186492 -221.804484)
		(width 0.1143)
		(layer "In2.Cu")
		(net "GMI_CPU0_G2_CPU1_G0_TX_DN<3>")
	)
	(segment
		(start 372.874794 -229.904036)
		(end 373.172736 -229.904036)
		(width 0.1143)
		(layer "In2.Cu")
		(net "GMI_CPU0_G2_CPU1_G0_TX_DN<3>")
	)
	(segment
		(start 311.153048 -178.81473)
		(end 309.787798 -178.2953)
		(width 0.14224)
		(layer "In2.Cu")
		(net "GMI_CPU0_G2_CPU1_G0_TX_DN<3>")
	)
	(segment
		(start 373.061738 -229.58171)
		(end 373.025416 -229.560628)
		(width 0.1143)
		(layer "In2.Cu")
		(net "GMI_CPU0_G2_CPU1_G0_TX_DN<3>")
	)
	(segment
		(start 371.648228 -222.289624)
		(end 371.612668 -222.268796)
		(width 0.1143)
		(layer "In2.Cu")
		(net "GMI_CPU0_G2_CPU1_G0_TX_DN<3>")
	)
	(segment
		(start 99.232466 -221.174564)
		(end 99.232466 -221.203012)
		(width 0.1143)
		(layer "In2.Cu")
		(net "GMI_CPU0_G2_CPU1_G0_TX_DN<3>")
	)
	(segment
		(start 98.906584 -228.770434)
		(end 98.90506 -228.77145)
		(width 0.1143)
		(layer "In2.Cu")
		(net "GMI_CPU0_G2_CPU1_G0_TX_DN<3>")
	)
	(segment
		(start 99.840542 -225.533966)
		(end 99.83978 -225.534474)
		(width 0.1143)
		(layer "In2.Cu")
		(net "GMI_CPU0_G2_CPU1_G0_TX_DN<3>")
	)
	(segment
		(start 164.751004 -177.337974)
		(end 161.390584 -178.297078)
		(width 0.14224)
		(layer "In2.Cu")
		(net "GMI_CPU0_G2_CPU1_G0_TX_DN<3>")
	)
	(segment
		(start 99.812348 -224.538794)
		(end 99.842066 -224.555812)
		(width 0.1143)
		(layer "In2.Cu")
		(net "GMI_CPU0_G2_CPU1_G0_TX_DN<3>")
	)
	(segment
		(start 102.649782 -209.856578)
		(end 102.353618 -210.152742)
		(width 0.14224)
		(layer "In2.Cu")
		(net "GMI_CPU0_G2_CPU1_G0_TX_DN<3>")
	)
	(segment
		(start 326.17664 -186.050936)
		(end 311.153048 -178.81473)
		(width 0.14224)
		(layer "In2.Cu")
		(net "GMI_CPU0_G2_CPU1_G0_TX_DN<3>")
	)
	(segment
		(start 99.707954 -212.988906)
		(end 99.517454 -212.988906)
		(width 0.14224)
		(layer "In2.Cu")
		(net "GMI_CPU0_G2_CPU1_G0_TX_DN<3>")
	)
	(segment
		(start 99.373944 -227.961952)
		(end 99.343464 -227.979732)
		(width 0.1143)
		(layer "In2.Cu")
		(net "GMI_CPU0_G2_CPU1_G0_TX_DN<3>")
	)
	(arc
		(start 99.894644 -227.120958)
		(mid 99.88757 -227.125965)
		(end 99.88042 -227.130864)
		(width 0.1143)
		(layer "In2.Cu")
		(net "GMI_CPU0_G2_CPU1_G0_TX_DN<3>")
	)
	(arc
		(start 99.9109 -222.979742)
		(mid 100.1389 -223.424496)
		(end 99.9109 -223.86925)
		(width 0.1143)
		(layer "In2.Cu")
		(net "GMI_CPU0_G2_CPU1_G0_TX_DN<3>")
	)
	(arc
		(start 371.612668 -225.50882)
		(mid 371.369341 -225.044254)
		(end 371.612668 -224.579688)
		(width 0.1143)
		(layer "In2.Cu")
		(net "GMI_CPU0_G2_CPU1_G0_TX_DN<3>")
	)
	(arc
		(start 372.779544 -229.094284)
		(mid 372.738289 -228.923313)
		(end 372.623588 -228.789992)
		(width 0.1143)
		(layer "In2.Cu")
		(net "GMI_CPU0_G2_CPU1_G0_TX_DN<3>")
	)
	(arc
		(start 99.656392 -222.61449)
		(mid 99.697647 -222.785461)
		(end 99.812348 -222.918782)
		(width 0.1143)
		(layer "In2.Cu")
		(net "GMI_CPU0_G2_CPU1_G0_TX_DN<3>")
	)
	(arc
		(start 99.88042 -226.198176)
		(mid 99.887569 -226.203076)
		(end 99.894644 -226.208082)
		(width 0.1143)
		(layer "In2.Cu")
		(net "GMI_CPU0_G2_CPU1_G0_TX_DN<3>")
	)
	(arc
		(start 99.812348 -227.170234)
		(mid 99.697672 -227.303568)
		(end 99.656392 -227.474526)
		(width 0.1143)
		(layer "In2.Cu")
		(net "GMI_CPU0_G2_CPU1_G0_TX_DN<3>")
	)
	(arc
		(start 371.683534 -222.918528)
		(mid 371.839462 -222.614236)
		(end 371.683534 -222.309944)
		(width 0.1143)
		(layer "In2.Cu")
		(net "GMI_CPU0_G2_CPU1_G0_TX_DN<3>")
	)
	(arc
		(start 99.186492 -221.804484)
		(mid 99.228041 -221.975906)
		(end 99.343464 -222.109284)
		(width 0.1143)
		(layer "In2.Cu")
		(net "GMI_CPU0_G2_CPU1_G0_TX_DN<3>")
	)
	(arc
		(start 98.716338 -229.094538)
		(mid 98.651823 -229.356757)
		(end 98.473006 -229.559104)
		(width 0.1143)
		(layer "In2.Cu")
		(net "GMI_CPU0_G2_CPU1_G0_TX_DN<3>")
	)
	(arc
		(start 373.025416 -229.560628)
		(mid 372.844764 -229.357883)
		(end 372.779544 -229.094284)
		(width 0.1143)
		(layer "In2.Cu")
		(net "GMI_CPU0_G2_CPU1_G0_TX_DN<3>")
	)
	(arc
		(start 99.812348 -223.93021)
		(mid 99.65642 -224.234502)
		(end 99.812348 -224.538794)
		(width 0.1143)
		(layer "In2.Cu")
		(net "GMI_CPU0_G2_CPU1_G0_TX_DN<3>")
	)
	(arc
		(start 98.401378 -229.60076)
		(mid 98.304938 -229.703415)
		(end 98.253296 -229.83444)
		(width 0.1143)
		(layer "In2.Cu")
		(net "GMI_CPU0_G2_CPU1_G0_TX_DN<3>")
	)
	(arc
		(start 99.343464 -227.979732)
		(mid 99.228037 -228.113108)
		(end 99.186492 -228.284532)
		(width 0.1143)
		(layer "In2.Cu")
		(net "GMI_CPU0_G2_CPU1_G0_TX_DN<3>")
	)
	(arc
		(start 371.612668 -222.268796)
		(mid 371.540341 -222.209329)
		(end 371.47881 -222.138748)
		(width 0.1143)
		(layer "In2.Cu")
		(net "GMI_CPU0_G2_CPU1_G0_TX_DN<3>")
	)
	(arc
		(start 372.30939 -228.283516)
		(mid 372.262081 -228.109333)
		(end 372.134638 -227.98151)
		(width 0.1143)
		(layer "In2.Cu")
		(net "GMI_CPU0_G2_CPU1_G0_TX_DN<3>")
	)
	(arc
		(start 371.612668 -227.128832)
		(mid 371.369341 -226.664266)
		(end 371.612668 -226.1997)
		(width 0.1143)
		(layer "In2.Cu")
		(net "GMI_CPU0_G2_CPU1_G0_TX_DN<3>")
	)
	(arc
		(start 99.186492 -228.284532)
		(mid 99.121977 -228.546751)
		(end 98.94316 -228.749098)
		(width 0.1143)
		(layer "In2.Cu")
		(net "GMI_CPU0_G2_CPU1_G0_TX_DN<3>")
	)
	(arc
		(start 98.872294 -228.790246)
		(mid 98.757618 -228.92358)
		(end 98.716338 -229.094538)
		(width 0.1143)
		(layer "In2.Cu")
		(net "GMI_CPU0_G2_CPU1_G0_TX_DN<3>")
	)
	(arc
		(start 372.559326 -228.751892)
		(mid 372.375719 -228.54928)
		(end 372.30939 -228.284024)
		(width 0.1143)
		(layer "In2.Cu")
		(net "GMI_CPU0_G2_CPU1_G0_TX_DN<3>")
	)
	(arc
		(start 372.095268 -227.958396)
		(mid 371.916913 -227.756182)
		(end 371.852444 -227.494338)
		(width 0.1143)
		(layer "In2.Cu")
		(net "GMI_CPU0_G2_CPU1_G0_TX_DN<3>")
	)
	(arc
		(start 99.812348 -225.550222)
		(mid 99.65642 -225.854514)
		(end 99.812348 -226.158806)
		(width 0.1143)
		(layer "In2.Cu")
		(net "GMI_CPU0_G2_CPU1_G0_TX_DN<3>")
	)
	(arc
		(start 99.41306 -222.149924)
		(mid 99.591873 -222.352274)
		(end 99.656392 -222.61449)
		(width 0.1143)
		(layer "In2.Cu")
		(net "GMI_CPU0_G2_CPU1_G0_TX_DN<3>")
	)
	(arc
		(start 371.612668 -223.888808)
		(mid 371.369341 -223.424242)
		(end 371.612668 -222.959676)
		(width 0.1143)
		(layer "In2.Cu")
		(net "GMI_CPU0_G2_CPU1_G0_TX_DN<3>")
	)
	(arc
		(start 371.683534 -224.53854)
		(mid 371.839462 -224.234248)
		(end 371.683534 -223.929956)
		(width 0.1143)
		(layer "In2.Cu")
		(net "GMI_CPU0_G2_CPU1_G0_TX_DN<3>")
	)
	(arc
		(start 99.894644 -226.208082)
		(mid 100.122027 -226.66452)
		(end 99.894644 -227.120958)
		(width 0.1143)
		(layer "In2.Cu")
		(net "GMI_CPU0_G2_CPU1_G0_TX_DN<3>")
	)
	(arc
		(start 99.656392 -227.474526)
		(mid 99.591877 -227.736745)
		(end 99.41306 -227.939092)
		(width 0.1143)
		(layer "In2.Cu")
		(net "GMI_CPU0_G2_CPU1_G0_TX_DN<3>")
	)
	(arc
		(start 99.9109 -224.599754)
		(mid 100.1389 -225.044508)
		(end 99.9109 -225.489262)
		(width 0.1143)
		(layer "In2.Cu")
		(net "GMI_CPU0_G2_CPU1_G0_TX_DN<3>")
	)
	(arc
		(start 373.242586 -229.834186)
		(mid 373.191096 -229.703713)
		(end 373.095266 -229.601268)
		(width 0.1143)
		(layer "In2.Cu")
		(net "GMI_CPU0_G2_CPU1_G0_TX_DN<3>")
	)
	(arc
		(start 371.47881 -222.138748)
		(mid 371.397519 -221.980201)
		(end 371.36959 -221.80423)
		(width 0.1143)
		(layer "In2.Cu")
		(net "GMI_CPU0_G2_CPU1_G0_TX_DN<3>")
	)
	(arc
		(start 371.852444 -227.46716)
		(mid 371.807036 -227.295959)
		(end 371.682772 -227.169726)
		(width 0.1143)
		(layer "In2.Cu")
		(net "GMI_CPU0_G2_CPU1_G0_TX_DN<3>")
	)
	(arc
		(start 371.683534 -226.158552)
		(mid 371.839462 -225.85426)
		(end 371.683534 -225.549968)
		(width 0.1143)
		(layer "In2.Cu")
		(net "GMI_CPU0_G2_CPU1_G0_TX_DN<3>")
	)
	(segment
		(start 372.407942 -226.930204)
		(end 372.874794 -226.664266)
		(width 0.12954)
		(layer "F.Cu")
		(net "GMI_CPU0_G2_CPU1_G0_TX_DN<2>")
	)
	(segment
		(start 99.08794 -226.930458)
		(end 98.621088 -226.66452)
		(width 0.12954)
		(layer "F.Cu")
		(net "GMI_CPU0_G2_CPU1_G0_TX_DN<2>")
	)
	(segment
		(start 98.323146 -226.66452)
		(end 98.240342 -226.581716)
		(width 0.1143)
		(layer "In2.Cu")
		(net "GMI_CPU0_G2_CPU1_G0_TX_DN<2>")
	)
	(segment
		(start 373.203724 -217.612976)
		(end 373.203724 -221.17431)
		(width 0.14224)
		(layer "In2.Cu")
		(net "GMI_CPU0_G2_CPU1_G0_TX_DN<2>")
	)
	(segment
		(start 100.760022 -208.669128)
		(end 100.950522 -208.669128)
		(width 0.14224)
		(layer "In2.Cu")
		(net "GMI_CPU0_G2_CPU1_G0_TX_DN<2>")
	)
	(segment
		(start 103.596186 -205.832964)
		(end 105.772966 -203.656184)
		(width 0.14224)
		(layer "In2.Cu")
		(net "GMI_CPU0_G2_CPU1_G0_TX_DN<2>")
	)
	(segment
		(start 97.96399 -226.177094)
		(end 97.93224 -226.158806)
		(width 0.1143)
		(layer "In2.Cu")
		(net "GMI_CPU0_G2_CPU1_G0_TX_DN<2>")
	)
	(segment
		(start 102.516686 -207.102964)
		(end 102.813104 -206.806292)
		(width 0.14224)
		(layer "In2.Cu")
		(net "GMI_CPU0_G2_CPU1_G0_TX_DN<2>")
	)
	(segment
		(start 98.003106 -224.579942)
		(end 97.965006 -224.55759)
		(width 0.1143)
		(layer "In2.Cu")
		(net "GMI_CPU0_G2_CPU1_G0_TX_DN<2>")
	)
	(segment
		(start 373.249698 -221.624906)
		(end 373.249698 -221.80423)
		(width 0.1143)
		(layer "In2.Cu")
		(net "GMI_CPU0_G2_CPU1_G0_TX_DN<2>")
	)
	(segment
		(start 373.531892 -225.53168)
		(end 373.562372 -225.54946)
		(width 0.1143)
		(layer "In2.Cu")
		(net "GMI_CPU0_G2_CPU1_G0_TX_DN<2>")
	)
	(segment
		(start 100.463858 -209.155538)
		(end 100.463858 -208.965292)
		(width 0.14224)
		(layer "In2.Cu")
		(net "GMI_CPU0_G2_CPU1_G0_TX_DN<2>")
	)
	(segment
		(start 164.386006 -175.45939)
		(end 234.88904 -172.93209)
		(width 0.14224)
		(layer "In2.Cu")
		(net "GMI_CPU0_G2_CPU1_G0_TX_DN<2>")
	)
	(segment
		(start 100.463858 -208.965292)
		(end 100.760022 -208.669128)
		(width 0.14224)
		(layer "In2.Cu")
		(net "GMI_CPU0_G2_CPU1_G0_TX_DN<2>")
	)
	(segment
		(start 98.601276 -211.018374)
		(end 98.897694 -210.721702)
		(width 0.14224)
		(layer "In2.Cu")
		(net "GMI_CPU0_G2_CPU1_G0_TX_DN<2>")
	)
	(segment
		(start 358.881426 -203.18095)
		(end 365.753396 -207.831944)
		(width 0.14224)
		(layer "In2.Cu")
		(net "GMI_CPU0_G2_CPU1_G0_TX_DN<2>")
	)
	(segment
		(start 97.306384 -221.487492)
		(end 97.28581 -221.466918)
		(width 0.1143)
		(layer "In2.Cu")
		(net "GMI_CPU0_G2_CPU1_G0_TX_DN<2>")
	)
	(segment
		(start 103.596186 -206.02321)
		(end 103.596186 -205.832964)
		(width 0.14224)
		(layer "In2.Cu")
		(net "GMI_CPU0_G2_CPU1_G0_TX_DN<2>")
	)
	(segment
		(start 98.410776 -211.018374)
		(end 98.601276 -211.018374)
		(width 0.14224)
		(layer "In2.Cu")
		(net "GMI_CPU0_G2_CPU1_G0_TX_DN<2>")
	)
	(segment
		(start 98.897694 -210.531456)
		(end 99.193858 -210.235292)
		(width 0.14224)
		(layer "In2.Cu")
		(net "GMI_CPU0_G2_CPU1_G0_TX_DN<2>")
	)
	(segment
		(start 373.492776 -225.50882)
		(end 373.531892 -225.53168)
		(width 0.1143)
		(layer "In2.Cu")
		(net "GMI_CPU0_G2_CPU1_G0_TX_DN<2>")
	)
	(segment
		(start 97.33153 -221.203012)
		(end 97.33153 -221.174564)
		(width 0.1143)
		(layer "In2.Cu")
		(net "GMI_CPU0_G2_CPU1_G0_TX_DN<2>")
	)
	(segment
		(start 102.813104 -206.806292)
		(end 102.813104 -206.616046)
		(width 0.14224)
		(layer "In2.Cu")
		(net "GMI_CPU0_G2_CPU1_G0_TX_DN<2>")
	)
	(segment
		(start 373.531892 -223.911668)
		(end 373.562372 -223.929448)
		(width 0.1143)
		(layer "In2.Cu")
		(net "GMI_CPU0_G2_CPU1_G0_TX_DN<2>")
	)
	(segment
		(start 97.786698 -222.629984)
		(end 97.786698 -222.622872)
		(width 0.1143)
		(layer "In2.Cu")
		(net "GMI_CPU0_G2_CPU1_G0_TX_DN<2>")
	)
	(segment
		(start 373.531892 -224.556828)
		(end 373.492776 -224.579688)
		(width 0.1143)
		(layer "In2.Cu")
		(net "GMI_CPU0_G2_CPU1_G0_TX_DN<2>")
	)
	(segment
		(start 373.25554 -226.581462)
		(end 373.172736 -226.664266)
		(width 0.1143)
		(layer "In2.Cu")
		(net "GMI_CPU0_G2_CPU1_G0_TX_DN<2>")
	)
	(segment
		(start 99.193858 -210.235292)
		(end 99.384358 -210.235292)
		(width 0.14224)
		(layer "In2.Cu")
		(net "GMI_CPU0_G2_CPU1_G0_TX_DN<2>")
	)
	(segment
		(start 98.114612 -211.314538)
		(end 98.410776 -211.018374)
		(width 0.14224)
		(layer "In2.Cu")
		(net "GMI_CPU0_G2_CPU1_G0_TX_DN<2>")
	)
	(segment
		(start 97.28581 -221.466918)
		(end 97.28581 -221.248732)
		(width 0.1143)
		(layer "In2.Cu")
		(net "GMI_CPU0_G2_CPU1_G0_TX_DN<2>")
	)
	(segment
		(start 373.562372 -224.539048)
		(end 373.531892 -224.556828)
		(width 0.1143)
		(layer "In2.Cu")
		(net "GMI_CPU0_G2_CPU1_G0_TX_DN<2>")
	)
	(segment
		(start 97.627694 -211.801456)
		(end 97.818194 -211.801456)
		(width 0.14224)
		(layer "In2.Cu")
		(net "GMI_CPU0_G2_CPU1_G0_TX_DN<2>")
	)
	(segment
		(start 97.96399 -222.93707)
		(end 97.963228 -222.936816)
		(width 0.1143)
		(layer "In2.Cu")
		(net "GMI_CPU0_G2_CPU1_G0_TX_DN<2>")
	)
	(segment
		(start 97.504504 -222.13316)
		(end 97.462086 -222.108522)
		(width 0.1143)
		(layer "In2.Cu")
		(net "GMI_CPU0_G2_CPU1_G0_TX_DN<2>")
	)
	(segment
		(start 102.326186 -207.102964)
		(end 102.516686 -207.102964)
		(width 0.14224)
		(layer "In2.Cu")
		(net "GMI_CPU0_G2_CPU1_G0_TX_DN<2>")
	)
	(segment
		(start 97.965006 -222.937578)
		(end 97.96399 -222.93707)
		(width 0.1143)
		(layer "In2.Cu")
		(net "GMI_CPU0_G2_CPU1_G0_TX_DN<2>")
	)
	(segment
		(start 101.733604 -207.886046)
		(end 102.030022 -207.589374)
		(width 0.14224)
		(layer "In2.Cu")
		(net "GMI_CPU0_G2_CPU1_G0_TX_DN<2>")
	)
	(segment
		(start 97.818194 -211.801456)
		(end 98.114612 -211.504784)
		(width 0.14224)
		(layer "In2.Cu")
		(net "GMI_CPU0_G2_CPU1_G0_TX_DN<2>")
	)
	(segment
		(start 370.722398 -212.160866)
		(end 373.203724 -217.612976)
		(width 0.14224)
		(layer "In2.Cu")
		(net "GMI_CPU0_G2_CPU1_G0_TX_DN<2>")
	)
	(segment
		(start 99.384358 -210.235292)
		(end 99.680776 -209.93862)
		(width 0.14224)
		(layer "In2.Cu")
		(net "GMI_CPU0_G2_CPU1_G0_TX_DN<2>")
	)
	(segment
		(start 98.621088 -226.66452)
		(end 98.323146 -226.66452)
		(width 0.1143)
		(layer "In2.Cu")
		(net "GMI_CPU0_G2_CPU1_G0_TX_DN<2>")
	)
	(segment
		(start 103.299768 -206.319882)
		(end 103.596186 -206.02321)
		(width 0.14224)
		(layer "In2.Cu")
		(net "GMI_CPU0_G2_CPU1_G0_TX_DN<2>")
	)
	(segment
		(start 310.043068 -176.358042)
		(end 312.60542 -177.333148)
		(width 0.14224)
		(layer "In2.Cu")
		(net "GMI_CPU0_G2_CPU1_G0_TX_DN<2>")
	)
	(segment
		(start 101.24694 -208.18221)
		(end 101.543104 -207.886046)
		(width 0.14224)
		(layer "In2.Cu")
		(net "GMI_CPU0_G2_CPU1_G0_TX_DN<2>")
	)
	(segment
		(start 161.062416 -176.40808)
		(end 164.386006 -175.45939)
		(width 0.14224)
		(layer "In2.Cu")
		(net "GMI_CPU0_G2_CPU1_G0_TX_DN<2>")
	)
	(segment
		(start 98.003106 -222.95993)
		(end 97.965006 -222.937578)
		(width 0.1143)
		(layer "In2.Cu")
		(net "GMI_CPU0_G2_CPU1_G0_TX_DN<2>")
	)
	(segment
		(start 373.531892 -222.936816)
		(end 373.492776 -222.959676)
		(width 0.1143)
		(layer "In2.Cu")
		(net "GMI_CPU0_G2_CPU1_G0_TX_DN<2>")
	)
	(segment
		(start 102.030022 -207.589374)
		(end 102.030022 -207.399128)
		(width 0.14224)
		(layer "In2.Cu")
		(net "GMI_CPU0_G2_CPU1_G0_TX_DN<2>")
	)
	(segment
		(start 99.97694 -209.45221)
		(end 100.16744 -209.45221)
		(width 0.14224)
		(layer "In2.Cu")
		(net "GMI_CPU0_G2_CPU1_G0_TX_DN<2>")
	)
	(segment
		(start 102.813104 -206.616046)
		(end 103.109268 -206.319882)
		(width 0.14224)
		(layer "In2.Cu")
		(net "GMI_CPU0_G2_CPU1_G0_TX_DN<2>")
	)
	(segment
		(start 101.543104 -207.886046)
		(end 101.733604 -207.886046)
		(width 0.14224)
		(layer "In2.Cu")
		(net "GMI_CPU0_G2_CPU1_G0_TX_DN<2>")
	)
	(segment
		(start 102.030022 -207.399128)
		(end 102.326186 -207.102964)
		(width 0.14224)
		(layer "In2.Cu")
		(net "GMI_CPU0_G2_CPU1_G0_TX_DN<2>")
	)
	(segment
		(start 373.562372 -222.919036)
		(end 373.531892 -222.936816)
		(width 0.1143)
		(layer "In2.Cu")
		(net "GMI_CPU0_G2_CPU1_G0_TX_DN<2>")
	)
	(segment
		(start 105.772966 -203.656184)
		(end 151.115268 -180.604414)
		(width 0.14224)
		(layer "In2.Cu")
		(net "GMI_CPU0_G2_CPU1_G0_TX_DN<2>")
	)
	(segment
		(start 98.897694 -210.721702)
		(end 98.897694 -210.531456)
		(width 0.14224)
		(layer "In2.Cu")
		(net "GMI_CPU0_G2_CPU1_G0_TX_DN<2>")
	)
	(segment
		(start 373.492776 -223.888808)
		(end 373.531892 -223.911668)
		(width 0.1143)
		(layer "In2.Cu")
		(net "GMI_CPU0_G2_CPU1_G0_TX_DN<2>")
	)
	(segment
		(start 97.93224 -223.93021)
		(end 97.96399 -223.911922)
		(width 0.1143)
		(layer "In2.Cu")
		(net "GMI_CPU0_G2_CPU1_G0_TX_DN<2>")
	)
	(segment
		(start 97.33153 -212.09762)
		(end 97.627694 -211.801456)
		(width 0.14224)
		(layer "In2.Cu")
		(net "GMI_CPU0_G2_CPU1_G0_TX_DN<2>")
	)
	(segment
		(start 101.24694 -208.372456)
		(end 101.24694 -208.18221)
		(width 0.14224)
		(layer "In2.Cu")
		(net "GMI_CPU0_G2_CPU1_G0_TX_DN<2>")
	)
	(segment
		(start 326.991726 -184.318656)
		(end 358.881426 -203.18095)
		(width 0.14224)
		(layer "In2.Cu")
		(net "GMI_CPU0_G2_CPU1_G0_TX_DN<2>")
	)
	(segment
		(start 373.172736 -226.664266)
		(end 372.874794 -226.664266)
		(width 0.1143)
		(layer "In2.Cu")
		(net "GMI_CPU0_G2_CPU1_G0_TX_DN<2>")
	)
	(segment
		(start 98.003106 -226.199954)
		(end 97.96399 -226.177094)
		(width 0.1143)
		(layer "In2.Cu")
		(net "GMI_CPU0_G2_CPU1_G0_TX_DN<2>")
	)
	(segment
		(start 97.96399 -225.531934)
		(end 98.003106 -225.509074)
		(width 0.1143)
		(layer "In2.Cu")
		(net "GMI_CPU0_G2_CPU1_G0_TX_DN<2>")
	)
	(segment
		(start 312.60542 -177.333148)
		(end 318.75222 -180.067458)
		(width 0.14224)
		(layer "In2.Cu")
		(net "GMI_CPU0_G2_CPU1_G0_TX_DN<2>")
	)
	(segment
		(start 306.314856 -175.39081)
		(end 310.043068 -176.358042)
		(width 0.14224)
		(layer "In2.Cu")
		(net "GMI_CPU0_G2_CPU1_G0_TX_DN<2>")
	)
	(segment
		(start 373.249444 -221.248478)
		(end 373.249444 -221.624652)
		(width 0.1143)
		(layer "In2.Cu")
		(net "GMI_CPU0_G2_CPU1_G0_TX_DN<2>")
	)
	(segment
		(start 97.28581 -221.248732)
		(end 97.33153 -221.203012)
		(width 0.1143)
		(layer "In2.Cu")
		(net "GMI_CPU0_G2_CPU1_G0_TX_DN<2>")
	)
	(segment
		(start 373.203724 -221.17431)
		(end 373.203724 -221.202758)
		(width 0.1143)
		(layer "In2.Cu")
		(net "GMI_CPU0_G2_CPU1_G0_TX_DN<2>")
	)
	(segment
		(start 373.531892 -226.17684)
		(end 373.492776 -226.1997)
		(width 0.1143)
		(layer "In2.Cu")
		(net "GMI_CPU0_G2_CPU1_G0_TX_DN<2>")
	)
	(segment
		(start 97.33153 -221.174564)
		(end 97.33153 -212.09762)
		(width 0.14224)
		(layer "In2.Cu")
		(net "GMI_CPU0_G2_CPU1_G0_TX_DN<2>")
	)
	(segment
		(start 373.492776 -222.268796)
		(end 373.562372 -222.309436)
		(width 0.1143)
		(layer "In2.Cu")
		(net "GMI_CPU0_G2_CPU1_G0_TX_DN<2>")
	)
	(segment
		(start 373.249444 -221.624652)
		(end 373.249698 -221.624906)
		(width 0.1143)
		(layer "In2.Cu")
		(net "GMI_CPU0_G2_CPU1_G0_TX_DN<2>")
	)
	(segment
		(start 365.753396 -207.831944)
		(end 370.722398 -212.160866)
		(width 0.14224)
		(layer "In2.Cu")
		(net "GMI_CPU0_G2_CPU1_G0_TX_DN<2>")
	)
	(segment
		(start 97.306384 -221.804484)
		(end 97.306384 -221.487492)
		(width 0.1143)
		(layer "In2.Cu")
		(net "GMI_CPU0_G2_CPU1_G0_TX_DN<2>")
	)
	(segment
		(start 100.16744 -209.45221)
		(end 100.463858 -209.155538)
		(width 0.14224)
		(layer "In2.Cu")
		(net "GMI_CPU0_G2_CPU1_G0_TX_DN<2>")
	)
	(segment
		(start 100.950522 -208.669128)
		(end 101.24694 -208.372456)
		(width 0.14224)
		(layer "In2.Cu")
		(net "GMI_CPU0_G2_CPU1_G0_TX_DN<2>")
	)
	(segment
		(start 99.680776 -209.748374)
		(end 99.97694 -209.45221)
		(width 0.14224)
		(layer "In2.Cu")
		(net "GMI_CPU0_G2_CPU1_G0_TX_DN<2>")
	)
	(segment
		(start 373.562372 -226.15906)
		(end 373.531892 -226.17684)
		(width 0.1143)
		(layer "In2.Cu")
		(net "GMI_CPU0_G2_CPU1_G0_TX_DN<2>")
	)
	(segment
		(start 318.75222 -180.067458)
		(end 326.991726 -184.318656)
		(width 0.14224)
		(layer "In2.Cu")
		(net "GMI_CPU0_G2_CPU1_G0_TX_DN<2>")
	)
	(segment
		(start 151.115268 -180.604414)
		(end 161.062416 -176.40808)
		(width 0.14224)
		(layer "In2.Cu")
		(net "GMI_CPU0_G2_CPU1_G0_TX_DN<2>")
	)
	(segment
		(start 99.680776 -209.93862)
		(end 99.680776 -209.748374)
		(width 0.14224)
		(layer "In2.Cu")
		(net "GMI_CPU0_G2_CPU1_G0_TX_DN<2>")
	)
	(segment
		(start 97.96399 -224.557082)
		(end 97.963228 -224.556574)
		(width 0.1143)
		(layer "In2.Cu")
		(net "GMI_CPU0_G2_CPU1_G0_TX_DN<2>")
	)
	(segment
		(start 103.109268 -206.319882)
		(end 103.299768 -206.319882)
		(width 0.14224)
		(layer "In2.Cu")
		(net "GMI_CPU0_G2_CPU1_G0_TX_DN<2>")
	)
	(segment
		(start 97.963228 -224.556574)
		(end 97.93224 -224.538794)
		(width 0.1143)
		(layer "In2.Cu")
		(net "GMI_CPU0_G2_CPU1_G0_TX_DN<2>")
	)
	(segment
		(start 97.96399 -223.911922)
		(end 98.003106 -223.889062)
		(width 0.1143)
		(layer "In2.Cu")
		(net "GMI_CPU0_G2_CPU1_G0_TX_DN<2>")
	)
	(segment
		(start 373.203724 -221.202758)
		(end 373.249444 -221.248478)
		(width 0.1143)
		(layer "In2.Cu")
		(net "GMI_CPU0_G2_CPU1_G0_TX_DN<2>")
	)
	(segment
		(start 97.965006 -224.55759)
		(end 97.96399 -224.557082)
		(width 0.1143)
		(layer "In2.Cu")
		(net "GMI_CPU0_G2_CPU1_G0_TX_DN<2>")
	)
	(segment
		(start 98.114612 -211.504784)
		(end 98.114612 -211.314538)
		(width 0.14224)
		(layer "In2.Cu")
		(net "GMI_CPU0_G2_CPU1_G0_TX_DN<2>")
	)
	(segment
		(start 97.93224 -225.550222)
		(end 97.96399 -225.531934)
		(width 0.1143)
		(layer "In2.Cu")
		(net "GMI_CPU0_G2_CPU1_G0_TX_DN<2>")
	)
	(segment
		(start 234.88904 -172.93209)
		(end 306.314856 -175.39081)
		(width 0.14224)
		(layer "In2.Cu")
		(net "GMI_CPU0_G2_CPU1_G0_TX_DN<2>")
	)
	(arc
		(start 373.25935 -226.558602)
		(mid 373.257327 -226.570012)
		(end 373.25554 -226.581462)
		(width 0.1143)
		(layer "In2.Cu")
		(net "GMI_CPU0_G2_CPU1_G0_TX_DN<2>")
	)
	(arc
		(start 97.93224 -224.538794)
		(mid 97.781855 -224.234502)
		(end 97.93224 -223.93021)
		(width 0.1143)
		(layer "In2.Cu")
		(net "GMI_CPU0_G2_CPU1_G0_TX_DN<2>")
	)
	(arc
		(start 98.003106 -223.889062)
		(mid 98.246433 -223.424496)
		(end 98.003106 -222.95993)
		(width 0.1143)
		(layer "In2.Cu")
		(net "GMI_CPU0_G2_CPU1_G0_TX_DN<2>")
	)
	(arc
		(start 373.249698 -221.80423)
		(mid 373.314072 -222.066434)
		(end 373.492776 -222.268796)
		(width 0.1143)
		(layer "In2.Cu")
		(net "GMI_CPU0_G2_CPU1_G0_TX_DN<2>")
	)
	(arc
		(start 97.786698 -222.622872)
		(mid 97.711167 -222.340227)
		(end 97.504504 -222.13316)
		(width 0.1143)
		(layer "In2.Cu")
		(net "GMI_CPU0_G2_CPU1_G0_TX_DN<2>")
	)
	(arc
		(start 373.562372 -223.929448)
		(mid 373.719349 -224.234248)
		(end 373.562372 -224.539048)
		(width 0.1143)
		(layer "In2.Cu")
		(net "GMI_CPU0_G2_CPU1_G0_TX_DN<2>")
	)
	(arc
		(start 373.492776 -224.579688)
		(mid 373.249449 -225.044254)
		(end 373.492776 -225.50882)
		(width 0.1143)
		(layer "In2.Cu")
		(net "GMI_CPU0_G2_CPU1_G0_TX_DN<2>")
	)
	(arc
		(start 373.492776 -226.1997)
		(mid 373.340789 -226.356208)
		(end 373.25935 -226.558602)
		(width 0.1143)
		(layer "In2.Cu")
		(net "GMI_CPU0_G2_CPU1_G0_TX_DN<2>")
	)
	(arc
		(start 98.240342 -226.581716)
		(mid 98.238554 -226.570267)
		(end 98.236532 -226.558856)
		(width 0.1143)
		(layer "In2.Cu")
		(net "GMI_CPU0_G2_CPU1_G0_TX_DN<2>")
	)
	(arc
		(start 97.462086 -222.108522)
		(mid 97.347559 -221.975282)
		(end 97.306384 -221.804484)
		(width 0.1143)
		(layer "In2.Cu")
		(net "GMI_CPU0_G2_CPU1_G0_TX_DN<2>")
	)
	(arc
		(start 98.236532 -226.558856)
		(mid 98.155099 -226.356458)
		(end 98.003106 -226.199954)
		(width 0.1143)
		(layer "In2.Cu")
		(net "GMI_CPU0_G2_CPU1_G0_TX_DN<2>")
	)
	(arc
		(start 373.492776 -222.959676)
		(mid 373.249449 -223.424242)
		(end 373.492776 -223.888808)
		(width 0.1143)
		(layer "In2.Cu")
		(net "GMI_CPU0_G2_CPU1_G0_TX_DN<2>")
	)
	(arc
		(start 98.003106 -225.509074)
		(mid 98.246433 -225.044508)
		(end 98.003106 -224.579942)
		(width 0.1143)
		(layer "In2.Cu")
		(net "GMI_CPU0_G2_CPU1_G0_TX_DN<2>")
	)
	(arc
		(start 373.562372 -225.54946)
		(mid 373.719349 -225.85426)
		(end 373.562372 -226.15906)
		(width 0.1143)
		(layer "In2.Cu")
		(net "GMI_CPU0_G2_CPU1_G0_TX_DN<2>")
	)
	(arc
		(start 373.562372 -222.309436)
		(mid 373.719349 -222.614236)
		(end 373.562372 -222.919036)
		(width 0.1143)
		(layer "In2.Cu")
		(net "GMI_CPU0_G2_CPU1_G0_TX_DN<2>")
	)
	(arc
		(start 97.93224 -226.158806)
		(mid 97.783143 -225.854514)
		(end 97.93224 -225.550222)
		(width 0.1143)
		(layer "In2.Cu")
		(net "GMI_CPU0_G2_CPU1_G0_TX_DN<2>")
	)
	(arc
		(start 97.963228 -222.936816)
		(mid 97.833951 -222.806989)
		(end 97.786698 -222.629984)
		(width 0.1143)
		(layer "In2.Cu")
		(net "GMI_CPU0_G2_CPU1_G0_TX_DN<2>")
	)
	(segment
		(start 99.08794 -228.55047)
		(end 98.621088 -228.284532)
		(width 0.12954)
		(layer "F.Cu")
		(net "GMI_CPU0_G2_CPU1_G0_TX_DN<1>")
	)
	(segment
		(start 372.407942 -228.550216)
		(end 372.874794 -228.284278)
		(width 0.12954)
		(layer "F.Cu")
		(net "GMI_CPU0_G2_CPU1_G0_TX_DN<1>")
	)
	(segment
		(start 98.906584 -222.938594)
		(end 98.90506 -222.937578)
		(width 0.1143)
		(layer "In2.Cu")
		(net "GMI_CPU0_G2_CPU1_G0_TX_DN<1>")
	)
	(segment
		(start 372.26367 -221.17431)
		(end 372.26367 -221.202758)
		(width 0.1143)
		(layer "In2.Cu")
		(net "GMI_CPU0_G2_CPU1_G0_TX_DN<1>")
	)
	(segment
		(start 100.625656 -210.322922)
		(end 100.92182 -210.026758)
		(width 0.14224)
		(layer "In2.Cu")
		(net "GMI_CPU0_G2_CPU1_G0_TX_DN<1>")
	)
	(segment
		(start 372.623588 -223.929956)
		(end 372.6434 -223.94418)
		(width 0.1143)
		(layer "In2.Cu")
		(net "GMI_CPU0_G2_CPU1_G0_TX_DN<1>")
	)
	(segment
		(start 101.408738 -209.53984)
		(end 101.704902 -209.243676)
		(width 0.14224)
		(layer "In2.Cu")
		(net "GMI_CPU0_G2_CPU1_G0_TX_DN<1>")
	)
	(segment
		(start 99.059492 -211.889086)
		(end 99.355656 -211.592922)
		(width 0.14224)
		(layer "In2.Cu")
		(net "GMI_CPU0_G2_CPU1_G0_TX_DN<1>")
	)
	(segment
		(start 98.872294 -225.550222)
		(end 98.904044 -225.531934)
		(width 0.1143)
		(layer "In2.Cu")
		(net "GMI_CPU0_G2_CPU1_G0_TX_DN<1>")
	)
	(segment
		(start 98.900488 -224.55505)
		(end 98.872294 -224.538794)
		(width 0.1143)
		(layer "In2.Cu")
		(net "GMI_CPU0_G2_CPU1_G0_TX_DN<1>")
	)
	(segment
		(start 98.90506 -224.55759)
		(end 98.904044 -224.557082)
		(width 0.1143)
		(layer "In2.Cu")
		(net "GMI_CPU0_G2_CPU1_G0_TX_DN<1>")
	)
	(segment
		(start 98.900488 -222.935038)
		(end 98.872294 -222.918782)
		(width 0.1143)
		(layer "In2.Cu")
		(net "GMI_CPU0_G2_CPU1_G0_TX_DN<1>")
	)
	(segment
		(start 372.30939 -221.248478)
		(end 372.30939 -221.624652)
		(width 0.1143)
		(layer "In2.Cu")
		(net "GMI_CPU0_G2_CPU1_G0_TX_DN<1>")
	)
	(segment
		(start 102.974902 -207.973676)
		(end 103.271066 -207.677512)
		(width 0.14224)
		(layer "In2.Cu")
		(net "GMI_CPU0_G2_CPU1_G0_TX_DN<1>")
	)
	(segment
		(start 99.355656 -211.592922)
		(end 99.546156 -211.592922)
		(width 0.14224)
		(layer "In2.Cu")
		(net "GMI_CPU0_G2_CPU1_G0_TX_DN<1>")
	)
	(segment
		(start 372.623588 -224.53854)
		(end 372.591838 -224.556828)
		(width 0.1143)
		(layer "In2.Cu")
		(net "GMI_CPU0_G2_CPU1_G0_TX_DN<1>")
	)
	(segment
		(start 104.541066 -206.407512)
		(end 106.532934 -204.415644)
		(width 0.14224)
		(layer "In2.Cu")
		(net "GMI_CPU0_G2_CPU1_G0_TX_DN<1>")
	)
	(segment
		(start 98.94316 -226.199954)
		(end 98.9076 -226.179126)
		(width 0.1143)
		(layer "In2.Cu")
		(net "GMI_CPU0_G2_CPU1_G0_TX_DN<1>")
	)
	(segment
		(start 164.516308 -176.40046)
		(end 234.962192 -173.875192)
		(width 0.14224)
		(layer "In2.Cu")
		(net "GMI_CPU0_G2_CPU1_G0_TX_DN<1>")
	)
	(segment
		(start 100.329238 -210.80984)
		(end 100.625656 -210.513168)
		(width 0.14224)
		(layer "In2.Cu")
		(net "GMI_CPU0_G2_CPU1_G0_TX_DN<1>")
	)
	(segment
		(start 101.408738 -209.730086)
		(end 101.408738 -209.53984)
		(width 0.14224)
		(layer "In2.Cu")
		(net "GMI_CPU0_G2_CPU1_G0_TX_DN<1>")
	)
	(segment
		(start 98.27641 -212.672168)
		(end 98.572574 -212.376004)
		(width 0.14224)
		(layer "In2.Cu")
		(net "GMI_CPU0_G2_CPU1_G0_TX_DN<1>")
	)
	(segment
		(start 98.246438 -221.627954)
		(end 98.23069 -221.612206)
		(width 0.1143)
		(layer "In2.Cu")
		(net "GMI_CPU0_G2_CPU1_G0_TX_DN<1>")
	)
	(segment
		(start 98.9076 -223.90989)
		(end 98.94316 -223.889062)
		(width 0.1143)
		(layer "In2.Cu")
		(net "GMI_CPU0_G2_CPU1_G0_TX_DN<1>")
	)
	(segment
		(start 372.591838 -224.556828)
		(end 372.552722 -224.579688)
		(width 0.1143)
		(layer "In2.Cu")
		(net "GMI_CPU0_G2_CPU1_G0_TX_DN<1>")
	)
	(segment
		(start 98.94316 -222.95993)
		(end 98.9076 -222.939102)
		(width 0.1143)
		(layer "In2.Cu")
		(net "GMI_CPU0_G2_CPU1_G0_TX_DN<1>")
	)
	(segment
		(start 101.704902 -209.243676)
		(end 101.895402 -209.243676)
		(width 0.14224)
		(layer "In2.Cu")
		(net "GMI_CPU0_G2_CPU1_G0_TX_DN<1>")
	)
	(segment
		(start 98.904044 -227.151946)
		(end 98.90506 -227.151438)
		(width 0.1143)
		(layer "In2.Cu")
		(net "GMI_CPU0_G2_CPU1_G0_TX_DN<1>")
	)
	(segment
		(start 372.26367 -221.202758)
		(end 372.30939 -221.248478)
		(width 0.1143)
		(layer "In2.Cu")
		(net "GMI_CPU0_G2_CPU1_G0_TX_DN<1>")
	)
	(segment
		(start 372.591838 -222.936816)
		(end 372.552722 -222.959676)
		(width 0.1143)
		(layer "In2.Cu")
		(net "GMI_CPU0_G2_CPU1_G0_TX_DN<1>")
	)
	(segment
		(start 98.23069 -221.612206)
		(end 98.23069 -221.248732)
		(width 0.1143)
		(layer "In2.Cu")
		(net "GMI_CPU0_G2_CPU1_G0_TX_DN<1>")
	)
	(segment
		(start 98.903282 -222.936562)
		(end 98.902012 -222.9358)
		(width 0.1143)
		(layer "In2.Cu")
		(net "GMI_CPU0_G2_CPU1_G0_TX_DN<1>")
	)
	(segment
		(start 372.309644 -221.624906)
		(end 372.309644 -221.80423)
		(width 0.1143)
		(layer "In2.Cu")
		(net "GMI_CPU0_G2_CPU1_G0_TX_DN<1>")
	)
	(segment
		(start 103.271066 -207.677512)
		(end 103.461566 -207.677512)
		(width 0.14224)
		(layer "In2.Cu")
		(net "GMI_CPU0_G2_CPU1_G0_TX_DN<1>")
	)
	(segment
		(start 309.808118 -177.305208)
		(end 312.062876 -178.16322)
		(width 0.14224)
		(layer "In2.Cu")
		(net "GMI_CPU0_G2_CPU1_G0_TX_DN<1>")
	)
	(segment
		(start 372.792244 -227.483924)
		(end 372.792244 -227.49637)
		(width 0.1143)
		(layer "In2.Cu")
		(net "GMI_CPU0_G2_CPU1_G0_TX_DN<1>")
	)
	(segment
		(start 373.0625 -227.962206)
		(end 373.093488 -227.979986)
		(width 0.1143)
		(layer "In2.Cu")
		(net "GMI_CPU0_G2_CPU1_G0_TX_DN<1>")
	)
	(segment
		(start 98.872294 -227.170234)
		(end 98.904044 -227.151946)
		(width 0.1143)
		(layer "In2.Cu")
		(net "GMI_CPU0_G2_CPU1_G0_TX_DN<1>")
	)
	(segment
		(start 102.19182 -208.947004)
		(end 102.19182 -208.756758)
		(width 0.14224)
		(layer "In2.Cu")
		(net "GMI_CPU0_G2_CPU1_G0_TX_DN<1>")
	)
	(segment
		(start 372.552722 -222.268796)
		(end 372.623588 -222.309944)
		(width 0.1143)
		(layer "In2.Cu")
		(net "GMI_CPU0_G2_CPU1_G0_TX_DN<1>")
	)
	(segment
		(start 98.904044 -224.557082)
		(end 98.903282 -224.556574)
		(width 0.1143)
		(layer "In2.Cu")
		(net "GMI_CPU0_G2_CPU1_G0_TX_DN<1>")
	)
	(segment
		(start 372.552722 -223.888808)
		(end 372.623588 -223.929956)
		(width 0.1143)
		(layer "In2.Cu")
		(net "GMI_CPU0_G2_CPU1_G0_TX_DN<1>")
	)
	(segment
		(start 98.90506 -223.911414)
		(end 98.906584 -223.910398)
		(width 0.1143)
		(layer "In2.Cu")
		(net "GMI_CPU0_G2_CPU1_G0_TX_DN<1>")
	)
	(segment
		(start 98.902012 -226.175824)
		(end 98.900488 -226.175062)
		(width 0.1143)
		(layer "In2.Cu")
		(net "GMI_CPU0_G2_CPU1_G0_TX_DN<1>")
	)
	(segment
		(start 98.621088 -228.284532)
		(end 98.323146 -228.284532)
		(width 0.1143)
		(layer "In2.Cu")
		(net "GMI_CPU0_G2_CPU1_G0_TX_DN<1>")
	)
	(segment
		(start 102.19182 -208.756758)
		(end 102.487984 -208.460594)
		(width 0.14224)
		(layer "In2.Cu")
		(net "GMI_CPU0_G2_CPU1_G0_TX_DN<1>")
	)
	(segment
		(start 98.9076 -222.939102)
		(end 98.906584 -222.938594)
		(width 0.1143)
		(layer "In2.Cu")
		(net "GMI_CPU0_G2_CPU1_G0_TX_DN<1>")
	)
	(segment
		(start 102.974902 -208.163922)
		(end 102.974902 -207.973676)
		(width 0.14224)
		(layer "In2.Cu")
		(net "GMI_CPU0_G2_CPU1_G0_TX_DN<1>")
	)
	(segment
		(start 358.220264 -203.905104)
		(end 365.147098 -208.592928)
		(width 0.14224)
		(layer "In2.Cu")
		(net "GMI_CPU0_G2_CPU1_G0_TX_DN<1>")
	)
	(segment
		(start 98.763074 -212.376004)
		(end 99.059492 -212.079332)
		(width 0.14224)
		(layer "In2.Cu")
		(net "GMI_CPU0_G2_CPU1_G0_TX_DN<1>")
	)
	(segment
		(start 98.94316 -224.579942)
		(end 98.9076 -224.559114)
		(width 0.1143)
		(layer "In2.Cu")
		(net "GMI_CPU0_G2_CPU1_G0_TX_DN<1>")
	)
	(segment
		(start 98.872294 -223.93021)
		(end 98.902012 -223.913192)
		(width 0.1143)
		(layer "In2.Cu")
		(net "GMI_CPU0_G2_CPU1_G0_TX_DN<1>")
	)
	(segment
		(start 98.906584 -223.910398)
		(end 98.9076 -223.90989)
		(width 0.1143)
		(layer "In2.Cu")
		(net "GMI_CPU0_G2_CPU1_G0_TX_DN<1>")
	)
	(segment
		(start 98.903282 -223.91243)
		(end 98.904044 -223.911922)
		(width 0.1143)
		(layer "In2.Cu")
		(net "GMI_CPU0_G2_CPU1_G0_TX_DN<1>")
	)
	(segment
		(start 372.30939 -221.624652)
		(end 372.309644 -221.624906)
		(width 0.1143)
		(layer "In2.Cu")
		(net "GMI_CPU0_G2_CPU1_G0_TX_DN<1>")
	)
	(segment
		(start 100.625656 -210.513168)
		(end 100.625656 -210.322922)
		(width 0.14224)
		(layer "In2.Cu")
		(net "GMI_CPU0_G2_CPU1_G0_TX_DN<1>")
	)
	(segment
		(start 98.906584 -225.53041)
		(end 98.94316 -225.509074)
		(width 0.1143)
		(layer "In2.Cu")
		(net "GMI_CPU0_G2_CPU1_G0_TX_DN<1>")
	)
	(segment
		(start 99.059492 -212.079332)
		(end 99.059492 -211.889086)
		(width 0.14224)
		(layer "In2.Cu")
		(net "GMI_CPU0_G2_CPU1_G0_TX_DN<1>")
	)
	(segment
		(start 98.903282 -224.556574)
		(end 98.902012 -224.555812)
		(width 0.1143)
		(layer "In2.Cu")
		(net "GMI_CPU0_G2_CPU1_G0_TX_DN<1>")
	)
	(segment
		(start 104.541066 -206.597758)
		(end 104.541066 -206.407512)
		(width 0.14224)
		(layer "In2.Cu")
		(net "GMI_CPU0_G2_CPU1_G0_TX_DN<1>")
	)
	(segment
		(start 100.138738 -210.80984)
		(end 100.329238 -210.80984)
		(width 0.14224)
		(layer "In2.Cu")
		(net "GMI_CPU0_G2_CPU1_G0_TX_DN<1>")
	)
	(segment
		(start 102.487984 -208.460594)
		(end 102.678484 -208.460594)
		(width 0.14224)
		(layer "In2.Cu")
		(net "GMI_CPU0_G2_CPU1_G0_TX_DN<1>")
	)
	(segment
		(start 372.6434 -224.524316)
		(end 372.623588 -224.53854)
		(width 0.1143)
		(layer "In2.Cu")
		(net "GMI_CPU0_G2_CPU1_G0_TX_DN<1>")
	)
	(segment
		(start 104.244648 -206.89443)
		(end 104.541066 -206.597758)
		(width 0.14224)
		(layer "In2.Cu")
		(net "GMI_CPU0_G2_CPU1_G0_TX_DN<1>")
	)
	(segment
		(start 98.906584 -224.558606)
		(end 98.90506 -224.55759)
		(width 0.1143)
		(layer "In2.Cu")
		(net "GMI_CPU0_G2_CPU1_G0_TX_DN<1>")
	)
	(segment
		(start 99.842574 -211.106004)
		(end 100.138738 -210.80984)
		(width 0.14224)
		(layer "In2.Cu")
		(net "GMI_CPU0_G2_CPU1_G0_TX_DN<1>")
	)
	(segment
		(start 98.904044 -226.177094)
		(end 98.903282 -226.176586)
		(width 0.1143)
		(layer "In2.Cu")
		(net "GMI_CPU0_G2_CPU1_G0_TX_DN<1>")
	)
	(segment
		(start 98.906584 -227.150422)
		(end 98.94316 -227.129086)
		(width 0.1143)
		(layer "In2.Cu")
		(net "GMI_CPU0_G2_CPU1_G0_TX_DN<1>")
	)
	(segment
		(start 98.23069 -221.248732)
		(end 98.27641 -221.203012)
		(width 0.1143)
		(layer "In2.Cu")
		(net "GMI_CPU0_G2_CPU1_G0_TX_DN<1>")
	)
	(segment
		(start 98.90506 -227.151438)
		(end 98.906584 -227.150422)
		(width 0.1143)
		(layer "In2.Cu")
		(net "GMI_CPU0_G2_CPU1_G0_TX_DN<1>")
	)
	(segment
		(start 98.904044 -223.911922)
		(end 98.90506 -223.911414)
		(width 0.1143)
		(layer "In2.Cu")
		(net "GMI_CPU0_G2_CPU1_G0_TX_DN<1>")
	)
	(segment
		(start 106.532934 -204.415644)
		(end 151.710898 -181.365398)
		(width 0.14224)
		(layer "In2.Cu")
		(net "GMI_CPU0_G2_CPU1_G0_TX_DN<1>")
	)
	(segment
		(start 98.902012 -223.913192)
		(end 98.903282 -223.91243)
		(width 0.1143)
		(layer "In2.Cu")
		(net "GMI_CPU0_G2_CPU1_G0_TX_DN<1>")
	)
	(segment
		(start 99.842574 -211.29625)
		(end 99.842574 -211.106004)
		(width 0.14224)
		(layer "In2.Cu")
		(net "GMI_CPU0_G2_CPU1_G0_TX_DN<1>")
	)
	(segment
		(start 98.27641 -221.174564)
		(end 98.27641 -212.672168)
		(width 0.14224)
		(layer "In2.Cu")
		(net "GMI_CPU0_G2_CPU1_G0_TX_DN<1>")
	)
	(segment
		(start 98.43389 -227.961952)
		(end 98.473006 -227.939092)
		(width 0.1143)
		(layer "In2.Cu")
		(net "GMI_CPU0_G2_CPU1_G0_TX_DN<1>")
	)
	(segment
		(start 98.90506 -225.531426)
		(end 98.906584 -225.53041)
		(width 0.1143)
		(layer "In2.Cu")
		(net "GMI_CPU0_G2_CPU1_G0_TX_DN<1>")
	)
	(segment
		(start 151.710898 -181.365398)
		(end 161.31286 -177.31486)
		(width 0.14224)
		(layer "In2.Cu")
		(net "GMI_CPU0_G2_CPU1_G0_TX_DN<1>")
	)
	(segment
		(start 372.552722 -227.128832)
		(end 372.604538 -227.159058)
		(width 0.1143)
		(layer "In2.Cu")
		(net "GMI_CPU0_G2_CPU1_G0_TX_DN<1>")
	)
	(segment
		(start 372.623588 -222.918528)
		(end 372.591838 -222.936816)
		(width 0.1143)
		(layer "In2.Cu")
		(net "GMI_CPU0_G2_CPU1_G0_TX_DN<1>")
	)
	(segment
		(start 98.572574 -212.376004)
		(end 98.763074 -212.376004)
		(width 0.14224)
		(layer "In2.Cu")
		(net "GMI_CPU0_G2_CPU1_G0_TX_DN<1>")
	)
	(segment
		(start 365.147098 -208.592928)
		(end 369.962938 -212.788246)
		(width 0.14224)
		(layer "In2.Cu")
		(net "GMI_CPU0_G2_CPU1_G0_TX_DN<1>")
	)
	(segment
		(start 372.591838 -225.53168)
		(end 372.623588 -225.549968)
		(width 0.1143)
		(layer "In2.Cu")
		(net "GMI_CPU0_G2_CPU1_G0_TX_DN<1>")
	)
	(segment
		(start 100.92182 -210.026758)
		(end 101.11232 -210.026758)
		(width 0.14224)
		(layer "In2.Cu")
		(net "GMI_CPU0_G2_CPU1_G0_TX_DN<1>")
	)
	(segment
		(start 103.757984 -207.190594)
		(end 104.054148 -206.89443)
		(width 0.14224)
		(layer "In2.Cu")
		(net "GMI_CPU0_G2_CPU1_G0_TX_DN<1>")
	)
	(segment
		(start 98.27641 -221.203012)
		(end 98.27641 -221.174564)
		(width 0.1143)
		(layer "In2.Cu")
		(net "GMI_CPU0_G2_CPU1_G0_TX_DN<1>")
	)
	(segment
		(start 99.546156 -211.592922)
		(end 99.842574 -211.29625)
		(width 0.14224)
		(layer "In2.Cu")
		(net "GMI_CPU0_G2_CPU1_G0_TX_DN<1>")
	)
	(segment
		(start 98.903282 -226.176586)
		(end 98.902012 -226.175824)
		(width 0.1143)
		(layer "In2.Cu")
		(net "GMI_CPU0_G2_CPU1_G0_TX_DN<1>")
	)
	(segment
		(start 98.90506 -222.937578)
		(end 98.904044 -222.93707)
		(width 0.1143)
		(layer "In2.Cu")
		(net "GMI_CPU0_G2_CPU1_G0_TX_DN<1>")
	)
	(segment
		(start 161.31286 -177.31486)
		(end 164.516308 -176.40046)
		(width 0.14224)
		(layer "In2.Cu")
		(net "GMI_CPU0_G2_CPU1_G0_TX_DN<1>")
	)
	(segment
		(start 98.323146 -228.284532)
		(end 98.253296 -228.214682)
		(width 0.1143)
		(layer "In2.Cu")
		(net "GMI_CPU0_G2_CPU1_G0_TX_DN<1>")
	)
	(segment
		(start 98.902012 -222.9358)
		(end 98.900488 -222.935038)
		(width 0.1143)
		(layer "In2.Cu")
		(net "GMI_CPU0_G2_CPU1_G0_TX_DN<1>")
	)
	(segment
		(start 103.461566 -207.677512)
		(end 103.757984 -207.38084)
		(width 0.14224)
		(layer "In2.Cu")
		(net "GMI_CPU0_G2_CPU1_G0_TX_DN<1>")
	)
	(segment
		(start 98.246438 -221.804484)
		(end 98.246438 -221.627954)
		(width 0.1143)
		(layer "In2.Cu")
		(net "GMI_CPU0_G2_CPU1_G0_TX_DN<1>")
	)
	(segment
		(start 312.062876 -178.16322)
		(end 326.25792 -185.000138)
		(width 0.14224)
		(layer "In2.Cu")
		(net "GMI_CPU0_G2_CPU1_G0_TX_DN<1>")
	)
	(segment
		(start 372.26367 -217.844624)
		(end 372.26367 -221.17431)
		(width 0.14224)
		(layer "In2.Cu")
		(net "GMI_CPU0_G2_CPU1_G0_TX_DN<1>")
	)
	(segment
		(start 98.904044 -222.93707)
		(end 98.903282 -222.936562)
		(width 0.1143)
		(layer "In2.Cu")
		(net "GMI_CPU0_G2_CPU1_G0_TX_DN<1>")
	)
	(segment
		(start 98.40341 -227.979732)
		(end 98.43389 -227.961952)
		(width 0.1143)
		(layer "In2.Cu")
		(net "GMI_CPU0_G2_CPU1_G0_TX_DN<1>")
	)
	(segment
		(start 373.172736 -228.284278)
		(end 372.874794 -228.284278)
		(width 0.1143)
		(layer "In2.Cu")
		(net "GMI_CPU0_G2_CPU1_G0_TX_DN<1>")
	)
	(segment
		(start 372.552722 -225.50882)
		(end 372.591838 -225.53168)
		(width 0.1143)
		(layer "In2.Cu")
		(net "GMI_CPU0_G2_CPU1_G0_TX_DN<1>")
	)
	(segment
		(start 98.9076 -226.179126)
		(end 98.906584 -226.178618)
		(width 0.1143)
		(layer "In2.Cu")
		(net "GMI_CPU0_G2_CPU1_G0_TX_DN<1>")
	)
	(segment
		(start 98.904044 -225.531934)
		(end 98.90506 -225.531426)
		(width 0.1143)
		(layer "In2.Cu")
		(net "GMI_CPU0_G2_CPU1_G0_TX_DN<1>")
	)
	(segment
		(start 373.059452 -227.960428)
		(end 373.061738 -227.961698)
		(width 0.1143)
		(layer "In2.Cu")
		(net "GMI_CPU0_G2_CPU1_G0_TX_DN<1>")
	)
	(segment
		(start 373.061738 -227.961698)
		(end 373.0625 -227.962206)
		(width 0.1143)
		(layer "In2.Cu")
		(net "GMI_CPU0_G2_CPU1_G0_TX_DN<1>")
	)
	(segment
		(start 373.242586 -228.214428)
		(end 373.172736 -228.284278)
		(width 0.1143)
		(layer "In2.Cu")
		(net "GMI_CPU0_G2_CPU1_G0_TX_DN<1>")
	)
	(segment
		(start 98.90506 -226.177602)
		(end 98.904044 -226.177094)
		(width 0.1143)
		(layer "In2.Cu")
		(net "GMI_CPU0_G2_CPU1_G0_TX_DN<1>")
	)
	(segment
		(start 234.962192 -173.875192)
		(end 306.015136 -176.321212)
		(width 0.14224)
		(layer "In2.Cu")
		(net "GMI_CPU0_G2_CPU1_G0_TX_DN<1>")
	)
	(segment
		(start 98.9076 -224.559114)
		(end 98.906584 -224.558606)
		(width 0.1143)
		(layer "In2.Cu")
		(net "GMI_CPU0_G2_CPU1_G0_TX_DN<1>")
	)
	(segment
		(start 104.054148 -206.89443)
		(end 104.244648 -206.89443)
		(width 0.14224)
		(layer "In2.Cu")
		(net "GMI_CPU0_G2_CPU1_G0_TX_DN<1>")
	)
	(segment
		(start 98.902012 -224.555812)
		(end 98.900488 -224.55505)
		(width 0.1143)
		(layer "In2.Cu")
		(net "GMI_CPU0_G2_CPU1_G0_TX_DN<1>")
	)
	(segment
		(start 101.895402 -209.243676)
		(end 102.19182 -208.947004)
		(width 0.14224)
		(layer "In2.Cu")
		(net "GMI_CPU0_G2_CPU1_G0_TX_DN<1>")
	)
	(segment
		(start 372.623588 -226.158552)
		(end 372.591838 -226.17684)
		(width 0.1143)
		(layer "In2.Cu")
		(net "GMI_CPU0_G2_CPU1_G0_TX_DN<1>")
	)
	(segment
		(start 101.11232 -210.026758)
		(end 101.408738 -209.730086)
		(width 0.14224)
		(layer "In2.Cu")
		(net "GMI_CPU0_G2_CPU1_G0_TX_DN<1>")
	)
	(segment
		(start 369.962938 -212.788246)
		(end 372.26367 -217.844624)
		(width 0.14224)
		(layer "In2.Cu")
		(net "GMI_CPU0_G2_CPU1_G0_TX_DN<1>")
	)
	(segment
		(start 326.25792 -185.000138)
		(end 358.220264 -203.905104)
		(width 0.14224)
		(layer "In2.Cu")
		(net "GMI_CPU0_G2_CPU1_G0_TX_DN<1>")
	)
	(segment
		(start 103.757984 -207.38084)
		(end 103.757984 -207.190594)
		(width 0.14224)
		(layer "In2.Cu")
		(net "GMI_CPU0_G2_CPU1_G0_TX_DN<1>")
	)
	(segment
		(start 306.015136 -176.321212)
		(end 309.808118 -177.305208)
		(width 0.14224)
		(layer "In2.Cu")
		(net "GMI_CPU0_G2_CPU1_G0_TX_DN<1>")
	)
	(segment
		(start 98.471736 -222.148908)
		(end 98.401378 -222.108014)
		(width 0.1143)
		(layer "In2.Cu")
		(net "GMI_CPU0_G2_CPU1_G0_TX_DN<1>")
	)
	(segment
		(start 372.591838 -226.17684)
		(end 372.552722 -226.1997)
		(width 0.1143)
		(layer "In2.Cu")
		(net "GMI_CPU0_G2_CPU1_G0_TX_DN<1>")
	)
	(segment
		(start 98.906584 -226.178618)
		(end 98.90506 -226.177602)
		(width 0.1143)
		(layer "In2.Cu")
		(net "GMI_CPU0_G2_CPU1_G0_TX_DN<1>")
	)
	(segment
		(start 98.900488 -226.175062)
		(end 98.872294 -226.158806)
		(width 0.1143)
		(layer "In2.Cu")
		(net "GMI_CPU0_G2_CPU1_G0_TX_DN<1>")
	)
	(segment
		(start 102.678484 -208.460594)
		(end 102.974902 -208.163922)
		(width 0.14224)
		(layer "In2.Cu")
		(net "GMI_CPU0_G2_CPU1_G0_TX_DN<1>")
	)
	(arc
		(start 98.872294 -226.158806)
		(mid 98.716366 -225.854514)
		(end 98.872294 -225.550222)
		(width 0.1143)
		(layer "In2.Cu")
		(net "GMI_CPU0_G2_CPU1_G0_TX_DN<1>")
	)
	(arc
		(start 372.604538 -227.159058)
		(mid 372.74197 -227.296317)
		(end 372.792244 -227.483924)
		(width 0.1143)
		(layer "In2.Cu")
		(net "GMI_CPU0_G2_CPU1_G0_TX_DN<1>")
	)
	(arc
		(start 98.94316 -227.129086)
		(mid 99.186487 -226.66452)
		(end 98.94316 -226.199954)
		(width 0.1143)
		(layer "In2.Cu")
		(net "GMI_CPU0_G2_CPU1_G0_TX_DN<1>")
	)
	(arc
		(start 372.552722 -226.1997)
		(mid 372.309395 -226.664266)
		(end 372.552722 -227.128832)
		(width 0.1143)
		(layer "In2.Cu")
		(net "GMI_CPU0_G2_CPU1_G0_TX_DN<1>")
	)
	(arc
		(start 98.872294 -222.918782)
		(mid 98.757618 -222.785448)
		(end 98.716338 -222.61449)
		(width 0.1143)
		(layer "In2.Cu")
		(net "GMI_CPU0_G2_CPU1_G0_TX_DN<1>")
	)
	(arc
		(start 98.401378 -222.108014)
		(mid 98.287449 -221.974867)
		(end 98.246438 -221.804484)
		(width 0.1143)
		(layer "In2.Cu")
		(net "GMI_CPU0_G2_CPU1_G0_TX_DN<1>")
	)
	(arc
		(start 98.94316 -225.509074)
		(mid 99.186487 -225.044508)
		(end 98.94316 -224.579942)
		(width 0.1143)
		(layer "In2.Cu")
		(net "GMI_CPU0_G2_CPU1_G0_TX_DN<1>")
	)
	(arc
		(start 372.792244 -227.49637)
		(mid 372.86383 -227.7641)
		(end 373.059452 -227.960428)
		(width 0.1143)
		(layer "In2.Cu")
		(net "GMI_CPU0_G2_CPU1_G0_TX_DN<1>")
	)
	(arc
		(start 98.716338 -227.474526)
		(mid 98.757593 -227.303555)
		(end 98.872294 -227.170234)
		(width 0.1143)
		(layer "In2.Cu")
		(net "GMI_CPU0_G2_CPU1_G0_TX_DN<1>")
	)
	(arc
		(start 372.623588 -222.309944)
		(mid 372.775177 -222.614236)
		(end 372.623588 -222.918528)
		(width 0.1143)
		(layer "In2.Cu")
		(net "GMI_CPU0_G2_CPU1_G0_TX_DN<1>")
	)
	(arc
		(start 372.552722 -222.959676)
		(mid 372.309395 -223.424242)
		(end 372.552722 -223.888808)
		(width 0.1143)
		(layer "In2.Cu")
		(net "GMI_CPU0_G2_CPU1_G0_TX_DN<1>")
	)
	(arc
		(start 98.253296 -228.214682)
		(mid 98.305713 -228.082751)
		(end 98.40341 -227.979732)
		(width 0.1143)
		(layer "In2.Cu")
		(net "GMI_CPU0_G2_CPU1_G0_TX_DN<1>")
	)
	(arc
		(start 373.093488 -227.979986)
		(mid 373.190623 -228.082855)
		(end 373.242586 -228.214428)
		(width 0.1143)
		(layer "In2.Cu")
		(net "GMI_CPU0_G2_CPU1_G0_TX_DN<1>")
	)
	(arc
		(start 372.623588 -225.549968)
		(mid 372.775177 -225.85426)
		(end 372.623588 -226.158552)
		(width 0.1143)
		(layer "In2.Cu")
		(net "GMI_CPU0_G2_CPU1_G0_TX_DN<1>")
	)
	(arc
		(start 98.473006 -227.939092)
		(mid 98.651819 -227.736742)
		(end 98.716338 -227.474526)
		(width 0.1143)
		(layer "In2.Cu")
		(net "GMI_CPU0_G2_CPU1_G0_TX_DN<1>")
	)
	(arc
		(start 372.6434 -223.94418)
		(mid 372.792114 -224.234248)
		(end 372.6434 -224.524316)
		(width 0.1143)
		(layer "In2.Cu")
		(net "GMI_CPU0_G2_CPU1_G0_TX_DN<1>")
	)
	(arc
		(start 98.94316 -223.889062)
		(mid 99.186487 -223.424496)
		(end 98.94316 -222.95993)
		(width 0.1143)
		(layer "In2.Cu")
		(net "GMI_CPU0_G2_CPU1_G0_TX_DN<1>")
	)
	(arc
		(start 98.716338 -222.61449)
		(mid 98.651466 -222.351527)
		(end 98.471736 -222.148908)
		(width 0.1143)
		(layer "In2.Cu")
		(net "GMI_CPU0_G2_CPU1_G0_TX_DN<1>")
	)
	(arc
		(start 372.552722 -224.579688)
		(mid 372.309395 -225.044254)
		(end 372.552722 -225.50882)
		(width 0.1143)
		(layer "In2.Cu")
		(net "GMI_CPU0_G2_CPU1_G0_TX_DN<1>")
	)
	(arc
		(start 98.872294 -224.538794)
		(mid 98.716366 -224.234502)
		(end 98.872294 -223.93021)
		(width 0.1143)
		(layer "In2.Cu")
		(net "GMI_CPU0_G2_CPU1_G0_TX_DN<1>")
	)
	(arc
		(start 372.309644 -221.80423)
		(mid 372.374091 -222.066382)
		(end 372.552722 -222.268796)
		(width 0.1143)
		(layer "In2.Cu")
		(net "GMI_CPU0_G2_CPU1_G0_TX_DN<1>")
	)
	(segment
		(start 361.597956 -230.97998)
		(end 362.064808 -230.714296)
		(width 0.12954)
		(layer "F.Cu")
		(net "GMI_CPU0_G2_CPU1_G0_TX_DN<15>")
	)
	(segment
		(start 109.897926 -230.980234)
		(end 109.431074 -230.71455)
		(width 0.12954)
		(layer "F.Cu")
		(net "GMI_CPU0_G2_CPU1_G0_TX_DN<15>")
	)
	(segment
		(start 362.36275 -230.714296)
		(end 362.432854 -230.644192)
		(width 0.1143)
		(layer "In2.Cu")
		(net "GMI_CPU0_G2_CPU1_G0_TX_DN<15>")
	)
	(segment
		(start 110.46587 -221.580202)
		(end 110.46587 -221.804738)
		(width 0.1143)
		(layer "In2.Cu")
		(net "GMI_CPU0_G2_CPU1_G0_TX_DN<15>")
	)
	(segment
		(start 111.096552 -222.921322)
		(end 111.107728 -222.927926)
		(width 0.1143)
		(layer "In2.Cu")
		(net "GMI_CPU0_G2_CPU1_G0_TX_DN<15>")
	)
	(segment
		(start 119.056658 -214.093552)
		(end 118.683786 -214.28583)
		(width 0.14224)
		(layer "In2.Cu")
		(net "GMI_CPU0_G2_CPU1_G0_TX_DN<15>")
	)
	(segment
		(start 110.51413 -221.273116)
		(end 110.51413 -221.531942)
		(width 0.1143)
		(layer "In2.Cu")
		(net "GMI_CPU0_G2_CPU1_G0_TX_DN<15>")
	)
	(segment
		(start 109.243622 -230.391716)
		(end 109.214158 -230.408988)
		(width 0.1143)
		(layer "In2.Cu")
		(net "GMI_CPU0_G2_CPU1_G0_TX_DN<15>")
	)
	(segment
		(start 111.092488 -222.918782)
		(end 111.096552 -222.921322)
		(width 0.1143)
		(layer "In2.Cu")
		(net "GMI_CPU0_G2_CPU1_G0_TX_DN<15>")
	)
	(segment
		(start 111.304832 -223.26219)
		(end 111.304832 -227.447856)
		(width 0.1143)
		(layer "In2.Cu")
		(net "GMI_CPU0_G2_CPU1_G0_TX_DN<15>")
	)
	(segment
		(start 109.513624 -229.913688)
		(end 109.513624 -229.924102)
		(width 0.1143)
		(layer "In2.Cu")
		(net "GMI_CPU0_G2_CPU1_G0_TX_DN<15>")
	)
	(segment
		(start 113.243106 -217.826082)
		(end 112.946942 -218.122246)
		(width 0.14224)
		(layer "In2.Cu")
		(net "GMI_CPU0_G2_CPU1_G0_TX_DN<15>")
	)
	(segment
		(start 114.498882 -216.75344)
		(end 114.20221 -217.050112)
		(width 0.14224)
		(layer "In2.Cu")
		(net "GMI_CPU0_G2_CPU1_G0_TX_DN<15>")
	)
	(segment
		(start 360.745532 -227.891086)
		(end 360.351832 -227.49764)
		(width 0.1143)
		(layer "In2.Cu")
		(net "GMI_CPU0_G2_CPU1_G0_TX_DN<15>")
	)
	(segment
		(start 111.395002 -219.85732)
		(end 111.098584 -220.153738)
		(width 0.14224)
		(layer "In2.Cu")
		(net "GMI_CPU0_G2_CPU1_G0_TX_DN<15>")
	)
	(segment
		(start 362.432854 -230.644192)
		(end 362.433108 -230.644192)
		(width 0.1143)
		(layer "In2.Cu")
		(net "GMI_CPU0_G2_CPU1_G0_TX_DN<15>")
	)
	(segment
		(start 163.395152 -191.062102)
		(end 119.112284 -213.919054)
		(width 0.14224)
		(layer "In2.Cu")
		(net "GMI_CPU0_G2_CPU1_G0_TX_DN<15>")
	)
	(segment
		(start 110.91545 -220.153738)
		(end 110.55985 -220.509338)
		(width 0.14224)
		(layer "In2.Cu")
		(net "GMI_CPU0_G2_CPU1_G0_TX_DN<15>")
	)
	(segment
		(start 362.281724 -230.408734)
		(end 362.25607 -230.394002)
		(width 0.1143)
		(layer "In2.Cu")
		(net "GMI_CPU0_G2_CPU1_G0_TX_DN<15>")
	)
	(segment
		(start 117.70868 -214.789258)
		(end 117.534182 -214.733632)
		(width 0.14224)
		(layer "In2.Cu")
		(net "GMI_CPU0_G2_CPU1_G0_TX_DN<15>")
	)
	(segment
		(start 118.683786 -214.28583)
		(end 118.509288 -214.230204)
		(width 0.14224)
		(layer "In2.Cu")
		(net "GMI_CPU0_G2_CPU1_G0_TX_DN<15>")
	)
	(segment
		(start 111.12373 -222.927926)
		(end 111.196882 -223.001078)
		(width 0.1143)
		(layer "In2.Cu")
		(net "GMI_CPU0_G2_CPU1_G0_TX_DN<15>")
	)
	(segment
		(start 117.106192 -215.100408)
		(end 116.733574 -215.292686)
		(width 0.14224)
		(layer "In2.Cu")
		(net "GMI_CPU0_G2_CPU1_G0_TX_DN<15>")
	)
	(segment
		(start 110.184184 -228.771704)
		(end 110.18393 -228.771958)
		(width 0.1143)
		(layer "In2.Cu")
		(net "GMI_CPU0_G2_CPU1_G0_TX_DN<15>")
	)
	(segment
		(start 119.112284 -213.9188)
		(end 119.056658 -214.093552)
		(width 0.14224)
		(layer "In2.Cu")
		(net "GMI_CPU0_G2_CPU1_G0_TX_DN<15>")
	)
	(segment
		(start 110.51413 -221.531942)
		(end 110.46587 -221.580202)
		(width 0.1143)
		(layer "In2.Cu")
		(net "GMI_CPU0_G2_CPU1_G0_TX_DN<15>")
	)
	(segment
		(start 119.112284 -213.919054)
		(end 119.112284 -213.9188)
		(width 0.14224)
		(layer "In2.Cu")
		(net "GMI_CPU0_G2_CPU1_G0_TX_DN<15>")
	)
	(segment
		(start 236.44225 -186.633866)
		(end 222.399606 -188.780166)
		(width 0.14224)
		(layer "In2.Cu")
		(net "GMI_CPU0_G2_CPU1_G0_TX_DN<15>")
	)
	(segment
		(start 359.866438 -223.122998)
		(end 358.773222 -220.483684)
		(width 0.14224)
		(layer "In2.Cu")
		(net "GMI_CPU0_G2_CPU1_G0_TX_DN<15>")
	)
	(segment
		(start 118.136924 -214.422228)
		(end 118.081298 -214.59698)
		(width 0.14224)
		(layer "In2.Cu")
		(net "GMI_CPU0_G2_CPU1_G0_TX_DN<15>")
	)
	(segment
		(start 109.063282 -230.6447)
		(end 109.133132 -230.71455)
		(width 0.1143)
		(layer "In2.Cu")
		(net "GMI_CPU0_G2_CPU1_G0_TX_DN<15>")
	)
	(segment
		(start 116.733574 -215.292686)
		(end 116.559076 -215.23706)
		(width 0.14224)
		(layer "In2.Cu")
		(net "GMI_CPU0_G2_CPU1_G0_TX_DN<15>")
	)
	(segment
		(start 358.773222 -220.483684)
		(end 355.536754 -217.247216)
		(width 0.14224)
		(layer "In2.Cu")
		(net "GMI_CPU0_G2_CPU1_G0_TX_DN<15>")
	)
	(segment
		(start 359.912158 -226.148138)
		(end 359.866438 -226.102418)
		(width 0.1143)
		(layer "In2.Cu")
		(net "GMI_CPU0_G2_CPU1_G0_TX_DN<15>")
	)
	(segment
		(start 112.467136 -218.602052)
		(end 112.170972 -218.898216)
		(width 0.14224)
		(layer "In2.Cu")
		(net "GMI_CPU0_G2_CPU1_G0_TX_DN<15>")
	)
	(segment
		(start 222.399606 -188.780166)
		(end 222.399606 -188.78042)
		(width 0.14224)
		(layer "In2.Cu")
		(net "GMI_CPU0_G2_CPU1_G0_TX_DN<15>")
	)
	(segment
		(start 118.081298 -214.59698)
		(end 117.70868 -214.789258)
		(width 0.14224)
		(layer "In2.Cu")
		(net "GMI_CPU0_G2_CPU1_G0_TX_DN<15>")
	)
	(segment
		(start 110.55985 -221.198948)
		(end 110.55985 -221.227396)
		(width 0.1143)
		(layer "In2.Cu")
		(net "GMI_CPU0_G2_CPU1_G0_TX_DN<15>")
	)
	(segment
		(start 111.098584 -220.153738)
		(end 110.91545 -220.153738)
		(width 0.14224)
		(layer "In2.Cu")
		(net "GMI_CPU0_G2_CPU1_G0_TX_DN<15>")
	)
	(segment
		(start 113.722912 -217.52941)
		(end 113.42624 -217.826082)
		(width 0.14224)
		(layer "In2.Cu")
		(net "GMI_CPU0_G2_CPU1_G0_TX_DN<15>")
	)
	(segment
		(start 222.399606 -188.78042)
		(end 208.33715 -190.92926)
		(width 0.14224)
		(layer "In2.Cu")
		(net "GMI_CPU0_G2_CPU1_G0_TX_DN<15>")
	)
	(segment
		(start 110.622588 -222.109284)
		(end 110.653322 -222.127064)
		(width 0.1143)
		(layer "In2.Cu")
		(net "GMI_CPU0_G2_CPU1_G0_TX_DN<15>")
	)
	(segment
		(start 116.559076 -215.23706)
		(end 115.057428 -216.01176)
		(width 0.14224)
		(layer "In2.Cu")
		(net "GMI_CPU0_G2_CPU1_G0_TX_DN<15>")
	)
	(segment
		(start 112.946942 -218.30538)
		(end 112.65027 -218.602052)
		(width 0.14224)
		(layer "In2.Cu")
		(net "GMI_CPU0_G2_CPU1_G0_TX_DN<15>")
	)
	(segment
		(start 114.019076 -217.050112)
		(end 113.722912 -217.346276)
		(width 0.14224)
		(layer "In2.Cu")
		(net "GMI_CPU0_G2_CPU1_G0_TX_DN<15>")
	)
	(segment
		(start 208.316068 -190.92926)
		(end 163.395152 -191.062102)
		(width 0.14224)
		(layer "In2.Cu")
		(net "GMI_CPU0_G2_CPU1_G0_TX_DN<15>")
	)
	(segment
		(start 113.42624 -217.826082)
		(end 113.243106 -217.826082)
		(width 0.14224)
		(layer "In2.Cu")
		(net "GMI_CPU0_G2_CPU1_G0_TX_DN<15>")
	)
	(segment
		(start 362.25607 -230.394002)
		(end 362.255308 -230.393494)
		(width 0.1143)
		(layer "In2.Cu")
		(net "GMI_CPU0_G2_CPU1_G0_TX_DN<15>")
	)
	(segment
		(start 110.55985 -220.509338)
		(end 110.55985 -221.198948)
		(width 0.14224)
		(layer "In2.Cu")
		(net "GMI_CPU0_G2_CPU1_G0_TX_DN<15>")
	)
	(segment
		(start 264.933176 -191.50711)
		(end 236.44225 -186.633866)
		(width 0.14224)
		(layer "In2.Cu")
		(net "GMI_CPU0_G2_CPU1_G0_TX_DN<15>")
	)
	(segment
		(start 111.691166 -219.378022)
		(end 111.395002 -219.674186)
		(width 0.14224)
		(layer "In2.Cu")
		(net "GMI_CPU0_G2_CPU1_G0_TX_DN<15>")
	)
	(segment
		(start 111.14278 -227.839524)
		(end 110.299754 -228.682804)
		(width 0.1143)
		(layer "In2.Cu")
		(net "GMI_CPU0_G2_CPU1_G0_TX_DN<15>")
	)
	(segment
		(start 112.65027 -218.602052)
		(end 112.467136 -218.602052)
		(width 0.14224)
		(layer "In2.Cu")
		(net "GMI_CPU0_G2_CPU1_G0_TX_DN<15>")
	)
	(segment
		(start 112.946942 -218.122246)
		(end 112.946942 -218.30538)
		(width 0.14224)
		(layer "In2.Cu")
		(net "GMI_CPU0_G2_CPU1_G0_TX_DN<15>")
	)
	(segment
		(start 111.395002 -219.674186)
		(end 111.395002 -219.85732)
		(width 0.14224)
		(layer "In2.Cu")
		(net "GMI_CPU0_G2_CPU1_G0_TX_DN<15>")
	)
	(segment
		(start 117.534182 -214.733632)
		(end 117.161818 -214.925656)
		(width 0.14224)
		(layer "In2.Cu")
		(net "GMI_CPU0_G2_CPU1_G0_TX_DN<15>")
	)
	(segment
		(start 310.010048 -191.510666)
		(end 307.147722 -191.005968)
		(width 0.14224)
		(layer "In2.Cu")
		(net "GMI_CPU0_G2_CPU1_G0_TX_DN<15>")
	)
	(segment
		(start 361.740704 -229.557326)
		(end 361.74045 -229.557326)
		(width 0.1143)
		(layer "In2.Cu")
		(net "GMI_CPU0_G2_CPU1_G0_TX_DN<15>")
	)
	(segment
		(start 208.33715 -190.92926)
		(end 208.316068 -190.92926)
		(width 0.14224)
		(layer "In2.Cu")
		(net "GMI_CPU0_G2_CPU1_G0_TX_DN<15>")
	)
	(segment
		(start 111.8743 -219.378022)
		(end 111.691166 -219.378022)
		(width 0.14224)
		(layer "In2.Cu")
		(net "GMI_CPU0_G2_CPU1_G0_TX_DN<15>")
	)
	(segment
		(start 114.498882 -216.570306)
		(end 114.498882 -216.75344)
		(width 0.14224)
		(layer "In2.Cu")
		(net "GMI_CPU0_G2_CPU1_G0_TX_DN<15>")
	)
	(segment
		(start 112.170972 -218.898216)
		(end 112.170972 -219.08135)
		(width 0.14224)
		(layer "In2.Cu")
		(net "GMI_CPU0_G2_CPU1_G0_TX_DN<15>")
	)
	(segment
		(start 112.170972 -219.08135)
		(end 111.8743 -219.378022)
		(width 0.14224)
		(layer "In2.Cu")
		(net "GMI_CPU0_G2_CPU1_G0_TX_DN<15>")
	)
	(segment
		(start 110.691422 -222.148908)
		(end 110.693962 -222.150686)
		(width 0.1143)
		(layer "In2.Cu")
		(net "GMI_CPU0_G2_CPU1_G0_TX_DN<15>")
	)
	(segment
		(start 109.700568 -229.58933)
		(end 109.700314 -229.589584)
		(width 0.1143)
		(layer "In2.Cu")
		(net "GMI_CPU0_G2_CPU1_G0_TX_DN<15>")
	)
	(segment
		(start 109.747558 -229.561898)
		(end 109.700568 -229.58933)
		(width 0.1143)
		(layer "In2.Cu")
		(net "GMI_CPU0_G2_CPU1_G0_TX_DN<15>")
	)
	(segment
		(start 361.311952 -228.771704)
		(end 361.27563 -228.750622)
		(width 0.1143)
		(layer "In2.Cu")
		(net "GMI_CPU0_G2_CPU1_G0_TX_DN<15>")
	)
	(segment
		(start 361.78617 -229.583742)
		(end 361.784646 -229.583234)
		(width 0.1143)
		(layer "In2.Cu")
		(net "GMI_CPU0_G2_CPU1_G0_TX_DN<15>")
	)
	(segment
		(start 361.784646 -229.583234)
		(end 361.780836 -229.580694)
		(width 0.1143)
		(layer "In2.Cu")
		(net "GMI_CPU0_G2_CPU1_G0_TX_DN<15>")
	)
	(segment
		(start 115.057428 -216.01176)
		(end 114.498882 -216.570306)
		(width 0.14224)
		(layer "In2.Cu")
		(net "GMI_CPU0_G2_CPU1_G0_TX_DN<15>")
	)
	(segment
		(start 110.55985 -221.227396)
		(end 110.51413 -221.273116)
		(width 0.1143)
		(layer "In2.Cu")
		(net "GMI_CPU0_G2_CPU1_G0_TX_DN<15>")
	)
	(segment
		(start 111.107728 -222.927926)
		(end 111.12373 -222.927926)
		(width 0.1143)
		(layer "In2.Cu")
		(net "GMI_CPU0_G2_CPU1_G0_TX_DN<15>")
	)
	(segment
		(start 110.653322 -222.127064)
		(end 110.691422 -222.148908)
		(width 0.1143)
		(layer "In2.Cu")
		(net "GMI_CPU0_G2_CPU1_G0_TX_DN<15>")
	)
	(segment
		(start 110.714536 -222.166688)
		(end 110.721902 -222.17253)
		(width 0.1143)
		(layer "In2.Cu")
		(net "GMI_CPU0_G2_CPU1_G0_TX_DN<15>")
	)
	(segment
		(start 359.912158 -226.436174)
		(end 359.912158 -226.148138)
		(width 0.1143)
		(layer "In2.Cu")
		(net "GMI_CPU0_G2_CPU1_G0_TX_DN<15>")
	)
	(segment
		(start 114.20221 -217.050112)
		(end 114.019076 -217.050112)
		(width 0.14224)
		(layer "In2.Cu")
		(net "GMI_CPU0_G2_CPU1_G0_TX_DN<15>")
	)
	(segment
		(start 110.721902 -222.17253)
		(end 110.7313 -222.181928)
		(width 0.1143)
		(layer "In2.Cu")
		(net "GMI_CPU0_G2_CPU1_G0_TX_DN<15>")
	)
	(segment
		(start 360.351832 -227.49764)
		(end 359.912158 -226.436174)
		(width 0.1143)
		(layer "In2.Cu")
		(net "GMI_CPU0_G2_CPU1_G0_TX_DN<15>")
	)
	(segment
		(start 361.780836 -229.580694)
		(end 361.740704 -229.557326)
		(width 0.1143)
		(layer "In2.Cu")
		(net "GMI_CPU0_G2_CPU1_G0_TX_DN<15>")
	)
	(segment
		(start 362.064808 -230.714296)
		(end 362.36275 -230.714296)
		(width 0.1143)
		(layer "In2.Cu")
		(net "GMI_CPU0_G2_CPU1_G0_TX_DN<15>")
	)
	(segment
		(start 110.621826 -222.108776)
		(end 110.622588 -222.109284)
		(width 0.1143)
		(layer "In2.Cu")
		(net "GMI_CPU0_G2_CPU1_G0_TX_DN<15>")
	)
	(segment
		(start 361.342432 -228.789484)
		(end 361.311952 -228.771704)
		(width 0.1143)
		(layer "In2.Cu")
		(net "GMI_CPU0_G2_CPU1_G0_TX_DN<15>")
	)
	(segment
		(start 355.536754 -217.247216)
		(end 310.010048 -191.510666)
		(width 0.14224)
		(layer "In2.Cu")
		(net "GMI_CPU0_G2_CPU1_G0_TX_DN<15>")
	)
	(segment
		(start 113.722912 -217.346276)
		(end 113.722912 -217.52941)
		(width 0.14224)
		(layer "In2.Cu")
		(net "GMI_CPU0_G2_CPU1_G0_TX_DN<15>")
	)
	(segment
		(start 359.866438 -226.07397)
		(end 359.866438 -223.122998)
		(width 0.14224)
		(layer "In2.Cu")
		(net "GMI_CPU0_G2_CPU1_G0_TX_DN<15>")
	)
	(segment
		(start 110.926372 -222.543116)
		(end 110.927642 -222.548196)
		(width 0.1143)
		(layer "In2.Cu")
		(net "GMI_CPU0_G2_CPU1_G0_TX_DN<15>")
	)
	(segment
		(start 359.866438 -226.102418)
		(end 359.866438 -226.07397)
		(width 0.1143)
		(layer "In2.Cu")
		(net "GMI_CPU0_G2_CPU1_G0_TX_DN<15>")
	)
	(segment
		(start 109.133132 -230.71455)
		(end 109.431074 -230.71455)
		(width 0.1143)
		(layer "In2.Cu")
		(net "GMI_CPU0_G2_CPU1_G0_TX_DN<15>")
	)
	(segment
		(start 307.147722 -191.005968)
		(end 264.933176 -191.50711)
		(width 0.14224)
		(layer "In2.Cu")
		(net "GMI_CPU0_G2_CPU1_G0_TX_DN<15>")
	)
	(segment
		(start 117.161818 -214.925656)
		(end 117.106192 -215.100408)
		(width 0.14224)
		(layer "In2.Cu")
		(net "GMI_CPU0_G2_CPU1_G0_TX_DN<15>")
	)
	(segment
		(start 118.509288 -214.230204)
		(end 118.136924 -214.422228)
		(width 0.14224)
		(layer "In2.Cu")
		(net "GMI_CPU0_G2_CPU1_G0_TX_DN<15>")
	)
	(segment
		(start 110.18393 -228.771958)
		(end 110.15345 -228.789738)
		(width 0.1143)
		(layer "In2.Cu")
		(net "GMI_CPU0_G2_CPU1_G0_TX_DN<15>")
	)
	(segment
		(start 109.753146 -229.559104)
		(end 109.747558 -229.561898)
		(width 0.1143)
		(layer "In2.Cu")
		(net "GMI_CPU0_G2_CPU1_G0_TX_DN<15>")
	)
	(arc
		(start 361.27563 -228.750622)
		(mid 361.27117 -228.747468)
		(end 361.26674 -228.744272)
		(width 0.1143)
		(layer "In2.Cu")
		(net "GMI_CPU0_G2_CPU1_G0_TX_DN<15>")
	)
	(arc
		(start 109.21238 -230.410258)
		(mid 109.115245 -230.513127)
		(end 109.063282 -230.6447)
		(width 0.1143)
		(layer "In2.Cu")
		(net "GMI_CPU0_G2_CPU1_G0_TX_DN<15>")
	)
	(arc
		(start 110.7313 -222.181928)
		(mid 110.855904 -222.347908)
		(end 110.926372 -222.543116)
		(width 0.1143)
		(layer "In2.Cu")
		(net "GMI_CPU0_G2_CPU1_G0_TX_DN<15>")
	)
	(arc
		(start 361.970828 -229.904544)
		(mid 361.921375 -229.719455)
		(end 361.78617 -229.583742)
		(width 0.1143)
		(layer "In2.Cu")
		(net "GMI_CPU0_G2_CPU1_G0_TX_DN<15>")
	)
	(arc
		(start 110.705138 -222.159068)
		(mid 110.709857 -222.162853)
		(end 110.714536 -222.166688)
		(width 0.1143)
		(layer "In2.Cu")
		(net "GMI_CPU0_G2_CPU1_G0_TX_DN<15>")
	)
	(arc
		(start 109.700314 -229.589584)
		(mid 109.563625 -229.726671)
		(end 109.513624 -229.913688)
		(width 0.1143)
		(layer "In2.Cu")
		(net "GMI_CPU0_G2_CPU1_G0_TX_DN<15>")
	)
	(arc
		(start 110.603792 -222.094806)
		(mid 110.6127 -222.101931)
		(end 110.621826 -222.108776)
		(width 0.1143)
		(layer "In2.Cu")
		(net "GMI_CPU0_G2_CPU1_G0_TX_DN<15>")
	)
	(arc
		(start 110.46587 -221.804738)
		(mid 110.50222 -221.965271)
		(end 110.603792 -222.094806)
		(width 0.1143)
		(layer "In2.Cu")
		(net "GMI_CPU0_G2_CPU1_G0_TX_DN<15>")
	)
	(arc
		(start 361.499404 -229.094284)
		(mid 361.457855 -228.922862)
		(end 361.342432 -228.789484)
		(width 0.1143)
		(layer "In2.Cu")
		(net "GMI_CPU0_G2_CPU1_G0_TX_DN<15>")
	)
	(arc
		(start 360.954066 -228.176582)
		(mid 360.860894 -228.025729)
		(end 360.745532 -227.891086)
		(width 0.1143)
		(layer "In2.Cu")
		(net "GMI_CPU0_G2_CPU1_G0_TX_DN<15>")
	)
	(arc
		(start 361.74045 -229.557326)
		(mid 361.563238 -229.355309)
		(end 361.499404 -229.094284)
		(width 0.1143)
		(layer "In2.Cu")
		(net "GMI_CPU0_G2_CPU1_G0_TX_DN<15>")
	)
	(arc
		(start 362.433108 -230.644192)
		(mid 362.380223 -230.511797)
		(end 362.281724 -230.408734)
		(width 0.1143)
		(layer "In2.Cu")
		(net "GMI_CPU0_G2_CPU1_G0_TX_DN<15>")
	)
	(arc
		(start 110.693962 -222.150686)
		(mid 110.699576 -222.154842)
		(end 110.705138 -222.159068)
		(width 0.1143)
		(layer "In2.Cu")
		(net "GMI_CPU0_G2_CPU1_G0_TX_DN<15>")
	)
	(arc
		(start 111.196882 -223.001078)
		(mid 111.276768 -223.12092)
		(end 111.304832 -223.26219)
		(width 0.1143)
		(layer "In2.Cu")
		(net "GMI_CPU0_G2_CPU1_G0_TX_DN<15>")
	)
	(arc
		(start 362.255308 -230.393494)
		(mid 362.047101 -230.187408)
		(end 361.970828 -229.904544)
		(width 0.1143)
		(layer "In2.Cu")
		(net "GMI_CPU0_G2_CPU1_G0_TX_DN<15>")
	)
	(arc
		(start 110.299754 -228.682804)
		(mid 110.244855 -228.731006)
		(end 110.184184 -228.771704)
		(width 0.1143)
		(layer "In2.Cu")
		(net "GMI_CPU0_G2_CPU1_G0_TX_DN<15>")
	)
	(arc
		(start 110.927642 -222.548196)
		(mid 110.933499 -222.586623)
		(end 110.936024 -222.625412)
		(width 0.1143)
		(layer "In2.Cu")
		(net "GMI_CPU0_G2_CPU1_G0_TX_DN<15>")
	)
	(arc
		(start 110.936024 -222.625412)
		(mid 110.979889 -222.790436)
		(end 111.092488 -222.918782)
		(width 0.1143)
		(layer "In2.Cu")
		(net "GMI_CPU0_G2_CPU1_G0_TX_DN<15>")
	)
	(arc
		(start 361.26674 -228.744272)
		(mid 361.127906 -228.60273)
		(end 361.046522 -228.421946)
		(width 0.1143)
		(layer "In2.Cu")
		(net "GMI_CPU0_G2_CPU1_G0_TX_DN<15>")
	)
	(arc
		(start 110.15345 -228.789738)
		(mid 110.038023 -228.923114)
		(end 109.996478 -229.094538)
		(width 0.1143)
		(layer "In2.Cu")
		(net "GMI_CPU0_G2_CPU1_G0_TX_DN<15>")
	)
	(arc
		(start 111.304832 -227.447856)
		(mid 111.262713 -227.659784)
		(end 111.14278 -227.839524)
		(width 0.1143)
		(layer "In2.Cu")
		(net "GMI_CPU0_G2_CPU1_G0_TX_DN<15>")
	)
	(arc
		(start 109.214158 -230.408988)
		(mid 109.213268 -230.409622)
		(end 109.21238 -230.410258)
		(width 0.1143)
		(layer "In2.Cu")
		(net "GMI_CPU0_G2_CPU1_G0_TX_DN<15>")
	)
	(arc
		(start 361.046522 -228.421946)
		(mid 361.00733 -228.296614)
		(end 360.954066 -228.176582)
		(width 0.1143)
		(layer "In2.Cu")
		(net "GMI_CPU0_G2_CPU1_G0_TX_DN<15>")
	)
	(arc
		(start 109.513624 -229.924102)
		(mid 109.441283 -230.194095)
		(end 109.243622 -230.391716)
		(width 0.1143)
		(layer "In2.Cu")
		(net "GMI_CPU0_G2_CPU1_G0_TX_DN<15>")
	)
	(arc
		(start 109.996478 -229.094538)
		(mid 109.931963 -229.356757)
		(end 109.753146 -229.559104)
		(width 0.1143)
		(layer "In2.Cu")
		(net "GMI_CPU0_G2_CPU1_G0_TX_DN<15>")
	)
	(segment
		(start 361.597956 -229.360222)
		(end 362.064808 -229.094284)
		(width 0.12954)
		(layer "F.Cu")
		(net "GMI_CPU0_G2_CPU1_G0_TX_DN<14>")
	)
	(segment
		(start 109.897926 -229.360476)
		(end 109.431074 -229.094538)
		(width 0.12954)
		(layer "F.Cu")
		(net "GMI_CPU0_G2_CPU1_G0_TX_DN<14>")
	)
	(segment
		(start 111.964216 -217.73134)
		(end 111.667798 -218.028012)
		(width 0.14224)
		(layer "In2.Cu")
		(net "GMI_CPU0_G2_CPU1_G0_TX_DN<14>")
	)
	(segment
		(start 110.186724 -225.53041)
		(end 110.1852 -225.531426)
		(width 0.1143)
		(layer "In2.Cu")
		(net "GMI_CPU0_G2_CPU1_G0_TX_DN<14>")
	)
	(segment
		(start 109.242098 -228.773228)
		(end 109.21238 -228.790246)
		(width 0.1143)
		(layer "In2.Cu")
		(net "GMI_CPU0_G2_CPU1_G0_TX_DN<14>")
	)
	(segment
		(start 362.283502 -228.789992)
		(end 362.251752 -228.771704)
		(width 0.1143)
		(layer "In2.Cu")
		(net "GMI_CPU0_G2_CPU1_G0_TX_DN<14>")
	)
	(segment
		(start 361.309158 -222.290132)
		(end 361.308142 -222.289624)
		(width 0.1143)
		(layer "In2.Cu")
		(net "GMI_CPU0_G2_CPU1_G0_TX_DN<14>")
	)
	(segment
		(start 111.181134 -218.514422)
		(end 110.884716 -218.811094)
		(width 0.14224)
		(layer "In2.Cu")
		(net "GMI_CPU0_G2_CPU1_G0_TX_DN<14>")
	)
	(segment
		(start 113.043462 -216.461848)
		(end 112.747298 -216.758012)
		(width 0.14224)
		(layer "In2.Cu")
		(net "GMI_CPU0_G2_CPU1_G0_TX_DN<14>")
	)
	(segment
		(start 162.413696 -190.119762)
		(end 116.788692 -213.669118)
		(width 0.14224)
		(layer "In2.Cu")
		(net "GMI_CPU0_G2_CPU1_G0_TX_DN<14>")
	)
	(segment
		(start 360.961178 -221.128844)
		(end 360.915458 -221.083124)
		(width 0.1143)
		(layer "In2.Cu")
		(net "GMI_CPU0_G2_CPU1_G0_TX_DN<14>")
	)
	(segment
		(start 109.681772 -222.108776)
		(end 109.753908 -222.150686)
		(width 0.1143)
		(layer "In2.Cu")
		(net "GMI_CPU0_G2_CPU1_G0_TX_DN<14>")
	)
	(segment
		(start 115.192556 -214.493094)
		(end 114.820192 -214.685118)
		(width 0.14224)
		(layer "In2.Cu")
		(net "GMI_CPU0_G2_CPU1_G0_TX_DN<14>")
	)
	(segment
		(start 361.272836 -222.959676)
		(end 361.342432 -222.919036)
		(width 0.1143)
		(layer "In2.Cu")
		(net "GMI_CPU0_G2_CPU1_G0_TX_DN<14>")
	)
	(segment
		(start 110.220252 -227.130864)
		(end 110.15345 -227.169726)
		(width 0.1143)
		(layer "In2.Cu")
		(net "GMI_CPU0_G2_CPU1_G0_TX_DN<14>")
	)
	(segment
		(start 109.283246 -228.749352)
		(end 109.24413 -228.771958)
		(width 0.1143)
		(layer "In2.Cu")
		(net "GMI_CPU0_G2_CPU1_G0_TX_DN<14>")
	)
	(segment
		(start 361.305094 -222.287846)
		(end 361.272582 -222.268796)
		(width 0.1143)
		(layer "In2.Cu")
		(net "GMI_CPU0_G2_CPU1_G0_TX_DN<14>")
	)
	(segment
		(start 110.1852 -225.531426)
		(end 110.184184 -225.531934)
		(width 0.1143)
		(layer "In2.Cu")
		(net "GMI_CPU0_G2_CPU1_G0_TX_DN<14>")
	)
	(segment
		(start 116.176806 -213.985094)
		(end 115.804442 -214.177118)
		(width 0.14224)
		(layer "In2.Cu")
		(net "GMI_CPU0_G2_CPU1_G0_TX_DN<14>")
	)
	(segment
		(start 361.343448 -222.309944)
		(end 361.311698 -222.291656)
		(width 0.1143)
		(layer "In2.Cu")
		(net "GMI_CPU0_G2_CPU1_G0_TX_DN<14>")
	)
	(segment
		(start 236.450632 -185.67654)
		(end 208.263998 -189.98438)
		(width 0.14224)
		(layer "In2.Cu")
		(net "GMI_CPU0_G2_CPU1_G0_TX_DN<14>")
	)
	(segment
		(start 361.029758 -226.664266)
		(end 361.029504 -226.664266)
		(width 0.1143)
		(layer "In2.Cu")
		(net "GMI_CPU0_G2_CPU1_G0_TX_DN<14>")
	)
	(segment
		(start 110.884716 -218.811094)
		(end 110.694216 -218.811094)
		(width 0.14224)
		(layer "In2.Cu")
		(net "GMI_CPU0_G2_CPU1_G0_TX_DN<14>")
	)
	(segment
		(start 109.243368 -228.772466)
		(end 109.242098 -228.773228)
		(width 0.1143)
		(layer "In2.Cu")
		(net "GMI_CPU0_G2_CPU1_G0_TX_DN<14>")
	)
	(segment
		(start 361.311952 -227.151692)
		(end 361.27563 -227.13061)
		(width 0.1143)
		(layer "In2.Cu")
		(net "GMI_CPU0_G2_CPU1_G0_TX_DN<14>")
	)
	(segment
		(start 356.170992 -216.526872)
		(end 310.336184 -190.620904)
		(width 0.14224)
		(layer "In2.Cu")
		(net "GMI_CPU0_G2_CPU1_G0_TX_DN<14>")
	)
	(segment
		(start 114.017044 -215.678766)
		(end 113.826544 -215.678766)
		(width 0.14224)
		(layer "In2.Cu")
		(net "GMI_CPU0_G2_CPU1_G0_TX_DN<14>")
	)
	(segment
		(start 109.24413 -228.771958)
		(end 109.243368 -228.772466)
		(width 0.1143)
		(layer "In2.Cu")
		(net "GMI_CPU0_G2_CPU1_G0_TX_DN<14>")
	)
	(segment
		(start 114.313462 -215.382094)
		(end 114.017044 -215.678766)
		(width 0.14224)
		(layer "In2.Cu")
		(net "GMI_CPU0_G2_CPU1_G0_TX_DN<14>")
	)
	(segment
		(start 361.029504 -221.80423)
		(end 361.029504 -221.573344)
		(width 0.1143)
		(layer "In2.Cu")
		(net "GMI_CPU0_G2_CPU1_G0_TX_DN<14>")
	)
	(segment
		(start 361.310682 -222.291148)
		(end 361.309158 -222.290132)
		(width 0.1143)
		(layer "In2.Cu")
		(net "GMI_CPU0_G2_CPU1_G0_TX_DN<14>")
	)
	(segment
		(start 360.915458 -221.083124)
		(end 360.915458 -220.862144)
		(width 0.14224)
		(layer "In2.Cu")
		(net "GMI_CPU0_G2_CPU1_G0_TX_DN<14>")
	)
	(segment
		(start 361.342432 -227.169472)
		(end 361.311952 -227.151692)
		(width 0.1143)
		(layer "In2.Cu")
		(net "GMI_CPU0_G2_CPU1_G0_TX_DN<14>")
	)
	(segment
		(start 361.311698 -222.291656)
		(end 361.310682 -222.291148)
		(width 0.1143)
		(layer "In2.Cu")
		(net "GMI_CPU0_G2_CPU1_G0_TX_DN<14>")
	)
	(segment
		(start 115.373912 -214.551006)
		(end 115.192556 -214.493094)
		(width 0.14224)
		(layer "In2.Cu")
		(net "GMI_CPU0_G2_CPU1_G0_TX_DN<14>")
	)
	(segment
		(start 109.753146 -227.939092)
		(end 109.684312 -227.979224)
		(width 0.1143)
		(layer "In2.Cu")
		(net "GMI_CPU0_G2_CPU1_G0_TX_DN<14>")
	)
	(segment
		(start 208.263998 -189.98438)
		(end 162.413696 -190.119762)
		(width 0.14224)
		(layer "In2.Cu")
		(net "GMI_CPU0_G2_CPU1_G0_TX_DN<14>")
	)
	(segment
		(start 361.109514 -225.316796)
		(end 361.10926 -225.316542)
		(width 0.1143)
		(layer "In2.Cu")
		(net "GMI_CPU0_G2_CPU1_G0_TX_DN<14>")
	)
	(segment
		(start 110.398052 -219.107258)
		(end 110.398052 -219.297504)
		(width 0.14224)
		(layer "In2.Cu")
		(net "GMI_CPU0_G2_CPU1_G0_TX_DN<14>")
	)
	(segment
		(start 361.311444 -224.556828)
		(end 361.313984 -224.555558)
		(width 0.1143)
		(layer "In2.Cu")
		(net "GMI_CPU0_G2_CPU1_G0_TX_DN<14>")
	)
	(segment
		(start 110.184184 -225.531934)
		(end 110.152434 -225.550222)
		(width 0.1143)
		(layer "In2.Cu")
		(net "GMI_CPU0_G2_CPU1_G0_TX_DN<14>")
	)
	(segment
		(start 310.336184 -190.620904)
		(end 307.15839 -190.06058)
		(width 0.14224)
		(layer "In2.Cu")
		(net "GMI_CPU0_G2_CPU1_G0_TX_DN<14>")
	)
	(segment
		(start 109.61497 -221.174564)
		(end 109.61497 -221.203012)
		(width 0.1143)
		(layer "In2.Cu")
		(net "GMI_CPU0_G2_CPU1_G0_TX_DN<14>")
	)
	(segment
		(start 113.826544 -215.678766)
		(end 113.53038 -215.97493)
		(width 0.14224)
		(layer "In2.Cu")
		(net "GMI_CPU0_G2_CPU1_G0_TX_DN<14>")
	)
	(segment
		(start 116.358162 -214.043006)
		(end 116.176806 -213.985094)
		(width 0.14224)
		(layer "In2.Cu")
		(net "GMI_CPU0_G2_CPU1_G0_TX_DN<14>")
	)
	(segment
		(start 115.804442 -214.177118)
		(end 115.74653 -214.358728)
		(width 0.14224)
		(layer "In2.Cu")
		(net "GMI_CPU0_G2_CPU1_G0_TX_DN<14>")
	)
	(segment
		(start 110.694216 -218.811094)
		(end 110.398052 -219.107258)
		(width 0.14224)
		(layer "In2.Cu")
		(net "GMI_CPU0_G2_CPU1_G0_TX_DN<14>")
	)
	(segment
		(start 111.181134 -218.324176)
		(end 111.181134 -218.514422)
		(width 0.14224)
		(layer "In2.Cu")
		(net "GMI_CPU0_G2_CPU1_G0_TX_DN<14>")
	)
	(segment
		(start 116.73078 -213.850728)
		(end 116.358162 -214.043006)
		(width 0.14224)
		(layer "In2.Cu")
		(net "GMI_CPU0_G2_CPU1_G0_TX_DN<14>")
	)
	(segment
		(start 110.202472 -222.947992)
		(end 110.22584 -222.961454)
		(width 0.1143)
		(layer "In2.Cu")
		(net "GMI_CPU0_G2_CPU1_G0_TX_DN<14>")
	)
	(segment
		(start 110.2233 -225.509074)
		(end 110.186724 -225.53041)
		(width 0.1143)
		(layer "In2.Cu")
		(net "GMI_CPU0_G2_CPU1_G0_TX_DN<14>")
	)
	(segment
		(start 361.029758 -223.424242)
		(end 361.029504 -223.424242)
		(width 0.1143)
		(layer "In2.Cu")
		(net "GMI_CPU0_G2_CPU1_G0_TX_DN<14>")
	)
	(segment
		(start 301.88916 -190.123318)
		(end 265.007852 -190.56096)
		(width 0.14224)
		(layer "In2.Cu")
		(net "GMI_CPU0_G2_CPU1_G0_TX_DN<14>")
	)
	(segment
		(start 115.74653 -214.358728)
		(end 115.373912 -214.551006)
		(width 0.14224)
		(layer "In2.Cu")
		(net "GMI_CPU0_G2_CPU1_G0_TX_DN<14>")
	)
	(segment
		(start 112.45088 -217.24493)
		(end 112.26038 -217.24493)
		(width 0.14224)
		(layer "In2.Cu")
		(net "GMI_CPU0_G2_CPU1_G0_TX_DN<14>")
	)
	(segment
		(start 112.26038 -217.24493)
		(end 111.964216 -217.541094)
		(width 0.14224)
		(layer "In2.Cu")
		(net "GMI_CPU0_G2_CPU1_G0_TX_DN<14>")
	)
	(segment
		(start 361.02925 -225.044254)
		(end 361.029504 -225.044254)
		(width 0.1143)
		(layer "In2.Cu")
		(net "GMI_CPU0_G2_CPU1_G0_TX_DN<14>")
	)
	(segment
		(start 110.101634 -219.594176)
		(end 109.911134 -219.594176)
		(width 0.14224)
		(layer "In2.Cu")
		(net "GMI_CPU0_G2_CPU1_G0_TX_DN<14>")
	)
	(segment
		(start 113.53038 -215.97493)
		(end 113.53038 -216.165176)
		(width 0.14224)
		(layer "In2.Cu")
		(net "GMI_CPU0_G2_CPU1_G0_TX_DN<14>")
	)
	(segment
		(start 362.36275 -229.094284)
		(end 362.4326 -229.024434)
		(width 0.1143)
		(layer "In2.Cu")
		(net "GMI_CPU0_G2_CPU1_G0_TX_DN<14>")
	)
	(segment
		(start 111.477298 -218.028012)
		(end 111.181134 -218.324176)
		(width 0.14224)
		(layer "In2.Cu")
		(net "GMI_CPU0_G2_CPU1_G0_TX_DN<14>")
	)
	(segment
		(start 111.667798 -218.028012)
		(end 111.477298 -218.028012)
		(width 0.14224)
		(layer "In2.Cu")
		(net "GMI_CPU0_G2_CPU1_G0_TX_DN<14>")
	)
	(segment
		(start 360.961178 -221.505018)
		(end 360.961178 -221.128844)
		(width 0.1143)
		(layer "In2.Cu")
		(net "GMI_CPU0_G2_CPU1_G0_TX_DN<14>")
	)
	(segment
		(start 361.272836 -226.1997)
		(end 361.343448 -226.158298)
		(width 0.1143)
		(layer "In2.Cu")
		(net "GMI_CPU0_G2_CPU1_G0_TX_DN<14>")
	)
	(segment
		(start 109.413294 -228.655626)
		(end 109.283246 -228.749352)
		(width 0.1143)
		(layer "In2.Cu")
		(net "GMI_CPU0_G2_CPU1_G0_TX_DN<14>")
	)
	(segment
		(start 111.964216 -217.541094)
		(end 111.964216 -217.73134)
		(width 0.14224)
		(layer "In2.Cu")
		(net "GMI_CPU0_G2_CPU1_G0_TX_DN<14>")
	)
	(segment
		(start 110.398052 -219.297504)
		(end 110.101634 -219.594176)
		(width 0.14224)
		(layer "In2.Cu")
		(net "GMI_CPU0_G2_CPU1_G0_TX_DN<14>")
	)
	(segment
		(start 112.747298 -216.948258)
		(end 112.45088 -217.24493)
		(width 0.14224)
		(layer "In2.Cu")
		(net "GMI_CPU0_G2_CPU1_G0_TX_DN<14>")
	)
	(segment
		(start 110.466632 -223.424496)
		(end 110.466632 -225.044508)
		(width 0.1143)
		(layer "In2.Cu")
		(net "GMI_CPU0_G2_CPU1_G0_TX_DN<14>")
	)
	(segment
		(start 116.788692 -213.669118)
		(end 116.73078 -213.850728)
		(width 0.14224)
		(layer "In2.Cu")
		(net "GMI_CPU0_G2_CPU1_G0_TX_DN<14>")
	)
	(segment
		(start 362.251752 -228.771704)
		(end 362.21543 -228.750622)
		(width 0.1143)
		(layer "In2.Cu")
		(net "GMI_CPU0_G2_CPU1_G0_TX_DN<14>")
	)
	(segment
		(start 360.689398 -220.373194)
		(end 356.170992 -216.526872)
		(width 0.14224)
		(layer "In2.Cu")
		(net "GMI_CPU0_G2_CPU1_G0_TX_DN<14>")
	)
	(segment
		(start 360.915458 -220.862144)
		(end 360.689398 -220.373194)
		(width 0.14224)
		(layer "In2.Cu")
		(net "GMI_CPU0_G2_CPU1_G0_TX_DN<14>")
	)
	(segment
		(start 109.56925 -221.536514)
		(end 109.525816 -221.579948)
		(width 0.1143)
		(layer "In2.Cu")
		(net "GMI_CPU0_G2_CPU1_G0_TX_DN<14>")
	)
	(segment
		(start 109.525816 -221.579948)
		(end 109.525816 -221.804484)
		(width 0.1143)
		(layer "In2.Cu")
		(net "GMI_CPU0_G2_CPU1_G0_TX_DN<14>")
	)
	(segment
		(start 361.806744 -227.976176)
		(end 361.742736 -227.938838)
		(width 0.1143)
		(layer "In2.Cu")
		(net "GMI_CPU0_G2_CPU1_G0_TX_DN<14>")
	)
	(segment
		(start 307.15839 -190.06058)
		(end 301.88916 -190.123318)
		(width 0.14224)
		(layer "In2.Cu")
		(net "GMI_CPU0_G2_CPU1_G0_TX_DN<14>")
	)
	(segment
		(start 361.306618 -222.288608)
		(end 361.305094 -222.287846)
		(width 0.1143)
		(layer "In2.Cu")
		(net "GMI_CPU0_G2_CPU1_G0_TX_DN<14>")
	)
	(segment
		(start 114.313462 -215.191848)
		(end 114.313462 -215.382094)
		(width 0.14224)
		(layer "In2.Cu")
		(net "GMI_CPU0_G2_CPU1_G0_TX_DN<14>")
	)
	(segment
		(start 113.233962 -216.461848)
		(end 113.043462 -216.461848)
		(width 0.14224)
		(layer "In2.Cu")
		(net "GMI_CPU0_G2_CPU1_G0_TX_DN<14>")
	)
	(segment
		(start 265.007852 -190.56096)
		(end 236.450632 -185.67654)
		(width 0.14224)
		(layer "In2.Cu")
		(net "GMI_CPU0_G2_CPU1_G0_TX_DN<14>")
	)
	(segment
		(start 362.064808 -229.094284)
		(end 362.36275 -229.094284)
		(width 0.1143)
		(layer "In2.Cu")
		(net "GMI_CPU0_G2_CPU1_G0_TX_DN<14>")
	)
	(segment
		(start 112.747298 -216.758012)
		(end 112.747298 -216.948258)
		(width 0.14224)
		(layer "In2.Cu")
		(net "GMI_CPU0_G2_CPU1_G0_TX_DN<14>")
	)
	(segment
		(start 361.029504 -221.573344)
		(end 360.961178 -221.505018)
		(width 0.1143)
		(layer "In2.Cu")
		(net "GMI_CPU0_G2_CPU1_G0_TX_DN<14>")
	)
	(segment
		(start 109.61497 -219.89034)
		(end 109.61497 -221.174564)
		(width 0.14224)
		(layer "In2.Cu")
		(net "GMI_CPU0_G2_CPU1_G0_TX_DN<14>")
	)
	(segment
		(start 114.820192 -214.685118)
		(end 114.313462 -215.191848)
		(width 0.14224)
		(layer "In2.Cu")
		(net "GMI_CPU0_G2_CPU1_G0_TX_DN<14>")
	)
	(segment
		(start 109.063282 -229.024688)
		(end 109.133132 -229.094538)
		(width 0.1143)
		(layer "In2.Cu")
		(net "GMI_CPU0_G2_CPU1_G0_TX_DN<14>")
	)
	(segment
		(start 109.133132 -229.094538)
		(end 109.431074 -229.094538)
		(width 0.1143)
		(layer "In2.Cu")
		(net "GMI_CPU0_G2_CPU1_G0_TX_DN<14>")
	)
	(segment
		(start 113.53038 -216.165176)
		(end 113.233962 -216.461848)
		(width 0.14224)
		(layer "In2.Cu")
		(net "GMI_CPU0_G2_CPU1_G0_TX_DN<14>")
	)
	(segment
		(start 361.308142 -222.289624)
		(end 361.306618 -222.288608)
		(width 0.1143)
		(layer "In2.Cu")
		(net "GMI_CPU0_G2_CPU1_G0_TX_DN<14>")
	)
	(segment
		(start 109.56925 -221.248732)
		(end 109.56925 -221.536514)
		(width 0.1143)
		(layer "In2.Cu")
		(net "GMI_CPU0_G2_CPU1_G0_TX_DN<14>")
	)
	(segment
		(start 109.526324 -228.284532)
		(end 109.526324 -228.4349)
		(width 0.1143)
		(layer "In2.Cu")
		(net "GMI_CPU0_G2_CPU1_G0_TX_DN<14>")
	)
	(segment
		(start 361.343702 -223.93021)
		(end 361.27563 -223.890586)
		(width 0.1143)
		(layer "In2.Cu")
		(net "GMI_CPU0_G2_CPU1_G0_TX_DN<14>")
	)
	(segment
		(start 109.61497 -221.203012)
		(end 109.56925 -221.248732)
		(width 0.1143)
		(layer "In2.Cu")
		(net "GMI_CPU0_G2_CPU1_G0_TX_DN<14>")
	)
	(segment
		(start 110.15345 -226.159314)
		(end 110.223554 -226.200462)
		(width 0.1143)
		(layer "In2.Cu")
		(net "GMI_CPU0_G2_CPU1_G0_TX_DN<14>")
	)
	(segment
		(start 109.911134 -219.594176)
		(end 109.61497 -219.89034)
		(width 0.14224)
		(layer "In2.Cu")
		(net "GMI_CPU0_G2_CPU1_G0_TX_DN<14>")
	)
	(segment
		(start 361.036362 -225.132646)
		(end 361.036108 -225.13163)
		(width 0.1143)
		(layer "In2.Cu")
		(net "GMI_CPU0_G2_CPU1_G0_TX_DN<14>")
	)
	(arc
		(start 361.27563 -223.890586)
		(mid 361.094978 -223.687841)
		(end 361.029758 -223.424242)
		(width 0.1143)
		(layer "In2.Cu")
		(net "GMI_CPU0_G2_CPU1_G0_TX_DN<14>")
	)
	(arc
		(start 361.10926 -225.316542)
		(mid 361.062602 -225.22864)
		(end 361.036362 -225.132646)
		(width 0.1143)
		(layer "In2.Cu")
		(net "GMI_CPU0_G2_CPU1_G0_TX_DN<14>")
	)
	(arc
		(start 109.996478 -225.854514)
		(mid 110.038027 -226.025936)
		(end 110.15345 -226.159314)
		(width 0.1143)
		(layer "In2.Cu")
		(net "GMI_CPU0_G2_CPU1_G0_TX_DN<14>")
	)
	(arc
		(start 361.742736 -227.938838)
		(mid 361.563923 -227.736488)
		(end 361.499404 -227.474272)
		(width 0.1143)
		(layer "In2.Cu")
		(net "GMI_CPU0_G2_CPU1_G0_TX_DN<14>")
	)
	(arc
		(start 361.035346 -225.126804)
		(mid 361.030785 -225.085641)
		(end 361.02925 -225.044254)
		(width 0.1143)
		(layer "In2.Cu")
		(net "GMI_CPU0_G2_CPU1_G0_TX_DN<14>")
	)
	(arc
		(start 109.684312 -227.979224)
		(mid 109.568265 -228.112695)
		(end 109.526324 -228.284532)
		(width 0.1143)
		(layer "In2.Cu")
		(net "GMI_CPU0_G2_CPU1_G0_TX_DN<14>")
	)
	(arc
		(start 361.211368 -225.443796)
		(mid 361.15799 -225.382262)
		(end 361.109514 -225.316796)
		(width 0.1143)
		(layer "In2.Cu")
		(net "GMI_CPU0_G2_CPU1_G0_TX_DN<14>")
	)
	(arc
		(start 109.21238 -228.790246)
		(mid 109.115245 -228.893115)
		(end 109.063282 -229.024688)
		(width 0.1143)
		(layer "In2.Cu")
		(net "GMI_CPU0_G2_CPU1_G0_TX_DN<14>")
	)
	(arc
		(start 361.499404 -222.614236)
		(mid 361.458149 -222.443265)
		(end 361.343448 -222.309944)
		(width 0.1143)
		(layer "In2.Cu")
		(net "GMI_CPU0_G2_CPU1_G0_TX_DN<14>")
	)
	(arc
		(start 361.036108 -225.13163)
		(mid 361.035721 -225.129218)
		(end 361.035346 -225.126804)
		(width 0.1143)
		(layer "In2.Cu")
		(net "GMI_CPU0_G2_CPU1_G0_TX_DN<14>")
	)
	(arc
		(start 361.499404 -227.474272)
		(mid 361.457855 -227.30285)
		(end 361.342432 -227.169472)
		(width 0.1143)
		(layer "In2.Cu")
		(net "GMI_CPU0_G2_CPU1_G0_TX_DN<14>")
	)
	(arc
		(start 109.525816 -221.804484)
		(mid 109.567071 -221.975455)
		(end 109.681772 -222.108776)
		(width 0.1143)
		(layer "In2.Cu")
		(net "GMI_CPU0_G2_CPU1_G0_TX_DN<14>")
	)
	(arc
		(start 361.029758 -226.656392)
		(mid 361.099375 -226.400404)
		(end 361.272836 -226.1997)
		(width 0.1143)
		(layer "In2.Cu")
		(net "GMI_CPU0_G2_CPU1_G0_TX_DN<14>")
	)
	(arc
		(start 361.029504 -226.664266)
		(mid 361.029617 -226.660329)
		(end 361.029758 -226.656392)
		(width 0.1143)
		(layer "In2.Cu")
		(net "GMI_CPU0_G2_CPU1_G0_TX_DN<14>")
	)
	(arc
		(start 362.4326 -229.024434)
		(mid 362.380551 -228.892915)
		(end 362.283502 -228.789992)
		(width 0.1143)
		(layer "In2.Cu")
		(net "GMI_CPU0_G2_CPU1_G0_TX_DN<14>")
	)
	(arc
		(start 110.367064 -225.365056)
		(mid 110.301716 -225.443587)
		(end 110.2233 -225.509074)
		(width 0.1143)
		(layer "In2.Cu")
		(net "GMI_CPU0_G2_CPU1_G0_TX_DN<14>")
	)
	(arc
		(start 110.466632 -225.044508)
		(mid 110.441202 -225.212346)
		(end 110.367064 -225.365056)
		(width 0.1143)
		(layer "In2.Cu")
		(net "GMI_CPU0_G2_CPU1_G0_TX_DN<14>")
	)
	(arc
		(start 110.22584 -222.961454)
		(mid 110.402822 -223.163546)
		(end 110.466632 -223.424496)
		(width 0.1143)
		(layer "In2.Cu")
		(net "GMI_CPU0_G2_CPU1_G0_TX_DN<14>")
	)
	(arc
		(start 361.313984 -224.555558)
		(mid 361.498478 -224.25095)
		(end 361.343702 -223.93021)
		(width 0.1143)
		(layer "In2.Cu")
		(net "GMI_CPU0_G2_CPU1_G0_TX_DN<14>")
	)
	(arc
		(start 362.21543 -228.750622)
		(mid 362.207252 -228.744979)
		(end 362.199174 -228.739192)
		(width 0.1143)
		(layer "In2.Cu")
		(net "GMI_CPU0_G2_CPU1_G0_TX_DN<14>")
	)
	(arc
		(start 362.199174 -228.739192)
		(mid 362.034507 -228.540585)
		(end 361.969558 -228.290882)
		(width 0.1143)
		(layer "In2.Cu")
		(net "GMI_CPU0_G2_CPU1_G0_TX_DN<14>")
	)
	(arc
		(start 109.996478 -227.474526)
		(mid 109.931963 -227.736745)
		(end 109.753146 -227.939092)
		(width 0.1143)
		(layer "In2.Cu")
		(net "GMI_CPU0_G2_CPU1_G0_TX_DN<14>")
	)
	(arc
		(start 361.029504 -225.044254)
		(mid 361.105009 -224.762676)
		(end 361.311444 -224.556828)
		(width 0.1143)
		(layer "In2.Cu")
		(net "GMI_CPU0_G2_CPU1_G0_TX_DN<14>")
	)
	(arc
		(start 110.15345 -227.169726)
		(mid 110.038023 -227.303102)
		(end 109.996478 -227.474526)
		(width 0.1143)
		(layer "In2.Cu")
		(net "GMI_CPU0_G2_CPU1_G0_TX_DN<14>")
	)
	(arc
		(start 361.343448 -226.158298)
		(mid 361.498509 -225.849231)
		(end 361.33278 -225.54565)
		(width 0.1143)
		(layer "In2.Cu")
		(net "GMI_CPU0_G2_CPU1_G0_TX_DN<14>")
	)
	(arc
		(start 109.526324 -228.4349)
		(mid 109.496423 -228.558892)
		(end 109.413294 -228.655626)
		(width 0.1143)
		(layer "In2.Cu")
		(net "GMI_CPU0_G2_CPU1_G0_TX_DN<14>")
	)
	(arc
		(start 361.33278 -225.54565)
		(mid 361.269137 -225.498225)
		(end 361.211368 -225.443796)
		(width 0.1143)
		(layer "In2.Cu")
		(net "GMI_CPU0_G2_CPU1_G0_TX_DN<14>")
	)
	(arc
		(start 110.223554 -226.200462)
		(mid 110.390193 -226.407381)
		(end 110.466124 -226.66198)
		(width 0.1143)
		(layer "In2.Cu")
		(net "GMI_CPU0_G2_CPU1_G0_TX_DN<14>")
	)
	(arc
		(start 361.138724 -222.138748)
		(mid 361.057433 -221.980201)
		(end 361.029504 -221.80423)
		(width 0.1143)
		(layer "In2.Cu")
		(net "GMI_CPU0_G2_CPU1_G0_TX_DN<14>")
	)
	(arc
		(start 110.152434 -225.550222)
		(mid 110.037758 -225.683556)
		(end 109.996478 -225.854514)
		(width 0.1143)
		(layer "In2.Cu")
		(net "GMI_CPU0_G2_CPU1_G0_TX_DN<14>")
	)
	(arc
		(start 361.272582 -222.268796)
		(mid 361.200255 -222.209329)
		(end 361.138724 -222.138748)
		(width 0.1143)
		(layer "In2.Cu")
		(net "GMI_CPU0_G2_CPU1_G0_TX_DN<14>")
	)
	(arc
		(start 361.029504 -223.424242)
		(mid 361.02984 -223.416747)
		(end 361.030266 -223.409256)
		(width 0.1143)
		(layer "In2.Cu")
		(net "GMI_CPU0_G2_CPU1_G0_TX_DN<14>")
	)
	(arc
		(start 361.969558 -228.290882)
		(mid 361.920168 -228.116974)
		(end 361.806744 -227.976176)
		(width 0.1143)
		(layer "In2.Cu")
		(net "GMI_CPU0_G2_CPU1_G0_TX_DN<14>")
	)
	(arc
		(start 361.27563 -227.13061)
		(mid 361.094978 -226.927865)
		(end 361.029758 -226.664266)
		(width 0.1143)
		(layer "In2.Cu")
		(net "GMI_CPU0_G2_CPU1_G0_TX_DN<14>")
	)
	(arc
		(start 109.996224 -222.61449)
		(mid 110.057617 -222.807054)
		(end 110.202472 -222.947992)
		(width 0.1143)
		(layer "In2.Cu")
		(net "GMI_CPU0_G2_CPU1_G0_TX_DN<14>")
	)
	(arc
		(start 361.030266 -223.409256)
		(mid 361.104189 -223.158909)
		(end 361.272836 -222.959676)
		(width 0.1143)
		(layer "In2.Cu")
		(net "GMI_CPU0_G2_CPU1_G0_TX_DN<14>")
	)
	(arc
		(start 109.753908 -222.150686)
		(mid 109.924244 -222.356902)
		(end 109.996224 -222.61449)
		(width 0.1143)
		(layer "In2.Cu")
		(net "GMI_CPU0_G2_CPU1_G0_TX_DN<14>")
	)
	(arc
		(start 110.466124 -226.66198)
		(mid 110.463255 -226.722505)
		(end 110.453932 -226.782376)
		(width 0.1143)
		(layer "In2.Cu")
		(net "GMI_CPU0_G2_CPU1_G0_TX_DN<14>")
	)
	(arc
		(start 361.342432 -222.919036)
		(mid 361.457859 -222.78566)
		(end 361.499404 -222.614236)
		(width 0.1143)
		(layer "In2.Cu")
		(net "GMI_CPU0_G2_CPU1_G0_TX_DN<14>")
	)
	(arc
		(start 110.453932 -226.782376)
		(mid 110.370609 -226.979089)
		(end 110.220252 -227.130864)
		(width 0.1143)
		(layer "In2.Cu")
		(net "GMI_CPU0_G2_CPU1_G0_TX_DN<14>")
	)
	(segment
		(start 361.597956 -227.74021)
		(end 362.064808 -227.474272)
		(width 0.12954)
		(layer "F.Cu")
		(net "GMI_CPU0_G2_CPU1_G0_TX_DN<13>")
	)
	(segment
		(start 109.897926 -227.740464)
		(end 109.431074 -227.474526)
		(width 0.12954)
		(layer "F.Cu")
		(net "GMI_CPU0_G2_CPU1_G0_TX_DN<13>")
	)
	(segment
		(start 115.198906 -213.23046)
		(end 115.140994 -213.41207)
		(width 0.14224)
		(layer "In2.Cu")
		(net "GMI_CPU0_G2_CPU1_G0_TX_DN<13>")
	)
	(segment
		(start 114.214656 -213.73846)
		(end 113.368582 -214.584788)
		(width 0.14224)
		(layer "In2.Cu")
		(net "GMI_CPU0_G2_CPU1_G0_TX_DN<13>")
	)
	(segment
		(start 115.57127 -213.038436)
		(end 115.198906 -213.23046)
		(width 0.14224)
		(layer "In2.Cu")
		(net "GMI_CPU0_G2_CPU1_G0_TX_DN<13>")
	)
	(segment
		(start 362.251752 -223.911668)
		(end 362.248958 -223.90989)
		(width 0.1143)
		(layer "In2.Cu")
		(net "GMI_CPU0_G2_CPU1_G0_TX_DN<13>")
	)
	(segment
		(start 362.248958 -223.90989)
		(end 362.21289 -223.889062)
		(width 0.1143)
		(layer "In2.Cu")
		(net "GMI_CPU0_G2_CPU1_G0_TX_DN<13>")
	)
	(segment
		(start 108.62437 -221.624906)
		(end 108.586016 -221.66326)
		(width 0.1143)
		(layer "In2.Cu")
		(net "GMI_CPU0_G2_CPU1_G0_TX_DN<13>")
	)
	(segment
		(start 109.242098 -224.555812)
		(end 109.243368 -224.556574)
		(width 0.1143)
		(layer "In2.Cu")
		(net "GMI_CPU0_G2_CPU1_G0_TX_DN<13>")
	)
	(segment
		(start 362.283502 -223.929956)
		(end 362.252514 -223.912176)
		(width 0.1143)
		(layer "In2.Cu")
		(net "GMI_CPU0_G2_CPU1_G0_TX_DN<13>")
	)
	(segment
		(start 113.072164 -215.071452)
		(end 112.881664 -215.071452)
		(width 0.14224)
		(layer "In2.Cu")
		(net "GMI_CPU0_G2_CPU1_G0_TX_DN<13>")
	)
	(segment
		(start 109.243876 -223.911922)
		(end 109.213396 -223.929702)
		(width 0.1143)
		(layer "In2.Cu")
		(net "GMI_CPU0_G2_CPU1_G0_TX_DN<13>")
	)
	(segment
		(start 361.906058 -221.426024)
		(end 361.906058 -221.128844)
		(width 0.1143)
		(layer "In2.Cu")
		(net "GMI_CPU0_G2_CPU1_G0_TX_DN<13>")
	)
	(segment
		(start 362.36275 -227.474272)
		(end 362.4326 -227.404422)
		(width 0.1143)
		(layer "In2.Cu")
		(net "GMI_CPU0_G2_CPU1_G0_TX_DN<13>")
	)
	(segment
		(start 109.239812 -224.554542)
		(end 109.240574 -224.55505)
		(width 0.1143)
		(layer "In2.Cu")
		(net "GMI_CPU0_G2_CPU1_G0_TX_DN<13>")
	)
	(segment
		(start 362.251752 -227.151692)
		(end 362.21543 -227.13061)
		(width 0.1143)
		(layer "In2.Cu")
		(net "GMI_CPU0_G2_CPU1_G0_TX_DN<13>")
	)
	(segment
		(start 109.453172 -218.500706)
		(end 109.453172 -218.690952)
		(width 0.14224)
		(layer "In2.Cu")
		(net "GMI_CPU0_G2_CPU1_G0_TX_DN<13>")
	)
	(segment
		(start 362.283502 -227.16998)
		(end 362.252514 -227.1522)
		(width 0.1143)
		(layer "In2.Cu")
		(net "GMI_CPU0_G2_CPU1_G0_TX_DN<13>")
	)
	(segment
		(start 112.881664 -215.071452)
		(end 112.5855 -215.36787)
		(width 0.14224)
		(layer "In2.Cu")
		(net "GMI_CPU0_G2_CPU1_G0_TX_DN<13>")
	)
	(segment
		(start 110.236254 -217.71737)
		(end 110.236254 -217.907616)
		(width 0.14224)
		(layer "In2.Cu")
		(net "GMI_CPU0_G2_CPU1_G0_TX_DN<13>")
	)
	(segment
		(start 361.860338 -221.083124)
		(end 361.860338 -220.560646)
		(width 0.14224)
		(layer "In2.Cu")
		(net "GMI_CPU0_G2_CPU1_G0_TX_DN<13>")
	)
	(segment
		(start 108.586016 -221.66326)
		(end 108.586016 -221.804484)
		(width 0.1143)
		(layer "In2.Cu")
		(net "GMI_CPU0_G2_CPU1_G0_TX_DN<13>")
	)
	(segment
		(start 362.250228 -222.937832)
		(end 362.252514 -222.936308)
		(width 0.1143)
		(layer "In2.Cu")
		(net "GMI_CPU0_G2_CPU1_G0_TX_DN<13>")
	)
	(segment
		(start 109.283246 -225.509074)
		(end 109.24667 -225.53041)
		(width 0.1143)
		(layer "In2.Cu")
		(net "GMI_CPU0_G2_CPU1_G0_TX_DN<13>")
	)
	(segment
		(start 362.251752 -225.53168)
		(end 362.251752 -225.531426)
		(width 0.1143)
		(layer "In2.Cu")
		(net "GMI_CPU0_G2_CPU1_G0_TX_DN<13>")
	)
	(segment
		(start 114.768376 -213.604348)
		(end 114.58702 -213.546436)
		(width 0.14224)
		(layer "In2.Cu")
		(net "GMI_CPU0_G2_CPU1_G0_TX_DN<13>")
	)
	(segment
		(start 109.242098 -227.153216)
		(end 109.21238 -227.170234)
		(width 0.1143)
		(layer "In2.Cu")
		(net "GMI_CPU0_G2_CPU1_G0_TX_DN<13>")
	)
	(segment
		(start 112.289082 -215.854534)
		(end 112.098582 -215.854534)
		(width 0.14224)
		(layer "In2.Cu")
		(net "GMI_CPU0_G2_CPU1_G0_TX_DN<13>")
	)
	(segment
		(start 111.506 -216.637616)
		(end 111.315754 -216.637616)
		(width 0.14224)
		(layer "In2.Cu")
		(net "GMI_CPU0_G2_CPU1_G0_TX_DN<13>")
	)
	(segment
		(start 362.21289 -222.959422)
		(end 362.250228 -222.937832)
		(width 0.1143)
		(layer "In2.Cu")
		(net "GMI_CPU0_G2_CPU1_G0_TX_DN<13>")
	)
	(segment
		(start 361.860338 -220.560646)
		(end 361.48391 -219.74556)
		(width 0.14224)
		(layer "In2.Cu")
		(net "GMI_CPU0_G2_CPU1_G0_TX_DN<13>")
	)
	(segment
		(start 265.083798 -189.615064)
		(end 236.459014 -184.719214)
		(width 0.14224)
		(layer "In2.Cu")
		(net "GMI_CPU0_G2_CPU1_G0_TX_DN<13>")
	)
	(segment
		(start 362.251752 -224.556828)
		(end 362.252514 -224.55632)
		(width 0.1143)
		(layer "In2.Cu")
		(net "GMI_CPU0_G2_CPU1_G0_TX_DN<13>")
	)
	(segment
		(start 111.802418 -216.340944)
		(end 111.506 -216.637616)
		(width 0.14224)
		(layer "In2.Cu")
		(net "GMI_CPU0_G2_CPU1_G0_TX_DN<13>")
	)
	(segment
		(start 109.063282 -227.404676)
		(end 109.133132 -227.474526)
		(width 0.1143)
		(layer "In2.Cu")
		(net "GMI_CPU0_G2_CPU1_G0_TX_DN<13>")
	)
	(segment
		(start 362.283502 -225.549968)
		(end 362.251752 -225.53168)
		(width 0.1143)
		(layer "In2.Cu")
		(net "GMI_CPU0_G2_CPU1_G0_TX_DN<13>")
	)
	(segment
		(start 362.21289 -223.889062)
		(end 362.18495 -223.868996)
		(width 0.1143)
		(layer "In2.Cu")
		(net "GMI_CPU0_G2_CPU1_G0_TX_DN<13>")
	)
	(segment
		(start 109.133132 -227.474526)
		(end 109.431074 -227.474526)
		(width 0.1143)
		(layer "In2.Cu")
		(net "GMI_CPU0_G2_CPU1_G0_TX_DN<13>")
	)
	(segment
		(start 109.242098 -225.533204)
		(end 109.21238 -225.550222)
		(width 0.1143)
		(layer "In2.Cu")
		(net "GMI_CPU0_G2_CPU1_G0_TX_DN<13>")
	)
	(segment
		(start 109.245146 -225.531426)
		(end 109.24413 -225.531934)
		(width 0.1143)
		(layer "In2.Cu")
		(net "GMI_CPU0_G2_CPU1_G0_TX_DN<13>")
	)
	(segment
		(start 362.251752 -225.531426)
		(end 362.212128 -225.50882)
		(width 0.1143)
		(layer "In2.Cu")
		(net "GMI_CPU0_G2_CPU1_G0_TX_DN<13>")
	)
	(segment
		(start 356.273862 -215.309196)
		(end 355.555804 -214.84082)
		(width 0.14224)
		(layer "In2.Cu")
		(net "GMI_CPU0_G2_CPU1_G0_TX_DN<13>")
	)
	(segment
		(start 109.243368 -225.532442)
		(end 109.242098 -225.533204)
		(width 0.1143)
		(layer "In2.Cu")
		(net "GMI_CPU0_G2_CPU1_G0_TX_DN<13>")
	)
	(segment
		(start 361.969558 -221.489524)
		(end 361.906058 -221.426024)
		(width 0.1143)
		(layer "In2.Cu")
		(net "GMI_CPU0_G2_CPU1_G0_TX_DN<13>")
	)
	(segment
		(start 112.5855 -215.557862)
		(end 112.289082 -215.854534)
		(width 0.14224)
		(layer "In2.Cu")
		(net "GMI_CPU0_G2_CPU1_G0_TX_DN<13>")
	)
	(segment
		(start 362.252514 -227.1522)
		(end 362.251752 -227.151692)
		(width 0.1143)
		(layer "In2.Cu")
		(net "GMI_CPU0_G2_CPU1_G0_TX_DN<13>")
	)
	(segment
		(start 109.242098 -226.175824)
		(end 109.243368 -226.176586)
		(width 0.1143)
		(layer "In2.Cu")
		(net "GMI_CPU0_G2_CPU1_G0_TX_DN<13>")
	)
	(segment
		(start 313.913012 -191.299592)
		(end 310.638952 -189.714378)
		(width 0.14224)
		(layer "In2.Cu")
		(net "GMI_CPU0_G2_CPU1_G0_TX_DN<13>")
	)
	(segment
		(start 362.251752 -226.17684)
		(end 362.252514 -226.176332)
		(width 0.1143)
		(layer "In2.Cu")
		(net "GMI_CPU0_G2_CPU1_G0_TX_DN<13>")
	)
	(segment
		(start 362.212128 -224.579688)
		(end 362.251752 -224.556828)
		(width 0.1143)
		(layer "In2.Cu")
		(net "GMI_CPU0_G2_CPU1_G0_TX_DN<13>")
	)
	(segment
		(start 109.240574 -224.55505)
		(end 109.242098 -224.555812)
		(width 0.1143)
		(layer "In2.Cu")
		(net "GMI_CPU0_G2_CPU1_G0_TX_DN<13>")
	)
	(segment
		(start 113.368582 -214.77478)
		(end 113.072164 -215.071452)
		(width 0.14224)
		(layer "In2.Cu")
		(net "GMI_CPU0_G2_CPU1_G0_TX_DN<13>")
	)
	(segment
		(start 208.190846 -189.0395)
		(end 161.801556 -189.176152)
		(width 0.14224)
		(layer "In2.Cu")
		(net "GMI_CPU0_G2_CPU1_G0_TX_DN<13>")
	)
	(segment
		(start 115.140994 -213.41207)
		(end 114.768376 -213.604348)
		(width 0.14224)
		(layer "In2.Cu")
		(net "GMI_CPU0_G2_CPU1_G0_TX_DN<13>")
	)
	(segment
		(start 362.212128 -225.50882)
		(end 362.185204 -225.489262)
		(width 0.1143)
		(layer "In2.Cu")
		(net "GMI_CPU0_G2_CPU1_G0_TX_DN<13>")
	)
	(segment
		(start 111.019336 -217.12428)
		(end 110.722918 -217.420952)
		(width 0.14224)
		(layer "In2.Cu")
		(net "GMI_CPU0_G2_CPU1_G0_TX_DN<13>")
	)
	(segment
		(start 109.21238 -226.158806)
		(end 109.239812 -226.174554)
		(width 0.1143)
		(layer "In2.Cu")
		(net "GMI_CPU0_G2_CPU1_G0_TX_DN<13>")
	)
	(segment
		(start 362.252514 -222.936308)
		(end 362.253784 -222.935546)
		(width 0.1143)
		(layer "In2.Cu")
		(net "GMI_CPU0_G2_CPU1_G0_TX_DN<13>")
	)
	(segment
		(start 109.243368 -226.176586)
		(end 109.24413 -226.177094)
		(width 0.1143)
		(layer "In2.Cu")
		(net "GMI_CPU0_G2_CPU1_G0_TX_DN<13>")
	)
	(segment
		(start 236.459014 -184.719214)
		(end 208.190846 -189.0395)
		(width 0.14224)
		(layer "In2.Cu")
		(net "GMI_CPU0_G2_CPU1_G0_TX_DN<13>")
	)
	(segment
		(start 362.253784 -226.17557)
		(end 362.283502 -226.158552)
		(width 0.1143)
		(layer "In2.Cu")
		(net "GMI_CPU0_G2_CPU1_G0_TX_DN<13>")
	)
	(segment
		(start 108.966254 -218.987624)
		(end 108.67009 -219.283788)
		(width 0.14224)
		(layer "In2.Cu")
		(net "GMI_CPU0_G2_CPU1_G0_TX_DN<13>")
	)
	(segment
		(start 108.62437 -221.248732)
		(end 108.62437 -221.624906)
		(width 0.1143)
		(layer "In2.Cu")
		(net "GMI_CPU0_G2_CPU1_G0_TX_DN<13>")
	)
	(segment
		(start 108.67009 -221.203012)
		(end 108.62437 -221.248732)
		(width 0.1143)
		(layer "In2.Cu")
		(net "GMI_CPU0_G2_CPU1_G0_TX_DN<13>")
	)
	(segment
		(start 111.802418 -216.150952)
		(end 111.802418 -216.340944)
		(width 0.14224)
		(layer "In2.Cu")
		(net "GMI_CPU0_G2_CPU1_G0_TX_DN<13>")
	)
	(segment
		(start 362.252514 -226.176332)
		(end 362.253784 -226.17557)
		(width 0.1143)
		(layer "In2.Cu")
		(net "GMI_CPU0_G2_CPU1_G0_TX_DN<13>")
	)
	(segment
		(start 109.245146 -224.55759)
		(end 109.24667 -224.558606)
		(width 0.1143)
		(layer "In2.Cu")
		(net "GMI_CPU0_G2_CPU1_G0_TX_DN<13>")
	)
	(segment
		(start 362.283502 -222.309944)
		(end 362.212636 -222.268796)
		(width 0.1143)
		(layer "In2.Cu")
		(net "GMI_CPU0_G2_CPU1_G0_TX_DN<13>")
	)
	(segment
		(start 111.315754 -216.637616)
		(end 111.01959 -216.934034)
		(width 0.14224)
		(layer "In2.Cu")
		(net "GMI_CPU0_G2_CPU1_G0_TX_DN<13>")
	)
	(segment
		(start 362.185204 -224.599246)
		(end 362.212128 -224.579688)
		(width 0.1143)
		(layer "In2.Cu")
		(net "GMI_CPU0_G2_CPU1_G0_TX_DN<13>")
	)
	(segment
		(start 109.749336 -218.204288)
		(end 109.453172 -218.500706)
		(width 0.14224)
		(layer "In2.Cu")
		(net "GMI_CPU0_G2_CPU1_G0_TX_DN<13>")
	)
	(segment
		(start 115.752626 -213.096348)
		(end 115.57127 -213.038436)
		(width 0.14224)
		(layer "In2.Cu")
		(net "GMI_CPU0_G2_CPU1_G0_TX_DN<13>")
	)
	(segment
		(start 110.236254 -217.907616)
		(end 109.939836 -218.204288)
		(width 0.14224)
		(layer "In2.Cu")
		(net "GMI_CPU0_G2_CPU1_G0_TX_DN<13>")
	)
	(segment
		(start 116.125244 -212.90407)
		(end 115.752626 -213.096348)
		(width 0.14224)
		(layer "In2.Cu")
		(net "GMI_CPU0_G2_CPU1_G0_TX_DN<13>")
	)
	(segment
		(start 109.236256 -222.932752)
		(end 109.28223 -222.959422)
		(width 0.1143)
		(layer "In2.Cu")
		(net "GMI_CPU0_G2_CPU1_G0_TX_DN<13>")
	)
	(segment
		(start 110.532418 -217.420952)
		(end 110.236254 -217.71737)
		(width 0.14224)
		(layer "In2.Cu")
		(net "GMI_CPU0_G2_CPU1_G0_TX_DN<13>")
	)
	(segment
		(start 362.18495 -222.979488)
		(end 362.21289 -222.959422)
		(width 0.1143)
		(layer "In2.Cu")
		(net "GMI_CPU0_G2_CPU1_G0_TX_DN<13>")
	)
	(segment
		(start 108.67009 -219.283788)
		(end 108.67009 -221.174564)
		(width 0.14224)
		(layer "In2.Cu")
		(net "GMI_CPU0_G2_CPU1_G0_TX_DN<13>")
	)
	(segment
		(start 108.741972 -222.108776)
		(end 108.776262 -222.128588)
		(width 0.1143)
		(layer "In2.Cu")
		(net "GMI_CPU0_G2_CPU1_G0_TX_DN<13>")
	)
	(segment
		(start 355.555804 -214.84082)
		(end 313.913012 -191.299592)
		(width 0.14224)
		(layer "In2.Cu")
		(net "GMI_CPU0_G2_CPU1_G0_TX_DN<13>")
	)
	(segment
		(start 361.906058 -221.128844)
		(end 361.860338 -221.083124)
		(width 0.1143)
		(layer "In2.Cu")
		(net "GMI_CPU0_G2_CPU1_G0_TX_DN<13>")
	)
	(segment
		(start 361.48391 -219.74556)
		(end 356.273862 -215.309196)
		(width 0.14224)
		(layer "In2.Cu")
		(net "GMI_CPU0_G2_CPU1_G0_TX_DN<13>")
	)
	(segment
		(start 109.24413 -224.557082)
		(end 109.245146 -224.55759)
		(width 0.1143)
		(layer "In2.Cu")
		(net "GMI_CPU0_G2_CPU1_G0_TX_DN<13>")
	)
	(segment
		(start 310.638952 -189.714378)
		(end 307.235606 -189.11443)
		(width 0.14224)
		(layer "In2.Cu")
		(net "GMI_CPU0_G2_CPU1_G0_TX_DN<13>")
	)
	(segment
		(start 109.453172 -218.690952)
		(end 109.156754 -218.987624)
		(width 0.14224)
		(layer "In2.Cu")
		(net "GMI_CPU0_G2_CPU1_G0_TX_DN<13>")
	)
	(segment
		(start 114.58702 -213.546436)
		(end 114.214656 -213.73846)
		(width 0.14224)
		(layer "In2.Cu")
		(net "GMI_CPU0_G2_CPU1_G0_TX_DN<13>")
	)
	(segment
		(start 109.24413 -225.531934)
		(end 109.243368 -225.532442)
		(width 0.1143)
		(layer "In2.Cu")
		(net "GMI_CPU0_G2_CPU1_G0_TX_DN<13>")
	)
	(segment
		(start 362.253784 -224.555558)
		(end 362.283502 -224.53854)
		(width 0.1143)
		(layer "In2.Cu")
		(net "GMI_CPU0_G2_CPU1_G0_TX_DN<13>")
	)
	(segment
		(start 109.24667 -225.53041)
		(end 109.245146 -225.531426)
		(width 0.1143)
		(layer "In2.Cu")
		(net "GMI_CPU0_G2_CPU1_G0_TX_DN<13>")
	)
	(segment
		(start 161.801556 -189.176152)
		(end 116.183156 -212.72246)
		(width 0.14224)
		(layer "In2.Cu")
		(net "GMI_CPU0_G2_CPU1_G0_TX_DN<13>")
	)
	(segment
		(start 362.252514 -224.55632)
		(end 362.253784 -224.555558)
		(width 0.1143)
		(layer "In2.Cu")
		(net "GMI_CPU0_G2_CPU1_G0_TX_DN<13>")
	)
	(segment
		(start 116.183156 -212.72246)
		(end 116.125244 -212.90407)
		(width 0.14224)
		(layer "In2.Cu")
		(net "GMI_CPU0_G2_CPU1_G0_TX_DN<13>")
	)
	(segment
		(start 110.722918 -217.420952)
		(end 110.532418 -217.420952)
		(width 0.14224)
		(layer "In2.Cu")
		(net "GMI_CPU0_G2_CPU1_G0_TX_DN<13>")
	)
	(segment
		(start 111.01959 -216.934034)
		(end 111.019336 -216.93378)
		(width 0.14224)
		(layer "In2.Cu")
		(net "GMI_CPU0_G2_CPU1_G0_TX_DN<13>")
	)
	(segment
		(start 109.24667 -224.558606)
		(end 109.283246 -224.579942)
		(width 0.1143)
		(layer "In2.Cu")
		(net "GMI_CPU0_G2_CPU1_G0_TX_DN<13>")
	)
	(segment
		(start 109.24413 -227.151946)
		(end 109.243368 -227.152454)
		(width 0.1143)
		(layer "In2.Cu")
		(net "GMI_CPU0_G2_CPU1_G0_TX_DN<13>")
	)
	(segment
		(start 109.240574 -226.175062)
		(end 109.242098 -226.175824)
		(width 0.1143)
		(layer "In2.Cu")
		(net "GMI_CPU0_G2_CPU1_G0_TX_DN<13>")
	)
	(segment
		(start 109.282992 -223.889062)
		(end 109.243876 -223.911922)
		(width 0.1143)
		(layer "In2.Cu")
		(net "GMI_CPU0_G2_CPU1_G0_TX_DN<13>")
	)
	(segment
		(start 113.368582 -214.584788)
		(end 113.368582 -214.77478)
		(width 0.14224)
		(layer "In2.Cu")
		(net "GMI_CPU0_G2_CPU1_G0_TX_DN<13>")
	)
	(segment
		(start 362.253784 -222.935546)
		(end 362.283502 -222.918528)
		(width 0.1143)
		(layer "In2.Cu")
		(net "GMI_CPU0_G2_CPU1_G0_TX_DN<13>")
	)
	(segment
		(start 109.243368 -227.152454)
		(end 109.242098 -227.153216)
		(width 0.1143)
		(layer "In2.Cu")
		(net "GMI_CPU0_G2_CPU1_G0_TX_DN<13>")
	)
	(segment
		(start 109.939836 -218.204288)
		(end 109.749336 -218.204288)
		(width 0.14224)
		(layer "In2.Cu")
		(net "GMI_CPU0_G2_CPU1_G0_TX_DN<13>")
	)
	(segment
		(start 362.064808 -227.474272)
		(end 362.36275 -227.474272)
		(width 0.1143)
		(layer "In2.Cu")
		(net "GMI_CPU0_G2_CPU1_G0_TX_DN<13>")
	)
	(segment
		(start 109.239812 -226.174554)
		(end 109.240574 -226.175062)
		(width 0.1143)
		(layer "In2.Cu")
		(net "GMI_CPU0_G2_CPU1_G0_TX_DN<13>")
	)
	(segment
		(start 307.235606 -189.11443)
		(end 265.083798 -189.615064)
		(width 0.14224)
		(layer "In2.Cu")
		(net "GMI_CPU0_G2_CPU1_G0_TX_DN<13>")
	)
	(segment
		(start 109.21238 -224.538794)
		(end 109.239812 -224.554542)
		(width 0.1143)
		(layer "In2.Cu")
		(net "GMI_CPU0_G2_CPU1_G0_TX_DN<13>")
	)
	(segment
		(start 362.252514 -223.912176)
		(end 362.251752 -223.911668)
		(width 0.1143)
		(layer "In2.Cu")
		(net "GMI_CPU0_G2_CPU1_G0_TX_DN<13>")
	)
	(segment
		(start 108.67009 -221.174564)
		(end 108.67009 -221.203012)
		(width 0.1143)
		(layer "In2.Cu")
		(net "GMI_CPU0_G2_CPU1_G0_TX_DN<13>")
	)
	(segment
		(start 112.5855 -215.36787)
		(end 112.5855 -215.557862)
		(width 0.14224)
		(layer "In2.Cu")
		(net "GMI_CPU0_G2_CPU1_G0_TX_DN<13>")
	)
	(segment
		(start 109.156754 -218.987624)
		(end 108.966254 -218.987624)
		(width 0.14224)
		(layer "In2.Cu")
		(net "GMI_CPU0_G2_CPU1_G0_TX_DN<13>")
	)
	(segment
		(start 111.019336 -216.93378)
		(end 111.019336 -217.12428)
		(width 0.14224)
		(layer "In2.Cu")
		(net "GMI_CPU0_G2_CPU1_G0_TX_DN<13>")
	)
	(segment
		(start 109.243368 -224.556574)
		(end 109.24413 -224.557082)
		(width 0.1143)
		(layer "In2.Cu")
		(net "GMI_CPU0_G2_CPU1_G0_TX_DN<13>")
	)
	(segment
		(start 361.969558 -221.80423)
		(end 361.969558 -221.489524)
		(width 0.1143)
		(layer "In2.Cu")
		(net "GMI_CPU0_G2_CPU1_G0_TX_DN<13>")
	)
	(segment
		(start 362.21543 -226.197922)
		(end 362.251752 -226.17684)
		(width 0.1143)
		(layer "In2.Cu")
		(net "GMI_CPU0_G2_CPU1_G0_TX_DN<13>")
	)
	(segment
		(start 112.098582 -215.854534)
		(end 111.802418 -216.150952)
		(width 0.14224)
		(layer "In2.Cu")
		(net "GMI_CPU0_G2_CPU1_G0_TX_DN<13>")
	)
	(arc
		(start 362.185204 -225.489262)
		(mid 361.957526 -225.044254)
		(end 362.185204 -224.599246)
		(width 0.1143)
		(layer "In2.Cu")
		(net "GMI_CPU0_G2_CPU1_G0_TX_DN<13>")
	)
	(arc
		(start 362.199174 -226.209352)
		(mid 362.207252 -226.203566)
		(end 362.21543 -226.197922)
		(width 0.1143)
		(layer "In2.Cu")
		(net "GMI_CPU0_G2_CPU1_G0_TX_DN<13>")
	)
	(arc
		(start 362.283502 -226.158552)
		(mid 362.43943 -225.85426)
		(end 362.283502 -225.549968)
		(width 0.1143)
		(layer "In2.Cu")
		(net "GMI_CPU0_G2_CPU1_G0_TX_DN<13>")
	)
	(arc
		(start 109.283246 -224.579942)
		(mid 109.526573 -225.044508)
		(end 109.283246 -225.509074)
		(width 0.1143)
		(layer "In2.Cu")
		(net "GMI_CPU0_G2_CPU1_G0_TX_DN<13>")
	)
	(arc
		(start 109.060234 -222.619062)
		(mid 109.107319 -222.798858)
		(end 109.236256 -222.932752)
		(width 0.1143)
		(layer "In2.Cu")
		(net "GMI_CPU0_G2_CPU1_G0_TX_DN<13>")
	)
	(arc
		(start 109.21238 -225.550222)
		(mid 109.056452 -225.854514)
		(end 109.21238 -226.158806)
		(width 0.1143)
		(layer "In2.Cu")
		(net "GMI_CPU0_G2_CPU1_G0_TX_DN<13>")
	)
	(arc
		(start 109.21238 -227.170234)
		(mid 109.115245 -227.273103)
		(end 109.063282 -227.404676)
		(width 0.1143)
		(layer "In2.Cu")
		(net "GMI_CPU0_G2_CPU1_G0_TX_DN<13>")
	)
	(arc
		(start 362.4326 -227.404422)
		(mid 362.380551 -227.272903)
		(end 362.283502 -227.16998)
		(width 0.1143)
		(layer "In2.Cu")
		(net "GMI_CPU0_G2_CPU1_G0_TX_DN<13>")
	)
	(arc
		(start 109.282992 -222.95993)
		(mid 109.526319 -223.424496)
		(end 109.282992 -223.889062)
		(width 0.1143)
		(layer "In2.Cu")
		(net "GMI_CPU0_G2_CPU1_G0_TX_DN<13>")
	)
	(arc
		(start 362.18495 -223.868996)
		(mid 361.95695 -223.424242)
		(end 362.18495 -222.979488)
		(width 0.1143)
		(layer "In2.Cu")
		(net "GMI_CPU0_G2_CPU1_G0_TX_DN<13>")
	)
	(arc
		(start 109.213396 -223.929702)
		(mid 109.097969 -224.063078)
		(end 109.056424 -224.234502)
		(width 0.1143)
		(layer "In2.Cu")
		(net "GMI_CPU0_G2_CPU1_G0_TX_DN<13>")
	)
	(arc
		(start 108.776262 -222.128588)
		(mid 108.984084 -222.3357)
		(end 109.060234 -222.619062)
		(width 0.1143)
		(layer "In2.Cu")
		(net "GMI_CPU0_G2_CPU1_G0_TX_DN<13>")
	)
	(arc
		(start 362.199174 -227.11918)
		(mid 361.97629 -226.664266)
		(end 362.199174 -226.209352)
		(width 0.1143)
		(layer "In2.Cu")
		(net "GMI_CPU0_G2_CPU1_G0_TX_DN<13>")
	)
	(arc
		(start 362.283502 -224.53854)
		(mid 362.43943 -224.234248)
		(end 362.283502 -223.929956)
		(width 0.1143)
		(layer "In2.Cu")
		(net "GMI_CPU0_G2_CPU1_G0_TX_DN<13>")
	)
	(arc
		(start 362.212636 -222.268796)
		(mid 362.033978 -222.066396)
		(end 361.969558 -221.80423)
		(width 0.1143)
		(layer "In2.Cu")
		(net "GMI_CPU0_G2_CPU1_G0_TX_DN<13>")
	)
	(arc
		(start 109.24413 -226.177094)
		(mid 109.524777 -226.66452)
		(end 109.24413 -227.151946)
		(width 0.1143)
		(layer "In2.Cu")
		(net "GMI_CPU0_G2_CPU1_G0_TX_DN<13>")
	)
	(arc
		(start 109.056424 -224.234502)
		(mid 109.097679 -224.405473)
		(end 109.21238 -224.538794)
		(width 0.1143)
		(layer "In2.Cu")
		(net "GMI_CPU0_G2_CPU1_G0_TX_DN<13>")
	)
	(arc
		(start 109.28223 -222.959422)
		(mid 109.282611 -222.959676)
		(end 109.282992 -222.95993)
		(width 0.1143)
		(layer "In2.Cu")
		(net "GMI_CPU0_G2_CPU1_G0_TX_DN<13>")
	)
	(arc
		(start 108.586016 -221.804484)
		(mid 108.627271 -221.975455)
		(end 108.741972 -222.108776)
		(width 0.1143)
		(layer "In2.Cu")
		(net "GMI_CPU0_G2_CPU1_G0_TX_DN<13>")
	)
	(arc
		(start 362.283502 -222.918528)
		(mid 362.43943 -222.614236)
		(end 362.283502 -222.309944)
		(width 0.1143)
		(layer "In2.Cu")
		(net "GMI_CPU0_G2_CPU1_G0_TX_DN<13>")
	)
	(arc
		(start 362.21543 -227.13061)
		(mid 362.207252 -227.124967)
		(end 362.199174 -227.11918)
		(width 0.1143)
		(layer "In2.Cu")
		(net "GMI_CPU0_G2_CPU1_G0_TX_DN<13>")
	)
	(segment
		(start 363.947964 -230.169974)
		(end 364.414816 -229.904036)
		(width 0.12954)
		(layer "F.Cu")
		(net "GMI_CPU0_G2_CPU1_G0_TX_DN<12>")
	)
	(segment
		(start 107.547918 -230.170228)
		(end 107.081066 -229.90429)
		(width 0.12954)
		(layer "F.Cu")
		(net "GMI_CPU0_G2_CPU1_G0_TX_DN<12>")
	)
	(segment
		(start 108.325666 -225.519234)
		(end 108.321602 -225.523552)
		(width 0.1143)
		(layer "In2.Cu")
		(net "GMI_CPU0_G2_CPU1_G0_TX_DN<12>")
	)
	(segment
		(start 108.299758 -226.174554)
		(end 108.30052 -226.175062)
		(width 0.1143)
		(layer "In2.Cu")
		(net "GMI_CPU0_G2_CPU1_G0_TX_DN<12>")
	)
	(segment
		(start 108.3056 -223.910906)
		(end 108.303314 -223.91243)
		(width 0.1143)
		(layer "In2.Cu")
		(net "GMI_CPU0_G2_CPU1_G0_TX_DN<12>")
	)
	(segment
		(start 362.805218 -221.083124)
		(end 362.805218 -220.191584)
		(width 0.14224)
		(layer "In2.Cu")
		(net "GMI_CPU0_G2_CPU1_G0_TX_DN<12>")
	)
	(segment
		(start 108.272326 -222.918782)
		(end 108.299758 -222.93453)
		(width 0.1143)
		(layer "In2.Cu")
		(net "GMI_CPU0_G2_CPU1_G0_TX_DN<12>")
	)
	(segment
		(start 363.193838 -222.935546)
		(end 363.223556 -222.918528)
		(width 0.1143)
		(layer "In2.Cu")
		(net "GMI_CPU0_G2_CPU1_G0_TX_DN<12>")
	)
	(segment
		(start 108.299758 -225.534474)
		(end 108.297726 -225.53549)
		(width 0.1143)
		(layer "In2.Cu")
		(net "GMI_CPU0_G2_CPU1_G0_TX_DN<12>")
	)
	(segment
		(start 110.857538 -215.735662)
		(end 110.56112 -216.032334)
		(width 0.14224)
		(layer "In2.Cu")
		(net "GMI_CPU0_G2_CPU1_G0_TX_DN<12>")
	)
	(segment
		(start 363.191806 -224.556828)
		(end 363.192568 -224.55632)
		(width 0.1143)
		(layer "In2.Cu")
		(net "GMI_CPU0_G2_CPU1_G0_TX_DN<12>")
	)
	(segment
		(start 110.074456 -216.518998)
		(end 109.778038 -216.81567)
		(width 0.14224)
		(layer "In2.Cu")
		(net "GMI_CPU0_G2_CPU1_G0_TX_DN<12>")
	)
	(segment
		(start 110.370874 -216.032334)
		(end 110.07471 -216.328752)
		(width 0.14224)
		(layer "In2.Cu")
		(net "GMI_CPU0_G2_CPU1_G0_TX_DN<12>")
	)
	(segment
		(start 108.303314 -225.532442)
		(end 108.302044 -225.533204)
		(width 0.1143)
		(layer "In2.Cu")
		(net "GMI_CPU0_G2_CPU1_G0_TX_DN<12>")
	)
	(segment
		(start 113.206784 -213.195662)
		(end 113.206784 -213.385908)
		(width 0.14224)
		(layer "In2.Cu")
		(net "GMI_CPU0_G2_CPU1_G0_TX_DN<12>")
	)
	(segment
		(start 314.48629 -190.526416)
		(end 310.932576 -188.806328)
		(width 0.14224)
		(layer "In2.Cu")
		(net "GMI_CPU0_G2_CPU1_G0_TX_DN<12>")
	)
	(segment
		(start 108.303314 -226.176586)
		(end 108.304076 -226.177094)
		(width 0.1143)
		(layer "In2.Cu")
		(net "GMI_CPU0_G2_CPU1_G0_TX_DN<12>")
	)
	(segment
		(start 363.189266 -223.910144)
		(end 363.15269 -223.888808)
		(width 0.1143)
		(layer "In2.Cu")
		(net "GMI_CPU0_G2_CPU1_G0_TX_DN<12>")
	)
	(segment
		(start 111.640874 -214.762334)
		(end 111.64062 -214.761826)
		(width 0.14224)
		(layer "In2.Cu")
		(net "GMI_CPU0_G2_CPU1_G0_TX_DN<12>")
	)
	(segment
		(start 108.302044 -227.153216)
		(end 108.30052 -227.153978)
		(width 0.1143)
		(layer "In2.Cu")
		(net "GMI_CPU0_G2_CPU1_G0_TX_DN<12>")
	)
	(segment
		(start 108.30052 -222.935038)
		(end 108.302044 -222.9358)
		(width 0.1143)
		(layer "In2.Cu")
		(net "GMI_CPU0_G2_CPU1_G0_TX_DN<12>")
	)
	(segment
		(start 363.221778 -227.169218)
		(end 363.218476 -227.167186)
		(width 0.1143)
		(layer "In2.Cu")
		(net "GMI_CPU0_G2_CPU1_G0_TX_DN<12>")
	)
	(segment
		(start 107.646724 -221.624906)
		(end 107.646724 -221.804992)
		(width 0.1143)
		(layer "In2.Cu")
		(net "GMI_CPU0_G2_CPU1_G0_TX_DN<12>")
	)
	(segment
		(start 362.850938 -221.128844)
		(end 362.805218 -221.083124)
		(width 0.1143)
		(layer "In2.Cu")
		(net "GMI_CPU0_G2_CPU1_G0_TX_DN<12>")
	)
	(segment
		(start 107.803442 -222.109284)
		(end 107.873038 -222.149924)
		(width 0.1143)
		(layer "In2.Cu")
		(net "GMI_CPU0_G2_CPU1_G0_TX_DN<12>")
	)
	(segment
		(start 114.885978 -212.171026)
		(end 114.828066 -212.352636)
		(width 0.14224)
		(layer "In2.Cu")
		(net "GMI_CPU0_G2_CPU1_G0_TX_DN<12>")
	)
	(segment
		(start 107.36199 -228.773228)
		(end 107.360466 -228.77399)
		(width 0.1143)
		(layer "In2.Cu")
		(net "GMI_CPU0_G2_CPU1_G0_TX_DN<12>")
	)
	(segment
		(start 108.30052 -226.175062)
		(end 108.302044 -226.175824)
		(width 0.1143)
		(layer "In2.Cu")
		(net "GMI_CPU0_G2_CPU1_G0_TX_DN<12>")
	)
	(segment
		(start 110.857538 -215.545162)
		(end 110.857538 -215.735662)
		(width 0.14224)
		(layer "In2.Cu")
		(net "GMI_CPU0_G2_CPU1_G0_TX_DN<12>")
	)
	(segment
		(start 111.937038 -214.465916)
		(end 111.640874 -214.762334)
		(width 0.14224)
		(layer "In2.Cu")
		(net "GMI_CPU0_G2_CPU1_G0_TX_DN<12>")
	)
	(segment
		(start 363.21746 -227.166678)
		(end 363.192568 -227.1522)
		(width 0.1143)
		(layer "In2.Cu")
		(net "GMI_CPU0_G2_CPU1_G0_TX_DN<12>")
	)
	(segment
		(start 108.370878 -225.489262)
		(end 108.342938 -225.509328)
		(width 0.1143)
		(layer "In2.Cu")
		(net "GMI_CPU0_G2_CPU1_G0_TX_DN<12>")
	)
	(segment
		(start 108.302044 -222.9358)
		(end 108.303314 -222.936562)
		(width 0.1143)
		(layer "In2.Cu")
		(net "GMI_CPU0_G2_CPU1_G0_TX_DN<12>")
	)
	(segment
		(start 108.211874 -218.382342)
		(end 108.021374 -218.382342)
		(width 0.14224)
		(layer "In2.Cu")
		(net "GMI_CPU0_G2_CPU1_G0_TX_DN<12>")
	)
	(segment
		(start 109.778038 -216.81567)
		(end 109.587538 -216.81567)
		(width 0.14224)
		(layer "In2.Cu")
		(net "GMI_CPU0_G2_CPU1_G0_TX_DN<12>")
	)
	(segment
		(start 363.192568 -223.912176)
		(end 363.191806 -223.911668)
		(width 0.1143)
		(layer "In2.Cu")
		(net "GMI_CPU0_G2_CPU1_G0_TX_DN<12>")
	)
	(segment
		(start 310.932576 -188.806328)
		(end 307.312822 -188.16828)
		(width 0.14224)
		(layer "In2.Cu")
		(net "GMI_CPU0_G2_CPU1_G0_TX_DN<12>")
	)
	(segment
		(start 108.342938 -225.509328)
		(end 108.325666 -225.519234)
		(width 0.1143)
		(layer "In2.Cu")
		(net "GMI_CPU0_G2_CPU1_G0_TX_DN<12>")
	)
	(segment
		(start 363.192568 -224.55632)
		(end 363.193838 -224.555558)
		(width 0.1143)
		(layer "In2.Cu")
		(net "GMI_CPU0_G2_CPU1_G0_TX_DN<12>")
	)
	(segment
		(start 265.157204 -188.66866)
		(end 236.467396 -183.761888)
		(width 0.14224)
		(layer "In2.Cu")
		(net "GMI_CPU0_G2_CPU1_G0_TX_DN<12>")
	)
	(segment
		(start 108.370878 -223.86925)
		(end 108.342938 -223.889316)
		(width 0.1143)
		(layer "In2.Cu")
		(net "GMI_CPU0_G2_CPU1_G0_TX_DN<12>")
	)
	(segment
		(start 108.30052 -225.533966)
		(end 108.299758 -225.534474)
		(width 0.1143)
		(layer "In2.Cu")
		(net "GMI_CPU0_G2_CPU1_G0_TX_DN<12>")
	)
	(segment
		(start 364.414816 -229.904036)
		(end 364.712758 -229.904036)
		(width 0.1143)
		(layer "In2.Cu")
		(net "GMI_CPU0_G2_CPU1_G0_TX_DN<12>")
	)
	(segment
		(start 108.299758 -227.154486)
		(end 108.297726 -227.155502)
		(width 0.1143)
		(layer "In2.Cu")
		(net "GMI_CPU0_G2_CPU1_G0_TX_DN<12>")
	)
	(segment
		(start 362.805218 -220.191584)
		(end 362.318554 -219.137738)
		(width 0.14224)
		(layer "In2.Cu")
		(net "GMI_CPU0_G2_CPU1_G0_TX_DN<12>")
	)
	(segment
		(start 108.304076 -227.151946)
		(end 108.303314 -227.152454)
		(width 0.1143)
		(layer "In2.Cu")
		(net "GMI_CPU0_G2_CPU1_G0_TX_DN<12>")
	)
	(segment
		(start 107.72521 -221.203012)
		(end 107.67949 -221.248732)
		(width 0.1143)
		(layer "In2.Cu")
		(net "GMI_CPU0_G2_CPU1_G0_TX_DN<12>")
	)
	(segment
		(start 364.16361 -228.789992)
		(end 364.133384 -228.77272)
		(width 0.1143)
		(layer "In2.Cu")
		(net "GMI_CPU0_G2_CPU1_G0_TX_DN<12>")
	)
	(segment
		(start 108.342938 -223.889316)
		(end 108.3056 -223.910906)
		(width 0.1143)
		(layer "In2.Cu")
		(net "GMI_CPU0_G2_CPU1_G0_TX_DN<12>")
	)
	(segment
		(start 108.30052 -227.153978)
		(end 108.299758 -227.154486)
		(width 0.1143)
		(layer "In2.Cu")
		(net "GMI_CPU0_G2_CPU1_G0_TX_DN<12>")
	)
	(segment
		(start 107.833922 -227.961952)
		(end 107.803442 -227.979732)
		(width 0.1143)
		(layer "In2.Cu")
		(net "GMI_CPU0_G2_CPU1_G0_TX_DN<12>")
	)
	(segment
		(start 108.508292 -217.895424)
		(end 108.508292 -218.08567)
		(width 0.14224)
		(layer "In2.Cu")
		(net "GMI_CPU0_G2_CPU1_G0_TX_DN<12>")
	)
	(segment
		(start 364.133384 -228.77272)
		(end 364.132114 -228.772974)
		(width 0.1143)
		(layer "In2.Cu")
		(net "GMI_CPU0_G2_CPU1_G0_TX_DN<12>")
	)
	(segment
		(start 111.64062 -214.952326)
		(end 111.344202 -215.248998)
		(width 0.14224)
		(layer "In2.Cu")
		(net "GMI_CPU0_G2_CPU1_G0_TX_DN<12>")
	)
	(segment
		(start 363.19079 -223.91116)
		(end 363.189266 -223.910144)
		(width 0.1143)
		(layer "In2.Cu")
		(net "GMI_CPU0_G2_CPU1_G0_TX_DN<12>")
	)
	(segment
		(start 106.713274 -229.83444)
		(end 106.783124 -229.90429)
		(width 0.1143)
		(layer "In2.Cu")
		(net "GMI_CPU0_G2_CPU1_G0_TX_DN<12>")
	)
	(segment
		(start 357.299006 -214.863934)
		(end 355.692456 -213.815676)
		(width 0.14224)
		(layer "In2.Cu")
		(net "GMI_CPU0_G2_CPU1_G0_TX_DN<12>")
	)
	(segment
		(start 364.60176 -229.58171)
		(end 364.565438 -229.560628)
		(width 0.1143)
		(layer "In2.Cu")
		(net "GMI_CPU0_G2_CPU1_G0_TX_DN<12>")
	)
	(segment
		(start 108.30052 -223.913954)
		(end 108.299758 -223.914462)
		(width 0.1143)
		(layer "In2.Cu")
		(net "GMI_CPU0_G2_CPU1_G0_TX_DN<12>")
	)
	(segment
		(start 108.302044 -225.533204)
		(end 108.30052 -225.533966)
		(width 0.1143)
		(layer "In2.Cu")
		(net "GMI_CPU0_G2_CPU1_G0_TX_DN<12>")
	)
	(segment
		(start 110.074456 -216.328498)
		(end 110.074456 -216.518998)
		(width 0.14224)
		(layer "In2.Cu")
		(net "GMI_CPU0_G2_CPU1_G0_TX_DN<12>")
	)
	(segment
		(start 114.455448 -212.544914)
		(end 114.274092 -212.487002)
		(width 0.14224)
		(layer "In2.Cu")
		(net "GMI_CPU0_G2_CPU1_G0_TX_DN<12>")
	)
	(segment
		(start 363.189266 -225.530156)
		(end 363.15269 -225.50882)
		(width 0.1143)
		(layer "In2.Cu")
		(net "GMI_CPU0_G2_CPU1_G0_TX_DN<12>")
	)
	(segment
		(start 307.312822 -188.16828)
		(end 265.157204 -188.66866)
		(width 0.14224)
		(layer "In2.Cu")
		(net "GMI_CPU0_G2_CPU1_G0_TX_DN<12>")
	)
	(segment
		(start 107.365038 -228.77145)
		(end 107.364022 -228.771958)
		(width 0.1143)
		(layer "In2.Cu")
		(net "GMI_CPU0_G2_CPU1_G0_TX_DN<12>")
	)
	(segment
		(start 363.18825 -222.289624)
		(end 363.15269 -222.268796)
		(width 0.1143)
		(layer "In2.Cu")
		(net "GMI_CPU0_G2_CPU1_G0_TX_DN<12>")
	)
	(segment
		(start 363.15269 -224.579688)
		(end 363.19079 -224.557336)
		(width 0.1143)
		(layer "In2.Cu")
		(net "GMI_CPU0_G2_CPU1_G0_TX_DN<12>")
	)
	(segment
		(start 363.191806 -223.911668)
		(end 363.19079 -223.91116)
		(width 0.1143)
		(layer "In2.Cu")
		(net "GMI_CPU0_G2_CPU1_G0_TX_DN<12>")
	)
	(segment
		(start 106.932984 -229.559104)
		(end 106.893868 -229.581964)
		(width 0.1143)
		(layer "In2.Cu")
		(net "GMI_CPU0_G2_CPU1_G0_TX_DN<12>")
	)
	(segment
		(start 108.302044 -224.555812)
		(end 108.303314 -224.556574)
		(width 0.1143)
		(layer "In2.Cu")
		(net "GMI_CPU0_G2_CPU1_G0_TX_DN<12>")
	)
	(segment
		(start 112.127284 -214.465662)
		(end 111.936784 -214.465662)
		(width 0.14224)
		(layer "In2.Cu")
		(net "GMI_CPU0_G2_CPU1_G0_TX_DN<12>")
	)
	(segment
		(start 112.423702 -213.978744)
		(end 112.423702 -214.16899)
		(width 0.14224)
		(layer "In2.Cu")
		(net "GMI_CPU0_G2_CPU1_G0_TX_DN<12>")
	)
	(segment
		(start 108.321602 -225.523552)
		(end 108.303822 -225.532442)
		(width 0.1143)
		(layer "In2.Cu")
		(net "GMI_CPU0_G2_CPU1_G0_TX_DN<12>")
	)
	(segment
		(start 107.359704 -228.774498)
		(end 107.357672 -228.775514)
		(width 0.1143)
		(layer "In2.Cu")
		(net "GMI_CPU0_G2_CPU1_G0_TX_DN<12>")
	)
	(segment
		(start 108.021374 -218.382342)
		(end 107.72521 -218.678506)
		(width 0.14224)
		(layer "In2.Cu")
		(net "GMI_CPU0_G2_CPU1_G0_TX_DN<12>")
	)
	(segment
		(start 363.223556 -222.309944)
		(end 363.191806 -222.291656)
		(width 0.1143)
		(layer "In2.Cu")
		(net "GMI_CPU0_G2_CPU1_G0_TX_DN<12>")
	)
	(segment
		(start 113.206784 -213.385908)
		(end 112.910366 -213.68258)
		(width 0.14224)
		(layer "In2.Cu")
		(net "GMI_CPU0_G2_CPU1_G0_TX_DN<12>")
	)
	(segment
		(start 363.67466 -227.98151)
		(end 363.674152 -227.981256)
		(width 0.1143)
		(layer "In2.Cu")
		(net "GMI_CPU0_G2_CPU1_G0_TX_DN<12>")
	)
	(segment
		(start 110.857792 -215.545416)
		(end 110.857538 -215.545162)
		(width 0.14224)
		(layer "In2.Cu")
		(net "GMI_CPU0_G2_CPU1_G0_TX_DN<12>")
	)
	(segment
		(start 362.909612 -221.484698)
		(end 362.850938 -221.426024)
		(width 0.1143)
		(layer "In2.Cu")
		(net "GMI_CPU0_G2_CPU1_G0_TX_DN<12>")
	)
	(segment
		(start 363.15269 -226.1997)
		(end 363.19079 -226.177348)
		(width 0.1143)
		(layer "In2.Cu")
		(net "GMI_CPU0_G2_CPU1_G0_TX_DN<12>")
	)
	(segment
		(start 107.364022 -228.771958)
		(end 107.36326 -228.772466)
		(width 0.1143)
		(layer "In2.Cu")
		(net "GMI_CPU0_G2_CPU1_G0_TX_DN<12>")
	)
	(segment
		(start 363.192568 -222.936308)
		(end 363.193838 -222.935546)
		(width 0.1143)
		(layer "In2.Cu")
		(net "GMI_CPU0_G2_CPU1_G0_TX_DN<12>")
	)
	(segment
		(start 363.19079 -226.177348)
		(end 363.191806 -226.17684)
		(width 0.1143)
		(layer "In2.Cu")
		(net "GMI_CPU0_G2_CPU1_G0_TX_DN<12>")
	)
	(segment
		(start 109.291374 -217.302334)
		(end 108.994956 -217.599006)
		(width 0.14224)
		(layer "In2.Cu")
		(net "GMI_CPU0_G2_CPU1_G0_TX_DN<12>")
	)
	(segment
		(start 108.299758 -224.554542)
		(end 108.30052 -224.55505)
		(width 0.1143)
		(layer "In2.Cu")
		(net "GMI_CPU0_G2_CPU1_G0_TX_DN<12>")
	)
	(segment
		(start 363.15269 -222.959676)
		(end 363.155484 -222.957644)
		(width 0.1143)
		(layer "In2.Cu")
		(net "GMI_CPU0_G2_CPU1_G0_TX_DN<12>")
	)
	(segment
		(start 108.297726 -225.53549)
		(end 108.272326 -225.550222)
		(width 0.1143)
		(layer "In2.Cu")
		(net "GMI_CPU0_G2_CPU1_G0_TX_DN<12>")
	)
	(segment
		(start 363.155484 -222.957644)
		(end 363.191806 -222.936816)
		(width 0.1143)
		(layer "In2.Cu")
		(net "GMI_CPU0_G2_CPU1_G0_TX_DN<12>")
	)
	(segment
		(start 108.272326 -226.158806)
		(end 108.299758 -226.174554)
		(width 0.1143)
		(layer "In2.Cu")
		(net "GMI_CPU0_G2_CPU1_G0_TX_DN<12>")
	)
	(segment
		(start 108.303314 -223.91243)
		(end 108.302044 -223.913192)
		(width 0.1143)
		(layer "In2.Cu")
		(net "GMI_CPU0_G2_CPU1_G0_TX_DN<12>")
	)
	(segment
		(start 364.132114 -228.772974)
		(end 364.131098 -228.772466)
		(width 0.1143)
		(layer "In2.Cu")
		(net "GMI_CPU0_G2_CPU1_G0_TX_DN<12>")
	)
	(segment
		(start 364.131098 -228.772466)
		(end 364.099348 -228.751892)
		(width 0.1143)
		(layer "In2.Cu")
		(net "GMI_CPU0_G2_CPU1_G0_TX_DN<12>")
	)
	(segment
		(start 364.635288 -229.601268)
		(end 364.60176 -229.58171)
		(width 0.1143)
		(layer "In2.Cu")
		(net "GMI_CPU0_G2_CPU1_G0_TX_DN<12>")
	)
	(segment
		(start 363.223556 -225.549968)
		(end 363.192568 -225.532188)
		(width 0.1143)
		(layer "In2.Cu")
		(net "GMI_CPU0_G2_CPU1_G0_TX_DN<12>")
	)
	(segment
		(start 363.191806 -225.53168)
		(end 363.19079 -225.531172)
		(width 0.1143)
		(layer "In2.Cu")
		(net "GMI_CPU0_G2_CPU1_G0_TX_DN<12>")
	)
	(segment
		(start 112.423702 -214.16899)
		(end 112.127284 -214.465662)
		(width 0.14224)
		(layer "In2.Cu")
		(net "GMI_CPU0_G2_CPU1_G0_TX_DN<12>")
	)
	(segment
		(start 108.302044 -226.175824)
		(end 108.303314 -226.176586)
		(width 0.1143)
		(layer "In2.Cu")
		(net "GMI_CPU0_G2_CPU1_G0_TX_DN<12>")
	)
	(segment
		(start 107.403138 -228.749098)
		(end 107.366562 -228.770434)
		(width 0.1143)
		(layer "In2.Cu")
		(net "GMI_CPU0_G2_CPU1_G0_TX_DN<12>")
	)
	(segment
		(start 108.272326 -224.538794)
		(end 108.299758 -224.554542)
		(width 0.1143)
		(layer "In2.Cu")
		(net "GMI_CPU0_G2_CPU1_G0_TX_DN<12>")
	)
	(segment
		(start 111.936784 -214.465662)
		(end 111.937038 -214.465916)
		(width 0.14224)
		(layer "In2.Cu")
		(net "GMI_CPU0_G2_CPU1_G0_TX_DN<12>")
	)
	(segment
		(start 363.392466 -227.494338)
		(end 363.392466 -227.46716)
		(width 0.1143)
		(layer "In2.Cu")
		(net "GMI_CPU0_G2_CPU1_G0_TX_DN<12>")
	)
	(segment
		(start 110.56112 -216.032334)
		(end 110.370874 -216.032334)
		(width 0.14224)
		(layer "In2.Cu")
		(net "GMI_CPU0_G2_CPU1_G0_TX_DN<12>")
	)
	(segment
		(start 111.153956 -215.248998)
		(end 110.857792 -215.545416)
		(width 0.14224)
		(layer "In2.Cu")
		(net "GMI_CPU0_G2_CPU1_G0_TX_DN<12>")
	)
	(segment
		(start 362.909612 -221.80423)
		(end 362.909612 -221.484698)
		(width 0.1143)
		(layer "In2.Cu")
		(net "GMI_CPU0_G2_CPU1_G0_TX_DN<12>")
	)
	(segment
		(start 112.423956 -213.978998)
		(end 112.423702 -213.978744)
		(width 0.14224)
		(layer "In2.Cu")
		(net "GMI_CPU0_G2_CPU1_G0_TX_DN<12>")
	)
	(segment
		(start 208.117694 -188.09462)
		(end 161.264092 -188.232542)
		(width 0.14224)
		(layer "In2.Cu")
		(net "GMI_CPU0_G2_CPU1_G0_TX_DN<12>")
	)
	(segment
		(start 363.19079 -227.151184)
		(end 363.189266 -227.150168)
		(width 0.1143)
		(layer "In2.Cu")
		(net "GMI_CPU0_G2_CPU1_G0_TX_DN<12>")
	)
	(segment
		(start 107.873038 -227.939092)
		(end 107.833922 -227.961952)
		(width 0.1143)
		(layer "In2.Cu")
		(net "GMI_CPU0_G2_CPU1_G0_TX_DN<12>")
	)
	(segment
		(start 112.72012 -213.68258)
		(end 112.423956 -213.978998)
		(width 0.14224)
		(layer "In2.Cu")
		(net "GMI_CPU0_G2_CPU1_G0_TX_DN<12>")
	)
	(segment
		(start 107.72521 -218.678506)
		(end 107.72521 -221.174564)
		(width 0.14224)
		(layer "In2.Cu")
		(net "GMI_CPU0_G2_CPU1_G0_TX_DN<12>")
	)
	(segment
		(start 236.467396 -183.761888)
		(end 208.117694 -188.09462)
		(width 0.14224)
		(layer "In2.Cu")
		(net "GMI_CPU0_G2_CPU1_G0_TX_DN<12>")
	)
	(segment
		(start 108.342938 -224.579688)
		(end 108.370878 -224.599754)
		(width 0.1143)
		(layer "In2.Cu")
		(net "GMI_CPU0_G2_CPU1_G0_TX_DN<12>")
	)
	(segment
		(start 363.19079 -222.291148)
		(end 363.189266 -222.290132)
		(width 0.1143)
		(layer "In2.Cu")
		(net "GMI_CPU0_G2_CPU1_G0_TX_DN<12>")
	)
	(segment
		(start 114.828066 -212.352636)
		(end 114.455448 -212.544914)
		(width 0.14224)
		(layer "In2.Cu")
		(net "GMI_CPU0_G2_CPU1_G0_TX_DN<12>")
	)
	(segment
		(start 107.36326 -228.772466)
		(end 107.36199 -228.773228)
		(width 0.1143)
		(layer "In2.Cu")
		(net "GMI_CPU0_G2_CPU1_G0_TX_DN<12>")
	)
	(segment
		(start 108.303314 -222.936562)
		(end 108.304076 -222.93707)
		(width 0.1143)
		(layer "In2.Cu")
		(net "GMI_CPU0_G2_CPU1_G0_TX_DN<12>")
	)
	(segment
		(start 114.274092 -212.487002)
		(end 113.533682 -212.868764)
		(width 0.14224)
		(layer "In2.Cu")
		(net "GMI_CPU0_G2_CPU1_G0_TX_DN<12>")
	)
	(segment
		(start 363.191806 -227.151692)
		(end 363.19079 -227.151184)
		(width 0.1143)
		(layer "In2.Cu")
		(net "GMI_CPU0_G2_CPU1_G0_TX_DN<12>")
	)
	(segment
		(start 108.340398 -227.130864)
		(end 108.304076 -227.151946)
		(width 0.1143)
		(layer "In2.Cu")
		(net "GMI_CPU0_G2_CPU1_G0_TX_DN<12>")
	)
	(segment
		(start 363.19079 -225.531172)
		(end 363.189266 -225.530156)
		(width 0.1143)
		(layer "In2.Cu")
		(net "GMI_CPU0_G2_CPU1_G0_TX_DN<12>")
	)
	(segment
		(start 107.357672 -228.775514)
		(end 107.332272 -228.790246)
		(width 0.1143)
		(layer "In2.Cu")
		(net "GMI_CPU0_G2_CPU1_G0_TX_DN<12>")
	)
	(segment
		(start 363.223556 -223.929956)
		(end 363.192568 -223.912176)
		(width 0.1143)
		(layer "In2.Cu")
		(net "GMI_CPU0_G2_CPU1_G0_TX_DN<12>")
	)
	(segment
		(start 363.189266 -227.150168)
		(end 363.15269 -227.128832)
		(width 0.1143)
		(layer "In2.Cu")
		(net "GMI_CPU0_G2_CPU1_G0_TX_DN<12>")
	)
	(segment
		(start 363.19079 -224.557336)
		(end 363.191806 -224.556828)
		(width 0.1143)
		(layer "In2.Cu")
		(net "GMI_CPU0_G2_CPU1_G0_TX_DN<12>")
	)
	(segment
		(start 108.30687 -222.938848)
		(end 108.342938 -222.959676)
		(width 0.1143)
		(layer "In2.Cu")
		(net "GMI_CPU0_G2_CPU1_G0_TX_DN<12>")
	)
	(segment
		(start 363.218476 -227.167186)
		(end 363.21746 -227.166678)
		(width 0.1143)
		(layer "In2.Cu")
		(net "GMI_CPU0_G2_CPU1_G0_TX_DN<12>")
	)
	(segment
		(start 108.30687 -224.55886)
		(end 108.342938 -224.579688)
		(width 0.1143)
		(layer "In2.Cu")
		(net "GMI_CPU0_G2_CPU1_G0_TX_DN<12>")
	)
	(segment
		(start 113.533682 -212.868764)
		(end 113.206784 -213.195662)
		(width 0.14224)
		(layer "In2.Cu")
		(net "GMI_CPU0_G2_CPU1_G0_TX_DN<12>")
	)
	(segment
		(start 108.302044 -223.913192)
		(end 108.30052 -223.913954)
		(width 0.1143)
		(layer "In2.Cu")
		(net "GMI_CPU0_G2_CPU1_G0_TX_DN<12>")
	)
	(segment
		(start 363.191806 -222.291656)
		(end 363.19079 -222.291148)
		(width 0.1143)
		(layer "In2.Cu")
		(net "GMI_CPU0_G2_CPU1_G0_TX_DN<12>")
	)
	(segment
		(start 363.193838 -226.17557)
		(end 363.223556 -226.158552)
		(width 0.1143)
		(layer "In2.Cu")
		(net "GMI_CPU0_G2_CPU1_G0_TX_DN<12>")
	)
	(segment
		(start 109.587538 -216.81567)
		(end 109.291374 -217.112088)
		(width 0.14224)
		(layer "In2.Cu")
		(net "GMI_CPU0_G2_CPU1_G0_TX_DN<12>")
	)
	(segment
		(start 363.192568 -227.1522)
		(end 363.191806 -227.151692)
		(width 0.1143)
		(layer "In2.Cu")
		(net "GMI_CPU0_G2_CPU1_G0_TX_DN<12>")
	)
	(segment
		(start 108.304076 -226.177094)
		(end 108.340398 -226.198176)
		(width 0.1143)
		(layer "In2.Cu")
		(net "GMI_CPU0_G2_CPU1_G0_TX_DN<12>")
	)
	(segment
		(start 363.674152 -227.981256)
		(end 363.63529 -227.958396)
		(width 0.1143)
		(layer "In2.Cu")
		(net "GMI_CPU0_G2_CPU1_G0_TX_DN<12>")
	)
	(segment
		(start 108.804456 -217.599006)
		(end 108.508292 -217.895424)
		(width 0.14224)
		(layer "In2.Cu")
		(net "GMI_CPU0_G2_CPU1_G0_TX_DN<12>")
	)
	(segment
		(start 362.318554 -219.137738)
		(end 357.299006 -214.863934)
		(width 0.14224)
		(layer "In2.Cu")
		(net "GMI_CPU0_G2_CPU1_G0_TX_DN<12>")
	)
	(segment
		(start 363.222794 -227.169726)
		(end 363.221778 -227.169218)
		(width 0.1143)
		(layer "In2.Cu")
		(net "GMI_CPU0_G2_CPU1_G0_TX_DN<12>")
	)
	(segment
		(start 107.72521 -221.174564)
		(end 107.72521 -221.203012)
		(width 0.1143)
		(layer "In2.Cu")
		(net "GMI_CPU0_G2_CPU1_G0_TX_DN<12>")
	)
	(segment
		(start 364.712758 -229.904036)
		(end 364.782608 -229.834186)
		(width 0.1143)
		(layer "In2.Cu")
		(net "GMI_CPU0_G2_CPU1_G0_TX_DN<12>")
	)
	(segment
		(start 108.342938 -222.959676)
		(end 108.370878 -222.979742)
		(width 0.1143)
		(layer "In2.Cu")
		(net "GMI_CPU0_G2_CPU1_G0_TX_DN<12>")
	)
	(segment
		(start 106.783124 -229.90429)
		(end 107.081066 -229.90429)
		(width 0.1143)
		(layer "In2.Cu")
		(net "GMI_CPU0_G2_CPU1_G0_TX_DN<12>")
	)
	(segment
		(start 108.304076 -222.93707)
		(end 108.30687 -222.938848)
		(width 0.1143)
		(layer "In2.Cu")
		(net "GMI_CPU0_G2_CPU1_G0_TX_DN<12>")
	)
	(segment
		(start 111.344202 -215.248998)
		(end 111.153956 -215.248998)
		(width 0.14224)
		(layer "In2.Cu")
		(net "GMI_CPU0_G2_CPU1_G0_TX_DN<12>")
	)
	(segment
		(start 108.303822 -225.532442)
		(end 108.303314 -225.532442)
		(width 0.1143)
		(layer "In2.Cu")
		(net "GMI_CPU0_G2_CPU1_G0_TX_DN<12>")
	)
	(segment
		(start 108.303314 -227.152454)
		(end 108.302044 -227.153216)
		(width 0.1143)
		(layer "In2.Cu")
		(net "GMI_CPU0_G2_CPU1_G0_TX_DN<12>")
	)
	(segment
		(start 107.360466 -228.77399)
		(end 107.359704 -228.774498)
		(width 0.1143)
		(layer "In2.Cu")
		(net "GMI_CPU0_G2_CPU1_G0_TX_DN<12>")
	)
	(segment
		(start 108.30052 -224.55505)
		(end 108.302044 -224.555812)
		(width 0.1143)
		(layer "In2.Cu")
		(net "GMI_CPU0_G2_CPU1_G0_TX_DN<12>")
	)
	(segment
		(start 108.299758 -222.93453)
		(end 108.30052 -222.935038)
		(width 0.1143)
		(layer "In2.Cu")
		(net "GMI_CPU0_G2_CPU1_G0_TX_DN<12>")
	)
	(segment
		(start 108.299758 -223.914462)
		(end 108.297726 -223.915478)
		(width 0.1143)
		(layer "In2.Cu")
		(net "GMI_CPU0_G2_CPU1_G0_TX_DN<12>")
	)
	(segment
		(start 355.692456 -213.815676)
		(end 314.48629 -190.526416)
		(width 0.14224)
		(layer "In2.Cu")
		(net "GMI_CPU0_G2_CPU1_G0_TX_DN<12>")
	)
	(segment
		(start 363.191806 -226.17684)
		(end 363.192568 -226.176332)
		(width 0.1143)
		(layer "In2.Cu")
		(net "GMI_CPU0_G2_CPU1_G0_TX_DN<12>")
	)
	(segment
		(start 363.191806 -222.936816)
		(end 363.192568 -222.936308)
		(width 0.1143)
		(layer "In2.Cu")
		(net "GMI_CPU0_G2_CPU1_G0_TX_DN<12>")
	)
	(segment
		(start 107.366562 -228.770434)
		(end 107.365038 -228.77145)
		(width 0.1143)
		(layer "In2.Cu")
		(net "GMI_CPU0_G2_CPU1_G0_TX_DN<12>")
	)
	(segment
		(start 108.297726 -223.915478)
		(end 108.272326 -223.93021)
		(width 0.1143)
		(layer "In2.Cu")
		(net "GMI_CPU0_G2_CPU1_G0_TX_DN<12>")
	)
	(segment
		(start 363.849412 -228.284024)
		(end 363.849412 -228.283516)
		(width 0.1143)
		(layer "In2.Cu")
		(net "GMI_CPU0_G2_CPU1_G0_TX_DN<12>")
	)
	(segment
		(start 107.67949 -221.248732)
		(end 107.67949 -221.59214)
		(width 0.1143)
		(layer "In2.Cu")
		(net "GMI_CPU0_G2_CPU1_G0_TX_DN<12>")
	)
	(segment
		(start 363.192568 -226.176332)
		(end 363.193838 -226.17557)
		(width 0.1143)
		(layer "In2.Cu")
		(net "GMI_CPU0_G2_CPU1_G0_TX_DN<12>")
	)
	(segment
		(start 108.994956 -217.599006)
		(end 108.804456 -217.599006)
		(width 0.14224)
		(layer "In2.Cu")
		(net "GMI_CPU0_G2_CPU1_G0_TX_DN<12>")
	)
	(segment
		(start 106.893868 -229.581964)
		(end 106.861356 -229.60076)
		(width 0.1143)
		(layer "In2.Cu")
		(net "GMI_CPU0_G2_CPU1_G0_TX_DN<12>")
	)
	(segment
		(start 108.304076 -224.557082)
		(end 108.30687 -224.55886)
		(width 0.1143)
		(layer "In2.Cu")
		(net "GMI_CPU0_G2_CPU1_G0_TX_DN<12>")
	)
	(segment
		(start 363.192568 -225.532188)
		(end 363.191806 -225.53168)
		(width 0.1143)
		(layer "In2.Cu")
		(net "GMI_CPU0_G2_CPU1_G0_TX_DN<12>")
	)
	(segment
		(start 107.67949 -221.59214)
		(end 107.646724 -221.624906)
		(width 0.1143)
		(layer "In2.Cu")
		(net "GMI_CPU0_G2_CPU1_G0_TX_DN<12>")
	)
	(segment
		(start 112.910366 -213.68258)
		(end 112.72012 -213.68258)
		(width 0.14224)
		(layer "In2.Cu")
		(net "GMI_CPU0_G2_CPU1_G0_TX_DN<12>")
	)
	(segment
		(start 362.850938 -221.426024)
		(end 362.850938 -221.128844)
		(width 0.1143)
		(layer "In2.Cu")
		(net "GMI_CPU0_G2_CPU1_G0_TX_DN<12>")
	)
	(segment
		(start 363.189266 -222.290132)
		(end 363.18825 -222.289624)
		(width 0.1143)
		(layer "In2.Cu")
		(net "GMI_CPU0_G2_CPU1_G0_TX_DN<12>")
	)
	(segment
		(start 108.508292 -218.08567)
		(end 108.211874 -218.382342)
		(width 0.14224)
		(layer "In2.Cu")
		(net "GMI_CPU0_G2_CPU1_G0_TX_DN<12>")
	)
	(segment
		(start 108.297726 -227.155502)
		(end 108.272326 -227.170234)
		(width 0.1143)
		(layer "In2.Cu")
		(net "GMI_CPU0_G2_CPU1_G0_TX_DN<12>")
	)
	(segment
		(start 363.193838 -224.555558)
		(end 363.223556 -224.53854)
		(width 0.1143)
		(layer "In2.Cu")
		(net "GMI_CPU0_G2_CPU1_G0_TX_DN<12>")
	)
	(segment
		(start 109.291374 -217.112088)
		(end 109.291374 -217.302334)
		(width 0.14224)
		(layer "In2.Cu")
		(net "GMI_CPU0_G2_CPU1_G0_TX_DN<12>")
	)
	(segment
		(start 111.64062 -214.761826)
		(end 111.64062 -214.952326)
		(width 0.14224)
		(layer "In2.Cu")
		(net "GMI_CPU0_G2_CPU1_G0_TX_DN<12>")
	)
	(segment
		(start 161.264092 -188.232542)
		(end 114.885978 -212.171026)
		(width 0.14224)
		(layer "In2.Cu")
		(net "GMI_CPU0_G2_CPU1_G0_TX_DN<12>")
	)
	(segment
		(start 110.07471 -216.328752)
		(end 110.074456 -216.328498)
		(width 0.14224)
		(layer "In2.Cu")
		(net "GMI_CPU0_G2_CPU1_G0_TX_DN<12>")
	)
	(segment
		(start 108.303314 -224.556574)
		(end 108.304076 -224.557082)
		(width 0.1143)
		(layer "In2.Cu")
		(net "GMI_CPU0_G2_CPU1_G0_TX_DN<12>")
	)
	(arc
		(start 363.849412 -228.283516)
		(mid 363.802103 -228.109333)
		(end 363.67466 -227.98151)
		(width 0.1143)
		(layer "In2.Cu")
		(net "GMI_CPU0_G2_CPU1_G0_TX_DN<12>")
	)
	(arc
		(start 363.223556 -226.158552)
		(mid 363.379484 -225.85426)
		(end 363.223556 -225.549968)
		(width 0.1143)
		(layer "In2.Cu")
		(net "GMI_CPU0_G2_CPU1_G0_TX_DN<12>")
	)
	(arc
		(start 363.15269 -225.50882)
		(mid 362.909363 -225.044254)
		(end 363.15269 -224.579688)
		(width 0.1143)
		(layer "In2.Cu")
		(net "GMI_CPU0_G2_CPU1_G0_TX_DN<12>")
	)
	(arc
		(start 108.11637 -227.474526)
		(mid 108.051855 -227.736745)
		(end 107.873038 -227.939092)
		(width 0.1143)
		(layer "In2.Cu")
		(net "GMI_CPU0_G2_CPU1_G0_TX_DN<12>")
	)
	(arc
		(start 108.370878 -222.979742)
		(mid 108.598878 -223.424496)
		(end 108.370878 -223.86925)
		(width 0.1143)
		(layer "In2.Cu")
		(net "GMI_CPU0_G2_CPU1_G0_TX_DN<12>")
	)
	(arc
		(start 363.223556 -224.53854)
		(mid 363.379484 -224.234248)
		(end 363.223556 -223.929956)
		(width 0.1143)
		(layer "In2.Cu")
		(net "GMI_CPU0_G2_CPU1_G0_TX_DN<12>")
	)
	(arc
		(start 363.15269 -227.128832)
		(mid 362.909363 -226.664266)
		(end 363.15269 -226.1997)
		(width 0.1143)
		(layer "In2.Cu")
		(net "GMI_CPU0_G2_CPU1_G0_TX_DN<12>")
	)
	(arc
		(start 107.176316 -229.094538)
		(mid 107.111801 -229.356757)
		(end 106.932984 -229.559104)
		(width 0.1143)
		(layer "In2.Cu")
		(net "GMI_CPU0_G2_CPU1_G0_TX_DN<12>")
	)
	(arc
		(start 108.11637 -222.61449)
		(mid 108.157625 -222.785461)
		(end 108.272326 -222.918782)
		(width 0.1143)
		(layer "In2.Cu")
		(net "GMI_CPU0_G2_CPU1_G0_TX_DN<12>")
	)
	(arc
		(start 107.646724 -221.804992)
		(mid 107.688197 -221.976142)
		(end 107.803442 -222.109284)
		(width 0.1143)
		(layer "In2.Cu")
		(net "GMI_CPU0_G2_CPU1_G0_TX_DN<12>")
	)
	(arc
		(start 106.861356 -229.60076)
		(mid 106.764916 -229.703415)
		(end 106.713274 -229.83444)
		(width 0.1143)
		(layer "In2.Cu")
		(net "GMI_CPU0_G2_CPU1_G0_TX_DN<12>")
	)
	(arc
		(start 107.873038 -222.149924)
		(mid 108.051851 -222.352274)
		(end 108.11637 -222.61449)
		(width 0.1143)
		(layer "In2.Cu")
		(net "GMI_CPU0_G2_CPU1_G0_TX_DN<12>")
	)
	(arc
		(start 108.272326 -225.550222)
		(mid 108.116398 -225.854514)
		(end 108.272326 -226.158806)
		(width 0.1143)
		(layer "In2.Cu")
		(net "GMI_CPU0_G2_CPU1_G0_TX_DN<12>")
	)
	(arc
		(start 364.782608 -229.834186)
		(mid 364.731118 -229.703713)
		(end 364.635288 -229.601268)
		(width 0.1143)
		(layer "In2.Cu")
		(net "GMI_CPU0_G2_CPU1_G0_TX_DN<12>")
	)
	(arc
		(start 107.803442 -227.979732)
		(mid 107.688015 -228.113108)
		(end 107.64647 -228.284532)
		(width 0.1143)
		(layer "In2.Cu")
		(net "GMI_CPU0_G2_CPU1_G0_TX_DN<12>")
	)
	(arc
		(start 363.15269 -222.268796)
		(mid 363.080363 -222.209329)
		(end 363.018832 -222.138748)
		(width 0.1143)
		(layer "In2.Cu")
		(net "GMI_CPU0_G2_CPU1_G0_TX_DN<12>")
	)
	(arc
		(start 108.354622 -227.120958)
		(mid 108.347548 -227.125965)
		(end 108.340398 -227.130864)
		(width 0.1143)
		(layer "In2.Cu")
		(net "GMI_CPU0_G2_CPU1_G0_TX_DN<12>")
	)
	(arc
		(start 108.354622 -226.208082)
		(mid 108.582005 -226.66452)
		(end 108.354622 -227.120958)
		(width 0.1143)
		(layer "In2.Cu")
		(net "GMI_CPU0_G2_CPU1_G0_TX_DN<12>")
	)
	(arc
		(start 363.018832 -222.138748)
		(mid 362.937541 -221.980201)
		(end 362.909612 -221.80423)
		(width 0.1143)
		(layer "In2.Cu")
		(net "GMI_CPU0_G2_CPU1_G0_TX_DN<12>")
	)
	(arc
		(start 363.223556 -222.918528)
		(mid 363.379484 -222.614236)
		(end 363.223556 -222.309944)
		(width 0.1143)
		(layer "In2.Cu")
		(net "GMI_CPU0_G2_CPU1_G0_TX_DN<12>")
	)
	(arc
		(start 363.15269 -223.888808)
		(mid 362.909363 -223.424242)
		(end 363.15269 -222.959676)
		(width 0.1143)
		(layer "In2.Cu")
		(net "GMI_CPU0_G2_CPU1_G0_TX_DN<12>")
	)
	(arc
		(start 364.565438 -229.560628)
		(mid 364.384786 -229.357883)
		(end 364.319566 -229.094284)
		(width 0.1143)
		(layer "In2.Cu")
		(net "GMI_CPU0_G2_CPU1_G0_TX_DN<12>")
	)
	(arc
		(start 364.319566 -229.094284)
		(mid 364.278311 -228.923313)
		(end 364.16361 -228.789992)
		(width 0.1143)
		(layer "In2.Cu")
		(net "GMI_CPU0_G2_CPU1_G0_TX_DN<12>")
	)
	(arc
		(start 107.64647 -228.284532)
		(mid 107.581955 -228.546751)
		(end 107.403138 -228.749098)
		(width 0.1143)
		(layer "In2.Cu")
		(net "GMI_CPU0_G2_CPU1_G0_TX_DN<12>")
	)
	(arc
		(start 363.392466 -227.46716)
		(mid 363.347058 -227.295959)
		(end 363.222794 -227.169726)
		(width 0.1143)
		(layer "In2.Cu")
		(net "GMI_CPU0_G2_CPU1_G0_TX_DN<12>")
	)
	(arc
		(start 363.63529 -227.958396)
		(mid 363.456935 -227.756182)
		(end 363.392466 -227.494338)
		(width 0.1143)
		(layer "In2.Cu")
		(net "GMI_CPU0_G2_CPU1_G0_TX_DN<12>")
	)
	(arc
		(start 107.332272 -228.790246)
		(mid 107.217596 -228.92358)
		(end 107.176316 -229.094538)
		(width 0.1143)
		(layer "In2.Cu")
		(net "GMI_CPU0_G2_CPU1_G0_TX_DN<12>")
	)
	(arc
		(start 108.340398 -226.198176)
		(mid 108.347547 -226.203076)
		(end 108.354622 -226.208082)
		(width 0.1143)
		(layer "In2.Cu")
		(net "GMI_CPU0_G2_CPU1_G0_TX_DN<12>")
	)
	(arc
		(start 108.272326 -223.93021)
		(mid 108.116398 -224.234502)
		(end 108.272326 -224.538794)
		(width 0.1143)
		(layer "In2.Cu")
		(net "GMI_CPU0_G2_CPU1_G0_TX_DN<12>")
	)
	(arc
		(start 364.099348 -228.751892)
		(mid 363.915741 -228.54928)
		(end 363.849412 -228.284024)
		(width 0.1143)
		(layer "In2.Cu")
		(net "GMI_CPU0_G2_CPU1_G0_TX_DN<12>")
	)
	(arc
		(start 108.370878 -224.599754)
		(mid 108.598878 -225.044508)
		(end 108.370878 -225.489262)
		(width 0.1143)
		(layer "In2.Cu")
		(net "GMI_CPU0_G2_CPU1_G0_TX_DN<12>")
	)
	(arc
		(start 108.272326 -227.170234)
		(mid 108.15765 -227.303568)
		(end 108.11637 -227.474526)
		(width 0.1143)
		(layer "In2.Cu")
		(net "GMI_CPU0_G2_CPU1_G0_TX_DN<12>")
	)
	(segment
		(start 363.947964 -226.930204)
		(end 364.414816 -226.664266)
		(width 0.12954)
		(layer "F.Cu")
		(net "GMI_CPU0_G2_CPU1_G0_TX_DN<11>")
	)
	(segment
		(start 107.547918 -226.930458)
		(end 107.081066 -226.66452)
		(width 0.12954)
		(layer "F.Cu")
		(net "GMI_CPU0_G2_CPU1_G0_TX_DN<11>")
	)
	(segment
		(start 365.071914 -223.911668)
		(end 365.032798 -223.888808)
		(width 0.1143)
		(layer "In2.Cu")
		(net "GMI_CPU0_G2_CPU1_G0_TX_DN<11>")
	)
	(segment
		(start 107.888278 -215.613742)
		(end 107.697778 -215.613742)
		(width 0.14224)
		(layer "In2.Cu")
		(net "GMI_CPU0_G2_CPU1_G0_TX_DN<11>")
	)
	(segment
		(start 364.740698 -221.128844)
		(end 364.694978 -221.083124)
		(width 0.1143)
		(layer "In2.Cu")
		(net "GMI_CPU0_G2_CPU1_G0_TX_DN<11>")
	)
	(segment
		(start 106.424984 -222.937578)
		(end 106.463084 -222.95993)
		(width 0.1143)
		(layer "In2.Cu")
		(net "GMI_CPU0_G2_CPU1_G0_TX_DN<11>")
	)
	(segment
		(start 106.618532 -216.692988)
		(end 106.618532 -216.883234)
		(width 0.14224)
		(layer "In2.Cu")
		(net "GMI_CPU0_G2_CPU1_G0_TX_DN<11>")
	)
	(segment
		(start 105.922064 -222.108522)
		(end 105.964482 -222.13316)
		(width 0.1143)
		(layer "In2.Cu")
		(net "GMI_CPU0_G2_CPU1_G0_TX_DN<11>")
	)
	(segment
		(start 111.803688 -211.698332)
		(end 111.613188 -211.698332)
		(width 0.14224)
		(layer "In2.Cu")
		(net "GMI_CPU0_G2_CPU1_G0_TX_DN<11>")
	)
	(segment
		(start 321.158362 -191.049402)
		(end 308.928516 -185.147458)
		(width 0.14224)
		(layer "In2.Cu")
		(net "GMI_CPU0_G2_CPU1_G0_TX_DN<11>")
	)
	(segment
		(start 109.75086 -213.750906)
		(end 109.454442 -214.047578)
		(width 0.14224)
		(layer "In2.Cu")
		(net "GMI_CPU0_G2_CPU1_G0_TX_DN<11>")
	)
	(segment
		(start 111.613188 -211.698332)
		(end 111.317024 -211.994496)
		(width 0.14224)
		(layer "In2.Cu")
		(net "GMI_CPU0_G2_CPU1_G0_TX_DN<11>")
	)
	(segment
		(start 106.423968 -225.531934)
		(end 106.392218 -225.550222)
		(width 0.1143)
		(layer "In2.Cu")
		(net "GMI_CPU0_G2_CPU1_G0_TX_DN<11>")
	)
	(segment
		(start 111.317024 -212.184742)
		(end 111.020606 -212.481414)
		(width 0.14224)
		(layer "In2.Cu")
		(net "GMI_CPU0_G2_CPU1_G0_TX_DN<11>")
	)
	(segment
		(start 106.423206 -222.936816)
		(end 106.423968 -222.93707)
		(width 0.1143)
		(layer "In2.Cu")
		(net "GMI_CPU0_G2_CPU1_G0_TX_DN<11>")
	)
	(segment
		(start 107.401614 -215.909906)
		(end 107.401614 -216.100152)
		(width 0.14224)
		(layer "In2.Cu")
		(net "GMI_CPU0_G2_CPU1_G0_TX_DN<11>")
	)
	(segment
		(start 106.423206 -224.556574)
		(end 106.423968 -224.557082)
		(width 0.1143)
		(layer "In2.Cu")
		(net "GMI_CPU0_G2_CPU1_G0_TX_DN<11>")
	)
	(segment
		(start 364.414816 -226.664266)
		(end 364.712758 -226.664266)
		(width 0.1143)
		(layer "In2.Cu")
		(net "GMI_CPU0_G2_CPU1_G0_TX_DN<11>")
	)
	(segment
		(start 307.682646 -184.672224)
		(end 306.131722 -184.268872)
		(width 0.14224)
		(layer "In2.Cu")
		(net "GMI_CPU0_G2_CPU1_G0_TX_DN<11>")
	)
	(segment
		(start 106.423968 -224.557082)
		(end 106.424984 -224.55759)
		(width 0.1143)
		(layer "In2.Cu")
		(net "GMI_CPU0_G2_CPU1_G0_TX_DN<11>")
	)
	(segment
		(start 365.032798 -226.1997)
		(end 365.071914 -226.17684)
		(width 0.1143)
		(layer "In2.Cu")
		(net "GMI_CPU0_G2_CPU1_G0_TX_DN<11>")
	)
	(segment
		(start 110.533942 -212.967824)
		(end 110.237524 -213.264496)
		(width 0.14224)
		(layer "In2.Cu")
		(net "GMI_CPU0_G2_CPU1_G0_TX_DN<11>")
	)
	(segment
		(start 108.967778 -214.343742)
		(end 108.967778 -214.533988)
		(width 0.14224)
		(layer "In2.Cu")
		(net "GMI_CPU0_G2_CPU1_G0_TX_DN<11>")
	)
	(segment
		(start 236.60989 -181.852824)
		(end 166.492682 -183.93537)
		(width 0.14224)
		(layer "In2.Cu")
		(net "GMI_CPU0_G2_CPU1_G0_TX_DN<11>")
	)
	(segment
		(start 363.994446 -218.013788)
		(end 359.087166 -213.734904)
		(width 0.14224)
		(layer "In2.Cu")
		(net "GMI_CPU0_G2_CPU1_G0_TX_DN<11>")
	)
	(segment
		(start 111.020606 -212.481414)
		(end 110.830106 -212.481414)
		(width 0.14224)
		(layer "In2.Cu")
		(net "GMI_CPU0_G2_CPU1_G0_TX_DN<11>")
	)
	(segment
		(start 364.78972 -221.80423)
		(end 364.78972 -221.475046)
		(width 0.1143)
		(layer "In2.Cu")
		(net "GMI_CPU0_G2_CPU1_G0_TX_DN<11>")
	)
	(segment
		(start 112.100106 -211.211414)
		(end 112.100106 -211.40166)
		(width 0.14224)
		(layer "In2.Cu")
		(net "GMI_CPU0_G2_CPU1_G0_TX_DN<11>")
	)
	(segment
		(start 106.392218 -226.158806)
		(end 106.423968 -226.177094)
		(width 0.1143)
		(layer "In2.Cu")
		(net "GMI_CPU0_G2_CPU1_G0_TX_DN<11>")
	)
	(segment
		(start 106.246676 -222.622872)
		(end 106.246676 -222.629984)
		(width 0.1143)
		(layer "In2.Cu")
		(net "GMI_CPU0_G2_CPU1_G0_TX_DN<11>")
	)
	(segment
		(start 105.83545 -221.203012)
		(end 105.78973 -221.248732)
		(width 0.1143)
		(layer "In2.Cu")
		(net "GMI_CPU0_G2_CPU1_G0_TX_DN<11>")
	)
	(segment
		(start 106.424984 -224.55759)
		(end 106.463084 -224.579942)
		(width 0.1143)
		(layer "In2.Cu")
		(net "GMI_CPU0_G2_CPU1_G0_TX_DN<11>")
	)
	(segment
		(start 106.914696 -216.396824)
		(end 106.618532 -216.692988)
		(width 0.14224)
		(layer "In2.Cu")
		(net "GMI_CPU0_G2_CPU1_G0_TX_DN<11>")
	)
	(segment
		(start 108.67136 -214.83066)
		(end 108.48086 -214.83066)
		(width 0.14224)
		(layer "In2.Cu")
		(net "GMI_CPU0_G2_CPU1_G0_TX_DN<11>")
	)
	(segment
		(start 106.70032 -226.581716)
		(end 106.783124 -226.66452)
		(width 0.1143)
		(layer "In2.Cu")
		(net "GMI_CPU0_G2_CPU1_G0_TX_DN<11>")
	)
	(segment
		(start 106.423968 -222.93707)
		(end 106.424984 -222.937578)
		(width 0.1143)
		(layer "In2.Cu")
		(net "GMI_CPU0_G2_CPU1_G0_TX_DN<11>")
	)
	(segment
		(start 106.131614 -217.179906)
		(end 105.83545 -217.47607)
		(width 0.14224)
		(layer "In2.Cu")
		(net "GMI_CPU0_G2_CPU1_G0_TX_DN<11>")
	)
	(segment
		(start 110.533942 -212.777578)
		(end 110.533942 -212.967824)
		(width 0.14224)
		(layer "In2.Cu")
		(net "GMI_CPU0_G2_CPU1_G0_TX_DN<11>")
	)
	(segment
		(start 105.83545 -217.47607)
		(end 105.83545 -221.174564)
		(width 0.14224)
		(layer "In2.Cu")
		(net "GMI_CPU0_G2_CPU1_G0_TX_DN<11>")
	)
	(segment
		(start 109.454442 -214.047578)
		(end 109.263942 -214.047578)
		(width 0.14224)
		(layer "In2.Cu")
		(net "GMI_CPU0_G2_CPU1_G0_TX_DN<11>")
	)
	(segment
		(start 106.463084 -223.889062)
		(end 106.423968 -223.911922)
		(width 0.1143)
		(layer "In2.Cu")
		(net "GMI_CPU0_G2_CPU1_G0_TX_DN<11>")
	)
	(segment
		(start 108.184696 -215.31707)
		(end 107.888278 -215.613742)
		(width 0.14224)
		(layer "In2.Cu")
		(net "GMI_CPU0_G2_CPU1_G0_TX_DN<11>")
	)
	(segment
		(start 308.928516 -185.147458)
		(end 307.682646 -184.672224)
		(width 0.14224)
		(layer "In2.Cu")
		(net "GMI_CPU0_G2_CPU1_G0_TX_DN<11>")
	)
	(segment
		(start 107.401614 -216.100152)
		(end 107.105196 -216.396824)
		(width 0.14224)
		(layer "In2.Cu")
		(net "GMI_CPU0_G2_CPU1_G0_TX_DN<11>")
	)
	(segment
		(start 365.071914 -225.53168)
		(end 365.032798 -225.50882)
		(width 0.1143)
		(layer "In2.Cu")
		(net "GMI_CPU0_G2_CPU1_G0_TX_DN<11>")
	)
	(segment
		(start 107.105196 -216.396824)
		(end 106.914696 -216.396824)
		(width 0.14224)
		(layer "In2.Cu")
		(net "GMI_CPU0_G2_CPU1_G0_TX_DN<11>")
	)
	(segment
		(start 338.87283 -201.544936)
		(end 338.872576 -201.544936)
		(width 0.14224)
		(layer "In2.Cu")
		(net "GMI_CPU0_G2_CPU1_G0_TX_DN<11>")
	)
	(segment
		(start 110.830106 -212.481414)
		(end 110.533942 -212.777578)
		(width 0.14224)
		(layer "In2.Cu")
		(net "GMI_CPU0_G2_CPU1_G0_TX_DN<11>")
	)
	(segment
		(start 106.423968 -226.177094)
		(end 106.463084 -226.199954)
		(width 0.1143)
		(layer "In2.Cu")
		(net "GMI_CPU0_G2_CPU1_G0_TX_DN<11>")
	)
	(segment
		(start 109.75086 -213.56066)
		(end 109.75086 -213.750906)
		(width 0.14224)
		(layer "In2.Cu")
		(net "GMI_CPU0_G2_CPU1_G0_TX_DN<11>")
	)
	(segment
		(start 365.032798 -224.579688)
		(end 365.071914 -224.556828)
		(width 0.1143)
		(layer "In2.Cu")
		(net "GMI_CPU0_G2_CPU1_G0_TX_DN<11>")
	)
	(segment
		(start 364.78972 -221.475046)
		(end 364.740698 -221.426024)
		(width 0.1143)
		(layer "In2.Cu")
		(net "GMI_CPU0_G2_CPU1_G0_TX_DN<11>")
	)
	(segment
		(start 365.102394 -223.929448)
		(end 365.071914 -223.911668)
		(width 0.1143)
		(layer "In2.Cu")
		(net "GMI_CPU0_G2_CPU1_G0_TX_DN<11>")
	)
	(segment
		(start 365.071914 -226.17684)
		(end 365.102394 -226.15906)
		(width 0.1143)
		(layer "In2.Cu")
		(net "GMI_CPU0_G2_CPU1_G0_TX_DN<11>")
	)
	(segment
		(start 365.071914 -222.936816)
		(end 365.102394 -222.919036)
		(width 0.1143)
		(layer "In2.Cu")
		(net "GMI_CPU0_G2_CPU1_G0_TX_DN<11>")
	)
	(segment
		(start 359.087166 -213.734904)
		(end 356.58679 -212.04047)
		(width 0.14224)
		(layer "In2.Cu")
		(net "GMI_CPU0_G2_CPU1_G0_TX_DN<11>")
	)
	(segment
		(start 364.694978 -221.083124)
		(end 364.694978 -219.553536)
		(width 0.14224)
		(layer "In2.Cu")
		(net "GMI_CPU0_G2_CPU1_G0_TX_DN<11>")
	)
	(segment
		(start 110.047024 -213.264496)
		(end 109.75086 -213.56066)
		(width 0.14224)
		(layer "In2.Cu")
		(net "GMI_CPU0_G2_CPU1_G0_TX_DN<11>")
	)
	(segment
		(start 106.618532 -216.883234)
		(end 106.322114 -217.179906)
		(width 0.14224)
		(layer "In2.Cu")
		(net "GMI_CPU0_G2_CPU1_G0_TX_DN<11>")
	)
	(segment
		(start 106.463084 -225.509074)
		(end 106.423968 -225.531934)
		(width 0.1143)
		(layer "In2.Cu")
		(net "GMI_CPU0_G2_CPU1_G0_TX_DN<11>")
	)
	(segment
		(start 365.071914 -224.556828)
		(end 365.102394 -224.539048)
		(width 0.1143)
		(layer "In2.Cu")
		(net "GMI_CPU0_G2_CPU1_G0_TX_DN<11>")
	)
	(segment
		(start 108.184696 -215.126824)
		(end 108.184696 -215.31707)
		(width 0.14224)
		(layer "In2.Cu")
		(net "GMI_CPU0_G2_CPU1_G0_TX_DN<11>")
	)
	(segment
		(start 364.712758 -226.664266)
		(end 364.795562 -226.581462)
		(width 0.1143)
		(layer "In2.Cu")
		(net "GMI_CPU0_G2_CPU1_G0_TX_DN<11>")
	)
	(segment
		(start 106.783124 -226.66452)
		(end 107.081066 -226.66452)
		(width 0.1143)
		(layer "In2.Cu")
		(net "GMI_CPU0_G2_CPU1_G0_TX_DN<11>")
	)
	(segment
		(start 365.102394 -222.309436)
		(end 365.032798 -222.268796)
		(width 0.1143)
		(layer "In2.Cu")
		(net "GMI_CPU0_G2_CPU1_G0_TX_DN<11>")
	)
	(segment
		(start 105.83545 -221.174564)
		(end 105.83545 -221.203012)
		(width 0.1143)
		(layer "In2.Cu")
		(net "GMI_CPU0_G2_CPU1_G0_TX_DN<11>")
	)
	(segment
		(start 338.872576 -201.544936)
		(end 321.158362 -191.049402)
		(width 0.14224)
		(layer "In2.Cu")
		(net "GMI_CPU0_G2_CPU1_G0_TX_DN<11>")
	)
	(segment
		(start 106.322114 -217.179906)
		(end 106.131614 -217.179906)
		(width 0.14224)
		(layer "In2.Cu")
		(net "GMI_CPU0_G2_CPU1_G0_TX_DN<11>")
	)
	(segment
		(start 108.48086 -214.83066)
		(end 108.184696 -215.126824)
		(width 0.14224)
		(layer "In2.Cu")
		(net "GMI_CPU0_G2_CPU1_G0_TX_DN<11>")
	)
	(segment
		(start 108.967778 -214.533988)
		(end 108.67136 -214.83066)
		(width 0.14224)
		(layer "In2.Cu")
		(net "GMI_CPU0_G2_CPU1_G0_TX_DN<11>")
	)
	(segment
		(start 105.78973 -221.248732)
		(end 105.78973 -221.622366)
		(width 0.1143)
		(layer "In2.Cu")
		(net "GMI_CPU0_G2_CPU1_G0_TX_DN<11>")
	)
	(segment
		(start 106.392218 -224.538794)
		(end 106.423206 -224.556574)
		(width 0.1143)
		(layer "In2.Cu")
		(net "GMI_CPU0_G2_CPU1_G0_TX_DN<11>")
	)
	(segment
		(start 364.694978 -219.553536)
		(end 363.994446 -218.013788)
		(width 0.14224)
		(layer "In2.Cu")
		(net "GMI_CPU0_G2_CPU1_G0_TX_DN<11>")
	)
	(segment
		(start 105.766362 -221.645734)
		(end 105.766362 -221.804484)
		(width 0.1143)
		(layer "In2.Cu")
		(net "GMI_CPU0_G2_CPU1_G0_TX_DN<11>")
	)
	(segment
		(start 365.102394 -225.54946)
		(end 365.071914 -225.53168)
		(width 0.1143)
		(layer "In2.Cu")
		(net "GMI_CPU0_G2_CPU1_G0_TX_DN<11>")
	)
	(segment
		(start 166.492682 -183.93537)
		(end 165.344602 -184.237884)
		(width 0.14224)
		(layer "In2.Cu")
		(net "GMI_CPU0_G2_CPU1_G0_TX_DN<11>")
	)
	(segment
		(start 111.317024 -211.994496)
		(end 111.317024 -212.184742)
		(width 0.14224)
		(layer "In2.Cu")
		(net "GMI_CPU0_G2_CPU1_G0_TX_DN<11>")
	)
	(segment
		(start 110.237524 -213.264496)
		(end 110.047024 -213.264496)
		(width 0.14224)
		(layer "In2.Cu")
		(net "GMI_CPU0_G2_CPU1_G0_TX_DN<11>")
	)
	(segment
		(start 112.100106 -211.40166)
		(end 111.803688 -211.698332)
		(width 0.14224)
		(layer "In2.Cu")
		(net "GMI_CPU0_G2_CPU1_G0_TX_DN<11>")
	)
	(segment
		(start 105.78973 -221.622366)
		(end 105.766362 -221.645734)
		(width 0.1143)
		(layer "In2.Cu")
		(net "GMI_CPU0_G2_CPU1_G0_TX_DN<11>")
	)
	(segment
		(start 165.344602 -184.237884)
		(end 155.88361 -187.923424)
		(width 0.14224)
		(layer "In2.Cu")
		(net "GMI_CPU0_G2_CPU1_G0_TX_DN<11>")
	)
	(segment
		(start 106.423968 -223.911922)
		(end 106.392218 -223.93021)
		(width 0.1143)
		(layer "In2.Cu")
		(net "GMI_CPU0_G2_CPU1_G0_TX_DN<11>")
	)
	(segment
		(start 306.131722 -184.268872)
		(end 236.60989 -181.852824)
		(width 0.14224)
		(layer "In2.Cu")
		(net "GMI_CPU0_G2_CPU1_G0_TX_DN<11>")
	)
	(segment
		(start 364.740698 -221.426024)
		(end 364.740698 -221.128844)
		(width 0.1143)
		(layer "In2.Cu")
		(net "GMI_CPU0_G2_CPU1_G0_TX_DN<11>")
	)
	(segment
		(start 155.88361 -187.923424)
		(end 112.508538 -210.802982)
		(width 0.14224)
		(layer "In2.Cu")
		(net "GMI_CPU0_G2_CPU1_G0_TX_DN<11>")
	)
	(segment
		(start 356.58679 -212.04047)
		(end 338.87283 -201.544936)
		(width 0.14224)
		(layer "In2.Cu")
		(net "GMI_CPU0_G2_CPU1_G0_TX_DN<11>")
	)
	(segment
		(start 365.032798 -222.959676)
		(end 365.071914 -222.936816)
		(width 0.1143)
		(layer "In2.Cu")
		(net "GMI_CPU0_G2_CPU1_G0_TX_DN<11>")
	)
	(segment
		(start 107.697778 -215.613742)
		(end 107.401614 -215.909906)
		(width 0.14224)
		(layer "In2.Cu")
		(net "GMI_CPU0_G2_CPU1_G0_TX_DN<11>")
	)
	(segment
		(start 112.508538 -210.802982)
		(end 112.100106 -211.211414)
		(width 0.14224)
		(layer "In2.Cu")
		(net "GMI_CPU0_G2_CPU1_G0_TX_DN<11>")
	)
	(segment
		(start 109.263942 -214.047578)
		(end 108.967778 -214.343742)
		(width 0.14224)
		(layer "In2.Cu")
		(net "GMI_CPU0_G2_CPU1_G0_TX_DN<11>")
	)
	(arc
		(start 364.799372 -226.558602)
		(mid 364.880805 -226.356204)
		(end 365.032798 -226.1997)
		(width 0.1143)
		(layer "In2.Cu")
		(net "GMI_CPU0_G2_CPU1_G0_TX_DN<11>")
	)
	(arc
		(start 106.463084 -224.579942)
		(mid 106.706411 -225.044508)
		(end 106.463084 -225.509074)
		(width 0.1143)
		(layer "In2.Cu")
		(net "GMI_CPU0_G2_CPU1_G0_TX_DN<11>")
	)
	(arc
		(start 106.392218 -225.550222)
		(mid 106.243121 -225.854514)
		(end 106.392218 -226.158806)
		(width 0.1143)
		(layer "In2.Cu")
		(net "GMI_CPU0_G2_CPU1_G0_TX_DN<11>")
	)
	(arc
		(start 365.102394 -226.15906)
		(mid 365.259371 -225.85426)
		(end 365.102394 -225.54946)
		(width 0.1143)
		(layer "In2.Cu")
		(net "GMI_CPU0_G2_CPU1_G0_TX_DN<11>")
	)
	(arc
		(start 365.102394 -224.539048)
		(mid 365.259371 -224.234248)
		(end 365.102394 -223.929448)
		(width 0.1143)
		(layer "In2.Cu")
		(net "GMI_CPU0_G2_CPU1_G0_TX_DN<11>")
	)
	(arc
		(start 365.032798 -223.888808)
		(mid 364.789471 -223.424242)
		(end 365.032798 -222.959676)
		(width 0.1143)
		(layer "In2.Cu")
		(net "GMI_CPU0_G2_CPU1_G0_TX_DN<11>")
	)
	(arc
		(start 365.032798 -225.50882)
		(mid 364.789471 -225.044254)
		(end 365.032798 -224.579688)
		(width 0.1143)
		(layer "In2.Cu")
		(net "GMI_CPU0_G2_CPU1_G0_TX_DN<11>")
	)
	(arc
		(start 106.463084 -226.199954)
		(mid 106.615071 -226.356462)
		(end 106.69651 -226.558856)
		(width 0.1143)
		(layer "In2.Cu")
		(net "GMI_CPU0_G2_CPU1_G0_TX_DN<11>")
	)
	(arc
		(start 106.246676 -222.629984)
		(mid 106.293965 -222.806968)
		(end 106.423206 -222.936816)
		(width 0.1143)
		(layer "In2.Cu")
		(net "GMI_CPU0_G2_CPU1_G0_TX_DN<11>")
	)
	(arc
		(start 105.766362 -221.804484)
		(mid 105.807555 -221.975273)
		(end 105.922064 -222.108522)
		(width 0.1143)
		(layer "In2.Cu")
		(net "GMI_CPU0_G2_CPU1_G0_TX_DN<11>")
	)
	(arc
		(start 106.392218 -223.93021)
		(mid 106.241833 -224.234502)
		(end 106.392218 -224.538794)
		(width 0.1143)
		(layer "In2.Cu")
		(net "GMI_CPU0_G2_CPU1_G0_TX_DN<11>")
	)
	(arc
		(start 106.463084 -222.95993)
		(mid 106.706411 -223.424496)
		(end 106.463084 -223.889062)
		(width 0.1143)
		(layer "In2.Cu")
		(net "GMI_CPU0_G2_CPU1_G0_TX_DN<11>")
	)
	(arc
		(start 365.102394 -222.919036)
		(mid 365.259371 -222.614236)
		(end 365.102394 -222.309436)
		(width 0.1143)
		(layer "In2.Cu")
		(net "GMI_CPU0_G2_CPU1_G0_TX_DN<11>")
	)
	(arc
		(start 106.69651 -226.558856)
		(mid 106.698533 -226.570266)
		(end 106.70032 -226.581716)
		(width 0.1143)
		(layer "In2.Cu")
		(net "GMI_CPU0_G2_CPU1_G0_TX_DN<11>")
	)
	(arc
		(start 365.032798 -222.268796)
		(mid 364.854155 -222.066401)
		(end 364.78972 -221.80423)
		(width 0.1143)
		(layer "In2.Cu")
		(net "GMI_CPU0_G2_CPU1_G0_TX_DN<11>")
	)
	(arc
		(start 364.795562 -226.581462)
		(mid 364.79735 -226.570013)
		(end 364.799372 -226.558602)
		(width 0.1143)
		(layer "In2.Cu")
		(net "GMI_CPU0_G2_CPU1_G0_TX_DN<11>")
	)
	(arc
		(start 105.964482 -222.13316)
		(mid 106.171108 -222.340249)
		(end 106.246676 -222.622872)
		(width 0.1143)
		(layer "In2.Cu")
		(net "GMI_CPU0_G2_CPU1_G0_TX_DN<11>")
	)
	(segment
		(start 107.547918 -228.55047)
		(end 107.081066 -228.284532)
		(width 0.12954)
		(layer "F.Cu")
		(net "GMI_CPU0_G2_CPU1_G0_TX_DN<10>")
	)
	(segment
		(start 363.947964 -228.550216)
		(end 364.414816 -228.284278)
		(width 0.12954)
		(layer "F.Cu")
		(net "GMI_CPU0_G2_CPU1_G0_TX_DN<10>")
	)
	(segment
		(start 107.076494 -217.77579)
		(end 106.78033 -218.071954)
		(width 0.14224)
		(layer "In2.Cu")
		(net "GMI_CPU0_G2_CPU1_G0_TX_DN<10>")
	)
	(segment
		(start 107.364022 -224.557082)
		(end 107.365038 -224.55759)
		(width 0.1143)
		(layer "In2.Cu")
		(net "GMI_CPU0_G2_CPU1_G0_TX_DN<10>")
	)
	(segment
		(start 166.692326 -184.87517)
		(end 165.636956 -185.154062)
		(width 0.14224)
		(layer "In2.Cu")
		(net "GMI_CPU0_G2_CPU1_G0_TX_DN<10>")
	)
	(segment
		(start 106.932984 -227.939092)
		(end 106.893868 -227.961952)
		(width 0.1143)
		(layer "In2.Cu")
		(net "GMI_CPU0_G2_CPU1_G0_TX_DN<10>")
	)
	(segment
		(start 107.332272 -226.158806)
		(end 107.360466 -226.175062)
		(width 0.1143)
		(layer "In2.Cu")
		(net "GMI_CPU0_G2_CPU1_G0_TX_DN<10>")
	)
	(segment
		(start 107.36326 -222.936562)
		(end 107.364022 -222.93707)
		(width 0.1143)
		(layer "In2.Cu")
		(net "GMI_CPU0_G2_CPU1_G0_TX_DN<10>")
	)
	(segment
		(start 107.364022 -223.911922)
		(end 107.36326 -223.91243)
		(width 0.1143)
		(layer "In2.Cu")
		(net "GMI_CPU0_G2_CPU1_G0_TX_DN<10>")
	)
	(segment
		(start 364.14456 -227.159058)
		(end 364.092744 -227.128832)
		(width 0.1143)
		(layer "In2.Cu")
		(net "GMI_CPU0_G2_CPU1_G0_TX_DN<10>")
	)
	(segment
		(start 364.13186 -222.936816)
		(end 364.16361 -222.918528)
		(width 0.1143)
		(layer "In2.Cu")
		(net "GMI_CPU0_G2_CPU1_G0_TX_DN<10>")
	)
	(segment
		(start 109.61624 -215.426544)
		(end 109.42574 -215.426544)
		(width 0.14224)
		(layer "In2.Cu")
		(net "GMI_CPU0_G2_CPU1_G0_TX_DN<10>")
	)
	(segment
		(start 364.332266 -227.49637)
		(end 364.332266 -227.483924)
		(width 0.1143)
		(layer "In2.Cu")
		(net "GMI_CPU0_G2_CPU1_G0_TX_DN<10>")
	)
	(segment
		(start 364.13186 -226.17684)
		(end 364.16361 -226.158552)
		(width 0.1143)
		(layer "In2.Cu")
		(net "GMI_CPU0_G2_CPU1_G0_TX_DN<10>")
	)
	(segment
		(start 364.16361 -224.53854)
		(end 364.183422 -224.524316)
		(width 0.1143)
		(layer "In2.Cu")
		(net "GMI_CPU0_G2_CPU1_G0_TX_DN<10>")
	)
	(segment
		(start 107.365038 -222.937578)
		(end 107.366562 -222.938594)
		(width 0.1143)
		(layer "In2.Cu")
		(net "GMI_CPU0_G2_CPU1_G0_TX_DN<10>")
	)
	(segment
		(start 321.381628 -192.315084)
		(end 307.377084 -185.556144)
		(width 0.14224)
		(layer "In2.Cu")
		(net "GMI_CPU0_G2_CPU1_G0_TX_DN<10>")
	)
	(segment
		(start 107.371134 -226.181158)
		(end 107.403138 -226.199954)
		(width 0.1143)
		(layer "In2.Cu")
		(net "GMI_CPU0_G2_CPU1_G0_TX_DN<10>")
	)
	(segment
		(start 306.051966 -185.21172)
		(end 236.60735 -182.798466)
		(width 0.14224)
		(layer "In2.Cu")
		(net "GMI_CPU0_G2_CPU1_G0_TX_DN<10>")
	)
	(segment
		(start 110.69574 -214.156544)
		(end 110.69574 -214.34679)
		(width 0.14224)
		(layer "In2.Cu")
		(net "GMI_CPU0_G2_CPU1_G0_TX_DN<10>")
	)
	(segment
		(start 107.332272 -222.918782)
		(end 107.360466 -222.935038)
		(width 0.1143)
		(layer "In2.Cu")
		(net "GMI_CPU0_G2_CPU1_G0_TX_DN<10>")
	)
	(segment
		(start 108.346494 -216.696036)
		(end 108.050076 -216.992708)
		(width 0.14224)
		(layer "In2.Cu")
		(net "GMI_CPU0_G2_CPU1_G0_TX_DN<10>")
	)
	(segment
		(start 363.22762 -218.63304)
		(end 358.309164 -214.34552)
		(width 0.14224)
		(layer "In2.Cu")
		(net "GMI_CPU0_G2_CPU1_G0_TX_DN<10>")
	)
	(segment
		(start 236.60735 -182.798466)
		(end 166.692326 -184.87517)
		(width 0.14224)
		(layer "In2.Cu")
		(net "GMI_CPU0_G2_CPU1_G0_TX_DN<10>")
	)
	(segment
		(start 364.16361 -222.309944)
		(end 364.092744 -222.268796)
		(width 0.1143)
		(layer "In2.Cu")
		(net "GMI_CPU0_G2_CPU1_G0_TX_DN<10>")
	)
	(segment
		(start 107.403138 -223.889062)
		(end 107.366562 -223.910398)
		(width 0.1143)
		(layer "In2.Cu")
		(net "GMI_CPU0_G2_CPU1_G0_TX_DN<10>")
	)
	(segment
		(start 107.365038 -227.151438)
		(end 107.364022 -227.151946)
		(width 0.1143)
		(layer "In2.Cu")
		(net "GMI_CPU0_G2_CPU1_G0_TX_DN<10>")
	)
	(segment
		(start 107.360466 -226.175062)
		(end 107.36199 -226.175824)
		(width 0.1143)
		(layer "In2.Cu")
		(net "GMI_CPU0_G2_CPU1_G0_TX_DN<10>")
	)
	(segment
		(start 107.364022 -225.531934)
		(end 107.332272 -225.550222)
		(width 0.1143)
		(layer "In2.Cu")
		(net "GMI_CPU0_G2_CPU1_G0_TX_DN<10>")
	)
	(segment
		(start 109.129576 -215.912954)
		(end 108.833158 -216.209626)
		(width 0.14224)
		(layer "In2.Cu")
		(net "GMI_CPU0_G2_CPU1_G0_TX_DN<10>")
	)
	(segment
		(start 107.360466 -222.935038)
		(end 107.36199 -222.9358)
		(width 0.1143)
		(layer "In2.Cu")
		(net "GMI_CPU0_G2_CPU1_G0_TX_DN<10>")
	)
	(segment
		(start 107.36199 -223.913192)
		(end 107.332272 -223.93021)
		(width 0.1143)
		(layer "In2.Cu")
		(net "GMI_CPU0_G2_CPU1_G0_TX_DN<10>")
	)
	(segment
		(start 363.795818 -221.426024)
		(end 363.795818 -221.128844)
		(width 0.1143)
		(layer "In2.Cu")
		(net "GMI_CPU0_G2_CPU1_G0_TX_DN<10>")
	)
	(segment
		(start 364.16361 -225.549968)
		(end 364.13186 -225.53168)
		(width 0.1143)
		(layer "In2.Cu")
		(net "GMI_CPU0_G2_CPU1_G0_TX_DN<10>")
	)
	(segment
		(start 106.713274 -228.214682)
		(end 106.783124 -228.284532)
		(width 0.1143)
		(layer "In2.Cu")
		(net "GMI_CPU0_G2_CPU1_G0_TX_DN<10>")
	)
	(segment
		(start 111.478822 -213.563708)
		(end 111.182404 -213.86038)
		(width 0.14224)
		(layer "In2.Cu")
		(net "GMI_CPU0_G2_CPU1_G0_TX_DN<10>")
	)
	(segment
		(start 107.36326 -226.176586)
		(end 107.364022 -226.177094)
		(width 0.1143)
		(layer "In2.Cu")
		(net "GMI_CPU0_G2_CPU1_G0_TX_DN<10>")
	)
	(segment
		(start 364.712758 -228.284278)
		(end 364.782608 -228.214428)
		(width 0.1143)
		(layer "In2.Cu")
		(net "GMI_CPU0_G2_CPU1_G0_TX_DN<10>")
	)
	(segment
		(start 107.403138 -227.129086)
		(end 107.366562 -227.150422)
		(width 0.1143)
		(layer "In2.Cu")
		(net "GMI_CPU0_G2_CPU1_G0_TX_DN<10>")
	)
	(segment
		(start 364.092744 -224.579688)
		(end 364.13186 -224.556828)
		(width 0.1143)
		(layer "In2.Cu")
		(net "GMI_CPU0_G2_CPU1_G0_TX_DN<10>")
	)
	(segment
		(start 107.366562 -227.150422)
		(end 107.365038 -227.151438)
		(width 0.1143)
		(layer "In2.Cu")
		(net "GMI_CPU0_G2_CPU1_G0_TX_DN<10>")
	)
	(segment
		(start 108.346494 -216.50579)
		(end 108.346494 -216.696036)
		(width 0.14224)
		(layer "In2.Cu")
		(net "GMI_CPU0_G2_CPU1_G0_TX_DN<10>")
	)
	(segment
		(start 107.366562 -222.938594)
		(end 107.371134 -222.941134)
		(width 0.1143)
		(layer "In2.Cu")
		(net "GMI_CPU0_G2_CPU1_G0_TX_DN<10>")
	)
	(segment
		(start 364.16361 -223.929956)
		(end 364.092744 -223.888808)
		(width 0.1143)
		(layer "In2.Cu")
		(net "GMI_CPU0_G2_CPU1_G0_TX_DN<10>")
	)
	(segment
		(start 109.912658 -214.939626)
		(end 109.912658 -215.129872)
		(width 0.14224)
		(layer "In2.Cu")
		(net "GMI_CPU0_G2_CPU1_G0_TX_DN<10>")
	)
	(segment
		(start 358.309164 -214.34552)
		(end 356.538022 -213.145116)
		(width 0.14224)
		(layer "In2.Cu")
		(net "GMI_CPU0_G2_CPU1_G0_TX_DN<10>")
	)
	(segment
		(start 109.912658 -215.129872)
		(end 109.61624 -215.426544)
		(width 0.14224)
		(layer "In2.Cu")
		(net "GMI_CPU0_G2_CPU1_G0_TX_DN<10>")
	)
	(segment
		(start 307.377084 -185.556144)
		(end 306.051966 -185.21172)
		(width 0.14224)
		(layer "In2.Cu")
		(net "GMI_CPU0_G2_CPU1_G0_TX_DN<10>")
	)
	(segment
		(start 107.366562 -226.178618)
		(end 107.371134 -226.181158)
		(width 0.1143)
		(layer "In2.Cu")
		(net "GMI_CPU0_G2_CPU1_G0_TX_DN<10>")
	)
	(segment
		(start 107.36199 -224.555812)
		(end 107.36326 -224.556574)
		(width 0.1143)
		(layer "In2.Cu")
		(net "GMI_CPU0_G2_CPU1_G0_TX_DN<10>")
	)
	(segment
		(start 110.69574 -214.34679)
		(end 110.399322 -214.643462)
		(width 0.14224)
		(layer "In2.Cu")
		(net "GMI_CPU0_G2_CPU1_G0_TX_DN<10>")
	)
	(segment
		(start 106.861356 -222.108014)
		(end 106.931714 -222.148908)
		(width 0.1143)
		(layer "In2.Cu")
		(net "GMI_CPU0_G2_CPU1_G0_TX_DN<10>")
	)
	(segment
		(start 114.266218 -211.074254)
		(end 114.210338 -211.256372)
		(width 0.14224)
		(layer "In2.Cu")
		(net "GMI_CPU0_G2_CPU1_G0_TX_DN<10>")
	)
	(segment
		(start 364.60176 -227.961698)
		(end 364.599474 -227.960428)
		(width 0.1143)
		(layer "In2.Cu")
		(net "GMI_CPU0_G2_CPU1_G0_TX_DN<10>")
	)
	(segment
		(start 364.414816 -228.284278)
		(end 364.712758 -228.284278)
		(width 0.1143)
		(layer "In2.Cu")
		(net "GMI_CPU0_G2_CPU1_G0_TX_DN<10>")
	)
	(segment
		(start 107.332272 -224.538794)
		(end 107.360466 -224.55505)
		(width 0.1143)
		(layer "In2.Cu")
		(net "GMI_CPU0_G2_CPU1_G0_TX_DN<10>")
	)
	(segment
		(start 107.365038 -225.531426)
		(end 107.364022 -225.531934)
		(width 0.1143)
		(layer "In2.Cu")
		(net "GMI_CPU0_G2_CPU1_G0_TX_DN<10>")
	)
	(segment
		(start 108.642658 -216.209626)
		(end 108.346494 -216.50579)
		(width 0.14224)
		(layer "In2.Cu")
		(net "GMI_CPU0_G2_CPU1_G0_TX_DN<10>")
	)
	(segment
		(start 113.657634 -211.39658)
		(end 113.228374 -211.62391)
		(width 0.14224)
		(layer "In2.Cu")
		(net "GMI_CPU0_G2_CPU1_G0_TX_DN<10>")
	)
	(segment
		(start 106.706416 -221.627954)
		(end 106.706416 -221.804484)
		(width 0.1143)
		(layer "In2.Cu")
		(net "GMI_CPU0_G2_CPU1_G0_TX_DN<10>")
	)
	(segment
		(start 108.833158 -216.209626)
		(end 108.642658 -216.209626)
		(width 0.14224)
		(layer "In2.Cu")
		(net "GMI_CPU0_G2_CPU1_G0_TX_DN<10>")
	)
	(segment
		(start 107.364022 -227.151946)
		(end 107.332272 -227.170234)
		(width 0.1143)
		(layer "In2.Cu")
		(net "GMI_CPU0_G2_CPU1_G0_TX_DN<10>")
	)
	(segment
		(start 156.366972 -188.778642)
		(end 114.266218 -211.074254)
		(width 0.14224)
		(layer "In2.Cu")
		(net "GMI_CPU0_G2_CPU1_G0_TX_DN<10>")
	)
	(segment
		(start 106.78033 -221.203012)
		(end 106.73461 -221.248732)
		(width 0.1143)
		(layer "In2.Cu")
		(net "GMI_CPU0_G2_CPU1_G0_TX_DN<10>")
	)
	(segment
		(start 364.183422 -223.94418)
		(end 364.16361 -223.929956)
		(width 0.1143)
		(layer "In2.Cu")
		(net "GMI_CPU0_G2_CPU1_G0_TX_DN<10>")
	)
	(segment
		(start 107.365038 -223.911414)
		(end 107.364022 -223.911922)
		(width 0.1143)
		(layer "In2.Cu")
		(net "GMI_CPU0_G2_CPU1_G0_TX_DN<10>")
	)
	(segment
		(start 111.774986 -213.077298)
		(end 111.478822 -213.373462)
		(width 0.14224)
		(layer "In2.Cu")
		(net "GMI_CPU0_G2_CPU1_G0_TX_DN<10>")
	)
	(segment
		(start 107.366562 -224.558606)
		(end 107.371134 -224.561146)
		(width 0.1143)
		(layer "In2.Cu")
		(net "GMI_CPU0_G2_CPU1_G0_TX_DN<10>")
	)
	(segment
		(start 113.839498 -211.452714)
		(end 113.657634 -211.39658)
		(width 0.14224)
		(layer "In2.Cu")
		(net "GMI_CPU0_G2_CPU1_G0_TX_DN<10>")
	)
	(segment
		(start 364.092744 -222.959676)
		(end 364.13186 -222.936816)
		(width 0.1143)
		(layer "In2.Cu")
		(net "GMI_CPU0_G2_CPU1_G0_TX_DN<10>")
	)
	(segment
		(start 107.371134 -222.941134)
		(end 107.403138 -222.95993)
		(width 0.1143)
		(layer "In2.Cu")
		(net "GMI_CPU0_G2_CPU1_G0_TX_DN<10>")
	)
	(segment
		(start 107.371134 -224.561146)
		(end 107.403138 -224.579942)
		(width 0.1143)
		(layer "In2.Cu")
		(net "GMI_CPU0_G2_CPU1_G0_TX_DN<10>")
	)
	(segment
		(start 107.266994 -217.77579)
		(end 107.076494 -217.77579)
		(width 0.14224)
		(layer "In2.Cu")
		(net "GMI_CPU0_G2_CPU1_G0_TX_DN<10>")
	)
	(segment
		(start 363.750098 -221.083124)
		(end 363.750098 -219.781628)
		(width 0.14224)
		(layer "In2.Cu")
		(net "GMI_CPU0_G2_CPU1_G0_TX_DN<10>")
	)
	(segment
		(start 112.261904 -212.59038)
		(end 112.261904 -212.780626)
		(width 0.14224)
		(layer "In2.Cu")
		(net "GMI_CPU0_G2_CPU1_G0_TX_DN<10>")
	)
	(segment
		(start 107.360466 -224.55505)
		(end 107.36199 -224.555812)
		(width 0.1143)
		(layer "In2.Cu")
		(net "GMI_CPU0_G2_CPU1_G0_TX_DN<10>")
	)
	(segment
		(start 165.636956 -185.154062)
		(end 156.366972 -188.778642)
		(width 0.14224)
		(layer "In2.Cu")
		(net "GMI_CPU0_G2_CPU1_G0_TX_DN<10>")
	)
	(segment
		(start 107.365038 -224.55759)
		(end 107.366562 -224.558606)
		(width 0.1143)
		(layer "In2.Cu")
		(net "GMI_CPU0_G2_CPU1_G0_TX_DN<10>")
	)
	(segment
		(start 363.849666 -221.479872)
		(end 363.795818 -221.426024)
		(width 0.1143)
		(layer "In2.Cu")
		(net "GMI_CPU0_G2_CPU1_G0_TX_DN<10>")
	)
	(segment
		(start 363.795818 -221.128844)
		(end 363.750098 -221.083124)
		(width 0.1143)
		(layer "In2.Cu")
		(net "GMI_CPU0_G2_CPU1_G0_TX_DN<10>")
	)
	(segment
		(start 364.13186 -225.53168)
		(end 364.092744 -225.50882)
		(width 0.1143)
		(layer "In2.Cu")
		(net "GMI_CPU0_G2_CPU1_G0_TX_DN<10>")
	)
	(segment
		(start 364.092744 -226.1997)
		(end 364.13186 -226.17684)
		(width 0.1143)
		(layer "In2.Cu")
		(net "GMI_CPU0_G2_CPU1_G0_TX_DN<10>")
	)
	(segment
		(start 107.859576 -216.992708)
		(end 107.563412 -217.288872)
		(width 0.14224)
		(layer "In2.Cu")
		(net "GMI_CPU0_G2_CPU1_G0_TX_DN<10>")
	)
	(segment
		(start 364.13186 -224.556828)
		(end 364.16361 -224.53854)
		(width 0.1143)
		(layer "In2.Cu")
		(net "GMI_CPU0_G2_CPU1_G0_TX_DN<10>")
	)
	(segment
		(start 114.210338 -211.256372)
		(end 113.839498 -211.452714)
		(width 0.14224)
		(layer "In2.Cu")
		(net "GMI_CPU0_G2_CPU1_G0_TX_DN<10>")
	)
	(segment
		(start 108.050076 -216.992708)
		(end 107.859576 -216.992708)
		(width 0.14224)
		(layer "In2.Cu")
		(net "GMI_CPU0_G2_CPU1_G0_TX_DN<10>")
	)
	(segment
		(start 107.36326 -223.91243)
		(end 107.36199 -223.913192)
		(width 0.1143)
		(layer "In2.Cu")
		(net "GMI_CPU0_G2_CPU1_G0_TX_DN<10>")
	)
	(segment
		(start 363.849666 -221.80423)
		(end 363.849666 -221.479872)
		(width 0.1143)
		(layer "In2.Cu")
		(net "GMI_CPU0_G2_CPU1_G0_TX_DN<10>")
	)
	(segment
		(start 111.965486 -213.077298)
		(end 111.774986 -213.077298)
		(width 0.14224)
		(layer "In2.Cu")
		(net "GMI_CPU0_G2_CPU1_G0_TX_DN<10>")
	)
	(segment
		(start 106.73461 -221.248732)
		(end 106.73461 -221.59976)
		(width 0.1143)
		(layer "In2.Cu")
		(net "GMI_CPU0_G2_CPU1_G0_TX_DN<10>")
	)
	(segment
		(start 109.42574 -215.426544)
		(end 109.129576 -215.722708)
		(width 0.14224)
		(layer "In2.Cu")
		(net "GMI_CPU0_G2_CPU1_G0_TX_DN<10>")
	)
	(segment
		(start 107.36326 -224.556574)
		(end 107.364022 -224.557082)
		(width 0.1143)
		(layer "In2.Cu")
		(net "GMI_CPU0_G2_CPU1_G0_TX_DN<10>")
	)
	(segment
		(start 107.365038 -226.177602)
		(end 107.366562 -226.178618)
		(width 0.1143)
		(layer "In2.Cu")
		(net "GMI_CPU0_G2_CPU1_G0_TX_DN<10>")
	)
	(segment
		(start 106.783124 -228.284532)
		(end 107.081066 -228.284532)
		(width 0.1143)
		(layer "In2.Cu")
		(net "GMI_CPU0_G2_CPU1_G0_TX_DN<10>")
	)
	(segment
		(start 107.366562 -225.53041)
		(end 107.365038 -225.531426)
		(width 0.1143)
		(layer "In2.Cu")
		(net "GMI_CPU0_G2_CPU1_G0_TX_DN<10>")
	)
	(segment
		(start 110.991904 -213.86038)
		(end 110.69574 -214.156544)
		(width 0.14224)
		(layer "In2.Cu")
		(net "GMI_CPU0_G2_CPU1_G0_TX_DN<10>")
	)
	(segment
		(start 106.78033 -221.174564)
		(end 106.78033 -221.203012)
		(width 0.1143)
		(layer "In2.Cu")
		(net "GMI_CPU0_G2_CPU1_G0_TX_DN<10>")
	)
	(segment
		(start 107.36199 -226.175824)
		(end 107.36326 -226.176586)
		(width 0.1143)
		(layer "In2.Cu")
		(net "GMI_CPU0_G2_CPU1_G0_TX_DN<10>")
	)
	(segment
		(start 107.366562 -223.910398)
		(end 107.365038 -223.911414)
		(width 0.1143)
		(layer "In2.Cu")
		(net "GMI_CPU0_G2_CPU1_G0_TX_DN<10>")
	)
	(segment
		(start 106.893868 -227.961952)
		(end 106.863388 -227.979732)
		(width 0.1143)
		(layer "In2.Cu")
		(net "GMI_CPU0_G2_CPU1_G0_TX_DN<10>")
	)
	(segment
		(start 111.182404 -213.86038)
		(end 110.991904 -213.86038)
		(width 0.14224)
		(layer "In2.Cu")
		(net "GMI_CPU0_G2_CPU1_G0_TX_DN<10>")
	)
	(segment
		(start 112.261904 -212.780626)
		(end 111.965486 -213.077298)
		(width 0.14224)
		(layer "In2.Cu")
		(net "GMI_CPU0_G2_CPU1_G0_TX_DN<10>")
	)
	(segment
		(start 356.538022 -213.145116)
		(end 321.381628 -192.315084)
		(width 0.14224)
		(layer "In2.Cu")
		(net "GMI_CPU0_G2_CPU1_G0_TX_DN<10>")
	)
	(segment
		(start 364.602522 -227.962206)
		(end 364.60176 -227.961698)
		(width 0.1143)
		(layer "In2.Cu")
		(net "GMI_CPU0_G2_CPU1_G0_TX_DN<10>")
	)
	(segment
		(start 109.129576 -215.722708)
		(end 109.129576 -215.912954)
		(width 0.14224)
		(layer "In2.Cu")
		(net "GMI_CPU0_G2_CPU1_G0_TX_DN<10>")
	)
	(segment
		(start 364.63351 -227.979986)
		(end 364.602522 -227.962206)
		(width 0.1143)
		(layer "In2.Cu")
		(net "GMI_CPU0_G2_CPU1_G0_TX_DN<10>")
	)
	(segment
		(start 107.36199 -222.9358)
		(end 107.36326 -222.936562)
		(width 0.1143)
		(layer "In2.Cu")
		(net "GMI_CPU0_G2_CPU1_G0_TX_DN<10>")
	)
	(segment
		(start 110.399322 -214.643462)
		(end 110.208822 -214.643462)
		(width 0.14224)
		(layer "In2.Cu")
		(net "GMI_CPU0_G2_CPU1_G0_TX_DN<10>")
	)
	(segment
		(start 107.563412 -217.288872)
		(end 107.563412 -217.479118)
		(width 0.14224)
		(layer "In2.Cu")
		(net "GMI_CPU0_G2_CPU1_G0_TX_DN<10>")
	)
	(segment
		(start 111.478822 -213.373462)
		(end 111.478822 -213.563708)
		(width 0.14224)
		(layer "In2.Cu")
		(net "GMI_CPU0_G2_CPU1_G0_TX_DN<10>")
	)
	(segment
		(start 107.403138 -225.509074)
		(end 107.366562 -225.53041)
		(width 0.1143)
		(layer "In2.Cu")
		(net "GMI_CPU0_G2_CPU1_G0_TX_DN<10>")
	)
	(segment
		(start 113.228374 -211.62391)
		(end 112.261904 -212.59038)
		(width 0.14224)
		(layer "In2.Cu")
		(net "GMI_CPU0_G2_CPU1_G0_TX_DN<10>")
	)
	(segment
		(start 110.208822 -214.643462)
		(end 109.912658 -214.939626)
		(width 0.14224)
		(layer "In2.Cu")
		(net "GMI_CPU0_G2_CPU1_G0_TX_DN<10>")
	)
	(segment
		(start 363.750098 -219.781628)
		(end 363.22762 -218.63304)
		(width 0.14224)
		(layer "In2.Cu")
		(net "GMI_CPU0_G2_CPU1_G0_TX_DN<10>")
	)
	(segment
		(start 106.78033 -218.071954)
		(end 106.78033 -221.174564)
		(width 0.14224)
		(layer "In2.Cu")
		(net "GMI_CPU0_G2_CPU1_G0_TX_DN<10>")
	)
	(segment
		(start 107.364022 -222.93707)
		(end 107.365038 -222.937578)
		(width 0.1143)
		(layer "In2.Cu")
		(net "GMI_CPU0_G2_CPU1_G0_TX_DN<10>")
	)
	(segment
		(start 107.364022 -226.177094)
		(end 107.365038 -226.177602)
		(width 0.1143)
		(layer "In2.Cu")
		(net "GMI_CPU0_G2_CPU1_G0_TX_DN<10>")
	)
	(segment
		(start 106.73461 -221.59976)
		(end 106.706416 -221.627954)
		(width 0.1143)
		(layer "In2.Cu")
		(net "GMI_CPU0_G2_CPU1_G0_TX_DN<10>")
	)
	(segment
		(start 107.563412 -217.479118)
		(end 107.266994 -217.77579)
		(width 0.14224)
		(layer "In2.Cu")
		(net "GMI_CPU0_G2_CPU1_G0_TX_DN<10>")
	)
	(arc
		(start 364.092744 -223.888808)
		(mid 363.849417 -223.424242)
		(end 364.092744 -222.959676)
		(width 0.1143)
		(layer "In2.Cu")
		(net "GMI_CPU0_G2_CPU1_G0_TX_DN<10>")
	)
	(arc
		(start 107.403138 -222.95993)
		(mid 107.646465 -223.424496)
		(end 107.403138 -223.889062)
		(width 0.1143)
		(layer "In2.Cu")
		(net "GMI_CPU0_G2_CPU1_G0_TX_DN<10>")
	)
	(arc
		(start 107.332272 -223.93021)
		(mid 107.176344 -224.234502)
		(end 107.332272 -224.538794)
		(width 0.1143)
		(layer "In2.Cu")
		(net "GMI_CPU0_G2_CPU1_G0_TX_DN<10>")
	)
	(arc
		(start 364.782608 -228.214428)
		(mid 364.730559 -228.082909)
		(end 364.63351 -227.979986)
		(width 0.1143)
		(layer "In2.Cu")
		(net "GMI_CPU0_G2_CPU1_G0_TX_DN<10>")
	)
	(arc
		(start 364.092744 -222.268796)
		(mid 363.914086 -222.066396)
		(end 363.849666 -221.80423)
		(width 0.1143)
		(layer "In2.Cu")
		(net "GMI_CPU0_G2_CPU1_G0_TX_DN<10>")
	)
	(arc
		(start 107.403138 -224.579942)
		(mid 107.646465 -225.044508)
		(end 107.403138 -225.509074)
		(width 0.1143)
		(layer "In2.Cu")
		(net "GMI_CPU0_G2_CPU1_G0_TX_DN<10>")
	)
	(arc
		(start 364.332266 -227.483924)
		(mid 364.28196 -227.296336)
		(end 364.14456 -227.159058)
		(width 0.1143)
		(layer "In2.Cu")
		(net "GMI_CPU0_G2_CPU1_G0_TX_DN<10>")
	)
	(arc
		(start 364.16361 -226.158552)
		(mid 364.315199 -225.85426)
		(end 364.16361 -225.549968)
		(width 0.1143)
		(layer "In2.Cu")
		(net "GMI_CPU0_G2_CPU1_G0_TX_DN<10>")
	)
	(arc
		(start 107.176316 -222.61449)
		(mid 107.217571 -222.785461)
		(end 107.332272 -222.918782)
		(width 0.1143)
		(layer "In2.Cu")
		(net "GMI_CPU0_G2_CPU1_G0_TX_DN<10>")
	)
	(arc
		(start 364.599474 -227.960428)
		(mid 364.4038 -227.76413)
		(end 364.332266 -227.49637)
		(width 0.1143)
		(layer "In2.Cu")
		(net "GMI_CPU0_G2_CPU1_G0_TX_DN<10>")
	)
	(arc
		(start 364.16361 -222.918528)
		(mid 364.315199 -222.614236)
		(end 364.16361 -222.309944)
		(width 0.1143)
		(layer "In2.Cu")
		(net "GMI_CPU0_G2_CPU1_G0_TX_DN<10>")
	)
	(arc
		(start 107.403138 -226.199954)
		(mid 107.646465 -226.66452)
		(end 107.403138 -227.129086)
		(width 0.1143)
		(layer "In2.Cu")
		(net "GMI_CPU0_G2_CPU1_G0_TX_DN<10>")
	)
	(arc
		(start 364.183422 -224.524316)
		(mid 364.332136 -224.234248)
		(end 364.183422 -223.94418)
		(width 0.1143)
		(layer "In2.Cu")
		(net "GMI_CPU0_G2_CPU1_G0_TX_DN<10>")
	)
	(arc
		(start 106.706416 -221.804484)
		(mid 106.747382 -221.97489)
		(end 106.861356 -222.108014)
		(width 0.1143)
		(layer "In2.Cu")
		(net "GMI_CPU0_G2_CPU1_G0_TX_DN<10>")
	)
	(arc
		(start 364.092744 -225.50882)
		(mid 363.849417 -225.044254)
		(end 364.092744 -224.579688)
		(width 0.1143)
		(layer "In2.Cu")
		(net "GMI_CPU0_G2_CPU1_G0_TX_DN<10>")
	)
	(arc
		(start 106.931714 -222.148908)
		(mid 107.111443 -222.351528)
		(end 107.176316 -222.61449)
		(width 0.1143)
		(layer "In2.Cu")
		(net "GMI_CPU0_G2_CPU1_G0_TX_DN<10>")
	)
	(arc
		(start 107.332272 -227.170234)
		(mid 107.217596 -227.303568)
		(end 107.176316 -227.474526)
		(width 0.1143)
		(layer "In2.Cu")
		(net "GMI_CPU0_G2_CPU1_G0_TX_DN<10>")
	)
	(arc
		(start 106.863388 -227.979732)
		(mid 106.765623 -228.082708)
		(end 106.713274 -228.214682)
		(width 0.1143)
		(layer "In2.Cu")
		(net "GMI_CPU0_G2_CPU1_G0_TX_DN<10>")
	)
	(arc
		(start 107.176316 -227.474526)
		(mid 107.111801 -227.736745)
		(end 106.932984 -227.939092)
		(width 0.1143)
		(layer "In2.Cu")
		(net "GMI_CPU0_G2_CPU1_G0_TX_DN<10>")
	)
	(arc
		(start 364.092744 -227.128832)
		(mid 363.849417 -226.664266)
		(end 364.092744 -226.1997)
		(width 0.1143)
		(layer "In2.Cu")
		(net "GMI_CPU0_G2_CPU1_G0_TX_DN<10>")
	)
	(arc
		(start 107.332272 -225.550222)
		(mid 107.176344 -225.854514)
		(end 107.332272 -226.158806)
		(width 0.1143)
		(layer "In2.Cu")
		(net "GMI_CPU0_G2_CPU1_G0_TX_DN<10>")
	)
	(segment
		(start 99.08794 -231.79024)
		(end 98.621088 -231.524302)
		(width 0.12954)
		(layer "F.Cu")
		(net "GMI_CPU0_G2_CPU1_G0_TX_DN<0>")
	)
	(segment
		(start 372.407942 -231.789986)
		(end 372.874794 -231.524048)
		(width 0.12954)
		(layer "F.Cu")
		(net "GMI_CPU0_G2_CPU1_G0_TX_DN<0>")
	)
	(segment
		(start 96.993456 -224.539302)
		(end 97.023936 -224.557082)
		(width 0.1143)
		(layer "In2.Cu")
		(net "GMI_CPU0_G2_CPU1_G0_TX_DN<0>")
	)
	(segment
		(start 98.005138 -231.06126)
		(end 98.005138 -231.061006)
		(width 0.1143)
		(layer "In2.Cu")
		(net "GMI_CPU0_G2_CPU1_G0_TX_DN<0>")
	)
	(segment
		(start 374.43283 -229.43947)
		(end 374.471946 -229.41661)
		(width 0.1143)
		(layer "In2.Cu")
		(net "GMI_CPU0_G2_CPU1_G0_TX_DN<0>")
	)
	(segment
		(start 373.965216 -230.247952)
		(end 374.001792 -230.226616)
		(width 0.1143)
		(layer "In2.Cu")
		(net "GMI_CPU0_G2_CPU1_G0_TX_DN<0>")
	)
	(segment
		(start 100.753672 -207.337406)
		(end 100.563172 -207.337406)
		(width 0.14224)
		(layer "In2.Cu")
		(net "GMI_CPU0_G2_CPU1_G0_TX_DN<0>")
	)
	(segment
		(start 97.063052 -228.749098)
		(end 97.023936 -228.771958)
		(width 0.1143)
		(layer "In2.Cu")
		(net "GMI_CPU0_G2_CPU1_G0_TX_DN<0>")
	)
	(segment
		(start 96.555052 -222.127572)
		(end 96.593152 -222.149924)
		(width 0.1143)
		(layer "In2.Cu")
		(net "GMI_CPU0_G2_CPU1_G0_TX_DN<0>")
	)
	(segment
		(start 374.43283 -226.1997)
		(end 374.471946 -226.17684)
		(width 0.1143)
		(layer "In2.Cu")
		(net "GMI_CPU0_G2_CPU1_G0_TX_DN<0>")
	)
	(segment
		(start 97.917762 -210.173062)
		(end 97.621344 -210.469734)
		(width 0.14224)
		(layer "In2.Cu")
		(net "GMI_CPU0_G2_CPU1_G0_TX_DN<0>")
	)
	(segment
		(start 102.129336 -205.771242)
		(end 101.833172 -206.067406)
		(width 0.14224)
		(layer "In2.Cu")
		(net "GMI_CPU0_G2_CPU1_G0_TX_DN<0>")
	)
	(segment
		(start 98.213926 -209.686652)
		(end 97.917762 -209.982816)
		(width 0.14224)
		(layer "In2.Cu")
		(net "GMI_CPU0_G2_CPU1_G0_TX_DN<0>")
	)
	(segment
		(start 96.552004 -222.125794)
		(end 96.553274 -222.126556)
		(width 0.1143)
		(layer "In2.Cu")
		(net "GMI_CPU0_G2_CPU1_G0_TX_DN<0>")
	)
	(segment
		(start 96.351598 -221.203012)
		(end 96.305878 -221.248732)
		(width 0.1143)
		(layer "In2.Cu")
		(net "GMI_CPU0_G2_CPU1_G0_TX_DN<0>")
	)
	(segment
		(start 99.483926 -208.606898)
		(end 99.187508 -208.90357)
		(width 0.14224)
		(layer "In2.Cu")
		(net "GMI_CPU0_G2_CPU1_G0_TX_DN<0>")
	)
	(segment
		(start 97.917762 -209.982816)
		(end 97.917762 -210.173062)
		(width 0.14224)
		(layer "In2.Cu")
		(net "GMI_CPU0_G2_CPU1_G0_TX_DN<0>")
	)
	(segment
		(start 97.023936 -224.557082)
		(end 97.063052 -224.579942)
		(width 0.1143)
		(layer "In2.Cu")
		(net "GMI_CPU0_G2_CPU1_G0_TX_DN<0>")
	)
	(segment
		(start 97.023936 -229.416864)
		(end 97.06102 -229.4382)
		(width 0.1143)
		(layer "In2.Cu")
		(net "GMI_CPU0_G2_CPU1_G0_TX_DN<0>")
	)
	(segment
		(start 100.267008 -207.63357)
		(end 100.267008 -207.823816)
		(width 0.14224)
		(layer "In2.Cu")
		(net "GMI_CPU0_G2_CPU1_G0_TX_DN<0>")
	)
	(segment
		(start 98.404426 -209.686652)
		(end 98.213926 -209.686652)
		(width 0.14224)
		(layer "In2.Cu")
		(net "GMI_CPU0_G2_CPU1_G0_TX_DN<0>")
	)
	(segment
		(start 96.838262 -211.252816)
		(end 96.647762 -211.252816)
		(width 0.14224)
		(layer "In2.Cu")
		(net "GMI_CPU0_G2_CPU1_G0_TX_DN<0>")
	)
	(segment
		(start 98.700844 -209.199734)
		(end 98.700844 -209.38998)
		(width 0.14224)
		(layer "In2.Cu")
		(net "GMI_CPU0_G2_CPU1_G0_TX_DN<0>")
	)
	(segment
		(start 97.023936 -222.93707)
		(end 97.063052 -222.95993)
		(width 0.1143)
		(layer "In2.Cu")
		(net "GMI_CPU0_G2_CPU1_G0_TX_DN<0>")
	)
	(segment
		(start 358.82961 -202.016106)
		(end 325.234554 -182.145178)
		(width 0.14224)
		(layer "In2.Cu")
		(net "GMI_CPU0_G2_CPU1_G0_TX_DN<0>")
	)
	(segment
		(start 374.502426 -225.54946)
		(end 374.471946 -225.53168)
		(width 0.1143)
		(layer "In2.Cu")
		(net "GMI_CPU0_G2_CPU1_G0_TX_DN<0>")
	)
	(segment
		(start 374.143524 -221.202758)
		(end 374.143524 -221.17431)
		(width 0.1143)
		(layer "In2.Cu")
		(net "GMI_CPU0_G2_CPU1_G0_TX_DN<0>")
	)
	(segment
		(start 99.187508 -208.90357)
		(end 98.997008 -208.90357)
		(width 0.14224)
		(layer "In2.Cu")
		(net "GMI_CPU0_G2_CPU1_G0_TX_DN<0>")
	)
	(segment
		(start 160.74009 -175.515016)
		(end 150.280878 -179.92725)
		(width 0.14224)
		(layer "In2.Cu")
		(net "GMI_CPU0_G2_CPU1_G0_TX_DN<0>")
	)
	(segment
		(start 97.023936 -225.531934)
		(end 96.993456 -225.549714)
		(width 0.1143)
		(layer "In2.Cu")
		(net "GMI_CPU0_G2_CPU1_G0_TX_DN<0>")
	)
	(segment
		(start 374.001792 -230.226616)
		(end 374.033542 -230.208328)
		(width 0.1143)
		(layer "In2.Cu")
		(net "GMI_CPU0_G2_CPU1_G0_TX_DN<0>")
	)
	(segment
		(start 374.43283 -227.819712)
		(end 374.471946 -227.796852)
		(width 0.1143)
		(layer "In2.Cu")
		(net "GMI_CPU0_G2_CPU1_G0_TX_DN<0>")
	)
	(segment
		(start 96.305878 -221.248732)
		(end 96.305878 -221.545912)
		(width 0.1143)
		(layer "In2.Cu")
		(net "GMI_CPU0_G2_CPU1_G0_TX_DN<0>")
	)
	(segment
		(start 97.023936 -223.911922)
		(end 96.993456 -223.929702)
		(width 0.1143)
		(layer "In2.Cu")
		(net "GMI_CPU0_G2_CPU1_G0_TX_DN<0>")
	)
	(segment
		(start 97.063052 -225.509074)
		(end 97.023936 -225.531934)
		(width 0.1143)
		(layer "In2.Cu")
		(net "GMI_CPU0_G2_CPU1_G0_TX_DN<0>")
	)
	(segment
		(start 99.78009 -208.120488)
		(end 99.483926 -208.416652)
		(width 0.14224)
		(layer "In2.Cu")
		(net "GMI_CPU0_G2_CPU1_G0_TX_DN<0>")
	)
	(segment
		(start 97.023936 -226.177094)
		(end 97.063052 -226.199954)
		(width 0.1143)
		(layer "In2.Cu")
		(net "GMI_CPU0_G2_CPU1_G0_TX_DN<0>")
	)
	(segment
		(start 374.502426 -222.309436)
		(end 374.43283 -222.268796)
		(width 0.1143)
		(layer "In2.Cu")
		(net "GMI_CPU0_G2_CPU1_G0_TX_DN<0>")
	)
	(segment
		(start 371.603016 -211.686902)
		(end 366.32134 -207.086454)
		(width 0.14224)
		(layer "In2.Cu")
		(net "GMI_CPU0_G2_CPU1_G0_TX_DN<0>")
	)
	(segment
		(start 98.323146 -231.524302)
		(end 98.621088 -231.524302)
		(width 0.1143)
		(layer "In2.Cu")
		(net "GMI_CPU0_G2_CPU1_G0_TX_DN<0>")
	)
	(segment
		(start 164.368734 -174.479204)
		(end 160.74009 -175.515016)
		(width 0.14224)
		(layer "In2.Cu")
		(net "GMI_CPU0_G2_CPU1_G0_TX_DN<0>")
	)
	(segment
		(start 325.234554 -182.145178)
		(end 315.046868 -177.238406)
		(width 0.14224)
		(layer "In2.Cu")
		(net "GMI_CPU0_G2_CPU1_G0_TX_DN<0>")
	)
	(segment
		(start 374.471946 -225.53168)
		(end 374.43283 -225.50882)
		(width 0.1143)
		(layer "In2.Cu")
		(net "GMI_CPU0_G2_CPU1_G0_TX_DN<0>")
	)
	(segment
		(start 101.346254 -206.554324)
		(end 101.05009 -206.850488)
		(width 0.14224)
		(layer "In2.Cu")
		(net "GMI_CPU0_G2_CPU1_G0_TX_DN<0>")
	)
	(segment
		(start 374.502426 -227.169472)
		(end 374.471946 -227.151692)
		(width 0.1143)
		(layer "In2.Cu")
		(net "GMI_CPU0_G2_CPU1_G0_TX_DN<0>")
	)
	(segment
		(start 96.993456 -227.779326)
		(end 97.023936 -227.797106)
		(width 0.1143)
		(layer "In2.Cu")
		(net "GMI_CPU0_G2_CPU1_G0_TX_DN<0>")
	)
	(segment
		(start 98.240342 -231.441498)
		(end 98.323146 -231.524302)
		(width 0.1143)
		(layer "In2.Cu")
		(net "GMI_CPU0_G2_CPU1_G0_TX_DN<0>")
	)
	(segment
		(start 97.023936 -228.771958)
		(end 96.993456 -228.789738)
		(width 0.1143)
		(layer "In2.Cu")
		(net "GMI_CPU0_G2_CPU1_G0_TX_DN<0>")
	)
	(segment
		(start 97.306384 -229.90429)
		(end 97.30613 -229.90429)
		(width 0.1143)
		(layer "In2.Cu")
		(net "GMI_CPU0_G2_CPU1_G0_TX_DN<0>")
	)
	(segment
		(start 96.305878 -221.545912)
		(end 96.36633 -221.606364)
		(width 0.1143)
		(layer "In2.Cu")
		(net "GMI_CPU0_G2_CPU1_G0_TX_DN<0>")
	)
	(segment
		(start 96.991424 -229.398068)
		(end 97.023936 -229.416864)
		(width 0.1143)
		(layer "In2.Cu")
		(net "GMI_CPU0_G2_CPU1_G0_TX_DN<0>")
	)
	(segment
		(start 374.471946 -227.151692)
		(end 374.43283 -227.128832)
		(width 0.1143)
		(layer "In2.Cu")
		(net "GMI_CPU0_G2_CPU1_G0_TX_DN<0>")
	)
	(segment
		(start 374.43283 -222.959676)
		(end 374.471946 -222.936816)
		(width 0.1143)
		(layer "In2.Cu")
		(net "GMI_CPU0_G2_CPU1_G0_TX_DN<0>")
	)
	(segment
		(start 373.531892 -231.036622)
		(end 373.564404 -231.017826)
		(width 0.1143)
		(layer "In2.Cu")
		(net "GMI_CPU0_G2_CPU1_G0_TX_DN<0>")
	)
	(segment
		(start 96.554036 -222.127064)
		(end 96.555052 -222.127572)
		(width 0.1143)
		(layer "In2.Cu")
		(net "GMI_CPU0_G2_CPU1_G0_TX_DN<0>")
	)
	(segment
		(start 96.553274 -222.126556)
		(end 96.554036 -222.127064)
		(width 0.1143)
		(layer "In2.Cu")
		(net "GMI_CPU0_G2_CPU1_G0_TX_DN<0>")
	)
	(segment
		(start 96.522286 -222.108776)
		(end 96.552004 -222.125794)
		(width 0.1143)
		(layer "In2.Cu")
		(net "GMI_CPU0_G2_CPU1_G0_TX_DN<0>")
	)
	(segment
		(start 373.492776 -231.059482)
		(end 373.531892 -231.036622)
		(width 0.1143)
		(layer "In2.Cu")
		(net "GMI_CPU0_G2_CPU1_G0_TX_DN<0>")
	)
	(segment
		(start 97.13468 -210.956144)
		(end 96.838262 -211.252816)
		(width 0.14224)
		(layer "In2.Cu")
		(net "GMI_CPU0_G2_CPU1_G0_TX_DN<0>")
	)
	(segment
		(start 374.471946 -222.936816)
		(end 374.502426 -222.919036)
		(width 0.1143)
		(layer "In2.Cu")
		(net "GMI_CPU0_G2_CPU1_G0_TX_DN<0>")
	)
	(segment
		(start 101.05009 -207.040734)
		(end 100.753672 -207.337406)
		(width 0.14224)
		(layer "In2.Cu")
		(net "GMI_CPU0_G2_CPU1_G0_TX_DN<0>")
	)
	(segment
		(start 97.063052 -227.129086)
		(end 97.023936 -227.151946)
		(width 0.1143)
		(layer "In2.Cu")
		(net "GMI_CPU0_G2_CPU1_G0_TX_DN<0>")
	)
	(segment
		(start 373.172736 -231.524048)
		(end 373.25554 -231.441244)
		(width 0.1143)
		(layer "In2.Cu")
		(net "GMI_CPU0_G2_CPU1_G0_TX_DN<0>")
	)
	(segment
		(start 100.267008 -207.823816)
		(end 99.97059 -208.120488)
		(width 0.14224)
		(layer "In2.Cu")
		(net "GMI_CPU0_G2_CPU1_G0_TX_DN<0>")
	)
	(segment
		(start 97.483168 -230.220774)
		(end 97.48393 -230.221282)
		(width 0.1143)
		(layer "In2.Cu")
		(net "GMI_CPU0_G2_CPU1_G0_TX_DN<0>")
	)
	(segment
		(start 96.647762 -211.252816)
		(end 96.351598 -211.54898)
		(width 0.14224)
		(layer "In2.Cu")
		(net "GMI_CPU0_G2_CPU1_G0_TX_DN<0>")
	)
	(segment
		(start 372.874794 -231.524048)
		(end 373.172736 -231.524048)
		(width 0.1143)
		(layer "In2.Cu")
		(net "GMI_CPU0_G2_CPU1_G0_TX_DN<0>")
	)
	(segment
		(start 374.471946 -226.17684)
		(end 374.502426 -226.15906)
		(width 0.1143)
		(layer "In2.Cu")
		(net "GMI_CPU0_G2_CPU1_G0_TX_DN<0>")
	)
	(segment
		(start 374.143524 -217.269822)
		(end 371.603016 -211.686902)
		(width 0.14224)
		(layer "In2.Cu")
		(net "GMI_CPU0_G2_CPU1_G0_TX_DN<0>")
	)
	(segment
		(start 97.464118 -230.209852)
		(end 97.481644 -230.220012)
		(width 0.1143)
		(layer "In2.Cu")
		(net "GMI_CPU0_G2_CPU1_G0_TX_DN<0>")
	)
	(segment
		(start 100.563172 -207.337406)
		(end 100.267008 -207.63357)
		(width 0.14224)
		(layer "In2.Cu")
		(net "GMI_CPU0_G2_CPU1_G0_TX_DN<0>")
	)
	(segment
		(start 101.833172 -206.067406)
		(end 101.833172 -206.257652)
		(width 0.14224)
		(layer "In2.Cu")
		(net "GMI_CPU0_G2_CPU1_G0_TX_DN<0>")
	)
	(segment
		(start 374.471946 -223.911668)
		(end 374.43283 -223.888808)
		(width 0.1143)
		(layer "In2.Cu")
		(net "GMI_CPU0_G2_CPU1_G0_TX_DN<0>")
	)
	(segment
		(start 96.993456 -226.159314)
		(end 97.023936 -226.177094)
		(width 0.1143)
		(layer "In2.Cu")
		(net "GMI_CPU0_G2_CPU1_G0_TX_DN<0>")
	)
	(segment
		(start 102.616254 -205.284324)
		(end 102.616254 -205.47457)
		(width 0.14224)
		(layer "In2.Cu")
		(net "GMI_CPU0_G2_CPU1_G0_TX_DN<0>")
	)
	(segment
		(start 97.958656 -231.034336)
		(end 98.005138 -231.06126)
		(width 0.1143)
		(layer "In2.Cu")
		(net "GMI_CPU0_G2_CPU1_G0_TX_DN<0>")
	)
	(segment
		(start 374.471946 -229.41661)
		(end 374.504458 -229.397814)
		(width 0.1143)
		(layer "In2.Cu")
		(net "GMI_CPU0_G2_CPU1_G0_TX_DN<0>")
	)
	(segment
		(start 101.536754 -206.554324)
		(end 101.346254 -206.554324)
		(width 0.14224)
		(layer "In2.Cu")
		(net "GMI_CPU0_G2_CPU1_G0_TX_DN<0>")
	)
	(segment
		(start 98.997008 -208.90357)
		(end 98.700844 -209.199734)
		(width 0.14224)
		(layer "In2.Cu")
		(net "GMI_CPU0_G2_CPU1_G0_TX_DN<0>")
	)
	(segment
		(start 97.06102 -229.4382)
		(end 97.063052 -229.439724)
		(width 0.1143)
		(layer "In2.Cu")
		(net "GMI_CPU0_G2_CPU1_G0_TX_DN<0>")
	)
	(segment
		(start 102.319836 -205.771242)
		(end 102.129336 -205.771242)
		(width 0.14224)
		(layer "In2.Cu")
		(net "GMI_CPU0_G2_CPU1_G0_TX_DN<0>")
	)
	(segment
		(start 102.616254 -205.47457)
		(end 102.319836 -205.771242)
		(width 0.14224)
		(layer "In2.Cu")
		(net "GMI_CPU0_G2_CPU1_G0_TX_DN<0>")
	)
	(segment
		(start 101.05009 -206.850488)
		(end 101.05009 -207.040734)
		(width 0.14224)
		(layer "In2.Cu")
		(net "GMI_CPU0_G2_CPU1_G0_TX_DN<0>")
	)
	(segment
		(start 374.502426 -228.789484)
		(end 374.471946 -228.771704)
		(width 0.1143)
		(layer "In2.Cu")
		(net "GMI_CPU0_G2_CPU1_G0_TX_DN<0>")
	)
	(segment
		(start 374.43283 -224.579688)
		(end 374.471946 -224.556828)
		(width 0.1143)
		(layer "In2.Cu")
		(net "GMI_CPU0_G2_CPU1_G0_TX_DN<0>")
	)
	(segment
		(start 96.351598 -221.174564)
		(end 96.351598 -221.203012)
		(width 0.1143)
		(layer "In2.Cu")
		(net "GMI_CPU0_G2_CPU1_G0_TX_DN<0>")
	)
	(segment
		(start 150.280878 -179.92725)
		(end 105.00868 -202.891898)
		(width 0.14224)
		(layer "In2.Cu")
		(net "GMI_CPU0_G2_CPU1_G0_TX_DN<0>")
	)
	(segment
		(start 97.063052 -223.889062)
		(end 97.023936 -223.911922)
		(width 0.1143)
		(layer "In2.Cu")
		(net "GMI_CPU0_G2_CPU1_G0_TX_DN<0>")
	)
	(segment
		(start 97.48393 -230.221282)
		(end 97.485454 -230.222044)
		(width 0.1143)
		(layer "In2.Cu")
		(net "GMI_CPU0_G2_CPU1_G0_TX_DN<0>")
	)
	(segment
		(start 374.471946 -227.796852)
		(end 374.502426 -227.779072)
		(width 0.1143)
		(layer "In2.Cu")
		(net "GMI_CPU0_G2_CPU1_G0_TX_DN<0>")
	)
	(segment
		(start 99.97059 -208.120488)
		(end 99.78009 -208.120488)
		(width 0.14224)
		(layer "In2.Cu")
		(net "GMI_CPU0_G2_CPU1_G0_TX_DN<0>")
	)
	(segment
		(start 306.574444 -174.438056)
		(end 234.617006 -171.961302)
		(width 0.14224)
		(layer "In2.Cu")
		(net "GMI_CPU0_G2_CPU1_G0_TX_DN<0>")
	)
	(segment
		(start 374.502426 -223.929448)
		(end 374.471946 -223.911668)
		(width 0.1143)
		(layer "In2.Cu")
		(net "GMI_CPU0_G2_CPU1_G0_TX_DN<0>")
	)
	(segment
		(start 374.143524 -221.17431)
		(end 374.143524 -217.269822)
		(width 0.14224)
		(layer "In2.Cu")
		(net "GMI_CPU0_G2_CPU1_G0_TX_DN<0>")
	)
	(segment
		(start 99.483926 -208.416652)
		(end 99.483926 -208.606898)
		(width 0.14224)
		(layer "In2.Cu")
		(net "GMI_CPU0_G2_CPU1_G0_TX_DN<0>")
	)
	(segment
		(start 97.430844 -210.469734)
		(end 97.13468 -210.765898)
		(width 0.14224)
		(layer "In2.Cu")
		(net "GMI_CPU0_G2_CPU1_G0_TX_DN<0>")
	)
	(segment
		(start 101.833172 -206.257652)
		(end 101.536754 -206.554324)
		(width 0.14224)
		(layer "In2.Cu")
		(net "GMI_CPU0_G2_CPU1_G0_TX_DN<0>")
	)
	(segment
		(start 97.481644 -230.220012)
		(end 97.483168 -230.220774)
		(width 0.1143)
		(layer "In2.Cu")
		(net "GMI_CPU0_G2_CPU1_G0_TX_DN<0>")
	)
	(segment
		(start 105.00868 -202.891898)
		(end 102.616254 -205.284324)
		(width 0.14224)
		(layer "In2.Cu")
		(net "GMI_CPU0_G2_CPU1_G0_TX_DN<0>")
	)
	(segment
		(start 374.189752 -221.80423)
		(end 374.189752 -221.546166)
		(width 0.1143)
		(layer "In2.Cu")
		(net "GMI_CPU0_G2_CPU1_G0_TX_DN<0>")
	)
	(segment
		(start 96.351598 -211.54898)
		(end 96.351598 -221.174564)
		(width 0.14224)
		(layer "In2.Cu")
		(net "GMI_CPU0_G2_CPU1_G0_TX_DN<0>")
	)
	(segment
		(start 97.621344 -210.469734)
		(end 97.430844 -210.469734)
		(width 0.14224)
		(layer "In2.Cu")
		(net "GMI_CPU0_G2_CPU1_G0_TX_DN<0>")
	)
	(segment
		(start 374.189244 -221.545658)
		(end 374.189244 -221.248478)
		(width 0.1143)
		(layer "In2.Cu")
		(net "GMI_CPU0_G2_CPU1_G0_TX_DN<0>")
	)
	(segment
		(start 315.046868 -177.238406)
		(end 310.072532 -175.345598)
		(width 0.14224)
		(layer "In2.Cu")
		(net "GMI_CPU0_G2_CPU1_G0_TX_DN<0>")
	)
	(segment
		(start 98.700844 -209.38998)
		(end 98.404426 -209.686652)
		(width 0.14224)
		(layer "In2.Cu")
		(net "GMI_CPU0_G2_CPU1_G0_TX_DN<0>")
	)
	(segment
		(start 374.189244 -221.248478)
		(end 374.143524 -221.202758)
		(width 0.1143)
		(layer "In2.Cu")
		(net "GMI_CPU0_G2_CPU1_G0_TX_DN<0>")
	)
	(segment
		(start 96.993456 -222.91929)
		(end 97.023936 -222.93707)
		(width 0.1143)
		(layer "In2.Cu")
		(net "GMI_CPU0_G2_CPU1_G0_TX_DN<0>")
	)
	(segment
		(start 97.13468 -210.765898)
		(end 97.13468 -210.956144)
		(width 0.14224)
		(layer "In2.Cu")
		(net "GMI_CPU0_G2_CPU1_G0_TX_DN<0>")
	)
	(segment
		(start 310.072532 -175.345598)
		(end 306.574444 -174.438056)
		(width 0.14224)
		(layer "In2.Cu")
		(net "GMI_CPU0_G2_CPU1_G0_TX_DN<0>")
	)
	(segment
		(start 234.617006 -171.961302)
		(end 164.368734 -174.479204)
		(width 0.14224)
		(layer "In2.Cu")
		(net "GMI_CPU0_G2_CPU1_G0_TX_DN<0>")
	)
	(segment
		(start 374.471946 -228.771704)
		(end 374.43283 -228.748844)
		(width 0.1143)
		(layer "In2.Cu")
		(net "GMI_CPU0_G2_CPU1_G0_TX_DN<0>")
	)
	(segment
		(start 97.023936 -227.151946)
		(end 96.993456 -227.169726)
		(width 0.1143)
		(layer "In2.Cu")
		(net "GMI_CPU0_G2_CPU1_G0_TX_DN<0>")
	)
	(segment
		(start 96.36633 -221.606364)
		(end 96.36633 -221.804484)
		(width 0.1143)
		(layer "In2.Cu")
		(net "GMI_CPU0_G2_CPU1_G0_TX_DN<0>")
	)
	(segment
		(start 97.023936 -227.797106)
		(end 97.063052 -227.819966)
		(width 0.1143)
		(layer "In2.Cu")
		(net "GMI_CPU0_G2_CPU1_G0_TX_DN<0>")
	)
	(segment
		(start 374.471946 -224.556828)
		(end 374.502426 -224.539048)
		(width 0.1143)
		(layer "In2.Cu")
		(net "GMI_CPU0_G2_CPU1_G0_TX_DN<0>")
	)
	(segment
		(start 374.189752 -221.546166)
		(end 374.189244 -221.545658)
		(width 0.1143)
		(layer "In2.Cu")
		(net "GMI_CPU0_G2_CPU1_G0_TX_DN<0>")
	)
	(segment
		(start 366.32134 -207.086454)
		(end 358.82961 -202.016106)
		(width 0.14224)
		(layer "In2.Cu")
		(net "GMI_CPU0_G2_CPU1_G0_TX_DN<0>")
	)
	(arc
		(start 374.43283 -227.128832)
		(mid 374.189503 -226.664266)
		(end 374.43283 -226.1997)
		(width 0.1143)
		(layer "In2.Cu")
		(net "GMI_CPU0_G2_CPU1_G0_TX_DN<0>")
	)
	(arc
		(start 97.063052 -222.95993)
		(mid 97.306379 -223.424496)
		(end 97.063052 -223.889062)
		(width 0.1143)
		(layer "In2.Cu")
		(net "GMI_CPU0_G2_CPU1_G0_TX_DN<0>")
	)
	(arc
		(start 97.485454 -230.222044)
		(mid 97.698034 -230.429474)
		(end 97.77603 -230.716074)
		(width 0.1143)
		(layer "In2.Cu")
		(net "GMI_CPU0_G2_CPU1_G0_TX_DN<0>")
	)
	(arc
		(start 374.502426 -224.539048)
		(mid 374.659403 -224.234248)
		(end 374.502426 -223.929448)
		(width 0.1143)
		(layer "In2.Cu")
		(net "GMI_CPU0_G2_CPU1_G0_TX_DN<0>")
	)
	(arc
		(start 373.719344 -230.714296)
		(mid 373.78458 -230.450705)
		(end 373.965216 -230.247952)
		(width 0.1143)
		(layer "In2.Cu")
		(net "GMI_CPU0_G2_CPU1_G0_TX_DN<0>")
	)
	(arc
		(start 374.43283 -228.748844)
		(mid 374.189503 -228.284278)
		(end 374.43283 -227.819712)
		(width 0.1143)
		(layer "In2.Cu")
		(net "GMI_CPU0_G2_CPU1_G0_TX_DN<0>")
	)
	(arc
		(start 374.659398 -229.094284)
		(mid 374.617849 -228.922862)
		(end 374.502426 -228.789484)
		(width 0.1143)
		(layer "In2.Cu")
		(net "GMI_CPU0_G2_CPU1_G0_TX_DN<0>")
	)
	(arc
		(start 374.033542 -230.208328)
		(mid 374.148218 -230.074994)
		(end 374.189498 -229.904036)
		(width 0.1143)
		(layer "In2.Cu")
		(net "GMI_CPU0_G2_CPU1_G0_TX_DN<0>")
	)
	(arc
		(start 97.30613 -229.90429)
		(mid 97.34797 -230.076276)
		(end 97.464118 -230.209852)
		(width 0.1143)
		(layer "In2.Cu")
		(net "GMI_CPU0_G2_CPU1_G0_TX_DN<0>")
	)
	(arc
		(start 96.993456 -225.549714)
		(mid 96.836479 -225.854514)
		(end 96.993456 -226.159314)
		(width 0.1143)
		(layer "In2.Cu")
		(net "GMI_CPU0_G2_CPU1_G0_TX_DN<0>")
	)
	(arc
		(start 96.36633 -221.804484)
		(mid 96.407585 -221.975455)
		(end 96.522286 -222.108776)
		(width 0.1143)
		(layer "In2.Cu")
		(net "GMI_CPU0_G2_CPU1_G0_TX_DN<0>")
	)
	(arc
		(start 374.43283 -225.50882)
		(mid 374.189503 -225.044254)
		(end 374.43283 -224.579688)
		(width 0.1143)
		(layer "In2.Cu")
		(net "GMI_CPU0_G2_CPU1_G0_TX_DN<0>")
	)
	(arc
		(start 96.593152 -222.149924)
		(mid 96.771965 -222.352274)
		(end 96.836484 -222.61449)
		(width 0.1143)
		(layer "In2.Cu")
		(net "GMI_CPU0_G2_CPU1_G0_TX_DN<0>")
	)
	(arc
		(start 96.836484 -222.61449)
		(mid 96.878033 -222.785912)
		(end 96.993456 -222.91929)
		(width 0.1143)
		(layer "In2.Cu")
		(net "GMI_CPU0_G2_CPU1_G0_TX_DN<0>")
	)
	(arc
		(start 373.564404 -231.017826)
		(mid 373.678333 -230.884679)
		(end 373.719344 -230.714296)
		(width 0.1143)
		(layer "In2.Cu")
		(net "GMI_CPU0_G2_CPU1_G0_TX_DN<0>")
	)
	(arc
		(start 96.993456 -223.929702)
		(mid 96.836479 -224.234502)
		(end 96.993456 -224.539302)
		(width 0.1143)
		(layer "In2.Cu")
		(net "GMI_CPU0_G2_CPU1_G0_TX_DN<0>")
	)
	(arc
		(start 96.836484 -229.094538)
		(mid 96.87745 -229.264944)
		(end 96.991424 -229.398068)
		(width 0.1143)
		(layer "In2.Cu")
		(net "GMI_CPU0_G2_CPU1_G0_TX_DN<0>")
	)
	(arc
		(start 97.063052 -224.579942)
		(mid 97.306379 -225.044508)
		(end 97.063052 -225.509074)
		(width 0.1143)
		(layer "In2.Cu")
		(net "GMI_CPU0_G2_CPU1_G0_TX_DN<0>")
	)
	(arc
		(start 97.063052 -226.199954)
		(mid 97.306379 -226.66452)
		(end 97.063052 -227.129086)
		(width 0.1143)
		(layer "In2.Cu")
		(net "GMI_CPU0_G2_CPU1_G0_TX_DN<0>")
	)
	(arc
		(start 374.43283 -223.888808)
		(mid 374.189503 -223.424242)
		(end 374.43283 -222.959676)
		(width 0.1143)
		(layer "In2.Cu")
		(net "GMI_CPU0_G2_CPU1_G0_TX_DN<0>")
	)
	(arc
		(start 374.189498 -229.904036)
		(mid 374.254013 -229.641817)
		(end 374.43283 -229.43947)
		(width 0.1143)
		(layer "In2.Cu")
		(net "GMI_CPU0_G2_CPU1_G0_TX_DN<0>")
	)
	(arc
		(start 374.504458 -229.397814)
		(mid 374.618387 -229.264667)
		(end 374.659398 -229.094284)
		(width 0.1143)
		(layer "In2.Cu")
		(net "GMI_CPU0_G2_CPU1_G0_TX_DN<0>")
	)
	(arc
		(start 374.43283 -222.268796)
		(mid 374.254187 -222.066401)
		(end 374.189752 -221.80423)
		(width 0.1143)
		(layer "In2.Cu")
		(net "GMI_CPU0_G2_CPU1_G0_TX_DN<0>")
	)
	(arc
		(start 374.502426 -226.15906)
		(mid 374.659403 -225.85426)
		(end 374.502426 -225.54946)
		(width 0.1143)
		(layer "In2.Cu")
		(net "GMI_CPU0_G2_CPU1_G0_TX_DN<0>")
	)
	(arc
		(start 96.993456 -227.169726)
		(mid 96.836479 -227.474526)
		(end 96.993456 -227.779326)
		(width 0.1143)
		(layer "In2.Cu")
		(net "GMI_CPU0_G2_CPU1_G0_TX_DN<0>")
	)
	(arc
		(start 97.063052 -227.819966)
		(mid 97.306379 -228.284532)
		(end 97.063052 -228.749098)
		(width 0.1143)
		(layer "In2.Cu")
		(net "GMI_CPU0_G2_CPU1_G0_TX_DN<0>")
	)
	(arc
		(start 97.063052 -229.439724)
		(mid 97.241865 -229.642074)
		(end 97.306384 -229.90429)
		(width 0.1143)
		(layer "In2.Cu")
		(net "GMI_CPU0_G2_CPU1_G0_TX_DN<0>")
	)
	(arc
		(start 374.502426 -222.919036)
		(mid 374.659403 -222.614236)
		(end 374.502426 -222.309436)
		(width 0.1143)
		(layer "In2.Cu")
		(net "GMI_CPU0_G2_CPU1_G0_TX_DN<0>")
	)
	(arc
		(start 96.993456 -228.789738)
		(mid 96.878029 -228.923114)
		(end 96.836484 -229.094538)
		(width 0.1143)
		(layer "In2.Cu")
		(net "GMI_CPU0_G2_CPU1_G0_TX_DN<0>")
	)
	(arc
		(start 97.77603 -230.716074)
		(mid 97.824936 -230.899533)
		(end 97.958656 -231.034336)
		(width 0.1143)
		(layer "In2.Cu")
		(net "GMI_CPU0_G2_CPU1_G0_TX_DN<0>")
	)
	(arc
		(start 373.25554 -231.441244)
		(mid 373.334619 -231.225799)
		(end 373.492776 -231.059482)
		(width 0.1143)
		(layer "In2.Cu")
		(net "GMI_CPU0_G2_CPU1_G0_TX_DN<0>")
	)
	(arc
		(start 98.005138 -231.061006)
		(mid 98.16197 -231.227002)
		(end 98.240342 -231.441498)
		(width 0.1143)
		(layer "In2.Cu")
		(net "GMI_CPU0_G2_CPU1_G0_TX_DN<0>")
	)
	(arc
		(start 374.502426 -227.779072)
		(mid 374.659403 -227.474272)
		(end 374.502426 -227.169472)
		(width 0.1143)
		(layer "In2.Cu")
		(net "GMI_CPU0_G2_CPU1_G0_TX_DN<0>")
	)
	(segment
		(start 352.668078 -246.370094)
		(end 352.201226 -246.104156)
		(width 0.12954)
		(layer "F.Cu")
		(net "GMI_CPU0_G1_CPU1_G3_TX_DP<9>")
	)
	(segment
		(start 118.827804 -246.370348)
		(end 119.294656 -246.10441)
		(width 0.12954)
		(layer "F.Cu")
		(net "GMI_CPU0_G1_CPU1_G3_TX_DP<9>")
	)
	(segment
		(start 349.021146 -221.083124)
		(end 349.021146 -219.09659)
		(width 0.14224)
		(layer "In15.Cu")
		(net "GMI_CPU0_G1_CPU1_G3_TX_DP<9>")
	)
	(segment
		(start 120.53443 -219.543884)
		(end 120.53443 -220.991938)
		(width 0.14224)
		(layer "In15.Cu")
		(net "GMI_CPU0_G1_CPU1_G3_TX_DP<9>")
	)
	(segment
		(start 120.852692 -235.228892)
		(end 120.891808 -235.251752)
		(width 0.1143)
		(layer "In15.Cu")
		(net "GMI_CPU0_G1_CPU1_G3_TX_DP<9>")
	)
	(segment
		(start 350.604074 -226.17684)
		(end 350.573594 -226.15906)
		(width 0.1143)
		(layer "In15.Cu")
		(net "GMI_CPU0_G1_CPU1_G3_TX_DP<9>")
	)
	(segment
		(start 349.006414 -221.339664)
		(end 348.975426 -221.308676)
		(width 0.1143)
		(layer "In15.Cu")
		(net "GMI_CPU0_G1_CPU1_G3_TX_DP<9>")
	)
	(segment
		(start 120.891808 -226.177094)
		(end 120.852692 -226.199954)
		(width 0.1143)
		(layer "In15.Cu")
		(net "GMI_CPU0_G1_CPU1_G3_TX_DP<9>")
	)
	(segment
		(start 313.98718 -187.019946)
		(end 311.05856 -185.362088)
		(width 0.14224)
		(layer "In15.Cu")
		(net "GMI_CPU0_G1_CPU1_G3_TX_DP<9>")
	)
	(segment
		(start 350.604074 -239.136682)
		(end 350.573594 -239.118902)
		(width 0.1143)
		(layer "In15.Cu")
		(net "GMI_CPU0_G1_CPU1_G3_TX_DP<9>")
	)
	(segment
		(start 120.419114 -244.808502)
		(end 120.382538 -244.829838)
		(width 0.1143)
		(layer "In15.Cu")
		(net "GMI_CPU0_G1_CPU1_G3_TX_DP<9>")
	)
	(segment
		(start 350.64319 -234.299506)
		(end 350.604074 -234.276646)
		(width 0.1143)
		(layer "In15.Cu")
		(net "GMI_CPU0_G1_CPU1_G3_TX_DP<9>")
	)
	(segment
		(start 349.233236 -222.14967)
		(end 349.163132 -222.108776)
		(width 0.1143)
		(layer "In15.Cu")
		(net "GMI_CPU0_G1_CPU1_G3_TX_DP<9>")
	)
	(segment
		(start 350.604074 -232.656634)
		(end 350.573594 -232.638854)
		(width 0.1143)
		(layer "In15.Cu")
		(net "GMI_CPU0_G1_CPU1_G3_TX_DP<9>")
	)
	(segment
		(start 120.922288 -242.35918)
		(end 120.891808 -242.37696)
		(width 0.1143)
		(layer "In15.Cu")
		(net "GMI_CPU0_G1_CPU1_G3_TX_DP<9>")
	)
	(segment
		(start 350.604074 -243.351558)
		(end 350.64319 -243.328698)
		(width 0.1143)
		(layer "In15.Cu")
		(net "GMI_CPU0_G1_CPU1_G3_TX_DP<9>")
	)
	(segment
		(start 120.891808 -227.151946)
		(end 120.922288 -227.169726)
		(width 0.1143)
		(layer "In15.Cu")
		(net "GMI_CPU0_G1_CPU1_G3_TX_DP<9>")
	)
	(segment
		(start 350.604074 -240.756694)
		(end 350.573594 -240.738914)
		(width 0.1143)
		(layer "In15.Cu")
		(net "GMI_CPU0_G1_CPU1_G3_TX_DP<9>")
	)
	(segment
		(start 311.058306 -185.361834)
		(end 308.12994 -183.70423)
		(width 0.14224)
		(layer "In15.Cu")
		(net "GMI_CPU0_G1_CPU1_G3_TX_DP<9>")
	)
	(segment
		(start 351.903284 -246.104156)
		(end 351.82048 -246.021352)
		(width 0.1143)
		(layer "In15.Cu")
		(net "GMI_CPU0_G1_CPU1_G3_TX_DP<9>")
	)
	(segment
		(start 120.922288 -222.91929)
		(end 120.891808 -222.93707)
		(width 0.1143)
		(layer "In15.Cu")
		(net "GMI_CPU0_G1_CPU1_G3_TX_DP<9>")
	)
	(segment
		(start 350.604074 -234.276646)
		(end 350.573594 -234.258866)
		(width 0.1143)
		(layer "In15.Cu")
		(net "GMI_CPU0_G1_CPU1_G3_TX_DP<9>")
	)
	(segment
		(start 120.922288 -243.979192)
		(end 120.891808 -243.996972)
		(width 0.1143)
		(layer "In15.Cu")
		(net "GMI_CPU0_G1_CPU1_G3_TX_DP<9>")
	)
	(segment
		(start 350.604074 -240.111534)
		(end 350.64319 -240.088674)
		(width 0.1143)
		(layer "In15.Cu")
		(net "GMI_CPU0_G1_CPU1_G3_TX_DP<9>")
	)
	(segment
		(start 350.573594 -240.129314)
		(end 350.604074 -240.111534)
		(width 0.1143)
		(layer "In15.Cu")
		(net "GMI_CPU0_G1_CPU1_G3_TX_DP<9>")
	)
	(segment
		(start 120.852692 -240.088928)
		(end 120.891808 -240.111788)
		(width 0.1143)
		(layer "In15.Cu")
		(net "GMI_CPU0_G1_CPU1_G3_TX_DP<9>")
	)
	(segment
		(start 120.852692 -236.848904)
		(end 120.891808 -236.871764)
		(width 0.1143)
		(layer "In15.Cu")
		(net "GMI_CPU0_G1_CPU1_G3_TX_DP<9>")
	)
	(segment
		(start 350.573594 -238.509302)
		(end 350.604074 -238.491522)
		(width 0.1143)
		(layer "In15.Cu")
		(net "GMI_CPU0_G1_CPU1_G3_TX_DP<9>")
	)
	(segment
		(start 350.573594 -243.369338)
		(end 350.604074 -243.351558)
		(width 0.1143)
		(layer "In15.Cu")
		(net "GMI_CPU0_G1_CPU1_G3_TX_DP<9>")
	)
	(segment
		(start 350.604074 -231.036622)
		(end 350.571562 -231.017826)
		(width 0.1143)
		(layer "In15.Cu")
		(net "GMI_CPU0_G1_CPU1_G3_TX_DP<9>")
	)
	(segment
		(start 350.573594 -230.409496)
		(end 350.64065 -230.37038)
		(width 0.1143)
		(layer "In15.Cu")
		(net "GMI_CPU0_G1_CPU1_G3_TX_DP<9>")
	)
	(segment
		(start 350.604074 -228.771704)
		(end 350.642682 -228.749098)
		(width 0.1143)
		(layer "In15.Cu")
		(net "GMI_CPU0_G1_CPU1_G3_TX_DP<9>")
	)
	(segment
		(start 120.922288 -224.539302)
		(end 120.891808 -224.557082)
		(width 0.1143)
		(layer "In15.Cu")
		(net "GMI_CPU0_G1_CPU1_G3_TX_DP<9>")
	)
	(segment
		(start 120.53443 -221.020386)
		(end 120.58015 -221.066106)
		(width 0.1143)
		(layer "In15.Cu")
		(net "GMI_CPU0_G1_CPU1_G3_TX_DP<9>")
	)
	(segment
		(start 350.64319 -237.53953)
		(end 350.604074 -237.51667)
		(width 0.1143)
		(layer "In15.Cu")
		(net "GMI_CPU0_G1_CPU1_G3_TX_DP<9>")
	)
	(segment
		(start 350.604074 -243.996718)
		(end 350.573594 -243.978938)
		(width 0.1143)
		(layer "In15.Cu")
		(net "GMI_CPU0_G1_CPU1_G3_TX_DP<9>")
	)
	(segment
		(start 348.975426 -221.128844)
		(end 349.021146 -221.083124)
		(width 0.1143)
		(layer "In15.Cu")
		(net "GMI_CPU0_G1_CPU1_G3_TX_DP<9>")
	)
	(segment
		(start 350.133412 -225.366326)
		(end 350.132142 -225.365564)
		(width 0.1143)
		(layer "In15.Cu")
		(net "GMI_CPU0_G1_CPU1_G3_TX_DP<9>")
	)
	(segment
		(start 120.854724 -229.4382)
		(end 120.852692 -229.439724)
		(width 0.1143)
		(layer "In15.Cu")
		(net "GMI_CPU0_G1_CPU1_G3_TX_DP<9>")
	)
	(segment
		(start 349.021146 -219.09659)
		(end 346.4306 -213.622382)
		(width 0.14224)
		(layer "In15.Cu")
		(net "GMI_CPU0_G1_CPU1_G3_TX_DP<9>")
	)
	(segment
		(start 351.085404 -244.813328)
		(end 351.042224 -244.788182)
		(width 0.1143)
		(layer "In15.Cu")
		(net "GMI_CPU0_G1_CPU1_G3_TX_DP<9>")
	)
	(segment
		(start 120.92432 -231.01808)
		(end 120.891808 -231.036876)
		(width 0.1143)
		(layer "In15.Cu")
		(net "GMI_CPU0_G1_CPU1_G3_TX_DP<9>")
	)
	(segment
		(start 306.86756 -183.252872)
		(end 302.892968 -183.252872)
		(width 0.14224)
		(layer "In15.Cu")
		(net "GMI_CPU0_G1_CPU1_G3_TX_DP<9>")
	)
	(segment
		(start 157.068012 -188.047376)
		(end 157.067758 -188.047376)
		(width 0.14224)
		(layer "In15.Cu")
		(net "GMI_CPU0_G1_CPU1_G3_TX_DP<9>")
	)
	(segment
		(start 120.891808 -222.93707)
		(end 120.852692 -222.95993)
		(width 0.1143)
		(layer "In15.Cu")
		(net "GMI_CPU0_G1_CPU1_G3_TX_DP<9>")
	)
	(segment
		(start 120.852692 -225.509074)
		(end 120.891808 -225.531934)
		(width 0.1143)
		(layer "In15.Cu")
		(net "GMI_CPU0_G1_CPU1_G3_TX_DP<9>")
	)
	(segment
		(start 349.163132 -222.108776)
		(end 349.162878 -222.108776)
		(width 0.1143)
		(layer "In15.Cu")
		(net "GMI_CPU0_G1_CPU1_G3_TX_DP<9>")
	)
	(segment
		(start 120.891808 -240.756948)
		(end 120.852692 -240.779808)
		(width 0.1143)
		(layer "In15.Cu")
		(net "GMI_CPU0_G1_CPU1_G3_TX_DP<9>")
	)
	(segment
		(start 120.891808 -243.996972)
		(end 120.852692 -244.019832)
		(width 0.1143)
		(layer "In15.Cu")
		(net "GMI_CPU0_G1_CPU1_G3_TX_DP<9>")
	)
	(segment
		(start 350.64319 -240.779554)
		(end 350.604074 -240.756694)
		(width 0.1143)
		(layer "In15.Cu")
		(net "GMI_CPU0_G1_CPU1_G3_TX_DP<9>")
	)
	(segment
		(start 349.006414 -221.80423)
		(end 349.006414 -221.339664)
		(width 0.1143)
		(layer "In15.Cu")
		(net "GMI_CPU0_G1_CPU1_G3_TX_DP<9>")
	)
	(segment
		(start 352.201226 -246.104156)
		(end 351.903284 -246.104156)
		(width 0.1143)
		(layer "In15.Cu")
		(net "GMI_CPU0_G1_CPU1_G3_TX_DP<9>")
	)
	(segment
		(start 349.63354 -223.929448)
		(end 349.66402 -223.911668)
		(width 0.1143)
		(layer "In15.Cu")
		(net "GMI_CPU0_G1_CPU1_G3_TX_DP<9>")
	)
	(segment
		(start 161.749994 -184.208166)
		(end 157.068012 -188.047376)
		(width 0.14224)
		(layer "In15.Cu")
		(net "GMI_CPU0_G1_CPU1_G3_TX_DP<9>")
	)
	(segment
		(start 120.855232 -230.370634)
		(end 120.922288 -230.40975)
		(width 0.1143)
		(layer "In15.Cu")
		(net "GMI_CPU0_G1_CPU1_G3_TX_DP<9>")
	)
	(segment
		(start 120.891808 -224.557082)
		(end 120.852692 -224.579942)
		(width 0.1143)
		(layer "In15.Cu")
		(net "GMI_CPU0_G1_CPU1_G3_TX_DP<9>")
	)
	(segment
		(start 120.420638 -244.807486)
		(end 120.419114 -244.808502)
		(width 0.1143)
		(layer "In15.Cu")
		(net "GMI_CPU0_G1_CPU1_G3_TX_DP<9>")
	)
	(segment
		(start 350.573594 -228.789484)
		(end 350.604074 -228.771704)
		(width 0.1143)
		(layer "In15.Cu")
		(net "GMI_CPU0_G1_CPU1_G3_TX_DP<9>")
	)
	(segment
		(start 120.852692 -233.60888)
		(end 120.891808 -233.63174)
		(width 0.1143)
		(layer "In15.Cu")
		(net "GMI_CPU0_G1_CPU1_G3_TX_DP<9>")
	)
	(segment
		(start 120.421654 -244.806978)
		(end 120.420638 -244.807486)
		(width 0.1143)
		(layer "In15.Cu")
		(net "GMI_CPU0_G1_CPU1_G3_TX_DP<9>")
	)
	(segment
		(start 349.66402 -222.936816)
		(end 349.63354 -222.919036)
		(width 0.1143)
		(layer "In15.Cu")
		(net "GMI_CPU0_G1_CPU1_G3_TX_DP<9>")
	)
	(segment
		(start 120.852692 -241.70894)
		(end 120.891808 -241.7318)
		(width 0.1143)
		(layer "In15.Cu")
		(net "GMI_CPU0_G1_CPU1_G3_TX_DP<9>")
	)
	(segment
		(start 349.703136 -224.579688)
		(end 349.66402 -224.556828)
		(width 0.1143)
		(layer "In15.Cu")
		(net "GMI_CPU0_G1_CPU1_G3_TX_DP<9>")
	)
	(segment
		(start 120.922288 -237.499144)
		(end 120.891808 -237.516924)
		(width 0.1143)
		(layer "In15.Cu")
		(net "GMI_CPU0_G1_CPU1_G3_TX_DP<9>")
	)
	(segment
		(start 123.048522 -215.234012)
		(end 120.53443 -219.543884)
		(width 0.14224)
		(layer "In15.Cu")
		(net "GMI_CPU0_G1_CPU1_G3_TX_DP<9>")
	)
	(segment
		(start 120.891808 -233.63174)
		(end 120.922288 -233.64952)
		(width 0.1143)
		(layer "In15.Cu")
		(net "GMI_CPU0_G1_CPU1_G3_TX_DP<9>")
	)
	(segment
		(start 350.64319 -227.819712)
		(end 350.604074 -227.796852)
		(width 0.1143)
		(layer "In15.Cu")
		(net "GMI_CPU0_G1_CPU1_G3_TX_DP<9>")
	)
	(segment
		(start 348.975426 -221.308676)
		(end 348.975426 -221.128844)
		(width 0.1143)
		(layer "In15.Cu")
		(net "GMI_CPU0_G1_CPU1_G3_TX_DP<9>")
	)
	(segment
		(start 302.892968 -183.252872)
		(end 166.62908 -182.458868)
		(width 0.14224)
		(layer "In15.Cu")
		(net "GMI_CPU0_G1_CPU1_G3_TX_DP<9>")
	)
	(segment
		(start 120.58015 -221.277942)
		(end 120.608852 -221.306644)
		(width 0.1143)
		(layer "In15.Cu")
		(net "GMI_CPU0_G1_CPU1_G3_TX_DP<9>")
	)
	(segment
		(start 350.64319 -226.1997)
		(end 350.604074 -226.17684)
		(width 0.1143)
		(layer "In15.Cu")
		(net "GMI_CPU0_G1_CPU1_G3_TX_DP<9>")
	)
	(segment
		(start 350.604074 -235.251498)
		(end 350.64319 -235.228638)
		(width 0.1143)
		(layer "In15.Cu")
		(net "GMI_CPU0_G1_CPU1_G3_TX_DP<9>")
	)
	(segment
		(start 120.922288 -240.739168)
		(end 120.891808 -240.756948)
		(width 0.1143)
		(layer "In15.Cu")
		(net "GMI_CPU0_G1_CPU1_G3_TX_DP<9>")
	)
	(segment
		(start 350.604074 -238.491522)
		(end 350.64319 -238.468662)
		(width 0.1143)
		(layer "In15.Cu")
		(net "GMI_CPU0_G1_CPU1_G3_TX_DP<9>")
	)
	(segment
		(start 120.891808 -237.516924)
		(end 120.852692 -237.539784)
		(width 0.1143)
		(layer "In15.Cu")
		(net "GMI_CPU0_G1_CPU1_G3_TX_DP<9>")
	)
	(segment
		(start 120.922288 -239.119156)
		(end 120.891808 -239.136936)
		(width 0.1143)
		(layer "In15.Cu")
		(net "GMI_CPU0_G1_CPU1_G3_TX_DP<9>")
	)
	(segment
		(start 350.604074 -232.011474)
		(end 350.64319 -231.988614)
		(width 0.1143)
		(layer "In15.Cu")
		(net "GMI_CPU0_G1_CPU1_G3_TX_DP<9>")
	)
	(segment
		(start 120.891808 -231.036876)
		(end 120.852692 -231.059736)
		(width 0.1143)
		(layer "In15.Cu")
		(net "GMI_CPU0_G1_CPU1_G3_TX_DP<9>")
	)
	(segment
		(start 120.453404 -244.78869)
		(end 120.422416 -244.80647)
		(width 0.1143)
		(layer "In15.Cu")
		(net "GMI_CPU0_G1_CPU1_G3_TX_DP<9>")
	)
	(segment
		(start 350.136714 -225.368358)
		(end 350.13519 -225.367342)
		(width 0.1143)
		(layer "In15.Cu")
		(net "GMI_CPU0_G1_CPU1_G3_TX_DP<9>")
	)
	(segment
		(start 350.604074 -237.51667)
		(end 350.573594 -237.49889)
		(width 0.1143)
		(layer "In15.Cu")
		(net "GMI_CPU0_G1_CPU1_G3_TX_DP<9>")
	)
	(segment
		(start 120.891808 -232.656888)
		(end 120.852692 -232.679748)
		(width 0.1143)
		(layer "In15.Cu")
		(net "GMI_CPU0_G1_CPU1_G3_TX_DP<9>")
	)
	(segment
		(start 350.12884 -225.363786)
		(end 350.102424 -225.348546)
		(width 0.1143)
		(layer "In15.Cu")
		(net "GMI_CPU0_G1_CPU1_G3_TX_DP<9>")
	)
	(segment
		(start 120.852692 -238.468916)
		(end 120.891808 -238.491776)
		(width 0.1143)
		(layer "In15.Cu")
		(net "GMI_CPU0_G1_CPU1_G3_TX_DP<9>")
	)
	(segment
		(start 120.891808 -232.011728)
		(end 120.922288 -232.029508)
		(width 0.1143)
		(layer "In15.Cu")
		(net "GMI_CPU0_G1_CPU1_G3_TX_DP<9>")
	)
	(segment
		(start 144.859756 -197.349618)
		(end 123.048522 -215.234012)
		(width 0.14224)
		(layer "In15.Cu")
		(net "GMI_CPU0_G1_CPU1_G3_TX_DP<9>")
	)
	(segment
		(start 120.891808 -243.351812)
		(end 120.922288 -243.369592)
		(width 0.1143)
		(layer "In15.Cu")
		(net "GMI_CPU0_G1_CPU1_G3_TX_DP<9>")
	)
	(segment
		(start 350.64319 -239.159542)
		(end 350.604074 -239.136682)
		(width 0.1143)
		(layer "In15.Cu")
		(net "GMI_CPU0_G1_CPU1_G3_TX_DP<9>")
	)
	(segment
		(start 120.891808 -223.911922)
		(end 120.922288 -223.929702)
		(width 0.1143)
		(layer "In15.Cu")
		(net "GMI_CPU0_G1_CPU1_G3_TX_DP<9>")
	)
	(segment
		(start 350.64319 -235.919518)
		(end 350.604074 -235.896658)
		(width 0.1143)
		(layer "In15.Cu")
		(net "GMI_CPU0_G1_CPU1_G3_TX_DP<9>")
	)
	(segment
		(start 119.675402 -246.021606)
		(end 119.592598 -246.10441)
		(width 0.1143)
		(layer "In15.Cu")
		(net "GMI_CPU0_G1_CPU1_G3_TX_DP<9>")
	)
	(segment
		(start 120.922288 -227.779326)
		(end 120.891808 -227.797106)
		(width 0.1143)
		(layer "In15.Cu")
		(net "GMI_CPU0_G1_CPU1_G3_TX_DP<9>")
	)
	(segment
		(start 120.608852 -221.306644)
		(end 120.608852 -221.804484)
		(width 0.1143)
		(layer "In15.Cu")
		(net "GMI_CPU0_G1_CPU1_G3_TX_DP<9>")
	)
	(segment
		(start 146.22907 -196.93509)
		(end 144.859756 -197.349618)
		(width 0.14224)
		(layer "In15.Cu")
		(net "GMI_CPU0_G1_CPU1_G3_TX_DP<9>")
	)
	(segment
		(start 120.891808 -238.491776)
		(end 120.922288 -238.509556)
		(width 0.1143)
		(layer "In15.Cu")
		(net "GMI_CPU0_G1_CPU1_G3_TX_DP<9>")
	)
	(segment
		(start 120.891808 -240.111788)
		(end 120.922288 -240.129568)
		(width 0.1143)
		(layer "In15.Cu")
		(net "GMI_CPU0_G1_CPU1_G3_TX_DP<9>")
	)
	(segment
		(start 351.582482 -245.639082)
		(end 351.54362 -245.616476)
		(width 0.1143)
		(layer "In15.Cu")
		(net "GMI_CPU0_G1_CPU1_G3_TX_DP<9>")
	)
	(segment
		(start 350.17329 -225.389694)
		(end 350.136714 -225.368358)
		(width 0.1143)
		(layer "In15.Cu")
		(net "GMI_CPU0_G1_CPU1_G3_TX_DP<9>")
	)
	(segment
		(start 120.922288 -234.25912)
		(end 120.891808 -234.2769)
		(width 0.1143)
		(layer "In15.Cu")
		(net "GMI_CPU0_G1_CPU1_G3_TX_DP<9>")
	)
	(segment
		(start 311.05856 -185.362088)
		(end 311.058306 -185.361834)
		(width 0.14224)
		(layer "In15.Cu")
		(net "GMI_CPU0_G1_CPU1_G3_TX_DP<9>")
	)
	(segment
		(start 350.642682 -228.749098)
		(end 350.64319 -228.748844)
		(width 0.1143)
		(layer "In15.Cu")
		(net "GMI_CPU0_G1_CPU1_G3_TX_DP<9>")
	)
	(segment
		(start 350.604074 -235.896658)
		(end 350.573594 -235.878878)
		(width 0.1143)
		(layer "In15.Cu")
		(net "GMI_CPU0_G1_CPU1_G3_TX_DP<9>")
	)
	(segment
		(start 350.132142 -225.365564)
		(end 350.130618 -225.364802)
		(width 0.1143)
		(layer "In15.Cu")
		(net "GMI_CPU0_G1_CPU1_G3_TX_DP<9>")
	)
	(segment
		(start 120.922288 -226.159314)
		(end 120.891808 -226.177094)
		(width 0.1143)
		(layer "In15.Cu")
		(net "GMI_CPU0_G1_CPU1_G3_TX_DP<9>")
	)
	(segment
		(start 346.4306 -213.622382)
		(end 313.98718 -187.019946)
		(width 0.14224)
		(layer "In15.Cu")
		(net "GMI_CPU0_G1_CPU1_G3_TX_DP<9>")
	)
	(segment
		(start 120.891808 -227.797106)
		(end 120.852692 -227.819966)
		(width 0.1143)
		(layer "In15.Cu")
		(net "GMI_CPU0_G1_CPU1_G3_TX_DP<9>")
	)
	(segment
		(start 350.604074 -241.731546)
		(end 350.64319 -241.708686)
		(width 0.1143)
		(layer "In15.Cu")
		(net "GMI_CPU0_G1_CPU1_G3_TX_DP<9>")
	)
	(segment
		(start 349.66402 -224.556828)
		(end 349.63354 -224.539048)
		(width 0.1143)
		(layer "In15.Cu")
		(net "GMI_CPU0_G1_CPU1_G3_TX_DP<9>")
	)
	(segment
		(start 350.604074 -229.41661)
		(end 350.571562 -229.397814)
		(width 0.1143)
		(layer "In15.Cu")
		(net "GMI_CPU0_G1_CPU1_G3_TX_DP<9>")
	)
	(segment
		(start 351.368868 -245.3132)
		(end 351.368868 -245.303548)
		(width 0.1143)
		(layer "In15.Cu")
		(net "GMI_CPU0_G1_CPU1_G3_TX_DP<9>")
	)
	(segment
		(start 308.12994 -183.70423)
		(end 306.86756 -183.252872)
		(width 0.14224)
		(layer "In15.Cu")
		(net "GMI_CPU0_G1_CPU1_G3_TX_DP<9>")
	)
	(segment
		(start 120.922288 -232.639108)
		(end 120.891808 -232.656888)
		(width 0.1143)
		(layer "In15.Cu")
		(net "GMI_CPU0_G1_CPU1_G3_TX_DP<9>")
	)
	(segment
		(start 349.703136 -222.959676)
		(end 349.66402 -222.936816)
		(width 0.1143)
		(layer "In15.Cu")
		(net "GMI_CPU0_G1_CPU1_G3_TX_DP<9>")
	)
	(segment
		(start 350.134174 -225.366834)
		(end 350.133412 -225.366326)
		(width 0.1143)
		(layer "In15.Cu")
		(net "GMI_CPU0_G1_CPU1_G3_TX_DP<9>")
	)
	(segment
		(start 119.951754 -245.616984)
		(end 119.912638 -245.639844)
		(width 0.1143)
		(layer "In15.Cu")
		(net "GMI_CPU0_G1_CPU1_G3_TX_DP<9>")
	)
	(segment
		(start 350.64319 -231.059482)
		(end 350.604074 -231.036622)
		(width 0.1143)
		(layer "In15.Cu")
		(net "GMI_CPU0_G1_CPU1_G3_TX_DP<9>")
	)
	(segment
		(start 350.573594 -241.749326)
		(end 350.604074 -241.731546)
		(width 0.1143)
		(layer "In15.Cu")
		(net "GMI_CPU0_G1_CPU1_G3_TX_DP<9>")
	)
	(segment
		(start 120.422416 -244.80647)
		(end 120.421654 -244.806978)
		(width 0.1143)
		(layer "In15.Cu")
		(net "GMI_CPU0_G1_CPU1_G3_TX_DP<9>")
	)
	(segment
		(start 120.53443 -220.991938)
		(end 120.53443 -221.020386)
		(width 0.1143)
		(layer "In15.Cu")
		(net "GMI_CPU0_G1_CPU1_G3_TX_DP<9>")
	)
	(segment
		(start 119.982234 -245.599204)
		(end 119.951754 -245.616984)
		(width 0.1143)
		(layer "In15.Cu")
		(net "GMI_CPU0_G1_CPU1_G3_TX_DP<9>")
	)
	(segment
		(start 120.891808 -235.251752)
		(end 120.922288 -235.269532)
		(width 0.1143)
		(layer "In15.Cu")
		(net "GMI_CPU0_G1_CPU1_G3_TX_DP<9>")
	)
	(segment
		(start 120.891808 -235.896912)
		(end 120.852692 -235.919772)
		(width 0.1143)
		(layer "In15.Cu")
		(net "GMI_CPU0_G1_CPU1_G3_TX_DP<9>")
	)
	(segment
		(start 120.891808 -241.7318)
		(end 120.922288 -241.74958)
		(width 0.1143)
		(layer "In15.Cu")
		(net "GMI_CPU0_G1_CPU1_G3_TX_DP<9>")
	)
	(segment
		(start 350.604074 -227.796852)
		(end 350.573594 -227.779072)
		(width 0.1143)
		(layer "In15.Cu")
		(net "GMI_CPU0_G1_CPU1_G3_TX_DP<9>")
	)
	(segment
		(start 120.891808 -225.531934)
		(end 120.922288 -225.549714)
		(width 0.1143)
		(layer "In15.Cu")
		(net "GMI_CPU0_G1_CPU1_G3_TX_DP<9>")
	)
	(segment
		(start 157.067758 -188.047376)
		(end 146.22907 -196.93509)
		(width 0.14224)
		(layer "In15.Cu")
		(net "GMI_CPU0_G1_CPU1_G3_TX_DP<9>")
	)
	(segment
		(start 350.64319 -229.43947)
		(end 350.604074 -229.41661)
		(width 0.1143)
		(layer "In15.Cu")
		(net "GMI_CPU0_G1_CPU1_G3_TX_DP<9>")
	)
	(segment
		(start 119.592598 -246.10441)
		(end 119.294656 -246.10441)
		(width 0.1143)
		(layer "In15.Cu")
		(net "GMI_CPU0_G1_CPU1_G3_TX_DP<9>")
	)
	(segment
		(start 349.66402 -223.911668)
		(end 349.703136 -223.888808)
		(width 0.1143)
		(layer "In15.Cu")
		(net "GMI_CPU0_G1_CPU1_G3_TX_DP<9>")
	)
	(segment
		(start 350.64319 -232.679494)
		(end 350.604074 -232.656634)
		(width 0.1143)
		(layer "In15.Cu")
		(net "GMI_CPU0_G1_CPU1_G3_TX_DP<9>")
	)
	(segment
		(start 350.573594 -227.169472)
		(end 350.604074 -227.151692)
		(width 0.1143)
		(layer "In15.Cu")
		(net "GMI_CPU0_G1_CPU1_G3_TX_DP<9>")
	)
	(segment
		(start 350.64319 -242.399566)
		(end 350.604074 -242.376706)
		(width 0.1143)
		(layer "In15.Cu")
		(net "GMI_CPU0_G1_CPU1_G3_TX_DP<9>")
	)
	(segment
		(start 120.891808 -229.416864)
		(end 120.854724 -229.4382)
		(width 0.1143)
		(layer "In15.Cu")
		(net "GMI_CPU0_G1_CPU1_G3_TX_DP<9>")
	)
	(segment
		(start 120.852692 -223.889062)
		(end 120.891808 -223.911922)
		(width 0.1143)
		(layer "In15.Cu")
		(net "GMI_CPU0_G1_CPU1_G3_TX_DP<9>")
	)
	(segment
		(start 350.604074 -236.87151)
		(end 350.64319 -236.84865)
		(width 0.1143)
		(layer "In15.Cu")
		(net "GMI_CPU0_G1_CPU1_G3_TX_DP<9>")
	)
	(segment
		(start 350.64319 -244.019578)
		(end 350.604074 -243.996718)
		(width 0.1143)
		(layer "In15.Cu")
		(net "GMI_CPU0_G1_CPU1_G3_TX_DP<9>")
	)
	(segment
		(start 166.62908 -182.458868)
		(end 161.749994 -184.208166)
		(width 0.14224)
		(layer "In15.Cu")
		(net "GMI_CPU0_G1_CPU1_G3_TX_DP<9>")
	)
	(segment
		(start 350.573594 -232.029254)
		(end 350.604074 -232.011474)
		(width 0.1143)
		(layer "In15.Cu")
		(net "GMI_CPU0_G1_CPU1_G3_TX_DP<9>")
	)
	(segment
		(start 120.92305 -222.310198)
		(end 120.924066 -222.31096)
		(width 0.1143)
		(layer "In15.Cu")
		(net "GMI_CPU0_G1_CPU1_G3_TX_DP<9>")
	)
	(segment
		(start 120.891808 -236.871764)
		(end 120.922288 -236.889544)
		(width 0.1143)
		(layer "In15.Cu")
		(net "GMI_CPU0_G1_CPU1_G3_TX_DP<9>")
	)
	(segment
		(start 120.852692 -243.328952)
		(end 120.891808 -243.351812)
		(width 0.1143)
		(layer "In15.Cu")
		(net "GMI_CPU0_G1_CPU1_G3_TX_DP<9>")
	)
	(segment
		(start 120.922288 -235.879132)
		(end 120.891808 -235.896912)
		(width 0.1143)
		(layer "In15.Cu")
		(net "GMI_CPU0_G1_CPU1_G3_TX_DP<9>")
	)
	(segment
		(start 120.891808 -239.136936)
		(end 120.852692 -239.159796)
		(width 0.1143)
		(layer "In15.Cu")
		(net "GMI_CPU0_G1_CPU1_G3_TX_DP<9>")
	)
	(segment
		(start 350.573594 -236.88929)
		(end 350.604074 -236.87151)
		(width 0.1143)
		(layer "In15.Cu")
		(net "GMI_CPU0_G1_CPU1_G3_TX_DP<9>")
	)
	(segment
		(start 120.852692 -231.988868)
		(end 120.891808 -232.011728)
		(width 0.1143)
		(layer "In15.Cu")
		(net "GMI_CPU0_G1_CPU1_G3_TX_DP<9>")
	)
	(segment
		(start 350.573594 -233.649266)
		(end 350.604074 -233.631486)
		(width 0.1143)
		(layer "In15.Cu")
		(net "GMI_CPU0_G1_CPU1_G3_TX_DP<9>")
	)
	(segment
		(start 120.58015 -221.066106)
		(end 120.58015 -221.277942)
		(width 0.1143)
		(layer "In15.Cu")
		(net "GMI_CPU0_G1_CPU1_G3_TX_DP<9>")
	)
	(segment
		(start 120.852692 -228.749098)
		(end 120.891808 -228.771958)
		(width 0.1143)
		(layer "In15.Cu")
		(net "GMI_CPU0_G1_CPU1_G3_TX_DP<9>")
	)
	(segment
		(start 120.853454 -222.270066)
		(end 120.92305 -222.310198)
		(width 0.1143)
		(layer "In15.Cu")
		(net "GMI_CPU0_G1_CPU1_G3_TX_DP<9>")
	)
	(segment
		(start 350.13519 -225.367342)
		(end 350.134174 -225.366834)
		(width 0.1143)
		(layer "In15.Cu")
		(net "GMI_CPU0_G1_CPU1_G3_TX_DP<9>")
	)
	(segment
		(start 120.92432 -229.398068)
		(end 120.891808 -229.416864)
		(width 0.1143)
		(layer "In15.Cu")
		(net "GMI_CPU0_G1_CPU1_G3_TX_DP<9>")
	)
	(segment
		(start 120.852692 -227.129086)
		(end 120.891808 -227.151946)
		(width 0.1143)
		(layer "In15.Cu")
		(net "GMI_CPU0_G1_CPU1_G3_TX_DP<9>")
	)
	(segment
		(start 120.891808 -234.2769)
		(end 120.852692 -234.29976)
		(width 0.1143)
		(layer "In15.Cu")
		(net "GMI_CPU0_G1_CPU1_G3_TX_DP<9>")
	)
	(segment
		(start 120.891808 -242.37696)
		(end 120.852692 -242.39982)
		(width 0.1143)
		(layer "In15.Cu")
		(net "GMI_CPU0_G1_CPU1_G3_TX_DP<9>")
	)
	(segment
		(start 350.604074 -233.631486)
		(end 350.64319 -233.608626)
		(width 0.1143)
		(layer "In15.Cu")
		(net "GMI_CPU0_G1_CPU1_G3_TX_DP<9>")
	)
	(segment
		(start 350.604074 -242.376706)
		(end 350.573594 -242.358926)
		(width 0.1143)
		(layer "In15.Cu")
		(net "GMI_CPU0_G1_CPU1_G3_TX_DP<9>")
	)
	(segment
		(start 350.573594 -235.269278)
		(end 350.604074 -235.251498)
		(width 0.1143)
		(layer "In15.Cu")
		(net "GMI_CPU0_G1_CPU1_G3_TX_DP<9>")
	)
	(segment
		(start 350.604074 -227.151692)
		(end 350.64319 -227.128832)
		(width 0.1143)
		(layer "In15.Cu")
		(net "GMI_CPU0_G1_CPU1_G3_TX_DP<9>")
	)
	(segment
		(start 350.129856 -225.364294)
		(end 350.12884 -225.363786)
		(width 0.1143)
		(layer "In15.Cu")
		(net "GMI_CPU0_G1_CPU1_G3_TX_DP<9>")
	)
	(segment
		(start 120.891808 -228.771958)
		(end 120.922288 -228.789738)
		(width 0.1143)
		(layer "In15.Cu")
		(net "GMI_CPU0_G1_CPU1_G3_TX_DP<9>")
	)
	(segment
		(start 350.130618 -225.364802)
		(end 350.129856 -225.364294)
		(width 0.1143)
		(layer "In15.Cu")
		(net "GMI_CPU0_G1_CPU1_G3_TX_DP<9>")
	)
	(arc
		(start 350.416622 -229.094284)
		(mid 350.458171 -228.922862)
		(end 350.573594 -228.789484)
		(width 0.1143)
		(layer "In15.Cu")
		(net "GMI_CPU0_G1_CPU1_G3_TX_DP<9>")
	)
	(arc
		(start 120.922288 -243.369592)
		(mid 121.079265 -243.674392)
		(end 120.922288 -243.979192)
		(width 0.1143)
		(layer "In15.Cu")
		(net "GMI_CPU0_G1_CPU1_G3_TX_DP<9>")
	)
	(arc
		(start 121.07926 -229.094538)
		(mid 121.038294 -229.264944)
		(end 120.92432 -229.398068)
		(width 0.1143)
		(layer "In15.Cu")
		(net "GMI_CPU0_G1_CPU1_G3_TX_DP<9>")
	)
	(arc
		(start 120.382538 -244.829838)
		(mid 120.203725 -245.032188)
		(end 120.139206 -245.294404)
		(width 0.1143)
		(layer "In15.Cu")
		(net "GMI_CPU0_G1_CPU1_G3_TX_DP<9>")
	)
	(arc
		(start 351.583244 -245.63959)
		(mid 351.582863 -245.639336)
		(end 351.582482 -245.639082)
		(width 0.1143)
		(layer "In15.Cu")
		(net "GMI_CPU0_G1_CPU1_G3_TX_DP<9>")
	)
	(arc
		(start 120.922288 -236.889544)
		(mid 121.079265 -237.194344)
		(end 120.922288 -237.499144)
		(width 0.1143)
		(layer "In15.Cu")
		(net "GMI_CPU0_G1_CPU1_G3_TX_DP<9>")
	)
	(arc
		(start 350.64319 -228.748844)
		(mid 350.886517 -228.284278)
		(end 350.64319 -227.819712)
		(width 0.1143)
		(layer "In15.Cu")
		(net "GMI_CPU0_G1_CPU1_G3_TX_DP<9>")
	)
	(arc
		(start 119.679212 -245.998746)
		(mid 119.677189 -246.010156)
		(end 119.675402 -246.021606)
		(width 0.1143)
		(layer "In15.Cu")
		(net "GMI_CPU0_G1_CPU1_G3_TX_DP<9>")
	)
	(arc
		(start 120.852692 -232.679748)
		(mid 120.609365 -233.144314)
		(end 120.852692 -233.60888)
		(width 0.1143)
		(layer "In15.Cu")
		(net "GMI_CPU0_G1_CPU1_G3_TX_DP<9>")
	)
	(arc
		(start 120.139206 -245.294404)
		(mid 120.097657 -245.465826)
		(end 119.982234 -245.599204)
		(width 0.1143)
		(layer "In15.Cu")
		(net "GMI_CPU0_G1_CPU1_G3_TX_DP<9>")
	)
	(arc
		(start 350.64319 -236.84865)
		(mid 350.886517 -236.384084)
		(end 350.64319 -235.919518)
		(width 0.1143)
		(layer "In15.Cu")
		(net "GMI_CPU0_G1_CPU1_G3_TX_DP<9>")
	)
	(arc
		(start 120.922288 -225.549714)
		(mid 121.079265 -225.854514)
		(end 120.922288 -226.159314)
		(width 0.1143)
		(layer "In15.Cu")
		(net "GMI_CPU0_G1_CPU1_G3_TX_DP<9>")
	)
	(arc
		(start 350.64319 -231.988614)
		(mid 350.886517 -231.524048)
		(end 350.64319 -231.059482)
		(width 0.1143)
		(layer "In15.Cu")
		(net "GMI_CPU0_G1_CPU1_G3_TX_DP<9>")
	)
	(arc
		(start 120.922288 -228.789738)
		(mid 121.037715 -228.923114)
		(end 121.07926 -229.094538)
		(width 0.1143)
		(layer "In15.Cu")
		(net "GMI_CPU0_G1_CPU1_G3_TX_DP<9>")
	)
	(arc
		(start 350.573594 -243.978938)
		(mid 350.416617 -243.674138)
		(end 350.573594 -243.369338)
		(width 0.1143)
		(layer "In15.Cu")
		(net "GMI_CPU0_G1_CPU1_G3_TX_DP<9>")
	)
	(arc
		(start 120.922288 -223.929702)
		(mid 121.079265 -224.234502)
		(end 120.922288 -224.539302)
		(width 0.1143)
		(layer "In15.Cu")
		(net "GMI_CPU0_G1_CPU1_G3_TX_DP<9>")
	)
	(arc
		(start 120.922288 -238.509556)
		(mid 121.079265 -238.814356)
		(end 120.922288 -239.119156)
		(width 0.1143)
		(layer "In15.Cu")
		(net "GMI_CPU0_G1_CPU1_G3_TX_DP<9>")
	)
	(arc
		(start 350.571562 -229.397814)
		(mid 350.457633 -229.264667)
		(end 350.416622 -229.094284)
		(width 0.1143)
		(layer "In15.Cu")
		(net "GMI_CPU0_G1_CPU1_G3_TX_DP<9>")
	)
	(arc
		(start 350.416622 -225.85426)
		(mid 350.352107 -225.592041)
		(end 350.17329 -225.389694)
		(width 0.1143)
		(layer "In15.Cu")
		(net "GMI_CPU0_G1_CPU1_G3_TX_DP<9>")
	)
	(arc
		(start 350.571562 -231.017826)
		(mid 350.457633 -230.884679)
		(end 350.416622 -230.714296)
		(width 0.1143)
		(layer "In15.Cu")
		(net "GMI_CPU0_G1_CPU1_G3_TX_DP<9>")
	)
	(arc
		(start 120.60936 -244.484398)
		(mid 120.568105 -244.655369)
		(end 120.453404 -244.78869)
		(width 0.1143)
		(layer "In15.Cu")
		(net "GMI_CPU0_G1_CPU1_G3_TX_DP<9>")
	)
	(arc
		(start 351.042224 -244.788182)
		(mid 350.927697 -244.654942)
		(end 350.886522 -244.484144)
		(width 0.1143)
		(layer "In15.Cu")
		(net "GMI_CPU0_G1_CPU1_G3_TX_DP<9>")
	)
	(arc
		(start 350.573594 -239.118902)
		(mid 350.416617 -238.814102)
		(end 350.573594 -238.509302)
		(width 0.1143)
		(layer "In15.Cu")
		(net "GMI_CPU0_G1_CPU1_G3_TX_DP<9>")
	)
	(arc
		(start 120.60936 -229.90429)
		(mid 120.674596 -230.167881)
		(end 120.855232 -230.370634)
		(width 0.1143)
		(layer "In15.Cu")
		(net "GMI_CPU0_G1_CPU1_G3_TX_DP<9>")
	)
	(arc
		(start 120.922288 -227.169726)
		(mid 121.079265 -227.474526)
		(end 120.922288 -227.779326)
		(width 0.1143)
		(layer "In15.Cu")
		(net "GMI_CPU0_G1_CPU1_G3_TX_DP<9>")
	)
	(arc
		(start 120.922288 -230.40975)
		(mid 121.037715 -230.543126)
		(end 121.07926 -230.71455)
		(width 0.1143)
		(layer "In15.Cu")
		(net "GMI_CPU0_G1_CPU1_G3_TX_DP<9>")
	)
	(arc
		(start 120.852692 -234.29976)
		(mid 120.609365 -234.764326)
		(end 120.852692 -235.228892)
		(width 0.1143)
		(layer "In15.Cu")
		(net "GMI_CPU0_G1_CPU1_G3_TX_DP<9>")
	)
	(arc
		(start 120.852692 -224.579942)
		(mid 120.609365 -225.044508)
		(end 120.852692 -225.509074)
		(width 0.1143)
		(layer "In15.Cu")
		(net "GMI_CPU0_G1_CPU1_G3_TX_DP<9>")
	)
	(arc
		(start 350.64319 -233.608626)
		(mid 350.886517 -233.14406)
		(end 350.64319 -232.679494)
		(width 0.1143)
		(layer "In15.Cu")
		(net "GMI_CPU0_G1_CPU1_G3_TX_DP<9>")
	)
	(arc
		(start 120.852692 -231.059736)
		(mid 120.609365 -231.524302)
		(end 120.852692 -231.988868)
		(width 0.1143)
		(layer "In15.Cu")
		(net "GMI_CPU0_G1_CPU1_G3_TX_DP<9>")
	)
	(arc
		(start 350.573594 -227.779072)
		(mid 350.416617 -227.474272)
		(end 350.573594 -227.169472)
		(width 0.1143)
		(layer "In15.Cu")
		(net "GMI_CPU0_G1_CPU1_G3_TX_DP<9>")
	)
	(arc
		(start 120.852692 -244.019832)
		(mid 120.673879 -244.222182)
		(end 120.60936 -244.484398)
		(width 0.1143)
		(layer "In15.Cu")
		(net "GMI_CPU0_G1_CPU1_G3_TX_DP<9>")
	)
	(arc
		(start 349.703136 -223.888808)
		(mid 349.946463 -223.424242)
		(end 349.703136 -222.959676)
		(width 0.1143)
		(layer "In15.Cu")
		(net "GMI_CPU0_G1_CPU1_G3_TX_DP<9>")
	)
	(arc
		(start 120.852692 -240.779808)
		(mid 120.609365 -241.244374)
		(end 120.852692 -241.70894)
		(width 0.1143)
		(layer "In15.Cu")
		(net "GMI_CPU0_G1_CPU1_G3_TX_DP<9>")
	)
	(arc
		(start 120.852692 -242.39982)
		(mid 120.609365 -242.864386)
		(end 120.852692 -243.328952)
		(width 0.1143)
		(layer "In15.Cu")
		(net "GMI_CPU0_G1_CPU1_G3_TX_DP<9>")
	)
	(arc
		(start 120.852692 -222.95993)
		(mid 120.609365 -223.424496)
		(end 120.852692 -223.889062)
		(width 0.1143)
		(layer "In15.Cu")
		(net "GMI_CPU0_G1_CPU1_G3_TX_DP<9>")
	)
	(arc
		(start 351.82048 -246.021352)
		(mid 351.818692 -246.009903)
		(end 351.81667 -245.998492)
		(width 0.1143)
		(layer "In15.Cu")
		(net "GMI_CPU0_G1_CPU1_G3_TX_DP<9>")
	)
	(arc
		(start 350.886522 -229.904036)
		(mid 350.822007 -229.641817)
		(end 350.64319 -229.43947)
		(width 0.1143)
		(layer "In15.Cu")
		(net "GMI_CPU0_G1_CPU1_G3_TX_DP<9>")
	)
	(arc
		(start 351.368868 -245.303548)
		(mid 351.292903 -245.020406)
		(end 351.085404 -244.813328)
		(width 0.1143)
		(layer "In15.Cu")
		(net "GMI_CPU0_G1_CPU1_G3_TX_DP<9>")
	)
	(arc
		(start 350.64319 -238.468662)
		(mid 350.886517 -238.004096)
		(end 350.64319 -237.53953)
		(width 0.1143)
		(layer "In15.Cu")
		(net "GMI_CPU0_G1_CPU1_G3_TX_DP<9>")
	)
	(arc
		(start 351.54362 -245.616476)
		(mid 351.415669 -245.488202)
		(end 351.368868 -245.3132)
		(width 0.1143)
		(layer "In15.Cu")
		(net "GMI_CPU0_G1_CPU1_G3_TX_DP<9>")
	)
	(arc
		(start 120.924066 -222.31096)
		(mid 121.038219 -222.444036)
		(end 121.07926 -222.61449)
		(width 0.1143)
		(layer "In15.Cu")
		(net "GMI_CPU0_G1_CPU1_G3_TX_DP<9>")
	)
	(arc
		(start 350.64319 -240.088674)
		(mid 350.886517 -239.624108)
		(end 350.64319 -239.159542)
		(width 0.1143)
		(layer "In15.Cu")
		(net "GMI_CPU0_G1_CPU1_G3_TX_DP<9>")
	)
	(arc
		(start 349.162878 -222.108776)
		(mid 349.047827 -221.975421)
		(end 349.006414 -221.80423)
		(width 0.1143)
		(layer "In15.Cu")
		(net "GMI_CPU0_G1_CPU1_G3_TX_DP<9>")
	)
	(arc
		(start 350.573594 -237.49889)
		(mid 350.416617 -237.19409)
		(end 350.573594 -236.88929)
		(width 0.1143)
		(layer "In15.Cu")
		(net "GMI_CPU0_G1_CPU1_G3_TX_DP<9>")
	)
	(arc
		(start 120.852692 -237.539784)
		(mid 120.609365 -238.00435)
		(end 120.852692 -238.468916)
		(width 0.1143)
		(layer "In15.Cu")
		(net "GMI_CPU0_G1_CPU1_G3_TX_DP<9>")
	)
	(arc
		(start 120.852692 -227.819966)
		(mid 120.609365 -228.284532)
		(end 120.852692 -228.749098)
		(width 0.1143)
		(layer "In15.Cu")
		(net "GMI_CPU0_G1_CPU1_G3_TX_DP<9>")
	)
	(arc
		(start 120.852692 -229.439724)
		(mid 120.673879 -229.642074)
		(end 120.60936 -229.90429)
		(width 0.1143)
		(layer "In15.Cu")
		(net "GMI_CPU0_G1_CPU1_G3_TX_DP<9>")
	)
	(arc
		(start 120.922288 -235.269532)
		(mid 121.079265 -235.574332)
		(end 120.922288 -235.879132)
		(width 0.1143)
		(layer "In15.Cu")
		(net "GMI_CPU0_G1_CPU1_G3_TX_DP<9>")
	)
	(arc
		(start 350.102424 -225.348546)
		(mid 349.987748 -225.215212)
		(end 349.946468 -225.044254)
		(width 0.1143)
		(layer "In15.Cu")
		(net "GMI_CPU0_G1_CPU1_G3_TX_DP<9>")
	)
	(arc
		(start 121.07926 -222.61449)
		(mid 121.037711 -222.785912)
		(end 120.922288 -222.91929)
		(width 0.1143)
		(layer "In15.Cu")
		(net "GMI_CPU0_G1_CPU1_G3_TX_DP<9>")
	)
	(arc
		(start 350.64065 -230.37038)
		(mid 350.821302 -230.167635)
		(end 350.886522 -229.904036)
		(width 0.1143)
		(layer "In15.Cu")
		(net "GMI_CPU0_G1_CPU1_G3_TX_DP<9>")
	)
	(arc
		(start 350.64319 -227.128832)
		(mid 350.886517 -226.664266)
		(end 350.64319 -226.1997)
		(width 0.1143)
		(layer "In15.Cu")
		(net "GMI_CPU0_G1_CPU1_G3_TX_DP<9>")
	)
	(arc
		(start 350.416622 -230.714296)
		(mid 350.458171 -230.542874)
		(end 350.573594 -230.409496)
		(width 0.1143)
		(layer "In15.Cu")
		(net "GMI_CPU0_G1_CPU1_G3_TX_DP<9>")
	)
	(arc
		(start 350.573594 -226.15906)
		(mid 350.458167 -226.025684)
		(end 350.416622 -225.85426)
		(width 0.1143)
		(layer "In15.Cu")
		(net "GMI_CPU0_G1_CPU1_G3_TX_DP<9>")
	)
	(arc
		(start 350.64319 -235.228638)
		(mid 350.886517 -234.764072)
		(end 350.64319 -234.299506)
		(width 0.1143)
		(layer "In15.Cu")
		(net "GMI_CPU0_G1_CPU1_G3_TX_DP<9>")
	)
	(arc
		(start 349.63354 -222.919036)
		(mid 349.518113 -222.78566)
		(end 349.476568 -222.614236)
		(width 0.1143)
		(layer "In15.Cu")
		(net "GMI_CPU0_G1_CPU1_G3_TX_DP<9>")
	)
	(arc
		(start 351.81667 -245.998492)
		(mid 351.735237 -245.796094)
		(end 351.583244 -245.63959)
		(width 0.1143)
		(layer "In15.Cu")
		(net "GMI_CPU0_G1_CPU1_G3_TX_DP<9>")
	)
	(arc
		(start 350.573594 -232.638854)
		(mid 350.416617 -232.334054)
		(end 350.573594 -232.029254)
		(width 0.1143)
		(layer "In15.Cu")
		(net "GMI_CPU0_G1_CPU1_G3_TX_DP<9>")
	)
	(arc
		(start 350.64319 -241.708686)
		(mid 350.886517 -241.24412)
		(end 350.64319 -240.779554)
		(width 0.1143)
		(layer "In15.Cu")
		(net "GMI_CPU0_G1_CPU1_G3_TX_DP<9>")
	)
	(arc
		(start 350.573594 -235.878878)
		(mid 350.416617 -235.574078)
		(end 350.573594 -235.269278)
		(width 0.1143)
		(layer "In15.Cu")
		(net "GMI_CPU0_G1_CPU1_G3_TX_DP<9>")
	)
	(arc
		(start 349.476568 -222.614236)
		(mid 349.412053 -222.352017)
		(end 349.233236 -222.14967)
		(width 0.1143)
		(layer "In15.Cu")
		(net "GMI_CPU0_G1_CPU1_G3_TX_DP<9>")
	)
	(arc
		(start 120.608852 -221.804484)
		(mid 120.673724 -222.067447)
		(end 120.853454 -222.270066)
		(width 0.1143)
		(layer "In15.Cu")
		(net "GMI_CPU0_G1_CPU1_G3_TX_DP<9>")
	)
	(arc
		(start 350.64319 -243.328698)
		(mid 350.886517 -242.864132)
		(end 350.64319 -242.399566)
		(width 0.1143)
		(layer "In15.Cu")
		(net "GMI_CPU0_G1_CPU1_G3_TX_DP<9>")
	)
	(arc
		(start 350.573594 -242.358926)
		(mid 350.416617 -242.054126)
		(end 350.573594 -241.749326)
		(width 0.1143)
		(layer "In15.Cu")
		(net "GMI_CPU0_G1_CPU1_G3_TX_DP<9>")
	)
	(arc
		(start 120.852692 -235.919772)
		(mid 120.609365 -236.384338)
		(end 120.852692 -236.848904)
		(width 0.1143)
		(layer "In15.Cu")
		(net "GMI_CPU0_G1_CPU1_G3_TX_DP<9>")
	)
	(arc
		(start 120.852692 -239.159796)
		(mid 120.609365 -239.624362)
		(end 120.852692 -240.088928)
		(width 0.1143)
		(layer "In15.Cu")
		(net "GMI_CPU0_G1_CPU1_G3_TX_DP<9>")
	)
	(arc
		(start 120.852692 -226.199954)
		(mid 120.609365 -226.66452)
		(end 120.852692 -227.129086)
		(width 0.1143)
		(layer "In15.Cu")
		(net "GMI_CPU0_G1_CPU1_G3_TX_DP<9>")
	)
	(arc
		(start 120.922288 -232.029508)
		(mid 121.079265 -232.334308)
		(end 120.922288 -232.639108)
		(width 0.1143)
		(layer "In15.Cu")
		(net "GMI_CPU0_G1_CPU1_G3_TX_DP<9>")
	)
	(arc
		(start 349.946468 -225.044254)
		(mid 349.881953 -224.782035)
		(end 349.703136 -224.579688)
		(width 0.1143)
		(layer "In15.Cu")
		(net "GMI_CPU0_G1_CPU1_G3_TX_DP<9>")
	)
	(arc
		(start 120.922288 -240.129568)
		(mid 121.079265 -240.434368)
		(end 120.922288 -240.739168)
		(width 0.1143)
		(layer "In15.Cu")
		(net "GMI_CPU0_G1_CPU1_G3_TX_DP<9>")
	)
	(arc
		(start 119.912638 -245.639844)
		(mid 119.760651 -245.796352)
		(end 119.679212 -245.998746)
		(width 0.1143)
		(layer "In15.Cu")
		(net "GMI_CPU0_G1_CPU1_G3_TX_DP<9>")
	)
	(arc
		(start 350.573594 -240.738914)
		(mid 350.416617 -240.434114)
		(end 350.573594 -240.129314)
		(width 0.1143)
		(layer "In15.Cu")
		(net "GMI_CPU0_G1_CPU1_G3_TX_DP<9>")
	)
	(arc
		(start 350.886522 -244.484144)
		(mid 350.822007 -244.221925)
		(end 350.64319 -244.019578)
		(width 0.1143)
		(layer "In15.Cu")
		(net "GMI_CPU0_G1_CPU1_G3_TX_DP<9>")
	)
	(arc
		(start 120.922288 -233.64952)
		(mid 121.079265 -233.95432)
		(end 120.922288 -234.25912)
		(width 0.1143)
		(layer "In15.Cu")
		(net "GMI_CPU0_G1_CPU1_G3_TX_DP<9>")
	)
	(arc
		(start 120.922288 -241.74958)
		(mid 121.079265 -242.05438)
		(end 120.922288 -242.35918)
		(width 0.1143)
		(layer "In15.Cu")
		(net "GMI_CPU0_G1_CPU1_G3_TX_DP<9>")
	)
	(arc
		(start 121.07926 -230.71455)
		(mid 121.038294 -230.884956)
		(end 120.92432 -231.01808)
		(width 0.1143)
		(layer "In15.Cu")
		(net "GMI_CPU0_G1_CPU1_G3_TX_DP<9>")
	)
	(arc
		(start 349.63354 -224.539048)
		(mid 349.476563 -224.234248)
		(end 349.63354 -223.929448)
		(width 0.1143)
		(layer "In15.Cu")
		(net "GMI_CPU0_G1_CPU1_G3_TX_DP<9>")
	)
	(arc
		(start 350.573594 -234.258866)
		(mid 350.416617 -233.954066)
		(end 350.573594 -233.649266)
		(width 0.1143)
		(layer "In15.Cu")
		(net "GMI_CPU0_G1_CPU1_G3_TX_DP<9>")
	)
	(segment
		(start 352.668078 -244.750082)
		(end 352.201226 -244.484144)
		(width 0.12954)
		(layer "F.Cu")
		(net "GMI_CPU0_G1_CPU1_G3_TX_DP<8>")
	)
	(segment
		(start 118.827804 -244.750336)
		(end 119.294656 -244.484398)
		(width 0.12954)
		(layer "F.Cu")
		(net "GMI_CPU0_G1_CPU1_G3_TX_DP<8>")
	)
	(segment
		(start 302.896016 -182.311548)
		(end 166.385494 -181.515766)
		(width 0.14224)
		(layer "In15.Cu")
		(net "GMI_CPU0_G1_CPU1_G3_TX_DP<8>")
	)
	(segment
		(start 351.543366 -243.99621)
		(end 351.512378 -243.97843)
		(width 0.1143)
		(layer "In15.Cu")
		(net "GMI_CPU0_G1_CPU1_G3_TX_DP<8>")
	)
	(segment
		(start 119.982234 -239.119156)
		(end 119.951754 -239.136936)
		(width 0.1143)
		(layer "In15.Cu")
		(net "GMI_CPU0_G1_CPU1_G3_TX_DP<8>")
	)
	(segment
		(start 160.978342 -183.449214)
		(end 155.589986 -187.867798)
		(width 0.14224)
		(layer "In15.Cu")
		(net "GMI_CPU0_G1_CPU1_G3_TX_DP<8>")
	)
	(segment
		(start 119.63527 -221.066106)
		(end 119.63527 -221.277942)
		(width 0.1143)
		(layer "In15.Cu")
		(net "GMI_CPU0_G1_CPU1_G3_TX_DP<8>")
	)
	(segment
		(start 119.63527 -221.277942)
		(end 119.669052 -221.311724)
		(width 0.1143)
		(layer "In15.Cu")
		(net "GMI_CPU0_G1_CPU1_G3_TX_DP<8>")
	)
	(segment
		(start 351.544128 -243.351558)
		(end 351.545144 -243.35105)
		(width 0.1143)
		(layer "In15.Cu")
		(net "GMI_CPU0_G1_CPU1_G3_TX_DP<8>")
	)
	(segment
		(start 119.951754 -226.177094)
		(end 119.912638 -226.199954)
		(width 0.1143)
		(layer "In15.Cu")
		(net "GMI_CPU0_G1_CPU1_G3_TX_DP<8>")
	)
	(segment
		(start 351.5487 -235.899198)
		(end 351.547176 -235.898436)
		(width 0.1143)
		(layer "In15.Cu")
		(net "GMI_CPU0_G1_CPU1_G3_TX_DP<8>")
	)
	(segment
		(start 351.540572 -230.393748)
		(end 351.542096 -230.392986)
		(width 0.1143)
		(layer "In15.Cu")
		(net "GMI_CPU0_G1_CPU1_G3_TX_DP<8>")
	)
	(segment
		(start 119.982234 -232.639108)
		(end 119.951754 -232.656888)
		(width 0.1143)
		(layer "In15.Cu")
		(net "GMI_CPU0_G1_CPU1_G3_TX_DP<8>")
	)
	(segment
		(start 119.982234 -224.539302)
		(end 119.951754 -224.557082)
		(width 0.1143)
		(layer "In15.Cu")
		(net "GMI_CPU0_G1_CPU1_G3_TX_DP<8>")
	)
	(segment
		(start 351.545144 -233.630978)
		(end 351.583244 -233.608626)
		(width 0.1143)
		(layer "In15.Cu")
		(net "GMI_CPU0_G1_CPU1_G3_TX_DP<8>")
	)
	(segment
		(start 351.543366 -233.631994)
		(end 351.544128 -233.631486)
		(width 0.1143)
		(layer "In15.Cu")
		(net "GMI_CPU0_G1_CPU1_G3_TX_DP<8>")
	)
	(segment
		(start 119.951754 -225.531934)
		(end 119.982234 -225.549714)
		(width 0.1143)
		(layer "In15.Cu")
		(net "GMI_CPU0_G1_CPU1_G3_TX_DP<8>")
	)
	(segment
		(start 349.946468 -221.80423)
		(end 349.946468 -221.128844)
		(width 0.1143)
		(layer "In15.Cu")
		(net "GMI_CPU0_G1_CPU1_G3_TX_DP<8>")
	)
	(segment
		(start 119.592598 -244.484398)
		(end 119.294656 -244.484398)
		(width 0.1143)
		(layer "In15.Cu")
		(net "GMI_CPU0_G1_CPU1_G3_TX_DP<8>")
	)
	(segment
		(start 119.951754 -227.797106)
		(end 119.912638 -227.819966)
		(width 0.1143)
		(layer "In15.Cu")
		(net "GMI_CPU0_G1_CPU1_G3_TX_DP<8>")
	)
	(segment
		(start 351.543366 -230.392224)
		(end 351.544128 -230.391716)
		(width 0.1143)
		(layer "In15.Cu")
		(net "GMI_CPU0_G1_CPU1_G3_TX_DP<8>")
	)
	(segment
		(start 351.57537 -235.914692)
		(end 351.549462 -235.899706)
		(width 0.1143)
		(layer "In15.Cu")
		(net "GMI_CPU0_G1_CPU1_G3_TX_DP<8>")
	)
	(segment
		(start 119.951754 -235.896912)
		(end 119.912638 -235.919772)
		(width 0.1143)
		(layer "In15.Cu")
		(net "GMI_CPU0_G1_CPU1_G3_TX_DP<8>")
	)
	(segment
		(start 119.951754 -239.136936)
		(end 119.912638 -239.159796)
		(width 0.1143)
		(layer "In15.Cu")
		(net "GMI_CPU0_G1_CPU1_G3_TX_DP<8>")
	)
	(segment
		(start 166.385494 -181.515766)
		(end 160.978342 -183.449214)
		(width 0.14224)
		(layer "In15.Cu")
		(net "GMI_CPU0_G1_CPU1_G3_TX_DP<8>")
	)
	(segment
		(start 351.550478 -228.767894)
		(end 351.583244 -228.748844)
		(width 0.1143)
		(layer "In15.Cu")
		(net "GMI_CPU0_G1_CPU1_G3_TX_DP<8>")
	)
	(segment
		(start 350.126046 -222.122238)
		(end 350.102424 -222.108522)
		(width 0.1143)
		(layer "In15.Cu")
		(net "GMI_CPU0_G1_CPU1_G3_TX_DP<8>")
	)
	(segment
		(start 350.133412 -222.126302)
		(end 350.126046 -222.122238)
		(width 0.1143)
		(layer "In15.Cu")
		(net "GMI_CPU0_G1_CPU1_G3_TX_DP<8>")
	)
	(segment
		(start 119.982234 -227.779326)
		(end 119.951754 -227.797106)
		(width 0.1143)
		(layer "In15.Cu")
		(net "GMI_CPU0_G1_CPU1_G3_TX_DP<8>")
	)
	(segment
		(start 122.348244 -214.582248)
		(end 119.58955 -219.304362)
		(width 0.14224)
		(layer "In15.Cu")
		(net "GMI_CPU0_G1_CPU1_G3_TX_DP<8>")
	)
	(segment
		(start 119.951754 -232.011728)
		(end 119.982234 -232.029508)
		(width 0.1143)
		(layer "In15.Cu")
		(net "GMI_CPU0_G1_CPU1_G3_TX_DP<8>")
	)
	(segment
		(start 351.544128 -243.996718)
		(end 351.543366 -243.99621)
		(width 0.1143)
		(layer "In15.Cu")
		(net "GMI_CPU0_G1_CPU1_G3_TX_DP<8>")
	)
	(segment
		(start 350.17329 -222.14967)
		(end 350.13519 -222.127318)
		(width 0.1143)
		(layer "In15.Cu")
		(net "GMI_CPU0_G1_CPU1_G3_TX_DP<8>")
	)
	(segment
		(start 119.912638 -225.509074)
		(end 119.951754 -225.531934)
		(width 0.1143)
		(layer "In15.Cu")
		(net "GMI_CPU0_G1_CPU1_G3_TX_DP<8>")
	)
	(segment
		(start 351.54362 -241.7318)
		(end 351.564956 -241.719354)
		(width 0.1143)
		(layer "In15.Cu")
		(net "GMI_CPU0_G1_CPU1_G3_TX_DP<8>")
	)
	(segment
		(start 351.564956 -235.239306)
		(end 351.56521 -235.239306)
		(width 0.1143)
		(layer "In15.Cu")
		(net "GMI_CPU0_G1_CPU1_G3_TX_DP<8>")
	)
	(segment
		(start 119.913654 -222.270066)
		(end 119.98325 -222.310198)
		(width 0.1143)
		(layer "In15.Cu")
		(net "GMI_CPU0_G1_CPU1_G3_TX_DP<8>")
	)
	(segment
		(start 351.544128 -228.771704)
		(end 351.545144 -228.771196)
		(width 0.1143)
		(layer "In15.Cu")
		(net "GMI_CPU0_G1_CPU1_G3_TX_DP<8>")
	)
	(segment
		(start 351.11055 -225.387916)
		(end 351.07753 -225.368866)
		(width 0.1143)
		(layer "In15.Cu")
		(net "GMI_CPU0_G1_CPU1_G3_TX_DP<8>")
	)
	(segment
		(start 351.546668 -228.77018)
		(end 351.548446 -228.769164)
		(width 0.1143)
		(layer "In15.Cu")
		(net "GMI_CPU0_G1_CPU1_G3_TX_DP<8>")
	)
	(segment
		(start 351.545144 -232.657142)
		(end 351.544128 -232.656634)
		(width 0.1143)
		(layer "In15.Cu")
		(net "GMI_CPU0_G1_CPU1_G3_TX_DP<8>")
	)
	(segment
		(start 351.5487 -240.759234)
		(end 351.536254 -240.752122)
		(width 0.1143)
		(layer "In15.Cu")
		(net "GMI_CPU0_G1_CPU1_G3_TX_DP<8>")
	)
	(segment
		(start 308.426358 -182.790846)
		(end 307.085746 -182.311548)
		(width 0.14224)
		(layer "In15.Cu")
		(net "GMI_CPU0_G1_CPU1_G3_TX_DP<8>")
	)
	(segment
		(start 119.912638 -235.228892)
		(end 119.951754 -235.251752)
		(width 0.1143)
		(layer "In15.Cu")
		(net "GMI_CPU0_G1_CPU1_G3_TX_DP<8>")
	)
	(segment
		(start 351.544128 -227.151692)
		(end 351.58045 -227.130864)
		(width 0.1143)
		(layer "In15.Cu")
		(net "GMI_CPU0_G1_CPU1_G3_TX_DP<8>")
	)
	(segment
		(start 119.912638 -238.468916)
		(end 119.951754 -238.491776)
		(width 0.1143)
		(layer "In15.Cu")
		(net "GMI_CPU0_G1_CPU1_G3_TX_DP<8>")
	)
	(segment
		(start 119.951754 -229.416864)
		(end 119.91467 -229.4382)
		(width 0.1143)
		(layer "In15.Cu")
		(net "GMI_CPU0_G1_CPU1_G3_TX_DP<8>")
	)
	(segment
		(start 351.583244 -227.819712)
		(end 351.544128 -227.796852)
		(width 0.1143)
		(layer "In15.Cu")
		(net "GMI_CPU0_G1_CPU1_G3_TX_DP<8>")
	)
	(segment
		(start 351.076006 -225.36785)
		(end 351.074228 -225.366834)
		(width 0.1143)
		(layer "In15.Cu")
		(net "GMI_CPU0_G1_CPU1_G3_TX_DP<8>")
	)
	(segment
		(start 351.564956 -236.859318)
		(end 351.56521 -236.859318)
		(width 0.1143)
		(layer "In15.Cu")
		(net "GMI_CPU0_G1_CPU1_G3_TX_DP<8>")
	)
	(segment
		(start 347.16466 -212.979)
		(end 314.63107 -186.303158)
		(width 0.14224)
		(layer "In15.Cu")
		(net "GMI_CPU0_G1_CPU1_G3_TX_DP<8>")
	)
	(segment
		(start 351.544128 -230.391716)
		(end 351.545144 -230.391208)
		(width 0.1143)
		(layer "In15.Cu")
		(net "GMI_CPU0_G1_CPU1_G3_TX_DP<8>")
	)
	(segment
		(start 350.604074 -224.556828)
		(end 350.573594 -224.539048)
		(width 0.1143)
		(layer "In15.Cu")
		(net "GMI_CPU0_G1_CPU1_G3_TX_DP<8>")
	)
	(segment
		(start 351.550478 -239.140238)
		(end 351.549462 -239.13973)
		(width 0.1143)
		(layer "In15.Cu")
		(net "GMI_CPU0_G1_CPU1_G3_TX_DP<8>")
	)
	(segment
		(start 351.544128 -232.011474)
		(end 351.545144 -232.010966)
		(width 0.1143)
		(layer "In15.Cu")
		(net "GMI_CPU0_G1_CPU1_G3_TX_DP<8>")
	)
	(segment
		(start 351.544128 -233.631486)
		(end 351.545144 -233.630978)
		(width 0.1143)
		(layer "In15.Cu")
		(net "GMI_CPU0_G1_CPU1_G3_TX_DP<8>")
	)
	(segment
		(start 351.56521 -235.239306)
		(end 351.583244 -235.228638)
		(width 0.1143)
		(layer "In15.Cu")
		(net "GMI_CPU0_G1_CPU1_G3_TX_DP<8>")
	)
	(segment
		(start 351.549462 -240.759742)
		(end 351.5487 -240.759234)
		(width 0.1143)
		(layer "In15.Cu")
		(net "GMI_CPU0_G1_CPU1_G3_TX_DP<8>")
	)
	(segment
		(start 351.543366 -243.352066)
		(end 351.544128 -243.351558)
		(width 0.1143)
		(layer "In15.Cu")
		(net "GMI_CPU0_G1_CPU1_G3_TX_DP<8>")
	)
	(segment
		(start 119.912638 -240.088928)
		(end 119.951754 -240.111788)
		(width 0.1143)
		(layer "In15.Cu")
		(net "GMI_CPU0_G1_CPU1_G3_TX_DP<8>")
	)
	(segment
		(start 350.604074 -223.911668)
		(end 350.64319 -223.888808)
		(width 0.1143)
		(layer "In15.Cu")
		(net "GMI_CPU0_G1_CPU1_G3_TX_DP<8>")
	)
	(segment
		(start 119.912638 -241.70894)
		(end 119.951754 -241.7318)
		(width 0.1143)
		(layer "In15.Cu")
		(net "GMI_CPU0_G1_CPU1_G3_TX_DP<8>")
	)
	(segment
		(start 119.91467 -229.4382)
		(end 119.912638 -229.439724)
		(width 0.1143)
		(layer "In15.Cu")
		(net "GMI_CPU0_G1_CPU1_G3_TX_DP<8>")
	)
	(segment
		(start 350.13519 -222.127318)
		(end 350.134174 -222.12681)
		(width 0.1143)
		(layer "In15.Cu")
		(net "GMI_CPU0_G1_CPU1_G3_TX_DP<8>")
	)
	(segment
		(start 351.582482 -239.159034)
		(end 351.550478 -239.140238)
		(width 0.1143)
		(layer "In15.Cu")
		(net "GMI_CPU0_G1_CPU1_G3_TX_DP<8>")
	)
	(segment
		(start 307.085746 -182.311548)
		(end 302.896016 -182.311548)
		(width 0.14224)
		(layer "In15.Cu")
		(net "GMI_CPU0_G1_CPU1_G3_TX_DP<8>")
	)
	(segment
		(start 119.912638 -228.749098)
		(end 119.951754 -228.771958)
		(width 0.1143)
		(layer "In15.Cu")
		(net "GMI_CPU0_G1_CPU1_G3_TX_DP<8>")
	)
	(segment
		(start 144.724628 -196.23405)
		(end 122.348244 -214.582248)
		(width 0.14224)
		(layer "In15.Cu")
		(net "GMI_CPU0_G1_CPU1_G3_TX_DP<8>")
	)
	(segment
		(start 351.074228 -225.366834)
		(end 351.042478 -225.348546)
		(width 0.1143)
		(layer "In15.Cu")
		(net "GMI_CPU0_G1_CPU1_G3_TX_DP<8>")
	)
	(segment
		(start 351.544128 -226.17684)
		(end 351.513394 -226.15906)
		(width 0.1143)
		(layer "In15.Cu")
		(net "GMI_CPU0_G1_CPU1_G3_TX_DP<8>")
	)
	(segment
		(start 351.512378 -227.16998)
		(end 351.544128 -227.151692)
		(width 0.1143)
		(layer "In15.Cu")
		(net "GMI_CPU0_G1_CPU1_G3_TX_DP<8>")
	)
	(segment
		(start 351.564956 -240.099342)
		(end 351.56521 -240.099342)
		(width 0.1143)
		(layer "In15.Cu")
		(net "GMI_CPU0_G1_CPU1_G3_TX_DP<8>")
	)
	(segment
		(start 351.54362 -235.251752)
		(end 351.564956 -235.239306)
		(width 0.1143)
		(layer "In15.Cu")
		(net "GMI_CPU0_G1_CPU1_G3_TX_DP<8>")
	)
	(segment
		(start 351.512378 -243.369846)
		(end 351.543366 -243.352066)
		(width 0.1143)
		(layer "In15.Cu")
		(net "GMI_CPU0_G1_CPU1_G3_TX_DP<8>")
	)
	(segment
		(start 352.201226 -244.484144)
		(end 351.903284 -244.484144)
		(width 0.1143)
		(layer "In15.Cu")
		(net "GMI_CPU0_G1_CPU1_G3_TX_DP<8>")
	)
	(segment
		(start 351.545144 -230.391208)
		(end 351.580704 -230.37038)
		(width 0.1143)
		(layer "In15.Cu")
		(net "GMI_CPU0_G1_CPU1_G3_TX_DP<8>")
	)
	(segment
		(start 119.951754 -240.111788)
		(end 119.982234 -240.129568)
		(width 0.1143)
		(layer "In15.Cu")
		(net "GMI_CPU0_G1_CPU1_G3_TX_DP<8>")
	)
	(segment
		(start 351.542858 -228.772466)
		(end 351.543366 -228.772212)
		(width 0.1143)
		(layer "In15.Cu")
		(net "GMI_CPU0_G1_CPU1_G3_TX_DP<8>")
	)
	(segment
		(start 145.773648 -195.91655)
		(end 144.724628 -196.23405)
		(width 0.14224)
		(layer "In15.Cu")
		(net "GMI_CPU0_G1_CPU1_G3_TX_DP<8>")
	)
	(segment
		(start 351.550478 -240.76025)
		(end 351.549462 -240.759742)
		(width 0.1143)
		(layer "In15.Cu")
		(net "GMI_CPU0_G1_CPU1_G3_TX_DP<8>")
	)
	(segment
		(start 314.63107 -186.303158)
		(end 308.426358 -182.790846)
		(width 0.14224)
		(layer "In15.Cu")
		(net "GMI_CPU0_G1_CPU1_G3_TX_DP<8>")
	)
	(segment
		(start 119.982234 -243.979192)
		(end 119.951754 -243.996972)
		(width 0.1143)
		(layer "In15.Cu")
		(net "GMI_CPU0_G1_CPU1_G3_TX_DP<8>")
	)
	(segment
		(start 119.951754 -243.996972)
		(end 119.912638 -244.019832)
		(width 0.1143)
		(layer "In15.Cu")
		(net "GMI_CPU0_G1_CPU1_G3_TX_DP<8>")
	)
	(segment
		(start 351.579688 -234.296966)
		(end 351.544128 -234.276646)
		(width 0.1143)
		(layer "In15.Cu")
		(net "GMI_CPU0_G1_CPU1_G3_TX_DP<8>")
	)
	(segment
		(start 351.548446 -228.769164)
		(end 351.549716 -228.768402)
		(width 0.1143)
		(layer "In15.Cu")
		(net "GMI_CPU0_G1_CPU1_G3_TX_DP<8>")
	)
	(segment
		(start 351.512378 -232.029762)
		(end 351.543366 -232.011982)
		(width 0.1143)
		(layer "In15.Cu")
		(net "GMI_CPU0_G1_CPU1_G3_TX_DP<8>")
	)
	(segment
		(start 119.982234 -235.879132)
		(end 119.951754 -235.896912)
		(width 0.1143)
		(layer "In15.Cu")
		(net "GMI_CPU0_G1_CPU1_G3_TX_DP<8>")
	)
	(segment
		(start 351.5487 -242.379246)
		(end 351.536254 -242.372134)
		(width 0.1143)
		(layer "In15.Cu")
		(net "GMI_CPU0_G1_CPU1_G3_TX_DP<8>")
	)
	(segment
		(start 119.951754 -237.516924)
		(end 119.912638 -237.539784)
		(width 0.1143)
		(layer "In15.Cu")
		(net "GMI_CPU0_G1_CPU1_G3_TX_DP<8>")
	)
	(segment
		(start 119.982234 -240.739168)
		(end 119.951754 -240.756948)
		(width 0.1143)
		(layer "In15.Cu")
		(net "GMI_CPU0_G1_CPU1_G3_TX_DP<8>")
	)
	(segment
		(start 351.512378 -233.649774)
		(end 351.543366 -233.631994)
		(width 0.1143)
		(layer "In15.Cu")
		(net "GMI_CPU0_G1_CPU1_G3_TX_DP<8>")
	)
	(segment
		(start 119.951754 -222.93707)
		(end 119.912638 -222.95993)
		(width 0.1143)
		(layer "In15.Cu")
		(net "GMI_CPU0_G1_CPU1_G3_TX_DP<8>")
	)
	(segment
		(start 350.64319 -222.959676)
		(end 350.604074 -222.936816)
		(width 0.1143)
		(layer "In15.Cu")
		(net "GMI_CPU0_G1_CPU1_G3_TX_DP<8>")
	)
	(segment
		(start 119.982234 -242.35918)
		(end 119.951754 -242.37696)
		(width 0.1143)
		(layer "In15.Cu")
		(net "GMI_CPU0_G1_CPU1_G3_TX_DP<8>")
	)
	(segment
		(start 351.550478 -237.520226)
		(end 351.549462 -237.519718)
		(width 0.1143)
		(layer "In15.Cu")
		(net "GMI_CPU0_G1_CPU1_G3_TX_DP<8>")
	)
	(segment
		(start 351.545144 -232.010966)
		(end 351.583244 -231.988614)
		(width 0.1143)
		(layer "In15.Cu")
		(net "GMI_CPU0_G1_CPU1_G3_TX_DP<8>")
	)
	(segment
		(start 119.912638 -243.328952)
		(end 119.951754 -243.351812)
		(width 0.1143)
		(layer "In15.Cu")
		(net "GMI_CPU0_G1_CPU1_G3_TX_DP<8>")
	)
	(segment
		(start 351.543366 -232.656126)
		(end 351.512378 -232.638346)
		(width 0.1143)
		(layer "In15.Cu")
		(net "GMI_CPU0_G1_CPU1_G3_TX_DP<8>")
	)
	(segment
		(start 351.544128 -227.796852)
		(end 351.543366 -227.796344)
		(width 0.1143)
		(layer "In15.Cu")
		(net "GMI_CPU0_G1_CPU1_G3_TX_DP<8>")
	)
	(segment
		(start 349.992188 -218.953842)
		(end 347.16466 -212.979)
		(width 0.14224)
		(layer "In15.Cu")
		(net "GMI_CPU0_G1_CPU1_G3_TX_DP<8>")
	)
	(segment
		(start 119.915178 -230.370634)
		(end 119.982234 -230.40975)
		(width 0.1143)
		(layer "In15.Cu")
		(net "GMI_CPU0_G1_CPU1_G3_TX_DP<8>")
	)
	(segment
		(start 351.56521 -238.47933)
		(end 351.583244 -238.468662)
		(width 0.1143)
		(layer "In15.Cu")
		(net "GMI_CPU0_G1_CPU1_G3_TX_DP<8>")
	)
	(segment
		(start 351.56521 -240.099342)
		(end 351.583244 -240.088674)
		(width 0.1143)
		(layer "In15.Cu")
		(net "GMI_CPU0_G1_CPU1_G3_TX_DP<8>")
	)
	(segment
		(start 351.56521 -236.859318)
		(end 351.583244 -236.84865)
		(width 0.1143)
		(layer "In15.Cu")
		(net "GMI_CPU0_G1_CPU1_G3_TX_DP<8>")
	)
	(segment
		(start 349.992188 -221.083124)
		(end 349.992188 -218.953842)
		(width 0.14224)
		(layer "In15.Cu")
		(net "GMI_CPU0_G1_CPU1_G3_TX_DP<8>")
	)
	(segment
		(start 119.951754 -238.491776)
		(end 119.982234 -238.509556)
		(width 0.1143)
		(layer "In15.Cu")
		(net "GMI_CPU0_G1_CPU1_G3_TX_DP<8>")
	)
	(segment
		(start 351.542096 -230.392986)
		(end 351.543366 -230.392224)
		(width 0.1143)
		(layer "In15.Cu")
		(net "GMI_CPU0_G1_CPU1_G3_TX_DP<8>")
	)
	(segment
		(start 351.58045 -227.130864)
		(end 351.583244 -227.128832)
		(width 0.1143)
		(layer "In15.Cu")
		(net "GMI_CPU0_G1_CPU1_G3_TX_DP<8>")
	)
	(segment
		(start 119.912638 -236.848904)
		(end 119.951754 -236.871764)
		(width 0.1143)
		(layer "In15.Cu")
		(net "GMI_CPU0_G1_CPU1_G3_TX_DP<8>")
	)
	(segment
		(start 119.912638 -233.60888)
		(end 119.951754 -233.63174)
		(width 0.1143)
		(layer "In15.Cu")
		(net "GMI_CPU0_G1_CPU1_G3_TX_DP<8>")
	)
	(segment
		(start 351.550478 -242.380262)
		(end 351.549462 -242.379754)
		(width 0.1143)
		(layer "In15.Cu")
		(net "GMI_CPU0_G1_CPU1_G3_TX_DP<8>")
	)
	(segment
		(start 351.564956 -241.719354)
		(end 351.56521 -241.719354)
		(width 0.1143)
		(layer "In15.Cu")
		(net "GMI_CPU0_G1_CPU1_G3_TX_DP<8>")
	)
	(segment
		(start 351.583244 -244.019578)
		(end 351.544128 -243.996718)
		(width 0.1143)
		(layer "In15.Cu")
		(net "GMI_CPU0_G1_CPU1_G3_TX_DP<8>")
	)
	(segment
		(start 119.982234 -226.159314)
		(end 119.951754 -226.177094)
		(width 0.1143)
		(layer "In15.Cu")
		(net "GMI_CPU0_G1_CPU1_G3_TX_DP<8>")
	)
	(segment
		(start 119.912638 -227.129086)
		(end 119.951754 -227.151946)
		(width 0.1143)
		(layer "In15.Cu")
		(net "GMI_CPU0_G1_CPU1_G3_TX_DP<8>")
	)
	(segment
		(start 351.583244 -231.059482)
		(end 351.533968 -231.03078)
		(width 0.1143)
		(layer "In15.Cu")
		(net "GMI_CPU0_G1_CPU1_G3_TX_DP<8>")
	)
	(segment
		(start 351.549462 -239.13973)
		(end 351.5487 -239.139222)
		(width 0.1143)
		(layer "In15.Cu")
		(net "GMI_CPU0_G1_CPU1_G3_TX_DP<8>")
	)
	(segment
		(start 119.984266 -231.01808)
		(end 119.951754 -231.036876)
		(width 0.1143)
		(layer "In15.Cu")
		(net "GMI_CPU0_G1_CPU1_G3_TX_DP<8>")
	)
	(segment
		(start 351.549462 -242.379754)
		(end 351.5487 -242.379246)
		(width 0.1143)
		(layer "In15.Cu")
		(net "GMI_CPU0_G1_CPU1_G3_TX_DP<8>")
	)
	(segment
		(start 119.951754 -234.2769)
		(end 119.912638 -234.29976)
		(width 0.1143)
		(layer "In15.Cu")
		(net "GMI_CPU0_G1_CPU1_G3_TX_DP<8>")
	)
	(segment
		(start 119.951754 -236.871764)
		(end 119.982234 -236.889544)
		(width 0.1143)
		(layer "In15.Cu")
		(net "GMI_CPU0_G1_CPU1_G3_TX_DP<8>")
	)
	(segment
		(start 119.58955 -219.304362)
		(end 119.58955 -220.991938)
		(width 0.14224)
		(layer "In15.Cu")
		(net "GMI_CPU0_G1_CPU1_G3_TX_DP<8>")
	)
	(segment
		(start 119.951754 -224.557082)
		(end 119.912638 -224.579942)
		(width 0.1143)
		(layer "In15.Cu")
		(net "GMI_CPU0_G1_CPU1_G3_TX_DP<8>")
	)
	(segment
		(start 119.982234 -237.499144)
		(end 119.951754 -237.516924)
		(width 0.1143)
		(layer "In15.Cu")
		(net "GMI_CPU0_G1_CPU1_G3_TX_DP<8>")
	)
	(segment
		(start 119.58955 -221.020386)
		(end 119.63527 -221.066106)
		(width 0.1143)
		(layer "In15.Cu")
		(net "GMI_CPU0_G1_CPU1_G3_TX_DP<8>")
	)
	(segment
		(start 155.589986 -187.867798)
		(end 155.589986 -187.867544)
		(width 0.14224)
		(layer "In15.Cu")
		(net "GMI_CPU0_G1_CPU1_G3_TX_DP<8>")
	)
	(segment
		(start 119.912638 -223.889062)
		(end 119.951754 -223.911922)
		(width 0.1143)
		(layer "In15.Cu")
		(net "GMI_CPU0_G1_CPU1_G3_TX_DP<8>")
	)
	(segment
		(start 350.604074 -222.936816)
		(end 350.573594 -222.919036)
		(width 0.1143)
		(layer "In15.Cu")
		(net "GMI_CPU0_G1_CPU1_G3_TX_DP<8>")
	)
	(segment
		(start 119.951754 -227.151946)
		(end 119.982234 -227.169726)
		(width 0.1143)
		(layer "In15.Cu")
		(net "GMI_CPU0_G1_CPU1_G3_TX_DP<8>")
	)
	(segment
		(start 119.669052 -221.311724)
		(end 119.669052 -221.804484)
		(width 0.1143)
		(layer "In15.Cu")
		(net "GMI_CPU0_G1_CPU1_G3_TX_DP<8>")
	)
	(segment
		(start 119.951754 -233.63174)
		(end 119.982234 -233.64952)
		(width 0.1143)
		(layer "In15.Cu")
		(net "GMI_CPU0_G1_CPU1_G3_TX_DP<8>")
	)
	(segment
		(start 351.545144 -228.771196)
		(end 351.546668 -228.77018)
		(width 0.1143)
		(layer "In15.Cu")
		(net "GMI_CPU0_G1_CPU1_G3_TX_DP<8>")
	)
	(segment
		(start 351.543366 -228.772212)
		(end 351.544128 -228.771704)
		(width 0.1143)
		(layer "In15.Cu")
		(net "GMI_CPU0_G1_CPU1_G3_TX_DP<8>")
	)
	(segment
		(start 350.573594 -223.929448)
		(end 350.604074 -223.911668)
		(width 0.1143)
		(layer "In15.Cu")
		(net "GMI_CPU0_G1_CPU1_G3_TX_DP<8>")
	)
	(segment
		(start 351.543366 -227.796344)
		(end 351.512378 -227.778564)
		(width 0.1143)
		(layer "In15.Cu")
		(net "GMI_CPU0_G1_CPU1_G3_TX_DP<8>")
	)
	(segment
		(start 351.56521 -241.719354)
		(end 351.583244 -241.708686)
		(width 0.1143)
		(layer "In15.Cu")
		(net "GMI_CPU0_G1_CPU1_G3_TX_DP<8>")
	)
	(segment
		(start 119.951754 -231.036876)
		(end 119.912638 -231.059736)
		(width 0.1143)
		(layer "In15.Cu")
		(net "GMI_CPU0_G1_CPU1_G3_TX_DP<8>")
	)
	(segment
		(start 351.549462 -237.519718)
		(end 351.5487 -237.51921)
		(width 0.1143)
		(layer "In15.Cu")
		(net "GMI_CPU0_G1_CPU1_G3_TX_DP<8>")
	)
	(segment
		(start 351.5487 -237.51921)
		(end 351.536254 -237.512098)
		(width 0.1143)
		(layer "In15.Cu")
		(net "GMI_CPU0_G1_CPU1_G3_TX_DP<8>")
	)
	(segment
		(start 351.54362 -236.871764)
		(end 351.564956 -236.859318)
		(width 0.1143)
		(layer "In15.Cu")
		(net "GMI_CPU0_G1_CPU1_G3_TX_DP<8>")
	)
	(segment
		(start 119.951754 -242.37696)
		(end 119.912638 -242.39982)
		(width 0.1143)
		(layer "In15.Cu")
		(net "GMI_CPU0_G1_CPU1_G3_TX_DP<8>")
	)
	(segment
		(start 119.951754 -223.911922)
		(end 119.982234 -223.929702)
		(width 0.1143)
		(layer "In15.Cu")
		(net "GMI_CPU0_G1_CPU1_G3_TX_DP<8>")
	)
	(segment
		(start 119.982234 -222.91929)
		(end 119.951754 -222.93707)
		(width 0.1143)
		(layer "In15.Cu")
		(net "GMI_CPU0_G1_CPU1_G3_TX_DP<8>")
	)
	(segment
		(start 351.54362 -240.111788)
		(end 351.564956 -240.099342)
		(width 0.1143)
		(layer "In15.Cu")
		(net "GMI_CPU0_G1_CPU1_G3_TX_DP<8>")
	)
	(segment
		(start 119.675402 -244.401594)
		(end 119.592598 -244.484398)
		(width 0.1143)
		(layer "In15.Cu")
		(net "GMI_CPU0_G1_CPU1_G3_TX_DP<8>")
	)
	(segment
		(start 351.543366 -232.011982)
		(end 351.544128 -232.011474)
		(width 0.1143)
		(layer "In15.Cu")
		(net "GMI_CPU0_G1_CPU1_G3_TX_DP<8>")
	)
	(segment
		(start 351.564956 -238.47933)
		(end 351.56521 -238.47933)
		(width 0.1143)
		(layer "In15.Cu")
		(net "GMI_CPU0_G1_CPU1_G3_TX_DP<8>")
	)
	(segment
		(start 351.583244 -232.679494)
		(end 351.545144 -232.657142)
		(width 0.1143)
		(layer "In15.Cu")
		(net "GMI_CPU0_G1_CPU1_G3_TX_DP<8>")
	)
	(segment
		(start 351.545144 -243.35105)
		(end 351.583244 -243.328698)
		(width 0.1143)
		(layer "In15.Cu")
		(net "GMI_CPU0_G1_CPU1_G3_TX_DP<8>")
	)
	(segment
		(start 155.589986 -187.867544)
		(end 145.773648 -195.91655)
		(width 0.14224)
		(layer "In15.Cu")
		(net "GMI_CPU0_G1_CPU1_G3_TX_DP<8>")
	)
	(segment
		(start 351.547176 -235.898436)
		(end 351.536254 -235.892086)
		(width 0.1143)
		(layer "In15.Cu")
		(net "GMI_CPU0_G1_CPU1_G3_TX_DP<8>")
	)
	(segment
		(start 119.912638 -231.988868)
		(end 119.951754 -232.011728)
		(width 0.1143)
		(layer "In15.Cu")
		(net "GMI_CPU0_G1_CPU1_G3_TX_DP<8>")
	)
	(segment
		(start 351.07753 -225.368866)
		(end 351.076006 -225.36785)
		(width 0.1143)
		(layer "In15.Cu")
		(net "GMI_CPU0_G1_CPU1_G3_TX_DP<8>")
	)
	(segment
		(start 351.583244 -226.1997)
		(end 351.544128 -226.17684)
		(width 0.1143)
		(layer "In15.Cu")
		(net "GMI_CPU0_G1_CPU1_G3_TX_DP<8>")
	)
	(segment
		(start 351.544128 -234.276646)
		(end 351.512378 -234.258358)
		(width 0.1143)
		(layer "In15.Cu")
		(net "GMI_CPU0_G1_CPU1_G3_TX_DP<8>")
	)
	(segment
		(start 351.549462 -235.899706)
		(end 351.5487 -235.899198)
		(width 0.1143)
		(layer "In15.Cu")
		(net "GMI_CPU0_G1_CPU1_G3_TX_DP<8>")
	)
	(segment
		(start 351.54362 -238.491776)
		(end 351.564956 -238.47933)
		(width 0.1143)
		(layer "In15.Cu")
		(net "GMI_CPU0_G1_CPU1_G3_TX_DP<8>")
	)
	(segment
		(start 351.583244 -229.43947)
		(end 351.544128 -229.41661)
		(width 0.1143)
		(layer "In15.Cu")
		(net "GMI_CPU0_G1_CPU1_G3_TX_DP<8>")
	)
	(segment
		(start 351.576132 -235.9152)
		(end 351.57537 -235.914692)
		(width 0.1143)
		(layer "In15.Cu")
		(net "GMI_CPU0_G1_CPU1_G3_TX_DP<8>")
	)
	(segment
		(start 351.582482 -237.539022)
		(end 351.550478 -237.520226)
		(width 0.1143)
		(layer "In15.Cu")
		(net "GMI_CPU0_G1_CPU1_G3_TX_DP<8>")
	)
	(segment
		(start 349.946468 -221.128844)
		(end 349.992188 -221.083124)
		(width 0.1143)
		(layer "In15.Cu")
		(net "GMI_CPU0_G1_CPU1_G3_TX_DP<8>")
	)
	(segment
		(start 119.951754 -240.756948)
		(end 119.912638 -240.779808)
		(width 0.1143)
		(layer "In15.Cu")
		(net "GMI_CPU0_G1_CPU1_G3_TX_DP<8>")
	)
	(segment
		(start 119.982234 -234.25912)
		(end 119.951754 -234.2769)
		(width 0.1143)
		(layer "In15.Cu")
		(net "GMI_CPU0_G1_CPU1_G3_TX_DP<8>")
	)
	(segment
		(start 351.544128 -229.41661)
		(end 351.5106 -229.397052)
		(width 0.1143)
		(layer "In15.Cu")
		(net "GMI_CPU0_G1_CPU1_G3_TX_DP<8>")
	)
	(segment
		(start 119.951754 -241.7318)
		(end 119.982234 -241.74958)
		(width 0.1143)
		(layer "In15.Cu")
		(net "GMI_CPU0_G1_CPU1_G3_TX_DP<8>")
	)
	(segment
		(start 351.582482 -242.399058)
		(end 351.550478 -242.380262)
		(width 0.1143)
		(layer "In15.Cu")
		(net "GMI_CPU0_G1_CPU1_G3_TX_DP<8>")
	)
	(segment
		(start 351.582482 -235.91901)
		(end 351.576132 -235.9152)
		(width 0.1143)
		(layer "In15.Cu")
		(net "GMI_CPU0_G1_CPU1_G3_TX_DP<8>")
	)
	(segment
		(start 119.951754 -232.656888)
		(end 119.912638 -232.679748)
		(width 0.1143)
		(layer "In15.Cu")
		(net "GMI_CPU0_G1_CPU1_G3_TX_DP<8>")
	)
	(segment
		(start 351.582482 -234.298998)
		(end 351.579688 -234.296966)
		(width 0.1143)
		(layer "In15.Cu")
		(net "GMI_CPU0_G1_CPU1_G3_TX_DP<8>")
	)
	(segment
		(start 119.984266 -229.398068)
		(end 119.951754 -229.416864)
		(width 0.1143)
		(layer "In15.Cu")
		(net "GMI_CPU0_G1_CPU1_G3_TX_DP<8>")
	)
	(segment
		(start 351.5487 -239.139222)
		(end 351.536254 -239.13211)
		(width 0.1143)
		(layer "In15.Cu")
		(net "GMI_CPU0_G1_CPU1_G3_TX_DP<8>")
	)
	(segment
		(start 119.951754 -228.771958)
		(end 119.982234 -228.789738)
		(width 0.1143)
		(layer "In15.Cu")
		(net "GMI_CPU0_G1_CPU1_G3_TX_DP<8>")
	)
	(segment
		(start 119.58955 -220.991938)
		(end 119.58955 -221.020386)
		(width 0.1143)
		(layer "In15.Cu")
		(net "GMI_CPU0_G1_CPU1_G3_TX_DP<8>")
	)
	(segment
		(start 351.903284 -244.484144)
		(end 351.82048 -244.40134)
		(width 0.1143)
		(layer "In15.Cu")
		(net "GMI_CPU0_G1_CPU1_G3_TX_DP<8>")
	)
	(segment
		(start 351.582482 -240.779046)
		(end 351.550478 -240.76025)
		(width 0.1143)
		(layer "In15.Cu")
		(net "GMI_CPU0_G1_CPU1_G3_TX_DP<8>")
	)
	(segment
		(start 351.549716 -228.768402)
		(end 351.550478 -228.767894)
		(width 0.1143)
		(layer "In15.Cu")
		(net "GMI_CPU0_G1_CPU1_G3_TX_DP<8>")
	)
	(segment
		(start 350.64319 -224.579688)
		(end 350.604074 -224.556828)
		(width 0.1143)
		(layer "In15.Cu")
		(net "GMI_CPU0_G1_CPU1_G3_TX_DP<8>")
	)
	(segment
		(start 119.951754 -235.251752)
		(end 119.982234 -235.269532)
		(width 0.1143)
		(layer "In15.Cu")
		(net "GMI_CPU0_G1_CPU1_G3_TX_DP<8>")
	)
	(segment
		(start 350.134174 -222.12681)
		(end 350.133412 -222.126302)
		(width 0.1143)
		(layer "In15.Cu")
		(net "GMI_CPU0_G1_CPU1_G3_TX_DP<8>")
	)
	(segment
		(start 351.544128 -232.656634)
		(end 351.543366 -232.656126)
		(width 0.1143)
		(layer "In15.Cu")
		(net "GMI_CPU0_G1_CPU1_G3_TX_DP<8>")
	)
	(segment
		(start 351.512378 -230.410004)
		(end 351.540572 -230.393748)
		(width 0.1143)
		(layer "In15.Cu")
		(net "GMI_CPU0_G1_CPU1_G3_TX_DP<8>")
	)
	(segment
		(start 119.951754 -243.351812)
		(end 119.982234 -243.369592)
		(width 0.1143)
		(layer "In15.Cu")
		(net "GMI_CPU0_G1_CPU1_G3_TX_DP<8>")
	)
	(arc
		(start 119.912638 -226.199954)
		(mid 119.669311 -226.66452)
		(end 119.912638 -227.129086)
		(width 0.1143)
		(layer "In15.Cu")
		(net "GMI_CPU0_G1_CPU1_G3_TX_DP<8>")
	)
	(arc
		(start 119.982234 -243.369592)
		(mid 120.139211 -243.674392)
		(end 119.982234 -243.979192)
		(width 0.1143)
		(layer "In15.Cu")
		(net "GMI_CPU0_G1_CPU1_G3_TX_DP<8>")
	)
	(arc
		(start 351.583244 -227.128832)
		(mid 351.826571 -226.664266)
		(end 351.583244 -226.1997)
		(width 0.1143)
		(layer "In15.Cu")
		(net "GMI_CPU0_G1_CPU1_G3_TX_DP<8>")
	)
	(arc
		(start 350.64319 -223.888808)
		(mid 350.886517 -223.424242)
		(end 350.64319 -222.959676)
		(width 0.1143)
		(layer "In15.Cu")
		(net "GMI_CPU0_G1_CPU1_G3_TX_DP<8>")
	)
	(arc
		(start 351.356422 -229.094284)
		(mid 351.406387 -228.908308)
		(end 351.542858 -228.772466)
		(width 0.1143)
		(layer "In15.Cu")
		(net "GMI_CPU0_G1_CPU1_G3_TX_DP<8>")
	)
	(arc
		(start 119.912638 -235.919772)
		(mid 119.669311 -236.384338)
		(end 119.912638 -236.848904)
		(width 0.1143)
		(layer "In15.Cu")
		(net "GMI_CPU0_G1_CPU1_G3_TX_DP<8>")
	)
	(arc
		(start 351.513394 -226.15906)
		(mid 351.400547 -226.030627)
		(end 351.356422 -225.865436)
		(width 0.1143)
		(layer "In15.Cu")
		(net "GMI_CPU0_G1_CPU1_G3_TX_DP<8>")
	)
	(arc
		(start 350.573594 -222.919036)
		(mid 350.458167 -222.78566)
		(end 350.416622 -222.614236)
		(width 0.1143)
		(layer "In15.Cu")
		(net "GMI_CPU0_G1_CPU1_G3_TX_DP<8>")
	)
	(arc
		(start 351.348548 -225.79076)
		(mid 351.27443 -225.585754)
		(end 351.142046 -225.412554)
		(width 0.1143)
		(layer "In15.Cu")
		(net "GMI_CPU0_G1_CPU1_G3_TX_DP<8>")
	)
	(arc
		(start 119.912892 -222.269558)
		(mid 119.913273 -222.269812)
		(end 119.913654 -222.270066)
		(width 0.1143)
		(layer "In15.Cu")
		(net "GMI_CPU0_G1_CPU1_G3_TX_DP<8>")
	)
	(arc
		(start 351.356422 -230.714296)
		(mid 351.399287 -230.544144)
		(end 351.512378 -230.410004)
		(width 0.1143)
		(layer "In15.Cu")
		(net "GMI_CPU0_G1_CPU1_G3_TX_DP<8>")
	)
	(arc
		(start 351.583244 -242.399566)
		(mid 351.582863 -242.399312)
		(end 351.582482 -242.399058)
		(width 0.1143)
		(layer "In15.Cu")
		(net "GMI_CPU0_G1_CPU1_G3_TX_DP<8>")
	)
	(arc
		(start 351.583244 -237.53953)
		(mid 351.582863 -237.539276)
		(end 351.582482 -237.539022)
		(width 0.1143)
		(layer "In15.Cu")
		(net "GMI_CPU0_G1_CPU1_G3_TX_DP<8>")
	)
	(arc
		(start 351.583244 -233.608626)
		(mid 351.826571 -233.14406)
		(end 351.583244 -232.679494)
		(width 0.1143)
		(layer "In15.Cu")
		(net "GMI_CPU0_G1_CPU1_G3_TX_DP<8>")
	)
	(arc
		(start 120.139206 -230.71455)
		(mid 120.09824 -230.884956)
		(end 119.984266 -231.01808)
		(width 0.1143)
		(layer "In15.Cu")
		(net "GMI_CPU0_G1_CPU1_G3_TX_DP<8>")
	)
	(arc
		(start 119.912638 -229.439724)
		(mid 119.733825 -229.642074)
		(end 119.669306 -229.90429)
		(width 0.1143)
		(layer "In15.Cu")
		(net "GMI_CPU0_G1_CPU1_G3_TX_DP<8>")
	)
	(arc
		(start 351.583244 -235.228638)
		(mid 351.826571 -234.764072)
		(end 351.583244 -234.299506)
		(width 0.1143)
		(layer "In15.Cu")
		(net "GMI_CPU0_G1_CPU1_G3_TX_DP<8>")
	)
	(arc
		(start 119.912638 -234.29976)
		(mid 119.669311 -234.764326)
		(end 119.912638 -235.228892)
		(width 0.1143)
		(layer "In15.Cu")
		(net "GMI_CPU0_G1_CPU1_G3_TX_DP<8>")
	)
	(arc
		(start 351.583244 -243.328698)
		(mid 351.826571 -242.864132)
		(end 351.583244 -242.399566)
		(width 0.1143)
		(layer "In15.Cu")
		(net "GMI_CPU0_G1_CPU1_G3_TX_DP<8>")
	)
	(arc
		(start 119.982234 -223.929702)
		(mid 120.139211 -224.234502)
		(end 119.982234 -224.539302)
		(width 0.1143)
		(layer "In15.Cu")
		(net "GMI_CPU0_G1_CPU1_G3_TX_DP<8>")
	)
	(arc
		(start 351.536254 -242.372134)
		(mid 351.358037 -242.049857)
		(end 351.54362 -241.7318)
		(width 0.1143)
		(layer "In15.Cu")
		(net "GMI_CPU0_G1_CPU1_G3_TX_DP<8>")
	)
	(arc
		(start 351.512378 -227.778564)
		(mid 351.363281 -227.474272)
		(end 351.512378 -227.16998)
		(width 0.1143)
		(layer "In15.Cu")
		(net "GMI_CPU0_G1_CPU1_G3_TX_DP<8>")
	)
	(arc
		(start 119.912638 -227.819966)
		(mid 119.669311 -228.284532)
		(end 119.912638 -228.749098)
		(width 0.1143)
		(layer "In15.Cu")
		(net "GMI_CPU0_G1_CPU1_G3_TX_DP<8>")
	)
	(arc
		(start 351.583244 -235.919518)
		(mid 351.582863 -235.919264)
		(end 351.582482 -235.91901)
		(width 0.1143)
		(layer "In15.Cu")
		(net "GMI_CPU0_G1_CPU1_G3_TX_DP<8>")
	)
	(arc
		(start 351.583244 -240.088674)
		(mid 351.826571 -239.624108)
		(end 351.583244 -239.159542)
		(width 0.1143)
		(layer "In15.Cu")
		(net "GMI_CPU0_G1_CPU1_G3_TX_DP<8>")
	)
	(arc
		(start 351.82048 -244.40134)
		(mid 351.818692 -244.389891)
		(end 351.81667 -244.37848)
		(width 0.1143)
		(layer "In15.Cu")
		(net "GMI_CPU0_G1_CPU1_G3_TX_DP<8>")
	)
	(arc
		(start 119.912638 -237.539784)
		(mid 119.669311 -238.00435)
		(end 119.912638 -238.468916)
		(width 0.1143)
		(layer "In15.Cu")
		(net "GMI_CPU0_G1_CPU1_G3_TX_DP<8>")
	)
	(arc
		(start 351.142046 -225.412554)
		(mid 351.126514 -225.399959)
		(end 351.11055 -225.387916)
		(width 0.1143)
		(layer "In15.Cu")
		(net "GMI_CPU0_G1_CPU1_G3_TX_DP<8>")
	)
	(arc
		(start 351.536254 -235.892086)
		(mid 351.358037 -235.569809)
		(end 351.54362 -235.251752)
		(width 0.1143)
		(layer "In15.Cu")
		(net "GMI_CPU0_G1_CPU1_G3_TX_DP<8>")
	)
	(arc
		(start 119.912638 -239.159796)
		(mid 119.669311 -239.624362)
		(end 119.912638 -240.088928)
		(width 0.1143)
		(layer "In15.Cu")
		(net "GMI_CPU0_G1_CPU1_G3_TX_DP<8>")
	)
	(arc
		(start 119.982234 -232.029508)
		(mid 120.139211 -232.334308)
		(end 119.982234 -232.639108)
		(width 0.1143)
		(layer "In15.Cu")
		(net "GMI_CPU0_G1_CPU1_G3_TX_DP<8>")
	)
	(arc
		(start 119.679212 -244.378734)
		(mid 119.677189 -244.390144)
		(end 119.675402 -244.401594)
		(width 0.1143)
		(layer "In15.Cu")
		(net "GMI_CPU0_G1_CPU1_G3_TX_DP<8>")
	)
	(arc
		(start 351.583244 -231.988614)
		(mid 351.826571 -231.524048)
		(end 351.583244 -231.059482)
		(width 0.1143)
		(layer "In15.Cu")
		(net "GMI_CPU0_G1_CPU1_G3_TX_DP<8>")
	)
	(arc
		(start 351.580704 -230.37038)
		(mid 351.761356 -230.167635)
		(end 351.826576 -229.904036)
		(width 0.1143)
		(layer "In15.Cu")
		(net "GMI_CPU0_G1_CPU1_G3_TX_DP<8>")
	)
	(arc
		(start 351.356422 -225.865436)
		(mid 351.354043 -225.827933)
		(end 351.348548 -225.79076)
		(width 0.1143)
		(layer "In15.Cu")
		(net "GMI_CPU0_G1_CPU1_G3_TX_DP<8>")
	)
	(arc
		(start 119.669052 -221.804484)
		(mid 119.733711 -222.067041)
		(end 119.912892 -222.269558)
		(width 0.1143)
		(layer "In15.Cu")
		(net "GMI_CPU0_G1_CPU1_G3_TX_DP<8>")
	)
	(arc
		(start 119.912638 -240.779808)
		(mid 119.669311 -241.244374)
		(end 119.912638 -241.70894)
		(width 0.1143)
		(layer "In15.Cu")
		(net "GMI_CPU0_G1_CPU1_G3_TX_DP<8>")
	)
	(arc
		(start 351.512378 -234.258358)
		(mid 351.360789 -233.954066)
		(end 351.512378 -233.649774)
		(width 0.1143)
		(layer "In15.Cu")
		(net "GMI_CPU0_G1_CPU1_G3_TX_DP<8>")
	)
	(arc
		(start 351.826576 -229.904036)
		(mid 351.762061 -229.641817)
		(end 351.583244 -229.43947)
		(width 0.1143)
		(layer "In15.Cu")
		(net "GMI_CPU0_G1_CPU1_G3_TX_DP<8>")
	)
	(arc
		(start 119.982234 -235.269532)
		(mid 120.139211 -235.574332)
		(end 119.982234 -235.879132)
		(width 0.1143)
		(layer "In15.Cu")
		(net "GMI_CPU0_G1_CPU1_G3_TX_DP<8>")
	)
	(arc
		(start 351.583244 -241.708686)
		(mid 351.826571 -241.24412)
		(end 351.583244 -240.779554)
		(width 0.1143)
		(layer "In15.Cu")
		(net "GMI_CPU0_G1_CPU1_G3_TX_DP<8>")
	)
	(arc
		(start 119.982234 -230.40975)
		(mid 120.097661 -230.543126)
		(end 120.139206 -230.71455)
		(width 0.1143)
		(layer "In15.Cu")
		(net "GMI_CPU0_G1_CPU1_G3_TX_DP<8>")
	)
	(arc
		(start 119.982234 -225.549714)
		(mid 120.139211 -225.854514)
		(end 119.982234 -226.159314)
		(width 0.1143)
		(layer "In15.Cu")
		(net "GMI_CPU0_G1_CPU1_G3_TX_DP<8>")
	)
	(arc
		(start 351.583244 -240.779554)
		(mid 351.582863 -240.7793)
		(end 351.582482 -240.779046)
		(width 0.1143)
		(layer "In15.Cu")
		(net "GMI_CPU0_G1_CPU1_G3_TX_DP<8>")
	)
	(arc
		(start 119.982234 -238.509556)
		(mid 120.139211 -238.814356)
		(end 119.982234 -239.119156)
		(width 0.1143)
		(layer "In15.Cu")
		(net "GMI_CPU0_G1_CPU1_G3_TX_DP<8>")
	)
	(arc
		(start 351.583244 -228.748844)
		(mid 351.826571 -228.284278)
		(end 351.583244 -227.819712)
		(width 0.1143)
		(layer "In15.Cu")
		(net "GMI_CPU0_G1_CPU1_G3_TX_DP<8>")
	)
	(arc
		(start 351.583244 -236.84865)
		(mid 351.826571 -236.384084)
		(end 351.583244 -235.919518)
		(width 0.1143)
		(layer "In15.Cu")
		(net "GMI_CPU0_G1_CPU1_G3_TX_DP<8>")
	)
	(arc
		(start 351.81667 -244.37848)
		(mid 351.735237 -244.176082)
		(end 351.583244 -244.019578)
		(width 0.1143)
		(layer "In15.Cu")
		(net "GMI_CPU0_G1_CPU1_G3_TX_DP<8>")
	)
	(arc
		(start 119.912638 -224.579942)
		(mid 119.669311 -225.044508)
		(end 119.912638 -225.509074)
		(width 0.1143)
		(layer "In15.Cu")
		(net "GMI_CPU0_G1_CPU1_G3_TX_DP<8>")
	)
	(arc
		(start 350.416622 -222.614236)
		(mid 350.352107 -222.352017)
		(end 350.17329 -222.14967)
		(width 0.1143)
		(layer "In15.Cu")
		(net "GMI_CPU0_G1_CPU1_G3_TX_DP<8>")
	)
	(arc
		(start 119.912638 -232.679748)
		(mid 119.669311 -233.144314)
		(end 119.912638 -233.60888)
		(width 0.1143)
		(layer "In15.Cu")
		(net "GMI_CPU0_G1_CPU1_G3_TX_DP<8>")
	)
	(arc
		(start 119.982234 -241.74958)
		(mid 120.139211 -242.05438)
		(end 119.982234 -242.35918)
		(width 0.1143)
		(layer "In15.Cu")
		(net "GMI_CPU0_G1_CPU1_G3_TX_DP<8>")
	)
	(arc
		(start 351.042478 -225.348546)
		(mid 350.927802 -225.215212)
		(end 350.886522 -225.044254)
		(width 0.1143)
		(layer "In15.Cu")
		(net "GMI_CPU0_G1_CPU1_G3_TX_DP<8>")
	)
	(arc
		(start 351.536254 -240.752122)
		(mid 351.358037 -240.429845)
		(end 351.54362 -240.111788)
		(width 0.1143)
		(layer "In15.Cu")
		(net "GMI_CPU0_G1_CPU1_G3_TX_DP<8>")
	)
	(arc
		(start 351.536254 -237.512098)
		(mid 351.358037 -237.189821)
		(end 351.54362 -236.871764)
		(width 0.1143)
		(layer "In15.Cu")
		(net "GMI_CPU0_G1_CPU1_G3_TX_DP<8>")
	)
	(arc
		(start 119.912638 -244.019832)
		(mid 119.760651 -244.17634)
		(end 119.679212 -244.378734)
		(width 0.1143)
		(layer "In15.Cu")
		(net "GMI_CPU0_G1_CPU1_G3_TX_DP<8>")
	)
	(arc
		(start 350.573594 -224.539048)
		(mid 350.416617 -224.234248)
		(end 350.573594 -223.929448)
		(width 0.1143)
		(layer "In15.Cu")
		(net "GMI_CPU0_G1_CPU1_G3_TX_DP<8>")
	)
	(arc
		(start 351.583244 -238.468662)
		(mid 351.826571 -238.004096)
		(end 351.583244 -237.53953)
		(width 0.1143)
		(layer "In15.Cu")
		(net "GMI_CPU0_G1_CPU1_G3_TX_DP<8>")
	)
	(arc
		(start 351.512378 -243.97843)
		(mid 351.363281 -243.674138)
		(end 351.512378 -243.369846)
		(width 0.1143)
		(layer "In15.Cu")
		(net "GMI_CPU0_G1_CPU1_G3_TX_DP<8>")
	)
	(arc
		(start 351.533968 -231.03078)
		(mid 351.402065 -230.896727)
		(end 351.356422 -230.714296)
		(width 0.1143)
		(layer "In15.Cu")
		(net "GMI_CPU0_G1_CPU1_G3_TX_DP<8>")
	)
	(arc
		(start 120.139206 -229.094538)
		(mid 120.09824 -229.264944)
		(end 119.984266 -229.398068)
		(width 0.1143)
		(layer "In15.Cu")
		(net "GMI_CPU0_G1_CPU1_G3_TX_DP<8>")
	)
	(arc
		(start 351.512378 -232.638346)
		(mid 351.363281 -232.334054)
		(end 351.512378 -232.029762)
		(width 0.1143)
		(layer "In15.Cu")
		(net "GMI_CPU0_G1_CPU1_G3_TX_DP<8>")
	)
	(arc
		(start 120.139206 -222.61449)
		(mid 120.097657 -222.785912)
		(end 119.982234 -222.91929)
		(width 0.1143)
		(layer "In15.Cu")
		(net "GMI_CPU0_G1_CPU1_G3_TX_DP<8>")
	)
	(arc
		(start 119.669306 -229.90429)
		(mid 119.734542 -230.167881)
		(end 119.915178 -230.370634)
		(width 0.1143)
		(layer "In15.Cu")
		(net "GMI_CPU0_G1_CPU1_G3_TX_DP<8>")
	)
	(arc
		(start 119.912638 -222.95993)
		(mid 119.669311 -223.424496)
		(end 119.912638 -223.889062)
		(width 0.1143)
		(layer "In15.Cu")
		(net "GMI_CPU0_G1_CPU1_G3_TX_DP<8>")
	)
	(arc
		(start 119.912638 -242.39982)
		(mid 119.669311 -242.864386)
		(end 119.912638 -243.328952)
		(width 0.1143)
		(layer "In15.Cu")
		(net "GMI_CPU0_G1_CPU1_G3_TX_DP<8>")
	)
	(arc
		(start 119.982234 -240.129568)
		(mid 120.139211 -240.434368)
		(end 119.982234 -240.739168)
		(width 0.1143)
		(layer "In15.Cu")
		(net "GMI_CPU0_G1_CPU1_G3_TX_DP<8>")
	)
	(arc
		(start 119.982234 -227.169726)
		(mid 120.139211 -227.474526)
		(end 119.982234 -227.779326)
		(width 0.1143)
		(layer "In15.Cu")
		(net "GMI_CPU0_G1_CPU1_G3_TX_DP<8>")
	)
	(arc
		(start 119.982234 -228.789738)
		(mid 120.097661 -228.923114)
		(end 120.139206 -229.094538)
		(width 0.1143)
		(layer "In15.Cu")
		(net "GMI_CPU0_G1_CPU1_G3_TX_DP<8>")
	)
	(arc
		(start 350.102424 -222.108522)
		(mid 349.987748 -221.975188)
		(end 349.946468 -221.80423)
		(width 0.1143)
		(layer "In15.Cu")
		(net "GMI_CPU0_G1_CPU1_G3_TX_DP<8>")
	)
	(arc
		(start 351.583244 -234.299506)
		(mid 351.582863 -234.299252)
		(end 351.582482 -234.298998)
		(width 0.1143)
		(layer "In15.Cu")
		(net "GMI_CPU0_G1_CPU1_G3_TX_DP<8>")
	)
	(arc
		(start 119.912638 -231.059736)
		(mid 119.669311 -231.524302)
		(end 119.912638 -231.988868)
		(width 0.1143)
		(layer "In15.Cu")
		(net "GMI_CPU0_G1_CPU1_G3_TX_DP<8>")
	)
	(arc
		(start 119.982234 -233.64952)
		(mid 120.139211 -233.95432)
		(end 119.982234 -234.25912)
		(width 0.1143)
		(layer "In15.Cu")
		(net "GMI_CPU0_G1_CPU1_G3_TX_DP<8>")
	)
	(arc
		(start 350.886522 -225.044254)
		(mid 350.822007 -224.782035)
		(end 350.64319 -224.579688)
		(width 0.1143)
		(layer "In15.Cu")
		(net "GMI_CPU0_G1_CPU1_G3_TX_DP<8>")
	)
	(arc
		(start 351.536254 -239.13211)
		(mid 351.358037 -238.809833)
		(end 351.54362 -238.491776)
		(width 0.1143)
		(layer "In15.Cu")
		(net "GMI_CPU0_G1_CPU1_G3_TX_DP<8>")
	)
	(arc
		(start 119.982234 -236.889544)
		(mid 120.139211 -237.194344)
		(end 119.982234 -237.499144)
		(width 0.1143)
		(layer "In15.Cu")
		(net "GMI_CPU0_G1_CPU1_G3_TX_DP<8>")
	)
	(arc
		(start 351.5106 -229.397052)
		(mid 351.397193 -229.264163)
		(end 351.356422 -229.094284)
		(width 0.1143)
		(layer "In15.Cu")
		(net "GMI_CPU0_G1_CPU1_G3_TX_DP<8>")
	)
	(arc
		(start 119.98325 -222.310198)
		(mid 120.097926 -222.443532)
		(end 120.139206 -222.61449)
		(width 0.1143)
		(layer "In15.Cu")
		(net "GMI_CPU0_G1_CPU1_G3_TX_DP<8>")
	)
	(arc
		(start 351.583244 -239.159542)
		(mid 351.582863 -239.159288)
		(end 351.582482 -239.159034)
		(width 0.1143)
		(layer "In15.Cu")
		(net "GMI_CPU0_G1_CPU1_G3_TX_DP<8>")
	)
	(segment
		(start 352.668078 -247.990106)
		(end 352.201226 -247.724168)
		(width 0.12954)
		(layer "F.Cu")
		(net "GMI_CPU0_G1_CPU1_G3_TX_DP<7>")
	)
	(segment
		(start 118.827804 -247.99036)
		(end 119.294656 -247.724422)
		(width 0.12954)
		(layer "F.Cu")
		(net "GMI_CPU0_G1_CPU1_G3_TX_DP<7>")
	)
	(segment
		(start 119.008906 -232.010204)
		(end 119.007382 -232.009188)
		(width 0.1143)
		(layer "In15.Cu")
		(net "GMI_CPU0_G1_CPU1_G3_TX_DP<7>")
	)
	(segment
		(start 118.972584 -234.29976)
		(end 119.00916 -234.278424)
		(width 0.1143)
		(layer "In15.Cu")
		(net "GMI_CPU0_G1_CPU1_G3_TX_DP<7>")
	)
	(segment
		(start 119.010176 -236.870748)
		(end 118.98122 -236.854238)
		(width 0.1143)
		(layer "In15.Cu")
		(net "GMI_CPU0_G1_CPU1_G3_TX_DP<7>")
	)
	(segment
		(start 119.007382 -232.009188)
		(end 119.006366 -232.00868)
		(width 0.1143)
		(layer "In15.Cu")
		(net "GMI_CPU0_G1_CPU1_G3_TX_DP<7>")
	)
	(segment
		(start 119.00916 -232.658412)
		(end 119.010684 -232.657396)
		(width 0.1143)
		(layer "In15.Cu")
		(net "GMI_CPU0_G1_CPU1_G3_TX_DP<7>")
	)
	(segment
		(start 352.484182 -240.111534)
		(end 352.48342 -240.112042)
		(width 0.1143)
		(layer "In15.Cu")
		(net "GMI_CPU0_G1_CPU1_G3_TX_DP<7>")
	)
	(segment
		(start 121.658888 -213.903814)
		(end 144.222216 -195.402962)
		(width 0.14224)
		(layer "In15.Cu")
		(net "GMI_CPU0_G1_CPU1_G3_TX_DP<7>")
	)
	(segment
		(start 119.054626 -243.378228)
		(end 119.04345 -243.3701)
		(width 0.1143)
		(layer "In15.Cu")
		(net "GMI_CPU0_G1_CPU1_G3_TX_DP<7>")
	)
	(segment
		(start 352.523298 -240.088674)
		(end 352.486722 -240.11001)
		(width 0.1143)
		(layer "In15.Cu")
		(net "GMI_CPU0_G1_CPU1_G3_TX_DP<7>")
	)
	(segment
		(start 352.485198 -241.731038)
		(end 352.484182 -241.731546)
		(width 0.1143)
		(layer "In15.Cu")
		(net "GMI_CPU0_G1_CPU1_G3_TX_DP<7>")
	)
	(segment
		(start 119.04345 -223.93021)
		(end 119.012462 -223.91243)
		(width 0.1143)
		(layer "In15.Cu")
		(net "GMI_CPU0_G1_CPU1_G3_TX_DP<7>")
	)
	(segment
		(start 348.053914 -212.419184)
		(end 351.837498 -220.41485)
		(width 0.14224)
		(layer "In15.Cu")
		(net "GMI_CPU0_G1_CPU1_G3_TX_DP<7>")
	)
	(segment
		(start 352.479102 -245.613682)
		(end 352.483674 -245.616476)
		(width 0.1143)
		(layer "In15.Cu")
		(net "GMI_CPU0_G1_CPU1_G3_TX_DP<7>")
	)
	(segment
		(start 119.012208 -240.111788)
		(end 118.997476 -240.104422)
		(width 0.1143)
		(layer "In15.Cu")
		(net "GMI_CPU0_G1_CPU1_G3_TX_DP<7>")
	)
	(segment
		(start 119.04345 -222.310198)
		(end 118.973854 -222.270066)
		(width 0.1143)
		(layer "In15.Cu")
		(net "GMI_CPU0_G1_CPU1_G3_TX_DP<7>")
	)
	(segment
		(start 119.010684 -224.55759)
		(end 119.0117 -224.557082)
		(width 0.1143)
		(layer "In15.Cu")
		(net "GMI_CPU0_G1_CPU1_G3_TX_DP<7>")
	)
	(segment
		(start 351.837498 -220.41485)
		(end 351.837498 -221.083124)
		(width 0.14224)
		(layer "In15.Cu")
		(net "GMI_CPU0_G1_CPU1_G3_TX_DP<7>")
	)
	(segment
		(start 352.484182 -236.87151)
		(end 352.48342 -236.872018)
		(width 0.1143)
		(layer "In15.Cu")
		(net "GMI_CPU0_G1_CPU1_G3_TX_DP<7>")
	)
	(segment
		(start 352.49231 -234.281472)
		(end 352.523298 -234.299506)
		(width 0.1143)
		(layer "In15.Cu")
		(net "GMI_CPU0_G1_CPU1_G3_TX_DP<7>")
	)
	(segment
		(start 352.452432 -243.97843)
		(end 352.48342 -243.99621)
		(width 0.1143)
		(layer "In15.Cu")
		(net "GMI_CPU0_G1_CPU1_G3_TX_DP<7>")
	)
	(segment
		(start 352.484182 -244.97157)
		(end 352.48342 -244.972078)
		(width 0.1143)
		(layer "In15.Cu")
		(net "GMI_CPU0_G1_CPU1_G3_TX_DP<7>")
	)
	(segment
		(start 119.0117 -234.2769)
		(end 119.012462 -234.276392)
		(width 0.1143)
		(layer "In15.Cu")
		(net "GMI_CPU0_G1_CPU1_G3_TX_DP<7>")
	)
	(segment
		(start 352.48342 -232.011982)
		(end 352.452432 -232.029762)
		(width 0.1143)
		(layer "In15.Cu")
		(net "GMI_CPU0_G1_CPU1_G3_TX_DP<7>")
	)
	(segment
		(start 119.010684 -240.757456)
		(end 119.0117 -240.756948)
		(width 0.1143)
		(layer "In15.Cu")
		(net "GMI_CPU0_G1_CPU1_G3_TX_DP<7>")
	)
	(segment
		(start 351.540318 -223.913954)
		(end 351.512378 -223.929956)
		(width 0.1143)
		(layer "In15.Cu")
		(net "GMI_CPU0_G1_CPU1_G3_TX_DP<7>")
	)
	(segment
		(start 119.006366 -232.00868)
		(end 119.004842 -232.007664)
		(width 0.1143)
		(layer "In15.Cu")
		(net "GMI_CPU0_G1_CPU1_G3_TX_DP<7>")
	)
	(segment
		(start 119.0117 -227.151946)
		(end 119.010684 -227.151438)
		(width 0.1143)
		(layer "In15.Cu")
		(net "GMI_CPU0_G1_CPU1_G3_TX_DP<7>")
	)
	(segment
		(start 119.0117 -242.37696)
		(end 119.012462 -242.376452)
		(width 0.1143)
		(layer "In15.Cu")
		(net "GMI_CPU0_G1_CPU1_G3_TX_DP<7>")
	)
	(segment
		(start 119.0117 -223.911922)
		(end 119.010684 -223.911414)
		(width 0.1143)
		(layer "In15.Cu")
		(net "GMI_CPU0_G1_CPU1_G3_TX_DP<7>")
	)
	(segment
		(start 119.00916 -234.278424)
		(end 119.010684 -234.277408)
		(width 0.1143)
		(layer "In15.Cu")
		(net "GMI_CPU0_G1_CPU1_G3_TX_DP<7>")
	)
	(segment
		(start 119.010684 -235.89742)
		(end 119.0117 -235.896912)
		(width 0.1143)
		(layer "In15.Cu")
		(net "GMI_CPU0_G1_CPU1_G3_TX_DP<7>")
	)
	(segment
		(start 352.485198 -237.517178)
		(end 352.523298 -237.53953)
		(width 0.1143)
		(layer "In15.Cu")
		(net "GMI_CPU0_G1_CPU1_G3_TX_DP<7>")
	)
	(segment
		(start 118.980204 -243.333524)
		(end 118.979442 -243.333016)
		(width 0.1143)
		(layer "In15.Cu")
		(net "GMI_CPU0_G1_CPU1_G3_TX_DP<7>")
	)
	(segment
		(start 352.4885 -240.759234)
		(end 352.490786 -240.760504)
		(width 0.1143)
		(layer "In15.Cu")
		(net "GMI_CPU0_G1_CPU1_G3_TX_DP<7>")
	)
	(segment
		(start 352.484182 -233.631486)
		(end 352.48342 -233.631994)
		(width 0.1143)
		(layer "In15.Cu")
		(net "GMI_CPU0_G1_CPU1_G3_TX_DP<7>")
	)
	(segment
		(start 119.012462 -232.65638)
		(end 119.04345 -232.6386)
		(width 0.1143)
		(layer "In15.Cu")
		(net "GMI_CPU0_G1_CPU1_G3_TX_DP<7>")
	)
	(segment
		(start 352.452432 -242.358418)
		(end 352.47453 -242.371118)
		(width 0.1143)
		(layer "In15.Cu")
		(net "GMI_CPU0_G1_CPU1_G3_TX_DP<7>")
	)
	(segment
		(start 119.059198 -222.321628)
		(end 119.04345 -222.310198)
		(width 0.1143)
		(layer "In15.Cu")
		(net "GMI_CPU0_G1_CPU1_G3_TX_DP<7>")
	)
	(segment
		(start 118.980204 -235.233464)
		(end 118.979442 -235.232956)
		(width 0.1143)
		(layer "In15.Cu")
		(net "GMI_CPU0_G1_CPU1_G3_TX_DP<7>")
	)
	(segment
		(start 118.64467 -221.020386)
		(end 118.64467 -220.991938)
		(width 0.1143)
		(layer "In15.Cu")
		(net "GMI_CPU0_G1_CPU1_G3_TX_DP<7>")
	)
	(segment
		(start 352.520758 -230.37038)
		(end 352.452432 -230.410004)
		(width 0.1143)
		(layer "In15.Cu")
		(net "GMI_CPU0_G1_CPU1_G3_TX_DP<7>")
	)
	(segment
		(start 118.69039 -221.066106)
		(end 118.64467 -221.020386)
		(width 0.1143)
		(layer "In15.Cu")
		(net "GMI_CPU0_G1_CPU1_G3_TX_DP<7>")
	)
	(segment
		(start 118.979442 -233.612944)
		(end 118.972584 -233.60888)
		(width 0.1143)
		(layer "In15.Cu")
		(net "GMI_CPU0_G1_CPU1_G3_TX_DP<7>")
	)
	(segment
		(start 308.81066 -181.929532)
		(end 315.461142 -185.694066)
		(width 0.14224)
		(layer "In15.Cu")
		(net "GMI_CPU0_G1_CPU1_G3_TX_DP<7>")
	)
	(segment
		(start 352.486722 -238.489998)
		(end 352.482658 -238.492284)
		(width 0.1143)
		(layer "In15.Cu")
		(net "GMI_CPU0_G1_CPU1_G3_TX_DP<7>")
	)
	(segment
		(start 352.48342 -244.972078)
		(end 352.452432 -244.989858)
		(width 0.1143)
		(layer "In15.Cu")
		(net "GMI_CPU0_G1_CPU1_G3_TX_DP<7>")
	)
	(segment
		(start 119.004842 -238.487712)
		(end 118.980204 -238.473488)
		(width 0.1143)
		(layer "In15.Cu")
		(net "GMI_CPU0_G1_CPU1_G3_TX_DP<7>")
	)
	(segment
		(start 119.04345 -227.778818)
		(end 119.051832 -227.772722)
		(width 0.1143)
		(layer "In15.Cu")
		(net "GMI_CPU0_G1_CPU1_G3_TX_DP<7>")
	)
	(segment
		(start 119.012462 -227.796598)
		(end 119.04345 -227.778818)
		(width 0.1143)
		(layer "In15.Cu")
		(net "GMI_CPU0_G1_CPU1_G3_TX_DP<7>")
	)
	(segment
		(start 119.012462 -234.276392)
		(end 119.04345 -234.258612)
		(width 0.1143)
		(layer "In15.Cu")
		(net "GMI_CPU0_G1_CPU1_G3_TX_DP<7>")
	)
	(segment
		(start 352.485198 -243.997226)
		(end 352.4885 -243.999258)
		(width 0.1143)
		(layer "In15.Cu")
		(net "GMI_CPU0_G1_CPU1_G3_TX_DP<7>")
	)
	(segment
		(start 351.826576 -221.658942)
		(end 351.826576 -221.80423)
		(width 0.1143)
		(layer "In15.Cu")
		(net "GMI_CPU0_G1_CPU1_G3_TX_DP<7>")
	)
	(segment
		(start 118.979442 -225.513138)
		(end 118.972584 -225.509074)
		(width 0.1143)
		(layer "In15.Cu")
		(net "GMI_CPU0_G1_CPU1_G3_TX_DP<7>")
	)
	(segment
		(start 119.010684 -223.911414)
		(end 119.008906 -223.910398)
		(width 0.1143)
		(layer "In15.Cu")
		(net "GMI_CPU0_G1_CPU1_G3_TX_DP<7>")
	)
	(segment
		(start 119.010684 -241.731292)
		(end 119.008906 -241.730276)
		(width 0.1143)
		(layer "In15.Cu")
		(net "GMI_CPU0_G1_CPU1_G3_TX_DP<7>")
	)
	(segment
		(start 119.0117 -224.557082)
		(end 119.012462 -224.556574)
		(width 0.1143)
		(layer "In15.Cu")
		(net "GMI_CPU0_G1_CPU1_G3_TX_DP<7>")
	)
	(segment
		(start 119.00916 -237.518448)
		(end 119.010684 -237.517432)
		(width 0.1143)
		(layer "In15.Cu")
		(net "GMI_CPU0_G1_CPU1_G3_TX_DP<7>")
	)
	(segment
		(start 119.04345 -232.030016)
		(end 119.012462 -232.012236)
		(width 0.1143)
		(layer "In15.Cu")
		(net "GMI_CPU0_G1_CPU1_G3_TX_DP<7>")
	)
	(segment
		(start 119.008906 -228.770434)
		(end 119.007382 -228.769418)
		(width 0.1143)
		(layer "In15.Cu")
		(net "GMI_CPU0_G1_CPU1_G3_TX_DP<7>")
	)
	(segment
		(start 119.0117 -235.896912)
		(end 119.012462 -235.896658)
		(width 0.1143)
		(layer "In15.Cu")
		(net "GMI_CPU0_G1_CPU1_G3_TX_DP<7>")
	)
	(segment
		(start 351.837498 -221.083124)
		(end 351.791778 -221.128844)
		(width 0.1143)
		(layer "In15.Cu")
		(net "GMI_CPU0_G1_CPU1_G3_TX_DP<7>")
	)
	(segment
		(start 351.903284 -247.724168)
		(end 352.201226 -247.724168)
		(width 0.1143)
		(layer "In15.Cu")
		(net "GMI_CPU0_G1_CPU1_G3_TX_DP<7>")
	)
	(segment
		(start 352.490786 -240.760504)
		(end 352.49231 -240.76152)
		(width 0.1143)
		(layer "In15.Cu")
		(net "GMI_CPU0_G1_CPU1_G3_TX_DP<7>")
	)
	(segment
		(start 119.050054 -232.034842)
		(end 119.04345 -232.030016)
		(width 0.1143)
		(layer "In15.Cu")
		(net "GMI_CPU0_G1_CPU1_G3_TX_DP<7>")
	)
	(segment
		(start 119.0117 -226.177094)
		(end 119.012462 -226.176586)
		(width 0.1143)
		(layer "In15.Cu")
		(net "GMI_CPU0_G1_CPU1_G3_TX_DP<7>")
	)
	(segment
		(start 119.0117 -232.656888)
		(end 119.012462 -232.65638)
		(width 0.1143)
		(layer "In15.Cu")
		(net "GMI_CPU0_G1_CPU1_G3_TX_DP<7>")
	)
	(segment
		(start 352.484182 -235.251498)
		(end 352.48342 -235.252006)
		(width 0.1143)
		(layer "In15.Cu")
		(net "GMI_CPU0_G1_CPU1_G3_TX_DP<7>")
	)
	(segment
		(start 119.004842 -228.767894)
		(end 118.980204 -228.75367)
		(width 0.1143)
		(layer "In15.Cu")
		(net "GMI_CPU0_G1_CPU1_G3_TX_DP<7>")
	)
	(segment
		(start 352.450654 -231.017064)
		(end 352.523298 -231.059482)
		(width 0.1143)
		(layer "In15.Cu")
		(net "GMI_CPU0_G1_CPU1_G3_TX_DP<7>")
	)
	(segment
		(start 119.0117 -238.491776)
		(end 119.010684 -238.491268)
		(width 0.1143)
		(layer "In15.Cu")
		(net "GMI_CPU0_G1_CPU1_G3_TX_DP<7>")
	)
	(segment
		(start 119.006366 -243.348764)
		(end 119.004842 -243.347748)
		(width 0.1143)
		(layer "In15.Cu")
		(net "GMI_CPU0_G1_CPU1_G3_TX_DP<7>")
	)
	(segment
		(start 118.98122 -235.234226)
		(end 118.97995 -235.233464)
		(width 0.1143)
		(layer "In15.Cu")
		(net "GMI_CPU0_G1_CPU1_G3_TX_DP<7>")
	)
	(segment
		(start 352.49231 -240.76152)
		(end 352.523298 -240.779554)
		(width 0.1143)
		(layer "In15.Cu")
		(net "GMI_CPU0_G1_CPU1_G3_TX_DP<7>")
	)
	(segment
		(start 119.0117 -232.011728)
		(end 119.010684 -232.01122)
		(width 0.1143)
		(layer "In15.Cu")
		(net "GMI_CPU0_G1_CPU1_G3_TX_DP<7>")
	)
	(segment
		(start 352.452432 -240.738406)
		(end 352.48342 -240.756186)
		(width 0.1143)
		(layer "In15.Cu")
		(net "GMI_CPU0_G1_CPU1_G3_TX_DP<7>")
	)
	(segment
		(start 118.729252 -221.804484)
		(end 118.729252 -221.316804)
		(width 0.1143)
		(layer "In15.Cu")
		(net "GMI_CPU0_G1_CPU1_G3_TX_DP<7>")
	)
	(segment
		(start 352.485198 -240.757202)
		(end 352.4885 -240.759234)
		(width 0.1143)
		(layer "In15.Cu")
		(net "GMI_CPU0_G1_CPU1_G3_TX_DP<7>")
	)
	(segment
		(start 352.453702 -226.15906)
		(end 352.523298 -226.1997)
		(width 0.1143)
		(layer "In15.Cu")
		(net "GMI_CPU0_G1_CPU1_G3_TX_DP<7>")
	)
	(segment
		(start 352.48342 -239.136174)
		(end 352.485198 -239.13719)
		(width 0.1143)
		(layer "In15.Cu")
		(net "GMI_CPU0_G1_CPU1_G3_TX_DP<7>")
	)
	(segment
		(start 352.486722 -232.00995)
		(end 352.485198 -232.010966)
		(width 0.1143)
		(layer "In15.Cu")
		(net "GMI_CPU0_G1_CPU1_G3_TX_DP<7>")
	)
	(segment
		(start 166.178738 -180.579776)
		(end 302.899064 -181.377336)
		(width 0.14224)
		(layer "In15.Cu")
		(net "GMI_CPU0_G1_CPU1_G3_TX_DP<7>")
	)
	(segment
		(start 119.008906 -223.910398)
		(end 119.007382 -223.909382)
		(width 0.1143)
		(layer "In15.Cu")
		(net "GMI_CPU0_G1_CPU1_G3_TX_DP<7>")
	)
	(segment
		(start 118.979442 -223.893126)
		(end 118.972584 -223.889062)
		(width 0.1143)
		(layer "In15.Cu")
		(net "GMI_CPU0_G1_CPU1_G3_TX_DP<7>")
	)
	(segment
		(start 119.006366 -223.908874)
		(end 119.004842 -223.907858)
		(width 0.1143)
		(layer "In15.Cu")
		(net "GMI_CPU0_G1_CPU1_G3_TX_DP<7>")
	)
	(segment
		(start 352.4758 -242.37188)
		(end 352.479102 -242.373658)
		(width 0.1143)
		(layer "In15.Cu")
		(net "GMI_CPU0_G1_CPU1_G3_TX_DP<7>")
	)
	(segment
		(start 119.012462 -239.136428)
		(end 119.04345 -239.118648)
		(width 0.1143)
		(layer "In15.Cu")
		(net "GMI_CPU0_G1_CPU1_G3_TX_DP<7>")
	)
	(segment
		(start 119.004842 -233.627676)
		(end 118.980204 -233.613452)
		(width 0.1143)
		(layer "In15.Cu")
		(net "GMI_CPU0_G1_CPU1_G3_TX_DP<7>")
	)
	(segment
		(start 352.523298 -238.468662)
		(end 352.486722 -238.489998)
		(width 0.1143)
		(layer "In15.Cu")
		(net "GMI_CPU0_G1_CPU1_G3_TX_DP<7>")
	)
	(segment
		(start 119.012462 -242.376452)
		(end 119.04345 -242.358672)
		(width 0.1143)
		(layer "In15.Cu")
		(net "GMI_CPU0_G1_CPU1_G3_TX_DP<7>")
	)
	(segment
		(start 119.007382 -243.349272)
		(end 119.006366 -243.348764)
		(width 0.1143)
		(layer "In15.Cu")
		(net "GMI_CPU0_G1_CPU1_G3_TX_DP<7>")
	)
	(segment
		(start 352.005646 -225.3615)
		(end 352.00971 -225.36404)
		(width 0.1143)
		(layer "In15.Cu")
		(net "GMI_CPU0_G1_CPU1_G3_TX_DP<7>")
	)
	(segment
		(start 352.48342 -240.112042)
		(end 352.452432 -240.129822)
		(width 0.1143)
		(layer "In15.Cu")
		(net "GMI_CPU0_G1_CPU1_G3_TX_DP<7>")
	)
	(segment
		(start 352.48342 -233.631994)
		(end 352.452432 -233.649774)
		(width 0.1143)
		(layer "In15.Cu")
		(net "GMI_CPU0_G1_CPU1_G3_TX_DP<7>")
	)
	(segment
		(start 118.64467 -220.991938)
		(end 118.64467 -219.05468)
		(width 0.14224)
		(layer "In15.Cu")
		(net "GMI_CPU0_G1_CPU1_G3_TX_DP<7>")
	)
	(segment
		(start 352.48342 -235.252006)
		(end 352.452432 -235.269786)
		(width 0.1143)
		(layer "In15.Cu")
		(net "GMI_CPU0_G1_CPU1_G3_TX_DP<7>")
	)
	(segment
		(start 351.583244 -223.888808)
		(end 351.545144 -223.91116)
		(width 0.1143)
		(layer "In15.Cu")
		(net "GMI_CPU0_G1_CPU1_G3_TX_DP<7>")
	)
	(segment
		(start 352.045778 -225.385122)
		(end 352.053398 -225.389694)
		(width 0.1143)
		(layer "In15.Cu")
		(net "GMI_CPU0_G1_CPU1_G3_TX_DP<7>")
	)
	(segment
		(start 118.979442 -246.57304)
		(end 118.972584 -246.568976)
		(width 0.1143)
		(layer "In15.Cu")
		(net "GMI_CPU0_G1_CPU1_G3_TX_DP<7>")
	)
	(segment
		(start 352.490786 -244.000528)
		(end 352.49231 -244.001544)
		(width 0.1143)
		(layer "In15.Cu")
		(net "GMI_CPU0_G1_CPU1_G3_TX_DP<7>")
	)
	(segment
		(start 119.012462 -228.772466)
		(end 119.0117 -228.771958)
		(width 0.1143)
		(layer "In15.Cu")
		(net "GMI_CPU0_G1_CPU1_G3_TX_DP<7>")
	)
	(segment
		(start 119.010684 -244.971316)
		(end 119.008906 -244.9703)
		(width 0.1143)
		(layer "In15.Cu")
		(net "GMI_CPU0_G1_CPU1_G3_TX_DP<7>")
	)
	(segment
		(start 119.010684 -238.491268)
		(end 119.008906 -238.490252)
		(width 0.1143)
		(layer "In15.Cu")
		(net "GMI_CPU0_G1_CPU1_G3_TX_DP<7>")
	)
	(segment
		(start 119.004842 -225.52787)
		(end 118.980204 -225.513646)
		(width 0.1143)
		(layer "In15.Cu")
		(net "GMI_CPU0_G1_CPU1_G3_TX_DP<7>")
	)
	(segment
		(start 351.580704 -222.270574)
		(end 351.544382 -222.291656)
		(width 0.1143)
		(layer "In15.Cu")
		(net "GMI_CPU0_G1_CPU1_G3_TX_DP<7>")
	)
	(segment
		(start 118.97995 -236.853476)
		(end 118.980204 -236.853476)
		(width 0.1143)
		(layer "In15.Cu")
		(net "GMI_CPU0_G1_CPU1_G3_TX_DP<7>")
	)
	(segment
		(start 119.0117 -225.531934)
		(end 119.010684 -225.531426)
		(width 0.1143)
		(layer "In15.Cu")
		(net "GMI_CPU0_G1_CPU1_G3_TX_DP<7>")
	)
	(segment
		(start 118.980204 -246.573548)
		(end 118.979442 -246.57304)
		(width 0.1143)
		(layer "In15.Cu")
		(net "GMI_CPU0_G1_CPU1_G3_TX_DP<7>")
	)
	(segment
		(start 119.04345 -243.978684)
		(end 119.054626 -243.970556)
		(width 0.1143)
		(layer "In15.Cu")
		(net "GMI_CPU0_G1_CPU1_G3_TX_DP<7>")
	)
	(segment
		(start 119.010684 -237.517432)
		(end 119.0117 -237.516924)
		(width 0.1143)
		(layer "In15.Cu")
		(net "GMI_CPU0_G1_CPU1_G3_TX_DP<7>")
	)
	(segment
		(start 119.04345 -239.118648)
		(end 119.057166 -239.108742)
		(width 0.1143)
		(layer "In15.Cu")
		(net "GMI_CPU0_G1_CPU1_G3_TX_DP<7>")
	)
	(segment
		(start 119.004842 -223.907858)
		(end 118.980204 -223.893634)
		(width 0.1143)
		(layer "In15.Cu")
		(net "GMI_CPU0_G1_CPU1_G3_TX_DP<7>")
	)
	(segment
		(start 119.004842 -244.96776)
		(end 118.980204 -244.953536)
		(width 0.1143)
		(layer "In15.Cu")
		(net "GMI_CPU0_G1_CPU1_G3_TX_DP<7>")
	)
	(segment
		(start 352.4885 -234.279186)
		(end 352.490786 -234.280456)
		(width 0.1143)
		(layer "In15.Cu")
		(net "GMI_CPU0_G1_CPU1_G3_TX_DP<7>")
	)
	(segment
		(start 119.012208 -236.871764)
		(end 119.010176 -236.870748)
		(width 0.1143)
		(layer "In15.Cu")
		(net "GMI_CPU0_G1_CPU1_G3_TX_DP<7>")
	)
	(segment
		(start 119.007382 -233.6292)
		(end 119.006366 -233.628692)
		(width 0.1143)
		(layer "In15.Cu")
		(net "GMI_CPU0_G1_CPU1_G3_TX_DP<7>")
	)
	(segment
		(start 352.485198 -244.971062)
		(end 352.484182 -244.97157)
		(width 0.1143)
		(layer "In15.Cu")
		(net "GMI_CPU0_G1_CPU1_G3_TX_DP<7>")
	)
	(segment
		(start 119.00916 -224.558606)
		(end 119.010684 -224.55759)
		(width 0.1143)
		(layer "In15.Cu")
		(net "GMI_CPU0_G1_CPU1_G3_TX_DP<7>")
	)
	(segment
		(start 146.953986 -193.557906)
		(end 146.953732 -193.557906)
		(width 0.14224)
		(layer "In15.Cu")
		(net "GMI_CPU0_G1_CPU1_G3_TX_DP<7>")
	)
	(segment
		(start 351.82683 -221.658688)
		(end 351.826576 -221.658942)
		(width 0.1143)
		(layer "In15.Cu")
		(net "GMI_CPU0_G1_CPU1_G3_TX_DP<7>")
	)
	(segment
		(start 119.006366 -246.588788)
		(end 119.004842 -246.587772)
		(width 0.1143)
		(layer "In15.Cu")
		(net "GMI_CPU0_G1_CPU1_G3_TX_DP<7>")
	)
	(segment
		(start 119.00916 -239.13846)
		(end 119.010684 -239.137444)
		(width 0.1143)
		(layer "In15.Cu")
		(net "GMI_CPU0_G1_CPU1_G3_TX_DP<7>")
	)
	(segment
		(start 352.523298 -236.84865)
		(end 352.486722 -236.869986)
		(width 0.1143)
		(layer "In15.Cu")
		(net "GMI_CPU0_G1_CPU1_G3_TX_DP<7>")
	)
	(segment
		(start 352.520504 -228.750876)
		(end 352.452432 -228.789992)
		(width 0.1143)
		(layer "In15.Cu")
		(net "GMI_CPU0_G1_CPU1_G3_TX_DP<7>")
	)
	(segment
		(start 119.0117 -244.971824)
		(end 119.010684 -244.971316)
		(width 0.1143)
		(layer "In15.Cu")
		(net "GMI_CPU0_G1_CPU1_G3_TX_DP<7>")
	)
	(segment
		(start 352.485198 -246.591074)
		(end 352.484182 -246.591582)
		(width 0.1143)
		(layer "In15.Cu")
		(net "GMI_CPU0_G1_CPU1_G3_TX_DP<7>")
	)
	(segment
		(start 118.980204 -231.99344)
		(end 118.979442 -231.992932)
		(width 0.1143)
		(layer "In15.Cu")
		(net "GMI_CPU0_G1_CPU1_G3_TX_DP<7>")
	)
	(segment
		(start 352.49231 -235.901484)
		(end 352.523298 -235.919518)
		(width 0.1143)
		(layer "In15.Cu")
		(net "GMI_CPU0_G1_CPU1_G3_TX_DP<7>")
	)
	(segment
		(start 119.012462 -241.732308)
		(end 119.0117 -241.7318)
		(width 0.1143)
		(layer "In15.Cu")
		(net "GMI_CPU0_G1_CPU1_G3_TX_DP<7>")
	)
	(segment
		(start 119.004842 -227.147882)
		(end 118.980204 -227.133658)
		(width 0.1143)
		(layer "In15.Cu")
		(net "GMI_CPU0_G1_CPU1_G3_TX_DP<7>")
	)
	(segment
		(start 119.0117 -239.136936)
		(end 119.012462 -239.136428)
		(width 0.1143)
		(layer "In15.Cu")
		(net "GMI_CPU0_G1_CPU1_G3_TX_DP<7>")
	)
	(segment
		(start 118.972584 -232.679748)
		(end 119.00916 -232.658412)
		(width 0.1143)
		(layer "In15.Cu")
		(net "GMI_CPU0_G1_CPU1_G3_TX_DP<7>")
	)
	(segment
		(start 352.452432 -239.118394)
		(end 352.48342 -239.136174)
		(width 0.1143)
		(layer "In15.Cu")
		(net "GMI_CPU0_G1_CPU1_G3_TX_DP<7>")
	)
	(segment
		(start 118.980204 -225.513646)
		(end 118.979442 -225.513138)
		(width 0.1143)
		(layer "In15.Cu")
		(net "GMI_CPU0_G1_CPU1_G3_TX_DP<7>")
	)
	(segment
		(start 118.972584 -240.779808)
		(end 119.00916 -240.758472)
		(width 0.1143)
		(layer "In15.Cu")
		(net "GMI_CPU0_G1_CPU1_G3_TX_DP<7>")
	)
	(segment
		(start 119.012462 -224.556574)
		(end 119.04345 -224.538794)
		(width 0.1143)
		(layer "In15.Cu")
		(net "GMI_CPU0_G1_CPU1_G3_TX_DP<7>")
	)
	(segment
		(start 352.523298 -228.748844)
		(end 352.520504 -228.750876)
		(width 0.1143)
		(layer "In15.Cu")
		(net "GMI_CPU0_G1_CPU1_G3_TX_DP<7>")
	)
	(segment
		(start 119.006366 -244.968776)
		(end 119.004842 -244.96776)
		(width 0.1143)
		(layer "In15.Cu")
		(net "GMI_CPU0_G1_CPU1_G3_TX_DP<7>")
	)
	(segment
		(start 352.486722 -244.970046)
		(end 352.485198 -244.971062)
		(width 0.1143)
		(layer "In15.Cu")
		(net "GMI_CPU0_G1_CPU1_G3_TX_DP<7>")
	)
	(segment
		(start 119.00916 -222.938594)
		(end 119.010684 -222.937578)
		(width 0.1143)
		(layer "In15.Cu")
		(net "GMI_CPU0_G1_CPU1_G3_TX_DP<7>")
	)
	(segment
		(start 119.592598 -247.724422)
		(end 119.662448 -247.654572)
		(width 0.1143)
		(layer "In15.Cu")
		(net "GMI_CPU0_G1_CPU1_G3_TX_DP<7>")
	)
	(segment
		(start 152.080468 -189.353952)
		(end 152.080722 -189.35446)
		(width 0.14224)
		(layer "In15.Cu")
		(net "GMI_CPU0_G1_CPU1_G3_TX_DP<7>")
	)
	(segment
		(start 119.010684 -232.01122)
		(end 119.008906 -232.010204)
		(width 0.1143)
		(layer "In15.Cu")
		(net "GMI_CPU0_G1_CPU1_G3_TX_DP<7>")
	)
	(segment
		(start 352.480118 -238.493808)
		(end 352.452432 -238.50981)
		(width 0.1143)
		(layer "In15.Cu")
		(net "GMI_CPU0_G1_CPU1_G3_TX_DP<7>")
	)
	(segment
		(start 118.64467 -219.05468)
		(end 121.658888 -213.903814)
		(width 0.14224)
		(layer "In15.Cu")
		(net "GMI_CPU0_G1_CPU1_G3_TX_DP<7>")
	)
	(segment
		(start 118.980204 -241.713512)
		(end 118.979442 -241.713004)
		(width 0.1143)
		(layer "In15.Cu")
		(net "GMI_CPU0_G1_CPU1_G3_TX_DP<7>")
	)
	(segment
		(start 119.0117 -233.63174)
		(end 119.010684 -233.631232)
		(width 0.1143)
		(layer "In15.Cu")
		(net "GMI_CPU0_G1_CPU1_G3_TX_DP<7>")
	)
	(segment
		(start 118.979442 -243.333016)
		(end 118.972584 -243.328952)
		(width 0.1143)
		(layer "In15.Cu")
		(net "GMI_CPU0_G1_CPU1_G3_TX_DP<7>")
	)
	(segment
		(start 352.49231 -239.141508)
		(end 352.523298 -239.159542)
		(width 0.1143)
		(layer "In15.Cu")
		(net "GMI_CPU0_G1_CPU1_G3_TX_DP<7>")
	)
	(segment
		(start 119.0117 -222.93707)
		(end 119.012462 -222.936562)
		(width 0.1143)
		(layer "In15.Cu")
		(net "GMI_CPU0_G1_CPU1_G3_TX_DP<7>")
	)
	(segment
		(start 351.82683 -221.343474)
		(end 351.82683 -221.658688)
		(width 0.1143)
		(layer "In15.Cu")
		(net "GMI_CPU0_G1_CPU1_G3_TX_DP<7>")
	)
	(segment
		(start 119.012208 -235.251752)
		(end 119.010176 -235.250736)
		(width 0.1143)
		(layer "In15.Cu")
		(net "GMI_CPU0_G1_CPU1_G3_TX_DP<7>")
	)
	(segment
		(start 119.007382 -246.589296)
		(end 119.006366 -246.588788)
		(width 0.1143)
		(layer "In15.Cu")
		(net "GMI_CPU0_G1_CPU1_G3_TX_DP<7>")
	)
	(segment
		(start 119.012462 -225.532442)
		(end 119.0117 -225.531934)
		(width 0.1143)
		(layer "In15.Cu")
		(net "GMI_CPU0_G1_CPU1_G3_TX_DP<7>")
	)
	(segment
		(start 351.791778 -221.128844)
		(end 351.791778 -221.308422)
		(width 0.1143)
		(layer "In15.Cu")
		(net "GMI_CPU0_G1_CPU1_G3_TX_DP<7>")
	)
	(segment
		(start 352.486722 -235.249974)
		(end 352.485198 -235.25099)
		(width 0.1143)
		(layer "In15.Cu")
		(net "GMI_CPU0_G1_CPU1_G3_TX_DP<7>")
	)
	(segment
		(start 119.007382 -227.149406)
		(end 119.006366 -227.148898)
		(width 0.1143)
		(layer "In15.Cu")
		(net "GMI_CPU0_G1_CPU1_G3_TX_DP<7>")
	)
	(segment
		(start 119.012462 -233.632248)
		(end 119.0117 -233.63174)
		(width 0.1143)
		(layer "In15.Cu")
		(net "GMI_CPU0_G1_CPU1_G3_TX_DP<7>")
	)
	(segment
		(start 351.58045 -224.577656)
		(end 351.583244 -224.579688)
		(width 0.1143)
		(layer "In15.Cu")
		(net "GMI_CPU0_G1_CPU1_G3_TX_DP<7>")
	)
	(segment
		(start 119.0117 -227.797106)
		(end 119.012462 -227.796598)
		(width 0.1143)
		(layer "In15.Cu")
		(net "GMI_CPU0_G1_CPU1_G3_TX_DP<7>")
	)
	(segment
		(start 119.012462 -245.616476)
		(end 119.04345 -245.598696)
		(width 0.1143)
		(layer "In15.Cu")
		(net "GMI_CPU0_G1_CPU1_G3_TX_DP<7>")
	)
	(segment
		(start 119.006366 -241.728752)
		(end 119.004842 -241.727736)
		(width 0.1143)
		(layer "In15.Cu")
		(net "GMI_CPU0_G1_CPU1_G3_TX_DP<7>")
	)
	(segment
		(start 119.04345 -243.3701)
		(end 119.012462 -243.35232)
		(width 0.1143)
		(layer "In15.Cu")
		(net "GMI_CPU0_G1_CPU1_G3_TX_DP<7>")
	)
	(segment
		(start 352.484182 -243.351558)
		(end 352.48342 -243.352066)
		(width 0.1143)
		(layer "In15.Cu")
		(net "GMI_CPU0_G1_CPU1_G3_TX_DP<7>")
	)
	(segment
		(start 352.48342 -246.59209)
		(end 352.452432 -246.60987)
		(width 0.1143)
		(layer "In15.Cu")
		(net "GMI_CPU0_G1_CPU1_G3_TX_DP<7>")
	)
	(segment
		(start 352.490786 -234.280456)
		(end 352.49231 -234.281472)
		(width 0.1143)
		(layer "In15.Cu")
		(net "GMI_CPU0_G1_CPU1_G3_TX_DP<7>")
	)
	(segment
		(start 119.008906 -244.9703)
		(end 119.007382 -244.969284)
		(width 0.1143)
		(layer "In15.Cu")
		(net "GMI_CPU0_G1_CPU1_G3_TX_DP<7>")
	)
	(segment
		(start 119.053102 -244.99697)
		(end 119.04345 -244.990112)
		(width 0.1143)
		(layer "In15.Cu")
		(net "GMI_CPU0_G1_CPU1_G3_TX_DP<7>")
	)
	(segment
		(start 119.012462 -246.592344)
		(end 119.0117 -246.591836)
		(width 0.1143)
		(layer "In15.Cu")
		(net "GMI_CPU0_G1_CPU1_G3_TX_DP<7>")
	)
	(segment
		(start 352.4885 -239.139222)
		(end 352.490786 -239.140492)
		(width 0.1143)
		(layer "In15.Cu")
		(net "GMI_CPU0_G1_CPU1_G3_TX_DP<7>")
	)
	(segment
		(start 352.484182 -241.731546)
		(end 352.48342 -241.732054)
		(width 0.1143)
		(layer "In15.Cu")
		(net "GMI_CPU0_G1_CPU1_G3_TX_DP<7>")
	)
	(segment
		(start 119.010684 -222.937578)
		(end 119.0117 -222.93707)
		(width 0.1143)
		(layer "In15.Cu")
		(net "GMI_CPU0_G1_CPU1_G3_TX_DP<7>")
	)
	(segment
		(start 119.010684 -230.391462)
		(end 118.980204 -230.373682)
		(width 0.1143)
		(layer "In15.Cu")
		(net "GMI_CPU0_G1_CPU1_G3_TX_DP<7>")
	)
	(segment
		(start 352.479102 -237.513622)
		(end 352.483674 -237.516416)
		(width 0.1143)
		(layer "In15.Cu")
		(net "GMI_CPU0_G1_CPU1_G3_TX_DP<7>")
	)
	(segment
		(start 119.01297 -246.592344)
		(end 119.012462 -246.592344)
		(width 0.1143)
		(layer "In15.Cu")
		(net "GMI_CPU0_G1_CPU1_G3_TX_DP<7>")
	)
	(segment
		(start 119.010684 -246.591328)
		(end 119.008906 -246.590312)
		(width 0.1143)
		(layer "In15.Cu")
		(net "GMI_CPU0_G1_CPU1_G3_TX_DP<7>")
	)
	(segment
		(start 119.0117 -241.7318)
		(end 119.010684 -241.731292)
		(width 0.1143)
		(layer "In15.Cu")
		(net "GMI_CPU0_G1_CPU1_G3_TX_DP<7>")
	)
	(segment
		(start 119.0117 -229.416864)
		(end 119.045228 -229.397306)
		(width 0.1143)
		(layer "In15.Cu")
		(net "GMI_CPU0_G1_CPU1_G3_TX_DP<7>")
	)
	(segment
		(start 351.833434 -247.654318)
		(end 351.903284 -247.724168)
		(width 0.1143)
		(layer "In15.Cu")
		(net "GMI_CPU0_G1_CPU1_G3_TX_DP<7>")
	)
	(segment
		(start 352.485198 -236.871002)
		(end 352.484182 -236.87151)
		(width 0.1143)
		(layer "In15.Cu")
		(net "GMI_CPU0_G1_CPU1_G3_TX_DP<7>")
	)
	(segment
		(start 118.972584 -231.059736)
		(end 119.0117 -231.036876)
		(width 0.1143)
		(layer "In15.Cu")
		(net "GMI_CPU0_G1_CPU1_G3_TX_DP<7>")
	)
	(segment
		(start 352.452432 -235.87837)
		(end 352.48342 -235.89615)
		(width 0.1143)
		(layer "In15.Cu")
		(net "GMI_CPU0_G1_CPU1_G3_TX_DP<7>")
	)
	(segment
		(start 352.49231 -232.66146)
		(end 352.523298 -232.679494)
		(width 0.1143)
		(layer "In15.Cu")
		(net "GMI_CPU0_G1_CPU1_G3_TX_DP<7>")
	)
	(segment
		(start 352.484182 -246.591582)
		(end 352.48342 -246.59209)
		(width 0.1143)
		(layer "In15.Cu")
		(net "GMI_CPU0_G1_CPU1_G3_TX_DP<7>")
	)
	(segment
		(start 118.979442 -238.47298)
		(end 118.972584 -238.468916)
		(width 0.1143)
		(layer "In15.Cu")
		(net "GMI_CPU0_G1_CPU1_G3_TX_DP<7>")
	)
	(segment
		(start 118.97995 -235.233464)
		(end 118.980204 -235.233464)
		(width 0.1143)
		(layer "In15.Cu")
		(net "GMI_CPU0_G1_CPU1_G3_TX_DP<7>")
	)
	(segment
		(start 352.485198 -235.25099)
		(end 352.484182 -235.251498)
		(width 0.1143)
		(layer "In15.Cu")
		(net "GMI_CPU0_G1_CPU1_G3_TX_DP<7>")
	)
	(segment
		(start 119.006112 -242.380262)
		(end 119.010684 -242.377468)
		(width 0.1143)
		(layer "In15.Cu")
		(net "GMI_CPU0_G1_CPU1_G3_TX_DP<7>")
	)
	(segment
		(start 119.05361 -225.557588)
		(end 119.04345 -225.550222)
		(width 0.1143)
		(layer "In15.Cu")
		(net "GMI_CPU0_G1_CPU1_G3_TX_DP<7>")
	)
	(segment
		(start 352.485198 -243.35105)
		(end 352.484182 -243.351558)
		(width 0.1143)
		(layer "In15.Cu")
		(net "GMI_CPU0_G1_CPU1_G3_TX_DP<7>")
	)
	(segment
		(start 159.91967 -182.926228)
		(end 160.459674 -182.625238)
		(width 0.14224)
		(layer "In15.Cu")
		(net "GMI_CPU0_G1_CPU1_G3_TX_DP<7>")
	)
	(segment
		(start 119.008906 -225.53041)
		(end 119.007382 -225.529394)
		(width 0.1143)
		(layer "In15.Cu")
		(net "GMI_CPU0_G1_CPU1_G3_TX_DP<7>")
	)
	(segment
		(start 144.222216 -195.402962)
		(end 144.985994 -195.171314)
		(width 0.14224)
		(layer "In15.Cu")
		(net "GMI_CPU0_G1_CPU1_G3_TX_DP<7>")
	)
	(segment
		(start 119.010684 -243.99748)
		(end 119.0117 -243.996972)
		(width 0.1143)
		(layer "In15.Cu")
		(net "GMI_CPU0_G1_CPU1_G3_TX_DP<7>")
	)
	(segment
		(start 119.0117 -240.756948)
		(end 119.0117 -240.757202)
		(width 0.1143)
		(layer "In15.Cu")
		(net "GMI_CPU0_G1_CPU1_G3_TX_DP<7>")
	)
	(segment
		(start 352.490786 -239.140492)
		(end 352.49231 -239.141508)
		(width 0.1143)
		(layer "In15.Cu")
		(net "GMI_CPU0_G1_CPU1_G3_TX_DP<7>")
	)
	(segment
		(start 119.04345 -241.750088)
		(end 119.012462 -241.732308)
		(width 0.1143)
		(layer "In15.Cu")
		(net "GMI_CPU0_G1_CPU1_G3_TX_DP<7>")
	)
	(segment
		(start 119.063262 -223.944434)
		(end 119.04345 -223.93021)
		(width 0.1143)
		(layer "In15.Cu")
		(net "GMI_CPU0_G1_CPU1_G3_TX_DP<7>")
	)
	(segment
		(start 118.972584 -222.95993)
		(end 119.00916 -222.938594)
		(width 0.1143)
		(layer "In15.Cu")
		(net "GMI_CPU0_G1_CPU1_G3_TX_DP<7>")
	)
	(segment
		(start 352.486722 -241.730022)
		(end 352.485198 -241.731038)
		(width 0.1143)
		(layer "In15.Cu")
		(net "GMI_CPU0_G1_CPU1_G3_TX_DP<7>")
	)
	(segment
		(start 119.012462 -243.996464)
		(end 119.04345 -243.978684)
		(width 0.1143)
		(layer "In15.Cu")
		(net "GMI_CPU0_G1_CPU1_G3_TX_DP<7>")
	)
	(segment
		(start 118.972584 -229.439724)
		(end 119.0117 -229.416864)
		(width 0.1143)
		(layer "In15.Cu")
		(net "GMI_CPU0_G1_CPU1_G3_TX_DP<7>")
	)
	(segment
		(start 351.512378 -224.53854)
		(end 351.58045 -224.577656)
		(width 0.1143)
		(layer "In15.Cu")
		(net "GMI_CPU0_G1_CPU1_G3_TX_DP<7>")
	)
	(segment
		(start 352.48342 -243.352066)
		(end 352.452432 -243.369846)
		(width 0.1143)
		(layer "In15.Cu")
		(net "GMI_CPU0_G1_CPU1_G3_TX_DP<7>")
	)
	(segment
		(start 119.008906 -241.730276)
		(end 119.007382 -241.72926)
		(width 0.1143)
		(layer "In15.Cu")
		(net "GMI_CPU0_G1_CPU1_G3_TX_DP<7>")
	)
	(segment
		(start 352.483674 -237.516416)
		(end 352.485198 -237.517178)
		(width 0.1143)
		(layer "In15.Cu")
		(net "GMI_CPU0_G1_CPU1_G3_TX_DP<7>")
	)
	(segment
		(start 119.010684 -227.151438)
		(end 119.008906 -227.150422)
		(width 0.1143)
		(layer "In15.Cu")
		(net "GMI_CPU0_G1_CPU1_G3_TX_DP<7>")
	)
	(segment
		(start 352.49231 -244.001544)
		(end 352.523298 -244.019578)
		(width 0.1143)
		(layer "In15.Cu")
		(net "GMI_CPU0_G1_CPU1_G3_TX_DP<7>")
	)
	(segment
		(start 119.006366 -238.488728)
		(end 119.004842 -238.487712)
		(width 0.1143)
		(layer "In15.Cu")
		(net "GMI_CPU0_G1_CPU1_G3_TX_DP<7>")
	)
	(segment
		(start 352.486722 -240.11001)
		(end 352.485198 -240.111026)
		(width 0.1143)
		(layer "In15.Cu")
		(net "GMI_CPU0_G1_CPU1_G3_TX_DP<7>")
	)
	(segment
		(start 119.010684 -228.77145)
		(end 119.008906 -228.770434)
		(width 0.1143)
		(layer "In15.Cu")
		(net "GMI_CPU0_G1_CPU1_G3_TX_DP<7>")
	)
	(segment
		(start 119.010684 -232.657396)
		(end 119.0117 -232.656888)
		(width 0.1143)
		(layer "In15.Cu")
		(net "GMI_CPU0_G1_CPU1_G3_TX_DP<7>")
	)
	(segment
		(start 119.057166 -238.51997)
		(end 119.04345 -238.510064)
		(width 0.1143)
		(layer "In15.Cu")
		(net "GMI_CPU0_G1_CPU1_G3_TX_DP<7>")
	)
	(segment
		(start 352.485198 -235.897166)
		(end 352.4885 -235.899198)
		(width 0.1143)
		(layer "In15.Cu")
		(net "GMI_CPU0_G1_CPU1_G3_TX_DP<7>")
	)
	(segment
		(start 352.4758 -237.511844)
		(end 352.479102 -237.513622)
		(width 0.1143)
		(layer "In15.Cu")
		(net "GMI_CPU0_G1_CPU1_G3_TX_DP<7>")
	)
	(segment
		(start 352.485198 -232.010966)
		(end 352.484182 -232.011474)
		(width 0.1143)
		(layer "In15.Cu")
		(net "GMI_CPU0_G1_CPU1_G3_TX_DP<7>")
	)
	(segment
		(start 119.007382 -241.72926)
		(end 119.006366 -241.728752)
		(width 0.1143)
		(layer "In15.Cu")
		(net "GMI_CPU0_G1_CPU1_G3_TX_DP<7>")
	)
	(segment
		(start 352.483674 -245.616476)
		(end 352.485198 -245.617238)
		(width 0.1143)
		(layer "In15.Cu")
		(net "GMI_CPU0_G1_CPU1_G3_TX_DP<7>")
	)
	(segment
		(start 352.523298 -244.94871)
		(end 352.486722 -244.970046)
		(width 0.1143)
		(layer "In15.Cu")
		(net "GMI_CPU0_G1_CPU1_G3_TX_DP<7>")
	)
	(segment
		(start 118.972584 -239.159796)
		(end 119.00916 -239.13846)
		(width 0.1143)
		(layer "In15.Cu")
		(net "GMI_CPU0_G1_CPU1_G3_TX_DP<7>")
	)
	(segment
		(start 119.010684 -226.177602)
		(end 119.0117 -226.177094)
		(width 0.1143)
		(layer "In15.Cu")
		(net "GMI_CPU0_G1_CPU1_G3_TX_DP<7>")
	)
	(segment
		(start 352.523298 -246.568722)
		(end 352.486722 -246.590058)
		(width 0.1143)
		(layer "In15.Cu")
		(net "GMI_CPU0_G1_CPU1_G3_TX_DP<7>")
	)
	(segment
		(start 119.006366 -227.148898)
		(end 119.004842 -227.147882)
		(width 0.1143)
		(layer "In15.Cu")
		(net "GMI_CPU0_G1_CPU1_G3_TX_DP<7>")
	)
	(segment
		(start 118.972584 -226.199954)
		(end 119.010684 -226.177602)
		(width 0.1143)
		(layer "In15.Cu")
		(net "GMI_CPU0_G1_CPU1_G3_TX_DP<7>")
	)
	(segment
		(start 118.980204 -238.473488)
		(end 118.979442 -238.47298)
		(width 0.1143)
		(layer "In15.Cu")
		(net "GMI_CPU0_G1_CPU1_G3_TX_DP<7>")
	)
	(segment
		(start 352.486722 -246.590058)
		(end 352.485198 -246.591074)
		(width 0.1143)
		(layer "In15.Cu")
		(net "GMI_CPU0_G1_CPU1_G3_TX_DP<7>")
	)
	(segment
		(start 119.04345 -222.918782)
		(end 119.059198 -222.907352)
		(width 0.1143)
		(layer "In15.Cu")
		(net "GMI_CPU0_G1_CPU1_G3_TX_DP<7>")
	)
	(segment
		(start 352.485198 -239.13719)
		(end 352.4885 -239.139222)
		(width 0.1143)
		(layer "In15.Cu")
		(net "GMI_CPU0_G1_CPU1_G3_TX_DP<7>")
	)
	(segment
		(start 119.0117 -245.616984)
		(end 119.012462 -245.616476)
		(width 0.1143)
		(layer "In15.Cu")
		(net "GMI_CPU0_G1_CPU1_G3_TX_DP<7>")
	)
	(segment
		(start 119.04345 -227.170234)
		(end 119.012462 -227.152454)
		(width 0.1143)
		(layer "In15.Cu")
		(net "GMI_CPU0_G1_CPU1_G3_TX_DP<7>")
	)
	(segment
		(start 119.008906 -243.350288)
		(end 119.007382 -243.349272)
		(width 0.1143)
		(layer "In15.Cu")
		(net "GMI_CPU0_G1_CPU1_G3_TX_DP<7>")
	)
	(segment
		(start 119.04345 -245.598696)
		(end 119.053102 -245.591838)
		(width 0.1143)
		(layer "In15.Cu")
		(net "GMI_CPU0_G1_CPU1_G3_TX_DP<7>")
	)
	(segment
		(start 119.010684 -239.137444)
		(end 119.0117 -239.136936)
		(width 0.1143)
		(layer "In15.Cu")
		(net "GMI_CPU0_G1_CPU1_G3_TX_DP<7>")
	)
	(segment
		(start 352.523298 -243.328698)
		(end 352.486722 -243.350034)
		(width 0.1143)
		(layer "In15.Cu")
		(net "GMI_CPU0_G1_CPU1_G3_TX_DP<7>")
	)
	(segment
		(start 118.979442 -231.992932)
		(end 118.972584 -231.988868)
		(width 0.1143)
		(layer "In15.Cu")
		(net "GMI_CPU0_G1_CPU1_G3_TX_DP<7>")
	)
	(segment
		(start 352.486722 -236.869986)
		(end 352.485198 -236.871002)
		(width 0.1143)
		(layer "In15.Cu")
		(net "GMI_CPU0_G1_CPU1_G3_TX_DP<7>")
	)
	(segment
		(start 352.452432 -245.598442)
		(end 352.47453 -245.611142)
		(width 0.1143)
		(layer "In15.Cu")
		(net "GMI_CPU0_G1_CPU1_G3_TX_DP<7>")
	)
	(segment
		(start 352.48342 -236.872018)
		(end 352.452432 -236.889798)
		(width 0.1143)
		(layer "In15.Cu")
		(net "GMI_CPU0_G1_CPU1_G3_TX_DP<7>")
	)
	(segment
		(start 352.523298 -241.708686)
		(end 352.486722 -241.730022)
		(width 0.1143)
		(layer "In15.Cu")
		(net "GMI_CPU0_G1_CPU1_G3_TX_DP<7>")
	)
	(segment
		(start 119.010684 -243.351304)
		(end 119.008906 -243.350288)
		(width 0.1143)
		(layer "In15.Cu")
		(net "GMI_CPU0_G1_CPU1_G3_TX_DP<7>")
	)
	(segment
		(start 352.485198 -232.657142)
		(end 352.4885 -232.659174)
		(width 0.1143)
		(layer "In15.Cu")
		(net "GMI_CPU0_G1_CPU1_G3_TX_DP<7>")
	)
	(segment
		(start 119.013478 -230.392986)
		(end 119.010684 -230.391462)
		(width 0.1143)
		(layer "In15.Cu")
		(net "GMI_CPU0_G1_CPU1_G3_TX_DP<7>")
	)
	(segment
		(start 119.004842 -232.007664)
		(end 118.980204 -231.99344)
		(width 0.1143)
		(layer "In15.Cu")
		(net "GMI_CPU0_G1_CPU1_G3_TX_DP<7>")
	)
	(segment
		(start 352.450654 -229.397052)
		(end 352.520504 -229.437692)
		(width 0.1143)
		(layer "In15.Cu")
		(net "GMI_CPU0_G1_CPU1_G3_TX_DP<7>")
	)
	(segment
		(start 119.0117 -237.516924)
		(end 119.0117 -237.517178)
		(width 0.1143)
		(layer "In15.Cu")
		(net "GMI_CPU0_G1_CPU1_G3_TX_DP<7>")
	)
	(segment
		(start 352.485198 -240.111026)
		(end 352.484182 -240.111534)
		(width 0.1143)
		(layer "In15.Cu")
		(net "GMI_CPU0_G1_CPU1_G3_TX_DP<7>")
	)
	(segment
		(start 119.006366 -228.76891)
		(end 119.004842 -228.767894)
		(width 0.1143)
		(layer "In15.Cu")
		(net "GMI_CPU0_G1_CPU1_G3_TX_DP<7>")
	)
	(segment
		(start 118.972584 -235.919772)
		(end 119.010684 -235.89742)
		(width 0.1143)
		(layer "In15.Cu")
		(net "GMI_CPU0_G1_CPU1_G3_TX_DP<7>")
	)
	(segment
		(start 352.485198 -234.277154)
		(end 352.4885 -234.279186)
		(width 0.1143)
		(layer "In15.Cu")
		(net "GMI_CPU0_G1_CPU1_G3_TX_DP<7>")
	)
	(segment
		(start 352.453702 -227.779072)
		(end 352.523298 -227.819712)
		(width 0.1143)
		(layer "In15.Cu")
		(net "GMI_CPU0_G1_CPU1_G3_TX_DP<7>")
	)
	(segment
		(start 119.01297 -228.77272)
		(end 119.012462 -228.772466)
		(width 0.1143)
		(layer "In15.Cu")
		(net "GMI_CPU0_G1_CPU1_G3_TX_DP<7>")
	)
	(segment
		(start 119.012462 -226.176586)
		(end 119.04345 -226.158806)
		(width 0.1143)
		(layer "In15.Cu")
		(net "GMI_CPU0_G1_CPU1_G3_TX_DP<7>")
	)
	(segment
		(start 118.979442 -244.953028)
		(end 118.972584 -244.948964)
		(width 0.1143)
		(layer "In15.Cu")
		(net "GMI_CPU0_G1_CPU1_G3_TX_DP<7>")
	)
	(segment
		(start 119.026686 -246.600218)
		(end 119.01297 -246.592344)
		(width 0.1143)
		(layer "In15.Cu")
		(net "GMI_CPU0_G1_CPU1_G3_TX_DP<7>")
	)
	(segment
		(start 119.04345 -225.550222)
		(end 119.012462 -225.532442)
		(width 0.1143)
		(layer "In15.Cu")
		(net "GMI_CPU0_G1_CPU1_G3_TX_DP<7>")
	)
	(segment
		(start 118.972584 -227.819966)
		(end 119.00916 -227.79863)
		(width 0.1143)
		(layer "In15.Cu")
		(net "GMI_CPU0_G1_CPU1_G3_TX_DP<7>")
	)
	(segment
		(start 352.485198 -245.617238)
		(end 352.523298 -245.63959)
		(width 0.1143)
		(layer "In15.Cu")
		(net "GMI_CPU0_G1_CPU1_G3_TX_DP<7>")
	)
	(segment
		(start 119.05361 -241.757454)
		(end 119.04345 -241.750088)
		(width 0.1143)
		(layer "In15.Cu")
		(net "GMI_CPU0_G1_CPU1_G3_TX_DP<7>")
	)
	(segment
		(start 119.008906 -238.490252)
		(end 119.007382 -238.489236)
		(width 0.1143)
		(layer "In15.Cu")
		(net "GMI_CPU0_G1_CPU1_G3_TX_DP<7>")
	)
	(segment
		(start 118.980204 -228.75367)
		(end 118.979442 -228.753162)
		(width 0.1143)
		(layer "In15.Cu")
		(net "GMI_CPU0_G1_CPU1_G3_TX_DP<7>")
	)
	(segment
		(start 351.791778 -221.308422)
		(end 351.82683 -221.343474)
		(width 0.1143)
		(layer "In15.Cu")
		(net "GMI_CPU0_G1_CPU1_G3_TX_DP<7>")
	)
	(segment
		(start 119.0117 -228.771958)
		(end 119.010684 -228.77145)
		(width 0.1143)
		(layer "In15.Cu")
		(net "GMI_CPU0_G1_CPU1_G3_TX_DP<7>")
	)
	(segment
		(start 118.979442 -230.373174)
		(end 118.975124 -230.370634)
		(width 0.1143)
		(layer "In15.Cu")
		(net "GMI_CPU0_G1_CPU1_G3_TX_DP<7>")
	)
	(segment
		(start 118.972584 -237.539784)
		(end 119.00916 -237.518448)
		(width 0.1143)
		(layer "In15.Cu")
		(net "GMI_CPU0_G1_CPU1_G3_TX_DP<7>")
	)
	(segment
		(start 152.080722 -189.35446)
		(end 159.91967 -182.926228)
		(width 0.14224)
		(layer "In15.Cu")
		(net "GMI_CPU0_G1_CPU1_G3_TX_DP<7>")
	)
	(segment
		(start 352.483674 -242.376452)
		(end 352.485198 -242.377214)
		(width 0.1143)
		(layer "In15.Cu")
		(net "GMI_CPU0_G1_CPU1_G3_TX_DP<7>")
	)
	(segment
		(start 119.0117 -246.591836)
		(end 119.010684 -246.591328)
		(width 0.1143)
		(layer "In15.Cu")
		(net "GMI_CPU0_G1_CPU1_G3_TX_DP<7>")
	)
	(segment
		(start 160.459674 -182.625238)
		(end 166.178738 -180.579776)
		(width 0.14224)
		(layer "In15.Cu")
		(net "GMI_CPU0_G1_CPU1_G3_TX_DP<7>")
	)
	(segment
		(start 352.523298 -233.608626)
		(end 352.486722 -233.629962)
		(width 0.1143)
		(layer "In15.Cu")
		(net "GMI_CPU0_G1_CPU1_G3_TX_DP<7>")
	)
	(segment
		(start 119.004842 -243.347748)
		(end 118.980204 -243.333524)
		(width 0.1143)
		(layer "In15.Cu")
		(net "GMI_CPU0_G1_CPU1_G3_TX_DP<7>")
	)
	(segment
		(start 352.48342 -243.99621)
		(end 352.485198 -243.997226)
		(width 0.1143)
		(layer "In15.Cu")
		(net "GMI_CPU0_G1_CPU1_G3_TX_DP<7>")
	)
	(segment
		(start 118.972584 -245.639844)
		(end 119.00916 -245.618508)
		(width 0.1143)
		(layer "In15.Cu")
		(net "GMI_CPU0_G1_CPU1_G3_TX_DP<7>")
	)
	(segment
		(start 352.523298 -231.988614)
		(end 352.486722 -232.00995)
		(width 0.1143)
		(layer "In15.Cu")
		(net "GMI_CPU0_G1_CPU1_G3_TX_DP<7>")
	)
	(segment
		(start 119.010176 -235.250736)
		(end 118.98122 -235.234226)
		(width 0.1143)
		(layer "In15.Cu")
		(net "GMI_CPU0_G1_CPU1_G3_TX_DP<7>")
	)
	(segment
		(start 118.972584 -244.019832)
		(end 119.00916 -243.998496)
		(width 0.1143)
		(layer "In15.Cu")
		(net "GMI_CPU0_G1_CPU1_G3_TX_DP<7>")
	)
	(segment
		(start 119.007382 -238.489236)
		(end 119.006366 -238.488728)
		(width 0.1143)
		(layer "In15.Cu")
		(net "GMI_CPU0_G1_CPU1_G3_TX_DP<7>")
	)
	(segment
		(start 119.294656 -247.724422)
		(end 119.592598 -247.724422)
		(width 0.1143)
		(layer "In15.Cu")
		(net "GMI_CPU0_G1_CPU1_G3_TX_DP<7>")
	)
	(segment
		(start 118.98122 -236.854238)
		(end 118.97995 -236.853476)
		(width 0.1143)
		(layer "In15.Cu")
		(net "GMI_CPU0_G1_CPU1_G3_TX_DP<7>")
	)
	(segment
		(start 352.47453 -237.511082)
		(end 352.4758 -237.511844)
		(width 0.1143)
		(layer "In15.Cu")
		(net "GMI_CPU0_G1_CPU1_G3_TX_DP<7>")
	)
	(segment
		(start 352.482658 -238.492284)
		(end 352.481896 -238.492792)
		(width 0.1143)
		(layer "In15.Cu")
		(net "GMI_CPU0_G1_CPU1_G3_TX_DP<7>")
	)
	(segment
		(start 352.481896 -238.492792)
		(end 352.48088 -238.4933)
		(width 0.1143)
		(layer "In15.Cu")
		(net "GMI_CPU0_G1_CPU1_G3_TX_DP<7>")
	)
	(segment
		(start 119.012462 -232.012236)
		(end 119.0117 -232.011728)
		(width 0.1143)
		(layer "In15.Cu")
		(net "GMI_CPU0_G1_CPU1_G3_TX_DP<7>")
	)
	(segment
		(start 302.899064 -181.377336)
		(end 307.267102 -181.377336)
		(width 0.14224)
		(layer "In15.Cu")
		(net "GMI_CPU0_G1_CPU1_G3_TX_DP<7>")
	)
	(segment
		(start 118.972584 -240.091468)
		(end 118.972584 -240.088928)
		(width 0.1143)
		(layer "In15.Cu")
		(net "GMI_CPU0_G1_CPU1_G3_TX_DP<7>")
	)
	(segment
		(start 352.00971 -225.36404)
		(end 352.01352 -225.366326)
		(width 0.1143)
		(layer "In15.Cu")
		(net "GMI_CPU0_G1_CPU1_G3_TX_DP<7>")
	)
	(segment
		(start 352.48342 -234.276138)
		(end 352.485198 -234.277154)
		(width 0.1143)
		(layer "In15.Cu")
		(net "GMI_CPU0_G1_CPU1_G3_TX_DP<7>")
	)
	(segment
		(start 119.010684 -227.797614)
		(end 119.0117 -227.797106)
		(width 0.1143)
		(layer "In15.Cu")
		(net "GMI_CPU0_G1_CPU1_G3_TX_DP<7>")
	)
	(segment
		(start 119.012462 -238.492284)
		(end 119.0117 -238.491776)
		(width 0.1143)
		(layer "In15.Cu")
		(net "GMI_CPU0_G1_CPU1_G3_TX_DP<7>")
	)
	(segment
		(start 315.461142 -185.694066)
		(end 348.053914 -212.419184)
		(width 0.14224)
		(layer "In15.Cu")
		(net "GMI_CPU0_G1_CPU1_G3_TX_DP<7>")
	)
	(segment
		(start 118.979442 -227.13315)
		(end 118.972584 -227.129086)
		(width 0.1143)
		(layer "In15.Cu")
		(net "GMI_CPU0_G1_CPU1_G3_TX_DP<7>")
	)
	(segment
		(start 119.008906 -227.150422)
		(end 119.007382 -227.149406)
		(width 0.1143)
		(layer "In15.Cu")
		(net "GMI_CPU0_G1_CPU1_G3_TX_DP<7>")
	)
	(segment
		(start 352.523298 -235.228638)
		(end 352.486722 -235.249974)
		(width 0.1143)
		(layer "In15.Cu")
		(net "GMI_CPU0_G1_CPU1_G3_TX_DP<7>")
	)
	(segment
		(start 352.485198 -233.630978)
		(end 352.484182 -233.631486)
		(width 0.1143)
		(layer "In15.Cu")
		(net "GMI_CPU0_G1_CPU1_G3_TX_DP<7>")
	)
	(segment
		(start 352.053144 -247.378728)
		(end 351.983548 -247.419368)
		(width 0.1143)
		(layer "In15.Cu")
		(net "GMI_CPU0_G1_CPU1_G3_TX_DP<7>")
	)
	(segment
		(start 352.452432 -237.498382)
		(end 352.47453 -237.511082)
		(width 0.1143)
		(layer "In15.Cu")
		(net "GMI_CPU0_G1_CPU1_G3_TX_DP<7>")
	)
	(segment
		(start 118.980204 -230.373682)
		(end 118.979442 -230.373174)
		(width 0.1143)
		(layer "In15.Cu")
		(net "GMI_CPU0_G1_CPU1_G3_TX_DP<7>")
	)
	(segment
		(start 118.979442 -228.753162)
		(end 118.972584 -228.749098)
		(width 0.1143)
		(layer "In15.Cu")
		(net "GMI_CPU0_G1_CPU1_G3_TX_DP<7>")
	)
	(segment
		(start 118.729252 -221.316804)
		(end 118.69039 -221.277942)
		(width 0.1143)
		(layer "In15.Cu")
		(net "GMI_CPU0_G1_CPU1_G3_TX_DP<7>")
	)
	(segment
		(start 119.00916 -227.79863)
		(end 119.010684 -227.797614)
		(width 0.1143)
		(layer "In15.Cu")
		(net "GMI_CPU0_G1_CPU1_G3_TX_DP<7>")
	)
	(segment
		(start 119.00916 -243.998496)
		(end 119.010684 -243.99748)
		(width 0.1143)
		(layer "In15.Cu")
		(net "GMI_CPU0_G1_CPU1_G3_TX_DP<7>")
	)
	(segment
		(start 352.523298 -227.128832)
		(end 352.453702 -227.169472)
		(width 0.1143)
		(layer "In15.Cu")
		(net "GMI_CPU0_G1_CPU1_G3_TX_DP<7>")
	)
	(segment
		(start 118.980204 -227.133658)
		(end 118.979442 -227.13315)
		(width 0.1143)
		(layer "In15.Cu")
		(net "GMI_CPU0_G1_CPU1_G3_TX_DP<7>")
	)
	(segment
		(start 352.452432 -232.638346)
		(end 352.48342 -232.656126)
		(width 0.1143)
		(layer "In15.Cu")
		(net "GMI_CPU0_G1_CPU1_G3_TX_DP<7>")
	)
	(segment
		(start 119.006366 -225.528886)
		(end 119.004842 -225.52787)
		(width 0.1143)
		(layer "In15.Cu")
		(net "GMI_CPU0_G1_CPU1_G3_TX_DP<7>")
	)
	(segment
		(start 352.48342 -240.756186)
		(end 352.485198 -240.757202)
		(width 0.1143)
		(layer "In15.Cu")
		(net "GMI_CPU0_G1_CPU1_G3_TX_DP<7>")
	)
	(segment
		(start 119.0117 -237.517178)
		(end 119.012208 -237.516924)
		(width 0.1143)
		(layer "In15.Cu")
		(net "GMI_CPU0_G1_CPU1_G3_TX_DP<7>")
	)
	(segment
		(start 119.010684 -242.377468)
		(end 119.0117 -242.37696)
		(width 0.1143)
		(layer "In15.Cu")
		(net "GMI_CPU0_G1_CPU1_G3_TX_DP<7>")
	)
	(segment
		(start 118.979442 -235.232956)
		(end 118.972584 -235.228892)
		(width 0.1143)
		(layer "In15.Cu")
		(net "GMI_CPU0_G1_CPU1_G3_TX_DP<7>")
	)
	(segment
		(start 119.04345 -242.358672)
		(end 119.05361 -242.351306)
		(width 0.1143)
		(layer "In15.Cu")
		(net "GMI_CPU0_G1_CPU1_G3_TX_DP<7>")
	)
	(segment
		(start 119.51335 -247.420384)
		(end 119.481854 -247.401842)
		(width 0.1143)
		(layer "In15.Cu")
		(net "GMI_CPU0_G1_CPU1_G3_TX_DP<7>")
	)
	(segment
		(start 118.980204 -244.953536)
		(end 118.979442 -244.953028)
		(width 0.1143)
		(layer "In15.Cu")
		(net "GMI_CPU0_G1_CPU1_G3_TX_DP<7>")
	)
	(segment
		(start 119.00916 -240.758472)
		(end 119.010684 -240.757456)
		(width 0.1143)
		(layer "In15.Cu")
		(net "GMI_CPU0_G1_CPU1_G3_TX_DP<7>")
	)
	(segment
		(start 118.979442 -241.713004)
		(end 118.972584 -241.70894)
		(width 0.1143)
		(layer "In15.Cu")
		(net "GMI_CPU0_G1_CPU1_G3_TX_DP<7>")
	)
	(segment
		(start 119.006366 -233.628692)
		(end 119.004842 -233.627676)
		(width 0.1143)
		(layer "In15.Cu")
		(net "GMI_CPU0_G1_CPU1_G3_TX_DP<7>")
	)
	(segment
		(start 119.0117 -243.996972)
		(end 119.012462 -243.996464)
		(width 0.1143)
		(layer "In15.Cu")
		(net "GMI_CPU0_G1_CPU1_G3_TX_DP<7>")
	)
	(segment
		(start 119.012462 -222.936562)
		(end 119.04345 -222.918782)
		(width 0.1143)
		(layer "In15.Cu")
		(net "GMI_CPU0_G1_CPU1_G3_TX_DP<7>")
	)
	(segment
		(start 351.982532 -225.348546)
		(end 352.005646 -225.3615)
		(width 0.1143)
		(layer "In15.Cu")
		(net "GMI_CPU0_G1_CPU1_G3_TX_DP<7>")
	)
	(segment
		(start 119.012462 -227.152454)
		(end 119.0117 -227.151946)
		(width 0.1143)
		(layer "In15.Cu")
		(net "GMI_CPU0_G1_CPU1_G3_TX_DP<7>")
	)
	(segment
		(start 118.69039 -221.277942)
		(end 118.69039 -221.066106)
		(width 0.1143)
		(layer "In15.Cu")
		(net "GMI_CPU0_G1_CPU1_G3_TX_DP<7>")
	)
	(segment
		(start 352.48342 -241.732054)
		(end 352.452432 -241.749834)
		(width 0.1143)
		(layer "In15.Cu")
		(net "GMI_CPU0_G1_CPU1_G3_TX_DP<7>")
	)
	(segment
		(start 352.014282 -225.366834)
		(end 352.045778 -225.385122)
		(width 0.1143)
		(layer "In15.Cu")
		(net "GMI_CPU0_G1_CPU1_G3_TX_DP<7>")
	)
	(segment
		(start 119.008906 -233.630216)
		(end 119.007382 -233.6292)
		(width 0.1143)
		(layer "In15.Cu")
		(net "GMI_CPU0_G1_CPU1_G3_TX_DP<7>")
	)
	(segment
		(start 119.007382 -225.529394)
		(end 119.006366 -225.528886)
		(width 0.1143)
		(layer "In15.Cu")
		(net "GMI_CPU0_G1_CPU1_G3_TX_DP<7>")
	)
	(segment
		(start 119.0117 -240.757202)
		(end 119.012208 -240.756948)
		(width 0.1143)
		(layer "In15.Cu")
		(net "GMI_CPU0_G1_CPU1_G3_TX_DP<7>")
	)
	(segment
		(start 352.47453 -242.371118)
		(end 352.4758 -242.37188)
		(width 0.1143)
		(layer "In15.Cu")
		(net "GMI_CPU0_G1_CPU1_G3_TX_DP<7>")
	)
	(segment
		(start 119.007382 -244.969284)
		(end 119.006366 -244.968776)
		(width 0.1143)
		(layer "In15.Cu")
		(net "GMI_CPU0_G1_CPU1_G3_TX_DP<7>")
	)
	(segment
		(start 352.486722 -233.629962)
		(end 352.485198 -233.630978)
		(width 0.1143)
		(layer "In15.Cu")
		(net "GMI_CPU0_G1_CPU1_G3_TX_DP<7>")
	)
	(segment
		(start 352.4758 -245.611904)
		(end 352.479102 -245.613682)
		(width 0.1143)
		(layer "In15.Cu")
		(net "GMI_CPU0_G1_CPU1_G3_TX_DP<7>")
	)
	(segment
		(start 307.267102 -181.377336)
		(end 308.81066 -181.929532)
		(width 0.14224)
		(layer "In15.Cu")
		(net "GMI_CPU0_G1_CPU1_G3_TX_DP<7>")
	)
	(segment
		(start 119.008906 -246.590312)
		(end 119.007382 -246.589296)
		(width 0.1143)
		(layer "In15.Cu")
		(net "GMI_CPU0_G1_CPU1_G3_TX_DP<7>")
	)
	(segment
		(start 119.012462 -223.91243)
		(end 119.0117 -223.911922)
		(width 0.1143)
		(layer "In15.Cu")
		(net "GMI_CPU0_G1_CPU1_G3_TX_DP<7>")
	)
	(segment
		(start 119.04345 -226.158806)
		(end 119.05361 -226.15144)
		(width 0.1143)
		(layer "In15.Cu")
		(net "GMI_CPU0_G1_CPU1_G3_TX_DP<7>")
	)
	(segment
		(start 119.010684 -225.531426)
		(end 119.008906 -225.53041)
		(width 0.1143)
		(layer "In15.Cu")
		(net "GMI_CPU0_G1_CPU1_G3_TX_DP<7>")
	)
	(segment
		(start 351.54108 -223.913446)
		(end 351.540318 -223.913954)
		(width 0.1143)
		(layer "In15.Cu")
		(net "GMI_CPU0_G1_CPU1_G3_TX_DP<7>")
	)
	(segment
		(start 119.004842 -246.587772)
		(end 118.980204 -246.573548)
		(width 0.1143)
		(layer "In15.Cu")
		(net "GMI_CPU0_G1_CPU1_G3_TX_DP<7>")
	)
	(segment
		(start 119.0117 -243.351812)
		(end 119.010684 -243.351304)
		(width 0.1143)
		(layer "In15.Cu")
		(net "GMI_CPU0_G1_CPU1_G3_TX_DP<7>")
	)
	(segment
		(start 352.490786 -232.660444)
		(end 352.49231 -232.66146)
		(width 0.1143)
		(layer "In15.Cu")
		(net "GMI_CPU0_G1_CPU1_G3_TX_DP<7>")
	)
	(segment
		(start 352.490786 -235.900468)
		(end 352.49231 -235.901484)
		(width 0.1143)
		(layer "In15.Cu")
		(net "GMI_CPU0_G1_CPU1_G3_TX_DP<7>")
	)
	(segment
		(start 352.452432 -234.258358)
		(end 352.48342 -234.276138)
		(width 0.1143)
		(layer "In15.Cu")
		(net "GMI_CPU0_G1_CPU1_G3_TX_DP<7>")
	)
	(segment
		(start 119.012462 -244.972332)
		(end 119.0117 -244.971824)
		(width 0.1143)
		(layer "In15.Cu")
		(net "GMI_CPU0_G1_CPU1_G3_TX_DP<7>")
	)
	(segment
		(start 119.010684 -233.631232)
		(end 119.008906 -233.630216)
		(width 0.1143)
		(layer "In15.Cu")
		(net "GMI_CPU0_G1_CPU1_G3_TX_DP<7>")
	)
	(segment
		(start 352.4885 -235.899198)
		(end 352.490786 -235.900468)
		(width 0.1143)
		(layer "In15.Cu")
		(net "GMI_CPU0_G1_CPU1_G3_TX_DP<7>")
	)
	(segment
		(start 118.980204 -233.613452)
		(end 118.979442 -233.612944)
		(width 0.1143)
		(layer "In15.Cu")
		(net "GMI_CPU0_G1_CPU1_G3_TX_DP<7>")
	)
	(segment
		(start 351.545144 -223.91116)
		(end 351.54108 -223.913446)
		(width 0.1143)
		(layer "In15.Cu")
		(net "GMI_CPU0_G1_CPU1_G3_TX_DP<7>")
	)
	(segment
		(start 352.48342 -232.656126)
		(end 352.485198 -232.657142)
		(width 0.1143)
		(layer "In15.Cu")
		(net "GMI_CPU0_G1_CPU1_G3_TX_DP<7>")
	)
	(segment
		(start 119.004842 -241.727736)
		(end 118.980204 -241.713512)
		(width 0.1143)
		(layer "In15.Cu")
		(net "GMI_CPU0_G1_CPU1_G3_TX_DP<7>")
	)
	(segment
		(start 118.972584 -242.39982)
		(end 119.006112 -242.380262)
		(width 0.1143)
		(layer "In15.Cu")
		(net "GMI_CPU0_G1_CPU1_G3_TX_DP<7>")
	)
	(segment
		(start 352.48342 -235.89615)
		(end 352.485198 -235.897166)
		(width 0.1143)
		(layer "In15.Cu")
		(net "GMI_CPU0_G1_CPU1_G3_TX_DP<7>")
	)
	(segment
		(start 119.04345 -232.6386)
		(end 119.050054 -232.633774)
		(width 0.1143)
		(layer "In15.Cu")
		(net "GMI_CPU0_G1_CPU1_G3_TX_DP<7>")
	)
	(segment
		(start 119.010684 -234.277408)
		(end 119.0117 -234.2769)
		(width 0.1143)
		(layer "In15.Cu")
		(net "GMI_CPU0_G1_CPU1_G3_TX_DP<7>")
	)
	(segment
		(start 352.479102 -242.373658)
		(end 352.483674 -242.376452)
		(width 0.1143)
		(layer "In15.Cu")
		(net "GMI_CPU0_G1_CPU1_G3_TX_DP<7>")
	)
	(segment
		(start 119.010684 -245.617492)
		(end 119.0117 -245.616984)
		(width 0.1143)
		(layer "In15.Cu")
		(net "GMI_CPU0_G1_CPU1_G3_TX_DP<7>")
	)
	(segment
		(start 352.485198 -242.377214)
		(end 352.523298 -242.399566)
		(width 0.1143)
		(layer "In15.Cu")
		(net "GMI_CPU0_G1_CPU1_G3_TX_DP<7>")
	)
	(segment
		(start 146.953732 -193.557906)
		(end 152.080468 -189.353952)
		(width 0.14224)
		(layer "In15.Cu")
		(net "GMI_CPU0_G1_CPU1_G3_TX_DP<7>")
	)
	(segment
		(start 119.04345 -238.510064)
		(end 119.012462 -238.492284)
		(width 0.1143)
		(layer "In15.Cu")
		(net "GMI_CPU0_G1_CPU1_G3_TX_DP<7>")
	)
	(segment
		(start 352.484182 -232.011474)
		(end 352.48342 -232.011982)
		(width 0.1143)
		(layer "In15.Cu")
		(net "GMI_CPU0_G1_CPU1_G3_TX_DP<7>")
	)
	(segment
		(start 352.01352 -225.366326)
		(end 352.014282 -225.366834)
		(width 0.1143)
		(layer "In15.Cu")
		(net "GMI_CPU0_G1_CPU1_G3_TX_DP<7>")
	)
	(segment
		(start 144.985994 -195.171314)
		(end 146.953986 -193.557906)
		(width 0.14224)
		(layer "In15.Cu")
		(net "GMI_CPU0_G1_CPU1_G3_TX_DP<7>")
	)
	(segment
		(start 119.007382 -223.909382)
		(end 119.006366 -223.908874)
		(width 0.1143)
		(layer "In15.Cu")
		(net "GMI_CPU0_G1_CPU1_G3_TX_DP<7>")
	)
	(segment
		(start 118.979442 -236.852968)
		(end 118.972584 -236.848904)
		(width 0.1143)
		(layer "In15.Cu")
		(net "GMI_CPU0_G1_CPU1_G3_TX_DP<7>")
	)
	(segment
		(start 119.0117 -231.036876)
		(end 119.045228 -231.017318)
		(width 0.1143)
		(layer "In15.Cu")
		(net "GMI_CPU0_G1_CPU1_G3_TX_DP<7>")
	)
	(segment
		(start 119.00916 -245.618508)
		(end 119.010684 -245.617492)
		(width 0.1143)
		(layer "In15.Cu")
		(net "GMI_CPU0_G1_CPU1_G3_TX_DP<7>")
	)
	(segment
		(start 118.972584 -224.579942)
		(end 119.00916 -224.558606)
		(width 0.1143)
		(layer "In15.Cu")
		(net "GMI_CPU0_G1_CPU1_G3_TX_DP<7>")
	)
	(segment
		(start 352.486722 -243.350034)
		(end 352.485198 -243.35105)
		(width 0.1143)
		(layer "In15.Cu")
		(net "GMI_CPU0_G1_CPU1_G3_TX_DP<7>")
	)
	(segment
		(start 119.007382 -228.769418)
		(end 119.006366 -228.76891)
		(width 0.1143)
		(layer "In15.Cu")
		(net "GMI_CPU0_G1_CPU1_G3_TX_DP<7>")
	)
	(segment
		(start 119.04345 -224.538794)
		(end 119.063262 -224.52457)
		(width 0.1143)
		(layer "In15.Cu")
		(net "GMI_CPU0_G1_CPU1_G3_TX_DP<7>")
	)
	(segment
		(start 118.997476 -240.104422)
		(end 118.972584 -240.091468)
		(width 0.1143)
		(layer "In15.Cu")
		(net "GMI_CPU0_G1_CPU1_G3_TX_DP<7>")
	)
	(segment
		(start 119.04345 -244.990112)
		(end 119.012462 -244.972332)
		(width 0.1143)
		(layer "In15.Cu")
		(net "GMI_CPU0_G1_CPU1_G3_TX_DP<7>")
	)
	(segment
		(start 118.980204 -236.853476)
		(end 118.979442 -236.852968)
		(width 0.1143)
		(layer "In15.Cu")
		(net "GMI_CPU0_G1_CPU1_G3_TX_DP<7>")
	)
	(segment
		(start 118.980204 -223.893634)
		(end 118.979442 -223.893126)
		(width 0.1143)
		(layer "In15.Cu")
		(net "GMI_CPU0_G1_CPU1_G3_TX_DP<7>")
	)
	(segment
		(start 352.4885 -243.999258)
		(end 352.490786 -244.000528)
		(width 0.1143)
		(layer "In15.Cu")
		(net "GMI_CPU0_G1_CPU1_G3_TX_DP<7>")
	)
	(segment
		(start 119.212106 -246.934228)
		(end 119.212106 -246.922798)
		(width 0.1143)
		(layer "In15.Cu")
		(net "GMI_CPU0_G1_CPU1_G3_TX_DP<7>")
	)
	(segment
		(start 351.536254 -222.93199)
		(end 351.58172 -222.95866)
		(width 0.1143)
		(layer "In15.Cu")
		(net "GMI_CPU0_G1_CPU1_G3_TX_DP<7>")
	)
	(segment
		(start 119.012462 -243.35232)
		(end 119.0117 -243.351812)
		(width 0.1143)
		(layer "In15.Cu")
		(net "GMI_CPU0_G1_CPU1_G3_TX_DP<7>")
	)
	(segment
		(start 352.4885 -232.659174)
		(end 352.490786 -232.660444)
		(width 0.1143)
		(layer "In15.Cu")
		(net "GMI_CPU0_G1_CPU1_G3_TX_DP<7>")
	)
	(segment
		(start 119.04345 -233.650028)
		(end 119.012462 -233.632248)
		(width 0.1143)
		(layer "In15.Cu")
		(net "GMI_CPU0_G1_CPU1_G3_TX_DP<7>")
	)
	(segment
		(start 352.47453 -245.611142)
		(end 352.4758 -245.611904)
		(width 0.1143)
		(layer "In15.Cu")
		(net "GMI_CPU0_G1_CPU1_G3_TX_DP<7>")
	)
	(segment
		(start 352.48088 -238.4933)
		(end 352.480118 -238.493808)
		(width 0.1143)
		(layer "In15.Cu")
		(net "GMI_CPU0_G1_CPU1_G3_TX_DP<7>")
	)
	(segment
		(start 119.051832 -227.17633)
		(end 119.04345 -227.170234)
		(width 0.1143)
		(layer "In15.Cu")
		(net "GMI_CPU0_G1_CPU1_G3_TX_DP<7>")
	)
	(arc
		(start 118.972584 -244.948964)
		(mid 118.729257 -244.484398)
		(end 118.972584 -244.019832)
		(width 0.1143)
		(layer "In15.Cu")
		(net "GMI_CPU0_G1_CPU1_G3_TX_DP<7>")
	)
	(arc
		(start 119.012208 -237.516924)
		(mid 119.197846 -237.194344)
		(end 119.012208 -236.871764)
		(width 0.1143)
		(layer "In15.Cu")
		(net "GMI_CPU0_G1_CPU1_G3_TX_DP<7>")
	)
	(arc
		(start 119.012462 -235.896658)
		(mid 119.197754 -235.574158)
		(end 119.012208 -235.251752)
		(width 0.1143)
		(layer "In15.Cu")
		(net "GMI_CPU0_G1_CPU1_G3_TX_DP<7>")
	)
	(arc
		(start 118.972584 -231.988868)
		(mid 118.729257 -231.524302)
		(end 118.972584 -231.059736)
		(width 0.1143)
		(layer "In15.Cu")
		(net "GMI_CPU0_G1_CPU1_G3_TX_DP<7>")
	)
	(arc
		(start 119.063262 -224.52457)
		(mid 119.211976 -224.234502)
		(end 119.063262 -223.944434)
		(width 0.1143)
		(layer "In15.Cu")
		(net "GMI_CPU0_G1_CPU1_G3_TX_DP<7>")
	)
	(arc
		(start 118.972584 -227.129086)
		(mid 118.729257 -226.66452)
		(end 118.972584 -226.199954)
		(width 0.1143)
		(layer "In15.Cu")
		(net "GMI_CPU0_G1_CPU1_G3_TX_DP<7>")
	)
	(arc
		(start 119.481854 -247.401842)
		(mid 119.284404 -247.204139)
		(end 119.212106 -246.934228)
		(width 0.1143)
		(layer "In15.Cu")
		(net "GMI_CPU0_G1_CPU1_G3_TX_DP<7>")
	)
	(arc
		(start 352.452432 -232.029762)
		(mid 352.296504 -232.334054)
		(end 352.452432 -232.638346)
		(width 0.1143)
		(layer "In15.Cu")
		(net "GMI_CPU0_G1_CPU1_G3_TX_DP<7>")
	)
	(arc
		(start 352.523298 -245.63959)
		(mid 352.766625 -246.104156)
		(end 352.523298 -246.568722)
		(width 0.1143)
		(layer "In15.Cu")
		(net "GMI_CPU0_G1_CPU1_G3_TX_DP<7>")
	)
	(arc
		(start 352.452432 -243.369846)
		(mid 352.296504 -243.674138)
		(end 352.452432 -243.97843)
		(width 0.1143)
		(layer "In15.Cu")
		(net "GMI_CPU0_G1_CPU1_G3_TX_DP<7>")
	)
	(arc
		(start 352.29673 -225.85426)
		(mid 352.338279 -226.025682)
		(end 352.453702 -226.15906)
		(width 0.1143)
		(layer "In15.Cu")
		(net "GMI_CPU0_G1_CPU1_G3_TX_DP<7>")
	)
	(arc
		(start 352.523298 -226.1997)
		(mid 352.766625 -226.664266)
		(end 352.523298 -227.128832)
		(width 0.1143)
		(layer "In15.Cu")
		(net "GMI_CPU0_G1_CPU1_G3_TX_DP<7>")
	)
	(arc
		(start 352.452432 -246.60987)
		(mid 352.337756 -246.743204)
		(end 352.296476 -246.914162)
		(width 0.1143)
		(layer "In15.Cu")
		(net "GMI_CPU0_G1_CPU1_G3_TX_DP<7>")
	)
	(arc
		(start 352.523298 -235.919518)
		(mid 352.766625 -236.384084)
		(end 352.523298 -236.84865)
		(width 0.1143)
		(layer "In15.Cu")
		(net "GMI_CPU0_G1_CPU1_G3_TX_DP<7>")
	)
	(arc
		(start 352.452432 -230.410004)
		(mid 352.337756 -230.543338)
		(end 352.296476 -230.714296)
		(width 0.1143)
		(layer "In15.Cu")
		(net "GMI_CPU0_G1_CPU1_G3_TX_DP<7>")
	)
	(arc
		(start 119.05361 -242.351306)
		(mid 119.205777 -242.05438)
		(end 119.05361 -241.757454)
		(width 0.1143)
		(layer "In15.Cu")
		(net "GMI_CPU0_G1_CPU1_G3_TX_DP<7>")
	)
	(arc
		(start 119.051832 -227.772722)
		(mid 119.204713 -227.474526)
		(end 119.051832 -227.17633)
		(width 0.1143)
		(layer "In15.Cu")
		(net "GMI_CPU0_G1_CPU1_G3_TX_DP<7>")
	)
	(arc
		(start 119.05361 -226.15144)
		(mid 119.205777 -225.854514)
		(end 119.05361 -225.557588)
		(width 0.1143)
		(layer "In15.Cu")
		(net "GMI_CPU0_G1_CPU1_G3_TX_DP<7>")
	)
	(arc
		(start 118.972584 -225.509074)
		(mid 118.729257 -225.044508)
		(end 118.972584 -224.579942)
		(width 0.1143)
		(layer "In15.Cu")
		(net "GMI_CPU0_G1_CPU1_G3_TX_DP<7>")
	)
	(arc
		(start 351.512378 -223.929956)
		(mid 351.35645 -224.234248)
		(end 351.512378 -224.53854)
		(width 0.1143)
		(layer "In15.Cu")
		(net "GMI_CPU0_G1_CPU1_G3_TX_DP<7>")
	)
	(arc
		(start 352.523298 -242.399566)
		(mid 352.766625 -242.864132)
		(end 352.523298 -243.328698)
		(width 0.1143)
		(layer "In15.Cu")
		(net "GMI_CPU0_G1_CPU1_G3_TX_DP<7>")
	)
	(arc
		(start 119.045228 -229.397306)
		(mid 119.158635 -229.264417)
		(end 119.199406 -229.094538)
		(width 0.1143)
		(layer "In15.Cu")
		(net "GMI_CPU0_G1_CPU1_G3_TX_DP<7>")
	)
	(arc
		(start 118.975124 -230.370634)
		(mid 118.794472 -230.167889)
		(end 118.729252 -229.90429)
		(width 0.1143)
		(layer "In15.Cu")
		(net "GMI_CPU0_G1_CPU1_G3_TX_DP<7>")
	)
	(arc
		(start 352.452432 -236.889798)
		(mid 352.296504 -237.19409)
		(end 352.452432 -237.498382)
		(width 0.1143)
		(layer "In15.Cu")
		(net "GMI_CPU0_G1_CPU1_G3_TX_DP<7>")
	)
	(arc
		(start 352.523298 -234.299506)
		(mid 352.766625 -234.764072)
		(end 352.523298 -235.228638)
		(width 0.1143)
		(layer "In15.Cu")
		(net "GMI_CPU0_G1_CPU1_G3_TX_DP<7>")
	)
	(arc
		(start 352.523298 -231.059482)
		(mid 352.766625 -231.524048)
		(end 352.523298 -231.988614)
		(width 0.1143)
		(layer "In15.Cu")
		(net "GMI_CPU0_G1_CPU1_G3_TX_DP<7>")
	)
	(arc
		(start 119.199406 -230.71455)
		(mid 119.149583 -230.52882)
		(end 119.013478 -230.392986)
		(width 0.1143)
		(layer "In15.Cu")
		(net "GMI_CPU0_G1_CPU1_G3_TX_DP<7>")
	)
	(arc
		(start 118.972584 -228.749098)
		(mid 118.729257 -228.284532)
		(end 118.972584 -227.819966)
		(width 0.1143)
		(layer "In15.Cu")
		(net "GMI_CPU0_G1_CPU1_G3_TX_DP<7>")
	)
	(arc
		(start 352.452432 -235.269786)
		(mid 352.296504 -235.574078)
		(end 352.452432 -235.87837)
		(width 0.1143)
		(layer "In15.Cu")
		(net "GMI_CPU0_G1_CPU1_G3_TX_DP<7>")
	)
	(arc
		(start 118.972584 -243.328952)
		(mid 118.729257 -242.864386)
		(end 118.972584 -242.39982)
		(width 0.1143)
		(layer "In15.Cu")
		(net "GMI_CPU0_G1_CPU1_G3_TX_DP<7>")
	)
	(arc
		(start 352.452432 -233.649774)
		(mid 352.296504 -233.954066)
		(end 352.452432 -234.258358)
		(width 0.1143)
		(layer "In15.Cu")
		(net "GMI_CPU0_G1_CPU1_G3_TX_DP<7>")
	)
	(arc
		(start 351.594928 -222.260668)
		(mid 351.587855 -222.265677)
		(end 351.580704 -222.270574)
		(width 0.1143)
		(layer "In15.Cu")
		(net "GMI_CPU0_G1_CPU1_G3_TX_DP<7>")
	)
	(arc
		(start 351.983548 -247.419368)
		(mid 351.885783 -247.522344)
		(end 351.833434 -247.654318)
		(width 0.1143)
		(layer "In15.Cu")
		(net "GMI_CPU0_G1_CPU1_G3_TX_DP<7>")
	)
	(arc
		(start 352.296476 -230.714296)
		(mid 352.337238 -230.88418)
		(end 352.450654 -231.017064)
		(width 0.1143)
		(layer "In15.Cu")
		(net "GMI_CPU0_G1_CPU1_G3_TX_DP<7>")
	)
	(arc
		(start 351.58172 -222.95866)
		(mid 351.582482 -222.959167)
		(end 351.583244 -222.959676)
		(width 0.1143)
		(layer "In15.Cu")
		(net "GMI_CPU0_G1_CPU1_G3_TX_DP<7>")
	)
	(arc
		(start 119.057166 -239.108742)
		(mid 119.208011 -238.814356)
		(end 119.057166 -238.51997)
		(width 0.1143)
		(layer "In15.Cu")
		(net "GMI_CPU0_G1_CPU1_G3_TX_DP<7>")
	)
	(arc
		(start 352.520504 -229.437692)
		(mid 352.766505 -229.903931)
		(end 352.520758 -230.37038)
		(width 0.1143)
		(layer "In15.Cu")
		(net "GMI_CPU0_G1_CPU1_G3_TX_DP<7>")
	)
	(arc
		(start 351.544382 -222.291656)
		(mid 351.359404 -222.60951)
		(end 351.536254 -222.93199)
		(width 0.1143)
		(layer "In15.Cu")
		(net "GMI_CPU0_G1_CPU1_G3_TX_DP<7>")
	)
	(arc
		(start 352.452432 -241.749834)
		(mid 352.296504 -242.054126)
		(end 352.452432 -242.358418)
		(width 0.1143)
		(layer "In15.Cu")
		(net "GMI_CPU0_G1_CPU1_G3_TX_DP<7>")
	)
	(arc
		(start 119.199406 -229.094538)
		(mid 119.149441 -228.908562)
		(end 119.01297 -228.77272)
		(width 0.1143)
		(layer "In15.Cu")
		(net "GMI_CPU0_G1_CPU1_G3_TX_DP<7>")
	)
	(arc
		(start 352.296476 -229.094284)
		(mid 352.337238 -229.264168)
		(end 352.450654 -229.397052)
		(width 0.1143)
		(layer "In15.Cu")
		(net "GMI_CPU0_G1_CPU1_G3_TX_DP<7>")
	)
	(arc
		(start 119.053102 -245.591838)
		(mid 119.205576 -245.294404)
		(end 119.053102 -244.99697)
		(width 0.1143)
		(layer "In15.Cu")
		(net "GMI_CPU0_G1_CPU1_G3_TX_DP<7>")
	)
	(arc
		(start 119.012208 -240.756948)
		(mid 119.197846 -240.434368)
		(end 119.012208 -240.111788)
		(width 0.1143)
		(layer "In15.Cu")
		(net "GMI_CPU0_G1_CPU1_G3_TX_DP<7>")
	)
	(arc
		(start 118.972584 -241.70894)
		(mid 118.729257 -241.244374)
		(end 118.972584 -240.779808)
		(width 0.1143)
		(layer "In15.Cu")
		(net "GMI_CPU0_G1_CPU1_G3_TX_DP<7>")
	)
	(arc
		(start 352.296476 -246.914162)
		(mid 352.231961 -247.176381)
		(end 352.053144 -247.378728)
		(width 0.1143)
		(layer "In15.Cu")
		(net "GMI_CPU0_G1_CPU1_G3_TX_DP<7>")
	)
	(arc
		(start 352.523298 -232.679494)
		(mid 352.766625 -233.14406)
		(end 352.523298 -233.608626)
		(width 0.1143)
		(layer "In15.Cu")
		(net "GMI_CPU0_G1_CPU1_G3_TX_DP<7>")
	)
	(arc
		(start 119.045228 -231.017318)
		(mid 119.158635 -230.884429)
		(end 119.199406 -230.71455)
		(width 0.1143)
		(layer "In15.Cu")
		(net "GMI_CPU0_G1_CPU1_G3_TX_DP<7>")
	)
	(arc
		(start 119.054626 -243.970556)
		(mid 119.206386 -243.674392)
		(end 119.054626 -243.378228)
		(width 0.1143)
		(layer "In15.Cu")
		(net "GMI_CPU0_G1_CPU1_G3_TX_DP<7>")
	)
	(arc
		(start 352.452432 -244.989858)
		(mid 352.296504 -245.29415)
		(end 352.452432 -245.598442)
		(width 0.1143)
		(layer "In15.Cu")
		(net "GMI_CPU0_G1_CPU1_G3_TX_DP<7>")
	)
	(arc
		(start 119.04345 -234.258612)
		(mid 119.195039 -233.95432)
		(end 119.04345 -233.650028)
		(width 0.1143)
		(layer "In15.Cu")
		(net "GMI_CPU0_G1_CPU1_G3_TX_DP<7>")
	)
	(arc
		(start 352.452432 -228.789992)
		(mid 352.337756 -228.923326)
		(end 352.296476 -229.094284)
		(width 0.1143)
		(layer "In15.Cu")
		(net "GMI_CPU0_G1_CPU1_G3_TX_DP<7>")
	)
	(arc
		(start 118.972584 -240.088928)
		(mid 118.729257 -239.624362)
		(end 118.972584 -239.159796)
		(width 0.1143)
		(layer "In15.Cu")
		(net "GMI_CPU0_G1_CPU1_G3_TX_DP<7>")
	)
	(arc
		(start 118.972584 -233.60888)
		(mid 118.729257 -233.144314)
		(end 118.972584 -232.679748)
		(width 0.1143)
		(layer "In15.Cu")
		(net "GMI_CPU0_G1_CPU1_G3_TX_DP<7>")
	)
	(arc
		(start 352.523298 -244.019578)
		(mid 352.766625 -244.484144)
		(end 352.523298 -244.94871)
		(width 0.1143)
		(layer "In15.Cu")
		(net "GMI_CPU0_G1_CPU1_G3_TX_DP<7>")
	)
	(arc
		(start 118.972584 -246.568976)
		(mid 118.729257 -246.10441)
		(end 118.972584 -245.639844)
		(width 0.1143)
		(layer "In15.Cu")
		(net "GMI_CPU0_G1_CPU1_G3_TX_DP<7>")
	)
	(arc
		(start 352.523298 -237.53953)
		(mid 352.766625 -238.004096)
		(end 352.523298 -238.468662)
		(width 0.1143)
		(layer "In15.Cu")
		(net "GMI_CPU0_G1_CPU1_G3_TX_DP<7>")
	)
	(arc
		(start 118.972584 -235.228892)
		(mid 118.729257 -234.764326)
		(end 118.972584 -234.29976)
		(width 0.1143)
		(layer "In15.Cu")
		(net "GMI_CPU0_G1_CPU1_G3_TX_DP<7>")
	)
	(arc
		(start 118.972584 -238.468916)
		(mid 118.729257 -238.00435)
		(end 118.972584 -237.539784)
		(width 0.1143)
		(layer "In15.Cu")
		(net "GMI_CPU0_G1_CPU1_G3_TX_DP<7>")
	)
	(arc
		(start 352.053398 -225.389694)
		(mid 352.232211 -225.592044)
		(end 352.29673 -225.85426)
		(width 0.1143)
		(layer "In15.Cu")
		(net "GMI_CPU0_G1_CPU1_G3_TX_DP<7>")
	)
	(arc
		(start 118.729252 -229.90429)
		(mid 118.793767 -229.642071)
		(end 118.972584 -229.439724)
		(width 0.1143)
		(layer "In15.Cu")
		(net "GMI_CPU0_G1_CPU1_G3_TX_DP<7>")
	)
	(arc
		(start 352.523298 -227.819712)
		(mid 352.766625 -228.284278)
		(end 352.523298 -228.748844)
		(width 0.1143)
		(layer "In15.Cu")
		(net "GMI_CPU0_G1_CPU1_G3_TX_DP<7>")
	)
	(arc
		(start 352.452432 -238.50981)
		(mid 352.296504 -238.814102)
		(end 352.452432 -239.118394)
		(width 0.1143)
		(layer "In15.Cu")
		(net "GMI_CPU0_G1_CPU1_G3_TX_DP<7>")
	)
	(arc
		(start 118.973854 -222.270066)
		(mid 118.973473 -222.269812)
		(end 118.973092 -222.269558)
		(width 0.1143)
		(layer "In15.Cu")
		(net "GMI_CPU0_G1_CPU1_G3_TX_DP<7>")
	)
	(arc
		(start 119.050054 -232.633774)
		(mid 119.203544 -232.334308)
		(end 119.050054 -232.034842)
		(width 0.1143)
		(layer "In15.Cu")
		(net "GMI_CPU0_G1_CPU1_G3_TX_DP<7>")
	)
	(arc
		(start 352.523298 -240.779554)
		(mid 352.766625 -241.24412)
		(end 352.523298 -241.708686)
		(width 0.1143)
		(layer "In15.Cu")
		(net "GMI_CPU0_G1_CPU1_G3_TX_DP<7>")
	)
	(arc
		(start 119.212106 -246.922798)
		(mid 119.162454 -246.736753)
		(end 119.026686 -246.600218)
		(width 0.1143)
		(layer "In15.Cu")
		(net "GMI_CPU0_G1_CPU1_G3_TX_DP<7>")
	)
	(arc
		(start 351.826576 -221.80423)
		(mid 351.826581 -221.806389)
		(end 351.826576 -221.808548)
		(width 0.1143)
		(layer "In15.Cu")
		(net "GMI_CPU0_G1_CPU1_G3_TX_DP<7>")
	)
	(arc
		(start 118.973092 -222.269558)
		(mid 118.793899 -222.067048)
		(end 118.729252 -221.804484)
		(width 0.1143)
		(layer "In15.Cu")
		(net "GMI_CPU0_G1_CPU1_G3_TX_DP<7>")
	)
	(arc
		(start 119.059198 -222.907352)
		(mid 119.209334 -222.61449)
		(end 119.059198 -222.321628)
		(width 0.1143)
		(layer "In15.Cu")
		(net "GMI_CPU0_G1_CPU1_G3_TX_DP<7>")
	)
	(arc
		(start 351.826576 -225.044254)
		(mid 351.867831 -225.215225)
		(end 351.982532 -225.348546)
		(width 0.1143)
		(layer "In15.Cu")
		(net "GMI_CPU0_G1_CPU1_G3_TX_DP<7>")
	)
	(arc
		(start 351.583244 -224.579688)
		(mid 351.762057 -224.782038)
		(end 351.826576 -225.044254)
		(width 0.1143)
		(layer "In15.Cu")
		(net "GMI_CPU0_G1_CPU1_G3_TX_DP<7>")
	)
	(arc
		(start 352.523298 -239.159542)
		(mid 352.766625 -239.624108)
		(end 352.523298 -240.088674)
		(width 0.1143)
		(layer "In15.Cu")
		(net "GMI_CPU0_G1_CPU1_G3_TX_DP<7>")
	)
	(arc
		(start 351.826576 -221.808548)
		(mid 351.762599 -222.061178)
		(end 351.594928 -222.260668)
		(width 0.1143)
		(layer "In15.Cu")
		(net "GMI_CPU0_G1_CPU1_G3_TX_DP<7>")
	)
	(arc
		(start 119.662448 -247.654572)
		(mid 119.629875 -247.557557)
		(end 119.572278 -247.472962)
		(width 0.1143)
		(layer "In15.Cu")
		(net "GMI_CPU0_G1_CPU1_G3_TX_DP<7>")
	)
	(arc
		(start 119.572278 -247.472962)
		(mid 119.544208 -247.445109)
		(end 119.51335 -247.420384)
		(width 0.1143)
		(layer "In15.Cu")
		(net "GMI_CPU0_G1_CPU1_G3_TX_DP<7>")
	)
	(arc
		(start 351.583244 -222.959676)
		(mid 351.826571 -223.424242)
		(end 351.583244 -223.888808)
		(width 0.1143)
		(layer "In15.Cu")
		(net "GMI_CPU0_G1_CPU1_G3_TX_DP<7>")
	)
	(arc
		(start 352.452432 -240.129822)
		(mid 352.296504 -240.434114)
		(end 352.452432 -240.738406)
		(width 0.1143)
		(layer "In15.Cu")
		(net "GMI_CPU0_G1_CPU1_G3_TX_DP<7>")
	)
	(arc
		(start 118.972584 -223.889062)
		(mid 118.729257 -223.424496)
		(end 118.972584 -222.95993)
		(width 0.1143)
		(layer "In15.Cu")
		(net "GMI_CPU0_G1_CPU1_G3_TX_DP<7>")
	)
	(arc
		(start 118.972584 -236.848904)
		(mid 118.729257 -236.384338)
		(end 118.972584 -235.919772)
		(width 0.1143)
		(layer "In15.Cu")
		(net "GMI_CPU0_G1_CPU1_G3_TX_DP<7>")
	)
	(arc
		(start 352.453702 -227.169472)
		(mid 352.296725 -227.474272)
		(end 352.453702 -227.779072)
		(width 0.1143)
		(layer "In15.Cu")
		(net "GMI_CPU0_G1_CPU1_G3_TX_DP<7>")
	)
	(segment
		(start 116.007896 -246.370348)
		(end 116.474748 -246.10441)
		(width 0.12954)
		(layer "F.Cu")
		(net "GMI_CPU0_G1_CPU1_G3_TX_DP<6>")
	)
	(segment
		(start 355.487986 -246.370094)
		(end 355.021134 -246.104156)
		(width 0.12954)
		(layer "F.Cu")
		(net "GMI_CPU0_G1_CPU1_G3_TX_DP<6>")
	)
	(segment
		(start 352.955098 -225.367342)
		(end 352.954082 -225.366834)
		(width 0.1143)
		(layer "In15.Cu")
		(net "GMI_CPU0_G1_CPU1_G3_TX_DP<6>")
	)
	(segment
		(start 117.131846 -245.616984)
		(end 117.09273 -245.639844)
		(width 0.1143)
		(layer "In15.Cu")
		(net "GMI_CPU0_G1_CPU1_G3_TX_DP<6>")
	)
	(segment
		(start 118.0719 -241.7318)
		(end 118.10238 -241.74958)
		(width 0.1143)
		(layer "In15.Cu")
		(net "GMI_CPU0_G1_CPU1_G3_TX_DP<6>")
	)
	(segment
		(start 354.188776 -245.3132)
		(end 354.188776 -245.303548)
		(width 0.1143)
		(layer "In15.Cu")
		(net "GMI_CPU0_G1_CPU1_G3_TX_DP<6>")
	)
	(segment
		(start 312.610246 -182.920894)
		(end 312.610246 -182.921148)
		(width 0.14224)
		(layer "In15.Cu")
		(net "GMI_CPU0_G1_CPU1_G3_TX_DP<6>")
	)
	(segment
		(start 117.788944 -221.321376)
		(end 117.788944 -221.804484)
		(width 0.1143)
		(layer "In15.Cu")
		(net "GMI_CPU0_G1_CPU1_G3_TX_DP<6>")
	)
	(segment
		(start 352.741992 -221.128844)
		(end 352.787712 -221.083124)
		(width 0.1143)
		(layer "In15.Cu")
		(net "GMI_CPU0_G1_CPU1_G3_TX_DP<6>")
	)
	(segment
		(start 118.10238 -240.739168)
		(end 118.0719 -240.756948)
		(width 0.1143)
		(layer "In15.Cu")
		(net "GMI_CPU0_G1_CPU1_G3_TX_DP<6>")
	)
	(segment
		(start 352.741992 -221.308676)
		(end 352.741992 -221.128844)
		(width 0.1143)
		(layer "In15.Cu")
		(net "GMI_CPU0_G1_CPU1_G3_TX_DP<6>")
	)
	(segment
		(start 353.463098 -240.779554)
		(end 353.423982 -240.756694)
		(width 0.1143)
		(layer "In15.Cu")
		(net "GMI_CPU0_G1_CPU1_G3_TX_DP<6>")
	)
	(segment
		(start 353.423982 -241.731546)
		(end 353.463098 -241.708686)
		(width 0.1143)
		(layer "In15.Cu")
		(net "GMI_CPU0_G1_CPU1_G3_TX_DP<6>")
	)
	(segment
		(start 144.272762 -194.366388)
		(end 143.8656 -194.489578)
		(width 0.14224)
		(layer "In15.Cu")
		(net "GMI_CPU0_G1_CPU1_G3_TX_DP<6>")
	)
	(segment
		(start 352.787712 -221.083124)
		(end 352.787712 -220.15704)
		(width 0.14224)
		(layer "In15.Cu")
		(net "GMI_CPU0_G1_CPU1_G3_TX_DP<6>")
	)
	(segment
		(start 118.032784 -243.328952)
		(end 118.0719 -243.351812)
		(width 0.1143)
		(layer "In15.Cu")
		(net "GMI_CPU0_G1_CPU1_G3_TX_DP<6>")
	)
	(segment
		(start 353.463098 -232.679494)
		(end 353.423982 -232.656634)
		(width 0.1143)
		(layer "In15.Cu")
		(net "GMI_CPU0_G1_CPU1_G3_TX_DP<6>")
	)
	(segment
		(start 117.602508 -244.80647)
		(end 117.601746 -244.806978)
		(width 0.1143)
		(layer "In15.Cu")
		(net "GMI_CPU0_G1_CPU1_G3_TX_DP<6>")
	)
	(segment
		(start 118.0719 -240.756948)
		(end 118.032784 -240.779808)
		(width 0.1143)
		(layer "In15.Cu")
		(net "GMI_CPU0_G1_CPU1_G3_TX_DP<6>")
	)
	(segment
		(start 118.034816 -229.4382)
		(end 118.032784 -229.439724)
		(width 0.1143)
		(layer "In15.Cu")
		(net "GMI_CPU0_G1_CPU1_G3_TX_DP<6>")
	)
	(segment
		(start 117.69979 -218.787726)
		(end 117.69979 -220.991938)
		(width 0.14224)
		(layer "In15.Cu")
		(net "GMI_CPU0_G1_CPU1_G3_TX_DP<6>")
	)
	(segment
		(start 118.0719 -242.37696)
		(end 118.032784 -242.39982)
		(width 0.1143)
		(layer "In15.Cu")
		(net "GMI_CPU0_G1_CPU1_G3_TX_DP<6>")
	)
	(segment
		(start 353.423982 -237.51667)
		(end 353.393502 -237.49889)
		(width 0.1143)
		(layer "In15.Cu")
		(net "GMI_CPU0_G1_CPU1_G3_TX_DP<6>")
	)
	(segment
		(start 118.032784 -223.889062)
		(end 118.0719 -223.911922)
		(width 0.1143)
		(layer "In15.Cu")
		(net "GMI_CPU0_G1_CPU1_G3_TX_DP<6>")
	)
	(segment
		(start 352.484182 -223.911668)
		(end 352.523298 -223.888808)
		(width 0.1143)
		(layer "In15.Cu")
		(net "GMI_CPU0_G1_CPU1_G3_TX_DP<6>")
	)
	(segment
		(start 118.0719 -239.136936)
		(end 118.032784 -239.159796)
		(width 0.1143)
		(layer "In15.Cu")
		(net "GMI_CPU0_G1_CPU1_G3_TX_DP<6>")
	)
	(segment
		(start 353.423982 -232.656634)
		(end 353.393502 -232.638854)
		(width 0.1143)
		(layer "In15.Cu")
		(net "GMI_CPU0_G1_CPU1_G3_TX_DP<6>")
	)
	(segment
		(start 352.954082 -225.366834)
		(end 352.95332 -225.366326)
		(width 0.1143)
		(layer "In15.Cu")
		(net "GMI_CPU0_G1_CPU1_G3_TX_DP<6>")
	)
	(segment
		(start 118.0719 -243.996972)
		(end 118.032784 -244.019832)
		(width 0.1143)
		(layer "In15.Cu")
		(net "GMI_CPU0_G1_CPU1_G3_TX_DP<6>")
	)
	(segment
		(start 117.60073 -244.807486)
		(end 117.599206 -244.808502)
		(width 0.1143)
		(layer "In15.Cu")
		(net "GMI_CPU0_G1_CPU1_G3_TX_DP<6>")
	)
	(segment
		(start 118.032784 -225.509074)
		(end 118.0719 -225.531934)
		(width 0.1143)
		(layer "In15.Cu")
		(net "GMI_CPU0_G1_CPU1_G3_TX_DP<6>")
	)
	(segment
		(start 353.423982 -234.276646)
		(end 353.393502 -234.258866)
		(width 0.1143)
		(layer "In15.Cu")
		(net "GMI_CPU0_G1_CPU1_G3_TX_DP<6>")
	)
	(segment
		(start 118.103142 -222.310198)
		(end 118.104158 -222.31096)
		(width 0.1143)
		(layer "In15.Cu")
		(net "GMI_CPU0_G1_CPU1_G3_TX_DP<6>")
	)
	(segment
		(start 352.76663 -221.658688)
		(end 352.76663 -221.333314)
		(width 0.1143)
		(layer "In15.Cu")
		(net "GMI_CPU0_G1_CPU1_G3_TX_DP<6>")
	)
	(segment
		(start 118.0719 -235.896912)
		(end 118.032784 -235.919772)
		(width 0.1143)
		(layer "In15.Cu")
		(net "GMI_CPU0_G1_CPU1_G3_TX_DP<6>")
	)
	(segment
		(start 118.032784 -240.088928)
		(end 118.0719 -240.111788)
		(width 0.1143)
		(layer "In15.Cu")
		(net "GMI_CPU0_G1_CPU1_G3_TX_DP<6>")
	)
	(segment
		(start 118.032784 -236.848904)
		(end 118.0719 -236.871764)
		(width 0.1143)
		(layer "In15.Cu")
		(net "GMI_CPU0_G1_CPU1_G3_TX_DP<6>")
	)
	(segment
		(start 118.10238 -224.539302)
		(end 118.0719 -224.557082)
		(width 0.1143)
		(layer "In15.Cu")
		(net "GMI_CPU0_G1_CPU1_G3_TX_DP<6>")
	)
	(segment
		(start 143.8656 -194.489578)
		(end 120.906794 -213.314026)
		(width 0.14224)
		(layer "In15.Cu")
		(net "GMI_CPU0_G1_CPU1_G3_TX_DP<6>")
	)
	(segment
		(start 353.423982 -238.491522)
		(end 353.463098 -238.468662)
		(width 0.1143)
		(layer "In15.Cu")
		(net "GMI_CPU0_G1_CPU1_G3_TX_DP<6>")
	)
	(segment
		(start 118.104412 -231.01808)
		(end 118.0719 -231.036876)
		(width 0.1143)
		(layer "In15.Cu")
		(net "GMI_CPU0_G1_CPU1_G3_TX_DP<6>")
	)
	(segment
		(start 353.393502 -232.029254)
		(end 353.423982 -232.011474)
		(width 0.1143)
		(layer "In15.Cu")
		(net "GMI_CPU0_G1_CPU1_G3_TX_DP<6>")
	)
	(segment
		(start 118.0719 -223.911922)
		(end 118.10238 -223.929702)
		(width 0.1143)
		(layer "In15.Cu")
		(net "GMI_CPU0_G1_CPU1_G3_TX_DP<6>")
	)
	(segment
		(start 353.463098 -242.399566)
		(end 353.423982 -242.376706)
		(width 0.1143)
		(layer "In15.Cu")
		(net "GMI_CPU0_G1_CPU1_G3_TX_DP<6>")
	)
	(segment
		(start 355.021134 -246.104156)
		(end 354.723192 -246.104156)
		(width 0.1143)
		(layer "In15.Cu")
		(net "GMI_CPU0_G1_CPU1_G3_TX_DP<6>")
	)
	(segment
		(start 353.463098 -235.919518)
		(end 353.423982 -235.896658)
		(width 0.1143)
		(layer "In15.Cu")
		(net "GMI_CPU0_G1_CPU1_G3_TX_DP<6>")
	)
	(segment
		(start 118.10238 -239.119156)
		(end 118.0719 -239.136936)
		(width 0.1143)
		(layer "In15.Cu")
		(net "GMI_CPU0_G1_CPU1_G3_TX_DP<6>")
	)
	(segment
		(start 118.0719 -236.871764)
		(end 118.10238 -236.889544)
		(width 0.1143)
		(layer "In15.Cu")
		(net "GMI_CPU0_G1_CPU1_G3_TX_DP<6>")
	)
	(segment
		(start 348.86392 -211.865718)
		(end 315.691266 -184.665366)
		(width 0.14224)
		(layer "In15.Cu")
		(net "GMI_CPU0_G1_CPU1_G3_TX_DP<6>")
	)
	(segment
		(start 354.723192 -246.104156)
		(end 354.640388 -246.021352)
		(width 0.1143)
		(layer "In15.Cu")
		(net "GMI_CPU0_G1_CPU1_G3_TX_DP<6>")
	)
	(segment
		(start 312.609992 -182.921148)
		(end 309.529226 -181.177184)
		(width 0.14224)
		(layer "In15.Cu")
		(net "GMI_CPU0_G1_CPU1_G3_TX_DP<6>")
	)
	(segment
		(start 353.423982 -228.771704)
		(end 353.46259 -228.749098)
		(width 0.1143)
		(layer "In15.Cu")
		(net "GMI_CPU0_G1_CPU1_G3_TX_DP<6>")
	)
	(segment
		(start 352.76663 -221.333314)
		(end 352.741992 -221.308676)
		(width 0.1143)
		(layer "In15.Cu")
		(net "GMI_CPU0_G1_CPU1_G3_TX_DP<6>")
	)
	(segment
		(start 353.393502 -230.409496)
		(end 353.460558 -230.37038)
		(width 0.1143)
		(layer "In15.Cu")
		(net "GMI_CPU0_G1_CPU1_G3_TX_DP<6>")
	)
	(segment
		(start 352.483674 -222.291656)
		(end 352.520504 -222.270574)
		(width 0.1143)
		(layer "In15.Cu")
		(net "GMI_CPU0_G1_CPU1_G3_TX_DP<6>")
	)
	(segment
		(start 117.74551 -221.277942)
		(end 117.788944 -221.321376)
		(width 0.1143)
		(layer "In15.Cu")
		(net "GMI_CPU0_G1_CPU1_G3_TX_DP<6>")
	)
	(segment
		(start 118.0719 -224.557082)
		(end 118.032784 -224.579942)
		(width 0.1143)
		(layer "In15.Cu")
		(net "GMI_CPU0_G1_CPU1_G3_TX_DP<6>")
	)
	(segment
		(start 118.10238 -227.779326)
		(end 118.0719 -227.797106)
		(width 0.1143)
		(layer "In15.Cu")
		(net "GMI_CPU0_G1_CPU1_G3_TX_DP<6>")
	)
	(segment
		(start 353.423982 -235.251498)
		(end 353.463098 -235.228638)
		(width 0.1143)
		(layer "In15.Cu")
		(net "GMI_CPU0_G1_CPU1_G3_TX_DP<6>")
	)
	(segment
		(start 117.599206 -244.808502)
		(end 117.56263 -244.829838)
		(width 0.1143)
		(layer "In15.Cu")
		(net "GMI_CPU0_G1_CPU1_G3_TX_DP<6>")
	)
	(segment
		(start 118.0719 -233.63174)
		(end 118.10238 -233.64952)
		(width 0.1143)
		(layer "In15.Cu")
		(net "GMI_CPU0_G1_CPU1_G3_TX_DP<6>")
	)
	(segment
		(start 117.633496 -244.78869)
		(end 117.602508 -244.80647)
		(width 0.1143)
		(layer "In15.Cu")
		(net "GMI_CPU0_G1_CPU1_G3_TX_DP<6>")
	)
	(segment
		(start 353.463098 -244.019578)
		(end 353.423982 -243.996718)
		(width 0.1143)
		(layer "In15.Cu")
		(net "GMI_CPU0_G1_CPU1_G3_TX_DP<6>")
	)
	(segment
		(start 118.0719 -234.2769)
		(end 118.032784 -234.29976)
		(width 0.1143)
		(layer "In15.Cu")
		(net "GMI_CPU0_G1_CPU1_G3_TX_DP<6>")
	)
	(segment
		(start 117.69979 -221.020386)
		(end 117.74551 -221.066106)
		(width 0.1143)
		(layer "In15.Cu")
		(net "GMI_CPU0_G1_CPU1_G3_TX_DP<6>")
	)
	(segment
		(start 118.032784 -241.70894)
		(end 118.0719 -241.7318)
		(width 0.1143)
		(layer "In15.Cu")
		(net "GMI_CPU0_G1_CPU1_G3_TX_DP<6>")
	)
	(segment
		(start 118.0719 -222.93707)
		(end 118.032784 -222.95993)
		(width 0.1143)
		(layer "In15.Cu")
		(net "GMI_CPU0_G1_CPU1_G3_TX_DP<6>")
	)
	(segment
		(start 353.423982 -236.87151)
		(end 353.463098 -236.84865)
		(width 0.1143)
		(layer "In15.Cu")
		(net "GMI_CPU0_G1_CPU1_G3_TX_DP<6>")
	)
	(segment
		(start 118.104412 -229.398068)
		(end 118.0719 -229.416864)
		(width 0.1143)
		(layer "In15.Cu")
		(net "GMI_CPU0_G1_CPU1_G3_TX_DP<6>")
	)
	(segment
		(start 118.0719 -238.491776)
		(end 118.10238 -238.509556)
		(width 0.1143)
		(layer "In15.Cu")
		(net "GMI_CPU0_G1_CPU1_G3_TX_DP<6>")
	)
	(segment
		(start 353.423982 -239.136682)
		(end 353.393502 -239.118902)
		(width 0.1143)
		(layer "In15.Cu")
		(net "GMI_CPU0_G1_CPU1_G3_TX_DP<6>")
	)
	(segment
		(start 352.766376 -221.80423)
		(end 352.766376 -221.658942)
		(width 0.1143)
		(layer "In15.Cu")
		(net "GMI_CPU0_G1_CPU1_G3_TX_DP<6>")
	)
	(segment
		(start 166.046404 -179.631086)
		(end 159.300672 -182.04307)
		(width 0.14224)
		(layer "In15.Cu")
		(net "GMI_CPU0_G1_CPU1_G3_TX_DP<6>")
	)
	(segment
		(start 352.956622 -225.368358)
		(end 352.955098 -225.367342)
		(width 0.1143)
		(layer "In15.Cu")
		(net "GMI_CPU0_G1_CPU1_G3_TX_DP<6>")
	)
	(segment
		(start 352.766376 -221.658942)
		(end 352.76663 -221.658688)
		(width 0.1143)
		(layer "In15.Cu")
		(net "GMI_CPU0_G1_CPU1_G3_TX_DP<6>")
	)
	(segment
		(start 353.393502 -233.649266)
		(end 353.423982 -233.631486)
		(width 0.1143)
		(layer "In15.Cu")
		(net "GMI_CPU0_G1_CPU1_G3_TX_DP<6>")
	)
	(segment
		(start 117.69979 -220.991938)
		(end 117.69979 -221.020386)
		(width 0.1143)
		(layer "In15.Cu")
		(net "GMI_CPU0_G1_CPU1_G3_TX_DP<6>")
	)
	(segment
		(start 118.0719 -235.251752)
		(end 118.10238 -235.269532)
		(width 0.1143)
		(layer "In15.Cu")
		(net "GMI_CPU0_G1_CPU1_G3_TX_DP<6>")
	)
	(segment
		(start 352.993198 -225.389694)
		(end 352.956622 -225.368358)
		(width 0.1143)
		(layer "In15.Cu")
		(net "GMI_CPU0_G1_CPU1_G3_TX_DP<6>")
	)
	(segment
		(start 353.463098 -226.1997)
		(end 353.423982 -226.17684)
		(width 0.1143)
		(layer "In15.Cu")
		(net "GMI_CPU0_G1_CPU1_G3_TX_DP<6>")
	)
	(segment
		(start 118.0719 -227.797106)
		(end 118.032784 -227.819966)
		(width 0.1143)
		(layer "In15.Cu")
		(net "GMI_CPU0_G1_CPU1_G3_TX_DP<6>")
	)
	(segment
		(start 353.423982 -226.17684)
		(end 353.393502 -226.15906)
		(width 0.1143)
		(layer "In15.Cu")
		(net "GMI_CPU0_G1_CPU1_G3_TX_DP<6>")
	)
	(segment
		(start 352.453448 -223.929448)
		(end 352.484182 -223.911668)
		(width 0.1143)
		(layer "In15.Cu")
		(net "GMI_CPU0_G1_CPU1_G3_TX_DP<6>")
	)
	(segment
		(start 353.463098 -234.299506)
		(end 353.423982 -234.276646)
		(width 0.1143)
		(layer "In15.Cu")
		(net "GMI_CPU0_G1_CPU1_G3_TX_DP<6>")
	)
	(segment
		(start 353.423982 -233.631486)
		(end 353.463098 -233.608626)
		(width 0.1143)
		(layer "In15.Cu")
		(net "GMI_CPU0_G1_CPU1_G3_TX_DP<6>")
	)
	(segment
		(start 116.855494 -246.021606)
		(end 116.77269 -246.10441)
		(width 0.1143)
		(layer "In15.Cu")
		(net "GMI_CPU0_G1_CPU1_G3_TX_DP<6>")
	)
	(segment
		(start 352.523298 -222.959676)
		(end 352.500184 -222.94596)
		(width 0.1143)
		(layer "In15.Cu")
		(net "GMI_CPU0_G1_CPU1_G3_TX_DP<6>")
	)
	(segment
		(start 118.0719 -228.771958)
		(end 118.10238 -228.789738)
		(width 0.1143)
		(layer "In15.Cu")
		(net "GMI_CPU0_G1_CPU1_G3_TX_DP<6>")
	)
	(segment
		(start 118.0719 -226.177094)
		(end 118.032784 -226.199954)
		(width 0.1143)
		(layer "In15.Cu")
		(net "GMI_CPU0_G1_CPU1_G3_TX_DP<6>")
	)
	(segment
		(start 118.0719 -243.351812)
		(end 118.10238 -243.369592)
		(width 0.1143)
		(layer "In15.Cu")
		(net "GMI_CPU0_G1_CPU1_G3_TX_DP<6>")
	)
	(segment
		(start 353.423982 -243.351558)
		(end 353.463098 -243.328698)
		(width 0.1143)
		(layer "In15.Cu")
		(net "GMI_CPU0_G1_CPU1_G3_TX_DP<6>")
	)
	(segment
		(start 353.423982 -227.796852)
		(end 353.393502 -227.779072)
		(width 0.1143)
		(layer "In15.Cu")
		(net "GMI_CPU0_G1_CPU1_G3_TX_DP<6>")
	)
	(segment
		(start 118.0719 -237.516924)
		(end 118.032784 -237.539784)
		(width 0.1143)
		(layer "In15.Cu")
		(net "GMI_CPU0_G1_CPU1_G3_TX_DP<6>")
	)
	(segment
		(start 354.40239 -245.639082)
		(end 354.363528 -245.616476)
		(width 0.1143)
		(layer "In15.Cu")
		(net "GMI_CPU0_G1_CPU1_G3_TX_DP<6>")
	)
	(segment
		(start 353.393502 -243.369338)
		(end 353.423982 -243.351558)
		(width 0.1143)
		(layer "In15.Cu")
		(net "GMI_CPU0_G1_CPU1_G3_TX_DP<6>")
	)
	(segment
		(start 117.601746 -244.806978)
		(end 117.60073 -244.807486)
		(width 0.1143)
		(layer "In15.Cu")
		(net "GMI_CPU0_G1_CPU1_G3_TX_DP<6>")
	)
	(segment
		(start 352.95205 -225.365564)
		(end 352.94951 -225.364294)
		(width 0.1143)
		(layer "In15.Cu")
		(net "GMI_CPU0_G1_CPU1_G3_TX_DP<6>")
	)
	(segment
		(start 353.423982 -229.41661)
		(end 353.39147 -229.397814)
		(width 0.1143)
		(layer "In15.Cu")
		(net "GMI_CPU0_G1_CPU1_G3_TX_DP<6>")
	)
	(segment
		(start 353.423982 -242.376706)
		(end 353.393502 -242.358926)
		(width 0.1143)
		(layer "In15.Cu")
		(net "GMI_CPU0_G1_CPU1_G3_TX_DP<6>")
	)
	(segment
		(start 118.0719 -231.036876)
		(end 118.032784 -231.059736)
		(width 0.1143)
		(layer "In15.Cu")
		(net "GMI_CPU0_G1_CPU1_G3_TX_DP<6>")
	)
	(segment
		(start 117.162326 -245.599204)
		(end 117.131846 -245.616984)
		(width 0.1143)
		(layer "In15.Cu")
		(net "GMI_CPU0_G1_CPU1_G3_TX_DP<6>")
	)
	(segment
		(start 118.10238 -232.639108)
		(end 118.0719 -232.656888)
		(width 0.1143)
		(layer "In15.Cu")
		(net "GMI_CPU0_G1_CPU1_G3_TX_DP<6>")
	)
	(segment
		(start 353.423982 -243.996718)
		(end 353.393502 -243.978938)
		(width 0.1143)
		(layer "In15.Cu")
		(net "GMI_CPU0_G1_CPU1_G3_TX_DP<6>")
	)
	(segment
		(start 309.529226 -181.177184)
		(end 307.437028 -180.429408)
		(width 0.14224)
		(layer "In15.Cu")
		(net "GMI_CPU0_G1_CPU1_G3_TX_DP<6>")
	)
	(segment
		(start 353.463098 -231.059482)
		(end 353.423982 -231.036622)
		(width 0.1143)
		(layer "In15.Cu")
		(net "GMI_CPU0_G1_CPU1_G3_TX_DP<6>")
	)
	(segment
		(start 353.423982 -232.011474)
		(end 353.463098 -231.988614)
		(width 0.1143)
		(layer "In15.Cu")
		(net "GMI_CPU0_G1_CPU1_G3_TX_DP<6>")
	)
	(segment
		(start 116.77269 -246.10441)
		(end 116.474748 -246.10441)
		(width 0.1143)
		(layer "In15.Cu")
		(net "GMI_CPU0_G1_CPU1_G3_TX_DP<6>")
	)
	(segment
		(start 353.393502 -238.509302)
		(end 353.423982 -238.491522)
		(width 0.1143)
		(layer "In15.Cu")
		(net "GMI_CPU0_G1_CPU1_G3_TX_DP<6>")
	)
	(segment
		(start 352.95332 -225.366326)
		(end 352.95205 -225.365564)
		(width 0.1143)
		(layer "In15.Cu")
		(net "GMI_CPU0_G1_CPU1_G3_TX_DP<6>")
	)
	(segment
		(start 353.393502 -228.789484)
		(end 353.423982 -228.771704)
		(width 0.1143)
		(layer "In15.Cu")
		(net "GMI_CPU0_G1_CPU1_G3_TX_DP<6>")
	)
	(segment
		(start 352.483928 -224.556828)
		(end 352.453448 -224.539048)
		(width 0.1143)
		(layer "In15.Cu")
		(net "GMI_CPU0_G1_CPU1_G3_TX_DP<6>")
	)
	(segment
		(start 118.10238 -222.91929)
		(end 118.0719 -222.93707)
		(width 0.1143)
		(layer "In15.Cu")
		(net "GMI_CPU0_G1_CPU1_G3_TX_DP<6>")
	)
	(segment
		(start 302.902112 -180.429408)
		(end 166.046404 -179.631086)
		(width 0.14224)
		(layer "In15.Cu")
		(net "GMI_CPU0_G1_CPU1_G3_TX_DP<6>")
	)
	(segment
		(start 118.032784 -233.60888)
		(end 118.0719 -233.63174)
		(width 0.1143)
		(layer "In15.Cu")
		(net "GMI_CPU0_G1_CPU1_G3_TX_DP<6>")
	)
	(segment
		(start 118.10238 -235.879132)
		(end 118.0719 -235.896912)
		(width 0.1143)
		(layer "In15.Cu")
		(net "GMI_CPU0_G1_CPU1_G3_TX_DP<6>")
	)
	(segment
		(start 118.10238 -226.159314)
		(end 118.0719 -226.177094)
		(width 0.1143)
		(layer "In15.Cu")
		(net "GMI_CPU0_G1_CPU1_G3_TX_DP<6>")
	)
	(segment
		(start 353.393502 -241.749326)
		(end 353.423982 -241.731546)
		(width 0.1143)
		(layer "In15.Cu")
		(net "GMI_CPU0_G1_CPU1_G3_TX_DP<6>")
	)
	(segment
		(start 353.423982 -231.036622)
		(end 353.39147 -231.017826)
		(width 0.1143)
		(layer "In15.Cu")
		(net "GMI_CPU0_G1_CPU1_G3_TX_DP<6>")
	)
	(segment
		(start 352.947224 -225.36277)
		(end 352.946208 -225.362262)
		(width 0.1143)
		(layer "In15.Cu")
		(net "GMI_CPU0_G1_CPU1_G3_TX_DP<6>")
	)
	(segment
		(start 154.81554 -185.721244)
		(end 154.815286 -185.72099)
		(width 0.14224)
		(layer "In15.Cu")
		(net "GMI_CPU0_G1_CPU1_G3_TX_DP<6>")
	)
	(segment
		(start 118.10238 -242.35918)
		(end 118.0719 -242.37696)
		(width 0.1143)
		(layer "In15.Cu")
		(net "GMI_CPU0_G1_CPU1_G3_TX_DP<6>")
	)
	(segment
		(start 352.94951 -225.364294)
		(end 352.947224 -225.36277)
		(width 0.1143)
		(layer "In15.Cu")
		(net "GMI_CPU0_G1_CPU1_G3_TX_DP<6>")
	)
	(segment
		(start 312.610246 -182.921148)
		(end 312.609992 -182.921148)
		(width 0.14224)
		(layer "In15.Cu")
		(net "GMI_CPU0_G1_CPU1_G3_TX_DP<6>")
	)
	(segment
		(start 118.035324 -230.370634)
		(end 118.10238 -230.40975)
		(width 0.1143)
		(layer "In15.Cu")
		(net "GMI_CPU0_G1_CPU1_G3_TX_DP<6>")
	)
	(segment
		(start 154.815286 -185.72099)
		(end 144.272762 -194.366388)
		(width 0.14224)
		(layer "In15.Cu")
		(net "GMI_CPU0_G1_CPU1_G3_TX_DP<6>")
	)
	(segment
		(start 118.033546 -222.270066)
		(end 118.103142 -222.310198)
		(width 0.1143)
		(layer "In15.Cu")
		(net "GMI_CPU0_G1_CPU1_G3_TX_DP<6>")
	)
	(segment
		(start 352.787712 -220.15704)
		(end 348.86392 -211.865718)
		(width 0.14224)
		(layer "In15.Cu")
		(net "GMI_CPU0_G1_CPU1_G3_TX_DP<6>")
	)
	(segment
		(start 353.463098 -239.159542)
		(end 353.423982 -239.136682)
		(width 0.1143)
		(layer "In15.Cu")
		(net "GMI_CPU0_G1_CPU1_G3_TX_DP<6>")
	)
	(segment
		(start 118.0719 -240.111788)
		(end 118.10238 -240.129568)
		(width 0.1143)
		(layer "In15.Cu")
		(net "GMI_CPU0_G1_CPU1_G3_TX_DP<6>")
	)
	(segment
		(start 118.032784 -238.468916)
		(end 118.0719 -238.491776)
		(width 0.1143)
		(layer "In15.Cu")
		(net "GMI_CPU0_G1_CPU1_G3_TX_DP<6>")
	)
	(segment
		(start 117.74551 -221.066106)
		(end 117.74551 -221.277942)
		(width 0.1143)
		(layer "In15.Cu")
		(net "GMI_CPU0_G1_CPU1_G3_TX_DP<6>")
	)
	(segment
		(start 315.691266 -184.665366)
		(end 312.610246 -182.920894)
		(width 0.14224)
		(layer "In15.Cu")
		(net "GMI_CPU0_G1_CPU1_G3_TX_DP<6>")
	)
	(segment
		(start 353.393502 -235.269278)
		(end 353.423982 -235.251498)
		(width 0.1143)
		(layer "In15.Cu")
		(net "GMI_CPU0_G1_CPU1_G3_TX_DP<6>")
	)
	(segment
		(start 118.0719 -227.151946)
		(end 118.10238 -227.169726)
		(width 0.1143)
		(layer "In15.Cu")
		(net "GMI_CPU0_G1_CPU1_G3_TX_DP<6>")
	)
	(segment
		(start 118.10238 -234.25912)
		(end 118.0719 -234.2769)
		(width 0.1143)
		(layer "In15.Cu")
		(net "GMI_CPU0_G1_CPU1_G3_TX_DP<6>")
	)
	(segment
		(start 352.523044 -224.579688)
		(end 352.483928 -224.556828)
		(width 0.1143)
		(layer "In15.Cu")
		(net "GMI_CPU0_G1_CPU1_G3_TX_DP<6>")
	)
	(segment
		(start 353.423982 -240.111534)
		(end 353.463098 -240.088674)
		(width 0.1143)
		(layer "In15.Cu")
		(net "GMI_CPU0_G1_CPU1_G3_TX_DP<6>")
	)
	(segment
		(start 353.463098 -229.43947)
		(end 353.423982 -229.41661)
		(width 0.1143)
		(layer "In15.Cu")
		(net "GMI_CPU0_G1_CPU1_G3_TX_DP<6>")
	)
	(segment
		(start 159.300672 -182.04307)
		(end 154.81554 -185.721244)
		(width 0.14224)
		(layer "In15.Cu")
		(net "GMI_CPU0_G1_CPU1_G3_TX_DP<6>")
	)
	(segment
		(start 353.905312 -244.813328)
		(end 353.862132 -244.788182)
		(width 0.1143)
		(layer "In15.Cu")
		(net "GMI_CPU0_G1_CPU1_G3_TX_DP<6>")
	)
	(segment
		(start 353.423982 -227.151692)
		(end 353.463098 -227.128832)
		(width 0.1143)
		(layer "In15.Cu")
		(net "GMI_CPU0_G1_CPU1_G3_TX_DP<6>")
	)
	(segment
		(start 353.393502 -227.169472)
		(end 353.423982 -227.151692)
		(width 0.1143)
		(layer "In15.Cu")
		(net "GMI_CPU0_G1_CPU1_G3_TX_DP<6>")
	)
	(segment
		(start 118.0719 -232.656888)
		(end 118.032784 -232.679748)
		(width 0.1143)
		(layer "In15.Cu")
		(net "GMI_CPU0_G1_CPU1_G3_TX_DP<6>")
	)
	(segment
		(start 118.10238 -237.499144)
		(end 118.0719 -237.516924)
		(width 0.1143)
		(layer "In15.Cu")
		(net "GMI_CPU0_G1_CPU1_G3_TX_DP<6>")
	)
	(segment
		(start 353.46259 -228.749098)
		(end 353.463098 -228.748844)
		(width 0.1143)
		(layer "In15.Cu")
		(net "GMI_CPU0_G1_CPU1_G3_TX_DP<6>")
	)
	(segment
		(start 352.946208 -225.362262)
		(end 352.922332 -225.348546)
		(width 0.1143)
		(layer "In15.Cu")
		(net "GMI_CPU0_G1_CPU1_G3_TX_DP<6>")
	)
	(segment
		(start 353.423982 -240.756694)
		(end 353.393502 -240.738914)
		(width 0.1143)
		(layer "In15.Cu")
		(net "GMI_CPU0_G1_CPU1_G3_TX_DP<6>")
	)
	(segment
		(start 353.393502 -240.129314)
		(end 353.423982 -240.111534)
		(width 0.1143)
		(layer "In15.Cu")
		(net "GMI_CPU0_G1_CPU1_G3_TX_DP<6>")
	)
	(segment
		(start 307.437028 -180.429408)
		(end 302.902112 -180.429408)
		(width 0.14224)
		(layer "In15.Cu")
		(net "GMI_CPU0_G1_CPU1_G3_TX_DP<6>")
	)
	(segment
		(start 118.032784 -235.228892)
		(end 118.0719 -235.251752)
		(width 0.1143)
		(layer "In15.Cu")
		(net "GMI_CPU0_G1_CPU1_G3_TX_DP<6>")
	)
	(segment
		(start 118.10238 -243.979192)
		(end 118.0719 -243.996972)
		(width 0.1143)
		(layer "In15.Cu")
		(net "GMI_CPU0_G1_CPU1_G3_TX_DP<6>")
	)
	(segment
		(start 118.0719 -232.011728)
		(end 118.10238 -232.029508)
		(width 0.1143)
		(layer "In15.Cu")
		(net "GMI_CPU0_G1_CPU1_G3_TX_DP<6>")
	)
	(segment
		(start 352.500184 -222.94596)
		(end 352.483674 -222.936562)
		(width 0.1143)
		(layer "In15.Cu")
		(net "GMI_CPU0_G1_CPU1_G3_TX_DP<6>")
	)
	(segment
		(start 118.0719 -229.416864)
		(end 118.034816 -229.4382)
		(width 0.1143)
		(layer "In15.Cu")
		(net "GMI_CPU0_G1_CPU1_G3_TX_DP<6>")
	)
	(segment
		(start 118.032784 -231.988868)
		(end 118.0719 -232.011728)
		(width 0.1143)
		(layer "In15.Cu")
		(net "GMI_CPU0_G1_CPU1_G3_TX_DP<6>")
	)
	(segment
		(start 353.393502 -236.88929)
		(end 353.423982 -236.87151)
		(width 0.1143)
		(layer "In15.Cu")
		(net "GMI_CPU0_G1_CPU1_G3_TX_DP<6>")
	)
	(segment
		(start 353.463098 -227.819712)
		(end 353.423982 -227.796852)
		(width 0.1143)
		(layer "In15.Cu")
		(net "GMI_CPU0_G1_CPU1_G3_TX_DP<6>")
	)
	(segment
		(start 118.0719 -225.531934)
		(end 118.10238 -225.549714)
		(width 0.1143)
		(layer "In15.Cu")
		(net "GMI_CPU0_G1_CPU1_G3_TX_DP<6>")
	)
	(segment
		(start 353.463098 -237.53953)
		(end 353.423982 -237.51667)
		(width 0.1143)
		(layer "In15.Cu")
		(net "GMI_CPU0_G1_CPU1_G3_TX_DP<6>")
	)
	(segment
		(start 118.032784 -227.129086)
		(end 118.0719 -227.151946)
		(width 0.1143)
		(layer "In15.Cu")
		(net "GMI_CPU0_G1_CPU1_G3_TX_DP<6>")
	)
	(segment
		(start 118.032784 -228.749098)
		(end 118.0719 -228.771958)
		(width 0.1143)
		(layer "In15.Cu")
		(net "GMI_CPU0_G1_CPU1_G3_TX_DP<6>")
	)
	(segment
		(start 120.906794 -213.314026)
		(end 117.69979 -218.787726)
		(width 0.14224)
		(layer "In15.Cu")
		(net "GMI_CPU0_G1_CPU1_G3_TX_DP<6>")
	)
	(segment
		(start 353.423982 -235.896658)
		(end 353.393502 -235.878878)
		(width 0.1143)
		(layer "In15.Cu")
		(net "GMI_CPU0_G1_CPU1_G3_TX_DP<6>")
	)
	(arc
		(start 352.766376 -221.810834)
		(mid 352.766386 -221.807532)
		(end 352.766376 -221.80423)
		(width 0.1143)
		(layer "In15.Cu")
		(net "GMI_CPU0_G1_CPU1_G3_TX_DP<6>")
	)
	(arc
		(start 117.319298 -245.294404)
		(mid 117.277749 -245.465826)
		(end 117.162326 -245.599204)
		(width 0.1143)
		(layer "In15.Cu")
		(net "GMI_CPU0_G1_CPU1_G3_TX_DP<6>")
	)
	(arc
		(start 118.10238 -241.74958)
		(mid 118.259357 -242.05438)
		(end 118.10238 -242.35918)
		(width 0.1143)
		(layer "In15.Cu")
		(net "GMI_CPU0_G1_CPU1_G3_TX_DP<6>")
	)
	(arc
		(start 118.10238 -223.929702)
		(mid 118.259357 -224.234502)
		(end 118.10238 -224.539302)
		(width 0.1143)
		(layer "In15.Cu")
		(net "GMI_CPU0_G1_CPU1_G3_TX_DP<6>")
	)
	(arc
		(start 118.104158 -222.31096)
		(mid 118.218311 -222.444036)
		(end 118.259352 -222.61449)
		(width 0.1143)
		(layer "In15.Cu")
		(net "GMI_CPU0_G1_CPU1_G3_TX_DP<6>")
	)
	(arc
		(start 118.032784 -231.059736)
		(mid 117.789457 -231.524302)
		(end 118.032784 -231.988868)
		(width 0.1143)
		(layer "In15.Cu")
		(net "GMI_CPU0_G1_CPU1_G3_TX_DP<6>")
	)
	(arc
		(start 117.788944 -221.804484)
		(mid 117.853816 -222.067447)
		(end 118.033546 -222.270066)
		(width 0.1143)
		(layer "In15.Cu")
		(net "GMI_CPU0_G1_CPU1_G3_TX_DP<6>")
	)
	(arc
		(start 118.10238 -240.129568)
		(mid 118.259357 -240.434368)
		(end 118.10238 -240.739168)
		(width 0.1143)
		(layer "In15.Cu")
		(net "GMI_CPU0_G1_CPU1_G3_TX_DP<6>")
	)
	(arc
		(start 353.393502 -242.358926)
		(mid 353.236525 -242.054126)
		(end 353.393502 -241.749326)
		(width 0.1143)
		(layer "In15.Cu")
		(net "GMI_CPU0_G1_CPU1_G3_TX_DP<6>")
	)
	(arc
		(start 353.463098 -231.988614)
		(mid 353.706425 -231.524048)
		(end 353.463098 -231.059482)
		(width 0.1143)
		(layer "In15.Cu")
		(net "GMI_CPU0_G1_CPU1_G3_TX_DP<6>")
	)
	(arc
		(start 353.23653 -229.094284)
		(mid 353.278079 -228.922862)
		(end 353.393502 -228.789484)
		(width 0.1143)
		(layer "In15.Cu")
		(net "GMI_CPU0_G1_CPU1_G3_TX_DP<6>")
	)
	(arc
		(start 353.393502 -240.738914)
		(mid 353.236525 -240.434114)
		(end 353.393502 -240.129314)
		(width 0.1143)
		(layer "In15.Cu")
		(net "GMI_CPU0_G1_CPU1_G3_TX_DP<6>")
	)
	(arc
		(start 352.766376 -225.044254)
		(mid 352.701861 -224.782035)
		(end 352.523044 -224.579688)
		(width 0.1143)
		(layer "In15.Cu")
		(net "GMI_CPU0_G1_CPU1_G3_TX_DP<6>")
	)
	(arc
		(start 352.483674 -222.936562)
		(mid 352.298256 -222.614172)
		(end 352.483674 -222.291656)
		(width 0.1143)
		(layer "In15.Cu")
		(net "GMI_CPU0_G1_CPU1_G3_TX_DP<6>")
	)
	(arc
		(start 118.032784 -227.819966)
		(mid 117.789457 -228.284532)
		(end 118.032784 -228.749098)
		(width 0.1143)
		(layer "In15.Cu")
		(net "GMI_CPU0_G1_CPU1_G3_TX_DP<6>")
	)
	(arc
		(start 118.032784 -232.679748)
		(mid 117.789457 -233.144314)
		(end 118.032784 -233.60888)
		(width 0.1143)
		(layer "In15.Cu")
		(net "GMI_CPU0_G1_CPU1_G3_TX_DP<6>")
	)
	(arc
		(start 118.10238 -233.64952)
		(mid 118.259357 -233.95432)
		(end 118.10238 -234.25912)
		(width 0.1143)
		(layer "In15.Cu")
		(net "GMI_CPU0_G1_CPU1_G3_TX_DP<6>")
	)
	(arc
		(start 353.23653 -225.85426)
		(mid 353.172015 -225.592041)
		(end 352.993198 -225.389694)
		(width 0.1143)
		(layer "In15.Cu")
		(net "GMI_CPU0_G1_CPU1_G3_TX_DP<6>")
	)
	(arc
		(start 118.032784 -235.919772)
		(mid 117.789457 -236.384338)
		(end 118.032784 -236.848904)
		(width 0.1143)
		(layer "In15.Cu")
		(net "GMI_CPU0_G1_CPU1_G3_TX_DP<6>")
	)
	(arc
		(start 352.53676 -222.259144)
		(mid 352.701427 -222.060537)
		(end 352.766376 -221.810834)
		(width 0.1143)
		(layer "In15.Cu")
		(net "GMI_CPU0_G1_CPU1_G3_TX_DP<6>")
	)
	(arc
		(start 353.463098 -235.228638)
		(mid 353.706425 -234.764072)
		(end 353.463098 -234.299506)
		(width 0.1143)
		(layer "In15.Cu")
		(net "GMI_CPU0_G1_CPU1_G3_TX_DP<6>")
	)
	(arc
		(start 118.032784 -237.539784)
		(mid 117.789457 -238.00435)
		(end 118.032784 -238.468916)
		(width 0.1143)
		(layer "In15.Cu")
		(net "GMI_CPU0_G1_CPU1_G3_TX_DP<6>")
	)
	(arc
		(start 353.393502 -226.15906)
		(mid 353.278075 -226.025684)
		(end 353.23653 -225.85426)
		(width 0.1143)
		(layer "In15.Cu")
		(net "GMI_CPU0_G1_CPU1_G3_TX_DP<6>")
	)
	(arc
		(start 117.789452 -244.484398)
		(mid 117.748197 -244.655369)
		(end 117.633496 -244.78869)
		(width 0.1143)
		(layer "In15.Cu")
		(net "GMI_CPU0_G1_CPU1_G3_TX_DP<6>")
	)
	(arc
		(start 353.393502 -237.49889)
		(mid 353.236525 -237.19409)
		(end 353.393502 -236.88929)
		(width 0.1143)
		(layer "In15.Cu")
		(net "GMI_CPU0_G1_CPU1_G3_TX_DP<6>")
	)
	(arc
		(start 353.463098 -227.128832)
		(mid 353.706425 -226.664266)
		(end 353.463098 -226.1997)
		(width 0.1143)
		(layer "In15.Cu")
		(net "GMI_CPU0_G1_CPU1_G3_TX_DP<6>")
	)
	(arc
		(start 118.032784 -234.29976)
		(mid 117.789457 -234.764326)
		(end 118.032784 -235.228892)
		(width 0.1143)
		(layer "In15.Cu")
		(net "GMI_CPU0_G1_CPU1_G3_TX_DP<6>")
	)
	(arc
		(start 352.453448 -224.539048)
		(mid 352.296471 -224.234248)
		(end 352.453448 -223.929448)
		(width 0.1143)
		(layer "In15.Cu")
		(net "GMI_CPU0_G1_CPU1_G3_TX_DP<6>")
	)
	(arc
		(start 118.032784 -239.159796)
		(mid 117.789457 -239.624362)
		(end 118.032784 -240.088928)
		(width 0.1143)
		(layer "In15.Cu")
		(net "GMI_CPU0_G1_CPU1_G3_TX_DP<6>")
	)
	(arc
		(start 118.032784 -229.439724)
		(mid 117.853971 -229.642074)
		(end 117.789452 -229.90429)
		(width 0.1143)
		(layer "In15.Cu")
		(net "GMI_CPU0_G1_CPU1_G3_TX_DP<6>")
	)
	(arc
		(start 354.363528 -245.616476)
		(mid 354.235577 -245.488202)
		(end 354.188776 -245.3132)
		(width 0.1143)
		(layer "In15.Cu")
		(net "GMI_CPU0_G1_CPU1_G3_TX_DP<6>")
	)
	(arc
		(start 354.188776 -245.303548)
		(mid 354.112811 -245.020406)
		(end 353.905312 -244.813328)
		(width 0.1143)
		(layer "In15.Cu")
		(net "GMI_CPU0_G1_CPU1_G3_TX_DP<6>")
	)
	(arc
		(start 353.39147 -231.017826)
		(mid 353.277541 -230.884679)
		(end 353.23653 -230.714296)
		(width 0.1143)
		(layer "In15.Cu")
		(net "GMI_CPU0_G1_CPU1_G3_TX_DP<6>")
	)
	(arc
		(start 118.032784 -224.579942)
		(mid 117.789457 -225.044508)
		(end 118.032784 -225.509074)
		(width 0.1143)
		(layer "In15.Cu")
		(net "GMI_CPU0_G1_CPU1_G3_TX_DP<6>")
	)
	(arc
		(start 353.70643 -229.904036)
		(mid 353.641915 -229.641817)
		(end 353.463098 -229.43947)
		(width 0.1143)
		(layer "In15.Cu")
		(net "GMI_CPU0_G1_CPU1_G3_TX_DP<6>")
	)
	(arc
		(start 354.640388 -246.021352)
		(mid 354.6386 -246.009903)
		(end 354.636578 -245.998492)
		(width 0.1143)
		(layer "In15.Cu")
		(net "GMI_CPU0_G1_CPU1_G3_TX_DP<6>")
	)
	(arc
		(start 353.393502 -243.978938)
		(mid 353.236525 -243.674138)
		(end 353.393502 -243.369338)
		(width 0.1143)
		(layer "In15.Cu")
		(net "GMI_CPU0_G1_CPU1_G3_TX_DP<6>")
	)
	(arc
		(start 353.460558 -230.37038)
		(mid 353.64121 -230.167635)
		(end 353.70643 -229.904036)
		(width 0.1143)
		(layer "In15.Cu")
		(net "GMI_CPU0_G1_CPU1_G3_TX_DP<6>")
	)
	(arc
		(start 353.463098 -238.468662)
		(mid 353.706425 -238.004096)
		(end 353.463098 -237.53953)
		(width 0.1143)
		(layer "In15.Cu")
		(net "GMI_CPU0_G1_CPU1_G3_TX_DP<6>")
	)
	(arc
		(start 354.636578 -245.998492)
		(mid 354.555145 -245.796094)
		(end 354.403152 -245.63959)
		(width 0.1143)
		(layer "In15.Cu")
		(net "GMI_CPU0_G1_CPU1_G3_TX_DP<6>")
	)
	(arc
		(start 353.70643 -244.484144)
		(mid 353.641915 -244.221925)
		(end 353.463098 -244.019578)
		(width 0.1143)
		(layer "In15.Cu")
		(net "GMI_CPU0_G1_CPU1_G3_TX_DP<6>")
	)
	(arc
		(start 353.862132 -244.788182)
		(mid 353.747605 -244.654942)
		(end 353.70643 -244.484144)
		(width 0.1143)
		(layer "In15.Cu")
		(net "GMI_CPU0_G1_CPU1_G3_TX_DP<6>")
	)
	(arc
		(start 118.259352 -222.61449)
		(mid 118.217803 -222.785912)
		(end 118.10238 -222.91929)
		(width 0.1143)
		(layer "In15.Cu")
		(net "GMI_CPU0_G1_CPU1_G3_TX_DP<6>")
	)
	(arc
		(start 117.789452 -229.90429)
		(mid 117.854688 -230.167881)
		(end 118.035324 -230.370634)
		(width 0.1143)
		(layer "In15.Cu")
		(net "GMI_CPU0_G1_CPU1_G3_TX_DP<6>")
	)
	(arc
		(start 118.10238 -230.40975)
		(mid 118.217807 -230.543126)
		(end 118.259352 -230.71455)
		(width 0.1143)
		(layer "In15.Cu")
		(net "GMI_CPU0_G1_CPU1_G3_TX_DP<6>")
	)
	(arc
		(start 118.259352 -230.71455)
		(mid 118.218386 -230.884956)
		(end 118.104412 -231.01808)
		(width 0.1143)
		(layer "In15.Cu")
		(net "GMI_CPU0_G1_CPU1_G3_TX_DP<6>")
	)
	(arc
		(start 118.10238 -232.029508)
		(mid 118.259357 -232.334308)
		(end 118.10238 -232.639108)
		(width 0.1143)
		(layer "In15.Cu")
		(net "GMI_CPU0_G1_CPU1_G3_TX_DP<6>")
	)
	(arc
		(start 118.10238 -227.169726)
		(mid 118.259357 -227.474526)
		(end 118.10238 -227.779326)
		(width 0.1143)
		(layer "In15.Cu")
		(net "GMI_CPU0_G1_CPU1_G3_TX_DP<6>")
	)
	(arc
		(start 118.032784 -226.199954)
		(mid 117.789457 -226.66452)
		(end 118.032784 -227.129086)
		(width 0.1143)
		(layer "In15.Cu")
		(net "GMI_CPU0_G1_CPU1_G3_TX_DP<6>")
	)
	(arc
		(start 116.859304 -245.998746)
		(mid 116.857281 -246.010156)
		(end 116.855494 -246.021606)
		(width 0.1143)
		(layer "In15.Cu")
		(net "GMI_CPU0_G1_CPU1_G3_TX_DP<6>")
	)
	(arc
		(start 353.393502 -234.258866)
		(mid 353.236525 -233.954066)
		(end 353.393502 -233.649266)
		(width 0.1143)
		(layer "In15.Cu")
		(net "GMI_CPU0_G1_CPU1_G3_TX_DP<6>")
	)
	(arc
		(start 353.393502 -239.118902)
		(mid 353.236525 -238.814102)
		(end 353.393502 -238.509302)
		(width 0.1143)
		(layer "In15.Cu")
		(net "GMI_CPU0_G1_CPU1_G3_TX_DP<6>")
	)
	(arc
		(start 352.922332 -225.348546)
		(mid 352.807656 -225.215212)
		(end 352.766376 -225.044254)
		(width 0.1143)
		(layer "In15.Cu")
		(net "GMI_CPU0_G1_CPU1_G3_TX_DP<6>")
	)
	(arc
		(start 353.393502 -232.638854)
		(mid 353.236525 -232.334054)
		(end 353.393502 -232.029254)
		(width 0.1143)
		(layer "In15.Cu")
		(net "GMI_CPU0_G1_CPU1_G3_TX_DP<6>")
	)
	(arc
		(start 118.032784 -240.779808)
		(mid 117.789457 -241.244374)
		(end 118.032784 -241.70894)
		(width 0.1143)
		(layer "In15.Cu")
		(net "GMI_CPU0_G1_CPU1_G3_TX_DP<6>")
	)
	(arc
		(start 353.393502 -235.878878)
		(mid 353.236525 -235.574078)
		(end 353.393502 -235.269278)
		(width 0.1143)
		(layer "In15.Cu")
		(net "GMI_CPU0_G1_CPU1_G3_TX_DP<6>")
	)
	(arc
		(start 352.520504 -222.270574)
		(mid 352.528682 -222.264931)
		(end 352.53676 -222.259144)
		(width 0.1143)
		(layer "In15.Cu")
		(net "GMI_CPU0_G1_CPU1_G3_TX_DP<6>")
	)
	(arc
		(start 118.10238 -235.269532)
		(mid 118.259357 -235.574332)
		(end 118.10238 -235.879132)
		(width 0.1143)
		(layer "In15.Cu")
		(net "GMI_CPU0_G1_CPU1_G3_TX_DP<6>")
	)
	(arc
		(start 118.032784 -222.95993)
		(mid 117.789457 -223.424496)
		(end 118.032784 -223.889062)
		(width 0.1143)
		(layer "In15.Cu")
		(net "GMI_CPU0_G1_CPU1_G3_TX_DP<6>")
	)
	(arc
		(start 117.56263 -244.829838)
		(mid 117.383817 -245.032188)
		(end 117.319298 -245.294404)
		(width 0.1143)
		(layer "In15.Cu")
		(net "GMI_CPU0_G1_CPU1_G3_TX_DP<6>")
	)
	(arc
		(start 353.463098 -241.708686)
		(mid 353.706425 -241.24412)
		(end 353.463098 -240.779554)
		(width 0.1143)
		(layer "In15.Cu")
		(net "GMI_CPU0_G1_CPU1_G3_TX_DP<6>")
	)
	(arc
		(start 352.523298 -223.888808)
		(mid 352.766625 -223.424242)
		(end 352.523298 -222.959676)
		(width 0.1143)
		(layer "In15.Cu")
		(net "GMI_CPU0_G1_CPU1_G3_TX_DP<6>")
	)
	(arc
		(start 118.032784 -244.019832)
		(mid 117.853971 -244.222182)
		(end 117.789452 -244.484398)
		(width 0.1143)
		(layer "In15.Cu")
		(net "GMI_CPU0_G1_CPU1_G3_TX_DP<6>")
	)
	(arc
		(start 118.10238 -243.369592)
		(mid 118.259357 -243.674392)
		(end 118.10238 -243.979192)
		(width 0.1143)
		(layer "In15.Cu")
		(net "GMI_CPU0_G1_CPU1_G3_TX_DP<6>")
	)
	(arc
		(start 353.463098 -228.748844)
		(mid 353.706425 -228.284278)
		(end 353.463098 -227.819712)
		(width 0.1143)
		(layer "In15.Cu")
		(net "GMI_CPU0_G1_CPU1_G3_TX_DP<6>")
	)
	(arc
		(start 353.39147 -229.397814)
		(mid 353.277541 -229.264667)
		(end 353.23653 -229.094284)
		(width 0.1143)
		(layer "In15.Cu")
		(net "GMI_CPU0_G1_CPU1_G3_TX_DP<6>")
	)
	(arc
		(start 118.10238 -238.509556)
		(mid 118.259357 -238.814356)
		(end 118.10238 -239.119156)
		(width 0.1143)
		(layer "In15.Cu")
		(net "GMI_CPU0_G1_CPU1_G3_TX_DP<6>")
	)
	(arc
		(start 353.463098 -243.328698)
		(mid 353.706425 -242.864132)
		(end 353.463098 -242.399566)
		(width 0.1143)
		(layer "In15.Cu")
		(net "GMI_CPU0_G1_CPU1_G3_TX_DP<6>")
	)
	(arc
		(start 353.463098 -233.608626)
		(mid 353.706425 -233.14406)
		(end 353.463098 -232.679494)
		(width 0.1143)
		(layer "In15.Cu")
		(net "GMI_CPU0_G1_CPU1_G3_TX_DP<6>")
	)
	(arc
		(start 118.10238 -228.789738)
		(mid 118.217807 -228.923114)
		(end 118.259352 -229.094538)
		(width 0.1143)
		(layer "In15.Cu")
		(net "GMI_CPU0_G1_CPU1_G3_TX_DP<6>")
	)
	(arc
		(start 353.463098 -236.84865)
		(mid 353.706425 -236.384084)
		(end 353.463098 -235.919518)
		(width 0.1143)
		(layer "In15.Cu")
		(net "GMI_CPU0_G1_CPU1_G3_TX_DP<6>")
	)
	(arc
		(start 353.463098 -240.088674)
		(mid 353.706425 -239.624108)
		(end 353.463098 -239.159542)
		(width 0.1143)
		(layer "In15.Cu")
		(net "GMI_CPU0_G1_CPU1_G3_TX_DP<6>")
	)
	(arc
		(start 354.403152 -245.63959)
		(mid 354.402771 -245.639336)
		(end 354.40239 -245.639082)
		(width 0.1143)
		(layer "In15.Cu")
		(net "GMI_CPU0_G1_CPU1_G3_TX_DP<6>")
	)
	(arc
		(start 118.259352 -229.094538)
		(mid 118.218386 -229.264944)
		(end 118.104412 -229.398068)
		(width 0.1143)
		(layer "In15.Cu")
		(net "GMI_CPU0_G1_CPU1_G3_TX_DP<6>")
	)
	(arc
		(start 353.393502 -227.779072)
		(mid 353.236525 -227.474272)
		(end 353.393502 -227.169472)
		(width 0.1143)
		(layer "In15.Cu")
		(net "GMI_CPU0_G1_CPU1_G3_TX_DP<6>")
	)
	(arc
		(start 353.23653 -230.714296)
		(mid 353.278079 -230.542874)
		(end 353.393502 -230.409496)
		(width 0.1143)
		(layer "In15.Cu")
		(net "GMI_CPU0_G1_CPU1_G3_TX_DP<6>")
	)
	(arc
		(start 118.10238 -236.889544)
		(mid 118.259357 -237.194344)
		(end 118.10238 -237.499144)
		(width 0.1143)
		(layer "In15.Cu")
		(net "GMI_CPU0_G1_CPU1_G3_TX_DP<6>")
	)
	(arc
		(start 117.09273 -245.639844)
		(mid 116.940743 -245.796352)
		(end 116.859304 -245.998746)
		(width 0.1143)
		(layer "In15.Cu")
		(net "GMI_CPU0_G1_CPU1_G3_TX_DP<6>")
	)
	(arc
		(start 118.10238 -225.549714)
		(mid 118.259357 -225.854514)
		(end 118.10238 -226.159314)
		(width 0.1143)
		(layer "In15.Cu")
		(net "GMI_CPU0_G1_CPU1_G3_TX_DP<6>")
	)
	(arc
		(start 118.032784 -242.39982)
		(mid 117.789457 -242.864386)
		(end 118.032784 -243.328952)
		(width 0.1143)
		(layer "In15.Cu")
		(net "GMI_CPU0_G1_CPU1_G3_TX_DP<6>")
	)
	(segment
		(start 116.007896 -244.750336)
		(end 116.474748 -244.484398)
		(width 0.12954)
		(layer "F.Cu")
		(net "GMI_CPU0_G1_CPU1_G3_TX_DP<5>")
	)
	(segment
		(start 355.487986 -244.750082)
		(end 355.021134 -244.484144)
		(width 0.12954)
		(layer "F.Cu")
		(net "GMI_CPU0_G1_CPU1_G3_TX_DP<5>")
	)
	(segment
		(start 353.441 -222.28175)
		(end 353.464114 -222.268542)
		(width 0.1143)
		(layer "In15.Cu")
		(net "GMI_CPU0_G1_CPU1_G3_TX_DP<5>")
	)
	(segment
		(start 117.131846 -224.557082)
		(end 117.09273 -224.579942)
		(width 0.1143)
		(layer "In15.Cu")
		(net "GMI_CPU0_G1_CPU1_G3_TX_DP<5>")
	)
	(segment
		(start 354.366576 -228.77018)
		(end 354.403152 -228.748844)
		(width 0.1143)
		(layer "In15.Cu")
		(net "GMI_CPU0_G1_CPU1_G3_TX_DP<5>")
	)
	(segment
		(start 354.364036 -232.656634)
		(end 354.363274 -232.656126)
		(width 0.1143)
		(layer "In15.Cu")
		(net "GMI_CPU0_G1_CPU1_G3_TX_DP<5>")
	)
	(segment
		(start 354.364036 -227.796852)
		(end 354.363274 -227.796344)
		(width 0.1143)
		(layer "In15.Cu")
		(net "GMI_CPU0_G1_CPU1_G3_TX_DP<5>")
	)
	(segment
		(start 117.09273 -225.509074)
		(end 117.131846 -225.531934)
		(width 0.1143)
		(layer "In15.Cu")
		(net "GMI_CPU0_G1_CPU1_G3_TX_DP<5>")
	)
	(segment
		(start 354.385118 -235.239306)
		(end 354.403152 -235.228638)
		(width 0.1143)
		(layer "In15.Cu")
		(net "GMI_CPU0_G1_CPU1_G3_TX_DP<5>")
	)
	(segment
		(start 117.131846 -235.896912)
		(end 117.09273 -235.919772)
		(width 0.1143)
		(layer "In15.Cu")
		(net "GMI_CPU0_G1_CPU1_G3_TX_DP<5>")
	)
	(segment
		(start 354.40239 -240.779046)
		(end 354.370386 -240.76025)
		(width 0.1143)
		(layer "In15.Cu")
		(net "GMI_CPU0_G1_CPU1_G3_TX_DP<5>")
	)
	(segment
		(start 117.131846 -240.111788)
		(end 117.162326 -240.129568)
		(width 0.1143)
		(layer "In15.Cu")
		(net "GMI_CPU0_G1_CPU1_G3_TX_DP<5>")
	)
	(segment
		(start 117.162326 -224.539302)
		(end 117.131846 -224.557082)
		(width 0.1143)
		(layer "In15.Cu")
		(net "GMI_CPU0_G1_CPU1_G3_TX_DP<5>")
	)
	(segment
		(start 120.238012 -212.563456)
		(end 116.75491 -218.505532)
		(width 0.14224)
		(layer "In15.Cu")
		(net "GMI_CPU0_G1_CPU1_G3_TX_DP<5>")
	)
	(segment
		(start 354.384864 -235.239306)
		(end 354.385118 -235.239306)
		(width 0.1143)
		(layer "In15.Cu")
		(net "GMI_CPU0_G1_CPU1_G3_TX_DP<5>")
	)
	(segment
		(start 117.131846 -225.531934)
		(end 117.162326 -225.549714)
		(width 0.1143)
		(layer "In15.Cu")
		(net "GMI_CPU0_G1_CPU1_G3_TX_DP<5>")
	)
	(segment
		(start 116.75491 -218.505532)
		(end 116.75491 -220.991938)
		(width 0.14224)
		(layer "In15.Cu")
		(net "GMI_CPU0_G1_CPU1_G3_TX_DP<5>")
	)
	(segment
		(start 354.363528 -238.491776)
		(end 354.384864 -238.47933)
		(width 0.1143)
		(layer "In15.Cu")
		(net "GMI_CPU0_G1_CPU1_G3_TX_DP<5>")
	)
	(segment
		(start 165.81755 -178.692302)
		(end 158.503112 -181.30774)
		(width 0.14224)
		(layer "In15.Cu")
		(net "GMI_CPU0_G1_CPU1_G3_TX_DP<5>")
	)
	(segment
		(start 150.223982 -188.095128)
		(end 150.223982 -188.095382)
		(width 0.14224)
		(layer "In15.Cu")
		(net "GMI_CPU0_G1_CPU1_G3_TX_DP<5>")
	)
	(segment
		(start 144.013682 -193.068194)
		(end 120.238012 -212.563456)
		(width 0.14224)
		(layer "In15.Cu")
		(net "GMI_CPU0_G1_CPU1_G3_TX_DP<5>")
	)
	(segment
		(start 117.131846 -234.2769)
		(end 117.09273 -234.29976)
		(width 0.1143)
		(layer "In15.Cu")
		(net "GMI_CPU0_G1_CPU1_G3_TX_DP<5>")
	)
	(segment
		(start 117.131846 -237.516924)
		(end 117.09273 -237.539784)
		(width 0.1143)
		(layer "In15.Cu")
		(net "GMI_CPU0_G1_CPU1_G3_TX_DP<5>")
	)
	(segment
		(start 354.364036 -226.17684)
		(end 354.333302 -226.15906)
		(width 0.1143)
		(layer "In15.Cu")
		(net "GMI_CPU0_G1_CPU1_G3_TX_DP<5>")
	)
	(segment
		(start 117.162326 -240.739168)
		(end 117.131846 -240.756948)
		(width 0.1143)
		(layer "In15.Cu")
		(net "GMI_CPU0_G1_CPU1_G3_TX_DP<5>")
	)
	(segment
		(start 354.364036 -232.011474)
		(end 354.365052 -232.010966)
		(width 0.1143)
		(layer "In15.Cu")
		(net "GMI_CPU0_G1_CPU1_G3_TX_DP<5>")
	)
	(segment
		(start 354.364036 -229.41661)
		(end 354.330508 -229.397052)
		(width 0.1143)
		(layer "In15.Cu")
		(net "GMI_CPU0_G1_CPU1_G3_TX_DP<5>")
	)
	(segment
		(start 353.423982 -224.556828)
		(end 353.393502 -224.539048)
		(width 0.1143)
		(layer "In15.Cu")
		(net "GMI_CPU0_G1_CPU1_G3_TX_DP<5>")
	)
	(segment
		(start 117.131846 -232.656888)
		(end 117.09273 -232.679748)
		(width 0.1143)
		(layer "In15.Cu")
		(net "GMI_CPU0_G1_CPU1_G3_TX_DP<5>")
	)
	(segment
		(start 117.162326 -234.25912)
		(end 117.131846 -234.2769)
		(width 0.1143)
		(layer "In15.Cu")
		(net "GMI_CPU0_G1_CPU1_G3_TX_DP<5>")
	)
	(segment
		(start 354.368608 -242.379246)
		(end 354.356162 -242.372134)
		(width 0.1143)
		(layer "In15.Cu")
		(net "GMI_CPU0_G1_CPU1_G3_TX_DP<5>")
	)
	(segment
		(start 117.131846 -239.136936)
		(end 117.09273 -239.159796)
		(width 0.1143)
		(layer "In15.Cu")
		(net "GMI_CPU0_G1_CPU1_G3_TX_DP<5>")
	)
	(segment
		(start 354.368608 -240.759234)
		(end 354.356162 -240.752122)
		(width 0.1143)
		(layer "In15.Cu")
		(net "GMI_CPU0_G1_CPU1_G3_TX_DP<5>")
	)
	(segment
		(start 354.367084 -230.389938)
		(end 354.39604 -230.373174)
		(width 0.1143)
		(layer "In15.Cu")
		(net "GMI_CPU0_G1_CPU1_G3_TX_DP<5>")
	)
	(segment
		(start 354.403152 -244.019578)
		(end 354.396294 -244.015514)
		(width 0.1143)
		(layer "In15.Cu")
		(net "GMI_CPU0_G1_CPU1_G3_TX_DP<5>")
	)
	(segment
		(start 354.366322 -230.390446)
		(end 354.367084 -230.389938)
		(width 0.1143)
		(layer "In15.Cu")
		(net "GMI_CPU0_G1_CPU1_G3_TX_DP<5>")
	)
	(segment
		(start 117.131846 -232.011728)
		(end 117.162326 -232.029508)
		(width 0.1143)
		(layer "In15.Cu")
		(net "GMI_CPU0_G1_CPU1_G3_TX_DP<5>")
	)
	(segment
		(start 117.131846 -222.93707)
		(end 117.09273 -222.95993)
		(width 0.1143)
		(layer "In15.Cu")
		(net "GMI_CPU0_G1_CPU1_G3_TX_DP<5>")
	)
	(segment
		(start 353.42068 -222.934784)
		(end 353.419918 -222.934276)
		(width 0.1143)
		(layer "In15.Cu")
		(net "GMI_CPU0_G1_CPU1_G3_TX_DP<5>")
	)
	(segment
		(start 117.09273 -243.328952)
		(end 117.131846 -243.351812)
		(width 0.1143)
		(layer "In15.Cu")
		(net "GMI_CPU0_G1_CPU1_G3_TX_DP<5>")
	)
	(segment
		(start 354.364036 -227.151692)
		(end 354.400358 -227.130864)
		(width 0.1143)
		(layer "In15.Cu")
		(net "GMI_CPU0_G1_CPU1_G3_TX_DP<5>")
	)
	(segment
		(start 353.424236 -222.936816)
		(end 353.423474 -222.936308)
		(width 0.1143)
		(layer "In15.Cu")
		(net "GMI_CPU0_G1_CPU1_G3_TX_DP<5>")
	)
	(segment
		(start 354.363274 -243.99621)
		(end 354.332286 -243.97843)
		(width 0.1143)
		(layer "In15.Cu")
		(net "GMI_CPU0_G1_CPU1_G3_TX_DP<5>")
	)
	(segment
		(start 353.930458 -225.387916)
		(end 353.897438 -225.368866)
		(width 0.1143)
		(layer "In15.Cu")
		(net "GMI_CPU0_G1_CPU1_G3_TX_DP<5>")
	)
	(segment
		(start 117.162326 -242.35918)
		(end 117.131846 -242.37696)
		(width 0.1143)
		(layer "In15.Cu")
		(net "GMI_CPU0_G1_CPU1_G3_TX_DP<5>")
	)
	(segment
		(start 354.363528 -235.251752)
		(end 354.384864 -235.239306)
		(width 0.1143)
		(layer "In15.Cu")
		(net "GMI_CPU0_G1_CPU1_G3_TX_DP<5>")
	)
	(segment
		(start 354.332286 -233.649774)
		(end 354.363274 -233.631994)
		(width 0.1143)
		(layer "In15.Cu")
		(net "GMI_CPU0_G1_CPU1_G3_TX_DP<5>")
	)
	(segment
		(start 354.384864 -236.859318)
		(end 354.385118 -236.859318)
		(width 0.1143)
		(layer "In15.Cu")
		(net "GMI_CPU0_G1_CPU1_G3_TX_DP<5>")
	)
	(segment
		(start 354.363528 -241.7318)
		(end 354.384864 -241.719354)
		(width 0.1143)
		(layer "In15.Cu")
		(net "GMI_CPU0_G1_CPU1_G3_TX_DP<5>")
	)
	(segment
		(start 154.710638 -184.416446)
		(end 154.710892 -184.4167)
		(width 0.14224)
		(layer "In15.Cu")
		(net "GMI_CPU0_G1_CPU1_G3_TX_DP<5>")
	)
	(segment
		(start 117.162326 -237.499144)
		(end 117.131846 -237.516924)
		(width 0.1143)
		(layer "In15.Cu")
		(net "GMI_CPU0_G1_CPU1_G3_TX_DP<5>")
	)
	(segment
		(start 117.131846 -241.7318)
		(end 117.162326 -241.74958)
		(width 0.1143)
		(layer "In15.Cu")
		(net "GMI_CPU0_G1_CPU1_G3_TX_DP<5>")
	)
	(segment
		(start 316.182756 -183.861964)
		(end 313.047888 -182.08752)
		(width 0.14224)
		(layer "In15.Cu")
		(net "GMI_CPU0_G1_CPU1_G3_TX_DP<5>")
	)
	(segment
		(start 117.131846 -236.871764)
		(end 117.162326 -236.889544)
		(width 0.1143)
		(layer "In15.Cu")
		(net "GMI_CPU0_G1_CPU1_G3_TX_DP<5>")
	)
	(segment
		(start 354.403152 -232.679494)
		(end 354.365052 -232.657142)
		(width 0.1143)
		(layer "In15.Cu")
		(net "GMI_CPU0_G1_CPU1_G3_TX_DP<5>")
	)
	(segment
		(start 354.40239 -234.298998)
		(end 354.399596 -234.296966)
		(width 0.1143)
		(layer "In15.Cu")
		(net "GMI_CPU0_G1_CPU1_G3_TX_DP<5>")
	)
	(segment
		(start 117.131846 -228.771958)
		(end 117.162326 -228.789738)
		(width 0.1143)
		(layer "In15.Cu")
		(net "GMI_CPU0_G1_CPU1_G3_TX_DP<5>")
	)
	(segment
		(start 354.36937 -235.899706)
		(end 354.368608 -235.899198)
		(width 0.1143)
		(layer "In15.Cu")
		(net "GMI_CPU0_G1_CPU1_G3_TX_DP<5>")
	)
	(segment
		(start 353.70643 -221.80423)
		(end 353.70643 -221.328234)
		(width 0.1143)
		(layer "In15.Cu")
		(net "GMI_CPU0_G1_CPU1_G3_TX_DP<5>")
	)
	(segment
		(start 353.897438 -225.368866)
		(end 353.895914 -225.36785)
		(width 0.1143)
		(layer "In15.Cu")
		(net "GMI_CPU0_G1_CPU1_G3_TX_DP<5>")
	)
	(segment
		(start 354.363274 -227.796344)
		(end 354.332286 -227.778564)
		(width 0.1143)
		(layer "In15.Cu")
		(net "GMI_CPU0_G1_CPU1_G3_TX_DP<5>")
	)
	(segment
		(start 354.400358 -227.130864)
		(end 354.403152 -227.128832)
		(width 0.1143)
		(layer "In15.Cu")
		(net "GMI_CPU0_G1_CPU1_G3_TX_DP<5>")
	)
	(segment
		(start 354.395532 -244.015006)
		(end 354.364036 -243.996718)
		(width 0.1143)
		(layer "In15.Cu")
		(net "GMI_CPU0_G1_CPU1_G3_TX_DP<5>")
	)
	(segment
		(start 354.385118 -236.859318)
		(end 354.403152 -236.84865)
		(width 0.1143)
		(layer "In15.Cu")
		(net "GMI_CPU0_G1_CPU1_G3_TX_DP<5>")
	)
	(segment
		(start 354.384864 -238.47933)
		(end 354.385118 -238.47933)
		(width 0.1143)
		(layer "In15.Cu")
		(net "GMI_CPU0_G1_CPU1_G3_TX_DP<5>")
	)
	(segment
		(start 117.09273 -241.70894)
		(end 117.131846 -241.7318)
		(width 0.1143)
		(layer "In15.Cu")
		(net "GMI_CPU0_G1_CPU1_G3_TX_DP<5>")
	)
	(segment
		(start 354.364036 -228.771704)
		(end 354.365052 -228.771196)
		(width 0.1143)
		(layer "In15.Cu")
		(net "GMI_CPU0_G1_CPU1_G3_TX_DP<5>")
	)
	(segment
		(start 354.363528 -240.111788)
		(end 354.384864 -240.099342)
		(width 0.1143)
		(layer "In15.Cu")
		(net "GMI_CPU0_G1_CPU1_G3_TX_DP<5>")
	)
	(segment
		(start 354.365052 -243.35105)
		(end 354.403152 -243.328698)
		(width 0.1143)
		(layer "In15.Cu")
		(net "GMI_CPU0_G1_CPU1_G3_TX_DP<5>")
	)
	(segment
		(start 117.131846 -238.491776)
		(end 117.162326 -238.509556)
		(width 0.1143)
		(layer "In15.Cu")
		(net "GMI_CPU0_G1_CPU1_G3_TX_DP<5>")
	)
	(segment
		(start 354.370386 -242.380262)
		(end 354.36937 -242.379754)
		(width 0.1143)
		(layer "In15.Cu")
		(net "GMI_CPU0_G1_CPU1_G3_TX_DP<5>")
	)
	(segment
		(start 353.463352 -222.959676)
		(end 353.424236 -222.936816)
		(width 0.1143)
		(layer "In15.Cu")
		(net "GMI_CPU0_G1_CPU1_G3_TX_DP<5>")
	)
	(segment
		(start 354.36937 -242.379754)
		(end 354.368608 -242.379246)
		(width 0.1143)
		(layer "In15.Cu")
		(net "GMI_CPU0_G1_CPU1_G3_TX_DP<5>")
	)
	(segment
		(start 354.385118 -240.099342)
		(end 354.403152 -240.088674)
		(width 0.1143)
		(layer "In15.Cu")
		(net "GMI_CPU0_G1_CPU1_G3_TX_DP<5>")
	)
	(segment
		(start 354.396294 -244.015514)
		(end 354.395532 -244.015006)
		(width 0.1143)
		(layer "In15.Cu")
		(net "GMI_CPU0_G1_CPU1_G3_TX_DP<5>")
	)
	(segment
		(start 353.894136 -225.366834)
		(end 353.862386 -225.348546)
		(width 0.1143)
		(layer "In15.Cu")
		(net "GMI_CPU0_G1_CPU1_G3_TX_DP<5>")
	)
	(segment
		(start 354.364036 -234.276646)
		(end 354.332286 -234.258358)
		(width 0.1143)
		(layer "In15.Cu")
		(net "GMI_CPU0_G1_CPU1_G3_TX_DP<5>")
	)
	(segment
		(start 354.368608 -237.51921)
		(end 354.356162 -237.512098)
		(width 0.1143)
		(layer "In15.Cu")
		(net "GMI_CPU0_G1_CPU1_G3_TX_DP<5>")
	)
	(segment
		(start 354.365052 -230.391208)
		(end 354.366322 -230.390446)
		(width 0.1143)
		(layer "In15.Cu")
		(net "GMI_CPU0_G1_CPU1_G3_TX_DP<5>")
	)
	(segment
		(start 354.364036 -243.351558)
		(end 354.365052 -243.35105)
		(width 0.1143)
		(layer "In15.Cu")
		(net "GMI_CPU0_G1_CPU1_G3_TX_DP<5>")
	)
	(segment
		(start 354.36048 -230.393748)
		(end 354.362004 -230.392986)
		(width 0.1143)
		(layer "In15.Cu")
		(net "GMI_CPU0_G1_CPU1_G3_TX_DP<5>")
	)
	(segment
		(start 117.09527 -230.370634)
		(end 117.162326 -230.40975)
		(width 0.1143)
		(layer "In15.Cu")
		(net "GMI_CPU0_G1_CPU1_G3_TX_DP<5>")
	)
	(segment
		(start 353.732592 -221.083124)
		(end 353.732592 -219.866718)
		(width 0.14224)
		(layer "In15.Cu")
		(net "GMI_CPU0_G1_CPU1_G3_TX_DP<5>")
	)
	(segment
		(start 117.09273 -223.889062)
		(end 117.131846 -223.911922)
		(width 0.1143)
		(layer "In15.Cu")
		(net "GMI_CPU0_G1_CPU1_G3_TX_DP<5>")
	)
	(segment
		(start 354.370386 -239.140238)
		(end 354.36937 -239.13973)
		(width 0.1143)
		(layer "In15.Cu")
		(net "GMI_CPU0_G1_CPU1_G3_TX_DP<5>")
	)
	(segment
		(start 354.40239 -242.399058)
		(end 354.370386 -242.380262)
		(width 0.1143)
		(layer "In15.Cu")
		(net "GMI_CPU0_G1_CPU1_G3_TX_DP<5>")
	)
	(segment
		(start 354.395278 -235.914692)
		(end 354.36937 -235.899706)
		(width 0.1143)
		(layer "In15.Cu")
		(net "GMI_CPU0_G1_CPU1_G3_TX_DP<5>")
	)
	(segment
		(start 354.40239 -235.91901)
		(end 354.39604 -235.9152)
		(width 0.1143)
		(layer "In15.Cu")
		(net "GMI_CPU0_G1_CPU1_G3_TX_DP<5>")
	)
	(segment
		(start 313.047888 -182.08752)
		(end 313.04738 -182.087012)
		(width 0.14224)
		(layer "In15.Cu")
		(net "GMI_CPU0_G1_CPU1_G3_TX_DP<5>")
	)
	(segment
		(start 354.403152 -229.43947)
		(end 354.364036 -229.41661)
		(width 0.1143)
		(layer "In15.Cu")
		(net "GMI_CPU0_G1_CPU1_G3_TX_DP<5>")
	)
	(segment
		(start 117.09273 -228.749098)
		(end 117.131846 -228.771958)
		(width 0.1143)
		(layer "In15.Cu")
		(net "GMI_CPU0_G1_CPU1_G3_TX_DP<5>")
	)
	(segment
		(start 355.021134 -244.484144)
		(end 354.723192 -244.484144)
		(width 0.1143)
		(layer "In15.Cu")
		(net "GMI_CPU0_G1_CPU1_G3_TX_DP<5>")
	)
	(segment
		(start 354.403152 -226.1997)
		(end 354.364036 -226.17684)
		(width 0.1143)
		(layer "In15.Cu")
		(net "GMI_CPU0_G1_CPU1_G3_TX_DP<5>")
	)
	(segment
		(start 353.393502 -222.309436)
		(end 353.441 -222.28175)
		(width 0.1143)
		(layer "In15.Cu")
		(net "GMI_CPU0_G1_CPU1_G3_TX_DP<5>")
	)
	(segment
		(start 354.368608 -235.899198)
		(end 354.367084 -235.898436)
		(width 0.1143)
		(layer "In15.Cu")
		(net "GMI_CPU0_G1_CPU1_G3_TX_DP<5>")
	)
	(segment
		(start 117.131846 -227.797106)
		(end 117.09273 -227.819966)
		(width 0.1143)
		(layer "In15.Cu")
		(net "GMI_CPU0_G1_CPU1_G3_TX_DP<5>")
	)
	(segment
		(start 353.686872 -221.308676)
		(end 353.686872 -221.128844)
		(width 0.1143)
		(layer "In15.Cu")
		(net "GMI_CPU0_G1_CPU1_G3_TX_DP<5>")
	)
	(segment
		(start 354.362004 -230.392986)
		(end 354.363274 -230.392224)
		(width 0.1143)
		(layer "In15.Cu")
		(net "GMI_CPU0_G1_CPU1_G3_TX_DP<5>")
	)
	(segment
		(start 117.131846 -226.177094)
		(end 117.09273 -226.199954)
		(width 0.1143)
		(layer "In15.Cu")
		(net "GMI_CPU0_G1_CPU1_G3_TX_DP<5>")
	)
	(segment
		(start 354.36937 -240.759742)
		(end 354.368608 -240.759234)
		(width 0.1143)
		(layer "In15.Cu")
		(net "GMI_CPU0_G1_CPU1_G3_TX_DP<5>")
	)
	(segment
		(start 353.895914 -225.36785)
		(end 353.894136 -225.366834)
		(width 0.1143)
		(layer "In15.Cu")
		(net "GMI_CPU0_G1_CPU1_G3_TX_DP<5>")
	)
	(segment
		(start 354.399596 -234.296966)
		(end 354.364036 -234.276646)
		(width 0.1143)
		(layer "In15.Cu")
		(net "GMI_CPU0_G1_CPU1_G3_TX_DP<5>")
	)
	(segment
		(start 354.40239 -239.159034)
		(end 354.370386 -239.140238)
		(width 0.1143)
		(layer "In15.Cu")
		(net "GMI_CPU0_G1_CPU1_G3_TX_DP<5>")
	)
	(segment
		(start 354.367084 -235.898436)
		(end 354.356162 -235.892086)
		(width 0.1143)
		(layer "In15.Cu")
		(net "GMI_CPU0_G1_CPU1_G3_TX_DP<5>")
	)
	(segment
		(start 117.09273 -227.129086)
		(end 117.131846 -227.151946)
		(width 0.1143)
		(layer "In15.Cu")
		(net "GMI_CPU0_G1_CPU1_G3_TX_DP<5>")
	)
	(segment
		(start 354.39604 -230.373174)
		(end 354.400612 -230.37038)
		(width 0.1143)
		(layer "In15.Cu")
		(net "GMI_CPU0_G1_CPU1_G3_TX_DP<5>")
	)
	(segment
		(start 150.223982 -188.095382)
		(end 144.24279 -192.998598)
		(width 0.14224)
		(layer "In15.Cu")
		(net "GMI_CPU0_G1_CPU1_G3_TX_DP<5>")
	)
	(segment
		(start 309.912512 -180.312568)
		(end 307.617876 -179.492148)
		(width 0.14224)
		(layer "In15.Cu")
		(net "GMI_CPU0_G1_CPU1_G3_TX_DP<5>")
	)
	(segment
		(start 354.332286 -230.410004)
		(end 354.36048 -230.393748)
		(width 0.1143)
		(layer "In15.Cu")
		(net "GMI_CPU0_G1_CPU1_G3_TX_DP<5>")
	)
	(segment
		(start 354.39604 -235.9152)
		(end 354.395278 -235.914692)
		(width 0.1143)
		(layer "In15.Cu")
		(net "GMI_CPU0_G1_CPU1_G3_TX_DP<5>")
	)
	(segment
		(start 354.385118 -238.47933)
		(end 354.403152 -238.468662)
		(width 0.1143)
		(layer "In15.Cu")
		(net "GMI_CPU0_G1_CPU1_G3_TX_DP<5>")
	)
	(segment
		(start 354.332286 -232.029762)
		(end 354.363274 -232.011982)
		(width 0.1143)
		(layer "In15.Cu")
		(net "GMI_CPU0_G1_CPU1_G3_TX_DP<5>")
	)
	(segment
		(start 354.365052 -232.010966)
		(end 354.403152 -231.988614)
		(width 0.1143)
		(layer "In15.Cu")
		(net "GMI_CPU0_G1_CPU1_G3_TX_DP<5>")
	)
	(segment
		(start 117.09273 -238.468916)
		(end 117.131846 -238.491776)
		(width 0.1143)
		(layer "In15.Cu")
		(net "GMI_CPU0_G1_CPU1_G3_TX_DP<5>")
	)
	(segment
		(start 117.162326 -235.879132)
		(end 117.131846 -235.896912)
		(width 0.1143)
		(layer "In15.Cu")
		(net "GMI_CPU0_G1_CPU1_G3_TX_DP<5>")
	)
	(segment
		(start 353.422204 -222.935546)
		(end 353.42068 -222.934784)
		(width 0.1143)
		(layer "In15.Cu")
		(net "GMI_CPU0_G1_CPU1_G3_TX_DP<5>")
	)
	(segment
		(start 353.686872 -221.128844)
		(end 353.732592 -221.083124)
		(width 0.1143)
		(layer "In15.Cu")
		(net "GMI_CPU0_G1_CPU1_G3_TX_DP<5>")
	)
	(segment
		(start 154.710892 -184.4167)
		(end 150.223982 -188.095128)
		(width 0.14224)
		(layer "In15.Cu")
		(net "GMI_CPU0_G1_CPU1_G3_TX_DP<5>")
	)
	(segment
		(start 144.24279 -192.998598)
		(end 144.013682 -193.068194)
		(width 0.14224)
		(layer "In15.Cu")
		(net "GMI_CPU0_G1_CPU1_G3_TX_DP<5>")
	)
	(segment
		(start 117.093746 -222.270066)
		(end 117.163342 -222.310198)
		(width 0.1143)
		(layer "In15.Cu")
		(net "GMI_CPU0_G1_CPU1_G3_TX_DP<5>")
	)
	(segment
		(start 116.80063 -221.066106)
		(end 116.80063 -221.277942)
		(width 0.1143)
		(layer "In15.Cu")
		(net "GMI_CPU0_G1_CPU1_G3_TX_DP<5>")
	)
	(segment
		(start 354.36937 -237.519718)
		(end 354.368608 -237.51921)
		(width 0.1143)
		(layer "In15.Cu")
		(net "GMI_CPU0_G1_CPU1_G3_TX_DP<5>")
	)
	(segment
		(start 354.363274 -230.392224)
		(end 354.364036 -230.391716)
		(width 0.1143)
		(layer "In15.Cu")
		(net "GMI_CPU0_G1_CPU1_G3_TX_DP<5>")
	)
	(segment
		(start 354.332286 -243.369846)
		(end 354.363274 -243.352066)
		(width 0.1143)
		(layer "In15.Cu")
		(net "GMI_CPU0_G1_CPU1_G3_TX_DP<5>")
	)
	(segment
		(start 117.162326 -226.159314)
		(end 117.131846 -226.177094)
		(width 0.1143)
		(layer "In15.Cu")
		(net "GMI_CPU0_G1_CPU1_G3_TX_DP<5>")
	)
	(segment
		(start 354.365052 -233.630978)
		(end 354.403152 -233.608626)
		(width 0.1143)
		(layer "In15.Cu")
		(net "GMI_CPU0_G1_CPU1_G3_TX_DP<5>")
	)
	(segment
		(start 117.131846 -227.151946)
		(end 117.162326 -227.169726)
		(width 0.1143)
		(layer "In15.Cu")
		(net "GMI_CPU0_G1_CPU1_G3_TX_DP<5>")
	)
	(segment
		(start 354.723192 -244.484144)
		(end 354.640388 -244.40134)
		(width 0.1143)
		(layer "In15.Cu")
		(net "GMI_CPU0_G1_CPU1_G3_TX_DP<5>")
	)
	(segment
		(start 117.09273 -240.088928)
		(end 117.131846 -240.111788)
		(width 0.1143)
		(layer "In15.Cu")
		(net "GMI_CPU0_G1_CPU1_G3_TX_DP<5>")
	)
	(segment
		(start 354.363274 -228.772212)
		(end 354.364036 -228.771704)
		(width 0.1143)
		(layer "In15.Cu")
		(net "GMI_CPU0_G1_CPU1_G3_TX_DP<5>")
	)
	(segment
		(start 354.396294 -227.815648)
		(end 354.395532 -227.81514)
		(width 0.1143)
		(layer "In15.Cu")
		(net "GMI_CPU0_G1_CPU1_G3_TX_DP<5>")
	)
	(segment
		(start 117.094762 -229.4382)
		(end 117.09273 -229.439724)
		(width 0.1143)
		(layer "In15.Cu")
		(net "GMI_CPU0_G1_CPU1_G3_TX_DP<5>")
	)
	(segment
		(start 117.09273 -231.988868)
		(end 117.131846 -232.011728)
		(width 0.1143)
		(layer "In15.Cu")
		(net "GMI_CPU0_G1_CPU1_G3_TX_DP<5>")
	)
	(segment
		(start 116.80063 -221.277942)
		(end 116.849144 -221.326456)
		(width 0.1143)
		(layer "In15.Cu")
		(net "GMI_CPU0_G1_CPU1_G3_TX_DP<5>")
	)
	(segment
		(start 354.403152 -231.059482)
		(end 354.353876 -231.03078)
		(width 0.1143)
		(layer "In15.Cu")
		(net "GMI_CPU0_G1_CPU1_G3_TX_DP<5>")
	)
	(segment
		(start 353.41814 -222.93326)
		(end 353.417124 -222.932752)
		(width 0.1143)
		(layer "In15.Cu")
		(net "GMI_CPU0_G1_CPU1_G3_TX_DP<5>")
	)
	(segment
		(start 117.162326 -239.119156)
		(end 117.131846 -239.136936)
		(width 0.1143)
		(layer "In15.Cu")
		(net "GMI_CPU0_G1_CPU1_G3_TX_DP<5>")
	)
	(segment
		(start 354.362766 -228.772466)
		(end 354.363274 -228.772212)
		(width 0.1143)
		(layer "In15.Cu")
		(net "GMI_CPU0_G1_CPU1_G3_TX_DP<5>")
	)
	(segment
		(start 354.364036 -233.631486)
		(end 354.365052 -233.630978)
		(width 0.1143)
		(layer "In15.Cu")
		(net "GMI_CPU0_G1_CPU1_G3_TX_DP<5>")
	)
	(segment
		(start 117.131846 -242.37696)
		(end 117.09273 -242.39982)
		(width 0.1143)
		(layer "In15.Cu")
		(net "GMI_CPU0_G1_CPU1_G3_TX_DP<5>")
	)
	(segment
		(start 354.363274 -232.011982)
		(end 354.364036 -232.011474)
		(width 0.1143)
		(layer "In15.Cu")
		(net "GMI_CPU0_G1_CPU1_G3_TX_DP<5>")
	)
	(segment
		(start 354.395532 -227.81514)
		(end 354.364036 -227.796852)
		(width 0.1143)
		(layer "In15.Cu")
		(net "GMI_CPU0_G1_CPU1_G3_TX_DP<5>")
	)
	(segment
		(start 353.463098 -224.579688)
		(end 353.423982 -224.556828)
		(width 0.1143)
		(layer "In15.Cu")
		(net "GMI_CPU0_G1_CPU1_G3_TX_DP<5>")
	)
	(segment
		(start 116.855494 -244.401594)
		(end 116.77269 -244.484398)
		(width 0.1143)
		(layer "In15.Cu")
		(net "GMI_CPU0_G1_CPU1_G3_TX_DP<5>")
	)
	(segment
		(start 116.75491 -220.991938)
		(end 116.75491 -221.020386)
		(width 0.1143)
		(layer "In15.Cu")
		(net "GMI_CPU0_G1_CPU1_G3_TX_DP<5>")
	)
	(segment
		(start 349.699834 -211.345018)
		(end 316.182756 -183.861964)
		(width 0.14224)
		(layer "In15.Cu")
		(net "GMI_CPU0_G1_CPU1_G3_TX_DP<5>")
	)
	(segment
		(start 354.36937 -239.13973)
		(end 354.368608 -239.139222)
		(width 0.1143)
		(layer "In15.Cu")
		(net "GMI_CPU0_G1_CPU1_G3_TX_DP<5>")
	)
	(segment
		(start 354.363274 -243.352066)
		(end 354.364036 -243.351558)
		(width 0.1143)
		(layer "In15.Cu")
		(net "GMI_CPU0_G1_CPU1_G3_TX_DP<5>")
	)
	(segment
		(start 117.09273 -233.60888)
		(end 117.131846 -233.63174)
		(width 0.1143)
		(layer "In15.Cu")
		(net "GMI_CPU0_G1_CPU1_G3_TX_DP<5>")
	)
	(segment
		(start 117.131846 -223.911922)
		(end 117.162326 -223.929702)
		(width 0.1143)
		(layer "In15.Cu")
		(net "GMI_CPU0_G1_CPU1_G3_TX_DP<5>")
	)
	(segment
		(start 353.732592 -219.866718)
		(end 349.699834 -211.345018)
		(width 0.14224)
		(layer "In15.Cu")
		(net "GMI_CPU0_G1_CPU1_G3_TX_DP<5>")
	)
	(segment
		(start 353.423474 -222.936308)
		(end 353.422204 -222.935546)
		(width 0.1143)
		(layer "In15.Cu")
		(net "GMI_CPU0_G1_CPU1_G3_TX_DP<5>")
	)
	(segment
		(start 117.131846 -231.036876)
		(end 117.09273 -231.059736)
		(width 0.1143)
		(layer "In15.Cu")
		(net "GMI_CPU0_G1_CPU1_G3_TX_DP<5>")
	)
	(segment
		(start 117.164358 -229.398068)
		(end 117.131846 -229.416864)
		(width 0.1143)
		(layer "In15.Cu")
		(net "GMI_CPU0_G1_CPU1_G3_TX_DP<5>")
	)
	(segment
		(start 354.384864 -240.099342)
		(end 354.385118 -240.099342)
		(width 0.1143)
		(layer "In15.Cu")
		(net "GMI_CPU0_G1_CPU1_G3_TX_DP<5>")
	)
	(segment
		(start 354.370386 -237.520226)
		(end 354.36937 -237.519718)
		(width 0.1143)
		(layer "In15.Cu")
		(net "GMI_CPU0_G1_CPU1_G3_TX_DP<5>")
	)
	(segment
		(start 116.75491 -221.020386)
		(end 116.80063 -221.066106)
		(width 0.1143)
		(layer "In15.Cu")
		(net "GMI_CPU0_G1_CPU1_G3_TX_DP<5>")
	)
	(segment
		(start 354.363274 -233.631994)
		(end 354.364036 -233.631486)
		(width 0.1143)
		(layer "In15.Cu")
		(net "GMI_CPU0_G1_CPU1_G3_TX_DP<5>")
	)
	(segment
		(start 354.370386 -240.76025)
		(end 354.36937 -240.759742)
		(width 0.1143)
		(layer "In15.Cu")
		(net "GMI_CPU0_G1_CPU1_G3_TX_DP<5>")
	)
	(segment
		(start 307.617876 -179.492148)
		(end 302.90516 -179.492148)
		(width 0.14224)
		(layer "In15.Cu")
		(net "GMI_CPU0_G1_CPU1_G3_TX_DP<5>")
	)
	(segment
		(start 116.77269 -244.484398)
		(end 116.474748 -244.484398)
		(width 0.1143)
		(layer "In15.Cu")
		(net "GMI_CPU0_G1_CPU1_G3_TX_DP<5>")
	)
	(segment
		(start 354.364036 -230.391716)
		(end 354.365052 -230.391208)
		(width 0.1143)
		(layer "In15.Cu")
		(net "GMI_CPU0_G1_CPU1_G3_TX_DP<5>")
	)
	(segment
		(start 354.385118 -241.719354)
		(end 354.403152 -241.708686)
		(width 0.1143)
		(layer "In15.Cu")
		(net "GMI_CPU0_G1_CPU1_G3_TX_DP<5>")
	)
	(segment
		(start 354.368608 -239.139222)
		(end 354.356162 -239.13211)
		(width 0.1143)
		(layer "In15.Cu")
		(net "GMI_CPU0_G1_CPU1_G3_TX_DP<5>")
	)
	(segment
		(start 354.365052 -232.657142)
		(end 354.364036 -232.656634)
		(width 0.1143)
		(layer "In15.Cu")
		(net "GMI_CPU0_G1_CPU1_G3_TX_DP<5>")
	)
	(segment
		(start 353.70643 -221.328234)
		(end 353.686872 -221.308676)
		(width 0.1143)
		(layer "In15.Cu")
		(net "GMI_CPU0_G1_CPU1_G3_TX_DP<5>")
	)
	(segment
		(start 117.164358 -231.01808)
		(end 117.131846 -231.036876)
		(width 0.1143)
		(layer "In15.Cu")
		(net "GMI_CPU0_G1_CPU1_G3_TX_DP<5>")
	)
	(segment
		(start 354.363528 -236.871764)
		(end 354.384864 -236.859318)
		(width 0.1143)
		(layer "In15.Cu")
		(net "GMI_CPU0_G1_CPU1_G3_TX_DP<5>")
	)
	(segment
		(start 354.40239 -237.539022)
		(end 354.370386 -237.520226)
		(width 0.1143)
		(layer "In15.Cu")
		(net "GMI_CPU0_G1_CPU1_G3_TX_DP<5>")
	)
	(segment
		(start 117.162326 -243.979192)
		(end 117.131846 -243.996972)
		(width 0.1143)
		(layer "In15.Cu")
		(net "GMI_CPU0_G1_CPU1_G3_TX_DP<5>")
	)
	(segment
		(start 117.131846 -229.416864)
		(end 117.094762 -229.4382)
		(width 0.1143)
		(layer "In15.Cu")
		(net "GMI_CPU0_G1_CPU1_G3_TX_DP<5>")
	)
	(segment
		(start 354.365052 -228.771196)
		(end 354.366576 -228.77018)
		(width 0.1143)
		(layer "In15.Cu")
		(net "GMI_CPU0_G1_CPU1_G3_TX_DP<5>")
	)
	(segment
		(start 353.424236 -223.911668)
		(end 353.463352 -223.888808)
		(width 0.1143)
		(layer "In15.Cu")
		(net "GMI_CPU0_G1_CPU1_G3_TX_DP<5>")
	)
	(segment
		(start 117.162326 -232.639108)
		(end 117.131846 -232.656888)
		(width 0.1143)
		(layer "In15.Cu")
		(net "GMI_CPU0_G1_CPU1_G3_TX_DP<5>")
	)
	(segment
		(start 354.403152 -227.819712)
		(end 354.396294 -227.815648)
		(width 0.1143)
		(layer "In15.Cu")
		(net "GMI_CPU0_G1_CPU1_G3_TX_DP<5>")
	)
	(segment
		(start 353.419918 -222.934276)
		(end 353.418902 -222.933768)
		(width 0.1143)
		(layer "In15.Cu")
		(net "GMI_CPU0_G1_CPU1_G3_TX_DP<5>")
	)
	(segment
		(start 353.393502 -223.929448)
		(end 353.424236 -223.911668)
		(width 0.1143)
		(layer "In15.Cu")
		(net "GMI_CPU0_G1_CPU1_G3_TX_DP<5>")
	)
	(segment
		(start 117.131846 -240.756948)
		(end 117.09273 -240.779808)
		(width 0.1143)
		(layer "In15.Cu")
		(net "GMI_CPU0_G1_CPU1_G3_TX_DP<5>")
	)
	(segment
		(start 117.162326 -227.779326)
		(end 117.131846 -227.797106)
		(width 0.1143)
		(layer "In15.Cu")
		(net "GMI_CPU0_G1_CPU1_G3_TX_DP<5>")
	)
	(segment
		(start 354.363274 -232.656126)
		(end 354.332286 -232.638346)
		(width 0.1143)
		(layer "In15.Cu")
		(net "GMI_CPU0_G1_CPU1_G3_TX_DP<5>")
	)
	(segment
		(start 117.131846 -235.251752)
		(end 117.162326 -235.269532)
		(width 0.1143)
		(layer "In15.Cu")
		(net "GMI_CPU0_G1_CPU1_G3_TX_DP<5>")
	)
	(segment
		(start 313.04738 -182.087012)
		(end 309.912512 -180.312568)
		(width 0.14224)
		(layer "In15.Cu")
		(net "GMI_CPU0_G1_CPU1_G3_TX_DP<5>")
	)
	(segment
		(start 353.417124 -222.932752)
		(end 353.392486 -222.918528)
		(width 0.1143)
		(layer "In15.Cu")
		(net "GMI_CPU0_G1_CPU1_G3_TX_DP<5>")
	)
	(segment
		(start 117.162326 -222.91929)
		(end 117.131846 -222.93707)
		(width 0.1143)
		(layer "In15.Cu")
		(net "GMI_CPU0_G1_CPU1_G3_TX_DP<5>")
	)
	(segment
		(start 117.131846 -243.351812)
		(end 117.162326 -243.369592)
		(width 0.1143)
		(layer "In15.Cu")
		(net "GMI_CPU0_G1_CPU1_G3_TX_DP<5>")
	)
	(segment
		(start 354.384864 -241.719354)
		(end 354.385118 -241.719354)
		(width 0.1143)
		(layer "In15.Cu")
		(net "GMI_CPU0_G1_CPU1_G3_TX_DP<5>")
	)
	(segment
		(start 302.90516 -179.492148)
		(end 165.81755 -178.692302)
		(width 0.14224)
		(layer "In15.Cu")
		(net "GMI_CPU0_G1_CPU1_G3_TX_DP<5>")
	)
	(segment
		(start 353.418902 -222.933768)
		(end 353.41814 -222.93326)
		(width 0.1143)
		(layer "In15.Cu")
		(net "GMI_CPU0_G1_CPU1_G3_TX_DP<5>")
	)
	(segment
		(start 354.364036 -243.996718)
		(end 354.363274 -243.99621)
		(width 0.1143)
		(layer "In15.Cu")
		(net "GMI_CPU0_G1_CPU1_G3_TX_DP<5>")
	)
	(segment
		(start 354.332286 -227.16998)
		(end 354.364036 -227.151692)
		(width 0.1143)
		(layer "In15.Cu")
		(net "GMI_CPU0_G1_CPU1_G3_TX_DP<5>")
	)
	(segment
		(start 158.503112 -181.30774)
		(end 154.710638 -184.416446)
		(width 0.14224)
		(layer "In15.Cu")
		(net "GMI_CPU0_G1_CPU1_G3_TX_DP<5>")
	)
	(segment
		(start 117.09273 -236.848904)
		(end 117.131846 -236.871764)
		(width 0.1143)
		(layer "In15.Cu")
		(net "GMI_CPU0_G1_CPU1_G3_TX_DP<5>")
	)
	(segment
		(start 117.131846 -243.996972)
		(end 117.09273 -244.019832)
		(width 0.1143)
		(layer "In15.Cu")
		(net "GMI_CPU0_G1_CPU1_G3_TX_DP<5>")
	)
	(segment
		(start 117.131846 -233.63174)
		(end 117.162326 -233.64952)
		(width 0.1143)
		(layer "In15.Cu")
		(net "GMI_CPU0_G1_CPU1_G3_TX_DP<5>")
	)
	(segment
		(start 117.09273 -235.228892)
		(end 117.131846 -235.251752)
		(width 0.1143)
		(layer "In15.Cu")
		(net "GMI_CPU0_G1_CPU1_G3_TX_DP<5>")
	)
	(segment
		(start 116.849144 -221.326456)
		(end 116.849144 -221.804484)
		(width 0.1143)
		(layer "In15.Cu")
		(net "GMI_CPU0_G1_CPU1_G3_TX_DP<5>")
	)
	(arc
		(start 354.636578 -244.37848)
		(mid 354.555145 -244.176082)
		(end 354.403152 -244.019578)
		(width 0.1143)
		(layer "In15.Cu")
		(net "GMI_CPU0_G1_CPU1_G3_TX_DP<5>")
	)
	(arc
		(start 117.09273 -244.019832)
		(mid 116.940743 -244.17634)
		(end 116.859304 -244.378734)
		(width 0.1143)
		(layer "In15.Cu")
		(net "GMI_CPU0_G1_CPU1_G3_TX_DP<5>")
	)
	(arc
		(start 354.646484 -229.904036)
		(mid 354.581969 -229.641817)
		(end 354.403152 -229.43947)
		(width 0.1143)
		(layer "In15.Cu")
		(net "GMI_CPU0_G1_CPU1_G3_TX_DP<5>")
	)
	(arc
		(start 117.162326 -238.509556)
		(mid 117.319303 -238.814356)
		(end 117.162326 -239.119156)
		(width 0.1143)
		(layer "In15.Cu")
		(net "GMI_CPU0_G1_CPU1_G3_TX_DP<5>")
	)
	(arc
		(start 117.163342 -222.310198)
		(mid 117.278018 -222.443532)
		(end 117.319298 -222.61449)
		(width 0.1143)
		(layer "In15.Cu")
		(net "GMI_CPU0_G1_CPU1_G3_TX_DP<5>")
	)
	(arc
		(start 354.168456 -225.79076)
		(mid 354.094338 -225.585754)
		(end 353.961954 -225.412554)
		(width 0.1143)
		(layer "In15.Cu")
		(net "GMI_CPU0_G1_CPU1_G3_TX_DP<5>")
	)
	(arc
		(start 117.09273 -231.059736)
		(mid 116.849403 -231.524302)
		(end 117.09273 -231.988868)
		(width 0.1143)
		(layer "In15.Cu")
		(net "GMI_CPU0_G1_CPU1_G3_TX_DP<5>")
	)
	(arc
		(start 117.319298 -230.71455)
		(mid 117.278332 -230.884956)
		(end 117.164358 -231.01808)
		(width 0.1143)
		(layer "In15.Cu")
		(net "GMI_CPU0_G1_CPU1_G3_TX_DP<5>")
	)
	(arc
		(start 117.162326 -223.929702)
		(mid 117.319303 -224.234502)
		(end 117.162326 -224.539302)
		(width 0.1143)
		(layer "In15.Cu")
		(net "GMI_CPU0_G1_CPU1_G3_TX_DP<5>")
	)
	(arc
		(start 353.23653 -222.614236)
		(mid 353.278079 -222.442814)
		(end 353.393502 -222.309436)
		(width 0.1143)
		(layer "In15.Cu")
		(net "GMI_CPU0_G1_CPU1_G3_TX_DP<5>")
	)
	(arc
		(start 117.09273 -237.539784)
		(mid 116.849403 -238.00435)
		(end 117.09273 -238.468916)
		(width 0.1143)
		(layer "In15.Cu")
		(net "GMI_CPU0_G1_CPU1_G3_TX_DP<5>")
	)
	(arc
		(start 354.403152 -240.088674)
		(mid 354.646479 -239.624108)
		(end 354.403152 -239.159542)
		(width 0.1143)
		(layer "In15.Cu")
		(net "GMI_CPU0_G1_CPU1_G3_TX_DP<5>")
	)
	(arc
		(start 354.403152 -243.328698)
		(mid 354.646479 -242.864132)
		(end 354.403152 -242.399566)
		(width 0.1143)
		(layer "In15.Cu")
		(net "GMI_CPU0_G1_CPU1_G3_TX_DP<5>")
	)
	(arc
		(start 354.403152 -238.468662)
		(mid 354.646479 -238.004096)
		(end 354.403152 -237.53953)
		(width 0.1143)
		(layer "In15.Cu")
		(net "GMI_CPU0_G1_CPU1_G3_TX_DP<5>")
	)
	(arc
		(start 117.09273 -229.439724)
		(mid 116.913917 -229.642074)
		(end 116.849398 -229.90429)
		(width 0.1143)
		(layer "In15.Cu")
		(net "GMI_CPU0_G1_CPU1_G3_TX_DP<5>")
	)
	(arc
		(start 354.403152 -227.128832)
		(mid 354.646479 -226.664266)
		(end 354.403152 -226.1997)
		(width 0.1143)
		(layer "In15.Cu")
		(net "GMI_CPU0_G1_CPU1_G3_TX_DP<5>")
	)
	(arc
		(start 354.400612 -230.37038)
		(mid 354.581264 -230.167635)
		(end 354.646484 -229.904036)
		(width 0.1143)
		(layer "In15.Cu")
		(net "GMI_CPU0_G1_CPU1_G3_TX_DP<5>")
	)
	(arc
		(start 354.403152 -231.988614)
		(mid 354.646479 -231.524048)
		(end 354.403152 -231.059482)
		(width 0.1143)
		(layer "In15.Cu")
		(net "GMI_CPU0_G1_CPU1_G3_TX_DP<5>")
	)
	(arc
		(start 354.403152 -242.399566)
		(mid 354.402771 -242.399312)
		(end 354.40239 -242.399058)
		(width 0.1143)
		(layer "In15.Cu")
		(net "GMI_CPU0_G1_CPU1_G3_TX_DP<5>")
	)
	(arc
		(start 117.162326 -236.889544)
		(mid 117.319303 -237.194344)
		(end 117.162326 -237.499144)
		(width 0.1143)
		(layer "In15.Cu")
		(net "GMI_CPU0_G1_CPU1_G3_TX_DP<5>")
	)
	(arc
		(start 354.403152 -233.608626)
		(mid 354.646479 -233.14406)
		(end 354.403152 -232.679494)
		(width 0.1143)
		(layer "In15.Cu")
		(net "GMI_CPU0_G1_CPU1_G3_TX_DP<5>")
	)
	(arc
		(start 354.17633 -225.865436)
		(mid 354.173951 -225.827933)
		(end 354.168456 -225.79076)
		(width 0.1143)
		(layer "In15.Cu")
		(net "GMI_CPU0_G1_CPU1_G3_TX_DP<5>")
	)
	(arc
		(start 117.162326 -230.40975)
		(mid 117.277753 -230.543126)
		(end 117.319298 -230.71455)
		(width 0.1143)
		(layer "In15.Cu")
		(net "GMI_CPU0_G1_CPU1_G3_TX_DP<5>")
	)
	(arc
		(start 116.849144 -221.804484)
		(mid 116.913803 -222.067041)
		(end 117.092984 -222.269558)
		(width 0.1143)
		(layer "In15.Cu")
		(net "GMI_CPU0_G1_CPU1_G3_TX_DP<5>")
	)
	(arc
		(start 353.464114 -222.268542)
		(mid 353.642296 -222.066139)
		(end 353.70643 -221.80423)
		(width 0.1143)
		(layer "In15.Cu")
		(net "GMI_CPU0_G1_CPU1_G3_TX_DP<5>")
	)
	(arc
		(start 354.332286 -234.258358)
		(mid 354.180697 -233.954066)
		(end 354.332286 -233.649774)
		(width 0.1143)
		(layer "In15.Cu")
		(net "GMI_CPU0_G1_CPU1_G3_TX_DP<5>")
	)
	(arc
		(start 354.356162 -237.512098)
		(mid 354.177945 -237.189821)
		(end 354.363528 -236.871764)
		(width 0.1143)
		(layer "In15.Cu")
		(net "GMI_CPU0_G1_CPU1_G3_TX_DP<5>")
	)
	(arc
		(start 117.092984 -222.269558)
		(mid 117.093365 -222.269812)
		(end 117.093746 -222.270066)
		(width 0.1143)
		(layer "In15.Cu")
		(net "GMI_CPU0_G1_CPU1_G3_TX_DP<5>")
	)
	(arc
		(start 353.862386 -225.348546)
		(mid 353.74771 -225.215212)
		(end 353.70643 -225.044254)
		(width 0.1143)
		(layer "In15.Cu")
		(net "GMI_CPU0_G1_CPU1_G3_TX_DP<5>")
	)
	(arc
		(start 354.403152 -228.748844)
		(mid 354.646479 -228.284278)
		(end 354.403152 -227.819712)
		(width 0.1143)
		(layer "In15.Cu")
		(net "GMI_CPU0_G1_CPU1_G3_TX_DP<5>")
	)
	(arc
		(start 117.162326 -228.789738)
		(mid 117.277753 -228.923114)
		(end 117.319298 -229.094538)
		(width 0.1143)
		(layer "In15.Cu")
		(net "GMI_CPU0_G1_CPU1_G3_TX_DP<5>")
	)
	(arc
		(start 117.09273 -226.199954)
		(mid 116.849403 -226.66452)
		(end 117.09273 -227.129086)
		(width 0.1143)
		(layer "In15.Cu")
		(net "GMI_CPU0_G1_CPU1_G3_TX_DP<5>")
	)
	(arc
		(start 116.859304 -244.378734)
		(mid 116.857281 -244.390144)
		(end 116.855494 -244.401594)
		(width 0.1143)
		(layer "In15.Cu")
		(net "GMI_CPU0_G1_CPU1_G3_TX_DP<5>")
	)
	(arc
		(start 117.09273 -240.779808)
		(mid 116.849403 -241.244374)
		(end 117.09273 -241.70894)
		(width 0.1143)
		(layer "In15.Cu")
		(net "GMI_CPU0_G1_CPU1_G3_TX_DP<5>")
	)
	(arc
		(start 353.392486 -222.918528)
		(mid 353.27781 -222.785194)
		(end 353.23653 -222.614236)
		(width 0.1143)
		(layer "In15.Cu")
		(net "GMI_CPU0_G1_CPU1_G3_TX_DP<5>")
	)
	(arc
		(start 354.403152 -234.299506)
		(mid 354.402771 -234.299252)
		(end 354.40239 -234.298998)
		(width 0.1143)
		(layer "In15.Cu")
		(net "GMI_CPU0_G1_CPU1_G3_TX_DP<5>")
	)
	(arc
		(start 117.09273 -235.919772)
		(mid 116.849403 -236.384338)
		(end 117.09273 -236.848904)
		(width 0.1143)
		(layer "In15.Cu")
		(net "GMI_CPU0_G1_CPU1_G3_TX_DP<5>")
	)
	(arc
		(start 117.162326 -243.369592)
		(mid 117.319303 -243.674392)
		(end 117.162326 -243.979192)
		(width 0.1143)
		(layer "In15.Cu")
		(net "GMI_CPU0_G1_CPU1_G3_TX_DP<5>")
	)
	(arc
		(start 117.09273 -224.579942)
		(mid 116.849403 -225.044508)
		(end 117.09273 -225.509074)
		(width 0.1143)
		(layer "In15.Cu")
		(net "GMI_CPU0_G1_CPU1_G3_TX_DP<5>")
	)
	(arc
		(start 353.393502 -224.539048)
		(mid 353.236525 -224.234248)
		(end 353.393502 -223.929448)
		(width 0.1143)
		(layer "In15.Cu")
		(net "GMI_CPU0_G1_CPU1_G3_TX_DP<5>")
	)
	(arc
		(start 117.162326 -235.269532)
		(mid 117.319303 -235.574332)
		(end 117.162326 -235.879132)
		(width 0.1143)
		(layer "In15.Cu")
		(net "GMI_CPU0_G1_CPU1_G3_TX_DP<5>")
	)
	(arc
		(start 354.356162 -242.372134)
		(mid 354.177945 -242.049857)
		(end 354.363528 -241.7318)
		(width 0.1143)
		(layer "In15.Cu")
		(net "GMI_CPU0_G1_CPU1_G3_TX_DP<5>")
	)
	(arc
		(start 117.319298 -222.61449)
		(mid 117.277749 -222.785912)
		(end 117.162326 -222.91929)
		(width 0.1143)
		(layer "In15.Cu")
		(net "GMI_CPU0_G1_CPU1_G3_TX_DP<5>")
	)
	(arc
		(start 116.849398 -229.90429)
		(mid 116.914634 -230.167881)
		(end 117.09527 -230.370634)
		(width 0.1143)
		(layer "In15.Cu")
		(net "GMI_CPU0_G1_CPU1_G3_TX_DP<5>")
	)
	(arc
		(start 117.09273 -242.39982)
		(mid 116.849403 -242.864386)
		(end 117.09273 -243.328952)
		(width 0.1143)
		(layer "In15.Cu")
		(net "GMI_CPU0_G1_CPU1_G3_TX_DP<5>")
	)
	(arc
		(start 117.162326 -240.129568)
		(mid 117.319303 -240.434368)
		(end 117.162326 -240.739168)
		(width 0.1143)
		(layer "In15.Cu")
		(net "GMI_CPU0_G1_CPU1_G3_TX_DP<5>")
	)
	(arc
		(start 117.162326 -225.549714)
		(mid 117.319303 -225.854514)
		(end 117.162326 -226.159314)
		(width 0.1143)
		(layer "In15.Cu")
		(net "GMI_CPU0_G1_CPU1_G3_TX_DP<5>")
	)
	(arc
		(start 354.403152 -236.84865)
		(mid 354.646479 -236.384084)
		(end 354.403152 -235.919518)
		(width 0.1143)
		(layer "In15.Cu")
		(net "GMI_CPU0_G1_CPU1_G3_TX_DP<5>")
	)
	(arc
		(start 354.640388 -244.40134)
		(mid 354.6386 -244.389891)
		(end 354.636578 -244.37848)
		(width 0.1143)
		(layer "In15.Cu")
		(net "GMI_CPU0_G1_CPU1_G3_TX_DP<5>")
	)
	(arc
		(start 117.09273 -239.159796)
		(mid 116.849403 -239.624362)
		(end 117.09273 -240.088928)
		(width 0.1143)
		(layer "In15.Cu")
		(net "GMI_CPU0_G1_CPU1_G3_TX_DP<5>")
	)
	(arc
		(start 354.330508 -229.397052)
		(mid 354.217101 -229.264163)
		(end 354.17633 -229.094284)
		(width 0.1143)
		(layer "In15.Cu")
		(net "GMI_CPU0_G1_CPU1_G3_TX_DP<5>")
	)
	(arc
		(start 354.333302 -226.15906)
		(mid 354.220455 -226.030627)
		(end 354.17633 -225.865436)
		(width 0.1143)
		(layer "In15.Cu")
		(net "GMI_CPU0_G1_CPU1_G3_TX_DP<5>")
	)
	(arc
		(start 117.09273 -222.95993)
		(mid 116.849403 -223.424496)
		(end 117.09273 -223.889062)
		(width 0.1143)
		(layer "In15.Cu")
		(net "GMI_CPU0_G1_CPU1_G3_TX_DP<5>")
	)
	(arc
		(start 354.332286 -232.638346)
		(mid 354.183189 -232.334054)
		(end 354.332286 -232.029762)
		(width 0.1143)
		(layer "In15.Cu")
		(net "GMI_CPU0_G1_CPU1_G3_TX_DP<5>")
	)
	(arc
		(start 117.09273 -232.679748)
		(mid 116.849403 -233.144314)
		(end 117.09273 -233.60888)
		(width 0.1143)
		(layer "In15.Cu")
		(net "GMI_CPU0_G1_CPU1_G3_TX_DP<5>")
	)
	(arc
		(start 117.162326 -241.74958)
		(mid 117.319303 -242.05438)
		(end 117.162326 -242.35918)
		(width 0.1143)
		(layer "In15.Cu")
		(net "GMI_CPU0_G1_CPU1_G3_TX_DP<5>")
	)
	(arc
		(start 353.70643 -225.044254)
		(mid 353.641915 -224.782035)
		(end 353.463098 -224.579688)
		(width 0.1143)
		(layer "In15.Cu")
		(net "GMI_CPU0_G1_CPU1_G3_TX_DP<5>")
	)
	(arc
		(start 117.162326 -227.169726)
		(mid 117.319303 -227.474526)
		(end 117.162326 -227.779326)
		(width 0.1143)
		(layer "In15.Cu")
		(net "GMI_CPU0_G1_CPU1_G3_TX_DP<5>")
	)
	(arc
		(start 354.403152 -239.159542)
		(mid 354.402771 -239.159288)
		(end 354.40239 -239.159034)
		(width 0.1143)
		(layer "In15.Cu")
		(net "GMI_CPU0_G1_CPU1_G3_TX_DP<5>")
	)
	(arc
		(start 354.403152 -235.228638)
		(mid 354.646479 -234.764072)
		(end 354.403152 -234.299506)
		(width 0.1143)
		(layer "In15.Cu")
		(net "GMI_CPU0_G1_CPU1_G3_TX_DP<5>")
	)
	(arc
		(start 354.356162 -240.752122)
		(mid 354.177945 -240.429845)
		(end 354.363528 -240.111788)
		(width 0.1143)
		(layer "In15.Cu")
		(net "GMI_CPU0_G1_CPU1_G3_TX_DP<5>")
	)
	(arc
		(start 117.162326 -232.029508)
		(mid 117.319303 -232.334308)
		(end 117.162326 -232.639108)
		(width 0.1143)
		(layer "In15.Cu")
		(net "GMI_CPU0_G1_CPU1_G3_TX_DP<5>")
	)
	(arc
		(start 117.162326 -233.64952)
		(mid 117.319303 -233.95432)
		(end 117.162326 -234.25912)
		(width 0.1143)
		(layer "In15.Cu")
		(net "GMI_CPU0_G1_CPU1_G3_TX_DP<5>")
	)
	(arc
		(start 354.356162 -235.892086)
		(mid 354.177945 -235.569809)
		(end 354.363528 -235.251752)
		(width 0.1143)
		(layer "In15.Cu")
		(net "GMI_CPU0_G1_CPU1_G3_TX_DP<5>")
	)
	(arc
		(start 354.17633 -229.094284)
		(mid 354.226295 -228.908308)
		(end 354.362766 -228.772466)
		(width 0.1143)
		(layer "In15.Cu")
		(net "GMI_CPU0_G1_CPU1_G3_TX_DP<5>")
	)
	(arc
		(start 353.463352 -223.888808)
		(mid 353.706679 -223.424242)
		(end 353.463352 -222.959676)
		(width 0.1143)
		(layer "In15.Cu")
		(net "GMI_CPU0_G1_CPU1_G3_TX_DP<5>")
	)
	(arc
		(start 354.403152 -237.53953)
		(mid 354.402771 -237.539276)
		(end 354.40239 -237.539022)
		(width 0.1143)
		(layer "In15.Cu")
		(net "GMI_CPU0_G1_CPU1_G3_TX_DP<5>")
	)
	(arc
		(start 354.403152 -240.779554)
		(mid 354.402771 -240.7793)
		(end 354.40239 -240.779046)
		(width 0.1143)
		(layer "In15.Cu")
		(net "GMI_CPU0_G1_CPU1_G3_TX_DP<5>")
	)
	(arc
		(start 354.332286 -227.778564)
		(mid 354.183189 -227.474272)
		(end 354.332286 -227.16998)
		(width 0.1143)
		(layer "In15.Cu")
		(net "GMI_CPU0_G1_CPU1_G3_TX_DP<5>")
	)
	(arc
		(start 354.353876 -231.03078)
		(mid 354.221973 -230.896727)
		(end 354.17633 -230.714296)
		(width 0.1143)
		(layer "In15.Cu")
		(net "GMI_CPU0_G1_CPU1_G3_TX_DP<5>")
	)
	(arc
		(start 354.403152 -241.708686)
		(mid 354.646479 -241.24412)
		(end 354.403152 -240.779554)
		(width 0.1143)
		(layer "In15.Cu")
		(net "GMI_CPU0_G1_CPU1_G3_TX_DP<5>")
	)
	(arc
		(start 354.403152 -235.919518)
		(mid 354.402771 -235.919264)
		(end 354.40239 -235.91901)
		(width 0.1143)
		(layer "In15.Cu")
		(net "GMI_CPU0_G1_CPU1_G3_TX_DP<5>")
	)
	(arc
		(start 353.961954 -225.412554)
		(mid 353.946422 -225.399959)
		(end 353.930458 -225.387916)
		(width 0.1143)
		(layer "In15.Cu")
		(net "GMI_CPU0_G1_CPU1_G3_TX_DP<5>")
	)
	(arc
		(start 354.17633 -230.714296)
		(mid 354.219195 -230.544144)
		(end 354.332286 -230.410004)
		(width 0.1143)
		(layer "In15.Cu")
		(net "GMI_CPU0_G1_CPU1_G3_TX_DP<5>")
	)
	(arc
		(start 117.09273 -227.819966)
		(mid 116.849403 -228.284532)
		(end 117.09273 -228.749098)
		(width 0.1143)
		(layer "In15.Cu")
		(net "GMI_CPU0_G1_CPU1_G3_TX_DP<5>")
	)
	(arc
		(start 354.356162 -239.13211)
		(mid 354.177945 -238.809833)
		(end 354.363528 -238.491776)
		(width 0.1143)
		(layer "In15.Cu")
		(net "GMI_CPU0_G1_CPU1_G3_TX_DP<5>")
	)
	(arc
		(start 117.09273 -234.29976)
		(mid 116.849403 -234.764326)
		(end 117.09273 -235.228892)
		(width 0.1143)
		(layer "In15.Cu")
		(net "GMI_CPU0_G1_CPU1_G3_TX_DP<5>")
	)
	(arc
		(start 117.319298 -229.094538)
		(mid 117.278332 -229.264944)
		(end 117.164358 -229.398068)
		(width 0.1143)
		(layer "In15.Cu")
		(net "GMI_CPU0_G1_CPU1_G3_TX_DP<5>")
	)
	(arc
		(start 354.332286 -243.97843)
		(mid 354.183189 -243.674138)
		(end 354.332286 -243.369846)
		(width 0.1143)
		(layer "In15.Cu")
		(net "GMI_CPU0_G1_CPU1_G3_TX_DP<5>")
	)
	(segment
		(start 116.007896 -247.99036)
		(end 116.474748 -247.724422)
		(width 0.12954)
		(layer "F.Cu")
		(net "GMI_CPU0_G1_CPU1_G3_TX_DP<4>")
	)
	(segment
		(start 355.487986 -247.990106)
		(end 355.021134 -247.724168)
		(width 0.12954)
		(layer "F.Cu")
		(net "GMI_CPU0_G1_CPU1_G3_TX_DP<4>")
	)
	(segment
		(start 116.188998 -246.590312)
		(end 116.190776 -246.591328)
		(width 0.1143)
		(layer "In15.Cu")
		(net "GMI_CPU0_G1_CPU1_G3_TX_DP<4>")
	)
	(segment
		(start 355.303328 -236.872018)
		(end 355.30409 -236.87151)
		(width 0.1143)
		(layer "In15.Cu")
		(net "GMI_CPU0_G1_CPU1_G3_TX_DP<4>")
	)
	(segment
		(start 355.303328 -243.99621)
		(end 355.302058 -243.995448)
		(width 0.1143)
		(layer "In15.Cu")
		(net "GMI_CPU0_G1_CPU1_G3_TX_DP<4>")
	)
	(segment
		(start 116.192554 -234.276392)
		(end 116.191792 -234.2769)
		(width 0.1143)
		(layer "In15.Cu")
		(net "GMI_CPU0_G1_CPU1_G3_TX_DP<4>")
	)
	(segment
		(start 355.30409 -232.011474)
		(end 355.305106 -232.010966)
		(width 0.1143)
		(layer "In15.Cu")
		(net "GMI_CPU0_G1_CPU1_G3_TX_DP<4>")
	)
	(segment
		(start 116.190776 -241.731292)
		(end 116.191792 -241.7318)
		(width 0.1143)
		(layer "In15.Cu")
		(net "GMI_CPU0_G1_CPU1_G3_TX_DP<4>")
	)
	(segment
		(start 116.188998 -241.730276)
		(end 116.190776 -241.731292)
		(width 0.1143)
		(layer "In15.Cu")
		(net "GMI_CPU0_G1_CPU1_G3_TX_DP<4>")
	)
	(segment
		(start 116.155216 -230.370634)
		(end 116.159534 -230.373174)
		(width 0.1143)
		(layer "In15.Cu")
		(net "GMI_CPU0_G1_CPU1_G3_TX_DP<4>")
	)
	(segment
		(start 116.188998 -225.53041)
		(end 116.190776 -225.531426)
		(width 0.1143)
		(layer "In15.Cu")
		(net "GMI_CPU0_G1_CPU1_G3_TX_DP<4>")
	)
	(segment
		(start 355.300534 -246.593614)
		(end 355.302058 -246.592852)
		(width 0.1143)
		(layer "In15.Cu")
		(net "GMI_CPU0_G1_CPU1_G3_TX_DP<4>")
	)
	(segment
		(start 116.191792 -234.2769)
		(end 116.190776 -234.277408)
		(width 0.1143)
		(layer "In15.Cu")
		(net "GMI_CPU0_G1_CPU1_G3_TX_DP<4>")
	)
	(segment
		(start 116.186458 -228.76891)
		(end 116.187474 -228.769418)
		(width 0.1143)
		(layer "In15.Cu")
		(net "GMI_CPU0_G1_CPU1_G3_TX_DP<4>")
	)
	(segment
		(start 354.63226 -221.308676)
		(end 354.63226 -221.128844)
		(width 0.1143)
		(layer "In15.Cu")
		(net "GMI_CPU0_G1_CPU1_G3_TX_DP<4>")
	)
	(segment
		(start 355.305106 -239.13719)
		(end 355.30409 -239.136682)
		(width 0.1143)
		(layer "In15.Cu")
		(net "GMI_CPU0_G1_CPU1_G3_TX_DP<4>")
	)
	(segment
		(start 116.184934 -233.627676)
		(end 116.186458 -233.628692)
		(width 0.1143)
		(layer "In15.Cu")
		(net "GMI_CPU0_G1_CPU1_G3_TX_DP<4>")
	)
	(segment
		(start 355.343206 -234.299506)
		(end 355.30663 -234.27817)
		(width 0.1143)
		(layer "In15.Cu")
		(net "GMI_CPU0_G1_CPU1_G3_TX_DP<4>")
	)
	(segment
		(start 355.30409 -233.631486)
		(end 355.305106 -233.630978)
		(width 0.1143)
		(layer "In15.Cu")
		(net "GMI_CPU0_G1_CPU1_G3_TX_DP<4>")
	)
	(segment
		(start 355.30663 -244.970046)
		(end 355.311202 -244.967506)
		(width 0.1143)
		(layer "In15.Cu")
		(net "GMI_CPU0_G1_CPU1_G3_TX_DP<4>")
	)
	(segment
		(start 116.159534 -244.953028)
		(end 116.160296 -244.953536)
		(width 0.1143)
		(layer "In15.Cu")
		(net "GMI_CPU0_G1_CPU1_G3_TX_DP<4>")
	)
	(segment
		(start 355.297994 -243.993162)
		(end 355.296978 -243.992654)
		(width 0.1143)
		(layer "In15.Cu")
		(net "GMI_CPU0_G1_CPU1_G3_TX_DP<4>")
	)
	(segment
		(start 355.300534 -236.873542)
		(end 355.302058 -236.87278)
		(width 0.1143)
		(layer "In15.Cu")
		(net "GMI_CPU0_G1_CPU1_G3_TX_DP<4>")
	)
	(segment
		(start 116.223542 -242.358672)
		(end 116.192554 -242.376452)
		(width 0.1143)
		(layer "In15.Cu")
		(net "GMI_CPU0_G1_CPU1_G3_TX_DP<4>")
	)
	(segment
		(start 355.305106 -242.377214)
		(end 355.30409 -242.376706)
		(width 0.1143)
		(layer "In15.Cu")
		(net "GMI_CPU0_G1_CPU1_G3_TX_DP<4>")
	)
	(segment
		(start 116.223542 -222.918782)
		(end 116.192554 -222.936562)
		(width 0.1143)
		(layer "In15.Cu")
		(net "GMI_CPU0_G1_CPU1_G3_TX_DP<4>")
	)
	(segment
		(start 355.30409 -231.036622)
		(end 355.270562 -231.017064)
		(width 0.1143)
		(layer "In15.Cu")
		(net "GMI_CPU0_G1_CPU1_G3_TX_DP<4>")
	)
	(segment
		(start 355.30663 -238.489998)
		(end 355.343206 -238.468662)
		(width 0.1143)
		(layer "In15.Cu")
		(net "GMI_CPU0_G1_CPU1_G3_TX_DP<4>")
	)
	(segment
		(start 116.191792 -242.37696)
		(end 116.190776 -242.377468)
		(width 0.1143)
		(layer "In15.Cu")
		(net "GMI_CPU0_G1_CPU1_G3_TX_DP<4>")
	)
	(segment
		(start 355.302058 -241.732816)
		(end 355.303328 -241.732054)
		(width 0.1143)
		(layer "In15.Cu")
		(net "GMI_CPU0_G1_CPU1_G3_TX_DP<4>")
	)
	(segment
		(start 116.190776 -226.177602)
		(end 116.152676 -226.199954)
		(width 0.1143)
		(layer "In15.Cu")
		(net "GMI_CPU0_G1_CPU1_G3_TX_DP<4>")
	)
	(segment
		(start 116.192046 -235.251752)
		(end 116.1923 -235.251752)
		(width 0.1143)
		(layer "In15.Cu")
		(net "GMI_CPU0_G1_CPU1_G3_TX_DP<4>")
	)
	(segment
		(start 355.311202 -233.627422)
		(end 355.343206 -233.608626)
		(width 0.1143)
		(layer "In15.Cu")
		(net "GMI_CPU0_G1_CPU1_G3_TX_DP<4>")
	)
	(segment
		(start 116.189252 -237.518448)
		(end 116.152676 -237.539784)
		(width 0.1143)
		(layer "In15.Cu")
		(net "GMI_CPU0_G1_CPU1_G3_TX_DP<4>")
	)
	(segment
		(start 116.187474 -246.589296)
		(end 116.188998 -246.590312)
		(width 0.1143)
		(layer "In15.Cu")
		(net "GMI_CPU0_G1_CPU1_G3_TX_DP<4>")
	)
	(segment
		(start 355.302058 -235.252768)
		(end 355.303328 -235.252006)
		(width 0.1143)
		(layer "In15.Cu")
		(net "GMI_CPU0_G1_CPU1_G3_TX_DP<4>")
	)
	(segment
		(start 355.302058 -235.895388)
		(end 355.300534 -235.894626)
		(width 0.1143)
		(layer "In15.Cu")
		(net "GMI_CPU0_G1_CPU1_G3_TX_DP<4>")
	)
	(segment
		(start 355.299772 -235.894118)
		(end 355.298756 -235.89361)
		(width 0.1143)
		(layer "In15.Cu")
		(net "GMI_CPU0_G1_CPU1_G3_TX_DP<4>")
	)
	(segment
		(start 116.187474 -241.72926)
		(end 116.188998 -241.730276)
		(width 0.1143)
		(layer "In15.Cu")
		(net "GMI_CPU0_G1_CPU1_G3_TX_DP<4>")
	)
	(segment
		(start 116.191792 -235.896912)
		(end 116.190776 -235.89742)
		(width 0.1143)
		(layer "In15.Cu")
		(net "GMI_CPU0_G1_CPU1_G3_TX_DP<4>")
	)
	(segment
		(start 116.192554 -242.376452)
		(end 116.191792 -242.37696)
		(width 0.1143)
		(layer "In15.Cu")
		(net "GMI_CPU0_G1_CPU1_G3_TX_DP<4>")
	)
	(segment
		(start 355.311202 -235.247434)
		(end 355.343206 -235.228638)
		(width 0.1143)
		(layer "In15.Cu")
		(net "GMI_CPU0_G1_CPU1_G3_TX_DP<4>")
	)
	(segment
		(start 116.190776 -239.137444)
		(end 116.189252 -239.13846)
		(width 0.1143)
		(layer "In15.Cu")
		(net "GMI_CPU0_G1_CPU1_G3_TX_DP<4>")
	)
	(segment
		(start 116.192554 -224.556574)
		(end 116.191792 -224.557082)
		(width 0.1143)
		(layer "In15.Cu")
		(net "GMI_CPU0_G1_CPU1_G3_TX_DP<4>")
	)
	(segment
		(start 116.192554 -246.592344)
		(end 116.193062 -246.592344)
		(width 0.1143)
		(layer "In15.Cu")
		(net "GMI_CPU0_G1_CPU1_G3_TX_DP<4>")
	)
	(segment
		(start 355.300534 -241.733578)
		(end 355.302058 -241.732816)
		(width 0.1143)
		(layer "In15.Cu")
		(net "GMI_CPU0_G1_CPU1_G3_TX_DP<4>")
	)
	(segment
		(start 116.186458 -243.348764)
		(end 116.187474 -243.349272)
		(width 0.1143)
		(layer "In15.Cu")
		(net "GMI_CPU0_G1_CPU1_G3_TX_DP<4>")
	)
	(segment
		(start 116.192554 -235.896658)
		(end 116.191792 -235.896912)
		(width 0.1143)
		(layer "In15.Cu")
		(net "GMI_CPU0_G1_CPU1_G3_TX_DP<4>")
	)
	(segment
		(start 355.343206 -245.63959)
		(end 355.305106 -245.617238)
		(width 0.1143)
		(layer "In15.Cu")
		(net "GMI_CPU0_G1_CPU1_G3_TX_DP<4>")
	)
	(segment
		(start 355.305106 -245.617238)
		(end 355.30409 -245.61673)
		(width 0.1143)
		(layer "In15.Cu")
		(net "GMI_CPU0_G1_CPU1_G3_TX_DP<4>")
	)
	(segment
		(start 355.302058 -232.655364)
		(end 355.300534 -232.654602)
		(width 0.1143)
		(layer "In15.Cu")
		(net "GMI_CPU0_G1_CPU1_G3_TX_DP<4>")
	)
	(segment
		(start 355.302058 -243.995448)
		(end 355.300534 -243.994686)
		(width 0.1143)
		(layer "In15.Cu")
		(net "GMI_CPU0_G1_CPU1_G3_TX_DP<4>")
	)
	(segment
		(start 116.223542 -245.598696)
		(end 116.192554 -245.616476)
		(width 0.1143)
		(layer "In15.Cu")
		(net "GMI_CPU0_G1_CPU1_G3_TX_DP<4>")
	)
	(segment
		(start 355.300534 -239.13465)
		(end 355.299772 -239.134142)
		(width 0.1143)
		(layer "In15.Cu")
		(net "GMI_CPU0_G1_CPU1_G3_TX_DP<4>")
	)
	(segment
		(start 355.30663 -243.998242)
		(end 355.305106 -243.997226)
		(width 0.1143)
		(layer "In15.Cu")
		(net "GMI_CPU0_G1_CPU1_G3_TX_DP<4>")
	)
	(segment
		(start 355.30663 -240.11001)
		(end 355.311202 -240.10747)
		(width 0.1143)
		(layer "In15.Cu")
		(net "GMI_CPU0_G1_CPU1_G3_TX_DP<4>")
	)
	(segment
		(start 355.300534 -233.633518)
		(end 355.302058 -233.632756)
		(width 0.1143)
		(layer "In15.Cu")
		(net "GMI_CPU0_G1_CPU1_G3_TX_DP<4>")
	)
	(segment
		(start 116.152676 -240.088928)
		(end 116.152676 -240.091468)
		(width 0.1143)
		(layer "In15.Cu")
		(net "GMI_CPU0_G1_CPU1_G3_TX_DP<4>")
	)
	(segment
		(start 116.193062 -246.592344)
		(end 116.206778 -246.600218)
		(width 0.1143)
		(layer "In15.Cu")
		(net "GMI_CPU0_G1_CPU1_G3_TX_DP<4>")
	)
	(segment
		(start 116.192554 -226.176586)
		(end 116.191792 -226.177094)
		(width 0.1143)
		(layer "In15.Cu")
		(net "GMI_CPU0_G1_CPU1_G3_TX_DP<4>")
	)
	(segment
		(start 116.223542 -226.158806)
		(end 116.192554 -226.176586)
		(width 0.1143)
		(layer "In15.Cu")
		(net "GMI_CPU0_G1_CPU1_G3_TX_DP<4>")
	)
	(segment
		(start 354.364036 -223.911668)
		(end 354.403152 -223.888808)
		(width 0.1143)
		(layer "In15.Cu")
		(net "GMI_CPU0_G1_CPU1_G3_TX_DP<4>")
	)
	(segment
		(start 354.83419 -225.366834)
		(end 354.833428 -225.366326)
		(width 0.1143)
		(layer "In15.Cu")
		(net "GMI_CPU0_G1_CPU1_G3_TX_DP<4>")
	)
	(segment
		(start 116.160296 -244.953536)
		(end 116.184934 -244.96776)
		(width 0.1143)
		(layer "In15.Cu")
		(net "GMI_CPU0_G1_CPU1_G3_TX_DP<4>")
	)
	(segment
		(start 355.305106 -243.35105)
		(end 355.30663 -243.350034)
		(width 0.1143)
		(layer "In15.Cu")
		(net "GMI_CPU0_G1_CPU1_G3_TX_DP<4>")
	)
	(segment
		(start 355.299772 -243.994178)
		(end 355.298756 -243.99367)
		(width 0.1143)
		(layer "In15.Cu")
		(net "GMI_CPU0_G1_CPU1_G3_TX_DP<4>")
	)
	(segment
		(start 116.192554 -244.972332)
		(end 116.223542 -244.990112)
		(width 0.1143)
		(layer "In15.Cu")
		(net "GMI_CPU0_G1_CPU1_G3_TX_DP<4>")
	)
	(segment
		(start 354.332286 -222.309944)
		(end 354.364036 -222.291656)
		(width 0.1143)
		(layer "In15.Cu")
		(net "GMI_CPU0_G1_CPU1_G3_TX_DP<4>")
	)
	(segment
		(start 355.305106 -237.517178)
		(end 355.30409 -237.51667)
		(width 0.1143)
		(layer "In15.Cu")
		(net "GMI_CPU0_G1_CPU1_G3_TX_DP<4>")
	)
	(segment
		(start 116.152676 -243.328952)
		(end 116.159534 -243.333016)
		(width 0.1143)
		(layer "In15.Cu")
		(net "GMI_CPU0_G1_CPU1_G3_TX_DP<4>")
	)
	(segment
		(start 116.152676 -246.568976)
		(end 116.159534 -246.57304)
		(width 0.1143)
		(layer "In15.Cu")
		(net "GMI_CPU0_G1_CPU1_G3_TX_DP<4>")
	)
	(segment
		(start 355.30663 -240.758218)
		(end 355.305106 -240.757202)
		(width 0.1143)
		(layer "In15.Cu")
		(net "GMI_CPU0_G1_CPU1_G3_TX_DP<4>")
	)
	(segment
		(start 355.302058 -232.012744)
		(end 355.303328 -232.011982)
		(width 0.1143)
		(layer "In15.Cu")
		(net "GMI_CPU0_G1_CPU1_G3_TX_DP<4>")
	)
	(segment
		(start 116.191792 -243.351812)
		(end 116.192554 -243.35232)
		(width 0.1143)
		(layer "In15.Cu")
		(net "GMI_CPU0_G1_CPU1_G3_TX_DP<4>")
	)
	(segment
		(start 116.189252 -245.618508)
		(end 116.152676 -245.639844)
		(width 0.1143)
		(layer "In15.Cu")
		(net "GMI_CPU0_G1_CPU1_G3_TX_DP<4>")
	)
	(segment
		(start 355.30663 -235.249974)
		(end 355.311202 -235.247434)
		(width 0.1143)
		(layer "In15.Cu")
		(net "GMI_CPU0_G1_CPU1_G3_TX_DP<4>")
	)
	(segment
		(start 355.302058 -244.97284)
		(end 355.303328 -244.972078)
		(width 0.1143)
		(layer "In15.Cu")
		(net "GMI_CPU0_G1_CPU1_G3_TX_DP<4>")
	)
	(segment
		(start 116.160296 -227.133658)
		(end 116.184934 -227.147882)
		(width 0.1143)
		(layer "In15.Cu")
		(net "GMI_CPU0_G1_CPU1_G3_TX_DP<4>")
	)
	(segment
		(start 116.188998 -232.010204)
		(end 116.190776 -232.01122)
		(width 0.1143)
		(layer "In15.Cu")
		(net "GMI_CPU0_G1_CPU1_G3_TX_DP<4>")
	)
	(segment
		(start 355.305106 -236.871002)
		(end 355.30663 -236.869986)
		(width 0.1143)
		(layer "In15.Cu")
		(net "GMI_CPU0_G1_CPU1_G3_TX_DP<4>")
	)
	(segment
		(start 354.723192 -247.724168)
		(end 354.653342 -247.654318)
		(width 0.1143)
		(layer "In15.Cu")
		(net "GMI_CPU0_G1_CPU1_G3_TX_DP<4>")
	)
	(segment
		(start 355.305106 -234.277154)
		(end 355.30409 -234.276646)
		(width 0.1143)
		(layer "In15.Cu")
		(net "GMI_CPU0_G1_CPU1_G3_TX_DP<4>")
	)
	(segment
		(start 355.021134 -247.724168)
		(end 354.723192 -247.724168)
		(width 0.1143)
		(layer "In15.Cu")
		(net "GMI_CPU0_G1_CPU1_G3_TX_DP<4>")
	)
	(segment
		(start 355.300534 -235.894626)
		(end 355.299772 -235.894118)
		(width 0.1143)
		(layer "In15.Cu")
		(net "GMI_CPU0_G1_CPU1_G3_TX_DP<4>")
	)
	(segment
		(start 310.17337 -179.383182)
		(end 310.17337 -179.382928)
		(width 0.14224)
		(layer "In15.Cu")
		(net "GMI_CPU0_G1_CPU1_G3_TX_DP<4>")
	)
	(segment
		(start 355.343206 -242.399566)
		(end 355.305106 -242.377214)
		(width 0.1143)
		(layer "In15.Cu")
		(net "GMI_CPU0_G1_CPU1_G3_TX_DP<4>")
	)
	(segment
		(start 355.302058 -239.135412)
		(end 355.300534 -239.13465)
		(width 0.1143)
		(layer "In15.Cu")
		(net "GMI_CPU0_G1_CPU1_G3_TX_DP<4>")
	)
	(segment
		(start 354.366576 -222.290132)
		(end 354.403152 -222.268796)
		(width 0.1143)
		(layer "In15.Cu")
		(net "GMI_CPU0_G1_CPU1_G3_TX_DP<4>")
	)
	(segment
		(start 355.302058 -236.87278)
		(end 355.303328 -236.872018)
		(width 0.1143)
		(layer "In15.Cu")
		(net "GMI_CPU0_G1_CPU1_G3_TX_DP<4>")
	)
	(segment
		(start 116.152676 -235.228892)
		(end 116.152676 -235.229146)
		(width 0.1143)
		(layer "In15.Cu")
		(net "GMI_CPU0_G1_CPU1_G3_TX_DP<4>")
	)
	(segment
		(start 355.340412 -228.750876)
		(end 355.343206 -228.748844)
		(width 0.1143)
		(layer "In15.Cu")
		(net "GMI_CPU0_G1_CPU1_G3_TX_DP<4>")
	)
	(segment
		(start 355.299772 -239.134142)
		(end 355.298756 -239.133634)
		(width 0.1143)
		(layer "In15.Cu")
		(net "GMI_CPU0_G1_CPU1_G3_TX_DP<4>")
	)
	(segment
		(start 355.30409 -246.591582)
		(end 355.305106 -246.591074)
		(width 0.1143)
		(layer "In15.Cu")
		(net "GMI_CPU0_G1_CPU1_G3_TX_DP<4>")
	)
	(segment
		(start 116.188998 -223.910398)
		(end 116.190776 -223.911414)
		(width 0.1143)
		(layer "In15.Cu")
		(net "GMI_CPU0_G1_CPU1_G3_TX_DP<4>")
	)
	(segment
		(start 355.30409 -229.41661)
		(end 355.270562 -229.397052)
		(width 0.1143)
		(layer "In15.Cu")
		(net "GMI_CPU0_G1_CPU1_G3_TX_DP<4>")
	)
	(segment
		(start 116.191792 -224.557082)
		(end 116.190776 -224.55759)
		(width 0.1143)
		(layer "In15.Cu")
		(net "GMI_CPU0_G1_CPU1_G3_TX_DP<4>")
	)
	(segment
		(start 355.303328 -240.756186)
		(end 355.302058 -240.755424)
		(width 0.1143)
		(layer "In15.Cu")
		(net "GMI_CPU0_G1_CPU1_G3_TX_DP<4>")
	)
	(segment
		(start 116.159534 -243.333016)
		(end 116.160296 -243.333524)
		(width 0.1143)
		(layer "In15.Cu")
		(net "GMI_CPU0_G1_CPU1_G3_TX_DP<4>")
	)
	(segment
		(start 116.223542 -232.030016)
		(end 116.230146 -232.034842)
		(width 0.1143)
		(layer "In15.Cu")
		(net "GMI_CPU0_G1_CPU1_G3_TX_DP<4>")
	)
	(segment
		(start 310.152288 -179.371244)
		(end 307.854858 -178.549808)
		(width 0.14224)
		(layer "In15.Cu")
		(net "GMI_CPU0_G1_CPU1_G3_TX_DP<4>")
	)
	(segment
		(start 355.303328 -235.252006)
		(end 355.30409 -235.251498)
		(width 0.1143)
		(layer "In15.Cu")
		(net "GMI_CPU0_G1_CPU1_G3_TX_DP<4>")
	)
	(segment
		(start 355.303328 -243.352066)
		(end 355.30409 -243.351558)
		(width 0.1143)
		(layer "In15.Cu")
		(net "GMI_CPU0_G1_CPU1_G3_TX_DP<4>")
	)
	(segment
		(start 355.30409 -237.51667)
		(end 355.303328 -237.516162)
		(width 0.1143)
		(layer "In15.Cu")
		(net "GMI_CPU0_G1_CPU1_G3_TX_DP<4>")
	)
	(segment
		(start 116.223542 -232.6386)
		(end 116.192554 -232.65638)
		(width 0.1143)
		(layer "In15.Cu")
		(net "GMI_CPU0_G1_CPU1_G3_TX_DP<4>")
	)
	(segment
		(start 116.223542 -238.510064)
		(end 116.237258 -238.51997)
		(width 0.1143)
		(layer "In15.Cu")
		(net "GMI_CPU0_G1_CPU1_G3_TX_DP<4>")
	)
	(segment
		(start 116.191792 -237.516924)
		(end 116.190776 -237.517432)
		(width 0.1143)
		(layer "In15.Cu")
		(net "GMI_CPU0_G1_CPU1_G3_TX_DP<4>")
	)
	(segment
		(start 116.191792 -229.416864)
		(end 116.152676 -229.439724)
		(width 0.1143)
		(layer "In15.Cu")
		(net "GMI_CPU0_G1_CPU1_G3_TX_DP<4>")
	)
	(segment
		(start 116.191792 -245.616984)
		(end 116.190776 -245.617492)
		(width 0.1143)
		(layer "In15.Cu")
		(net "GMI_CPU0_G1_CPU1_G3_TX_DP<4>")
	)
	(segment
		(start 116.186458 -225.528886)
		(end 116.187474 -225.529394)
		(width 0.1143)
		(layer "In15.Cu")
		(net "GMI_CPU0_G1_CPU1_G3_TX_DP<4>")
	)
	(segment
		(start 355.30663 -241.730022)
		(end 355.311202 -241.727482)
		(width 0.1143)
		(layer "In15.Cu")
		(net "GMI_CPU0_G1_CPU1_G3_TX_DP<4>")
	)
	(segment
		(start 116.190776 -246.591328)
		(end 116.191792 -246.591836)
		(width 0.1143)
		(layer "In15.Cu")
		(net "GMI_CPU0_G1_CPU1_G3_TX_DP<4>")
	)
	(segment
		(start 115.81003 -220.991938)
		(end 115.81003 -221.020386)
		(width 0.1143)
		(layer "In15.Cu")
		(net "GMI_CPU0_G1_CPU1_G3_TX_DP<4>")
	)
	(segment
		(start 354.403152 -222.959676)
		(end 354.364036 -222.936816)
		(width 0.1143)
		(layer "In15.Cu")
		(net "GMI_CPU0_G1_CPU1_G3_TX_DP<4>")
	)
	(segment
		(start 116.189252 -224.558606)
		(end 116.152676 -224.579942)
		(width 0.1143)
		(layer "In15.Cu")
		(net "GMI_CPU0_G1_CPU1_G3_TX_DP<4>")
	)
	(segment
		(start 116.159534 -228.753162)
		(end 116.160296 -228.75367)
		(width 0.1143)
		(layer "In15.Cu")
		(net "GMI_CPU0_G1_CPU1_G3_TX_DP<4>")
	)
	(segment
		(start 355.302058 -242.375436)
		(end 355.27234 -242.358418)
		(width 0.1143)
		(layer "In15.Cu")
		(net "GMI_CPU0_G1_CPU1_G3_TX_DP<4>")
	)
	(segment
		(start 116.184934 -241.727736)
		(end 116.186458 -241.728752)
		(width 0.1143)
		(layer "In15.Cu")
		(net "GMI_CPU0_G1_CPU1_G3_TX_DP<4>")
	)
	(segment
		(start 355.302058 -237.5154)
		(end 355.27234 -237.498382)
		(width 0.1143)
		(layer "In15.Cu")
		(net "GMI_CPU0_G1_CPU1_G3_TX_DP<4>")
	)
	(segment
		(start 116.1923 -240.756948)
		(end 116.191792 -240.757202)
		(width 0.1143)
		(layer "In15.Cu")
		(net "GMI_CPU0_G1_CPU1_G3_TX_DP<4>")
	)
	(segment
		(start 116.223542 -239.118648)
		(end 116.192554 -239.136428)
		(width 0.1143)
		(layer "In15.Cu")
		(net "GMI_CPU0_G1_CPU1_G3_TX_DP<4>")
	)
	(segment
		(start 355.27234 -228.789992)
		(end 355.30409 -228.771704)
		(width 0.1143)
		(layer "In15.Cu")
		(net "GMI_CPU0_G1_CPU1_G3_TX_DP<4>")
	)
	(segment
		(start 116.189252 -234.278424)
		(end 116.152676 -234.29976)
		(width 0.1143)
		(layer "In15.Cu")
		(net "GMI_CPU0_G1_CPU1_G3_TX_DP<4>")
	)
	(segment
		(start 116.84254 -247.654572)
		(end 116.77269 -247.724422)
		(width 0.1143)
		(layer "In15.Cu")
		(net "GMI_CPU0_G1_CPU1_G3_TX_DP<4>")
	)
	(segment
		(start 355.296978 -243.992654)
		(end 355.27234 -243.97843)
		(width 0.1143)
		(layer "In15.Cu")
		(net "GMI_CPU0_G1_CPU1_G3_TX_DP<4>")
	)
	(segment
		(start 116.187474 -243.349272)
		(end 116.188998 -243.350288)
		(width 0.1143)
		(layer "In15.Cu")
		(net "GMI_CPU0_G1_CPU1_G3_TX_DP<4>")
	)
	(segment
		(start 116.153438 -235.229654)
		(end 116.183918 -235.24718)
		(width 0.1143)
		(layer "In15.Cu")
		(net "GMI_CPU0_G1_CPU1_G3_TX_DP<4>")
	)
	(segment
		(start 355.30663 -232.658158)
		(end 355.305106 -232.657142)
		(width 0.1143)
		(layer "In15.Cu")
		(net "GMI_CPU0_G1_CPU1_G3_TX_DP<4>")
	)
	(segment
		(start 355.305106 -240.757202)
		(end 355.30409 -240.756694)
		(width 0.1143)
		(layer "In15.Cu")
		(net "GMI_CPU0_G1_CPU1_G3_TX_DP<4>")
	)
	(segment
		(start 355.296978 -235.892594)
		(end 355.27234 -235.87837)
		(width 0.1143)
		(layer "In15.Cu")
		(net "GMI_CPU0_G1_CPU1_G3_TX_DP<4>")
	)
	(segment
		(start 116.187474 -232.009188)
		(end 116.188998 -232.010204)
		(width 0.1143)
		(layer "In15.Cu")
		(net "GMI_CPU0_G1_CPU1_G3_TX_DP<4>")
	)
	(segment
		(start 116.223542 -223.93021)
		(end 116.243354 -223.944434)
		(width 0.1143)
		(layer "In15.Cu")
		(net "GMI_CPU0_G1_CPU1_G3_TX_DP<4>")
	)
	(segment
		(start 116.152676 -241.70894)
		(end 116.159534 -241.713004)
		(width 0.1143)
		(layer "In15.Cu")
		(net "GMI_CPU0_G1_CPU1_G3_TX_DP<4>")
	)
	(segment
		(start 116.190776 -232.01122)
		(end 116.191792 -232.011728)
		(width 0.1143)
		(layer "In15.Cu")
		(net "GMI_CPU0_G1_CPU1_G3_TX_DP<4>")
	)
	(segment
		(start 116.184934 -227.147882)
		(end 116.186458 -227.148898)
		(width 0.1143)
		(layer "In15.Cu")
		(net "GMI_CPU0_G1_CPU1_G3_TX_DP<4>")
	)
	(segment
		(start 116.190776 -243.99748)
		(end 116.189252 -243.998496)
		(width 0.1143)
		(layer "In15.Cu")
		(net "GMI_CPU0_G1_CPU1_G3_TX_DP<4>")
	)
	(segment
		(start 355.30663 -233.629962)
		(end 355.311202 -233.627422)
		(width 0.1143)
		(layer "In15.Cu")
		(net "GMI_CPU0_G1_CPU1_G3_TX_DP<4>")
	)
	(segment
		(start 355.303328 -245.616222)
		(end 355.302058 -245.61546)
		(width 0.1143)
		(layer "In15.Cu")
		(net "GMI_CPU0_G1_CPU1_G3_TX_DP<4>")
	)
	(segment
		(start 116.159534 -223.893126)
		(end 116.160296 -223.893634)
		(width 0.1143)
		(layer "In15.Cu")
		(net "GMI_CPU0_G1_CPU1_G3_TX_DP<4>")
	)
	(segment
		(start 116.223542 -222.310198)
		(end 116.23929 -222.321628)
		(width 0.1143)
		(layer "In15.Cu")
		(net "GMI_CPU0_G1_CPU1_G3_TX_DP<4>")
	)
	(segment
		(start 116.186458 -232.00868)
		(end 116.187474 -232.009188)
		(width 0.1143)
		(layer "In15.Cu")
		(net "GMI_CPU0_G1_CPU1_G3_TX_DP<4>")
	)
	(segment
		(start 355.305106 -238.491014)
		(end 355.30663 -238.489998)
		(width 0.1143)
		(layer "In15.Cu")
		(net "GMI_CPU0_G1_CPU1_G3_TX_DP<4>")
	)
	(segment
		(start 116.159534 -246.57304)
		(end 116.160296 -246.573548)
		(width 0.1143)
		(layer "In15.Cu")
		(net "GMI_CPU0_G1_CPU1_G3_TX_DP<4>")
	)
	(segment
		(start 116.191792 -240.756948)
		(end 116.190776 -240.757456)
		(width 0.1143)
		(layer "In15.Cu")
		(net "GMI_CPU0_G1_CPU1_G3_TX_DP<4>")
	)
	(segment
		(start 355.300534 -232.654602)
		(end 355.299772 -232.654094)
		(width 0.1143)
		(layer "In15.Cu")
		(net "GMI_CPU0_G1_CPU1_G3_TX_DP<4>")
	)
	(segment
		(start 116.186458 -223.908874)
		(end 116.187474 -223.909382)
		(width 0.1143)
		(layer "In15.Cu")
		(net "GMI_CPU0_G1_CPU1_G3_TX_DP<4>")
	)
	(segment
		(start 116.152676 -240.091468)
		(end 116.166392 -240.09858)
		(width 0.1143)
		(layer "In15.Cu")
		(net "GMI_CPU0_G1_CPU1_G3_TX_DP<4>")
	)
	(segment
		(start 355.298756 -235.89361)
		(end 355.297994 -235.893102)
		(width 0.1143)
		(layer "In15.Cu")
		(net "GMI_CPU0_G1_CPU1_G3_TX_DP<4>")
	)
	(segment
		(start 116.152676 -228.749098)
		(end 116.159534 -228.753162)
		(width 0.1143)
		(layer "In15.Cu")
		(net "GMI_CPU0_G1_CPU1_G3_TX_DP<4>")
	)
	(segment
		(start 116.190776 -244.971316)
		(end 116.191792 -244.971824)
		(width 0.1143)
		(layer "In15.Cu")
		(net "GMI_CPU0_G1_CPU1_G3_TX_DP<4>")
	)
	(segment
		(start 116.192554 -232.012236)
		(end 116.223542 -232.030016)
		(width 0.1143)
		(layer "In15.Cu")
		(net "GMI_CPU0_G1_CPU1_G3_TX_DP<4>")
	)
	(segment
		(start 355.30409 -236.87151)
		(end 355.305106 -236.871002)
		(width 0.1143)
		(layer "In15.Cu")
		(net "GMI_CPU0_G1_CPU1_G3_TX_DP<4>")
	)
	(segment
		(start 355.30409 -235.251498)
		(end 355.305106 -235.25099)
		(width 0.1143)
		(layer "In15.Cu")
		(net "GMI_CPU0_G1_CPU1_G3_TX_DP<4>")
	)
	(segment
		(start 116.190776 -228.77145)
		(end 116.191792 -228.771958)
		(width 0.1143)
		(layer "In15.Cu")
		(net "GMI_CPU0_G1_CPU1_G3_TX_DP<4>")
	)
	(segment
		(start 355.30409 -243.351558)
		(end 355.305106 -243.35105)
		(width 0.1143)
		(layer "In15.Cu")
		(net "GMI_CPU0_G1_CPU1_G3_TX_DP<4>")
	)
	(segment
		(start 116.186458 -227.148898)
		(end 116.187474 -227.149406)
		(width 0.1143)
		(layer "In15.Cu")
		(net "GMI_CPU0_G1_CPU1_G3_TX_DP<4>")
	)
	(segment
		(start 116.189252 -240.758472)
		(end 116.152676 -240.779808)
		(width 0.1143)
		(layer "In15.Cu")
		(net "GMI_CPU0_G1_CPU1_G3_TX_DP<4>")
	)
	(segment
		(start 355.296978 -234.272582)
		(end 355.27234 -234.258358)
		(width 0.1143)
		(layer "In15.Cu")
		(net "GMI_CPU0_G1_CPU1_G3_TX_DP<4>")
	)
	(segment
		(start 116.186204 -242.380262)
		(end 116.152676 -242.39982)
		(width 0.1143)
		(layer "In15.Cu")
		(net "GMI_CPU0_G1_CPU1_G3_TX_DP<4>")
	)
	(segment
		(start 116.189252 -222.938594)
		(end 116.152676 -222.95993)
		(width 0.1143)
		(layer "In15.Cu")
		(net "GMI_CPU0_G1_CPU1_G3_TX_DP<4>")
	)
	(segment
		(start 355.303328 -244.972078)
		(end 355.30409 -244.97157)
		(width 0.1143)
		(layer "In15.Cu")
		(net "GMI_CPU0_G1_CPU1_G3_TX_DP<4>")
	)
	(segment
		(start 355.299772 -234.274106)
		(end 355.298756 -234.273598)
		(width 0.1143)
		(layer "In15.Cu")
		(net "GMI_CPU0_G1_CPU1_G3_TX_DP<4>")
	)
	(segment
		(start 116.186458 -244.968776)
		(end 116.187474 -244.969284)
		(width 0.1143)
		(layer "In15.Cu")
		(net "GMI_CPU0_G1_CPU1_G3_TX_DP<4>")
	)
	(segment
		(start 355.297994 -235.893102)
		(end 355.296978 -235.892594)
		(width 0.1143)
		(layer "In15.Cu")
		(net "GMI_CPU0_G1_CPU1_G3_TX_DP<4>")
	)
	(segment
		(start 116.190776 -243.351304)
		(end 116.191792 -243.351812)
		(width 0.1143)
		(layer "In15.Cu")
		(net "GMI_CPU0_G1_CPU1_G3_TX_DP<4>")
	)
	(segment
		(start 116.188998 -240.11001)
		(end 116.1923 -240.111788)
		(width 0.1143)
		(layer "In15.Cu")
		(net "GMI_CPU0_G1_CPU1_G3_TX_DP<4>")
	)
	(segment
		(start 355.343206 -231.059482)
		(end 355.30409 -231.036622)
		(width 0.1143)
		(layer "In15.Cu")
		(net "GMI_CPU0_G1_CPU1_G3_TX_DP<4>")
	)
	(segment
		(start 302.908208 -178.549808)
		(end 165.606984 -177.748438)
		(width 0.14224)
		(layer "In15.Cu")
		(net "GMI_CPU0_G1_CPU1_G3_TX_DP<4>")
	)
	(segment
		(start 116.192554 -222.936562)
		(end 116.191792 -222.93707)
		(width 0.1143)
		(layer "In15.Cu")
		(net "GMI_CPU0_G1_CPU1_G3_TX_DP<4>")
	)
	(segment
		(start 116.160296 -223.893634)
		(end 116.184934 -223.907858)
		(width 0.1143)
		(layer "In15.Cu")
		(net "GMI_CPU0_G1_CPU1_G3_TX_DP<4>")
	)
	(segment
		(start 355.30409 -244.97157)
		(end 355.305106 -244.971062)
		(width 0.1143)
		(layer "In15.Cu")
		(net "GMI_CPU0_G1_CPU1_G3_TX_DP<4>")
	)
	(segment
		(start 116.191792 -243.996972)
		(end 116.190776 -243.99748)
		(width 0.1143)
		(layer "In15.Cu")
		(net "GMI_CPU0_G1_CPU1_G3_TX_DP<4>")
	)
	(segment
		(start 116.190776 -238.491268)
		(end 116.191792 -238.491776)
		(width 0.1143)
		(layer "In15.Cu")
		(net "GMI_CPU0_G1_CPU1_G3_TX_DP<4>")
	)
	(segment
		(start 116.159534 -225.513138)
		(end 116.160296 -225.513646)
		(width 0.1143)
		(layer "In15.Cu")
		(net "GMI_CPU0_G1_CPU1_G3_TX_DP<4>")
	)
	(segment
		(start 355.30663 -243.350034)
		(end 355.311202 -243.347494)
		(width 0.1143)
		(layer "In15.Cu")
		(net "GMI_CPU0_G1_CPU1_G3_TX_DP<4>")
	)
	(segment
		(start 119.551704 -211.847176)
		(end 115.81003 -218.148916)
		(width 0.14224)
		(layer "In15.Cu")
		(net "GMI_CPU0_G1_CPU1_G3_TX_DP<4>")
	)
	(segment
		(start 116.191792 -232.011728)
		(end 116.192554 -232.012236)
		(width 0.1143)
		(layer "In15.Cu")
		(net "GMI_CPU0_G1_CPU1_G3_TX_DP<4>")
	)
	(segment
		(start 116.234718 -243.970556)
		(end 116.223542 -243.978684)
		(width 0.1143)
		(layer "In15.Cu")
		(net "GMI_CPU0_G1_CPU1_G3_TX_DP<4>")
	)
	(segment
		(start 157.683962 -180.581554)
		(end 152.414986 -184.901332)
		(width 0.14224)
		(layer "In15.Cu")
		(net "GMI_CPU0_G1_CPU1_G3_TX_DP<4>")
	)
	(segment
		(start 355.303328 -239.136174)
		(end 355.302058 -239.135412)
		(width 0.1143)
		(layer "In15.Cu")
		(net "GMI_CPU0_G1_CPU1_G3_TX_DP<4>")
	)
	(segment
		(start 355.302058 -240.112804)
		(end 355.303328 -240.112042)
		(width 0.1143)
		(layer "In15.Cu")
		(net "GMI_CPU0_G1_CPU1_G3_TX_DP<4>")
	)
	(segment
		(start 116.188998 -228.770434)
		(end 116.190776 -228.77145)
		(width 0.1143)
		(layer "In15.Cu")
		(net "GMI_CPU0_G1_CPU1_G3_TX_DP<4>")
	)
	(segment
		(start 116.166392 -240.09858)
		(end 116.188998 -240.11001)
		(width 0.1143)
		(layer "In15.Cu")
		(net "GMI_CPU0_G1_CPU1_G3_TX_DP<4>")
	)
	(segment
		(start 355.303328 -232.656126)
		(end 355.302058 -232.655364)
		(width 0.1143)
		(layer "In15.Cu")
		(net "GMI_CPU0_G1_CPU1_G3_TX_DP<4>")
	)
	(segment
		(start 116.223542 -241.750088)
		(end 116.233702 -241.757454)
		(width 0.1143)
		(layer "In15.Cu")
		(net "GMI_CPU0_G1_CPU1_G3_TX_DP<4>")
	)
	(segment
		(start 116.183918 -235.24718)
		(end 116.192046 -235.251752)
		(width 0.1143)
		(layer "In15.Cu")
		(net "GMI_CPU0_G1_CPU1_G3_TX_DP<4>")
	)
	(segment
		(start 116.190776 -227.797614)
		(end 116.189252 -227.79863)
		(width 0.1143)
		(layer "In15.Cu")
		(net "GMI_CPU0_G1_CPU1_G3_TX_DP<4>")
	)
	(segment
		(start 116.160296 -246.573548)
		(end 116.184934 -246.587772)
		(width 0.1143)
		(layer "In15.Cu")
		(net "GMI_CPU0_G1_CPU1_G3_TX_DP<4>")
	)
	(segment
		(start 316.689486 -183.07177)
		(end 310.17337 -179.383182)
		(width 0.14224)
		(layer "In15.Cu")
		(net "GMI_CPU0_G1_CPU1_G3_TX_DP<4>")
	)
	(segment
		(start 354.832158 -225.365564)
		(end 354.80244 -225.348546)
		(width 0.1143)
		(layer "In15.Cu")
		(net "GMI_CPU0_G1_CPU1_G3_TX_DP<4>")
	)
	(segment
		(start 116.191792 -225.531934)
		(end 116.192554 -225.532442)
		(width 0.1143)
		(layer "In15.Cu")
		(net "GMI_CPU0_G1_CPU1_G3_TX_DP<4>")
	)
	(segment
		(start 116.159534 -238.47298)
		(end 116.160296 -238.473488)
		(width 0.1143)
		(layer "In15.Cu")
		(net "GMI_CPU0_G1_CPU1_G3_TX_DP<4>")
	)
	(segment
		(start 115.81003 -218.148916)
		(end 115.81003 -220.991938)
		(width 0.14224)
		(layer "In15.Cu")
		(net "GMI_CPU0_G1_CPU1_G3_TX_DP<4>")
	)
	(segment
		(start 355.297994 -240.753138)
		(end 355.296978 -240.75263)
		(width 0.1143)
		(layer "In15.Cu")
		(net "GMI_CPU0_G1_CPU1_G3_TX_DP<4>")
	)
	(segment
		(start 355.298756 -232.653586)
		(end 355.297994 -232.653078)
		(width 0.1143)
		(layer "In15.Cu")
		(net "GMI_CPU0_G1_CPU1_G3_TX_DP<4>")
	)
	(segment
		(start 116.187474 -228.769418)
		(end 116.188998 -228.770434)
		(width 0.1143)
		(layer "In15.Cu")
		(net "GMI_CPU0_G1_CPU1_G3_TX_DP<4>")
	)
	(segment
		(start 116.186458 -233.628692)
		(end 116.187474 -233.6292)
		(width 0.1143)
		(layer "In15.Cu")
		(net "GMI_CPU0_G1_CPU1_G3_TX_DP<4>")
	)
	(segment
		(start 116.190776 -225.531426)
		(end 116.191792 -225.531934)
		(width 0.1143)
		(layer "In15.Cu")
		(net "GMI_CPU0_G1_CPU1_G3_TX_DP<4>")
	)
	(segment
		(start 354.403152 -224.579688)
		(end 354.364036 -224.556828)
		(width 0.1143)
		(layer "In15.Cu")
		(net "GMI_CPU0_G1_CPU1_G3_TX_DP<4>")
	)
	(segment
		(start 355.300534 -243.35359)
		(end 355.302058 -243.352828)
		(width 0.1143)
		(layer "In15.Cu")
		(net "GMI_CPU0_G1_CPU1_G3_TX_DP<4>")
	)
	(segment
		(start 116.152676 -227.129086)
		(end 116.159534 -227.13315)
		(width 0.1143)
		(layer "In15.Cu")
		(net "GMI_CPU0_G1_CPU1_G3_TX_DP<4>")
	)
	(segment
		(start 355.305106 -235.897166)
		(end 355.30409 -235.896658)
		(width 0.1143)
		(layer "In15.Cu")
		(net "GMI_CPU0_G1_CPU1_G3_TX_DP<4>")
	)
	(segment
		(start 350.619568 -210.893152)
		(end 316.689486 -183.07177)
		(width 0.14224)
		(layer "In15.Cu")
		(net "GMI_CPU0_G1_CPU1_G3_TX_DP<4>")
	)
	(segment
		(start 116.223542 -227.170234)
		(end 116.231924 -227.17633)
		(width 0.1143)
		(layer "In15.Cu")
		(net "GMI_CPU0_G1_CPU1_G3_TX_DP<4>")
	)
	(segment
		(start 355.30409 -238.491522)
		(end 355.305106 -238.491014)
		(width 0.1143)
		(layer "In15.Cu")
		(net "GMI_CPU0_G1_CPU1_G3_TX_DP<4>")
	)
	(segment
		(start 116.159534 -230.373174)
		(end 116.160296 -230.373682)
		(width 0.1143)
		(layer "In15.Cu")
		(net "GMI_CPU0_G1_CPU1_G3_TX_DP<4>")
	)
	(segment
		(start 116.190776 -223.911414)
		(end 116.191792 -223.911922)
		(width 0.1143)
		(layer "In15.Cu")
		(net "GMI_CPU0_G1_CPU1_G3_TX_DP<4>")
	)
	(segment
		(start 355.297994 -234.27309)
		(end 355.296978 -234.272582)
		(width 0.1143)
		(layer "In15.Cu")
		(net "GMI_CPU0_G1_CPU1_G3_TX_DP<4>")
	)
	(segment
		(start 116.191792 -239.136936)
		(end 116.190776 -239.137444)
		(width 0.1143)
		(layer "In15.Cu")
		(net "GMI_CPU0_G1_CPU1_G3_TX_DP<4>")
	)
	(segment
		(start 355.340412 -229.437692)
		(end 355.30409 -229.41661)
		(width 0.1143)
		(layer "In15.Cu")
		(net "GMI_CPU0_G1_CPU1_G3_TX_DP<4>")
	)
	(segment
		(start 355.30663 -246.590058)
		(end 355.311202 -246.587518)
		(width 0.1143)
		(layer "In15.Cu")
		(net "GMI_CPU0_G1_CPU1_G3_TX_DP<4>")
	)
	(segment
		(start 354.364036 -222.936816)
		(end 354.333556 -222.919036)
		(width 0.1143)
		(layer "In15.Cu")
		(net "GMI_CPU0_G1_CPU1_G3_TX_DP<4>")
	)
	(segment
		(start 116.192554 -238.492284)
		(end 116.223542 -238.510064)
		(width 0.1143)
		(layer "In15.Cu")
		(net "GMI_CPU0_G1_CPU1_G3_TX_DP<4>")
	)
	(segment
		(start 116.233194 -245.591838)
		(end 116.223542 -245.598696)
		(width 0.1143)
		(layer "In15.Cu")
		(net "GMI_CPU0_G1_CPU1_G3_TX_DP<4>")
	)
	(segment
		(start 115.81003 -221.020386)
		(end 115.85575 -221.066106)
		(width 0.1143)
		(layer "In15.Cu")
		(net "GMI_CPU0_G1_CPU1_G3_TX_DP<4>")
	)
	(segment
		(start 355.298756 -239.133634)
		(end 355.297994 -239.133126)
		(width 0.1143)
		(layer "In15.Cu")
		(net "GMI_CPU0_G1_CPU1_G3_TX_DP<4>")
	)
	(segment
		(start 116.187474 -225.529394)
		(end 116.188998 -225.53041)
		(width 0.1143)
		(layer "In15.Cu")
		(net "GMI_CPU0_G1_CPU1_G3_TX_DP<4>")
	)
	(segment
		(start 116.190776 -237.517432)
		(end 116.189252 -237.518448)
		(width 0.1143)
		(layer "In15.Cu")
		(net "GMI_CPU0_G1_CPU1_G3_TX_DP<4>")
	)
	(segment
		(start 116.191792 -231.036876)
		(end 116.152676 -231.059736)
		(width 0.1143)
		(layer "In15.Cu")
		(net "GMI_CPU0_G1_CPU1_G3_TX_DP<4>")
	)
	(segment
		(start 355.296978 -239.132618)
		(end 355.27234 -239.118394)
		(width 0.1143)
		(layer "In15.Cu")
		(net "GMI_CPU0_G1_CPU1_G3_TX_DP<4>")
	)
	(segment
		(start 116.152676 -233.60888)
		(end 116.159534 -233.612944)
		(width 0.1143)
		(layer "In15.Cu")
		(net "GMI_CPU0_G1_CPU1_G3_TX_DP<4>")
	)
	(segment
		(start 354.333556 -223.929448)
		(end 354.364036 -223.911668)
		(width 0.1143)
		(layer "In15.Cu")
		(net "GMI_CPU0_G1_CPU1_G3_TX_DP<4>")
	)
	(segment
		(start 355.27234 -233.649774)
		(end 355.300534 -233.633518)
		(width 0.1143)
		(layer "In15.Cu")
		(net "GMI_CPU0_G1_CPU1_G3_TX_DP<4>")
	)
	(segment
		(start 116.190776 -230.391462)
		(end 116.19357 -230.392986)
		(width 0.1143)
		(layer "In15.Cu")
		(net "GMI_CPU0_G1_CPU1_G3_TX_DP<4>")
	)
	(segment
		(start 355.296978 -232.65257)
		(end 355.27234 -232.638346)
		(width 0.1143)
		(layer "In15.Cu")
		(net "GMI_CPU0_G1_CPU1_G3_TX_DP<4>")
	)
	(segment
		(start 116.223542 -224.538794)
		(end 116.192554 -224.556574)
		(width 0.1143)
		(layer "In15.Cu")
		(net "GMI_CPU0_G1_CPU1_G3_TX_DP<4>")
	)
	(segment
		(start 116.192554 -227.152454)
		(end 116.223542 -227.170234)
		(width 0.1143)
		(layer "In15.Cu")
		(net "GMI_CPU0_G1_CPU1_G3_TX_DP<4>")
	)
	(segment
		(start 116.190776 -222.937578)
		(end 116.189252 -222.938594)
		(width 0.1143)
		(layer "In15.Cu")
		(net "GMI_CPU0_G1_CPU1_G3_TX_DP<4>")
	)
	(segment
		(start 354.866448 -225.38563)
		(end 354.865686 -225.385122)
		(width 0.1143)
		(layer "In15.Cu")
		(net "GMI_CPU0_G1_CPU1_G3_TX_DP<4>")
	)
	(segment
		(start 355.27234 -238.50981)
		(end 355.30409 -238.491522)
		(width 0.1143)
		(layer "In15.Cu")
		(net "GMI_CPU0_G1_CPU1_G3_TX_DP<4>")
	)
	(segment
		(start 116.192554 -245.616476)
		(end 116.191792 -245.616984)
		(width 0.1143)
		(layer "In15.Cu")
		(net "GMI_CPU0_G1_CPU1_G3_TX_DP<4>")
	)
	(segment
		(start 355.299772 -232.654094)
		(end 355.298756 -232.653586)
		(width 0.1143)
		(layer "In15.Cu")
		(net "GMI_CPU0_G1_CPU1_G3_TX_DP<4>")
	)
	(segment
		(start 355.303328 -242.376198)
		(end 355.302058 -242.375436)
		(width 0.1143)
		(layer "In15.Cu")
		(net "GMI_CPU0_G1_CPU1_G3_TX_DP<4>")
	)
	(segment
		(start 355.30409 -241.731546)
		(end 355.305106 -241.731038)
		(width 0.1143)
		(layer "In15.Cu")
		(net "GMI_CPU0_G1_CPU1_G3_TX_DP<4>")
	)
	(segment
		(start 355.30663 -235.898182)
		(end 355.305106 -235.897166)
		(width 0.1143)
		(layer "In15.Cu")
		(net "GMI_CPU0_G1_CPU1_G3_TX_DP<4>")
	)
	(segment
		(start 116.187474 -223.909382)
		(end 116.188998 -223.910398)
		(width 0.1143)
		(layer "In15.Cu")
		(net "GMI_CPU0_G1_CPU1_G3_TX_DP<4>")
	)
	(segment
		(start 355.343206 -239.159542)
		(end 355.30663 -239.138206)
		(width 0.1143)
		(layer "In15.Cu")
		(net "GMI_CPU0_G1_CPU1_G3_TX_DP<4>")
	)
	(segment
		(start 116.188998 -238.490252)
		(end 116.190776 -238.491268)
		(width 0.1143)
		(layer "In15.Cu")
		(net "GMI_CPU0_G1_CPU1_G3_TX_DP<4>")
	)
	(segment
		(start 355.30409 -240.111534)
		(end 355.305106 -240.111026)
		(width 0.1143)
		(layer "In15.Cu")
		(net "GMI_CPU0_G1_CPU1_G3_TX_DP<4>")
	)
	(segment
		(start 355.343206 -244.019578)
		(end 355.30663 -243.998242)
		(width 0.1143)
		(layer "In15.Cu")
		(net "GMI_CPU0_G1_CPU1_G3_TX_DP<4>")
	)
	(segment
		(start 354.865686 -225.385122)
		(end 354.83419 -225.366834)
		(width 0.1143)
		(layer "In15.Cu")
		(net "GMI_CPU0_G1_CPU1_G3_TX_DP<4>")
	)
	(segment
		(start 355.27234 -243.369846)
		(end 355.300534 -243.35359)
		(width 0.1143)
		(layer "In15.Cu")
		(net "GMI_CPU0_G1_CPU1_G3_TX_DP<4>")
	)
	(segment
		(start 355.305106 -233.630978)
		(end 355.30663 -233.629962)
		(width 0.1143)
		(layer "In15.Cu")
		(net "GMI_CPU0_G1_CPU1_G3_TX_DP<4>")
	)
	(segment
		(start 116.188998 -227.150422)
		(end 116.190776 -227.151438)
		(width 0.1143)
		(layer "In15.Cu")
		(net "GMI_CPU0_G1_CPU1_G3_TX_DP<4>")
	)
	(segment
		(start 355.30409 -235.896658)
		(end 355.303328 -235.89615)
		(width 0.1143)
		(layer "In15.Cu")
		(net "GMI_CPU0_G1_CPU1_G3_TX_DP<4>")
	)
	(segment
		(start 354.63226 -221.128844)
		(end 354.67798 -221.083124)
		(width 0.1143)
		(layer "In15.Cu")
		(net "GMI_CPU0_G1_CPU1_G3_TX_DP<4>")
	)
	(segment
		(start 355.303328 -234.276138)
		(end 355.302058 -234.275376)
		(width 0.1143)
		(layer "In15.Cu")
		(net "GMI_CPU0_G1_CPU1_G3_TX_DP<4>")
	)
	(segment
		(start 355.300534 -244.973602)
		(end 355.302058 -244.97284)
		(width 0.1143)
		(layer "In15.Cu")
		(net "GMI_CPU0_G1_CPU1_G3_TX_DP<4>")
	)
	(segment
		(start 116.237258 -239.108742)
		(end 116.223542 -239.118648)
		(width 0.1143)
		(layer "In15.Cu")
		(net "GMI_CPU0_G1_CPU1_G3_TX_DP<4>")
	)
	(segment
		(start 116.191792 -228.771958)
		(end 116.192554 -228.772466)
		(width 0.1143)
		(layer "In15.Cu")
		(net "GMI_CPU0_G1_CPU1_G3_TX_DP<4>")
	)
	(segment
		(start 116.187474 -244.969284)
		(end 116.188998 -244.9703)
		(width 0.1143)
		(layer "In15.Cu")
		(net "GMI_CPU0_G1_CPU1_G3_TX_DP<4>")
	)
	(segment
		(start 355.27234 -230.410004)
		(end 355.30409 -230.391716)
		(width 0.1143)
		(layer "In15.Cu")
		(net "GMI_CPU0_G1_CPU1_G3_TX_DP<4>")
	)
	(segment
		(start 355.30663 -236.869986)
		(end 355.311202 -236.867446)
		(width 0.1143)
		(layer "In15.Cu")
		(net "GMI_CPU0_G1_CPU1_G3_TX_DP<4>")
	)
	(segment
		(start 355.27234 -241.749834)
		(end 355.300534 -241.733578)
		(width 0.1143)
		(layer "In15.Cu")
		(net "GMI_CPU0_G1_CPU1_G3_TX_DP<4>")
	)
	(segment
		(start 355.297994 -232.653078)
		(end 355.296978 -232.65257)
		(width 0.1143)
		(layer "In15.Cu")
		(net "GMI_CPU0_G1_CPU1_G3_TX_DP<4>")
	)
	(segment
		(start 116.191792 -244.971824)
		(end 116.192554 -244.972332)
		(width 0.1143)
		(layer "In15.Cu")
		(net "GMI_CPU0_G1_CPU1_G3_TX_DP<4>")
	)
	(segment
		(start 116.191792 -222.93707)
		(end 116.190776 -222.937578)
		(width 0.1143)
		(layer "In15.Cu")
		(net "GMI_CPU0_G1_CPU1_G3_TX_DP<4>")
	)
	(segment
		(start 116.22532 -229.397306)
		(end 116.191792 -229.416864)
		(width 0.1143)
		(layer "In15.Cu")
		(net "GMI_CPU0_G1_CPU1_G3_TX_DP<4>")
	)
	(segment
		(start 116.22532 -231.017318)
		(end 116.191792 -231.036876)
		(width 0.1143)
		(layer "In15.Cu")
		(net "GMI_CPU0_G1_CPU1_G3_TX_DP<4>")
	)
	(segment
		(start 116.190776 -232.657396)
		(end 116.189252 -232.658412)
		(width 0.1143)
		(layer "In15.Cu")
		(net "GMI_CPU0_G1_CPU1_G3_TX_DP<4>")
	)
	(segment
		(start 355.30663 -239.138206)
		(end 355.305106 -239.13719)
		(width 0.1143)
		(layer "In15.Cu")
		(net "GMI_CPU0_G1_CPU1_G3_TX_DP<4>")
	)
	(segment
		(start 355.586538 -229.904036)
		(end 355.586284 -229.904036)
		(width 0.1143)
		(layer "In15.Cu")
		(net "GMI_CPU0_G1_CPU1_G3_TX_DP<4>")
	)
	(segment
		(start 116.186458 -246.588788)
		(end 116.187474 -246.589296)
		(width 0.1143)
		(layer "In15.Cu")
		(net "GMI_CPU0_G1_CPU1_G3_TX_DP<4>")
	)
	(segment
		(start 116.191792 -240.757202)
		(end 116.191792 -240.756948)
		(width 0.1143)
		(layer "In15.Cu")
		(net "GMI_CPU0_G1_CPU1_G3_TX_DP<4>")
	)
	(segment
		(start 355.303328 -241.732054)
		(end 355.30409 -241.731546)
		(width 0.1143)
		(layer "In15.Cu")
		(net "GMI_CPU0_G1_CPU1_G3_TX_DP<4>")
	)
	(segment
		(start 355.30409 -245.61673)
		(end 355.303328 -245.616222)
		(width 0.1143)
		(layer "In15.Cu")
		(net "GMI_CPU0_G1_CPU1_G3_TX_DP<4>")
	)
	(segment
		(start 116.223542 -243.3701)
		(end 116.234718 -243.378228)
		(width 0.1143)
		(layer "In15.Cu")
		(net "GMI_CPU0_G1_CPU1_G3_TX_DP<4>")
	)
	(segment
		(start 355.343206 -226.1997)
		(end 355.30409 -226.17684)
		(width 0.1143)
		(layer "In15.Cu")
		(net "GMI_CPU0_G1_CPU1_G3_TX_DP<4>")
	)
	(segment
		(start 116.191792 -237.517178)
		(end 116.191792 -237.516924)
		(width 0.1143)
		(layer "In15.Cu")
		(net "GMI_CPU0_G1_CPU1_G3_TX_DP<4>")
	)
	(segment
		(start 354.873306 -225.389694)
		(end 354.866448 -225.38563)
		(width 0.1143)
		(layer "In15.Cu")
		(net "GMI_CPU0_G1_CPU1_G3_TX_DP<4>")
	)
	(segment
		(start 355.300534 -232.013506)
		(end 355.302058 -232.012744)
		(width 0.1143)
		(layer "In15.Cu")
		(net "GMI_CPU0_G1_CPU1_G3_TX_DP<4>")
	)
	(segment
		(start 116.184934 -238.487712)
		(end 116.186458 -238.488728)
		(width 0.1143)
		(layer "In15.Cu")
		(net "GMI_CPU0_G1_CPU1_G3_TX_DP<4>")
	)
	(segment
		(start 116.191792 -226.177094)
		(end 116.190776 -226.177602)
		(width 0.1143)
		(layer "In15.Cu")
		(net "GMI_CPU0_G1_CPU1_G3_TX_DP<4>")
	)
	(segment
		(start 116.160296 -225.513646)
		(end 116.184934 -225.52787)
		(width 0.1143)
		(layer "In15.Cu")
		(net "GMI_CPU0_G1_CPU1_G3_TX_DP<4>")
	)
	(segment
		(start 115.909344 -221.331536)
		(end 115.909344 -221.804484)
		(width 0.1143)
		(layer "In15.Cu")
		(net "GMI_CPU0_G1_CPU1_G3_TX_DP<4>")
	)
	(segment
		(start 355.30409 -226.17684)
		(end 355.27361 -226.15906)
		(width 0.1143)
		(layer "In15.Cu")
		(net "GMI_CPU0_G1_CPU1_G3_TX_DP<4>")
	)
	(segment
		(start 355.298756 -243.99367)
		(end 355.297994 -243.993162)
		(width 0.1143)
		(layer "In15.Cu")
		(net "GMI_CPU0_G1_CPU1_G3_TX_DP<4>")
	)
	(segment
		(start 355.30663 -234.27817)
		(end 355.305106 -234.277154)
		(width 0.1143)
		(layer "In15.Cu")
		(net "GMI_CPU0_G1_CPU1_G3_TX_DP<4>")
	)
	(segment
		(start 116.190776 -233.631232)
		(end 116.191792 -233.63174)
		(width 0.1143)
		(layer "In15.Cu")
		(net "GMI_CPU0_G1_CPU1_G3_TX_DP<4>")
	)
	(segment
		(start 307.854858 -178.549808)
		(end 302.908208 -178.549808)
		(width 0.14224)
		(layer "In15.Cu")
		(net "GMI_CPU0_G1_CPU1_G3_TX_DP<4>")
	)
	(segment
		(start 116.187474 -227.149406)
		(end 116.188998 -227.150422)
		(width 0.1143)
		(layer "In15.Cu")
		(net "GMI_CPU0_G1_CPU1_G3_TX_DP<4>")
	)
	(segment
		(start 355.305106 -232.010966)
		(end 355.30663 -232.00995)
		(width 0.1143)
		(layer "In15.Cu")
		(net "GMI_CPU0_G1_CPU1_G3_TX_DP<4>")
	)
	(segment
		(start 355.311202 -244.967506)
		(end 355.343206 -244.94871)
		(width 0.1143)
		(layer "In15.Cu")
		(net "GMI_CPU0_G1_CPU1_G3_TX_DP<4>")
	)
	(segment
		(start 116.159534 -231.992932)
		(end 116.160296 -231.99344)
		(width 0.1143)
		(layer "In15.Cu")
		(net "GMI_CPU0_G1_CPU1_G3_TX_DP<4>")
	)
	(segment
		(start 116.190776 -224.55759)
		(end 116.189252 -224.558606)
		(width 0.1143)
		(layer "In15.Cu")
		(net "GMI_CPU0_G1_CPU1_G3_TX_DP<4>")
	)
	(segment
		(start 355.296978 -240.75263)
		(end 355.27234 -240.738406)
		(width 0.1143)
		(layer "In15.Cu")
		(net "GMI_CPU0_G1_CPU1_G3_TX_DP<4>")
	)
	(segment
		(start 355.303328 -235.89615)
		(end 355.302058 -235.895388)
		(width 0.1143)
		(layer "In15.Cu")
		(net "GMI_CPU0_G1_CPU1_G3_TX_DP<4>")
	)
	(segment
		(start 355.343206 -227.819712)
		(end 355.30409 -227.796852)
		(width 0.1143)
		(layer "In15.Cu")
		(net "GMI_CPU0_G1_CPU1_G3_TX_DP<4>")
	)
	(segment
		(start 116.223542 -227.778818)
		(end 116.192554 -227.796598)
		(width 0.1143)
		(layer "In15.Cu")
		(net "GMI_CPU0_G1_CPU1_G3_TX_DP<4>")
	)
	(segment
		(start 355.302058 -245.61546)
		(end 355.27234 -245.598442)
		(width 0.1143)
		(layer "In15.Cu")
		(net "GMI_CPU0_G1_CPU1_G3_TX_DP<4>")
	)
	(segment
		(start 355.343206 -232.679494)
		(end 355.30663 -232.658158)
		(width 0.1143)
		(layer "In15.Cu")
		(net "GMI_CPU0_G1_CPU1_G3_TX_DP<4>")
	)
	(segment
		(start 116.186458 -238.488728)
		(end 116.187474 -238.489236)
		(width 0.1143)
		(layer "In15.Cu")
		(net "GMI_CPU0_G1_CPU1_G3_TX_DP<4>")
	)
	(segment
		(start 355.27234 -232.029762)
		(end 355.300534 -232.013506)
		(width 0.1143)
		(layer "In15.Cu")
		(net "GMI_CPU0_G1_CPU1_G3_TX_DP<4>")
	)
	(segment
		(start 355.311202 -240.10747)
		(end 355.343206 -240.088674)
		(width 0.1143)
		(layer "In15.Cu")
		(net "GMI_CPU0_G1_CPU1_G3_TX_DP<4>")
	)
	(segment
		(start 355.343206 -235.919518)
		(end 355.30663 -235.898182)
		(width 0.1143)
		(layer "In15.Cu")
		(net "GMI_CPU0_G1_CPU1_G3_TX_DP<4>")
	)
	(segment
		(start 116.152676 -236.848904)
		(end 116.152676 -236.851444)
		(width 0.1143)
		(layer "In15.Cu")
		(net "GMI_CPU0_G1_CPU1_G3_TX_DP<4>")
	)
	(segment
		(start 116.160296 -231.99344)
		(end 116.184934 -232.007664)
		(width 0.1143)
		(layer "In15.Cu")
		(net "GMI_CPU0_G1_CPU1_G3_TX_DP<4>")
	)
	(segment
		(start 355.303328 -237.516162)
		(end 355.302058 -237.5154)
		(width 0.1143)
		(layer "In15.Cu")
		(net "GMI_CPU0_G1_CPU1_G3_TX_DP<4>")
	)
	(segment
		(start 115.85575 -221.277942)
		(end 115.909344 -221.331536)
		(width 0.1143)
		(layer "In15.Cu")
		(net "GMI_CPU0_G1_CPU1_G3_TX_DP<4>")
	)
	(segment
		(start 116.160296 -243.333524)
		(end 116.184934 -243.347748)
		(width 0.1143)
		(layer "In15.Cu")
		(net "GMI_CPU0_G1_CPU1_G3_TX_DP<4>")
	)
	(segment
		(start 355.30409 -243.996718)
		(end 355.303328 -243.99621)
		(width 0.1143)
		(layer "In15.Cu")
		(net "GMI_CPU0_G1_CPU1_G3_TX_DP<4>")
	)
	(segment
		(start 116.189252 -239.13846)
		(end 116.152676 -239.159796)
		(width 0.1143)
		(layer "In15.Cu")
		(net "GMI_CPU0_G1_CPU1_G3_TX_DP<4>")
	)
	(segment
		(start 116.188998 -243.350288)
		(end 116.190776 -243.351304)
		(width 0.1143)
		(layer "In15.Cu")
		(net "GMI_CPU0_G1_CPU1_G3_TX_DP<4>")
	)
	(segment
		(start 165.606984 -177.748438)
		(end 157.683962 -180.581554)
		(width 0.14224)
		(layer "In15.Cu")
		(net "GMI_CPU0_G1_CPU1_G3_TX_DP<4>")
	)
	(segment
		(start 355.30409 -242.376706)
		(end 355.303328 -242.376198)
		(width 0.1143)
		(layer "In15.Cu")
		(net "GMI_CPU0_G1_CPU1_G3_TX_DP<4>")
	)
	(segment
		(start 355.343206 -240.779554)
		(end 355.30663 -240.758218)
		(width 0.1143)
		(layer "In15.Cu")
		(net "GMI_CPU0_G1_CPU1_G3_TX_DP<4>")
	)
	(segment
		(start 116.23929 -222.907352)
		(end 116.223542 -222.918782)
		(width 0.1143)
		(layer "In15.Cu")
		(net "GMI_CPU0_G1_CPU1_G3_TX_DP<4>")
	)
	(segment
		(start 355.311202 -243.347494)
		(end 355.343206 -243.328698)
		(width 0.1143)
		(layer "In15.Cu")
		(net "GMI_CPU0_G1_CPU1_G3_TX_DP<4>")
	)
	(segment
		(start 116.184934 -244.96776)
		(end 116.186458 -244.968776)
		(width 0.1143)
		(layer "In15.Cu")
		(net "GMI_CPU0_G1_CPU1_G3_TX_DP<4>")
	)
	(segment
		(start 355.30409 -227.151692)
		(end 355.343206 -227.128832)
		(width 0.1143)
		(layer "In15.Cu")
		(net "GMI_CPU0_G1_CPU1_G3_TX_DP<4>")
	)
	(segment
		(start 116.188998 -244.9703)
		(end 116.190776 -244.971316)
		(width 0.1143)
		(layer "In15.Cu")
		(net "GMI_CPU0_G1_CPU1_G3_TX_DP<4>")
	)
	(segment
		(start 116.152676 -238.468916)
		(end 116.159534 -238.47298)
		(width 0.1143)
		(layer "In15.Cu")
		(net "GMI_CPU0_G1_CPU1_G3_TX_DP<4>")
	)
	(segment
		(start 310.17337 -179.382928)
		(end 310.152288 -179.371244)
		(width 0.14224)
		(layer "In15.Cu")
		(net "GMI_CPU0_G1_CPU1_G3_TX_DP<4>")
	)
	(segment
		(start 116.191792 -227.797106)
		(end 116.190776 -227.797614)
		(width 0.1143)
		(layer "In15.Cu")
		(net "GMI_CPU0_G1_CPU1_G3_TX_DP<4>")
	)
	(segment
		(start 116.160296 -230.373682)
		(end 116.190776 -230.391462)
		(width 0.1143)
		(layer "In15.Cu")
		(net "GMI_CPU0_G1_CPU1_G3_TX_DP<4>")
	)
	(segment
		(start 116.191792 -246.591836)
		(end 116.192554 -246.592344)
		(width 0.1143)
		(layer "In15.Cu")
		(net "GMI_CPU0_G1_CPU1_G3_TX_DP<4>")
	)
	(segment
		(start 116.152676 -223.889062)
		(end 116.159534 -223.893126)
		(width 0.1143)
		(layer "In15.Cu")
		(net "GMI_CPU0_G1_CPU1_G3_TX_DP<4>")
	)
	(segment
		(start 116.190776 -227.151438)
		(end 116.191792 -227.151946)
		(width 0.1143)
		(layer "In15.Cu")
		(net "GMI_CPU0_G1_CPU1_G3_TX_DP<4>")
	)
	(segment
		(start 355.302058 -234.275376)
		(end 355.300534 -234.274614)
		(width 0.1143)
		(layer "In15.Cu")
		(net "GMI_CPU0_G1_CPU1_G3_TX_DP<4>")
	)
	(segment
		(start 355.30409 -239.136682)
		(end 355.303328 -239.136174)
		(width 0.1143)
		(layer "In15.Cu")
		(net "GMI_CPU0_G1_CPU1_G3_TX_DP<4>")
	)
	(segment
		(start 116.230146 -232.633774)
		(end 116.223542 -232.6386)
		(width 0.1143)
		(layer "In15.Cu")
		(net "GMI_CPU0_G1_CPU1_G3_TX_DP<4>")
	)
	(segment
		(start 355.30409 -228.771704)
		(end 355.340412 -228.750876)
		(width 0.1143)
		(layer "In15.Cu")
		(net "GMI_CPU0_G1_CPU1_G3_TX_DP<4>")
	)
	(segment
		(start 355.305106 -240.111026)
		(end 355.30663 -240.11001)
		(width 0.1143)
		(layer "In15.Cu")
		(net "GMI_CPU0_G1_CPU1_G3_TX_DP<4>")
	)
	(segment
		(start 116.152676 -244.948964)
		(end 116.159534 -244.953028)
		(width 0.1143)
		(layer "In15.Cu")
		(net "GMI_CPU0_G1_CPU1_G3_TX_DP<4>")
	)
	(segment
		(start 355.302058 -246.592852)
		(end 355.303328 -246.59209)
		(width 0.1143)
		(layer "In15.Cu")
		(net "GMI_CPU0_G1_CPU1_G3_TX_DP<4>")
	)
	(segment
		(start 116.184934 -225.52787)
		(end 116.186458 -225.528886)
		(width 0.1143)
		(layer "In15.Cu")
		(net "GMI_CPU0_G1_CPU1_G3_TX_DP<4>")
	)
	(segment
		(start 354.176584 -222.614236)
		(end 354.17633 -222.614236)
		(width 0.1143)
		(layer "In15.Cu")
		(net "GMI_CPU0_G1_CPU1_G3_TX_DP<4>")
	)
	(segment
		(start 355.302058 -233.632756)
		(end 355.303328 -233.631994)
		(width 0.1143)
		(layer "In15.Cu")
		(net "GMI_CPU0_G1_CPU1_G3_TX_DP<4>")
	)
	(segment
		(start 116.192554 -232.65638)
		(end 116.191792 -232.656888)
		(width 0.1143)
		(layer "In15.Cu")
		(net "GMI_CPU0_G1_CPU1_G3_TX_DP<4>")
	)
	(segment
		(start 355.27234 -244.989858)
		(end 355.300534 -244.973602)
		(width 0.1143)
		(layer "In15.Cu")
		(net "GMI_CPU0_G1_CPU1_G3_TX_DP<4>")
	)
	(segment
		(start 354.365052 -222.291148)
		(end 354.366576 -222.290132)
		(width 0.1143)
		(layer "In15.Cu")
		(net "GMI_CPU0_G1_CPU1_G3_TX_DP<4>")
	)
	(segment
		(start 354.364036 -224.556828)
		(end 354.333556 -224.539048)
		(width 0.1143)
		(layer "In15.Cu")
		(net "GMI_CPU0_G1_CPU1_G3_TX_DP<4>")
	)
	(segment
		(start 355.305106 -232.657142)
		(end 355.30409 -232.656634)
		(width 0.1143)
		(layer "In15.Cu")
		(net "GMI_CPU0_G1_CPU1_G3_TX_DP<4>")
	)
	(segment
		(start 355.30409 -230.391716)
		(end 355.340666 -230.37038)
		(width 0.1143)
		(layer "In15.Cu")
		(net "GMI_CPU0_G1_CPU1_G3_TX_DP<4>")
	)
	(segment
		(start 355.27234 -235.269786)
		(end 355.300534 -235.25353)
		(width 0.1143)
		(layer "In15.Cu")
		(net "GMI_CPU0_G1_CPU1_G3_TX_DP<4>")
	)
	(segment
		(start 355.305106 -241.731038)
		(end 355.30663 -241.730022)
		(width 0.1143)
		(layer "In15.Cu")
		(net "GMI_CPU0_G1_CPU1_G3_TX_DP<4>")
	)
	(segment
		(start 355.305106 -244.971062)
		(end 355.30663 -244.970046)
		(width 0.1143)
		(layer "In15.Cu")
		(net "GMI_CPU0_G1_CPU1_G3_TX_DP<4>")
	)
	(segment
		(start 116.152676 -231.988868)
		(end 116.159534 -231.992932)
		(width 0.1143)
		(layer "In15.Cu")
		(net "GMI_CPU0_G1_CPU1_G3_TX_DP<4>")
	)
	(segment
		(start 116.190776 -245.617492)
		(end 116.189252 -245.618508)
		(width 0.1143)
		(layer "In15.Cu")
		(net "GMI_CPU0_G1_CPU1_G3_TX_DP<4>")
	)
	(segment
		(start 116.152676 -235.229146)
		(end 116.153438 -235.229654)
		(width 0.1143)
		(layer "In15.Cu")
		(net "GMI_CPU0_G1_CPU1_G3_TX_DP<4>")
	)
	(segment
		(start 116.191792 -241.7318)
		(end 116.192554 -241.732308)
		(width 0.1143)
		(layer "In15.Cu")
		(net "GMI_CPU0_G1_CPU1_G3_TX_DP<4>")
	)
	(segment
		(start 116.184934 -232.007664)
		(end 116.186458 -232.00868)
		(width 0.1143)
		(layer "In15.Cu")
		(net "GMI_CPU0_G1_CPU1_G3_TX_DP<4>")
	)
	(segment
		(start 116.184934 -223.907858)
		(end 116.186458 -223.908874)
		(width 0.1143)
		(layer "In15.Cu")
		(net "GMI_CPU0_G1_CPU1_G3_TX_DP<4>")
	)
	(segment
		(start 355.311202 -232.00741)
		(end 355.343206 -231.988614)
		(width 0.1143)
		(layer "In15.Cu")
		(net "GMI_CPU0_G1_CPU1_G3_TX_DP<4>")
	)
	(segment
		(start 116.192554 -223.91243)
		(end 116.223542 -223.93021)
		(width 0.1143)
		(layer "In15.Cu")
		(net "GMI_CPU0_G1_CPU1_G3_TX_DP<4>")
	)
	(segment
		(start 116.152676 -236.851444)
		(end 116.172742 -236.861858)
		(width 0.1143)
		(layer "In15.Cu")
		(net "GMI_CPU0_G1_CPU1_G3_TX_DP<4>")
	)
	(segment
		(start 355.305106 -246.591074)
		(end 355.30663 -246.590058)
		(width 0.1143)
		(layer "In15.Cu")
		(net "GMI_CPU0_G1_CPU1_G3_TX_DP<4>")
	)
	(segment
		(start 116.223542 -225.550222)
		(end 116.233702 -225.557588)
		(width 0.1143)
		(layer "In15.Cu")
		(net "GMI_CPU0_G1_CPU1_G3_TX_DP<4>")
	)
	(segment
		(start 116.231924 -227.772722)
		(end 116.223542 -227.778818)
		(width 0.1143)
		(layer "In15.Cu")
		(net "GMI_CPU0_G1_CPU1_G3_TX_DP<4>")
	)
	(segment
		(start 116.152676 -225.509074)
		(end 116.159534 -225.513138)
		(width 0.1143)
		(layer "In15.Cu")
		(net "GMI_CPU0_G1_CPU1_G3_TX_DP<4>")
	)
	(segment
		(start 355.300534 -240.113566)
		(end 355.302058 -240.112804)
		(width 0.1143)
		(layer "In15.Cu")
		(net "GMI_CPU0_G1_CPU1_G3_TX_DP<4>")
	)
	(segment
		(start 354.67798 -219.4687)
		(end 350.619568 -210.893152)
		(width 0.14224)
		(layer "In15.Cu")
		(net "GMI_CPU0_G1_CPU1_G3_TX_DP<4>")
	)
	(segment
		(start 355.305106 -235.25099)
		(end 355.30663 -235.249974)
		(width 0.1143)
		(layer "In15.Cu")
		(net "GMI_CPU0_G1_CPU1_G3_TX_DP<4>")
	)
	(segment
		(start 116.191792 -232.656888)
		(end 116.190776 -232.657396)
		(width 0.1143)
		(layer "In15.Cu")
		(net "GMI_CPU0_G1_CPU1_G3_TX_DP<4>")
	)
	(segment
		(start 355.27361 -227.169472)
		(end 355.30409 -227.151692)
		(width 0.1143)
		(layer "In15.Cu")
		(net "GMI_CPU0_G1_CPU1_G3_TX_DP<4>")
	)
	(segment
		(start 355.30409 -234.276646)
		(end 355.303328 -234.276138)
		(width 0.1143)
		(layer "In15.Cu")
		(net "GMI_CPU0_G1_CPU1_G3_TX_DP<4>")
	)
	(segment
		(start 116.189252 -227.79863)
		(end 116.152676 -227.819966)
		(width 0.1143)
		(layer "In15.Cu")
		(net "GMI_CPU0_G1_CPU1_G3_TX_DP<4>")
	)
	(segment
		(start 355.311202 -236.867446)
		(end 355.343206 -236.84865)
		(width 0.1143)
		(layer "In15.Cu")
		(net "GMI_CPU0_G1_CPU1_G3_TX_DP<4>")
	)
	(segment
		(start 354.646484 -221.3229)
		(end 354.63226 -221.308676)
		(width 0.1143)
		(layer "In15.Cu")
		(net "GMI_CPU0_G1_CPU1_G3_TX_DP<4>")
	)
	(segment
		(start 116.190776 -234.277408)
		(end 116.189252 -234.278424)
		(width 0.1143)
		(layer "In15.Cu")
		(net "GMI_CPU0_G1_CPU1_G3_TX_DP<4>")
	)
	(segment
		(start 355.300534 -235.25353)
		(end 355.302058 -235.252768)
		(width 0.1143)
		(layer "In15.Cu")
		(net "GMI_CPU0_G1_CPU1_G3_TX_DP<4>")
	)
	(segment
		(start 116.153946 -222.270066)
		(end 116.223542 -222.310198)
		(width 0.1143)
		(layer "In15.Cu")
		(net "GMI_CPU0_G1_CPU1_G3_TX_DP<4>")
	)
	(segment
		(start 354.646484 -221.80423)
		(end 354.646484 -221.3229)
		(width 0.1143)
		(layer "In15.Cu")
		(net "GMI_CPU0_G1_CPU1_G3_TX_DP<4>")
	)
	(segment
		(start 355.30409 -227.796852)
		(end 355.27361 -227.779072)
		(width 0.1143)
		(layer "In15.Cu")
		(net "GMI_CPU0_G1_CPU1_G3_TX_DP<4>")
	)
	(segment
		(start 116.172742 -236.861858)
		(end 116.1923 -236.871764)
		(width 0.1143)
		(layer "In15.Cu")
		(net "GMI_CPU0_G1_CPU1_G3_TX_DP<4>")
	)
	(segment
		(start 116.188998 -233.630216)
		(end 116.190776 -233.631232)
		(width 0.1143)
		(layer "In15.Cu")
		(net "GMI_CPU0_G1_CPU1_G3_TX_DP<4>")
	)
	(segment
		(start 116.192554 -227.796598)
		(end 116.191792 -227.797106)
		(width 0.1143)
		(layer "In15.Cu")
		(net "GMI_CPU0_G1_CPU1_G3_TX_DP<4>")
	)
	(segment
		(start 116.233702 -226.15144)
		(end 116.223542 -226.158806)
		(width 0.1143)
		(layer "In15.Cu")
		(net "GMI_CPU0_G1_CPU1_G3_TX_DP<4>")
	)
	(segment
		(start 116.159534 -227.13315)
		(end 116.160296 -227.133658)
		(width 0.1143)
		(layer "In15.Cu")
		(net "GMI_CPU0_G1_CPU1_G3_TX_DP<4>")
	)
	(segment
		(start 116.191792 -233.63174)
		(end 116.192554 -233.632248)
		(width 0.1143)
		(layer "In15.Cu")
		(net "GMI_CPU0_G1_CPU1_G3_TX_DP<4>")
	)
	(segment
		(start 116.223542 -234.258612)
		(end 116.192554 -234.276392)
		(width 0.1143)
		(layer "In15.Cu")
		(net "GMI_CPU0_G1_CPU1_G3_TX_DP<4>")
	)
	(segment
		(start 116.160296 -228.75367)
		(end 116.184934 -228.767894)
		(width 0.1143)
		(layer "In15.Cu")
		(net "GMI_CPU0_G1_CPU1_G3_TX_DP<4>")
	)
	(segment
		(start 355.300534 -240.754662)
		(end 355.299772 -240.754154)
		(width 0.1143)
		(layer "In15.Cu")
		(net "GMI_CPU0_G1_CPU1_G3_TX_DP<4>")
	)
	(segment
		(start 116.223542 -243.978684)
		(end 116.192554 -243.996464)
		(width 0.1143)
		(layer "In15.Cu")
		(net "GMI_CPU0_G1_CPU1_G3_TX_DP<4>")
	)
	(segment
		(start 116.159534 -241.713004)
		(end 116.160296 -241.713512)
		(width 0.1143)
		(layer "In15.Cu")
		(net "GMI_CPU0_G1_CPU1_G3_TX_DP<4>")
	)
	(segment
		(start 116.233702 -242.351306)
		(end 116.223542 -242.358672)
		(width 0.1143)
		(layer "In15.Cu")
		(net "GMI_CPU0_G1_CPU1_G3_TX_DP<4>")
	)
	(segment
		(start 355.27234 -240.129822)
		(end 355.300534 -240.113566)
		(width 0.1143)
		(layer "In15.Cu")
		(net "GMI_CPU0_G1_CPU1_G3_TX_DP<4>")
	)
	(segment
		(start 355.311202 -246.587518)
		(end 355.343206 -246.568722)
		(width 0.1143)
		(layer "In15.Cu")
		(net "GMI_CPU0_G1_CPU1_G3_TX_DP<4>")
	)
	(segment
		(start 355.303328 -232.011982)
		(end 355.30409 -232.011474)
		(width 0.1143)
		(layer "In15.Cu")
		(net "GMI_CPU0_G1_CPU1_G3_TX_DP<4>")
	)
	(segment
		(start 115.85575 -221.066106)
		(end 115.85575 -221.277942)
		(width 0.1143)
		(layer "In15.Cu")
		(net "GMI_CPU0_G1_CPU1_G3_TX_DP<4>")
	)
	(segment
		(start 116.77269 -247.724422)
		(end 116.474748 -247.724422)
		(width 0.1143)
		(layer "In15.Cu")
		(net "GMI_CPU0_G1_CPU1_G3_TX_DP<4>")
	)
	(segment
		(start 354.364036 -222.291656)
		(end 354.365052 -222.291148)
		(width 0.1143)
		(layer "In15.Cu")
		(net "GMI_CPU0_G1_CPU1_G3_TX_DP<4>")
	)
	(segment
		(start 116.184934 -228.767894)
		(end 116.186458 -228.76891)
		(width 0.1143)
		(layer "In15.Cu")
		(net "GMI_CPU0_G1_CPU1_G3_TX_DP<4>")
	)
	(segment
		(start 354.833428 -225.366326)
		(end 354.832158 -225.365564)
		(width 0.1143)
		(layer "In15.Cu")
		(net "GMI_CPU0_G1_CPU1_G3_TX_DP<4>")
	)
	(segment
		(start 355.300534 -234.274614)
		(end 355.299772 -234.274106)
		(width 0.1143)
		(layer "In15.Cu")
		(net "GMI_CPU0_G1_CPU1_G3_TX_DP<4>")
	)
	(segment
		(start 116.192554 -228.772466)
		(end 116.193062 -228.77272)
		(width 0.1143)
		(layer "In15.Cu")
		(net "GMI_CPU0_G1_CPU1_G3_TX_DP<4>")
	)
	(segment
		(start 116.190776 -240.757456)
		(end 116.189252 -240.758472)
		(width 0.1143)
		(layer "In15.Cu")
		(net "GMI_CPU0_G1_CPU1_G3_TX_DP<4>")
	)
	(segment
		(start 116.191792 -227.151946)
		(end 116.192554 -227.152454)
		(width 0.1143)
		(layer "In15.Cu")
		(net "GMI_CPU0_G1_CPU1_G3_TX_DP<4>")
	)
	(segment
		(start 355.302058 -243.352828)
		(end 355.303328 -243.352066)
		(width 0.1143)
		(layer "In15.Cu")
		(net "GMI_CPU0_G1_CPU1_G3_TX_DP<4>")
	)
	(segment
		(start 355.311202 -241.727482)
		(end 355.343206 -241.708686)
		(width 0.1143)
		(layer "In15.Cu")
		(net "GMI_CPU0_G1_CPU1_G3_TX_DP<4>")
	)
	(segment
		(start 116.189252 -232.658412)
		(end 116.152676 -232.679748)
		(width 0.1143)
		(layer "In15.Cu")
		(net "GMI_CPU0_G1_CPU1_G3_TX_DP<4>")
	)
	(segment
		(start 116.392198 -246.922798)
		(end 116.392198 -246.934228)
		(width 0.1143)
		(layer "In15.Cu")
		(net "GMI_CPU0_G1_CPU1_G3_TX_DP<4>")
	)
	(segment
		(start 116.192554 -243.35232)
		(end 116.223542 -243.3701)
		(width 0.1143)
		(layer "In15.Cu")
		(net "GMI_CPU0_G1_CPU1_G3_TX_DP<4>")
	)
	(segment
		(start 355.30409 -240.756694)
		(end 355.303328 -240.756186)
		(width 0.1143)
		(layer "In15.Cu")
		(net "GMI_CPU0_G1_CPU1_G3_TX_DP<4>")
	)
	(segment
		(start 355.303328 -246.59209)
		(end 355.30409 -246.591582)
		(width 0.1143)
		(layer "In15.Cu")
		(net "GMI_CPU0_G1_CPU1_G3_TX_DP<4>")
	)
	(segment
		(start 116.159534 -233.612944)
		(end 116.160296 -233.613452)
		(width 0.1143)
		(layer "In15.Cu")
		(net "GMI_CPU0_G1_CPU1_G3_TX_DP<4>")
	)
	(segment
		(start 116.243354 -224.52457)
		(end 116.223542 -224.538794)
		(width 0.1143)
		(layer "In15.Cu")
		(net "GMI_CPU0_G1_CPU1_G3_TX_DP<4>")
	)
	(segment
		(start 116.187474 -238.489236)
		(end 116.188998 -238.490252)
		(width 0.1143)
		(layer "In15.Cu")
		(net "GMI_CPU0_G1_CPU1_G3_TX_DP<4>")
	)
	(segment
		(start 116.192554 -233.632248)
		(end 116.223542 -233.650028)
		(width 0.1143)
		(layer "In15.Cu")
		(net "GMI_CPU0_G1_CPU1_G3_TX_DP<4>")
	)
	(segment
		(start 116.186458 -241.728752)
		(end 116.187474 -241.72926)
		(width 0.1143)
		(layer "In15.Cu")
		(net "GMI_CPU0_G1_CPU1_G3_TX_DP<4>")
	)
	(segment
		(start 355.297994 -239.133126)
		(end 355.296978 -239.132618)
		(width 0.1143)
		(layer "In15.Cu")
		(net "GMI_CPU0_G1_CPU1_G3_TX_DP<4>")
	)
	(segment
		(start 152.414986 -184.901332)
		(end 152.41524 -184.90184)
		(width 0.14224)
		(layer "In15.Cu")
		(net "GMI_CPU0_G1_CPU1_G3_TX_DP<4>")
	)
	(segment
		(start 355.303328 -240.112042)
		(end 355.30409 -240.111534)
		(width 0.1143)
		(layer "In15.Cu")
		(net "GMI_CPU0_G1_CPU1_G3_TX_DP<4>")
	)
	(segment
		(start 355.298756 -234.273598)
		(end 355.297994 -234.27309)
		(width 0.1143)
		(layer "In15.Cu")
		(net "GMI_CPU0_G1_CPU1_G3_TX_DP<4>")
	)
	(segment
		(start 355.302058 -240.755424)
		(end 355.300534 -240.754662)
		(width 0.1143)
		(layer "In15.Cu")
		(net "GMI_CPU0_G1_CPU1_G3_TX_DP<4>")
	)
	(segment
		(start 355.30409 -232.656634)
		(end 355.303328 -232.656126)
		(width 0.1143)
		(layer "In15.Cu")
		(net "GMI_CPU0_G1_CPU1_G3_TX_DP<4>")
	)
	(segment
		(start 116.160296 -241.713512)
		(end 116.184934 -241.727736)
		(width 0.1143)
		(layer "In15.Cu")
		(net "GMI_CPU0_G1_CPU1_G3_TX_DP<4>")
	)
	(segment
		(start 116.192554 -225.532442)
		(end 116.223542 -225.550222)
		(width 0.1143)
		(layer "In15.Cu")
		(net "GMI_CPU0_G1_CPU1_G3_TX_DP<4>")
	)
	(segment
		(start 355.300534 -243.994686)
		(end 355.299772 -243.994178)
		(width 0.1143)
		(layer "In15.Cu")
		(net "GMI_CPU0_G1_CPU1_G3_TX_DP<4>")
	)
	(segment
		(start 116.190776 -242.377468)
		(end 116.186204 -242.380262)
		(width 0.1143)
		(layer "In15.Cu")
		(net "GMI_CPU0_G1_CPU1_G3_TX_DP<4>")
	)
	(segment
		(start 116.189252 -243.998496)
		(end 116.152676 -244.019832)
		(width 0.1143)
		(layer "In15.Cu")
		(net "GMI_CPU0_G1_CPU1_G3_TX_DP<4>")
	)
	(segment
		(start 116.191792 -238.491776)
		(end 116.192554 -238.492284)
		(width 0.1143)
		(layer "In15.Cu")
		(net "GMI_CPU0_G1_CPU1_G3_TX_DP<4>")
	)
	(segment
		(start 116.160296 -238.473488)
		(end 116.184934 -238.487712)
		(width 0.1143)
		(layer "In15.Cu")
		(net "GMI_CPU0_G1_CPU1_G3_TX_DP<4>")
	)
	(segment
		(start 355.305106 -243.997226)
		(end 355.30409 -243.996718)
		(width 0.1143)
		(layer "In15.Cu")
		(net "GMI_CPU0_G1_CPU1_G3_TX_DP<4>")
	)
	(segment
		(start 116.191792 -223.911922)
		(end 116.192554 -223.91243)
		(width 0.1143)
		(layer "In15.Cu")
		(net "GMI_CPU0_G1_CPU1_G3_TX_DP<4>")
	)
	(segment
		(start 116.184934 -243.347748)
		(end 116.186458 -243.348764)
		(width 0.1143)
		(layer "In15.Cu")
		(net "GMI_CPU0_G1_CPU1_G3_TX_DP<4>")
	)
	(segment
		(start 116.192554 -243.996464)
		(end 116.191792 -243.996972)
		(width 0.1143)
		(layer "In15.Cu")
		(net "GMI_CPU0_G1_CPU1_G3_TX_DP<4>")
	)
	(segment
		(start 355.30663 -232.00995)
		(end 355.311202 -232.00741)
		(width 0.1143)
		(layer "In15.Cu")
		(net "GMI_CPU0_G1_CPU1_G3_TX_DP<4>")
	)
	(segment
		(start 116.1923 -237.516924)
		(end 116.191792 -237.517178)
		(width 0.1143)
		(layer "In15.Cu")
		(net "GMI_CPU0_G1_CPU1_G3_TX_DP<4>")
	)
	(segment
		(start 355.303328 -233.631994)
		(end 355.30409 -233.631486)
		(width 0.1143)
		(layer "In15.Cu")
		(net "GMI_CPU0_G1_CPU1_G3_TX_DP<4>")
	)
	(segment
		(start 116.192554 -239.136428)
		(end 116.191792 -239.136936)
		(width 0.1143)
		(layer "In15.Cu")
		(net "GMI_CPU0_G1_CPU1_G3_TX_DP<4>")
	)
	(segment
		(start 355.27234 -246.60987)
		(end 355.300534 -246.593614)
		(width 0.1143)
		(layer "In15.Cu")
		(net "GMI_CPU0_G1_CPU1_G3_TX_DP<4>")
	)
	(segment
		(start 152.41524 -184.90184)
		(end 119.551704 -211.847176)
		(width 0.14224)
		(layer "In15.Cu")
		(net "GMI_CPU0_G1_CPU1_G3_TX_DP<4>")
	)
	(segment
		(start 354.803456 -247.419368)
		(end 354.833936 -247.401588)
		(width 0.1143)
		(layer "In15.Cu")
		(net "GMI_CPU0_G1_CPU1_G3_TX_DP<4>")
	)
	(segment
		(start 116.187474 -233.6292)
		(end 116.188998 -233.630216)
		(width 0.1143)
		(layer "In15.Cu")
		(net "GMI_CPU0_G1_CPU1_G3_TX_DP<4>")
	)
	(segment
		(start 355.343206 -237.53953)
		(end 355.305106 -237.517178)
		(width 0.1143)
		(layer "In15.Cu")
		(net "GMI_CPU0_G1_CPU1_G3_TX_DP<4>")
	)
	(segment
		(start 354.833936 -247.401588)
		(end 354.873052 -247.378728)
		(width 0.1143)
		(layer "In15.Cu")
		(net "GMI_CPU0_G1_CPU1_G3_TX_DP<4>")
	)
	(segment
		(start 116.192554 -241.732308)
		(end 116.223542 -241.750088)
		(width 0.1143)
		(layer "In15.Cu")
		(net "GMI_CPU0_G1_CPU1_G3_TX_DP<4>")
	)
	(segment
		(start 355.298756 -240.753646)
		(end 355.297994 -240.753138)
		(width 0.1143)
		(layer "In15.Cu")
		(net "GMI_CPU0_G1_CPU1_G3_TX_DP<4>")
	)
	(segment
		(start 116.223542 -244.990112)
		(end 116.233194 -244.99697)
		(width 0.1143)
		(layer "In15.Cu")
		(net "GMI_CPU0_G1_CPU1_G3_TX_DP<4>")
	)
	(segment
		(start 116.661946 -247.401842)
		(end 116.693442 -247.420384)
		(width 0.1143)
		(layer "In15.Cu")
		(net "GMI_CPU0_G1_CPU1_G3_TX_DP<4>")
	)
	(segment
		(start 354.67798 -221.083124)
		(end 354.67798 -219.4687)
		(width 0.14224)
		(layer "In15.Cu")
		(net "GMI_CPU0_G1_CPU1_G3_TX_DP<4>")
	)
	(segment
		(start 116.190776 -235.89742)
		(end 116.152676 -235.919772)
		(width 0.1143)
		(layer "In15.Cu")
		(net "GMI_CPU0_G1_CPU1_G3_TX_DP<4>")
	)
	(segment
		(start 355.299772 -240.754154)
		(end 355.298756 -240.753646)
		(width 0.1143)
		(layer "In15.Cu")
		(net "GMI_CPU0_G1_CPU1_G3_TX_DP<4>")
	)
	(segment
		(start 116.184934 -246.587772)
		(end 116.186458 -246.588788)
		(width 0.1143)
		(layer "In15.Cu")
		(net "GMI_CPU0_G1_CPU1_G3_TX_DP<4>")
	)
	(segment
		(start 355.27234 -236.889798)
		(end 355.300534 -236.873542)
		(width 0.1143)
		(layer "In15.Cu")
		(net "GMI_CPU0_G1_CPU1_G3_TX_DP<4>")
	)
	(segment
		(start 116.160296 -233.613452)
		(end 116.184934 -233.627676)
		(width 0.1143)
		(layer "In15.Cu")
		(net "GMI_CPU0_G1_CPU1_G3_TX_DP<4>")
	)
	(arc
		(start 116.379498 -229.094538)
		(mid 116.338736 -229.264422)
		(end 116.22532 -229.397306)
		(width 0.1143)
		(layer "In15.Cu")
		(net "GMI_CPU0_G1_CPU1_G3_TX_DP<4>")
	)
	(arc
		(start 355.116384 -230.714296)
		(mid 355.157639 -230.543325)
		(end 355.27234 -230.410004)
		(width 0.1143)
		(layer "In15.Cu")
		(net "GMI_CPU0_G1_CPU1_G3_TX_DP<4>")
	)
	(arc
		(start 116.152676 -224.579942)
		(mid 115.909349 -225.044508)
		(end 116.152676 -225.509074)
		(width 0.1143)
		(layer "In15.Cu")
		(net "GMI_CPU0_G1_CPU1_G3_TX_DP<4>")
	)
	(arc
		(start 116.153184 -222.269558)
		(mid 116.153565 -222.269812)
		(end 116.153946 -222.270066)
		(width 0.1143)
		(layer "In15.Cu")
		(net "GMI_CPU0_G1_CPU1_G3_TX_DP<4>")
	)
	(arc
		(start 116.206778 -246.600218)
		(mid 116.342516 -246.73677)
		(end 116.392198 -246.922798)
		(width 0.1143)
		(layer "In15.Cu")
		(net "GMI_CPU0_G1_CPU1_G3_TX_DP<4>")
	)
	(arc
		(start 355.343206 -244.94871)
		(mid 355.586533 -244.484144)
		(end 355.343206 -244.019578)
		(width 0.1143)
		(layer "In15.Cu")
		(net "GMI_CPU0_G1_CPU1_G3_TX_DP<4>")
	)
	(arc
		(start 116.230146 -232.034842)
		(mid 116.383636 -232.334308)
		(end 116.230146 -232.633774)
		(width 0.1143)
		(layer "In15.Cu")
		(net "GMI_CPU0_G1_CPU1_G3_TX_DP<4>")
	)
	(arc
		(start 116.243354 -223.944434)
		(mid 116.392068 -224.234502)
		(end 116.243354 -224.52457)
		(width 0.1143)
		(layer "In15.Cu")
		(net "GMI_CPU0_G1_CPU1_G3_TX_DP<4>")
	)
	(arc
		(start 354.333556 -224.539048)
		(mid 354.176579 -224.234248)
		(end 354.333556 -223.929448)
		(width 0.1143)
		(layer "In15.Cu")
		(net "GMI_CPU0_G1_CPU1_G3_TX_DP<4>")
	)
	(arc
		(start 355.270562 -231.017064)
		(mid 355.157155 -230.884175)
		(end 355.116384 -230.714296)
		(width 0.1143)
		(layer "In15.Cu")
		(net "GMI_CPU0_G1_CPU1_G3_TX_DP<4>")
	)
	(arc
		(start 116.1923 -235.251752)
		(mid 116.377938 -235.574158)
		(end 116.192554 -235.896658)
		(width 0.1143)
		(layer "In15.Cu")
		(net "GMI_CPU0_G1_CPU1_G3_TX_DP<4>")
	)
	(arc
		(start 354.873052 -247.378728)
		(mid 355.051865 -247.176378)
		(end 355.116384 -246.914162)
		(width 0.1143)
		(layer "In15.Cu")
		(net "GMI_CPU0_G1_CPU1_G3_TX_DP<4>")
	)
	(arc
		(start 116.392198 -246.934228)
		(mid 116.464463 -247.204157)
		(end 116.661946 -247.401842)
		(width 0.1143)
		(layer "In15.Cu")
		(net "GMI_CPU0_G1_CPU1_G3_TX_DP<4>")
	)
	(arc
		(start 116.152676 -239.159796)
		(mid 115.909349 -239.624362)
		(end 116.152676 -240.088928)
		(width 0.1143)
		(layer "In15.Cu")
		(net "GMI_CPU0_G1_CPU1_G3_TX_DP<4>")
	)
	(arc
		(start 116.1923 -240.111788)
		(mid 116.377938 -240.434368)
		(end 116.1923 -240.756948)
		(width 0.1143)
		(layer "In15.Cu")
		(net "GMI_CPU0_G1_CPU1_G3_TX_DP<4>")
	)
	(arc
		(start 116.152676 -240.779808)
		(mid 115.909349 -241.244374)
		(end 116.152676 -241.70894)
		(width 0.1143)
		(layer "In15.Cu")
		(net "GMI_CPU0_G1_CPU1_G3_TX_DP<4>")
	)
	(arc
		(start 116.223542 -233.650028)
		(mid 116.375131 -233.95432)
		(end 116.223542 -234.258612)
		(width 0.1143)
		(layer "In15.Cu")
		(net "GMI_CPU0_G1_CPU1_G3_TX_DP<4>")
	)
	(arc
		(start 355.343206 -235.228638)
		(mid 355.586533 -234.764072)
		(end 355.343206 -234.299506)
		(width 0.1143)
		(layer "In15.Cu")
		(net "GMI_CPU0_G1_CPU1_G3_TX_DP<4>")
	)
	(arc
		(start 116.231924 -227.17633)
		(mid 116.384805 -227.474526)
		(end 116.231924 -227.772722)
		(width 0.1143)
		(layer "In15.Cu")
		(net "GMI_CPU0_G1_CPU1_G3_TX_DP<4>")
	)
	(arc
		(start 355.343206 -233.608626)
		(mid 355.586533 -233.14406)
		(end 355.343206 -232.679494)
		(width 0.1143)
		(layer "In15.Cu")
		(net "GMI_CPU0_G1_CPU1_G3_TX_DP<4>")
	)
	(arc
		(start 354.403152 -223.888808)
		(mid 354.646479 -223.424242)
		(end 354.403152 -222.959676)
		(width 0.1143)
		(layer "In15.Cu")
		(net "GMI_CPU0_G1_CPU1_G3_TX_DP<4>")
	)
	(arc
		(start 355.343206 -236.84865)
		(mid 355.586533 -236.384084)
		(end 355.343206 -235.919518)
		(width 0.1143)
		(layer "In15.Cu")
		(net "GMI_CPU0_G1_CPU1_G3_TX_DP<4>")
	)
	(arc
		(start 116.237258 -238.51997)
		(mid 116.388103 -238.814356)
		(end 116.237258 -239.108742)
		(width 0.1143)
		(layer "In15.Cu")
		(net "GMI_CPU0_G1_CPU1_G3_TX_DP<4>")
	)
	(arc
		(start 116.152676 -237.539784)
		(mid 115.909349 -238.00435)
		(end 116.152676 -238.468916)
		(width 0.1143)
		(layer "In15.Cu")
		(net "GMI_CPU0_G1_CPU1_G3_TX_DP<4>")
	)
	(arc
		(start 355.586284 -229.904036)
		(mid 355.521048 -229.640445)
		(end 355.340412 -229.437692)
		(width 0.1143)
		(layer "In15.Cu")
		(net "GMI_CPU0_G1_CPU1_G3_TX_DP<4>")
	)
	(arc
		(start 116.152676 -242.39982)
		(mid 115.909349 -242.864386)
		(end 116.152676 -243.328952)
		(width 0.1143)
		(layer "In15.Cu")
		(net "GMI_CPU0_G1_CPU1_G3_TX_DP<4>")
	)
	(arc
		(start 355.27361 -227.779072)
		(mid 355.116633 -227.474272)
		(end 355.27361 -227.169472)
		(width 0.1143)
		(layer "In15.Cu")
		(net "GMI_CPU0_G1_CPU1_G3_TX_DP<4>")
	)
	(arc
		(start 355.343206 -231.988614)
		(mid 355.586533 -231.524048)
		(end 355.343206 -231.059482)
		(width 0.1143)
		(layer "In15.Cu")
		(net "GMI_CPU0_G1_CPU1_G3_TX_DP<4>")
	)
	(arc
		(start 116.152676 -227.819966)
		(mid 115.909349 -228.284532)
		(end 116.152676 -228.749098)
		(width 0.1143)
		(layer "In15.Cu")
		(net "GMI_CPU0_G1_CPU1_G3_TX_DP<4>")
	)
	(arc
		(start 355.27234 -239.118394)
		(mid 355.116412 -238.814102)
		(end 355.27234 -238.50981)
		(width 0.1143)
		(layer "In15.Cu")
		(net "GMI_CPU0_G1_CPU1_G3_TX_DP<4>")
	)
	(arc
		(start 355.27361 -226.15906)
		(mid 355.158183 -226.025684)
		(end 355.116638 -225.85426)
		(width 0.1143)
		(layer "In15.Cu")
		(net "GMI_CPU0_G1_CPU1_G3_TX_DP<4>")
	)
	(arc
		(start 355.27234 -245.598442)
		(mid 355.116412 -245.29415)
		(end 355.27234 -244.989858)
		(width 0.1143)
		(layer "In15.Cu")
		(net "GMI_CPU0_G1_CPU1_G3_TX_DP<4>")
	)
	(arc
		(start 355.343206 -246.568722)
		(mid 355.586533 -246.104156)
		(end 355.343206 -245.63959)
		(width 0.1143)
		(layer "In15.Cu")
		(net "GMI_CPU0_G1_CPU1_G3_TX_DP<4>")
	)
	(arc
		(start 354.403152 -222.268796)
		(mid 354.544781 -222.12788)
		(end 354.62845 -221.94647)
		(width 0.1143)
		(layer "In15.Cu")
		(net "GMI_CPU0_G1_CPU1_G3_TX_DP<4>")
	)
	(arc
		(start 355.27234 -243.97843)
		(mid 355.116412 -243.674138)
		(end 355.27234 -243.369846)
		(width 0.1143)
		(layer "In15.Cu")
		(net "GMI_CPU0_G1_CPU1_G3_TX_DP<4>")
	)
	(arc
		(start 116.152676 -222.95993)
		(mid 115.909349 -223.424496)
		(end 116.152676 -223.889062)
		(width 0.1143)
		(layer "In15.Cu")
		(net "GMI_CPU0_G1_CPU1_G3_TX_DP<4>")
	)
	(arc
		(start 355.27234 -234.258358)
		(mid 355.116412 -233.954066)
		(end 355.27234 -233.649774)
		(width 0.1143)
		(layer "In15.Cu")
		(net "GMI_CPU0_G1_CPU1_G3_TX_DP<4>")
	)
	(arc
		(start 355.340666 -230.37038)
		(mid 355.521318 -230.167635)
		(end 355.586538 -229.904036)
		(width 0.1143)
		(layer "In15.Cu")
		(net "GMI_CPU0_G1_CPU1_G3_TX_DP<4>")
	)
	(arc
		(start 355.343206 -228.748844)
		(mid 355.586533 -228.284278)
		(end 355.343206 -227.819712)
		(width 0.1143)
		(layer "In15.Cu")
		(net "GMI_CPU0_G1_CPU1_G3_TX_DP<4>")
	)
	(arc
		(start 354.17633 -222.614236)
		(mid 354.217585 -222.443265)
		(end 354.332286 -222.309944)
		(width 0.1143)
		(layer "In15.Cu")
		(net "GMI_CPU0_G1_CPU1_G3_TX_DP<4>")
	)
	(arc
		(start 116.152676 -235.919772)
		(mid 115.909349 -236.384338)
		(end 116.152676 -236.848904)
		(width 0.1143)
		(layer "In15.Cu")
		(net "GMI_CPU0_G1_CPU1_G3_TX_DP<4>")
	)
	(arc
		(start 116.152676 -245.639844)
		(mid 115.909349 -246.10441)
		(end 116.152676 -246.568976)
		(width 0.1143)
		(layer "In15.Cu")
		(net "GMI_CPU0_G1_CPU1_G3_TX_DP<4>")
	)
	(arc
		(start 355.116384 -246.914162)
		(mid 355.157639 -246.743191)
		(end 355.27234 -246.60987)
		(width 0.1143)
		(layer "In15.Cu")
		(net "GMI_CPU0_G1_CPU1_G3_TX_DP<4>")
	)
	(arc
		(start 355.270562 -229.397052)
		(mid 355.157155 -229.264163)
		(end 355.116384 -229.094284)
		(width 0.1143)
		(layer "In15.Cu")
		(net "GMI_CPU0_G1_CPU1_G3_TX_DP<4>")
	)
	(arc
		(start 116.152676 -229.439724)
		(mid 115.973863 -229.642074)
		(end 115.909344 -229.90429)
		(width 0.1143)
		(layer "In15.Cu")
		(net "GMI_CPU0_G1_CPU1_G3_TX_DP<4>")
	)
	(arc
		(start 115.909344 -221.804484)
		(mid 115.974003 -222.067041)
		(end 116.153184 -222.269558)
		(width 0.1143)
		(layer "In15.Cu")
		(net "GMI_CPU0_G1_CPU1_G3_TX_DP<4>")
	)
	(arc
		(start 355.27234 -235.87837)
		(mid 355.116412 -235.574078)
		(end 355.27234 -235.269786)
		(width 0.1143)
		(layer "In15.Cu")
		(net "GMI_CPU0_G1_CPU1_G3_TX_DP<4>")
	)
	(arc
		(start 116.233702 -241.757454)
		(mid 116.385869 -242.05438)
		(end 116.233702 -242.351306)
		(width 0.1143)
		(layer "In15.Cu")
		(net "GMI_CPU0_G1_CPU1_G3_TX_DP<4>")
	)
	(arc
		(start 355.116384 -229.094284)
		(mid 355.157639 -228.923313)
		(end 355.27234 -228.789992)
		(width 0.1143)
		(layer "In15.Cu")
		(net "GMI_CPU0_G1_CPU1_G3_TX_DP<4>")
	)
	(arc
		(start 355.27234 -237.498382)
		(mid 355.116412 -237.19409)
		(end 355.27234 -236.889798)
		(width 0.1143)
		(layer "In15.Cu")
		(net "GMI_CPU0_G1_CPU1_G3_TX_DP<4>")
	)
	(arc
		(start 355.343206 -241.708686)
		(mid 355.586533 -241.24412)
		(end 355.343206 -240.779554)
		(width 0.1143)
		(layer "In15.Cu")
		(net "GMI_CPU0_G1_CPU1_G3_TX_DP<4>")
	)
	(arc
		(start 116.75237 -247.472962)
		(mid 116.809989 -247.557546)
		(end 116.84254 -247.654572)
		(width 0.1143)
		(layer "In15.Cu")
		(net "GMI_CPU0_G1_CPU1_G3_TX_DP<4>")
	)
	(arc
		(start 355.343206 -227.128832)
		(mid 355.586533 -226.664266)
		(end 355.343206 -226.1997)
		(width 0.1143)
		(layer "In15.Cu")
		(net "GMI_CPU0_G1_CPU1_G3_TX_DP<4>")
	)
	(arc
		(start 355.343206 -238.468662)
		(mid 355.586533 -238.004096)
		(end 355.343206 -237.53953)
		(width 0.1143)
		(layer "In15.Cu")
		(net "GMI_CPU0_G1_CPU1_G3_TX_DP<4>")
	)
	(arc
		(start 116.152676 -231.059736)
		(mid 115.909349 -231.524302)
		(end 116.152676 -231.988868)
		(width 0.1143)
		(layer "In15.Cu")
		(net "GMI_CPU0_G1_CPU1_G3_TX_DP<4>")
	)
	(arc
		(start 354.653342 -247.654318)
		(mid 354.705759 -247.522387)
		(end 354.803456 -247.419368)
		(width 0.1143)
		(layer "In15.Cu")
		(net "GMI_CPU0_G1_CPU1_G3_TX_DP<4>")
	)
	(arc
		(start 354.62845 -221.94647)
		(mid 354.642009 -221.875925)
		(end 354.646484 -221.80423)
		(width 0.1143)
		(layer "In15.Cu")
		(net "GMI_CPU0_G1_CPU1_G3_TX_DP<4>")
	)
	(arc
		(start 355.343206 -240.088674)
		(mid 355.586533 -239.624108)
		(end 355.343206 -239.159542)
		(width 0.1143)
		(layer "In15.Cu")
		(net "GMI_CPU0_G1_CPU1_G3_TX_DP<4>")
	)
	(arc
		(start 116.379498 -230.71455)
		(mid 116.338736 -230.884434)
		(end 116.22532 -231.017318)
		(width 0.1143)
		(layer "In15.Cu")
		(net "GMI_CPU0_G1_CPU1_G3_TX_DP<4>")
	)
	(arc
		(start 116.152676 -232.679748)
		(mid 115.909349 -233.144314)
		(end 116.152676 -233.60888)
		(width 0.1143)
		(layer "In15.Cu")
		(net "GMI_CPU0_G1_CPU1_G3_TX_DP<4>")
	)
	(arc
		(start 116.152676 -234.29976)
		(mid 115.909349 -234.764326)
		(end 116.152676 -235.228892)
		(width 0.1143)
		(layer "In15.Cu")
		(net "GMI_CPU0_G1_CPU1_G3_TX_DP<4>")
	)
	(arc
		(start 116.234718 -243.378228)
		(mid 116.386478 -243.674392)
		(end 116.234718 -243.970556)
		(width 0.1143)
		(layer "In15.Cu")
		(net "GMI_CPU0_G1_CPU1_G3_TX_DP<4>")
	)
	(arc
		(start 355.343206 -243.328698)
		(mid 355.586533 -242.864132)
		(end 355.343206 -242.399566)
		(width 0.1143)
		(layer "In15.Cu")
		(net "GMI_CPU0_G1_CPU1_G3_TX_DP<4>")
	)
	(arc
		(start 116.693442 -247.420384)
		(mid 116.724289 -247.445123)
		(end 116.75237 -247.472962)
		(width 0.1143)
		(layer "In15.Cu")
		(net "GMI_CPU0_G1_CPU1_G3_TX_DP<4>")
	)
	(arc
		(start 116.19357 -230.392986)
		(mid 116.329651 -230.528834)
		(end 116.379498 -230.71455)
		(width 0.1143)
		(layer "In15.Cu")
		(net "GMI_CPU0_G1_CPU1_G3_TX_DP<4>")
	)
	(arc
		(start 116.193062 -228.77272)
		(mid 116.32948 -228.908593)
		(end 116.379498 -229.094538)
		(width 0.1143)
		(layer "In15.Cu")
		(net "GMI_CPU0_G1_CPU1_G3_TX_DP<4>")
	)
	(arc
		(start 354.646484 -225.044254)
		(mid 354.581969 -224.782035)
		(end 354.403152 -224.579688)
		(width 0.1143)
		(layer "In15.Cu")
		(net "GMI_CPU0_G1_CPU1_G3_TX_DP<4>")
	)
	(arc
		(start 116.152676 -226.199954)
		(mid 115.909349 -226.66452)
		(end 116.152676 -227.129086)
		(width 0.1143)
		(layer "In15.Cu")
		(net "GMI_CPU0_G1_CPU1_G3_TX_DP<4>")
	)
	(arc
		(start 116.23929 -222.321628)
		(mid 116.389426 -222.61449)
		(end 116.23929 -222.907352)
		(width 0.1143)
		(layer "In15.Cu")
		(net "GMI_CPU0_G1_CPU1_G3_TX_DP<4>")
	)
	(arc
		(start 355.27234 -240.738406)
		(mid 355.116412 -240.434114)
		(end 355.27234 -240.129822)
		(width 0.1143)
		(layer "In15.Cu")
		(net "GMI_CPU0_G1_CPU1_G3_TX_DP<4>")
	)
	(arc
		(start 354.333556 -222.919036)
		(mid 354.218129 -222.78566)
		(end 354.176584 -222.614236)
		(width 0.1143)
		(layer "In15.Cu")
		(net "GMI_CPU0_G1_CPU1_G3_TX_DP<4>")
	)
	(arc
		(start 116.152676 -244.019832)
		(mid 115.909349 -244.484398)
		(end 116.152676 -244.948964)
		(width 0.1143)
		(layer "In15.Cu")
		(net "GMI_CPU0_G1_CPU1_G3_TX_DP<4>")
	)
	(arc
		(start 116.233702 -225.557588)
		(mid 116.385869 -225.854514)
		(end 116.233702 -226.15144)
		(width 0.1143)
		(layer "In15.Cu")
		(net "GMI_CPU0_G1_CPU1_G3_TX_DP<4>")
	)
	(arc
		(start 354.80244 -225.348546)
		(mid 354.687764 -225.215212)
		(end 354.646484 -225.044254)
		(width 0.1143)
		(layer "In15.Cu")
		(net "GMI_CPU0_G1_CPU1_G3_TX_DP<4>")
	)
	(arc
		(start 116.1923 -236.871764)
		(mid 116.377938 -237.194344)
		(end 116.1923 -237.516924)
		(width 0.1143)
		(layer "In15.Cu")
		(net "GMI_CPU0_G1_CPU1_G3_TX_DP<4>")
	)
	(arc
		(start 115.909344 -229.90429)
		(mid 115.97458 -230.167881)
		(end 116.155216 -230.370634)
		(width 0.1143)
		(layer "In15.Cu")
		(net "GMI_CPU0_G1_CPU1_G3_TX_DP<4>")
	)
	(arc
		(start 355.116638 -225.85426)
		(mid 355.052123 -225.592041)
		(end 354.873306 -225.389694)
		(width 0.1143)
		(layer "In15.Cu")
		(net "GMI_CPU0_G1_CPU1_G3_TX_DP<4>")
	)
	(arc
		(start 355.27234 -242.358418)
		(mid 355.116412 -242.054126)
		(end 355.27234 -241.749834)
		(width 0.1143)
		(layer "In15.Cu")
		(net "GMI_CPU0_G1_CPU1_G3_TX_DP<4>")
	)
	(arc
		(start 355.27234 -232.638346)
		(mid 355.116412 -232.334054)
		(end 355.27234 -232.029762)
		(width 0.1143)
		(layer "In15.Cu")
		(net "GMI_CPU0_G1_CPU1_G3_TX_DP<4>")
	)
	(arc
		(start 116.233194 -244.99697)
		(mid 116.385668 -245.294404)
		(end 116.233194 -245.591838)
		(width 0.1143)
		(layer "In15.Cu")
		(net "GMI_CPU0_G1_CPU1_G3_TX_DP<4>")
	)
	(segment
		(start 113.657888 -245.560342)
		(end 114.12474 -245.294404)
		(width 0.12954)
		(layer "F.Cu")
		(net "GMI_CPU0_G1_CPU1_G3_TX_DP<3>")
	)
	(segment
		(start 357.837994 -245.560088)
		(end 357.371142 -245.29415)
		(width 0.12954)
		(layer "F.Cu")
		(net "GMI_CPU0_G1_CPU1_G3_TX_DP<3>")
	)
	(segment
		(start 356.23881 -237.513622)
		(end 356.238048 -237.513114)
		(width 0.1143)
		(layer "In15.Cu")
		(net "GMI_CPU0_G1_CPU1_G3_TX_DP<3>")
	)
	(segment
		(start 355.117654 -224.240852)
		(end 355.116892 -224.225866)
		(width 0.1143)
		(layer "In15.Cu")
		(net "GMI_CPU0_G1_CPU1_G3_TX_DP<3>")
	)
	(segment
		(start 115.212622 -231.988868)
		(end 115.21948 -231.992932)
		(width 0.1143)
		(layer "In15.Cu")
		(net "GMI_CPU0_G1_CPU1_G3_TX_DP<3>")
	)
	(segment
		(start 356.235508 -239.131856)
		(end 356.212394 -239.118394)
		(width 0.1143)
		(layer "In15.Cu")
		(net "GMI_CPU0_G1_CPU1_G3_TX_DP<3>")
	)
	(segment
		(start 115.250722 -235.89742)
		(end 115.249198 -235.898436)
		(width 0.1143)
		(layer "In15.Cu")
		(net "GMI_CPU0_G1_CPU1_G3_TX_DP<3>")
	)
	(segment
		(start 356.276402 -232.67543)
		(end 356.27564 -232.674922)
		(width 0.1143)
		(layer "In15.Cu")
		(net "GMI_CPU0_G1_CPU1_G3_TX_DP<3>")
	)
	(segment
		(start 115.212622 -222.26905)
		(end 115.283488 -222.310198)
		(width 0.1143)
		(layer "In15.Cu")
		(net "GMI_CPU0_G1_CPU1_G3_TX_DP<3>")
	)
	(segment
		(start 356.24516 -242.377214)
		(end 356.244144 -242.376706)
		(width 0.1143)
		(layer "In15.Cu")
		(net "GMI_CPU0_G1_CPU1_G3_TX_DP<3>")
	)
	(segment
		(start 115.25758 -228.77526)
		(end 115.258342 -228.775768)
		(width 0.1143)
		(layer "In15.Cu")
		(net "GMI_CPU0_G1_CPU1_G3_TX_DP<3>")
	)
	(segment
		(start 356.23627 -226.172268)
		(end 356.23373 -226.170998)
		(width 0.1143)
		(layer "In15.Cu")
		(net "GMI_CPU0_G1_CPU1_G3_TX_DP<3>")
	)
	(segment
		(start 356.244144 -230.391716)
		(end 356.28072 -230.37038)
		(width 0.1143)
		(layer "In15.Cu")
		(net "GMI_CPU0_G1_CPU1_G3_TX_DP<3>")
	)
	(segment
		(start 355.30536 -223.91116)
		(end 355.307646 -223.909636)
		(width 0.1143)
		(layer "In15.Cu")
		(net "GMI_CPU0_G1_CPU1_G3_TX_DP<3>")
	)
	(segment
		(start 137.835132 -195.644008)
		(end 118.442486 -211.545424)
		(width 0.14224)
		(layer "In15.Cu")
		(net "GMI_CPU0_G1_CPU1_G3_TX_DP<3>")
	)
	(segment
		(start 115.21948 -231.992932)
		(end 115.220242 -231.99344)
		(width 0.1143)
		(layer "In15.Cu")
		(net "GMI_CPU0_G1_CPU1_G3_TX_DP<3>")
	)
	(segment
		(start 115.251738 -234.2769)
		(end 115.250722 -234.277408)
		(width 0.1143)
		(layer "In15.Cu")
		(net "GMI_CPU0_G1_CPU1_G3_TX_DP<3>")
	)
	(segment
		(start 355.340666 -224.57791)
		(end 355.27488 -224.539556)
		(width 0.1143)
		(layer "In15.Cu")
		(net "GMI_CPU0_G1_CPU1_G3_TX_DP<3>")
	)
	(segment
		(start 115.212622 -236.848904)
		(end 115.21948 -236.852968)
		(width 0.1143)
		(layer "In15.Cu")
		(net "GMI_CPU0_G1_CPU1_G3_TX_DP<3>")
	)
	(segment
		(start 115.25758 -235.255054)
		(end 115.258342 -235.255562)
		(width 0.1143)
		(layer "In15.Cu")
		(net "GMI_CPU0_G1_CPU1_G3_TX_DP<3>")
	)
	(segment
		(start 356.27564 -227.81514)
		(end 356.244144 -227.796852)
		(width 0.1143)
		(layer "In15.Cu")
		(net "GMI_CPU0_G1_CPU1_G3_TX_DP<3>")
	)
	(segment
		(start 356.28326 -232.679494)
		(end 356.276402 -232.67543)
		(width 0.1143)
		(layer "In15.Cu")
		(net "GMI_CPU0_G1_CPU1_G3_TX_DP<3>")
	)
	(segment
		(start 356.239826 -243.994178)
		(end 356.23881 -243.99367)
		(width 0.1143)
		(layer "In15.Cu")
		(net "GMI_CPU0_G1_CPU1_G3_TX_DP<3>")
	)
	(segment
		(start 356.24516 -228.771196)
		(end 356.246684 -228.77018)
		(width 0.1143)
		(layer "In15.Cu")
		(net "GMI_CPU0_G1_CPU1_G3_TX_DP<3>")
	)
	(segment
		(start 356.244144 -243.351558)
		(end 356.24516 -243.35105)
		(width 0.1143)
		(layer "In15.Cu")
		(net "GMI_CPU0_G1_CPU1_G3_TX_DP<3>")
	)
	(segment
		(start 115.255294 -240.11382)
		(end 115.256056 -240.114328)
		(width 0.1143)
		(layer "In15.Cu")
		(net "GMI_CPU0_G1_CPU1_G3_TX_DP<3>")
	)
	(segment
		(start 356.238048 -234.27309)
		(end 356.235508 -234.27182)
		(width 0.1143)
		(layer "In15.Cu")
		(net "GMI_CPU0_G1_CPU1_G3_TX_DP<3>")
	)
	(segment
		(start 115.251738 -227.797106)
		(end 115.250722 -227.797614)
		(width 0.1143)
		(layer "In15.Cu")
		(net "GMI_CPU0_G1_CPU1_G3_TX_DP<3>")
	)
	(segment
		(start 115.2525 -240.112296)
		(end 115.255294 -240.11382)
		(width 0.1143)
		(layer "In15.Cu")
		(net "GMI_CPU0_G1_CPU1_G3_TX_DP<3>")
	)
	(segment
		(start 115.259358 -228.776276)
		(end 115.283488 -228.790246)
		(width 0.1143)
		(layer "In15.Cu")
		(net "GMI_CPU0_G1_CPU1_G3_TX_DP<3>")
	)
	(segment
		(start 355.576886 -221.308676)
		(end 355.576886 -221.128844)
		(width 0.1143)
		(layer "In15.Cu")
		(net "GMI_CPU0_G1_CPU1_G3_TX_DP<3>")
	)
	(segment
		(start 115.250722 -224.55759)
		(end 115.249198 -224.558606)
		(width 0.1143)
		(layer "In15.Cu")
		(net "GMI_CPU0_G1_CPU1_G3_TX_DP<3>")
	)
	(segment
		(start 115.212622 -225.509074)
		(end 115.21948 -225.513138)
		(width 0.1143)
		(layer "In15.Cu")
		(net "GMI_CPU0_G1_CPU1_G3_TX_DP<3>")
	)
	(segment
		(start 308.091586 -177.613056)
		(end 302.911256 -177.613056)
		(width 0.14224)
		(layer "In15.Cu")
		(net "GMI_CPU0_G1_CPU1_G3_TX_DP<3>")
	)
	(segment
		(start 115.2525 -234.276392)
		(end 115.251738 -234.2769)
		(width 0.1143)
		(layer "In15.Cu")
		(net "GMI_CPU0_G1_CPU1_G3_TX_DP<3>")
	)
	(segment
		(start 115.220242 -231.99344)
		(end 115.251738 -232.011728)
		(width 0.1143)
		(layer "In15.Cu")
		(net "GMI_CPU0_G1_CPU1_G3_TX_DP<3>")
	)
	(segment
		(start 356.244144 -241.731546)
		(end 356.24516 -241.731038)
		(width 0.1143)
		(layer "In15.Cu")
		(net "GMI_CPU0_G1_CPU1_G3_TX_DP<3>")
	)
	(segment
		(start 115.259358 -235.25607)
		(end 115.283488 -235.27004)
		(width 0.1143)
		(layer "In15.Cu")
		(net "GMI_CPU0_G1_CPU1_G3_TX_DP<3>")
	)
	(segment
		(start 115.258342 -227.155756)
		(end 115.259358 -227.156264)
		(width 0.1143)
		(layer "In15.Cu")
		(net "GMI_CPU0_G1_CPU1_G3_TX_DP<3>")
	)
	(segment
		(start 356.212394 -232.029762)
		(end 356.244144 -232.011474)
		(width 0.1143)
		(layer "In15.Cu")
		(net "GMI_CPU0_G1_CPU1_G3_TX_DP<3>")
	)
	(segment
		(start 115.2525 -228.772466)
		(end 115.255294 -228.77399)
		(width 0.1143)
		(layer "In15.Cu")
		(net "GMI_CPU0_G1_CPU1_G3_TX_DP<3>")
	)
	(segment
		(start 115.283488 -226.158806)
		(end 115.2525 -226.176586)
		(width 0.1143)
		(layer "In15.Cu")
		(net "GMI_CPU0_G1_CPU1_G3_TX_DP<3>")
	)
	(segment
		(start 356.246684 -239.138206)
		(end 356.24516 -239.13719)
		(width 0.1143)
		(layer "In15.Cu")
		(net "GMI_CPU0_G1_CPU1_G3_TX_DP<3>")
	)
	(segment
		(start 356.235508 -232.651808)
		(end 356.212394 -232.638346)
		(width 0.1143)
		(layer "In15.Cu")
		(net "GMI_CPU0_G1_CPU1_G3_TX_DP<3>")
	)
	(segment
		(start 356.27564 -237.534958)
		(end 356.246684 -237.518194)
		(width 0.1143)
		(layer "In15.Cu")
		(net "GMI_CPU0_G1_CPU1_G3_TX_DP<3>")
	)
	(segment
		(start 356.239826 -242.374166)
		(end 356.23881 -242.373658)
		(width 0.1143)
		(layer "In15.Cu")
		(net "GMI_CPU0_G1_CPU1_G3_TX_DP<3>")
	)
	(segment
		(start 356.28326 -240.779554)
		(end 356.276402 -240.77549)
		(width 0.1143)
		(layer "In15.Cu")
		(net "GMI_CPU0_G1_CPU1_G3_TX_DP<3>")
	)
	(segment
		(start 355.586284 -221.318074)
		(end 355.576886 -221.308676)
		(width 0.1143)
		(layer "In15.Cu")
		(net "GMI_CPU0_G1_CPU1_G3_TX_DP<3>")
	)
	(segment
		(start 356.24516 -238.491014)
		(end 356.246684 -238.489998)
		(width 0.1143)
		(layer "In15.Cu")
		(net "GMI_CPU0_G1_CPU1_G3_TX_DP<3>")
	)
	(segment
		(start 356.27564 -234.294934)
		(end 356.246684 -234.27817)
		(width 0.1143)
		(layer "In15.Cu")
		(net "GMI_CPU0_G1_CPU1_G3_TX_DP<3>")
	)
	(segment
		(start 115.258342 -241.73561)
		(end 115.259358 -241.736118)
		(width 0.1143)
		(layer "In15.Cu")
		(net "GMI_CPU0_G1_CPU1_G3_TX_DP<3>")
	)
	(segment
		(start 115.259358 -236.876082)
		(end 115.283488 -236.890052)
		(width 0.1143)
		(layer "In15.Cu")
		(net "GMI_CPU0_G1_CPU1_G3_TX_DP<3>")
	)
	(segment
		(start 115.251738 -237.516924)
		(end 115.250722 -237.517432)
		(width 0.1143)
		(layer "In15.Cu")
		(net "GMI_CPU0_G1_CPU1_G3_TX_DP<3>")
	)
	(segment
		(start 115.251738 -227.151946)
		(end 115.2525 -227.152454)
		(width 0.1143)
		(layer "In15.Cu")
		(net "GMI_CPU0_G1_CPU1_G3_TX_DP<3>")
	)
	(segment
		(start 356.23881 -234.273598)
		(end 356.238048 -234.27309)
		(width 0.1143)
		(layer "In15.Cu")
		(net "GMI_CPU0_G1_CPU1_G3_TX_DP<3>")
	)
	(segment
		(start 356.244144 -243.996718)
		(end 356.243382 -243.99621)
		(width 0.1143)
		(layer "In15.Cu")
		(net "GMI_CPU0_G1_CPU1_G3_TX_DP<3>")
	)
	(segment
		(start 115.255294 -232.01376)
		(end 115.256056 -232.014268)
		(width 0.1143)
		(layer "In15.Cu")
		(net "GMI_CPU0_G1_CPU1_G3_TX_DP<3>")
	)
	(segment
		(start 356.27564 -239.15497)
		(end 356.246684 -239.138206)
		(width 0.1143)
		(layer "In15.Cu")
		(net "GMI_CPU0_G1_CPU1_G3_TX_DP<3>")
	)
	(segment
		(start 115.251738 -232.656888)
		(end 115.250722 -232.657396)
		(width 0.1143)
		(layer "In15.Cu")
		(net "GMI_CPU0_G1_CPU1_G3_TX_DP<3>")
	)
	(segment
		(start 356.243382 -239.136174)
		(end 356.242112 -239.135412)
		(width 0.1143)
		(layer "In15.Cu")
		(net "GMI_CPU0_G1_CPU1_G3_TX_DP<3>")
	)
	(segment
		(start 115.256056 -236.874304)
		(end 115.25758 -236.875066)
		(width 0.1143)
		(layer "In15.Cu")
		(net "GMI_CPU0_G1_CPU1_G3_TX_DP<3>")
	)
	(segment
		(start 356.212394 -233.649774)
		(end 356.243382 -233.631994)
		(width 0.1143)
		(layer "In15.Cu")
		(net "GMI_CPU0_G1_CPU1_G3_TX_DP<3>")
	)
	(segment
		(start 355.307646 -223.909636)
		(end 355.342444 -223.88957)
		(width 0.1143)
		(layer "In15.Cu")
		(net "GMI_CPU0_G1_CPU1_G3_TX_DP<3>")
	)
	(segment
		(start 356.243382 -235.252006)
		(end 356.244144 -235.251498)
		(width 0.1143)
		(layer "In15.Cu")
		(net "GMI_CPU0_G1_CPU1_G3_TX_DP<3>")
	)
	(segment
		(start 115.283488 -242.358672)
		(end 115.2525 -242.376452)
		(width 0.1143)
		(layer "In15.Cu")
		(net "GMI_CPU0_G1_CPU1_G3_TX_DP<3>")
	)
	(segment
		(start 137.83564 -195.643754)
		(end 137.835132 -195.644008)
		(width 0.14224)
		(layer "In15.Cu")
		(net "GMI_CPU0_G1_CPU1_G3_TX_DP<3>")
	)
	(segment
		(start 313.991498 -180.431186)
		(end 310.593486 -178.507644)
		(width 0.14224)
		(layer "In15.Cu")
		(net "GMI_CPU0_G1_CPU1_G3_TX_DP<3>")
	)
	(segment
		(start 115.251738 -240.111788)
		(end 115.2525 -240.112296)
		(width 0.1143)
		(layer "In15.Cu")
		(net "GMI_CPU0_G1_CPU1_G3_TX_DP<3>")
	)
	(segment
		(start 115.251738 -232.011728)
		(end 115.2525 -232.012236)
		(width 0.1143)
		(layer "In15.Cu")
		(net "GMI_CPU0_G1_CPU1_G3_TX_DP<3>")
	)
	(segment
		(start 115.250722 -227.797614)
		(end 115.249198 -227.79863)
		(width 0.1143)
		(layer "In15.Cu")
		(net "GMI_CPU0_G1_CPU1_G3_TX_DP<3>")
	)
	(segment
		(start 356.243382 -236.872018)
		(end 356.244144 -236.87151)
		(width 0.1143)
		(layer "In15.Cu")
		(net "GMI_CPU0_G1_CPU1_G3_TX_DP<3>")
	)
	(segment
		(start 115.2525 -243.996464)
		(end 115.251738 -243.996972)
		(width 0.1143)
		(layer "In15.Cu")
		(net "GMI_CPU0_G1_CPU1_G3_TX_DP<3>")
	)
	(segment
		(start 356.23881 -242.373658)
		(end 356.238048 -242.37315)
		(width 0.1143)
		(layer "In15.Cu")
		(net "GMI_CPU0_G1_CPU1_G3_TX_DP<3>")
	)
	(segment
		(start 356.235508 -242.37188)
		(end 356.212394 -242.358418)
		(width 0.1143)
		(layer "In15.Cu")
		(net "GMI_CPU0_G1_CPU1_G3_TX_DP<3>")
	)
	(segment
		(start 115.255294 -243.353844)
		(end 115.256056 -243.354352)
		(width 0.1143)
		(layer "In15.Cu")
		(net "GMI_CPU0_G1_CPU1_G3_TX_DP<3>")
	)
	(segment
		(start 356.243382 -240.756186)
		(end 356.242112 -240.755424)
		(width 0.1143)
		(layer "In15.Cu")
		(net "GMI_CPU0_G1_CPU1_G3_TX_DP<3>")
	)
	(segment
		(start 115.255294 -228.77399)
		(end 115.256056 -228.774498)
		(width 0.1143)
		(layer "In15.Cu")
		(net "GMI_CPU0_G1_CPU1_G3_TX_DP<3>")
	)
	(segment
		(start 115.2525 -232.65638)
		(end 115.251738 -232.656888)
		(width 0.1143)
		(layer "In15.Cu")
		(net "GMI_CPU0_G1_CPU1_G3_TX_DP<3>")
	)
	(segment
		(start 356.23754 -226.17303)
		(end 356.23627 -226.172268)
		(width 0.1143)
		(layer "In15.Cu")
		(net "GMI_CPU0_G1_CPU1_G3_TX_DP<3>")
	)
	(segment
		(start 115.256056 -232.014268)
		(end 115.25758 -232.01503)
		(width 0.1143)
		(layer "In15.Cu")
		(net "GMI_CPU0_G1_CPU1_G3_TX_DP<3>")
	)
	(segment
		(start 115.256056 -227.154486)
		(end 115.25758 -227.155248)
		(width 0.1143)
		(layer "In15.Cu")
		(net "GMI_CPU0_G1_CPU1_G3_TX_DP<3>")
	)
	(segment
		(start 356.280466 -227.130864)
		(end 356.28326 -227.128832)
		(width 0.1143)
		(layer "In15.Cu")
		(net "GMI_CPU0_G1_CPU1_G3_TX_DP<3>")
	)
	(segment
		(start 356.28326 -229.43947)
		(end 356.282752 -229.439216)
		(width 0.1143)
		(layer "In15.Cu")
		(net "GMI_CPU0_G1_CPU1_G3_TX_DP<3>")
	)
	(segment
		(start 355.272594 -223.929956)
		(end 355.304344 -223.911668)
		(width 0.1143)
		(layer "In15.Cu")
		(net "GMI_CPU0_G1_CPU1_G3_TX_DP<3>")
	)
	(segment
		(start 115.249198 -232.658412)
		(end 115.212622 -232.679748)
		(width 0.1143)
		(layer "In15.Cu")
		(net "GMI_CPU0_G1_CPU1_G3_TX_DP<3>")
	)
	(segment
		(start 115.250722 -232.657396)
		(end 115.249198 -232.658412)
		(width 0.1143)
		(layer "In15.Cu")
		(net "GMI_CPU0_G1_CPU1_G3_TX_DP<3>")
	)
	(segment
		(start 356.24516 -232.010966)
		(end 356.246684 -232.00995)
		(width 0.1143)
		(layer "In15.Cu")
		(net "GMI_CPU0_G1_CPU1_G3_TX_DP<3>")
	)
	(segment
		(start 356.240588 -237.514638)
		(end 356.239826 -237.51413)
		(width 0.1143)
		(layer "In15.Cu")
		(net "GMI_CPU0_G1_CPU1_G3_TX_DP<3>")
	)
	(segment
		(start 356.212394 -241.749834)
		(end 356.243382 -241.732054)
		(width 0.1143)
		(layer "In15.Cu")
		(net "GMI_CPU0_G1_CPU1_G3_TX_DP<3>")
	)
	(segment
		(start 115.259358 -233.636058)
		(end 115.283488 -233.650028)
		(width 0.1143)
		(layer "In15.Cu")
		(net "GMI_CPU0_G1_CPU1_G3_TX_DP<3>")
	)
	(segment
		(start 115.2525 -237.516416)
		(end 115.251738 -237.516924)
		(width 0.1143)
		(layer "In15.Cu")
		(net "GMI_CPU0_G1_CPU1_G3_TX_DP<3>")
	)
	(segment
		(start 356.235508 -237.511844)
		(end 356.212394 -237.498382)
		(width 0.1143)
		(layer "In15.Cu")
		(net "GMI_CPU0_G1_CPU1_G3_TX_DP<3>")
	)
	(segment
		(start 115.2525 -239.136428)
		(end 115.251738 -239.136936)
		(width 0.1143)
		(layer "In15.Cu")
		(net "GMI_CPU0_G1_CPU1_G3_TX_DP<3>")
	)
	(segment
		(start 356.239826 -234.274106)
		(end 356.23881 -234.273598)
		(width 0.1143)
		(layer "In15.Cu")
		(net "GMI_CPU0_G1_CPU1_G3_TX_DP<3>")
	)
	(segment
		(start 356.714044 -244.806724)
		(end 356.683564 -244.788944)
		(width 0.1143)
		(layer "In15.Cu")
		(net "GMI_CPU0_G1_CPU1_G3_TX_DP<3>")
	)
	(segment
		(start 356.27564 -244.015006)
		(end 356.246684 -243.998242)
		(width 0.1143)
		(layer "In15.Cu")
		(net "GMI_CPU0_G1_CPU1_G3_TX_DP<3>")
	)
	(segment
		(start 356.243382 -235.89615)
		(end 356.242112 -235.895388)
		(width 0.1143)
		(layer "In15.Cu")
		(net "GMI_CPU0_G1_CPU1_G3_TX_DP<3>")
	)
	(segment
		(start 115.2525 -227.796598)
		(end 115.251738 -227.797106)
		(width 0.1143)
		(layer "In15.Cu")
		(net "GMI_CPU0_G1_CPU1_G3_TX_DP<3>")
	)
	(segment
		(start 356.242112 -232.655364)
		(end 356.240588 -232.654602)
		(width 0.1143)
		(layer "In15.Cu")
		(net "GMI_CPU0_G1_CPU1_G3_TX_DP<3>")
	)
	(segment
		(start 356.212394 -228.789992)
		(end 356.244144 -228.771704)
		(width 0.1143)
		(layer "In15.Cu")
		(net "GMI_CPU0_G1_CPU1_G3_TX_DP<3>")
	)
	(segment
		(start 356.244144 -232.011474)
		(end 356.24516 -232.010966)
		(width 0.1143)
		(layer "In15.Cu")
		(net "GMI_CPU0_G1_CPU1_G3_TX_DP<3>")
	)
	(segment
		(start 115.251738 -236.871764)
		(end 115.2525 -236.872272)
		(width 0.1143)
		(layer "In15.Cu")
		(net "GMI_CPU0_G1_CPU1_G3_TX_DP<3>")
	)
	(segment
		(start 356.238048 -232.653078)
		(end 356.235508 -232.651808)
		(width 0.1143)
		(layer "In15.Cu")
		(net "GMI_CPU0_G1_CPU1_G3_TX_DP<3>")
	)
	(segment
		(start 115.251738 -233.63174)
		(end 115.2525 -233.632248)
		(width 0.1143)
		(layer "In15.Cu")
		(net "GMI_CPU0_G1_CPU1_G3_TX_DP<3>")
	)
	(segment
		(start 356.276402 -237.535466)
		(end 356.27564 -237.534958)
		(width 0.1143)
		(layer "In15.Cu")
		(net "GMI_CPU0_G1_CPU1_G3_TX_DP<3>")
	)
	(segment
		(start 356.244144 -236.87151)
		(end 356.24516 -236.871002)
		(width 0.1143)
		(layer "In15.Cu")
		(net "GMI_CPU0_G1_CPU1_G3_TX_DP<3>")
	)
	(segment
		(start 115.220242 -243.333524)
		(end 115.251738 -243.351812)
		(width 0.1143)
		(layer "In15.Cu")
		(net "GMI_CPU0_G1_CPU1_G3_TX_DP<3>")
	)
	(segment
		(start 115.249198 -222.938594)
		(end 115.212622 -222.95993)
		(width 0.1143)
		(layer "In15.Cu")
		(net "GMI_CPU0_G1_CPU1_G3_TX_DP<3>")
	)
	(segment
		(start 356.246684 -240.11001)
		(end 356.28326 -240.088674)
		(width 0.1143)
		(layer "In15.Cu")
		(net "GMI_CPU0_G1_CPU1_G3_TX_DP<3>")
	)
	(segment
		(start 356.242112 -240.755424)
		(end 356.240588 -240.754662)
		(width 0.1143)
		(layer "In15.Cu")
		(net "GMI_CPU0_G1_CPU1_G3_TX_DP<3>")
	)
	(segment
		(start 356.28326 -239.159542)
		(end 356.276402 -239.155478)
		(width 0.1143)
		(layer "In15.Cu")
		(net "GMI_CPU0_G1_CPU1_G3_TX_DP<3>")
	)
	(segment
		(start 356.246684 -226.178364)
		(end 356.24516 -226.177348)
		(width 0.1143)
		(layer "In15.Cu")
		(net "GMI_CPU0_G1_CPU1_G3_TX_DP<3>")
	)
	(segment
		(start 356.246684 -232.00995)
		(end 356.28326 -231.988614)
		(width 0.1143)
		(layer "In15.Cu")
		(net "GMI_CPU0_G1_CPU1_G3_TX_DP<3>")
	)
	(segment
		(start 115.249198 -243.998496)
		(end 115.212622 -244.019832)
		(width 0.1143)
		(layer "In15.Cu")
		(net "GMI_CPU0_G1_CPU1_G3_TX_DP<3>")
	)
	(segment
		(start 356.24516 -226.177348)
		(end 356.244144 -226.17684)
		(width 0.1143)
		(layer "In15.Cu")
		(net "GMI_CPU0_G1_CPU1_G3_TX_DP<3>")
	)
	(segment
		(start 356.235508 -235.891832)
		(end 356.212394 -235.87837)
		(width 0.1143)
		(layer "In15.Cu")
		(net "GMI_CPU0_G1_CPU1_G3_TX_DP<3>")
	)
	(segment
		(start 115.2525 -238.492284)
		(end 115.255294 -238.493808)
		(width 0.1143)
		(layer "In15.Cu")
		(net "GMI_CPU0_G1_CPU1_G3_TX_DP<3>")
	)
	(segment
		(start 115.212622 -238.468916)
		(end 115.21948 -238.47298)
		(width 0.1143)
		(layer "In15.Cu")
		(net "GMI_CPU0_G1_CPU1_G3_TX_DP<3>")
	)
	(segment
		(start 356.23881 -239.133634)
		(end 356.238048 -239.133126)
		(width 0.1143)
		(layer "In15.Cu")
		(net "GMI_CPU0_G1_CPU1_G3_TX_DP<3>")
	)
	(segment
		(start 115.283488 -240.73866)
		(end 115.2525 -240.75644)
		(width 0.1143)
		(layer "In15.Cu")
		(net "GMI_CPU0_G1_CPU1_G3_TX_DP<3>")
	)
	(segment
		(start 356.246684 -237.518194)
		(end 356.24516 -237.517178)
		(width 0.1143)
		(layer "In15.Cu")
		(net "GMI_CPU0_G1_CPU1_G3_TX_DP<3>")
	)
	(segment
		(start 356.243382 -243.99621)
		(end 356.242112 -243.995448)
		(width 0.1143)
		(layer "In15.Cu")
		(net "GMI_CPU0_G1_CPU1_G3_TX_DP<3>")
	)
	(segment
		(start 115.2525 -240.75644)
		(end 115.251738 -240.756948)
		(width 0.1143)
		(layer "In15.Cu")
		(net "GMI_CPU0_G1_CPU1_G3_TX_DP<3>")
	)
	(segment
		(start 356.27564 -242.394994)
		(end 356.246684 -242.37823)
		(width 0.1143)
		(layer "In15.Cu")
		(net "GMI_CPU0_G1_CPU1_G3_TX_DP<3>")
	)
	(segment
		(start 115.256056 -225.534474)
		(end 115.25758 -225.535236)
		(width 0.1143)
		(layer "In15.Cu")
		(net "GMI_CPU0_G1_CPU1_G3_TX_DP<3>")
	)
	(segment
		(start 356.243382 -226.176332)
		(end 356.240588 -226.174808)
		(width 0.1143)
		(layer "In15.Cu")
		(net "GMI_CPU0_G1_CPU1_G3_TX_DP<3>")
	)
	(segment
		(start 356.212394 -243.369846)
		(end 356.243382 -243.352066)
		(width 0.1143)
		(layer "In15.Cu")
		(net "GMI_CPU0_G1_CPU1_G3_TX_DP<3>")
	)
	(segment
		(start 115.283488 -243.978684)
		(end 115.2525 -243.996464)
		(width 0.1143)
		(layer "In15.Cu")
		(net "GMI_CPU0_G1_CPU1_G3_TX_DP<3>")
	)
	(segment
		(start 115.212622 -228.749098)
		(end 115.21948 -228.753162)
		(width 0.1143)
		(layer "In15.Cu")
		(net "GMI_CPU0_G1_CPU1_G3_TX_DP<3>")
	)
	(segment
		(start 115.250722 -234.277408)
		(end 115.249198 -234.278424)
		(width 0.1143)
		(layer "In15.Cu")
		(net "GMI_CPU0_G1_CPU1_G3_TX_DP<3>")
	)
	(segment
		(start 356.246684 -243.350034)
		(end 356.28326 -243.328698)
		(width 0.1143)
		(layer "In15.Cu")
		(net "GMI_CPU0_G1_CPU1_G3_TX_DP<3>")
	)
	(segment
		(start 115.249198 -223.910398)
		(end 115.250722 -223.911414)
		(width 0.1143)
		(layer "In15.Cu")
		(net "GMI_CPU0_G1_CPU1_G3_TX_DP<3>")
	)
	(segment
		(start 115.251738 -223.911922)
		(end 115.283488 -223.93021)
		(width 0.1143)
		(layer "In15.Cu")
		(net "GMI_CPU0_G1_CPU1_G3_TX_DP<3>")
	)
	(segment
		(start 115.220242 -235.233464)
		(end 115.251738 -235.251752)
		(width 0.1143)
		(layer "In15.Cu")
		(net "GMI_CPU0_G1_CPU1_G3_TX_DP<3>")
	)
	(segment
		(start 356.244144 -235.251498)
		(end 356.24516 -235.25099)
		(width 0.1143)
		(layer "In15.Cu")
		(net "GMI_CPU0_G1_CPU1_G3_TX_DP<3>")
	)
	(segment
		(start 115.21948 -236.852968)
		(end 115.220242 -236.853476)
		(width 0.1143)
		(layer "In15.Cu")
		(net "GMI_CPU0_G1_CPU1_G3_TX_DP<3>")
	)
	(segment
		(start 115.251738 -243.996972)
		(end 115.250722 -243.99748)
		(width 0.1143)
		(layer "In15.Cu")
		(net "GMI_CPU0_G1_CPU1_G3_TX_DP<3>")
	)
	(segment
		(start 115.215162 -230.370634)
		(end 115.251738 -230.39197)
		(width 0.1143)
		(layer "In15.Cu")
		(net "GMI_CPU0_G1_CPU1_G3_TX_DP<3>")
	)
	(segment
		(start 355.343968 -222.95993)
		(end 355.273102 -222.918782)
		(width 0.1143)
		(layer "In15.Cu")
		(net "GMI_CPU0_G1_CPU1_G3_TX_DP<3>")
	)
	(segment
		(start 355.27234 -222.918274)
		(end 355.27234 -222.918528)
		(width 0.1143)
		(layer "In15.Cu")
		(net "GMI_CPU0_G1_CPU1_G3_TX_DP<3>")
	)
	(segment
		(start 356.240588 -235.894626)
		(end 356.239826 -235.894118)
		(width 0.1143)
		(layer "In15.Cu")
		(net "GMI_CPU0_G1_CPU1_G3_TX_DP<3>")
	)
	(segment
		(start 115.220242 -228.75367)
		(end 115.251738 -228.771958)
		(width 0.1143)
		(layer "In15.Cu")
		(net "GMI_CPU0_G1_CPU1_G3_TX_DP<3>")
	)
	(segment
		(start 355.813106 -225.389694)
		(end 355.77399 -225.366834)
		(width 0.1143)
		(layer "In15.Cu")
		(net "GMI_CPU0_G1_CPU1_G3_TX_DP<3>")
	)
	(segment
		(start 115.250722 -222.937578)
		(end 115.249198 -222.938594)
		(width 0.1143)
		(layer "In15.Cu")
		(net "GMI_CPU0_G1_CPU1_G3_TX_DP<3>")
	)
	(segment
		(start 115.2525 -224.556574)
		(end 115.251738 -224.557082)
		(width 0.1143)
		(layer "In15.Cu")
		(net "GMI_CPU0_G1_CPU1_G3_TX_DP<3>")
	)
	(segment
		(start 115.250722 -239.137444)
		(end 115.212622 -239.159796)
		(width 0.1143)
		(layer "In15.Cu")
		(net "GMI_CPU0_G1_CPU1_G3_TX_DP<3>")
	)
	(segment
		(start 356.235508 -243.991892)
		(end 356.212394 -243.97843)
		(width 0.1143)
		(layer "In15.Cu")
		(net "GMI_CPU0_G1_CPU1_G3_TX_DP<3>")
	)
	(segment
		(start 115.249198 -226.178618)
		(end 115.212622 -226.199954)
		(width 0.1143)
		(layer "In15.Cu")
		(net "GMI_CPU0_G1_CPU1_G3_TX_DP<3>")
	)
	(segment
		(start 114.812318 -244.789198)
		(end 114.781838 -244.806978)
		(width 0.1143)
		(layer "In15.Cu")
		(net "GMI_CPU0_G1_CPU1_G3_TX_DP<3>")
	)
	(segment
		(start 356.244144 -226.17684)
		(end 356.243382 -226.176332)
		(width 0.1143)
		(layer "In15.Cu")
		(net "GMI_CPU0_G1_CPU1_G3_TX_DP<3>")
	)
	(segment
		(start 355.576886 -221.128844)
		(end 355.622606 -221.083124)
		(width 0.1143)
		(layer "In15.Cu")
		(net "GMI_CPU0_G1_CPU1_G3_TX_DP<3>")
	)
	(segment
		(start 356.24516 -235.25099)
		(end 356.246684 -235.249974)
		(width 0.1143)
		(layer "In15.Cu")
		(net "GMI_CPU0_G1_CPU1_G3_TX_DP<3>")
	)
	(segment
		(start 356.75316 -244.829584)
		(end 356.714044 -244.806724)
		(width 0.1143)
		(layer "In15.Cu")
		(net "GMI_CPU0_G1_CPU1_G3_TX_DP<3>")
	)
	(segment
		(start 115.258342 -225.535744)
		(end 115.259358 -225.536252)
		(width 0.1143)
		(layer "In15.Cu")
		(net "GMI_CPU0_G1_CPU1_G3_TX_DP<3>")
	)
	(segment
		(start 114.781838 -244.806978)
		(end 114.742722 -244.829838)
		(width 0.1143)
		(layer "In15.Cu")
		(net "GMI_CPU0_G1_CPU1_G3_TX_DP<3>")
	)
	(segment
		(start 356.276402 -242.395502)
		(end 356.27564 -242.394994)
		(width 0.1143)
		(layer "In15.Cu")
		(net "GMI_CPU0_G1_CPU1_G3_TX_DP<3>")
	)
	(segment
		(start 115.249198 -237.518448)
		(end 115.212622 -237.539784)
		(width 0.1143)
		(layer "In15.Cu")
		(net "GMI_CPU0_G1_CPU1_G3_TX_DP<3>")
	)
	(segment
		(start 356.244144 -240.756694)
		(end 356.243382 -240.756186)
		(width 0.1143)
		(layer "In15.Cu")
		(net "GMI_CPU0_G1_CPU1_G3_TX_DP<3>")
	)
	(segment
		(start 115.21948 -243.333016)
		(end 115.220242 -243.333524)
		(width 0.1143)
		(layer "In15.Cu")
		(net "GMI_CPU0_G1_CPU1_G3_TX_DP<3>")
	)
	(segment
		(start 356.27564 -232.674922)
		(end 356.246684 -232.658158)
		(width 0.1143)
		(layer "In15.Cu")
		(net "GMI_CPU0_G1_CPU1_G3_TX_DP<3>")
	)
	(segment
		(start 115.256056 -240.114328)
		(end 115.25758 -240.11509)
		(width 0.1143)
		(layer "In15.Cu")
		(net "GMI_CPU0_G1_CPU1_G3_TX_DP<3>")
	)
	(segment
		(start 356.238048 -243.993162)
		(end 356.235508 -243.991892)
		(width 0.1143)
		(layer "In15.Cu")
		(net "GMI_CPU0_G1_CPU1_G3_TX_DP<3>")
	)
	(segment
		(start 356.242112 -235.895388)
		(end 356.240588 -235.894626)
		(width 0.1143)
		(layer "In15.Cu")
		(net "GMI_CPU0_G1_CPU1_G3_TX_DP<3>")
	)
	(segment
		(start 115.256056 -243.354352)
		(end 115.25758 -243.355114)
		(width 0.1143)
		(layer "In15.Cu")
		(net "GMI_CPU0_G1_CPU1_G3_TX_DP<3>")
	)
	(segment
		(start 356.24516 -234.277154)
		(end 356.244144 -234.276646)
		(width 0.1143)
		(layer "In15.Cu")
		(net "GMI_CPU0_G1_CPU1_G3_TX_DP<3>")
	)
	(segment
		(start 115.258342 -233.63555)
		(end 115.259358 -233.636058)
		(width 0.1143)
		(layer "In15.Cu")
		(net "GMI_CPU0_G1_CPU1_G3_TX_DP<3>")
	)
	(segment
		(start 356.244144 -238.491522)
		(end 356.24516 -238.491014)
		(width 0.1143)
		(layer "In15.Cu")
		(net "GMI_CPU0_G1_CPU1_G3_TX_DP<3>")
	)
	(segment
		(start 356.246684 -228.77018)
		(end 356.28326 -228.748844)
		(width 0.1143)
		(layer "In15.Cu")
		(net "GMI_CPU0_G1_CPU1_G3_TX_DP<3>")
	)
	(segment
		(start 356.28326 -234.299506)
		(end 356.276402 -234.295442)
		(width 0.1143)
		(layer "In15.Cu")
		(net "GMI_CPU0_G1_CPU1_G3_TX_DP<3>")
	)
	(segment
		(start 115.251738 -229.416864)
		(end 115.212622 -229.439724)
		(width 0.1143)
		(layer "In15.Cu")
		(net "GMI_CPU0_G1_CPU1_G3_TX_DP<3>")
	)
	(segment
		(start 115.256056 -235.254292)
		(end 115.25758 -235.255054)
		(width 0.1143)
		(layer "In15.Cu")
		(net "GMI_CPU0_G1_CPU1_G3_TX_DP<3>")
	)
	(segment
		(start 356.244144 -232.656634)
		(end 356.243382 -232.656126)
		(width 0.1143)
		(layer "In15.Cu")
		(net "GMI_CPU0_G1_CPU1_G3_TX_DP<3>")
	)
	(segment
		(start 115.25377 -239.135666)
		(end 115.2525 -239.136428)
		(width 0.1143)
		(layer "In15.Cu")
		(net "GMI_CPU0_G1_CPU1_G3_TX_DP<3>")
	)
	(segment
		(start 115.250722 -243.99748)
		(end 115.249198 -243.998496)
		(width 0.1143)
		(layer "In15.Cu")
		(net "GMI_CPU0_G1_CPU1_G3_TX_DP<3>")
	)
	(segment
		(start 115.258342 -240.115598)
		(end 115.259358 -240.116106)
		(width 0.1143)
		(layer "In15.Cu")
		(net "GMI_CPU0_G1_CPU1_G3_TX_DP<3>")
	)
	(segment
		(start 356.240588 -243.994686)
		(end 356.239826 -243.994178)
		(width 0.1143)
		(layer "In15.Cu")
		(net "GMI_CPU0_G1_CPU1_G3_TX_DP<3>")
	)
	(segment
		(start 115.251738 -242.37696)
		(end 115.250722 -242.377468)
		(width 0.1143)
		(layer "In15.Cu")
		(net "GMI_CPU0_G1_CPU1_G3_TX_DP<3>")
	)
	(segment
		(start 356.27564 -240.774982)
		(end 356.246684 -240.758218)
		(width 0.1143)
		(layer "In15.Cu")
		(net "GMI_CPU0_G1_CPU1_G3_TX_DP<3>")
	)
	(segment
		(start 356.212394 -227.16998)
		(end 356.244144 -227.151692)
		(width 0.1143)
		(layer "In15.Cu")
		(net "GMI_CPU0_G1_CPU1_G3_TX_DP<3>")
	)
	(segment
		(start 115.255294 -227.153978)
		(end 115.256056 -227.154486)
		(width 0.1143)
		(layer "In15.Cu")
		(net "GMI_CPU0_G1_CPU1_G3_TX_DP<3>")
	)
	(segment
		(start 115.256056 -233.63428)
		(end 115.25758 -233.635042)
		(width 0.1143)
		(layer "In15.Cu")
		(net "GMI_CPU0_G1_CPU1_G3_TX_DP<3>")
	)
	(segment
		(start 115.251738 -238.491776)
		(end 115.2525 -238.492284)
		(width 0.1143)
		(layer "In15.Cu")
		(net "GMI_CPU0_G1_CPU1_G3_TX_DP<3>")
	)
	(segment
		(start 356.239826 -226.1743)
		(end 356.238302 -226.173538)
		(width 0.1143)
		(layer "In15.Cu")
		(net "GMI_CPU0_G1_CPU1_G3_TX_DP<3>")
	)
	(segment
		(start 115.250722 -237.517432)
		(end 115.249198 -237.518448)
		(width 0.1143)
		(layer "In15.Cu")
		(net "GMI_CPU0_G1_CPU1_G3_TX_DP<3>")
	)
	(segment
		(start 356.23881 -243.99367)
		(end 356.238048 -243.993162)
		(width 0.1143)
		(layer "In15.Cu")
		(net "GMI_CPU0_G1_CPU1_G3_TX_DP<3>")
	)
	(segment
		(start 356.23373 -226.170998)
		(end 356.212394 -226.158552)
		(width 0.1143)
		(layer "In15.Cu")
		(net "GMI_CPU0_G1_CPU1_G3_TX_DP<3>")
	)
	(segment
		(start 115.2525 -227.152454)
		(end 115.255294 -227.153978)
		(width 0.1143)
		(layer "In15.Cu")
		(net "GMI_CPU0_G1_CPU1_G3_TX_DP<3>")
	)
	(segment
		(start 356.242112 -243.995448)
		(end 356.240588 -243.994686)
		(width 0.1143)
		(layer "In15.Cu")
		(net "GMI_CPU0_G1_CPU1_G3_TX_DP<3>")
	)
	(segment
		(start 115.21948 -227.13315)
		(end 115.220242 -227.133658)
		(width 0.1143)
		(layer "In15.Cu")
		(net "GMI_CPU0_G1_CPU1_G3_TX_DP<3>")
	)
	(segment
		(start 357.0732 -245.29415)
		(end 356.990396 -245.211346)
		(width 0.1143)
		(layer "In15.Cu")
		(net "GMI_CPU0_G1_CPU1_G3_TX_DP<3>")
	)
	(segment
		(start 115.25758 -227.155248)
		(end 115.258342 -227.155756)
		(width 0.1143)
		(layer "In15.Cu")
		(net "GMI_CPU0_G1_CPU1_G3_TX_DP<3>")
	)
	(segment
		(start 115.251738 -228.771958)
		(end 115.2525 -228.772466)
		(width 0.1143)
		(layer "In15.Cu")
		(net "GMI_CPU0_G1_CPU1_G3_TX_DP<3>")
	)
	(segment
		(start 115.212622 -227.129086)
		(end 115.21948 -227.13315)
		(width 0.1143)
		(layer "In15.Cu")
		(net "GMI_CPU0_G1_CPU1_G3_TX_DP<3>")
	)
	(segment
		(start 115.256056 -238.494316)
		(end 115.25758 -238.495078)
		(width 0.1143)
		(layer "In15.Cu")
		(net "GMI_CPU0_G1_CPU1_G3_TX_DP<3>")
	)
	(segment
		(start 356.240588 -239.13465)
		(end 356.239826 -239.134142)
		(width 0.1143)
		(layer "In15.Cu")
		(net "GMI_CPU0_G1_CPU1_G3_TX_DP<3>")
	)
	(segment
		(start 356.24516 -235.897166)
		(end 356.244144 -235.896658)
		(width 0.1143)
		(layer "In15.Cu")
		(net "GMI_CPU0_G1_CPU1_G3_TX_DP<3>")
	)
	(segment
		(start 115.283488 -232.6386)
		(end 115.2525 -232.65638)
		(width 0.1143)
		(layer "In15.Cu")
		(net "GMI_CPU0_G1_CPU1_G3_TX_DP<3>")
	)
	(segment
		(start 115.2525 -242.376452)
		(end 115.251738 -242.37696)
		(width 0.1143)
		(layer "In15.Cu")
		(net "GMI_CPU0_G1_CPU1_G3_TX_DP<3>")
	)
	(segment
		(start 356.212394 -240.129822)
		(end 356.243382 -240.112042)
		(width 0.1143)
		(layer "In15.Cu")
		(net "GMI_CPU0_G1_CPU1_G3_TX_DP<3>")
	)
	(segment
		(start 356.239826 -235.894118)
		(end 356.23881 -235.89361)
		(width 0.1143)
		(layer "In15.Cu")
		(net "GMI_CPU0_G1_CPU1_G3_TX_DP<3>")
	)
	(segment
		(start 115.285266 -229.397306)
		(end 115.251738 -229.416864)
		(width 0.1143)
		(layer "In15.Cu")
		(net "GMI_CPU0_G1_CPU1_G3_TX_DP<3>")
	)
	(segment
		(start 115.21948 -228.753162)
		(end 115.220242 -228.75367)
		(width 0.1143)
		(layer "In15.Cu")
		(net "GMI_CPU0_G1_CPU1_G3_TX_DP<3>")
	)
	(segment
		(start 115.259358 -240.116106)
		(end 115.283488 -240.130076)
		(width 0.1143)
		(layer "In15.Cu")
		(net "GMI_CPU0_G1_CPU1_G3_TX_DP<3>")
	)
	(segment
		(start 356.240588 -234.274614)
		(end 356.239826 -234.274106)
		(width 0.1143)
		(layer "In15.Cu")
		(net "GMI_CPU0_G1_CPU1_G3_TX_DP<3>")
	)
	(segment
		(start 356.244144 -233.631486)
		(end 356.24516 -233.630978)
		(width 0.1143)
		(layer "In15.Cu")
		(net "GMI_CPU0_G1_CPU1_G3_TX_DP<3>")
	)
	(segment
		(start 115.285266 -231.017318)
		(end 115.251738 -231.036876)
		(width 0.1143)
		(layer "In15.Cu")
		(net "GMI_CPU0_G1_CPU1_G3_TX_DP<3>")
	)
	(segment
		(start 356.238302 -226.173538)
		(end 356.23754 -226.17303)
		(width 0.1143)
		(layer "In15.Cu")
		(net "GMI_CPU0_G1_CPU1_G3_TX_DP<3>")
	)
	(segment
		(start 115.2525 -233.632248)
		(end 115.255294 -233.633772)
		(width 0.1143)
		(layer "In15.Cu")
		(net "GMI_CPU0_G1_CPU1_G3_TX_DP<3>")
	)
	(segment
		(start 356.246684 -234.27817)
		(end 356.24516 -234.277154)
		(width 0.1143)
		(layer "In15.Cu")
		(net "GMI_CPU0_G1_CPU1_G3_TX_DP<3>")
	)
	(segment
		(start 115.25758 -236.875066)
		(end 115.258342 -236.875574)
		(width 0.1143)
		(layer "In15.Cu")
		(net "GMI_CPU0_G1_CPU1_G3_TX_DP<3>")
	)
	(segment
		(start 115.250722 -240.757456)
		(end 115.249198 -240.758472)
		(width 0.1143)
		(layer "In15.Cu")
		(net "GMI_CPU0_G1_CPU1_G3_TX_DP<3>")
	)
	(segment
		(start 115.212622 -233.60888)
		(end 115.21948 -233.612944)
		(width 0.1143)
		(layer "In15.Cu")
		(net "GMI_CPU0_G1_CPU1_G3_TX_DP<3>")
	)
	(segment
		(start 115.258342 -235.255562)
		(end 115.259358 -235.25607)
		(width 0.1143)
		(layer "In15.Cu")
		(net "GMI_CPU0_G1_CPU1_G3_TX_DP<3>")
	)
	(segment
		(start 114.86515 -220.991938)
		(end 114.86515 -221.020386)
		(width 0.1143)
		(layer "In15.Cu")
		(net "GMI_CPU0_G1_CPU1_G3_TX_DP<3>")
	)
	(segment
		(start 356.238048 -240.753138)
		(end 356.235508 -240.751868)
		(width 0.1143)
		(layer "In15.Cu")
		(net "GMI_CPU0_G1_CPU1_G3_TX_DP<3>")
	)
	(segment
		(start 115.256056 -241.73434)
		(end 115.25758 -241.735102)
		(width 0.1143)
		(layer "In15.Cu")
		(net "GMI_CPU0_G1_CPU1_G3_TX_DP<3>")
	)
	(segment
		(start 115.220242 -240.0935)
		(end 115.251738 -240.111788)
		(width 0.1143)
		(layer "In15.Cu")
		(net "GMI_CPU0_G1_CPU1_G3_TX_DP<3>")
	)
	(segment
		(start 115.25758 -241.735102)
		(end 115.258342 -241.73561)
		(width 0.1143)
		(layer "In15.Cu")
		(net "GMI_CPU0_G1_CPU1_G3_TX_DP<3>")
	)
	(segment
		(start 356.24516 -240.111026)
		(end 356.246684 -240.11001)
		(width 0.1143)
		(layer "In15.Cu")
		(net "GMI_CPU0_G1_CPU1_G3_TX_DP<3>")
	)
	(segment
		(start 356.246684 -235.249974)
		(end 356.28326 -235.228638)
		(width 0.1143)
		(layer "In15.Cu")
		(net "GMI_CPU0_G1_CPU1_G3_TX_DP<3>")
	)
	(segment
		(start 356.243382 -243.352066)
		(end 356.244144 -243.351558)
		(width 0.1143)
		(layer "In15.Cu")
		(net "GMI_CPU0_G1_CPU1_G3_TX_DP<3>")
	)
	(segment
		(start 356.244144 -229.41661)
		(end 356.210616 -229.397052)
		(width 0.1143)
		(layer "In15.Cu")
		(net "GMI_CPU0_G1_CPU1_G3_TX_DP<3>")
	)
	(segment
		(start 115.251738 -241.7318)
		(end 115.2525 -241.732308)
		(width 0.1143)
		(layer "In15.Cu")
		(net "GMI_CPU0_G1_CPU1_G3_TX_DP<3>")
	)
	(segment
		(start 356.243382 -232.656126)
		(end 356.242112 -232.655364)
		(width 0.1143)
		(layer "In15.Cu")
		(net "GMI_CPU0_G1_CPU1_G3_TX_DP<3>")
	)
	(segment
		(start 115.251738 -239.136936)
		(end 115.250722 -239.137444)
		(width 0.1143)
		(layer "In15.Cu")
		(net "GMI_CPU0_G1_CPU1_G3_TX_DP<3>")
	)
	(segment
		(start 356.27564 -235.914946)
		(end 356.246684 -235.898182)
		(width 0.1143)
		(layer "In15.Cu")
		(net "GMI_CPU0_G1_CPU1_G3_TX_DP<3>")
	)
	(segment
		(start 115.220242 -238.473488)
		(end 115.251738 -238.491776)
		(width 0.1143)
		(layer "In15.Cu")
		(net "GMI_CPU0_G1_CPU1_G3_TX_DP<3>")
	)
	(segment
		(start 356.28326 -231.059482)
		(end 356.244144 -231.036622)
		(width 0.1143)
		(layer "In15.Cu")
		(net "GMI_CPU0_G1_CPU1_G3_TX_DP<3>")
	)
	(segment
		(start 356.246684 -240.758218)
		(end 356.24516 -240.757202)
		(width 0.1143)
		(layer "In15.Cu")
		(net "GMI_CPU0_G1_CPU1_G3_TX_DP<3>")
	)
	(segment
		(start 356.24516 -239.13719)
		(end 356.244144 -239.136682)
		(width 0.1143)
		(layer "In15.Cu")
		(net "GMI_CPU0_G1_CPU1_G3_TX_DP<3>")
	)
	(segment
		(start 115.21948 -233.612944)
		(end 115.220242 -233.613452)
		(width 0.1143)
		(layer "In15.Cu")
		(net "GMI_CPU0_G1_CPU1_G3_TX_DP<3>")
	)
	(segment
		(start 356.238048 -237.513114)
		(end 356.235508 -237.511844)
		(width 0.1143)
		(layer "In15.Cu")
		(net "GMI_CPU0_G1_CPU1_G3_TX_DP<3>")
	)
	(segment
		(start 351.60458 -210.410044)
		(end 317.38951 -182.354728)
		(width 0.14224)
		(layer "In15.Cu")
		(net "GMI_CPU0_G1_CPU1_G3_TX_DP<3>")
	)
	(segment
		(start 356.246684 -238.489998)
		(end 356.28326 -238.468662)
		(width 0.1143)
		(layer "In15.Cu")
		(net "GMI_CPU0_G1_CPU1_G3_TX_DP<3>")
	)
	(segment
		(start 356.240588 -240.754662)
		(end 356.239826 -240.754154)
		(width 0.1143)
		(layer "In15.Cu")
		(net "GMI_CPU0_G1_CPU1_G3_TX_DP<3>")
	)
	(segment
		(start 356.24516 -232.657142)
		(end 356.244144 -232.656634)
		(width 0.1143)
		(layer "In15.Cu")
		(net "GMI_CPU0_G1_CPU1_G3_TX_DP<3>")
	)
	(segment
		(start 356.243382 -241.732054)
		(end 356.244144 -241.731546)
		(width 0.1143)
		(layer "In15.Cu")
		(net "GMI_CPU0_G1_CPU1_G3_TX_DP<3>")
	)
	(segment
		(start 115.2525 -241.732308)
		(end 115.255294 -241.733832)
		(width 0.1143)
		(layer "In15.Cu")
		(net "GMI_CPU0_G1_CPU1_G3_TX_DP<3>")
	)
	(segment
		(start 115.220242 -233.613452)
		(end 115.251738 -233.63174)
		(width 0.1143)
		(layer "In15.Cu")
		(net "GMI_CPU0_G1_CPU1_G3_TX_DP<3>")
	)
	(segment
		(start 115.283488 -235.878624)
		(end 115.2525 -235.896404)
		(width 0.1143)
		(layer "In15.Cu")
		(net "GMI_CPU0_G1_CPU1_G3_TX_DP<3>")
	)
	(segment
		(start 356.244144 -237.51667)
		(end 356.243382 -237.516162)
		(width 0.1143)
		(layer "In15.Cu")
		(net "GMI_CPU0_G1_CPU1_G3_TX_DP<3>")
	)
	(segment
		(start 115.220242 -227.133658)
		(end 115.251738 -227.151946)
		(width 0.1143)
		(layer "In15.Cu")
		(net "GMI_CPU0_G1_CPU1_G3_TX_DP<3>")
	)
	(segment
		(start 356.249478 -226.179888)
		(end 356.246684 -226.178364)
		(width 0.1143)
		(layer "In15.Cu")
		(net "GMI_CPU0_G1_CPU1_G3_TX_DP<3>")
	)
	(segment
		(start 356.246684 -232.658158)
		(end 356.24516 -232.657142)
		(width 0.1143)
		(layer "In15.Cu")
		(net "GMI_CPU0_G1_CPU1_G3_TX_DP<3>")
	)
	(segment
		(start 355.586284 -221.80423)
		(end 355.586284 -221.318074)
		(width 0.1143)
		(layer "In15.Cu")
		(net "GMI_CPU0_G1_CPU1_G3_TX_DP<3>")
	)
	(segment
		(start 356.246684 -236.869986)
		(end 356.28326 -236.84865)
		(width 0.1143)
		(layer "In15.Cu")
		(net "GMI_CPU0_G1_CPU1_G3_TX_DP<3>")
	)
	(segment
		(start 356.244144 -228.771704)
		(end 356.24516 -228.771196)
		(width 0.1143)
		(layer "In15.Cu")
		(net "GMI_CPU0_G1_CPU1_G3_TX_DP<3>")
	)
	(segment
		(start 115.2525 -226.176586)
		(end 115.251738 -226.177094)
		(width 0.1143)
		(layer "In15.Cu")
		(net "GMI_CPU0_G1_CPU1_G3_TX_DP<3>")
	)
	(segment
		(start 115.283488 -239.118648)
		(end 115.25377 -239.135666)
		(width 0.1143)
		(layer "In15.Cu")
		(net "GMI_CPU0_G1_CPU1_G3_TX_DP<3>")
	)
	(segment
		(start 356.244144 -231.036622)
		(end 356.210616 -231.017064)
		(width 0.1143)
		(layer "In15.Cu")
		(net "GMI_CPU0_G1_CPU1_G3_TX_DP<3>")
	)
	(segment
		(start 356.243382 -242.376198)
		(end 356.242112 -242.375436)
		(width 0.1143)
		(layer "In15.Cu")
		(net "GMI_CPU0_G1_CPU1_G3_TX_DP<3>")
	)
	(segment
		(start 115.249198 -227.79863)
		(end 115.212622 -227.819966)
		(width 0.1143)
		(layer "In15.Cu")
		(net "GMI_CPU0_G1_CPU1_G3_TX_DP<3>")
	)
	(segment
		(start 115.25758 -243.355114)
		(end 115.258342 -243.355622)
		(width 0.1143)
		(layer "In15.Cu")
		(net "GMI_CPU0_G1_CPU1_G3_TX_DP<3>")
	)
	(segment
		(start 356.242112 -242.375436)
		(end 356.240588 -242.374674)
		(width 0.1143)
		(layer "In15.Cu")
		(net "GMI_CPU0_G1_CPU1_G3_TX_DP<3>")
	)
	(segment
		(start 356.243382 -233.631994)
		(end 356.244144 -233.631486)
		(width 0.1143)
		(layer "In15.Cu")
		(net "GMI_CPU0_G1_CPU1_G3_TX_DP<3>")
	)
	(segment
		(start 115.255294 -241.733832)
		(end 115.256056 -241.73434)
		(width 0.1143)
		(layer "In15.Cu")
		(net "GMI_CPU0_G1_CPU1_G3_TX_DP<3>")
	)
	(segment
		(start 356.239826 -232.654094)
		(end 356.23881 -232.653586)
		(width 0.1143)
		(layer "In15.Cu")
		(net "GMI_CPU0_G1_CPU1_G3_TX_DP<3>")
	)
	(segment
		(start 115.250722 -242.377468)
		(end 115.249198 -242.378484)
		(width 0.1143)
		(layer "In15.Cu")
		(net "GMI_CPU0_G1_CPU1_G3_TX_DP<3>")
	)
	(segment
		(start 115.249198 -240.758472)
		(end 115.212622 -240.779808)
		(width 0.1143)
		(layer "In15.Cu")
		(net "GMI_CPU0_G1_CPU1_G3_TX_DP<3>")
	)
	(segment
		(start 356.243382 -240.112042)
		(end 356.244144 -240.111534)
		(width 0.1143)
		(layer "In15.Cu")
		(net "GMI_CPU0_G1_CPU1_G3_TX_DP<3>")
	)
	(segment
		(start 356.276402 -235.915454)
		(end 356.27564 -235.914946)
		(width 0.1143)
		(layer "In15.Cu")
		(net "GMI_CPU0_G1_CPU1_G3_TX_DP<3>")
	)
	(segment
		(start 115.283488 -222.918782)
		(end 115.2525 -222.936562)
		(width 0.1143)
		(layer "In15.Cu")
		(net "GMI_CPU0_G1_CPU1_G3_TX_DP<3>")
	)
	(segment
		(start 165.429438 -176.810162)
		(end 157.228032 -179.742846)
		(width 0.14224)
		(layer "In15.Cu")
		(net "GMI_CPU0_G1_CPU1_G3_TX_DP<3>")
	)
	(segment
		(start 356.212394 -236.889798)
		(end 356.243382 -236.872018)
		(width 0.1143)
		(layer "In15.Cu")
		(net "GMI_CPU0_G1_CPU1_G3_TX_DP<3>")
	)
	(segment
		(start 115.259358 -238.496094)
		(end 115.283488 -238.510064)
		(width 0.1143)
		(layer "In15.Cu")
		(net "GMI_CPU0_G1_CPU1_G3_TX_DP<3>")
	)
	(segment
		(start 356.239826 -237.51413)
		(end 356.23881 -237.513622)
		(width 0.1143)
		(layer "In15.Cu")
		(net "GMI_CPU0_G1_CPU1_G3_TX_DP<3>")
	)
	(segment
		(start 114.86515 -217.64498)
		(end 114.86515 -220.991938)
		(width 0.14224)
		(layer "In15.Cu")
		(net "GMI_CPU0_G1_CPU1_G3_TX_DP<3>")
	)
	(segment
		(start 115.21948 -225.513138)
		(end 115.220242 -225.513646)
		(width 0.1143)
		(layer "In15.Cu")
		(net "GMI_CPU0_G1_CPU1_G3_TX_DP<3>")
	)
	(segment
		(start 356.28326 -244.019578)
		(end 356.276402 -244.015514)
		(width 0.1143)
		(layer "In15.Cu")
		(net "GMI_CPU0_G1_CPU1_G3_TX_DP<3>")
	)
	(segment
		(start 356.244144 -242.376706)
		(end 356.243382 -242.376198)
		(width 0.1143)
		(layer "In15.Cu")
		(net "GMI_CPU0_G1_CPU1_G3_TX_DP<3>")
	)
	(segment
		(start 355.371654 -222.979742)
		(end 355.343968 -222.95993)
		(width 0.1143)
		(layer "In15.Cu")
		(net "GMI_CPU0_G1_CPU1_G3_TX_DP<3>")
	)
	(segment
		(start 356.276402 -234.295442)
		(end 356.27564 -234.294934)
		(width 0.1143)
		(layer "In15.Cu")
		(net "GMI_CPU0_G1_CPU1_G3_TX_DP<3>")
	)
	(segment
		(start 115.258342 -243.355622)
		(end 115.259358 -243.35613)
		(width 0.1143)
		(layer "In15.Cu")
		(net "GMI_CPU0_G1_CPU1_G3_TX_DP<3>")
	)
	(segment
		(start 115.251738 -235.896912)
		(end 115.250722 -235.89742)
		(width 0.1143)
		(layer "In15.Cu")
		(net "GMI_CPU0_G1_CPU1_G3_TX_DP<3>")
	)
	(segment
		(start 302.911256 -177.613056)
		(end 165.429438 -176.810162)
		(width 0.14224)
		(layer "In15.Cu")
		(net "GMI_CPU0_G1_CPU1_G3_TX_DP<3>")
	)
	(segment
		(start 115.2525 -225.532442)
		(end 115.255294 -225.533966)
		(width 0.1143)
		(layer "In15.Cu")
		(net "GMI_CPU0_G1_CPU1_G3_TX_DP<3>")
	)
	(segment
		(start 115.251738 -222.93707)
		(end 115.250722 -222.937578)
		(width 0.1143)
		(layer "In15.Cu")
		(net "GMI_CPU0_G1_CPU1_G3_TX_DP<3>")
	)
	(segment
		(start 356.276402 -227.815648)
		(end 356.27564 -227.81514)
		(width 0.1143)
		(layer "In15.Cu")
		(net "GMI_CPU0_G1_CPU1_G3_TX_DP<3>")
	)
	(segment
		(start 115.251738 -224.557082)
		(end 115.250722 -224.55759)
		(width 0.1143)
		(layer "In15.Cu")
		(net "GMI_CPU0_G1_CPU1_G3_TX_DP<3>")
	)
	(segment
		(start 115.25758 -225.535236)
		(end 115.258342 -225.535744)
		(width 0.1143)
		(layer "In15.Cu")
		(net "GMI_CPU0_G1_CPU1_G3_TX_DP<3>")
	)
	(segment
		(start 115.249198 -234.278424)
		(end 115.212622 -234.29976)
		(width 0.1143)
		(layer "In15.Cu")
		(net "GMI_CPU0_G1_CPU1_G3_TX_DP<3>")
	)
	(segment
		(start 115.255294 -233.633772)
		(end 115.256056 -233.63428)
		(width 0.1143)
		(layer "In15.Cu")
		(net "GMI_CPU0_G1_CPU1_G3_TX_DP<3>")
	)
	(segment
		(start 356.244144 -240.111534)
		(end 356.24516 -240.111026)
		(width 0.1143)
		(layer "In15.Cu")
		(net "GMI_CPU0_G1_CPU1_G3_TX_DP<3>")
	)
	(segment
		(start 356.28326 -242.399566)
		(end 356.276402 -242.395502)
		(width 0.1143)
		(layer "In15.Cu")
		(net "GMI_CPU0_G1_CPU1_G3_TX_DP<3>")
	)
	(segment
		(start 115.21948 -235.232956)
		(end 115.220242 -235.233464)
		(width 0.1143)
		(layer "In15.Cu")
		(net "GMI_CPU0_G1_CPU1_G3_TX_DP<3>")
	)
	(segment
		(start 115.212622 -240.088928)
		(end 115.21948 -240.092992)
		(width 0.1143)
		(layer "In15.Cu")
		(net "GMI_CPU0_G1_CPU1_G3_TX_DP<3>")
	)
	(segment
		(start 356.212394 -238.50981)
		(end 356.243382 -238.49203)
		(width 0.1143)
		(layer "In15.Cu")
		(net "GMI_CPU0_G1_CPU1_G3_TX_DP<3>")
	)
	(segment
		(start 356.24516 -236.871002)
		(end 356.246684 -236.869986)
		(width 0.1143)
		(layer "In15.Cu")
		(net "GMI_CPU0_G1_CPU1_G3_TX_DP<3>")
	)
	(segment
		(start 115.251738 -225.531934)
		(end 115.2525 -225.532442)
		(width 0.1143)
		(layer "In15.Cu")
		(net "GMI_CPU0_G1_CPU1_G3_TX_DP<3>")
	)
	(segment
		(start 356.212394 -230.410004)
		(end 356.244144 -230.391716)
		(width 0.1143)
		(layer "In15.Cu")
		(net "GMI_CPU0_G1_CPU1_G3_TX_DP<3>")
	)
	(segment
		(start 356.243382 -238.49203)
		(end 356.244144 -238.491522)
		(width 0.1143)
		(layer "In15.Cu")
		(net "GMI_CPU0_G1_CPU1_G3_TX_DP<3>")
	)
	(segment
		(start 356.235508 -234.27182)
		(end 356.212394 -234.258358)
		(width 0.1143)
		(layer "In15.Cu")
		(net "GMI_CPU0_G1_CPU1_G3_TX_DP<3>")
	)
	(segment
		(start 115.2525 -235.896404)
		(end 115.251738 -235.896912)
		(width 0.1143)
		(layer "In15.Cu")
		(net "GMI_CPU0_G1_CPU1_G3_TX_DP<3>")
	)
	(segment
		(start 355.304344 -223.911668)
		(end 355.30536 -223.91116)
		(width 0.1143)
		(layer "In15.Cu")
		(net "GMI_CPU0_G1_CPU1_G3_TX_DP<3>")
	)
	(segment
		(start 115.259358 -243.35613)
		(end 115.283488 -243.3701)
		(width 0.1143)
		(layer "In15.Cu")
		(net "GMI_CPU0_G1_CPU1_G3_TX_DP<3>")
	)
	(segment
		(start 115.251738 -231.036876)
		(end 115.212622 -231.059736)
		(width 0.1143)
		(layer "In15.Cu")
		(net "GMI_CPU0_G1_CPU1_G3_TX_DP<3>")
	)
	(segment
		(start 115.212622 -241.70894)
		(end 115.21948 -241.713004)
		(width 0.1143)
		(layer "In15.Cu")
		(net "GMI_CPU0_G1_CPU1_G3_TX_DP<3>")
	)
	(segment
		(start 356.276402 -240.77549)
		(end 356.27564 -240.774982)
		(width 0.1143)
		(layer "In15.Cu")
		(net "GMI_CPU0_G1_CPU1_G3_TX_DP<3>")
	)
	(segment
		(start 356.238048 -235.893102)
		(end 356.235508 -235.891832)
		(width 0.1143)
		(layer "In15.Cu")
		(net "GMI_CPU0_G1_CPU1_G3_TX_DP<3>")
	)
	(segment
		(start 115.250722 -226.177602)
		(end 115.249198 -226.178618)
		(width 0.1143)
		(layer "In15.Cu")
		(net "GMI_CPU0_G1_CPU1_G3_TX_DP<3>")
	)
	(segment
		(start 115.212622 -235.228892)
		(end 115.21948 -235.232956)
		(width 0.1143)
		(layer "In15.Cu")
		(net "GMI_CPU0_G1_CPU1_G3_TX_DP<3>")
	)
	(segment
		(start 355.273102 -222.918782)
		(end 355.27234 -222.918274)
		(width 0.1143)
		(layer "In15.Cu")
		(net "GMI_CPU0_G1_CPU1_G3_TX_DP<3>")
	)
	(segment
		(start 356.282752 -229.439216)
		(end 356.244144 -229.41661)
		(width 0.1143)
		(layer "In15.Cu")
		(net "GMI_CPU0_G1_CPU1_G3_TX_DP<3>")
	)
	(segment
		(start 356.276402 -244.015514)
		(end 356.27564 -244.015006)
		(width 0.1143)
		(layer "In15.Cu")
		(net "GMI_CPU0_G1_CPU1_G3_TX_DP<3>")
	)
	(segment
		(start 115.212622 -243.328952)
		(end 115.21948 -243.333016)
		(width 0.1143)
		(layer "In15.Cu")
		(net "GMI_CPU0_G1_CPU1_G3_TX_DP<3>")
	)
	(segment
		(start 356.246684 -241.730022)
		(end 356.28326 -241.708686)
		(width 0.1143)
		(layer "In15.Cu")
		(net "GMI_CPU0_G1_CPU1_G3_TX_DP<3>")
	)
	(segment
		(start 114.422682 -245.294404)
		(end 114.12474 -245.294404)
		(width 0.1143)
		(layer "In15.Cu")
		(net "GMI_CPU0_G1_CPU1_G3_TX_DP<3>")
	)
	(segment
		(start 115.249198 -224.558606)
		(end 115.212622 -224.579942)
		(width 0.1143)
		(layer "In15.Cu")
		(net "GMI_CPU0_G1_CPU1_G3_TX_DP<3>")
	)
	(segment
		(start 115.259358 -227.156264)
		(end 115.283488 -227.170234)
		(width 0.1143)
		(layer "In15.Cu")
		(net "GMI_CPU0_G1_CPU1_G3_TX_DP<3>")
	)
	(segment
		(start 356.240588 -232.654602)
		(end 356.239826 -232.654094)
		(width 0.1143)
		(layer "In15.Cu")
		(net "GMI_CPU0_G1_CPU1_G3_TX_DP<3>")
	)
	(segment
		(start 115.283488 -234.258612)
		(end 115.2525 -234.276392)
		(width 0.1143)
		(layer "In15.Cu")
		(net "GMI_CPU0_G1_CPU1_G3_TX_DP<3>")
	)
	(segment
		(start 115.2525 -235.25226)
		(end 115.255294 -235.253784)
		(width 0.1143)
		(layer "In15.Cu")
		(net "GMI_CPU0_G1_CPU1_G3_TX_DP<3>")
	)
	(segment
		(start 115.251738 -226.177094)
		(end 115.250722 -226.177602)
		(width 0.1143)
		(layer "In15.Cu")
		(net "GMI_CPU0_G1_CPU1_G3_TX_DP<3>")
	)
	(segment
		(start 115.255294 -225.533966)
		(end 115.256056 -225.534474)
		(width 0.1143)
		(layer "In15.Cu")
		(net "GMI_CPU0_G1_CPU1_G3_TX_DP<3>")
	)
	(segment
		(start 115.283488 -227.778818)
		(end 115.2525 -227.796598)
		(width 0.1143)
		(layer "In15.Cu")
		(net "GMI_CPU0_G1_CPU1_G3_TX_DP<3>")
	)
	(segment
		(start 356.28326 -235.919518)
		(end 356.276402 -235.915454)
		(width 0.1143)
		(layer "In15.Cu")
		(net "GMI_CPU0_G1_CPU1_G3_TX_DP<3>")
	)
	(segment
		(start 356.235508 -240.751868)
		(end 356.212394 -240.738406)
		(width 0.1143)
		(layer "In15.Cu")
		(net "GMI_CPU0_G1_CPU1_G3_TX_DP<3>")
	)
	(segment
		(start 115.258342 -232.015538)
		(end 115.259358 -232.016046)
		(width 0.1143)
		(layer "In15.Cu")
		(net "GMI_CPU0_G1_CPU1_G3_TX_DP<3>")
	)
	(segment
		(start 356.238048 -242.37315)
		(end 356.235508 -242.37188)
		(width 0.1143)
		(layer "In15.Cu")
		(net "GMI_CPU0_G1_CPU1_G3_TX_DP<3>")
	)
	(segment
		(start 356.244144 -239.136682)
		(end 356.243382 -239.136174)
		(width 0.1143)
		(layer "In15.Cu")
		(net "GMI_CPU0_G1_CPU1_G3_TX_DP<3>")
	)
	(segment
		(start 115.251738 -230.39197)
		(end 115.283488 -230.410258)
		(width 0.1143)
		(layer "In15.Cu")
		(net "GMI_CPU0_G1_CPU1_G3_TX_DP<3>")
	)
	(segment
		(start 115.258342 -236.875574)
		(end 115.259358 -236.876082)
		(width 0.1143)
		(layer "In15.Cu")
		(net "GMI_CPU0_G1_CPU1_G3_TX_DP<3>")
	)
	(segment
		(start 356.28326 -227.819712)
		(end 356.276402 -227.815648)
		(width 0.1143)
		(layer "In15.Cu")
		(net "GMI_CPU0_G1_CPU1_G3_TX_DP<3>")
	)
	(segment
		(start 356.276402 -239.155478)
		(end 356.27564 -239.15497)
		(width 0.1143)
		(layer "In15.Cu")
		(net "GMI_CPU0_G1_CPU1_G3_TX_DP<3>")
	)
	(segment
		(start 355.622606 -218.900248)
		(end 351.60458 -210.410044)
		(width 0.14224)
		(layer "In15.Cu")
		(net "GMI_CPU0_G1_CPU1_G3_TX_DP<3>")
	)
	(segment
		(start 157.228032 -179.742846)
		(end 137.83564 -195.643754)
		(width 0.14224)
		(layer "In15.Cu")
		(net "GMI_CPU0_G1_CPU1_G3_TX_DP<3>")
	)
	(segment
		(start 356.24516 -233.630978)
		(end 356.246684 -233.629962)
		(width 0.1143)
		(layer "In15.Cu")
		(net "GMI_CPU0_G1_CPU1_G3_TX_DP<3>")
	)
	(segment
		(start 356.246684 -243.998242)
		(end 356.24516 -243.997226)
		(width 0.1143)
		(layer "In15.Cu")
		(net "GMI_CPU0_G1_CPU1_G3_TX_DP<3>")
	)
	(segment
		(start 115.255294 -236.873796)
		(end 115.256056 -236.874304)
		(width 0.1143)
		(layer "In15.Cu")
		(net "GMI_CPU0_G1_CPU1_G3_TX_DP<3>")
	)
	(segment
		(start 115.283488 -237.498636)
		(end 115.2525 -237.516416)
		(width 0.1143)
		(layer "In15.Cu")
		(net "GMI_CPU0_G1_CPU1_G3_TX_DP<3>")
	)
	(segment
		(start 115.2525 -232.012236)
		(end 115.255294 -232.01376)
		(width 0.1143)
		(layer "In15.Cu")
		(net "GMI_CPU0_G1_CPU1_G3_TX_DP<3>")
	)
	(segment
		(start 356.242112 -237.5154)
		(end 356.240588 -237.514638)
		(width 0.1143)
		(layer "In15.Cu")
		(net "GMI_CPU0_G1_CPU1_G3_TX_DP<3>")
	)
	(segment
		(start 356.240588 -242.374674)
		(end 356.239826 -242.374166)
		(width 0.1143)
		(layer "In15.Cu")
		(net "GMI_CPU0_G1_CPU1_G3_TX_DP<3>")
	)
	(segment
		(start 115.251738 -235.251752)
		(end 115.2525 -235.25226)
		(width 0.1143)
		(layer "In15.Cu")
		(net "GMI_CPU0_G1_CPU1_G3_TX_DP<3>")
	)
	(segment
		(start 118.442486 -211.545424)
		(end 114.86515 -217.64498)
		(width 0.14224)
		(layer "In15.Cu")
		(net "GMI_CPU0_G1_CPU1_G3_TX_DP<3>")
	)
	(segment
		(start 356.239826 -240.754154)
		(end 356.23881 -240.753646)
		(width 0.1143)
		(layer "In15.Cu")
		(net "GMI_CPU0_G1_CPU1_G3_TX_DP<3>")
	)
	(segment
		(start 115.250722 -223.911414)
		(end 115.251738 -223.911922)
		(width 0.1143)
		(layer "In15.Cu")
		(net "GMI_CPU0_G1_CPU1_G3_TX_DP<3>")
	)
	(segment
		(start 115.255294 -235.253784)
		(end 115.256056 -235.254292)
		(width 0.1143)
		(layer "In15.Cu")
		(net "GMI_CPU0_G1_CPU1_G3_TX_DP<3>")
	)
	(segment
		(start 115.2525 -222.936562)
		(end 115.251738 -222.93707)
		(width 0.1143)
		(layer "In15.Cu")
		(net "GMI_CPU0_G1_CPU1_G3_TX_DP<3>")
	)
	(segment
		(start 115.25758 -232.01503)
		(end 115.258342 -232.015538)
		(width 0.1143)
		(layer "In15.Cu")
		(net "GMI_CPU0_G1_CPU1_G3_TX_DP<3>")
	)
	(segment
		(start 356.24516 -243.35105)
		(end 356.246684 -243.350034)
		(width 0.1143)
		(layer "In15.Cu")
		(net "GMI_CPU0_G1_CPU1_G3_TX_DP<3>")
	)
	(segment
		(start 115.25758 -233.635042)
		(end 115.258342 -233.63555)
		(width 0.1143)
		(layer "In15.Cu")
		(net "GMI_CPU0_G1_CPU1_G3_TX_DP<3>")
	)
	(segment
		(start 356.244144 -227.796852)
		(end 356.212394 -227.778564)
		(width 0.1143)
		(layer "In15.Cu")
		(net "GMI_CPU0_G1_CPU1_G3_TX_DP<3>")
	)
	(segment
		(start 355.77399 -225.366834)
		(end 355.74351 -225.349054)
		(width 0.1143)
		(layer "In15.Cu")
		(net "GMI_CPU0_G1_CPU1_G3_TX_DP<3>")
	)
	(segment
		(start 356.243382 -237.516162)
		(end 356.242112 -237.5154)
		(width 0.1143)
		(layer "In15.Cu")
		(net "GMI_CPU0_G1_CPU1_G3_TX_DP<3>")
	)
	(segment
		(start 115.220242 -241.713512)
		(end 115.251738 -241.7318)
		(width 0.1143)
		(layer "In15.Cu")
		(net "GMI_CPU0_G1_CPU1_G3_TX_DP<3>")
	)
	(segment
		(start 114.86515 -221.020386)
		(end 114.91087 -221.066106)
		(width 0.1143)
		(layer "In15.Cu")
		(net "GMI_CPU0_G1_CPU1_G3_TX_DP<3>")
	)
	(segment
		(start 115.256056 -228.774498)
		(end 115.25758 -228.77526)
		(width 0.1143)
		(layer "In15.Cu")
		(net "GMI_CPU0_G1_CPU1_G3_TX_DP<3>")
	)
	(segment
		(start 115.255294 -238.493808)
		(end 115.256056 -238.494316)
		(width 0.1143)
		(layer "In15.Cu")
		(net "GMI_CPU0_G1_CPU1_G3_TX_DP<3>")
	)
	(segment
		(start 115.2525 -236.872272)
		(end 115.255294 -236.873796)
		(width 0.1143)
		(layer "In15.Cu")
		(net "GMI_CPU0_G1_CPU1_G3_TX_DP<3>")
	)
	(segment
		(start 115.25758 -238.495078)
		(end 115.258342 -238.495586)
		(width 0.1143)
		(layer "In15.Cu")
		(net "GMI_CPU0_G1_CPU1_G3_TX_DP<3>")
	)
	(segment
		(start 115.251738 -243.351812)
		(end 115.2525 -243.35232)
		(width 0.1143)
		(layer "In15.Cu")
		(net "GMI_CPU0_G1_CPU1_G3_TX_DP<3>")
	)
	(segment
		(start 114.969544 -221.336616)
		(end 114.969544 -221.804484)
		(width 0.1143)
		(layer "In15.Cu")
		(net "GMI_CPU0_G1_CPU1_G3_TX_DP<3>")
	)
	(segment
		(start 356.244144 -234.276646)
		(end 356.243382 -234.276138)
		(width 0.1143)
		(layer "In15.Cu")
		(net "GMI_CPU0_G1_CPU1_G3_TX_DP<3>")
	)
	(segment
		(start 115.259358 -241.736118)
		(end 115.283488 -241.750088)
		(width 0.1143)
		(layer "In15.Cu")
		(net "GMI_CPU0_G1_CPU1_G3_TX_DP<3>")
	)
	(segment
		(start 310.593486 -178.507644)
		(end 308.091586 -177.613056)
		(width 0.14224)
		(layer "In15.Cu")
		(net "GMI_CPU0_G1_CPU1_G3_TX_DP<3>")
	)
	(segment
		(start 115.259358 -225.536252)
		(end 115.283488 -225.550222)
		(width 0.1143)
		(layer "In15.Cu")
		(net "GMI_CPU0_G1_CPU1_G3_TX_DP<3>")
	)
	(segment
		(start 115.220242 -236.853476)
		(end 115.251738 -236.871764)
		(width 0.1143)
		(layer "In15.Cu")
		(net "GMI_CPU0_G1_CPU1_G3_TX_DP<3>")
	)
	(segment
		(start 356.246684 -233.629962)
		(end 356.28326 -233.608626)
		(width 0.1143)
		(layer "In15.Cu")
		(net "GMI_CPU0_G1_CPU1_G3_TX_DP<3>")
	)
	(segment
		(start 115.283488 -224.538794)
		(end 115.2525 -224.556574)
		(width 0.1143)
		(layer "In15.Cu")
		(net "GMI_CPU0_G1_CPU1_G3_TX_DP<3>")
	)
	(segment
		(start 115.220242 -225.513646)
		(end 115.251738 -225.531934)
		(width 0.1143)
		(layer "In15.Cu")
		(net "GMI_CPU0_G1_CPU1_G3_TX_DP<3>")
	)
	(segment
		(start 115.258342 -238.495586)
		(end 115.259358 -238.496094)
		(width 0.1143)
		(layer "In15.Cu")
		(net "GMI_CPU0_G1_CPU1_G3_TX_DP<3>")
	)
	(segment
		(start 115.21948 -240.092992)
		(end 115.220242 -240.0935)
		(width 0.1143)
		(layer "In15.Cu")
		(net "GMI_CPU0_G1_CPU1_G3_TX_DP<3>")
	)
	(segment
		(start 317.38951 -182.354728)
		(end 313.991498 -180.430932)
		(width 0.14224)
		(layer "In15.Cu")
		(net "GMI_CPU0_G1_CPU1_G3_TX_DP<3>")
	)
	(segment
		(start 114.505486 -245.2116)
		(end 114.422682 -245.294404)
		(width 0.1143)
		(layer "In15.Cu")
		(net "GMI_CPU0_G1_CPU1_G3_TX_DP<3>")
	)
	(segment
		(start 114.91087 -221.066106)
		(end 114.91087 -221.277942)
		(width 0.1143)
		(layer "In15.Cu")
		(net "GMI_CPU0_G1_CPU1_G3_TX_DP<3>")
	)
	(segment
		(start 115.259358 -232.016046)
		(end 115.283488 -232.030016)
		(width 0.1143)
		(layer "In15.Cu")
		(net "GMI_CPU0_G1_CPU1_G3_TX_DP<3>")
	)
	(segment
		(start 356.240588 -226.174808)
		(end 356.239826 -226.1743)
		(width 0.1143)
		(layer "In15.Cu")
		(net "GMI_CPU0_G1_CPU1_G3_TX_DP<3>")
	)
	(segment
		(start 115.251738 -240.756948)
		(end 115.250722 -240.757456)
		(width 0.1143)
		(layer "In15.Cu")
		(net "GMI_CPU0_G1_CPU1_G3_TX_DP<3>")
	)
	(segment
		(start 115.25758 -240.11509)
		(end 115.258342 -240.115598)
		(width 0.1143)
		(layer "In15.Cu")
		(net "GMI_CPU0_G1_CPU1_G3_TX_DP<3>")
	)
	(segment
		(start 356.23881 -240.753646)
		(end 356.238048 -240.753138)
		(width 0.1143)
		(layer "In15.Cu")
		(net "GMI_CPU0_G1_CPU1_G3_TX_DP<3>")
	)
	(segment
		(start 313.991498 -180.430932)
		(end 313.991498 -180.431186)
		(width 0.14224)
		(layer "In15.Cu")
		(net "GMI_CPU0_G1_CPU1_G3_TX_DP<3>")
	)
	(segment
		(start 115.249198 -235.898436)
		(end 115.212622 -235.919772)
		(width 0.1143)
		(layer "In15.Cu")
		(net "GMI_CPU0_G1_CPU1_G3_TX_DP<3>")
	)
	(segment
		(start 356.242112 -234.275376)
		(end 356.240588 -234.274614)
		(width 0.1143)
		(layer "In15.Cu")
		(net "GMI_CPU0_G1_CPU1_G3_TX_DP<3>")
	)
	(segment
		(start 356.24516 -237.517178)
		(end 356.244144 -237.51667)
		(width 0.1143)
		(layer "In15.Cu")
		(net "GMI_CPU0_G1_CPU1_G3_TX_DP<3>")
	)
	(segment
		(start 115.2525 -243.35232)
		(end 115.255294 -243.353844)
		(width 0.1143)
		(layer "In15.Cu")
		(net "GMI_CPU0_G1_CPU1_G3_TX_DP<3>")
	)
	(segment
		(start 356.239826 -239.134142)
		(end 356.23881 -239.133634)
		(width 0.1143)
		(layer "In15.Cu")
		(net "GMI_CPU0_G1_CPU1_G3_TX_DP<3>")
	)
	(segment
		(start 356.24516 -243.997226)
		(end 356.244144 -243.996718)
		(width 0.1143)
		(layer "In15.Cu")
		(net "GMI_CPU0_G1_CPU1_G3_TX_DP<3>")
	)
	(segment
		(start 115.258342 -228.775768)
		(end 115.259358 -228.776276)
		(width 0.1143)
		(layer "In15.Cu")
		(net "GMI_CPU0_G1_CPU1_G3_TX_DP<3>")
	)
	(segment
		(start 356.238048 -239.133126)
		(end 356.235508 -239.131856)
		(width 0.1143)
		(layer "In15.Cu")
		(net "GMI_CPU0_G1_CPU1_G3_TX_DP<3>")
	)
	(segment
		(start 356.212394 -235.269786)
		(end 356.243382 -235.252006)
		(width 0.1143)
		(layer "In15.Cu")
		(net "GMI_CPU0_G1_CPU1_G3_TX_DP<3>")
	)
	(segment
		(start 356.246684 -242.37823)
		(end 356.24516 -242.377214)
		(width 0.1143)
		(layer "In15.Cu")
		(net "GMI_CPU0_G1_CPU1_G3_TX_DP<3>")
	)
	(segment
		(start 356.244144 -227.151692)
		(end 356.280466 -227.130864)
		(width 0.1143)
		(layer "In15.Cu")
		(net "GMI_CPU0_G1_CPU1_G3_TX_DP<3>")
	)
	(segment
		(start 356.28326 -237.53953)
		(end 356.276402 -237.535466)
		(width 0.1143)
		(layer "In15.Cu")
		(net "GMI_CPU0_G1_CPU1_G3_TX_DP<3>")
	)
	(segment
		(start 356.243382 -234.276138)
		(end 356.242112 -234.275376)
		(width 0.1143)
		(layer "In15.Cu")
		(net "GMI_CPU0_G1_CPU1_G3_TX_DP<3>")
	)
	(segment
		(start 356.24516 -240.757202)
		(end 356.244144 -240.756694)
		(width 0.1143)
		(layer "In15.Cu")
		(net "GMI_CPU0_G1_CPU1_G3_TX_DP<3>")
	)
	(segment
		(start 115.21948 -241.713004)
		(end 115.220242 -241.713512)
		(width 0.1143)
		(layer "In15.Cu")
		(net "GMI_CPU0_G1_CPU1_G3_TX_DP<3>")
	)
	(segment
		(start 356.246684 -235.898182)
		(end 356.24516 -235.897166)
		(width 0.1143)
		(layer "In15.Cu")
		(net "GMI_CPU0_G1_CPU1_G3_TX_DP<3>")
	)
	(segment
		(start 355.342444 -223.88957)
		(end 355.371654 -223.868742)
		(width 0.1143)
		(layer "In15.Cu")
		(net "GMI_CPU0_G1_CPU1_G3_TX_DP<3>")
	)
	(segment
		(start 356.24516 -241.731038)
		(end 356.246684 -241.730022)
		(width 0.1143)
		(layer "In15.Cu")
		(net "GMI_CPU0_G1_CPU1_G3_TX_DP<3>")
	)
	(segment
		(start 115.249198 -242.378484)
		(end 115.212622 -242.39982)
		(width 0.1143)
		(layer "In15.Cu")
		(net "GMI_CPU0_G1_CPU1_G3_TX_DP<3>")
	)
	(segment
		(start 115.212622 -223.889062)
		(end 115.249198 -223.910398)
		(width 0.1143)
		(layer "In15.Cu")
		(net "GMI_CPU0_G1_CPU1_G3_TX_DP<3>")
	)
	(segment
		(start 356.28326 -226.1997)
		(end 356.249478 -226.179888)
		(width 0.1143)
		(layer "In15.Cu")
		(net "GMI_CPU0_G1_CPU1_G3_TX_DP<3>")
	)
	(segment
		(start 114.91087 -221.277942)
		(end 114.969544 -221.336616)
		(width 0.1143)
		(layer "In15.Cu")
		(net "GMI_CPU0_G1_CPU1_G3_TX_DP<3>")
	)
	(segment
		(start 356.23881 -235.89361)
		(end 356.238048 -235.893102)
		(width 0.1143)
		(layer "In15.Cu")
		(net "GMI_CPU0_G1_CPU1_G3_TX_DP<3>")
	)
	(segment
		(start 357.371142 -245.29415)
		(end 357.0732 -245.29415)
		(width 0.1143)
		(layer "In15.Cu")
		(net "GMI_CPU0_G1_CPU1_G3_TX_DP<3>")
	)
	(segment
		(start 356.23881 -232.653586)
		(end 356.238048 -232.653078)
		(width 0.1143)
		(layer "In15.Cu")
		(net "GMI_CPU0_G1_CPU1_G3_TX_DP<3>")
	)
	(segment
		(start 355.622606 -221.083124)
		(end 355.622606 -218.900248)
		(width 0.14224)
		(layer "In15.Cu")
		(net "GMI_CPU0_G1_CPU1_G3_TX_DP<3>")
	)
	(segment
		(start 115.21948 -238.47298)
		(end 115.220242 -238.473488)
		(width 0.1143)
		(layer "In15.Cu")
		(net "GMI_CPU0_G1_CPU1_G3_TX_DP<3>")
	)
	(segment
		(start 356.242112 -239.135412)
		(end 356.240588 -239.13465)
		(width 0.1143)
		(layer "In15.Cu")
		(net "GMI_CPU0_G1_CPU1_G3_TX_DP<3>")
	)
	(segment
		(start 356.244144 -235.896658)
		(end 356.243382 -235.89615)
		(width 0.1143)
		(layer "In15.Cu")
		(net "GMI_CPU0_G1_CPU1_G3_TX_DP<3>")
	)
	(segment
		(start 355.2317 -222.346012)
		(end 355.2952 -222.309436)
		(width 0.1143)
		(layer "In15.Cu")
		(net "GMI_CPU0_G1_CPU1_G3_TX_DP<3>")
	)
	(arc
		(start 356.28326 -243.328698)
		(mid 356.526587 -242.864132)
		(end 356.28326 -242.399566)
		(width 0.1143)
		(layer "In15.Cu")
		(net "GMI_CPU0_G1_CPU1_G3_TX_DP<3>")
	)
	(arc
		(start 115.283488 -228.790246)
		(mid 115.398164 -228.92358)
		(end 115.439444 -229.094538)
		(width 0.1143)
		(layer "In15.Cu")
		(net "GMI_CPU0_G1_CPU1_G3_TX_DP<3>")
	)
	(arc
		(start 115.283488 -225.550222)
		(mid 115.439416 -225.854514)
		(end 115.283488 -226.158806)
		(width 0.1143)
		(layer "In15.Cu")
		(net "GMI_CPU0_G1_CPU1_G3_TX_DP<3>")
	)
	(arc
		(start 115.283488 -236.890052)
		(mid 115.439416 -237.194344)
		(end 115.283488 -237.498636)
		(width 0.1143)
		(layer "In15.Cu")
		(net "GMI_CPU0_G1_CPU1_G3_TX_DP<3>")
	)
	(arc
		(start 356.28326 -236.84865)
		(mid 356.526587 -236.384084)
		(end 356.28326 -235.919518)
		(width 0.1143)
		(layer "In15.Cu")
		(net "GMI_CPU0_G1_CPU1_G3_TX_DP<3>")
	)
	(arc
		(start 356.212394 -237.498382)
		(mid 356.056466 -237.19409)
		(end 356.212394 -236.889798)
		(width 0.1143)
		(layer "In15.Cu")
		(net "GMI_CPU0_G1_CPU1_G3_TX_DP<3>")
	)
	(arc
		(start 356.212394 -227.778564)
		(mid 356.056466 -227.474272)
		(end 356.212394 -227.16998)
		(width 0.1143)
		(layer "In15.Cu")
		(net "GMI_CPU0_G1_CPU1_G3_TX_DP<3>")
	)
	(arc
		(start 356.212394 -235.87837)
		(mid 356.056466 -235.574078)
		(end 356.212394 -235.269786)
		(width 0.1143)
		(layer "In15.Cu")
		(net "GMI_CPU0_G1_CPU1_G3_TX_DP<3>")
	)
	(arc
		(start 356.212394 -232.638346)
		(mid 356.056466 -232.334054)
		(end 356.212394 -232.029762)
		(width 0.1143)
		(layer "In15.Cu")
		(net "GMI_CPU0_G1_CPU1_G3_TX_DP<3>")
	)
	(arc
		(start 115.212622 -231.059736)
		(mid 114.969295 -231.524302)
		(end 115.212622 -231.988868)
		(width 0.1143)
		(layer "In15.Cu")
		(net "GMI_CPU0_G1_CPU1_G3_TX_DP<3>")
	)
	(arc
		(start 356.210616 -229.397052)
		(mid 356.097209 -229.264163)
		(end 356.056438 -229.094284)
		(width 0.1143)
		(layer "In15.Cu")
		(net "GMI_CPU0_G1_CPU1_G3_TX_DP<3>")
	)
	(arc
		(start 356.28326 -233.608626)
		(mid 356.526587 -233.14406)
		(end 356.28326 -232.679494)
		(width 0.1143)
		(layer "In15.Cu")
		(net "GMI_CPU0_G1_CPU1_G3_TX_DP<3>")
	)
	(arc
		(start 114.509296 -245.18874)
		(mid 114.507273 -245.20015)
		(end 114.505486 -245.2116)
		(width 0.1143)
		(layer "In15.Cu")
		(net "GMI_CPU0_G1_CPU1_G3_TX_DP<3>")
	)
	(arc
		(start 115.212622 -234.29976)
		(mid 114.969295 -234.764326)
		(end 115.212622 -235.228892)
		(width 0.1143)
		(layer "In15.Cu")
		(net "GMI_CPU0_G1_CPU1_G3_TX_DP<3>")
	)
	(arc
		(start 356.526592 -229.904036)
		(mid 356.462077 -229.641817)
		(end 356.28326 -229.43947)
		(width 0.1143)
		(layer "In15.Cu")
		(net "GMI_CPU0_G1_CPU1_G3_TX_DP<3>")
	)
	(arc
		(start 356.28326 -240.088674)
		(mid 356.526587 -239.624108)
		(end 356.28326 -239.159542)
		(width 0.1143)
		(layer "In15.Cu")
		(net "GMI_CPU0_G1_CPU1_G3_TX_DP<3>")
	)
	(arc
		(start 356.526592 -244.484144)
		(mid 356.462077 -244.221925)
		(end 356.28326 -244.019578)
		(width 0.1143)
		(layer "In15.Cu")
		(net "GMI_CPU0_G1_CPU1_G3_TX_DP<3>")
	)
	(arc
		(start 115.212622 -235.919772)
		(mid 114.969295 -236.384338)
		(end 115.212622 -236.848904)
		(width 0.1143)
		(layer "In15.Cu")
		(net "GMI_CPU0_G1_CPU1_G3_TX_DP<3>")
	)
	(arc
		(start 356.28326 -235.228638)
		(mid 356.526587 -234.764072)
		(end 356.28326 -234.299506)
		(width 0.1143)
		(layer "In15.Cu")
		(net "GMI_CPU0_G1_CPU1_G3_TX_DP<3>")
	)
	(arc
		(start 356.212394 -242.358418)
		(mid 356.056466 -242.054126)
		(end 356.212394 -241.749834)
		(width 0.1143)
		(layer "In15.Cu")
		(net "GMI_CPU0_G1_CPU1_G3_TX_DP<3>")
	)
	(arc
		(start 115.283488 -222.310198)
		(mid 115.439416 -222.61449)
		(end 115.283488 -222.918782)
		(width 0.1143)
		(layer "In15.Cu")
		(net "GMI_CPU0_G1_CPU1_G3_TX_DP<3>")
	)
	(arc
		(start 356.28326 -227.128832)
		(mid 356.526587 -226.664266)
		(end 356.28326 -226.1997)
		(width 0.1143)
		(layer "In15.Cu")
		(net "GMI_CPU0_G1_CPU1_G3_TX_DP<3>")
	)
	(arc
		(start 355.371654 -223.868742)
		(mid 355.599342 -223.424242)
		(end 355.371654 -222.979742)
		(width 0.1143)
		(layer "In15.Cu")
		(net "GMI_CPU0_G1_CPU1_G3_TX_DP<3>")
	)
	(arc
		(start 115.212622 -227.819966)
		(mid 114.969295 -228.284532)
		(end 115.212622 -228.749098)
		(width 0.1143)
		(layer "In15.Cu")
		(net "GMI_CPU0_G1_CPU1_G3_TX_DP<3>")
	)
	(arc
		(start 115.283488 -227.170234)
		(mid 115.439416 -227.474526)
		(end 115.283488 -227.778818)
		(width 0.1143)
		(layer "In15.Cu")
		(net "GMI_CPU0_G1_CPU1_G3_TX_DP<3>")
	)
	(arc
		(start 115.212622 -244.019832)
		(mid 115.033809 -244.222182)
		(end 114.96929 -244.484398)
		(width 0.1143)
		(layer "In15.Cu")
		(net "GMI_CPU0_G1_CPU1_G3_TX_DP<3>")
	)
	(arc
		(start 356.683564 -244.788944)
		(mid 356.568137 -244.655568)
		(end 356.526592 -244.484144)
		(width 0.1143)
		(layer "In15.Cu")
		(net "GMI_CPU0_G1_CPU1_G3_TX_DP<3>")
	)
	(arc
		(start 115.212622 -242.39982)
		(mid 114.969295 -242.864386)
		(end 115.212622 -243.328952)
		(width 0.1143)
		(layer "In15.Cu")
		(net "GMI_CPU0_G1_CPU1_G3_TX_DP<3>")
	)
	(arc
		(start 356.28326 -231.988614)
		(mid 356.526587 -231.524048)
		(end 356.28326 -231.059482)
		(width 0.1143)
		(layer "In15.Cu")
		(net "GMI_CPU0_G1_CPU1_G3_TX_DP<3>")
	)
	(arc
		(start 115.283488 -230.410258)
		(mid 115.398164 -230.543592)
		(end 115.439444 -230.71455)
		(width 0.1143)
		(layer "In15.Cu")
		(net "GMI_CPU0_G1_CPU1_G3_TX_DP<3>")
	)
	(arc
		(start 115.283488 -233.650028)
		(mid 115.439416 -233.95432)
		(end 115.283488 -234.258612)
		(width 0.1143)
		(layer "In15.Cu")
		(net "GMI_CPU0_G1_CPU1_G3_TX_DP<3>")
	)
	(arc
		(start 114.96929 -244.484398)
		(mid 114.927741 -244.65582)
		(end 114.812318 -244.789198)
		(width 0.1143)
		(layer "In15.Cu")
		(net "GMI_CPU0_G1_CPU1_G3_TX_DP<3>")
	)
	(arc
		(start 355.27234 -222.918528)
		(mid 355.12302 -222.641408)
		(end 355.2317 -222.346012)
		(width 0.1143)
		(layer "In15.Cu")
		(net "GMI_CPU0_G1_CPU1_G3_TX_DP<3>")
	)
	(arc
		(start 356.056438 -229.094284)
		(mid 356.097693 -228.923313)
		(end 356.212394 -228.789992)
		(width 0.1143)
		(layer "In15.Cu")
		(net "GMI_CPU0_G1_CPU1_G3_TX_DP<3>")
	)
	(arc
		(start 114.742722 -244.829838)
		(mid 114.590735 -244.986346)
		(end 114.509296 -245.18874)
		(width 0.1143)
		(layer "In15.Cu")
		(net "GMI_CPU0_G1_CPU1_G3_TX_DP<3>")
	)
	(arc
		(start 114.96929 -229.90429)
		(mid 115.034526 -230.167881)
		(end 115.215162 -230.370634)
		(width 0.1143)
		(layer "In15.Cu")
		(net "GMI_CPU0_G1_CPU1_G3_TX_DP<3>")
	)
	(arc
		(start 355.2952 -222.309436)
		(mid 355.508305 -222.095774)
		(end 355.586284 -221.80423)
		(width 0.1143)
		(layer "In15.Cu")
		(net "GMI_CPU0_G1_CPU1_G3_TX_DP<3>")
	)
	(arc
		(start 115.212622 -232.679748)
		(mid 114.969295 -233.144314)
		(end 115.212622 -233.60888)
		(width 0.1143)
		(layer "In15.Cu")
		(net "GMI_CPU0_G1_CPU1_G3_TX_DP<3>")
	)
	(arc
		(start 115.212622 -240.779808)
		(mid 114.969295 -241.244374)
		(end 115.212622 -241.70894)
		(width 0.1143)
		(layer "In15.Cu")
		(net "GMI_CPU0_G1_CPU1_G3_TX_DP<3>")
	)
	(arc
		(start 356.28326 -228.748844)
		(mid 356.526587 -228.284278)
		(end 356.28326 -227.819712)
		(width 0.1143)
		(layer "In15.Cu")
		(net "GMI_CPU0_G1_CPU1_G3_TX_DP<3>")
	)
	(arc
		(start 356.212394 -243.97843)
		(mid 356.056466 -243.674138)
		(end 356.212394 -243.369846)
		(width 0.1143)
		(layer "In15.Cu")
		(net "GMI_CPU0_G1_CPU1_G3_TX_DP<3>")
	)
	(arc
		(start 115.439444 -230.71455)
		(mid 115.398682 -230.884434)
		(end 115.285266 -231.017318)
		(width 0.1143)
		(layer "In15.Cu")
		(net "GMI_CPU0_G1_CPU1_G3_TX_DP<3>")
	)
	(arc
		(start 115.212622 -226.199954)
		(mid 114.969295 -226.66452)
		(end 115.212622 -227.129086)
		(width 0.1143)
		(layer "In15.Cu")
		(net "GMI_CPU0_G1_CPU1_G3_TX_DP<3>")
	)
	(arc
		(start 356.212394 -239.118394)
		(mid 356.056466 -238.814102)
		(end 356.212394 -238.50981)
		(width 0.1143)
		(layer "In15.Cu")
		(net "GMI_CPU0_G1_CPU1_G3_TX_DP<3>")
	)
	(arc
		(start 115.212622 -224.579942)
		(mid 114.969295 -225.044508)
		(end 115.212622 -225.509074)
		(width 0.1143)
		(layer "In15.Cu")
		(net "GMI_CPU0_G1_CPU1_G3_TX_DP<3>")
	)
	(arc
		(start 356.28072 -230.37038)
		(mid 356.461372 -230.167635)
		(end 356.526592 -229.904036)
		(width 0.1143)
		(layer "In15.Cu")
		(net "GMI_CPU0_G1_CPU1_G3_TX_DP<3>")
	)
	(arc
		(start 355.74351 -225.349054)
		(mid 355.628083 -225.215678)
		(end 355.586538 -225.044254)
		(width 0.1143)
		(layer "In15.Cu")
		(net "GMI_CPU0_G1_CPU1_G3_TX_DP<3>")
	)
	(arc
		(start 355.116892 -224.225866)
		(mid 355.159879 -224.059557)
		(end 355.272594 -223.929956)
		(width 0.1143)
		(layer "In15.Cu")
		(net "GMI_CPU0_G1_CPU1_G3_TX_DP<3>")
	)
	(arc
		(start 355.586538 -225.044254)
		(mid 355.521302 -224.780663)
		(end 355.340666 -224.57791)
		(width 0.1143)
		(layer "In15.Cu")
		(net "GMI_CPU0_G1_CPU1_G3_TX_DP<3>")
	)
	(arc
		(start 115.283488 -223.93021)
		(mid 115.439416 -224.234502)
		(end 115.283488 -224.538794)
		(width 0.1143)
		(layer "In15.Cu")
		(net "GMI_CPU0_G1_CPU1_G3_TX_DP<3>")
	)
	(arc
		(start 356.990396 -245.211346)
		(mid 356.988608 -245.199897)
		(end 356.986586 -245.188486)
		(width 0.1143)
		(layer "In15.Cu")
		(net "GMI_CPU0_G1_CPU1_G3_TX_DP<3>")
	)
	(arc
		(start 115.212622 -222.95993)
		(mid 114.969295 -223.424496)
		(end 115.212622 -223.889062)
		(width 0.1143)
		(layer "In15.Cu")
		(net "GMI_CPU0_G1_CPU1_G3_TX_DP<3>")
	)
	(arc
		(start 356.212394 -226.158552)
		(mid 356.097718 -226.025218)
		(end 356.056438 -225.85426)
		(width 0.1143)
		(layer "In15.Cu")
		(net "GMI_CPU0_G1_CPU1_G3_TX_DP<3>")
	)
	(arc
		(start 356.056438 -230.714296)
		(mid 356.097693 -230.543325)
		(end 356.212394 -230.410004)
		(width 0.1143)
		(layer "In15.Cu")
		(net "GMI_CPU0_G1_CPU1_G3_TX_DP<3>")
	)
	(arc
		(start 115.283488 -235.27004)
		(mid 115.439416 -235.574332)
		(end 115.283488 -235.878624)
		(width 0.1143)
		(layer "In15.Cu")
		(net "GMI_CPU0_G1_CPU1_G3_TX_DP<3>")
	)
	(arc
		(start 356.212394 -234.258358)
		(mid 356.056466 -233.954066)
		(end 356.212394 -233.649774)
		(width 0.1143)
		(layer "In15.Cu")
		(net "GMI_CPU0_G1_CPU1_G3_TX_DP<3>")
	)
	(arc
		(start 115.212622 -239.159796)
		(mid 114.969295 -239.624362)
		(end 115.212622 -240.088928)
		(width 0.1143)
		(layer "In15.Cu")
		(net "GMI_CPU0_G1_CPU1_G3_TX_DP<3>")
	)
	(arc
		(start 115.283488 -232.030016)
		(mid 115.439416 -232.334308)
		(end 115.283488 -232.6386)
		(width 0.1143)
		(layer "In15.Cu")
		(net "GMI_CPU0_G1_CPU1_G3_TX_DP<3>")
	)
	(arc
		(start 115.283488 -240.130076)
		(mid 115.439416 -240.434368)
		(end 115.283488 -240.73866)
		(width 0.1143)
		(layer "In15.Cu")
		(net "GMI_CPU0_G1_CPU1_G3_TX_DP<3>")
	)
	(arc
		(start 115.212622 -229.439724)
		(mid 115.033809 -229.642074)
		(end 114.96929 -229.90429)
		(width 0.1143)
		(layer "In15.Cu")
		(net "GMI_CPU0_G1_CPU1_G3_TX_DP<3>")
	)
	(arc
		(start 356.28326 -238.468662)
		(mid 356.526587 -238.004096)
		(end 356.28326 -237.53953)
		(width 0.1143)
		(layer "In15.Cu")
		(net "GMI_CPU0_G1_CPU1_G3_TX_DP<3>")
	)
	(arc
		(start 355.26726 -224.53346)
		(mid 355.168209 -224.399558)
		(end 355.117654 -224.240852)
		(width 0.1143)
		(layer "In15.Cu")
		(net "GMI_CPU0_G1_CPU1_G3_TX_DP<3>")
	)
	(arc
		(start 355.27488 -224.539556)
		(mid 355.27105 -224.536533)
		(end 355.26726 -224.53346)
		(width 0.1143)
		(layer "In15.Cu")
		(net "GMI_CPU0_G1_CPU1_G3_TX_DP<3>")
	)
	(arc
		(start 356.986586 -245.188486)
		(mid 356.905153 -244.986088)
		(end 356.75316 -244.829584)
		(width 0.1143)
		(layer "In15.Cu")
		(net "GMI_CPU0_G1_CPU1_G3_TX_DP<3>")
	)
	(arc
		(start 356.28326 -241.708686)
		(mid 356.526587 -241.24412)
		(end 356.28326 -240.779554)
		(width 0.1143)
		(layer "In15.Cu")
		(net "GMI_CPU0_G1_CPU1_G3_TX_DP<3>")
	)
	(arc
		(start 115.439444 -229.094538)
		(mid 115.398682 -229.264422)
		(end 115.285266 -229.397306)
		(width 0.1143)
		(layer "In15.Cu")
		(net "GMI_CPU0_G1_CPU1_G3_TX_DP<3>")
	)
	(arc
		(start 356.212394 -240.738406)
		(mid 356.056466 -240.434114)
		(end 356.212394 -240.129822)
		(width 0.1143)
		(layer "In15.Cu")
		(net "GMI_CPU0_G1_CPU1_G3_TX_DP<3>")
	)
	(arc
		(start 115.283488 -238.510064)
		(mid 115.439416 -238.814356)
		(end 115.283488 -239.118648)
		(width 0.1143)
		(layer "In15.Cu")
		(net "GMI_CPU0_G1_CPU1_G3_TX_DP<3>")
	)
	(arc
		(start 115.283488 -243.3701)
		(mid 115.439416 -243.674392)
		(end 115.283488 -243.978684)
		(width 0.1143)
		(layer "In15.Cu")
		(net "GMI_CPU0_G1_CPU1_G3_TX_DP<3>")
	)
	(arc
		(start 356.210616 -231.017064)
		(mid 356.097209 -230.884175)
		(end 356.056438 -230.714296)
		(width 0.1143)
		(layer "In15.Cu")
		(net "GMI_CPU0_G1_CPU1_G3_TX_DP<3>")
	)
	(arc
		(start 115.283488 -241.750088)
		(mid 115.439416 -242.05438)
		(end 115.283488 -242.358672)
		(width 0.1143)
		(layer "In15.Cu")
		(net "GMI_CPU0_G1_CPU1_G3_TX_DP<3>")
	)
	(arc
		(start 114.969544 -221.804484)
		(mid 115.033991 -222.066636)
		(end 115.212622 -222.26905)
		(width 0.1143)
		(layer "In15.Cu")
		(net "GMI_CPU0_G1_CPU1_G3_TX_DP<3>")
	)
	(arc
		(start 356.056438 -225.85426)
		(mid 355.991923 -225.592041)
		(end 355.813106 -225.389694)
		(width 0.1143)
		(layer "In15.Cu")
		(net "GMI_CPU0_G1_CPU1_G3_TX_DP<3>")
	)
	(arc
		(start 115.212622 -237.539784)
		(mid 114.969295 -238.00435)
		(end 115.212622 -238.468916)
		(width 0.1143)
		(layer "In15.Cu")
		(net "GMI_CPU0_G1_CPU1_G3_TX_DP<3>")
	)
	(segment
		(start 357.837994 -243.940076)
		(end 357.371142 -243.674138)
		(width 0.12954)
		(layer "F.Cu")
		(net "GMI_CPU0_G1_CPU1_G3_TX_DP<2>")
	)
	(segment
		(start 113.657888 -243.94033)
		(end 114.12474 -243.674392)
		(width 0.12954)
		(layer "F.Cu")
		(net "GMI_CPU0_G1_CPU1_G3_TX_DP<2>")
	)
	(segment
		(start 357.185722 -243.350542)
		(end 357.22306 -243.328952)
		(width 0.1143)
		(layer "In15.Cu")
		(net "GMI_CPU0_G1_CPU1_G3_TX_DP<2>")
	)
	(segment
		(start 357.182166 -242.375436)
		(end 357.180642 -242.374674)
		(width 0.1143)
		(layer "In15.Cu")
		(net "GMI_CPU0_G1_CPU1_G3_TX_DP<2>")
	)
	(segment
		(start 357.178102 -237.513114)
		(end 357.175562 -237.511844)
		(width 0.1143)
		(layer "In15.Cu")
		(net "GMI_CPU0_G1_CPU1_G3_TX_DP<2>")
	)
	(segment
		(start 357.183436 -233.631994)
		(end 357.184198 -233.631486)
		(width 0.1143)
		(layer "In15.Cu")
		(net "GMI_CPU0_G1_CPU1_G3_TX_DP<2>")
	)
	(segment
		(start 114.258598 -233.599228)
		(end 114.27333 -233.609388)
		(width 0.1143)
		(layer "In15.Cu")
		(net "GMI_CPU0_G1_CPU1_G3_TX_DP<2>")
	)
	(segment
		(start 357.186992 -235.898436)
		(end 357.184198 -235.896658)
		(width 0.1143)
		(layer "In15.Cu")
		(net "GMI_CPU0_G1_CPU1_G3_TX_DP<2>")
	)
	(segment
		(start 114.34318 -227.170234)
		(end 114.343434 -227.170234)
		(width 0.1143)
		(layer "In15.Cu")
		(net "GMI_CPU0_G1_CPU1_G3_TX_DP<2>")
	)
	(segment
		(start 357.17988 -234.274106)
		(end 357.178864 -234.273598)
		(width 0.1143)
		(layer "In15.Cu")
		(net "GMI_CPU0_G1_CPU1_G3_TX_DP<2>")
	)
	(segment
		(start 357.248714 -240.797588)
		(end 357.22306 -240.7793)
		(width 0.1143)
		(layer "In15.Cu")
		(net "GMI_CPU0_G1_CPU1_G3_TX_DP<2>")
	)
	(segment
		(start 357.22052 -237.537752)
		(end 357.184198 -237.51667)
		(width 0.1143)
		(layer "In15.Cu")
		(net "GMI_CPU0_G1_CPU1_G3_TX_DP<2>")
	)
	(segment
		(start 357.22052 -234.297728)
		(end 357.184198 -234.276646)
		(width 0.1143)
		(layer "In15.Cu")
		(net "GMI_CPU0_G1_CPU1_G3_TX_DP<2>")
	)
	(segment
		(start 357.186992 -240.758472)
		(end 357.184198 -240.756694)
		(width 0.1143)
		(layer "In15.Cu")
		(net "GMI_CPU0_G1_CPU1_G3_TX_DP<2>")
	)
	(segment
		(start 357.182166 -243.352828)
		(end 357.183436 -243.352066)
		(width 0.1143)
		(layer "In15.Cu")
		(net "GMI_CPU0_G1_CPU1_G3_TX_DP<2>")
	)
	(segment
		(start 357.22052 -232.677716)
		(end 357.184198 -232.656634)
		(width 0.1143)
		(layer "In15.Cu")
		(net "GMI_CPU0_G1_CPU1_G3_TX_DP<2>")
	)
	(segment
		(start 356.28453 -222.960438)
		(end 356.244144 -222.936816)
		(width 0.1143)
		(layer "In15.Cu")
		(net "GMI_CPU0_G1_CPU1_G3_TX_DP<2>")
	)
	(segment
		(start 114.317018 -238.494824)
		(end 114.31778 -238.495332)
		(width 0.1143)
		(layer "In15.Cu")
		(net "GMI_CPU0_G1_CPU1_G3_TX_DP<2>")
	)
	(segment
		(start 357.178102 -232.653078)
		(end 357.175562 -232.651808)
		(width 0.1143)
		(layer "In15.Cu")
		(net "GMI_CPU0_G1_CPU1_G3_TX_DP<2>")
	)
	(segment
		(start 357.177594 -227.793042)
		(end 357.176832 -227.792534)
		(width 0.1143)
		(layer "In15.Cu")
		(net "GMI_CPU0_G1_CPU1_G3_TX_DP<2>")
	)
	(segment
		(start 156.776166 -178.901852)
		(end 137.103358 -195.032376)
		(width 0.14224)
		(layer "In15.Cu")
		(net "GMI_CPU0_G1_CPU1_G3_TX_DP<2>")
	)
	(segment
		(start 357.182166 -232.012744)
		(end 357.183436 -232.011982)
		(width 0.1143)
		(layer "In15.Cu")
		(net "GMI_CPU0_G1_CPU1_G3_TX_DP<2>")
	)
	(segment
		(start 114.311684 -222.93707)
		(end 114.275362 -222.958152)
		(width 0.1143)
		(layer "In15.Cu")
		(net "GMI_CPU0_G1_CPU1_G3_TX_DP<2>")
	)
	(segment
		(start 113.96599 -221.277942)
		(end 114.02949 -221.341442)
		(width 0.1143)
		(layer "In15.Cu")
		(net "GMI_CPU0_G1_CPU1_G3_TX_DP<2>")
	)
	(segment
		(start 357.152448 -243.369846)
		(end 357.182166 -243.352828)
		(width 0.1143)
		(layer "In15.Cu")
		(net "GMI_CPU0_G1_CPU1_G3_TX_DP<2>")
	)
	(segment
		(start 357.0732 -243.674138)
		(end 357.00335 -243.604288)
		(width 0.1143)
		(layer "In15.Cu")
		(net "GMI_CPU0_G1_CPU1_G3_TX_DP<2>")
	)
	(segment
		(start 356.28453 -223.8883)
		(end 356.28453 -223.888046)
		(width 0.1143)
		(layer "In15.Cu")
		(net "GMI_CPU0_G1_CPU1_G3_TX_DP<2>")
	)
	(segment
		(start 357.172768 -227.790248)
		(end 357.172006 -227.78974)
		(width 0.1143)
		(layer "In15.Cu")
		(net "GMI_CPU0_G1_CPU1_G3_TX_DP<2>")
	)
	(segment
		(start 114.343434 -240.73866)
		(end 114.312446 -240.75644)
		(width 0.1143)
		(layer "In15.Cu")
		(net "GMI_CPU0_G1_CPU1_G3_TX_DP<2>")
	)
	(segment
		(start 357.213154 -229.433882)
		(end 357.152194 -229.398068)
		(width 0.1143)
		(layer "In15.Cu")
		(net "GMI_CPU0_G1_CPU1_G3_TX_DP<2>")
	)
	(segment
		(start 357.17099 -227.789232)
		(end 357.16972 -227.78847)
		(width 0.1143)
		(layer "In15.Cu")
		(net "GMI_CPU0_G1_CPU1_G3_TX_DP<2>")
	)
	(segment
		(start 356.212394 -223.93021)
		(end 356.214172 -223.92894)
		(width 0.1143)
		(layer "In15.Cu")
		(net "GMI_CPU0_G1_CPU1_G3_TX_DP<2>")
	)
	(segment
		(start 357.180642 -232.654602)
		(end 357.17988 -232.654094)
		(width 0.1143)
		(layer "In15.Cu")
		(net "GMI_CPU0_G1_CPU1_G3_TX_DP<2>")
	)
	(segment
		(start 357.178102 -234.27309)
		(end 357.175562 -234.27182)
		(width 0.1143)
		(layer "In15.Cu")
		(net "GMI_CPU0_G1_CPU1_G3_TX_DP<2>")
	)
	(segment
		(start 357.22052 -239.157764)
		(end 357.184198 -239.136682)
		(width 0.1143)
		(layer "In15.Cu")
		(net "GMI_CPU0_G1_CPU1_G3_TX_DP<2>")
	)
	(segment
		(start 114.345212 -231.017318)
		(end 114.270536 -231.06126)
		(width 0.1143)
		(layer "In15.Cu")
		(net "GMI_CPU0_G1_CPU1_G3_TX_DP<2>")
	)
	(segment
		(start 357.251 -235.93933)
		(end 357.22306 -235.919264)
		(width 0.1143)
		(layer "In15.Cu")
		(net "GMI_CPU0_G1_CPU1_G3_TX_DP<2>")
	)
	(segment
		(start 357.183436 -237.516162)
		(end 357.182166 -237.5154)
		(width 0.1143)
		(layer "In15.Cu")
		(net "GMI_CPU0_G1_CPU1_G3_TX_DP<2>")
	)
	(segment
		(start 357.15067 -231.017064)
		(end 357.150416 -231.017064)
		(width 0.1143)
		(layer "In15.Cu")
		(net "GMI_CPU0_G1_CPU1_G3_TX_DP<2>")
	)
	(segment
		(start 357.184198 -226.17684)
		(end 357.179372 -226.174046)
		(width 0.1143)
		(layer "In15.Cu")
		(net "GMI_CPU0_G1_CPU1_G3_TX_DP<2>")
	)
	(segment
		(start 114.34318 -232.030016)
		(end 114.343434 -232.030016)
		(width 0.1143)
		(layer "In15.Cu")
		(net "GMI_CPU0_G1_CPU1_G3_TX_DP<2>")
	)
	(segment
		(start 114.343434 -239.118648)
		(end 114.273076 -239.159288)
		(width 0.1143)
		(layer "In15.Cu")
		(net "GMI_CPU0_G1_CPU1_G3_TX_DP<2>")
	)
	(segment
		(start 357.17988 -232.654094)
		(end 357.178864 -232.653586)
		(width 0.1143)
		(layer "In15.Cu")
		(net "GMI_CPU0_G1_CPU1_G3_TX_DP<2>")
	)
	(segment
		(start 114.273838 -224.57918)
		(end 114.260122 -224.588578)
		(width 0.1143)
		(layer "In15.Cu")
		(net "GMI_CPU0_G1_CPU1_G3_TX_DP<2>")
	)
	(segment
		(start 114.332766 -242.364768)
		(end 114.311684 -242.37696)
		(width 0.1143)
		(layer "In15.Cu")
		(net "GMI_CPU0_G1_CPU1_G3_TX_DP<2>")
	)
	(segment
		(start 114.31143 -238.491776)
		(end 114.311684 -238.491776)
		(width 0.1143)
		(layer "In15.Cu")
		(net "GMI_CPU0_G1_CPU1_G3_TX_DP<2>")
	)
	(segment
		(start 357.180642 -237.514638)
		(end 357.17988 -237.51413)
		(width 0.1143)
		(layer "In15.Cu")
		(net "GMI_CPU0_G1_CPU1_G3_TX_DP<2>")
	)
	(segment
		(start 357.185722 -241.73053)
		(end 357.22306 -241.70894)
		(width 0.1143)
		(layer "In15.Cu")
		(net "GMI_CPU0_G1_CPU1_G3_TX_DP<2>")
	)
	(segment
		(start 114.311684 -241.7318)
		(end 114.343434 -241.750088)
		(width 0.1143)
		(layer "In15.Cu")
		(net "GMI_CPU0_G1_CPU1_G3_TX_DP<2>")
	)
	(segment
		(start 357.17988 -240.754154)
		(end 357.178864 -240.753646)
		(width 0.1143)
		(layer "In15.Cu")
		(net "GMI_CPU0_G1_CPU1_G3_TX_DP<2>")
	)
	(segment
		(start 114.343434 -237.498636)
		(end 114.333528 -237.504224)
		(width 0.1143)
		(layer "In15.Cu")
		(net "GMI_CPU0_G1_CPU1_G3_TX_DP<2>")
	)
	(segment
		(start 114.31524 -238.493808)
		(end 114.316002 -238.494316)
		(width 0.1143)
		(layer "In15.Cu")
		(net "GMI_CPU0_G1_CPU1_G3_TX_DP<2>")
	)
	(segment
		(start 357.182166 -235.252768)
		(end 357.183436 -235.252006)
		(width 0.1143)
		(layer "In15.Cu")
		(net "GMI_CPU0_G1_CPU1_G3_TX_DP<2>")
	)
	(segment
		(start 357.17861 -226.173538)
		(end 357.177594 -226.17303)
		(width 0.1143)
		(layer "In15.Cu")
		(net "GMI_CPU0_G1_CPU1_G3_TX_DP<2>")
	)
	(segment
		(start 357.183436 -235.89615)
		(end 357.182166 -235.895388)
		(width 0.1143)
		(layer "In15.Cu")
		(net "GMI_CPU0_G1_CPU1_G3_TX_DP<2>")
	)
	(segment
		(start 356.521512 -221.128844)
		(end 356.567232 -221.083124)
		(width 0.1143)
		(layer "In15.Cu")
		(net "GMI_CPU0_G1_CPU1_G3_TX_DP<2>")
	)
	(segment
		(start 357.22306 -235.919264)
		(end 357.186992 -235.898436)
		(width 0.1143)
		(layer "In15.Cu")
		(net "GMI_CPU0_G1_CPU1_G3_TX_DP<2>")
	)
	(segment
		(start 357.184198 -238.491522)
		(end 357.22052 -238.47044)
		(width 0.1143)
		(layer "In15.Cu")
		(net "GMI_CPU0_G1_CPU1_G3_TX_DP<2>")
	)
	(segment
		(start 114.34318 -235.27004)
		(end 114.343434 -235.27004)
		(width 0.1143)
		(layer "In15.Cu")
		(net "GMI_CPU0_G1_CPU1_G3_TX_DP<2>")
	)
	(segment
		(start 357.184198 -240.756694)
		(end 357.183436 -240.756186)
		(width 0.1143)
		(layer "In15.Cu")
		(net "GMI_CPU0_G1_CPU1_G3_TX_DP<2>")
	)
	(segment
		(start 114.343434 -234.258612)
		(end 114.27206 -234.300014)
		(width 0.1143)
		(layer "In15.Cu")
		(net "GMI_CPU0_G1_CPU1_G3_TX_DP<2>")
	)
	(segment
		(start 114.272568 -222.26905)
		(end 114.343434 -222.310198)
		(width 0.1143)
		(layer "In15.Cu")
		(net "GMI_CPU0_G1_CPU1_G3_TX_DP<2>")
	)
	(segment
		(start 114.311684 -238.491776)
		(end 114.312446 -238.492284)
		(width 0.1143)
		(layer "In15.Cu")
		(net "GMI_CPU0_G1_CPU1_G3_TX_DP<2>")
	)
	(segment
		(start 114.273584 -230.369872)
		(end 114.32794 -230.401114)
		(width 0.1143)
		(layer "In15.Cu")
		(net "GMI_CPU0_G1_CPU1_G3_TX_DP<2>")
	)
	(segment
		(start 357.180642 -240.754662)
		(end 357.17988 -240.754154)
		(width 0.1143)
		(layer "In15.Cu")
		(net "GMI_CPU0_G1_CPU1_G3_TX_DP<2>")
	)
	(segment
		(start 114.313462 -238.492792)
		(end 114.314224 -238.4933)
		(width 0.1143)
		(layer "In15.Cu")
		(net "GMI_CPU0_G1_CPU1_G3_TX_DP<2>")
	)
	(segment
		(start 114.27333 -233.609388)
		(end 114.34318 -233.650028)
		(width 0.1143)
		(layer "In15.Cu")
		(net "GMI_CPU0_G1_CPU1_G3_TX_DP<2>")
	)
	(segment
		(start 357.183436 -235.252006)
		(end 357.184198 -235.251498)
		(width 0.1143)
		(layer "In15.Cu")
		(net "GMI_CPU0_G1_CPU1_G3_TX_DP<2>")
	)
	(segment
		(start 356.209346 -222.31223)
		(end 356.212394 -222.309944)
		(width 0.1143)
		(layer "In15.Cu")
		(net "GMI_CPU0_G1_CPU1_G3_TX_DP<2>")
	)
	(segment
		(start 357.178864 -235.89361)
		(end 357.178102 -235.893102)
		(width 0.1143)
		(layer "In15.Cu")
		(net "GMI_CPU0_G1_CPU1_G3_TX_DP<2>")
	)
	(segment
		(start 114.422682 -243.674392)
		(end 114.12474 -243.674392)
		(width 0.1143)
		(layer "In15.Cu")
		(net "GMI_CPU0_G1_CPU1_G3_TX_DP<2>")
	)
	(segment
		(start 113.92027 -221.020386)
		(end 113.96599 -221.066106)
		(width 0.1143)
		(layer "In15.Cu")
		(net "GMI_CPU0_G1_CPU1_G3_TX_DP<2>")
	)
	(segment
		(start 114.333528 -237.504224)
		(end 114.332766 -237.504732)
		(width 0.1143)
		(layer "In15.Cu")
		(net "GMI_CPU0_G1_CPU1_G3_TX_DP<2>")
	)
	(segment
		(start 356.246684 -222.290132)
		(end 356.28326 -222.268796)
		(width 0.1143)
		(layer "In15.Cu")
		(net "GMI_CPU0_G1_CPU1_G3_TX_DP<2>")
	)
	(segment
		(start 357.184198 -227.796852)
		(end 357.183436 -227.796344)
		(width 0.1143)
		(layer "In15.Cu")
		(net "GMI_CPU0_G1_CPU1_G3_TX_DP<2>")
	)
	(segment
		(start 356.244144 -222.936816)
		(end 356.212394 -222.918528)
		(width 0.1143)
		(layer "In15.Cu")
		(net "GMI_CPU0_G1_CPU1_G3_TX_DP<2>")
	)
	(segment
		(start 114.311684 -228.771958)
		(end 114.343434 -228.790246)
		(width 0.1143)
		(layer "In15.Cu")
		(net "GMI_CPU0_G1_CPU1_G3_TX_DP<2>")
	)
	(segment
		(start 357.178864 -240.753646)
		(end 357.178102 -240.753138)
		(width 0.1143)
		(layer "In15.Cu")
		(net "GMI_CPU0_G1_CPU1_G3_TX_DP<2>")
	)
	(segment
		(start 357.180642 -239.13465)
		(end 357.17988 -239.134142)
		(width 0.1143)
		(layer "In15.Cu")
		(net "GMI_CPU0_G1_CPU1_G3_TX_DP<2>")
	)
	(segment
		(start 357.182166 -228.772974)
		(end 357.183436 -228.772212)
		(width 0.1143)
		(layer "In15.Cu")
		(net "GMI_CPU0_G1_CPU1_G3_TX_DP<2>")
	)
	(segment
		(start 357.174292 -227.79101)
		(end 357.172768 -227.790248)
		(width 0.1143)
		(layer "In15.Cu")
		(net "GMI_CPU0_G1_CPU1_G3_TX_DP<2>")
	)
	(segment
		(start 356.526592 -221.313756)
		(end 356.521512 -221.308676)
		(width 0.1143)
		(layer "In15.Cu")
		(net "GMI_CPU0_G1_CPU1_G3_TX_DP<2>")
	)
	(segment
		(start 357.182166 -234.275376)
		(end 357.180642 -234.274614)
		(width 0.1143)
		(layer "In15.Cu")
		(net "GMI_CPU0_G1_CPU1_G3_TX_DP<2>")
	)
	(segment
		(start 117.430042 -211.163662)
		(end 113.92027 -217.144346)
		(width 0.14224)
		(layer "In15.Cu")
		(net "GMI_CPU0_G1_CPU1_G3_TX_DP<2>")
	)
	(segment
		(start 357.168704 -227.787962)
		(end 357.152448 -227.778564)
		(width 0.1143)
		(layer "In15.Cu")
		(net "GMI_CPU0_G1_CPU1_G3_TX_DP<2>")
	)
	(segment
		(start 114.02949 -221.341442)
		(end 114.02949 -221.804484)
		(width 0.1143)
		(layer "In15.Cu")
		(net "GMI_CPU0_G1_CPU1_G3_TX_DP<2>")
	)
	(segment
		(start 114.02949 -231.524302)
		(end 114.02949 -231.53116)
		(width 0.1143)
		(layer "In15.Cu")
		(net "GMI_CPU0_G1_CPU1_G3_TX_DP<2>")
	)
	(segment
		(start 114.30889 -241.730276)
		(end 114.311684 -241.7318)
		(width 0.1143)
		(layer "In15.Cu")
		(net "GMI_CPU0_G1_CPU1_G3_TX_DP<2>")
	)
	(segment
		(start 357.178102 -240.753138)
		(end 357.175562 -240.751868)
		(width 0.1143)
		(layer "In15.Cu")
		(net "GMI_CPU0_G1_CPU1_G3_TX_DP<2>")
	)
	(segment
		(start 114.311684 -223.911922)
		(end 114.343434 -223.93021)
		(width 0.1143)
		(layer "In15.Cu")
		(net "GMI_CPU0_G1_CPU1_G3_TX_DP<2>")
	)
	(segment
		(start 356.75316 -225.389694)
		(end 356.682548 -225.348292)
		(width 0.1143)
		(layer "In15.Cu")
		(net "GMI_CPU0_G1_CPU1_G3_TX_DP<2>")
	)
	(segment
		(start 357.177594 -226.17303)
		(end 357.152448 -226.158552)
		(width 0.1143)
		(layer "In15.Cu")
		(net "GMI_CPU0_G1_CPU1_G3_TX_DP<2>")
	)
	(segment
		(start 114.343434 -226.158806)
		(end 114.27333 -226.199446)
		(width 0.1143)
		(layer "In15.Cu")
		(net "GMI_CPU0_G1_CPU1_G3_TX_DP<2>")
	)
	(segment
		(start 357.17861 -227.79355)
		(end 357.177594 -227.793042)
		(width 0.1143)
		(layer "In15.Cu")
		(net "GMI_CPU0_G1_CPU1_G3_TX_DP<2>")
	)
	(segment
		(start 114.343434 -242.358672)
		(end 114.333528 -242.36426)
		(width 0.1143)
		(layer "In15.Cu")
		(net "GMI_CPU0_G1_CPU1_G3_TX_DP<2>")
	)
	(segment
		(start 357.16972 -227.78847)
		(end 357.168704 -227.787962)
		(width 0.1143)
		(layer "In15.Cu")
		(net "GMI_CPU0_G1_CPU1_G3_TX_DP<2>")
	)
	(segment
		(start 356.521512 -221.308676)
		(end 356.521512 -221.128844)
		(width 0.1143)
		(layer "In15.Cu")
		(net "GMI_CPU0_G1_CPU1_G3_TX_DP<2>")
	)
	(segment
		(start 357.17988 -237.51413)
		(end 357.178864 -237.513622)
		(width 0.1143)
		(layer "In15.Cu")
		(net "GMI_CPU0_G1_CPU1_G3_TX_DP<2>")
	)
	(segment
		(start 357.183436 -227.796344)
		(end 357.18242 -227.795836)
		(width 0.1143)
		(layer "In15.Cu")
		(net "GMI_CPU0_G1_CPU1_G3_TX_DP<2>")
	)
	(segment
		(start 114.343434 -222.918782)
		(end 114.311684 -222.93707)
		(width 0.1143)
		(layer "In15.Cu")
		(net "GMI_CPU0_G1_CPU1_G3_TX_DP<2>")
	)
	(segment
		(start 308.443884 -176.673256)
		(end 302.914304 -176.673256)
		(width 0.14224)
		(layer "In15.Cu")
		(net "GMI_CPU0_G1_CPU1_G3_TX_DP<2>")
	)
	(segment
		(start 357.184706 -227.796852)
		(end 357.184198 -227.796852)
		(width 0.1143)
		(layer "In15.Cu")
		(net "GMI_CPU0_G1_CPU1_G3_TX_DP<2>")
	)
	(segment
		(start 356.212394 -222.309944)
		(end 356.244144 -222.291656)
		(width 0.1143)
		(layer "In15.Cu")
		(net "GMI_CPU0_G1_CPU1_G3_TX_DP<2>")
	)
	(segment
		(start 114.311684 -235.896912)
		(end 114.275362 -235.917994)
		(width 0.1143)
		(layer "In15.Cu")
		(net "GMI_CPU0_G1_CPU1_G3_TX_DP<2>")
	)
	(segment
		(start 114.312446 -238.492284)
		(end 114.313462 -238.492792)
		(width 0.1143)
		(layer "In15.Cu")
		(net "GMI_CPU0_G1_CPU1_G3_TX_DP<2>")
	)
	(segment
		(start 357.184198 -231.036622)
		(end 357.15067 -231.017064)
		(width 0.1143)
		(layer "In15.Cu")
		(net "GMI_CPU0_G1_CPU1_G3_TX_DP<2>")
	)
	(segment
		(start 357.154226 -230.408988)
		(end 357.229664 -230.3653)
		(width 0.1143)
		(layer "In15.Cu")
		(net "GMI_CPU0_G1_CPU1_G3_TX_DP<2>")
	)
	(segment
		(start 114.314224 -238.4933)
		(end 114.31524 -238.493808)
		(width 0.1143)
		(layer "In15.Cu")
		(net "GMI_CPU0_G1_CPU1_G3_TX_DP<2>")
	)
	(segment
		(start 357.183436 -238.49203)
		(end 357.184198 -238.491522)
		(width 0.1143)
		(layer "In15.Cu")
		(net "GMI_CPU0_G1_CPU1_G3_TX_DP<2>")
	)
	(segment
		(start 356.056438 -224.234248)
		(end 356.056438 -224.232978)
		(width 0.1143)
		(layer "In15.Cu")
		(net "GMI_CPU0_G1_CPU1_G3_TX_DP<2>")
	)
	(segment
		(start 357.152448 -227.16998)
		(end 357.184198 -227.151692)
		(width 0.1143)
		(layer "In15.Cu")
		(net "GMI_CPU0_G1_CPU1_G3_TX_DP<2>")
	)
	(segment
		(start 114.343434 -227.778818)
		(end 114.311684 -227.797106)
		(width 0.1143)
		(layer "In15.Cu")
		(net "GMI_CPU0_G1_CPU1_G3_TX_DP<2>")
	)
	(segment
		(start 114.275362 -228.750876)
		(end 114.311684 -228.771958)
		(width 0.1143)
		(layer "In15.Cu")
		(net "GMI_CPU0_G1_CPU1_G3_TX_DP<2>")
	)
	(segment
		(start 357.183436 -232.011982)
		(end 357.184198 -232.011474)
		(width 0.1143)
		(layer "In15.Cu")
		(net "GMI_CPU0_G1_CPU1_G3_TX_DP<2>")
	)
	(segment
		(start 357.22306 -242.399312)
		(end 357.186992 -242.378484)
		(width 0.1143)
		(layer "In15.Cu")
		(net "GMI_CPU0_G1_CPU1_G3_TX_DP<2>")
	)
	(segment
		(start 114.311684 -242.37696)
		(end 114.31143 -242.377214)
		(width 0.1143)
		(layer "In15.Cu")
		(net "GMI_CPU0_G1_CPU1_G3_TX_DP<2>")
	)
	(segment
		(start 357.182166 -235.895388)
		(end 357.180642 -235.894626)
		(width 0.1143)
		(layer "In15.Cu")
		(net "GMI_CPU0_G1_CPU1_G3_TX_DP<2>")
	)
	(segment
		(start 357.184198 -234.276646)
		(end 357.183436 -234.276138)
		(width 0.1143)
		(layer "In15.Cu")
		(net "GMI_CPU0_G1_CPU1_G3_TX_DP<2>")
	)
	(segment
		(start 114.312446 -243.35232)
		(end 114.343434 -243.3701)
		(width 0.1143)
		(layer "In15.Cu")
		(net "GMI_CPU0_G1_CPU1_G3_TX_DP<2>")
	)
	(segment
		(start 165.258242 -175.868838)
		(end 156.776166 -178.901852)
		(width 0.14224)
		(layer "In15.Cu")
		(net "GMI_CPU0_G1_CPU1_G3_TX_DP<2>")
	)
	(segment
		(start 356.567232 -218.32062)
		(end 356.361238 -217.88501)
		(width 0.14224)
		(layer "In15.Cu")
		(net "GMI_CPU0_G1_CPU1_G3_TX_DP<2>")
	)
	(segment
		(start 357.152194 -229.398068)
		(end 357.15067 -229.397052)
		(width 0.1143)
		(layer "In15.Cu")
		(net "GMI_CPU0_G1_CPU1_G3_TX_DP<2>")
	)
	(segment
		(start 114.27333 -227.129594)
		(end 114.34318 -227.170234)
		(width 0.1143)
		(layer "In15.Cu")
		(net "GMI_CPU0_G1_CPU1_G3_TX_DP<2>")
	)
	(segment
		(start 114.273838 -231.98963)
		(end 114.34318 -232.030016)
		(width 0.1143)
		(layer "In15.Cu")
		(net "GMI_CPU0_G1_CPU1_G3_TX_DP<2>")
	)
	(segment
		(start 356.526592 -221.80423)
		(end 356.526592 -221.313756)
		(width 0.1143)
		(layer "In15.Cu")
		(net "GMI_CPU0_G1_CPU1_G3_TX_DP<2>")
	)
	(segment
		(start 114.333528 -242.36426)
		(end 114.332766 -242.364768)
		(width 0.1143)
		(layer "In15.Cu")
		(net "GMI_CPU0_G1_CPU1_G3_TX_DP<2>")
	)
	(segment
		(start 357.182166 -241.732816)
		(end 357.183436 -241.732054)
		(width 0.1143)
		(layer "In15.Cu")
		(net "GMI_CPU0_G1_CPU1_G3_TX_DP<2>")
	)
	(segment
		(start 357.17988 -242.374166)
		(end 357.178864 -242.373658)
		(width 0.1143)
		(layer "In15.Cu")
		(net "GMI_CPU0_G1_CPU1_G3_TX_DP<2>")
	)
	(segment
		(start 356.212394 -222.918528)
		(end 356.209346 -222.916242)
		(width 0.1143)
		(layer "In15.Cu")
		(net "GMI_CPU0_G1_CPU1_G3_TX_DP<2>")
	)
	(segment
		(start 357.184198 -242.376706)
		(end 357.183436 -242.376198)
		(width 0.1143)
		(layer "In15.Cu")
		(net "GMI_CPU0_G1_CPU1_G3_TX_DP<2>")
	)
	(segment
		(start 114.343434 -232.6386)
		(end 114.27333 -232.67924)
		(width 0.1143)
		(layer "In15.Cu")
		(net "GMI_CPU0_G1_CPU1_G3_TX_DP<2>")
	)
	(segment
		(start 357.186992 -242.378484)
		(end 357.184198 -242.376706)
		(width 0.1143)
		(layer "In15.Cu")
		(net "GMI_CPU0_G1_CPU1_G3_TX_DP<2>")
	)
	(segment
		(start 356.214172 -223.92894)
		(end 356.282498 -223.88957)
		(width 0.1143)
		(layer "In15.Cu")
		(net "GMI_CPU0_G1_CPU1_G3_TX_DP<2>")
	)
	(segment
		(start 357.184198 -240.111534)
		(end 357.22052 -240.090452)
		(width 0.1143)
		(layer "In15.Cu")
		(net "GMI_CPU0_G1_CPU1_G3_TX_DP<2>")
	)
	(segment
		(start 114.25174 -230.353616)
		(end 114.273584 -230.369872)
		(width 0.1143)
		(layer "In15.Cu")
		(net "GMI_CPU0_G1_CPU1_G3_TX_DP<2>")
	)
	(segment
		(start 114.34318 -233.650028)
		(end 114.343434 -233.650028)
		(width 0.1143)
		(layer "In15.Cu")
		(net "GMI_CPU0_G1_CPU1_G3_TX_DP<2>")
	)
	(segment
		(start 357.183436 -236.872018)
		(end 357.185722 -236.870494)
		(width 0.1143)
		(layer "In15.Cu")
		(net "GMI_CPU0_G1_CPU1_G3_TX_DP<2>")
	)
	(segment
		(start 357.22306 -241.70894)
		(end 357.248714 -241.690652)
		(width 0.1143)
		(layer "In15.Cu")
		(net "GMI_CPU0_G1_CPU1_G3_TX_DP<2>")
	)
	(segment
		(start 357.152448 -240.129822)
		(end 357.182166 -240.112804)
		(width 0.1143)
		(layer "In15.Cu")
		(net "GMI_CPU0_G1_CPU1_G3_TX_DP<2>")
	)
	(segment
		(start 114.31143 -243.351812)
		(end 114.311684 -243.351812)
		(width 0.1143)
		(layer "In15.Cu")
		(net "GMI_CPU0_G1_CPU1_G3_TX_DP<2>")
	)
	(segment
		(start 357.182166 -238.492792)
		(end 357.183436 -238.49203)
		(width 0.1143)
		(layer "In15.Cu")
		(net "GMI_CPU0_G1_CPU1_G3_TX_DP<2>")
	)
	(segment
		(start 114.311684 -240.756948)
		(end 114.30889 -240.758472)
		(width 0.1143)
		(layer "In15.Cu")
		(net "GMI_CPU0_G1_CPU1_G3_TX_DP<2>")
	)
	(segment
		(start 356.24516 -222.291148)
		(end 356.246684 -222.290132)
		(width 0.1143)
		(layer "In15.Cu")
		(net "GMI_CPU0_G1_CPU1_G3_TX_DP<2>")
	)
	(segment
		(start 357.178102 -242.37315)
		(end 357.175562 -242.37188)
		(width 0.1143)
		(layer "In15.Cu")
		(net "GMI_CPU0_G1_CPU1_G3_TX_DP<2>")
	)
	(segment
		(start 357.175562 -240.751868)
		(end 357.152448 -240.738406)
		(width 0.1143)
		(layer "In15.Cu")
		(net "GMI_CPU0_G1_CPU1_G3_TX_DP<2>")
	)
	(segment
		(start 357.371142 -243.674138)
		(end 357.0732 -243.674138)
		(width 0.1143)
		(layer "In15.Cu")
		(net "GMI_CPU0_G1_CPU1_G3_TX_DP<2>")
	)
	(segment
		(start 114.31778 -238.495332)
		(end 114.32032 -238.496602)
		(width 0.1143)
		(layer "In15.Cu")
		(net "GMI_CPU0_G1_CPU1_G3_TX_DP<2>")
	)
	(segment
		(start 357.18496 -226.177348)
		(end 357.184198 -226.17684)
		(width 0.1143)
		(layer "In15.Cu")
		(net "GMI_CPU0_G1_CPU1_G3_TX_DP<2>")
	)
	(segment
		(start 114.311684 -237.516924)
		(end 114.31143 -237.517178)
		(width 0.1143)
		(layer "In15.Cu")
		(net "GMI_CPU0_G1_CPU1_G3_TX_DP<2>")
	)
	(segment
		(start 114.32032 -238.496602)
		(end 114.343434 -238.510064)
		(width 0.1143)
		(layer "In15.Cu")
		(net "GMI_CPU0_G1_CPU1_G3_TX_DP<2>")
	)
	(segment
		(start 357.175562 -232.651808)
		(end 357.152448 -232.638346)
		(width 0.1143)
		(layer "In15.Cu")
		(net "GMI_CPU0_G1_CPU1_G3_TX_DP<2>")
	)
	(segment
		(start 357.17988 -235.894118)
		(end 357.178864 -235.89361)
		(width 0.1143)
		(layer "In15.Cu")
		(net "GMI_CPU0_G1_CPU1_G3_TX_DP<2>")
	)
	(segment
		(start 357.182166 -232.655364)
		(end 357.180642 -232.654602)
		(width 0.1143)
		(layer "In15.Cu")
		(net "GMI_CPU0_G1_CPU1_G3_TX_DP<2>")
	)
	(segment
		(start 114.25301 -240.075212)
		(end 114.275108 -240.090706)
		(width 0.1143)
		(layer "In15.Cu")
		(net "GMI_CPU0_G1_CPU1_G3_TX_DP<2>")
	)
	(segment
		(start 357.184198 -232.656634)
		(end 357.183436 -232.656126)
		(width 0.1143)
		(layer "In15.Cu")
		(net "GMI_CPU0_G1_CPU1_G3_TX_DP<2>")
	)
	(segment
		(start 357.251 -242.419378)
		(end 357.22306 -242.399312)
		(width 0.1143)
		(layer "In15.Cu")
		(net "GMI_CPU0_G1_CPU1_G3_TX_DP<2>")
	)
	(segment
		(start 357.183436 -228.772212)
		(end 357.184198 -228.771704)
		(width 0.1143)
		(layer "In15.Cu")
		(net "GMI_CPU0_G1_CPU1_G3_TX_DP<2>")
	)
	(segment
		(start 357.175562 -237.511844)
		(end 357.152448 -237.498382)
		(width 0.1143)
		(layer "In15.Cu")
		(net "GMI_CPU0_G1_CPU1_G3_TX_DP<2>")
	)
	(segment
		(start 352.661982 -210.068414)
		(end 317.807848 -181.489858)
		(width 0.14224)
		(layer "In15.Cu")
		(net "GMI_CPU0_G1_CPU1_G3_TX_DP<2>")
	)
	(segment
		(start 357.182166 -240.755424)
		(end 357.180642 -240.754662)
		(width 0.1143)
		(layer "In15.Cu")
		(net "GMI_CPU0_G1_CPU1_G3_TX_DP<2>")
	)
	(segment
		(start 357.182166 -240.112804)
		(end 357.183436 -240.112042)
		(width 0.1143)
		(layer "In15.Cu")
		(net "GMI_CPU0_G1_CPU1_G3_TX_DP<2>")
	)
	(segment
		(start 310.787034 -177.51552)
		(end 310.787034 -177.515266)
		(width 0.14224)
		(layer "In15.Cu")
		(net "GMI_CPU0_G1_CPU1_G3_TX_DP<2>")
	)
	(segment
		(start 357.152448 -233.649774)
		(end 357.182166 -233.632756)
		(width 0.1143)
		(layer "In15.Cu")
		(net "GMI_CPU0_G1_CPU1_G3_TX_DP<2>")
	)
	(segment
		(start 356.283006 -224.579434)
		(end 356.245668 -224.557844)
		(width 0.1143)
		(layer "In15.Cu")
		(net "GMI_CPU0_G1_CPU1_G3_TX_DP<2>")
	)
	(segment
		(start 114.275362 -223.89084)
		(end 114.311684 -223.911922)
		(width 0.1143)
		(layer "In15.Cu")
		(net "GMI_CPU0_G1_CPU1_G3_TX_DP<2>")
	)
	(segment
		(start 357.184198 -235.896658)
		(end 357.183436 -235.89615)
		(width 0.1143)
		(layer "In15.Cu")
		(net "GMI_CPU0_G1_CPU1_G3_TX_DP<2>")
	)
	(segment
		(start 357.183436 -243.352066)
		(end 357.185722 -243.350542)
		(width 0.1143)
		(layer "In15.Cu")
		(net "GMI_CPU0_G1_CPU1_G3_TX_DP<2>")
	)
	(segment
		(start 137.103612 -195.032376)
		(end 137.103104 -195.03263)
		(width 0.14224)
		(layer "In15.Cu")
		(net "GMI_CPU0_G1_CPU1_G3_TX_DP<2>")
	)
	(segment
		(start 357.184198 -233.631486)
		(end 357.22052 -233.610404)
		(width 0.1143)
		(layer "In15.Cu")
		(net "GMI_CPU0_G1_CPU1_G3_TX_DP<2>")
	)
	(segment
		(start 357.178864 -239.133634)
		(end 357.178102 -239.133126)
		(width 0.1143)
		(layer "In15.Cu")
		(net "GMI_CPU0_G1_CPU1_G3_TX_DP<2>")
	)
	(segment
		(start 114.273076 -239.159288)
		(end 114.25301 -239.173512)
		(width 0.1143)
		(layer "In15.Cu")
		(net "GMI_CPU0_G1_CPU1_G3_TX_DP<2>")
	)
	(segment
		(start 356.292658 -224.586292)
		(end 356.283006 -224.579434)
		(width 0.1143)
		(layer "In15.Cu")
		(net "GMI_CPU0_G1_CPU1_G3_TX_DP<2>")
	)
	(segment
		(start 357.183436 -242.376198)
		(end 357.182166 -242.375436)
		(width 0.1143)
		(layer "In15.Cu")
		(net "GMI_CPU0_G1_CPU1_G3_TX_DP<2>")
	)
	(segment
		(start 357.176832 -227.792534)
		(end 357.175054 -227.791518)
		(width 0.1143)
		(layer "In15.Cu")
		(net "GMI_CPU0_G1_CPU1_G3_TX_DP<2>")
	)
	(segment
		(start 310.787034 -177.515266)
		(end 310.765952 -177.503582)
		(width 0.14224)
		(layer "In15.Cu")
		(net "GMI_CPU0_G1_CPU1_G3_TX_DP<2>")
	)
	(segment
		(start 356.243382 -224.55632)
		(end 356.240588 -224.55505)
		(width 0.1143)
		(layer "In15.Cu")
		(net "GMI_CPU0_G1_CPU1_G3_TX_DP<2>")
	)
	(segment
		(start 114.332766 -237.504732)
		(end 114.311684 -237.516924)
		(width 0.1143)
		(layer "In15.Cu")
		(net "GMI_CPU0_G1_CPU1_G3_TX_DP<2>")
	)
	(segment
		(start 357.17988 -239.134142)
		(end 357.178864 -239.133634)
		(width 0.1143)
		(layer "In15.Cu")
		(net "GMI_CPU0_G1_CPU1_G3_TX_DP<2>")
	)
	(segment
		(start 114.27333 -232.67924)
		(end 114.258598 -232.6894)
		(width 0.1143)
		(layer "In15.Cu")
		(net "GMI_CPU0_G1_CPU1_G3_TX_DP<2>")
	)
	(segment
		(start 114.259868 -231.980232)
		(end 114.273838 -231.98963)
		(width 0.1143)
		(layer "In15.Cu")
		(net "GMI_CPU0_G1_CPU1_G3_TX_DP<2>")
	)
	(segment
		(start 357.175054 -227.791518)
		(end 357.174292 -227.79101)
		(width 0.1143)
		(layer "In15.Cu")
		(net "GMI_CPU0_G1_CPU1_G3_TX_DP<2>")
	)
	(segment
		(start 114.32413 -240.1189)
		(end 114.343434 -240.130076)
		(width 0.1143)
		(layer "In15.Cu")
		(net "GMI_CPU0_G1_CPU1_G3_TX_DP<2>")
	)
	(segment
		(start 114.260122 -225.500438)
		(end 114.273838 -225.509836)
		(width 0.1143)
		(layer "In15.Cu")
		(net "GMI_CPU0_G1_CPU1_G3_TX_DP<2>")
	)
	(segment
		(start 357.183436 -241.732054)
		(end 357.185722 -241.73053)
		(width 0.1143)
		(layer "In15.Cu")
		(net "GMI_CPU0_G1_CPU1_G3_TX_DP<2>")
	)
	(segment
		(start 114.275108 -240.090706)
		(end 114.275362 -240.090706)
		(width 0.1143)
		(layer "In15.Cu")
		(net "GMI_CPU0_G1_CPU1_G3_TX_DP<2>")
	)
	(segment
		(start 357.180388 -227.794566)
		(end 357.17861 -227.79355)
		(width 0.1143)
		(layer "In15.Cu")
		(net "GMI_CPU0_G1_CPU1_G3_TX_DP<2>")
	)
	(segment
		(start 356.361238 -217.88501)
		(end 352.661982 -210.068414)
		(width 0.14224)
		(layer "In15.Cu")
		(net "GMI_CPU0_G1_CPU1_G3_TX_DP<2>")
	)
	(segment
		(start 114.311684 -236.871764)
		(end 114.343434 -236.890052)
		(width 0.1143)
		(layer "In15.Cu")
		(net "GMI_CPU0_G1_CPU1_G3_TX_DP<2>")
	)
	(segment
		(start 302.914304 -176.673256)
		(end 165.258242 -175.868838)
		(width 0.14224)
		(layer "In15.Cu")
		(net "GMI_CPU0_G1_CPU1_G3_TX_DP<2>")
	)
	(segment
		(start 114.273838 -225.509836)
		(end 114.34318 -225.550222)
		(width 0.1143)
		(layer "In15.Cu")
		(net "GMI_CPU0_G1_CPU1_G3_TX_DP<2>")
	)
	(segment
		(start 113.96599 -221.066106)
		(end 113.96599 -221.277942)
		(width 0.1143)
		(layer "In15.Cu")
		(net "GMI_CPU0_G1_CPU1_G3_TX_DP<2>")
	)
	(segment
		(start 114.345212 -229.397306)
		(end 114.296444 -229.426008)
		(width 0.1143)
		(layer "In15.Cu")
		(net "GMI_CPU0_G1_CPU1_G3_TX_DP<2>")
	)
	(segment
		(start 357.152448 -241.749834)
		(end 357.182166 -241.732816)
		(width 0.1143)
		(layer "In15.Cu")
		(net "GMI_CPU0_G1_CPU1_G3_TX_DP<2>")
	)
	(segment
		(start 357.183436 -240.112042)
		(end 357.184198 -240.111534)
		(width 0.1143)
		(layer "In15.Cu")
		(net "GMI_CPU0_G1_CPU1_G3_TX_DP<2>")
	)
	(segment
		(start 357.22306 -236.848904)
		(end 357.251 -236.828838)
		(width 0.1143)
		(layer "In15.Cu")
		(net "GMI_CPU0_G1_CPU1_G3_TX_DP<2>")
	)
	(segment
		(start 137.103104 -195.03263)
		(end 117.430042 -211.163662)
		(width 0.14224)
		(layer "In15.Cu")
		(net "GMI_CPU0_G1_CPU1_G3_TX_DP<2>")
	)
	(segment
		(start 113.92027 -217.144346)
		(end 113.92027 -220.991938)
		(width 0.14224)
		(layer "In15.Cu")
		(net "GMI_CPU0_G1_CPU1_G3_TX_DP<2>")
	)
	(segment
		(start 114.311684 -227.797106)
		(end 114.275362 -227.818188)
		(width 0.1143)
		(layer "In15.Cu")
		(net "GMI_CPU0_G1_CPU1_G3_TX_DP<2>")
	)
	(segment
		(start 357.181658 -227.795328)
		(end 357.180388 -227.794566)
		(width 0.1143)
		(layer "In15.Cu")
		(net "GMI_CPU0_G1_CPU1_G3_TX_DP<2>")
	)
	(segment
		(start 357.152448 -236.889798)
		(end 357.182166 -236.87278)
		(width 0.1143)
		(layer "In15.Cu")
		(net "GMI_CPU0_G1_CPU1_G3_TX_DP<2>")
	)
	(segment
		(start 356.056438 -224.232978)
		(end 356.056692 -224.230946)
		(width 0.1143)
		(layer "In15.Cu")
		(net "GMI_CPU0_G1_CPU1_G3_TX_DP<2>")
	)
	(segment
		(start 357.183436 -239.136174)
		(end 357.182166 -239.135412)
		(width 0.1143)
		(layer "In15.Cu")
		(net "GMI_CPU0_G1_CPU1_G3_TX_DP<2>")
	)
	(segment
		(start 357.182166 -237.5154)
		(end 357.180642 -237.514638)
		(width 0.1143)
		(layer "In15.Cu")
		(net "GMI_CPU0_G1_CPU1_G3_TX_DP<2>")
	)
	(segment
		(start 357.178864 -232.653586)
		(end 357.178102 -232.653078)
		(width 0.1143)
		(layer "In15.Cu")
		(net "GMI_CPU0_G1_CPU1_G3_TX_DP<2>")
	)
	(segment
		(start 310.765952 -177.503582)
		(end 308.443884 -176.673256)
		(width 0.14224)
		(layer "In15.Cu")
		(net "GMI_CPU0_G1_CPU1_G3_TX_DP<2>")
	)
	(segment
		(start 357.175562 -235.891832)
		(end 357.152448 -235.87837)
		(width 0.1143)
		(layer "In15.Cu")
		(net "GMI_CPU0_G1_CPU1_G3_TX_DP<2>")
	)
	(segment
		(start 114.27206 -234.300014)
		(end 114.245644 -234.319064)
		(width 0.1143)
		(layer "In15.Cu")
		(net "GMI_CPU0_G1_CPU1_G3_TX_DP<2>")
	)
	(segment
		(start 114.27206 -235.228638)
		(end 114.34318 -235.27004)
		(width 0.1143)
		(layer "In15.Cu")
		(net "GMI_CPU0_G1_CPU1_G3_TX_DP<2>")
	)
	(segment
		(start 356.245668 -224.557844)
		(end 356.243382 -224.55632)
		(width 0.1143)
		(layer "In15.Cu")
		(net "GMI_CPU0_G1_CPU1_G3_TX_DP<2>")
	)
	(segment
		(start 114.27333 -226.199446)
		(end 114.258598 -226.209606)
		(width 0.1143)
		(layer "In15.Cu")
		(net "GMI_CPU0_G1_CPU1_G3_TX_DP<2>")
	)
	(segment
		(start 357.183436 -240.756186)
		(end 357.182166 -240.755424)
		(width 0.1143)
		(layer "In15.Cu")
		(net "GMI_CPU0_G1_CPU1_G3_TX_DP<2>")
	)
	(segment
		(start 114.258598 -227.119434)
		(end 114.27333 -227.129594)
		(width 0.1143)
		(layer "In15.Cu")
		(net "GMI_CPU0_G1_CPU1_G3_TX_DP<2>")
	)
	(segment
		(start 357.152448 -228.789992)
		(end 357.182166 -228.772974)
		(width 0.1143)
		(layer "In15.Cu")
		(net "GMI_CPU0_G1_CPU1_G3_TX_DP<2>")
	)
	(segment
		(start 114.34318 -225.550222)
		(end 114.343434 -225.550222)
		(width 0.1143)
		(layer "In15.Cu")
		(net "GMI_CPU0_G1_CPU1_G3_TX_DP<2>")
	)
	(segment
		(start 357.185722 -236.870494)
		(end 357.22306 -236.848904)
		(width 0.1143)
		(layer "In15.Cu")
		(net "GMI_CPU0_G1_CPU1_G3_TX_DP<2>")
	)
	(segment
		(start 357.22306 -243.328952)
		(end 357.251 -243.308886)
		(width 0.1143)
		(layer "In15.Cu")
		(net "GMI_CPU0_G1_CPU1_G3_TX_DP<2>")
	)
	(segment
		(start 357.178102 -239.133126)
		(end 357.175562 -239.131856)
		(width 0.1143)
		(layer "In15.Cu")
		(net "GMI_CPU0_G1_CPU1_G3_TX_DP<2>")
	)
	(segment
		(start 357.182166 -233.632756)
		(end 357.183436 -233.631994)
		(width 0.1143)
		(layer "In15.Cu")
		(net "GMI_CPU0_G1_CPU1_G3_TX_DP<2>")
	)
	(segment
		(start 114.343434 -235.878624)
		(end 114.311684 -235.896912)
		(width 0.1143)
		(layer "In15.Cu")
		(net "GMI_CPU0_G1_CPU1_G3_TX_DP<2>")
	)
	(segment
		(start 357.178864 -234.273598)
		(end 357.178102 -234.27309)
		(width 0.1143)
		(layer "In15.Cu")
		(net "GMI_CPU0_G1_CPU1_G3_TX_DP<2>")
	)
	(segment
		(start 357.184198 -232.011474)
		(end 357.22052 -231.990392)
		(width 0.1143)
		(layer "In15.Cu")
		(net "GMI_CPU0_G1_CPU1_G3_TX_DP<2>")
	)
	(segment
		(start 356.244144 -222.291656)
		(end 356.24516 -222.291148)
		(width 0.1143)
		(layer "In15.Cu")
		(net "GMI_CPU0_G1_CPU1_G3_TX_DP<2>")
	)
	(segment
		(start 357.22052 -231.057704)
		(end 357.184198 -231.036622)
		(width 0.1143)
		(layer "In15.Cu")
		(net "GMI_CPU0_G1_CPU1_G3_TX_DP<2>")
	)
	(segment
		(start 357.22306 -240.7793)
		(end 357.186992 -240.758472)
		(width 0.1143)
		(layer "In15.Cu")
		(net "GMI_CPU0_G1_CPU1_G3_TX_DP<2>")
	)
	(segment
		(start 357.180642 -242.374674)
		(end 357.17988 -242.374166)
		(width 0.1143)
		(layer "In15.Cu")
		(net "GMI_CPU0_G1_CPU1_G3_TX_DP<2>")
	)
	(segment
		(start 356.526338 -225.044254)
		(end 356.526338 -225.042222)
		(width 0.1143)
		(layer "In15.Cu")
		(net "GMI_CPU0_G1_CPU1_G3_TX_DP<2>")
	)
	(segment
		(start 357.178102 -235.893102)
		(end 357.175562 -235.891832)
		(width 0.1143)
		(layer "In15.Cu")
		(net "GMI_CPU0_G1_CPU1_G3_TX_DP<2>")
	)
	(segment
		(start 357.178864 -237.513622)
		(end 357.178102 -237.513114)
		(width 0.1143)
		(layer "In15.Cu")
		(net "GMI_CPU0_G1_CPU1_G3_TX_DP<2>")
	)
	(segment
		(start 114.245644 -235.209842)
		(end 114.27206 -235.228638)
		(width 0.1143)
		(layer "In15.Cu")
		(net "GMI_CPU0_G1_CPU1_G3_TX_DP<2>")
	)
	(segment
		(start 357.182166 -239.135412)
		(end 357.180642 -239.13465)
		(width 0.1143)
		(layer "In15.Cu")
		(net "GMI_CPU0_G1_CPU1_G3_TX_DP<2>")
	)
	(segment
		(start 357.152448 -235.269786)
		(end 357.182166 -235.252768)
		(width 0.1143)
		(layer "In15.Cu")
		(net "GMI_CPU0_G1_CPU1_G3_TX_DP<2>")
	)
	(segment
		(start 357.184198 -227.151692)
		(end 357.18496 -227.151184)
		(width 0.1143)
		(layer "In15.Cu")
		(net "GMI_CPU0_G1_CPU1_G3_TX_DP<2>")
	)
	(segment
		(start 357.175562 -242.37188)
		(end 357.152448 -242.358418)
		(width 0.1143)
		(layer "In15.Cu")
		(net "GMI_CPU0_G1_CPU1_G3_TX_DP<2>")
	)
	(segment
		(start 357.178864 -242.373658)
		(end 357.178102 -242.37315)
		(width 0.1143)
		(layer "In15.Cu")
		(net "GMI_CPU0_G1_CPU1_G3_TX_DP<2>")
	)
	(segment
		(start 357.183436 -232.656126)
		(end 357.182166 -232.655364)
		(width 0.1143)
		(layer "In15.Cu")
		(net "GMI_CPU0_G1_CPU1_G3_TX_DP<2>")
	)
	(segment
		(start 114.275362 -240.090706)
		(end 114.32413 -240.1189)
		(width 0.1143)
		(layer "In15.Cu")
		(net "GMI_CPU0_G1_CPU1_G3_TX_DP<2>")
	)
	(segment
		(start 114.312446 -240.75644)
		(end 114.311684 -240.756948)
		(width 0.1143)
		(layer "In15.Cu")
		(net "GMI_CPU0_G1_CPU1_G3_TX_DP<2>")
	)
	(segment
		(start 357.183436 -234.276138)
		(end 357.182166 -234.275376)
		(width 0.1143)
		(layer "In15.Cu")
		(net "GMI_CPU0_G1_CPU1_G3_TX_DP<2>")
	)
	(segment
		(start 114.316002 -238.494316)
		(end 114.317018 -238.494824)
		(width 0.1143)
		(layer "In15.Cu")
		(net "GMI_CPU0_G1_CPU1_G3_TX_DP<2>")
	)
	(segment
		(start 357.18242 -227.795836)
		(end 357.181658 -227.795328)
		(width 0.1143)
		(layer "In15.Cu")
		(net "GMI_CPU0_G1_CPU1_G3_TX_DP<2>")
	)
	(segment
		(start 357.184198 -235.251498)
		(end 357.22052 -235.230416)
		(width 0.1143)
		(layer "In15.Cu")
		(net "GMI_CPU0_G1_CPU1_G3_TX_DP<2>")
	)
	(segment
		(start 317.807848 -181.489858)
		(end 310.787034 -177.51552)
		(width 0.14224)
		(layer "In15.Cu")
		(net "GMI_CPU0_G1_CPU1_G3_TX_DP<2>")
	)
	(segment
		(start 357.180642 -234.274614)
		(end 357.17988 -234.274106)
		(width 0.1143)
		(layer "In15.Cu")
		(net "GMI_CPU0_G1_CPU1_G3_TX_DP<2>")
	)
	(segment
		(start 357.175562 -239.131856)
		(end 357.152448 -239.118394)
		(width 0.1143)
		(layer "In15.Cu")
		(net "GMI_CPU0_G1_CPU1_G3_TX_DP<2>")
	)
	(segment
		(start 356.240588 -224.55505)
		(end 356.24008 -224.554796)
		(width 0.1143)
		(layer "In15.Cu")
		(net "GMI_CPU0_G1_CPU1_G3_TX_DP<2>")
	)
	(segment
		(start 357.172006 -227.78974)
		(end 357.17099 -227.789232)
		(width 0.1143)
		(layer "In15.Cu")
		(net "GMI_CPU0_G1_CPU1_G3_TX_DP<2>")
	)
	(segment
		(start 137.103358 -195.032376)
		(end 137.103612 -195.032376)
		(width 0.14224)
		(layer "In15.Cu")
		(net "GMI_CPU0_G1_CPU1_G3_TX_DP<2>")
	)
	(segment
		(start 357.175562 -234.27182)
		(end 357.152448 -234.258358)
		(width 0.1143)
		(layer "In15.Cu")
		(net "GMI_CPU0_G1_CPU1_G3_TX_DP<2>")
	)
	(segment
		(start 357.33863 -229.54615)
		(end 357.33863 -229.545896)
		(width 0.1143)
		(layer "In15.Cu")
		(net "GMI_CPU0_G1_CPU1_G3_TX_DP<2>")
	)
	(segment
		(start 357.182166 -236.87278)
		(end 357.183436 -236.872018)
		(width 0.1143)
		(layer "In15.Cu")
		(net "GMI_CPU0_G1_CPU1_G3_TX_DP<2>")
	)
	(segment
		(start 114.492532 -243.604542)
		(end 114.422682 -243.674392)
		(width 0.1143)
		(layer "In15.Cu")
		(net "GMI_CPU0_G1_CPU1_G3_TX_DP<2>")
	)
	(segment
		(start 357.152448 -232.029762)
		(end 357.182166 -232.012744)
		(width 0.1143)
		(layer "In15.Cu")
		(net "GMI_CPU0_G1_CPU1_G3_TX_DP<2>")
	)
	(segment
		(start 357.184198 -228.771704)
		(end 357.184706 -228.771704)
		(width 0.1143)
		(layer "In15.Cu")
		(net "GMI_CPU0_G1_CPU1_G3_TX_DP<2>")
	)
	(segment
		(start 357.179372 -226.174046)
		(end 357.17861 -226.173538)
		(width 0.1143)
		(layer "In15.Cu")
		(net "GMI_CPU0_G1_CPU1_G3_TX_DP<2>")
	)
	(segment
		(start 114.343434 -224.538794)
		(end 114.273838 -224.57918)
		(width 0.1143)
		(layer "In15.Cu")
		(net "GMI_CPU0_G1_CPU1_G3_TX_DP<2>")
	)
	(segment
		(start 357.180642 -235.894626)
		(end 357.17988 -235.894118)
		(width 0.1143)
		(layer "In15.Cu")
		(net "GMI_CPU0_G1_CPU1_G3_TX_DP<2>")
	)
	(segment
		(start 357.152448 -238.50981)
		(end 357.182166 -238.492792)
		(width 0.1143)
		(layer "In15.Cu")
		(net "GMI_CPU0_G1_CPU1_G3_TX_DP<2>")
	)
	(segment
		(start 114.311684 -243.351812)
		(end 114.312446 -243.35232)
		(width 0.1143)
		(layer "In15.Cu")
		(net "GMI_CPU0_G1_CPU1_G3_TX_DP<2>")
	)
	(segment
		(start 357.184198 -237.51667)
		(end 357.183436 -237.516162)
		(width 0.1143)
		(layer "In15.Cu")
		(net "GMI_CPU0_G1_CPU1_G3_TX_DP<2>")
	)
	(segment
		(start 113.92027 -220.991938)
		(end 113.92027 -221.020386)
		(width 0.1143)
		(layer "In15.Cu")
		(net "GMI_CPU0_G1_CPU1_G3_TX_DP<2>")
	)
	(segment
		(start 356.567232 -221.083124)
		(end 356.567232 -218.32062)
		(width 0.14224)
		(layer "In15.Cu")
		(net "GMI_CPU0_G1_CPU1_G3_TX_DP<2>")
	)
	(segment
		(start 357.184198 -239.136682)
		(end 357.183436 -239.136174)
		(width 0.1143)
		(layer "In15.Cu")
		(net "GMI_CPU0_G1_CPU1_G3_TX_DP<2>")
	)
	(segment
		(start 114.275362 -236.850682)
		(end 114.311684 -236.871764)
		(width 0.1143)
		(layer "In15.Cu")
		(net "GMI_CPU0_G1_CPU1_G3_TX_DP<2>")
	)
	(arc
		(start 357.22052 -238.47044)
		(mid 357.22767 -238.465542)
		(end 357.234744 -238.460534)
		(width 0.1143)
		(layer "In15.Cu")
		(net "GMI_CPU0_G1_CPU1_G3_TX_DP<2>")
	)
	(arc
		(start 114.49939 -230.71455)
		(mid 114.458628 -230.884434)
		(end 114.345212 -231.017318)
		(width 0.1143)
		(layer "In15.Cu")
		(net "GMI_CPU0_G1_CPU1_G3_TX_DP<2>")
	)
	(arc
		(start 114.275362 -227.818188)
		(mid 114.267698 -227.823459)
		(end 114.260122 -227.828856)
		(width 0.1143)
		(layer "In15.Cu")
		(net "GMI_CPU0_G1_CPU1_G3_TX_DP<2>")
	)
	(arc
		(start 357.152448 -237.498382)
		(mid 356.99652 -237.19409)
		(end 357.152448 -236.889798)
		(width 0.1143)
		(layer "In15.Cu")
		(net "GMI_CPU0_G1_CPU1_G3_TX_DP<2>")
	)
	(arc
		(start 114.49939 -229.094538)
		(mid 114.458628 -229.264422)
		(end 114.345212 -229.397306)
		(width 0.1143)
		(layer "In15.Cu")
		(net "GMI_CPU0_G1_CPU1_G3_TX_DP<2>")
	)
	(arc
		(start 114.343434 -225.550222)
		(mid 114.499362 -225.854514)
		(end 114.343434 -226.158806)
		(width 0.1143)
		(layer "In15.Cu")
		(net "GMI_CPU0_G1_CPU1_G3_TX_DP<2>")
	)
	(arc
		(start 114.343434 -227.170234)
		(mid 114.499362 -227.474526)
		(end 114.343434 -227.778818)
		(width 0.1143)
		(layer "In15.Cu")
		(net "GMI_CPU0_G1_CPU1_G3_TX_DP<2>")
	)
	(arc
		(start 357.248714 -241.690652)
		(mid 357.477734 -241.24412)
		(end 357.248714 -240.797588)
		(width 0.1143)
		(layer "In15.Cu")
		(net "GMI_CPU0_G1_CPU1_G3_TX_DP<2>")
	)
	(arc
		(start 357.152448 -234.258358)
		(mid 356.99652 -233.954066)
		(end 357.152448 -233.649774)
		(width 0.1143)
		(layer "In15.Cu")
		(net "GMI_CPU0_G1_CPU1_G3_TX_DP<2>")
	)
	(arc
		(start 114.033554 -229.946708)
		(mid 114.109108 -230.168143)
		(end 114.25174 -230.353616)
		(width 0.1143)
		(layer "In15.Cu")
		(net "GMI_CPU0_G1_CPU1_G3_TX_DP<2>")
	)
	(arc
		(start 357.152448 -240.738406)
		(mid 356.99652 -240.434114)
		(end 357.152448 -240.129822)
		(width 0.1143)
		(layer "In15.Cu")
		(net "GMI_CPU0_G1_CPU1_G3_TX_DP<2>")
	)
	(arc
		(start 356.28326 -222.268796)
		(mid 356.424829 -222.127854)
		(end 356.508558 -221.94647)
		(width 0.1143)
		(layer "In15.Cu")
		(net "GMI_CPU0_G1_CPU1_G3_TX_DP<2>")
	)
	(arc
		(start 357.236776 -233.598974)
		(mid 357.45966 -233.14406)
		(end 357.236776 -232.689146)
		(width 0.1143)
		(layer "In15.Cu")
		(net "GMI_CPU0_G1_CPU1_G3_TX_DP<2>")
	)
	(arc
		(start 356.996492 -225.85426)
		(mid 356.931977 -225.592041)
		(end 356.75316 -225.389694)
		(width 0.1143)
		(layer "In15.Cu")
		(net "GMI_CPU0_G1_CPU1_G3_TX_DP<2>")
	)
	(arc
		(start 357.466392 -231.524048)
		(mid 357.401156 -231.260457)
		(end 357.22052 -231.057704)
		(width 0.1143)
		(layer "In15.Cu")
		(net "GMI_CPU0_G1_CPU1_G3_TX_DP<2>")
	)
	(arc
		(start 114.02949 -231.53116)
		(mid 114.090385 -231.783554)
		(end 114.259868 -231.980232)
		(width 0.1143)
		(layer "In15.Cu")
		(net "GMI_CPU0_G1_CPU1_G3_TX_DP<2>")
	)
	(arc
		(start 114.343434 -243.3701)
		(mid 114.440569 -243.472969)
		(end 114.492532 -243.604542)
		(width 0.1143)
		(layer "In15.Cu")
		(net "GMI_CPU0_G1_CPU1_G3_TX_DP<2>")
	)
	(arc
		(start 357.22052 -235.230416)
		(mid 357.228698 -235.224773)
		(end 357.236776 -235.218986)
		(width 0.1143)
		(layer "In15.Cu")
		(net "GMI_CPU0_G1_CPU1_G3_TX_DP<2>")
	)
	(arc
		(start 357.152448 -227.778564)
		(mid 356.99652 -227.474272)
		(end 357.152448 -227.16998)
		(width 0.1143)
		(layer "In15.Cu")
		(net "GMI_CPU0_G1_CPU1_G3_TX_DP<2>")
	)
	(arc
		(start 357.234744 -238.460534)
		(mid 357.462127 -238.004096)
		(end 357.234744 -237.547658)
		(width 0.1143)
		(layer "In15.Cu")
		(net "GMI_CPU0_G1_CPU1_G3_TX_DP<2>")
	)
	(arc
		(start 357.00335 -243.604288)
		(mid 357.055399 -243.472769)
		(end 357.152448 -243.369846)
		(width 0.1143)
		(layer "In15.Cu")
		(net "GMI_CPU0_G1_CPU1_G3_TX_DP<2>")
	)
	(arc
		(start 356.24008 -224.554796)
		(mid 356.105608 -224.418958)
		(end 356.056438 -224.234248)
		(width 0.1143)
		(layer "In15.Cu")
		(net "GMI_CPU0_G1_CPU1_G3_TX_DP<2>")
	)
	(arc
		(start 357.152448 -232.638346)
		(mid 356.99652 -232.334054)
		(end 357.152448 -232.029762)
		(width 0.1143)
		(layer "In15.Cu")
		(net "GMI_CPU0_G1_CPU1_G3_TX_DP<2>")
	)
	(arc
		(start 114.343434 -228.790246)
		(mid 114.45811 -228.92358)
		(end 114.49939 -229.094538)
		(width 0.1143)
		(layer "In15.Cu")
		(net "GMI_CPU0_G1_CPU1_G3_TX_DP<2>")
	)
	(arc
		(start 357.234744 -239.16767)
		(mid 357.227671 -239.162661)
		(end 357.22052 -239.157764)
		(width 0.1143)
		(layer "In15.Cu")
		(net "GMI_CPU0_G1_CPU1_G3_TX_DP<2>")
	)
	(arc
		(start 357.22052 -240.090452)
		(mid 357.22767 -240.085554)
		(end 357.234744 -240.080546)
		(width 0.1143)
		(layer "In15.Cu")
		(net "GMI_CPU0_G1_CPU1_G3_TX_DP<2>")
	)
	(arc
		(start 114.343434 -236.890052)
		(mid 114.499362 -237.194344)
		(end 114.343434 -237.498636)
		(width 0.1143)
		(layer "In15.Cu")
		(net "GMI_CPU0_G1_CPU1_G3_TX_DP<2>")
	)
	(arc
		(start 357.152448 -242.358418)
		(mid 356.99652 -242.054126)
		(end 357.152448 -241.749834)
		(width 0.1143)
		(layer "In15.Cu")
		(net "GMI_CPU0_G1_CPU1_G3_TX_DP<2>")
	)
	(arc
		(start 114.259106 -223.87941)
		(mid 114.267184 -223.885196)
		(end 114.275362 -223.89084)
		(width 0.1143)
		(layer "In15.Cu")
		(net "GMI_CPU0_G1_CPU1_G3_TX_DP<2>")
	)
	(arc
		(start 357.251 -236.828838)
		(mid 357.479 -236.384084)
		(end 357.251 -235.93933)
		(width 0.1143)
		(layer "In15.Cu")
		(net "GMI_CPU0_G1_CPU1_G3_TX_DP<2>")
	)
	(arc
		(start 114.26317 -235.926376)
		(mid 114.031186 -236.384338)
		(end 114.26317 -236.8423)
		(width 0.1143)
		(layer "In15.Cu")
		(net "GMI_CPU0_G1_CPU1_G3_TX_DP<2>")
	)
	(arc
		(start 114.343434 -232.030016)
		(mid 114.499362 -232.334308)
		(end 114.343434 -232.6386)
		(width 0.1143)
		(layer "In15.Cu")
		(net "GMI_CPU0_G1_CPU1_G3_TX_DP<2>")
	)
	(arc
		(start 357.236776 -232.689146)
		(mid 357.228698 -232.68336)
		(end 357.22052 -232.677716)
		(width 0.1143)
		(layer "In15.Cu")
		(net "GMI_CPU0_G1_CPU1_G3_TX_DP<2>")
	)
	(arc
		(start 114.270536 -231.06126)
		(mid 114.09334 -231.263272)
		(end 114.02949 -231.524302)
		(width 0.1143)
		(layer "In15.Cu")
		(net "GMI_CPU0_G1_CPU1_G3_TX_DP<2>")
	)
	(arc
		(start 356.508558 -221.94647)
		(mid 356.522117 -221.875925)
		(end 356.526592 -221.80423)
		(width 0.1143)
		(layer "In15.Cu")
		(net "GMI_CPU0_G1_CPU1_G3_TX_DP<2>")
	)
	(arc
		(start 114.296444 -229.426008)
		(mid 114.248754 -229.457809)
		(end 114.205004 -229.494842)
		(width 0.1143)
		(layer "In15.Cu")
		(net "GMI_CPU0_G1_CPU1_G3_TX_DP<2>")
	)
	(arc
		(start 114.32794 -230.401114)
		(mid 114.346639 -230.412909)
		(end 114.364262 -230.42626)
		(width 0.1143)
		(layer "In15.Cu")
		(net "GMI_CPU0_G1_CPU1_G3_TX_DP<2>")
	)
	(arc
		(start 357.15067 -229.397052)
		(mid 357.037263 -229.264163)
		(end 356.996492 -229.094284)
		(width 0.1143)
		(layer "In15.Cu")
		(net "GMI_CPU0_G1_CPU1_G3_TX_DP<2>")
	)
	(arc
		(start 114.25301 -239.173512)
		(mid 114.021541 -239.624362)
		(end 114.25301 -240.075212)
		(width 0.1143)
		(layer "In15.Cu")
		(net "GMI_CPU0_G1_CPU1_G3_TX_DP<2>")
	)
	(arc
		(start 114.343434 -233.650028)
		(mid 114.499362 -233.95432)
		(end 114.343434 -234.258612)
		(width 0.1143)
		(layer "In15.Cu")
		(net "GMI_CPU0_G1_CPU1_G3_TX_DP<2>")
	)
	(arc
		(start 356.526338 -225.042222)
		(mid 356.464513 -224.786061)
		(end 356.292658 -224.586292)
		(width 0.1143)
		(layer "In15.Cu")
		(net "GMI_CPU0_G1_CPU1_G3_TX_DP<2>")
	)
	(arc
		(start 356.996492 -229.094284)
		(mid 357.037747 -228.923313)
		(end 357.152448 -228.789992)
		(width 0.1143)
		(layer "In15.Cu")
		(net "GMI_CPU0_G1_CPU1_G3_TX_DP<2>")
	)
	(arc
		(start 357.234744 -240.080546)
		(mid 357.462127 -239.624108)
		(end 357.234744 -239.16767)
		(width 0.1143)
		(layer "In15.Cu")
		(net "GMI_CPU0_G1_CPU1_G3_TX_DP<2>")
	)
	(arc
		(start 114.31143 -237.517178)
		(mid 114.030783 -238.00454)
		(end 114.31143 -238.491776)
		(width 0.1143)
		(layer "In15.Cu")
		(net "GMI_CPU0_G1_CPU1_G3_TX_DP<2>")
	)
	(arc
		(start 114.260122 -227.828856)
		(mid 114.034951 -228.284532)
		(end 114.260122 -228.740208)
		(width 0.1143)
		(layer "In15.Cu")
		(net "GMI_CPU0_G1_CPU1_G3_TX_DP<2>")
	)
	(arc
		(start 114.02949 -229.88651)
		(mid 114.03003 -229.91671)
		(end 114.033554 -229.946708)
		(width 0.1143)
		(layer "In15.Cu")
		(net "GMI_CPU0_G1_CPU1_G3_TX_DP<2>")
	)
	(arc
		(start 357.184706 -228.771704)
		(mid 357.465353 -228.284278)
		(end 357.184706 -227.796852)
		(width 0.1143)
		(layer "In15.Cu")
		(net "GMI_CPU0_G1_CPU1_G3_TX_DP<2>")
	)
	(arc
		(start 114.343434 -240.130076)
		(mid 114.499362 -240.434368)
		(end 114.343434 -240.73866)
		(width 0.1143)
		(layer "In15.Cu")
		(net "GMI_CPU0_G1_CPU1_G3_TX_DP<2>")
	)
	(arc
		(start 357.18496 -227.151184)
		(mid 357.465294 -226.664266)
		(end 357.18496 -226.177348)
		(width 0.1143)
		(layer "In15.Cu")
		(net "GMI_CPU0_G1_CPU1_G3_TX_DP<2>")
	)
	(arc
		(start 114.343434 -235.27004)
		(mid 114.499362 -235.574332)
		(end 114.343434 -235.878624)
		(width 0.1143)
		(layer "In15.Cu")
		(net "GMI_CPU0_G1_CPU1_G3_TX_DP<2>")
	)
	(arc
		(start 357.236776 -234.309158)
		(mid 357.228698 -234.303372)
		(end 357.22052 -234.297728)
		(width 0.1143)
		(layer "In15.Cu")
		(net "GMI_CPU0_G1_CPU1_G3_TX_DP<2>")
	)
	(arc
		(start 357.466392 -231.530652)
		(mid 357.466402 -231.52735)
		(end 357.466392 -231.524048)
		(width 0.1143)
		(layer "In15.Cu")
		(net "GMI_CPU0_G1_CPU1_G3_TX_DP<2>")
	)
	(arc
		(start 114.258598 -232.6894)
		(mid 114.024886 -233.144314)
		(end 114.258598 -233.599228)
		(width 0.1143)
		(layer "In15.Cu")
		(net "GMI_CPU0_G1_CPU1_G3_TX_DP<2>")
	)
	(arc
		(start 356.282498 -223.88957)
		(mid 356.283515 -223.888936)
		(end 356.28453 -223.8883)
		(width 0.1143)
		(layer "In15.Cu")
		(net "GMI_CPU0_G1_CPU1_G3_TX_DP<2>")
	)
	(arc
		(start 114.260122 -228.740208)
		(mid 114.267698 -228.745604)
		(end 114.275362 -228.750876)
		(width 0.1143)
		(layer "In15.Cu")
		(net "GMI_CPU0_G1_CPU1_G3_TX_DP<2>")
	)
	(arc
		(start 114.205004 -229.494842)
		(mid 114.078631 -229.673365)
		(end 114.02949 -229.88651)
		(width 0.1143)
		(layer "In15.Cu")
		(net "GMI_CPU0_G1_CPU1_G3_TX_DP<2>")
	)
	(arc
		(start 357.236776 -235.218986)
		(mid 357.45966 -234.764072)
		(end 357.236776 -234.309158)
		(width 0.1143)
		(layer "In15.Cu")
		(net "GMI_CPU0_G1_CPU1_G3_TX_DP<2>")
	)
	(arc
		(start 114.02949 -221.804484)
		(mid 114.093937 -222.066636)
		(end 114.272568 -222.26905)
		(width 0.1143)
		(layer "In15.Cu")
		(net "GMI_CPU0_G1_CPU1_G3_TX_DP<2>")
	)
	(arc
		(start 357.234744 -237.547658)
		(mid 357.227671 -237.542649)
		(end 357.22052 -237.537752)
		(width 0.1143)
		(layer "In15.Cu")
		(net "GMI_CPU0_G1_CPU1_G3_TX_DP<2>")
	)
	(arc
		(start 357.251 -243.308886)
		(mid 357.479 -242.864132)
		(end 357.251 -242.419378)
		(width 0.1143)
		(layer "In15.Cu")
		(net "GMI_CPU0_G1_CPU1_G3_TX_DP<2>")
	)
	(arc
		(start 357.22052 -233.610404)
		(mid 357.228698 -233.604761)
		(end 357.236776 -233.598974)
		(width 0.1143)
		(layer "In15.Cu")
		(net "GMI_CPU0_G1_CPU1_G3_TX_DP<2>")
	)
	(arc
		(start 114.364262 -230.42626)
		(mid 114.463915 -230.555361)
		(end 114.49939 -230.71455)
		(width 0.1143)
		(layer "In15.Cu")
		(net "GMI_CPU0_G1_CPU1_G3_TX_DP<2>")
	)
	(arc
		(start 357.22052 -231.990392)
		(mid 357.228698 -231.984749)
		(end 357.236776 -231.978962)
		(width 0.1143)
		(layer "In15.Cu")
		(net "GMI_CPU0_G1_CPU1_G3_TX_DP<2>")
	)
	(arc
		(start 357.152448 -226.158552)
		(mid 357.037772 -226.025218)
		(end 356.996492 -225.85426)
		(width 0.1143)
		(layer "In15.Cu")
		(net "GMI_CPU0_G1_CPU1_G3_TX_DP<2>")
	)
	(arc
		(start 357.152448 -235.87837)
		(mid 356.99652 -235.574078)
		(end 357.152448 -235.269786)
		(width 0.1143)
		(layer "In15.Cu")
		(net "GMI_CPU0_G1_CPU1_G3_TX_DP<2>")
	)
	(arc
		(start 114.258598 -226.209606)
		(mid 114.024886 -226.66452)
		(end 114.258598 -227.119434)
		(width 0.1143)
		(layer "In15.Cu")
		(net "GMI_CPU0_G1_CPU1_G3_TX_DP<2>")
	)
	(arc
		(start 114.30889 -240.758472)
		(mid 114.029055 -241.244374)
		(end 114.30889 -241.730276)
		(width 0.1143)
		(layer "In15.Cu")
		(net "GMI_CPU0_G1_CPU1_G3_TX_DP<2>")
	)
	(arc
		(start 356.056692 -224.230946)
		(mid 356.101922 -224.063694)
		(end 356.212394 -223.93021)
		(width 0.1143)
		(layer "In15.Cu")
		(net "GMI_CPU0_G1_CPU1_G3_TX_DP<2>")
	)
	(arc
		(start 114.245644 -234.319064)
		(mid 114.017448 -234.764506)
		(end 114.245644 -235.209842)
		(width 0.1143)
		(layer "In15.Cu")
		(net "GMI_CPU0_G1_CPU1_G3_TX_DP<2>")
	)
	(arc
		(start 114.275362 -235.917994)
		(mid 114.269239 -235.922146)
		(end 114.26317 -235.926376)
		(width 0.1143)
		(layer "In15.Cu")
		(net "GMI_CPU0_G1_CPU1_G3_TX_DP<2>")
	)
	(arc
		(start 114.259106 -222.969582)
		(mid 114.036222 -223.424496)
		(end 114.259106 -223.87941)
		(width 0.1143)
		(layer "In15.Cu")
		(net "GMI_CPU0_G1_CPU1_G3_TX_DP<2>")
	)
	(arc
		(start 114.343434 -223.93021)
		(mid 114.499362 -224.234502)
		(end 114.343434 -224.538794)
		(width 0.1143)
		(layer "In15.Cu")
		(net "GMI_CPU0_G1_CPU1_G3_TX_DP<2>")
	)
	(arc
		(start 357.150416 -231.017064)
		(mid 356.99636 -230.712007)
		(end 357.154226 -230.408988)
		(width 0.1143)
		(layer "In15.Cu")
		(net "GMI_CPU0_G1_CPU1_G3_TX_DP<2>")
	)
	(arc
		(start 357.33863 -229.545896)
		(mid 357.281475 -229.483634)
		(end 357.213154 -229.433882)
		(width 0.1143)
		(layer "In15.Cu")
		(net "GMI_CPU0_G1_CPU1_G3_TX_DP<2>")
	)
	(arc
		(start 114.260122 -224.588578)
		(mid 114.025583 -225.044508)
		(end 114.260122 -225.500438)
		(width 0.1143)
		(layer "In15.Cu")
		(net "GMI_CPU0_G1_CPU1_G3_TX_DP<2>")
	)
	(arc
		(start 114.26317 -236.8423)
		(mid 114.269238 -236.846532)
		(end 114.275362 -236.850682)
		(width 0.1143)
		(layer "In15.Cu")
		(net "GMI_CPU0_G1_CPU1_G3_TX_DP<2>")
	)
	(arc
		(start 356.28453 -223.888046)
		(mid 356.462595 -223.685869)
		(end 356.526846 -223.424242)
		(width 0.1143)
		(layer "In15.Cu")
		(net "GMI_CPU0_G1_CPU1_G3_TX_DP<2>")
	)
	(arc
		(start 357.229664 -230.3653)
		(mid 357.389163 -230.16396)
		(end 357.464868 -229.918514)
		(width 0.1143)
		(layer "In15.Cu")
		(net "GMI_CPU0_G1_CPU1_G3_TX_DP<2>")
	)
	(arc
		(start 357.236776 -231.978962)
		(mid 357.401443 -231.780355)
		(end 357.466392 -231.530652)
		(width 0.1143)
		(layer "In15.Cu")
		(net "GMI_CPU0_G1_CPU1_G3_TX_DP<2>")
	)
	(arc
		(start 356.526846 -223.424242)
		(mid 356.462553 -223.162637)
		(end 356.28453 -222.960438)
		(width 0.1143)
		(layer "In15.Cu")
		(net "GMI_CPU0_G1_CPU1_G3_TX_DP<2>")
	)
	(arc
		(start 114.343434 -222.310198)
		(mid 114.499362 -222.61449)
		(end 114.343434 -222.918782)
		(width 0.1143)
		(layer "In15.Cu")
		(net "GMI_CPU0_G1_CPU1_G3_TX_DP<2>")
	)
	(arc
		(start 114.31143 -242.377214)
		(mid 114.030783 -242.864576)
		(end 114.31143 -243.351812)
		(width 0.1143)
		(layer "In15.Cu")
		(net "GMI_CPU0_G1_CPU1_G3_TX_DP<2>")
	)
	(arc
		(start 114.275362 -222.958152)
		(mid 114.267184 -222.963795)
		(end 114.259106 -222.969582)
		(width 0.1143)
		(layer "In15.Cu")
		(net "GMI_CPU0_G1_CPU1_G3_TX_DP<2>")
	)
	(arc
		(start 357.464868 -229.918514)
		(mid 357.431437 -229.722273)
		(end 357.33863 -229.54615)
		(width 0.1143)
		(layer "In15.Cu")
		(net "GMI_CPU0_G1_CPU1_G3_TX_DP<2>")
	)
	(arc
		(start 114.343434 -238.510064)
		(mid 114.499362 -238.814356)
		(end 114.343434 -239.118648)
		(width 0.1143)
		(layer "In15.Cu")
		(net "GMI_CPU0_G1_CPU1_G3_TX_DP<2>")
	)
	(arc
		(start 114.343434 -241.750088)
		(mid 114.499362 -242.05438)
		(end 114.343434 -242.358672)
		(width 0.1143)
		(layer "In15.Cu")
		(net "GMI_CPU0_G1_CPU1_G3_TX_DP<2>")
	)
	(arc
		(start 357.152448 -239.118394)
		(mid 356.99652 -238.814102)
		(end 357.152448 -238.50981)
		(width 0.1143)
		(layer "In15.Cu")
		(net "GMI_CPU0_G1_CPU1_G3_TX_DP<2>")
	)
	(arc
		(start 356.209346 -222.916242)
		(mid 356.054534 -222.614236)
		(end 356.209346 -222.31223)
		(width 0.1143)
		(layer "In15.Cu")
		(net "GMI_CPU0_G1_CPU1_G3_TX_DP<2>")
	)
	(arc
		(start 356.682548 -225.348292)
		(mid 356.567705 -225.215144)
		(end 356.526338 -225.044254)
		(width 0.1143)
		(layer "In15.Cu")
		(net "GMI_CPU0_G1_CPU1_G3_TX_DP<2>")
	)
	(segment
		(start 113.657888 -247.180354)
		(end 114.12474 -246.914416)
		(width 0.12954)
		(layer "F.Cu")
		(net "GMI_CPU0_G1_CPU1_G3_TX_DP<1>")
	)
	(segment
		(start 357.837994 -247.1801)
		(end 357.371142 -246.914162)
		(width 0.12954)
		(layer "F.Cu")
		(net "GMI_CPU0_G1_CPU1_G3_TX_DP<1>")
	)
	(segment
		(start 358.16032 -227.817934)
		(end 358.123998 -227.796852)
		(width 0.1143)
		(layer "In15.Cu")
		(net "GMI_CPU0_G1_CPU1_G3_TX_DP<1>")
	)
	(segment
		(start 113.371884 -237.516924)
		(end 113.332768 -237.539784)
		(width 0.1143)
		(layer "In15.Cu")
		(net "GMI_CPU0_G1_CPU1_G3_TX_DP<1>")
	)
	(segment
		(start 358.163114 -231.059482)
		(end 358.123998 -231.036622)
		(width 0.1143)
		(layer "In15.Cu")
		(net "GMI_CPU0_G1_CPU1_G3_TX_DP<1>")
	)
	(segment
		(start 113.402364 -226.159314)
		(end 113.371884 -226.177094)
		(width 0.1143)
		(layer "In15.Cu")
		(net "GMI_CPU0_G1_CPU1_G3_TX_DP<1>")
	)
	(segment
		(start 113.335562 -238.470694)
		(end 113.371884 -238.491776)
		(width 0.1143)
		(layer "In15.Cu")
		(net "GMI_CPU0_G1_CPU1_G3_TX_DP<1>")
	)
	(segment
		(start 113.404396 -231.01808)
		(end 113.371884 -231.036876)
		(width 0.1143)
		(layer "In15.Cu")
		(net "GMI_CPU0_G1_CPU1_G3_TX_DP<1>")
	)
	(segment
		(start 308.619398 -175.740822)
		(end 302.917352 -175.740822)
		(width 0.14224)
		(layer "In15.Cu")
		(net "GMI_CPU0_G1_CPU1_G3_TX_DP<1>")
	)
	(segment
		(start 113.371884 -233.63174)
		(end 113.402364 -233.64952)
		(width 0.1143)
		(layer "In15.Cu")
		(net "GMI_CPU0_G1_CPU1_G3_TX_DP<1>")
	)
	(segment
		(start 113.402364 -232.639108)
		(end 113.372646 -232.65638)
		(width 0.1143)
		(layer "In15.Cu")
		(net "GMI_CPU0_G1_CPU1_G3_TX_DP<1>")
	)
	(segment
		(start 113.37163 -233.63174)
		(end 113.371884 -233.63174)
		(width 0.1143)
		(layer "In15.Cu")
		(net "GMI_CPU0_G1_CPU1_G3_TX_DP<1>")
	)
	(segment
		(start 113.371884 -231.036876)
		(end 113.3348 -231.058212)
		(width 0.1143)
		(layer "In15.Cu")
		(net "GMI_CPU0_G1_CPU1_G3_TX_DP<1>")
	)
	(segment
		(start 113.402364 -227.779326)
		(end 113.371884 -227.797106)
		(width 0.1143)
		(layer "In15.Cu")
		(net "GMI_CPU0_G1_CPU1_G3_TX_DP<1>")
	)
	(segment
		(start 358.176322 -239.168686)
		(end 358.166416 -239.16132)
		(width 0.1143)
		(layer "In15.Cu")
		(net "GMI_CPU0_G1_CPU1_G3_TX_DP<1>")
	)
	(segment
		(start 358.16032 -226.197922)
		(end 358.123998 -226.17684)
		(width 0.1143)
		(layer "In15.Cu")
		(net "GMI_CPU0_G1_CPU1_G3_TX_DP<1>")
	)
	(segment
		(start 357.371142 -246.914162)
		(end 357.0732 -246.914162)
		(width 0.1143)
		(layer "In15.Cu")
		(net "GMI_CPU0_G1_CPU1_G3_TX_DP<1>")
	)
	(segment
		(start 113.402364 -222.91929)
		(end 113.371884 -222.93707)
		(width 0.1143)
		(layer "In15.Cu")
		(net "GMI_CPU0_G1_CPU1_G3_TX_DP<1>")
	)
	(segment
		(start 113.371884 -242.37696)
		(end 113.332768 -242.39982)
		(width 0.1143)
		(layer "In15.Cu")
		(net "GMI_CPU0_G1_CPU1_G3_TX_DP<1>")
	)
	(segment
		(start 113.335562 -243.33073)
		(end 113.371884 -243.351812)
		(width 0.1143)
		(layer "In15.Cu")
		(net "GMI_CPU0_G1_CPU1_G3_TX_DP<1>")
	)
	(segment
		(start 358.166416 -235.921296)
		(end 358.093518 -235.878878)
		(width 0.1143)
		(layer "In15.Cu")
		(net "GMI_CPU0_G1_CPU1_G3_TX_DP<1>")
	)
	(segment
		(start 113.371884 -227.151946)
		(end 113.402364 -227.169726)
		(width 0.1143)
		(layer "In15.Cu")
		(net "GMI_CPU0_G1_CPU1_G3_TX_DP<1>")
	)
	(segment
		(start 358.176322 -235.928662)
		(end 358.166416 -235.921296)
		(width 0.1143)
		(layer "In15.Cu")
		(net "GMI_CPU0_G1_CPU1_G3_TX_DP<1>")
	)
	(segment
		(start 358.093518 -233.649266)
		(end 358.093518 -233.64952)
		(width 0.1143)
		(layer "In15.Cu")
		(net "GMI_CPU0_G1_CPU1_G3_TX_DP<1>")
	)
	(segment
		(start 113.402364 -239.119156)
		(end 113.372646 -239.136428)
		(width 0.1143)
		(layer "In15.Cu")
		(net "GMI_CPU0_G1_CPU1_G3_TX_DP<1>")
	)
	(segment
		(start 113.02111 -221.277942)
		(end 113.08969 -221.346522)
		(width 0.1143)
		(layer "In15.Cu")
		(net "GMI_CPU0_G1_CPU1_G3_TX_DP<1>")
	)
	(segment
		(start 357.622348 -244.788436)
		(end 357.612696 -244.781324)
		(width 0.1143)
		(layer "In15.Cu")
		(net "GMI_CPU0_G1_CPU1_G3_TX_DP<1>")
	)
	(segment
		(start 357.223314 -224.579688)
		(end 357.186738 -224.558352)
		(width 0.1143)
		(layer "In15.Cu")
		(net "GMI_CPU0_G1_CPU1_G3_TX_DP<1>")
	)
	(segment
		(start 113.372646 -239.136428)
		(end 113.371884 -239.136936)
		(width 0.1143)
		(layer "In15.Cu")
		(net "GMI_CPU0_G1_CPU1_G3_TX_DP<1>")
	)
	(segment
		(start 358.405684 -229.888288)
		(end 358.403906 -229.87508)
		(width 0.1143)
		(layer "In15.Cu")
		(net "GMI_CPU0_G1_CPU1_G3_TX_DP<1>")
	)
	(segment
		(start 357.184198 -222.291656)
		(end 357.185214 -222.291148)
		(width 0.1143)
		(layer "In15.Cu")
		(net "GMI_CPU0_G1_CPU1_G3_TX_DP<1>")
	)
	(segment
		(start 357.662988 -245.776242)
		(end 357.693214 -245.758716)
		(width 0.1143)
		(layer "In15.Cu")
		(net "GMI_CPU0_G1_CPU1_G3_TX_DP<1>")
	)
	(segment
		(start 358.166416 -240.086896)
		(end 358.176322 -240.07953)
		(width 0.1143)
		(layer "In15.Cu")
		(net "GMI_CPU0_G1_CPU1_G3_TX_DP<1>")
	)
	(segment
		(start 358.123998 -226.17684)
		(end 358.093518 -226.15906)
		(width 0.1143)
		(layer "In15.Cu")
		(net "GMI_CPU0_G1_CPU1_G3_TX_DP<1>")
	)
	(segment
		(start 113.02111 -221.066106)
		(end 113.02111 -221.277942)
		(width 0.1143)
		(layer "In15.Cu")
		(net "GMI_CPU0_G1_CPU1_G3_TX_DP<1>")
	)
	(segment
		(start 113.332768 -228.749098)
		(end 113.371884 -228.771958)
		(width 0.1143)
		(layer "In15.Cu")
		(net "GMI_CPU0_G1_CPU1_G3_TX_DP<1>")
	)
	(segment
		(start 113.404396 -229.398068)
		(end 113.371884 -229.416864)
		(width 0.1143)
		(layer "In15.Cu")
		(net "GMI_CPU0_G1_CPU1_G3_TX_DP<1>")
	)
	(segment
		(start 357.17988 -224.554288)
		(end 357.178356 -224.553526)
		(width 0.1143)
		(layer "In15.Cu")
		(net "GMI_CPU0_G1_CPU1_G3_TX_DP<1>")
	)
	(segment
		(start 358.093518 -233.64952)
		(end 358.166416 -233.606848)
		(width 0.1143)
		(layer "In15.Cu")
		(net "GMI_CPU0_G1_CPU1_G3_TX_DP<1>")
	)
	(segment
		(start 113.371884 -229.416864)
		(end 113.332768 -229.439724)
		(width 0.1143)
		(layer "In15.Cu")
		(net "GMI_CPU0_G1_CPU1_G3_TX_DP<1>")
	)
	(segment
		(start 357.660956 -245.777512)
		(end 357.662988 -245.776242)
		(width 0.1143)
		(layer "In15.Cu")
		(net "GMI_CPU0_G1_CPU1_G3_TX_DP<1>")
	)
	(segment
		(start 113.841784 -245.78183)
		(end 113.842038 -245.782084)
		(width 0.1143)
		(layer "In15.Cu")
		(net "GMI_CPU0_G1_CPU1_G3_TX_DP<1>")
	)
	(segment
		(start 358.093518 -240.129568)
		(end 358.166416 -240.086896)
		(width 0.1143)
		(layer "In15.Cu")
		(net "GMI_CPU0_G1_CPU1_G3_TX_DP<1>")
	)
	(segment
		(start 113.371884 -240.111788)
		(end 113.402364 -240.129568)
		(width 0.1143)
		(layer "In15.Cu")
		(net "GMI_CPU0_G1_CPU1_G3_TX_DP<1>")
	)
	(segment
		(start 357.186738 -224.558352)
		(end 357.185214 -224.557336)
		(width 0.1143)
		(layer "In15.Cu")
		(net "GMI_CPU0_G1_CPU1_G3_TX_DP<1>")
	)
	(segment
		(start 113.335562 -236.850682)
		(end 113.371884 -236.871764)
		(width 0.1143)
		(layer "In15.Cu")
		(net "GMI_CPU0_G1_CPU1_G3_TX_DP<1>")
	)
	(segment
		(start 113.332768 -227.129086)
		(end 113.371884 -227.151946)
		(width 0.1143)
		(layer "In15.Cu")
		(net "GMI_CPU0_G1_CPU1_G3_TX_DP<1>")
	)
	(segment
		(start 358.166416 -239.16132)
		(end 358.093518 -239.118902)
		(width 0.1143)
		(layer "In15.Cu")
		(net "GMI_CPU0_G1_CPU1_G3_TX_DP<1>")
	)
	(segment
		(start 357.650034 -245.783862)
		(end 357.653844 -245.78183)
		(width 0.1143)
		(layer "In15.Cu")
		(net "GMI_CPU0_G1_CPU1_G3_TX_DP<1>")
	)
	(segment
		(start 357.466646 -221.30893)
		(end 357.466392 -221.308676)
		(width 0.1143)
		(layer "In15.Cu")
		(net "GMI_CPU0_G1_CPU1_G3_TX_DP<1>")
	)
	(segment
		(start 113.371884 -238.491776)
		(end 113.402364 -238.509556)
		(width 0.1143)
		(layer "In15.Cu")
		(net "GMI_CPU0_G1_CPU1_G3_TX_DP<1>")
	)
	(segment
		(start 358.16413 -240.780062)
		(end 358.123998 -240.756694)
		(width 0.1143)
		(layer "In15.Cu")
		(net "GMI_CPU0_G1_CPU1_G3_TX_DP<1>")
	)
	(segment
		(start 112.97539 -216.623392)
		(end 112.97539 -220.991938)
		(width 0.14224)
		(layer "In15.Cu")
		(net "GMI_CPU0_G1_CPU1_G3_TX_DP<1>")
	)
	(segment
		(start 358.093518 -243.369592)
		(end 358.163114 -243.328698)
		(width 0.1143)
		(layer "In15.Cu")
		(net "GMI_CPU0_G1_CPU1_G3_TX_DP<1>")
	)
	(segment
		(start 357.177594 -224.553018)
		(end 357.176578 -224.55251)
		(width 0.1143)
		(layer "In15.Cu")
		(net "GMI_CPU0_G1_CPU1_G3_TX_DP<1>")
	)
	(segment
		(start 113.371884 -227.797106)
		(end 113.332768 -227.819966)
		(width 0.1143)
		(layer "In15.Cu")
		(net "GMI_CPU0_G1_CPU1_G3_TX_DP<1>")
	)
	(segment
		(start 113.371884 -239.136936)
		(end 113.37163 -239.13719)
		(width 0.1143)
		(layer "In15.Cu")
		(net "GMI_CPU0_G1_CPU1_G3_TX_DP<1>")
	)
	(segment
		(start 357.660194 -245.77802)
		(end 357.660956 -245.777512)
		(width 0.1143)
		(layer "In15.Cu")
		(net "GMI_CPU0_G1_CPU1_G3_TX_DP<1>")
	)
	(segment
		(start 113.089436 -238.00435)
		(end 113.08969 -238.00435)
		(width 0.1143)
		(layer "In15.Cu")
		(net "GMI_CPU0_G1_CPU1_G3_TX_DP<1>")
	)
	(segment
		(start 357.152448 -246.610124)
		(end 357.18369 -246.591836)
		(width 0.1143)
		(layer "In15.Cu")
		(net "GMI_CPU0_G1_CPU1_G3_TX_DP<1>")
	)
	(segment
		(start 358.123998 -228.771704)
		(end 358.16032 -228.750622)
		(width 0.1143)
		(layer "In15.Cu")
		(net "GMI_CPU0_G1_CPU1_G3_TX_DP<1>")
	)
	(segment
		(start 358.166416 -233.606848)
		(end 358.176322 -233.599482)
		(width 0.1143)
		(layer "In15.Cu")
		(net "GMI_CPU0_G1_CPU1_G3_TX_DP<1>")
	)
	(segment
		(start 113.371884 -226.177094)
		(end 113.332768 -226.199954)
		(width 0.1143)
		(layer "In15.Cu")
		(net "GMI_CPU0_G1_CPU1_G3_TX_DP<1>")
	)
	(segment
		(start 357.186738 -222.290132)
		(end 357.223314 -222.268796)
		(width 0.1143)
		(layer "In15.Cu")
		(net "GMI_CPU0_G1_CPU1_G3_TX_DP<1>")
	)
	(segment
		(start 114.02949 -246.10441)
		(end 114.02949 -246.12727)
		(width 0.1143)
		(layer "In15.Cu")
		(net "GMI_CPU0_G1_CPU1_G3_TX_DP<1>")
	)
	(segment
		(start 113.08969 -221.346522)
		(end 113.08969 -221.804484)
		(width 0.1143)
		(layer "In15.Cu")
		(net "GMI_CPU0_G1_CPU1_G3_TX_DP<1>")
	)
	(segment
		(start 318.16675 -180.572156)
		(end 311.36844 -176.723802)
		(width 0.14224)
		(layer "In15.Cu")
		(net "GMI_CPU0_G1_CPU1_G3_TX_DP<1>")
	)
	(segment
		(start 113.371884 -240.756948)
		(end 113.332768 -240.779808)
		(width 0.1143)
		(layer "In15.Cu")
		(net "GMI_CPU0_G1_CPU1_G3_TX_DP<1>")
	)
	(segment
		(start 113.802668 -245.75897)
		(end 113.809526 -245.763034)
		(width 0.1143)
		(layer "In15.Cu")
		(net "GMI_CPU0_G1_CPU1_G3_TX_DP<1>")
	)
	(segment
		(start 357.176578 -224.55251)
		(end 357.152448 -224.53854)
		(width 0.1143)
		(layer "In15.Cu")
		(net "GMI_CPU0_G1_CPU1_G3_TX_DP<1>")
	)
	(segment
		(start 357.178356 -224.553526)
		(end 357.177594 -224.553018)
		(width 0.1143)
		(layer "In15.Cu")
		(net "GMI_CPU0_G1_CPU1_G3_TX_DP<1>")
	)
	(segment
		(start 357.622348 -244.179852)
		(end 357.654098 -244.161564)
		(width 0.1143)
		(layer "In15.Cu")
		(net "GMI_CPU0_G1_CPU1_G3_TX_DP<1>")
	)
	(segment
		(start 357.466392 -221.308676)
		(end 357.466392 -221.128844)
		(width 0.1143)
		(layer "In15.Cu")
		(net "GMI_CPU0_G1_CPU1_G3_TX_DP<1>")
	)
	(segment
		(start 114.422682 -246.914416)
		(end 114.12474 -246.914416)
		(width 0.1143)
		(layer "In15.Cu")
		(net "GMI_CPU0_G1_CPU1_G3_TX_DP<1>")
	)
	(segment
		(start 113.371884 -222.93707)
		(end 113.332768 -222.95993)
		(width 0.1143)
		(layer "In15.Cu")
		(net "GMI_CPU0_G1_CPU1_G3_TX_DP<1>")
	)
	(segment
		(start 357.18369 -246.591836)
		(end 357.186484 -246.590058)
		(width 0.1143)
		(layer "In15.Cu")
		(net "GMI_CPU0_G1_CPU1_G3_TX_DP<1>")
	)
	(segment
		(start 358.093518 -236.88929)
		(end 358.093518 -236.889544)
		(width 0.1143)
		(layer "In15.Cu")
		(net "GMI_CPU0_G1_CPU1_G3_TX_DP<1>")
	)
	(segment
		(start 112.97539 -220.991938)
		(end 112.97539 -221.020386)
		(width 0.1143)
		(layer "In15.Cu")
		(net "GMI_CPU0_G1_CPU1_G3_TX_DP<1>")
	)
	(segment
		(start 357.185214 -222.291148)
		(end 357.186738 -222.290132)
		(width 0.1143)
		(layer "In15.Cu")
		(net "GMI_CPU0_G1_CPU1_G3_TX_DP<1>")
	)
	(segment
		(start 113.371884 -244.971824)
		(end 113.402364 -244.989604)
		(width 0.1143)
		(layer "In15.Cu")
		(net "GMI_CPU0_G1_CPU1_G3_TX_DP<1>")
	)
	(segment
		(start 357.654098 -225.366834)
		(end 357.623618 -225.349054)
		(width 0.1143)
		(layer "In15.Cu")
		(net "GMI_CPU0_G1_CPU1_G3_TX_DP<1>")
	)
	(segment
		(start 113.371884 -235.896912)
		(end 113.332768 -235.919772)
		(width 0.1143)
		(layer "In15.Cu")
		(net "GMI_CPU0_G1_CPU1_G3_TX_DP<1>")
	)
	(segment
		(start 357.180642 -224.554796)
		(end 357.17988 -224.554288)
		(width 0.1143)
		(layer "In15.Cu")
		(net "GMI_CPU0_G1_CPU1_G3_TX_DP<1>")
	)
	(segment
		(start 358.093518 -232.029254)
		(end 358.123998 -232.011474)
		(width 0.1143)
		(layer "In15.Cu")
		(net "GMI_CPU0_G1_CPU1_G3_TX_DP<1>")
	)
	(segment
		(start 113.332768 -231.988868)
		(end 113.371884 -232.011728)
		(width 0.1143)
		(layer "In15.Cu")
		(net "GMI_CPU0_G1_CPU1_G3_TX_DP<1>")
	)
	(segment
		(start 357.183436 -224.55632)
		(end 357.180642 -224.554796)
		(width 0.1143)
		(layer "In15.Cu")
		(net "GMI_CPU0_G1_CPU1_G3_TX_DP<1>")
	)
	(segment
		(start 114.492532 -246.844566)
		(end 114.422682 -246.914416)
		(width 0.1143)
		(layer "In15.Cu")
		(net "GMI_CPU0_G1_CPU1_G3_TX_DP<1>")
	)
	(segment
		(start 113.37163 -235.251752)
		(end 113.371884 -235.251752)
		(width 0.1143)
		(layer "In15.Cu")
		(net "GMI_CPU0_G1_CPU1_G3_TX_DP<1>")
	)
	(segment
		(start 357.654098 -244.161564)
		(end 357.693214 -244.138704)
		(width 0.1143)
		(layer "In15.Cu")
		(net "GMI_CPU0_G1_CPU1_G3_TX_DP<1>")
	)
	(segment
		(start 113.371884 -236.871764)
		(end 113.402364 -236.889544)
		(width 0.1143)
		(layer "In15.Cu")
		(net "GMI_CPU0_G1_CPU1_G3_TX_DP<1>")
	)
	(segment
		(start 116.397278 -210.798156)
		(end 112.97539 -216.623392)
		(width 0.14224)
		(layer "In15.Cu")
		(net "GMI_CPU0_G1_CPU1_G3_TX_DP<1>")
	)
	(segment
		(start 358.093518 -235.269278)
		(end 358.093518 -235.269532)
		(width 0.1143)
		(layer "In15.Cu")
		(net "GMI_CPU0_G1_CPU1_G3_TX_DP<1>")
	)
	(segment
		(start 113.810288 -245.763542)
		(end 113.841784 -245.78183)
		(width 0.1143)
		(layer "In15.Cu")
		(net "GMI_CPU0_G1_CPU1_G3_TX_DP<1>")
	)
	(segment
		(start 357.187246 -222.941642)
		(end 357.182928 -222.939102)
		(width 0.1143)
		(layer "In15.Cu")
		(net "GMI_CPU0_G1_CPU1_G3_TX_DP<1>")
	)
	(segment
		(start 113.371884 -232.656888)
		(end 113.37163 -232.657142)
		(width 0.1143)
		(layer "In15.Cu")
		(net "GMI_CPU0_G1_CPU1_G3_TX_DP<1>")
	)
	(segment
		(start 112.97539 -221.020386)
		(end 113.02111 -221.066106)
		(width 0.1143)
		(layer "In15.Cu")
		(net "GMI_CPU0_G1_CPU1_G3_TX_DP<1>")
	)
	(segment
		(start 358.166416 -235.22686)
		(end 358.176322 -235.219494)
		(width 0.1143)
		(layer "In15.Cu")
		(net "GMI_CPU0_G1_CPU1_G3_TX_DP<1>")
	)
	(segment
		(start 357.653844 -245.78183)
		(end 357.657146 -245.779798)
		(width 0.1143)
		(layer "In15.Cu")
		(net "GMI_CPU0_G1_CPU1_G3_TX_DP<1>")
	)
	(segment
		(start 113.372646 -232.65638)
		(end 113.371884 -232.656888)
		(width 0.1143)
		(layer "In15.Cu")
		(net "GMI_CPU0_G1_CPU1_G3_TX_DP<1>")
	)
	(segment
		(start 357.693214 -225.389694)
		(end 357.654098 -225.366834)
		(width 0.1143)
		(layer "In15.Cu")
		(net "GMI_CPU0_G1_CPU1_G3_TX_DP<1>")
	)
	(segment
		(start 358.405684 -229.89667)
		(end 358.405684 -229.888288)
		(width 0.1143)
		(layer "In15.Cu")
		(net "GMI_CPU0_G1_CPU1_G3_TX_DP<1>")
	)
	(segment
		(start 357.512112 -217.776044)
		(end 353.690428 -209.700368)
		(width 0.14224)
		(layer "In15.Cu")
		(net "GMI_CPU0_G1_CPU1_G3_TX_DP<1>")
	)
	(segment
		(start 358.093518 -236.889544)
		(end 358.166416 -236.846872)
		(width 0.1143)
		(layer "In15.Cu")
		(net "GMI_CPU0_G1_CPU1_G3_TX_DP<1>")
	)
	(segment
		(start 113.402364 -237.499144)
		(end 113.371884 -237.516924)
		(width 0.1143)
		(layer "In15.Cu")
		(net "GMI_CPU0_G1_CPU1_G3_TX_DP<1>")
	)
	(segment
		(start 358.125776 -229.417626)
		(end 358.091486 -229.397814)
		(width 0.1143)
		(layer "In15.Cu")
		(net "GMI_CPU0_G1_CPU1_G3_TX_DP<1>")
	)
	(segment
		(start 113.332768 -225.509074)
		(end 113.371884 -225.531934)
		(width 0.1143)
		(layer "In15.Cu")
		(net "GMI_CPU0_G1_CPU1_G3_TX_DP<1>")
	)
	(segment
		(start 358.093518 -238.509302)
		(end 358.093518 -238.509556)
		(width 0.1143)
		(layer "In15.Cu")
		(net "GMI_CPU0_G1_CPU1_G3_TX_DP<1>")
	)
	(segment
		(start 358.166416 -236.846872)
		(end 358.176322 -236.839506)
		(width 0.1143)
		(layer "In15.Cu")
		(net "GMI_CPU0_G1_CPU1_G3_TX_DP<1>")
	)
	(segment
		(start 357.612696 -244.186964)
		(end 357.622348 -244.179852)
		(width 0.1143)
		(layer "In15.Cu")
		(net "GMI_CPU0_G1_CPU1_G3_TX_DP<1>")
	)
	(segment
		(start 113.335308 -222.270828)
		(end 113.40338 -222.310198)
		(width 0.1143)
		(layer "In15.Cu")
		(net "GMI_CPU0_G1_CPU1_G3_TX_DP<1>")
	)
	(segment
		(start 357.466392 -221.128844)
		(end 357.512112 -221.083124)
		(width 0.1143)
		(layer "In15.Cu")
		(net "GMI_CPU0_G1_CPU1_G3_TX_DP<1>")
	)
	(segment
		(start 113.371884 -243.996972)
		(end 113.332768 -244.019832)
		(width 0.1143)
		(layer "In15.Cu")
		(net "GMI_CPU0_G1_CPU1_G3_TX_DP<1>")
	)
	(segment
		(start 114.245644 -246.549926)
		(end 114.27206 -246.568722)
		(width 0.1143)
		(layer "In15.Cu")
		(net "GMI_CPU0_G1_CPU1_G3_TX_DP<1>")
	)
	(segment
		(start 358.093518 -235.269532)
		(end 358.166416 -235.22686)
		(width 0.1143)
		(layer "In15.Cu")
		(net "GMI_CPU0_G1_CPU1_G3_TX_DP<1>")
	)
	(segment
		(start 113.371884 -243.351812)
		(end 113.402364 -243.369592)
		(width 0.1143)
		(layer "In15.Cu")
		(net "GMI_CPU0_G1_CPU1_G3_TX_DP<1>")
	)
	(segment
		(start 113.809526 -245.763034)
		(end 113.810288 -245.763542)
		(width 0.1143)
		(layer "In15.Cu")
		(net "GMI_CPU0_G1_CPU1_G3_TX_DP<1>")
	)
	(segment
		(start 113.402364 -243.979192)
		(end 113.371884 -243.996972)
		(width 0.1143)
		(layer "In15.Cu")
		(net "GMI_CPU0_G1_CPU1_G3_TX_DP<1>")
	)
	(segment
		(start 358.16413 -242.39982)
		(end 358.093518 -242.358926)
		(width 0.1143)
		(layer "In15.Cu")
		(net "GMI_CPU0_G1_CPU1_G3_TX_DP<1>")
	)
	(segment
		(start 165.001194 -174.934372)
		(end 156.372306 -178.019964)
		(width 0.14224)
		(layer "In15.Cu")
		(net "GMI_CPU0_G1_CPU1_G3_TX_DP<1>")
	)
	(segment
		(start 113.842546 -245.782338)
		(end 113.84534 -245.783862)
		(width 0.1143)
		(layer "In15.Cu")
		(net "GMI_CPU0_G1_CPU1_G3_TX_DP<1>")
	)
	(segment
		(start 113.371884 -228.771958)
		(end 113.402364 -228.789738)
		(width 0.1143)
		(layer "In15.Cu")
		(net "GMI_CPU0_G1_CPU1_G3_TX_DP<1>")
	)
	(segment
		(start 113.84534 -245.783862)
		(end 113.871502 -245.799102)
		(width 0.1143)
		(layer "In15.Cu")
		(net "GMI_CPU0_G1_CPU1_G3_TX_DP<1>")
	)
	(segment
		(start 113.335308 -230.370634)
		(end 113.402364 -230.40975)
		(width 0.1143)
		(layer "In15.Cu")
		(net "GMI_CPU0_G1_CPU1_G3_TX_DP<1>")
	)
	(segment
		(start 358.166416 -232.681272)
		(end 358.093518 -232.638854)
		(width 0.1143)
		(layer "In15.Cu")
		(net "GMI_CPU0_G1_CPU1_G3_TX_DP<1>")
	)
	(segment
		(start 113.335562 -244.950742)
		(end 113.371884 -244.971824)
		(width 0.1143)
		(layer "In15.Cu")
		(net "GMI_CPU0_G1_CPU1_G3_TX_DP<1>")
	)
	(segment
		(start 113.332768 -223.889062)
		(end 113.371884 -223.911922)
		(width 0.1143)
		(layer "In15.Cu")
		(net "GMI_CPU0_G1_CPU1_G3_TX_DP<1>")
	)
	(segment
		(start 113.402364 -242.35918)
		(end 113.371884 -242.37696)
		(width 0.1143)
		(layer "In15.Cu")
		(net "GMI_CPU0_G1_CPU1_G3_TX_DP<1>")
	)
	(segment
		(start 357.657146 -245.779798)
		(end 357.659178 -245.778528)
		(width 0.1143)
		(layer "In15.Cu")
		(net "GMI_CPU0_G1_CPU1_G3_TX_DP<1>")
	)
	(segment
		(start 113.402364 -234.25912)
		(end 113.372646 -234.276392)
		(width 0.1143)
		(layer "In15.Cu")
		(net "GMI_CPU0_G1_CPU1_G3_TX_DP<1>")
	)
	(segment
		(start 113.402364 -224.539302)
		(end 113.371884 -224.557082)
		(width 0.1143)
		(layer "In15.Cu")
		(net "GMI_CPU0_G1_CPU1_G3_TX_DP<1>")
	)
	(segment
		(start 358.166416 -238.466884)
		(end 358.176322 -238.459518)
		(width 0.1143)
		(layer "In15.Cu")
		(net "GMI_CPU0_G1_CPU1_G3_TX_DP<1>")
	)
	(segment
		(start 113.3348 -231.058212)
		(end 113.332768 -231.059736)
		(width 0.1143)
		(layer "In15.Cu")
		(net "GMI_CPU0_G1_CPU1_G3_TX_DP<1>")
	)
	(segment
		(start 113.842038 -245.782084)
		(end 113.842546 -245.782338)
		(width 0.1143)
		(layer "In15.Cu")
		(net "GMI_CPU0_G1_CPU1_G3_TX_DP<1>")
	)
	(segment
		(start 357.167434 -222.301308)
		(end 357.184198 -222.291656)
		(width 0.1143)
		(layer "In15.Cu")
		(net "GMI_CPU0_G1_CPU1_G3_TX_DP<1>")
	)
	(segment
		(start 113.402364 -240.739168)
		(end 113.371884 -240.756948)
		(width 0.1143)
		(layer "In15.Cu")
		(net "GMI_CPU0_G1_CPU1_G3_TX_DP<1>")
	)
	(segment
		(start 357.466646 -221.80423)
		(end 357.466646 -221.30893)
		(width 0.1143)
		(layer "In15.Cu")
		(net "GMI_CPU0_G1_CPU1_G3_TX_DP<1>")
	)
	(segment
		(start 358.093518 -230.409496)
		(end 358.160574 -230.37038)
		(width 0.1143)
		(layer "In15.Cu")
		(net "GMI_CPU0_G1_CPU1_G3_TX_DP<1>")
	)
	(segment
		(start 358.093518 -241.749326)
		(end 358.16413 -241.708178)
		(width 0.1143)
		(layer "In15.Cu")
		(net "GMI_CPU0_G1_CPU1_G3_TX_DP<1>")
	)
	(segment
		(start 113.371884 -235.251752)
		(end 113.402364 -235.269532)
		(width 0.1143)
		(layer "In15.Cu")
		(net "GMI_CPU0_G1_CPU1_G3_TX_DP<1>")
	)
	(segment
		(start 358.123998 -227.796852)
		(end 358.093518 -227.779072)
		(width 0.1143)
		(layer "In15.Cu")
		(net "GMI_CPU0_G1_CPU1_G3_TX_DP<1>")
	)
	(segment
		(start 358.093518 -228.789484)
		(end 358.123998 -228.771704)
		(width 0.1143)
		(layer "In15.Cu")
		(net "GMI_CPU0_G1_CPU1_G3_TX_DP<1>")
	)
	(segment
		(start 358.176322 -237.548674)
		(end 358.166416 -237.541308)
		(width 0.1143)
		(layer "In15.Cu")
		(net "GMI_CPU0_G1_CPU1_G3_TX_DP<1>")
	)
	(segment
		(start 357.512112 -221.083124)
		(end 357.512112 -217.776044)
		(width 0.14224)
		(layer "In15.Cu")
		(net "GMI_CPU0_G1_CPU1_G3_TX_DP<1>")
	)
	(segment
		(start 358.123998 -232.011474)
		(end 358.163114 -231.988614)
		(width 0.1143)
		(layer "In15.Cu")
		(net "GMI_CPU0_G1_CPU1_G3_TX_DP<1>")
	)
	(segment
		(start 113.371884 -225.531934)
		(end 113.402364 -225.549714)
		(width 0.1143)
		(layer "In15.Cu")
		(net "GMI_CPU0_G1_CPU1_G3_TX_DP<1>")
	)
	(segment
		(start 358.093518 -240.129314)
		(end 358.093518 -240.129568)
		(width 0.1143)
		(layer "In15.Cu")
		(net "GMI_CPU0_G1_CPU1_G3_TX_DP<1>")
	)
	(segment
		(start 358.406192 -229.904036)
		(end 358.405684 -229.89667)
		(width 0.1143)
		(layer "In15.Cu")
		(net "GMI_CPU0_G1_CPU1_G3_TX_DP<1>")
	)
	(segment
		(start 358.159304 -229.437184)
		(end 358.125776 -229.417626)
		(width 0.1143)
		(layer "In15.Cu")
		(net "GMI_CPU0_G1_CPU1_G3_TX_DP<1>")
	)
	(segment
		(start 113.372646 -234.276392)
		(end 113.371884 -234.2769)
		(width 0.1143)
		(layer "In15.Cu")
		(net "GMI_CPU0_G1_CPU1_G3_TX_DP<1>")
	)
	(segment
		(start 357.184198 -224.556828)
		(end 357.183436 -224.55632)
		(width 0.1143)
		(layer "In15.Cu")
		(net "GMI_CPU0_G1_CPU1_G3_TX_DP<1>")
	)
	(segment
		(start 358.123998 -227.151692)
		(end 358.16032 -227.13061)
		(width 0.1143)
		(layer "In15.Cu")
		(net "GMI_CPU0_G1_CPU1_G3_TX_DP<1>")
	)
	(segment
		(start 113.402364 -235.879132)
		(end 113.371884 -235.896912)
		(width 0.1143)
		(layer "In15.Cu")
		(net "GMI_CPU0_G1_CPU1_G3_TX_DP<1>")
	)
	(segment
		(start 357.0732 -246.914162)
		(end 357.00335 -246.844312)
		(width 0.1143)
		(layer "In15.Cu")
		(net "GMI_CPU0_G1_CPU1_G3_TX_DP<1>")
	)
	(segment
		(start 113.335562 -241.710718)
		(end 113.371884 -241.7318)
		(width 0.1143)
		(layer "In15.Cu")
		(net "GMI_CPU0_G1_CPU1_G3_TX_DP<1>")
	)
	(segment
		(start 357.659178 -245.778528)
		(end 357.660194 -245.77802)
		(width 0.1143)
		(layer "In15.Cu")
		(net "GMI_CPU0_G1_CPU1_G3_TX_DP<1>")
	)
	(segment
		(start 302.917352 -175.740822)
		(end 165.001194 -174.934372)
		(width 0.14224)
		(layer "In15.Cu")
		(net "GMI_CPU0_G1_CPU1_G3_TX_DP<1>")
	)
	(segment
		(start 357.152448 -222.310198)
		(end 357.167434 -222.301308)
		(width 0.1143)
		(layer "In15.Cu")
		(net "GMI_CPU0_G1_CPU1_G3_TX_DP<1>")
	)
	(segment
		(start 357.185214 -224.557336)
		(end 357.184198 -224.556828)
		(width 0.1143)
		(layer "In15.Cu")
		(net "GMI_CPU0_G1_CPU1_G3_TX_DP<1>")
	)
	(segment
		(start 113.37163 -240.111788)
		(end 113.371884 -240.111788)
		(width 0.1143)
		(layer "In15.Cu")
		(net "GMI_CPU0_G1_CPU1_G3_TX_DP<1>")
	)
	(segment
		(start 114.27206 -246.568722)
		(end 114.34318 -246.610124)
		(width 0.1143)
		(layer "In15.Cu")
		(net "GMI_CPU0_G1_CPU1_G3_TX_DP<1>")
	)
	(segment
		(start 311.36844 -176.723802)
		(end 308.619398 -175.740822)
		(width 0.14224)
		(layer "In15.Cu")
		(net "GMI_CPU0_G1_CPU1_G3_TX_DP<1>")
	)
	(segment
		(start 113.371884 -232.011728)
		(end 113.402364 -232.029508)
		(width 0.1143)
		(layer "In15.Cu")
		(net "GMI_CPU0_G1_CPU1_G3_TX_DP<1>")
	)
	(segment
		(start 114.34318 -246.610124)
		(end 114.343434 -246.610124)
		(width 0.1143)
		(layer "In15.Cu")
		(net "GMI_CPU0_G1_CPU1_G3_TX_DP<1>")
	)
	(segment
		(start 113.371884 -234.2769)
		(end 113.37163 -234.277154)
		(width 0.1143)
		(layer "In15.Cu")
		(net "GMI_CPU0_G1_CPU1_G3_TX_DP<1>")
	)
	(segment
		(start 358.166416 -234.301284)
		(end 358.093518 -234.258866)
		(width 0.1143)
		(layer "In15.Cu")
		(net "GMI_CPU0_G1_CPU1_G3_TX_DP<1>")
	)
	(segment
		(start 113.371884 -224.557082)
		(end 113.332768 -224.579942)
		(width 0.1143)
		(layer "In15.Cu")
		(net "GMI_CPU0_G1_CPU1_G3_TX_DP<1>")
	)
	(segment
		(start 156.372306 -178.019964)
		(end 116.397278 -210.798156)
		(width 0.14224)
		(layer "In15.Cu")
		(net "GMI_CPU0_G1_CPU1_G3_TX_DP<1>")
	)
	(segment
		(start 358.163114 -243.328698)
		(end 358.17302 -243.321586)
		(width 0.1143)
		(layer "In15.Cu")
		(net "GMI_CPU0_G1_CPU1_G3_TX_DP<1>")
	)
	(segment
		(start 358.176322 -234.30865)
		(end 358.166416 -234.301284)
		(width 0.1143)
		(layer "In15.Cu")
		(net "GMI_CPU0_G1_CPU1_G3_TX_DP<1>")
	)
	(segment
		(start 358.166416 -237.541308)
		(end 358.093518 -237.49889)
		(width 0.1143)
		(layer "In15.Cu")
		(net "GMI_CPU0_G1_CPU1_G3_TX_DP<1>")
	)
	(segment
		(start 113.371884 -241.7318)
		(end 113.402364 -241.74958)
		(width 0.1143)
		(layer "In15.Cu")
		(net "GMI_CPU0_G1_CPU1_G3_TX_DP<1>")
	)
	(segment
		(start 358.093518 -227.169472)
		(end 358.123998 -227.151692)
		(width 0.1143)
		(layer "In15.Cu")
		(net "GMI_CPU0_G1_CPU1_G3_TX_DP<1>")
	)
	(segment
		(start 357.150924 -223.931226)
		(end 357.222806 -223.889316)
		(width 0.1143)
		(layer "In15.Cu")
		(net "GMI_CPU0_G1_CPU1_G3_TX_DP<1>")
	)
	(segment
		(start 358.093518 -243.369338)
		(end 358.093518 -243.369592)
		(width 0.1143)
		(layer "In15.Cu")
		(net "GMI_CPU0_G1_CPU1_G3_TX_DP<1>")
	)
	(segment
		(start 357.693214 -244.829584)
		(end 357.622348 -244.788436)
		(width 0.1143)
		(layer "In15.Cu")
		(net "GMI_CPU0_G1_CPU1_G3_TX_DP<1>")
	)
	(segment
		(start 358.176322 -232.688638)
		(end 358.166416 -232.681272)
		(width 0.1143)
		(layer "In15.Cu")
		(net "GMI_CPU0_G1_CPU1_G3_TX_DP<1>")
	)
	(segment
		(start 358.406446 -229.904036)
		(end 358.406192 -229.904036)
		(width 0.1143)
		(layer "In15.Cu")
		(net "GMI_CPU0_G1_CPU1_G3_TX_DP<1>")
	)
	(segment
		(start 353.690428 -209.700368)
		(end 318.16675 -180.572156)
		(width 0.14224)
		(layer "In15.Cu")
		(net "GMI_CPU0_G1_CPU1_G3_TX_DP<1>")
	)
	(segment
		(start 113.371884 -223.911922)
		(end 113.402364 -223.929702)
		(width 0.1143)
		(layer "In15.Cu")
		(net "GMI_CPU0_G1_CPU1_G3_TX_DP<1>")
	)
	(segment
		(start 358.093518 -238.509556)
		(end 358.166416 -238.466884)
		(width 0.1143)
		(layer "In15.Cu")
		(net "GMI_CPU0_G1_CPU1_G3_TX_DP<1>")
	)
	(segment
		(start 358.123998 -231.036622)
		(end 358.091486 -231.017826)
		(width 0.1143)
		(layer "In15.Cu")
		(net "GMI_CPU0_G1_CPU1_G3_TX_DP<1>")
	)
	(segment
		(start 358.123998 -240.756694)
		(end 358.093518 -240.738914)
		(width 0.1143)
		(layer "In15.Cu")
		(net "GMI_CPU0_G1_CPU1_G3_TX_DP<1>")
	)
	(arc
		(start 113.402364 -233.64952)
		(mid 113.559341 -233.95432)
		(end 113.402364 -234.25912)
		(width 0.1143)
		(layer "In15.Cu")
		(net "GMI_CPU0_G1_CPU1_G3_TX_DP<1>")
	)
	(arc
		(start 357.466646 -225.044254)
		(mid 357.402131 -224.782035)
		(end 357.223314 -224.579688)
		(width 0.1143)
		(layer "In15.Cu")
		(net "GMI_CPU0_G1_CPU1_G3_TX_DP<1>")
	)
	(arc
		(start 358.1908 -229.46106)
		(mid 358.175262 -229.448845)
		(end 358.159304 -229.437184)
		(width 0.1143)
		(layer "In15.Cu")
		(net "GMI_CPU0_G1_CPU1_G3_TX_DP<1>")
	)
	(arc
		(start 357.936546 -230.714296)
		(mid 357.978095 -230.542874)
		(end 358.093518 -230.409496)
		(width 0.1143)
		(layer "In15.Cu")
		(net "GMI_CPU0_G1_CPU1_G3_TX_DP<1>")
	)
	(arc
		(start 357.693214 -245.758716)
		(mid 357.936541 -245.29415)
		(end 357.693214 -244.829584)
		(width 0.1143)
		(layer "In15.Cu")
		(net "GMI_CPU0_G1_CPU1_G3_TX_DP<1>")
	)
	(arc
		(start 358.176322 -233.599482)
		(mid 358.407921 -233.14406)
		(end 358.176322 -232.688638)
		(width 0.1143)
		(layer "In15.Cu")
		(net "GMI_CPU0_G1_CPU1_G3_TX_DP<1>")
	)
	(arc
		(start 358.091486 -229.397814)
		(mid 357.977557 -229.264667)
		(end 357.936546 -229.094284)
		(width 0.1143)
		(layer "In15.Cu")
		(net "GMI_CPU0_G1_CPU1_G3_TX_DP<1>")
	)
	(arc
		(start 113.559336 -230.71455)
		(mid 113.51837 -230.884956)
		(end 113.404396 -231.01808)
		(width 0.1143)
		(layer "In15.Cu")
		(net "GMI_CPU0_G1_CPU1_G3_TX_DP<1>")
	)
	(arc
		(start 357.00335 -246.844312)
		(mid 357.035923 -246.747297)
		(end 357.09352 -246.662702)
		(width 0.1143)
		(layer "In15.Cu")
		(net "GMI_CPU0_G1_CPU1_G3_TX_DP<1>")
	)
	(arc
		(start 358.406446 -242.864132)
		(mid 358.34227 -242.602245)
		(end 358.16413 -242.39982)
		(width 0.1143)
		(layer "In15.Cu")
		(net "GMI_CPU0_G1_CPU1_G3_TX_DP<1>")
	)
	(arc
		(start 113.332768 -237.539784)
		(mid 113.158729 -237.744629)
		(end 113.089436 -238.00435)
		(width 0.1143)
		(layer "In15.Cu")
		(net "GMI_CPU0_G1_CPU1_G3_TX_DP<1>")
	)
	(arc
		(start 357.936546 -243.674138)
		(mid 357.978095 -243.502716)
		(end 358.093518 -243.369338)
		(width 0.1143)
		(layer "In15.Cu")
		(net "GMI_CPU0_G1_CPU1_G3_TX_DP<1>")
	)
	(arc
		(start 357.936546 -225.85426)
		(mid 357.872031 -225.592041)
		(end 357.693214 -225.389694)
		(width 0.1143)
		(layer "In15.Cu")
		(net "GMI_CPU0_G1_CPU1_G3_TX_DP<1>")
	)
	(arc
		(start 113.08969 -238.00435)
		(mid 113.154926 -238.267941)
		(end 113.335562 -238.470694)
		(width 0.1143)
		(layer "In15.Cu")
		(net "GMI_CPU0_G1_CPU1_G3_TX_DP<1>")
	)
	(arc
		(start 113.332768 -240.779808)
		(mid 113.171536 -240.975927)
		(end 113.092484 -241.217196)
		(width 0.1143)
		(layer "In15.Cu")
		(net "GMI_CPU0_G1_CPU1_G3_TX_DP<1>")
	)
	(arc
		(start 113.40338 -222.310198)
		(mid 113.518056 -222.443532)
		(end 113.559336 -222.61449)
		(width 0.1143)
		(layer "In15.Cu")
		(net "GMI_CPU0_G1_CPU1_G3_TX_DP<1>")
	)
	(arc
		(start 113.402364 -238.509556)
		(mid 113.559341 -238.814356)
		(end 113.402364 -239.119156)
		(width 0.1143)
		(layer "In15.Cu")
		(net "GMI_CPU0_G1_CPU1_G3_TX_DP<1>")
	)
	(arc
		(start 113.402364 -244.989604)
		(mid 113.517791 -245.12298)
		(end 113.559336 -245.294404)
		(width 0.1143)
		(layer "In15.Cu")
		(net "GMI_CPU0_G1_CPU1_G3_TX_DP<1>")
	)
	(arc
		(start 357.152448 -224.53854)
		(mid 356.996416 -224.235238)
		(end 357.150924 -223.931226)
		(width 0.1143)
		(layer "In15.Cu")
		(net "GMI_CPU0_G1_CPU1_G3_TX_DP<1>")
	)
	(arc
		(start 113.332768 -231.059736)
		(mid 113.153974 -231.262224)
		(end 113.089436 -231.524556)
		(width 0.1143)
		(layer "In15.Cu")
		(net "GMI_CPU0_G1_CPU1_G3_TX_DP<1>")
	)
	(arc
		(start 114.02949 -246.12727)
		(mid 114.086617 -246.364649)
		(end 114.245644 -246.549926)
		(width 0.1143)
		(layer "In15.Cu")
		(net "GMI_CPU0_G1_CPU1_G3_TX_DP<1>")
	)
	(arc
		(start 358.163114 -231.988614)
		(mid 358.406441 -231.524048)
		(end 358.163114 -231.059482)
		(width 0.1143)
		(layer "In15.Cu")
		(net "GMI_CPU0_G1_CPU1_G3_TX_DP<1>")
	)
	(arc
		(start 358.091486 -231.017826)
		(mid 357.977557 -230.884679)
		(end 357.936546 -230.714296)
		(width 0.1143)
		(layer "In15.Cu")
		(net "GMI_CPU0_G1_CPU1_G3_TX_DP<1>")
	)
	(arc
		(start 357.623618 -225.349054)
		(mid 357.508191 -225.215678)
		(end 357.466646 -225.044254)
		(width 0.1143)
		(layer "In15.Cu")
		(net "GMI_CPU0_G1_CPU1_G3_TX_DP<1>")
	)
	(arc
		(start 113.402364 -225.549714)
		(mid 113.559341 -225.854514)
		(end 113.402364 -226.159314)
		(width 0.1143)
		(layer "In15.Cu")
		(net "GMI_CPU0_G1_CPU1_G3_TX_DP<1>")
	)
	(arc
		(start 113.332768 -226.199954)
		(mid 113.089441 -226.66452)
		(end 113.332768 -227.129086)
		(width 0.1143)
		(layer "In15.Cu")
		(net "GMI_CPU0_G1_CPU1_G3_TX_DP<1>")
	)
	(arc
		(start 113.37163 -239.13719)
		(mid 113.091866 -239.624552)
		(end 113.37163 -240.111788)
		(width 0.1143)
		(layer "In15.Cu")
		(net "GMI_CPU0_G1_CPU1_G3_TX_DP<1>")
	)
	(arc
		(start 357.936546 -229.094284)
		(mid 357.978095 -228.922862)
		(end 358.093518 -228.789484)
		(width 0.1143)
		(layer "In15.Cu")
		(net "GMI_CPU0_G1_CPU1_G3_TX_DP<1>")
	)
	(arc
		(start 113.402364 -223.929702)
		(mid 113.559341 -224.234502)
		(end 113.402364 -224.539302)
		(width 0.1143)
		(layer "In15.Cu")
		(net "GMI_CPU0_G1_CPU1_G3_TX_DP<1>")
	)
	(arc
		(start 357.182928 -222.939102)
		(mid 357.046465 -222.801485)
		(end 356.996492 -222.614236)
		(width 0.1143)
		(layer "In15.Cu")
		(net "GMI_CPU0_G1_CPU1_G3_TX_DP<1>")
	)
	(arc
		(start 113.332768 -229.439724)
		(mid 113.153974 -229.642212)
		(end 113.089436 -229.904544)
		(width 0.1143)
		(layer "In15.Cu")
		(net "GMI_CPU0_G1_CPU1_G3_TX_DP<1>")
	)
	(arc
		(start 358.403906 -229.87508)
		(mid 358.332293 -229.650089)
		(end 358.1908 -229.46106)
		(width 0.1143)
		(layer "In15.Cu")
		(net "GMI_CPU0_G1_CPU1_G3_TX_DP<1>")
	)
	(arc
		(start 356.996492 -222.614236)
		(mid 357.037751 -222.443379)
		(end 357.152448 -222.310198)
		(width 0.1143)
		(layer "In15.Cu")
		(net "GMI_CPU0_G1_CPU1_G3_TX_DP<1>")
	)
	(arc
		(start 358.16032 -227.13061)
		(mid 358.40621 -226.664266)
		(end 358.16032 -226.197922)
		(width 0.1143)
		(layer "In15.Cu")
		(net "GMI_CPU0_G1_CPU1_G3_TX_DP<1>")
	)
	(arc
		(start 358.093518 -239.118902)
		(mid 357.936541 -238.814102)
		(end 358.093518 -238.509302)
		(width 0.1143)
		(layer "In15.Cu")
		(net "GMI_CPU0_G1_CPU1_G3_TX_DP<1>")
	)
	(arc
		(start 113.090198 -242.889278)
		(mid 113.160818 -243.138944)
		(end 113.335562 -243.33073)
		(width 0.1143)
		(layer "In15.Cu")
		(net "GMI_CPU0_G1_CPU1_G3_TX_DP<1>")
	)
	(arc
		(start 113.332768 -227.819966)
		(mid 113.089441 -228.284532)
		(end 113.332768 -228.749098)
		(width 0.1143)
		(layer "In15.Cu")
		(net "GMI_CPU0_G1_CPU1_G3_TX_DP<1>")
	)
	(arc
		(start 113.871502 -245.799102)
		(mid 113.987549 -245.932573)
		(end 114.02949 -246.10441)
		(width 0.1143)
		(layer "In15.Cu")
		(net "GMI_CPU0_G1_CPU1_G3_TX_DP<1>")
	)
	(arc
		(start 113.090198 -236.408976)
		(mid 113.160766 -236.65878)
		(end 113.335562 -236.850682)
		(width 0.1143)
		(layer "In15.Cu")
		(net "GMI_CPU0_G1_CPU1_G3_TX_DP<1>")
	)
	(arc
		(start 113.332768 -224.579942)
		(mid 113.089441 -225.044508)
		(end 113.332768 -225.509074)
		(width 0.1143)
		(layer "In15.Cu")
		(net "GMI_CPU0_G1_CPU1_G3_TX_DP<1>")
	)
	(arc
		(start 358.093518 -235.878878)
		(mid 357.936541 -235.574078)
		(end 358.093518 -235.269278)
		(width 0.1143)
		(layer "In15.Cu")
		(net "GMI_CPU0_G1_CPU1_G3_TX_DP<1>")
	)
	(arc
		(start 358.16032 -228.750622)
		(mid 358.40621 -228.284278)
		(end 358.16032 -227.817934)
		(width 0.1143)
		(layer "In15.Cu")
		(net "GMI_CPU0_G1_CPU1_G3_TX_DP<1>")
	)
	(arc
		(start 113.092484 -241.217196)
		(mid 113.090227 -241.243182)
		(end 113.090198 -241.269266)
		(width 0.1143)
		(layer "In15.Cu")
		(net "GMI_CPU0_G1_CPU1_G3_TX_DP<1>")
	)
	(arc
		(start 113.402364 -243.369592)
		(mid 113.559341 -243.674392)
		(end 113.402364 -243.979192)
		(width 0.1143)
		(layer "In15.Cu")
		(net "GMI_CPU0_G1_CPU1_G3_TX_DP<1>")
	)
	(arc
		(start 113.559336 -229.094538)
		(mid 113.51837 -229.264944)
		(end 113.404396 -229.398068)
		(width 0.1143)
		(layer "In15.Cu")
		(net "GMI_CPU0_G1_CPU1_G3_TX_DP<1>")
	)
	(arc
		(start 358.093518 -232.638854)
		(mid 357.936541 -232.334054)
		(end 358.093518 -232.029254)
		(width 0.1143)
		(layer "In15.Cu")
		(net "GMI_CPU0_G1_CPU1_G3_TX_DP<1>")
	)
	(arc
		(start 113.332768 -244.019832)
		(mid 113.171665 -244.215883)
		(end 113.092484 -244.456966)
		(width 0.1143)
		(layer "In15.Cu")
		(net "GMI_CPU0_G1_CPU1_G3_TX_DP<1>")
	)
	(arc
		(start 113.089436 -229.904544)
		(mid 113.154711 -230.168019)
		(end 113.335308 -230.370634)
		(width 0.1143)
		(layer "In15.Cu")
		(net "GMI_CPU0_G1_CPU1_G3_TX_DP<1>")
	)
	(arc
		(start 113.402364 -240.129568)
		(mid 113.559341 -240.434368)
		(end 113.402364 -240.739168)
		(width 0.1143)
		(layer "In15.Cu")
		(net "GMI_CPU0_G1_CPU1_G3_TX_DP<1>")
	)
	(arc
		(start 113.402364 -236.889544)
		(mid 113.559341 -237.194344)
		(end 113.402364 -237.499144)
		(width 0.1143)
		(layer "In15.Cu")
		(net "GMI_CPU0_G1_CPU1_G3_TX_DP<1>")
	)
	(arc
		(start 358.093518 -237.49889)
		(mid 357.936541 -237.19409)
		(end 358.093518 -236.88929)
		(width 0.1143)
		(layer "In15.Cu")
		(net "GMI_CPU0_G1_CPU1_G3_TX_DP<1>")
	)
	(arc
		(start 358.16413 -241.708178)
		(mid 358.430388 -241.24412)
		(end 358.16413 -240.780062)
		(width 0.1143)
		(layer "In15.Cu")
		(net "GMI_CPU0_G1_CPU1_G3_TX_DP<1>")
	)
	(arc
		(start 113.092484 -236.356906)
		(mid 113.090227 -236.382892)
		(end 113.090198 -236.408976)
		(width 0.1143)
		(layer "In15.Cu")
		(net "GMI_CPU0_G1_CPU1_G3_TX_DP<1>")
	)
	(arc
		(start 113.559336 -245.294404)
		(mid 113.623851 -245.556623)
		(end 113.802668 -245.75897)
		(width 0.1143)
		(layer "In15.Cu")
		(net "GMI_CPU0_G1_CPU1_G3_TX_DP<1>")
	)
	(arc
		(start 357.612696 -244.781324)
		(mid 357.460428 -244.484144)
		(end 357.612696 -244.186964)
		(width 0.1143)
		(layer "In15.Cu")
		(net "GMI_CPU0_G1_CPU1_G3_TX_DP<1>")
	)
	(arc
		(start 357.09352 -246.662702)
		(mid 357.12159 -246.634849)
		(end 357.152448 -246.610124)
		(width 0.1143)
		(layer "In15.Cu")
		(net "GMI_CPU0_G1_CPU1_G3_TX_DP<1>")
	)
	(arc
		(start 113.202466 -222.143828)
		(mid 113.263685 -222.21277)
		(end 113.335308 -222.270828)
		(width 0.1143)
		(layer "In15.Cu")
		(net "GMI_CPU0_G1_CPU1_G3_TX_DP<1>")
	)
	(arc
		(start 358.093518 -242.358926)
		(mid 357.936541 -242.054126)
		(end 358.093518 -241.749326)
		(width 0.1143)
		(layer "In15.Cu")
		(net "GMI_CPU0_G1_CPU1_G3_TX_DP<1>")
	)
	(arc
		(start 113.092484 -242.837208)
		(mid 113.090227 -242.863194)
		(end 113.090198 -242.889278)
		(width 0.1143)
		(layer "In15.Cu")
		(net "GMI_CPU0_G1_CPU1_G3_TX_DP<1>")
	)
	(arc
		(start 358.176322 -235.219494)
		(mid 358.407921 -234.764072)
		(end 358.176322 -234.30865)
		(width 0.1143)
		(layer "In15.Cu")
		(net "GMI_CPU0_G1_CPU1_G3_TX_DP<1>")
	)
	(arc
		(start 357.693214 -244.138704)
		(mid 357.872027 -243.936354)
		(end 357.936546 -243.674138)
		(width 0.1143)
		(layer "In15.Cu")
		(net "GMI_CPU0_G1_CPU1_G3_TX_DP<1>")
	)
	(arc
		(start 358.093518 -234.258866)
		(mid 357.936541 -233.954066)
		(end 358.093518 -233.649266)
		(width 0.1143)
		(layer "In15.Cu")
		(net "GMI_CPU0_G1_CPU1_G3_TX_DP<1>")
	)
	(arc
		(start 113.559336 -222.61449)
		(mid 113.517787 -222.785912)
		(end 113.402364 -222.91929)
		(width 0.1143)
		(layer "In15.Cu")
		(net "GMI_CPU0_G1_CPU1_G3_TX_DP<1>")
	)
	(arc
		(start 113.402364 -235.269532)
		(mid 113.559341 -235.574332)
		(end 113.402364 -235.879132)
		(width 0.1143)
		(layer "In15.Cu")
		(net "GMI_CPU0_G1_CPU1_G3_TX_DP<1>")
	)
	(arc
		(start 357.469948 -246.100092)
		(mid 357.518192 -245.91818)
		(end 357.650034 -245.783862)
		(width 0.1143)
		(layer "In15.Cu")
		(net "GMI_CPU0_G1_CPU1_G3_TX_DP<1>")
	)
	(arc
		(start 358.093518 -240.738914)
		(mid 357.936541 -240.434114)
		(end 358.093518 -240.129314)
		(width 0.1143)
		(layer "In15.Cu")
		(net "GMI_CPU0_G1_CPU1_G3_TX_DP<1>")
	)
	(arc
		(start 113.090198 -244.509036)
		(mid 113.160766 -244.75884)
		(end 113.335562 -244.950742)
		(width 0.1143)
		(layer "In15.Cu")
		(net "GMI_CPU0_G1_CPU1_G3_TX_DP<1>")
	)
	(arc
		(start 113.332768 -222.95993)
		(mid 113.089441 -223.424496)
		(end 113.332768 -223.889062)
		(width 0.1143)
		(layer "In15.Cu")
		(net "GMI_CPU0_G1_CPU1_G3_TX_DP<1>")
	)
	(arc
		(start 113.089436 -231.524556)
		(mid 113.15399 -231.786659)
		(end 113.332768 -231.988868)
		(width 0.1143)
		(layer "In15.Cu")
		(net "GMI_CPU0_G1_CPU1_G3_TX_DP<1>")
	)
	(arc
		(start 357.186484 -246.590058)
		(mid 357.393988 -246.383124)
		(end 357.469948 -246.100092)
		(width 0.1143)
		(layer "In15.Cu")
		(net "GMI_CPU0_G1_CPU1_G3_TX_DP<1>")
	)
	(arc
		(start 358.17302 -243.321586)
		(mid 358.333697 -243.142726)
		(end 358.404414 -242.9129)
		(width 0.1143)
		(layer "In15.Cu")
		(net "GMI_CPU0_G1_CPU1_G3_TX_DP<1>")
	)
	(arc
		(start 358.176322 -236.839506)
		(mid 358.407921 -236.384084)
		(end 358.176322 -235.928662)
		(width 0.1143)
		(layer "In15.Cu")
		(net "GMI_CPU0_G1_CPU1_G3_TX_DP<1>")
	)
	(arc
		(start 358.093518 -227.779072)
		(mid 357.936541 -227.474272)
		(end 358.093518 -227.169472)
		(width 0.1143)
		(layer "In15.Cu")
		(net "GMI_CPU0_G1_CPU1_G3_TX_DP<1>")
	)
	(arc
		(start 357.223314 -222.268796)
		(mid 357.301713 -222.203431)
		(end 357.367078 -222.125032)
		(width 0.1143)
		(layer "In15.Cu")
		(net "GMI_CPU0_G1_CPU1_G3_TX_DP<1>")
	)
	(arc
		(start 357.448612 -221.94647)
		(mid 357.462171 -221.875925)
		(end 357.466646 -221.80423)
		(width 0.1143)
		(layer "In15.Cu")
		(net "GMI_CPU0_G1_CPU1_G3_TX_DP<1>")
	)
	(arc
		(start 114.343434 -246.610124)
		(mid 114.440569 -246.712993)
		(end 114.492532 -246.844566)
		(width 0.1143)
		(layer "In15.Cu")
		(net "GMI_CPU0_G1_CPU1_G3_TX_DP<1>")
	)
	(arc
		(start 113.37163 -234.277154)
		(mid 113.091866 -234.764516)
		(end 113.37163 -235.251752)
		(width 0.1143)
		(layer "In15.Cu")
		(net "GMI_CPU0_G1_CPU1_G3_TX_DP<1>")
	)
	(arc
		(start 113.092484 -244.456966)
		(mid 113.090227 -244.482952)
		(end 113.090198 -244.509036)
		(width 0.1143)
		(layer "In15.Cu")
		(net "GMI_CPU0_G1_CPU1_G3_TX_DP<1>")
	)
	(arc
		(start 113.090198 -241.269266)
		(mid 113.160818 -241.518932)
		(end 113.335562 -241.710718)
		(width 0.1143)
		(layer "In15.Cu")
		(net "GMI_CPU0_G1_CPU1_G3_TX_DP<1>")
	)
	(arc
		(start 358.160574 -230.37038)
		(mid 358.341226 -230.167635)
		(end 358.406446 -229.904036)
		(width 0.1143)
		(layer "In15.Cu")
		(net "GMI_CPU0_G1_CPU1_G3_TX_DP<1>")
	)
	(arc
		(start 357.222806 -223.889316)
		(mid 357.465052 -223.405713)
		(end 357.187246 -222.941642)
		(width 0.1143)
		(layer "In15.Cu")
		(net "GMI_CPU0_G1_CPU1_G3_TX_DP<1>")
	)
	(arc
		(start 357.367078 -222.125032)
		(mid 357.415665 -222.039321)
		(end 357.448612 -221.94647)
		(width 0.1143)
		(layer "In15.Cu")
		(net "GMI_CPU0_G1_CPU1_G3_TX_DP<1>")
	)
	(arc
		(start 113.08969 -221.804484)
		(mid 113.118555 -221.983299)
		(end 113.202466 -222.143828)
		(width 0.1143)
		(layer "In15.Cu")
		(net "GMI_CPU0_G1_CPU1_G3_TX_DP<1>")
	)
	(arc
		(start 113.402364 -241.74958)
		(mid 113.559341 -242.05438)
		(end 113.402364 -242.35918)
		(width 0.1143)
		(layer "In15.Cu")
		(net "GMI_CPU0_G1_CPU1_G3_TX_DP<1>")
	)
	(arc
		(start 113.332768 -242.39982)
		(mid 113.171536 -242.595939)
		(end 113.092484 -242.837208)
		(width 0.1143)
		(layer "In15.Cu")
		(net "GMI_CPU0_G1_CPU1_G3_TX_DP<1>")
	)
	(arc
		(start 358.176322 -240.07953)
		(mid 358.407921 -239.624108)
		(end 358.176322 -239.168686)
		(width 0.1143)
		(layer "In15.Cu")
		(net "GMI_CPU0_G1_CPU1_G3_TX_DP<1>")
	)
	(arc
		(start 113.402364 -227.169726)
		(mid 113.559341 -227.474526)
		(end 113.402364 -227.779326)
		(width 0.1143)
		(layer "In15.Cu")
		(net "GMI_CPU0_G1_CPU1_G3_TX_DP<1>")
	)
	(arc
		(start 358.093518 -226.15906)
		(mid 357.978091 -226.025684)
		(end 357.936546 -225.85426)
		(width 0.1143)
		(layer "In15.Cu")
		(net "GMI_CPU0_G1_CPU1_G3_TX_DP<1>")
	)
	(arc
		(start 113.402364 -230.40975)
		(mid 113.517791 -230.543126)
		(end 113.559336 -230.71455)
		(width 0.1143)
		(layer "In15.Cu")
		(net "GMI_CPU0_G1_CPU1_G3_TX_DP<1>")
	)
	(arc
		(start 113.402364 -232.029508)
		(mid 113.559341 -232.334308)
		(end 113.402364 -232.639108)
		(width 0.1143)
		(layer "In15.Cu")
		(net "GMI_CPU0_G1_CPU1_G3_TX_DP<1>")
	)
	(arc
		(start 358.176322 -238.459518)
		(mid 358.407921 -238.004096)
		(end 358.176322 -237.548674)
		(width 0.1143)
		(layer "In15.Cu")
		(net "GMI_CPU0_G1_CPU1_G3_TX_DP<1>")
	)
	(arc
		(start 113.332768 -235.919772)
		(mid 113.171665 -236.115823)
		(end 113.092484 -236.356906)
		(width 0.1143)
		(layer "In15.Cu")
		(net "GMI_CPU0_G1_CPU1_G3_TX_DP<1>")
	)
	(arc
		(start 113.402364 -228.789738)
		(mid 113.517791 -228.923114)
		(end 113.559336 -229.094538)
		(width 0.1143)
		(layer "In15.Cu")
		(net "GMI_CPU0_G1_CPU1_G3_TX_DP<1>")
	)
	(arc
		(start 113.37163 -232.657142)
		(mid 113.091866 -233.144504)
		(end 113.37163 -233.63174)
		(width 0.1143)
		(layer "In15.Cu")
		(net "GMI_CPU0_G1_CPU1_G3_TX_DP<1>")
	)
	(arc
		(start 358.404414 -242.9129)
		(mid 358.405961 -242.888538)
		(end 358.406446 -242.864132)
		(width 0.1143)
		(layer "In15.Cu")
		(net "GMI_CPU0_G1_CPU1_G3_TX_DP<1>")
	)
	(segment
		(start 124.467874 -246.370348)
		(end 124.934726 -246.10441)
		(width 0.12954)
		(layer "F.Cu")
		(net "GMI_CPU0_G1_CPU1_G3_TX_DP<15>")
	)
	(segment
		(start 347.028008 -246.370094)
		(end 346.561156 -246.104156)
		(width 0.12954)
		(layer "F.Cu")
		(net "GMI_CPU0_G1_CPU1_G3_TX_DP<15>")
	)
	(segment
		(start 126.531878 -242.37696)
		(end 126.492762 -242.39982)
		(width 0.1143)
		(layer "In15.Cu")
		(net "GMI_CPU0_G1_CPU1_G3_TX_DP<15>")
	)
	(segment
		(start 126.492762 -223.889062)
		(end 126.531878 -223.911922)
		(width 0.1143)
		(layer "In15.Cu")
		(net "GMI_CPU0_G1_CPU1_G3_TX_DP<15>")
	)
	(segment
		(start 126.562358 -234.25912)
		(end 126.531878 -234.2769)
		(width 0.1143)
		(layer "In15.Cu")
		(net "GMI_CPU0_G1_CPU1_G3_TX_DP<15>")
	)
	(segment
		(start 126.56439 -231.01808)
		(end 126.531878 -231.036876)
		(width 0.1143)
		(layer "In15.Cu")
		(net "GMI_CPU0_G1_CPU1_G3_TX_DP<15>")
	)
	(segment
		(start 344.964004 -232.011474)
		(end 345.00312 -231.988614)
		(width 0.1143)
		(layer "In15.Cu")
		(net "GMI_CPU0_G1_CPU1_G3_TX_DP<15>")
	)
	(segment
		(start 344.933524 -240.129314)
		(end 344.964004 -240.111534)
		(width 0.1143)
		(layer "In15.Cu")
		(net "GMI_CPU0_G1_CPU1_G3_TX_DP<15>")
	)
	(segment
		(start 344.964004 -243.351558)
		(end 345.00312 -243.328698)
		(width 0.1143)
		(layer "In15.Cu")
		(net "GMI_CPU0_G1_CPU1_G3_TX_DP<15>")
	)
	(segment
		(start 126.531878 -224.557082)
		(end 126.492762 -224.579942)
		(width 0.1143)
		(layer "In15.Cu")
		(net "GMI_CPU0_G1_CPU1_G3_TX_DP<15>")
	)
	(segment
		(start 126.493524 -222.270066)
		(end 126.56312 -222.310198)
		(width 0.1143)
		(layer "In15.Cu")
		(net "GMI_CPU0_G1_CPU1_G3_TX_DP<15>")
	)
	(segment
		(start 126.492762 -240.088928)
		(end 126.531878 -240.111788)
		(width 0.1143)
		(layer "In15.Cu")
		(net "GMI_CPU0_G1_CPU1_G3_TX_DP<15>")
	)
	(segment
		(start 344.964004 -236.87151)
		(end 345.00312 -236.84865)
		(width 0.1143)
		(layer "In15.Cu")
		(net "GMI_CPU0_G1_CPU1_G3_TX_DP<15>")
	)
	(segment
		(start 126.531878 -231.036876)
		(end 126.492762 -231.059736)
		(width 0.1143)
		(layer "In15.Cu")
		(net "GMI_CPU0_G1_CPU1_G3_TX_DP<15>")
	)
	(segment
		(start 344.964004 -243.996718)
		(end 344.933524 -243.978938)
		(width 0.1143)
		(layer "In15.Cu")
		(net "GMI_CPU0_G1_CPU1_G3_TX_DP<15>")
	)
	(segment
		(start 345.00312 -237.53953)
		(end 344.964004 -237.51667)
		(width 0.1143)
		(layer "In15.Cu")
		(net "GMI_CPU0_G1_CPU1_G3_TX_DP<15>")
	)
	(segment
		(start 344.494104 -225.366834)
		(end 344.493342 -225.366326)
		(width 0.1143)
		(layer "In15.Cu")
		(net "GMI_CPU0_G1_CPU1_G3_TX_DP<15>")
	)
	(segment
		(start 344.063066 -224.579688)
		(end 344.02395 -224.556828)
		(width 0.1143)
		(layer "In15.Cu")
		(net "GMI_CPU0_G1_CPU1_G3_TX_DP<15>")
	)
	(segment
		(start 341.787734 -217.460322)
		(end 316.58433 -196.795136)
		(width 0.14224)
		(layer "In15.Cu")
		(net "GMI_CPU0_G1_CPU1_G3_TX_DP<15>")
	)
	(segment
		(start 345.00312 -232.679494)
		(end 344.964004 -232.656634)
		(width 0.1143)
		(layer "In15.Cu")
		(net "GMI_CPU0_G1_CPU1_G3_TX_DP<15>")
	)
	(segment
		(start 126.531878 -225.531934)
		(end 126.562358 -225.549714)
		(width 0.1143)
		(layer "In15.Cu")
		(net "GMI_CPU0_G1_CPU1_G3_TX_DP<15>")
	)
	(segment
		(start 126.059184 -244.808502)
		(end 126.022608 -244.829838)
		(width 0.1143)
		(layer "In15.Cu")
		(net "GMI_CPU0_G1_CPU1_G3_TX_DP<15>")
	)
	(segment
		(start 126.531878 -234.2769)
		(end 126.492762 -234.29976)
		(width 0.1143)
		(layer "In15.Cu")
		(net "GMI_CPU0_G1_CPU1_G3_TX_DP<15>")
	)
	(segment
		(start 126.531878 -232.011728)
		(end 126.562358 -232.029508)
		(width 0.1143)
		(layer "In15.Cu")
		(net "GMI_CPU0_G1_CPU1_G3_TX_DP<15>")
	)
	(segment
		(start 147.284948 -202.981814)
		(end 127.10795 -219.525596)
		(width 0.14224)
		(layer "In15.Cu")
		(net "GMI_CPU0_G1_CPU1_G3_TX_DP<15>")
	)
	(segment
		(start 125.232668 -246.10441)
		(end 124.934726 -246.10441)
		(width 0.1143)
		(layer "In15.Cu")
		(net "GMI_CPU0_G1_CPU1_G3_TX_DP<15>")
	)
	(segment
		(start 126.492762 -227.129086)
		(end 126.531878 -227.151946)
		(width 0.1143)
		(layer "In15.Cu")
		(net "GMI_CPU0_G1_CPU1_G3_TX_DP<15>")
	)
	(segment
		(start 127.10795 -219.525596)
		(end 126.203456 -221.04858)
		(width 0.14224)
		(layer "In15.Cu")
		(net "GMI_CPU0_G1_CPU1_G3_TX_DP<15>")
	)
	(segment
		(start 345.00312 -227.819712)
		(end 344.964004 -227.796852)
		(width 0.1143)
		(layer "In15.Cu")
		(net "GMI_CPU0_G1_CPU1_G3_TX_DP<15>")
	)
	(segment
		(start 344.933524 -236.88929)
		(end 344.964004 -236.87151)
		(width 0.1143)
		(layer "In15.Cu")
		(net "GMI_CPU0_G1_CPU1_G3_TX_DP<15>")
	)
	(segment
		(start 343.55405 -222.12681)
		(end 343.5223 -222.108522)
		(width 0.1143)
		(layer "In15.Cu")
		(net "GMI_CPU0_G1_CPU1_G3_TX_DP<15>")
	)
	(segment
		(start 345.00312 -226.1997)
		(end 344.964004 -226.17684)
		(width 0.1143)
		(layer "In15.Cu")
		(net "GMI_CPU0_G1_CPU1_G3_TX_DP<15>")
	)
	(segment
		(start 149.343364 -202.35799)
		(end 149.343364 -202.358244)
		(width 0.14224)
		(layer "In15.Cu")
		(net "GMI_CPU0_G1_CPU1_G3_TX_DP<15>")
	)
	(segment
		(start 345.002612 -228.749098)
		(end 345.00312 -228.748844)
		(width 0.1143)
		(layer "In15.Cu")
		(net "GMI_CPU0_G1_CPU1_G3_TX_DP<15>")
	)
	(segment
		(start 126.562358 -240.739168)
		(end 126.531878 -240.756948)
		(width 0.1143)
		(layer "In15.Cu")
		(net "GMI_CPU0_G1_CPU1_G3_TX_DP<15>")
	)
	(segment
		(start 344.964004 -240.756694)
		(end 344.933524 -240.738914)
		(width 0.1143)
		(layer "In15.Cu")
		(net "GMI_CPU0_G1_CPU1_G3_TX_DP<15>")
	)
	(segment
		(start 126.203456 -221.174564)
		(end 126.248922 -221.22003)
		(width 0.1143)
		(layer "In15.Cu")
		(net "GMI_CPU0_G1_CPU1_G3_TX_DP<15>")
	)
	(segment
		(start 344.964004 -228.771704)
		(end 345.002612 -228.749098)
		(width 0.1143)
		(layer "In15.Cu")
		(net "GMI_CPU0_G1_CPU1_G3_TX_DP<15>")
	)
	(segment
		(start 126.562358 -239.119156)
		(end 126.531878 -239.136936)
		(width 0.1143)
		(layer "In15.Cu")
		(net "GMI_CPU0_G1_CPU1_G3_TX_DP<15>")
	)
	(segment
		(start 126.531878 -243.996972)
		(end 126.492762 -244.019832)
		(width 0.1143)
		(layer "In15.Cu")
		(net "GMI_CPU0_G1_CPU1_G3_TX_DP<15>")
	)
	(segment
		(start 344.53322 -225.389694)
		(end 344.496644 -225.368358)
		(width 0.1143)
		(layer "In15.Cu")
		(net "GMI_CPU0_G1_CPU1_G3_TX_DP<15>")
	)
	(segment
		(start 344.933524 -233.649266)
		(end 344.964004 -233.631486)
		(width 0.1143)
		(layer "In15.Cu")
		(net "GMI_CPU0_G1_CPU1_G3_TX_DP<15>")
	)
	(segment
		(start 316.58433 -196.795136)
		(end 308.357016 -191.050164)
		(width 0.14224)
		(layer "In15.Cu")
		(net "GMI_CPU0_G1_CPU1_G3_TX_DP<15>")
	)
	(segment
		(start 343.34704 -220.755464)
		(end 341.787734 -217.460322)
		(width 0.14224)
		(layer "In15.Cu")
		(net "GMI_CPU0_G1_CPU1_G3_TX_DP<15>")
	)
	(segment
		(start 126.492762 -225.509074)
		(end 126.531878 -225.531934)
		(width 0.1143)
		(layer "In15.Cu")
		(net "GMI_CPU0_G1_CPU1_G3_TX_DP<15>")
	)
	(segment
		(start 148.68398 -202.557888)
		(end 148.664676 -202.563984)
		(width 0.14224)
		(layer "In15.Cu")
		(net "GMI_CPU0_G1_CPU1_G3_TX_DP<15>")
	)
	(segment
		(start 209.814922 -191.403224)
		(end 207.150716 -190.933324)
		(width 0.14224)
		(layer "In15.Cu")
		(net "GMI_CPU0_G1_CPU1_G3_TX_DP<15>")
	)
	(segment
		(start 126.562358 -222.91929)
		(end 126.531878 -222.93707)
		(width 0.1143)
		(layer "In15.Cu")
		(net "GMI_CPU0_G1_CPU1_G3_TX_DP<15>")
	)
	(segment
		(start 344.02395 -224.556828)
		(end 343.99347 -224.539048)
		(width 0.1143)
		(layer "In15.Cu")
		(net "GMI_CPU0_G1_CPU1_G3_TX_DP<15>")
	)
	(segment
		(start 126.531878 -232.656888)
		(end 126.492762 -232.679748)
		(width 0.1143)
		(layer "In15.Cu")
		(net "GMI_CPU0_G1_CPU1_G3_TX_DP<15>")
	)
	(segment
		(start 344.933524 -232.029254)
		(end 344.964004 -232.011474)
		(width 0.1143)
		(layer "In15.Cu")
		(net "GMI_CPU0_G1_CPU1_G3_TX_DP<15>")
	)
	(segment
		(start 343.30132 -221.308676)
		(end 343.30132 -221.128844)
		(width 0.1143)
		(layer "In15.Cu")
		(net "GMI_CPU0_G1_CPU1_G3_TX_DP<15>")
	)
	(segment
		(start 126.531878 -235.896912)
		(end 126.492762 -235.919772)
		(width 0.1143)
		(layer "In15.Cu")
		(net "GMI_CPU0_G1_CPU1_G3_TX_DP<15>")
	)
	(segment
		(start 301.602902 -191.050164)
		(end 301.582836 -191.030098)
		(width 0.14224)
		(layer "In15.Cu")
		(net "GMI_CPU0_G1_CPU1_G3_TX_DP<15>")
	)
	(segment
		(start 251.681234 -192.63614)
		(end 240.165128 -200.700386)
		(width 0.14224)
		(layer "In15.Cu")
		(net "GMI_CPU0_G1_CPU1_G3_TX_DP<15>")
	)
	(segment
		(start 126.562358 -232.639108)
		(end 126.531878 -232.656888)
		(width 0.1143)
		(layer "In15.Cu")
		(net "GMI_CPU0_G1_CPU1_G3_TX_DP<15>")
	)
	(segment
		(start 126.531878 -240.111788)
		(end 126.562358 -240.129568)
		(width 0.1143)
		(layer "In15.Cu")
		(net "GMI_CPU0_G1_CPU1_G3_TX_DP<15>")
	)
	(segment
		(start 162.268662 -191.622172)
		(end 161.781236 -192.531492)
		(width 0.14224)
		(layer "In15.Cu")
		(net "GMI_CPU0_G1_CPU1_G3_TX_DP<15>")
	)
	(segment
		(start 126.531878 -243.351812)
		(end 126.562358 -243.369592)
		(width 0.1143)
		(layer "In15.Cu")
		(net "GMI_CPU0_G1_CPU1_G3_TX_DP<15>")
	)
	(segment
		(start 126.531878 -229.416864)
		(end 126.494794 -229.4382)
		(width 0.1143)
		(layer "In15.Cu")
		(net "GMI_CPU0_G1_CPU1_G3_TX_DP<15>")
	)
	(segment
		(start 126.531878 -239.136936)
		(end 126.492762 -239.159796)
		(width 0.1143)
		(layer "In15.Cu")
		(net "GMI_CPU0_G1_CPU1_G3_TX_DP<15>")
	)
	(segment
		(start 126.531878 -227.151946)
		(end 126.562358 -227.169726)
		(width 0.1143)
		(layer "In15.Cu")
		(net "GMI_CPU0_G1_CPU1_G3_TX_DP<15>")
	)
	(segment
		(start 126.562358 -237.499144)
		(end 126.531878 -237.516924)
		(width 0.1143)
		(layer "In15.Cu")
		(net "GMI_CPU0_G1_CPU1_G3_TX_DP<15>")
	)
	(segment
		(start 344.49512 -225.367342)
		(end 344.494104 -225.366834)
		(width 0.1143)
		(layer "In15.Cu")
		(net "GMI_CPU0_G1_CPU1_G3_TX_DP<15>")
	)
	(segment
		(start 125.315472 -246.021606)
		(end 125.232668 -246.10441)
		(width 0.1143)
		(layer "In15.Cu")
		(net "GMI_CPU0_G1_CPU1_G3_TX_DP<15>")
	)
	(segment
		(start 346.561156 -246.104156)
		(end 346.263214 -246.104156)
		(width 0.1143)
		(layer "In15.Cu")
		(net "GMI_CPU0_G1_CPU1_G3_TX_DP<15>")
	)
	(segment
		(start 343.366344 -221.3737)
		(end 343.30132 -221.308676)
		(width 0.1143)
		(layer "In15.Cu")
		(net "GMI_CPU0_G1_CPU1_G3_TX_DP<15>")
	)
	(segment
		(start 345.445334 -244.813328)
		(end 345.402154 -244.788182)
		(width 0.1143)
		(layer "In15.Cu")
		(net "GMI_CPU0_G1_CPU1_G3_TX_DP<15>")
	)
	(segment
		(start 126.562358 -227.779326)
		(end 126.531878 -227.797106)
		(width 0.1143)
		(layer "In15.Cu")
		(net "GMI_CPU0_G1_CPU1_G3_TX_DP<15>")
	)
	(segment
		(start 126.56439 -229.398068)
		(end 126.531878 -229.416864)
		(width 0.1143)
		(layer "In15.Cu")
		(net "GMI_CPU0_G1_CPU1_G3_TX_DP<15>")
	)
	(segment
		(start 344.964004 -240.111534)
		(end 345.00312 -240.088674)
		(width 0.1143)
		(layer "In15.Cu")
		(net "GMI_CPU0_G1_CPU1_G3_TX_DP<15>")
	)
	(segment
		(start 125.591824 -245.616984)
		(end 125.552708 -245.639844)
		(width 0.1143)
		(layer "In15.Cu")
		(net "GMI_CPU0_G1_CPU1_G3_TX_DP<15>")
	)
	(segment
		(start 344.964004 -231.036622)
		(end 344.931492 -231.017826)
		(width 0.1143)
		(layer "In15.Cu")
		(net "GMI_CPU0_G1_CPU1_G3_TX_DP<15>")
	)
	(segment
		(start 126.495302 -230.370634)
		(end 126.562358 -230.40975)
		(width 0.1143)
		(layer "In15.Cu")
		(net "GMI_CPU0_G1_CPU1_G3_TX_DP<15>")
	)
	(segment
		(start 344.02395 -222.936816)
		(end 343.99347 -222.919036)
		(width 0.1143)
		(layer "In15.Cu")
		(net "GMI_CPU0_G1_CPU1_G3_TX_DP<15>")
	)
	(segment
		(start 209.814922 -191.410336)
		(end 209.814922 -191.403224)
		(width 0.14224)
		(layer "In15.Cu")
		(net "GMI_CPU0_G1_CPU1_G3_TX_DP<15>")
	)
	(segment
		(start 126.531878 -233.63174)
		(end 126.562358 -233.64952)
		(width 0.1143)
		(layer "In15.Cu")
		(net "GMI_CPU0_G1_CPU1_G3_TX_DP<15>")
	)
	(segment
		(start 344.964004 -234.276646)
		(end 344.933524 -234.258866)
		(width 0.1143)
		(layer "In15.Cu")
		(net "GMI_CPU0_G1_CPU1_G3_TX_DP<15>")
	)
	(segment
		(start 149.343364 -202.358244)
		(end 148.68398 -202.557888)
		(width 0.14224)
		(layer "In15.Cu")
		(net "GMI_CPU0_G1_CPU1_G3_TX_DP<15>")
	)
	(segment
		(start 345.00312 -234.299506)
		(end 344.964004 -234.276646)
		(width 0.1143)
		(layer "In15.Cu")
		(net "GMI_CPU0_G1_CPU1_G3_TX_DP<15>")
	)
	(segment
		(start 344.964004 -227.796852)
		(end 344.933524 -227.779072)
		(width 0.1143)
		(layer "In15.Cu")
		(net "GMI_CPU0_G1_CPU1_G3_TX_DP<15>")
	)
	(segment
		(start 126.492762 -243.328952)
		(end 126.531878 -243.351812)
		(width 0.1143)
		(layer "In15.Cu")
		(net "GMI_CPU0_G1_CPU1_G3_TX_DP<15>")
	)
	(segment
		(start 262.816848 -190.672974)
		(end 251.681234 -192.63614)
		(width 0.14224)
		(layer "In15.Cu")
		(net "GMI_CPU0_G1_CPU1_G3_TX_DP<15>")
	)
	(segment
		(start 126.093474 -244.78869)
		(end 126.066042 -244.804438)
		(width 0.1143)
		(layer "In15.Cu")
		(net "GMI_CPU0_G1_CPU1_G3_TX_DP<15>")
	)
	(segment
		(start 344.933524 -228.789484)
		(end 344.964004 -228.771704)
		(width 0.1143)
		(layer "In15.Cu")
		(net "GMI_CPU0_G1_CPU1_G3_TX_DP<15>")
	)
	(segment
		(start 148.663406 -202.564238)
		(end 147.284948 -202.981814)
		(width 0.14224)
		(layer "In15.Cu")
		(net "GMI_CPU0_G1_CPU1_G3_TX_DP<15>")
	)
	(segment
		(start 344.964004 -241.731546)
		(end 345.00312 -241.708686)
		(width 0.1143)
		(layer "In15.Cu")
		(net "GMI_CPU0_G1_CPU1_G3_TX_DP<15>")
	)
	(segment
		(start 126.492762 -231.988868)
		(end 126.531878 -232.011728)
		(width 0.1143)
		(layer "In15.Cu")
		(net "GMI_CPU0_G1_CPU1_G3_TX_DP<15>")
	)
	(segment
		(start 308.357016 -191.050164)
		(end 301.602902 -191.050164)
		(width 0.14224)
		(layer "In15.Cu")
		(net "GMI_CPU0_G1_CPU1_G3_TX_DP<15>")
	)
	(segment
		(start 148.664168 -202.563984)
		(end 148.663406 -202.564238)
		(width 0.14224)
		(layer "In15.Cu")
		(net "GMI_CPU0_G1_CPU1_G3_TX_DP<15>")
	)
	(segment
		(start 343.366344 -221.80423)
		(end 343.366344 -221.3737)
		(width 0.1143)
		(layer "In15.Cu")
		(net "GMI_CPU0_G1_CPU1_G3_TX_DP<15>")
	)
	(segment
		(start 343.30132 -221.128844)
		(end 343.34704 -221.083124)
		(width 0.1143)
		(layer "In15.Cu")
		(net "GMI_CPU0_G1_CPU1_G3_TX_DP<15>")
	)
	(segment
		(start 345.00312 -235.919518)
		(end 344.964004 -235.896658)
		(width 0.1143)
		(layer "In15.Cu")
		(net "GMI_CPU0_G1_CPU1_G3_TX_DP<15>")
	)
	(segment
		(start 126.494794 -229.4382)
		(end 126.492762 -229.439724)
		(width 0.1143)
		(layer "In15.Cu")
		(net "GMI_CPU0_G1_CPU1_G3_TX_DP<15>")
	)
	(segment
		(start 126.492762 -236.848904)
		(end 126.531878 -236.871764)
		(width 0.1143)
		(layer "In15.Cu")
		(net "GMI_CPU0_G1_CPU1_G3_TX_DP<15>")
	)
	(segment
		(start 126.531878 -240.756948)
		(end 126.492762 -240.779808)
		(width 0.1143)
		(layer "In15.Cu")
		(net "GMI_CPU0_G1_CPU1_G3_TX_DP<15>")
	)
	(segment
		(start 126.062486 -244.80647)
		(end 126.061724 -244.806978)
		(width 0.1143)
		(layer "In15.Cu")
		(net "GMI_CPU0_G1_CPU1_G3_TX_DP<15>")
	)
	(segment
		(start 343.99347 -223.929448)
		(end 344.02395 -223.911668)
		(width 0.1143)
		(layer "In15.Cu")
		(net "GMI_CPU0_G1_CPU1_G3_TX_DP<15>")
	)
	(segment
		(start 344.933524 -235.269278)
		(end 344.964004 -235.251498)
		(width 0.1143)
		(layer "In15.Cu")
		(net "GMI_CPU0_G1_CPU1_G3_TX_DP<15>")
	)
	(segment
		(start 345.00312 -242.399566)
		(end 344.964004 -242.376706)
		(width 0.1143)
		(layer "In15.Cu")
		(net "GMI_CPU0_G1_CPU1_G3_TX_DP<15>")
	)
	(segment
		(start 344.964004 -238.491522)
		(end 345.00312 -238.468662)
		(width 0.1143)
		(layer "In15.Cu")
		(net "GMI_CPU0_G1_CPU1_G3_TX_DP<15>")
	)
	(segment
		(start 346.263214 -246.104156)
		(end 346.18041 -246.021352)
		(width 0.1143)
		(layer "In15.Cu")
		(net "GMI_CPU0_G1_CPU1_G3_TX_DP<15>")
	)
	(segment
		(start 344.489786 -225.364294)
		(end 344.48877 -225.363786)
		(width 0.1143)
		(layer "In15.Cu")
		(net "GMI_CPU0_G1_CPU1_G3_TX_DP<15>")
	)
	(segment
		(start 126.531878 -236.871764)
		(end 126.562358 -236.889544)
		(width 0.1143)
		(layer "In15.Cu")
		(net "GMI_CPU0_G1_CPU1_G3_TX_DP<15>")
	)
	(segment
		(start 344.964004 -239.136682)
		(end 344.933524 -239.118902)
		(width 0.1143)
		(layer "In15.Cu")
		(net "GMI_CPU0_G1_CPU1_G3_TX_DP<15>")
	)
	(segment
		(start 240.165128 -200.700386)
		(end 236.351064 -201.372978)
		(width 0.14224)
		(layer "In15.Cu")
		(net "GMI_CPU0_G1_CPU1_G3_TX_DP<15>")
	)
	(segment
		(start 126.203456 -221.04858)
		(end 126.203456 -221.174564)
		(width 0.14224)
		(layer "In15.Cu")
		(net "GMI_CPU0_G1_CPU1_G3_TX_DP<15>")
	)
	(segment
		(start 344.490548 -225.364802)
		(end 344.489786 -225.364294)
		(width 0.1143)
		(layer "In15.Cu")
		(net "GMI_CPU0_G1_CPU1_G3_TX_DP<15>")
	)
	(segment
		(start 126.562358 -224.539302)
		(end 126.531878 -224.557082)
		(width 0.1143)
		(layer "In15.Cu")
		(net "GMI_CPU0_G1_CPU1_G3_TX_DP<15>")
	)
	(segment
		(start 344.063066 -222.959676)
		(end 344.02395 -222.936816)
		(width 0.1143)
		(layer "In15.Cu")
		(net "GMI_CPU0_G1_CPU1_G3_TX_DP<15>")
	)
	(segment
		(start 344.493342 -225.366326)
		(end 344.492072 -225.365564)
		(width 0.1143)
		(layer "In15.Cu")
		(net "GMI_CPU0_G1_CPU1_G3_TX_DP<15>")
	)
	(segment
		(start 345.00312 -240.779554)
		(end 344.964004 -240.756694)
		(width 0.1143)
		(layer "In15.Cu")
		(net "GMI_CPU0_G1_CPU1_G3_TX_DP<15>")
	)
	(segment
		(start 125.622304 -245.599204)
		(end 125.591824 -245.616984)
		(width 0.1143)
		(layer "In15.Cu")
		(net "GMI_CPU0_G1_CPU1_G3_TX_DP<15>")
	)
	(segment
		(start 161.781236 -192.531492)
		(end 150.061676 -202.140566)
		(width 0.14224)
		(layer "In15.Cu")
		(net "GMI_CPU0_G1_CPU1_G3_TX_DP<15>")
	)
	(segment
		(start 343.593166 -222.14967)
		(end 343.55405 -222.12681)
		(width 0.1143)
		(layer "In15.Cu")
		(net "GMI_CPU0_G1_CPU1_G3_TX_DP<15>")
	)
	(segment
		(start 344.492072 -225.365564)
		(end 344.490548 -225.364802)
		(width 0.1143)
		(layer "In15.Cu")
		(net "GMI_CPU0_G1_CPU1_G3_TX_DP<15>")
	)
	(segment
		(start 344.964004 -237.51667)
		(end 344.933524 -237.49889)
		(width 0.1143)
		(layer "In15.Cu")
		(net "GMI_CPU0_G1_CPU1_G3_TX_DP<15>")
	)
	(segment
		(start 126.562358 -243.979192)
		(end 126.531878 -243.996972)
		(width 0.1143)
		(layer "In15.Cu")
		(net "GMI_CPU0_G1_CPU1_G3_TX_DP<15>")
	)
	(segment
		(start 126.562358 -235.879132)
		(end 126.531878 -235.896912)
		(width 0.1143)
		(layer "In15.Cu")
		(net "GMI_CPU0_G1_CPU1_G3_TX_DP<15>")
	)
	(segment
		(start 301.582836 -191.030098)
		(end 262.816848 -190.672974)
		(width 0.14224)
		(layer "In15.Cu")
		(net "GMI_CPU0_G1_CPU1_G3_TX_DP<15>")
	)
	(segment
		(start 232.027222 -200.610724)
		(end 209.814922 -191.410336)
		(width 0.14224)
		(layer "In15.Cu")
		(net "GMI_CPU0_G1_CPU1_G3_TX_DP<15>")
	)
	(segment
		(start 345.728798 -245.3132)
		(end 345.728798 -245.303548)
		(width 0.1143)
		(layer "In15.Cu")
		(net "GMI_CPU0_G1_CPU1_G3_TX_DP<15>")
	)
	(segment
		(start 126.562358 -226.159314)
		(end 126.531878 -226.177094)
		(width 0.1143)
		(layer "In15.Cu")
		(net "GMI_CPU0_G1_CPU1_G3_TX_DP<15>")
	)
	(segment
		(start 126.531878 -241.7318)
		(end 126.562358 -241.74958)
		(width 0.1143)
		(layer "In15.Cu")
		(net "GMI_CPU0_G1_CPU1_G3_TX_DP<15>")
	)
	(segment
		(start 126.531878 -222.93707)
		(end 126.492762 -222.95993)
		(width 0.1143)
		(layer "In15.Cu")
		(net "GMI_CPU0_G1_CPU1_G3_TX_DP<15>")
	)
	(segment
		(start 344.964004 -226.17684)
		(end 344.933524 -226.15906)
		(width 0.1143)
		(layer "In15.Cu")
		(net "GMI_CPU0_G1_CPU1_G3_TX_DP<15>")
	)
	(segment
		(start 344.02395 -223.911668)
		(end 344.063066 -223.888808)
		(width 0.1143)
		(layer "In15.Cu")
		(net "GMI_CPU0_G1_CPU1_G3_TX_DP<15>")
	)
	(segment
		(start 345.942412 -245.639082)
		(end 345.90355 -245.616476)
		(width 0.1143)
		(layer "In15.Cu")
		(net "GMI_CPU0_G1_CPU1_G3_TX_DP<15>")
	)
	(segment
		(start 126.492762 -241.70894)
		(end 126.531878 -241.7318)
		(width 0.1143)
		(layer "In15.Cu")
		(net "GMI_CPU0_G1_CPU1_G3_TX_DP<15>")
	)
	(segment
		(start 344.964004 -227.151692)
		(end 345.00312 -227.128832)
		(width 0.1143)
		(layer "In15.Cu")
		(net "GMI_CPU0_G1_CPU1_G3_TX_DP<15>")
	)
	(segment
		(start 207.150716 -190.933324)
		(end 162.879532 -191.120522)
		(width 0.14224)
		(layer "In15.Cu")
		(net "GMI_CPU0_G1_CPU1_G3_TX_DP<15>")
	)
	(segment
		(start 344.964004 -232.656634)
		(end 344.933524 -232.638854)
		(width 0.1143)
		(layer "In15.Cu")
		(net "GMI_CPU0_G1_CPU1_G3_TX_DP<15>")
	)
	(segment
		(start 126.531878 -238.491776)
		(end 126.562358 -238.509556)
		(width 0.1143)
		(layer "In15.Cu")
		(net "GMI_CPU0_G1_CPU1_G3_TX_DP<15>")
	)
	(segment
		(start 345.00312 -244.019578)
		(end 344.964004 -243.996718)
		(width 0.1143)
		(layer "In15.Cu")
		(net "GMI_CPU0_G1_CPU1_G3_TX_DP<15>")
	)
	(segment
		(start 344.933524 -243.369338)
		(end 344.964004 -243.351558)
		(width 0.1143)
		(layer "In15.Cu")
		(net "GMI_CPU0_G1_CPU1_G3_TX_DP<15>")
	)
	(segment
		(start 126.531878 -228.771958)
		(end 126.562358 -228.789738)
		(width 0.1143)
		(layer "In15.Cu")
		(net "GMI_CPU0_G1_CPU1_G3_TX_DP<15>")
	)
	(segment
		(start 148.664676 -202.563984)
		(end 148.664168 -202.563984)
		(width 0.14224)
		(layer "In15.Cu")
		(net "GMI_CPU0_G1_CPU1_G3_TX_DP<15>")
	)
	(segment
		(start 162.879532 -191.120522)
		(end 162.268662 -191.622172)
		(width 0.14224)
		(layer "In15.Cu")
		(net "GMI_CPU0_G1_CPU1_G3_TX_DP<15>")
	)
	(segment
		(start 126.531878 -237.516924)
		(end 126.492762 -237.539784)
		(width 0.1143)
		(layer "In15.Cu")
		(net "GMI_CPU0_G1_CPU1_G3_TX_DP<15>")
	)
	(segment
		(start 344.964004 -229.41661)
		(end 344.931492 -229.397814)
		(width 0.1143)
		(layer "In15.Cu")
		(net "GMI_CPU0_G1_CPU1_G3_TX_DP<15>")
	)
	(segment
		(start 345.00312 -239.159542)
		(end 344.964004 -239.136682)
		(width 0.1143)
		(layer "In15.Cu")
		(net "GMI_CPU0_G1_CPU1_G3_TX_DP<15>")
	)
	(segment
		(start 126.531878 -226.177094)
		(end 126.492762 -226.199954)
		(width 0.1143)
		(layer "In15.Cu")
		(net "GMI_CPU0_G1_CPU1_G3_TX_DP<15>")
	)
	(segment
		(start 126.492762 -238.468916)
		(end 126.531878 -238.491776)
		(width 0.1143)
		(layer "In15.Cu")
		(net "GMI_CPU0_G1_CPU1_G3_TX_DP<15>")
	)
	(segment
		(start 344.964004 -233.631486)
		(end 345.00312 -233.608626)
		(width 0.1143)
		(layer "In15.Cu")
		(net "GMI_CPU0_G1_CPU1_G3_TX_DP<15>")
	)
	(segment
		(start 344.933524 -230.409496)
		(end 345.00058 -230.37038)
		(width 0.1143)
		(layer "In15.Cu")
		(net "GMI_CPU0_G1_CPU1_G3_TX_DP<15>")
	)
	(segment
		(start 344.933524 -241.749326)
		(end 344.964004 -241.731546)
		(width 0.1143)
		(layer "In15.Cu")
		(net "GMI_CPU0_G1_CPU1_G3_TX_DP<15>")
	)
	(segment
		(start 126.492762 -235.228892)
		(end 126.531878 -235.251752)
		(width 0.1143)
		(layer "In15.Cu")
		(net "GMI_CPU0_G1_CPU1_G3_TX_DP<15>")
	)
	(segment
		(start 126.061724 -244.806978)
		(end 126.060708 -244.807486)
		(width 0.1143)
		(layer "In15.Cu")
		(net "GMI_CPU0_G1_CPU1_G3_TX_DP<15>")
	)
	(segment
		(start 126.492762 -233.60888)
		(end 126.531878 -233.63174)
		(width 0.1143)
		(layer "In15.Cu")
		(net "GMI_CPU0_G1_CPU1_G3_TX_DP<15>")
	)
	(segment
		(start 126.531878 -223.911922)
		(end 126.562358 -223.929702)
		(width 0.1143)
		(layer "In15.Cu")
		(net "GMI_CPU0_G1_CPU1_G3_TX_DP<15>")
	)
	(segment
		(start 344.496644 -225.368358)
		(end 344.49512 -225.367342)
		(width 0.1143)
		(layer "In15.Cu")
		(net "GMI_CPU0_G1_CPU1_G3_TX_DP<15>")
	)
	(segment
		(start 126.531878 -235.251752)
		(end 126.562358 -235.269532)
		(width 0.1143)
		(layer "In15.Cu")
		(net "GMI_CPU0_G1_CPU1_G3_TX_DP<15>")
	)
	(segment
		(start 236.351064 -201.372978)
		(end 232.027222 -200.610724)
		(width 0.14224)
		(layer "In15.Cu")
		(net "GMI_CPU0_G1_CPU1_G3_TX_DP<15>")
	)
	(segment
		(start 344.964004 -242.376706)
		(end 344.933524 -242.358926)
		(width 0.1143)
		(layer "In15.Cu")
		(net "GMI_CPU0_G1_CPU1_G3_TX_DP<15>")
	)
	(segment
		(start 343.34704 -221.083124)
		(end 343.34704 -220.755464)
		(width 0.14224)
		(layer "In15.Cu")
		(net "GMI_CPU0_G1_CPU1_G3_TX_DP<15>")
	)
	(segment
		(start 344.933524 -238.509302)
		(end 344.964004 -238.491522)
		(width 0.1143)
		(layer "In15.Cu")
		(net "GMI_CPU0_G1_CPU1_G3_TX_DP<15>")
	)
	(segment
		(start 126.066042 -244.804438)
		(end 126.06528 -244.804946)
		(width 0.1143)
		(layer "In15.Cu")
		(net "GMI_CPU0_G1_CPU1_G3_TX_DP<15>")
	)
	(segment
		(start 344.964004 -235.251498)
		(end 345.00312 -235.228638)
		(width 0.1143)
		(layer "In15.Cu")
		(net "GMI_CPU0_G1_CPU1_G3_TX_DP<15>")
	)
	(segment
		(start 344.964004 -235.896658)
		(end 344.933524 -235.878878)
		(width 0.1143)
		(layer "In15.Cu")
		(net "GMI_CPU0_G1_CPU1_G3_TX_DP<15>")
	)
	(segment
		(start 345.00312 -229.43947)
		(end 344.964004 -229.41661)
		(width 0.1143)
		(layer "In15.Cu")
		(net "GMI_CPU0_G1_CPU1_G3_TX_DP<15>")
	)
	(segment
		(start 345.00312 -231.059482)
		(end 344.964004 -231.036622)
		(width 0.1143)
		(layer "In15.Cu")
		(net "GMI_CPU0_G1_CPU1_G3_TX_DP<15>")
	)
	(segment
		(start 126.248922 -221.22003)
		(end 126.248922 -221.804484)
		(width 0.1143)
		(layer "In15.Cu")
		(net "GMI_CPU0_G1_CPU1_G3_TX_DP<15>")
	)
	(segment
		(start 126.562358 -242.35918)
		(end 126.531878 -242.37696)
		(width 0.1143)
		(layer "In15.Cu")
		(net "GMI_CPU0_G1_CPU1_G3_TX_DP<15>")
	)
	(segment
		(start 126.060708 -244.807486)
		(end 126.059184 -244.808502)
		(width 0.1143)
		(layer "In15.Cu")
		(net "GMI_CPU0_G1_CPU1_G3_TX_DP<15>")
	)
	(segment
		(start 126.56312 -222.310198)
		(end 126.564136 -222.31096)
		(width 0.1143)
		(layer "In15.Cu")
		(net "GMI_CPU0_G1_CPU1_G3_TX_DP<15>")
	)
	(segment
		(start 126.492762 -228.749098)
		(end 126.531878 -228.771958)
		(width 0.1143)
		(layer "In15.Cu")
		(net "GMI_CPU0_G1_CPU1_G3_TX_DP<15>")
	)
	(segment
		(start 150.061676 -202.140566)
		(end 149.343364 -202.35799)
		(width 0.14224)
		(layer "In15.Cu")
		(net "GMI_CPU0_G1_CPU1_G3_TX_DP<15>")
	)
	(segment
		(start 344.933524 -227.169472)
		(end 344.964004 -227.151692)
		(width 0.1143)
		(layer "In15.Cu")
		(net "GMI_CPU0_G1_CPU1_G3_TX_DP<15>")
	)
	(segment
		(start 126.531878 -227.797106)
		(end 126.492762 -227.819966)
		(width 0.1143)
		(layer "In15.Cu")
		(net "GMI_CPU0_G1_CPU1_G3_TX_DP<15>")
	)
	(segment
		(start 126.06528 -244.804946)
		(end 126.062486 -244.80647)
		(width 0.1143)
		(layer "In15.Cu")
		(net "GMI_CPU0_G1_CPU1_G3_TX_DP<15>")
	)
	(segment
		(start 344.48877 -225.363786)
		(end 344.462354 -225.348546)
		(width 0.1143)
		(layer "In15.Cu")
		(net "GMI_CPU0_G1_CPU1_G3_TX_DP<15>")
	)
	(arc
		(start 126.492762 -240.779808)
		(mid 126.249435 -241.244374)
		(end 126.492762 -241.70894)
		(width 0.1143)
		(layer "In15.Cu")
		(net "GMI_CPU0_G1_CPU1_G3_TX_DP<15>")
	)
	(arc
		(start 345.90355 -245.616476)
		(mid 345.775599 -245.488202)
		(end 345.728798 -245.3132)
		(width 0.1143)
		(layer "In15.Cu")
		(net "GMI_CPU0_G1_CPU1_G3_TX_DP<15>")
	)
	(arc
		(start 344.933524 -227.779072)
		(mid 344.776547 -227.474272)
		(end 344.933524 -227.169472)
		(width 0.1143)
		(layer "In15.Cu")
		(net "GMI_CPU0_G1_CPU1_G3_TX_DP<15>")
	)
	(arc
		(start 345.00058 -230.37038)
		(mid 345.181232 -230.167635)
		(end 345.246452 -229.904036)
		(width 0.1143)
		(layer "In15.Cu")
		(net "GMI_CPU0_G1_CPU1_G3_TX_DP<15>")
	)
	(arc
		(start 126.562358 -232.029508)
		(mid 126.719335 -232.334308)
		(end 126.562358 -232.639108)
		(width 0.1143)
		(layer "In15.Cu")
		(net "GMI_CPU0_G1_CPU1_G3_TX_DP<15>")
	)
	(arc
		(start 344.933524 -242.358926)
		(mid 344.776547 -242.054126)
		(end 344.933524 -241.749326)
		(width 0.1143)
		(layer "In15.Cu")
		(net "GMI_CPU0_G1_CPU1_G3_TX_DP<15>")
	)
	(arc
		(start 343.836498 -222.614236)
		(mid 343.771983 -222.352017)
		(end 343.593166 -222.14967)
		(width 0.1143)
		(layer "In15.Cu")
		(net "GMI_CPU0_G1_CPU1_G3_TX_DP<15>")
	)
	(arc
		(start 345.728798 -245.303548)
		(mid 345.652833 -245.020406)
		(end 345.445334 -244.813328)
		(width 0.1143)
		(layer "In15.Cu")
		(net "GMI_CPU0_G1_CPU1_G3_TX_DP<15>")
	)
	(arc
		(start 126.71933 -230.71455)
		(mid 126.678364 -230.884956)
		(end 126.56439 -231.01808)
		(width 0.1143)
		(layer "In15.Cu")
		(net "GMI_CPU0_G1_CPU1_G3_TX_DP<15>")
	)
	(arc
		(start 345.402154 -244.788182)
		(mid 345.287627 -244.654942)
		(end 345.246452 -244.484144)
		(width 0.1143)
		(layer "In15.Cu")
		(net "GMI_CPU0_G1_CPU1_G3_TX_DP<15>")
	)
	(arc
		(start 126.492762 -235.919772)
		(mid 126.249435 -236.384338)
		(end 126.492762 -236.848904)
		(width 0.1143)
		(layer "In15.Cu")
		(net "GMI_CPU0_G1_CPU1_G3_TX_DP<15>")
	)
	(arc
		(start 126.562358 -235.269532)
		(mid 126.719335 -235.574332)
		(end 126.562358 -235.879132)
		(width 0.1143)
		(layer "In15.Cu")
		(net "GMI_CPU0_G1_CPU1_G3_TX_DP<15>")
	)
	(arc
		(start 125.552708 -245.639844)
		(mid 125.400721 -245.796352)
		(end 125.319282 -245.998746)
		(width 0.1143)
		(layer "In15.Cu")
		(net "GMI_CPU0_G1_CPU1_G3_TX_DP<15>")
	)
	(arc
		(start 126.562358 -225.549714)
		(mid 126.719335 -225.854514)
		(end 126.562358 -226.159314)
		(width 0.1143)
		(layer "In15.Cu")
		(net "GMI_CPU0_G1_CPU1_G3_TX_DP<15>")
	)
	(arc
		(start 343.99347 -222.919036)
		(mid 343.878043 -222.78566)
		(end 343.836498 -222.614236)
		(width 0.1143)
		(layer "In15.Cu")
		(net "GMI_CPU0_G1_CPU1_G3_TX_DP<15>")
	)
	(arc
		(start 344.776552 -225.85426)
		(mid 344.712037 -225.592041)
		(end 344.53322 -225.389694)
		(width 0.1143)
		(layer "In15.Cu")
		(net "GMI_CPU0_G1_CPU1_G3_TX_DP<15>")
	)
	(arc
		(start 344.776552 -229.094284)
		(mid 344.818101 -228.922862)
		(end 344.933524 -228.789484)
		(width 0.1143)
		(layer "In15.Cu")
		(net "GMI_CPU0_G1_CPU1_G3_TX_DP<15>")
	)
	(arc
		(start 126.562358 -240.129568)
		(mid 126.719335 -240.434368)
		(end 126.562358 -240.739168)
		(width 0.1143)
		(layer "In15.Cu")
		(net "GMI_CPU0_G1_CPU1_G3_TX_DP<15>")
	)
	(arc
		(start 126.492762 -239.159796)
		(mid 126.249435 -239.624362)
		(end 126.492762 -240.088928)
		(width 0.1143)
		(layer "In15.Cu")
		(net "GMI_CPU0_G1_CPU1_G3_TX_DP<15>")
	)
	(arc
		(start 126.562358 -227.169726)
		(mid 126.719335 -227.474526)
		(end 126.562358 -227.779326)
		(width 0.1143)
		(layer "In15.Cu")
		(net "GMI_CPU0_G1_CPU1_G3_TX_DP<15>")
	)
	(arc
		(start 345.00312 -227.128832)
		(mid 345.246447 -226.664266)
		(end 345.00312 -226.1997)
		(width 0.1143)
		(layer "In15.Cu")
		(net "GMI_CPU0_G1_CPU1_G3_TX_DP<15>")
	)
	(arc
		(start 126.24943 -229.90429)
		(mid 126.314666 -230.167881)
		(end 126.495302 -230.370634)
		(width 0.1143)
		(layer "In15.Cu")
		(net "GMI_CPU0_G1_CPU1_G3_TX_DP<15>")
	)
	(arc
		(start 344.933524 -234.258866)
		(mid 344.776547 -233.954066)
		(end 344.933524 -233.649266)
		(width 0.1143)
		(layer "In15.Cu")
		(net "GMI_CPU0_G1_CPU1_G3_TX_DP<15>")
	)
	(arc
		(start 344.933524 -226.15906)
		(mid 344.818097 -226.025684)
		(end 344.776552 -225.85426)
		(width 0.1143)
		(layer "In15.Cu")
		(net "GMI_CPU0_G1_CPU1_G3_TX_DP<15>")
	)
	(arc
		(start 345.943174 -245.63959)
		(mid 345.942793 -245.639336)
		(end 345.942412 -245.639082)
		(width 0.1143)
		(layer "In15.Cu")
		(net "GMI_CPU0_G1_CPU1_G3_TX_DP<15>")
	)
	(arc
		(start 345.00312 -236.84865)
		(mid 345.246447 -236.384084)
		(end 345.00312 -235.919518)
		(width 0.1143)
		(layer "In15.Cu")
		(net "GMI_CPU0_G1_CPU1_G3_TX_DP<15>")
	)
	(arc
		(start 126.562358 -228.789738)
		(mid 126.677785 -228.923114)
		(end 126.71933 -229.094538)
		(width 0.1143)
		(layer "In15.Cu")
		(net "GMI_CPU0_G1_CPU1_G3_TX_DP<15>")
	)
	(arc
		(start 126.492762 -226.199954)
		(mid 126.249435 -226.66452)
		(end 126.492762 -227.129086)
		(width 0.1143)
		(layer "In15.Cu")
		(net "GMI_CPU0_G1_CPU1_G3_TX_DP<15>")
	)
	(arc
		(start 345.00312 -231.988614)
		(mid 345.246447 -231.524048)
		(end 345.00312 -231.059482)
		(width 0.1143)
		(layer "In15.Cu")
		(net "GMI_CPU0_G1_CPU1_G3_TX_DP<15>")
	)
	(arc
		(start 345.246452 -244.484144)
		(mid 345.181937 -244.221925)
		(end 345.00312 -244.019578)
		(width 0.1143)
		(layer "In15.Cu")
		(net "GMI_CPU0_G1_CPU1_G3_TX_DP<15>")
	)
	(arc
		(start 344.933524 -239.118902)
		(mid 344.776547 -238.814102)
		(end 344.933524 -238.509302)
		(width 0.1143)
		(layer "In15.Cu")
		(net "GMI_CPU0_G1_CPU1_G3_TX_DP<15>")
	)
	(arc
		(start 126.492762 -237.539784)
		(mid 126.249435 -238.00435)
		(end 126.492762 -238.468916)
		(width 0.1143)
		(layer "In15.Cu")
		(net "GMI_CPU0_G1_CPU1_G3_TX_DP<15>")
	)
	(arc
		(start 344.063066 -223.888808)
		(mid 344.306393 -223.424242)
		(end 344.063066 -222.959676)
		(width 0.1143)
		(layer "In15.Cu")
		(net "GMI_CPU0_G1_CPU1_G3_TX_DP<15>")
	)
	(arc
		(start 126.562358 -223.929702)
		(mid 126.719335 -224.234502)
		(end 126.562358 -224.539302)
		(width 0.1143)
		(layer "In15.Cu")
		(net "GMI_CPU0_G1_CPU1_G3_TX_DP<15>")
	)
	(arc
		(start 345.00312 -241.708686)
		(mid 345.246447 -241.24412)
		(end 345.00312 -240.779554)
		(width 0.1143)
		(layer "In15.Cu")
		(net "GMI_CPU0_G1_CPU1_G3_TX_DP<15>")
	)
	(arc
		(start 126.492762 -227.819966)
		(mid 126.249435 -228.284532)
		(end 126.492762 -228.749098)
		(width 0.1143)
		(layer "In15.Cu")
		(net "GMI_CPU0_G1_CPU1_G3_TX_DP<15>")
	)
	(arc
		(start 346.18041 -246.021352)
		(mid 346.178622 -246.009903)
		(end 346.1766 -245.998492)
		(width 0.1143)
		(layer "In15.Cu")
		(net "GMI_CPU0_G1_CPU1_G3_TX_DP<15>")
	)
	(arc
		(start 346.1766 -245.998492)
		(mid 346.095167 -245.796094)
		(end 345.943174 -245.63959)
		(width 0.1143)
		(layer "In15.Cu")
		(net "GMI_CPU0_G1_CPU1_G3_TX_DP<15>")
	)
	(arc
		(start 345.00312 -235.228638)
		(mid 345.246447 -234.764072)
		(end 345.00312 -234.299506)
		(width 0.1143)
		(layer "In15.Cu")
		(net "GMI_CPU0_G1_CPU1_G3_TX_DP<15>")
	)
	(arc
		(start 344.933524 -237.49889)
		(mid 344.776547 -237.19409)
		(end 344.933524 -236.88929)
		(width 0.1143)
		(layer "In15.Cu")
		(net "GMI_CPU0_G1_CPU1_G3_TX_DP<15>")
	)
	(arc
		(start 126.492762 -234.29976)
		(mid 126.249435 -234.764326)
		(end 126.492762 -235.228892)
		(width 0.1143)
		(layer "In15.Cu")
		(net "GMI_CPU0_G1_CPU1_G3_TX_DP<15>")
	)
	(arc
		(start 126.492762 -242.39982)
		(mid 126.249435 -242.864386)
		(end 126.492762 -243.328952)
		(width 0.1143)
		(layer "In15.Cu")
		(net "GMI_CPU0_G1_CPU1_G3_TX_DP<15>")
	)
	(arc
		(start 345.246452 -229.904036)
		(mid 345.181937 -229.641817)
		(end 345.00312 -229.43947)
		(width 0.1143)
		(layer "In15.Cu")
		(net "GMI_CPU0_G1_CPU1_G3_TX_DP<15>")
	)
	(arc
		(start 126.562358 -243.369592)
		(mid 126.719335 -243.674392)
		(end 126.562358 -243.979192)
		(width 0.1143)
		(layer "In15.Cu")
		(net "GMI_CPU0_G1_CPU1_G3_TX_DP<15>")
	)
	(arc
		(start 344.933524 -232.638854)
		(mid 344.776547 -232.334054)
		(end 344.933524 -232.029254)
		(width 0.1143)
		(layer "In15.Cu")
		(net "GMI_CPU0_G1_CPU1_G3_TX_DP<15>")
	)
	(arc
		(start 126.492762 -244.019832)
		(mid 126.313949 -244.222182)
		(end 126.24943 -244.484398)
		(width 0.1143)
		(layer "In15.Cu")
		(net "GMI_CPU0_G1_CPU1_G3_TX_DP<15>")
	)
	(arc
		(start 126.492762 -231.059736)
		(mid 126.249435 -231.524302)
		(end 126.492762 -231.988868)
		(width 0.1143)
		(layer "In15.Cu")
		(net "GMI_CPU0_G1_CPU1_G3_TX_DP<15>")
	)
	(arc
		(start 126.492762 -224.579942)
		(mid 126.249435 -225.044508)
		(end 126.492762 -225.509074)
		(width 0.1143)
		(layer "In15.Cu")
		(net "GMI_CPU0_G1_CPU1_G3_TX_DP<15>")
	)
	(arc
		(start 126.71933 -229.094538)
		(mid 126.678364 -229.264944)
		(end 126.56439 -229.398068)
		(width 0.1143)
		(layer "In15.Cu")
		(net "GMI_CPU0_G1_CPU1_G3_TX_DP<15>")
	)
	(arc
		(start 344.306398 -225.044254)
		(mid 344.241883 -224.782035)
		(end 344.063066 -224.579688)
		(width 0.1143)
		(layer "In15.Cu")
		(net "GMI_CPU0_G1_CPU1_G3_TX_DP<15>")
	)
	(arc
		(start 126.562358 -241.74958)
		(mid 126.719335 -242.05438)
		(end 126.562358 -242.35918)
		(width 0.1143)
		(layer "In15.Cu")
		(net "GMI_CPU0_G1_CPU1_G3_TX_DP<15>")
	)
	(arc
		(start 344.933524 -243.978938)
		(mid 344.776547 -243.674138)
		(end 344.933524 -243.369338)
		(width 0.1143)
		(layer "In15.Cu")
		(net "GMI_CPU0_G1_CPU1_G3_TX_DP<15>")
	)
	(arc
		(start 345.00312 -240.088674)
		(mid 345.246447 -239.624108)
		(end 345.00312 -239.159542)
		(width 0.1143)
		(layer "In15.Cu")
		(net "GMI_CPU0_G1_CPU1_G3_TX_DP<15>")
	)
	(arc
		(start 126.248922 -221.804484)
		(mid 126.313794 -222.067447)
		(end 126.493524 -222.270066)
		(width 0.1143)
		(layer "In15.Cu")
		(net "GMI_CPU0_G1_CPU1_G3_TX_DP<15>")
	)
	(arc
		(start 344.933524 -240.738914)
		(mid 344.776547 -240.434114)
		(end 344.933524 -240.129314)
		(width 0.1143)
		(layer "In15.Cu")
		(net "GMI_CPU0_G1_CPU1_G3_TX_DP<15>")
	)
	(arc
		(start 126.492762 -222.95993)
		(mid 126.249435 -223.424496)
		(end 126.492762 -223.889062)
		(width 0.1143)
		(layer "In15.Cu")
		(net "GMI_CPU0_G1_CPU1_G3_TX_DP<15>")
	)
	(arc
		(start 345.00312 -233.608626)
		(mid 345.246447 -233.14406)
		(end 345.00312 -232.679494)
		(width 0.1143)
		(layer "In15.Cu")
		(net "GMI_CPU0_G1_CPU1_G3_TX_DP<15>")
	)
	(arc
		(start 126.564136 -222.31096)
		(mid 126.678289 -222.444036)
		(end 126.71933 -222.61449)
		(width 0.1143)
		(layer "In15.Cu")
		(net "GMI_CPU0_G1_CPU1_G3_TX_DP<15>")
	)
	(arc
		(start 126.562358 -230.40975)
		(mid 126.677785 -230.543126)
		(end 126.71933 -230.71455)
		(width 0.1143)
		(layer "In15.Cu")
		(net "GMI_CPU0_G1_CPU1_G3_TX_DP<15>")
	)
	(arc
		(start 126.562358 -236.889544)
		(mid 126.719335 -237.194344)
		(end 126.562358 -237.499144)
		(width 0.1143)
		(layer "In15.Cu")
		(net "GMI_CPU0_G1_CPU1_G3_TX_DP<15>")
	)
	(arc
		(start 125.319282 -245.998746)
		(mid 125.317259 -246.010156)
		(end 125.315472 -246.021606)
		(width 0.1143)
		(layer "In15.Cu")
		(net "GMI_CPU0_G1_CPU1_G3_TX_DP<15>")
	)
	(arc
		(start 345.00312 -238.468662)
		(mid 345.246447 -238.004096)
		(end 345.00312 -237.53953)
		(width 0.1143)
		(layer "In15.Cu")
		(net "GMI_CPU0_G1_CPU1_G3_TX_DP<15>")
	)
	(arc
		(start 126.24943 -244.484398)
		(mid 126.208175 -244.655369)
		(end 126.093474 -244.78869)
		(width 0.1143)
		(layer "In15.Cu")
		(net "GMI_CPU0_G1_CPU1_G3_TX_DP<15>")
	)
	(arc
		(start 126.492762 -229.439724)
		(mid 126.313949 -229.642074)
		(end 126.24943 -229.90429)
		(width 0.1143)
		(layer "In15.Cu")
		(net "GMI_CPU0_G1_CPU1_G3_TX_DP<15>")
	)
	(arc
		(start 345.00312 -228.748844)
		(mid 345.246447 -228.284278)
		(end 345.00312 -227.819712)
		(width 0.1143)
		(layer "In15.Cu")
		(net "GMI_CPU0_G1_CPU1_G3_TX_DP<15>")
	)
	(arc
		(start 343.99347 -224.539048)
		(mid 343.836493 -224.234248)
		(end 343.99347 -223.929448)
		(width 0.1143)
		(layer "In15.Cu")
		(net "GMI_CPU0_G1_CPU1_G3_TX_DP<15>")
	)
	(arc
		(start 344.776552 -230.714296)
		(mid 344.818101 -230.542874)
		(end 344.933524 -230.409496)
		(width 0.1143)
		(layer "In15.Cu")
		(net "GMI_CPU0_G1_CPU1_G3_TX_DP<15>")
	)
	(arc
		(start 344.931492 -231.017826)
		(mid 344.817563 -230.884679)
		(end 344.776552 -230.714296)
		(width 0.1143)
		(layer "In15.Cu")
		(net "GMI_CPU0_G1_CPU1_G3_TX_DP<15>")
	)
	(arc
		(start 126.562358 -233.64952)
		(mid 126.719335 -233.95432)
		(end 126.562358 -234.25912)
		(width 0.1143)
		(layer "In15.Cu")
		(net "GMI_CPU0_G1_CPU1_G3_TX_DP<15>")
	)
	(arc
		(start 126.562358 -238.509556)
		(mid 126.719335 -238.814356)
		(end 126.562358 -239.119156)
		(width 0.1143)
		(layer "In15.Cu")
		(net "GMI_CPU0_G1_CPU1_G3_TX_DP<15>")
	)
	(arc
		(start 126.022608 -244.829838)
		(mid 125.843795 -245.032188)
		(end 125.779276 -245.294404)
		(width 0.1143)
		(layer "In15.Cu")
		(net "GMI_CPU0_G1_CPU1_G3_TX_DP<15>")
	)
	(arc
		(start 125.779276 -245.294404)
		(mid 125.737727 -245.465826)
		(end 125.622304 -245.599204)
		(width 0.1143)
		(layer "In15.Cu")
		(net "GMI_CPU0_G1_CPU1_G3_TX_DP<15>")
	)
	(arc
		(start 345.00312 -243.328698)
		(mid 345.246447 -242.864132)
		(end 345.00312 -242.399566)
		(width 0.1143)
		(layer "In15.Cu")
		(net "GMI_CPU0_G1_CPU1_G3_TX_DP<15>")
	)
	(arc
		(start 343.5223 -222.108522)
		(mid 343.407624 -221.975188)
		(end 343.366344 -221.80423)
		(width 0.1143)
		(layer "In15.Cu")
		(net "GMI_CPU0_G1_CPU1_G3_TX_DP<15>")
	)
	(arc
		(start 126.71933 -222.61449)
		(mid 126.677781 -222.785912)
		(end 126.562358 -222.91929)
		(width 0.1143)
		(layer "In15.Cu")
		(net "GMI_CPU0_G1_CPU1_G3_TX_DP<15>")
	)
	(arc
		(start 344.933524 -235.878878)
		(mid 344.776547 -235.574078)
		(end 344.933524 -235.269278)
		(width 0.1143)
		(layer "In15.Cu")
		(net "GMI_CPU0_G1_CPU1_G3_TX_DP<15>")
	)
	(arc
		(start 344.931492 -229.397814)
		(mid 344.817563 -229.264667)
		(end 344.776552 -229.094284)
		(width 0.1143)
		(layer "In15.Cu")
		(net "GMI_CPU0_G1_CPU1_G3_TX_DP<15>")
	)
	(arc
		(start 344.462354 -225.348546)
		(mid 344.347678 -225.215212)
		(end 344.306398 -225.044254)
		(width 0.1143)
		(layer "In15.Cu")
		(net "GMI_CPU0_G1_CPU1_G3_TX_DP<15>")
	)
	(arc
		(start 126.492762 -232.679748)
		(mid 126.249435 -233.144314)
		(end 126.492762 -233.60888)
		(width 0.1143)
		(layer "In15.Cu")
		(net "GMI_CPU0_G1_CPU1_G3_TX_DP<15>")
	)
	(segment
		(start 124.467874 -244.750336)
		(end 124.934726 -244.484398)
		(width 0.12954)
		(layer "F.Cu")
		(net "GMI_CPU0_G1_CPU1_G3_TX_DP<14>")
	)
	(segment
		(start 347.028008 -244.750082)
		(end 346.561156 -244.484144)
		(width 0.12954)
		(layer "F.Cu")
		(net "GMI_CPU0_G1_CPU1_G3_TX_DP<14>")
	)
	(segment
		(start 345.907106 -230.389938)
		(end 345.936062 -230.373174)
		(width 0.1143)
		(layer "In15.Cu")
		(net "GMI_CPU0_G1_CPU1_G3_TX_DP<14>")
	)
	(segment
		(start 125.591824 -237.516924)
		(end 125.552708 -237.539784)
		(width 0.1143)
		(layer "In15.Cu")
		(net "GMI_CPU0_G1_CPU1_G3_TX_DP<14>")
	)
	(segment
		(start 345.924886 -238.47933)
		(end 345.92514 -238.47933)
		(width 0.1143)
		(layer "In15.Cu")
		(net "GMI_CPU0_G1_CPU1_G3_TX_DP<14>")
	)
	(segment
		(start 345.906344 -230.390446)
		(end 345.907106 -230.389938)
		(width 0.1143)
		(layer "In15.Cu")
		(net "GMI_CPU0_G1_CPU1_G3_TX_DP<14>")
	)
	(segment
		(start 345.910408 -237.520226)
		(end 345.909392 -237.519718)
		(width 0.1143)
		(layer "In15.Cu")
		(net "GMI_CPU0_G1_CPU1_G3_TX_DP<14>")
	)
	(segment
		(start 345.00312 -222.959676)
		(end 344.964004 -222.936816)
		(width 0.1143)
		(layer "In15.Cu")
		(net "GMI_CPU0_G1_CPU1_G3_TX_DP<14>")
	)
	(segment
		(start 125.591824 -232.011728)
		(end 125.622304 -232.029508)
		(width 0.1143)
		(layer "In15.Cu")
		(net "GMI_CPU0_G1_CPU1_G3_TX_DP<14>")
	)
	(segment
		(start 125.622304 -234.25912)
		(end 125.591824 -234.2769)
		(width 0.1143)
		(layer "In15.Cu")
		(net "GMI_CPU0_G1_CPU1_G3_TX_DP<14>")
	)
	(segment
		(start 344.933524 -223.929448)
		(end 344.964004 -223.911668)
		(width 0.1143)
		(layer "In15.Cu")
		(net "GMI_CPU0_G1_CPU1_G3_TX_DP<14>")
	)
	(segment
		(start 345.903296 -228.772212)
		(end 345.904058 -228.771704)
		(width 0.1143)
		(layer "In15.Cu")
		(net "GMI_CPU0_G1_CPU1_G3_TX_DP<14>")
	)
	(segment
		(start 162.552126 -190.180214)
		(end 161.468816 -191.068452)
		(width 0.14224)
		(layer "In15.Cu")
		(net "GMI_CPU0_G1_CPU1_G3_TX_DP<14>")
	)
	(segment
		(start 251.312934 -191.746886)
		(end 239.796066 -199.811132)
		(width 0.14224)
		(layer "In15.Cu")
		(net "GMI_CPU0_G1_CPU1_G3_TX_DP<14>")
	)
	(segment
		(start 125.591824 -239.136936)
		(end 125.552708 -239.159796)
		(width 0.1143)
		(layer "In15.Cu")
		(net "GMI_CPU0_G1_CPU1_G3_TX_DP<14>")
	)
	(segment
		(start 125.553724 -222.270066)
		(end 125.62332 -222.310198)
		(width 0.1143)
		(layer "In15.Cu")
		(net "GMI_CPU0_G1_CPU1_G3_TX_DP<14>")
	)
	(segment
		(start 149.344634 -201.33691)
		(end 146.839178 -202.09637)
		(width 0.14224)
		(layer "In15.Cu")
		(net "GMI_CPU0_G1_CPU1_G3_TX_DP<14>")
	)
	(segment
		(start 125.624336 -229.398068)
		(end 125.591824 -229.416864)
		(width 0.1143)
		(layer "In15.Cu")
		(net "GMI_CPU0_G1_CPU1_G3_TX_DP<14>")
	)
	(segment
		(start 345.906598 -228.77018)
		(end 345.907614 -228.769672)
		(width 0.1143)
		(layer "In15.Cu")
		(net "GMI_CPU0_G1_CPU1_G3_TX_DP<14>")
	)
	(segment
		(start 262.742426 -189.73165)
		(end 251.312934 -191.746886)
		(width 0.14224)
		(layer "In15.Cu")
		(net "GMI_CPU0_G1_CPU1_G3_TX_DP<14>")
	)
	(segment
		(start 125.309122 -221.59849)
		(end 125.309122 -221.804484)
		(width 0.1143)
		(layer "In15.Cu")
		(net "GMI_CPU0_G1_CPU1_G3_TX_DP<14>")
	)
	(segment
		(start 346.263214 -244.484144)
		(end 346.18041 -244.40134)
		(width 0.1143)
		(layer "In15.Cu")
		(net "GMI_CPU0_G1_CPU1_G3_TX_DP<14>")
	)
	(segment
		(start 345.904058 -233.631486)
		(end 345.905074 -233.630978)
		(width 0.1143)
		(layer "In15.Cu")
		(net "GMI_CPU0_G1_CPU1_G3_TX_DP<14>")
	)
	(segment
		(start 125.591824 -234.2769)
		(end 125.552708 -234.29976)
		(width 0.1143)
		(layer "In15.Cu")
		(net "GMI_CPU0_G1_CPU1_G3_TX_DP<14>")
	)
	(segment
		(start 345.905074 -233.630978)
		(end 345.906598 -233.629962)
		(width 0.1143)
		(layer "In15.Cu")
		(net "GMI_CPU0_G1_CPU1_G3_TX_DP<14>")
	)
	(segment
		(start 345.872308 -227.16998)
		(end 345.904058 -227.151692)
		(width 0.1143)
		(layer "In15.Cu")
		(net "GMI_CPU0_G1_CPU1_G3_TX_DP<14>")
	)
	(segment
		(start 344.49512 -222.127318)
		(end 344.494104 -222.12681)
		(width 0.1143)
		(layer "In15.Cu")
		(net "GMI_CPU0_G1_CPU1_G3_TX_DP<14>")
	)
	(segment
		(start 345.903296 -243.99621)
		(end 345.872308 -243.97843)
		(width 0.1143)
		(layer "In15.Cu")
		(net "GMI_CPU0_G1_CPU1_G3_TX_DP<14>")
	)
	(segment
		(start 207.178402 -189.990984)
		(end 162.552126 -190.180214)
		(width 0.14224)
		(layer "In15.Cu")
		(net "GMI_CPU0_G1_CPU1_G3_TX_DP<14>")
	)
	(segment
		(start 345.903296 -232.656126)
		(end 345.872308 -232.638346)
		(width 0.1143)
		(layer "In15.Cu")
		(net "GMI_CPU0_G1_CPU1_G3_TX_DP<14>")
	)
	(segment
		(start 345.935554 -227.81514)
		(end 345.904058 -227.796852)
		(width 0.1143)
		(layer "In15.Cu")
		(net "GMI_CPU0_G1_CPU1_G3_TX_DP<14>")
	)
	(segment
		(start 125.622304 -227.779326)
		(end 125.591824 -227.797106)
		(width 0.1143)
		(layer "In15.Cu")
		(net "GMI_CPU0_G1_CPU1_G3_TX_DP<14>")
	)
	(segment
		(start 345.942412 -237.539022)
		(end 345.910408 -237.520226)
		(width 0.1143)
		(layer "In15.Cu")
		(net "GMI_CPU0_G1_CPU1_G3_TX_DP<14>")
	)
	(segment
		(start 125.552708 -243.328952)
		(end 125.591824 -243.351812)
		(width 0.1143)
		(layer "In15.Cu")
		(net "GMI_CPU0_G1_CPU1_G3_TX_DP<14>")
	)
	(segment
		(start 317.269622 -196.116956)
		(end 308.735476 -190.109856)
		(width 0.14224)
		(layer "In15.Cu")
		(net "GMI_CPU0_G1_CPU1_G3_TX_DP<14>")
	)
	(segment
		(start 125.309376 -221.598236)
		(end 125.309122 -221.59849)
		(width 0.1143)
		(layer "In15.Cu")
		(net "GMI_CPU0_G1_CPU1_G3_TX_DP<14>")
	)
	(segment
		(start 345.906598 -232.00995)
		(end 345.943174 -231.988614)
		(width 0.1143)
		(layer "In15.Cu")
		(net "GMI_CPU0_G1_CPU1_G3_TX_DP<14>")
	)
	(segment
		(start 345.90355 -235.251752)
		(end 345.924886 -235.239306)
		(width 0.1143)
		(layer "In15.Cu")
		(net "GMI_CPU0_G1_CPU1_G3_TX_DP<14>")
	)
	(segment
		(start 344.306398 -221.368874)
		(end 344.2462 -221.308676)
		(width 0.1143)
		(layer "In15.Cu")
		(net "GMI_CPU0_G1_CPU1_G3_TX_DP<14>")
	)
	(segment
		(start 345.90355 -240.111788)
		(end 345.924886 -240.099342)
		(width 0.1143)
		(layer "In15.Cu")
		(net "GMI_CPU0_G1_CPU1_G3_TX_DP<14>")
	)
	(segment
		(start 345.943174 -229.43947)
		(end 345.904058 -229.41661)
		(width 0.1143)
		(layer "In15.Cu")
		(net "GMI_CPU0_G1_CPU1_G3_TX_DP<14>")
	)
	(segment
		(start 233.086148 -199.843136)
		(end 210.873594 -190.643002)
		(width 0.14224)
		(layer "In15.Cu")
		(net "GMI_CPU0_G1_CPU1_G3_TX_DP<14>")
	)
	(segment
		(start 345.924886 -236.859318)
		(end 345.92514 -236.859318)
		(width 0.1143)
		(layer "In15.Cu")
		(net "GMI_CPU0_G1_CPU1_G3_TX_DP<14>")
	)
	(segment
		(start 125.622304 -224.539302)
		(end 125.591824 -224.557082)
		(width 0.1143)
		(layer "In15.Cu")
		(net "GMI_CPU0_G1_CPU1_G3_TX_DP<14>")
	)
	(segment
		(start 125.622304 -243.979192)
		(end 125.591824 -243.996972)
		(width 0.1143)
		(layer "In15.Cu")
		(net "GMI_CPU0_G1_CPU1_G3_TX_DP<14>")
	)
	(segment
		(start 161.468816 -191.068452)
		(end 161.15538 -191.653922)
		(width 0.14224)
		(layer "In15.Cu")
		(net "GMI_CPU0_G1_CPU1_G3_TX_DP<14>")
	)
	(segment
		(start 345.94038 -227.130864)
		(end 345.943174 -227.128832)
		(width 0.1143)
		(layer "In15.Cu")
		(net "GMI_CPU0_G1_CPU1_G3_TX_DP<14>")
	)
	(segment
		(start 344.964004 -222.936816)
		(end 344.933524 -222.919036)
		(width 0.1143)
		(layer "In15.Cu")
		(net "GMI_CPU0_G1_CPU1_G3_TX_DP<14>")
	)
	(segment
		(start 345.92514 -238.47933)
		(end 345.943174 -238.468662)
		(width 0.1143)
		(layer "In15.Cu")
		(net "GMI_CPU0_G1_CPU1_G3_TX_DP<14>")
	)
	(segment
		(start 345.903296 -233.631994)
		(end 345.904058 -233.631486)
		(width 0.1143)
		(layer "In15.Cu")
		(net "GMI_CPU0_G1_CPU1_G3_TX_DP<14>")
	)
	(segment
		(start 345.924886 -241.719354)
		(end 345.92514 -241.719354)
		(width 0.1143)
		(layer "In15.Cu")
		(net "GMI_CPU0_G1_CPU1_G3_TX_DP<14>")
	)
	(segment
		(start 345.904058 -230.391716)
		(end 345.905074 -230.391208)
		(width 0.1143)
		(layer "In15.Cu")
		(net "GMI_CPU0_G1_CPU1_G3_TX_DP<14>")
	)
	(segment
		(start 125.591824 -235.896912)
		(end 125.552708 -235.919772)
		(width 0.1143)
		(layer "In15.Cu")
		(net "GMI_CPU0_G1_CPU1_G3_TX_DP<14>")
	)
	(segment
		(start 345.943174 -227.819712)
		(end 345.936316 -227.815648)
		(width 0.1143)
		(layer "In15.Cu")
		(net "GMI_CPU0_G1_CPU1_G3_TX_DP<14>")
	)
	(segment
		(start 345.904058 -228.771704)
		(end 345.905074 -228.771196)
		(width 0.1143)
		(layer "In15.Cu")
		(net "GMI_CPU0_G1_CPU1_G3_TX_DP<14>")
	)
	(segment
		(start 125.552708 -235.228892)
		(end 125.591824 -235.251752)
		(width 0.1143)
		(layer "In15.Cu")
		(net "GMI_CPU0_G1_CPU1_G3_TX_DP<14>")
	)
	(segment
		(start 345.942412 -239.159034)
		(end 345.910408 -239.140238)
		(width 0.1143)
		(layer "In15.Cu")
		(net "GMI_CPU0_G1_CPU1_G3_TX_DP<14>")
	)
	(segment
		(start 345.906598 -233.629962)
		(end 345.943174 -233.608626)
		(width 0.1143)
		(layer "In15.Cu")
		(net "GMI_CPU0_G1_CPU1_G3_TX_DP<14>")
	)
	(segment
		(start 125.552708 -240.088928)
		(end 125.591824 -240.111788)
		(width 0.1143)
		(layer "In15.Cu")
		(net "GMI_CPU0_G1_CPU1_G3_TX_DP<14>")
	)
	(segment
		(start 345.905074 -243.35105)
		(end 345.906598 -243.350034)
		(width 0.1143)
		(layer "In15.Cu")
		(net "GMI_CPU0_G1_CPU1_G3_TX_DP<14>")
	)
	(segment
		(start 153.969974 -197.544944)
		(end 153.970228 -197.544944)
		(width 0.14224)
		(layer "In15.Cu")
		(net "GMI_CPU0_G1_CPU1_G3_TX_DP<14>")
	)
	(segment
		(start 345.943174 -244.019578)
		(end 345.936316 -244.015514)
		(width 0.1143)
		(layer "In15.Cu")
		(net "GMI_CPU0_G1_CPU1_G3_TX_DP<14>")
	)
	(segment
		(start 345.939618 -234.296966)
		(end 345.904058 -234.276646)
		(width 0.1143)
		(layer "In15.Cu")
		(net "GMI_CPU0_G1_CPU1_G3_TX_DP<14>")
	)
	(segment
		(start 125.591824 -223.911922)
		(end 125.622304 -223.929702)
		(width 0.1143)
		(layer "In15.Cu")
		(net "GMI_CPU0_G1_CPU1_G3_TX_DP<14>")
	)
	(segment
		(start 146.839178 -202.09637)
		(end 126.350014 -218.896692)
		(width 0.14224)
		(layer "In15.Cu")
		(net "GMI_CPU0_G1_CPU1_G3_TX_DP<14>")
	)
	(segment
		(start 345.907614 -228.769672)
		(end 345.919552 -228.76256)
		(width 0.1143)
		(layer "In15.Cu")
		(net "GMI_CPU0_G1_CPU1_G3_TX_DP<14>")
	)
	(segment
		(start 125.591824 -231.036876)
		(end 125.552708 -231.059736)
		(width 0.1143)
		(layer "In15.Cu")
		(net "GMI_CPU0_G1_CPU1_G3_TX_DP<14>")
	)
	(segment
		(start 239.796066 -199.811132)
		(end 236.351064 -200.4187)
		(width 0.14224)
		(layer "In15.Cu")
		(net "GMI_CPU0_G1_CPU1_G3_TX_DP<14>")
	)
	(segment
		(start 345.909392 -239.13973)
		(end 345.90863 -239.139222)
		(width 0.1143)
		(layer "In15.Cu")
		(net "GMI_CPU0_G1_CPU1_G3_TX_DP<14>")
	)
	(segment
		(start 345.90355 -241.7318)
		(end 345.924886 -241.719354)
		(width 0.1143)
		(layer "In15.Cu")
		(net "GMI_CPU0_G1_CPU1_G3_TX_DP<14>")
	)
	(segment
		(start 125.315472 -244.401594)
		(end 125.232668 -244.484398)
		(width 0.1143)
		(layer "In15.Cu")
		(net "GMI_CPU0_G1_CPU1_G3_TX_DP<14>")
	)
	(segment
		(start 125.591824 -242.37696)
		(end 125.552708 -242.39982)
		(width 0.1143)
		(layer "In15.Cu")
		(net "GMI_CPU0_G1_CPU1_G3_TX_DP<14>")
	)
	(segment
		(start 125.591824 -227.797106)
		(end 125.552708 -227.819966)
		(width 0.1143)
		(layer "In15.Cu")
		(net "GMI_CPU0_G1_CPU1_G3_TX_DP<14>")
	)
	(segment
		(start 125.591824 -238.491776)
		(end 125.622304 -238.509556)
		(width 0.1143)
		(layer "In15.Cu")
		(net "GMI_CPU0_G1_CPU1_G3_TX_DP<14>")
	)
	(segment
		(start 345.904058 -227.151692)
		(end 345.94038 -227.130864)
		(width 0.1143)
		(layer "In15.Cu")
		(net "GMI_CPU0_G1_CPU1_G3_TX_DP<14>")
	)
	(segment
		(start 345.904058 -232.011474)
		(end 345.905074 -232.010966)
		(width 0.1143)
		(layer "In15.Cu")
		(net "GMI_CPU0_G1_CPU1_G3_TX_DP<14>")
	)
	(segment
		(start 345.900502 -230.393748)
		(end 345.902026 -230.392986)
		(width 0.1143)
		(layer "In15.Cu")
		(net "GMI_CPU0_G1_CPU1_G3_TX_DP<14>")
	)
	(segment
		(start 125.552708 -225.509074)
		(end 125.591824 -225.531934)
		(width 0.1143)
		(layer "In15.Cu")
		(net "GMI_CPU0_G1_CPU1_G3_TX_DP<14>")
	)
	(segment
		(start 344.493342 -222.126302)
		(end 344.485976 -222.122238)
		(width 0.1143)
		(layer "In15.Cu")
		(net "GMI_CPU0_G1_CPU1_G3_TX_DP<14>")
	)
	(segment
		(start 210.873594 -190.643002)
		(end 207.178402 -189.990984)
		(width 0.14224)
		(layer "In15.Cu")
		(net "GMI_CPU0_G1_CPU1_G3_TX_DP<14>")
	)
	(segment
		(start 345.90355 -238.491776)
		(end 345.924886 -238.47933)
		(width 0.1143)
		(layer "In15.Cu")
		(net "GMI_CPU0_G1_CPU1_G3_TX_DP<14>")
	)
	(segment
		(start 344.964004 -223.911668)
		(end 345.00312 -223.888808)
		(width 0.1143)
		(layer "In15.Cu")
		(net "GMI_CPU0_G1_CPU1_G3_TX_DP<14>")
	)
	(segment
		(start 345.904058 -227.796852)
		(end 345.903296 -227.796344)
		(width 0.1143)
		(layer "In15.Cu")
		(net "GMI_CPU0_G1_CPU1_G3_TX_DP<14>")
	)
	(segment
		(start 345.434158 -225.366834)
		(end 345.402408 -225.348546)
		(width 0.1143)
		(layer "In15.Cu")
		(net "GMI_CPU0_G1_CPU1_G3_TX_DP<14>")
	)
	(segment
		(start 345.919552 -228.76256)
		(end 345.943174 -228.748844)
		(width 0.1143)
		(layer "In15.Cu")
		(net "GMI_CPU0_G1_CPU1_G3_TX_DP<14>")
	)
	(segment
		(start 345.872308 -232.029762)
		(end 345.903296 -232.011982)
		(width 0.1143)
		(layer "In15.Cu")
		(net "GMI_CPU0_G1_CPU1_G3_TX_DP<14>")
	)
	(segment
		(start 125.591824 -243.351812)
		(end 125.622304 -243.369592)
		(width 0.1143)
		(layer "In15.Cu")
		(net "GMI_CPU0_G1_CPU1_G3_TX_DP<14>")
	)
	(segment
		(start 125.622304 -237.499144)
		(end 125.591824 -237.516924)
		(width 0.1143)
		(layer "In15.Cu")
		(net "GMI_CPU0_G1_CPU1_G3_TX_DP<14>")
	)
	(segment
		(start 125.263656 -220.815408)
		(end 125.263656 -221.174564)
		(width 0.14224)
		(layer "In15.Cu")
		(net "GMI_CPU0_G1_CPU1_G3_TX_DP<14>")
	)
	(segment
		(start 161.155634 -191.653922)
		(end 153.969974 -197.544944)
		(width 0.14224)
		(layer "In15.Cu")
		(net "GMI_CPU0_G1_CPU1_G3_TX_DP<14>")
	)
	(segment
		(start 344.29192 -220.486732)
		(end 342.580468 -216.87028)
		(width 0.14224)
		(layer "In15.Cu")
		(net "GMI_CPU0_G1_CPU1_G3_TX_DP<14>")
	)
	(segment
		(start 345.90863 -237.51921)
		(end 345.896184 -237.512098)
		(width 0.1143)
		(layer "In15.Cu")
		(net "GMI_CPU0_G1_CPU1_G3_TX_DP<14>")
	)
	(segment
		(start 344.29192 -221.097602)
		(end 344.29192 -221.083124)
		(width 0.1143)
		(layer "In15.Cu")
		(net "GMI_CPU0_G1_CPU1_G3_TX_DP<14>")
	)
	(segment
		(start 125.309376 -221.248732)
		(end 125.309376 -221.598236)
		(width 0.1143)
		(layer "In15.Cu")
		(net "GMI_CPU0_G1_CPU1_G3_TX_DP<14>")
	)
	(segment
		(start 345.943174 -226.1997)
		(end 345.904058 -226.17684)
		(width 0.1143)
		(layer "In15.Cu")
		(net "GMI_CPU0_G1_CPU1_G3_TX_DP<14>")
	)
	(segment
		(start 345.936062 -230.373174)
		(end 345.940634 -230.37038)
		(width 0.1143)
		(layer "In15.Cu")
		(net "GMI_CPU0_G1_CPU1_G3_TX_DP<14>")
	)
	(segment
		(start 345.90863 -239.139222)
		(end 345.896184 -239.13211)
		(width 0.1143)
		(layer "In15.Cu")
		(net "GMI_CPU0_G1_CPU1_G3_TX_DP<14>")
	)
	(segment
		(start 125.591824 -226.177094)
		(end 125.552708 -226.199954)
		(width 0.1143)
		(layer "In15.Cu")
		(net "GMI_CPU0_G1_CPU1_G3_TX_DP<14>")
	)
	(segment
		(start 125.591824 -232.656888)
		(end 125.552708 -232.679748)
		(width 0.1143)
		(layer "In15.Cu")
		(net "GMI_CPU0_G1_CPU1_G3_TX_DP<14>")
	)
	(segment
		(start 125.552708 -241.70894)
		(end 125.591824 -241.7318)
		(width 0.1143)
		(layer "In15.Cu")
		(net "GMI_CPU0_G1_CPU1_G3_TX_DP<14>")
	)
	(segment
		(start 345.905074 -232.657142)
		(end 345.904058 -232.656634)
		(width 0.1143)
		(layer "In15.Cu")
		(net "GMI_CPU0_G1_CPU1_G3_TX_DP<14>")
	)
	(segment
		(start 345.90863 -242.379246)
		(end 345.896184 -242.372134)
		(width 0.1143)
		(layer "In15.Cu")
		(net "GMI_CPU0_G1_CPU1_G3_TX_DP<14>")
	)
	(segment
		(start 345.909392 -240.759742)
		(end 345.90863 -240.759234)
		(width 0.1143)
		(layer "In15.Cu")
		(net "GMI_CPU0_G1_CPU1_G3_TX_DP<14>")
	)
	(segment
		(start 345.872308 -230.410004)
		(end 345.900502 -230.393748)
		(width 0.1143)
		(layer "In15.Cu")
		(net "GMI_CPU0_G1_CPU1_G3_TX_DP<14>")
	)
	(segment
		(start 345.910408 -239.140238)
		(end 345.909392 -239.13973)
		(width 0.1143)
		(layer "In15.Cu")
		(net "GMI_CPU0_G1_CPU1_G3_TX_DP<14>")
	)
	(segment
		(start 125.552708 -227.129086)
		(end 125.591824 -227.151946)
		(width 0.1143)
		(layer "In15.Cu")
		(net "GMI_CPU0_G1_CPU1_G3_TX_DP<14>")
	)
	(segment
		(start 342.580468 -216.87028)
		(end 317.269622 -196.116956)
		(width 0.14224)
		(layer "In15.Cu")
		(net "GMI_CPU0_G1_CPU1_G3_TX_DP<14>")
	)
	(segment
		(start 345.904058 -234.276646)
		(end 345.872308 -234.258358)
		(width 0.1143)
		(layer "In15.Cu")
		(net "GMI_CPU0_G1_CPU1_G3_TX_DP<14>")
	)
	(segment
		(start 125.263656 -221.174564)
		(end 125.263656 -221.203012)
		(width 0.1143)
		(layer "In15.Cu")
		(net "GMI_CPU0_G1_CPU1_G3_TX_DP<14>")
	)
	(segment
		(start 126.350014 -218.896692)
		(end 125.263656 -220.815408)
		(width 0.14224)
		(layer "In15.Cu")
		(net "GMI_CPU0_G1_CPU1_G3_TX_DP<14>")
	)
	(segment
		(start 344.2462 -221.143322)
		(end 344.29192 -221.097602)
		(width 0.1143)
		(layer "In15.Cu")
		(net "GMI_CPU0_G1_CPU1_G3_TX_DP<14>")
	)
	(segment
		(start 344.2462 -221.308676)
		(end 344.2462 -221.143322)
		(width 0.1143)
		(layer "In15.Cu")
		(net "GMI_CPU0_G1_CPU1_G3_TX_DP<14>")
	)
	(segment
		(start 125.552708 -233.60888)
		(end 125.591824 -233.63174)
		(width 0.1143)
		(layer "In15.Cu")
		(net "GMI_CPU0_G1_CPU1_G3_TX_DP<14>")
	)
	(segment
		(start 125.555248 -230.370634)
		(end 125.622304 -230.40975)
		(width 0.1143)
		(layer "In15.Cu")
		(net "GMI_CPU0_G1_CPU1_G3_TX_DP<14>")
	)
	(segment
		(start 161.15538 -191.653922)
		(end 161.155634 -191.653922)
		(width 0.14224)
		(layer "In15.Cu")
		(net "GMI_CPU0_G1_CPU1_G3_TX_DP<14>")
	)
	(segment
		(start 345.872308 -233.649774)
		(end 345.903296 -233.631994)
		(width 0.1143)
		(layer "In15.Cu")
		(net "GMI_CPU0_G1_CPU1_G3_TX_DP<14>")
	)
	(segment
		(start 125.591824 -228.771958)
		(end 125.622304 -228.789738)
		(width 0.1143)
		(layer "In15.Cu")
		(net "GMI_CPU0_G1_CPU1_G3_TX_DP<14>")
	)
	(segment
		(start 345.942412 -240.779046)
		(end 345.910408 -240.76025)
		(width 0.1143)
		(layer "In15.Cu")
		(net "GMI_CPU0_G1_CPU1_G3_TX_DP<14>")
	)
	(segment
		(start 125.624336 -231.01808)
		(end 125.591824 -231.036876)
		(width 0.1143)
		(layer "In15.Cu")
		(net "GMI_CPU0_G1_CPU1_G3_TX_DP<14>")
	)
	(segment
		(start 345.924886 -240.099342)
		(end 345.92514 -240.099342)
		(width 0.1143)
		(layer "In15.Cu")
		(net "GMI_CPU0_G1_CPU1_G3_TX_DP<14>")
	)
	(segment
		(start 345.903296 -230.392224)
		(end 345.904058 -230.391716)
		(width 0.1143)
		(layer "In15.Cu")
		(net "GMI_CPU0_G1_CPU1_G3_TX_DP<14>")
	)
	(segment
		(start 344.53322 -222.14967)
		(end 344.49512 -222.127318)
		(width 0.1143)
		(layer "In15.Cu")
		(net "GMI_CPU0_G1_CPU1_G3_TX_DP<14>")
	)
	(segment
		(start 125.552708 -231.988868)
		(end 125.591824 -232.011728)
		(width 0.1143)
		(layer "In15.Cu")
		(net "GMI_CPU0_G1_CPU1_G3_TX_DP<14>")
	)
	(segment
		(start 345.903296 -227.796344)
		(end 345.872308 -227.778564)
		(width 0.1143)
		(layer "In15.Cu")
		(net "GMI_CPU0_G1_CPU1_G3_TX_DP<14>")
	)
	(segment
		(start 345.936316 -227.815648)
		(end 345.935554 -227.81514)
		(width 0.1143)
		(layer "In15.Cu")
		(net "GMI_CPU0_G1_CPU1_G3_TX_DP<14>")
	)
	(segment
		(start 345.909392 -237.519718)
		(end 345.90863 -237.51921)
		(width 0.1143)
		(layer "In15.Cu")
		(net "GMI_CPU0_G1_CPU1_G3_TX_DP<14>")
	)
	(segment
		(start 345.872308 -243.369846)
		(end 345.903296 -243.352066)
		(width 0.1143)
		(layer "In15.Cu")
		(net "GMI_CPU0_G1_CPU1_G3_TX_DP<14>")
	)
	(segment
		(start 345.435936 -225.36785)
		(end 345.434158 -225.366834)
		(width 0.1143)
		(layer "In15.Cu")
		(net "GMI_CPU0_G1_CPU1_G3_TX_DP<14>")
	)
	(segment
		(start 345.904058 -243.351558)
		(end 345.905074 -243.35105)
		(width 0.1143)
		(layer "In15.Cu")
		(net "GMI_CPU0_G1_CPU1_G3_TX_DP<14>")
	)
	(segment
		(start 345.904058 -226.17684)
		(end 345.873324 -226.15906)
		(width 0.1143)
		(layer "In15.Cu")
		(net "GMI_CPU0_G1_CPU1_G3_TX_DP<14>")
	)
	(segment
		(start 125.552708 -223.889062)
		(end 125.591824 -223.911922)
		(width 0.1143)
		(layer "In15.Cu")
		(net "GMI_CPU0_G1_CPU1_G3_TX_DP<14>")
	)
	(segment
		(start 345.92514 -240.099342)
		(end 345.943174 -240.088674)
		(width 0.1143)
		(layer "In15.Cu")
		(net "GMI_CPU0_G1_CPU1_G3_TX_DP<14>")
	)
	(segment
		(start 345.906598 -243.350034)
		(end 345.943174 -243.328698)
		(width 0.1143)
		(layer "In15.Cu")
		(net "GMI_CPU0_G1_CPU1_G3_TX_DP<14>")
	)
	(segment
		(start 345.9353 -235.914692)
		(end 345.909392 -235.899706)
		(width 0.1143)
		(layer "In15.Cu")
		(net "GMI_CPU0_G1_CPU1_G3_TX_DP<14>")
	)
	(segment
		(start 125.622304 -242.35918)
		(end 125.591824 -242.37696)
		(width 0.1143)
		(layer "In15.Cu")
		(net "GMI_CPU0_G1_CPU1_G3_TX_DP<14>")
	)
	(segment
		(start 125.591824 -225.531934)
		(end 125.622304 -225.549714)
		(width 0.1143)
		(layer "In15.Cu")
		(net "GMI_CPU0_G1_CPU1_G3_TX_DP<14>")
	)
	(segment
		(start 345.904058 -229.41661)
		(end 345.87053 -229.397052)
		(width 0.1143)
		(layer "In15.Cu")
		(net "GMI_CPU0_G1_CPU1_G3_TX_DP<14>")
	)
	(segment
		(start 345.905074 -228.771196)
		(end 345.906598 -228.77018)
		(width 0.1143)
		(layer "In15.Cu")
		(net "GMI_CPU0_G1_CPU1_G3_TX_DP<14>")
	)
	(segment
		(start 345.924886 -235.239306)
		(end 345.92514 -235.239306)
		(width 0.1143)
		(layer "In15.Cu")
		(net "GMI_CPU0_G1_CPU1_G3_TX_DP<14>")
	)
	(segment
		(start 345.943174 -232.679494)
		(end 345.905074 -232.657142)
		(width 0.1143)
		(layer "In15.Cu")
		(net "GMI_CPU0_G1_CPU1_G3_TX_DP<14>")
	)
	(segment
		(start 125.591824 -240.111788)
		(end 125.622304 -240.129568)
		(width 0.1143)
		(layer "In15.Cu")
		(net "GMI_CPU0_G1_CPU1_G3_TX_DP<14>")
	)
	(segment
		(start 345.905074 -230.391208)
		(end 345.906344 -230.390446)
		(width 0.1143)
		(layer "In15.Cu")
		(net "GMI_CPU0_G1_CPU1_G3_TX_DP<14>")
	)
	(segment
		(start 345.909392 -235.899706)
		(end 345.90863 -235.899198)
		(width 0.1143)
		(layer "In15.Cu")
		(net "GMI_CPU0_G1_CPU1_G3_TX_DP<14>")
	)
	(segment
		(start 345.907106 -235.898436)
		(end 345.896184 -235.892086)
		(width 0.1143)
		(layer "In15.Cu")
		(net "GMI_CPU0_G1_CPU1_G3_TX_DP<14>")
	)
	(segment
		(start 344.964004 -224.556828)
		(end 344.933524 -224.539048)
		(width 0.1143)
		(layer "In15.Cu")
		(net "GMI_CPU0_G1_CPU1_G3_TX_DP<14>")
	)
	(segment
		(start 125.591824 -233.63174)
		(end 125.622304 -233.64952)
		(width 0.1143)
		(layer "In15.Cu")
		(net "GMI_CPU0_G1_CPU1_G3_TX_DP<14>")
	)
	(segment
		(start 345.92514 -241.719354)
		(end 345.943174 -241.708686)
		(width 0.1143)
		(layer "In15.Cu")
		(net "GMI_CPU0_G1_CPU1_G3_TX_DP<14>")
	)
	(segment
		(start 345.47048 -225.387916)
		(end 345.43746 -225.368866)
		(width 0.1143)
		(layer "In15.Cu")
		(net "GMI_CPU0_G1_CPU1_G3_TX_DP<14>")
	)
	(segment
		(start 125.622304 -222.91929)
		(end 125.591824 -222.93707)
		(width 0.1143)
		(layer "In15.Cu")
		(net "GMI_CPU0_G1_CPU1_G3_TX_DP<14>")
	)
	(segment
		(start 125.552708 -236.848904)
		(end 125.591824 -236.871764)
		(width 0.1143)
		(layer "In15.Cu")
		(net "GMI_CPU0_G1_CPU1_G3_TX_DP<14>")
	)
	(segment
		(start 344.485976 -222.122238)
		(end 344.462354 -222.108522)
		(width 0.1143)
		(layer "In15.Cu")
		(net "GMI_CPU0_G1_CPU1_G3_TX_DP<14>")
	)
	(segment
		(start 125.622304 -240.739168)
		(end 125.591824 -240.756948)
		(width 0.1143)
		(layer "In15.Cu")
		(net "GMI_CPU0_G1_CPU1_G3_TX_DP<14>")
	)
	(segment
		(start 345.92514 -236.859318)
		(end 345.943174 -236.84865)
		(width 0.1143)
		(layer "In15.Cu")
		(net "GMI_CPU0_G1_CPU1_G3_TX_DP<14>")
	)
	(segment
		(start 125.591824 -235.251752)
		(end 125.622304 -235.269532)
		(width 0.1143)
		(layer "In15.Cu")
		(net "GMI_CPU0_G1_CPU1_G3_TX_DP<14>")
	)
	(segment
		(start 345.903296 -243.352066)
		(end 345.904058 -243.351558)
		(width 0.1143)
		(layer "In15.Cu")
		(net "GMI_CPU0_G1_CPU1_G3_TX_DP<14>")
	)
	(segment
		(start 345.942412 -234.298998)
		(end 345.939618 -234.296966)
		(width 0.1143)
		(layer "In15.Cu")
		(net "GMI_CPU0_G1_CPU1_G3_TX_DP<14>")
	)
	(segment
		(start 346.561156 -244.484144)
		(end 346.263214 -244.484144)
		(width 0.1143)
		(layer "In15.Cu")
		(net "GMI_CPU0_G1_CPU1_G3_TX_DP<14>")
	)
	(segment
		(start 125.622304 -232.639108)
		(end 125.591824 -232.656888)
		(width 0.1143)
		(layer "In15.Cu")
		(net "GMI_CPU0_G1_CPU1_G3_TX_DP<14>")
	)
	(segment
		(start 125.552708 -228.749098)
		(end 125.591824 -228.771958)
		(width 0.1143)
		(layer "In15.Cu")
		(net "GMI_CPU0_G1_CPU1_G3_TX_DP<14>")
	)
	(segment
		(start 125.591824 -224.557082)
		(end 125.552708 -224.579942)
		(width 0.1143)
		(layer "In15.Cu")
		(net "GMI_CPU0_G1_CPU1_G3_TX_DP<14>")
	)
	(segment
		(start 125.55474 -229.4382)
		(end 125.552708 -229.439724)
		(width 0.1143)
		(layer "In15.Cu")
		(net "GMI_CPU0_G1_CPU1_G3_TX_DP<14>")
	)
	(segment
		(start 345.942412 -235.91901)
		(end 345.936062 -235.9152)
		(width 0.1143)
		(layer "In15.Cu")
		(net "GMI_CPU0_G1_CPU1_G3_TX_DP<14>")
	)
	(segment
		(start 345.904058 -243.996718)
		(end 345.903296 -243.99621)
		(width 0.1143)
		(layer "In15.Cu")
		(net "GMI_CPU0_G1_CPU1_G3_TX_DP<14>")
	)
	(segment
		(start 125.552708 -238.468916)
		(end 125.591824 -238.491776)
		(width 0.1143)
		(layer "In15.Cu")
		(net "GMI_CPU0_G1_CPU1_G3_TX_DP<14>")
	)
	(segment
		(start 303.734724 -190.109856)
		(end 262.742426 -189.73165)
		(width 0.14224)
		(layer "In15.Cu")
		(net "GMI_CPU0_G1_CPU1_G3_TX_DP<14>")
	)
	(segment
		(start 125.232668 -244.484398)
		(end 124.934726 -244.484398)
		(width 0.1143)
		(layer "In15.Cu")
		(net "GMI_CPU0_G1_CPU1_G3_TX_DP<14>")
	)
	(segment
		(start 345.90355 -236.871764)
		(end 345.924886 -236.859318)
		(width 0.1143)
		(layer "In15.Cu")
		(net "GMI_CPU0_G1_CPU1_G3_TX_DP<14>")
	)
	(segment
		(start 345.90863 -235.899198)
		(end 345.907106 -235.898436)
		(width 0.1143)
		(layer "In15.Cu")
		(net "GMI_CPU0_G1_CPU1_G3_TX_DP<14>")
	)
	(segment
		(start 125.591824 -241.7318)
		(end 125.622304 -241.74958)
		(width 0.1143)
		(layer "In15.Cu")
		(net "GMI_CPU0_G1_CPU1_G3_TX_DP<14>")
	)
	(segment
		(start 345.904058 -232.656634)
		(end 345.903296 -232.656126)
		(width 0.1143)
		(layer "In15.Cu")
		(net "GMI_CPU0_G1_CPU1_G3_TX_DP<14>")
	)
	(segment
		(start 125.591824 -236.871764)
		(end 125.622304 -236.889544)
		(width 0.1143)
		(layer "In15.Cu")
		(net "GMI_CPU0_G1_CPU1_G3_TX_DP<14>")
	)
	(segment
		(start 345.942412 -242.399058)
		(end 345.910408 -242.380262)
		(width 0.1143)
		(layer "In15.Cu")
		(net "GMI_CPU0_G1_CPU1_G3_TX_DP<14>")
	)
	(segment
		(start 345.43746 -225.368866)
		(end 345.435936 -225.36785)
		(width 0.1143)
		(layer "In15.Cu")
		(net "GMI_CPU0_G1_CPU1_G3_TX_DP<14>")
	)
	(segment
		(start 344.494104 -222.12681)
		(end 344.493342 -222.126302)
		(width 0.1143)
		(layer "In15.Cu")
		(net "GMI_CPU0_G1_CPU1_G3_TX_DP<14>")
	)
	(segment
		(start 125.591824 -243.996972)
		(end 125.552708 -244.019832)
		(width 0.1143)
		(layer "In15.Cu")
		(net "GMI_CPU0_G1_CPU1_G3_TX_DP<14>")
	)
	(segment
		(start 345.905074 -232.010966)
		(end 345.906598 -232.00995)
		(width 0.1143)
		(layer "In15.Cu")
		(net "GMI_CPU0_G1_CPU1_G3_TX_DP<14>")
	)
	(segment
		(start 345.936316 -244.015514)
		(end 345.935554 -244.015006)
		(width 0.1143)
		(layer "In15.Cu")
		(net "GMI_CPU0_G1_CPU1_G3_TX_DP<14>")
	)
	(segment
		(start 125.622304 -235.879132)
		(end 125.591824 -235.896912)
		(width 0.1143)
		(layer "In15.Cu")
		(net "GMI_CPU0_G1_CPU1_G3_TX_DP<14>")
	)
	(segment
		(start 125.591824 -227.151946)
		(end 125.622304 -227.169726)
		(width 0.1143)
		(layer "In15.Cu")
		(net "GMI_CPU0_G1_CPU1_G3_TX_DP<14>")
	)
	(segment
		(start 125.263656 -221.203012)
		(end 125.309376 -221.248732)
		(width 0.1143)
		(layer "In15.Cu")
		(net "GMI_CPU0_G1_CPU1_G3_TX_DP<14>")
	)
	(segment
		(start 125.591824 -240.756948)
		(end 125.552708 -240.779808)
		(width 0.1143)
		(layer "In15.Cu")
		(net "GMI_CPU0_G1_CPU1_G3_TX_DP<14>")
	)
	(segment
		(start 308.735476 -190.109856)
		(end 303.734724 -190.109856)
		(width 0.14224)
		(layer "In15.Cu")
		(net "GMI_CPU0_G1_CPU1_G3_TX_DP<14>")
	)
	(segment
		(start 125.591824 -229.416864)
		(end 125.55474 -229.4382)
		(width 0.1143)
		(layer "In15.Cu")
		(net "GMI_CPU0_G1_CPU1_G3_TX_DP<14>")
	)
	(segment
		(start 344.29192 -221.083124)
		(end 344.29192 -220.486732)
		(width 0.14224)
		(layer "In15.Cu")
		(net "GMI_CPU0_G1_CPU1_G3_TX_DP<14>")
	)
	(segment
		(start 345.902026 -230.392986)
		(end 345.903296 -230.392224)
		(width 0.1143)
		(layer "In15.Cu")
		(net "GMI_CPU0_G1_CPU1_G3_TX_DP<14>")
	)
	(segment
		(start 345.903296 -232.011982)
		(end 345.904058 -232.011474)
		(width 0.1143)
		(layer "In15.Cu")
		(net "GMI_CPU0_G1_CPU1_G3_TX_DP<14>")
	)
	(segment
		(start 236.351064 -200.4187)
		(end 233.086148 -199.843136)
		(width 0.14224)
		(layer "In15.Cu")
		(net "GMI_CPU0_G1_CPU1_G3_TX_DP<14>")
	)
	(segment
		(start 345.00312 -224.579688)
		(end 344.964004 -224.556828)
		(width 0.1143)
		(layer "In15.Cu")
		(net "GMI_CPU0_G1_CPU1_G3_TX_DP<14>")
	)
	(segment
		(start 345.902788 -228.772466)
		(end 345.903296 -228.772212)
		(width 0.1143)
		(layer "In15.Cu")
		(net "GMI_CPU0_G1_CPU1_G3_TX_DP<14>")
	)
	(segment
		(start 345.92514 -235.239306)
		(end 345.943174 -235.228638)
		(width 0.1143)
		(layer "In15.Cu")
		(net "GMI_CPU0_G1_CPU1_G3_TX_DP<14>")
	)
	(segment
		(start 345.910408 -240.76025)
		(end 345.909392 -240.759742)
		(width 0.1143)
		(layer "In15.Cu")
		(net "GMI_CPU0_G1_CPU1_G3_TX_DP<14>")
	)
	(segment
		(start 125.622304 -226.159314)
		(end 125.591824 -226.177094)
		(width 0.1143)
		(layer "In15.Cu")
		(net "GMI_CPU0_G1_CPU1_G3_TX_DP<14>")
	)
	(segment
		(start 345.935554 -244.015006)
		(end 345.904058 -243.996718)
		(width 0.1143)
		(layer "In15.Cu")
		(net "GMI_CPU0_G1_CPU1_G3_TX_DP<14>")
	)
	(segment
		(start 125.591824 -222.93707)
		(end 125.552708 -222.95993)
		(width 0.1143)
		(layer "In15.Cu")
		(net "GMI_CPU0_G1_CPU1_G3_TX_DP<14>")
	)
	(segment
		(start 345.943174 -231.059482)
		(end 345.893898 -231.03078)
		(width 0.1143)
		(layer "In15.Cu")
		(net "GMI_CPU0_G1_CPU1_G3_TX_DP<14>")
	)
	(segment
		(start 344.306398 -221.80423)
		(end 344.306398 -221.368874)
		(width 0.1143)
		(layer "In15.Cu")
		(net "GMI_CPU0_G1_CPU1_G3_TX_DP<14>")
	)
	(segment
		(start 345.910408 -242.380262)
		(end 345.909392 -242.379754)
		(width 0.1143)
		(layer "In15.Cu")
		(net "GMI_CPU0_G1_CPU1_G3_TX_DP<14>")
	)
	(segment
		(start 345.90863 -240.759234)
		(end 345.896184 -240.752122)
		(width 0.1143)
		(layer "In15.Cu")
		(net "GMI_CPU0_G1_CPU1_G3_TX_DP<14>")
	)
	(segment
		(start 125.622304 -239.119156)
		(end 125.591824 -239.136936)
		(width 0.1143)
		(layer "In15.Cu")
		(net "GMI_CPU0_G1_CPU1_G3_TX_DP<14>")
	)
	(segment
		(start 153.970228 -197.544944)
		(end 149.344634 -201.33691)
		(width 0.14224)
		(layer "In15.Cu")
		(net "GMI_CPU0_G1_CPU1_G3_TX_DP<14>")
	)
	(segment
		(start 345.909392 -242.379754)
		(end 345.90863 -242.379246)
		(width 0.1143)
		(layer "In15.Cu")
		(net "GMI_CPU0_G1_CPU1_G3_TX_DP<14>")
	)
	(segment
		(start 345.936062 -235.9152)
		(end 345.9353 -235.914692)
		(width 0.1143)
		(layer "In15.Cu")
		(net "GMI_CPU0_G1_CPU1_G3_TX_DP<14>")
	)
	(arc
		(start 125.319282 -244.378734)
		(mid 125.317259 -244.390144)
		(end 125.315472 -244.401594)
		(width 0.1143)
		(layer "In15.Cu")
		(net "GMI_CPU0_G1_CPU1_G3_TX_DP<14>")
	)
	(arc
		(start 125.622304 -230.40975)
		(mid 125.737731 -230.543126)
		(end 125.779276 -230.71455)
		(width 0.1143)
		(layer "In15.Cu")
		(net "GMI_CPU0_G1_CPU1_G3_TX_DP<14>")
	)
	(arc
		(start 346.1766 -244.37848)
		(mid 346.095167 -244.176082)
		(end 345.943174 -244.019578)
		(width 0.1143)
		(layer "In15.Cu")
		(net "GMI_CPU0_G1_CPU1_G3_TX_DP<14>")
	)
	(arc
		(start 125.552708 -244.019832)
		(mid 125.400721 -244.17634)
		(end 125.319282 -244.378734)
		(width 0.1143)
		(layer "In15.Cu")
		(net "GMI_CPU0_G1_CPU1_G3_TX_DP<14>")
	)
	(arc
		(start 125.62332 -222.310198)
		(mid 125.737996 -222.443532)
		(end 125.779276 -222.61449)
		(width 0.1143)
		(layer "In15.Cu")
		(net "GMI_CPU0_G1_CPU1_G3_TX_DP<14>")
	)
	(arc
		(start 125.622304 -225.549714)
		(mid 125.779281 -225.854514)
		(end 125.622304 -226.159314)
		(width 0.1143)
		(layer "In15.Cu")
		(net "GMI_CPU0_G1_CPU1_G3_TX_DP<14>")
	)
	(arc
		(start 125.622304 -235.269532)
		(mid 125.779281 -235.574332)
		(end 125.622304 -235.879132)
		(width 0.1143)
		(layer "In15.Cu")
		(net "GMI_CPU0_G1_CPU1_G3_TX_DP<14>")
	)
	(arc
		(start 345.943174 -241.708686)
		(mid 346.186501 -241.24412)
		(end 345.943174 -240.779554)
		(width 0.1143)
		(layer "In15.Cu")
		(net "GMI_CPU0_G1_CPU1_G3_TX_DP<14>")
	)
	(arc
		(start 125.622304 -223.929702)
		(mid 125.779281 -224.234502)
		(end 125.622304 -224.539302)
		(width 0.1143)
		(layer "In15.Cu")
		(net "GMI_CPU0_G1_CPU1_G3_TX_DP<14>")
	)
	(arc
		(start 345.943174 -231.988614)
		(mid 346.186501 -231.524048)
		(end 345.943174 -231.059482)
		(width 0.1143)
		(layer "In15.Cu")
		(net "GMI_CPU0_G1_CPU1_G3_TX_DP<14>")
	)
	(arc
		(start 125.622304 -227.169726)
		(mid 125.779281 -227.474526)
		(end 125.622304 -227.779326)
		(width 0.1143)
		(layer "In15.Cu")
		(net "GMI_CPU0_G1_CPU1_G3_TX_DP<14>")
	)
	(arc
		(start 345.943174 -239.159542)
		(mid 345.942793 -239.159288)
		(end 345.942412 -239.159034)
		(width 0.1143)
		(layer "In15.Cu")
		(net "GMI_CPU0_G1_CPU1_G3_TX_DP<14>")
	)
	(arc
		(start 125.552708 -232.679748)
		(mid 125.309381 -233.144314)
		(end 125.552708 -233.60888)
		(width 0.1143)
		(layer "In15.Cu")
		(net "GMI_CPU0_G1_CPU1_G3_TX_DP<14>")
	)
	(arc
		(start 125.552708 -235.919772)
		(mid 125.309381 -236.384338)
		(end 125.552708 -236.848904)
		(width 0.1143)
		(layer "In15.Cu")
		(net "GMI_CPU0_G1_CPU1_G3_TX_DP<14>")
	)
	(arc
		(start 125.552708 -229.439724)
		(mid 125.373895 -229.642074)
		(end 125.309376 -229.90429)
		(width 0.1143)
		(layer "In15.Cu")
		(net "GMI_CPU0_G1_CPU1_G3_TX_DP<14>")
	)
	(arc
		(start 345.716352 -225.865436)
		(mid 345.713973 -225.827933)
		(end 345.708478 -225.79076)
		(width 0.1143)
		(layer "In15.Cu")
		(net "GMI_CPU0_G1_CPU1_G3_TX_DP<14>")
	)
	(arc
		(start 345.943174 -227.128832)
		(mid 346.186501 -226.664266)
		(end 345.943174 -226.1997)
		(width 0.1143)
		(layer "In15.Cu")
		(net "GMI_CPU0_G1_CPU1_G3_TX_DP<14>")
	)
	(arc
		(start 344.933524 -224.539048)
		(mid 344.776547 -224.234248)
		(end 344.933524 -223.929448)
		(width 0.1143)
		(layer "In15.Cu")
		(net "GMI_CPU0_G1_CPU1_G3_TX_DP<14>")
	)
	(arc
		(start 345.872308 -234.258358)
		(mid 345.720719 -233.954066)
		(end 345.872308 -233.649774)
		(width 0.1143)
		(layer "In15.Cu")
		(net "GMI_CPU0_G1_CPU1_G3_TX_DP<14>")
	)
	(arc
		(start 345.943174 -240.779554)
		(mid 345.942793 -240.7793)
		(end 345.942412 -240.779046)
		(width 0.1143)
		(layer "In15.Cu")
		(net "GMI_CPU0_G1_CPU1_G3_TX_DP<14>")
	)
	(arc
		(start 125.552708 -226.199954)
		(mid 125.309381 -226.66452)
		(end 125.552708 -227.129086)
		(width 0.1143)
		(layer "In15.Cu")
		(net "GMI_CPU0_G1_CPU1_G3_TX_DP<14>")
	)
	(arc
		(start 344.776552 -222.614236)
		(mid 344.712037 -222.352017)
		(end 344.53322 -222.14967)
		(width 0.1143)
		(layer "In15.Cu")
		(net "GMI_CPU0_G1_CPU1_G3_TX_DP<14>")
	)
	(arc
		(start 125.552708 -227.819966)
		(mid 125.309381 -228.284532)
		(end 125.552708 -228.749098)
		(width 0.1143)
		(layer "In15.Cu")
		(net "GMI_CPU0_G1_CPU1_G3_TX_DP<14>")
	)
	(arc
		(start 345.716352 -229.094284)
		(mid 345.766317 -228.908308)
		(end 345.902788 -228.772466)
		(width 0.1143)
		(layer "In15.Cu")
		(net "GMI_CPU0_G1_CPU1_G3_TX_DP<14>")
	)
	(arc
		(start 125.552708 -240.779808)
		(mid 125.309381 -241.244374)
		(end 125.552708 -241.70894)
		(width 0.1143)
		(layer "In15.Cu")
		(net "GMI_CPU0_G1_CPU1_G3_TX_DP<14>")
	)
	(arc
		(start 125.622304 -232.029508)
		(mid 125.779281 -232.334308)
		(end 125.622304 -232.639108)
		(width 0.1143)
		(layer "In15.Cu")
		(net "GMI_CPU0_G1_CPU1_G3_TX_DP<14>")
	)
	(arc
		(start 125.779276 -222.61449)
		(mid 125.737727 -222.785912)
		(end 125.622304 -222.91929)
		(width 0.1143)
		(layer "In15.Cu")
		(net "GMI_CPU0_G1_CPU1_G3_TX_DP<14>")
	)
	(arc
		(start 345.943174 -238.468662)
		(mid 346.186501 -238.004096)
		(end 345.943174 -237.53953)
		(width 0.1143)
		(layer "In15.Cu")
		(net "GMI_CPU0_G1_CPU1_G3_TX_DP<14>")
	)
	(arc
		(start 346.18041 -244.40134)
		(mid 346.178622 -244.389891)
		(end 346.1766 -244.37848)
		(width 0.1143)
		(layer "In15.Cu")
		(net "GMI_CPU0_G1_CPU1_G3_TX_DP<14>")
	)
	(arc
		(start 345.00312 -223.888808)
		(mid 345.246447 -223.424242)
		(end 345.00312 -222.959676)
		(width 0.1143)
		(layer "In15.Cu")
		(net "GMI_CPU0_G1_CPU1_G3_TX_DP<14>")
	)
	(arc
		(start 125.309376 -229.90429)
		(mid 125.374612 -230.167881)
		(end 125.555248 -230.370634)
		(width 0.1143)
		(layer "In15.Cu")
		(net "GMI_CPU0_G1_CPU1_G3_TX_DP<14>")
	)
	(arc
		(start 125.552708 -242.39982)
		(mid 125.309381 -242.864386)
		(end 125.552708 -243.328952)
		(width 0.1143)
		(layer "In15.Cu")
		(net "GMI_CPU0_G1_CPU1_G3_TX_DP<14>")
	)
	(arc
		(start 345.893898 -231.03078)
		(mid 345.761995 -230.896727)
		(end 345.716352 -230.714296)
		(width 0.1143)
		(layer "In15.Cu")
		(net "GMI_CPU0_G1_CPU1_G3_TX_DP<14>")
	)
	(arc
		(start 345.943174 -236.84865)
		(mid 346.186501 -236.384084)
		(end 345.943174 -235.919518)
		(width 0.1143)
		(layer "In15.Cu")
		(net "GMI_CPU0_G1_CPU1_G3_TX_DP<14>")
	)
	(arc
		(start 345.872308 -243.97843)
		(mid 345.723211 -243.674138)
		(end 345.872308 -243.369846)
		(width 0.1143)
		(layer "In15.Cu")
		(net "GMI_CPU0_G1_CPU1_G3_TX_DP<14>")
	)
	(arc
		(start 345.87053 -229.397052)
		(mid 345.757123 -229.264163)
		(end 345.716352 -229.094284)
		(width 0.1143)
		(layer "In15.Cu")
		(net "GMI_CPU0_G1_CPU1_G3_TX_DP<14>")
	)
	(arc
		(start 345.943174 -233.608626)
		(mid 346.186501 -233.14406)
		(end 345.943174 -232.679494)
		(width 0.1143)
		(layer "In15.Cu")
		(net "GMI_CPU0_G1_CPU1_G3_TX_DP<14>")
	)
	(arc
		(start 125.779276 -229.094538)
		(mid 125.73831 -229.264944)
		(end 125.624336 -229.398068)
		(width 0.1143)
		(layer "In15.Cu")
		(net "GMI_CPU0_G1_CPU1_G3_TX_DP<14>")
	)
	(arc
		(start 345.501976 -225.412554)
		(mid 345.486444 -225.399959)
		(end 345.47048 -225.387916)
		(width 0.1143)
		(layer "In15.Cu")
		(net "GMI_CPU0_G1_CPU1_G3_TX_DP<14>")
	)
	(arc
		(start 345.716352 -230.714296)
		(mid 345.759217 -230.544144)
		(end 345.872308 -230.410004)
		(width 0.1143)
		(layer "In15.Cu")
		(net "GMI_CPU0_G1_CPU1_G3_TX_DP<14>")
	)
	(arc
		(start 345.943174 -242.399566)
		(mid 345.942793 -242.399312)
		(end 345.942412 -242.399058)
		(width 0.1143)
		(layer "In15.Cu")
		(net "GMI_CPU0_G1_CPU1_G3_TX_DP<14>")
	)
	(arc
		(start 125.622304 -240.129568)
		(mid 125.779281 -240.434368)
		(end 125.622304 -240.739168)
		(width 0.1143)
		(layer "In15.Cu")
		(net "GMI_CPU0_G1_CPU1_G3_TX_DP<14>")
	)
	(arc
		(start 345.943174 -234.299506)
		(mid 345.942793 -234.299252)
		(end 345.942412 -234.298998)
		(width 0.1143)
		(layer "In15.Cu")
		(net "GMI_CPU0_G1_CPU1_G3_TX_DP<14>")
	)
	(arc
		(start 345.873324 -226.15906)
		(mid 345.760477 -226.030627)
		(end 345.716352 -225.865436)
		(width 0.1143)
		(layer "In15.Cu")
		(net "GMI_CPU0_G1_CPU1_G3_TX_DP<14>")
	)
	(arc
		(start 344.933524 -222.919036)
		(mid 344.818097 -222.78566)
		(end 344.776552 -222.614236)
		(width 0.1143)
		(layer "In15.Cu")
		(net "GMI_CPU0_G1_CPU1_G3_TX_DP<14>")
	)
	(arc
		(start 345.896184 -239.13211)
		(mid 345.717967 -238.809833)
		(end 345.90355 -238.491776)
		(width 0.1143)
		(layer "In15.Cu")
		(net "GMI_CPU0_G1_CPU1_G3_TX_DP<14>")
	)
	(arc
		(start 345.872308 -232.638346)
		(mid 345.723211 -232.334054)
		(end 345.872308 -232.029762)
		(width 0.1143)
		(layer "In15.Cu")
		(net "GMI_CPU0_G1_CPU1_G3_TX_DP<14>")
	)
	(arc
		(start 345.402408 -225.348546)
		(mid 345.287732 -225.215212)
		(end 345.246452 -225.044254)
		(width 0.1143)
		(layer "In15.Cu")
		(net "GMI_CPU0_G1_CPU1_G3_TX_DP<14>")
	)
	(arc
		(start 125.552708 -234.29976)
		(mid 125.309381 -234.764326)
		(end 125.552708 -235.228892)
		(width 0.1143)
		(layer "In15.Cu")
		(net "GMI_CPU0_G1_CPU1_G3_TX_DP<14>")
	)
	(arc
		(start 125.552708 -222.95993)
		(mid 125.309381 -223.424496)
		(end 125.552708 -223.889062)
		(width 0.1143)
		(layer "In15.Cu")
		(net "GMI_CPU0_G1_CPU1_G3_TX_DP<14>")
	)
	(arc
		(start 345.940634 -230.37038)
		(mid 346.121286 -230.167635)
		(end 346.186506 -229.904036)
		(width 0.1143)
		(layer "In15.Cu")
		(net "GMI_CPU0_G1_CPU1_G3_TX_DP<14>")
	)
	(arc
		(start 345.943174 -235.228638)
		(mid 346.186501 -234.764072)
		(end 345.943174 -234.299506)
		(width 0.1143)
		(layer "In15.Cu")
		(net "GMI_CPU0_G1_CPU1_G3_TX_DP<14>")
	)
	(arc
		(start 345.896184 -235.892086)
		(mid 345.717967 -235.569809)
		(end 345.90355 -235.251752)
		(width 0.1143)
		(layer "In15.Cu")
		(net "GMI_CPU0_G1_CPU1_G3_TX_DP<14>")
	)
	(arc
		(start 345.708478 -225.79076)
		(mid 345.63436 -225.585754)
		(end 345.501976 -225.412554)
		(width 0.1143)
		(layer "In15.Cu")
		(net "GMI_CPU0_G1_CPU1_G3_TX_DP<14>")
	)
	(arc
		(start 125.309122 -221.804484)
		(mid 125.373781 -222.067041)
		(end 125.552962 -222.269558)
		(width 0.1143)
		(layer "In15.Cu")
		(net "GMI_CPU0_G1_CPU1_G3_TX_DP<14>")
	)
	(arc
		(start 125.552708 -239.159796)
		(mid 125.309381 -239.624362)
		(end 125.552708 -240.088928)
		(width 0.1143)
		(layer "In15.Cu")
		(net "GMI_CPU0_G1_CPU1_G3_TX_DP<14>")
	)
	(arc
		(start 125.552962 -222.269558)
		(mid 125.553343 -222.269812)
		(end 125.553724 -222.270066)
		(width 0.1143)
		(layer "In15.Cu")
		(net "GMI_CPU0_G1_CPU1_G3_TX_DP<14>")
	)
	(arc
		(start 345.943174 -228.748844)
		(mid 346.186501 -228.284278)
		(end 345.943174 -227.819712)
		(width 0.1143)
		(layer "In15.Cu")
		(net "GMI_CPU0_G1_CPU1_G3_TX_DP<14>")
	)
	(arc
		(start 125.622304 -243.369592)
		(mid 125.779281 -243.674392)
		(end 125.622304 -243.979192)
		(width 0.1143)
		(layer "In15.Cu")
		(net "GMI_CPU0_G1_CPU1_G3_TX_DP<14>")
	)
	(arc
		(start 345.896184 -242.372134)
		(mid 345.717967 -242.049857)
		(end 345.90355 -241.7318)
		(width 0.1143)
		(layer "In15.Cu")
		(net "GMI_CPU0_G1_CPU1_G3_TX_DP<14>")
	)
	(arc
		(start 125.552708 -237.539784)
		(mid 125.309381 -238.00435)
		(end 125.552708 -238.468916)
		(width 0.1143)
		(layer "In15.Cu")
		(net "GMI_CPU0_G1_CPU1_G3_TX_DP<14>")
	)
	(arc
		(start 125.552708 -224.579942)
		(mid 125.309381 -225.044508)
		(end 125.552708 -225.509074)
		(width 0.1143)
		(layer "In15.Cu")
		(net "GMI_CPU0_G1_CPU1_G3_TX_DP<14>")
	)
	(arc
		(start 125.622304 -236.889544)
		(mid 125.779281 -237.194344)
		(end 125.622304 -237.499144)
		(width 0.1143)
		(layer "In15.Cu")
		(net "GMI_CPU0_G1_CPU1_G3_TX_DP<14>")
	)
	(arc
		(start 346.186506 -229.904036)
		(mid 346.121991 -229.641817)
		(end 345.943174 -229.43947)
		(width 0.1143)
		(layer "In15.Cu")
		(net "GMI_CPU0_G1_CPU1_G3_TX_DP<14>")
	)
	(arc
		(start 344.462354 -222.108522)
		(mid 344.347678 -221.975188)
		(end 344.306398 -221.80423)
		(width 0.1143)
		(layer "In15.Cu")
		(net "GMI_CPU0_G1_CPU1_G3_TX_DP<14>")
	)
	(arc
		(start 345.943174 -237.53953)
		(mid 345.942793 -237.539276)
		(end 345.942412 -237.539022)
		(width 0.1143)
		(layer "In15.Cu")
		(net "GMI_CPU0_G1_CPU1_G3_TX_DP<14>")
	)
	(arc
		(start 345.943174 -243.328698)
		(mid 346.186501 -242.864132)
		(end 345.943174 -242.399566)
		(width 0.1143)
		(layer "In15.Cu")
		(net "GMI_CPU0_G1_CPU1_G3_TX_DP<14>")
	)
	(arc
		(start 125.622304 -228.789738)
		(mid 125.737731 -228.923114)
		(end 125.779276 -229.094538)
		(width 0.1143)
		(layer "In15.Cu")
		(net "GMI_CPU0_G1_CPU1_G3_TX_DP<14>")
	)
	(arc
		(start 345.872308 -227.778564)
		(mid 345.723211 -227.474272)
		(end 345.872308 -227.16998)
		(width 0.1143)
		(layer "In15.Cu")
		(net "GMI_CPU0_G1_CPU1_G3_TX_DP<14>")
	)
	(arc
		(start 125.622304 -238.509556)
		(mid 125.779281 -238.814356)
		(end 125.622304 -239.119156)
		(width 0.1143)
		(layer "In15.Cu")
		(net "GMI_CPU0_G1_CPU1_G3_TX_DP<14>")
	)
	(arc
		(start 345.896184 -237.512098)
		(mid 345.717967 -237.189821)
		(end 345.90355 -236.871764)
		(width 0.1143)
		(layer "In15.Cu")
		(net "GMI_CPU0_G1_CPU1_G3_TX_DP<14>")
	)
	(arc
		(start 345.896184 -240.752122)
		(mid 345.717967 -240.429845)
		(end 345.90355 -240.111788)
		(width 0.1143)
		(layer "In15.Cu")
		(net "GMI_CPU0_G1_CPU1_G3_TX_DP<14>")
	)
	(arc
		(start 125.622304 -241.74958)
		(mid 125.779281 -242.05438)
		(end 125.622304 -242.35918)
		(width 0.1143)
		(layer "In15.Cu")
		(net "GMI_CPU0_G1_CPU1_G3_TX_DP<14>")
	)
	(arc
		(start 345.246452 -225.044254)
		(mid 345.181937 -224.782035)
		(end 345.00312 -224.579688)
		(width 0.1143)
		(layer "In15.Cu")
		(net "GMI_CPU0_G1_CPU1_G3_TX_DP<14>")
	)
	(arc
		(start 345.943174 -235.919518)
		(mid 345.942793 -235.919264)
		(end 345.942412 -235.91901)
		(width 0.1143)
		(layer "In15.Cu")
		(net "GMI_CPU0_G1_CPU1_G3_TX_DP<14>")
	)
	(arc
		(start 345.943174 -240.088674)
		(mid 346.186501 -239.624108)
		(end 345.943174 -239.159542)
		(width 0.1143)
		(layer "In15.Cu")
		(net "GMI_CPU0_G1_CPU1_G3_TX_DP<14>")
	)
	(arc
		(start 125.779276 -230.71455)
		(mid 125.73831 -230.884956)
		(end 125.624336 -231.01808)
		(width 0.1143)
		(layer "In15.Cu")
		(net "GMI_CPU0_G1_CPU1_G3_TX_DP<14>")
	)
	(arc
		(start 125.552708 -231.059736)
		(mid 125.309381 -231.524302)
		(end 125.552708 -231.988868)
		(width 0.1143)
		(layer "In15.Cu")
		(net "GMI_CPU0_G1_CPU1_G3_TX_DP<14>")
	)
	(arc
		(start 125.622304 -233.64952)
		(mid 125.779281 -233.95432)
		(end 125.622304 -234.25912)
		(width 0.1143)
		(layer "In15.Cu")
		(net "GMI_CPU0_G1_CPU1_G3_TX_DP<14>")
	)
	(segment
		(start 347.028008 -247.990106)
		(end 346.561156 -247.724168)
		(width 0.12954)
		(layer "F.Cu")
		(net "GMI_CPU0_G1_CPU1_G3_TX_DP<13>")
	)
	(segment
		(start 124.467874 -247.99036)
		(end 124.934726 -247.724422)
		(width 0.12954)
		(layer "F.Cu")
		(net "GMI_CPU0_G1_CPU1_G3_TX_DP<13>")
	)
	(segment
		(start 345.904058 -222.936816)
		(end 345.903296 -222.936308)
		(width 0.1143)
		(layer "In15.Cu")
		(net "GMI_CPU0_G1_CPU1_G3_TX_DP<13>")
	)
	(segment
		(start 124.650754 -223.911414)
		(end 124.65177 -223.911922)
		(width 0.1143)
		(layer "In15.Cu")
		(net "GMI_CPU0_G1_CPU1_G3_TX_DP<13>")
	)
	(segment
		(start 124.619512 -244.953028)
		(end 124.620274 -244.953536)
		(width 0.1143)
		(layer "In15.Cu")
		(net "GMI_CPU0_G1_CPU1_G3_TX_DP<13>")
	)
	(segment
		(start 124.65177 -241.7318)
		(end 124.652532 -241.732308)
		(width 0.1143)
		(layer "In15.Cu")
		(net "GMI_CPU0_G1_CPU1_G3_TX_DP<13>")
	)
	(segment
		(start 345.904058 -223.911668)
		(end 345.905074 -223.91116)
		(width 0.1143)
		(layer "In15.Cu")
		(net "GMI_CPU0_G1_CPU1_G3_TX_DP<13>")
	)
	(segment
		(start 124.613924 -222.270066)
		(end 124.68352 -222.310198)
		(width 0.1143)
		(layer "In15.Cu")
		(net "GMI_CPU0_G1_CPU1_G3_TX_DP<13>")
	)
	(segment
		(start 346.844112 -231.036622)
		(end 346.810584 -231.017064)
		(width 0.1143)
		(layer "In15.Cu")
		(net "GMI_CPU0_G1_CPU1_G3_TX_DP<13>")
	)
	(segment
		(start 124.647452 -246.589296)
		(end 124.648976 -246.590312)
		(width 0.1143)
		(layer "In15.Cu")
		(net "GMI_CPU0_G1_CPU1_G3_TX_DP<13>")
	)
	(segment
		(start 346.84208 -240.755424)
		(end 346.812362 -240.738406)
		(width 0.1143)
		(layer "In15.Cu")
		(net "GMI_CPU0_G1_CPU1_G3_TX_DP<13>")
	)
	(segment
		(start 124.65177 -232.011728)
		(end 124.652532 -232.012236)
		(width 0.1143)
		(layer "In15.Cu")
		(net "GMI_CPU0_G1_CPU1_G3_TX_DP<13>")
	)
	(segment
		(start 345.936062 -223.893126)
		(end 345.936824 -223.892618)
		(width 0.1143)
		(layer "In15.Cu")
		(net "GMI_CPU0_G1_CPU1_G3_TX_DP<13>")
	)
	(segment
		(start 346.87637 -227.815648)
		(end 346.875608 -227.81514)
		(width 0.1143)
		(layer "In15.Cu")
		(net "GMI_CPU0_G1_CPU1_G3_TX_DP<13>")
	)
	(segment
		(start 346.812362 -243.369846)
		(end 346.84335 -243.352066)
		(width 0.1143)
		(layer "In15.Cu")
		(net "GMI_CPU0_G1_CPU1_G3_TX_DP<13>")
	)
	(segment
		(start 124.68352 -223.93021)
		(end 124.703332 -223.944434)
		(width 0.1143)
		(layer "In15.Cu")
		(net "GMI_CPU0_G1_CPU1_G3_TX_DP<13>")
	)
	(segment
		(start 239.428274 -198.921624)
		(end 236.351826 -199.463914)
		(width 0.14224)
		(layer "In15.Cu")
		(net "GMI_CPU0_G1_CPU1_G3_TX_DP<13>")
	)
	(segment
		(start 346.84335 -234.276138)
		(end 346.84208 -234.275376)
		(width 0.1143)
		(layer "In15.Cu")
		(net "GMI_CPU0_G1_CPU1_G3_TX_DP<13>")
	)
	(segment
		(start 346.883228 -242.399566)
		(end 346.845128 -242.377214)
		(width 0.1143)
		(layer "In15.Cu")
		(net "GMI_CPU0_G1_CPU1_G3_TX_DP<13>")
	)
	(segment
		(start 124.650754 -227.797614)
		(end 124.64923 -227.79863)
		(width 0.1143)
		(layer "In15.Cu")
		(net "GMI_CPU0_G1_CPU1_G3_TX_DP<13>")
	)
	(segment
		(start 124.650754 -241.731292)
		(end 124.65177 -241.7318)
		(width 0.1143)
		(layer "In15.Cu")
		(net "GMI_CPU0_G1_CPU1_G3_TX_DP<13>")
	)
	(segment
		(start 345.906598 -223.910144)
		(end 345.907614 -223.909636)
		(width 0.1143)
		(layer "In15.Cu")
		(net "GMI_CPU0_G1_CPU1_G3_TX_DP<13>")
	)
	(segment
		(start 124.612654 -240.091468)
		(end 124.630434 -240.100612)
		(width 0.1143)
		(layer "In15.Cu")
		(net "GMI_CPU0_G1_CPU1_G3_TX_DP<13>")
	)
	(segment
		(start 124.652278 -240.756948)
		(end 124.65177 -240.757202)
		(width 0.1143)
		(layer "In15.Cu")
		(net "GMI_CPU0_G1_CPU1_G3_TX_DP<13>")
	)
	(segment
		(start 346.846652 -246.590058)
		(end 346.883228 -246.568722)
		(width 0.1143)
		(layer "In15.Cu")
		(net "GMI_CPU0_G1_CPU1_G3_TX_DP<13>")
	)
	(segment
		(start 124.852176 -246.922798)
		(end 124.852176 -246.934228)
		(width 0.1143)
		(layer "In15.Cu")
		(net "GMI_CPU0_G1_CPU1_G3_TX_DP<13>")
	)
	(segment
		(start 124.652532 -223.91243)
		(end 124.68352 -223.93021)
		(width 0.1143)
		(layer "In15.Cu")
		(net "GMI_CPU0_G1_CPU1_G3_TX_DP<13>")
	)
	(segment
		(start 124.64923 -243.998496)
		(end 124.612654 -244.019832)
		(width 0.1143)
		(layer "In15.Cu")
		(net "GMI_CPU0_G1_CPU1_G3_TX_DP<13>")
	)
	(segment
		(start 346.844112 -245.61673)
		(end 346.84335 -245.616222)
		(width 0.1143)
		(layer "In15.Cu")
		(net "GMI_CPU0_G1_CPU1_G3_TX_DP<13>")
	)
	(segment
		(start 124.65177 -242.37696)
		(end 124.650754 -242.377468)
		(width 0.1143)
		(layer "In15.Cu")
		(net "GMI_CPU0_G1_CPU1_G3_TX_DP<13>")
	)
	(segment
		(start 124.619512 -246.57304)
		(end 124.620274 -246.573548)
		(width 0.1143)
		(layer "In15.Cu")
		(net "GMI_CPU0_G1_CPU1_G3_TX_DP<13>")
	)
	(segment
		(start 124.613416 -235.229654)
		(end 124.643896 -235.24718)
		(width 0.1143)
		(layer "In15.Cu")
		(net "GMI_CPU0_G1_CPU1_G3_TX_DP<13>")
	)
	(segment
		(start 346.845128 -232.010966)
		(end 346.846652 -232.00995)
		(width 0.1143)
		(layer "In15.Cu")
		(net "GMI_CPU0_G1_CPU1_G3_TX_DP<13>")
	)
	(segment
		(start 124.650754 -243.351304)
		(end 124.65177 -243.351812)
		(width 0.1143)
		(layer "In15.Cu")
		(net "GMI_CPU0_G1_CPU1_G3_TX_DP<13>")
	)
	(segment
		(start 345.872308 -223.929956)
		(end 345.903296 -223.912176)
		(width 0.1143)
		(layer "In15.Cu")
		(net "GMI_CPU0_G1_CPU1_G3_TX_DP<13>")
	)
	(segment
		(start 346.84335 -243.99621)
		(end 346.84208 -243.995448)
		(width 0.1143)
		(layer "In15.Cu")
		(net "GMI_CPU0_G1_CPU1_G3_TX_DP<13>")
	)
	(segment
		(start 346.883228 -244.019578)
		(end 346.87637 -244.015514)
		(width 0.1143)
		(layer "In15.Cu")
		(net "GMI_CPU0_G1_CPU1_G3_TX_DP<13>")
	)
	(segment
		(start 124.646436 -238.488728)
		(end 124.647452 -238.489236)
		(width 0.1143)
		(layer "In15.Cu")
		(net "GMI_CPU0_G1_CPU1_G3_TX_DP<13>")
	)
	(segment
		(start 345.246452 -221.80423)
		(end 345.246452 -221.364048)
		(width 0.1143)
		(layer "In15.Cu")
		(net "GMI_CPU0_G1_CPU1_G3_TX_DP<13>")
	)
	(segment
		(start 124.641864 -236.86643)
		(end 124.652278 -236.871764)
		(width 0.1143)
		(layer "In15.Cu")
		(net "GMI_CPU0_G1_CPU1_G3_TX_DP<13>")
	)
	(segment
		(start 124.612654 -241.70894)
		(end 124.619512 -241.713004)
		(width 0.1143)
		(layer "In15.Cu")
		(net "GMI_CPU0_G1_CPU1_G3_TX_DP<13>")
	)
	(segment
		(start 346.84335 -233.631994)
		(end 346.844112 -233.631486)
		(width 0.1143)
		(layer "In15.Cu")
		(net "GMI_CPU0_G1_CPU1_G3_TX_DP<13>")
	)
	(segment
		(start 124.652532 -243.996464)
		(end 124.65177 -243.996972)
		(width 0.1143)
		(layer "In15.Cu")
		(net "GMI_CPU0_G1_CPU1_G3_TX_DP<13>")
	)
	(segment
		(start 124.646436 -232.00868)
		(end 124.647452 -232.009188)
		(width 0.1143)
		(layer "In15.Cu")
		(net "GMI_CPU0_G1_CPU1_G3_TX_DP<13>")
	)
	(segment
		(start 345.930982 -223.896174)
		(end 345.932506 -223.895158)
		(width 0.1143)
		(layer "In15.Cu")
		(net "GMI_CPU0_G1_CPU1_G3_TX_DP<13>")
	)
	(segment
		(start 124.612654 -235.229146)
		(end 124.613416 -235.229654)
		(width 0.1143)
		(layer "In15.Cu")
		(net "GMI_CPU0_G1_CPU1_G3_TX_DP<13>")
	)
	(segment
		(start 346.87637 -240.77549)
		(end 346.875608 -240.774982)
		(width 0.1143)
		(layer "In15.Cu")
		(net "GMI_CPU0_G1_CPU1_G3_TX_DP<13>")
	)
	(segment
		(start 124.650754 -235.89742)
		(end 124.612654 -235.919772)
		(width 0.1143)
		(layer "In15.Cu")
		(net "GMI_CPU0_G1_CPU1_G3_TX_DP<13>")
	)
	(segment
		(start 346.844112 -246.591582)
		(end 346.845128 -246.591074)
		(width 0.1143)
		(layer "In15.Cu")
		(net "GMI_CPU0_G1_CPU1_G3_TX_DP<13>")
	)
	(segment
		(start 124.68352 -227.170234)
		(end 124.691902 -227.17633)
		(width 0.1143)
		(layer "In15.Cu")
		(net "GMI_CPU0_G1_CPU1_G3_TX_DP<13>")
	)
	(segment
		(start 345.909646 -223.908366)
		(end 345.91244 -223.906842)
		(width 0.1143)
		(layer "In15.Cu")
		(net "GMI_CPU0_G1_CPU1_G3_TX_DP<13>")
	)
	(segment
		(start 124.612654 -240.088928)
		(end 124.612654 -240.091468)
		(width 0.1143)
		(layer "In15.Cu")
		(net "GMI_CPU0_G1_CPU1_G3_TX_DP<13>")
	)
	(segment
		(start 124.652532 -226.176586)
		(end 124.65177 -226.177094)
		(width 0.1143)
		(layer "In15.Cu")
		(net "GMI_CPU0_G1_CPU1_G3_TX_DP<13>")
	)
	(segment
		(start 346.844112 -232.656634)
		(end 346.84335 -232.656126)
		(width 0.1143)
		(layer "In15.Cu")
		(net "GMI_CPU0_G1_CPU1_G3_TX_DP<13>")
	)
	(segment
		(start 124.650754 -242.377468)
		(end 124.646182 -242.380262)
		(width 0.1143)
		(layer "In15.Cu")
		(net "GMI_CPU0_G1_CPU1_G3_TX_DP<13>")
	)
	(segment
		(start 345.908884 -223.908874)
		(end 345.909646 -223.908366)
		(width 0.1143)
		(layer "In15.Cu")
		(net "GMI_CPU0_G1_CPU1_G3_TX_DP<13>")
	)
	(segment
		(start 346.845128 -240.111026)
		(end 346.846652 -240.11001)
		(width 0.1143)
		(layer "In15.Cu")
		(net "GMI_CPU0_G1_CPU1_G3_TX_DP<13>")
	)
	(segment
		(start 262.665464 -188.790326)
		(end 250.944634 -190.857124)
		(width 0.14224)
		(layer "In15.Cu")
		(net "GMI_CPU0_G1_CPU1_G3_TX_DP<13>")
	)
	(segment
		(start 124.650754 -226.177602)
		(end 124.612654 -226.199954)
		(width 0.1143)
		(layer "In15.Cu")
		(net "GMI_CPU0_G1_CPU1_G3_TX_DP<13>")
	)
	(segment
		(start 346.883228 -240.779554)
		(end 346.87637 -240.77549)
		(width 0.1143)
		(layer "In15.Cu")
		(net "GMI_CPU0_G1_CPU1_G3_TX_DP<13>")
	)
	(segment
		(start 346.883228 -231.059482)
		(end 346.844112 -231.036622)
		(width 0.1143)
		(layer "In15.Cu")
		(net "GMI_CPU0_G1_CPU1_G3_TX_DP<13>")
	)
	(segment
		(start 160.633156 -190.526924)
		(end 160.47847 -190.815722)
		(width 0.14224)
		(layer "In15.Cu")
		(net "GMI_CPU0_G1_CPU1_G3_TX_DP<13>")
	)
	(segment
		(start 124.64923 -240.758472)
		(end 124.612654 -240.779808)
		(width 0.1143)
		(layer "In15.Cu")
		(net "GMI_CPU0_G1_CPU1_G3_TX_DP<13>")
	)
	(segment
		(start 124.650754 -222.937578)
		(end 124.64923 -222.938594)
		(width 0.1143)
		(layer "In15.Cu")
		(net "GMI_CPU0_G1_CPU1_G3_TX_DP<13>")
	)
	(segment
		(start 346.84335 -244.972078)
		(end 346.844112 -244.97157)
		(width 0.1143)
		(layer "In15.Cu")
		(net "GMI_CPU0_G1_CPU1_G3_TX_DP<13>")
	)
	(segment
		(start 124.65177 -232.656888)
		(end 124.650754 -232.657396)
		(width 0.1143)
		(layer "In15.Cu")
		(net "GMI_CPU0_G1_CPU1_G3_TX_DP<13>")
	)
	(segment
		(start 345.936824 -223.892618)
		(end 345.943174 -223.888808)
		(width 0.1143)
		(layer "In15.Cu")
		(net "GMI_CPU0_G1_CPU1_G3_TX_DP<13>")
	)
	(segment
		(start 346.875608 -239.15497)
		(end 346.844112 -239.136682)
		(width 0.1143)
		(layer "In15.Cu")
		(net "GMI_CPU0_G1_CPU1_G3_TX_DP<13>")
	)
	(segment
		(start 346.84208 -232.655364)
		(end 346.812362 -232.638346)
		(width 0.1143)
		(layer "In15.Cu")
		(net "GMI_CPU0_G1_CPU1_G3_TX_DP<13>")
	)
	(segment
		(start 346.846652 -233.629962)
		(end 346.883228 -233.608626)
		(width 0.1143)
		(layer "In15.Cu")
		(net "GMI_CPU0_G1_CPU1_G3_TX_DP<13>")
	)
	(segment
		(start 346.844112 -241.731546)
		(end 346.845128 -241.731038)
		(width 0.1143)
		(layer "In15.Cu")
		(net "GMI_CPU0_G1_CPU1_G3_TX_DP<13>")
	)
	(segment
		(start 250.944634 -190.857124)
		(end 239.428274 -198.921624)
		(width 0.14224)
		(layer "In15.Cu")
		(net "GMI_CPU0_G1_CPU1_G3_TX_DP<13>")
	)
	(segment
		(start 346.875608 -234.294934)
		(end 346.844112 -234.276646)
		(width 0.1143)
		(layer "In15.Cu")
		(net "GMI_CPU0_G1_CPU1_G3_TX_DP<13>")
	)
	(segment
		(start 346.87637 -239.155478)
		(end 346.875608 -239.15497)
		(width 0.1143)
		(layer "In15.Cu")
		(net "GMI_CPU0_G1_CPU1_G3_TX_DP<13>")
	)
	(segment
		(start 345.936316 -224.575624)
		(end 345.935554 -224.575116)
		(width 0.1143)
		(layer "In15.Cu")
		(net "GMI_CPU0_G1_CPU1_G3_TX_DP<13>")
	)
	(segment
		(start 124.644912 -243.347748)
		(end 124.646436 -243.348764)
		(width 0.1143)
		(layer "In15.Cu")
		(net "GMI_CPU0_G1_CPU1_G3_TX_DP<13>")
	)
	(segment
		(start 346.846652 -232.00995)
		(end 346.883228 -231.988614)
		(width 0.1143)
		(layer "In15.Cu")
		(net "GMI_CPU0_G1_CPU1_G3_TX_DP<13>")
	)
	(segment
		(start 124.323602 -221.174564)
		(end 124.323602 -221.203012)
		(width 0.1143)
		(layer "In15.Cu")
		(net "GMI_CPU0_G1_CPU1_G3_TX_DP<13>")
	)
	(segment
		(start 124.647452 -228.769418)
		(end 124.648976 -228.770434)
		(width 0.1143)
		(layer "In15.Cu")
		(net "GMI_CPU0_G1_CPU1_G3_TX_DP<13>")
	)
	(segment
		(start 124.68352 -238.510064)
		(end 124.697236 -238.51997)
		(width 0.1143)
		(layer "In15.Cu")
		(net "GMI_CPU0_G1_CPU1_G3_TX_DP<13>")
	)
	(segment
		(start 124.650754 -246.591328)
		(end 124.65177 -246.591836)
		(width 0.1143)
		(layer "In15.Cu")
		(net "GMI_CPU0_G1_CPU1_G3_TX_DP<13>")
	)
	(segment
		(start 124.68352 -242.358672)
		(end 124.652532 -242.376452)
		(width 0.1143)
		(layer "In15.Cu")
		(net "GMI_CPU0_G1_CPU1_G3_TX_DP<13>")
	)
	(segment
		(start 346.845128 -237.517178)
		(end 346.844112 -237.51667)
		(width 0.1143)
		(layer "In15.Cu")
		(net "GMI_CPU0_G1_CPU1_G3_TX_DP<13>")
	)
	(segment
		(start 345.246452 -221.364048)
		(end 345.19108 -221.308676)
		(width 0.1143)
		(layer "In15.Cu")
		(net "GMI_CPU0_G1_CPU1_G3_TX_DP<13>")
	)
	(segment
		(start 124.652532 -239.136428)
		(end 124.65177 -239.136936)
		(width 0.1143)
		(layer "In15.Cu")
		(net "GMI_CPU0_G1_CPU1_G3_TX_DP<13>")
	)
	(segment
		(start 124.612654 -227.129086)
		(end 124.619512 -227.13315)
		(width 0.1143)
		(layer "In15.Cu")
		(net "GMI_CPU0_G1_CPU1_G3_TX_DP<13>")
	)
	(segment
		(start 346.846652 -240.11001)
		(end 346.883228 -240.088674)
		(width 0.1143)
		(layer "In15.Cu")
		(net "GMI_CPU0_G1_CPU1_G3_TX_DP<13>")
	)
	(segment
		(start 124.644912 -225.52787)
		(end 124.646436 -225.528886)
		(width 0.1143)
		(layer "In15.Cu")
		(net "GMI_CPU0_G1_CPU1_G3_TX_DP<13>")
	)
	(segment
		(start 346.263214 -247.724168)
		(end 346.193364 -247.654318)
		(width 0.1143)
		(layer "In15.Cu")
		(net "GMI_CPU0_G1_CPU1_G3_TX_DP<13>")
	)
	(segment
		(start 346.84335 -239.136174)
		(end 346.84208 -239.135412)
		(width 0.1143)
		(layer "In15.Cu")
		(net "GMI_CPU0_G1_CPU1_G3_TX_DP<13>")
	)
	(segment
		(start 346.87637 -226.195636)
		(end 346.875608 -226.195128)
		(width 0.1143)
		(layer "In15.Cu")
		(net "GMI_CPU0_G1_CPU1_G3_TX_DP<13>")
	)
	(segment
		(start 124.697236 -239.108742)
		(end 124.68352 -239.118648)
		(width 0.1143)
		(layer "In15.Cu")
		(net "GMI_CPU0_G1_CPU1_G3_TX_DP<13>")
	)
	(segment
		(start 124.650754 -238.491268)
		(end 124.65177 -238.491776)
		(width 0.1143)
		(layer "In15.Cu")
		(net "GMI_CPU0_G1_CPU1_G3_TX_DP<13>")
	)
	(segment
		(start 345.932506 -223.895158)
		(end 345.936062 -223.893126)
		(width 0.1143)
		(layer "In15.Cu")
		(net "GMI_CPU0_G1_CPU1_G3_TX_DP<13>")
	)
	(segment
		(start 346.84208 -234.275376)
		(end 346.812362 -234.258358)
		(width 0.1143)
		(layer "In15.Cu")
		(net "GMI_CPU0_G1_CPU1_G3_TX_DP<13>")
	)
	(segment
		(start 124.620274 -231.99344)
		(end 124.644912 -232.007664)
		(width 0.1143)
		(layer "In15.Cu")
		(net "GMI_CPU0_G1_CPU1_G3_TX_DP<13>")
	)
	(segment
		(start 345.943174 -222.959676)
		(end 345.936316 -222.955612)
		(width 0.1143)
		(layer "In15.Cu")
		(net "GMI_CPU0_G1_CPU1_G3_TX_DP<13>")
	)
	(segment
		(start 346.87637 -234.295442)
		(end 346.875608 -234.294934)
		(width 0.1143)
		(layer "In15.Cu")
		(net "GMI_CPU0_G1_CPU1_G3_TX_DP<13>")
	)
	(segment
		(start 124.65177 -222.93707)
		(end 124.650754 -222.937578)
		(width 0.1143)
		(layer "In15.Cu")
		(net "GMI_CPU0_G1_CPU1_G3_TX_DP<13>")
	)
	(segment
		(start 346.88272 -229.439216)
		(end 346.844112 -229.41661)
		(width 0.1143)
		(layer "In15.Cu")
		(net "GMI_CPU0_G1_CPU1_G3_TX_DP<13>")
	)
	(segment
		(start 346.84335 -240.756186)
		(end 346.84208 -240.755424)
		(width 0.1143)
		(layer "In15.Cu")
		(net "GMI_CPU0_G1_CPU1_G3_TX_DP<13>")
	)
	(segment
		(start 124.647452 -241.72926)
		(end 124.648976 -241.730276)
		(width 0.1143)
		(layer "In15.Cu")
		(net "GMI_CPU0_G1_CPU1_G3_TX_DP<13>")
	)
	(segment
		(start 124.650754 -230.391462)
		(end 124.653548 -230.392986)
		(width 0.1143)
		(layer "In15.Cu")
		(net "GMI_CPU0_G1_CPU1_G3_TX_DP<13>")
	)
	(segment
		(start 346.84335 -245.616222)
		(end 346.84208 -245.61546)
		(width 0.1143)
		(layer "In15.Cu")
		(net "GMI_CPU0_G1_CPU1_G3_TX_DP<13>")
	)
	(segment
		(start 346.844112 -228.771704)
		(end 346.845128 -228.771196)
		(width 0.1143)
		(layer "In15.Cu")
		(net "GMI_CPU0_G1_CPU1_G3_TX_DP<13>")
	)
	(segment
		(start 124.615194 -230.370634)
		(end 124.619512 -230.373174)
		(width 0.1143)
		(layer "In15.Cu")
		(net "GMI_CPU0_G1_CPU1_G3_TX_DP<13>")
	)
	(segment
		(start 346.84335 -232.656126)
		(end 346.84208 -232.655364)
		(width 0.1143)
		(layer "In15.Cu")
		(net "GMI_CPU0_G1_CPU1_G3_TX_DP<13>")
	)
	(segment
		(start 345.903296 -222.936308)
		(end 345.902788 -222.936054)
		(width 0.1143)
		(layer "In15.Cu")
		(net "GMI_CPU0_G1_CPU1_G3_TX_DP<13>")
	)
	(segment
		(start 124.68352 -243.978684)
		(end 124.652532 -243.996464)
		(width 0.1143)
		(layer "In15.Cu")
		(net "GMI_CPU0_G1_CPU1_G3_TX_DP<13>")
	)
	(segment
		(start 345.919044 -223.903032)
		(end 345.921076 -223.901762)
		(width 0.1143)
		(layer "In15.Cu")
		(net "GMI_CPU0_G1_CPU1_G3_TX_DP<13>")
	)
	(segment
		(start 345.925394 -223.899222)
		(end 345.92641 -223.898714)
		(width 0.1143)
		(layer "In15.Cu")
		(net "GMI_CPU0_G1_CPU1_G3_TX_DP<13>")
	)
	(segment
		(start 124.644912 -228.767894)
		(end 124.646436 -228.76891)
		(width 0.1143)
		(layer "In15.Cu")
		(net "GMI_CPU0_G1_CPU1_G3_TX_DP<13>")
	)
	(segment
		(start 124.691902 -227.772722)
		(end 124.68352 -227.778818)
		(width 0.1143)
		(layer "In15.Cu")
		(net "GMI_CPU0_G1_CPU1_G3_TX_DP<13>")
	)
	(segment
		(start 124.65177 -239.136936)
		(end 124.650754 -239.137444)
		(width 0.1143)
		(layer "In15.Cu")
		(net "GMI_CPU0_G1_CPU1_G3_TX_DP<13>")
	)
	(segment
		(start 346.84335 -232.011982)
		(end 346.844112 -232.011474)
		(width 0.1143)
		(layer "In15.Cu")
		(net "GMI_CPU0_G1_CPU1_G3_TX_DP<13>")
	)
	(segment
		(start 124.612654 -238.468916)
		(end 124.619512 -238.47298)
		(width 0.1143)
		(layer "In15.Cu")
		(net "GMI_CPU0_G1_CPU1_G3_TX_DP<13>")
	)
	(segment
		(start 124.646436 -246.588788)
		(end 124.647452 -246.589296)
		(width 0.1143)
		(layer "In15.Cu")
		(net "GMI_CPU0_G1_CPU1_G3_TX_DP<13>")
	)
	(segment
		(start 124.652532 -233.632248)
		(end 124.68352 -233.650028)
		(width 0.1143)
		(layer "In15.Cu")
		(net "GMI_CPU0_G1_CPU1_G3_TX_DP<13>")
	)
	(segment
		(start 124.68352 -243.3701)
		(end 124.694696 -243.378228)
		(width 0.1143)
		(layer "In15.Cu")
		(net "GMI_CPU0_G1_CPU1_G3_TX_DP<13>")
	)
	(segment
		(start 346.883228 -226.1997)
		(end 346.87637 -226.195636)
		(width 0.1143)
		(layer "In15.Cu")
		(net "GMI_CPU0_G1_CPU1_G3_TX_DP<13>")
	)
	(segment
		(start 124.69368 -226.15144)
		(end 124.68352 -226.158806)
		(width 0.1143)
		(layer "In15.Cu")
		(net "GMI_CPU0_G1_CPU1_G3_TX_DP<13>")
	)
	(segment
		(start 124.65177 -237.517178)
		(end 124.65177 -237.516924)
		(width 0.1143)
		(layer "In15.Cu")
		(net "GMI_CPU0_G1_CPU1_G3_TX_DP<13>")
	)
	(segment
		(start 346.812362 -238.50981)
		(end 346.844112 -238.491522)
		(width 0.1143)
		(layer "In15.Cu")
		(net "GMI_CPU0_G1_CPU1_G3_TX_DP<13>")
	)
	(segment
		(start 124.647452 -225.529394)
		(end 124.648976 -225.53041)
		(width 0.1143)
		(layer "In15.Cu")
		(net "GMI_CPU0_G1_CPU1_G3_TX_DP<13>")
	)
	(segment
		(start 346.875608 -235.914946)
		(end 346.844112 -235.896658)
		(width 0.1143)
		(layer "In15.Cu")
		(net "GMI_CPU0_G1_CPU1_G3_TX_DP<13>")
	)
	(segment
		(start 124.644912 -244.96776)
		(end 124.646436 -244.968776)
		(width 0.1143)
		(layer "In15.Cu")
		(net "GMI_CPU0_G1_CPU1_G3_TX_DP<13>")
	)
	(segment
		(start 346.844112 -240.111534)
		(end 346.845128 -240.111026)
		(width 0.1143)
		(layer "In15.Cu")
		(net "GMI_CPU0_G1_CPU1_G3_TX_DP<13>")
	)
	(segment
		(start 303.701196 -189.169294)
		(end 303.690528 -189.16904)
		(width 0.14224)
		(layer "In15.Cu")
		(net "GMI_CPU0_G1_CPU1_G3_TX_DP<13>")
	)
	(segment
		(start 124.648976 -244.9703)
		(end 124.650754 -244.971316)
		(width 0.1143)
		(layer "In15.Cu")
		(net "GMI_CPU0_G1_CPU1_G3_TX_DP<13>")
	)
	(segment
		(start 124.620274 -227.133658)
		(end 124.644912 -227.147882)
		(width 0.1143)
		(layer "In15.Cu")
		(net "GMI_CPU0_G1_CPU1_G3_TX_DP<13>")
	)
	(segment
		(start 124.652532 -224.556574)
		(end 124.65177 -224.557082)
		(width 0.1143)
		(layer "In15.Cu")
		(net "GMI_CPU0_G1_CPU1_G3_TX_DP<13>")
	)
	(segment
		(start 124.652532 -238.492284)
		(end 124.68352 -238.510064)
		(width 0.1143)
		(layer "In15.Cu")
		(net "GMI_CPU0_G1_CPU1_G3_TX_DP<13>")
	)
	(segment
		(start 346.84335 -242.376198)
		(end 346.84208 -242.375436)
		(width 0.1143)
		(layer "In15.Cu")
		(net "GMI_CPU0_G1_CPU1_G3_TX_DP<13>")
	)
	(segment
		(start 346.883228 -237.53953)
		(end 346.845128 -237.517178)
		(width 0.1143)
		(layer "In15.Cu")
		(net "GMI_CPU0_G1_CPU1_G3_TX_DP<13>")
	)
	(segment
		(start 346.812362 -236.889798)
		(end 346.84335 -236.872018)
		(width 0.1143)
		(layer "In15.Cu")
		(net "GMI_CPU0_G1_CPU1_G3_TX_DP<13>")
	)
	(segment
		(start 345.2368 -221.083124)
		(end 345.2368 -220.268038)
		(width 0.14224)
		(layer "In15.Cu")
		(net "GMI_CPU0_G1_CPU1_G3_TX_DP<13>")
	)
	(segment
		(start 124.652532 -241.732308)
		(end 124.68352 -241.750088)
		(width 0.1143)
		(layer "In15.Cu")
		(net "GMI_CPU0_G1_CPU1_G3_TX_DP<13>")
	)
	(segment
		(start 318.610996 -195.874386)
		(end 309.09768 -189.169548)
		(width 0.14224)
		(layer "In15.Cu")
		(net "GMI_CPU0_G1_CPU1_G3_TX_DP<13>")
	)
	(segment
		(start 124.64923 -224.558606)
		(end 124.612654 -224.579942)
		(width 0.1143)
		(layer "In15.Cu")
		(net "GMI_CPU0_G1_CPU1_G3_TX_DP<13>")
	)
	(segment
		(start 124.685298 -231.017318)
		(end 124.65177 -231.036876)
		(width 0.1143)
		(layer "In15.Cu")
		(net "GMI_CPU0_G1_CPU1_G3_TX_DP<13>")
	)
	(segment
		(start 124.646436 -241.728752)
		(end 124.647452 -241.72926)
		(width 0.1143)
		(layer "In15.Cu")
		(net "GMI_CPU0_G1_CPU1_G3_TX_DP<13>")
	)
	(segment
		(start 346.883228 -227.819712)
		(end 346.87637 -227.815648)
		(width 0.1143)
		(layer "In15.Cu")
		(net "GMI_CPU0_G1_CPU1_G3_TX_DP<13>")
	)
	(segment
		(start 148.580602 -200.5711)
		(end 146.36623 -201.242168)
		(width 0.14224)
		(layer "In15.Cu")
		(net "GMI_CPU0_G1_CPU1_G3_TX_DP<13>")
	)
	(segment
		(start 346.812362 -232.029762)
		(end 346.84335 -232.011982)
		(width 0.1143)
		(layer "In15.Cu")
		(net "GMI_CPU0_G1_CPU1_G3_TX_DP<13>")
	)
	(segment
		(start 345.19108 -221.308676)
		(end 345.19108 -221.143322)
		(width 0.1143)
		(layer "In15.Cu")
		(net "GMI_CPU0_G1_CPU1_G3_TX_DP<13>")
	)
	(segment
		(start 124.619512 -231.992932)
		(end 124.620274 -231.99344)
		(width 0.1143)
		(layer "In15.Cu")
		(net "GMI_CPU0_G1_CPU1_G3_TX_DP<13>")
	)
	(segment
		(start 345.904058 -224.556828)
		(end 345.903296 -224.55632)
		(width 0.1143)
		(layer "In15.Cu")
		(net "GMI_CPU0_G1_CPU1_G3_TX_DP<13>")
	)
	(segment
		(start 124.64923 -237.518448)
		(end 124.612654 -237.539784)
		(width 0.1143)
		(layer "In15.Cu")
		(net "GMI_CPU0_G1_CPU1_G3_TX_DP<13>")
	)
	(segment
		(start 124.652532 -222.936562)
		(end 124.65177 -222.93707)
		(width 0.1143)
		(layer "In15.Cu")
		(net "GMI_CPU0_G1_CPU1_G3_TX_DP<13>")
	)
	(segment
		(start 346.851732 -228.767132)
		(end 346.883228 -228.748844)
		(width 0.1143)
		(layer "In15.Cu")
		(net "GMI_CPU0_G1_CPU1_G3_TX_DP<13>")
	)
	(segment
		(start 124.647452 -244.969284)
		(end 124.648976 -244.9703)
		(width 0.1143)
		(layer "In15.Cu")
		(net "GMI_CPU0_G1_CPU1_G3_TX_DP<13>")
	)
	(segment
		(start 124.620274 -225.513646)
		(end 124.644912 -225.52787)
		(width 0.1143)
		(layer "In15.Cu")
		(net "GMI_CPU0_G1_CPU1_G3_TX_DP<13>")
	)
	(segment
		(start 124.650754 -240.757456)
		(end 124.64923 -240.758472)
		(width 0.1143)
		(layer "In15.Cu")
		(net "GMI_CPU0_G1_CPU1_G3_TX_DP<13>")
	)
	(segment
		(start 124.65177 -231.036876)
		(end 124.612654 -231.059736)
		(width 0.1143)
		(layer "In15.Cu")
		(net "GMI_CPU0_G1_CPU1_G3_TX_DP<13>")
	)
	(segment
		(start 124.652532 -232.65638)
		(end 124.65177 -232.656888)
		(width 0.1143)
		(layer "In15.Cu")
		(net "GMI_CPU0_G1_CPU1_G3_TX_DP<13>")
	)
	(segment
		(start 124.647452 -232.009188)
		(end 124.648976 -232.010204)
		(width 0.1143)
		(layer "In15.Cu")
		(net "GMI_CPU0_G1_CPU1_G3_TX_DP<13>")
	)
	(segment
		(start 124.369322 -221.248732)
		(end 124.369322 -221.804484)
		(width 0.1143)
		(layer "In15.Cu")
		(net "GMI_CPU0_G1_CPU1_G3_TX_DP<13>")
	)
	(segment
		(start 346.84208 -235.895388)
		(end 346.812362 -235.87837)
		(width 0.1143)
		(layer "In15.Cu")
		(net "GMI_CPU0_G1_CPU1_G3_TX_DP<13>")
	)
	(segment
		(start 124.650754 -239.137444)
		(end 124.64923 -239.13846)
		(width 0.1143)
		(layer "In15.Cu")
		(net "GMI_CPU0_G1_CPU1_G3_TX_DP<13>")
	)
	(segment
		(start 124.648976 -243.350288)
		(end 124.650754 -243.351304)
		(width 0.1143)
		(layer "In15.Cu")
		(net "GMI_CPU0_G1_CPU1_G3_TX_DP<13>")
	)
	(segment
		(start 124.652532 -246.592344)
		(end 124.65304 -246.592344)
		(width 0.1143)
		(layer "In15.Cu")
		(net "GMI_CPU0_G1_CPU1_G3_TX_DP<13>")
	)
	(segment
		(start 124.650754 -232.01122)
		(end 124.65177 -232.011728)
		(width 0.1143)
		(layer "In15.Cu")
		(net "GMI_CPU0_G1_CPU1_G3_TX_DP<13>")
	)
	(segment
		(start 124.652532 -245.616476)
		(end 124.65177 -245.616984)
		(width 0.1143)
		(layer "In15.Cu")
		(net "GMI_CPU0_G1_CPU1_G3_TX_DP<13>")
	)
	(segment
		(start 124.64923 -227.79863)
		(end 124.612654 -227.819966)
		(width 0.1143)
		(layer "In15.Cu")
		(net "GMI_CPU0_G1_CPU1_G3_TX_DP<13>")
	)
	(segment
		(start 346.845128 -241.731038)
		(end 346.846652 -241.730022)
		(width 0.1143)
		(layer "In15.Cu")
		(net "GMI_CPU0_G1_CPU1_G3_TX_DP<13>")
	)
	(segment
		(start 124.652278 -237.516924)
		(end 124.65177 -237.517178)
		(width 0.1143)
		(layer "In15.Cu")
		(net "GMI_CPU0_G1_CPU1_G3_TX_DP<13>")
	)
	(segment
		(start 124.65177 -237.516924)
		(end 124.650754 -237.517432)
		(width 0.1143)
		(layer "In15.Cu")
		(net "GMI_CPU0_G1_CPU1_G3_TX_DP<13>")
	)
	(segment
		(start 346.883228 -235.919518)
		(end 346.87637 -235.915454)
		(width 0.1143)
		(layer "In15.Cu")
		(net "GMI_CPU0_G1_CPU1_G3_TX_DP<13>")
	)
	(segment
		(start 124.648976 -246.590312)
		(end 124.650754 -246.591328)
		(width 0.1143)
		(layer "In15.Cu")
		(net "GMI_CPU0_G1_CPU1_G3_TX_DP<13>")
	)
	(segment
		(start 345.903296 -224.55632)
		(end 345.872308 -224.53854)
		(width 0.1143)
		(layer "In15.Cu")
		(net "GMI_CPU0_G1_CPU1_G3_TX_DP<13>")
	)
	(segment
		(start 346.844112 -239.136682)
		(end 346.84335 -239.136174)
		(width 0.1143)
		(layer "In15.Cu")
		(net "GMI_CPU0_G1_CPU1_G3_TX_DP<13>")
	)
	(segment
		(start 124.648976 -238.490252)
		(end 124.650754 -238.491268)
		(width 0.1143)
		(layer "In15.Cu")
		(net "GMI_CPU0_G1_CPU1_G3_TX_DP<13>")
	)
	(segment
		(start 124.68352 -224.538794)
		(end 124.652532 -224.556574)
		(width 0.1143)
		(layer "In15.Cu")
		(net "GMI_CPU0_G1_CPU1_G3_TX_DP<13>")
	)
	(segment
		(start 303.734724 -189.169548)
		(end 303.73447 -189.169294)
		(width 0.14224)
		(layer "In15.Cu")
		(net "GMI_CPU0_G1_CPU1_G3_TX_DP<13>")
	)
	(segment
		(start 345.927172 -223.898206)
		(end 345.92895 -223.89719)
		(width 0.1143)
		(layer "In15.Cu")
		(net "GMI_CPU0_G1_CPU1_G3_TX_DP<13>")
	)
	(segment
		(start 124.68352 -241.750088)
		(end 124.69368 -241.757454)
		(width 0.1143)
		(layer "In15.Cu")
		(net "GMI_CPU0_G1_CPU1_G3_TX_DP<13>")
	)
	(segment
		(start 124.612654 -243.328952)
		(end 124.619512 -243.333016)
		(width 0.1143)
		(layer "In15.Cu")
		(net "GMI_CPU0_G1_CPU1_G3_TX_DP<13>")
	)
	(segment
		(start 125.302518 -247.654572)
		(end 125.232668 -247.724422)
		(width 0.1143)
		(layer "In15.Cu")
		(net "GMI_CPU0_G1_CPU1_G3_TX_DP<13>")
	)
	(segment
		(start 124.693172 -245.591838)
		(end 124.68352 -245.598696)
		(width 0.1143)
		(layer "In15.Cu")
		(net "GMI_CPU0_G1_CPU1_G3_TX_DP<13>")
	)
	(segment
		(start 162.253676 -189.197742)
		(end 160.633156 -190.526924)
		(width 0.14224)
		(layer "In15.Cu")
		(net "GMI_CPU0_G1_CPU1_G3_TX_DP<13>")
	)
	(segment
		(start 346.845128 -243.35105)
		(end 346.846652 -243.350034)
		(width 0.1143)
		(layer "In15.Cu")
		(net "GMI_CPU0_G1_CPU1_G3_TX_DP<13>")
	)
	(segment
		(start 124.612654 -231.988868)
		(end 124.619512 -231.992932)
		(width 0.1143)
		(layer "In15.Cu")
		(net "GMI_CPU0_G1_CPU1_G3_TX_DP<13>")
	)
	(segment
		(start 124.64923 -232.658412)
		(end 124.612654 -232.679748)
		(width 0.1143)
		(layer "In15.Cu")
		(net "GMI_CPU0_G1_CPU1_G3_TX_DP<13>")
	)
	(segment
		(start 124.646182 -242.380262)
		(end 124.612654 -242.39982)
		(width 0.1143)
		(layer "In15.Cu")
		(net "GMI_CPU0_G1_CPU1_G3_TX_DP<13>")
	)
	(segment
		(start 124.652532 -225.532442)
		(end 124.68352 -225.550222)
		(width 0.1143)
		(layer "In15.Cu")
		(net "GMI_CPU0_G1_CPU1_G3_TX_DP<13>")
	)
	(segment
		(start 124.69368 -242.351306)
		(end 124.68352 -242.358672)
		(width 0.1143)
		(layer "In15.Cu")
		(net "GMI_CPU0_G1_CPU1_G3_TX_DP<13>")
	)
	(segment
		(start 346.812362 -246.60987)
		(end 346.84335 -246.59209)
		(width 0.1143)
		(layer "In15.Cu")
		(net "GMI_CPU0_G1_CPU1_G3_TX_DP<13>")
	)
	(segment
		(start 345.943174 -224.579688)
		(end 345.936316 -224.575624)
		(width 0.1143)
		(layer "In15.Cu")
		(net "GMI_CPU0_G1_CPU1_G3_TX_DP<13>")
	)
	(segment
		(start 124.652024 -235.251752)
		(end 124.652278 -235.251752)
		(width 0.1143)
		(layer "In15.Cu")
		(net "GMI_CPU0_G1_CPU1_G3_TX_DP<13>")
	)
	(segment
		(start 346.883228 -234.299506)
		(end 346.87637 -234.295442)
		(width 0.1143)
		(layer "In15.Cu")
		(net "GMI_CPU0_G1_CPU1_G3_TX_DP<13>")
	)
	(segment
		(start 346.845128 -233.630978)
		(end 346.846652 -233.629962)
		(width 0.1143)
		(layer "In15.Cu")
		(net "GMI_CPU0_G1_CPU1_G3_TX_DP<13>")
	)
	(segment
		(start 346.845128 -235.25099)
		(end 346.846652 -235.249974)
		(width 0.1143)
		(layer "In15.Cu")
		(net "GMI_CPU0_G1_CPU1_G3_TX_DP<13>")
	)
	(segment
		(start 236.351826 -199.463914)
		(end 234.011978 -199.051418)
		(width 0.14224)
		(layer "In15.Cu")
		(net "GMI_CPU0_G1_CPU1_G3_TX_DP<13>")
	)
	(segment
		(start 124.68352 -234.258612)
		(end 124.652532 -234.276392)
		(width 0.1143)
		(layer "In15.Cu")
		(net "GMI_CPU0_G1_CPU1_G3_TX_DP<13>")
	)
	(segment
		(start 346.845128 -238.491014)
		(end 346.846652 -238.489998)
		(width 0.1143)
		(layer "In15.Cu")
		(net "GMI_CPU0_G1_CPU1_G3_TX_DP<13>")
	)
	(segment
		(start 124.620274 -228.75367)
		(end 124.644912 -228.767894)
		(width 0.1143)
		(layer "In15.Cu")
		(net "GMI_CPU0_G1_CPU1_G3_TX_DP<13>")
	)
	(segment
		(start 346.84208 -243.995448)
		(end 346.812362 -243.97843)
		(width 0.1143)
		(layer "In15.Cu")
		(net "GMI_CPU0_G1_CPU1_G3_TX_DP<13>")
	)
	(segment
		(start 146.36623 -201.242168)
		(end 125.6538 -218.224862)
		(width 0.14224)
		(layer "In15.Cu")
		(net "GMI_CPU0_G1_CPU1_G3_TX_DP<13>")
	)
	(segment
		(start 125.232668 -247.724422)
		(end 124.934726 -247.724422)
		(width 0.1143)
		(layer "In15.Cu")
		(net "GMI_CPU0_G1_CPU1_G3_TX_DP<13>")
	)
	(segment
		(start 124.652532 -242.376452)
		(end 124.65177 -242.37696)
		(width 0.1143)
		(layer "In15.Cu")
		(net "GMI_CPU0_G1_CPU1_G3_TX_DP<13>")
	)
	(segment
		(start 124.644912 -233.627676)
		(end 124.646436 -233.628692)
		(width 0.1143)
		(layer "In15.Cu")
		(net "GMI_CPU0_G1_CPU1_G3_TX_DP<13>")
	)
	(segment
		(start 124.65177 -229.416864)
		(end 124.612654 -229.439724)
		(width 0.1143)
		(layer "In15.Cu")
		(net "GMI_CPU0_G1_CPU1_G3_TX_DP<13>")
	)
	(segment
		(start 346.875608 -232.674922)
		(end 346.844112 -232.656634)
		(width 0.1143)
		(layer "In15.Cu")
		(net "GMI_CPU0_G1_CPU1_G3_TX_DP<13>")
	)
	(segment
		(start 124.644912 -232.007664)
		(end 124.646436 -232.00868)
		(width 0.1143)
		(layer "In15.Cu")
		(net "GMI_CPU0_G1_CPU1_G3_TX_DP<13>")
	)
	(segment
		(start 124.620274 -246.573548)
		(end 124.644912 -246.587772)
		(width 0.1143)
		(layer "In15.Cu")
		(net "GMI_CPU0_G1_CPU1_G3_TX_DP<13>")
	)
	(segment
		(start 124.652532 -227.152454)
		(end 124.68352 -227.170234)
		(width 0.1143)
		(layer "In15.Cu")
		(net "GMI_CPU0_G1_CPU1_G3_TX_DP<13>")
	)
	(segment
		(start 346.844112 -240.756694)
		(end 346.84335 -240.756186)
		(width 0.1143)
		(layer "In15.Cu")
		(net "GMI_CPU0_G1_CPU1_G3_TX_DP<13>")
	)
	(segment
		(start 345.907614 -223.909636)
		(end 345.908884 -223.908874)
		(width 0.1143)
		(layer "In15.Cu")
		(net "GMI_CPU0_G1_CPU1_G3_TX_DP<13>")
	)
	(segment
		(start 125.121924 -247.401842)
		(end 125.15342 -247.420384)
		(width 0.1143)
		(layer "In15.Cu")
		(net "GMI_CPU0_G1_CPU1_G3_TX_DP<13>")
	)
	(segment
		(start 124.648976 -225.53041)
		(end 124.650754 -225.531426)
		(width 0.1143)
		(layer "In15.Cu")
		(net "GMI_CPU0_G1_CPU1_G3_TX_DP<13>")
	)
	(segment
		(start 346.561156 -247.724168)
		(end 346.263214 -247.724168)
		(width 0.1143)
		(layer "In15.Cu")
		(net "GMI_CPU0_G1_CPU1_G3_TX_DP<13>")
	)
	(segment
		(start 124.690124 -232.633774)
		(end 124.68352 -232.6386)
		(width 0.1143)
		(layer "In15.Cu")
		(net "GMI_CPU0_G1_CPU1_G3_TX_DP<13>")
	)
	(segment
		(start 124.650754 -233.631232)
		(end 124.65177 -233.63174)
		(width 0.1143)
		(layer "In15.Cu")
		(net "GMI_CPU0_G1_CPU1_G3_TX_DP<13>")
	)
	(segment
		(start 345.92641 -223.898714)
		(end 345.927172 -223.898206)
		(width 0.1143)
		(layer "In15.Cu")
		(net "GMI_CPU0_G1_CPU1_G3_TX_DP<13>")
	)
	(segment
		(start 346.812362 -233.649774)
		(end 346.84335 -233.631994)
		(width 0.1143)
		(layer "In15.Cu")
		(net "GMI_CPU0_G1_CPU1_G3_TX_DP<13>")
	)
	(segment
		(start 346.87637 -235.915454)
		(end 346.875608 -235.914946)
		(width 0.1143)
		(layer "In15.Cu")
		(net "GMI_CPU0_G1_CPU1_G3_TX_DP<13>")
	)
	(segment
		(start 124.65304 -246.592344)
		(end 124.666756 -246.600218)
		(width 0.1143)
		(layer "In15.Cu")
		(net "GMI_CPU0_G1_CPU1_G3_TX_DP<13>")
	)
	(segment
		(start 346.846652 -244.970046)
		(end 346.883228 -244.94871)
		(width 0.1143)
		(layer "In15.Cu")
		(net "GMI_CPU0_G1_CPU1_G3_TX_DP<13>")
	)
	(segment
		(start 124.620274 -243.333524)
		(end 124.644912 -243.347748)
		(width 0.1143)
		(layer "In15.Cu")
		(net "GMI_CPU0_G1_CPU1_G3_TX_DP<13>")
	)
	(segment
		(start 124.65177 -244.971824)
		(end 124.652532 -244.972332)
		(width 0.1143)
		(layer "In15.Cu")
		(net "GMI_CPU0_G1_CPU1_G3_TX_DP<13>")
	)
	(segment
		(start 124.68352 -225.550222)
		(end 124.69368 -225.557588)
		(width 0.1143)
		(layer "In15.Cu")
		(net "GMI_CPU0_G1_CPU1_G3_TX_DP<13>")
	)
	(segment
		(start 124.65177 -243.351812)
		(end 124.652532 -243.35232)
		(width 0.1143)
		(layer "In15.Cu")
		(net "GMI_CPU0_G1_CPU1_G3_TX_DP<13>")
	)
	(segment
		(start 346.844112 -236.87151)
		(end 346.845128 -236.871002)
		(width 0.1143)
		(layer "In15.Cu")
		(net "GMI_CPU0_G1_CPU1_G3_TX_DP<13>")
	)
	(segment
		(start 124.644912 -223.907858)
		(end 124.646436 -223.908874)
		(width 0.1143)
		(layer "In15.Cu")
		(net "GMI_CPU0_G1_CPU1_G3_TX_DP<13>")
	)
	(segment
		(start 124.644912 -227.147882)
		(end 124.646436 -227.148898)
		(width 0.1143)
		(layer "In15.Cu")
		(net "GMI_CPU0_G1_CPU1_G3_TX_DP<13>")
	)
	(segment
		(start 124.619512 -228.753162)
		(end 124.620274 -228.75367)
		(width 0.1143)
		(layer "In15.Cu")
		(net "GMI_CPU0_G1_CPU1_G3_TX_DP<13>")
	)
	(segment
		(start 346.875608 -240.774982)
		(end 346.844112 -240.756694)
		(width 0.1143)
		(layer "In15.Cu")
		(net "GMI_CPU0_G1_CPU1_G3_TX_DP<13>")
	)
	(segment
		(start 124.650754 -243.99748)
		(end 124.64923 -243.998496)
		(width 0.1143)
		(layer "In15.Cu")
		(net "GMI_CPU0_G1_CPU1_G3_TX_DP<13>")
	)
	(segment
		(start 124.65177 -238.491776)
		(end 124.652532 -238.492284)
		(width 0.1143)
		(layer "In15.Cu")
		(net "GMI_CPU0_G1_CPU1_G3_TX_DP<13>")
	)
	(segment
		(start 346.812362 -227.16998)
		(end 346.84335 -227.1522)
		(width 0.1143)
		(layer "In15.Cu")
		(net "GMI_CPU0_G1_CPU1_G3_TX_DP<13>")
	)
	(segment
		(start 346.84335 -236.872018)
		(end 346.844112 -236.87151)
		(width 0.1143)
		(layer "In15.Cu")
		(net "GMI_CPU0_G1_CPU1_G3_TX_DP<13>")
	)
	(segment
		(start 124.65177 -228.771958)
		(end 124.652532 -228.772466)
		(width 0.1143)
		(layer "In15.Cu")
		(net "GMI_CPU0_G1_CPU1_G3_TX_DP<13>")
	)
	(segment
		(start 124.619512 -233.612944)
		(end 124.620274 -233.613452)
		(width 0.1143)
		(layer "In15.Cu")
		(net "GMI_CPU0_G1_CPU1_G3_TX_DP<13>")
	)
	(segment
		(start 346.844112 -243.996718)
		(end 346.84335 -243.99621)
		(width 0.1143)
		(layer "In15.Cu")
		(net "GMI_CPU0_G1_CPU1_G3_TX_DP<13>")
	)
	(segment
		(start 346.844112 -230.391716)
		(end 346.880688 -230.37038)
		(width 0.1143)
		(layer "In15.Cu")
		(net "GMI_CPU0_G1_CPU1_G3_TX_DP<13>")
	)
	(segment
		(start 124.619512 -230.373174)
		(end 124.620274 -230.373682)
		(width 0.1143)
		(layer "In15.Cu")
		(net "GMI_CPU0_G1_CPU1_G3_TX_DP<13>")
	)
	(segment
		(start 346.847668 -228.769672)
		(end 346.851732 -228.767132)
		(width 0.1143)
		(layer "In15.Cu")
		(net "GMI_CPU0_G1_CPU1_G3_TX_DP<13>")
	)
	(segment
		(start 124.612654 -244.948964)
		(end 124.619512 -244.953028)
		(width 0.1143)
		(layer "In15.Cu")
		(net "GMI_CPU0_G1_CPU1_G3_TX_DP<13>")
	)
	(segment
		(start 346.875608 -244.015006)
		(end 346.844112 -243.996718)
		(width 0.1143)
		(layer "In15.Cu")
		(net "GMI_CPU0_G1_CPU1_G3_TX_DP<13>")
	)
	(segment
		(start 346.846652 -243.350034)
		(end 346.883228 -243.328698)
		(width 0.1143)
		(layer "In15.Cu")
		(net "GMI_CPU0_G1_CPU1_G3_TX_DP<13>")
	)
	(segment
		(start 124.68352 -239.118648)
		(end 124.652532 -239.136428)
		(width 0.1143)
		(layer "In15.Cu")
		(net "GMI_CPU0_G1_CPU1_G3_TX_DP<13>")
	)
	(segment
		(start 124.68352 -226.158806)
		(end 124.652532 -226.176586)
		(width 0.1143)
		(layer "In15.Cu")
		(net "GMI_CPU0_G1_CPU1_G3_TX_DP<13>")
	)
	(segment
		(start 303.690528 -189.16904)
		(end 303.685194 -189.16904)
		(width 0.14224)
		(layer "In15.Cu")
		(net "GMI_CPU0_G1_CPU1_G3_TX_DP<13>")
	)
	(segment
		(start 124.650754 -245.617492)
		(end 124.64923 -245.618508)
		(width 0.1143)
		(layer "In15.Cu")
		(net "GMI_CPU0_G1_CPU1_G3_TX_DP<13>")
	)
	(segment
		(start 346.844112 -227.151692)
		(end 346.880434 -227.130864)
		(width 0.1143)
		(layer "In15.Cu")
		(net "GMI_CPU0_G1_CPU1_G3_TX_DP<13>")
	)
	(segment
		(start 343.254838 -216.08034)
		(end 318.610996 -195.874386)
		(width 0.14224)
		(layer "In15.Cu")
		(net "GMI_CPU0_G1_CPU1_G3_TX_DP<13>")
	)
	(segment
		(start 346.84335 -226.176332)
		(end 346.835984 -226.172268)
		(width 0.1143)
		(layer "In15.Cu")
		(net "GMI_CPU0_G1_CPU1_G3_TX_DP<13>")
	)
	(segment
		(start 124.632466 -236.861858)
		(end 124.641864 -236.86643)
		(width 0.1143)
		(layer "In15.Cu")
		(net "GMI_CPU0_G1_CPU1_G3_TX_DP<13>")
	)
	(segment
		(start 150.882858 -198.683118)
		(end 150.882858 -198.683372)
		(width 0.14224)
		(layer "In15.Cu")
		(net "GMI_CPU0_G1_CPU1_G3_TX_DP<13>")
	)
	(segment
		(start 160.47847 -190.815722)
		(end 150.882858 -198.683118)
		(width 0.14224)
		(layer "In15.Cu")
		(net "GMI_CPU0_G1_CPU1_G3_TX_DP<13>")
	)
	(segment
		(start 124.68352 -244.990112)
		(end 124.693172 -244.99697)
		(width 0.1143)
		(layer "In15.Cu")
		(net "GMI_CPU0_G1_CPU1_G3_TX_DP<13>")
	)
	(segment
		(start 124.619512 -225.513138)
		(end 124.620274 -225.513646)
		(width 0.1143)
		(layer "In15.Cu")
		(net "GMI_CPU0_G1_CPU1_G3_TX_DP<13>")
	)
	(segment
		(start 346.84335 -237.516162)
		(end 346.84208 -237.5154)
		(width 0.1143)
		(layer "In15.Cu")
		(net "GMI_CPU0_G1_CPU1_G3_TX_DP<13>")
	)
	(segment
		(start 346.875608 -227.81514)
		(end 346.844112 -227.796852)
		(width 0.1143)
		(layer "In15.Cu")
		(net "GMI_CPU0_G1_CPU1_G3_TX_DP<13>")
	)
	(segment
		(start 346.883228 -229.43947)
		(end 346.88272 -229.439216)
		(width 0.1143)
		(layer "In15.Cu")
		(net "GMI_CPU0_G1_CPU1_G3_TX_DP<13>")
	)
	(segment
		(start 124.323602 -221.203012)
		(end 124.369322 -221.248732)
		(width 0.1143)
		(layer "In15.Cu")
		(net "GMI_CPU0_G1_CPU1_G3_TX_DP<13>")
	)
	(segment
		(start 346.844112 -244.97157)
		(end 346.845128 -244.971062)
		(width 0.1143)
		(layer "In15.Cu")
		(net "GMI_CPU0_G1_CPU1_G3_TX_DP<13>")
	)
	(segment
		(start 124.620274 -238.473488)
		(end 124.644912 -238.487712)
		(width 0.1143)
		(layer "In15.Cu")
		(net "GMI_CPU0_G1_CPU1_G3_TX_DP<13>")
	)
	(segment
		(start 124.68352 -227.778818)
		(end 124.652532 -227.796598)
		(width 0.1143)
		(layer "In15.Cu")
		(net "GMI_CPU0_G1_CPU1_G3_TX_DP<13>")
	)
	(segment
		(start 124.646436 -223.908874)
		(end 124.647452 -223.909382)
		(width 0.1143)
		(layer "In15.Cu")
		(net "GMI_CPU0_G1_CPU1_G3_TX_DP<13>")
	)
	(segment
		(start 346.883228 -245.63959)
		(end 346.845128 -245.617238)
		(width 0.1143)
		(layer "In15.Cu")
		(net "GMI_CPU0_G1_CPU1_G3_TX_DP<13>")
	)
	(segment
		(start 346.84335 -235.252006)
		(end 346.844112 -235.251498)
		(width 0.1143)
		(layer "In15.Cu")
		(net "GMI_CPU0_G1_CPU1_G3_TX_DP<13>")
	)
	(segment
		(start 124.65177 -245.616984)
		(end 124.650754 -245.617492)
		(width 0.1143)
		(layer "In15.Cu")
		(net "GMI_CPU0_G1_CPU1_G3_TX_DP<13>")
	)
	(segment
		(start 124.650754 -244.971316)
		(end 124.65177 -244.971824)
		(width 0.1143)
		(layer "In15.Cu")
		(net "GMI_CPU0_G1_CPU1_G3_TX_DP<13>")
	)
	(segment
		(start 124.65177 -233.63174)
		(end 124.652532 -233.632248)
		(width 0.1143)
		(layer "In15.Cu")
		(net "GMI_CPU0_G1_CPU1_G3_TX_DP<13>")
	)
	(segment
		(start 346.844112 -226.17684)
		(end 346.84335 -226.176332)
		(width 0.1143)
		(layer "In15.Cu")
		(net "GMI_CPU0_G1_CPU1_G3_TX_DP<13>")
	)
	(segment
		(start 124.647452 -238.489236)
		(end 124.648976 -238.490252)
		(width 0.1143)
		(layer "In15.Cu")
		(net "GMI_CPU0_G1_CPU1_G3_TX_DP<13>")
	)
	(segment
		(start 345.19108 -221.143322)
		(end 345.2368 -221.097602)
		(width 0.1143)
		(layer "In15.Cu")
		(net "GMI_CPU0_G1_CPU1_G3_TX_DP<13>")
	)
	(segment
		(start 124.644912 -241.727736)
		(end 124.646436 -241.728752)
		(width 0.1143)
		(layer "In15.Cu")
		(net "GMI_CPU0_G1_CPU1_G3_TX_DP<13>")
	)
	(segment
		(start 124.64923 -234.278424)
		(end 124.612654 -234.29976)
		(width 0.1143)
		(layer "In15.Cu")
		(net "GMI_CPU0_G1_CPU1_G3_TX_DP<13>")
	)
	(segment
		(start 346.84208 -237.5154)
		(end 346.812362 -237.498382)
		(width 0.1143)
		(layer "In15.Cu")
		(net "GMI_CPU0_G1_CPU1_G3_TX_DP<13>")
	)
	(segment
		(start 124.647452 -243.349272)
		(end 124.648976 -243.350288)
		(width 0.1143)
		(layer "In15.Cu")
		(net "GMI_CPU0_G1_CPU1_G3_TX_DP<13>")
	)
	(segment
		(start 124.65177 -246.591836)
		(end 124.652532 -246.592344)
		(width 0.1143)
		(layer "In15.Cu")
		(net "GMI_CPU0_G1_CPU1_G3_TX_DP<13>")
	)
	(segment
		(start 346.812362 -228.789992)
		(end 346.844112 -228.771704)
		(width 0.1143)
		(layer "In15.Cu")
		(net "GMI_CPU0_G1_CPU1_G3_TX_DP<13>")
	)
	(segment
		(start 149.731984 -199.627236)
		(end 148.580602 -200.5711)
		(width 0.14224)
		(layer "In15.Cu")
		(net "GMI_CPU0_G1_CPU1_G3_TX_DP<13>")
	)
	(segment
		(start 346.845128 -228.771196)
		(end 346.846652 -228.77018)
		(width 0.1143)
		(layer "In15.Cu")
		(net "GMI_CPU0_G1_CPU1_G3_TX_DP<13>")
	)
	(segment
		(start 124.694696 -243.970556)
		(end 124.68352 -243.978684)
		(width 0.1143)
		(layer "In15.Cu")
		(net "GMI_CPU0_G1_CPU1_G3_TX_DP<13>")
	)
	(segment
		(start 124.620274 -223.893634)
		(end 124.644912 -223.907858)
		(width 0.1143)
		(layer "In15.Cu")
		(net "GMI_CPU0_G1_CPU1_G3_TX_DP<13>")
	)
	(segment
		(start 346.812362 -230.410004)
		(end 346.844112 -230.391716)
		(width 0.1143)
		(layer "In15.Cu")
		(net "GMI_CPU0_G1_CPU1_G3_TX_DP<13>")
	)
	(segment
		(start 124.652532 -227.796598)
		(end 124.65177 -227.797106)
		(width 0.1143)
		(layer "In15.Cu")
		(net "GMI_CPU0_G1_CPU1_G3_TX_DP<13>")
	)
	(segment
		(start 346.343478 -247.419368)
		(end 346.373958 -247.401588)
		(width 0.1143)
		(layer "In15.Cu")
		(net "GMI_CPU0_G1_CPU1_G3_TX_DP<13>")
	)
	(segment
		(start 124.685298 -229.397306)
		(end 124.65177 -229.416864)
		(width 0.1143)
		(layer "In15.Cu")
		(net "GMI_CPU0_G1_CPU1_G3_TX_DP<13>")
	)
	(segment
		(start 124.620274 -230.373682)
		(end 124.650754 -230.391462)
		(width 0.1143)
		(layer "In15.Cu")
		(net "GMI_CPU0_G1_CPU1_G3_TX_DP<13>")
	)
	(segment
		(start 346.84335 -227.1522)
		(end 346.844112 -227.151692)
		(width 0.1143)
		(layer "In15.Cu")
		(net "GMI_CPU0_G1_CPU1_G3_TX_DP<13>")
	)
	(segment
		(start 346.844112 -229.41661)
		(end 346.810584 -229.397052)
		(width 0.1143)
		(layer "In15.Cu")
		(net "GMI_CPU0_G1_CPU1_G3_TX_DP<13>")
	)
	(segment
		(start 345.2368 -221.097602)
		(end 345.2368 -221.083124)
		(width 0.1143)
		(layer "In15.Cu")
		(net "GMI_CPU0_G1_CPU1_G3_TX_DP<13>")
	)
	(segment
		(start 124.612654 -233.60888)
		(end 124.619512 -233.612944)
		(width 0.1143)
		(layer "In15.Cu")
		(net "GMI_CPU0_G1_CPU1_G3_TX_DP<13>")
	)
	(segment
		(start 346.812362 -241.749834)
		(end 346.84335 -241.732054)
		(width 0.1143)
		(layer "In15.Cu")
		(net "GMI_CPU0_G1_CPU1_G3_TX_DP<13>")
	)
	(segment
		(start 346.846652 -235.249974)
		(end 346.883228 -235.228638)
		(width 0.1143)
		(layer "In15.Cu")
		(net "GMI_CPU0_G1_CPU1_G3_TX_DP<13>")
	)
	(segment
		(start 124.643896 -235.24718)
		(end 124.652024 -235.251752)
		(width 0.1143)
		(layer "In15.Cu")
		(net "GMI_CPU0_G1_CPU1_G3_TX_DP<13>")
	)
	(segment
		(start 124.619512 -223.893126)
		(end 124.620274 -223.893634)
		(width 0.1143)
		(layer "In15.Cu")
		(net "GMI_CPU0_G1_CPU1_G3_TX_DP<13>")
	)
	(segment
		(start 124.652532 -235.896658)
		(end 124.65177 -235.896912)
		(width 0.1143)
		(layer "In15.Cu")
		(net "GMI_CPU0_G1_CPU1_G3_TX_DP<13>")
	)
	(segment
		(start 124.620274 -244.953536)
		(end 124.644912 -244.96776)
		(width 0.1143)
		(layer "In15.Cu")
		(net "GMI_CPU0_G1_CPU1_G3_TX_DP<13>")
	)
	(segment
		(start 124.644912 -246.587772)
		(end 124.646436 -246.588788)
		(width 0.1143)
		(layer "In15.Cu")
		(net "GMI_CPU0_G1_CPU1_G3_TX_DP<13>")
	)
	(segment
		(start 346.844112 -232.011474)
		(end 346.845128 -232.010966)
		(width 0.1143)
		(layer "In15.Cu")
		(net "GMI_CPU0_G1_CPU1_G3_TX_DP<13>")
	)
	(segment
		(start 124.65177 -243.996972)
		(end 124.650754 -243.99748)
		(width 0.1143)
		(layer "In15.Cu")
		(net "GMI_CPU0_G1_CPU1_G3_TX_DP<13>")
	)
	(segment
		(start 346.880434 -227.130864)
		(end 346.883228 -227.128832)
		(width 0.1143)
		(layer "In15.Cu")
		(net "GMI_CPU0_G1_CPU1_G3_TX_DP<13>")
	)
	(segment
		(start 124.612654 -225.509074)
		(end 124.619512 -225.513138)
		(width 0.1143)
		(layer "In15.Cu")
		(net "GMI_CPU0_G1_CPU1_G3_TX_DP<13>")
	)
	(segment
		(start 124.619512 -243.333016)
		(end 124.620274 -243.333524)
		(width 0.1143)
		(layer "In15.Cu")
		(net "GMI_CPU0_G1_CPU1_G3_TX_DP<13>")
	)
	(segment
		(start 124.646436 -233.628692)
		(end 124.647452 -233.6292)
		(width 0.1143)
		(layer "In15.Cu")
		(net "GMI_CPU0_G1_CPU1_G3_TX_DP<13>")
	)
	(segment
		(start 345.903296 -223.912176)
		(end 345.904058 -223.911668)
		(width 0.1143)
		(layer "In15.Cu")
		(net "GMI_CPU0_G1_CPU1_G3_TX_DP<13>")
	)
	(segment
		(start 346.84335 -235.89615)
		(end 346.84208 -235.895388)
		(width 0.1143)
		(layer "In15.Cu")
		(net "GMI_CPU0_G1_CPU1_G3_TX_DP<13>")
	)
	(segment
		(start 346.835984 -226.172268)
		(end 346.812362 -226.158552)
		(width 0.1143)
		(layer "In15.Cu")
		(net "GMI_CPU0_G1_CPU1_G3_TX_DP<13>")
	)
	(segment
		(start 346.845128 -236.871002)
		(end 346.846652 -236.869986)
		(width 0.1143)
		(layer "In15.Cu")
		(net "GMI_CPU0_G1_CPU1_G3_TX_DP<13>")
	)
	(segment
		(start 124.650754 -224.55759)
		(end 124.64923 -224.558606)
		(width 0.1143)
		(layer "In15.Cu")
		(net "GMI_CPU0_G1_CPU1_G3_TX_DP<13>")
	)
	(segment
		(start 124.647452 -223.909382)
		(end 124.648976 -223.910398)
		(width 0.1143)
		(layer "In15.Cu")
		(net "GMI_CPU0_G1_CPU1_G3_TX_DP<13>")
	)
	(segment
		(start 345.91244 -223.906842)
		(end 345.914472 -223.905572)
		(width 0.1143)
		(layer "In15.Cu")
		(net "GMI_CPU0_G1_CPU1_G3_TX_DP<13>")
	)
	(segment
		(start 124.644912 -238.487712)
		(end 124.646436 -238.488728)
		(width 0.1143)
		(layer "In15.Cu")
		(net "GMI_CPU0_G1_CPU1_G3_TX_DP<13>")
	)
	(segment
		(start 124.65177 -225.531934)
		(end 124.652532 -225.532442)
		(width 0.1143)
		(layer "In15.Cu")
		(net "GMI_CPU0_G1_CPU1_G3_TX_DP<13>")
	)
	(segment
		(start 124.650754 -227.151438)
		(end 124.65177 -227.151946)
		(width 0.1143)
		(layer "In15.Cu")
		(net "GMI_CPU0_G1_CPU1_G3_TX_DP<13>")
	)
	(segment
		(start 125.6538 -218.224862)
		(end 124.323602 -220.541342)
		(width 0.14224)
		(layer "In15.Cu")
		(net "GMI_CPU0_G1_CPU1_G3_TX_DP<13>")
	)
	(segment
		(start 124.620274 -233.613452)
		(end 124.644912 -233.627676)
		(width 0.1143)
		(layer "In15.Cu")
		(net "GMI_CPU0_G1_CPU1_G3_TX_DP<13>")
	)
	(segment
		(start 207.01635 -189.00775)
		(end 162.253676 -189.197742)
		(width 0.14224)
		(layer "In15.Cu")
		(net "GMI_CPU0_G1_CPU1_G3_TX_DP<13>")
	)
	(segment
		(start 346.846652 -236.869986)
		(end 346.883228 -236.84865)
		(width 0.1143)
		(layer "In15.Cu")
		(net "GMI_CPU0_G1_CPU1_G3_TX_DP<13>")
	)
	(segment
		(start 124.68352 -222.918782)
		(end 124.652532 -222.936562)
		(width 0.1143)
		(layer "In15.Cu")
		(net "GMI_CPU0_G1_CPU1_G3_TX_DP<13>")
	)
	(segment
		(start 124.647452 -227.149406)
		(end 124.648976 -227.150422)
		(width 0.1143)
		(layer "In15.Cu")
		(net "GMI_CPU0_G1_CPU1_G3_TX_DP<13>")
	)
	(segment
		(start 346.84208 -239.135412)
		(end 346.812362 -239.118394)
		(width 0.1143)
		(layer "In15.Cu")
		(net "GMI_CPU0_G1_CPU1_G3_TX_DP<13>")
	)
	(segment
		(start 124.652532 -243.35232)
		(end 124.68352 -243.3701)
		(width 0.1143)
		(layer "In15.Cu")
		(net "GMI_CPU0_G1_CPU1_G3_TX_DP<13>")
	)
	(segment
		(start 124.612654 -246.568976)
		(end 124.619512 -246.57304)
		(width 0.1143)
		(layer "In15.Cu")
		(net "GMI_CPU0_G1_CPU1_G3_TX_DP<13>")
	)
	(segment
		(start 124.619512 -241.713004)
		(end 124.620274 -241.713512)
		(width 0.1143)
		(layer "In15.Cu")
		(net "GMI_CPU0_G1_CPU1_G3_TX_DP<13>")
	)
	(segment
		(start 346.844112 -238.491522)
		(end 346.845128 -238.491014)
		(width 0.1143)
		(layer "In15.Cu")
		(net "GMI_CPU0_G1_CPU1_G3_TX_DP<13>")
	)
	(segment
		(start 124.65177 -224.557082)
		(end 124.650754 -224.55759)
		(width 0.1143)
		(layer "In15.Cu")
		(net "GMI_CPU0_G1_CPU1_G3_TX_DP<13>")
	)
	(segment
		(start 346.84335 -241.732054)
		(end 346.844112 -241.731546)
		(width 0.1143)
		(layer "In15.Cu")
		(net "GMI_CPU0_G1_CPU1_G3_TX_DP<13>")
	)
	(segment
		(start 346.844112 -243.351558)
		(end 346.845128 -243.35105)
		(width 0.1143)
		(layer "In15.Cu")
		(net "GMI_CPU0_G1_CPU1_G3_TX_DP<13>")
	)
	(segment
		(start 124.68352 -232.6386)
		(end 124.652532 -232.65638)
		(width 0.1143)
		(layer "In15.Cu")
		(net "GMI_CPU0_G1_CPU1_G3_TX_DP<13>")
	)
	(segment
		(start 124.699268 -222.907352)
		(end 124.68352 -222.918782)
		(width 0.1143)
		(layer "In15.Cu")
		(net "GMI_CPU0_G1_CPU1_G3_TX_DP<13>")
	)
	(segment
		(start 303.685194 -189.16904)
		(end 262.665464 -188.790326)
		(width 0.14224)
		(layer "In15.Cu")
		(net "GMI_CPU0_G1_CPU1_G3_TX_DP<13>")
	)
	(segment
		(start 124.323602 -220.541342)
		(end 124.323602 -221.174564)
		(width 0.14224)
		(layer "In15.Cu")
		(net "GMI_CPU0_G1_CPU1_G3_TX_DP<13>")
	)
	(segment
		(start 124.652532 -244.972332)
		(end 124.68352 -244.990112)
		(width 0.1143)
		(layer "In15.Cu")
		(net "GMI_CPU0_G1_CPU1_G3_TX_DP<13>")
	)
	(segment
		(start 124.652532 -232.012236)
		(end 124.68352 -232.030016)
		(width 0.1143)
		(layer "In15.Cu")
		(net "GMI_CPU0_G1_CPU1_G3_TX_DP<13>")
	)
	(segment
		(start 346.883228 -239.159542)
		(end 346.87637 -239.155478)
		(width 0.1143)
		(layer "In15.Cu")
		(net "GMI_CPU0_G1_CPU1_G3_TX_DP<13>")
	)
	(segment
		(start 124.68352 -232.030016)
		(end 124.690124 -232.034842)
		(width 0.1143)
		(layer "In15.Cu")
		(net "GMI_CPU0_G1_CPU1_G3_TX_DP<13>")
	)
	(segment
		(start 345.923108 -223.900746)
		(end 345.925394 -223.899222)
		(width 0.1143)
		(layer "In15.Cu")
		(net "GMI_CPU0_G1_CPU1_G3_TX_DP<13>")
	)
	(segment
		(start 124.68352 -222.310198)
		(end 124.699268 -222.321628)
		(width 0.1143)
		(layer "In15.Cu")
		(net "GMI_CPU0_G1_CPU1_G3_TX_DP<13>")
	)
	(segment
		(start 124.65177 -227.797106)
		(end 124.650754 -227.797614)
		(width 0.1143)
		(layer "In15.Cu")
		(net "GMI_CPU0_G1_CPU1_G3_TX_DP<13>")
	)
	(segment
		(start 345.914472 -223.905572)
		(end 345.919044 -223.903032)
		(width 0.1143)
		(layer "In15.Cu")
		(net "GMI_CPU0_G1_CPU1_G3_TX_DP<13>")
	)
	(segment
		(start 346.844112 -235.251498)
		(end 346.845128 -235.25099)
		(width 0.1143)
		(layer "In15.Cu")
		(net "GMI_CPU0_G1_CPU1_G3_TX_DP<13>")
	)
	(segment
		(start 124.648976 -241.730276)
		(end 124.650754 -241.731292)
		(width 0.1143)
		(layer "In15.Cu")
		(net "GMI_CPU0_G1_CPU1_G3_TX_DP<13>")
	)
	(segment
		(start 124.650754 -234.277408)
		(end 124.64923 -234.278424)
		(width 0.1143)
		(layer "In15.Cu")
		(net "GMI_CPU0_G1_CPU1_G3_TX_DP<13>")
	)
	(segment
		(start 346.845128 -244.971062)
		(end 346.846652 -244.970046)
		(width 0.1143)
		(layer "In15.Cu")
		(net "GMI_CPU0_G1_CPU1_G3_TX_DP<13>")
	)
	(segment
		(start 124.65177 -234.2769)
		(end 124.650754 -234.277408)
		(width 0.1143)
		(layer "In15.Cu")
		(net "GMI_CPU0_G1_CPU1_G3_TX_DP<13>")
	)
	(segment
		(start 345.436444 -222.12808)
		(end 345.402408 -222.108522)
		(width 0.1143)
		(layer "In15.Cu")
		(net "GMI_CPU0_G1_CPU1_G3_TX_DP<13>")
	)
	(segment
		(start 346.875608 -226.195128)
		(end 346.844112 -226.17684)
		(width 0.1143)
		(layer "In15.Cu")
		(net "GMI_CPU0_G1_CPU1_G3_TX_DP<13>")
	)
	(segment
		(start 124.648976 -228.770434)
		(end 124.650754 -228.77145)
		(width 0.1143)
		(layer "In15.Cu")
		(net "GMI_CPU0_G1_CPU1_G3_TX_DP<13>")
	)
	(segment
		(start 346.87637 -232.67543)
		(end 346.875608 -232.674922)
		(width 0.1143)
		(layer "In15.Cu")
		(net "GMI_CPU0_G1_CPU1_G3_TX_DP<13>")
	)
	(segment
		(start 309.09768 -189.169548)
		(end 303.734724 -189.169548)
		(width 0.14224)
		(layer "In15.Cu")
		(net "GMI_CPU0_G1_CPU1_G3_TX_DP<13>")
	)
	(segment
		(start 346.844112 -235.896658)
		(end 346.84335 -235.89615)
		(width 0.1143)
		(layer "In15.Cu")
		(net "GMI_CPU0_G1_CPU1_G3_TX_DP<13>")
	)
	(segment
		(start 124.65177 -223.911922)
		(end 124.652532 -223.91243)
		(width 0.1143)
		(layer "In15.Cu")
		(net "GMI_CPU0_G1_CPU1_G3_TX_DP<13>")
	)
	(segment
		(start 346.844112 -234.276646)
		(end 346.84335 -234.276138)
		(width 0.1143)
		(layer "In15.Cu")
		(net "GMI_CPU0_G1_CPU1_G3_TX_DP<13>")
	)
	(segment
		(start 124.646436 -243.348764)
		(end 124.647452 -243.349272)
		(width 0.1143)
		(layer "In15.Cu")
		(net "GMI_CPU0_G1_CPU1_G3_TX_DP<13>")
	)
	(segment
		(start 124.647452 -233.6292)
		(end 124.648976 -233.630216)
		(width 0.1143)
		(layer "In15.Cu")
		(net "GMI_CPU0_G1_CPU1_G3_TX_DP<13>")
	)
	(segment
		(start 124.612654 -223.889062)
		(end 124.619512 -223.893126)
		(width 0.1143)
		(layer "In15.Cu")
		(net "GMI_CPU0_G1_CPU1_G3_TX_DP<13>")
	)
	(segment
		(start 124.65177 -235.896912)
		(end 124.650754 -235.89742)
		(width 0.1143)
		(layer "In15.Cu")
		(net "GMI_CPU0_G1_CPU1_G3_TX_DP<13>")
	)
	(segment
		(start 345.2368 -220.268038)
		(end 343.254838 -216.08034)
		(width 0.14224)
		(layer "In15.Cu")
		(net "GMI_CPU0_G1_CPU1_G3_TX_DP<13>")
	)
	(segment
		(start 211.800186 -189.850776)
		(end 207.01635 -189.00775)
		(width 0.14224)
		(layer "In15.Cu")
		(net "GMI_CPU0_G1_CPU1_G3_TX_DP<13>")
	)
	(segment
		(start 303.73447 -189.169294)
		(end 303.701196 -189.169294)
		(width 0.14224)
		(layer "In15.Cu")
		(net "GMI_CPU0_G1_CPU1_G3_TX_DP<13>")
	)
	(segment
		(start 124.646436 -228.76891)
		(end 124.647452 -228.769418)
		(width 0.1143)
		(layer "In15.Cu")
		(net "GMI_CPU0_G1_CPU1_G3_TX_DP<13>")
	)
	(segment
		(start 124.612654 -228.749098)
		(end 124.619512 -228.753162)
		(width 0.1143)
		(layer "In15.Cu")
		(net "GMI_CPU0_G1_CPU1_G3_TX_DP<13>")
	)
	(segment
		(start 346.844112 -242.376706)
		(end 346.84335 -242.376198)
		(width 0.1143)
		(layer "In15.Cu")
		(net "GMI_CPU0_G1_CPU1_G3_TX_DP<13>")
	)
	(segment
		(start 124.648976 -223.910398)
		(end 124.650754 -223.911414)
		(width 0.1143)
		(layer "In15.Cu")
		(net "GMI_CPU0_G1_CPU1_G3_TX_DP<13>")
	)
	(segment
		(start 124.65177 -227.151946)
		(end 124.652532 -227.152454)
		(width 0.1143)
		(layer "In15.Cu")
		(net "GMI_CPU0_G1_CPU1_G3_TX_DP<13>")
	)
	(segment
		(start 124.65177 -226.177094)
		(end 124.650754 -226.177602)
		(width 0.1143)
		(layer "In15.Cu")
		(net "GMI_CPU0_G1_CPU1_G3_TX_DP<13>")
	)
	(segment
		(start 346.373958 -225.366834)
		(end 346.343478 -225.349054)
		(width 0.1143)
		(layer "In15.Cu")
		(net "GMI_CPU0_G1_CPU1_G3_TX_DP<13>")
	)
	(segment
		(start 345.921076 -223.901762)
		(end 345.923108 -223.900746)
		(width 0.1143)
		(layer "In15.Cu")
		(net "GMI_CPU0_G1_CPU1_G3_TX_DP<13>")
	)
	(segment
		(start 346.812362 -240.129822)
		(end 346.84335 -240.112042)
		(width 0.1143)
		(layer "In15.Cu")
		(net "GMI_CPU0_G1_CPU1_G3_TX_DP<13>")
	)
	(segment
		(start 124.650754 -225.531426)
		(end 124.65177 -225.531934)
		(width 0.1143)
		(layer "In15.Cu")
		(net "GMI_CPU0_G1_CPU1_G3_TX_DP<13>")
	)
	(segment
		(start 345.936316 -222.955612)
		(end 345.935554 -222.955104)
		(width 0.1143)
		(layer "In15.Cu")
		(net "GMI_CPU0_G1_CPU1_G3_TX_DP<13>")
	)
	(segment
		(start 346.413074 -225.389694)
		(end 346.373958 -225.366834)
		(width 0.1143)
		(layer "In15.Cu")
		(net "GMI_CPU0_G1_CPU1_G3_TX_DP<13>")
	)
	(segment
		(start 345.935554 -224.575116)
		(end 345.904058 -224.556828)
		(width 0.1143)
		(layer "In15.Cu")
		(net "GMI_CPU0_G1_CPU1_G3_TX_DP<13>")
	)
	(segment
		(start 124.65177 -240.756948)
		(end 124.650754 -240.757456)
		(width 0.1143)
		(layer "In15.Cu")
		(net "GMI_CPU0_G1_CPU1_G3_TX_DP<13>")
	)
	(segment
		(start 124.648976 -233.630216)
		(end 124.650754 -233.631232)
		(width 0.1143)
		(layer "In15.Cu")
		(net "GMI_CPU0_G1_CPU1_G3_TX_DP<13>")
	)
	(segment
		(start 124.652532 -228.772466)
		(end 124.65304 -228.77272)
		(width 0.1143)
		(layer "In15.Cu")
		(net "GMI_CPU0_G1_CPU1_G3_TX_DP<13>")
	)
	(segment
		(start 124.650754 -228.77145)
		(end 124.65177 -228.771958)
		(width 0.1143)
		(layer "In15.Cu")
		(net "GMI_CPU0_G1_CPU1_G3_TX_DP<13>")
	)
	(segment
		(start 346.84335 -240.112042)
		(end 346.844112 -240.111534)
		(width 0.1143)
		(layer "In15.Cu")
		(net "GMI_CPU0_G1_CPU1_G3_TX_DP<13>")
	)
	(segment
		(start 346.844112 -227.796852)
		(end 346.812362 -227.778564)
		(width 0.1143)
		(layer "In15.Cu")
		(net "GMI_CPU0_G1_CPU1_G3_TX_DP<13>")
	)
	(segment
		(start 345.935554 -222.955104)
		(end 345.904058 -222.936816)
		(width 0.1143)
		(layer "In15.Cu")
		(net "GMI_CPU0_G1_CPU1_G3_TX_DP<13>")
	)
	(segment
		(start 150.882858 -198.683372)
		(end 149.73173 -199.627236)
		(width 0.14224)
		(layer "In15.Cu")
		(net "GMI_CPU0_G1_CPU1_G3_TX_DP<13>")
	)
	(segment
		(start 346.812362 -235.269786)
		(end 346.84335 -235.252006)
		(width 0.1143)
		(layer "In15.Cu")
		(net "GMI_CPU0_G1_CPU1_G3_TX_DP<13>")
	)
	(segment
		(start 234.011978 -199.051418)
		(end 211.800186 -189.850776)
		(width 0.14224)
		(layer "In15.Cu")
		(net "GMI_CPU0_G1_CPU1_G3_TX_DP<13>")
	)
	(segment
		(start 346.84335 -246.59209)
		(end 346.844112 -246.591582)
		(width 0.1143)
		(layer "In15.Cu")
		(net "GMI_CPU0_G1_CPU1_G3_TX_DP<13>")
	)
	(segment
		(start 124.619512 -227.13315)
		(end 124.620274 -227.133658)
		(width 0.1143)
		(layer "In15.Cu")
		(net "GMI_CPU0_G1_CPU1_G3_TX_DP<13>")
	)
	(segment
		(start 124.652532 -234.276392)
		(end 124.65177 -234.2769)
		(width 0.1143)
		(layer "In15.Cu")
		(net "GMI_CPU0_G1_CPU1_G3_TX_DP<13>")
	)
	(segment
		(start 124.64923 -222.938594)
		(end 124.612654 -222.95993)
		(width 0.1143)
		(layer "In15.Cu")
		(net "GMI_CPU0_G1_CPU1_G3_TX_DP<13>")
	)
	(segment
		(start 124.612654 -236.851444)
		(end 124.632466 -236.861858)
		(width 0.1143)
		(layer "In15.Cu")
		(net "GMI_CPU0_G1_CPU1_G3_TX_DP<13>")
	)
	(segment
		(start 124.619512 -238.47298)
		(end 124.620274 -238.473488)
		(width 0.1143)
		(layer "In15.Cu")
		(net "GMI_CPU0_G1_CPU1_G3_TX_DP<13>")
	)
	(segment
		(start 346.87637 -244.015514)
		(end 346.875608 -244.015006)
		(width 0.1143)
		(layer "In15.Cu")
		(net "GMI_CPU0_G1_CPU1_G3_TX_DP<13>")
	)
	(segment
		(start 124.650754 -232.657396)
		(end 124.64923 -232.658412)
		(width 0.1143)
		(layer "In15.Cu")
		(net "GMI_CPU0_G1_CPU1_G3_TX_DP<13>")
	)
	(segment
		(start 124.68352 -245.598696)
		(end 124.652532 -245.616476)
		(width 0.1143)
		(layer "In15.Cu")
		(net "GMI_CPU0_G1_CPU1_G3_TX_DP<13>")
	)
	(segment
		(start 346.84335 -243.352066)
		(end 346.844112 -243.351558)
		(width 0.1143)
		(layer "In15.Cu")
		(net "GMI_CPU0_G1_CPU1_G3_TX_DP<13>")
	)
	(segment
		(start 345.905074 -223.91116)
		(end 345.906598 -223.910144)
		(width 0.1143)
		(layer "In15.Cu")
		(net "GMI_CPU0_G1_CPU1_G3_TX_DP<13>")
	)
	(segment
		(start 124.612654 -235.228892)
		(end 124.612654 -235.229146)
		(width 0.1143)
		(layer "In15.Cu")
		(net "GMI_CPU0_G1_CPU1_G3_TX_DP<13>")
	)
	(segment
		(start 124.630434 -240.100612)
		(end 124.652278 -240.111788)
		(width 0.1143)
		(layer "In15.Cu")
		(net "GMI_CPU0_G1_CPU1_G3_TX_DP<13>")
	)
	(segment
		(start 346.844112 -237.51667)
		(end 346.84335 -237.516162)
		(width 0.1143)
		(layer "In15.Cu")
		(net "GMI_CPU0_G1_CPU1_G3_TX_DP<13>")
	)
	(segment
		(start 346.846652 -228.77018)
		(end 346.847668 -228.769672)
		(width 0.1143)
		(layer "In15.Cu")
		(net "GMI_CPU0_G1_CPU1_G3_TX_DP<13>")
	)
	(segment
		(start 124.646436 -244.968776)
		(end 124.647452 -244.969284)
		(width 0.1143)
		(layer "In15.Cu")
		(net "GMI_CPU0_G1_CPU1_G3_TX_DP<13>")
	)
	(segment
		(start 149.73173 -199.627236)
		(end 149.731984 -199.627236)
		(width 0.14224)
		(layer "In15.Cu")
		(net "GMI_CPU0_G1_CPU1_G3_TX_DP<13>")
	)
	(segment
		(start 124.65177 -240.757202)
		(end 124.65177 -240.756948)
		(width 0.1143)
		(layer "In15.Cu")
		(net "GMI_CPU0_G1_CPU1_G3_TX_DP<13>")
	)
	(segment
		(start 346.373958 -247.401588)
		(end 346.413074 -247.378728)
		(width 0.1143)
		(layer "In15.Cu")
		(net "GMI_CPU0_G1_CPU1_G3_TX_DP<13>")
	)
	(segment
		(start 124.646436 -225.528886)
		(end 124.647452 -225.529394)
		(width 0.1143)
		(layer "In15.Cu")
		(net "GMI_CPU0_G1_CPU1_G3_TX_DP<13>")
	)
	(segment
		(start 124.648976 -232.010204)
		(end 124.650754 -232.01122)
		(width 0.1143)
		(layer "In15.Cu")
		(net "GMI_CPU0_G1_CPU1_G3_TX_DP<13>")
	)
	(segment
		(start 124.646436 -227.148898)
		(end 124.647452 -227.149406)
		(width 0.1143)
		(layer "In15.Cu")
		(net "GMI_CPU0_G1_CPU1_G3_TX_DP<13>")
	)
	(segment
		(start 124.703332 -224.52457)
		(end 124.68352 -224.538794)
		(width 0.1143)
		(layer "In15.Cu")
		(net "GMI_CPU0_G1_CPU1_G3_TX_DP<13>")
	)
	(segment
		(start 124.620274 -241.713512)
		(end 124.644912 -241.727736)
		(width 0.1143)
		(layer "In15.Cu")
		(net "GMI_CPU0_G1_CPU1_G3_TX_DP<13>")
	)
	(segment
		(start 346.844112 -233.631486)
		(end 346.845128 -233.630978)
		(width 0.1143)
		(layer "In15.Cu")
		(net "GMI_CPU0_G1_CPU1_G3_TX_DP<13>")
	)
	(segment
		(start 346.845128 -246.591074)
		(end 346.846652 -246.590058)
		(width 0.1143)
		(layer "In15.Cu")
		(net "GMI_CPU0_G1_CPU1_G3_TX_DP<13>")
	)
	(segment
		(start 346.845128 -242.377214)
		(end 346.844112 -242.376706)
		(width 0.1143)
		(layer "In15.Cu")
		(net "GMI_CPU0_G1_CPU1_G3_TX_DP<13>")
	)
	(segment
		(start 124.648976 -227.150422)
		(end 124.650754 -227.151438)
		(width 0.1143)
		(layer "In15.Cu")
		(net "GMI_CPU0_G1_CPU1_G3_TX_DP<13>")
	)
	(segment
		(start 124.650754 -237.517432)
		(end 124.64923 -237.518448)
		(width 0.1143)
		(layer "In15.Cu")
		(net "GMI_CPU0_G1_CPU1_G3_TX_DP<13>")
	)
	(segment
		(start 124.612654 -236.848904)
		(end 124.612654 -236.851444)
		(width 0.1143)
		(layer "In15.Cu")
		(net "GMI_CPU0_G1_CPU1_G3_TX_DP<13>")
	)
	(segment
		(start 346.846652 -241.730022)
		(end 346.883228 -241.708686)
		(width 0.1143)
		(layer "In15.Cu")
		(net "GMI_CPU0_G1_CPU1_G3_TX_DP<13>")
	)
	(segment
		(start 346.846652 -238.489998)
		(end 346.883228 -238.468662)
		(width 0.1143)
		(layer "In15.Cu")
		(net "GMI_CPU0_G1_CPU1_G3_TX_DP<13>")
	)
	(segment
		(start 346.84208 -242.375436)
		(end 346.812362 -242.358418)
		(width 0.1143)
		(layer "In15.Cu")
		(net "GMI_CPU0_G1_CPU1_G3_TX_DP<13>")
	)
	(segment
		(start 346.883228 -232.679494)
		(end 346.87637 -232.67543)
		(width 0.1143)
		(layer "In15.Cu")
		(net "GMI_CPU0_G1_CPU1_G3_TX_DP<13>")
	)
	(segment
		(start 346.84208 -245.61546)
		(end 346.812362 -245.598442)
		(width 0.1143)
		(layer "In15.Cu")
		(net "GMI_CPU0_G1_CPU1_G3_TX_DP<13>")
	)
	(segment
		(start 346.845128 -245.617238)
		(end 346.844112 -245.61673)
		(width 0.1143)
		(layer "In15.Cu")
		(net "GMI_CPU0_G1_CPU1_G3_TX_DP<13>")
	)
	(segment
		(start 124.64923 -239.13846)
		(end 124.612654 -239.159796)
		(width 0.1143)
		(layer "In15.Cu")
		(net "GMI_CPU0_G1_CPU1_G3_TX_DP<13>")
	)
	(segment
		(start 124.64923 -245.618508)
		(end 124.612654 -245.639844)
		(width 0.1143)
		(layer "In15.Cu")
		(net "GMI_CPU0_G1_CPU1_G3_TX_DP<13>")
	)
	(segment
		(start 346.812362 -244.989858)
		(end 346.84335 -244.972078)
		(width 0.1143)
		(layer "In15.Cu")
		(net "GMI_CPU0_G1_CPU1_G3_TX_DP<13>")
	)
	(segment
		(start 345.92895 -223.89719)
		(end 345.930982 -223.896174)
		(width 0.1143)
		(layer "In15.Cu")
		(net "GMI_CPU0_G1_CPU1_G3_TX_DP<13>")
	)
	(arc
		(start 124.612654 -226.199954)
		(mid 124.369327 -226.66452)
		(end 124.612654 -227.129086)
		(width 0.1143)
		(layer "In15.Cu")
		(net "GMI_CPU0_G1_CPU1_G3_TX_DP<13>")
	)
	(arc
		(start 124.613162 -222.269558)
		(mid 124.613543 -222.269812)
		(end 124.613924 -222.270066)
		(width 0.1143)
		(layer "In15.Cu")
		(net "GMI_CPU0_G1_CPU1_G3_TX_DP<13>")
	)
	(arc
		(start 124.703332 -223.944434)
		(mid 124.852046 -224.234502)
		(end 124.703332 -224.52457)
		(width 0.1143)
		(layer "In15.Cu")
		(net "GMI_CPU0_G1_CPU1_G3_TX_DP<13>")
	)
	(arc
		(start 346.656406 -246.914162)
		(mid 346.697661 -246.743191)
		(end 346.812362 -246.60987)
		(width 0.1143)
		(layer "In15.Cu")
		(net "GMI_CPU0_G1_CPU1_G3_TX_DP<13>")
	)
	(arc
		(start 346.883228 -236.84865)
		(mid 347.126555 -236.384084)
		(end 346.883228 -235.919518)
		(width 0.1143)
		(layer "In15.Cu")
		(net "GMI_CPU0_G1_CPU1_G3_TX_DP<13>")
	)
	(arc
		(start 124.68352 -233.650028)
		(mid 124.835109 -233.95432)
		(end 124.68352 -234.258612)
		(width 0.1143)
		(layer "In15.Cu")
		(net "GMI_CPU0_G1_CPU1_G3_TX_DP<13>")
	)
	(arc
		(start 346.883228 -231.988614)
		(mid 347.126555 -231.524048)
		(end 346.883228 -231.059482)
		(width 0.1143)
		(layer "In15.Cu")
		(net "GMI_CPU0_G1_CPU1_G3_TX_DP<13>")
	)
	(arc
		(start 346.883228 -243.328698)
		(mid 347.126555 -242.864132)
		(end 346.883228 -242.399566)
		(width 0.1143)
		(layer "In15.Cu")
		(net "GMI_CPU0_G1_CPU1_G3_TX_DP<13>")
	)
	(arc
		(start 124.691902 -227.17633)
		(mid 124.844783 -227.474526)
		(end 124.691902 -227.772722)
		(width 0.1143)
		(layer "In15.Cu")
		(net "GMI_CPU0_G1_CPU1_G3_TX_DP<13>")
	)
	(arc
		(start 124.666756 -246.600218)
		(mid 124.802494 -246.73677)
		(end 124.852176 -246.922798)
		(width 0.1143)
		(layer "In15.Cu")
		(net "GMI_CPU0_G1_CPU1_G3_TX_DP<13>")
	)
	(arc
		(start 124.369322 -229.90429)
		(mid 124.434558 -230.167881)
		(end 124.615194 -230.370634)
		(width 0.1143)
		(layer "In15.Cu")
		(net "GMI_CPU0_G1_CPU1_G3_TX_DP<13>")
	)
	(arc
		(start 124.369322 -221.804484)
		(mid 124.433981 -222.067041)
		(end 124.613162 -222.269558)
		(width 0.1143)
		(layer "In15.Cu")
		(net "GMI_CPU0_G1_CPU1_G3_TX_DP<13>")
	)
	(arc
		(start 345.402408 -222.108522)
		(mid 345.287732 -221.975188)
		(end 345.246452 -221.80423)
		(width 0.1143)
		(layer "In15.Cu")
		(net "GMI_CPU0_G1_CPU1_G3_TX_DP<13>")
	)
	(arc
		(start 124.612654 -231.059736)
		(mid 124.369327 -231.524302)
		(end 124.612654 -231.988868)
		(width 0.1143)
		(layer "In15.Cu")
		(net "GMI_CPU0_G1_CPU1_G3_TX_DP<13>")
	)
	(arc
		(start 124.612654 -237.539784)
		(mid 124.369327 -238.00435)
		(end 124.612654 -238.468916)
		(width 0.1143)
		(layer "In15.Cu")
		(net "GMI_CPU0_G1_CPU1_G3_TX_DP<13>")
	)
	(arc
		(start 124.653548 -230.392986)
		(mid 124.789629 -230.528834)
		(end 124.839476 -230.71455)
		(width 0.1143)
		(layer "In15.Cu")
		(net "GMI_CPU0_G1_CPU1_G3_TX_DP<13>")
	)
	(arc
		(start 124.612654 -240.779808)
		(mid 124.369327 -241.244374)
		(end 124.612654 -241.70894)
		(width 0.1143)
		(layer "In15.Cu")
		(net "GMI_CPU0_G1_CPU1_G3_TX_DP<13>")
	)
	(arc
		(start 124.694696 -243.378228)
		(mid 124.846456 -243.674392)
		(end 124.694696 -243.970556)
		(width 0.1143)
		(layer "In15.Cu")
		(net "GMI_CPU0_G1_CPU1_G3_TX_DP<13>")
	)
	(arc
		(start 346.656406 -229.094284)
		(mid 346.697661 -228.923313)
		(end 346.812362 -228.789992)
		(width 0.1143)
		(layer "In15.Cu")
		(net "GMI_CPU0_G1_CPU1_G3_TX_DP<13>")
	)
	(arc
		(start 345.872308 -224.53854)
		(mid 345.721923 -224.234248)
		(end 345.872308 -223.929956)
		(width 0.1143)
		(layer "In15.Cu")
		(net "GMI_CPU0_G1_CPU1_G3_TX_DP<13>")
	)
	(arc
		(start 124.697236 -238.51997)
		(mid 124.848081 -238.814356)
		(end 124.697236 -239.108742)
		(width 0.1143)
		(layer "In15.Cu")
		(net "GMI_CPU0_G1_CPU1_G3_TX_DP<13>")
	)
	(arc
		(start 124.612654 -245.639844)
		(mid 124.369327 -246.10441)
		(end 124.612654 -246.568976)
		(width 0.1143)
		(layer "In15.Cu")
		(net "GMI_CPU0_G1_CPU1_G3_TX_DP<13>")
	)
	(arc
		(start 125.15342 -247.420384)
		(mid 125.184267 -247.445123)
		(end 125.212348 -247.472962)
		(width 0.1143)
		(layer "In15.Cu")
		(net "GMI_CPU0_G1_CPU1_G3_TX_DP<13>")
	)
	(arc
		(start 346.810584 -231.017064)
		(mid 346.697177 -230.884175)
		(end 346.656406 -230.714296)
		(width 0.1143)
		(layer "In15.Cu")
		(net "GMI_CPU0_G1_CPU1_G3_TX_DP<13>")
	)
	(arc
		(start 346.810584 -229.397052)
		(mid 346.697177 -229.264163)
		(end 346.656406 -229.094284)
		(width 0.1143)
		(layer "In15.Cu")
		(net "GMI_CPU0_G1_CPU1_G3_TX_DP<13>")
	)
	(arc
		(start 124.65304 -228.77272)
		(mid 124.789458 -228.908593)
		(end 124.839476 -229.094538)
		(width 0.1143)
		(layer "In15.Cu")
		(net "GMI_CPU0_G1_CPU1_G3_TX_DP<13>")
	)
	(arc
		(start 346.343478 -225.349054)
		(mid 346.228051 -225.215678)
		(end 346.186506 -225.044254)
		(width 0.1143)
		(layer "In15.Cu")
		(net "GMI_CPU0_G1_CPU1_G3_TX_DP<13>")
	)
	(arc
		(start 345.716352 -222.614236)
		(mid 345.641372 -222.333752)
		(end 345.436444 -222.12808)
		(width 0.1143)
		(layer "In15.Cu")
		(net "GMI_CPU0_G1_CPU1_G3_TX_DP<13>")
	)
	(arc
		(start 346.812362 -234.258358)
		(mid 346.656434 -233.954066)
		(end 346.812362 -233.649774)
		(width 0.1143)
		(layer "In15.Cu")
		(net "GMI_CPU0_G1_CPU1_G3_TX_DP<13>")
	)
	(arc
		(start 124.612654 -234.29976)
		(mid 124.369327 -234.764326)
		(end 124.612654 -235.228892)
		(width 0.1143)
		(layer "In15.Cu")
		(net "GMI_CPU0_G1_CPU1_G3_TX_DP<13>")
	)
	(arc
		(start 346.193364 -247.654318)
		(mid 346.245781 -247.522387)
		(end 346.343478 -247.419368)
		(width 0.1143)
		(layer "In15.Cu")
		(net "GMI_CPU0_G1_CPU1_G3_TX_DP<13>")
	)
	(arc
		(start 346.883228 -244.94871)
		(mid 347.126555 -244.484144)
		(end 346.883228 -244.019578)
		(width 0.1143)
		(layer "In15.Cu")
		(net "GMI_CPU0_G1_CPU1_G3_TX_DP<13>")
	)
	(arc
		(start 124.699268 -222.321628)
		(mid 124.849404 -222.61449)
		(end 124.699268 -222.907352)
		(width 0.1143)
		(layer "In15.Cu")
		(net "GMI_CPU0_G1_CPU1_G3_TX_DP<13>")
	)
	(arc
		(start 346.883228 -246.568722)
		(mid 347.126555 -246.104156)
		(end 346.883228 -245.63959)
		(width 0.1143)
		(layer "In15.Cu")
		(net "GMI_CPU0_G1_CPU1_G3_TX_DP<13>")
	)
	(arc
		(start 346.883228 -235.228638)
		(mid 347.126555 -234.764072)
		(end 346.883228 -234.299506)
		(width 0.1143)
		(layer "In15.Cu")
		(net "GMI_CPU0_G1_CPU1_G3_TX_DP<13>")
	)
	(arc
		(start 125.212348 -247.472962)
		(mid 125.269967 -247.557546)
		(end 125.302518 -247.654572)
		(width 0.1143)
		(layer "In15.Cu")
		(net "GMI_CPU0_G1_CPU1_G3_TX_DP<13>")
	)
	(arc
		(start 124.612654 -244.019832)
		(mid 124.369327 -244.484398)
		(end 124.612654 -244.948964)
		(width 0.1143)
		(layer "In15.Cu")
		(net "GMI_CPU0_G1_CPU1_G3_TX_DP<13>")
	)
	(arc
		(start 124.612654 -222.95993)
		(mid 124.369327 -223.424496)
		(end 124.612654 -223.889062)
		(width 0.1143)
		(layer "In15.Cu")
		(net "GMI_CPU0_G1_CPU1_G3_TX_DP<13>")
	)
	(arc
		(start 346.883228 -240.088674)
		(mid 347.126555 -239.624108)
		(end 346.883228 -239.159542)
		(width 0.1143)
		(layer "In15.Cu")
		(net "GMI_CPU0_G1_CPU1_G3_TX_DP<13>")
	)
	(arc
		(start 346.656406 -230.714296)
		(mid 346.697661 -230.543325)
		(end 346.812362 -230.410004)
		(width 0.1143)
		(layer "In15.Cu")
		(net "GMI_CPU0_G1_CPU1_G3_TX_DP<13>")
	)
	(arc
		(start 124.612654 -227.819966)
		(mid 124.369327 -228.284532)
		(end 124.612654 -228.749098)
		(width 0.1143)
		(layer "In15.Cu")
		(net "GMI_CPU0_G1_CPU1_G3_TX_DP<13>")
	)
	(arc
		(start 345.902788 -222.936054)
		(mid 345.76637 -222.800181)
		(end 345.716352 -222.614236)
		(width 0.1143)
		(layer "In15.Cu")
		(net "GMI_CPU0_G1_CPU1_G3_TX_DP<13>")
	)
	(arc
		(start 346.812362 -235.87837)
		(mid 346.656434 -235.574078)
		(end 346.812362 -235.269786)
		(width 0.1143)
		(layer "In15.Cu")
		(net "GMI_CPU0_G1_CPU1_G3_TX_DP<13>")
	)
	(arc
		(start 124.612654 -232.679748)
		(mid 124.369327 -233.144314)
		(end 124.612654 -233.60888)
		(width 0.1143)
		(layer "In15.Cu")
		(net "GMI_CPU0_G1_CPU1_G3_TX_DP<13>")
	)
	(arc
		(start 346.413074 -247.378728)
		(mid 346.591887 -247.176378)
		(end 346.656406 -246.914162)
		(width 0.1143)
		(layer "In15.Cu")
		(net "GMI_CPU0_G1_CPU1_G3_TX_DP<13>")
	)
	(arc
		(start 346.883228 -227.128832)
		(mid 347.126555 -226.664266)
		(end 346.883228 -226.1997)
		(width 0.1143)
		(layer "In15.Cu")
		(net "GMI_CPU0_G1_CPU1_G3_TX_DP<13>")
	)
	(arc
		(start 124.652278 -235.251752)
		(mid 124.837916 -235.574158)
		(end 124.652532 -235.896658)
		(width 0.1143)
		(layer "In15.Cu")
		(net "GMI_CPU0_G1_CPU1_G3_TX_DP<13>")
	)
	(arc
		(start 124.693172 -244.99697)
		(mid 124.845646 -245.294404)
		(end 124.693172 -245.591838)
		(width 0.1143)
		(layer "In15.Cu")
		(net "GMI_CPU0_G1_CPU1_G3_TX_DP<13>")
	)
	(arc
		(start 124.839476 -229.094538)
		(mid 124.798714 -229.264422)
		(end 124.685298 -229.397306)
		(width 0.1143)
		(layer "In15.Cu")
		(net "GMI_CPU0_G1_CPU1_G3_TX_DP<13>")
	)
	(arc
		(start 346.883228 -241.708686)
		(mid 347.126555 -241.24412)
		(end 346.883228 -240.779554)
		(width 0.1143)
		(layer "In15.Cu")
		(net "GMI_CPU0_G1_CPU1_G3_TX_DP<13>")
	)
	(arc
		(start 124.852176 -246.934228)
		(mid 124.924441 -247.204157)
		(end 125.121924 -247.401842)
		(width 0.1143)
		(layer "In15.Cu")
		(net "GMI_CPU0_G1_CPU1_G3_TX_DP<13>")
	)
	(arc
		(start 346.883228 -228.748844)
		(mid 347.126555 -228.284278)
		(end 346.883228 -227.819712)
		(width 0.1143)
		(layer "In15.Cu")
		(net "GMI_CPU0_G1_CPU1_G3_TX_DP<13>")
	)
	(arc
		(start 346.812362 -227.778564)
		(mid 346.656434 -227.474272)
		(end 346.812362 -227.16998)
		(width 0.1143)
		(layer "In15.Cu")
		(net "GMI_CPU0_G1_CPU1_G3_TX_DP<13>")
	)
	(arc
		(start 345.943174 -223.888808)
		(mid 346.186501 -223.424242)
		(end 345.943174 -222.959676)
		(width 0.1143)
		(layer "In15.Cu")
		(net "GMI_CPU0_G1_CPU1_G3_TX_DP<13>")
	)
	(arc
		(start 124.612654 -239.159796)
		(mid 124.369327 -239.624362)
		(end 124.612654 -240.088928)
		(width 0.1143)
		(layer "In15.Cu")
		(net "GMI_CPU0_G1_CPU1_G3_TX_DP<13>")
	)
	(arc
		(start 124.612654 -242.39982)
		(mid 124.369327 -242.864386)
		(end 124.612654 -243.328952)
		(width 0.1143)
		(layer "In15.Cu")
		(net "GMI_CPU0_G1_CPU1_G3_TX_DP<13>")
	)
	(arc
		(start 347.12656 -229.904036)
		(mid 347.062045 -229.641817)
		(end 346.883228 -229.43947)
		(width 0.1143)
		(layer "In15.Cu")
		(net "GMI_CPU0_G1_CPU1_G3_TX_DP<13>")
	)
	(arc
		(start 346.883228 -233.608626)
		(mid 347.126555 -233.14406)
		(end 346.883228 -232.679494)
		(width 0.1143)
		(layer "In15.Cu")
		(net "GMI_CPU0_G1_CPU1_G3_TX_DP<13>")
	)
	(arc
		(start 124.690124 -232.034842)
		(mid 124.843614 -232.334308)
		(end 124.690124 -232.633774)
		(width 0.1143)
		(layer "In15.Cu")
		(net "GMI_CPU0_G1_CPU1_G3_TX_DP<13>")
	)
	(arc
		(start 124.652278 -236.871764)
		(mid 124.837916 -237.194344)
		(end 124.652278 -237.516924)
		(width 0.1143)
		(layer "In15.Cu")
		(net "GMI_CPU0_G1_CPU1_G3_TX_DP<13>")
	)
	(arc
		(start 346.812362 -240.738406)
		(mid 346.656434 -240.434114)
		(end 346.812362 -240.129822)
		(width 0.1143)
		(layer "In15.Cu")
		(net "GMI_CPU0_G1_CPU1_G3_TX_DP<13>")
	)
	(arc
		(start 346.656406 -225.85426)
		(mid 346.591891 -225.592041)
		(end 346.413074 -225.389694)
		(width 0.1143)
		(layer "In15.Cu")
		(net "GMI_CPU0_G1_CPU1_G3_TX_DP<13>")
	)
	(arc
		(start 346.812362 -243.97843)
		(mid 346.656434 -243.674138)
		(end 346.812362 -243.369846)
		(width 0.1143)
		(layer "In15.Cu")
		(net "GMI_CPU0_G1_CPU1_G3_TX_DP<13>")
	)
	(arc
		(start 346.812362 -232.638346)
		(mid 346.656434 -232.334054)
		(end 346.812362 -232.029762)
		(width 0.1143)
		(layer "In15.Cu")
		(net "GMI_CPU0_G1_CPU1_G3_TX_DP<13>")
	)
	(arc
		(start 124.839476 -230.71455)
		(mid 124.798714 -230.884434)
		(end 124.685298 -231.017318)
		(width 0.1143)
		(layer "In15.Cu")
		(net "GMI_CPU0_G1_CPU1_G3_TX_DP<13>")
	)
	(arc
		(start 346.812362 -226.158552)
		(mid 346.697686 -226.025218)
		(end 346.656406 -225.85426)
		(width 0.1143)
		(layer "In15.Cu")
		(net "GMI_CPU0_G1_CPU1_G3_TX_DP<13>")
	)
	(arc
		(start 346.880688 -230.37038)
		(mid 347.06134 -230.167635)
		(end 347.12656 -229.904036)
		(width 0.1143)
		(layer "In15.Cu")
		(net "GMI_CPU0_G1_CPU1_G3_TX_DP<13>")
	)
	(arc
		(start 346.812362 -245.598442)
		(mid 346.656434 -245.29415)
		(end 346.812362 -244.989858)
		(width 0.1143)
		(layer "In15.Cu")
		(net "GMI_CPU0_G1_CPU1_G3_TX_DP<13>")
	)
	(arc
		(start 346.186506 -225.044254)
		(mid 346.121991 -224.782035)
		(end 345.943174 -224.579688)
		(width 0.1143)
		(layer "In15.Cu")
		(net "GMI_CPU0_G1_CPU1_G3_TX_DP<13>")
	)
	(arc
		(start 346.812362 -237.498382)
		(mid 346.656434 -237.19409)
		(end 346.812362 -236.889798)
		(width 0.1143)
		(layer "In15.Cu")
		(net "GMI_CPU0_G1_CPU1_G3_TX_DP<13>")
	)
	(arc
		(start 124.69368 -241.757454)
		(mid 124.845847 -242.05438)
		(end 124.69368 -242.351306)
		(width 0.1143)
		(layer "In15.Cu")
		(net "GMI_CPU0_G1_CPU1_G3_TX_DP<13>")
	)
	(arc
		(start 124.612654 -229.439724)
		(mid 124.433841 -229.642074)
		(end 124.369322 -229.90429)
		(width 0.1143)
		(layer "In15.Cu")
		(net "GMI_CPU0_G1_CPU1_G3_TX_DP<13>")
	)
	(arc
		(start 124.612654 -224.579942)
		(mid 124.369327 -225.044508)
		(end 124.612654 -225.509074)
		(width 0.1143)
		(layer "In15.Cu")
		(net "GMI_CPU0_G1_CPU1_G3_TX_DP<13>")
	)
	(arc
		(start 124.612654 -235.919772)
		(mid 124.369327 -236.384338)
		(end 124.612654 -236.848904)
		(width 0.1143)
		(layer "In15.Cu")
		(net "GMI_CPU0_G1_CPU1_G3_TX_DP<13>")
	)
	(arc
		(start 124.652278 -240.111788)
		(mid 124.837916 -240.434368)
		(end 124.652278 -240.756948)
		(width 0.1143)
		(layer "In15.Cu")
		(net "GMI_CPU0_G1_CPU1_G3_TX_DP<13>")
	)
	(arc
		(start 346.812362 -242.358418)
		(mid 346.656434 -242.054126)
		(end 346.812362 -241.749834)
		(width 0.1143)
		(layer "In15.Cu")
		(net "GMI_CPU0_G1_CPU1_G3_TX_DP<13>")
	)
	(arc
		(start 346.883228 -238.468662)
		(mid 347.126555 -238.004096)
		(end 346.883228 -237.53953)
		(width 0.1143)
		(layer "In15.Cu")
		(net "GMI_CPU0_G1_CPU1_G3_TX_DP<13>")
	)
	(arc
		(start 346.812362 -239.118394)
		(mid 346.656434 -238.814102)
		(end 346.812362 -238.50981)
		(width 0.1143)
		(layer "In15.Cu")
		(net "GMI_CPU0_G1_CPU1_G3_TX_DP<13>")
	)
	(arc
		(start 124.69368 -225.557588)
		(mid 124.845847 -225.854514)
		(end 124.69368 -226.15144)
		(width 0.1143)
		(layer "In15.Cu")
		(net "GMI_CPU0_G1_CPU1_G3_TX_DP<13>")
	)
	(segment
		(start 349.847916 -246.370094)
		(end 349.381064 -246.104156)
		(width 0.12954)
		(layer "F.Cu")
		(net "GMI_CPU0_G1_CPU1_G3_TX_DP<12>")
	)
	(segment
		(start 121.647966 -246.370348)
		(end 122.114818 -246.10441)
		(width 0.12954)
		(layer "F.Cu")
		(net "GMI_CPU0_G1_CPU1_G3_TX_DP<12>")
	)
	(segment
		(start 346.413074 -222.14967)
		(end 346.34297 -222.108776)
		(width 0.1143)
		(layer "In15.Cu")
		(net "GMI_CPU0_G1_CPU1_G3_TX_DP<12>")
	)
	(segment
		(start 347.753432 -243.369338)
		(end 347.783912 -243.351558)
		(width 0.1143)
		(layer "In15.Cu")
		(net "GMI_CPU0_G1_CPU1_G3_TX_DP<12>")
	)
	(segment
		(start 123.71197 -227.151946)
		(end 123.74245 -227.169726)
		(width 0.1143)
		(layer "In15.Cu")
		(net "GMI_CPU0_G1_CPU1_G3_TX_DP<12>")
	)
	(segment
		(start 123.71197 -222.93707)
		(end 123.672854 -222.95993)
		(width 0.1143)
		(layer "In15.Cu")
		(net "GMI_CPU0_G1_CPU1_G3_TX_DP<12>")
	)
	(segment
		(start 123.672854 -243.328952)
		(end 123.71197 -243.351812)
		(width 0.1143)
		(layer "In15.Cu")
		(net "GMI_CPU0_G1_CPU1_G3_TX_DP<12>")
	)
	(segment
		(start 303.706784 -188.201808)
		(end 262.7376 -187.823348)
		(width 0.14224)
		(layer "In15.Cu")
		(net "GMI_CPU0_G1_CPU1_G3_TX_DP<12>")
	)
	(segment
		(start 347.753432 -238.509302)
		(end 347.783912 -238.491522)
		(width 0.1143)
		(layer "In15.Cu")
		(net "GMI_CPU0_G1_CPU1_G3_TX_DP<12>")
	)
	(segment
		(start 347.753432 -233.649266)
		(end 347.783912 -233.631486)
		(width 0.1143)
		(layer "In15.Cu")
		(net "GMI_CPU0_G1_CPU1_G3_TX_DP<12>")
	)
	(segment
		(start 347.316552 -225.368358)
		(end 347.315028 -225.367342)
		(width 0.1143)
		(layer "In15.Cu")
		(net "GMI_CPU0_G1_CPU1_G3_TX_DP<12>")
	)
	(segment
		(start 348.76232 -245.639082)
		(end 348.723458 -245.616476)
		(width 0.1143)
		(layer "In15.Cu")
		(net "GMI_CPU0_G1_CPU1_G3_TX_DP<12>")
	)
	(segment
		(start 123.273566 -244.78869)
		(end 123.242578 -244.80647)
		(width 0.1143)
		(layer "In15.Cu")
		(net "GMI_CPU0_G1_CPU1_G3_TX_DP<12>")
	)
	(segment
		(start 347.823028 -227.819712)
		(end 347.783912 -227.796852)
		(width 0.1143)
		(layer "In15.Cu")
		(net "GMI_CPU0_G1_CPU1_G3_TX_DP<12>")
	)
	(segment
		(start 123.71197 -224.557082)
		(end 123.672854 -224.579942)
		(width 0.1143)
		(layer "In15.Cu")
		(net "GMI_CPU0_G1_CPU1_G3_TX_DP<12>")
	)
	(segment
		(start 347.783912 -233.631486)
		(end 347.823028 -233.608626)
		(width 0.1143)
		(layer "In15.Cu")
		(net "GMI_CPU0_G1_CPU1_G3_TX_DP<12>")
	)
	(segment
		(start 347.783912 -239.136682)
		(end 347.753432 -239.118902)
		(width 0.1143)
		(layer "In15.Cu")
		(net "GMI_CPU0_G1_CPU1_G3_TX_DP<12>")
	)
	(segment
		(start 150.220934 -197.834758)
		(end 147.870418 -199.76211)
		(width 0.14224)
		(layer "In15.Cu")
		(net "GMI_CPU0_G1_CPU1_G3_TX_DP<12>")
	)
	(segment
		(start 346.882974 -222.959676)
		(end 346.843858 -222.936816)
		(width 0.1143)
		(layer "In15.Cu")
		(net "GMI_CPU0_G1_CPU1_G3_TX_DP<12>")
	)
	(segment
		(start 347.783912 -227.151692)
		(end 347.823028 -227.128832)
		(width 0.1143)
		(layer "In15.Cu")
		(net "GMI_CPU0_G1_CPU1_G3_TX_DP<12>")
	)
	(segment
		(start 347.783912 -236.87151)
		(end 347.823028 -236.84865)
		(width 0.1143)
		(layer "In15.Cu")
		(net "GMI_CPU0_G1_CPU1_G3_TX_DP<12>")
	)
	(segment
		(start 236.351064 -198.509636)
		(end 235.326428 -198.329042)
		(width 0.14224)
		(layer "In15.Cu")
		(net "GMI_CPU0_G1_CPU1_G3_TX_DP<12>")
	)
	(segment
		(start 347.783912 -227.796852)
		(end 347.753432 -227.779072)
		(width 0.1143)
		(layer "In15.Cu")
		(net "GMI_CPU0_G1_CPU1_G3_TX_DP<12>")
	)
	(segment
		(start 347.783912 -243.996718)
		(end 347.753432 -243.978938)
		(width 0.1143)
		(layer "In15.Cu")
		(net "GMI_CPU0_G1_CPU1_G3_TX_DP<12>")
	)
	(segment
		(start 347.783912 -226.17684)
		(end 347.753432 -226.15906)
		(width 0.1143)
		(layer "In15.Cu")
		(net "GMI_CPU0_G1_CPU1_G3_TX_DP<12>")
	)
	(segment
		(start 347.783912 -229.41661)
		(end 347.7514 -229.397814)
		(width 0.1143)
		(layer "In15.Cu")
		(net "GMI_CPU0_G1_CPU1_G3_TX_DP<12>")
	)
	(segment
		(start 123.71197 -240.756948)
		(end 123.672854 -240.779808)
		(width 0.1143)
		(layer "In15.Cu")
		(net "GMI_CPU0_G1_CPU1_G3_TX_DP<12>")
	)
	(segment
		(start 123.71197 -242.37696)
		(end 123.672854 -242.39982)
		(width 0.1143)
		(layer "In15.Cu")
		(net "GMI_CPU0_G1_CPU1_G3_TX_DP<12>")
	)
	(segment
		(start 347.783912 -235.896658)
		(end 347.753432 -235.878878)
		(width 0.1143)
		(layer "In15.Cu")
		(net "GMI_CPU0_G1_CPU1_G3_TX_DP<12>")
	)
	(segment
		(start 346.18168 -220.016578)
		(end 344.061034 -215.535764)
		(width 0.14224)
		(layer "In15.Cu")
		(net "GMI_CPU0_G1_CPU1_G3_TX_DP<12>")
	)
	(segment
		(start 123.71197 -243.996972)
		(end 123.672854 -244.019832)
		(width 0.1143)
		(layer "In15.Cu")
		(net "GMI_CPU0_G1_CPU1_G3_TX_DP<12>")
	)
	(segment
		(start 346.13596 -221.128844)
		(end 346.18168 -221.083124)
		(width 0.1143)
		(layer "In15.Cu")
		(net "GMI_CPU0_G1_CPU1_G3_TX_DP<12>")
	)
	(segment
		(start 123.383548 -220.29293)
		(end 123.383548 -220.991938)
		(width 0.14224)
		(layer "In15.Cu")
		(net "GMI_CPU0_G1_CPU1_G3_TX_DP<12>")
	)
	(segment
		(start 347.783912 -232.656634)
		(end 347.753432 -232.638854)
		(width 0.1143)
		(layer "In15.Cu")
		(net "GMI_CPU0_G1_CPU1_G3_TX_DP<12>")
	)
	(segment
		(start 347.823028 -235.919518)
		(end 347.783912 -235.896658)
		(width 0.1143)
		(layer "In15.Cu")
		(net "GMI_CPU0_G1_CPU1_G3_TX_DP<12>")
	)
	(segment
		(start 122.802396 -245.599204)
		(end 122.771916 -245.616984)
		(width 0.1143)
		(layer "In15.Cu")
		(net "GMI_CPU0_G1_CPU1_G3_TX_DP<12>")
	)
	(segment
		(start 123.71197 -237.516924)
		(end 123.672854 -237.539784)
		(width 0.1143)
		(layer "In15.Cu")
		(net "GMI_CPU0_G1_CPU1_G3_TX_DP<12>")
	)
	(segment
		(start 160.963864 -189.025784)
		(end 160.963356 -189.026038)
		(width 0.14224)
		(layer "In15.Cu")
		(net "GMI_CPU0_G1_CPU1_G3_TX_DP<12>")
	)
	(segment
		(start 309.435754 -188.201808)
		(end 303.706784 -188.201808)
		(width 0.14224)
		(layer "In15.Cu")
		(net "GMI_CPU0_G1_CPU1_G3_TX_DP<12>")
	)
	(segment
		(start 123.74245 -239.119156)
		(end 123.71197 -239.136936)
		(width 0.1143)
		(layer "In15.Cu")
		(net "GMI_CPU0_G1_CPU1_G3_TX_DP<12>")
	)
	(segment
		(start 123.71197 -223.911922)
		(end 123.74245 -223.929702)
		(width 0.1143)
		(layer "In15.Cu")
		(net "GMI_CPU0_G1_CPU1_G3_TX_DP<12>")
	)
	(segment
		(start 123.744482 -231.01808)
		(end 123.71197 -231.036876)
		(width 0.1143)
		(layer "In15.Cu")
		(net "GMI_CPU0_G1_CPU1_G3_TX_DP<12>")
	)
	(segment
		(start 347.783912 -235.251498)
		(end 347.823028 -235.228638)
		(width 0.1143)
		(layer "In15.Cu")
		(net "GMI_CPU0_G1_CPU1_G3_TX_DP<12>")
	)
	(segment
		(start 347.783912 -232.011474)
		(end 347.823028 -231.988614)
		(width 0.1143)
		(layer "In15.Cu")
		(net "GMI_CPU0_G1_CPU1_G3_TX_DP<12>")
	)
	(segment
		(start 347.823028 -234.299506)
		(end 347.783912 -234.276646)
		(width 0.1143)
		(layer "In15.Cu")
		(net "GMI_CPU0_G1_CPU1_G3_TX_DP<12>")
	)
	(segment
		(start 123.672854 -235.228892)
		(end 123.71197 -235.251752)
		(width 0.1143)
		(layer "In15.Cu")
		(net "GMI_CPU0_G1_CPU1_G3_TX_DP<12>")
	)
	(segment
		(start 262.7376 -187.823348)
		(end 250.57608 -189.96787)
		(width 0.14224)
		(layer "In15.Cu")
		(net "GMI_CPU0_G1_CPU1_G3_TX_DP<12>")
	)
	(segment
		(start 123.71197 -232.656888)
		(end 123.672854 -232.679748)
		(width 0.1143)
		(layer "In15.Cu")
		(net "GMI_CPU0_G1_CPU1_G3_TX_DP<12>")
	)
	(segment
		(start 123.74245 -240.739168)
		(end 123.71197 -240.756948)
		(width 0.1143)
		(layer "In15.Cu")
		(net "GMI_CPU0_G1_CPU1_G3_TX_DP<12>")
	)
	(segment
		(start 347.753432 -241.749326)
		(end 347.783912 -241.731546)
		(width 0.1143)
		(layer "In15.Cu")
		(net "GMI_CPU0_G1_CPU1_G3_TX_DP<12>")
	)
	(segment
		(start 123.71197 -227.797106)
		(end 123.672854 -227.819966)
		(width 0.1143)
		(layer "In15.Cu")
		(net "GMI_CPU0_G1_CPU1_G3_TX_DP<12>")
	)
	(segment
		(start 123.674886 -229.4382)
		(end 123.672854 -229.439724)
		(width 0.1143)
		(layer "In15.Cu")
		(net "GMI_CPU0_G1_CPU1_G3_TX_DP<12>")
	)
	(segment
		(start 123.71197 -235.896912)
		(end 123.672854 -235.919772)
		(width 0.1143)
		(layer "In15.Cu")
		(net "GMI_CPU0_G1_CPU1_G3_TX_DP<12>")
	)
	(segment
		(start 123.71197 -239.136936)
		(end 123.672854 -239.159796)
		(width 0.1143)
		(layer "In15.Cu")
		(net "GMI_CPU0_G1_CPU1_G3_TX_DP<12>")
	)
	(segment
		(start 347.823028 -231.059482)
		(end 347.783912 -231.036622)
		(width 0.1143)
		(layer "In15.Cu")
		(net "GMI_CPU0_G1_CPU1_G3_TX_DP<12>")
	)
	(segment
		(start 123.71197 -229.416864)
		(end 123.674886 -229.4382)
		(width 0.1143)
		(layer "In15.Cu")
		(net "GMI_CPU0_G1_CPU1_G3_TX_DP<12>")
	)
	(segment
		(start 123.74245 -224.539302)
		(end 123.71197 -224.557082)
		(width 0.1143)
		(layer "In15.Cu")
		(net "GMI_CPU0_G1_CPU1_G3_TX_DP<12>")
	)
	(segment
		(start 239.058958 -198.032116)
		(end 236.351064 -198.509636)
		(width 0.14224)
		(layer "In15.Cu")
		(net "GMI_CPU0_G1_CPU1_G3_TX_DP<12>")
	)
	(segment
		(start 349.083122 -246.104156)
		(end 349.000318 -246.021352)
		(width 0.1143)
		(layer "In15.Cu")
		(net "GMI_CPU0_G1_CPU1_G3_TX_DP<12>")
	)
	(segment
		(start 347.309694 -225.364294)
		(end 347.308678 -225.363786)
		(width 0.1143)
		(layer "In15.Cu")
		(net "GMI_CPU0_G1_CPU1_G3_TX_DP<12>")
	)
	(segment
		(start 347.823028 -239.159542)
		(end 347.783912 -239.136682)
		(width 0.1143)
		(layer "In15.Cu")
		(net "GMI_CPU0_G1_CPU1_G3_TX_DP<12>")
	)
	(segment
		(start 347.308678 -225.363786)
		(end 347.282262 -225.348546)
		(width 0.1143)
		(layer "In15.Cu")
		(net "GMI_CPU0_G1_CPU1_G3_TX_DP<12>")
	)
	(segment
		(start 161.890202 -188.266324)
		(end 160.963864 -189.025784)
		(width 0.14224)
		(layer "In15.Cu")
		(net "GMI_CPU0_G1_CPU1_G3_TX_DP<12>")
	)
	(segment
		(start 123.71197 -241.7318)
		(end 123.74245 -241.74958)
		(width 0.1143)
		(layer "In15.Cu")
		(net "GMI_CPU0_G1_CPU1_G3_TX_DP<12>")
	)
	(segment
		(start 347.310456 -225.364802)
		(end 347.309694 -225.364294)
		(width 0.1143)
		(layer "In15.Cu")
		(net "GMI_CPU0_G1_CPU1_G3_TX_DP<12>")
	)
	(segment
		(start 123.672854 -225.509074)
		(end 123.71197 -225.531934)
		(width 0.1143)
		(layer "In15.Cu")
		(net "GMI_CPU0_G1_CPU1_G3_TX_DP<12>")
	)
	(segment
		(start 123.383548 -221.020386)
		(end 123.429268 -221.066106)
		(width 0.1143)
		(layer "In15.Cu")
		(net "GMI_CPU0_G1_CPU1_G3_TX_DP<12>")
	)
	(segment
		(start 123.74245 -232.639108)
		(end 123.71197 -232.656888)
		(width 0.1143)
		(layer "In15.Cu")
		(net "GMI_CPU0_G1_CPU1_G3_TX_DP<12>")
	)
	(segment
		(start 123.71197 -238.491776)
		(end 123.74245 -238.509556)
		(width 0.1143)
		(layer "In15.Cu")
		(net "GMI_CPU0_G1_CPU1_G3_TX_DP<12>")
	)
	(segment
		(start 123.429268 -221.066106)
		(end 123.429268 -221.119954)
		(width 0.1143)
		(layer "In15.Cu")
		(net "GMI_CPU0_G1_CPU1_G3_TX_DP<12>")
	)
	(segment
		(start 123.74245 -237.499144)
		(end 123.71197 -237.516924)
		(width 0.1143)
		(layer "In15.Cu")
		(net "GMI_CPU0_G1_CPU1_G3_TX_DP<12>")
	)
	(segment
		(start 346.843858 -224.556828)
		(end 346.813378 -224.539048)
		(width 0.1143)
		(layer "In15.Cu")
		(net "GMI_CPU0_G1_CPU1_G3_TX_DP<12>")
	)
	(segment
		(start 344.061034 -215.535764)
		(end 318.94907 -194.944746)
		(width 0.14224)
		(layer "In15.Cu")
		(net "GMI_CPU0_G1_CPU1_G3_TX_DP<12>")
	)
	(segment
		(start 347.753432 -232.029254)
		(end 347.783912 -232.011474)
		(width 0.1143)
		(layer "In15.Cu")
		(net "GMI_CPU0_G1_CPU1_G3_TX_DP<12>")
	)
	(segment
		(start 123.672854 -228.749098)
		(end 123.71197 -228.771958)
		(width 0.1143)
		(layer "In15.Cu")
		(net "GMI_CPU0_G1_CPU1_G3_TX_DP<12>")
	)
	(segment
		(start 123.672854 -238.468916)
		(end 123.71197 -238.491776)
		(width 0.1143)
		(layer "In15.Cu")
		(net "GMI_CPU0_G1_CPU1_G3_TX_DP<12>")
	)
	(segment
		(start 346.13596 -221.308676)
		(end 346.13596 -221.128844)
		(width 0.1143)
		(layer "In15.Cu")
		(net "GMI_CPU0_G1_CPU1_G3_TX_DP<12>")
	)
	(segment
		(start 347.783912 -240.111534)
		(end 347.823028 -240.088674)
		(width 0.1143)
		(layer "In15.Cu")
		(net "GMI_CPU0_G1_CPU1_G3_TX_DP<12>")
	)
	(segment
		(start 347.31198 -225.365564)
		(end 347.310456 -225.364802)
		(width 0.1143)
		(layer "In15.Cu")
		(net "GMI_CPU0_G1_CPU1_G3_TX_DP<12>")
	)
	(segment
		(start 347.753432 -235.269278)
		(end 347.783912 -235.251498)
		(width 0.1143)
		(layer "In15.Cu")
		(net "GMI_CPU0_G1_CPU1_G3_TX_DP<12>")
	)
	(segment
		(start 159.58185 -190.159132)
		(end 150.22068 -197.834758)
		(width 0.14224)
		(layer "In15.Cu")
		(net "GMI_CPU0_G1_CPU1_G3_TX_DP<12>")
	)
	(segment
		(start 347.823028 -244.019578)
		(end 347.783912 -243.996718)
		(width 0.1143)
		(layer "In15.Cu")
		(net "GMI_CPU0_G1_CPU1_G3_TX_DP<12>")
	)
	(segment
		(start 122.495564 -246.021606)
		(end 122.41276 -246.10441)
		(width 0.1143)
		(layer "In15.Cu")
		(net "GMI_CPU0_G1_CPU1_G3_TX_DP<12>")
	)
	(segment
		(start 123.239276 -244.808502)
		(end 123.2027 -244.829838)
		(width 0.1143)
		(layer "In15.Cu")
		(net "GMI_CPU0_G1_CPU1_G3_TX_DP<12>")
	)
	(segment
		(start 123.71197 -231.036876)
		(end 123.672854 -231.059736)
		(width 0.1143)
		(layer "In15.Cu")
		(net "GMI_CPU0_G1_CPU1_G3_TX_DP<12>")
	)
	(segment
		(start 348.548706 -245.3132)
		(end 348.548706 -245.303548)
		(width 0.1143)
		(layer "In15.Cu")
		(net "GMI_CPU0_G1_CPU1_G3_TX_DP<12>")
	)
	(segment
		(start 123.673616 -222.270066)
		(end 123.743212 -222.310198)
		(width 0.1143)
		(layer "In15.Cu")
		(net "GMI_CPU0_G1_CPU1_G3_TX_DP<12>")
	)
	(segment
		(start 160.963356 -189.026038)
		(end 159.582104 -190.158624)
		(width 0.14224)
		(layer "In15.Cu")
		(net "GMI_CPU0_G1_CPU1_G3_TX_DP<12>")
	)
	(segment
		(start 347.823028 -242.399566)
		(end 347.783912 -242.376706)
		(width 0.1143)
		(layer "In15.Cu")
		(net "GMI_CPU0_G1_CPU1_G3_TX_DP<12>")
	)
	(segment
		(start 123.71197 -234.2769)
		(end 123.672854 -234.29976)
		(width 0.1143)
		(layer "In15.Cu")
		(net "GMI_CPU0_G1_CPU1_G3_TX_DP<12>")
	)
	(segment
		(start 123.71197 -235.251752)
		(end 123.74245 -235.269532)
		(width 0.1143)
		(layer "In15.Cu")
		(net "GMI_CPU0_G1_CPU1_G3_TX_DP<12>")
	)
	(segment
		(start 347.783912 -242.376706)
		(end 347.753432 -242.358926)
		(width 0.1143)
		(layer "In15.Cu")
		(net "GMI_CPU0_G1_CPU1_G3_TX_DP<12>")
	)
	(segment
		(start 347.783912 -243.351558)
		(end 347.823028 -243.328698)
		(width 0.1143)
		(layer "In15.Cu")
		(net "GMI_CPU0_G1_CPU1_G3_TX_DP<12>")
	)
	(segment
		(start 123.672854 -233.60888)
		(end 123.71197 -233.63174)
		(width 0.1143)
		(layer "In15.Cu")
		(net "GMI_CPU0_G1_CPU1_G3_TX_DP<12>")
	)
	(segment
		(start 346.186252 -221.80423)
		(end 346.186252 -221.358968)
		(width 0.1143)
		(layer "In15.Cu")
		(net "GMI_CPU0_G1_CPU1_G3_TX_DP<12>")
	)
	(segment
		(start 123.743212 -222.310198)
		(end 123.744228 -222.31096)
		(width 0.1143)
		(layer "In15.Cu")
		(net "GMI_CPU0_G1_CPU1_G3_TX_DP<12>")
	)
	(segment
		(start 309.508906 -188.25337)
		(end 309.508906 -188.253116)
		(width 0.14224)
		(layer "In15.Cu")
		(net "GMI_CPU0_G1_CPU1_G3_TX_DP<12>")
	)
	(segment
		(start 159.582104 -190.158624)
		(end 159.58185 -190.159132)
		(width 0.14224)
		(layer "In15.Cu")
		(net "GMI_CPU0_G1_CPU1_G3_TX_DP<12>")
	)
	(segment
		(start 123.672854 -236.848904)
		(end 123.71197 -236.871764)
		(width 0.1143)
		(layer "In15.Cu")
		(net "GMI_CPU0_G1_CPU1_G3_TX_DP<12>")
	)
	(segment
		(start 318.94907 -194.944746)
		(end 318.819784 -194.815714)
		(width 0.14224)
		(layer "In15.Cu")
		(net "GMI_CPU0_G1_CPU1_G3_TX_DP<12>")
	)
	(segment
		(start 150.22068 -197.834758)
		(end 150.220934 -197.834758)
		(width 0.14224)
		(layer "In15.Cu")
		(net "GMI_CPU0_G1_CPU1_G3_TX_DP<12>")
	)
	(segment
		(start 123.429014 -221.120208)
		(end 123.429014 -221.804484)
		(width 0.1143)
		(layer "In15.Cu")
		(net "GMI_CPU0_G1_CPU1_G3_TX_DP<12>")
	)
	(segment
		(start 347.31325 -225.366326)
		(end 347.31198 -225.365564)
		(width 0.1143)
		(layer "In15.Cu")
		(net "GMI_CPU0_G1_CPU1_G3_TX_DP<12>")
	)
	(segment
		(start 347.783912 -228.771704)
		(end 347.82252 -228.749098)
		(width 0.1143)
		(layer "In15.Cu")
		(net "GMI_CPU0_G1_CPU1_G3_TX_DP<12>")
	)
	(segment
		(start 348.265242 -244.813328)
		(end 348.222062 -244.788182)
		(width 0.1143)
		(layer "In15.Cu")
		(net "GMI_CPU0_G1_CPU1_G3_TX_DP<12>")
	)
	(segment
		(start 123.672854 -231.988868)
		(end 123.71197 -232.011728)
		(width 0.1143)
		(layer "In15.Cu")
		(net "GMI_CPU0_G1_CPU1_G3_TX_DP<12>")
	)
	(segment
		(start 123.74245 -226.159314)
		(end 123.71197 -226.177094)
		(width 0.1143)
		(layer "In15.Cu")
		(net "GMI_CPU0_G1_CPU1_G3_TX_DP<12>")
	)
	(segment
		(start 250.57608 -189.96787)
		(end 239.058958 -198.032116)
		(width 0.14224)
		(layer "In15.Cu")
		(net "GMI_CPU0_G1_CPU1_G3_TX_DP<12>")
	)
	(segment
		(start 347.753432 -240.129314)
		(end 347.783912 -240.111534)
		(width 0.1143)
		(layer "In15.Cu")
		(net "GMI_CPU0_G1_CPU1_G3_TX_DP<12>")
	)
	(segment
		(start 346.34297 -222.108776)
		(end 346.342716 -222.108776)
		(width 0.1143)
		(layer "In15.Cu")
		(net "GMI_CPU0_G1_CPU1_G3_TX_DP<12>")
	)
	(segment
		(start 309.508906 -188.253116)
		(end 309.435754 -188.201808)
		(width 0.14224)
		(layer "In15.Cu")
		(net "GMI_CPU0_G1_CPU1_G3_TX_DP<12>")
	)
	(segment
		(start 125.084586 -217.345006)
		(end 123.383548 -220.29293)
		(width 0.14224)
		(layer "In15.Cu")
		(net "GMI_CPU0_G1_CPU1_G3_TX_DP<12>")
	)
	(segment
		(start 123.71197 -236.871764)
		(end 123.74245 -236.889544)
		(width 0.1143)
		(layer "In15.Cu")
		(net "GMI_CPU0_G1_CPU1_G3_TX_DP<12>")
	)
	(segment
		(start 347.753432 -230.409496)
		(end 347.820488 -230.37038)
		(width 0.1143)
		(layer "In15.Cu")
		(net "GMI_CPU0_G1_CPU1_G3_TX_DP<12>")
	)
	(segment
		(start 123.74245 -242.35918)
		(end 123.71197 -242.37696)
		(width 0.1143)
		(layer "In15.Cu")
		(net "GMI_CPU0_G1_CPU1_G3_TX_DP<12>")
	)
	(segment
		(start 347.753432 -227.169472)
		(end 347.783912 -227.151692)
		(width 0.1143)
		(layer "In15.Cu")
		(net "GMI_CPU0_G1_CPU1_G3_TX_DP<12>")
	)
	(segment
		(start 346.18168 -221.083124)
		(end 346.18168 -220.016578)
		(width 0.14224)
		(layer "In15.Cu")
		(net "GMI_CPU0_G1_CPU1_G3_TX_DP<12>")
	)
	(segment
		(start 347.783912 -238.491522)
		(end 347.823028 -238.468662)
		(width 0.1143)
		(layer "In15.Cu")
		(net "GMI_CPU0_G1_CPU1_G3_TX_DP<12>")
	)
	(segment
		(start 123.672854 -223.889062)
		(end 123.71197 -223.911922)
		(width 0.1143)
		(layer "In15.Cu")
		(net "GMI_CPU0_G1_CPU1_G3_TX_DP<12>")
	)
	(segment
		(start 122.41276 -246.10441)
		(end 122.114818 -246.10441)
		(width 0.1143)
		(layer "In15.Cu")
		(net "GMI_CPU0_G1_CPU1_G3_TX_DP<12>")
	)
	(segment
		(start 318.819784 -194.815714)
		(end 309.508906 -188.25337)
		(width 0.14224)
		(layer "In15.Cu")
		(net "GMI_CPU0_G1_CPU1_G3_TX_DP<12>")
	)
	(segment
		(start 123.675394 -230.370634)
		(end 123.74245 -230.40975)
		(width 0.1143)
		(layer "In15.Cu")
		(net "GMI_CPU0_G1_CPU1_G3_TX_DP<12>")
	)
	(segment
		(start 123.74245 -234.25912)
		(end 123.71197 -234.2769)
		(width 0.1143)
		(layer "In15.Cu")
		(net "GMI_CPU0_G1_CPU1_G3_TX_DP<12>")
	)
	(segment
		(start 213.113874 -189.128146)
		(end 207.137508 -188.074554)
		(width 0.14224)
		(layer "In15.Cu")
		(net "GMI_CPU0_G1_CPU1_G3_TX_DP<12>")
	)
	(segment
		(start 123.672854 -227.129086)
		(end 123.71197 -227.151946)
		(width 0.1143)
		(layer "In15.Cu")
		(net "GMI_CPU0_G1_CPU1_G3_TX_DP<12>")
	)
	(segment
		(start 123.383548 -220.991938)
		(end 123.383548 -221.020386)
		(width 0.1143)
		(layer "In15.Cu")
		(net "GMI_CPU0_G1_CPU1_G3_TX_DP<12>")
	)
	(segment
		(start 123.74245 -222.91929)
		(end 123.71197 -222.93707)
		(width 0.1143)
		(layer "In15.Cu")
		(net "GMI_CPU0_G1_CPU1_G3_TX_DP<12>")
	)
	(segment
		(start 347.353128 -225.389694)
		(end 347.316552 -225.368358)
		(width 0.1143)
		(layer "In15.Cu")
		(net "GMI_CPU0_G1_CPU1_G3_TX_DP<12>")
	)
	(segment
		(start 123.242578 -244.80647)
		(end 123.241816 -244.806978)
		(width 0.1143)
		(layer "In15.Cu")
		(net "GMI_CPU0_G1_CPU1_G3_TX_DP<12>")
	)
	(segment
		(start 349.381064 -246.104156)
		(end 349.083122 -246.104156)
		(width 0.1143)
		(layer "In15.Cu")
		(net "GMI_CPU0_G1_CPU1_G3_TX_DP<12>")
	)
	(segment
		(start 123.71197 -225.531934)
		(end 123.74245 -225.549714)
		(width 0.1143)
		(layer "In15.Cu")
		(net "GMI_CPU0_G1_CPU1_G3_TX_DP<12>")
	)
	(segment
		(start 123.74245 -243.979192)
		(end 123.71197 -243.996972)
		(width 0.1143)
		(layer "In15.Cu")
		(net "GMI_CPU0_G1_CPU1_G3_TX_DP<12>")
	)
	(segment
		(start 123.241816 -244.806978)
		(end 123.2408 -244.807486)
		(width 0.1143)
		(layer "In15.Cu")
		(net "GMI_CPU0_G1_CPU1_G3_TX_DP<12>")
	)
	(segment
		(start 346.843858 -223.911668)
		(end 346.882974 -223.888808)
		(width 0.1143)
		(layer "In15.Cu")
		(net "GMI_CPU0_G1_CPU1_G3_TX_DP<12>")
	)
	(segment
		(start 123.71197 -233.63174)
		(end 123.74245 -233.64952)
		(width 0.1143)
		(layer "In15.Cu")
		(net "GMI_CPU0_G1_CPU1_G3_TX_DP<12>")
	)
	(segment
		(start 147.870418 -199.76211)
		(end 145.74266 -200.406254)
		(width 0.14224)
		(layer "In15.Cu")
		(net "GMI_CPU0_G1_CPU1_G3_TX_DP<12>")
	)
	(segment
		(start 347.783912 -234.276646)
		(end 347.753432 -234.258866)
		(width 0.1143)
		(layer "In15.Cu")
		(net "GMI_CPU0_G1_CPU1_G3_TX_DP<12>")
	)
	(segment
		(start 346.813378 -223.929448)
		(end 346.843858 -223.911668)
		(width 0.1143)
		(layer "In15.Cu")
		(net "GMI_CPU0_G1_CPU1_G3_TX_DP<12>")
	)
	(segment
		(start 347.783912 -237.51667)
		(end 347.753432 -237.49889)
		(width 0.1143)
		(layer "In15.Cu")
		(net "GMI_CPU0_G1_CPU1_G3_TX_DP<12>")
	)
	(segment
		(start 347.82252 -228.749098)
		(end 347.823028 -228.748844)
		(width 0.1143)
		(layer "In15.Cu")
		(net "GMI_CPU0_G1_CPU1_G3_TX_DP<12>")
	)
	(segment
		(start 145.74266 -200.406254)
		(end 125.084586 -217.345006)
		(width 0.14224)
		(layer "In15.Cu")
		(net "GMI_CPU0_G1_CPU1_G3_TX_DP<12>")
	)
	(segment
		(start 123.71197 -228.771958)
		(end 123.74245 -228.789738)
		(width 0.1143)
		(layer "In15.Cu")
		(net "GMI_CPU0_G1_CPU1_G3_TX_DP<12>")
	)
	(segment
		(start 347.823028 -226.1997)
		(end 347.783912 -226.17684)
		(width 0.1143)
		(layer "In15.Cu")
		(net "GMI_CPU0_G1_CPU1_G3_TX_DP<12>")
	)
	(segment
		(start 346.186252 -221.358968)
		(end 346.13596 -221.308676)
		(width 0.1143)
		(layer "In15.Cu")
		(net "GMI_CPU0_G1_CPU1_G3_TX_DP<12>")
	)
	(segment
		(start 123.71197 -232.011728)
		(end 123.74245 -232.029508)
		(width 0.1143)
		(layer "In15.Cu")
		(net "GMI_CPU0_G1_CPU1_G3_TX_DP<12>")
	)
	(segment
		(start 347.783912 -231.036622)
		(end 347.7514 -231.017826)
		(width 0.1143)
		(layer "In15.Cu")
		(net "GMI_CPU0_G1_CPU1_G3_TX_DP<12>")
	)
	(segment
		(start 347.823028 -240.779554)
		(end 347.783912 -240.756694)
		(width 0.1143)
		(layer "In15.Cu")
		(net "GMI_CPU0_G1_CPU1_G3_TX_DP<12>")
	)
	(segment
		(start 347.823028 -232.679494)
		(end 347.783912 -232.656634)
		(width 0.1143)
		(layer "In15.Cu")
		(net "GMI_CPU0_G1_CPU1_G3_TX_DP<12>")
	)
	(segment
		(start 123.74245 -235.879132)
		(end 123.71197 -235.896912)
		(width 0.1143)
		(layer "In15.Cu")
		(net "GMI_CPU0_G1_CPU1_G3_TX_DP<12>")
	)
	(segment
		(start 207.137508 -188.074554)
		(end 161.890202 -188.266324)
		(width 0.14224)
		(layer "In15.Cu")
		(net "GMI_CPU0_G1_CPU1_G3_TX_DP<12>")
	)
	(segment
		(start 347.315028 -225.367342)
		(end 347.314012 -225.366834)
		(width 0.1143)
		(layer "In15.Cu")
		(net "GMI_CPU0_G1_CPU1_G3_TX_DP<12>")
	)
	(segment
		(start 347.823028 -237.53953)
		(end 347.783912 -237.51667)
		(width 0.1143)
		(layer "In15.Cu")
		(net "GMI_CPU0_G1_CPU1_G3_TX_DP<12>")
	)
	(segment
		(start 123.71197 -226.177094)
		(end 123.672854 -226.199954)
		(width 0.1143)
		(layer "In15.Cu")
		(net "GMI_CPU0_G1_CPU1_G3_TX_DP<12>")
	)
	(segment
		(start 347.783912 -240.756694)
		(end 347.753432 -240.738914)
		(width 0.1143)
		(layer "In15.Cu")
		(net "GMI_CPU0_G1_CPU1_G3_TX_DP<12>")
	)
	(segment
		(start 123.672854 -240.088928)
		(end 123.71197 -240.111788)
		(width 0.1143)
		(layer "In15.Cu")
		(net "GMI_CPU0_G1_CPU1_G3_TX_DP<12>")
	)
	(segment
		(start 346.882974 -224.579688)
		(end 346.843858 -224.556828)
		(width 0.1143)
		(layer "In15.Cu")
		(net "GMI_CPU0_G1_CPU1_G3_TX_DP<12>")
	)
	(segment
		(start 346.843858 -222.936816)
		(end 346.813378 -222.919036)
		(width 0.1143)
		(layer "In15.Cu")
		(net "GMI_CPU0_G1_CPU1_G3_TX_DP<12>")
	)
	(segment
		(start 123.429268 -221.119954)
		(end 123.429014 -221.120208)
		(width 0.1143)
		(layer "In15.Cu")
		(net "GMI_CPU0_G1_CPU1_G3_TX_DP<12>")
	)
	(segment
		(start 123.744482 -229.398068)
		(end 123.71197 -229.416864)
		(width 0.1143)
		(layer "In15.Cu")
		(net "GMI_CPU0_G1_CPU1_G3_TX_DP<12>")
	)
	(segment
		(start 347.823028 -229.43947)
		(end 347.783912 -229.41661)
		(width 0.1143)
		(layer "In15.Cu")
		(net "GMI_CPU0_G1_CPU1_G3_TX_DP<12>")
	)
	(segment
		(start 123.71197 -243.351812)
		(end 123.74245 -243.369592)
		(width 0.1143)
		(layer "In15.Cu")
		(net "GMI_CPU0_G1_CPU1_G3_TX_DP<12>")
	)
	(segment
		(start 235.326428 -198.329042)
		(end 213.113874 -189.128146)
		(width 0.14224)
		(layer "In15.Cu")
		(net "GMI_CPU0_G1_CPU1_G3_TX_DP<12>")
	)
	(segment
		(start 123.74245 -227.779326)
		(end 123.71197 -227.797106)
		(width 0.1143)
		(layer "In15.Cu")
		(net "GMI_CPU0_G1_CPU1_G3_TX_DP<12>")
	)
	(segment
		(start 347.753432 -236.88929)
		(end 347.783912 -236.87151)
		(width 0.1143)
		(layer "In15.Cu")
		(net "GMI_CPU0_G1_CPU1_G3_TX_DP<12>")
	)
	(segment
		(start 123.2408 -244.807486)
		(end 123.239276 -244.808502)
		(width 0.1143)
		(layer "In15.Cu")
		(net "GMI_CPU0_G1_CPU1_G3_TX_DP<12>")
	)
	(segment
		(start 123.672854 -241.70894)
		(end 123.71197 -241.7318)
		(width 0.1143)
		(layer "In15.Cu")
		(net "GMI_CPU0_G1_CPU1_G3_TX_DP<12>")
	)
	(segment
		(start 347.753432 -228.789484)
		(end 347.783912 -228.771704)
		(width 0.1143)
		(layer "In15.Cu")
		(net "GMI_CPU0_G1_CPU1_G3_TX_DP<12>")
	)
	(segment
		(start 122.771916 -245.616984)
		(end 122.7328 -245.639844)
		(width 0.1143)
		(layer "In15.Cu")
		(net "GMI_CPU0_G1_CPU1_G3_TX_DP<12>")
	)
	(segment
		(start 347.783912 -241.731546)
		(end 347.823028 -241.708686)
		(width 0.1143)
		(layer "In15.Cu")
		(net "GMI_CPU0_G1_CPU1_G3_TX_DP<12>")
	)
	(segment
		(start 123.71197 -240.111788)
		(end 123.74245 -240.129568)
		(width 0.1143)
		(layer "In15.Cu")
		(net "GMI_CPU0_G1_CPU1_G3_TX_DP<12>")
	)
	(segment
		(start 347.314012 -225.366834)
		(end 347.31325 -225.366326)
		(width 0.1143)
		(layer "In15.Cu")
		(net "GMI_CPU0_G1_CPU1_G3_TX_DP<12>")
	)
	(arc
		(start 123.74245 -223.929702)
		(mid 123.899427 -224.234502)
		(end 123.74245 -224.539302)
		(width 0.1143)
		(layer "In15.Cu")
		(net "GMI_CPU0_G1_CPU1_G3_TX_DP<12>")
	)
	(arc
		(start 347.753432 -227.779072)
		(mid 347.596455 -227.474272)
		(end 347.753432 -227.169472)
		(width 0.1143)
		(layer "In15.Cu")
		(net "GMI_CPU0_G1_CPU1_G3_TX_DP<12>")
	)
	(arc
		(start 347.282262 -225.348546)
		(mid 347.167586 -225.215212)
		(end 347.126306 -225.044254)
		(width 0.1143)
		(layer "In15.Cu")
		(net "GMI_CPU0_G1_CPU1_G3_TX_DP<12>")
	)
	(arc
		(start 349.000318 -246.021352)
		(mid 348.99853 -246.009903)
		(end 348.996508 -245.998492)
		(width 0.1143)
		(layer "In15.Cu")
		(net "GMI_CPU0_G1_CPU1_G3_TX_DP<12>")
	)
	(arc
		(start 123.672854 -242.39982)
		(mid 123.429527 -242.864386)
		(end 123.672854 -243.328952)
		(width 0.1143)
		(layer "In15.Cu")
		(net "GMI_CPU0_G1_CPU1_G3_TX_DP<12>")
	)
	(arc
		(start 123.74245 -236.889544)
		(mid 123.899427 -237.194344)
		(end 123.74245 -237.499144)
		(width 0.1143)
		(layer "In15.Cu")
		(net "GMI_CPU0_G1_CPU1_G3_TX_DP<12>")
	)
	(arc
		(start 123.672854 -232.679748)
		(mid 123.429527 -233.144314)
		(end 123.672854 -233.60888)
		(width 0.1143)
		(layer "In15.Cu")
		(net "GMI_CPU0_G1_CPU1_G3_TX_DP<12>")
	)
	(arc
		(start 347.823028 -233.608626)
		(mid 348.066355 -233.14406)
		(end 347.823028 -232.679494)
		(width 0.1143)
		(layer "In15.Cu")
		(net "GMI_CPU0_G1_CPU1_G3_TX_DP<12>")
	)
	(arc
		(start 348.723458 -245.616476)
		(mid 348.595507 -245.488202)
		(end 348.548706 -245.3132)
		(width 0.1143)
		(layer "In15.Cu")
		(net "GMI_CPU0_G1_CPU1_G3_TX_DP<12>")
	)
	(arc
		(start 347.7514 -231.017826)
		(mid 347.637471 -230.884679)
		(end 347.59646 -230.714296)
		(width 0.1143)
		(layer "In15.Cu")
		(net "GMI_CPU0_G1_CPU1_G3_TX_DP<12>")
	)
	(arc
		(start 346.813378 -222.919036)
		(mid 346.697951 -222.78566)
		(end 346.656406 -222.614236)
		(width 0.1143)
		(layer "In15.Cu")
		(net "GMI_CPU0_G1_CPU1_G3_TX_DP<12>")
	)
	(arc
		(start 348.763082 -245.63959)
		(mid 348.762701 -245.639336)
		(end 348.76232 -245.639082)
		(width 0.1143)
		(layer "In15.Cu")
		(net "GMI_CPU0_G1_CPU1_G3_TX_DP<12>")
	)
	(arc
		(start 123.429014 -221.804484)
		(mid 123.493886 -222.067447)
		(end 123.673616 -222.270066)
		(width 0.1143)
		(layer "In15.Cu")
		(net "GMI_CPU0_G1_CPU1_G3_TX_DP<12>")
	)
	(arc
		(start 346.342716 -222.108776)
		(mid 346.227665 -221.975421)
		(end 346.186252 -221.80423)
		(width 0.1143)
		(layer "In15.Cu")
		(net "GMI_CPU0_G1_CPU1_G3_TX_DP<12>")
	)
	(arc
		(start 348.996508 -245.998492)
		(mid 348.915075 -245.796094)
		(end 348.763082 -245.63959)
		(width 0.1143)
		(layer "In15.Cu")
		(net "GMI_CPU0_G1_CPU1_G3_TX_DP<12>")
	)
	(arc
		(start 347.823028 -227.128832)
		(mid 348.066355 -226.664266)
		(end 347.823028 -226.1997)
		(width 0.1143)
		(layer "In15.Cu")
		(net "GMI_CPU0_G1_CPU1_G3_TX_DP<12>")
	)
	(arc
		(start 123.74245 -230.40975)
		(mid 123.857877 -230.543126)
		(end 123.899422 -230.71455)
		(width 0.1143)
		(layer "In15.Cu")
		(net "GMI_CPU0_G1_CPU1_G3_TX_DP<12>")
	)
	(arc
		(start 123.744228 -222.31096)
		(mid 123.858381 -222.444036)
		(end 123.899422 -222.61449)
		(width 0.1143)
		(layer "In15.Cu")
		(net "GMI_CPU0_G1_CPU1_G3_TX_DP<12>")
	)
	(arc
		(start 123.74245 -228.789738)
		(mid 123.857877 -228.923114)
		(end 123.899422 -229.094538)
		(width 0.1143)
		(layer "In15.Cu")
		(net "GMI_CPU0_G1_CPU1_G3_TX_DP<12>")
	)
	(arc
		(start 123.672854 -235.919772)
		(mid 123.429527 -236.384338)
		(end 123.672854 -236.848904)
		(width 0.1143)
		(layer "In15.Cu")
		(net "GMI_CPU0_G1_CPU1_G3_TX_DP<12>")
	)
	(arc
		(start 347.823028 -228.748844)
		(mid 348.066355 -228.284278)
		(end 347.823028 -227.819712)
		(width 0.1143)
		(layer "In15.Cu")
		(net "GMI_CPU0_G1_CPU1_G3_TX_DP<12>")
	)
	(arc
		(start 123.74245 -243.369592)
		(mid 123.899427 -243.674392)
		(end 123.74245 -243.979192)
		(width 0.1143)
		(layer "In15.Cu")
		(net "GMI_CPU0_G1_CPU1_G3_TX_DP<12>")
	)
	(arc
		(start 123.74245 -227.169726)
		(mid 123.899427 -227.474526)
		(end 123.74245 -227.779326)
		(width 0.1143)
		(layer "In15.Cu")
		(net "GMI_CPU0_G1_CPU1_G3_TX_DP<12>")
	)
	(arc
		(start 123.899422 -230.71455)
		(mid 123.858456 -230.884956)
		(end 123.744482 -231.01808)
		(width 0.1143)
		(layer "In15.Cu")
		(net "GMI_CPU0_G1_CPU1_G3_TX_DP<12>")
	)
	(arc
		(start 347.7514 -229.397814)
		(mid 347.637471 -229.264667)
		(end 347.59646 -229.094284)
		(width 0.1143)
		(layer "In15.Cu")
		(net "GMI_CPU0_G1_CPU1_G3_TX_DP<12>")
	)
	(arc
		(start 123.672854 -226.199954)
		(mid 123.429527 -226.66452)
		(end 123.672854 -227.129086)
		(width 0.1143)
		(layer "In15.Cu")
		(net "GMI_CPU0_G1_CPU1_G3_TX_DP<12>")
	)
	(arc
		(start 347.753432 -235.878878)
		(mid 347.596455 -235.574078)
		(end 347.753432 -235.269278)
		(width 0.1143)
		(layer "In15.Cu")
		(net "GMI_CPU0_G1_CPU1_G3_TX_DP<12>")
	)
	(arc
		(start 347.59646 -230.714296)
		(mid 347.638009 -230.542874)
		(end 347.753432 -230.409496)
		(width 0.1143)
		(layer "In15.Cu")
		(net "GMI_CPU0_G1_CPU1_G3_TX_DP<12>")
	)
	(arc
		(start 123.672854 -240.779808)
		(mid 123.429527 -241.244374)
		(end 123.672854 -241.70894)
		(width 0.1143)
		(layer "In15.Cu")
		(net "GMI_CPU0_G1_CPU1_G3_TX_DP<12>")
	)
	(arc
		(start 123.672854 -239.159796)
		(mid 123.429527 -239.624362)
		(end 123.672854 -240.088928)
		(width 0.1143)
		(layer "In15.Cu")
		(net "GMI_CPU0_G1_CPU1_G3_TX_DP<12>")
	)
	(arc
		(start 347.126306 -225.044254)
		(mid 347.061791 -224.782035)
		(end 346.882974 -224.579688)
		(width 0.1143)
		(layer "In15.Cu")
		(net "GMI_CPU0_G1_CPU1_G3_TX_DP<12>")
	)
	(arc
		(start 347.823028 -235.228638)
		(mid 348.066355 -234.764072)
		(end 347.823028 -234.299506)
		(width 0.1143)
		(layer "In15.Cu")
		(net "GMI_CPU0_G1_CPU1_G3_TX_DP<12>")
	)
	(arc
		(start 347.753432 -243.978938)
		(mid 347.596455 -243.674138)
		(end 347.753432 -243.369338)
		(width 0.1143)
		(layer "In15.Cu")
		(net "GMI_CPU0_G1_CPU1_G3_TX_DP<12>")
	)
	(arc
		(start 123.429522 -244.484398)
		(mid 123.388267 -244.655369)
		(end 123.273566 -244.78869)
		(width 0.1143)
		(layer "In15.Cu")
		(net "GMI_CPU0_G1_CPU1_G3_TX_DP<12>")
	)
	(arc
		(start 123.672854 -222.95993)
		(mid 123.429527 -223.424496)
		(end 123.672854 -223.889062)
		(width 0.1143)
		(layer "In15.Cu")
		(net "GMI_CPU0_G1_CPU1_G3_TX_DP<12>")
	)
	(arc
		(start 123.74245 -238.509556)
		(mid 123.899427 -238.814356)
		(end 123.74245 -239.119156)
		(width 0.1143)
		(layer "In15.Cu")
		(net "GMI_CPU0_G1_CPU1_G3_TX_DP<12>")
	)
	(arc
		(start 348.222062 -244.788182)
		(mid 348.107535 -244.654942)
		(end 348.06636 -244.484144)
		(width 0.1143)
		(layer "In15.Cu")
		(net "GMI_CPU0_G1_CPU1_G3_TX_DP<12>")
	)
	(arc
		(start 123.74245 -240.129568)
		(mid 123.899427 -240.434368)
		(end 123.74245 -240.739168)
		(width 0.1143)
		(layer "In15.Cu")
		(net "GMI_CPU0_G1_CPU1_G3_TX_DP<12>")
	)
	(arc
		(start 346.882974 -223.888808)
		(mid 347.126301 -223.424242)
		(end 346.882974 -222.959676)
		(width 0.1143)
		(layer "In15.Cu")
		(net "GMI_CPU0_G1_CPU1_G3_TX_DP<12>")
	)
	(arc
		(start 347.59646 -225.85426)
		(mid 347.531945 -225.592041)
		(end 347.353128 -225.389694)
		(width 0.1143)
		(layer "In15.Cu")
		(net "GMI_CPU0_G1_CPU1_G3_TX_DP<12>")
	)
	(arc
		(start 347.59646 -229.094284)
		(mid 347.638009 -228.922862)
		(end 347.753432 -228.789484)
		(width 0.1143)
		(layer "In15.Cu")
		(net "GMI_CPU0_G1_CPU1_G3_TX_DP<12>")
	)
	(arc
		(start 123.672854 -237.539784)
		(mid 123.429527 -238.00435)
		(end 123.672854 -238.468916)
		(width 0.1143)
		(layer "In15.Cu")
		(net "GMI_CPU0_G1_CPU1_G3_TX_DP<12>")
	)
	(arc
		(start 123.2027 -244.829838)
		(mid 123.023887 -245.032188)
		(end 122.959368 -245.294404)
		(width 0.1143)
		(layer "In15.Cu")
		(net "GMI_CPU0_G1_CPU1_G3_TX_DP<12>")
	)
	(arc
		(start 123.672854 -244.019832)
		(mid 123.494041 -244.222182)
		(end 123.429522 -244.484398)
		(width 0.1143)
		(layer "In15.Cu")
		(net "GMI_CPU0_G1_CPU1_G3_TX_DP<12>")
	)
	(arc
		(start 347.753432 -239.118902)
		(mid 347.596455 -238.814102)
		(end 347.753432 -238.509302)
		(width 0.1143)
		(layer "In15.Cu")
		(net "GMI_CPU0_G1_CPU1_G3_TX_DP<12>")
	)
	(arc
		(start 122.959368 -245.294404)
		(mid 122.917819 -245.465826)
		(end 122.802396 -245.599204)
		(width 0.1143)
		(layer "In15.Cu")
		(net "GMI_CPU0_G1_CPU1_G3_TX_DP<12>")
	)
	(arc
		(start 347.753432 -232.638854)
		(mid 347.596455 -232.334054)
		(end 347.753432 -232.029254)
		(width 0.1143)
		(layer "In15.Cu")
		(net "GMI_CPU0_G1_CPU1_G3_TX_DP<12>")
	)
	(arc
		(start 123.672854 -231.059736)
		(mid 123.429527 -231.524302)
		(end 123.672854 -231.988868)
		(width 0.1143)
		(layer "In15.Cu")
		(net "GMI_CPU0_G1_CPU1_G3_TX_DP<12>")
	)
	(arc
		(start 348.06636 -229.904036)
		(mid 348.001845 -229.641817)
		(end 347.823028 -229.43947)
		(width 0.1143)
		(layer "In15.Cu")
		(net "GMI_CPU0_G1_CPU1_G3_TX_DP<12>")
	)
	(arc
		(start 347.823028 -243.328698)
		(mid 348.066355 -242.864132)
		(end 347.823028 -242.399566)
		(width 0.1143)
		(layer "In15.Cu")
		(net "GMI_CPU0_G1_CPU1_G3_TX_DP<12>")
	)
	(arc
		(start 347.753432 -234.258866)
		(mid 347.596455 -233.954066)
		(end 347.753432 -233.649266)
		(width 0.1143)
		(layer "In15.Cu")
		(net "GMI_CPU0_G1_CPU1_G3_TX_DP<12>")
	)
	(arc
		(start 347.753432 -226.15906)
		(mid 347.638005 -226.025684)
		(end 347.59646 -225.85426)
		(width 0.1143)
		(layer "In15.Cu")
		(net "GMI_CPU0_G1_CPU1_G3_TX_DP<12>")
	)
	(arc
		(start 122.499374 -245.998746)
		(mid 122.497351 -246.010156)
		(end 122.495564 -246.021606)
		(width 0.1143)
		(layer "In15.Cu")
		(net "GMI_CPU0_G1_CPU1_G3_TX_DP<12>")
	)
	(arc
		(start 123.74245 -225.549714)
		(mid 123.899427 -225.854514)
		(end 123.74245 -226.159314)
		(width 0.1143)
		(layer "In15.Cu")
		(net "GMI_CPU0_G1_CPU1_G3_TX_DP<12>")
	)
	(arc
		(start 123.672854 -234.29976)
		(mid 123.429527 -234.764326)
		(end 123.672854 -235.228892)
		(width 0.1143)
		(layer "In15.Cu")
		(net "GMI_CPU0_G1_CPU1_G3_TX_DP<12>")
	)
	(arc
		(start 123.74245 -232.029508)
		(mid 123.899427 -232.334308)
		(end 123.74245 -232.639108)
		(width 0.1143)
		(layer "In15.Cu")
		(net "GMI_CPU0_G1_CPU1_G3_TX_DP<12>")
	)
	(arc
		(start 123.74245 -233.64952)
		(mid 123.899427 -233.95432)
		(end 123.74245 -234.25912)
		(width 0.1143)
		(layer "In15.Cu")
		(net "GMI_CPU0_G1_CPU1_G3_TX_DP<12>")
	)
	(arc
		(start 347.753432 -237.49889)
		(mid 347.596455 -237.19409)
		(end 347.753432 -236.88929)
		(width 0.1143)
		(layer "In15.Cu")
		(net "GMI_CPU0_G1_CPU1_G3_TX_DP<12>")
	)
	(arc
		(start 123.429522 -229.90429)
		(mid 123.494758 -230.167881)
		(end 123.675394 -230.370634)
		(width 0.1143)
		(layer "In15.Cu")
		(net "GMI_CPU0_G1_CPU1_G3_TX_DP<12>")
	)
	(arc
		(start 347.753432 -242.358926)
		(mid 347.596455 -242.054126)
		(end 347.753432 -241.749326)
		(width 0.1143)
		(layer "In15.Cu")
		(net "GMI_CPU0_G1_CPU1_G3_TX_DP<12>")
	)
	(arc
		(start 348.06636 -244.484144)
		(mid 348.001845 -244.221925)
		(end 347.823028 -244.019578)
		(width 0.1143)
		(layer "In15.Cu")
		(net "GMI_CPU0_G1_CPU1_G3_TX_DP<12>")
	)
	(arc
		(start 123.672854 -229.439724)
		(mid 123.494041 -229.642074)
		(end 123.429522 -229.90429)
		(width 0.1143)
		(layer "In15.Cu")
		(net "GMI_CPU0_G1_CPU1_G3_TX_DP<12>")
	)
	(arc
		(start 347.823028 -238.468662)
		(mid 348.066355 -238.004096)
		(end 347.823028 -237.53953)
		(width 0.1143)
		(layer "In15.Cu")
		(net "GMI_CPU0_G1_CPU1_G3_TX_DP<12>")
	)
	(arc
		(start 123.74245 -235.269532)
		(mid 123.899427 -235.574332)
		(end 123.74245 -235.879132)
		(width 0.1143)
		(layer "In15.Cu")
		(net "GMI_CPU0_G1_CPU1_G3_TX_DP<12>")
	)
	(arc
		(start 347.823028 -231.988614)
		(mid 348.066355 -231.524048)
		(end 347.823028 -231.059482)
		(width 0.1143)
		(layer "In15.Cu")
		(net "GMI_CPU0_G1_CPU1_G3_TX_DP<12>")
	)
	(arc
		(start 123.672854 -227.819966)
		(mid 123.429527 -228.284532)
		(end 123.672854 -228.749098)
		(width 0.1143)
		(layer "In15.Cu")
		(net "GMI_CPU0_G1_CPU1_G3_TX_DP<12>")
	)
	(arc
		(start 347.823028 -240.088674)
		(mid 348.066355 -239.624108)
		(end 347.823028 -239.159542)
		(width 0.1143)
		(layer "In15.Cu")
		(net "GMI_CPU0_G1_CPU1_G3_TX_DP<12>")
	)
	(arc
		(start 123.899422 -229.094538)
		(mid 123.858456 -229.264944)
		(end 123.744482 -229.398068)
		(width 0.1143)
		(layer "In15.Cu")
		(net "GMI_CPU0_G1_CPU1_G3_TX_DP<12>")
	)
	(arc
		(start 347.820488 -230.37038)
		(mid 348.00114 -230.167635)
		(end 348.06636 -229.904036)
		(width 0.1143)
		(layer "In15.Cu")
		(net "GMI_CPU0_G1_CPU1_G3_TX_DP<12>")
	)
	(arc
		(start 123.672854 -224.579942)
		(mid 123.429527 -225.044508)
		(end 123.672854 -225.509074)
		(width 0.1143)
		(layer "In15.Cu")
		(net "GMI_CPU0_G1_CPU1_G3_TX_DP<12>")
	)
	(arc
		(start 347.823028 -241.708686)
		(mid 348.066355 -241.24412)
		(end 347.823028 -240.779554)
		(width 0.1143)
		(layer "In15.Cu")
		(net "GMI_CPU0_G1_CPU1_G3_TX_DP<12>")
	)
	(arc
		(start 123.74245 -241.74958)
		(mid 123.899427 -242.05438)
		(end 123.74245 -242.35918)
		(width 0.1143)
		(layer "In15.Cu")
		(net "GMI_CPU0_G1_CPU1_G3_TX_DP<12>")
	)
	(arc
		(start 348.548706 -245.303548)
		(mid 348.472741 -245.020406)
		(end 348.265242 -244.813328)
		(width 0.1143)
		(layer "In15.Cu")
		(net "GMI_CPU0_G1_CPU1_G3_TX_DP<12>")
	)
	(arc
		(start 347.823028 -236.84865)
		(mid 348.066355 -236.384084)
		(end 347.823028 -235.919518)
		(width 0.1143)
		(layer "In15.Cu")
		(net "GMI_CPU0_G1_CPU1_G3_TX_DP<12>")
	)
	(arc
		(start 346.813378 -224.539048)
		(mid 346.656401 -224.234248)
		(end 346.813378 -223.929448)
		(width 0.1143)
		(layer "In15.Cu")
		(net "GMI_CPU0_G1_CPU1_G3_TX_DP<12>")
	)
	(arc
		(start 123.899422 -222.61449)
		(mid 123.857873 -222.785912)
		(end 123.74245 -222.91929)
		(width 0.1143)
		(layer "In15.Cu")
		(net "GMI_CPU0_G1_CPU1_G3_TX_DP<12>")
	)
	(arc
		(start 122.7328 -245.639844)
		(mid 122.580813 -245.796352)
		(end 122.499374 -245.998746)
		(width 0.1143)
		(layer "In15.Cu")
		(net "GMI_CPU0_G1_CPU1_G3_TX_DP<12>")
	)
	(arc
		(start 347.753432 -240.738914)
		(mid 347.596455 -240.434114)
		(end 347.753432 -240.129314)
		(width 0.1143)
		(layer "In15.Cu")
		(net "GMI_CPU0_G1_CPU1_G3_TX_DP<12>")
	)
	(arc
		(start 346.656406 -222.614236)
		(mid 346.591891 -222.352017)
		(end 346.413074 -222.14967)
		(width 0.1143)
		(layer "In15.Cu")
		(net "GMI_CPU0_G1_CPU1_G3_TX_DP<12>")
	)
	(segment
		(start 349.847916 -244.750082)
		(end 349.381064 -244.484144)
		(width 0.12954)
		(layer "F.Cu")
		(net "GMI_CPU0_G1_CPU1_G3_TX_DP<11>")
	)
	(segment
		(start 121.647966 -244.750336)
		(end 122.114818 -244.484398)
		(width 0.12954)
		(layer "F.Cu")
		(net "GMI_CPU0_G1_CPU1_G3_TX_DP<11>")
	)
	(segment
		(start 122.802396 -226.159314)
		(end 122.771916 -226.177094)
		(width 0.1143)
		(layer "In15.Cu")
		(net "GMI_CPU0_G1_CPU1_G3_TX_DP<11>")
	)
	(segment
		(start 122.771916 -231.036876)
		(end 122.7328 -231.059736)
		(width 0.1143)
		(layer "In15.Cu")
		(net "GMI_CPU0_G1_CPU1_G3_TX_DP<11>")
	)
	(segment
		(start 348.723966 -227.796852)
		(end 348.723204 -227.796344)
		(width 0.1143)
		(layer "In15.Cu")
		(net "GMI_CPU0_G1_CPU1_G3_TX_DP<11>")
	)
	(segment
		(start 348.7293 -239.13973)
		(end 348.728538 -239.139222)
		(width 0.1143)
		(layer "In15.Cu")
		(net "GMI_CPU0_G1_CPU1_G3_TX_DP<11>")
	)
	(segment
		(start 347.12656 -221.083124)
		(end 347.12656 -219.783152)
		(width 0.14224)
		(layer "In15.Cu")
		(net "GMI_CPU0_G1_CPU1_G3_TX_DP<11>")
	)
	(segment
		(start 122.771916 -233.63174)
		(end 122.802396 -233.64952)
		(width 0.1143)
		(layer "In15.Cu")
		(net "GMI_CPU0_G1_CPU1_G3_TX_DP<11>")
	)
	(segment
		(start 344.795602 -214.857838)
		(end 314.258452 -189.817756)
		(width 0.14224)
		(layer "In15.Cu")
		(net "GMI_CPU0_G1_CPU1_G3_TX_DP<11>")
	)
	(segment
		(start 348.76232 -235.91901)
		(end 348.75597 -235.9152)
		(width 0.1143)
		(layer "In15.Cu")
		(net "GMI_CPU0_G1_CPU1_G3_TX_DP<11>")
	)
	(segment
		(start 348.730316 -242.380262)
		(end 348.7293 -242.379754)
		(width 0.1143)
		(layer "In15.Cu")
		(net "GMI_CPU0_G1_CPU1_G3_TX_DP<11>")
	)
	(segment
		(start 348.723966 -243.996718)
		(end 348.723204 -243.99621)
		(width 0.1143)
		(layer "In15.Cu")
		(net "GMI_CPU0_G1_CPU1_G3_TX_DP<11>")
	)
	(segment
		(start 122.771916 -235.251752)
		(end 122.802396 -235.269532)
		(width 0.1143)
		(layer "In15.Cu")
		(net "GMI_CPU0_G1_CPU1_G3_TX_DP<11>")
	)
	(segment
		(start 348.745048 -241.719354)
		(end 348.763082 -241.708686)
		(width 0.1143)
		(layer "In15.Cu")
		(net "GMI_CPU0_G1_CPU1_G3_TX_DP<11>")
	)
	(segment
		(start 122.771916 -240.111788)
		(end 122.802396 -240.129568)
		(width 0.1143)
		(layer "In15.Cu")
		(net "GMI_CPU0_G1_CPU1_G3_TX_DP<11>")
	)
	(segment
		(start 347.823028 -224.579688)
		(end 347.783912 -224.556828)
		(width 0.1143)
		(layer "In15.Cu")
		(net "GMI_CPU0_G1_CPU1_G3_TX_DP<11>")
	)
	(segment
		(start 347.305884 -222.122238)
		(end 347.282262 -222.108522)
		(width 0.1143)
		(layer "In15.Cu")
		(net "GMI_CPU0_G1_CPU1_G3_TX_DP<11>")
	)
	(segment
		(start 158.125414 -189.961774)
		(end 147.138136 -198.9709)
		(width 0.14224)
		(layer "In15.Cu")
		(net "GMI_CPU0_G1_CPU1_G3_TX_DP<11>")
	)
	(segment
		(start 122.771916 -243.996972)
		(end 122.7328 -244.019832)
		(width 0.1143)
		(layer "In15.Cu")
		(net "GMI_CPU0_G1_CPU1_G3_TX_DP<11>")
	)
	(segment
		(start 302.886872 -185.132726)
		(end 302.626268 -185.131202)
		(width 0.14224)
		(layer "In15.Cu")
		(net "GMI_CPU0_G1_CPU1_G3_TX_DP<11>")
	)
	(segment
		(start 302.886872 -185.13298)
		(end 302.886872 -185.132726)
		(width 0.14224)
		(layer "In15.Cu")
		(net "GMI_CPU0_G1_CPU1_G3_TX_DP<11>")
	)
	(segment
		(start 348.726506 -228.77018)
		(end 348.727522 -228.769672)
		(width 0.1143)
		(layer "In15.Cu")
		(net "GMI_CPU0_G1_CPU1_G3_TX_DP<11>")
	)
	(segment
		(start 348.723966 -229.41661)
		(end 348.690438 -229.397052)
		(width 0.1143)
		(layer "In15.Cu")
		(net "GMI_CPU0_G1_CPU1_G3_TX_DP<11>")
	)
	(segment
		(start 348.7293 -237.519718)
		(end 348.728538 -237.51921)
		(width 0.1143)
		(layer "In15.Cu")
		(net "GMI_CPU0_G1_CPU1_G3_TX_DP<11>")
	)
	(segment
		(start 122.802396 -224.539302)
		(end 122.771916 -224.557082)
		(width 0.1143)
		(layer "In15.Cu")
		(net "GMI_CPU0_G1_CPU1_G3_TX_DP<11>")
	)
	(segment
		(start 122.771916 -242.37696)
		(end 122.7328 -242.39982)
		(width 0.1143)
		(layer "In15.Cu")
		(net "GMI_CPU0_G1_CPU1_G3_TX_DP<11>")
	)
	(segment
		(start 348.76232 -240.779046)
		(end 348.730316 -240.76025)
		(width 0.1143)
		(layer "In15.Cu")
		(net "GMI_CPU0_G1_CPU1_G3_TX_DP<11>")
	)
	(segment
		(start 122.802396 -243.979192)
		(end 122.771916 -243.996972)
		(width 0.1143)
		(layer "In15.Cu")
		(net "GMI_CPU0_G1_CPU1_G3_TX_DP<11>")
	)
	(segment
		(start 347.783912 -223.911668)
		(end 347.823028 -223.888808)
		(width 0.1143)
		(layer "In15.Cu")
		(net "GMI_CPU0_G1_CPU1_G3_TX_DP<11>")
	)
	(segment
		(start 122.802396 -242.35918)
		(end 122.771916 -242.37696)
		(width 0.1143)
		(layer "In15.Cu")
		(net "GMI_CPU0_G1_CPU1_G3_TX_DP<11>")
	)
	(segment
		(start 348.723204 -233.631994)
		(end 348.723966 -233.631486)
		(width 0.1143)
		(layer "In15.Cu")
		(net "GMI_CPU0_G1_CPU1_G3_TX_DP<11>")
	)
	(segment
		(start 124.441458 -216.59215)
		(end 122.42419 -220.070934)
		(width 0.14224)
		(layer "In15.Cu")
		(net "GMI_CPU0_G1_CPU1_G3_TX_DP<11>")
	)
	(segment
		(start 348.76232 -234.298998)
		(end 348.759526 -234.296966)
		(width 0.1143)
		(layer "In15.Cu")
		(net "GMI_CPU0_G1_CPU1_G3_TX_DP<11>")
	)
	(segment
		(start 122.7328 -223.889062)
		(end 122.771916 -223.911922)
		(width 0.1143)
		(layer "In15.Cu")
		(net "GMI_CPU0_G1_CPU1_G3_TX_DP<11>")
	)
	(segment
		(start 158.125668 -189.961774)
		(end 158.125414 -189.961774)
		(width 0.14224)
		(layer "In15.Cu")
		(net "GMI_CPU0_G1_CPU1_G3_TX_DP<11>")
	)
	(segment
		(start 347.353128 -222.14967)
		(end 347.315028 -222.127318)
		(width 0.1143)
		(layer "In15.Cu")
		(net "GMI_CPU0_G1_CPU1_G3_TX_DP<11>")
	)
	(segment
		(start 348.763082 -227.819712)
		(end 348.756224 -227.815648)
		(width 0.1143)
		(layer "In15.Cu")
		(net "GMI_CPU0_G1_CPU1_G3_TX_DP<11>")
	)
	(segment
		(start 158.216092 -189.887606)
		(end 158.215838 -189.88786)
		(width 0.14224)
		(layer "In15.Cu")
		(net "GMI_CPU0_G1_CPU1_G3_TX_DP<11>")
	)
	(segment
		(start 348.759526 -234.296966)
		(end 348.723966 -234.276646)
		(width 0.1143)
		(layer "In15.Cu")
		(net "GMI_CPU0_G1_CPU1_G3_TX_DP<11>")
	)
	(segment
		(start 306.478432 -185.154316)
		(end 306.478432 -185.154062)
		(width 0.14224)
		(layer "In15.Cu")
		(net "GMI_CPU0_G1_CPU1_G3_TX_DP<11>")
	)
	(segment
		(start 306.42687 -185.13298)
		(end 302.886872 -185.13298)
		(width 0.14224)
		(layer "In15.Cu")
		(net "GMI_CPU0_G1_CPU1_G3_TX_DP<11>")
	)
	(segment
		(start 147.138136 -198.9709)
		(end 145.224754 -199.550528)
		(width 0.14224)
		(layer "In15.Cu")
		(net "GMI_CPU0_G1_CPU1_G3_TX_DP<11>")
	)
	(segment
		(start 348.723966 -233.631486)
		(end 348.724982 -233.630978)
		(width 0.1143)
		(layer "In15.Cu")
		(net "GMI_CPU0_G1_CPU1_G3_TX_DP<11>")
	)
	(segment
		(start 348.723966 -234.276646)
		(end 348.692216 -234.258358)
		(width 0.1143)
		(layer "In15.Cu")
		(net "GMI_CPU0_G1_CPU1_G3_TX_DP<11>")
	)
	(segment
		(start 348.726506 -233.629962)
		(end 348.763082 -233.608626)
		(width 0.1143)
		(layer "In15.Cu")
		(net "GMI_CPU0_G1_CPU1_G3_TX_DP<11>")
	)
	(segment
		(start 122.771916 -236.871764)
		(end 122.802396 -236.889544)
		(width 0.1143)
		(layer "In15.Cu")
		(net "GMI_CPU0_G1_CPU1_G3_TX_DP<11>")
	)
	(segment
		(start 122.771916 -227.797106)
		(end 122.7328 -227.819966)
		(width 0.1143)
		(layer "In15.Cu")
		(net "GMI_CPU0_G1_CPU1_G3_TX_DP<11>")
	)
	(segment
		(start 348.723966 -232.656634)
		(end 348.723204 -232.656126)
		(width 0.1143)
		(layer "In15.Cu")
		(net "GMI_CPU0_G1_CPU1_G3_TX_DP<11>")
	)
	(segment
		(start 122.7328 -233.60888)
		(end 122.771916 -233.63174)
		(width 0.1143)
		(layer "In15.Cu")
		(net "GMI_CPU0_G1_CPU1_G3_TX_DP<11>")
	)
	(segment
		(start 122.7328 -225.509074)
		(end 122.771916 -225.531934)
		(width 0.1143)
		(layer "In15.Cu")
		(net "GMI_CPU0_G1_CPU1_G3_TX_DP<11>")
	)
	(segment
		(start 348.745048 -235.239306)
		(end 348.763082 -235.228638)
		(width 0.1143)
		(layer "In15.Cu")
		(net "GMI_CPU0_G1_CPU1_G3_TX_DP<11>")
	)
	(segment
		(start 348.723204 -230.392224)
		(end 348.723966 -230.391716)
		(width 0.1143)
		(layer "In15.Cu")
		(net "GMI_CPU0_G1_CPU1_G3_TX_DP<11>")
	)
	(segment
		(start 122.7328 -236.848904)
		(end 122.771916 -236.871764)
		(width 0.1143)
		(layer "In15.Cu")
		(net "GMI_CPU0_G1_CPU1_G3_TX_DP<11>")
	)
	(segment
		(start 347.126306 -221.354142)
		(end 347.08084 -221.308676)
		(width 0.1143)
		(layer "In15.Cu")
		(net "GMI_CPU0_G1_CPU1_G3_TX_DP<11>")
	)
	(segment
		(start 348.692216 -233.649774)
		(end 348.723204 -233.631994)
		(width 0.1143)
		(layer "In15.Cu")
		(net "GMI_CPU0_G1_CPU1_G3_TX_DP<11>")
	)
	(segment
		(start 348.723458 -238.491776)
		(end 348.744794 -238.47933)
		(width 0.1143)
		(layer "In15.Cu")
		(net "GMI_CPU0_G1_CPU1_G3_TX_DP<11>")
	)
	(segment
		(start 348.723204 -228.772212)
		(end 348.723966 -228.771704)
		(width 0.1143)
		(layer "In15.Cu")
		(net "GMI_CPU0_G1_CPU1_G3_TX_DP<11>")
	)
	(segment
		(start 348.763082 -226.1997)
		(end 348.723966 -226.17684)
		(width 0.1143)
		(layer "In15.Cu")
		(net "GMI_CPU0_G1_CPU1_G3_TX_DP<11>")
	)
	(segment
		(start 348.75597 -235.9152)
		(end 348.755208 -235.914692)
		(width 0.1143)
		(layer "In15.Cu")
		(net "GMI_CPU0_G1_CPU1_G3_TX_DP<11>")
	)
	(segment
		(start 122.771916 -225.531934)
		(end 122.802396 -225.549714)
		(width 0.1143)
		(layer "In15.Cu")
		(net "GMI_CPU0_G1_CPU1_G3_TX_DP<11>")
	)
	(segment
		(start 122.771916 -240.756948)
		(end 122.7328 -240.779808)
		(width 0.1143)
		(layer "In15.Cu")
		(net "GMI_CPU0_G1_CPU1_G3_TX_DP<11>")
	)
	(segment
		(start 348.723458 -235.251752)
		(end 348.744794 -235.239306)
		(width 0.1143)
		(layer "In15.Cu")
		(net "GMI_CPU0_G1_CPU1_G3_TX_DP<11>")
	)
	(segment
		(start 122.771916 -235.896912)
		(end 122.7328 -235.919772)
		(width 0.1143)
		(layer "In15.Cu")
		(net "GMI_CPU0_G1_CPU1_G3_TX_DP<11>")
	)
	(segment
		(start 348.723204 -227.796344)
		(end 348.692216 -227.778564)
		(width 0.1143)
		(layer "In15.Cu")
		(net "GMI_CPU0_G1_CPU1_G3_TX_DP<11>")
	)
	(segment
		(start 122.41276 -244.484398)
		(end 122.114818 -244.484398)
		(width 0.1143)
		(layer "In15.Cu")
		(net "GMI_CPU0_G1_CPU1_G3_TX_DP<11>")
	)
	(segment
		(start 122.7328 -241.70894)
		(end 122.771916 -241.7318)
		(width 0.1143)
		(layer "In15.Cu")
		(net "GMI_CPU0_G1_CPU1_G3_TX_DP<11>")
	)
	(segment
		(start 122.771916 -223.911922)
		(end 122.802396 -223.929702)
		(width 0.1143)
		(layer "In15.Cu")
		(net "GMI_CPU0_G1_CPU1_G3_TX_DP<11>")
	)
	(segment
		(start 348.730316 -237.520226)
		(end 348.7293 -237.519718)
		(width 0.1143)
		(layer "In15.Cu")
		(net "GMI_CPU0_G1_CPU1_G3_TX_DP<11>")
	)
	(segment
		(start 347.126306 -221.80423)
		(end 347.126306 -221.354142)
		(width 0.1143)
		(layer "In15.Cu")
		(net "GMI_CPU0_G1_CPU1_G3_TX_DP<11>")
	)
	(segment
		(start 348.732094 -228.766878)
		(end 348.746064 -228.75875)
		(width 0.1143)
		(layer "In15.Cu")
		(net "GMI_CPU0_G1_CPU1_G3_TX_DP<11>")
	)
	(segment
		(start 158.216092 -189.88786)
		(end 158.216092 -189.887606)
		(width 0.14224)
		(layer "In15.Cu")
		(net "GMI_CPU0_G1_CPU1_G3_TX_DP<11>")
	)
	(segment
		(start 348.723966 -228.771704)
		(end 348.724982 -228.771196)
		(width 0.1143)
		(layer "In15.Cu")
		(net "GMI_CPU0_G1_CPU1_G3_TX_DP<11>")
	)
	(segment
		(start 122.771916 -228.771958)
		(end 122.802396 -228.789738)
		(width 0.1143)
		(layer "In15.Cu")
		(net "GMI_CPU0_G1_CPU1_G3_TX_DP<11>")
	)
	(segment
		(start 349.083122 -244.484144)
		(end 349.000318 -244.40134)
		(width 0.1143)
		(layer "In15.Cu")
		(net "GMI_CPU0_G1_CPU1_G3_TX_DP<11>")
	)
	(segment
		(start 122.802396 -227.779326)
		(end 122.771916 -227.797106)
		(width 0.1143)
		(layer "In15.Cu")
		(net "GMI_CPU0_G1_CPU1_G3_TX_DP<11>")
	)
	(segment
		(start 122.802396 -237.499144)
		(end 122.771916 -237.516924)
		(width 0.1143)
		(layer "In15.Cu")
		(net "GMI_CPU0_G1_CPU1_G3_TX_DP<11>")
	)
	(segment
		(start 348.724982 -232.657142)
		(end 348.723966 -232.656634)
		(width 0.1143)
		(layer "In15.Cu")
		(net "GMI_CPU0_G1_CPU1_G3_TX_DP<11>")
	)
	(segment
		(start 122.771916 -222.93707)
		(end 122.7328 -222.95993)
		(width 0.1143)
		(layer "In15.Cu")
		(net "GMI_CPU0_G1_CPU1_G3_TX_DP<11>")
	)
	(segment
		(start 348.723458 -236.871764)
		(end 348.744794 -236.859318)
		(width 0.1143)
		(layer "In15.Cu")
		(net "GMI_CPU0_G1_CPU1_G3_TX_DP<11>")
	)
	(segment
		(start 348.76232 -239.159034)
		(end 348.730316 -239.140238)
		(width 0.1143)
		(layer "In15.Cu")
		(net "GMI_CPU0_G1_CPU1_G3_TX_DP<11>")
	)
	(segment
		(start 348.692216 -227.16998)
		(end 348.723966 -227.151692)
		(width 0.1143)
		(layer "In15.Cu")
		(net "GMI_CPU0_G1_CPU1_G3_TX_DP<11>")
	)
	(segment
		(start 122.771916 -227.151946)
		(end 122.802396 -227.169726)
		(width 0.1143)
		(layer "In15.Cu")
		(net "GMI_CPU0_G1_CPU1_G3_TX_DP<11>")
	)
	(segment
		(start 348.763082 -232.679494)
		(end 348.724982 -232.657142)
		(width 0.1143)
		(layer "In15.Cu")
		(net "GMI_CPU0_G1_CPU1_G3_TX_DP<11>")
	)
	(segment
		(start 122.7328 -235.228892)
		(end 122.771916 -235.251752)
		(width 0.1143)
		(layer "In15.Cu")
		(net "GMI_CPU0_G1_CPU1_G3_TX_DP<11>")
	)
	(segment
		(start 348.730316 -239.140238)
		(end 348.7293 -239.13973)
		(width 0.1143)
		(layer "In15.Cu")
		(net "GMI_CPU0_G1_CPU1_G3_TX_DP<11>")
	)
	(segment
		(start 122.771916 -238.491776)
		(end 122.802396 -238.509556)
		(width 0.1143)
		(layer "In15.Cu")
		(net "GMI_CPU0_G1_CPU1_G3_TX_DP<11>")
	)
	(segment
		(start 347.31325 -222.126302)
		(end 347.305884 -222.122238)
		(width 0.1143)
		(layer "In15.Cu")
		(net "GMI_CPU0_G1_CPU1_G3_TX_DP<11>")
	)
	(segment
		(start 122.771916 -229.416864)
		(end 122.734832 -229.4382)
		(width 0.1143)
		(layer "In15.Cu")
		(net "GMI_CPU0_G1_CPU1_G3_TX_DP<11>")
	)
	(segment
		(start 348.723458 -241.7318)
		(end 348.744794 -241.719354)
		(width 0.1143)
		(layer "In15.Cu")
		(net "GMI_CPU0_G1_CPU1_G3_TX_DP<11>")
	)
	(segment
		(start 122.802396 -234.25912)
		(end 122.771916 -234.2769)
		(width 0.1143)
		(layer "In15.Cu")
		(net "GMI_CPU0_G1_CPU1_G3_TX_DP<11>")
	)
	(segment
		(start 348.744794 -236.859318)
		(end 348.745048 -236.859318)
		(width 0.1143)
		(layer "In15.Cu")
		(net "GMI_CPU0_G1_CPU1_G3_TX_DP<11>")
	)
	(segment
		(start 347.12656 -221.097602)
		(end 347.12656 -221.083124)
		(width 0.1143)
		(layer "In15.Cu")
		(net "GMI_CPU0_G1_CPU1_G3_TX_DP<11>")
	)
	(segment
		(start 167.288972 -184.343294)
		(end 163.189412 -185.809382)
		(width 0.14224)
		(layer "In15.Cu")
		(net "GMI_CPU0_G1_CPU1_G3_TX_DP<11>")
	)
	(segment
		(start 348.723966 -230.391716)
		(end 348.724982 -230.391208)
		(width 0.1143)
		(layer "In15.Cu")
		(net "GMI_CPU0_G1_CPU1_G3_TX_DP<11>")
	)
	(segment
		(start 302.626268 -185.131202)
		(end 302.62322 -185.131202)
		(width 0.14224)
		(layer "In15.Cu")
		(net "GMI_CPU0_G1_CPU1_G3_TX_DP<11>")
	)
	(segment
		(start 348.726506 -232.00995)
		(end 348.763082 -231.988614)
		(width 0.1143)
		(layer "In15.Cu")
		(net "GMI_CPU0_G1_CPU1_G3_TX_DP<11>")
	)
	(segment
		(start 348.746064 -228.75875)
		(end 348.763082 -228.748844)
		(width 0.1143)
		(layer "In15.Cu")
		(net "GMI_CPU0_G1_CPU1_G3_TX_DP<11>")
	)
	(segment
		(start 122.7328 -243.328952)
		(end 122.771916 -243.351812)
		(width 0.1143)
		(layer "In15.Cu")
		(net "GMI_CPU0_G1_CPU1_G3_TX_DP<11>")
	)
	(segment
		(start 122.771916 -237.516924)
		(end 122.7328 -237.539784)
		(width 0.1143)
		(layer "In15.Cu")
		(net "GMI_CPU0_G1_CPU1_G3_TX_DP<11>")
	)
	(segment
		(start 122.802396 -232.639108)
		(end 122.771916 -232.656888)
		(width 0.1143)
		(layer "In15.Cu")
		(net "GMI_CPU0_G1_CPU1_G3_TX_DP<11>")
	)
	(segment
		(start 348.723204 -232.656126)
		(end 348.692216 -232.638346)
		(width 0.1143)
		(layer "In15.Cu")
		(net "GMI_CPU0_G1_CPU1_G3_TX_DP<11>")
	)
	(segment
		(start 347.314012 -222.12681)
		(end 347.31325 -222.126302)
		(width 0.1143)
		(layer "In15.Cu")
		(net "GMI_CPU0_G1_CPU1_G3_TX_DP<11>")
	)
	(segment
		(start 348.723204 -243.352066)
		(end 348.723966 -243.351558)
		(width 0.1143)
		(layer "In15.Cu")
		(net "GMI_CPU0_G1_CPU1_G3_TX_DP<11>")
	)
	(segment
		(start 348.75597 -230.373174)
		(end 348.760542 -230.37038)
		(width 0.1143)
		(layer "In15.Cu")
		(net "GMI_CPU0_G1_CPU1_G3_TX_DP<11>")
	)
	(segment
		(start 348.7293 -242.379754)
		(end 348.728538 -242.379246)
		(width 0.1143)
		(layer "In15.Cu")
		(net "GMI_CPU0_G1_CPU1_G3_TX_DP<11>")
	)
	(segment
		(start 348.728538 -240.759234)
		(end 348.716092 -240.752122)
		(width 0.1143)
		(layer "In15.Cu")
		(net "GMI_CPU0_G1_CPU1_G3_TX_DP<11>")
	)
	(segment
		(start 348.724982 -243.35105)
		(end 348.726506 -243.350034)
		(width 0.1143)
		(layer "In15.Cu")
		(net "GMI_CPU0_G1_CPU1_G3_TX_DP<11>")
	)
	(segment
		(start 122.7328 -227.129086)
		(end 122.771916 -227.151946)
		(width 0.1143)
		(layer "In15.Cu")
		(net "GMI_CPU0_G1_CPU1_G3_TX_DP<11>")
	)
	(segment
		(start 348.723966 -227.151692)
		(end 348.760288 -227.130864)
		(width 0.1143)
		(layer "In15.Cu")
		(net "GMI_CPU0_G1_CPU1_G3_TX_DP<11>")
	)
	(segment
		(start 348.728538 -239.139222)
		(end 348.716092 -239.13211)
		(width 0.1143)
		(layer "In15.Cu")
		(net "GMI_CPU0_G1_CPU1_G3_TX_DP<11>")
	)
	(segment
		(start 348.724982 -233.630978)
		(end 348.726506 -233.629962)
		(width 0.1143)
		(layer "In15.Cu")
		(net "GMI_CPU0_G1_CPU1_G3_TX_DP<11>")
	)
	(segment
		(start 122.771916 -239.136936)
		(end 122.7328 -239.159796)
		(width 0.1143)
		(layer "In15.Cu")
		(net "GMI_CPU0_G1_CPU1_G3_TX_DP<11>")
	)
	(segment
		(start 348.756224 -244.015514)
		(end 348.755462 -244.015006)
		(width 0.1143)
		(layer "In15.Cu")
		(net "GMI_CPU0_G1_CPU1_G3_TX_DP<11>")
	)
	(segment
		(start 348.744794 -241.719354)
		(end 348.745048 -241.719354)
		(width 0.1143)
		(layer "In15.Cu")
		(net "GMI_CPU0_G1_CPU1_G3_TX_DP<11>")
	)
	(segment
		(start 348.692216 -232.029762)
		(end 348.723204 -232.011982)
		(width 0.1143)
		(layer "In15.Cu")
		(net "GMI_CPU0_G1_CPU1_G3_TX_DP<11>")
	)
	(segment
		(start 348.760288 -227.130864)
		(end 348.763082 -227.128832)
		(width 0.1143)
		(layer "In15.Cu")
		(net "GMI_CPU0_G1_CPU1_G3_TX_DP<11>")
	)
	(segment
		(start 122.7328 -228.749098)
		(end 122.771916 -228.771958)
		(width 0.1143)
		(layer "In15.Cu")
		(net "GMI_CPU0_G1_CPU1_G3_TX_DP<11>")
	)
	(segment
		(start 348.692216 -243.369846)
		(end 348.723204 -243.352066)
		(width 0.1143)
		(layer "In15.Cu")
		(net "GMI_CPU0_G1_CPU1_G3_TX_DP<11>")
	)
	(segment
		(start 347.08084 -221.308676)
		(end 347.08084 -221.143322)
		(width 0.1143)
		(layer "In15.Cu")
		(net "GMI_CPU0_G1_CPU1_G3_TX_DP<11>")
	)
	(segment
		(start 348.723458 -240.111788)
		(end 348.744794 -240.099342)
		(width 0.1143)
		(layer "In15.Cu")
		(net "GMI_CPU0_G1_CPU1_G3_TX_DP<11>")
	)
	(segment
		(start 122.42419 -220.070934)
		(end 122.42419 -220.991938)
		(width 0.14224)
		(layer "In15.Cu")
		(net "GMI_CPU0_G1_CPU1_G3_TX_DP<11>")
	)
	(segment
		(start 348.726252 -230.390446)
		(end 348.727014 -230.389938)
		(width 0.1143)
		(layer "In15.Cu")
		(net "GMI_CPU0_G1_CPU1_G3_TX_DP<11>")
	)
	(segment
		(start 302.62322 -185.131202)
		(end 302.62322 -185.130948)
		(width 0.14224)
		(layer "In15.Cu")
		(net "GMI_CPU0_G1_CPU1_G3_TX_DP<11>")
	)
	(segment
		(start 348.730316 -240.76025)
		(end 348.7293 -240.759742)
		(width 0.1143)
		(layer "In15.Cu")
		(net "GMI_CPU0_G1_CPU1_G3_TX_DP<11>")
	)
	(segment
		(start 348.723204 -232.011982)
		(end 348.723966 -232.011474)
		(width 0.1143)
		(layer "In15.Cu")
		(net "GMI_CPU0_G1_CPU1_G3_TX_DP<11>")
	)
	(segment
		(start 122.46991 -221.066106)
		(end 122.46991 -221.277942)
		(width 0.1143)
		(layer "In15.Cu")
		(net "GMI_CPU0_G1_CPU1_G3_TX_DP<11>")
	)
	(segment
		(start 163.189412 -185.809382)
		(end 158.216092 -189.88786)
		(width 0.14224)
		(layer "In15.Cu")
		(net "GMI_CPU0_G1_CPU1_G3_TX_DP<11>")
	)
	(segment
		(start 122.733816 -222.270066)
		(end 122.803412 -222.310198)
		(width 0.1143)
		(layer "In15.Cu")
		(net "GMI_CPU0_G1_CPU1_G3_TX_DP<11>")
	)
	(segment
		(start 348.257368 -225.368866)
		(end 348.255844 -225.36785)
		(width 0.1143)
		(layer "In15.Cu")
		(net "GMI_CPU0_G1_CPU1_G3_TX_DP<11>")
	)
	(segment
		(start 347.315028 -222.127318)
		(end 347.314012 -222.12681)
		(width 0.1143)
		(layer "In15.Cu")
		(net "GMI_CPU0_G1_CPU1_G3_TX_DP<11>")
	)
	(segment
		(start 348.722696 -228.772466)
		(end 348.723204 -228.772212)
		(width 0.1143)
		(layer "In15.Cu")
		(net "GMI_CPU0_G1_CPU1_G3_TX_DP<11>")
	)
	(segment
		(start 348.726506 -243.350034)
		(end 348.763082 -243.328698)
		(width 0.1143)
		(layer "In15.Cu")
		(net "GMI_CPU0_G1_CPU1_G3_TX_DP<11>")
	)
	(segment
		(start 348.76232 -237.539022)
		(end 348.730316 -237.520226)
		(width 0.1143)
		(layer "In15.Cu")
		(net "GMI_CPU0_G1_CPU1_G3_TX_DP<11>")
	)
	(segment
		(start 348.727014 -230.389938)
		(end 348.75597 -230.373174)
		(width 0.1143)
		(layer "In15.Cu")
		(net "GMI_CPU0_G1_CPU1_G3_TX_DP<11>")
	)
	(segment
		(start 122.771916 -234.2769)
		(end 122.7328 -234.29976)
		(width 0.1143)
		(layer "In15.Cu")
		(net "GMI_CPU0_G1_CPU1_G3_TX_DP<11>")
	)
	(segment
		(start 348.745048 -238.47933)
		(end 348.763082 -238.468662)
		(width 0.1143)
		(layer "In15.Cu")
		(net "GMI_CPU0_G1_CPU1_G3_TX_DP<11>")
	)
	(segment
		(start 122.73534 -230.370634)
		(end 122.802396 -230.40975)
		(width 0.1143)
		(layer "In15.Cu")
		(net "GMI_CPU0_G1_CPU1_G3_TX_DP<11>")
	)
	(segment
		(start 348.724982 -230.391208)
		(end 348.726252 -230.390446)
		(width 0.1143)
		(layer "In15.Cu")
		(net "GMI_CPU0_G1_CPU1_G3_TX_DP<11>")
	)
	(segment
		(start 348.290388 -225.387916)
		(end 348.257368 -225.368866)
		(width 0.1143)
		(layer "In15.Cu")
		(net "GMI_CPU0_G1_CPU1_G3_TX_DP<11>")
	)
	(segment
		(start 307.390292 -185.531252)
		(end 306.478432 -185.154316)
		(width 0.14224)
		(layer "In15.Cu")
		(net "GMI_CPU0_G1_CPU1_G3_TX_DP<11>")
	)
	(segment
		(start 302.62322 -185.130948)
		(end 302.60671 -185.130948)
		(width 0.14224)
		(layer "In15.Cu")
		(net "GMI_CPU0_G1_CPU1_G3_TX_DP<11>")
	)
	(segment
		(start 348.727522 -228.769672)
		(end 348.73057 -228.767894)
		(width 0.1143)
		(layer "In15.Cu")
		(net "GMI_CPU0_G1_CPU1_G3_TX_DP<11>")
	)
	(segment
		(start 348.692216 -230.410004)
		(end 348.72041 -230.393748)
		(width 0.1143)
		(layer "In15.Cu")
		(net "GMI_CPU0_G1_CPU1_G3_TX_DP<11>")
	)
	(segment
		(start 122.734832 -229.4382)
		(end 122.7328 -229.439724)
		(width 0.1143)
		(layer "In15.Cu")
		(net "GMI_CPU0_G1_CPU1_G3_TX_DP<11>")
	)
	(segment
		(start 348.73057 -228.767894)
		(end 348.732094 -228.766878)
		(width 0.1143)
		(layer "In15.Cu")
		(net "GMI_CPU0_G1_CPU1_G3_TX_DP<11>")
	)
	(segment
		(start 347.823028 -222.959676)
		(end 347.783912 -222.936816)
		(width 0.1143)
		(layer "In15.Cu")
		(net "GMI_CPU0_G1_CPU1_G3_TX_DP<11>")
	)
	(segment
		(start 122.771916 -243.351812)
		(end 122.802396 -243.369592)
		(width 0.1143)
		(layer "In15.Cu")
		(net "GMI_CPU0_G1_CPU1_G3_TX_DP<11>")
	)
	(segment
		(start 348.723966 -232.011474)
		(end 348.724982 -232.010966)
		(width 0.1143)
		(layer "In15.Cu")
		(net "GMI_CPU0_G1_CPU1_G3_TX_DP<11>")
	)
	(segment
		(start 348.724982 -232.010966)
		(end 348.726506 -232.00995)
		(width 0.1143)
		(layer "In15.Cu")
		(net "GMI_CPU0_G1_CPU1_G3_TX_DP<11>")
	)
	(segment
		(start 314.258452 -189.817756)
		(end 307.390292 -185.531252)
		(width 0.14224)
		(layer "In15.Cu")
		(net "GMI_CPU0_G1_CPU1_G3_TX_DP<11>")
	)
	(segment
		(start 348.744794 -238.47933)
		(end 348.745048 -238.47933)
		(width 0.1143)
		(layer "In15.Cu")
		(net "GMI_CPU0_G1_CPU1_G3_TX_DP<11>")
	)
	(segment
		(start 349.381064 -244.484144)
		(end 349.083122 -244.484144)
		(width 0.1143)
		(layer "In15.Cu")
		(net "GMI_CPU0_G1_CPU1_G3_TX_DP<11>")
	)
	(segment
		(start 348.255844 -225.36785)
		(end 348.254066 -225.366834)
		(width 0.1143)
		(layer "In15.Cu")
		(net "GMI_CPU0_G1_CPU1_G3_TX_DP<11>")
	)
	(segment
		(start 348.744794 -235.239306)
		(end 348.745048 -235.239306)
		(width 0.1143)
		(layer "In15.Cu")
		(net "GMI_CPU0_G1_CPU1_G3_TX_DP<11>")
	)
	(segment
		(start 122.804428 -231.01808)
		(end 122.771916 -231.036876)
		(width 0.1143)
		(layer "In15.Cu")
		(net "GMI_CPU0_G1_CPU1_G3_TX_DP<11>")
	)
	(segment
		(start 122.42419 -220.991938)
		(end 122.42419 -221.020386)
		(width 0.1143)
		(layer "In15.Cu")
		(net "GMI_CPU0_G1_CPU1_G3_TX_DP<11>")
	)
	(segment
		(start 348.76232 -242.399058)
		(end 348.730316 -242.380262)
		(width 0.1143)
		(layer "In15.Cu")
		(net "GMI_CPU0_G1_CPU1_G3_TX_DP<11>")
	)
	(segment
		(start 348.763082 -231.059482)
		(end 348.713806 -231.03078)
		(width 0.1143)
		(layer "In15.Cu")
		(net "GMI_CPU0_G1_CPU1_G3_TX_DP<11>")
	)
	(segment
		(start 347.12656 -219.783152)
		(end 344.795602 -214.857838)
		(width 0.14224)
		(layer "In15.Cu")
		(net "GMI_CPU0_G1_CPU1_G3_TX_DP<11>")
	)
	(segment
		(start 122.802396 -239.119156)
		(end 122.771916 -239.136936)
		(width 0.1143)
		(layer "In15.Cu")
		(net "GMI_CPU0_G1_CPU1_G3_TX_DP<11>")
	)
	(segment
		(start 348.728538 -235.899198)
		(end 348.727014 -235.898436)
		(width 0.1143)
		(layer "In15.Cu")
		(net "GMI_CPU0_G1_CPU1_G3_TX_DP<11>")
	)
	(segment
		(start 122.489214 -221.297246)
		(end 122.489214 -221.804484)
		(width 0.1143)
		(layer "In15.Cu")
		(net "GMI_CPU0_G1_CPU1_G3_TX_DP<11>")
	)
	(segment
		(start 348.763082 -229.43947)
		(end 348.723966 -229.41661)
		(width 0.1143)
		(layer "In15.Cu")
		(net "GMI_CPU0_G1_CPU1_G3_TX_DP<11>")
	)
	(segment
		(start 122.495564 -244.401594)
		(end 122.41276 -244.484398)
		(width 0.1143)
		(layer "In15.Cu")
		(net "GMI_CPU0_G1_CPU1_G3_TX_DP<11>")
	)
	(segment
		(start 348.728538 -242.379246)
		(end 348.716092 -242.372134)
		(width 0.1143)
		(layer "In15.Cu")
		(net "GMI_CPU0_G1_CPU1_G3_TX_DP<11>")
	)
	(segment
		(start 348.723966 -243.351558)
		(end 348.724982 -243.35105)
		(width 0.1143)
		(layer "In15.Cu")
		(net "GMI_CPU0_G1_CPU1_G3_TX_DP<11>")
	)
	(segment
		(start 122.771916 -232.656888)
		(end 122.7328 -232.679748)
		(width 0.1143)
		(layer "In15.Cu")
		(net "GMI_CPU0_G1_CPU1_G3_TX_DP<11>")
	)
	(segment
		(start 348.745048 -236.859318)
		(end 348.763082 -236.84865)
		(width 0.1143)
		(layer "In15.Cu")
		(net "GMI_CPU0_G1_CPU1_G3_TX_DP<11>")
	)
	(segment
		(start 348.756224 -227.815648)
		(end 348.755462 -227.81514)
		(width 0.1143)
		(layer "In15.Cu")
		(net "GMI_CPU0_G1_CPU1_G3_TX_DP<11>")
	)
	(segment
		(start 122.771916 -241.7318)
		(end 122.802396 -241.74958)
		(width 0.1143)
		(layer "In15.Cu")
		(net "GMI_CPU0_G1_CPU1_G3_TX_DP<11>")
	)
	(segment
		(start 348.72041 -230.393748)
		(end 348.721934 -230.392986)
		(width 0.1143)
		(layer "In15.Cu")
		(net "GMI_CPU0_G1_CPU1_G3_TX_DP<11>")
	)
	(segment
		(start 122.771916 -224.557082)
		(end 122.7328 -224.579942)
		(width 0.1143)
		(layer "In15.Cu")
		(net "GMI_CPU0_G1_CPU1_G3_TX_DP<11>")
	)
	(segment
		(start 122.802396 -240.739168)
		(end 122.771916 -240.756948)
		(width 0.1143)
		(layer "In15.Cu")
		(net "GMI_CPU0_G1_CPU1_G3_TX_DP<11>")
	)
	(segment
		(start 348.744794 -240.099342)
		(end 348.745048 -240.099342)
		(width 0.1143)
		(layer "In15.Cu")
		(net "GMI_CPU0_G1_CPU1_G3_TX_DP<11>")
	)
	(segment
		(start 348.727014 -235.898436)
		(end 348.716092 -235.892086)
		(width 0.1143)
		(layer "In15.Cu")
		(net "GMI_CPU0_G1_CPU1_G3_TX_DP<11>")
	)
	(segment
		(start 122.42419 -221.020386)
		(end 122.46991 -221.066106)
		(width 0.1143)
		(layer "In15.Cu")
		(net "GMI_CPU0_G1_CPU1_G3_TX_DP<11>")
	)
	(segment
		(start 348.763082 -244.019578)
		(end 348.756224 -244.015514)
		(width 0.1143)
		(layer "In15.Cu")
		(net "GMI_CPU0_G1_CPU1_G3_TX_DP<11>")
	)
	(segment
		(start 348.254066 -225.366834)
		(end 348.222316 -225.348546)
		(width 0.1143)
		(layer "In15.Cu")
		(net "GMI_CPU0_G1_CPU1_G3_TX_DP<11>")
	)
	(segment
		(start 348.728538 -237.51921)
		(end 348.716092 -237.512098)
		(width 0.1143)
		(layer "In15.Cu")
		(net "GMI_CPU0_G1_CPU1_G3_TX_DP<11>")
	)
	(segment
		(start 347.753432 -223.929448)
		(end 347.783912 -223.911668)
		(width 0.1143)
		(layer "In15.Cu")
		(net "GMI_CPU0_G1_CPU1_G3_TX_DP<11>")
	)
	(segment
		(start 348.755462 -244.015006)
		(end 348.723966 -243.996718)
		(width 0.1143)
		(layer "In15.Cu")
		(net "GMI_CPU0_G1_CPU1_G3_TX_DP<11>")
	)
	(segment
		(start 306.478432 -185.154062)
		(end 306.42687 -185.13298)
		(width 0.14224)
		(layer "In15.Cu")
		(net "GMI_CPU0_G1_CPU1_G3_TX_DP<11>")
	)
	(segment
		(start 348.723966 -226.17684)
		(end 348.693232 -226.15906)
		(width 0.1143)
		(layer "In15.Cu")
		(net "GMI_CPU0_G1_CPU1_G3_TX_DP<11>")
	)
	(segment
		(start 347.783912 -222.936816)
		(end 347.753432 -222.919036)
		(width 0.1143)
		(layer "In15.Cu")
		(net "GMI_CPU0_G1_CPU1_G3_TX_DP<11>")
	)
	(segment
		(start 122.771916 -226.177094)
		(end 122.7328 -226.199954)
		(width 0.1143)
		(layer "In15.Cu")
		(net "GMI_CPU0_G1_CPU1_G3_TX_DP<11>")
	)
	(segment
		(start 122.802396 -222.91929)
		(end 122.771916 -222.93707)
		(width 0.1143)
		(layer "In15.Cu")
		(net "GMI_CPU0_G1_CPU1_G3_TX_DP<11>")
	)
	(segment
		(start 348.7293 -240.759742)
		(end 348.728538 -240.759234)
		(width 0.1143)
		(layer "In15.Cu")
		(net "GMI_CPU0_G1_CPU1_G3_TX_DP<11>")
	)
	(segment
		(start 122.7328 -240.088928)
		(end 122.771916 -240.111788)
		(width 0.1143)
		(layer "In15.Cu")
		(net "GMI_CPU0_G1_CPU1_G3_TX_DP<11>")
	)
	(segment
		(start 302.60671 -185.130948)
		(end 167.288972 -184.343294)
		(width 0.14224)
		(layer "In15.Cu")
		(net "GMI_CPU0_G1_CPU1_G3_TX_DP<11>")
	)
	(segment
		(start 348.755462 -227.81514)
		(end 348.723966 -227.796852)
		(width 0.1143)
		(layer "In15.Cu")
		(net "GMI_CPU0_G1_CPU1_G3_TX_DP<11>")
	)
	(segment
		(start 348.7293 -235.899706)
		(end 348.728538 -235.899198)
		(width 0.1143)
		(layer "In15.Cu")
		(net "GMI_CPU0_G1_CPU1_G3_TX_DP<11>")
	)
	(segment
		(start 348.755208 -235.914692)
		(end 348.7293 -235.899706)
		(width 0.1143)
		(layer "In15.Cu")
		(net "GMI_CPU0_G1_CPU1_G3_TX_DP<11>")
	)
	(segment
		(start 122.7328 -231.988868)
		(end 122.771916 -232.011728)
		(width 0.1143)
		(layer "In15.Cu")
		(net "GMI_CPU0_G1_CPU1_G3_TX_DP<11>")
	)
	(segment
		(start 122.7328 -238.468916)
		(end 122.771916 -238.491776)
		(width 0.1143)
		(layer "In15.Cu")
		(net "GMI_CPU0_G1_CPU1_G3_TX_DP<11>")
	)
	(segment
		(start 348.723204 -243.99621)
		(end 348.692216 -243.97843)
		(width 0.1143)
		(layer "In15.Cu")
		(net "GMI_CPU0_G1_CPU1_G3_TX_DP<11>")
	)
	(segment
		(start 347.783912 -224.556828)
		(end 347.753432 -224.539048)
		(width 0.1143)
		(layer "In15.Cu")
		(net "GMI_CPU0_G1_CPU1_G3_TX_DP<11>")
	)
	(segment
		(start 122.771916 -232.011728)
		(end 122.802396 -232.029508)
		(width 0.1143)
		(layer "In15.Cu")
		(net "GMI_CPU0_G1_CPU1_G3_TX_DP<11>")
	)
	(segment
		(start 348.724982 -228.771196)
		(end 348.726506 -228.77018)
		(width 0.1143)
		(layer "In15.Cu")
		(net "GMI_CPU0_G1_CPU1_G3_TX_DP<11>")
	)
	(segment
		(start 145.224754 -199.550528)
		(end 124.441458 -216.59215)
		(width 0.14224)
		(layer "In15.Cu")
		(net "GMI_CPU0_G1_CPU1_G3_TX_DP<11>")
	)
	(segment
		(start 348.721934 -230.392986)
		(end 348.723204 -230.392224)
		(width 0.1143)
		(layer "In15.Cu")
		(net "GMI_CPU0_G1_CPU1_G3_TX_DP<11>")
	)
	(segment
		(start 348.745048 -240.099342)
		(end 348.763082 -240.088674)
		(width 0.1143)
		(layer "In15.Cu")
		(net "GMI_CPU0_G1_CPU1_G3_TX_DP<11>")
	)
	(segment
		(start 122.46991 -221.277942)
		(end 122.489214 -221.297246)
		(width 0.1143)
		(layer "In15.Cu")
		(net "GMI_CPU0_G1_CPU1_G3_TX_DP<11>")
	)
	(segment
		(start 122.802396 -235.879132)
		(end 122.771916 -235.896912)
		(width 0.1143)
		(layer "In15.Cu")
		(net "GMI_CPU0_G1_CPU1_G3_TX_DP<11>")
	)
	(segment
		(start 122.804428 -229.398068)
		(end 122.771916 -229.416864)
		(width 0.1143)
		(layer "In15.Cu")
		(net "GMI_CPU0_G1_CPU1_G3_TX_DP<11>")
	)
	(segment
		(start 347.08084 -221.143322)
		(end 347.12656 -221.097602)
		(width 0.1143)
		(layer "In15.Cu")
		(net "GMI_CPU0_G1_CPU1_G3_TX_DP<11>")
	)
	(segment
		(start 158.215838 -189.88786)
		(end 158.125668 -189.961774)
		(width 0.14224)
		(layer "In15.Cu")
		(net "GMI_CPU0_G1_CPU1_G3_TX_DP<11>")
	)
	(arc
		(start 122.959368 -230.71455)
		(mid 122.918402 -230.884956)
		(end 122.804428 -231.01808)
		(width 0.1143)
		(layer "In15.Cu")
		(net "GMI_CPU0_G1_CPU1_G3_TX_DP<11>")
	)
	(arc
		(start 122.802396 -238.509556)
		(mid 122.959373 -238.814356)
		(end 122.802396 -239.119156)
		(width 0.1143)
		(layer "In15.Cu")
		(net "GMI_CPU0_G1_CPU1_G3_TX_DP<11>")
	)
	(arc
		(start 347.59646 -222.614236)
		(mid 347.531945 -222.352017)
		(end 347.353128 -222.14967)
		(width 0.1143)
		(layer "In15.Cu")
		(net "GMI_CPU0_G1_CPU1_G3_TX_DP<11>")
	)
	(arc
		(start 122.7328 -237.539784)
		(mid 122.489473 -238.00435)
		(end 122.7328 -238.468916)
		(width 0.1143)
		(layer "In15.Cu")
		(net "GMI_CPU0_G1_CPU1_G3_TX_DP<11>")
	)
	(arc
		(start 348.06636 -225.044254)
		(mid 348.001845 -224.782035)
		(end 347.823028 -224.579688)
		(width 0.1143)
		(layer "In15.Cu")
		(net "GMI_CPU0_G1_CPU1_G3_TX_DP<11>")
	)
	(arc
		(start 347.823028 -223.888808)
		(mid 348.066355 -223.424242)
		(end 347.823028 -222.959676)
		(width 0.1143)
		(layer "In15.Cu")
		(net "GMI_CPU0_G1_CPU1_G3_TX_DP<11>")
	)
	(arc
		(start 122.733054 -222.269558)
		(mid 122.733435 -222.269812)
		(end 122.733816 -222.270066)
		(width 0.1143)
		(layer "In15.Cu")
		(net "GMI_CPU0_G1_CPU1_G3_TX_DP<11>")
	)
	(arc
		(start 347.753432 -222.919036)
		(mid 347.638005 -222.78566)
		(end 347.59646 -222.614236)
		(width 0.1143)
		(layer "In15.Cu")
		(net "GMI_CPU0_G1_CPU1_G3_TX_DP<11>")
	)
	(arc
		(start 122.959368 -229.094538)
		(mid 122.918402 -229.264944)
		(end 122.804428 -229.398068)
		(width 0.1143)
		(layer "In15.Cu")
		(net "GMI_CPU0_G1_CPU1_G3_TX_DP<11>")
	)
	(arc
		(start 348.996508 -244.37848)
		(mid 348.915075 -244.176082)
		(end 348.763082 -244.019578)
		(width 0.1143)
		(layer "In15.Cu")
		(net "GMI_CPU0_G1_CPU1_G3_TX_DP<11>")
	)
	(arc
		(start 122.802396 -241.74958)
		(mid 122.959373 -242.05438)
		(end 122.802396 -242.35918)
		(width 0.1143)
		(layer "In15.Cu")
		(net "GMI_CPU0_G1_CPU1_G3_TX_DP<11>")
	)
	(arc
		(start 348.716092 -235.892086)
		(mid 348.537875 -235.569809)
		(end 348.723458 -235.251752)
		(width 0.1143)
		(layer "In15.Cu")
		(net "GMI_CPU0_G1_CPU1_G3_TX_DP<11>")
	)
	(arc
		(start 348.763082 -231.988614)
		(mid 349.006409 -231.524048)
		(end 348.763082 -231.059482)
		(width 0.1143)
		(layer "In15.Cu")
		(net "GMI_CPU0_G1_CPU1_G3_TX_DP<11>")
	)
	(arc
		(start 122.7328 -234.29976)
		(mid 122.489473 -234.764326)
		(end 122.7328 -235.228892)
		(width 0.1143)
		(layer "In15.Cu")
		(net "GMI_CPU0_G1_CPU1_G3_TX_DP<11>")
	)
	(arc
		(start 122.7328 -222.95993)
		(mid 122.489473 -223.424496)
		(end 122.7328 -223.889062)
		(width 0.1143)
		(layer "In15.Cu")
		(net "GMI_CPU0_G1_CPU1_G3_TX_DP<11>")
	)
	(arc
		(start 348.692216 -234.258358)
		(mid 348.540627 -233.954066)
		(end 348.692216 -233.649774)
		(width 0.1143)
		(layer "In15.Cu")
		(net "GMI_CPU0_G1_CPU1_G3_TX_DP<11>")
	)
	(arc
		(start 122.802396 -230.40975)
		(mid 122.917823 -230.543126)
		(end 122.959368 -230.71455)
		(width 0.1143)
		(layer "In15.Cu")
		(net "GMI_CPU0_G1_CPU1_G3_TX_DP<11>")
	)
	(arc
		(start 122.489468 -229.90429)
		(mid 122.554704 -230.167881)
		(end 122.73534 -230.370634)
		(width 0.1143)
		(layer "In15.Cu")
		(net "GMI_CPU0_G1_CPU1_G3_TX_DP<11>")
	)
	(arc
		(start 348.763082 -236.84865)
		(mid 349.006409 -236.384084)
		(end 348.763082 -235.919518)
		(width 0.1143)
		(layer "In15.Cu")
		(net "GMI_CPU0_G1_CPU1_G3_TX_DP<11>")
	)
	(arc
		(start 348.53626 -225.865436)
		(mid 348.533881 -225.827933)
		(end 348.528386 -225.79076)
		(width 0.1143)
		(layer "In15.Cu")
		(net "GMI_CPU0_G1_CPU1_G3_TX_DP<11>")
	)
	(arc
		(start 348.716092 -237.512098)
		(mid 348.537875 -237.189821)
		(end 348.723458 -236.871764)
		(width 0.1143)
		(layer "In15.Cu")
		(net "GMI_CPU0_G1_CPU1_G3_TX_DP<11>")
	)
	(arc
		(start 348.763082 -235.919518)
		(mid 348.762701 -235.919264)
		(end 348.76232 -235.91901)
		(width 0.1143)
		(layer "In15.Cu")
		(net "GMI_CPU0_G1_CPU1_G3_TX_DP<11>")
	)
	(arc
		(start 348.763082 -228.748844)
		(mid 349.006409 -228.284278)
		(end 348.763082 -227.819712)
		(width 0.1143)
		(layer "In15.Cu")
		(net "GMI_CPU0_G1_CPU1_G3_TX_DP<11>")
	)
	(arc
		(start 122.802396 -236.889544)
		(mid 122.959373 -237.194344)
		(end 122.802396 -237.499144)
		(width 0.1143)
		(layer "In15.Cu")
		(net "GMI_CPU0_G1_CPU1_G3_TX_DP<11>")
	)
	(arc
		(start 122.802396 -233.64952)
		(mid 122.959373 -233.95432)
		(end 122.802396 -234.25912)
		(width 0.1143)
		(layer "In15.Cu")
		(net "GMI_CPU0_G1_CPU1_G3_TX_DP<11>")
	)
	(arc
		(start 122.802396 -232.029508)
		(mid 122.959373 -232.334308)
		(end 122.802396 -232.639108)
		(width 0.1143)
		(layer "In15.Cu")
		(net "GMI_CPU0_G1_CPU1_G3_TX_DP<11>")
	)
	(arc
		(start 348.222316 -225.348546)
		(mid 348.10764 -225.215212)
		(end 348.06636 -225.044254)
		(width 0.1143)
		(layer "In15.Cu")
		(net "GMI_CPU0_G1_CPU1_G3_TX_DP<11>")
	)
	(arc
		(start 122.489214 -221.804484)
		(mid 122.553873 -222.067041)
		(end 122.733054 -222.269558)
		(width 0.1143)
		(layer "In15.Cu")
		(net "GMI_CPU0_G1_CPU1_G3_TX_DP<11>")
	)
	(arc
		(start 348.760542 -230.37038)
		(mid 348.941194 -230.167635)
		(end 349.006414 -229.904036)
		(width 0.1143)
		(layer "In15.Cu")
		(net "GMI_CPU0_G1_CPU1_G3_TX_DP<11>")
	)
	(arc
		(start 348.763082 -234.299506)
		(mid 348.762701 -234.299252)
		(end 348.76232 -234.298998)
		(width 0.1143)
		(layer "In15.Cu")
		(net "GMI_CPU0_G1_CPU1_G3_TX_DP<11>")
	)
	(arc
		(start 348.53626 -230.714296)
		(mid 348.579125 -230.544144)
		(end 348.692216 -230.410004)
		(width 0.1143)
		(layer "In15.Cu")
		(net "GMI_CPU0_G1_CPU1_G3_TX_DP<11>")
	)
	(arc
		(start 122.7328 -235.919772)
		(mid 122.489473 -236.384338)
		(end 122.7328 -236.848904)
		(width 0.1143)
		(layer "In15.Cu")
		(net "GMI_CPU0_G1_CPU1_G3_TX_DP<11>")
	)
	(arc
		(start 122.7328 -229.439724)
		(mid 122.553987 -229.642074)
		(end 122.489468 -229.90429)
		(width 0.1143)
		(layer "In15.Cu")
		(net "GMI_CPU0_G1_CPU1_G3_TX_DP<11>")
	)
	(arc
		(start 122.802396 -228.789738)
		(mid 122.917823 -228.923114)
		(end 122.959368 -229.094538)
		(width 0.1143)
		(layer "In15.Cu")
		(net "GMI_CPU0_G1_CPU1_G3_TX_DP<11>")
	)
	(arc
		(start 348.763082 -233.608626)
		(mid 349.006409 -233.14406)
		(end 348.763082 -232.679494)
		(width 0.1143)
		(layer "In15.Cu")
		(net "GMI_CPU0_G1_CPU1_G3_TX_DP<11>")
	)
	(arc
		(start 348.716092 -240.752122)
		(mid 348.537875 -240.429845)
		(end 348.723458 -240.111788)
		(width 0.1143)
		(layer "In15.Cu")
		(net "GMI_CPU0_G1_CPU1_G3_TX_DP<11>")
	)
	(arc
		(start 122.7328 -231.059736)
		(mid 122.489473 -231.524302)
		(end 122.7328 -231.988868)
		(width 0.1143)
		(layer "In15.Cu")
		(net "GMI_CPU0_G1_CPU1_G3_TX_DP<11>")
	)
	(arc
		(start 348.763082 -243.328698)
		(mid 349.006409 -242.864132)
		(end 348.763082 -242.399566)
		(width 0.1143)
		(layer "In15.Cu")
		(net "GMI_CPU0_G1_CPU1_G3_TX_DP<11>")
	)
	(arc
		(start 122.802396 -227.169726)
		(mid 122.959373 -227.474526)
		(end 122.802396 -227.779326)
		(width 0.1143)
		(layer "In15.Cu")
		(net "GMI_CPU0_G1_CPU1_G3_TX_DP<11>")
	)
	(arc
		(start 348.716092 -239.13211)
		(mid 348.537875 -238.809833)
		(end 348.723458 -238.491776)
		(width 0.1143)
		(layer "In15.Cu")
		(net "GMI_CPU0_G1_CPU1_G3_TX_DP<11>")
	)
	(arc
		(start 348.528386 -225.79076)
		(mid 348.454268 -225.585754)
		(end 348.321884 -225.412554)
		(width 0.1143)
		(layer "In15.Cu")
		(net "GMI_CPU0_G1_CPU1_G3_TX_DP<11>")
	)
	(arc
		(start 122.802396 -243.369592)
		(mid 122.959373 -243.674392)
		(end 122.802396 -243.979192)
		(width 0.1143)
		(layer "In15.Cu")
		(net "GMI_CPU0_G1_CPU1_G3_TX_DP<11>")
	)
	(arc
		(start 122.7328 -227.819966)
		(mid 122.489473 -228.284532)
		(end 122.7328 -228.749098)
		(width 0.1143)
		(layer "In15.Cu")
		(net "GMI_CPU0_G1_CPU1_G3_TX_DP<11>")
	)
	(arc
		(start 122.802396 -225.549714)
		(mid 122.959373 -225.854514)
		(end 122.802396 -226.159314)
		(width 0.1143)
		(layer "In15.Cu")
		(net "GMI_CPU0_G1_CPU1_G3_TX_DP<11>")
	)
	(arc
		(start 348.693232 -226.15906)
		(mid 348.580385 -226.030627)
		(end 348.53626 -225.865436)
		(width 0.1143)
		(layer "In15.Cu")
		(net "GMI_CPU0_G1_CPU1_G3_TX_DP<11>")
	)
	(arc
		(start 347.282262 -222.108522)
		(mid 347.167586 -221.975188)
		(end 347.126306 -221.80423)
		(width 0.1143)
		(layer "In15.Cu")
		(net "GMI_CPU0_G1_CPU1_G3_TX_DP<11>")
	)
	(arc
		(start 122.7328 -224.579942)
		(mid 122.489473 -225.044508)
		(end 122.7328 -225.509074)
		(width 0.1143)
		(layer "In15.Cu")
		(net "GMI_CPU0_G1_CPU1_G3_TX_DP<11>")
	)
	(arc
		(start 122.7328 -240.779808)
		(mid 122.489473 -241.244374)
		(end 122.7328 -241.70894)
		(width 0.1143)
		(layer "In15.Cu")
		(net "GMI_CPU0_G1_CPU1_G3_TX_DP<11>")
	)
	(arc
		(start 348.763082 -227.128832)
		(mid 349.006409 -226.664266)
		(end 348.763082 -226.1997)
		(width 0.1143)
		(layer "In15.Cu")
		(net "GMI_CPU0_G1_CPU1_G3_TX_DP<11>")
	)
	(arc
		(start 122.959368 -222.61449)
		(mid 122.917819 -222.785912)
		(end 122.802396 -222.91929)
		(width 0.1143)
		(layer "In15.Cu")
		(net "GMI_CPU0_G1_CPU1_G3_TX_DP<11>")
	)
	(arc
		(start 348.763082 -239.159542)
		(mid 348.762701 -239.159288)
		(end 348.76232 -239.159034)
		(width 0.1143)
		(layer "In15.Cu")
		(net "GMI_CPU0_G1_CPU1_G3_TX_DP<11>")
	)
	(arc
		(start 349.000318 -244.40134)
		(mid 348.99853 -244.389891)
		(end 348.996508 -244.37848)
		(width 0.1143)
		(layer "In15.Cu")
		(net "GMI_CPU0_G1_CPU1_G3_TX_DP<11>")
	)
	(arc
		(start 348.763082 -240.779554)
		(mid 348.762701 -240.7793)
		(end 348.76232 -240.779046)
		(width 0.1143)
		(layer "In15.Cu")
		(net "GMI_CPU0_G1_CPU1_G3_TX_DP<11>")
	)
	(arc
		(start 347.753432 -224.539048)
		(mid 347.596455 -224.234248)
		(end 347.753432 -223.929448)
		(width 0.1143)
		(layer "In15.Cu")
		(net "GMI_CPU0_G1_CPU1_G3_TX_DP<11>")
	)
	(arc
		(start 348.763082 -237.53953)
		(mid 348.762701 -237.539276)
		(end 348.76232 -237.539022)
		(width 0.1143)
		(layer "In15.Cu")
		(net "GMI_CPU0_G1_CPU1_G3_TX_DP<11>")
	)
	(arc
		(start 122.7328 -239.159796)
		(mid 122.489473 -239.624362)
		(end 122.7328 -240.088928)
		(width 0.1143)
		(layer "In15.Cu")
		(net "GMI_CPU0_G1_CPU1_G3_TX_DP<11>")
	)
	(arc
		(start 348.692216 -243.97843)
		(mid 348.543119 -243.674138)
		(end 348.692216 -243.369846)
		(width 0.1143)
		(layer "In15.Cu")
		(net "GMI_CPU0_G1_CPU1_G3_TX_DP<11>")
	)
	(arc
		(start 348.763082 -242.399566)
		(mid 348.762701 -242.399312)
		(end 348.76232 -242.399058)
		(width 0.1143)
		(layer "In15.Cu")
		(net "GMI_CPU0_G1_CPU1_G3_TX_DP<11>")
	)
	(arc
		(start 348.713806 -231.03078)
		(mid 348.581903 -230.896727)
		(end 348.53626 -230.714296)
		(width 0.1143)
		(layer "In15.Cu")
		(net "GMI_CPU0_G1_CPU1_G3_TX_DP<11>")
	)
	(arc
		(start 122.7328 -242.39982)
		(mid 122.489473 -242.864386)
		(end 122.7328 -243.328952)
		(width 0.1143)
		(layer "In15.Cu")
		(net "GMI_CPU0_G1_CPU1_G3_TX_DP<11>")
	)
	(arc
		(start 122.7328 -232.679748)
		(mid 122.489473 -233.144314)
		(end 122.7328 -233.60888)
		(width 0.1143)
		(layer "In15.Cu")
		(net "GMI_CPU0_G1_CPU1_G3_TX_DP<11>")
	)
	(arc
		(start 348.763082 -240.088674)
		(mid 349.006409 -239.624108)
		(end 348.763082 -239.159542)
		(width 0.1143)
		(layer "In15.Cu")
		(net "GMI_CPU0_G1_CPU1_G3_TX_DP<11>")
	)
	(arc
		(start 348.763082 -238.468662)
		(mid 349.006409 -238.004096)
		(end 348.763082 -237.53953)
		(width 0.1143)
		(layer "In15.Cu")
		(net "GMI_CPU0_G1_CPU1_G3_TX_DP<11>")
	)
	(arc
		(start 348.763082 -241.708686)
		(mid 349.006409 -241.24412)
		(end 348.763082 -240.779554)
		(width 0.1143)
		(layer "In15.Cu")
		(net "GMI_CPU0_G1_CPU1_G3_TX_DP<11>")
	)
	(arc
		(start 122.802396 -240.129568)
		(mid 122.959373 -240.434368)
		(end 122.802396 -240.739168)
		(width 0.1143)
		(layer "In15.Cu")
		(net "GMI_CPU0_G1_CPU1_G3_TX_DP<11>")
	)
	(arc
		(start 348.763082 -235.228638)
		(mid 349.006409 -234.764072)
		(end 348.763082 -234.299506)
		(width 0.1143)
		(layer "In15.Cu")
		(net "GMI_CPU0_G1_CPU1_G3_TX_DP<11>")
	)
	(arc
		(start 122.7328 -226.199954)
		(mid 122.489473 -226.66452)
		(end 122.7328 -227.129086)
		(width 0.1143)
		(layer "In15.Cu")
		(net "GMI_CPU0_G1_CPU1_G3_TX_DP<11>")
	)
	(arc
		(start 122.802396 -223.929702)
		(mid 122.959373 -224.234502)
		(end 122.802396 -224.539302)
		(width 0.1143)
		(layer "In15.Cu")
		(net "GMI_CPU0_G1_CPU1_G3_TX_DP<11>")
	)
	(arc
		(start 348.53626 -229.094284)
		(mid 348.586225 -228.908308)
		(end 348.722696 -228.772466)
		(width 0.1143)
		(layer "In15.Cu")
		(net "GMI_CPU0_G1_CPU1_G3_TX_DP<11>")
	)
	(arc
		(start 348.716092 -242.372134)
		(mid 348.537875 -242.049857)
		(end 348.723458 -241.7318)
		(width 0.1143)
		(layer "In15.Cu")
		(net "GMI_CPU0_G1_CPU1_G3_TX_DP<11>")
	)
	(arc
		(start 348.692216 -232.638346)
		(mid 348.543119 -232.334054)
		(end 348.692216 -232.029762)
		(width 0.1143)
		(layer "In15.Cu")
		(net "GMI_CPU0_G1_CPU1_G3_TX_DP<11>")
	)
	(arc
		(start 122.803412 -222.310198)
		(mid 122.918088 -222.443532)
		(end 122.959368 -222.61449)
		(width 0.1143)
		(layer "In15.Cu")
		(net "GMI_CPU0_G1_CPU1_G3_TX_DP<11>")
	)
	(arc
		(start 348.321884 -225.412554)
		(mid 348.306352 -225.399959)
		(end 348.290388 -225.387916)
		(width 0.1143)
		(layer "In15.Cu")
		(net "GMI_CPU0_G1_CPU1_G3_TX_DP<11>")
	)
	(arc
		(start 348.692216 -227.778564)
		(mid 348.543119 -227.474272)
		(end 348.692216 -227.16998)
		(width 0.1143)
		(layer "In15.Cu")
		(net "GMI_CPU0_G1_CPU1_G3_TX_DP<11>")
	)
	(arc
		(start 122.7328 -244.019832)
		(mid 122.580813 -244.17634)
		(end 122.499374 -244.378734)
		(width 0.1143)
		(layer "In15.Cu")
		(net "GMI_CPU0_G1_CPU1_G3_TX_DP<11>")
	)
	(arc
		(start 122.499374 -244.378734)
		(mid 122.497351 -244.390144)
		(end 122.495564 -244.401594)
		(width 0.1143)
		(layer "In15.Cu")
		(net "GMI_CPU0_G1_CPU1_G3_TX_DP<11>")
	)
	(arc
		(start 122.802396 -235.269532)
		(mid 122.959373 -235.574332)
		(end 122.802396 -235.879132)
		(width 0.1143)
		(layer "In15.Cu")
		(net "GMI_CPU0_G1_CPU1_G3_TX_DP<11>")
	)
	(arc
		(start 348.690438 -229.397052)
		(mid 348.577031 -229.264163)
		(end 348.53626 -229.094284)
		(width 0.1143)
		(layer "In15.Cu")
		(net "GMI_CPU0_G1_CPU1_G3_TX_DP<11>")
	)
	(arc
		(start 349.006414 -229.904036)
		(mid 348.941899 -229.641817)
		(end 348.763082 -229.43947)
		(width 0.1143)
		(layer "In15.Cu")
		(net "GMI_CPU0_G1_CPU1_G3_TX_DP<11>")
	)
	(segment
		(start 349.847916 -247.990106)
		(end 349.381064 -247.724168)
		(width 0.12954)
		(layer "F.Cu")
		(net "GMI_CPU0_G1_CPU1_G3_TX_DP<10>")
	)
	(segment
		(start 121.647966 -247.99036)
		(end 122.114818 -247.724422)
		(width 0.12954)
		(layer "F.Cu")
		(net "GMI_CPU0_G1_CPU1_G3_TX_DP<10>")
	)
	(segment
		(start 121.79935 -243.333016)
		(end 121.800112 -243.333524)
		(width 0.1143)
		(layer "In15.Cu")
		(net "GMI_CPU0_G1_CPU1_G3_TX_DP<10>")
	)
	(segment
		(start 349.163386 -247.419368)
		(end 349.193866 -247.401588)
		(width 0.1143)
		(layer "In15.Cu")
		(net "GMI_CPU0_G1_CPU1_G3_TX_DP<10>")
	)
	(segment
		(start 349.665036 -235.897166)
		(end 349.66402 -235.896658)
		(width 0.1143)
		(layer "In15.Cu")
		(net "GMI_CPU0_G1_CPU1_G3_TX_DP<10>")
	)
	(segment
		(start 121.831608 -233.63174)
		(end 121.83237 -233.632248)
		(width 0.1143)
		(layer "In15.Cu")
		(net "GMI_CPU0_G1_CPU1_G3_TX_DP<10>")
	)
	(segment
		(start 121.792492 -243.328952)
		(end 121.79935 -243.333016)
		(width 0.1143)
		(layer "In15.Cu")
		(net "GMI_CPU0_G1_CPU1_G3_TX_DP<10>")
	)
	(segment
		(start 349.653606 -235.890816)
		(end 349.63227 -235.87837)
		(width 0.1143)
		(layer "In15.Cu")
		(net "GMI_CPU0_G1_CPU1_G3_TX_DP<10>")
	)
	(segment
		(start 348.06636 -221.34449)
		(end 348.030546 -221.308676)
		(width 0.1143)
		(layer "In15.Cu")
		(net "GMI_CPU0_G1_CPU1_G3_TX_DP<10>")
	)
	(segment
		(start 349.656146 -239.13211)
		(end 349.653606 -239.13084)
		(width 0.1143)
		(layer "In15.Cu")
		(net "GMI_CPU0_G1_CPU1_G3_TX_DP<10>")
	)
	(segment
		(start 307.211984 -184.420764)
		(end 307.211984 -184.421018)
		(width 0.14224)
		(layer "In15.Cu")
		(net "GMI_CPU0_G1_CPU1_G3_TX_DP<10>")
	)
	(segment
		(start 349.188786 -225.363786)
		(end 349.16237 -225.348546)
		(width 0.1143)
		(layer "In15.Cu")
		(net "GMI_CPU0_G1_CPU1_G3_TX_DP<10>")
	)
	(segment
		(start 121.829068 -237.518448)
		(end 121.792492 -237.539784)
		(width 0.1143)
		(layer "In15.Cu")
		(net "GMI_CPU0_G1_CPU1_G3_TX_DP<10>")
	)
	(segment
		(start 121.79935 -231.992932)
		(end 121.800112 -231.99344)
		(width 0.1143)
		(layer "In15.Cu")
		(net "GMI_CPU0_G1_CPU1_G3_TX_DP<10>")
	)
	(segment
		(start 349.696278 -235.915454)
		(end 349.695516 -235.914946)
		(width 0.1143)
		(layer "In15.Cu")
		(net "GMI_CPU0_G1_CPU1_G3_TX_DP<10>")
	)
	(segment
		(start 349.195136 -225.367342)
		(end 349.19412 -225.366834)
		(width 0.1143)
		(layer "In15.Cu")
		(net "GMI_CPU0_G1_CPU1_G3_TX_DP<10>")
	)
	(segment
		(start 349.66402 -239.136682)
		(end 349.663258 -239.136174)
		(width 0.1143)
		(layer "In15.Cu")
		(net "GMI_CPU0_G1_CPU1_G3_TX_DP<10>")
	)
	(segment
		(start 349.661988 -237.5154)
		(end 349.63227 -237.498382)
		(width 0.1143)
		(layer "In15.Cu")
		(net "GMI_CPU0_G1_CPU1_G3_TX_DP<10>")
	)
	(segment
		(start 349.703136 -231.059482)
		(end 349.66402 -231.036622)
		(width 0.1143)
		(layer "In15.Cu")
		(net "GMI_CPU0_G1_CPU1_G3_TX_DP<10>")
	)
	(segment
		(start 349.695516 -232.674922)
		(end 349.665036 -232.657142)
		(width 0.1143)
		(layer "In15.Cu")
		(net "GMI_CPU0_G1_CPU1_G3_TX_DP<10>")
	)
	(segment
		(start 349.659702 -240.754154)
		(end 349.658178 -240.753392)
		(width 0.1143)
		(layer "In15.Cu")
		(net "GMI_CPU0_G1_CPU1_G3_TX_DP<10>")
	)
	(segment
		(start 349.63227 -246.60987)
		(end 349.663258 -246.59209)
		(width 0.1143)
		(layer "In15.Cu")
		(net "GMI_CPU0_G1_CPU1_G3_TX_DP<10>")
	)
	(segment
		(start 349.660464 -232.654602)
		(end 349.659702 -232.654094)
		(width 0.1143)
		(layer "In15.Cu")
		(net "GMI_CPU0_G1_CPU1_G3_TX_DP<10>")
	)
	(segment
		(start 349.666306 -243.350288)
		(end 349.668592 -243.348764)
		(width 0.1143)
		(layer "In15.Cu")
		(net "GMI_CPU0_G1_CPU1_G3_TX_DP<10>")
	)
	(segment
		(start 121.88317 -224.52457)
		(end 121.863358 -224.538794)
		(width 0.1143)
		(layer "In15.Cu")
		(net "GMI_CPU0_G1_CPU1_G3_TX_DP<10>")
	)
	(segment
		(start 349.653606 -234.270804)
		(end 349.63227 -234.258358)
		(width 0.1143)
		(layer "In15.Cu")
		(net "GMI_CPU0_G1_CPU1_G3_TX_DP<10>")
	)
	(segment
		(start 121.830592 -226.177602)
		(end 121.792492 -226.199954)
		(width 0.1143)
		(layer "In15.Cu")
		(net "GMI_CPU0_G1_CPU1_G3_TX_DP<10>")
	)
	(segment
		(start 349.657416 -239.132872)
		(end 349.656146 -239.13211)
		(width 0.1143)
		(layer "In15.Cu")
		(net "GMI_CPU0_G1_CPU1_G3_TX_DP<10>")
	)
	(segment
		(start 349.665036 -244.971062)
		(end 349.666306 -244.9703)
		(width 0.1143)
		(layer "In15.Cu")
		(net "GMI_CPU0_G1_CPU1_G3_TX_DP<10>")
	)
	(segment
		(start 121.829068 -222.938594)
		(end 121.792492 -222.95993)
		(width 0.1143)
		(layer "In15.Cu")
		(net "GMI_CPU0_G1_CPU1_G3_TX_DP<10>")
	)
	(segment
		(start 302.88992 -184.192926)
		(end 166.993824 -183.401462)
		(width 0.14224)
		(layer "In15.Cu")
		(net "GMI_CPU0_G1_CPU1_G3_TX_DP<10>")
	)
	(segment
		(start 349.653606 -232.650792)
		(end 349.63227 -232.638346)
		(width 0.1143)
		(layer "In15.Cu")
		(net "GMI_CPU0_G1_CPU1_G3_TX_DP<10>")
	)
	(segment
		(start 123.755912 -215.88857)
		(end 121.47931 -219.801948)
		(width 0.14224)
		(layer "In15.Cu")
		(net "GMI_CPU0_G1_CPU1_G3_TX_DP<10>")
	)
	(segment
		(start 121.792492 -223.889062)
		(end 121.79935 -223.893126)
		(width 0.1143)
		(layer "In15.Cu")
		(net "GMI_CPU0_G1_CPU1_G3_TX_DP<10>")
	)
	(segment
		(start 349.665036 -242.377214)
		(end 349.66402 -242.376706)
		(width 0.1143)
		(layer "In15.Cu")
		(net "GMI_CPU0_G1_CPU1_G3_TX_DP<10>")
	)
	(segment
		(start 121.830592 -239.137444)
		(end 121.829068 -239.13846)
		(width 0.1143)
		(layer "In15.Cu")
		(net "GMI_CPU0_G1_CPU1_G3_TX_DP<10>")
	)
	(segment
		(start 349.703136 -226.1997)
		(end 349.66402 -226.17684)
		(width 0.1143)
		(layer "In15.Cu")
		(net "GMI_CPU0_G1_CPU1_G3_TX_DP<10>")
	)
	(segment
		(start 349.668592 -235.248704)
		(end 349.703136 -235.228638)
		(width 0.1143)
		(layer "In15.Cu")
		(net "GMI_CPU0_G1_CPU1_G3_TX_DP<10>")
	)
	(segment
		(start 349.63227 -240.129822)
		(end 349.663258 -240.112042)
		(width 0.1143)
		(layer "In15.Cu")
		(net "GMI_CPU0_G1_CPU1_G3_TX_DP<10>")
	)
	(segment
		(start 349.695516 -234.294934)
		(end 349.665036 -234.277154)
		(width 0.1143)
		(layer "In15.Cu")
		(net "GMI_CPU0_G1_CPU1_G3_TX_DP<10>")
	)
	(segment
		(start 349.66402 -229.41661)
		(end 349.631508 -229.397814)
		(width 0.1143)
		(layer "In15.Cu")
		(net "GMI_CPU0_G1_CPU1_G3_TX_DP<10>")
	)
	(segment
		(start 121.831608 -224.557082)
		(end 121.830592 -224.55759)
		(width 0.1143)
		(layer "In15.Cu")
		(net "GMI_CPU0_G1_CPU1_G3_TX_DP<10>")
	)
	(segment
		(start 121.831608 -235.251498)
		(end 121.832116 -235.251752)
		(width 0.1143)
		(layer "In15.Cu")
		(net "GMI_CPU0_G1_CPU1_G3_TX_DP<10>")
	)
	(segment
		(start 349.66402 -235.251498)
		(end 349.665036 -235.25099)
		(width 0.1143)
		(layer "In15.Cu")
		(net "GMI_CPU0_G1_CPU1_G3_TX_DP<10>")
	)
	(segment
		(start 349.665036 -239.13719)
		(end 349.66402 -239.136682)
		(width 0.1143)
		(layer "In15.Cu")
		(net "GMI_CPU0_G1_CPU1_G3_TX_DP<10>")
	)
	(segment
		(start 121.831608 -228.771958)
		(end 121.83237 -228.772466)
		(width 0.1143)
		(layer "In15.Cu")
		(net "GMI_CPU0_G1_CPU1_G3_TX_DP<10>")
	)
	(segment
		(start 349.66402 -238.491522)
		(end 349.665036 -238.491014)
		(width 0.1143)
		(layer "In15.Cu")
		(net "GMI_CPU0_G1_CPU1_G3_TX_DP<10>")
	)
	(segment
		(start 121.877074 -239.108742)
		(end 121.863358 -239.118648)
		(width 0.1143)
		(layer "In15.Cu")
		(net "GMI_CPU0_G1_CPU1_G3_TX_DP<10>")
	)
	(segment
		(start 121.831608 -240.757202)
		(end 121.831608 -240.756948)
		(width 0.1143)
		(layer "In15.Cu")
		(net "GMI_CPU0_G1_CPU1_G3_TX_DP<10>")
	)
	(segment
		(start 349.663258 -243.99621)
		(end 349.660464 -243.994686)
		(width 0.1143)
		(layer "In15.Cu")
		(net "GMI_CPU0_G1_CPU1_G3_TX_DP<10>")
	)
	(segment
		(start 121.800112 -231.99344)
		(end 121.830592 -232.01122)
		(width 0.1143)
		(layer "In15.Cu")
		(net "GMI_CPU0_G1_CPU1_G3_TX_DP<10>")
	)
	(segment
		(start 349.66402 -232.656634)
		(end 349.663258 -232.656126)
		(width 0.1143)
		(layer "In15.Cu")
		(net "GMI_CPU0_G1_CPU1_G3_TX_DP<10>")
	)
	(segment
		(start 121.83237 -232.65638)
		(end 121.831608 -232.656888)
		(width 0.1143)
		(layer "In15.Cu")
		(net "GMI_CPU0_G1_CPU1_G3_TX_DP<10>")
	)
	(segment
		(start 349.653606 -243.990876)
		(end 349.63227 -243.97843)
		(width 0.1143)
		(layer "In15.Cu")
		(net "GMI_CPU0_G1_CPU1_G3_TX_DP<10>")
	)
	(segment
		(start 349.696278 -244.015514)
		(end 349.695516 -244.015006)
		(width 0.1143)
		(layer "In15.Cu")
		(net "GMI_CPU0_G1_CPU1_G3_TX_DP<10>")
	)
	(segment
		(start 121.792492 -236.848904)
		(end 121.79935 -236.852968)
		(width 0.1143)
		(layer "In15.Cu")
		(net "GMI_CPU0_G1_CPU1_G3_TX_DP<10>")
	)
	(segment
		(start 121.792492 -233.60888)
		(end 121.79935 -233.612944)
		(width 0.1143)
		(layer "In15.Cu")
		(net "GMI_CPU0_G1_CPU1_G3_TX_DP<10>")
	)
	(segment
		(start 121.79935 -236.852968)
		(end 121.800112 -236.853476)
		(width 0.1143)
		(layer "In15.Cu")
		(net "GMI_CPU0_G1_CPU1_G3_TX_DP<10>")
	)
	(segment
		(start 349.66402 -234.276646)
		(end 349.663258 -234.276138)
		(width 0.1143)
		(layer "In15.Cu")
		(net "GMI_CPU0_G1_CPU1_G3_TX_DP<10>")
	)
	(segment
		(start 121.829068 -227.79863)
		(end 121.792492 -227.819966)
		(width 0.1143)
		(layer "In15.Cu")
		(net "GMI_CPU0_G1_CPU1_G3_TX_DP<10>")
	)
	(segment
		(start 349.657416 -240.752884)
		(end 349.656146 -240.752122)
		(width 0.1143)
		(layer "In15.Cu")
		(net "GMI_CPU0_G1_CPU1_G3_TX_DP<10>")
	)
	(segment
		(start 349.66402 -227.151692)
		(end 349.703136 -227.128832)
		(width 0.1143)
		(layer "In15.Cu")
		(net "GMI_CPU0_G1_CPU1_G3_TX_DP<10>")
	)
	(segment
		(start 349.66402 -230.391716)
		(end 349.700596 -230.37038)
		(width 0.1143)
		(layer "In15.Cu")
		(net "GMI_CPU0_G1_CPU1_G3_TX_DP<10>")
	)
	(segment
		(start 349.663258 -235.252006)
		(end 349.66402 -235.251498)
		(width 0.1143)
		(layer "In15.Cu")
		(net "GMI_CPU0_G1_CPU1_G3_TX_DP<10>")
	)
	(segment
		(start 348.693486 -223.929448)
		(end 348.723966 -223.911668)
		(width 0.1143)
		(layer "In15.Cu")
		(net "GMI_CPU0_G1_CPU1_G3_TX_DP<10>")
	)
	(segment
		(start 349.695516 -235.914946)
		(end 349.665036 -235.897166)
		(width 0.1143)
		(layer "In15.Cu")
		(net "GMI_CPU0_G1_CPU1_G3_TX_DP<10>")
	)
	(segment
		(start 349.666306 -246.590312)
		(end 349.668592 -246.588788)
		(width 0.1143)
		(layer "In15.Cu")
		(net "GMI_CPU0_G1_CPU1_G3_TX_DP<10>")
	)
	(segment
		(start 349.63227 -230.410004)
		(end 349.66402 -230.391716)
		(width 0.1143)
		(layer "In15.Cu")
		(net "GMI_CPU0_G1_CPU1_G3_TX_DP<10>")
	)
	(segment
		(start 121.830592 -233.631232)
		(end 121.831608 -233.63174)
		(width 0.1143)
		(layer "In15.Cu")
		(net "GMI_CPU0_G1_CPU1_G3_TX_DP<10>")
	)
	(segment
		(start 121.800112 -244.953536)
		(end 121.830592 -244.971316)
		(width 0.1143)
		(layer "In15.Cu")
		(net "GMI_CPU0_G1_CPU1_G3_TX_DP<10>")
	)
	(segment
		(start 349.658178 -235.893356)
		(end 349.657416 -235.892848)
		(width 0.1143)
		(layer "In15.Cu")
		(net "GMI_CPU0_G1_CPU1_G3_TX_DP<10>")
	)
	(segment
		(start 349.695516 -239.15497)
		(end 349.665036 -239.13719)
		(width 0.1143)
		(layer "In15.Cu")
		(net "GMI_CPU0_G1_CPU1_G3_TX_DP<10>")
	)
	(segment
		(start 121.863358 -227.170234)
		(end 121.87174 -227.17633)
		(width 0.1143)
		(layer "In15.Cu")
		(net "GMI_CPU0_G1_CPU1_G3_TX_DP<10>")
	)
	(segment
		(start 349.703136 -235.919518)
		(end 349.696278 -235.915454)
		(width 0.1143)
		(layer "In15.Cu")
		(net "GMI_CPU0_G1_CPU1_G3_TX_DP<10>")
	)
	(segment
		(start 121.829068 -240.758472)
		(end 121.792492 -240.779808)
		(width 0.1143)
		(layer "In15.Cu")
		(net "GMI_CPU0_G1_CPU1_G3_TX_DP<10>")
	)
	(segment
		(start 121.831608 -236.87151)
		(end 121.832116 -236.871764)
		(width 0.1143)
		(layer "In15.Cu")
		(net "GMI_CPU0_G1_CPU1_G3_TX_DP<10>")
	)
	(segment
		(start 121.83237 -235.896658)
		(end 121.831608 -235.896912)
		(width 0.1143)
		(layer "In15.Cu")
		(net "GMI_CPU0_G1_CPU1_G3_TX_DP<10>")
	)
	(segment
		(start 349.63227 -236.889798)
		(end 349.663258 -236.872018)
		(width 0.1143)
		(layer "In15.Cu")
		(net "GMI_CPU0_G1_CPU1_G3_TX_DP<10>")
	)
	(segment
		(start 348.06636 -221.80423)
		(end 348.06636 -221.34449)
		(width 0.1143)
		(layer "In15.Cu")
		(net "GMI_CPU0_G1_CPU1_G3_TX_DP<10>")
	)
	(segment
		(start 121.800112 -233.613452)
		(end 121.830592 -233.631232)
		(width 0.1143)
		(layer "In15.Cu")
		(net "GMI_CPU0_G1_CPU1_G3_TX_DP<10>")
	)
	(segment
		(start 349.233236 -225.389694)
		(end 349.19666 -225.368358)
		(width 0.1143)
		(layer "In15.Cu")
		(net "GMI_CPU0_G1_CPU1_G3_TX_DP<10>")
	)
	(segment
		(start 121.800112 -235.233464)
		(end 121.830592 -235.251244)
		(width 0.1143)
		(layer "In15.Cu")
		(net "GMI_CPU0_G1_CPU1_G3_TX_DP<10>")
	)
	(segment
		(start 121.800112 -230.373682)
		(end 121.830592 -230.391462)
		(width 0.1143)
		(layer "In15.Cu")
		(net "GMI_CPU0_G1_CPU1_G3_TX_DP<10>")
	)
	(segment
		(start 121.83237 -226.176586)
		(end 121.831608 -226.177094)
		(width 0.1143)
		(layer "In15.Cu")
		(net "GMI_CPU0_G1_CPU1_G3_TX_DP<10>")
	)
	(segment
		(start 121.79935 -238.47298)
		(end 121.800112 -238.473488)
		(width 0.1143)
		(layer "In15.Cu")
		(net "GMI_CPU0_G1_CPU1_G3_TX_DP<10>")
	)
	(segment
		(start 121.831608 -227.151946)
		(end 121.83237 -227.152454)
		(width 0.1143)
		(layer "In15.Cu")
		(net "GMI_CPU0_G1_CPU1_G3_TX_DP<10>")
	)
	(segment
		(start 121.83237 -223.91243)
		(end 121.863358 -223.93021)
		(width 0.1143)
		(layer "In15.Cu")
		(net "GMI_CPU0_G1_CPU1_G3_TX_DP<10>")
	)
	(segment
		(start 121.793762 -222.270066)
		(end 121.863358 -222.310198)
		(width 0.1143)
		(layer "In15.Cu")
		(net "GMI_CPU0_G1_CPU1_G3_TX_DP<10>")
	)
	(segment
		(start 349.66402 -226.17684)
		(end 349.63354 -226.15906)
		(width 0.1143)
		(layer "In15.Cu")
		(net "GMI_CPU0_G1_CPU1_G3_TX_DP<10>")
	)
	(segment
		(start 121.83237 -222.936562)
		(end 121.831608 -222.93707)
		(width 0.1143)
		(layer "In15.Cu")
		(net "GMI_CPU0_G1_CPU1_G3_TX_DP<10>")
	)
	(segment
		(start 121.792492 -228.749098)
		(end 121.79935 -228.753162)
		(width 0.1143)
		(layer "In15.Cu")
		(net "GMI_CPU0_G1_CPU1_G3_TX_DP<10>")
	)
	(segment
		(start 121.831608 -241.7318)
		(end 121.83237 -241.732308)
		(width 0.1143)
		(layer "In15.Cu")
		(net "GMI_CPU0_G1_CPU1_G3_TX_DP<10>")
	)
	(segment
		(start 121.792492 -235.228892)
		(end 121.79935 -235.232956)
		(width 0.1143)
		(layer "In15.Cu")
		(net "GMI_CPU0_G1_CPU1_G3_TX_DP<10>")
	)
	(segment
		(start 349.668592 -232.00868)
		(end 349.703136 -231.988614)
		(width 0.1143)
		(layer "In15.Cu")
		(net "GMI_CPU0_G1_CPU1_G3_TX_DP<10>")
	)
	(segment
		(start 349.663258 -241.732054)
		(end 349.66402 -241.731546)
		(width 0.1143)
		(layer "In15.Cu")
		(net "GMI_CPU0_G1_CPU1_G3_TX_DP<10>")
	)
	(segment
		(start 349.702628 -228.749098)
		(end 349.703136 -228.748844)
		(width 0.1143)
		(layer "In15.Cu")
		(net "GMI_CPU0_G1_CPU1_G3_TX_DP<10>")
	)
	(segment
		(start 121.830592 -228.77145)
		(end 121.831608 -228.771958)
		(width 0.1143)
		(layer "In15.Cu")
		(net "GMI_CPU0_G1_CPU1_G3_TX_DP<10>")
	)
	(segment
		(start 121.830592 -241.731292)
		(end 121.831608 -241.7318)
		(width 0.1143)
		(layer "In15.Cu")
		(net "GMI_CPU0_G1_CPU1_G3_TX_DP<10>")
	)
	(segment
		(start 349.66402 -241.731546)
		(end 349.665036 -241.731038)
		(width 0.1143)
		(layer "In15.Cu")
		(net "GMI_CPU0_G1_CPU1_G3_TX_DP<10>")
	)
	(segment
		(start 348.723966 -222.936816)
		(end 348.693486 -222.919036)
		(width 0.1143)
		(layer "In15.Cu")
		(net "GMI_CPU0_G1_CPU1_G3_TX_DP<10>")
	)
	(segment
		(start 121.863358 -238.510064)
		(end 121.877074 -238.51997)
		(width 0.1143)
		(layer "In15.Cu")
		(net "GMI_CPU0_G1_CPU1_G3_TX_DP<10>")
	)
	(segment
		(start 121.863358 -239.118648)
		(end 121.83237 -239.136428)
		(width 0.1143)
		(layer "In15.Cu")
		(net "GMI_CPU0_G1_CPU1_G3_TX_DP<10>")
	)
	(segment
		(start 121.863358 -223.93021)
		(end 121.88317 -223.944434)
		(width 0.1143)
		(layer "In15.Cu")
		(net "GMI_CPU0_G1_CPU1_G3_TX_DP<10>")
	)
	(segment
		(start 121.831608 -222.93707)
		(end 121.830592 -222.937578)
		(width 0.1143)
		(layer "In15.Cu")
		(net "GMI_CPU0_G1_CPU1_G3_TX_DP<10>")
	)
	(segment
		(start 121.83237 -232.012236)
		(end 121.863358 -232.030016)
		(width 0.1143)
		(layer "In15.Cu")
		(net "GMI_CPU0_G1_CPU1_G3_TX_DP<10>")
	)
	(segment
		(start 349.63227 -235.269786)
		(end 349.663258 -235.252006)
		(width 0.1143)
		(layer "In15.Cu")
		(net "GMI_CPU0_G1_CPU1_G3_TX_DP<10>")
	)
	(segment
		(start 349.668592 -241.728752)
		(end 349.703136 -241.708686)
		(width 0.1143)
		(layer "In15.Cu")
		(net "GMI_CPU0_G1_CPU1_G3_TX_DP<10>")
	)
	(segment
		(start 349.193358 -225.366326)
		(end 349.192088 -225.365564)
		(width 0.1143)
		(layer "In15.Cu")
		(net "GMI_CPU0_G1_CPU1_G3_TX_DP<10>")
	)
	(segment
		(start 349.63354 -227.169472)
		(end 349.66402 -227.151692)
		(width 0.1143)
		(layer "In15.Cu")
		(net "GMI_CPU0_G1_CPU1_G3_TX_DP<10>")
	)
	(segment
		(start 121.83237 -243.996464)
		(end 121.831608 -243.996972)
		(width 0.1143)
		(layer "In15.Cu")
		(net "GMI_CPU0_G1_CPU1_G3_TX_DP<10>")
	)
	(segment
		(start 121.83237 -242.376452)
		(end 121.831608 -242.37696)
		(width 0.1143)
		(layer "In15.Cu")
		(net "GMI_CPU0_G1_CPU1_G3_TX_DP<10>")
	)
	(segment
		(start 121.831608 -236.871764)
		(end 121.831608 -236.87151)
		(width 0.1143)
		(layer "In15.Cu")
		(net "GMI_CPU0_G1_CPU1_G3_TX_DP<10>")
	)
	(segment
		(start 349.66402 -246.591582)
		(end 349.665036 -246.591074)
		(width 0.1143)
		(layer "In15.Cu")
		(net "GMI_CPU0_G1_CPU1_G3_TX_DP<10>")
	)
	(segment
		(start 162.450272 -185.0263)
		(end 146.658076 -197.972426)
		(width 0.14224)
		(layer "In15.Cu")
		(net "GMI_CPU0_G1_CPU1_G3_TX_DP<10>")
	)
	(segment
		(start 349.66656 -238.489998)
		(end 349.703136 -238.468662)
		(width 0.1143)
		(layer "In15.Cu")
		(net "GMI_CPU0_G1_CPU1_G3_TX_DP<10>")
	)
	(segment
		(start 121.865136 -229.397306)
		(end 121.831608 -229.416864)
		(width 0.1143)
		(layer "In15.Cu")
		(net "GMI_CPU0_G1_CPU1_G3_TX_DP<10>")
	)
	(segment
		(start 121.800112 -236.853476)
		(end 121.830592 -236.871256)
		(width 0.1143)
		(layer "In15.Cu")
		(net "GMI_CPU0_G1_CPU1_G3_TX_DP<10>")
	)
	(segment
		(start 121.863358 -242.358672)
		(end 121.83237 -242.376452)
		(width 0.1143)
		(layer "In15.Cu")
		(net "GMI_CPU0_G1_CPU1_G3_TX_DP<10>")
	)
	(segment
		(start 349.696278 -232.67543)
		(end 349.695516 -232.674922)
		(width 0.1143)
		(layer "In15.Cu")
		(net "GMI_CPU0_G1_CPU1_G3_TX_DP<10>")
	)
	(segment
		(start 121.832878 -246.592344)
		(end 121.846594 -246.600218)
		(width 0.1143)
		(layer "In15.Cu")
		(net "GMI_CPU0_G1_CPU1_G3_TX_DP<10>")
	)
	(segment
		(start 349.665036 -234.277154)
		(end 349.66402 -234.276646)
		(width 0.1143)
		(layer "In15.Cu")
		(net "GMI_CPU0_G1_CPU1_G3_TX_DP<10>")
	)
	(segment
		(start 349.66402 -245.61673)
		(end 349.663258 -245.616222)
		(width 0.1143)
		(layer "In15.Cu")
		(net "GMI_CPU0_G1_CPU1_G3_TX_DP<10>")
	)
	(segment
		(start 121.795032 -230.370634)
		(end 121.79935 -230.373174)
		(width 0.1143)
		(layer "In15.Cu")
		(net "GMI_CPU0_G1_CPU1_G3_TX_DP<10>")
	)
	(segment
		(start 121.83237 -227.796598)
		(end 121.831608 -227.797106)
		(width 0.1143)
		(layer "In15.Cu")
		(net "GMI_CPU0_G1_CPU1_G3_TX_DP<10>")
	)
	(segment
		(start 121.829068 -224.558606)
		(end 121.792492 -224.579942)
		(width 0.1143)
		(layer "In15.Cu")
		(net "GMI_CPU0_G1_CPU1_G3_TX_DP<10>")
	)
	(segment
		(start 121.792492 -241.70894)
		(end 121.79935 -241.713004)
		(width 0.1143)
		(layer "In15.Cu")
		(net "GMI_CPU0_G1_CPU1_G3_TX_DP<10>")
	)
	(segment
		(start 121.830592 -245.617492)
		(end 121.829068 -245.618508)
		(width 0.1143)
		(layer "In15.Cu")
		(net "GMI_CPU0_G1_CPU1_G3_TX_DP<10>")
	)
	(segment
		(start 349.703136 -227.819712)
		(end 349.66402 -227.796852)
		(width 0.1143)
		(layer "In15.Cu")
		(net "GMI_CPU0_G1_CPU1_G3_TX_DP<10>")
	)
	(segment
		(start 349.660464 -239.13465)
		(end 349.659702 -239.134142)
		(width 0.1143)
		(layer "In15.Cu")
		(net "GMI_CPU0_G1_CPU1_G3_TX_DP<10>")
	)
	(segment
		(start 349.665036 -235.25099)
		(end 349.666306 -235.250228)
		(width 0.1143)
		(layer "In15.Cu")
		(net "GMI_CPU0_G1_CPU1_G3_TX_DP<10>")
	)
	(segment
		(start 121.831608 -243.996972)
		(end 121.830592 -243.99748)
		(width 0.1143)
		(layer "In15.Cu")
		(net "GMI_CPU0_G1_CPU1_G3_TX_DP<10>")
	)
	(segment
		(start 349.193866 -247.401588)
		(end 349.232982 -247.378728)
		(width 0.1143)
		(layer "In15.Cu")
		(net "GMI_CPU0_G1_CPU1_G3_TX_DP<10>")
	)
	(segment
		(start 121.792492 -225.509074)
		(end 121.79935 -225.513138)
		(width 0.1143)
		(layer "In15.Cu")
		(net "GMI_CPU0_G1_CPU1_G3_TX_DP<10>")
	)
	(segment
		(start 349.66402 -227.796852)
		(end 349.63354 -227.779072)
		(width 0.1143)
		(layer "In15.Cu")
		(net "GMI_CPU0_G1_CPU1_G3_TX_DP<10>")
	)
	(segment
		(start 121.863358 -234.258612)
		(end 121.83237 -234.276392)
		(width 0.1143)
		(layer "In15.Cu")
		(net "GMI_CPU0_G1_CPU1_G3_TX_DP<10>")
	)
	(segment
		(start 121.831608 -243.351812)
		(end 121.83237 -243.35232)
		(width 0.1143)
		(layer "In15.Cu")
		(net "GMI_CPU0_G1_CPU1_G3_TX_DP<10>")
	)
	(segment
		(start 349.659702 -234.274106)
		(end 349.658178 -234.273344)
		(width 0.1143)
		(layer "In15.Cu")
		(net "GMI_CPU0_G1_CPU1_G3_TX_DP<10>")
	)
	(segment
		(start 121.830592 -234.277408)
		(end 121.829068 -234.278424)
		(width 0.1143)
		(layer "In15.Cu")
		(net "GMI_CPU0_G1_CPU1_G3_TX_DP<10>")
	)
	(segment
		(start 121.831608 -238.491776)
		(end 121.83237 -238.492284)
		(width 0.1143)
		(layer "In15.Cu")
		(net "GMI_CPU0_G1_CPU1_G3_TX_DP<10>")
	)
	(segment
		(start 348.293182 -222.14967)
		(end 348.254066 -222.12681)
		(width 0.1143)
		(layer "In15.Cu")
		(net "GMI_CPU0_G1_CPU1_G3_TX_DP<10>")
	)
	(segment
		(start 306.713636 -184.192926)
		(end 302.88992 -184.192926)
		(width 0.14224)
		(layer "In15.Cu")
		(net "GMI_CPU0_G1_CPU1_G3_TX_DP<10>")
	)
	(segment
		(start 121.831608 -226.177094)
		(end 121.830592 -226.177602)
		(width 0.1143)
		(layer "In15.Cu")
		(net "GMI_CPU0_G1_CPU1_G3_TX_DP<10>")
	)
	(segment
		(start 349.66402 -232.011474)
		(end 349.665036 -232.010966)
		(width 0.1143)
		(layer "In15.Cu")
		(net "GMI_CPU0_G1_CPU1_G3_TX_DP<10>")
	)
	(segment
		(start 349.666306 -244.9703)
		(end 349.668592 -244.968776)
		(width 0.1143)
		(layer "In15.Cu")
		(net "GMI_CPU0_G1_CPU1_G3_TX_DP<10>")
	)
	(segment
		(start 349.659702 -239.134142)
		(end 349.658178 -239.13338)
		(width 0.1143)
		(layer "In15.Cu")
		(net "GMI_CPU0_G1_CPU1_G3_TX_DP<10>")
	)
	(segment
		(start 121.79935 -223.893126)
		(end 121.800112 -223.893634)
		(width 0.1143)
		(layer "In15.Cu")
		(net "GMI_CPU0_G1_CPU1_G3_TX_DP<10>")
	)
	(segment
		(start 121.79935 -233.612944)
		(end 121.800112 -233.613452)
		(width 0.1143)
		(layer "In15.Cu")
		(net "GMI_CPU0_G1_CPU1_G3_TX_DP<10>")
	)
	(segment
		(start 349.665036 -233.630978)
		(end 349.666306 -233.630216)
		(width 0.1143)
		(layer "In15.Cu")
		(net "GMI_CPU0_G1_CPU1_G3_TX_DP<10>")
	)
	(segment
		(start 349.663258 -236.872018)
		(end 349.66402 -236.87151)
		(width 0.1143)
		(layer "In15.Cu")
		(net "GMI_CPU0_G1_CPU1_G3_TX_DP<10>")
	)
	(segment
		(start 349.660464 -240.754662)
		(end 349.659702 -240.754154)
		(width 0.1143)
		(layer "In15.Cu")
		(net "GMI_CPU0_G1_CPU1_G3_TX_DP<10>")
	)
	(segment
		(start 121.863358 -226.158806)
		(end 121.83237 -226.176586)
		(width 0.1143)
		(layer "In15.Cu")
		(net "GMI_CPU0_G1_CPU1_G3_TX_DP<10>")
	)
	(segment
		(start 349.63354 -228.789484)
		(end 349.66402 -228.771704)
		(width 0.1143)
		(layer "In15.Cu")
		(net "GMI_CPU0_G1_CPU1_G3_TX_DP<10>")
	)
	(segment
		(start 121.831608 -240.111788)
		(end 121.831608 -240.111534)
		(width 0.1143)
		(layer "In15.Cu")
		(net "GMI_CPU0_G1_CPU1_G3_TX_DP<10>")
	)
	(segment
		(start 348.076266 -221.083124)
		(end 348.076266 -219.419424)
		(width 0.14224)
		(layer "In15.Cu")
		(net "GMI_CPU0_G1_CPU1_G3_TX_DP<10>")
	)
	(segment
		(start 348.723966 -224.556828)
		(end 348.693486 -224.539048)
		(width 0.1143)
		(layer "In15.Cu")
		(net "GMI_CPU0_G1_CPU1_G3_TX_DP<10>")
	)
	(segment
		(start 121.800112 -238.473488)
		(end 121.830592 -238.491268)
		(width 0.1143)
		(layer "In15.Cu")
		(net "GMI_CPU0_G1_CPU1_G3_TX_DP<10>")
	)
	(segment
		(start 121.800112 -246.573548)
		(end 121.830592 -246.591328)
		(width 0.1143)
		(layer "In15.Cu")
		(net "GMI_CPU0_G1_CPU1_G3_TX_DP<10>")
	)
	(segment
		(start 121.79935 -230.373174)
		(end 121.800112 -230.373682)
		(width 0.1143)
		(layer "In15.Cu")
		(net "GMI_CPU0_G1_CPU1_G3_TX_DP<10>")
	)
	(segment
		(start 349.189802 -225.364294)
		(end 349.188786 -225.363786)
		(width 0.1143)
		(layer "In15.Cu")
		(net "GMI_CPU0_G1_CPU1_G3_TX_DP<10>")
	)
	(segment
		(start 349.665036 -232.010966)
		(end 349.666306 -232.010204)
		(width 0.1143)
		(layer "In15.Cu")
		(net "GMI_CPU0_G1_CPU1_G3_TX_DP<10>")
	)
	(segment
		(start 349.63227 -241.749834)
		(end 349.663258 -241.732054)
		(width 0.1143)
		(layer "In15.Cu")
		(net "GMI_CPU0_G1_CPU1_G3_TX_DP<10>")
	)
	(segment
		(start 121.830592 -232.01122)
		(end 121.831608 -232.011728)
		(width 0.1143)
		(layer "In15.Cu")
		(net "GMI_CPU0_G1_CPU1_G3_TX_DP<10>")
	)
	(segment
		(start 349.665036 -240.111026)
		(end 349.666306 -240.110264)
		(width 0.1143)
		(layer "In15.Cu")
		(net "GMI_CPU0_G1_CPU1_G3_TX_DP<10>")
	)
	(segment
		(start 121.830592 -230.391462)
		(end 121.833386 -230.392986)
		(width 0.1143)
		(layer "In15.Cu")
		(net "GMI_CPU0_G1_CPU1_G3_TX_DP<10>")
	)
	(segment
		(start 349.663258 -240.112042)
		(end 349.66402 -240.111534)
		(width 0.1143)
		(layer "In15.Cu")
		(net "GMI_CPU0_G1_CPU1_G3_TX_DP<10>")
	)
	(segment
		(start 121.830592 -243.351304)
		(end 121.831608 -243.351812)
		(width 0.1143)
		(layer "In15.Cu")
		(net "GMI_CPU0_G1_CPU1_G3_TX_DP<10>")
	)
	(segment
		(start 121.549414 -221.302326)
		(end 121.54916 -221.30258)
		(width 0.1143)
		(layer "In15.Cu")
		(net "GMI_CPU0_G1_CPU1_G3_TX_DP<10>")
	)
	(segment
		(start 121.873518 -226.15144)
		(end 121.863358 -226.158806)
		(width 0.1143)
		(layer "In15.Cu")
		(net "GMI_CPU0_G1_CPU1_G3_TX_DP<10>")
	)
	(segment
		(start 121.829068 -243.998496)
		(end 121.792492 -244.019832)
		(width 0.1143)
		(layer "In15.Cu")
		(net "GMI_CPU0_G1_CPU1_G3_TX_DP<10>")
	)
	(segment
		(start 349.695516 -244.015006)
		(end 349.665036 -243.997226)
		(width 0.1143)
		(layer "In15.Cu")
		(net "GMI_CPU0_G1_CPU1_G3_TX_DP<10>")
	)
	(segment
		(start 121.830592 -232.657396)
		(end 121.829068 -232.658412)
		(width 0.1143)
		(layer "In15.Cu")
		(net "GMI_CPU0_G1_CPU1_G3_TX_DP<10>")
	)
	(segment
		(start 313.128406 -187.625736)
		(end 310.834024 -186.327034)
		(width 0.14224)
		(layer "In15.Cu")
		(net "GMI_CPU0_G1_CPU1_G3_TX_DP<10>")
	)
	(segment
		(start 121.831608 -242.37696)
		(end 121.830592 -242.377468)
		(width 0.1143)
		(layer "In15.Cu")
		(net "GMI_CPU0_G1_CPU1_G3_TX_DP<10>")
	)
	(segment
		(start 349.668592 -236.868716)
		(end 349.703136 -236.84865)
		(width 0.1143)
		(layer "In15.Cu")
		(net "GMI_CPU0_G1_CPU1_G3_TX_DP<10>")
	)
	(segment
		(start 349.661988 -245.61546)
		(end 349.63227 -245.598442)
		(width 0.1143)
		(layer "In15.Cu")
		(net "GMI_CPU0_G1_CPU1_G3_TX_DP<10>")
	)
	(segment
		(start 121.830592 -235.89742)
		(end 121.792492 -235.919772)
		(width 0.1143)
		(layer "In15.Cu")
		(net "GMI_CPU0_G1_CPU1_G3_TX_DP<10>")
	)
	(segment
		(start 121.830592 -243.99748)
		(end 121.829068 -243.998496)
		(width 0.1143)
		(layer "In15.Cu")
		(net "GMI_CPU0_G1_CPU1_G3_TX_DP<10>")
	)
	(segment
		(start 349.665036 -241.731038)
		(end 349.666306 -241.730276)
		(width 0.1143)
		(layer "In15.Cu")
		(net "GMI_CPU0_G1_CPU1_G3_TX_DP<10>")
	)
	(segment
		(start 121.800112 -225.513646)
		(end 121.830592 -225.531426)
		(width 0.1143)
		(layer "In15.Cu")
		(net "GMI_CPU0_G1_CPU1_G3_TX_DP<10>")
	)
	(segment
		(start 121.47931 -219.801948)
		(end 121.47931 -220.991938)
		(width 0.14224)
		(layer "In15.Cu")
		(net "GMI_CPU0_G1_CPU1_G3_TX_DP<10>")
	)
	(segment
		(start 121.863358 -227.778818)
		(end 121.83237 -227.796598)
		(width 0.1143)
		(layer "In15.Cu")
		(net "GMI_CPU0_G1_CPU1_G3_TX_DP<10>")
	)
	(segment
		(start 121.54916 -221.30258)
		(end 121.54916 -221.804484)
		(width 0.1143)
		(layer "In15.Cu")
		(net "GMI_CPU0_G1_CPU1_G3_TX_DP<10>")
	)
	(segment
		(start 349.665036 -243.35105)
		(end 349.666306 -243.350288)
		(width 0.1143)
		(layer "In15.Cu")
		(net "GMI_CPU0_G1_CPU1_G3_TX_DP<10>")
	)
	(segment
		(start 121.830592 -240.757456)
		(end 121.829068 -240.758472)
		(width 0.1143)
		(layer "In15.Cu")
		(net "GMI_CPU0_G1_CPU1_G3_TX_DP<10>")
	)
	(segment
		(start 349.703136 -239.159542)
		(end 349.696278 -239.155478)
		(width 0.1143)
		(layer "In15.Cu")
		(net "GMI_CPU0_G1_CPU1_G3_TX_DP<10>")
	)
	(segment
		(start 349.663258 -237.516162)
		(end 349.661988 -237.5154)
		(width 0.1143)
		(layer "In15.Cu")
		(net "GMI_CPU0_G1_CPU1_G3_TX_DP<10>")
	)
	(segment
		(start 121.863358 -243.3701)
		(end 121.874534 -243.378228)
		(width 0.1143)
		(layer "In15.Cu")
		(net "GMI_CPU0_G1_CPU1_G3_TX_DP<10>")
	)
	(segment
		(start 349.663258 -246.59209)
		(end 349.66402 -246.591582)
		(width 0.1143)
		(layer "In15.Cu")
		(net "GMI_CPU0_G1_CPU1_G3_TX_DP<10>")
	)
	(segment
		(start 121.830592 -235.251244)
		(end 121.831608 -235.251752)
		(width 0.1143)
		(layer "In15.Cu")
		(net "GMI_CPU0_G1_CPU1_G3_TX_DP<10>")
	)
	(segment
		(start 121.79935 -240.092992)
		(end 121.800112 -240.0935)
		(width 0.1143)
		(layer "In15.Cu")
		(net "GMI_CPU0_G1_CPU1_G3_TX_DP<10>")
	)
	(segment
		(start 121.792492 -231.988868)
		(end 121.79935 -231.992932)
		(width 0.1143)
		(layer "In15.Cu")
		(net "GMI_CPU0_G1_CPU1_G3_TX_DP<10>")
	)
	(segment
		(start 349.63227 -232.029762)
		(end 349.663258 -232.011982)
		(width 0.1143)
		(layer "In15.Cu")
		(net "GMI_CPU0_G1_CPU1_G3_TX_DP<10>")
	)
	(segment
		(start 121.792492 -227.129086)
		(end 121.79935 -227.13315)
		(width 0.1143)
		(layer "In15.Cu")
		(net "GMI_CPU0_G1_CPU1_G3_TX_DP<10>")
	)
	(segment
		(start 349.661988 -242.375436)
		(end 349.63227 -242.358418)
		(width 0.1143)
		(layer "In15.Cu")
		(net "GMI_CPU0_G1_CPU1_G3_TX_DP<10>")
	)
	(segment
		(start 121.52503 -221.066106)
		(end 121.52503 -221.277942)
		(width 0.1143)
		(layer "In15.Cu")
		(net "GMI_CPU0_G1_CPU1_G3_TX_DP<10>")
	)
	(segment
		(start 310.834278 -186.327034)
		(end 308.55031 -185.03392)
		(width 0.14224)
		(layer "In15.Cu")
		(net "GMI_CPU0_G1_CPU1_G3_TX_DP<10>")
	)
	(segment
		(start 121.831608 -240.111534)
		(end 121.832116 -240.111788)
		(width 0.1143)
		(layer "In15.Cu")
		(net "GMI_CPU0_G1_CPU1_G3_TX_DP<10>")
	)
	(segment
		(start 349.653606 -240.750852)
		(end 349.63227 -240.738406)
		(width 0.1143)
		(layer "In15.Cu")
		(net "GMI_CPU0_G1_CPU1_G3_TX_DP<10>")
	)
	(segment
		(start 349.703136 -232.679494)
		(end 349.696278 -232.67543)
		(width 0.1143)
		(layer "In15.Cu")
		(net "GMI_CPU0_G1_CPU1_G3_TX_DP<10>")
	)
	(segment
		(start 349.703136 -234.299506)
		(end 349.696278 -234.295442)
		(width 0.1143)
		(layer "In15.Cu")
		(net "GMI_CPU0_G1_CPU1_G3_TX_DP<10>")
	)
	(segment
		(start 349.703136 -229.43947)
		(end 349.66402 -229.41661)
		(width 0.1143)
		(layer "In15.Cu")
		(net "GMI_CPU0_G1_CPU1_G3_TX_DP<10>")
	)
	(segment
		(start 121.82602 -242.380262)
		(end 121.792492 -242.39982)
		(width 0.1143)
		(layer "In15.Cu")
		(net "GMI_CPU0_G1_CPU1_G3_TX_DP<10>")
	)
	(segment
		(start 349.66402 -228.771704)
		(end 349.702628 -228.749098)
		(width 0.1143)
		(layer "In15.Cu")
		(net "GMI_CPU0_G1_CPU1_G3_TX_DP<10>")
	)
	(segment
		(start 349.695516 -240.774982)
		(end 349.665036 -240.757202)
		(width 0.1143)
		(layer "In15.Cu")
		(net "GMI_CPU0_G1_CPU1_G3_TX_DP<10>")
	)
	(segment
		(start 349.703136 -242.399566)
		(end 349.665036 -242.377214)
		(width 0.1143)
		(layer "In15.Cu")
		(net "GMI_CPU0_G1_CPU1_G3_TX_DP<10>")
	)
	(segment
		(start 349.663258 -234.276138)
		(end 349.660464 -234.274614)
		(width 0.1143)
		(layer "In15.Cu")
		(net "GMI_CPU0_G1_CPU1_G3_TX_DP<10>")
	)
	(segment
		(start 121.83237 -227.152454)
		(end 121.863358 -227.170234)
		(width 0.1143)
		(layer "In15.Cu")
		(net "GMI_CPU0_G1_CPU1_G3_TX_DP<10>")
	)
	(segment
		(start 349.663258 -235.89615)
		(end 349.660464 -235.894626)
		(width 0.1143)
		(layer "In15.Cu")
		(net "GMI_CPU0_G1_CPU1_G3_TX_DP<10>")
	)
	(segment
		(start 121.831608 -237.516924)
		(end 121.830592 -237.517432)
		(width 0.1143)
		(layer "In15.Cu")
		(net "GMI_CPU0_G1_CPU1_G3_TX_DP<10>")
	)
	(segment
		(start 349.083122 -247.724168)
		(end 349.013272 -247.654318)
		(width 0.1143)
		(layer "In15.Cu")
		(net "GMI_CPU0_G1_CPU1_G3_TX_DP<10>")
	)
	(segment
		(start 349.663258 -232.011982)
		(end 349.66402 -232.011474)
		(width 0.1143)
		(layer "In15.Cu")
		(net "GMI_CPU0_G1_CPU1_G3_TX_DP<10>")
	)
	(segment
		(start 121.87174 -227.772722)
		(end 121.863358 -227.778818)
		(width 0.1143)
		(layer "In15.Cu")
		(net "GMI_CPU0_G1_CPU1_G3_TX_DP<10>")
	)
	(segment
		(start 349.663258 -243.352066)
		(end 349.66402 -243.351558)
		(width 0.1143)
		(layer "In15.Cu")
		(net "GMI_CPU0_G1_CPU1_G3_TX_DP<10>")
	)
	(segment
		(start 121.831608 -231.036876)
		(end 121.792492 -231.059736)
		(width 0.1143)
		(layer "In15.Cu")
		(net "GMI_CPU0_G1_CPU1_G3_TX_DP<10>")
	)
	(segment
		(start 349.703136 -244.019578)
		(end 349.696278 -244.015514)
		(width 0.1143)
		(layer "In15.Cu")
		(net "GMI_CPU0_G1_CPU1_G3_TX_DP<10>")
	)
	(segment
		(start 349.657416 -243.992908)
		(end 349.656146 -243.992146)
		(width 0.1143)
		(layer "In15.Cu")
		(net "GMI_CPU0_G1_CPU1_G3_TX_DP<10>")
	)
	(segment
		(start 121.800112 -227.133658)
		(end 121.830592 -227.151438)
		(width 0.1143)
		(layer "In15.Cu")
		(net "GMI_CPU0_G1_CPU1_G3_TX_DP<10>")
	)
	(segment
		(start 121.831608 -225.531934)
		(end 121.83237 -225.532442)
		(width 0.1143)
		(layer "In15.Cu")
		(net "GMI_CPU0_G1_CPU1_G3_TX_DP<10>")
	)
	(segment
		(start 349.660464 -235.894626)
		(end 349.659702 -235.894118)
		(width 0.1143)
		(layer "In15.Cu")
		(net "GMI_CPU0_G1_CPU1_G3_TX_DP<10>")
	)
	(segment
		(start 121.79935 -235.232956)
		(end 121.800112 -235.233464)
		(width 0.1143)
		(layer "In15.Cu")
		(net "GMI_CPU0_G1_CPU1_G3_TX_DP<10>")
	)
	(segment
		(start 349.665036 -243.997226)
		(end 349.66402 -243.996718)
		(width 0.1143)
		(layer "In15.Cu")
		(net "GMI_CPU0_G1_CPU1_G3_TX_DP<10>")
	)
	(segment
		(start 121.47931 -220.991938)
		(end 121.47931 -221.020386)
		(width 0.1143)
		(layer "In15.Cu")
		(net "GMI_CPU0_G1_CPU1_G3_TX_DP<10>")
	)
	(segment
		(start 166.993824 -183.401462)
		(end 162.450272 -185.0263)
		(width 0.14224)
		(layer "In15.Cu")
		(net "GMI_CPU0_G1_CPU1_G3_TX_DP<10>")
	)
	(segment
		(start 121.831608 -229.416864)
		(end 121.792492 -229.439724)
		(width 0.1143)
		(layer "In15.Cu")
		(net "GMI_CPU0_G1_CPU1_G3_TX_DP<10>")
	)
	(segment
		(start 349.696278 -240.77549)
		(end 349.695516 -240.774982)
		(width 0.1143)
		(layer "In15.Cu")
		(net "GMI_CPU0_G1_CPU1_G3_TX_DP<10>")
	)
	(segment
		(start 121.83237 -238.492284)
		(end 121.863358 -238.510064)
		(width 0.1143)
		(layer "In15.Cu")
		(net "GMI_CPU0_G1_CPU1_G3_TX_DP<10>")
	)
	(segment
		(start 349.663258 -233.631994)
		(end 349.66402 -233.631486)
		(width 0.1143)
		(layer "In15.Cu")
		(net "GMI_CPU0_G1_CPU1_G3_TX_DP<10>")
	)
	(segment
		(start 349.696278 -239.155478)
		(end 349.695516 -239.15497)
		(width 0.1143)
		(layer "In15.Cu")
		(net "GMI_CPU0_G1_CPU1_G3_TX_DP<10>")
	)
	(segment
		(start 121.863358 -224.538794)
		(end 121.83237 -224.556574)
		(width 0.1143)
		(layer "In15.Cu")
		(net "GMI_CPU0_G1_CPU1_G3_TX_DP<10>")
	)
	(segment
		(start 121.869962 -232.633774)
		(end 121.863358 -232.6386)
		(width 0.1143)
		(layer "In15.Cu")
		(net "GMI_CPU0_G1_CPU1_G3_TX_DP<10>")
	)
	(segment
		(start 121.83237 -233.632248)
		(end 121.863358 -233.650028)
		(width 0.1143)
		(layer "In15.Cu")
		(net "GMI_CPU0_G1_CPU1_G3_TX_DP<10>")
	)
	(segment
		(start 349.658178 -239.13338)
		(end 349.657416 -239.132872)
		(width 0.1143)
		(layer "In15.Cu")
		(net "GMI_CPU0_G1_CPU1_G3_TX_DP<10>")
	)
	(segment
		(start 349.666306 -232.010204)
		(end 349.668592 -232.00868)
		(width 0.1143)
		(layer "In15.Cu")
		(net "GMI_CPU0_G1_CPU1_G3_TX_DP<10>")
	)
	(segment
		(start 348.030546 -221.308676)
		(end 348.030546 -221.128844)
		(width 0.1143)
		(layer "In15.Cu")
		(net "GMI_CPU0_G1_CPU1_G3_TX_DP<10>")
	)
	(segment
		(start 349.66402 -240.111534)
		(end 349.665036 -240.111026)
		(width 0.1143)
		(layer "In15.Cu")
		(net "GMI_CPU0_G1_CPU1_G3_TX_DP<10>")
	)
	(segment
		(start 349.696278 -234.295442)
		(end 349.695516 -234.294934)
		(width 0.1143)
		(layer "In15.Cu")
		(net "GMI_CPU0_G1_CPU1_G3_TX_DP<10>")
	)
	(segment
		(start 349.66402 -240.756694)
		(end 349.663258 -240.756186)
		(width 0.1143)
		(layer "In15.Cu")
		(net "GMI_CPU0_G1_CPU1_G3_TX_DP<10>")
	)
	(segment
		(start 121.832116 -237.516924)
		(end 121.831608 -237.517178)
		(width 0.1143)
		(layer "In15.Cu")
		(net "GMI_CPU0_G1_CPU1_G3_TX_DP<10>")
	)
	(segment
		(start 121.831608 -227.797106)
		(end 121.830592 -227.797614)
		(width 0.1143)
		(layer "In15.Cu")
		(net "GMI_CPU0_G1_CPU1_G3_TX_DP<10>")
	)
	(segment
		(start 349.666306 -236.87024)
		(end 349.668592 -236.868716)
		(width 0.1143)
		(layer "In15.Cu")
		(net "GMI_CPU0_G1_CPU1_G3_TX_DP<10>")
	)
	(segment
		(start 121.792492 -238.468916)
		(end 121.79935 -238.47298)
		(width 0.1143)
		(layer "In15.Cu")
		(net "GMI_CPU0_G1_CPU1_G3_TX_DP<10>")
	)
	(segment
		(start 349.656146 -232.652062)
		(end 349.653606 -232.650792)
		(width 0.1143)
		(layer "In15.Cu")
		(net "GMI_CPU0_G1_CPU1_G3_TX_DP<10>")
	)
	(segment
		(start 348.030546 -221.128844)
		(end 348.076266 -221.083124)
		(width 0.1143)
		(layer "In15.Cu")
		(net "GMI_CPU0_G1_CPU1_G3_TX_DP<10>")
	)
	(segment
		(start 121.792492 -240.088928)
		(end 121.79935 -240.092992)
		(width 0.1143)
		(layer "In15.Cu")
		(net "GMI_CPU0_G1_CPU1_G3_TX_DP<10>")
	)
	(segment
		(start 121.874534 -243.970556)
		(end 121.863358 -243.978684)
		(width 0.1143)
		(layer "In15.Cu")
		(net "GMI_CPU0_G1_CPU1_G3_TX_DP<10>")
	)
	(segment
		(start 121.83237 -225.532442)
		(end 121.863358 -225.550222)
		(width 0.1143)
		(layer "In15.Cu")
		(net "GMI_CPU0_G1_CPU1_G3_TX_DP<10>")
	)
	(segment
		(start 121.829068 -239.13846)
		(end 121.792492 -239.159796)
		(width 0.1143)
		(layer "In15.Cu")
		(net "GMI_CPU0_G1_CPU1_G3_TX_DP<10>")
	)
	(segment
		(start 349.66402 -233.631486)
		(end 349.665036 -233.630978)
		(width 0.1143)
		(layer "In15.Cu")
		(net "GMI_CPU0_G1_CPU1_G3_TX_DP<10>")
	)
	(segment
		(start 308.55031 -185.03392)
		(end 307.654452 -184.623456)
		(width 0.14224)
		(layer "In15.Cu")
		(net "GMI_CPU0_G1_CPU1_G3_TX_DP<10>")
	)
	(segment
		(start 349.656146 -234.272074)
		(end 349.653606 -234.270804)
		(width 0.1143)
		(layer "In15.Cu")
		(net "GMI_CPU0_G1_CPU1_G3_TX_DP<10>")
	)
	(segment
		(start 121.829068 -232.658412)
		(end 121.792492 -232.679748)
		(width 0.1143)
		(layer "In15.Cu")
		(net "GMI_CPU0_G1_CPU1_G3_TX_DP<10>")
	)
	(segment
		(start 121.831608 -240.756948)
		(end 121.830592 -240.757456)
		(width 0.1143)
		(layer "In15.Cu")
		(net "GMI_CPU0_G1_CPU1_G3_TX_DP<10>")
	)
	(segment
		(start 122.482356 -247.654572)
		(end 122.412506 -247.724422)
		(width 0.1143)
		(layer "In15.Cu")
		(net "GMI_CPU0_G1_CPU1_G3_TX_DP<10>")
	)
	(segment
		(start 121.865136 -231.017318)
		(end 121.831608 -231.036876)
		(width 0.1143)
		(layer "In15.Cu")
		(net "GMI_CPU0_G1_CPU1_G3_TX_DP<10>")
	)
	(segment
		(start 121.831608 -244.971824)
		(end 121.83237 -244.972332)
		(width 0.1143)
		(layer "In15.Cu")
		(net "GMI_CPU0_G1_CPU1_G3_TX_DP<10>")
	)
	(segment
		(start 349.66402 -243.351558)
		(end 349.665036 -243.35105)
		(width 0.1143)
		(layer "In15.Cu")
		(net "GMI_CPU0_G1_CPU1_G3_TX_DP<10>")
	)
	(segment
		(start 349.668592 -243.348764)
		(end 349.703136 -243.328698)
		(width 0.1143)
		(layer "In15.Cu")
		(net "GMI_CPU0_G1_CPU1_G3_TX_DP<10>")
	)
	(segment
		(start 348.254066 -222.12681)
		(end 348.222316 -222.108522)
		(width 0.1143)
		(layer "In15.Cu")
		(net "GMI_CPU0_G1_CPU1_G3_TX_DP<10>")
	)
	(segment
		(start 122.412506 -247.724422)
		(end 122.114818 -247.724422)
		(width 0.1143)
		(layer "In15.Cu")
		(net "GMI_CPU0_G1_CPU1_G3_TX_DP<10>")
	)
	(segment
		(start 349.663258 -240.756186)
		(end 349.660464 -240.754662)
		(width 0.1143)
		(layer "In15.Cu")
		(net "GMI_CPU0_G1_CPU1_G3_TX_DP<10>")
	)
	(segment
		(start 146.658076 -197.972426)
		(end 144.98955 -198.47814)
		(width 0.14224)
		(layer "In15.Cu")
		(net "GMI_CPU0_G1_CPU1_G3_TX_DP<10>")
	)
	(segment
		(start 121.83237 -245.616476)
		(end 121.831608 -245.616984)
		(width 0.1143)
		(layer "In15.Cu")
		(net "GMI_CPU0_G1_CPU1_G3_TX_DP<10>")
	)
	(segment
		(start 122.032014 -246.922798)
		(end 122.032014 -246.934228)
		(width 0.1143)
		(layer "In15.Cu")
		(net "GMI_CPU0_G1_CPU1_G3_TX_DP<10>")
	)
	(segment
		(start 121.83237 -224.556574)
		(end 121.831608 -224.557082)
		(width 0.1143)
		(layer "In15.Cu")
		(net "GMI_CPU0_G1_CPU1_G3_TX_DP<10>")
	)
	(segment
		(start 121.800112 -223.893634)
		(end 121.830592 -223.911414)
		(width 0.1143)
		(layer "In15.Cu")
		(net "GMI_CPU0_G1_CPU1_G3_TX_DP<10>")
	)
	(segment
		(start 121.863358 -244.990112)
		(end 121.87301 -244.99697)
		(width 0.1143)
		(layer "In15.Cu")
		(net "GMI_CPU0_G1_CPU1_G3_TX_DP<10>")
	)
	(segment
		(start 121.83237 -244.972332)
		(end 121.863358 -244.990112)
		(width 0.1143)
		(layer "In15.Cu")
		(net "GMI_CPU0_G1_CPU1_G3_TX_DP<10>")
	)
	(segment
		(start 121.83237 -234.276392)
		(end 121.831608 -234.2769)
		(width 0.1143)
		(layer "In15.Cu")
		(net "GMI_CPU0_G1_CPU1_G3_TX_DP<10>")
	)
	(segment
		(start 349.703136 -240.779554)
		(end 349.696278 -240.77549)
		(width 0.1143)
		(layer "In15.Cu")
		(net "GMI_CPU0_G1_CPU1_G3_TX_DP<10>")
	)
	(segment
		(start 121.863358 -222.310198)
		(end 121.879106 -222.321628)
		(width 0.1143)
		(layer "In15.Cu")
		(net "GMI_CPU0_G1_CPU1_G3_TX_DP<10>")
	)
	(segment
		(start 349.668592 -240.10874)
		(end 349.703136 -240.088674)
		(width 0.1143)
		(layer "In15.Cu")
		(net "GMI_CPU0_G1_CPU1_G3_TX_DP<10>")
	)
	(segment
		(start 349.668592 -244.968776)
		(end 349.703136 -244.94871)
		(width 0.1143)
		(layer "In15.Cu")
		(net "GMI_CPU0_G1_CPU1_G3_TX_DP<10>")
	)
	(segment
		(start 349.666306 -235.250228)
		(end 349.668592 -235.248704)
		(width 0.1143)
		(layer "In15.Cu")
		(net "GMI_CPU0_G1_CPU1_G3_TX_DP<10>")
	)
	(segment
		(start 121.830592 -223.911414)
		(end 121.831608 -223.911922)
		(width 0.1143)
		(layer "In15.Cu")
		(net "GMI_CPU0_G1_CPU1_G3_TX_DP<10>")
	)
	(segment
		(start 349.66402 -236.87151)
		(end 349.665036 -236.871002)
		(width 0.1143)
		(layer "In15.Cu")
		(net "GMI_CPU0_G1_CPU1_G3_TX_DP<10>")
	)
	(segment
		(start 121.830592 -244.971316)
		(end 121.831608 -244.971824)
		(width 0.1143)
		(layer "In15.Cu")
		(net "GMI_CPU0_G1_CPU1_G3_TX_DP<10>")
	)
	(segment
		(start 349.660464 -234.274614)
		(end 349.659702 -234.274106)
		(width 0.1143)
		(layer "In15.Cu")
		(net "GMI_CPU0_G1_CPU1_G3_TX_DP<10>")
	)
	(segment
		(start 349.666306 -241.730276)
		(end 349.668592 -241.728752)
		(width 0.1143)
		(layer "In15.Cu")
		(net "GMI_CPU0_G1_CPU1_G3_TX_DP<10>")
	)
	(segment
		(start 307.211984 -184.421018)
		(end 306.713636 -184.192926)
		(width 0.14224)
		(layer "In15.Cu")
		(net "GMI_CPU0_G1_CPU1_G3_TX_DP<10>")
	)
	(segment
		(start 121.800112 -228.75367)
		(end 121.830592 -228.77145)
		(width 0.1143)
		(layer "In15.Cu")
		(net "GMI_CPU0_G1_CPU1_G3_TX_DP<10>")
	)
	(segment
		(start 121.863358 -222.918782)
		(end 121.83237 -222.936562)
		(width 0.1143)
		(layer "In15.Cu")
		(net "GMI_CPU0_G1_CPU1_G3_TX_DP<10>")
	)
	(segment
		(start 121.831608 -235.251752)
		(end 121.831608 -235.251498)
		(width 0.1143)
		(layer "In15.Cu")
		(net "GMI_CPU0_G1_CPU1_G3_TX_DP<10>")
	)
	(segment
		(start 121.830592 -225.531426)
		(end 121.831608 -225.531934)
		(width 0.1143)
		(layer "In15.Cu")
		(net "GMI_CPU0_G1_CPU1_G3_TX_DP<10>")
	)
	(segment
		(start 121.831608 -223.911922)
		(end 121.83237 -223.91243)
		(width 0.1143)
		(layer "In15.Cu")
		(net "GMI_CPU0_G1_CPU1_G3_TX_DP<10>")
	)
	(segment
		(start 349.663258 -245.616222)
		(end 349.661988 -245.61546)
		(width 0.1143)
		(layer "In15.Cu")
		(net "GMI_CPU0_G1_CPU1_G3_TX_DP<10>")
	)
	(segment
		(start 121.873518 -242.351306)
		(end 121.863358 -242.358672)
		(width 0.1143)
		(layer "In15.Cu")
		(net "GMI_CPU0_G1_CPU1_G3_TX_DP<10>")
	)
	(segment
		(start 310.834024 -186.327034)
		(end 310.834278 -186.327034)
		(width 0.14224)
		(layer "In15.Cu")
		(net "GMI_CPU0_G1_CPU1_G3_TX_DP<10>")
	)
	(segment
		(start 349.66402 -242.376706)
		(end 349.663258 -242.376198)
		(width 0.1143)
		(layer "In15.Cu")
		(net "GMI_CPU0_G1_CPU1_G3_TX_DP<10>")
	)
	(segment
		(start 121.830592 -227.797614)
		(end 121.829068 -227.79863)
		(width 0.1143)
		(layer "In15.Cu")
		(net "GMI_CPU0_G1_CPU1_G3_TX_DP<10>")
	)
	(segment
		(start 349.63227 -244.989858)
		(end 349.663258 -244.972078)
		(width 0.1143)
		(layer "In15.Cu")
		(net "GMI_CPU0_G1_CPU1_G3_TX_DP<10>")
	)
	(segment
		(start 349.666306 -240.110264)
		(end 349.668592 -240.10874)
		(width 0.1143)
		(layer "In15.Cu")
		(net "GMI_CPU0_G1_CPU1_G3_TX_DP<10>")
	)
	(segment
		(start 121.863358 -241.750088)
		(end 121.873518 -241.757454)
		(width 0.1143)
		(layer "In15.Cu")
		(net "GMI_CPU0_G1_CPU1_G3_TX_DP<10>")
	)
	(segment
		(start 121.829068 -245.618508)
		(end 121.792492 -245.639844)
		(width 0.1143)
		(layer "In15.Cu")
		(net "GMI_CPU0_G1_CPU1_G3_TX_DP<10>")
	)
	(segment
		(start 121.792492 -246.568976)
		(end 121.79935 -246.57304)
		(width 0.1143)
		(layer "In15.Cu")
		(net "GMI_CPU0_G1_CPU1_G3_TX_DP<10>")
	)
	(segment
		(start 349.63227 -233.649774)
		(end 349.663258 -233.631994)
		(width 0.1143)
		(layer "In15.Cu")
		(net "GMI_CPU0_G1_CPU1_G3_TX_DP<10>")
	)
	(segment
		(start 121.863358 -245.598696)
		(end 121.83237 -245.616476)
		(width 0.1143)
		(layer "In15.Cu")
		(net "GMI_CPU0_G1_CPU1_G3_TX_DP<10>")
	)
	(segment
		(start 348.763082 -222.959676)
		(end 348.723966 -222.936816)
		(width 0.1143)
		(layer "In15.Cu")
		(net "GMI_CPU0_G1_CPU1_G3_TX_DP<10>")
	)
	(segment
		(start 349.703136 -245.63959)
		(end 349.665036 -245.617238)
		(width 0.1143)
		(layer "In15.Cu")
		(net "GMI_CPU0_G1_CPU1_G3_TX_DP<10>")
	)
	(segment
		(start 349.665036 -237.517178)
		(end 349.66402 -237.51667)
		(width 0.1143)
		(layer "In15.Cu")
		(net "GMI_CPU0_G1_CPU1_G3_TX_DP<10>")
	)
	(segment
		(start 121.79935 -228.753162)
		(end 121.800112 -228.75367)
		(width 0.1143)
		(layer "In15.Cu")
		(net "GMI_CPU0_G1_CPU1_G3_TX_DP<10>")
	)
	(segment
		(start 121.800112 -240.0935)
		(end 121.830592 -240.11128)
		(width 0.1143)
		(layer "In15.Cu")
		(net "GMI_CPU0_G1_CPU1_G3_TX_DP<10>")
	)
	(segment
		(start 121.79935 -246.57304)
		(end 121.800112 -246.573548)
		(width 0.1143)
		(layer "In15.Cu")
		(net "GMI_CPU0_G1_CPU1_G3_TX_DP<10>")
	)
	(segment
		(start 349.190564 -225.364802)
		(end 349.189802 -225.364294)
		(width 0.1143)
		(layer "In15.Cu")
		(net "GMI_CPU0_G1_CPU1_G3_TX_DP<10>")
	)
	(segment
		(start 122.301762 -247.401842)
		(end 122.333258 -247.420384)
		(width 0.1143)
		(layer "In15.Cu")
		(net "GMI_CPU0_G1_CPU1_G3_TX_DP<10>")
	)
	(segment
		(start 144.98955 -198.47814)
		(end 123.755912 -215.88857)
		(width 0.14224)
		(layer "In15.Cu")
		(net "GMI_CPU0_G1_CPU1_G3_TX_DP<10>")
	)
	(segment
		(start 121.831608 -239.136936)
		(end 121.830592 -239.137444)
		(width 0.1143)
		(layer "In15.Cu")
		(net "GMI_CPU0_G1_CPU1_G3_TX_DP<10>")
	)
	(segment
		(start 349.657416 -234.272836)
		(end 349.656146 -234.272074)
		(width 0.1143)
		(layer "In15.Cu")
		(net "GMI_CPU0_G1_CPU1_G3_TX_DP<10>")
	)
	(segment
		(start 121.800112 -241.713512)
		(end 121.830592 -241.731292)
		(width 0.1143)
		(layer "In15.Cu")
		(net "GMI_CPU0_G1_CPU1_G3_TX_DP<10>")
	)
	(segment
		(start 121.87301 -245.591838)
		(end 121.863358 -245.598696)
		(width 0.1143)
		(layer "In15.Cu")
		(net "GMI_CPU0_G1_CPU1_G3_TX_DP<10>")
	)
	(segment
		(start 121.79935 -225.513138)
		(end 121.800112 -225.513646)
		(width 0.1143)
		(layer "In15.Cu")
		(net "GMI_CPU0_G1_CPU1_G3_TX_DP<10>")
	)
	(segment
		(start 349.663258 -244.972078)
		(end 349.66402 -244.97157)
		(width 0.1143)
		(layer "In15.Cu")
		(net "GMI_CPU0_G1_CPU1_G3_TX_DP<10>")
	)
	(segment
		(start 121.83237 -243.35232)
		(end 121.863358 -243.3701)
		(width 0.1143)
		(layer "In15.Cu")
		(net "GMI_CPU0_G1_CPU1_G3_TX_DP<10>")
	)
	(segment
		(start 121.79935 -227.13315)
		(end 121.800112 -227.133658)
		(width 0.1143)
		(layer "In15.Cu")
		(net "GMI_CPU0_G1_CPU1_G3_TX_DP<10>")
	)
	(segment
		(start 349.66402 -235.896658)
		(end 349.663258 -235.89615)
		(width 0.1143)
		(layer "In15.Cu")
		(net "GMI_CPU0_G1_CPU1_G3_TX_DP<10>")
	)
	(segment
		(start 349.665036 -246.591074)
		(end 349.666306 -246.590312)
		(width 0.1143)
		(layer "In15.Cu")
		(net "GMI_CPU0_G1_CPU1_G3_TX_DP<10>")
	)
	(segment
		(start 349.703136 -237.53953)
		(end 349.665036 -237.517178)
		(width 0.1143)
		(layer "In15.Cu")
		(net "GMI_CPU0_G1_CPU1_G3_TX_DP<10>")
	)
	(segment
		(start 349.656146 -243.992146)
		(end 349.653606 -243.990876)
		(width 0.1143)
		(layer "In15.Cu")
		(net "GMI_CPU0_G1_CPU1_G3_TX_DP<10>")
	)
	(segment
		(start 121.830592 -240.11128)
		(end 121.831608 -240.111788)
		(width 0.1143)
		(layer "In15.Cu")
		(net "GMI_CPU0_G1_CPU1_G3_TX_DP<10>")
	)
	(segment
		(start 121.47931 -221.020386)
		(end 121.52503 -221.066106)
		(width 0.1143)
		(layer "In15.Cu")
		(net "GMI_CPU0_G1_CPU1_G3_TX_DP<10>")
	)
	(segment
		(start 121.863358 -225.550222)
		(end 121.873518 -225.557588)
		(width 0.1143)
		(layer "In15.Cu")
		(net "GMI_CPU0_G1_CPU1_G3_TX_DP<10>")
	)
	(segment
		(start 121.79935 -241.713004)
		(end 121.800112 -241.713512)
		(width 0.1143)
		(layer "In15.Cu")
		(net "GMI_CPU0_G1_CPU1_G3_TX_DP<10>")
	)
	(segment
		(start 121.79935 -244.953028)
		(end 121.800112 -244.953536)
		(width 0.1143)
		(layer "In15.Cu")
		(net "GMI_CPU0_G1_CPU1_G3_TX_DP<10>")
	)
	(segment
		(start 121.831608 -232.656888)
		(end 121.830592 -232.657396)
		(width 0.1143)
		(layer "In15.Cu")
		(net "GMI_CPU0_G1_CPU1_G3_TX_DP<10>")
	)
	(segment
		(start 121.830592 -224.55759)
		(end 121.829068 -224.558606)
		(width 0.1143)
		(layer "In15.Cu")
		(net "GMI_CPU0_G1_CPU1_G3_TX_DP<10>")
	)
	(segment
		(start 121.831608 -237.517178)
		(end 121.831608 -237.516924)
		(width 0.1143)
		(layer "In15.Cu")
		(net "GMI_CPU0_G1_CPU1_G3_TX_DP<10>")
	)
	(segment
		(start 349.665036 -236.871002)
		(end 349.666306 -236.87024)
		(width 0.1143)
		(layer "In15.Cu")
		(net "GMI_CPU0_G1_CPU1_G3_TX_DP<10>")
	)
	(segment
		(start 349.658178 -232.653332)
		(end 349.657416 -232.652824)
		(width 0.1143)
		(layer "In15.Cu")
		(net "GMI_CPU0_G1_CPU1_G3_TX_DP<10>")
	)
	(segment
		(start 349.66402 -231.036622)
		(end 349.630492 -231.017064)
		(width 0.1143)
		(layer "In15.Cu")
		(net "GMI_CPU0_G1_CPU1_G3_TX_DP<10>")
	)
	(segment
		(start 307.654452 -184.62371)
		(end 307.211984 -184.420764)
		(width 0.14224)
		(layer "In15.Cu")
		(net "GMI_CPU0_G1_CPU1_G3_TX_DP<10>")
	)
	(segment
		(start 121.52503 -221.277942)
		(end 121.549414 -221.302326)
		(width 0.1143)
		(layer "In15.Cu")
		(net "GMI_CPU0_G1_CPU1_G3_TX_DP<10>")
	)
	(segment
		(start 121.83237 -246.592344)
		(end 121.832878 -246.592344)
		(width 0.1143)
		(layer "In15.Cu")
		(net "GMI_CPU0_G1_CPU1_G3_TX_DP<10>")
	)
	(segment
		(start 349.665036 -240.757202)
		(end 349.66402 -240.756694)
		(width 0.1143)
		(layer "In15.Cu")
		(net "GMI_CPU0_G1_CPU1_G3_TX_DP<10>")
	)
	(segment
		(start 349.66402 -244.97157)
		(end 349.665036 -244.971062)
		(width 0.1143)
		(layer "In15.Cu")
		(net "GMI_CPU0_G1_CPU1_G3_TX_DP<10>")
	)
	(segment
		(start 121.830592 -242.377468)
		(end 121.82602 -242.380262)
		(width 0.1143)
		(layer "In15.Cu")
		(net "GMI_CPU0_G1_CPU1_G3_TX_DP<10>")
	)
	(segment
		(start 349.666306 -233.630216)
		(end 349.668592 -233.628692)
		(width 0.1143)
		(layer "In15.Cu")
		(net "GMI_CPU0_G1_CPU1_G3_TX_DP<10>")
	)
	(segment
		(start 349.659702 -235.894118)
		(end 349.658178 -235.893356)
		(width 0.1143)
		(layer "In15.Cu")
		(net "GMI_CPU0_G1_CPU1_G3_TX_DP<10>")
	)
	(segment
		(start 121.831608 -232.011728)
		(end 121.83237 -232.012236)
		(width 0.1143)
		(layer "In15.Cu")
		(net "GMI_CPU0_G1_CPU1_G3_TX_DP<10>")
	)
	(segment
		(start 349.656146 -235.892086)
		(end 349.653606 -235.890816)
		(width 0.1143)
		(layer "In15.Cu")
		(net "GMI_CPU0_G1_CPU1_G3_TX_DP<10>")
	)
	(segment
		(start 349.658178 -234.273344)
		(end 349.657416 -234.272836)
		(width 0.1143)
		(layer "In15.Cu")
		(net "GMI_CPU0_G1_CPU1_G3_TX_DP<10>")
	)
	(segment
		(start 349.663258 -242.376198)
		(end 349.661988 -242.375436)
		(width 0.1143)
		(layer "In15.Cu")
		(net "GMI_CPU0_G1_CPU1_G3_TX_DP<10>")
	)
	(segment
		(start 121.831608 -246.591836)
		(end 121.83237 -246.592344)
		(width 0.1143)
		(layer "In15.Cu")
		(net "GMI_CPU0_G1_CPU1_G3_TX_DP<10>")
	)
	(segment
		(start 307.654452 -184.623456)
		(end 307.654452 -184.62371)
		(width 0.14224)
		(layer "In15.Cu")
		(net "GMI_CPU0_G1_CPU1_G3_TX_DP<10>")
	)
	(segment
		(start 121.831608 -235.896912)
		(end 121.830592 -235.89742)
		(width 0.1143)
		(layer "In15.Cu")
		(net "GMI_CPU0_G1_CPU1_G3_TX_DP<10>")
	)
	(segment
		(start 121.829068 -234.278424)
		(end 121.792492 -234.29976)
		(width 0.1143)
		(layer "In15.Cu")
		(net "GMI_CPU0_G1_CPU1_G3_TX_DP<10>")
	)
	(segment
		(start 349.663258 -232.656126)
		(end 349.660464 -232.654602)
		(width 0.1143)
		(layer "In15.Cu")
		(net "GMI_CPU0_G1_CPU1_G3_TX_DP<10>")
	)
	(segment
		(start 121.830592 -246.591328)
		(end 121.831608 -246.591836)
		(width 0.1143)
		(layer "In15.Cu")
		(net "GMI_CPU0_G1_CPU1_G3_TX_DP<10>")
	)
	(segment
		(start 349.657416 -235.892848)
		(end 349.656146 -235.892086)
		(width 0.1143)
		(layer "In15.Cu")
		(net "GMI_CPU0_G1_CPU1_G3_TX_DP<10>")
	)
	(segment
		(start 349.653606 -239.13084)
		(end 349.63227 -239.118394)
		(width 0.1143)
		(layer "In15.Cu")
		(net "GMI_CPU0_G1_CPU1_G3_TX_DP<10>")
	)
	(segment
		(start 349.658178 -240.753392)
		(end 349.657416 -240.752884)
		(width 0.1143)
		(layer "In15.Cu")
		(net "GMI_CPU0_G1_CPU1_G3_TX_DP<10>")
	)
	(segment
		(start 349.660464 -243.994686)
		(end 349.659702 -243.994178)
		(width 0.1143)
		(layer "In15.Cu")
		(net "GMI_CPU0_G1_CPU1_G3_TX_DP<10>")
	)
	(segment
		(start 349.668592 -246.588788)
		(end 349.703136 -246.568722)
		(width 0.1143)
		(layer "In15.Cu")
		(net "GMI_CPU0_G1_CPU1_G3_TX_DP<10>")
	)
	(segment
		(start 349.659702 -243.994178)
		(end 349.658178 -243.993416)
		(width 0.1143)
		(layer "In15.Cu")
		(net "GMI_CPU0_G1_CPU1_G3_TX_DP<10>")
	)
	(segment
		(start 121.879106 -222.907352)
		(end 121.863358 -222.918782)
		(width 0.1143)
		(layer "In15.Cu")
		(net "GMI_CPU0_G1_CPU1_G3_TX_DP<10>")
	)
	(segment
		(start 121.863358 -232.030016)
		(end 121.869962 -232.034842)
		(width 0.1143)
		(layer "In15.Cu")
		(net "GMI_CPU0_G1_CPU1_G3_TX_DP<10>")
	)
	(segment
		(start 349.668592 -233.628692)
		(end 349.703136 -233.608626)
		(width 0.1143)
		(layer "In15.Cu")
		(net "GMI_CPU0_G1_CPU1_G3_TX_DP<10>")
	)
	(segment
		(start 349.657416 -232.652824)
		(end 349.656146 -232.652062)
		(width 0.1143)
		(layer "In15.Cu")
		(net "GMI_CPU0_G1_CPU1_G3_TX_DP<10>")
	)
	(segment
		(start 121.830592 -236.871256)
		(end 121.831608 -236.871764)
		(width 0.1143)
		(layer "In15.Cu")
		(net "GMI_CPU0_G1_CPU1_G3_TX_DP<10>")
	)
	(segment
		(start 121.830592 -237.517432)
		(end 121.829068 -237.518448)
		(width 0.1143)
		(layer "In15.Cu")
		(net "GMI_CPU0_G1_CPU1_G3_TX_DP<10>")
	)
	(segment
		(start 121.831608 -234.2769)
		(end 121.830592 -234.277408)
		(width 0.1143)
		(layer "In15.Cu")
		(net "GMI_CPU0_G1_CPU1_G3_TX_DP<10>")
	)
	(segment
		(start 121.830592 -227.151438)
		(end 121.831608 -227.151946)
		(width 0.1143)
		(layer "In15.Cu")
		(net "GMI_CPU0_G1_CPU1_G3_TX_DP<10>")
	)
	(segment
		(start 349.19412 -225.366834)
		(end 349.193358 -225.366326)
		(width 0.1143)
		(layer "In15.Cu")
		(net "GMI_CPU0_G1_CPU1_G3_TX_DP<10>")
	)
	(segment
		(start 349.19666 -225.368358)
		(end 349.195136 -225.367342)
		(width 0.1143)
		(layer "In15.Cu")
		(net "GMI_CPU0_G1_CPU1_G3_TX_DP<10>")
	)
	(segment
		(start 348.763082 -224.579688)
		(end 348.723966 -224.556828)
		(width 0.1143)
		(layer "In15.Cu")
		(net "GMI_CPU0_G1_CPU1_G3_TX_DP<10>")
	)
	(segment
		(start 345.64955 -214.291418)
		(end 313.128406 -187.625736)
		(width 0.14224)
		(layer "In15.Cu")
		(net "GMI_CPU0_G1_CPU1_G3_TX_DP<10>")
	)
	(segment
		(start 121.830592 -222.937578)
		(end 121.829068 -222.938594)
		(width 0.1143)
		(layer "In15.Cu")
		(net "GMI_CPU0_G1_CPU1_G3_TX_DP<10>")
	)
	(segment
		(start 121.863358 -243.978684)
		(end 121.83237 -243.996464)
		(width 0.1143)
		(layer "In15.Cu")
		(net "GMI_CPU0_G1_CPU1_G3_TX_DP<10>")
	)
	(segment
		(start 121.863358 -232.6386)
		(end 121.83237 -232.65638)
		(width 0.1143)
		(layer "In15.Cu")
		(net "GMI_CPU0_G1_CPU1_G3_TX_DP<10>")
	)
	(segment
		(start 349.665036 -238.491014)
		(end 349.66656 -238.489998)
		(width 0.1143)
		(layer "In15.Cu")
		(net "GMI_CPU0_G1_CPU1_G3_TX_DP<10>")
	)
	(segment
		(start 349.63227 -243.369846)
		(end 349.663258 -243.352066)
		(width 0.1143)
		(layer "In15.Cu")
		(net "GMI_CPU0_G1_CPU1_G3_TX_DP<10>")
	)
	(segment
		(start 349.659702 -232.654094)
		(end 349.658178 -232.653332)
		(width 0.1143)
		(layer "In15.Cu")
		(net "GMI_CPU0_G1_CPU1_G3_TX_DP<10>")
	)
	(segment
		(start 121.800112 -243.333524)
		(end 121.830592 -243.351304)
		(width 0.1143)
		(layer "In15.Cu")
		(net "GMI_CPU0_G1_CPU1_G3_TX_DP<10>")
	)
	(segment
		(start 349.381064 -247.724168)
		(end 349.083122 -247.724168)
		(width 0.1143)
		(layer "In15.Cu")
		(net "GMI_CPU0_G1_CPU1_G3_TX_DP<10>")
	)
	(segment
		(start 349.63227 -238.50981)
		(end 349.66402 -238.491522)
		(width 0.1143)
		(layer "In15.Cu")
		(net "GMI_CPU0_G1_CPU1_G3_TX_DP<10>")
	)
	(segment
		(start 121.83237 -239.136428)
		(end 121.831608 -239.136936)
		(width 0.1143)
		(layer "In15.Cu")
		(net "GMI_CPU0_G1_CPU1_G3_TX_DP<10>")
	)
	(segment
		(start 121.83237 -228.772466)
		(end 121.832878 -228.77272)
		(width 0.1143)
		(layer "In15.Cu")
		(net "GMI_CPU0_G1_CPU1_G3_TX_DP<10>")
	)
	(segment
		(start 349.656146 -240.752122)
		(end 349.653606 -240.750852)
		(width 0.1143)
		(layer "In15.Cu")
		(net "GMI_CPU0_G1_CPU1_G3_TX_DP<10>")
	)
	(segment
		(start 349.665036 -232.657142)
		(end 349.66402 -232.656634)
		(width 0.1143)
		(layer "In15.Cu")
		(net "GMI_CPU0_G1_CPU1_G3_TX_DP<10>")
	)
	(segment
		(start 121.792492 -244.948964)
		(end 121.79935 -244.953028)
		(width 0.1143)
		(layer "In15.Cu")
		(net "GMI_CPU0_G1_CPU1_G3_TX_DP<10>")
	)
	(segment
		(start 121.831608 -245.616984)
		(end 121.830592 -245.617492)
		(width 0.1143)
		(layer "In15.Cu")
		(net "GMI_CPU0_G1_CPU1_G3_TX_DP<10>")
	)
	(segment
		(start 348.076266 -219.419424)
		(end 345.64955 -214.291418)
		(width 0.14224)
		(layer "In15.Cu")
		(net "GMI_CPU0_G1_CPU1_G3_TX_DP<10>")
	)
	(segment
		(start 349.658178 -243.993416)
		(end 349.657416 -243.992908)
		(width 0.1143)
		(layer "In15.Cu")
		(net "GMI_CPU0_G1_CPU1_G3_TX_DP<10>")
	)
	(segment
		(start 121.83237 -241.732308)
		(end 121.863358 -241.750088)
		(width 0.1143)
		(layer "In15.Cu")
		(net "GMI_CPU0_G1_CPU1_G3_TX_DP<10>")
	)
	(segment
		(start 349.665036 -245.617238)
		(end 349.66402 -245.61673)
		(width 0.1143)
		(layer "In15.Cu")
		(net "GMI_CPU0_G1_CPU1_G3_TX_DP<10>")
	)
	(segment
		(start 348.723966 -223.911668)
		(end 348.763082 -223.888808)
		(width 0.1143)
		(layer "In15.Cu")
		(net "GMI_CPU0_G1_CPU1_G3_TX_DP<10>")
	)
	(segment
		(start 349.66402 -237.51667)
		(end 349.663258 -237.516162)
		(width 0.1143)
		(layer "In15.Cu")
		(net "GMI_CPU0_G1_CPU1_G3_TX_DP<10>")
	)
	(segment
		(start 349.192088 -225.365564)
		(end 349.190564 -225.364802)
		(width 0.1143)
		(layer "In15.Cu")
		(net "GMI_CPU0_G1_CPU1_G3_TX_DP<10>")
	)
	(segment
		(start 349.663258 -239.136174)
		(end 349.660464 -239.13465)
		(width 0.1143)
		(layer "In15.Cu")
		(net "GMI_CPU0_G1_CPU1_G3_TX_DP<10>")
	)
	(segment
		(start 121.830592 -238.491268)
		(end 121.831608 -238.491776)
		(width 0.1143)
		(layer "In15.Cu")
		(net "GMI_CPU0_G1_CPU1_G3_TX_DP<10>")
	)
	(segment
		(start 349.66402 -243.996718)
		(end 349.663258 -243.99621)
		(width 0.1143)
		(layer "In15.Cu")
		(net "GMI_CPU0_G1_CPU1_G3_TX_DP<10>")
	)
	(segment
		(start 121.832116 -240.756948)
		(end 121.831608 -240.757202)
		(width 0.1143)
		(layer "In15.Cu")
		(net "GMI_CPU0_G1_CPU1_G3_TX_DP<10>")
	)
	(arc
		(start 348.222316 -222.108522)
		(mid 348.10764 -221.975188)
		(end 348.06636 -221.80423)
		(width 0.1143)
		(layer "In15.Cu")
		(net "GMI_CPU0_G1_CPU1_G3_TX_DP<10>")
	)
	(arc
		(start 121.832878 -228.77272)
		(mid 121.969296 -228.908593)
		(end 122.019314 -229.094538)
		(width 0.1143)
		(layer "In15.Cu")
		(net "GMI_CPU0_G1_CPU1_G3_TX_DP<10>")
	)
	(arc
		(start 348.693486 -222.919036)
		(mid 348.578059 -222.78566)
		(end 348.536514 -222.614236)
		(width 0.1143)
		(layer "In15.Cu")
		(net "GMI_CPU0_G1_CPU1_G3_TX_DP<10>")
	)
	(arc
		(start 349.703136 -240.088674)
		(mid 349.946463 -239.624108)
		(end 349.703136 -239.159542)
		(width 0.1143)
		(layer "In15.Cu")
		(net "GMI_CPU0_G1_CPU1_G3_TX_DP<10>")
	)
	(arc
		(start 349.63227 -234.258358)
		(mid 349.476342 -233.954066)
		(end 349.63227 -233.649774)
		(width 0.1143)
		(layer "In15.Cu")
		(net "GMI_CPU0_G1_CPU1_G3_TX_DP<10>")
	)
	(arc
		(start 349.006414 -225.044254)
		(mid 348.941899 -224.782035)
		(end 348.763082 -224.579688)
		(width 0.1143)
		(layer "In15.Cu")
		(net "GMI_CPU0_G1_CPU1_G3_TX_DP<10>")
	)
	(arc
		(start 349.63227 -242.358418)
		(mid 349.476342 -242.054126)
		(end 349.63227 -241.749834)
		(width 0.1143)
		(layer "In15.Cu")
		(net "GMI_CPU0_G1_CPU1_G3_TX_DP<10>")
	)
	(arc
		(start 121.54916 -221.804484)
		(mid 121.613819 -222.067041)
		(end 121.793 -222.269558)
		(width 0.1143)
		(layer "In15.Cu")
		(net "GMI_CPU0_G1_CPU1_G3_TX_DP<10>")
	)
	(arc
		(start 121.833386 -230.392986)
		(mid 121.969467 -230.528834)
		(end 122.019314 -230.71455)
		(width 0.1143)
		(layer "In15.Cu")
		(net "GMI_CPU0_G1_CPU1_G3_TX_DP<10>")
	)
	(arc
		(start 121.874534 -243.378228)
		(mid 122.026294 -243.674392)
		(end 121.874534 -243.970556)
		(width 0.1143)
		(layer "In15.Cu")
		(net "GMI_CPU0_G1_CPU1_G3_TX_DP<10>")
	)
	(arc
		(start 349.703136 -228.748844)
		(mid 349.946463 -228.284278)
		(end 349.703136 -227.819712)
		(width 0.1143)
		(layer "In15.Cu")
		(net "GMI_CPU0_G1_CPU1_G3_TX_DP<10>")
	)
	(arc
		(start 121.877074 -238.51997)
		(mid 122.027919 -238.814356)
		(end 121.877074 -239.108742)
		(width 0.1143)
		(layer "In15.Cu")
		(net "GMI_CPU0_G1_CPU1_G3_TX_DP<10>")
	)
	(arc
		(start 121.846594 -246.600218)
		(mid 121.982332 -246.73677)
		(end 122.032014 -246.922798)
		(width 0.1143)
		(layer "In15.Cu")
		(net "GMI_CPU0_G1_CPU1_G3_TX_DP<10>")
	)
	(arc
		(start 121.792492 -231.059736)
		(mid 121.549165 -231.524302)
		(end 121.792492 -231.988868)
		(width 0.1143)
		(layer "In15.Cu")
		(net "GMI_CPU0_G1_CPU1_G3_TX_DP<10>")
	)
	(arc
		(start 121.879106 -222.321628)
		(mid 122.029242 -222.61449)
		(end 121.879106 -222.907352)
		(width 0.1143)
		(layer "In15.Cu")
		(net "GMI_CPU0_G1_CPU1_G3_TX_DP<10>")
	)
	(arc
		(start 348.763082 -223.888808)
		(mid 349.006409 -223.424242)
		(end 348.763082 -222.959676)
		(width 0.1143)
		(layer "In15.Cu")
		(net "GMI_CPU0_G1_CPU1_G3_TX_DP<10>")
	)
	(arc
		(start 122.019314 -229.094538)
		(mid 121.978552 -229.264422)
		(end 121.865136 -229.397306)
		(width 0.1143)
		(layer "In15.Cu")
		(net "GMI_CPU0_G1_CPU1_G3_TX_DP<10>")
	)
	(arc
		(start 121.88317 -223.944434)
		(mid 122.031884 -224.234502)
		(end 121.88317 -224.52457)
		(width 0.1143)
		(layer "In15.Cu")
		(net "GMI_CPU0_G1_CPU1_G3_TX_DP<10>")
	)
	(arc
		(start 121.793 -222.269558)
		(mid 121.793381 -222.269812)
		(end 121.793762 -222.270066)
		(width 0.1143)
		(layer "In15.Cu")
		(net "GMI_CPU0_G1_CPU1_G3_TX_DP<10>")
	)
	(arc
		(start 121.792492 -226.199954)
		(mid 121.549165 -226.66452)
		(end 121.792492 -227.129086)
		(width 0.1143)
		(layer "In15.Cu")
		(net "GMI_CPU0_G1_CPU1_G3_TX_DP<10>")
	)
	(arc
		(start 121.832116 -235.251752)
		(mid 122.017754 -235.574158)
		(end 121.83237 -235.896658)
		(width 0.1143)
		(layer "In15.Cu")
		(net "GMI_CPU0_G1_CPU1_G3_TX_DP<10>")
	)
	(arc
		(start 122.392186 -247.472962)
		(mid 122.449805 -247.557546)
		(end 122.482356 -247.654572)
		(width 0.1143)
		(layer "In15.Cu")
		(net "GMI_CPU0_G1_CPU1_G3_TX_DP<10>")
	)
	(arc
		(start 121.792492 -237.539784)
		(mid 121.549165 -238.00435)
		(end 121.792492 -238.468916)
		(width 0.1143)
		(layer "In15.Cu")
		(net "GMI_CPU0_G1_CPU1_G3_TX_DP<10>")
	)
	(arc
		(start 121.54916 -229.90429)
		(mid 121.614396 -230.167881)
		(end 121.795032 -230.370634)
		(width 0.1143)
		(layer "In15.Cu")
		(net "GMI_CPU0_G1_CPU1_G3_TX_DP<10>")
	)
	(arc
		(start 121.873518 -241.757454)
		(mid 122.025685 -242.05438)
		(end 121.873518 -242.351306)
		(width 0.1143)
		(layer "In15.Cu")
		(net "GMI_CPU0_G1_CPU1_G3_TX_DP<10>")
	)
	(arc
		(start 121.792492 -245.639844)
		(mid 121.549165 -246.10441)
		(end 121.792492 -246.568976)
		(width 0.1143)
		(layer "In15.Cu")
		(net "GMI_CPU0_G1_CPU1_G3_TX_DP<10>")
	)
	(arc
		(start 349.703136 -235.228638)
		(mid 349.946463 -234.764072)
		(end 349.703136 -234.299506)
		(width 0.1143)
		(layer "In15.Cu")
		(net "GMI_CPU0_G1_CPU1_G3_TX_DP<10>")
	)
	(arc
		(start 121.832116 -236.871764)
		(mid 122.017754 -237.194344)
		(end 121.832116 -237.516924)
		(width 0.1143)
		(layer "In15.Cu")
		(net "GMI_CPU0_G1_CPU1_G3_TX_DP<10>")
	)
	(arc
		(start 349.476568 -225.85426)
		(mid 349.412053 -225.592041)
		(end 349.233236 -225.389694)
		(width 0.1143)
		(layer "In15.Cu")
		(net "GMI_CPU0_G1_CPU1_G3_TX_DP<10>")
	)
	(arc
		(start 121.792492 -239.159796)
		(mid 121.549165 -239.624362)
		(end 121.792492 -240.088928)
		(width 0.1143)
		(layer "In15.Cu")
		(net "GMI_CPU0_G1_CPU1_G3_TX_DP<10>")
	)
	(arc
		(start 349.700596 -230.37038)
		(mid 349.881248 -230.167635)
		(end 349.946468 -229.904036)
		(width 0.1143)
		(layer "In15.Cu")
		(net "GMI_CPU0_G1_CPU1_G3_TX_DP<10>")
	)
	(arc
		(start 122.333258 -247.420384)
		(mid 122.364105 -247.445123)
		(end 122.392186 -247.472962)
		(width 0.1143)
		(layer "In15.Cu")
		(net "GMI_CPU0_G1_CPU1_G3_TX_DP<10>")
	)
	(arc
		(start 349.703136 -244.94871)
		(mid 349.946463 -244.484144)
		(end 349.703136 -244.019578)
		(width 0.1143)
		(layer "In15.Cu")
		(net "GMI_CPU0_G1_CPU1_G3_TX_DP<10>")
	)
	(arc
		(start 348.536514 -222.614236)
		(mid 348.471999 -222.352017)
		(end 348.293182 -222.14967)
		(width 0.1143)
		(layer "In15.Cu")
		(net "GMI_CPU0_G1_CPU1_G3_TX_DP<10>")
	)
	(arc
		(start 349.946468 -229.904036)
		(mid 349.881953 -229.641817)
		(end 349.703136 -229.43947)
		(width 0.1143)
		(layer "In15.Cu")
		(net "GMI_CPU0_G1_CPU1_G3_TX_DP<10>")
	)
	(arc
		(start 121.792492 -222.95993)
		(mid 121.549165 -223.424496)
		(end 121.792492 -223.889062)
		(width 0.1143)
		(layer "In15.Cu")
		(net "GMI_CPU0_G1_CPU1_G3_TX_DP<10>")
	)
	(arc
		(start 349.703136 -231.988614)
		(mid 349.946463 -231.524048)
		(end 349.703136 -231.059482)
		(width 0.1143)
		(layer "In15.Cu")
		(net "GMI_CPU0_G1_CPU1_G3_TX_DP<10>")
	)
	(arc
		(start 121.792492 -234.29976)
		(mid 121.549165 -234.764326)
		(end 121.792492 -235.228892)
		(width 0.1143)
		(layer "In15.Cu")
		(net "GMI_CPU0_G1_CPU1_G3_TX_DP<10>")
	)
	(arc
		(start 349.63227 -237.498382)
		(mid 349.476342 -237.19409)
		(end 349.63227 -236.889798)
		(width 0.1143)
		(layer "In15.Cu")
		(net "GMI_CPU0_G1_CPU1_G3_TX_DP<10>")
	)
	(arc
		(start 121.863358 -233.650028)
		(mid 122.014947 -233.95432)
		(end 121.863358 -234.258612)
		(width 0.1143)
		(layer "In15.Cu")
		(net "GMI_CPU0_G1_CPU1_G3_TX_DP<10>")
	)
	(arc
		(start 121.792492 -232.679748)
		(mid 121.549165 -233.144314)
		(end 121.792492 -233.60888)
		(width 0.1143)
		(layer "In15.Cu")
		(net "GMI_CPU0_G1_CPU1_G3_TX_DP<10>")
	)
	(arc
		(start 349.63227 -240.738406)
		(mid 349.476342 -240.434114)
		(end 349.63227 -240.129822)
		(width 0.1143)
		(layer "In15.Cu")
		(net "GMI_CPU0_G1_CPU1_G3_TX_DP<10>")
	)
	(arc
		(start 349.63227 -239.118394)
		(mid 349.476342 -238.814102)
		(end 349.63227 -238.50981)
		(width 0.1143)
		(layer "In15.Cu")
		(net "GMI_CPU0_G1_CPU1_G3_TX_DP<10>")
	)
	(arc
		(start 349.703136 -246.568722)
		(mid 349.946463 -246.104156)
		(end 349.703136 -245.63959)
		(width 0.1143)
		(layer "In15.Cu")
		(net "GMI_CPU0_G1_CPU1_G3_TX_DP<10>")
	)
	(arc
		(start 121.792492 -229.439724)
		(mid 121.613679 -229.642074)
		(end 121.54916 -229.90429)
		(width 0.1143)
		(layer "In15.Cu")
		(net "GMI_CPU0_G1_CPU1_G3_TX_DP<10>")
	)
	(arc
		(start 349.63227 -232.638346)
		(mid 349.476342 -232.334054)
		(end 349.63227 -232.029762)
		(width 0.1143)
		(layer "In15.Cu")
		(net "GMI_CPU0_G1_CPU1_G3_TX_DP<10>")
	)
	(arc
		(start 121.792492 -242.39982)
		(mid 121.549165 -242.864386)
		(end 121.792492 -243.328952)
		(width 0.1143)
		(layer "In15.Cu")
		(net "GMI_CPU0_G1_CPU1_G3_TX_DP<10>")
	)
	(arc
		(start 349.703136 -236.84865)
		(mid 349.946463 -236.384084)
		(end 349.703136 -235.919518)
		(width 0.1143)
		(layer "In15.Cu")
		(net "GMI_CPU0_G1_CPU1_G3_TX_DP<10>")
	)
	(arc
		(start 349.630492 -231.017064)
		(mid 349.517085 -230.884175)
		(end 349.476314 -230.714296)
		(width 0.1143)
		(layer "In15.Cu")
		(net "GMI_CPU0_G1_CPU1_G3_TX_DP<10>")
	)
	(arc
		(start 121.832116 -240.111788)
		(mid 122.017754 -240.434368)
		(end 121.832116 -240.756948)
		(width 0.1143)
		(layer "In15.Cu")
		(net "GMI_CPU0_G1_CPU1_G3_TX_DP<10>")
	)
	(arc
		(start 349.63227 -245.598442)
		(mid 349.476342 -245.29415)
		(end 349.63227 -244.989858)
		(width 0.1143)
		(layer "In15.Cu")
		(net "GMI_CPU0_G1_CPU1_G3_TX_DP<10>")
	)
	(arc
		(start 349.63227 -235.87837)
		(mid 349.476342 -235.574078)
		(end 349.63227 -235.269786)
		(width 0.1143)
		(layer "In15.Cu")
		(net "GMI_CPU0_G1_CPU1_G3_TX_DP<10>")
	)
	(arc
		(start 349.63354 -226.15906)
		(mid 349.518113 -226.025684)
		(end 349.476568 -225.85426)
		(width 0.1143)
		(layer "In15.Cu")
		(net "GMI_CPU0_G1_CPU1_G3_TX_DP<10>")
	)
	(arc
		(start 349.63227 -243.97843)
		(mid 349.476342 -243.674138)
		(end 349.63227 -243.369846)
		(width 0.1143)
		(layer "In15.Cu")
		(net "GMI_CPU0_G1_CPU1_G3_TX_DP<10>")
	)
	(arc
		(start 121.873518 -225.557588)
		(mid 122.025685 -225.854514)
		(end 121.873518 -226.15144)
		(width 0.1143)
		(layer "In15.Cu")
		(net "GMI_CPU0_G1_CPU1_G3_TX_DP<10>")
	)
	(arc
		(start 349.631508 -229.397814)
		(mid 349.517579 -229.264667)
		(end 349.476568 -229.094284)
		(width 0.1143)
		(layer "In15.Cu")
		(net "GMI_CPU0_G1_CPU1_G3_TX_DP<10>")
	)
	(arc
		(start 349.703136 -243.328698)
		(mid 349.946463 -242.864132)
		(end 349.703136 -242.399566)
		(width 0.1143)
		(layer "In15.Cu")
		(net "GMI_CPU0_G1_CPU1_G3_TX_DP<10>")
	)
	(arc
		(start 349.703136 -233.608626)
		(mid 349.946463 -233.14406)
		(end 349.703136 -232.679494)
		(width 0.1143)
		(layer "In15.Cu")
		(net "GMI_CPU0_G1_CPU1_G3_TX_DP<10>")
	)
	(arc
		(start 121.869962 -232.034842)
		(mid 122.023452 -232.334308)
		(end 121.869962 -232.633774)
		(width 0.1143)
		(layer "In15.Cu")
		(net "GMI_CPU0_G1_CPU1_G3_TX_DP<10>")
	)
	(arc
		(start 349.232982 -247.378728)
		(mid 349.411795 -247.176378)
		(end 349.476314 -246.914162)
		(width 0.1143)
		(layer "In15.Cu")
		(net "GMI_CPU0_G1_CPU1_G3_TX_DP<10>")
	)
	(arc
		(start 349.16237 -225.348546)
		(mid 349.047694 -225.215212)
		(end 349.006414 -225.044254)
		(width 0.1143)
		(layer "In15.Cu")
		(net "GMI_CPU0_G1_CPU1_G3_TX_DP<10>")
	)
	(arc
		(start 121.792492 -227.819966)
		(mid 121.549165 -228.284532)
		(end 121.792492 -228.749098)
		(width 0.1143)
		(layer "In15.Cu")
		(net "GMI_CPU0_G1_CPU1_G3_TX_DP<10>")
	)
	(arc
		(start 349.703136 -238.468662)
		(mid 349.946463 -238.004096)
		(end 349.703136 -237.53953)
		(width 0.1143)
		(layer "In15.Cu")
		(net "GMI_CPU0_G1_CPU1_G3_TX_DP<10>")
	)
	(arc
		(start 349.703136 -227.128832)
		(mid 349.946463 -226.664266)
		(end 349.703136 -226.1997)
		(width 0.1143)
		(layer "In15.Cu")
		(net "GMI_CPU0_G1_CPU1_G3_TX_DP<10>")
	)
	(arc
		(start 349.703136 -241.708686)
		(mid 349.946463 -241.24412)
		(end 349.703136 -240.779554)
		(width 0.1143)
		(layer "In15.Cu")
		(net "GMI_CPU0_G1_CPU1_G3_TX_DP<10>")
	)
	(arc
		(start 121.792492 -224.579942)
		(mid 121.549165 -225.044508)
		(end 121.792492 -225.509074)
		(width 0.1143)
		(layer "In15.Cu")
		(net "GMI_CPU0_G1_CPU1_G3_TX_DP<10>")
	)
	(arc
		(start 121.792492 -235.919772)
		(mid 121.549165 -236.384338)
		(end 121.792492 -236.848904)
		(width 0.1143)
		(layer "In15.Cu")
		(net "GMI_CPU0_G1_CPU1_G3_TX_DP<10>")
	)
	(arc
		(start 121.87301 -244.99697)
		(mid 122.025484 -245.294404)
		(end 121.87301 -245.591838)
		(width 0.1143)
		(layer "In15.Cu")
		(net "GMI_CPU0_G1_CPU1_G3_TX_DP<10>")
	)
	(arc
		(start 122.032014 -246.934228)
		(mid 122.104279 -247.204157)
		(end 122.301762 -247.401842)
		(width 0.1143)
		(layer "In15.Cu")
		(net "GMI_CPU0_G1_CPU1_G3_TX_DP<10>")
	)
	(arc
		(start 122.019314 -230.71455)
		(mid 121.978552 -230.884434)
		(end 121.865136 -231.017318)
		(width 0.1143)
		(layer "In15.Cu")
		(net "GMI_CPU0_G1_CPU1_G3_TX_DP<10>")
	)
	(arc
		(start 348.693486 -224.539048)
		(mid 348.536509 -224.234248)
		(end 348.693486 -223.929448)
		(width 0.1143)
		(layer "In15.Cu")
		(net "GMI_CPU0_G1_CPU1_G3_TX_DP<10>")
	)
	(arc
		(start 349.013272 -247.654318)
		(mid 349.065689 -247.522387)
		(end 349.163386 -247.419368)
		(width 0.1143)
		(layer "In15.Cu")
		(net "GMI_CPU0_G1_CPU1_G3_TX_DP<10>")
	)
	(arc
		(start 121.87174 -227.17633)
		(mid 122.024621 -227.474526)
		(end 121.87174 -227.772722)
		(width 0.1143)
		(layer "In15.Cu")
		(net "GMI_CPU0_G1_CPU1_G3_TX_DP<10>")
	)
	(arc
		(start 349.476314 -246.914162)
		(mid 349.517569 -246.743191)
		(end 349.63227 -246.60987)
		(width 0.1143)
		(layer "In15.Cu")
		(net "GMI_CPU0_G1_CPU1_G3_TX_DP<10>")
	)
	(arc
		(start 121.792492 -244.019832)
		(mid 121.549165 -244.484398)
		(end 121.792492 -244.948964)
		(width 0.1143)
		(layer "In15.Cu")
		(net "GMI_CPU0_G1_CPU1_G3_TX_DP<10>")
	)
	(arc
		(start 349.476314 -230.714296)
		(mid 349.517569 -230.543325)
		(end 349.63227 -230.410004)
		(width 0.1143)
		(layer "In15.Cu")
		(net "GMI_CPU0_G1_CPU1_G3_TX_DP<10>")
	)
	(arc
		(start 349.63354 -227.779072)
		(mid 349.476563 -227.474272)
		(end 349.63354 -227.169472)
		(width 0.1143)
		(layer "In15.Cu")
		(net "GMI_CPU0_G1_CPU1_G3_TX_DP<10>")
	)
	(arc
		(start 121.792492 -240.779808)
		(mid 121.549165 -241.244374)
		(end 121.792492 -241.70894)
		(width 0.1143)
		(layer "In15.Cu")
		(net "GMI_CPU0_G1_CPU1_G3_TX_DP<10>")
	)
	(arc
		(start 349.476568 -229.094284)
		(mid 349.518117 -228.922862)
		(end 349.63354 -228.789484)
		(width 0.1143)
		(layer "In15.Cu")
		(net "GMI_CPU0_G1_CPU1_G3_TX_DP<10>")
	)
	(segment
		(start 113.657888 -248.800366)
		(end 114.12474 -248.534428)
		(width 0.12954)
		(layer "F.Cu")
		(net "GMI_CPU0_G1_CPU1_G3_TX_DP<0>")
	)
	(segment
		(start 357.837994 -248.800112)
		(end 357.371142 -248.534174)
		(width 0.12954)
		(layer "F.Cu")
		(net "GMI_CPU0_G1_CPU1_G3_TX_DP<0>")
	)
	(segment
		(start 112.901984 -245.78183)
		(end 112.933734 -245.800118)
		(width 0.1143)
		(layer "In15.Cu")
		(net "GMI_CPU0_G1_CPU1_G3_TX_DP<0>")
	)
	(segment
		(start 114.492532 -248.464578)
		(end 114.422682 -248.534428)
		(width 0.1143)
		(layer "In15.Cu")
		(net "GMI_CPU0_G1_CPU1_G3_TX_DP<0>")
	)
	(segment
		(start 112.0775 -243.597938)
		(end 112.0775 -244.984016)
		(width 0.1143)
		(layer "In15.Cu")
		(net "GMI_CPU0_G1_CPU1_G3_TX_DP<0>")
	)
	(segment
		(start 358.123998 -246.591582)
		(end 358.16032 -246.5705)
		(width 0.1143)
		(layer "In15.Cu")
		(net "GMI_CPU0_G1_CPU1_G3_TX_DP<0>")
	)
	(segment
		(start 113.802668 -247.378982)
		(end 113.809526 -247.383046)
		(width 0.1143)
		(layer "In15.Cu")
		(net "GMI_CPU0_G1_CPU1_G3_TX_DP<0>")
	)
	(segment
		(start 359.419652 -244.414548)
		(end 359.465372 -244.368828)
		(width 0.1143)
		(layer "In15.Cu")
		(net "GMI_CPU0_G1_CPU1_G3_TX_DP<0>")
	)
	(segment
		(start 358.583738 -245.787418)
		(end 358.584754 -245.78691)
		(width 0.1143)
		(layer "In15.Cu")
		(net "GMI_CPU0_G1_CPU1_G3_TX_DP<0>")
	)
	(segment
		(start 113.371884 -246.591836)
		(end 113.402364 -246.609616)
		(width 0.1143)
		(layer "In15.Cu")
		(net "GMI_CPU0_G1_CPU1_G3_TX_DP<0>")
	)
	(segment
		(start 357.65359 -247.401588)
		(end 357.654098 -247.401588)
		(width 0.1143)
		(layer "In15.Cu")
		(net "GMI_CPU0_G1_CPU1_G3_TX_DP<0>")
	)
	(segment
		(start 357.0732 -248.534174)
		(end 357.00335 -248.464324)
		(width 0.1143)
		(layer "In15.Cu")
		(net "GMI_CPU0_G1_CPU1_G3_TX_DP<0>")
	)
	(segment
		(start 354.54463 -209.191606)
		(end 318.563752 -179.688236)
		(width 0.14224)
		(layer "In15.Cu")
		(net "GMI_CPU0_G1_CPU1_G3_TX_DP<0>")
	)
	(segment
		(start 113.837466 -247.399302)
		(end 113.83899 -247.400318)
		(width 0.1143)
		(layer "In15.Cu")
		(net "GMI_CPU0_G1_CPU1_G3_TX_DP<0>")
	)
	(segment
		(start 113.83645 -247.398794)
		(end 113.837466 -247.399302)
		(width 0.1143)
		(layer "In15.Cu")
		(net "GMI_CPU0_G1_CPU1_G3_TX_DP<0>")
	)
	(segment
		(start 113.844324 -247.403366)
		(end 113.857278 -247.410732)
		(width 0.1143)
		(layer "In15.Cu")
		(net "GMI_CPU0_G1_CPU1_G3_TX_DP<0>")
	)
	(segment
		(start 302.9204 -174.784512)
		(end 164.760148 -173.975776)
		(width 0.14224)
		(layer "In15.Cu")
		(net "GMI_CPU0_G1_CPU1_G3_TX_DP<0>")
	)
	(segment
		(start 358.584754 -245.78691)
		(end 358.593898 -245.781576)
		(width 0.1143)
		(layer "In15.Cu")
		(net "GMI_CPU0_G1_CPU1_G3_TX_DP<0>")
	)
	(segment
		(start 114.422682 -248.534428)
		(end 114.12474 -248.534428)
		(width 0.1143)
		(layer "In15.Cu")
		(net "GMI_CPU0_G1_CPU1_G3_TX_DP<0>")
	)
	(segment
		(start 359.419652 -244.982492)
		(end 359.419652 -244.414548)
		(width 0.1143)
		(layer "In15.Cu")
		(net "GMI_CPU0_G1_CPU1_G3_TX_DP<0>")
	)
	(segment
		(start 135.687562 -193.747898)
		(end 135.687054 -193.748152)
		(width 0.14224)
		(layer "In15.Cu")
		(net "GMI_CPU0_G1_CPU1_G3_TX_DP<0>")
	)
	(segment
		(start 308.723538 -174.784512)
		(end 302.9204 -174.784512)
		(width 0.14224)
		(layer "In15.Cu")
		(net "GMI_CPU0_G1_CPU1_G3_TX_DP<0>")
	)
	(segment
		(start 357.656638 -247.400064)
		(end 357.657654 -247.399556)
		(width 0.1143)
		(layer "In15.Cu")
		(net "GMI_CPU0_G1_CPU1_G3_TX_DP<0>")
	)
	(segment
		(start 135.687054 -193.748152)
		(end 115.409726 -210.375246)
		(width 0.14224)
		(layer "In15.Cu")
		(net "GMI_CPU0_G1_CPU1_G3_TX_DP<0>")
	)
	(segment
		(start 357.62565 -247.417844)
		(end 357.65359 -247.401588)
		(width 0.1143)
		(layer "In15.Cu")
		(net "GMI_CPU0_G1_CPU1_G3_TX_DP<0>")
	)
	(segment
		(start 112.0775 -244.984016)
		(end 112.78616 -245.69293)
		(width 0.1143)
		(layer "In15.Cu")
		(net "GMI_CPU0_G1_CPU1_G3_TX_DP<0>")
	)
	(segment
		(start 357.152448 -248.229882)
		(end 357.184198 -248.211594)
		(width 0.1143)
		(layer "In15.Cu")
		(net "GMI_CPU0_G1_CPU1_G3_TX_DP<0>")
	)
	(segment
		(start 358.582976 -245.787926)
		(end 358.583738 -245.787418)
		(width 0.1143)
		(layer "In15.Cu")
		(net "GMI_CPU0_G1_CPU1_G3_TX_DP<0>")
	)
	(segment
		(start 115.409726 -210.375246)
		(end 112.03051 -216.123266)
		(width 0.14224)
		(layer "In15.Cu")
		(net "GMI_CPU0_G1_CPU1_G3_TX_DP<0>")
	)
	(segment
		(start 113.83899 -247.400318)
		(end 113.840768 -247.401334)
		(width 0.1143)
		(layer "In15.Cu")
		(net "GMI_CPU0_G1_CPU1_G3_TX_DP<0>")
	)
	(segment
		(start 318.563752 -179.688236)
		(end 311.920382 -175.927512)
		(width 0.14224)
		(layer "In15.Cu")
		(net "GMI_CPU0_G1_CPU1_G3_TX_DP<0>")
	)
	(segment
		(start 113.335562 -246.570754)
		(end 113.371884 -246.591836)
		(width 0.1143)
		(layer "In15.Cu")
		(net "GMI_CPU0_G1_CPU1_G3_TX_DP<0>")
	)
	(segment
		(start 113.840768 -247.401334)
		(end 113.842292 -247.402096)
		(width 0.1143)
		(layer "In15.Cu")
		(net "GMI_CPU0_G1_CPU1_G3_TX_DP<0>")
	)
	(segment
		(start 113.842292 -247.402096)
		(end 113.844324 -247.403366)
		(width 0.1143)
		(layer "In15.Cu")
		(net "GMI_CPU0_G1_CPU1_G3_TX_DP<0>")
	)
	(segment
		(start 358.85755 -245.544848)
		(end 359.419652 -244.982492)
		(width 0.1143)
		(layer "In15.Cu")
		(net "GMI_CPU0_G1_CPU1_G3_TX_DP<0>")
	)
	(segment
		(start 311.920382 -175.927512)
		(end 308.723538 -174.784512)
		(width 0.14224)
		(layer "In15.Cu")
		(net "GMI_CPU0_G1_CPU1_G3_TX_DP<0>")
	)
	(segment
		(start 358.709722 -245.692676)
		(end 358.85755 -245.544848)
		(width 0.1143)
		(layer "In15.Cu")
		(net "GMI_CPU0_G1_CPU1_G3_TX_DP<0>")
	)
	(segment
		(start 114.322606 -248.21769)
		(end 114.357912 -248.238518)
		(width 0.1143)
		(layer "In15.Cu")
		(net "GMI_CPU0_G1_CPU1_G3_TX_DP<0>")
	)
	(segment
		(start 113.810288 -247.383554)
		(end 113.834926 -247.397778)
		(width 0.1143)
		(layer "In15.Cu")
		(net "GMI_CPU0_G1_CPU1_G3_TX_DP<0>")
	)
	(segment
		(start 112.03051 -216.123266)
		(end 112.03051 -243.550948)
		(width 0.14224)
		(layer "In15.Cu")
		(net "GMI_CPU0_G1_CPU1_G3_TX_DP<0>")
	)
	(segment
		(start 359.465372 -244.34038)
		(end 359.465372 -219.590112)
		(width 0.14224)
		(layer "In15.Cu")
		(net "GMI_CPU0_G1_CPU1_G3_TX_DP<0>")
	)
	(segment
		(start 357.371142 -248.534174)
		(end 357.0732 -248.534174)
		(width 0.1143)
		(layer "In15.Cu")
		(net "GMI_CPU0_G1_CPU1_G3_TX_DP<0>")
	)
	(segment
		(start 114.48923 -248.444258)
		(end 114.492786 -248.46407)
		(width 0.1143)
		(layer "In15.Cu")
		(net "GMI_CPU0_G1_CPU1_G3_TX_DP<0>")
	)
	(segment
		(start 113.809526 -247.383046)
		(end 113.810288 -247.383554)
		(width 0.1143)
		(layer "In15.Cu")
		(net "GMI_CPU0_G1_CPU1_G3_TX_DP<0>")
	)
	(segment
		(start 114.492786 -248.46407)
		(end 114.492786 -248.464578)
		(width 0.1143)
		(layer "In15.Cu")
		(net "GMI_CPU0_G1_CPU1_G3_TX_DP<0>")
	)
	(segment
		(start 357.184198 -248.211594)
		(end 357.22052 -248.190512)
		(width 0.1143)
		(layer "In15.Cu")
		(net "GMI_CPU0_G1_CPU1_G3_TX_DP<0>")
	)
	(segment
		(start 113.834926 -247.397778)
		(end 113.83645 -247.398794)
		(width 0.1143)
		(layer "In15.Cu")
		(net "GMI_CPU0_G1_CPU1_G3_TX_DP<0>")
	)
	(segment
		(start 357.655114 -247.40108)
		(end 357.656638 -247.400064)
		(width 0.1143)
		(layer "In15.Cu")
		(net "GMI_CPU0_G1_CPU1_G3_TX_DP<0>")
	)
	(segment
		(start 358.093518 -246.609362)
		(end 358.123998 -246.591582)
		(width 0.1143)
		(layer "In15.Cu")
		(net "GMI_CPU0_G1_CPU1_G3_TX_DP<0>")
	)
	(segment
		(start 357.654098 -247.401588)
		(end 357.655114 -247.40108)
		(width 0.1143)
		(layer "In15.Cu")
		(net "GMI_CPU0_G1_CPU1_G3_TX_DP<0>")
	)
	(segment
		(start 112.03051 -243.550948)
		(end 112.0775 -243.597938)
		(width 0.1143)
		(layer "In15.Cu")
		(net "GMI_CPU0_G1_CPU1_G3_TX_DP<0>")
	)
	(segment
		(start 358.562148 -245.799864)
		(end 358.582976 -245.787926)
		(width 0.1143)
		(layer "In15.Cu")
		(net "GMI_CPU0_G1_CPU1_G3_TX_DP<0>")
	)
	(segment
		(start 357.657654 -247.399556)
		(end 357.693214 -247.378728)
		(width 0.1143)
		(layer "In15.Cu")
		(net "GMI_CPU0_G1_CPU1_G3_TX_DP<0>")
	)
	(segment
		(start 164.760148 -173.975776)
		(end 155.964382 -177.121312)
		(width 0.14224)
		(layer "In15.Cu")
		(net "GMI_CPU0_G1_CPU1_G3_TX_DP<0>")
	)
	(segment
		(start 114.492786 -248.464578)
		(end 114.492532 -248.464578)
		(width 0.1143)
		(layer "In15.Cu")
		(net "GMI_CPU0_G1_CPU1_G3_TX_DP<0>")
	)
	(segment
		(start 155.964382 -177.121312)
		(end 135.687562 -193.747898)
		(width 0.14224)
		(layer "In15.Cu")
		(net "GMI_CPU0_G1_CPU1_G3_TX_DP<0>")
	)
	(segment
		(start 359.465372 -244.368828)
		(end 359.465372 -244.34038)
		(width 0.1143)
		(layer "In15.Cu")
		(net "GMI_CPU0_G1_CPU1_G3_TX_DP<0>")
	)
	(segment
		(start 359.465372 -219.590112)
		(end 354.54463 -209.191606)
		(width 0.14224)
		(layer "In15.Cu")
		(net "GMI_CPU0_G1_CPU1_G3_TX_DP<0>")
	)
	(arc
		(start 357.236776 -248.179082)
		(mid 357.400803 -247.981721)
		(end 357.466138 -247.733566)
		(width 0.1143)
		(layer "In15.Cu")
		(net "GMI_CPU0_G1_CPU1_G3_TX_DP<0>")
	)
	(arc
		(start 114.04219 -247.731788)
		(mid 114.117332 -248.012281)
		(end 114.322606 -248.21769)
		(width 0.1143)
		(layer "In15.Cu")
		(net "GMI_CPU0_G1_CPU1_G3_TX_DP<0>")
	)
	(arc
		(start 357.693214 -247.378728)
		(mid 357.872027 -247.176378)
		(end 357.936546 -246.914162)
		(width 0.1143)
		(layer "In15.Cu")
		(net "GMI_CPU0_G1_CPU1_G3_TX_DP<0>")
	)
	(arc
		(start 358.16032 -246.5705)
		(mid 358.340972 -246.367755)
		(end 358.406192 -246.104156)
		(width 0.1143)
		(layer "In15.Cu")
		(net "GMI_CPU0_G1_CPU1_G3_TX_DP<0>")
	)
	(arc
		(start 113.559336 -246.914416)
		(mid 113.623851 -247.176635)
		(end 113.802668 -247.378982)
		(width 0.1143)
		(layer "In15.Cu")
		(net "GMI_CPU0_G1_CPU1_G3_TX_DP<0>")
	)
	(arc
		(start 113.857278 -247.410732)
		(mid 113.992685 -247.546529)
		(end 114.04219 -247.731788)
		(width 0.1143)
		(layer "In15.Cu")
		(net "GMI_CPU0_G1_CPU1_G3_TX_DP<0>")
	)
	(arc
		(start 357.466138 -247.733566)
		(mid 357.466835 -247.721221)
		(end 357.46817 -247.708928)
		(width 0.1143)
		(layer "In15.Cu")
		(net "GMI_CPU0_G1_CPU1_G3_TX_DP<0>")
	)
	(arc
		(start 357.618284 -247.423432)
		(mid 357.62195 -247.420615)
		(end 357.62565 -247.417844)
		(width 0.1143)
		(layer "In15.Cu")
		(net "GMI_CPU0_G1_CPU1_G3_TX_DP<0>")
	)
	(arc
		(start 114.357912 -248.238518)
		(mid 114.443274 -248.328817)
		(end 114.48923 -248.444258)
		(width 0.1143)
		(layer "In15.Cu")
		(net "GMI_CPU0_G1_CPU1_G3_TX_DP<0>")
	)
	(arc
		(start 358.593898 -245.781576)
		(mid 358.654708 -245.740901)
		(end 358.709722 -245.692676)
		(width 0.1143)
		(layer "In15.Cu")
		(net "GMI_CPU0_G1_CPU1_G3_TX_DP<0>")
	)
	(arc
		(start 357.00335 -248.464324)
		(mid 357.055399 -248.332805)
		(end 357.152448 -248.229882)
		(width 0.1143)
		(layer "In15.Cu")
		(net "GMI_CPU0_G1_CPU1_G3_TX_DP<0>")
	)
	(arc
		(start 112.78616 -245.69293)
		(mid 112.841185 -245.74114)
		(end 112.901984 -245.78183)
		(width 0.1143)
		(layer "In15.Cu")
		(net "GMI_CPU0_G1_CPU1_G3_TX_DP<0>")
	)
	(arc
		(start 358.406192 -246.104156)
		(mid 358.447447 -245.933185)
		(end 358.562148 -245.799864)
		(width 0.1143)
		(layer "In15.Cu")
		(net "GMI_CPU0_G1_CPU1_G3_TX_DP<0>")
	)
	(arc
		(start 357.46817 -247.708928)
		(mid 357.518549 -247.553205)
		(end 357.618284 -247.423432)
		(width 0.1143)
		(layer "In15.Cu")
		(net "GMI_CPU0_G1_CPU1_G3_TX_DP<0>")
	)
	(arc
		(start 113.402364 -246.609616)
		(mid 113.517791 -246.742992)
		(end 113.559336 -246.914416)
		(width 0.1143)
		(layer "In15.Cu")
		(net "GMI_CPU0_G1_CPU1_G3_TX_DP<0>")
	)
	(arc
		(start 113.08969 -246.10441)
		(mid 113.154926 -246.368001)
		(end 113.335562 -246.570754)
		(width 0.1143)
		(layer "In15.Cu")
		(net "GMI_CPU0_G1_CPU1_G3_TX_DP<0>")
	)
	(arc
		(start 357.936546 -246.914162)
		(mid 357.978095 -246.74274)
		(end 358.093518 -246.609362)
		(width 0.1143)
		(layer "In15.Cu")
		(net "GMI_CPU0_G1_CPU1_G3_TX_DP<0>")
	)
	(arc
		(start 357.22052 -248.190512)
		(mid 357.228698 -248.184869)
		(end 357.236776 -248.179082)
		(width 0.1143)
		(layer "In15.Cu")
		(net "GMI_CPU0_G1_CPU1_G3_TX_DP<0>")
	)
	(arc
		(start 112.933734 -245.800118)
		(mid 113.04841 -245.933452)
		(end 113.08969 -246.10441)
		(width 0.1143)
		(layer "In15.Cu")
		(net "GMI_CPU0_G1_CPU1_G3_TX_DP<0>")
	)
	(segment
		(start 351.728024 -246.370094)
		(end 351.261172 -246.104156)
		(width 0.12954)
		(layer "F.Cu")
		(net "GMI_CPU0_G1_CPU1_G3_TX_DN<9>")
	)
	(segment
		(start 119.767858 -246.370348)
		(end 120.23471 -246.10441)
		(width 0.12954)
		(layer "F.Cu")
		(net "GMI_CPU0_G1_CPU1_G3_TX_DN<9>")
	)
	(segment
		(start 120.987566 -232.821734)
		(end 120.957086 -232.839514)
		(width 0.1143)
		(layer "In15.Cu")
		(net "GMI_CPU0_G1_CPU1_G3_TX_DN<9>")
	)
	(segment
		(start 348.739206 -221.083124)
		(end 348.739206 -219.16009)
		(width 0.14224)
		(layer "In15.Cu")
		(net "GMI_CPU0_G1_CPU1_G3_TX_DN<9>")
	)
	(segment
		(start 146.364452 -197.188836)
		(end 144.995138 -197.603364)
		(width 0.14224)
		(layer "In15.Cu")
		(net "GMI_CPU0_G1_CPU1_G3_TX_DN<9>")
	)
	(segment
		(start 350.538796 -236.079284)
		(end 350.508316 -236.061504)
		(width 0.1143)
		(layer "In15.Cu")
		(net "GMI_CPU0_G1_CPU1_G3_TX_DN<9>")
	)
	(segment
		(start 302.891952 -183.534812)
		(end 166.67734 -182.741316)
		(width 0.14224)
		(layer "In15.Cu")
		(net "GMI_CPU0_G1_CPU1_G3_TX_DN<9>")
	)
	(segment
		(start 121.026682 -240.898934)
		(end 120.987566 -240.921794)
		(width 0.1143)
		(layer "In15.Cu")
		(net "GMI_CPU0_G1_CPU1_G3_TX_DN<9>")
	)
	(segment
		(start 121.026682 -234.418886)
		(end 120.987566 -234.441746)
		(width 0.1143)
		(layer "In15.Cu")
		(net "GMI_CPU0_G1_CPU1_G3_TX_DN<9>")
	)
	(segment
		(start 351.178368 -245.3132)
		(end 351.178368 -245.303548)
		(width 0.1143)
		(layer "In15.Cu")
		(net "GMI_CPU0_G1_CPU1_G3_TX_DN<9>")
	)
	(segment
		(start 350.006666 -225.513392)
		(end 350.005904 -225.512884)
		(width 0.1143)
		(layer "In15.Cu")
		(net "GMI_CPU0_G1_CPU1_G3_TX_DN<9>")
	)
	(segment
		(start 119.936768 -246.10441)
		(end 120.23471 -246.10441)
		(width 0.1143)
		(layer "In15.Cu")
		(net "GMI_CPU0_G1_CPU1_G3_TX_DN<9>")
	)
	(segment
		(start 152.866598 -192.034922)
		(end 152.536398 -192.305686)
		(width 0.14224)
		(layer "In15.Cu")
		(net "GMI_CPU0_G1_CPU1_G3_TX_DN<9>")
	)
	(segment
		(start 350.4692 -243.209572)
		(end 350.508316 -243.186712)
		(width 0.1143)
		(layer "In15.Cu")
		(net "GMI_CPU0_G1_CPU1_G3_TX_DN<9>")
	)
	(segment
		(start 349.129858 -222.309944)
		(end 349.061786 -222.270574)
		(width 0.1143)
		(layer "In15.Cu")
		(net "GMI_CPU0_G1_CPU1_G3_TX_DN<9>")
	)
	(segment
		(start 120.957086 -225.349308)
		(end 120.987566 -225.367088)
		(width 0.1143)
		(layer "In15.Cu")
		(net "GMI_CPU0_G1_CPU1_G3_TX_DN<9>")
	)
	(segment
		(start 155.153106 -190.159894)
		(end 154.960066 -190.140844)
		(width 0.14224)
		(layer "In15.Cu")
		(net "GMI_CPU0_G1_CPU1_G3_TX_DN<9>")
	)
	(segment
		(start 350.005904 -225.512884)
		(end 349.999046 -225.50882)
		(width 0.1143)
		(layer "In15.Cu")
		(net "GMI_CPU0_G1_CPU1_G3_TX_DN<9>")
	)
	(segment
		(start 346.202762 -213.800182)
		(end 313.82716 -187.253372)
		(width 0.14224)
		(layer "In15.Cu")
		(net "GMI_CPU0_G1_CPU1_G3_TX_DN<9>")
	)
	(segment
		(start 155.502356 -189.69609)
		(end 155.483306 -189.88913)
		(width 0.14224)
		(layer "In15.Cu")
		(net "GMI_CPU0_G1_CPU1_G3_TX_DN<9>")
	)
	(segment
		(start 121.026682 -224.699068)
		(end 120.987566 -224.721928)
		(width 0.1143)
		(layer "In15.Cu")
		(net "GMI_CPU0_G1_CPU1_G3_TX_DN<9>")
	)
	(segment
		(start 120.556782 -244.948964)
		(end 120.517666 -244.971824)
		(width 0.1143)
		(layer "In15.Cu")
		(net "GMI_CPU0_G1_CPU1_G3_TX_DN<9>")
	)
	(segment
		(start 121.026682 -223.079056)
		(end 120.987566 -223.101916)
		(width 0.1143)
		(layer "In15.Cu")
		(net "GMI_CPU0_G1_CPU1_G3_TX_DN<9>")
	)
	(segment
		(start 350.4692 -231.869488)
		(end 350.508316 -231.846628)
		(width 0.1143)
		(layer "In15.Cu")
		(net "GMI_CPU0_G1_CPU1_G3_TX_DN<9>")
	)
	(segment
		(start 351.261172 -246.104156)
		(end 351.559114 -246.104156)
		(width 0.1143)
		(layer "In15.Cu")
		(net "GMI_CPU0_G1_CPU1_G3_TX_DN<9>")
	)
	(segment
		(start 350.508316 -234.441492)
		(end 350.4692 -234.418632)
		(width 0.1143)
		(layer "In15.Cu")
		(net "GMI_CPU0_G1_CPU1_G3_TX_DN<9>")
	)
	(segment
		(start 154.960066 -190.140844)
		(end 154.63012 -190.411354)
		(width 0.14224)
		(layer "In15.Cu")
		(net "GMI_CPU0_G1_CPU1_G3_TX_DN<9>")
	)
	(segment
		(start 120.987566 -233.466894)
		(end 121.026682 -233.489754)
		(width 0.1143)
		(layer "In15.Cu")
		(net "GMI_CPU0_G1_CPU1_G3_TX_DN<9>")
	)
	(segment
		(start 120.987566 -226.34194)
		(end 120.957086 -226.35972)
		(width 0.1143)
		(layer "In15.Cu")
		(net "GMI_CPU0_G1_CPU1_G3_TX_DN<9>")
	)
	(segment
		(start 120.987566 -223.747076)
		(end 121.026682 -223.769936)
		(width 0.1143)
		(layer "In15.Cu")
		(net "GMI_CPU0_G1_CPU1_G3_TX_DN<9>")
	)
	(segment
		(start 348.815914 -221.80423)
		(end 348.815914 -221.418658)
		(width 0.1143)
		(layer "In15.Cu")
		(net "GMI_CPU0_G1_CPU1_G3_TX_DN<9>")
	)
	(segment
		(start 350.069912 -225.549968)
		(end 350.040194 -225.53295)
		(width 0.1143)
		(layer "In15.Cu")
		(net "GMI_CPU0_G1_CPU1_G3_TX_DN<9>")
	)
	(segment
		(start 120.987566 -239.301782)
		(end 120.957086 -239.319562)
		(width 0.1143)
		(layer "In15.Cu")
		(net "GMI_CPU0_G1_CPU1_G3_TX_DN<9>")
	)
	(segment
		(start 120.987566 -236.061758)
		(end 120.957086 -236.079538)
		(width 0.1143)
		(layer "In15.Cu")
		(net "GMI_CPU0_G1_CPU1_G3_TX_DN<9>")
	)
	(segment
		(start 121.026682 -242.518946)
		(end 120.987566 -242.541806)
		(width 0.1143)
		(layer "In15.Cu")
		(net "GMI_CPU0_G1_CPU1_G3_TX_DN<9>")
	)
	(segment
		(start 120.047512 -245.78183)
		(end 120.017032 -245.79961)
		(width 0.1143)
		(layer "In15.Cu")
		(net "GMI_CPU0_G1_CPU1_G3_TX_DN<9>")
	)
	(segment
		(start 120.77065 -221.066106)
		(end 120.77065 -221.198948)
		(width 0.1143)
		(layer "In15.Cu")
		(net "GMI_CPU0_G1_CPU1_G3_TX_DN<9>")
	)
	(segment
		(start 120.987566 -241.566954)
		(end 121.026682 -241.589814)
		(width 0.1143)
		(layer "In15.Cu")
		(net "GMI_CPU0_G1_CPU1_G3_TX_DN<9>")
	)
	(segment
		(start 350.538796 -232.83926)
		(end 350.508316 -232.82148)
		(width 0.1143)
		(layer "In15.Cu")
		(net "GMI_CPU0_G1_CPU1_G3_TX_DN<9>")
	)
	(segment
		(start 120.987566 -231.201976)
		(end 120.955054 -231.220772)
		(width 0.1143)
		(layer "In15.Cu")
		(net "GMI_CPU0_G1_CPU1_G3_TX_DN<9>")
	)
	(segment
		(start 121.026682 -229.559104)
		(end 120.987566 -229.581964)
		(width 0.1143)
		(layer "In15.Cu")
		(net "GMI_CPU0_G1_CPU1_G3_TX_DN<9>")
	)
	(segment
		(start 349.529146 -223.769682)
		(end 349.568262 -223.746822)
		(width 0.1143)
		(layer "In15.Cu")
		(net "GMI_CPU0_G1_CPU1_G3_TX_DN<9>")
	)
	(segment
		(start 157.246828 -188.265562)
		(end 157.227778 -188.458602)
		(width 0.14224)
		(layer "In15.Cu")
		(net "GMI_CPU0_G1_CPU1_G3_TX_DN<9>")
	)
	(segment
		(start 120.086628 -245.75897)
		(end 120.047512 -245.78183)
		(width 0.1143)
		(layer "In15.Cu")
		(net "GMI_CPU0_G1_CPU1_G3_TX_DN<9>")
	)
	(segment
		(start 120.81637 -221.020386)
		(end 120.77065 -221.066106)
		(width 0.1143)
		(layer "In15.Cu")
		(net "GMI_CPU0_G1_CPU1_G3_TX_DN<9>")
	)
	(segment
		(start 120.957086 -228.589332)
		(end 120.987566 -228.607112)
		(width 0.1143)
		(layer "In15.Cu")
		(net "GMI_CPU0_G1_CPU1_G3_TX_DN<9>")
	)
	(segment
		(start 120.987566 -226.9871)
		(end 121.026682 -227.00996)
		(width 0.1143)
		(layer "In15.Cu")
		(net "GMI_CPU0_G1_CPU1_G3_TX_DN<9>")
	)
	(segment
		(start 120.987566 -225.367088)
		(end 121.026682 -225.389948)
		(width 0.1143)
		(layer "In15.Cu")
		(net "GMI_CPU0_G1_CPU1_G3_TX_DN<9>")
	)
	(segment
		(start 166.67734 -182.741316)
		(end 161.891218 -184.45734)
		(width 0.14224)
		(layer "In15.Cu")
		(net "GMI_CPU0_G1_CPU1_G3_TX_DN<9>")
	)
	(segment
		(start 349.061786 -222.270574)
		(end 349.06077 -222.270066)
		(width 0.1143)
		(layer "In15.Cu")
		(net "GMI_CPU0_G1_CPU1_G3_TX_DN<9>")
	)
	(segment
		(start 350.471232 -229.560374)
		(end 350.4692 -229.55885)
		(width 0.1143)
		(layer "In15.Cu")
		(net "GMI_CPU0_G1_CPU1_G3_TX_DN<9>")
	)
	(segment
		(start 350.508316 -228.606858)
		(end 350.538796 -228.589078)
		(width 0.1143)
		(layer "In15.Cu")
		(net "GMI_CPU0_G1_CPU1_G3_TX_DN<9>")
	)
	(segment
		(start 350.508316 -231.201722)
		(end 350.4692 -231.178862)
		(width 0.1143)
		(layer "In15.Cu")
		(net "GMI_CPU0_G1_CPU1_G3_TX_DN<9>")
	)
	(segment
		(start 350.508316 -236.706664)
		(end 350.538796 -236.688884)
		(width 0.1143)
		(layer "In15.Cu")
		(net "GMI_CPU0_G1_CPU1_G3_TX_DN<9>")
	)
	(segment
		(start 306.818538 -183.534812)
		(end 302.891952 -183.534812)
		(width 0.14224)
		(layer "In15.Cu")
		(net "GMI_CPU0_G1_CPU1_G3_TX_DN<9>")
	)
	(segment
		(start 120.987566 -243.186966)
		(end 121.026682 -243.209826)
		(width 0.1143)
		(layer "In15.Cu")
		(net "GMI_CPU0_G1_CPU1_G3_TX_DN<9>")
	)
	(segment
		(start 120.517666 -244.971824)
		(end 120.516904 -244.972332)
		(width 0.1143)
		(layer "In15.Cu")
		(net "GMI_CPU0_G1_CPU1_G3_TX_DN<9>")
	)
	(segment
		(start 349.568262 -223.746822)
		(end 349.598742 -223.729042)
		(width 0.1143)
		(layer "In15.Cu")
		(net "GMI_CPU0_G1_CPU1_G3_TX_DN<9>")
	)
	(segment
		(start 350.038162 -225.53168)
		(end 350.037146 -225.531172)
		(width 0.1143)
		(layer "In15.Cu")
		(net "GMI_CPU0_G1_CPU1_G3_TX_DN<9>")
	)
	(segment
		(start 350.4692 -238.349536)
		(end 350.508316 -238.326676)
		(width 0.1143)
		(layer "In15.Cu")
		(net "GMI_CPU0_G1_CPU1_G3_TX_DN<9>")
	)
	(segment
		(start 153.757884 -191.126618)
		(end 153.738834 -191.319658)
		(width 0.14224)
		(layer "In15.Cu")
		(net "GMI_CPU0_G1_CPU1_G3_TX_DN<9>")
	)
	(segment
		(start 350.538796 -242.559332)
		(end 350.508316 -242.541552)
		(width 0.1143)
		(layer "In15.Cu")
		(net "GMI_CPU0_G1_CPU1_G3_TX_DN<9>")
	)
	(segment
		(start 152.343358 -192.286636)
		(end 152.013412 -192.557146)
		(width 0.14224)
		(layer "In15.Cu")
		(net "GMI_CPU0_G1_CPU1_G3_TX_DN<9>")
	)
	(segment
		(start 351.559114 -246.104156)
		(end 351.628964 -246.034306)
		(width 0.1143)
		(layer "In15.Cu")
		(net "GMI_CPU0_G1_CPU1_G3_TX_DN<9>")
	)
	(segment
		(start 350.508316 -243.186712)
		(end 350.538796 -243.168932)
		(width 0.1143)
		(layer "In15.Cu")
		(net "GMI_CPU0_G1_CPU1_G3_TX_DN<9>")
	)
	(segment
		(start 120.81637 -219.620338)
		(end 120.81637 -220.991938)
		(width 0.14224)
		(layer "In15.Cu")
		(net "GMI_CPU0_G1_CPU1_G3_TX_DN<9>")
	)
	(segment
		(start 120.987566 -234.441746)
		(end 120.957086 -234.459526)
		(width 0.1143)
		(layer "In15.Cu")
		(net "GMI_CPU0_G1_CPU1_G3_TX_DN<9>")
	)
	(segment
		(start 120.81637 -220.991938)
		(end 120.81637 -221.020386)
		(width 0.1143)
		(layer "In15.Cu")
		(net "GMI_CPU0_G1_CPU1_G3_TX_DN<9>")
	)
	(segment
		(start 350.538796 -226.359466)
		(end 350.508316 -226.341686)
		(width 0.1143)
		(layer "In15.Cu")
		(net "GMI_CPU0_G1_CPU1_G3_TX_DN<9>")
	)
	(segment
		(start 348.815914 -221.418658)
		(end 348.784926 -221.38767)
		(width 0.1143)
		(layer "In15.Cu")
		(net "GMI_CPU0_G1_CPU1_G3_TX_DN<9>")
	)
	(segment
		(start 120.77065 -221.198948)
		(end 120.799352 -221.22765)
		(width 0.1143)
		(layer "In15.Cu")
		(net "GMI_CPU0_G1_CPU1_G3_TX_DN<9>")
	)
	(segment
		(start 120.987566 -240.921794)
		(end 120.957086 -240.939574)
		(width 0.1143)
		(layer "In15.Cu")
		(net "GMI_CPU0_G1_CPU1_G3_TX_DN<9>")
	)
	(segment
		(start 153.408634 -191.590422)
		(end 153.215594 -191.571372)
		(width 0.14224)
		(layer "In15.Cu")
		(net "GMI_CPU0_G1_CPU1_G3_TX_DN<9>")
	)
	(segment
		(start 350.538796 -244.179344)
		(end 350.508316 -244.161564)
		(width 0.1143)
		(layer "In15.Cu")
		(net "GMI_CPU0_G1_CPU1_G3_TX_DN<9>")
	)
	(segment
		(start 120.987566 -231.846882)
		(end 121.026682 -231.869742)
		(width 0.1143)
		(layer "In15.Cu")
		(net "GMI_CPU0_G1_CPU1_G3_TX_DN<9>")
	)
	(segment
		(start 156.025342 -189.44463)
		(end 155.832302 -189.42558)
		(width 0.14224)
		(layer "In15.Cu")
		(net "GMI_CPU0_G1_CPU1_G3_TX_DN<9>")
	)
	(segment
		(start 350.4692 -228.629718)
		(end 350.508316 -228.606858)
		(width 0.1143)
		(layer "In15.Cu")
		(net "GMI_CPU0_G1_CPU1_G3_TX_DN<9>")
	)
	(segment
		(start 350.508316 -227.961698)
		(end 350.4692 -227.938838)
		(width 0.1143)
		(layer "In15.Cu")
		(net "GMI_CPU0_G1_CPU1_G3_TX_DN<9>")
	)
	(segment
		(start 120.957086 -235.069126)
		(end 120.987566 -235.086906)
		(width 0.1143)
		(layer "In15.Cu")
		(net "GMI_CPU0_G1_CPU1_G3_TX_DN<9>")
	)
	(segment
		(start 350.538796 -239.319308)
		(end 350.508316 -239.301528)
		(width 0.1143)
		(layer "In15.Cu")
		(net "GMI_CPU0_G1_CPU1_G3_TX_DN<9>")
	)
	(segment
		(start 120.957086 -231.829102)
		(end 120.987566 -231.846882)
		(width 0.1143)
		(layer "In15.Cu")
		(net "GMI_CPU0_G1_CPU1_G3_TX_DN<9>")
	)
	(segment
		(start 156.704538 -188.710316)
		(end 156.374592 -188.980826)
		(width 0.14224)
		(layer "In15.Cu")
		(net "GMI_CPU0_G1_CPU1_G3_TX_DN<9>")
	)
	(segment
		(start 120.957086 -238.30915)
		(end 120.987566 -238.32693)
		(width 0.1143)
		(layer "In15.Cu")
		(net "GMI_CPU0_G1_CPU1_G3_TX_DN<9>")
	)
	(segment
		(start 120.957086 -243.169186)
		(end 120.987566 -243.186966)
		(width 0.1143)
		(layer "In15.Cu")
		(net "GMI_CPU0_G1_CPU1_G3_TX_DN<9>")
	)
	(segment
		(start 150.791926 -193.736214)
		(end 150.598886 -193.717164)
		(width 0.14224)
		(layer "In15.Cu")
		(net "GMI_CPU0_G1_CPU1_G3_TX_DN<9>")
	)
	(segment
		(start 348.784926 -221.38767)
		(end 348.784926 -221.128844)
		(width 0.1143)
		(layer "In15.Cu")
		(net "GMI_CPU0_G1_CPU1_G3_TX_DN<9>")
	)
	(segment
		(start 150.598886 -193.717164)
		(end 146.364452 -197.188836)
		(width 0.14224)
		(layer "In15.Cu")
		(net "GMI_CPU0_G1_CPU1_G3_TX_DN<9>")
	)
	(segment
		(start 121.026682 -239.278922)
		(end 120.987566 -239.301782)
		(width 0.1143)
		(layer "In15.Cu")
		(net "GMI_CPU0_G1_CPU1_G3_TX_DN<9>")
	)
	(segment
		(start 157.227778 -188.458602)
		(end 156.897578 -188.729366)
		(width 0.14224)
		(layer "In15.Cu")
		(net "GMI_CPU0_G1_CPU1_G3_TX_DN<9>")
	)
	(segment
		(start 144.995138 -197.603364)
		(end 123.266708 -215.41994)
		(width 0.14224)
		(layer "In15.Cu")
		(net "GMI_CPU0_G1_CPU1_G3_TX_DN<9>")
	)
	(segment
		(start 348.739206 -219.16009)
		(end 346.202762 -213.800182)
		(width 0.14224)
		(layer "In15.Cu")
		(net "GMI_CPU0_G1_CPU1_G3_TX_DN<9>")
	)
	(segment
		(start 348.784926 -221.128844)
		(end 348.739206 -221.083124)
		(width 0.1143)
		(layer "In15.Cu")
		(net "GMI_CPU0_G1_CPU1_G3_TX_DN<9>")
	)
	(segment
		(start 313.82716 -187.253372)
		(end 308.012084 -183.961532)
		(width 0.14224)
		(layer "In15.Cu")
		(net "GMI_CPU0_G1_CPU1_G3_TX_DN<9>")
	)
	(segment
		(start 350.508316 -241.5667)
		(end 350.538796 -241.54892)
		(width 0.1143)
		(layer "In15.Cu")
		(net "GMI_CPU0_G1_CPU1_G3_TX_DN<9>")
	)
	(segment
		(start 120.516904 -244.972332)
		(end 120.515634 -244.973094)
		(width 0.1143)
		(layer "In15.Cu")
		(net "GMI_CPU0_G1_CPU1_G3_TX_DN<9>")
	)
	(segment
		(start 154.61107 -190.604394)
		(end 154.28087 -190.875158)
		(width 0.14224)
		(layer "In15.Cu")
		(net "GMI_CPU0_G1_CPU1_G3_TX_DN<9>")
	)
	(segment
		(start 350.990662 -244.978682)
		(end 350.9391 -244.94871)
		(width 0.1143)
		(layer "In15.Cu")
		(net "GMI_CPU0_G1_CPU1_G3_TX_DN<9>")
	)
	(segment
		(start 350.4692 -227.009706)
		(end 350.508316 -226.986846)
		(width 0.1143)
		(layer "In15.Cu")
		(net "GMI_CPU0_G1_CPU1_G3_TX_DN<9>")
	)
	(segment
		(start 120.987566 -227.961952)
		(end 120.957086 -227.979732)
		(width 0.1143)
		(layer "In15.Cu")
		(net "GMI_CPU0_G1_CPU1_G3_TX_DN<9>")
	)
	(segment
		(start 121.026682 -236.038898)
		(end 120.987566 -236.061758)
		(width 0.1143)
		(layer "In15.Cu")
		(net "GMI_CPU0_G1_CPU1_G3_TX_DN<9>")
	)
	(segment
		(start 350.47174 -230.247952)
		(end 350.538796 -230.208836)
		(width 0.1143)
		(layer "In15.Cu")
		(net "GMI_CPU0_G1_CPU1_G3_TX_DN<9>")
	)
	(segment
		(start 154.08783 -190.856108)
		(end 153.757884 -191.126618)
		(width 0.14224)
		(layer "In15.Cu")
		(net "GMI_CPU0_G1_CPU1_G3_TX_DN<9>")
	)
	(segment
		(start 350.4692 -235.109512)
		(end 350.508316 -235.086652)
		(width 0.1143)
		(layer "In15.Cu")
		(net "GMI_CPU0_G1_CPU1_G3_TX_DN<9>")
	)
	(segment
		(start 154.28087 -190.875158)
		(end 154.08783 -190.856108)
		(width 0.14224)
		(layer "In15.Cu")
		(net "GMI_CPU0_G1_CPU1_G3_TX_DN<9>")
	)
	(segment
		(start 350.4692 -233.4895)
		(end 350.508316 -233.46664)
		(width 0.1143)
		(layer "In15.Cu")
		(net "GMI_CPU0_G1_CPU1_G3_TX_DN<9>")
	)
	(segment
		(start 151.994362 -192.750186)
		(end 151.664162 -193.02095)
		(width 0.14224)
		(layer "In15.Cu")
		(net "GMI_CPU0_G1_CPU1_G3_TX_DN<9>")
	)
	(segment
		(start 152.536398 -192.305686)
		(end 152.343358 -192.286636)
		(width 0.14224)
		(layer "In15.Cu")
		(net "GMI_CPU0_G1_CPU1_G3_TX_DN<9>")
	)
	(segment
		(start 156.374592 -188.980826)
		(end 156.355542 -189.173866)
		(width 0.14224)
		(layer "In15.Cu")
		(net "GMI_CPU0_G1_CPU1_G3_TX_DN<9>")
	)
	(segment
		(start 161.891218 -184.45734)
		(end 157.246828 -188.265562)
		(width 0.14224)
		(layer "In15.Cu")
		(net "GMI_CPU0_G1_CPU1_G3_TX_DN<9>")
	)
	(segment
		(start 120.987566 -224.721928)
		(end 120.957086 -224.739708)
		(width 0.1143)
		(layer "In15.Cu")
		(net "GMI_CPU0_G1_CPU1_G3_TX_DN<9>")
	)
	(segment
		(start 350.508316 -237.681516)
		(end 350.4692 -237.658656)
		(width 0.1143)
		(layer "In15.Cu")
		(net "GMI_CPU0_G1_CPU1_G3_TX_DN<9>")
	)
	(segment
		(start 350.4692 -236.729524)
		(end 350.508316 -236.706664)
		(width 0.1143)
		(layer "In15.Cu")
		(net "GMI_CPU0_G1_CPU1_G3_TX_DN<9>")
	)
	(segment
		(start 308.012084 -183.961532)
		(end 306.818538 -183.534812)
		(width 0.14224)
		(layer "In15.Cu")
		(net "GMI_CPU0_G1_CPU1_G3_TX_DN<9>")
	)
	(segment
		(start 120.987566 -237.68177)
		(end 120.957086 -237.69955)
		(width 0.1143)
		(layer "In15.Cu")
		(net "GMI_CPU0_G1_CPU1_G3_TX_DN<9>")
	)
	(segment
		(start 120.957086 -226.96932)
		(end 120.987566 -226.9871)
		(width 0.1143)
		(layer "In15.Cu")
		(net "GMI_CPU0_G1_CPU1_G3_TX_DN<9>")
	)
	(segment
		(start 350.508316 -226.986846)
		(end 350.538796 -226.969066)
		(width 0.1143)
		(layer "In15.Cu")
		(net "GMI_CPU0_G1_CPU1_G3_TX_DN<9>")
	)
	(segment
		(start 120.957086 -223.729296)
		(end 120.987566 -223.747076)
		(width 0.1143)
		(layer "In15.Cu")
		(net "GMI_CPU0_G1_CPU1_G3_TX_DN<9>")
	)
	(segment
		(start 350.508316 -242.541552)
		(end 350.4692 -242.518692)
		(width 0.1143)
		(layer "In15.Cu")
		(net "GMI_CPU0_G1_CPU1_G3_TX_DN<9>")
	)
	(segment
		(start 350.508316 -233.46664)
		(end 350.538796 -233.44886)
		(width 0.1143)
		(layer "In15.Cu")
		(net "GMI_CPU0_G1_CPU1_G3_TX_DN<9>")
	)
	(segment
		(start 121.026682 -244.138958)
		(end 120.987566 -244.161818)
		(width 0.1143)
		(layer "In15.Cu")
		(net "GMI_CPU0_G1_CPU1_G3_TX_DN<9>")
	)
	(segment
		(start 350.508316 -239.301528)
		(end 350.4692 -239.278668)
		(width 0.1143)
		(layer "In15.Cu")
		(net "GMI_CPU0_G1_CPU1_G3_TX_DN<9>")
	)
	(segment
		(start 350.508316 -244.161564)
		(end 350.4692 -244.138704)
		(width 0.1143)
		(layer "In15.Cu")
		(net "GMI_CPU0_G1_CPU1_G3_TX_DN<9>")
	)
	(segment
		(start 120.987566 -235.086906)
		(end 121.026682 -235.109766)
		(width 0.1143)
		(layer "In15.Cu")
		(net "GMI_CPU0_G1_CPU1_G3_TX_DN<9>")
	)
	(segment
		(start 350.4692 -239.969548)
		(end 350.508316 -239.946688)
		(width 0.1143)
		(layer "In15.Cu")
		(net "GMI_CPU0_G1_CPU1_G3_TX_DN<9>")
	)
	(segment
		(start 120.987566 -229.581964)
		(end 120.955054 -229.60076)
		(width 0.1143)
		(layer "In15.Cu")
		(net "GMI_CPU0_G1_CPU1_G3_TX_DN<9>")
	)
	(segment
		(start 350.040194 -225.53295)
		(end 350.038924 -225.532188)
		(width 0.1143)
		(layer "In15.Cu")
		(net "GMI_CPU0_G1_CPU1_G3_TX_DN<9>")
	)
	(segment
		(start 121.026682 -231.179116)
		(end 120.987566 -231.201976)
		(width 0.1143)
		(layer "In15.Cu")
		(net "GMI_CPU0_G1_CPU1_G3_TX_DN<9>")
	)
	(segment
		(start 120.515634 -244.973094)
		(end 120.485916 -244.990112)
		(width 0.1143)
		(layer "In15.Cu")
		(net "GMI_CPU0_G1_CPU1_G3_TX_DN<9>")
	)
	(segment
		(start 120.987566 -236.706918)
		(end 121.026682 -236.729778)
		(width 0.1143)
		(layer "In15.Cu")
		(net "GMI_CPU0_G1_CPU1_G3_TX_DN<9>")
	)
	(segment
		(start 350.508316 -236.061504)
		(end 350.4692 -236.038644)
		(width 0.1143)
		(layer "In15.Cu")
		(net "GMI_CPU0_G1_CPU1_G3_TX_DN<9>")
	)
	(segment
		(start 350.538796 -237.699296)
		(end 350.508316 -237.681516)
		(width 0.1143)
		(layer "In15.Cu")
		(net "GMI_CPU0_G1_CPU1_G3_TX_DN<9>")
	)
	(segment
		(start 153.215594 -191.571372)
		(end 152.885648 -191.841882)
		(width 0.14224)
		(layer "In15.Cu")
		(net "GMI_CPU0_G1_CPU1_G3_TX_DN<9>")
	)
	(segment
		(start 350.508316 -226.341686)
		(end 350.4692 -226.318826)
		(width 0.1143)
		(layer "In15.Cu")
		(net "GMI_CPU0_G1_CPU1_G3_TX_DN<9>")
	)
	(segment
		(start 350.540828 -229.600506)
		(end 350.508316 -229.58171)
		(width 0.1143)
		(layer "In15.Cu")
		(net "GMI_CPU0_G1_CPU1_G3_TX_DN<9>")
	)
	(segment
		(start 120.957086 -241.549174)
		(end 120.987566 -241.566954)
		(width 0.1143)
		(layer "In15.Cu")
		(net "GMI_CPU0_G1_CPU1_G3_TX_DN<9>")
	)
	(segment
		(start 350.038924 -225.532188)
		(end 350.038162 -225.53168)
		(width 0.1143)
		(layer "In15.Cu")
		(net "GMI_CPU0_G1_CPU1_G3_TX_DN<9>")
	)
	(segment
		(start 350.508316 -231.846628)
		(end 350.538796 -231.828848)
		(width 0.1143)
		(layer "In15.Cu")
		(net "GMI_CPU0_G1_CPU1_G3_TX_DN<9>")
	)
	(segment
		(start 119.866918 -246.03456)
		(end 119.936768 -246.10441)
		(width 0.1143)
		(layer "In15.Cu")
		(net "GMI_CPU0_G1_CPU1_G3_TX_DN<9>")
	)
	(segment
		(start 351.479866 -245.799864)
		(end 351.448116 -245.781576)
		(width 0.1143)
		(layer "In15.Cu")
		(net "GMI_CPU0_G1_CPU1_G3_TX_DN<9>")
	)
	(segment
		(start 121.026682 -227.939092)
		(end 120.987566 -227.961952)
		(width 0.1143)
		(layer "In15.Cu")
		(net "GMI_CPU0_G1_CPU1_G3_TX_DN<9>")
	)
	(segment
		(start 120.954546 -222.108014)
		(end 121.027698 -222.150686)
		(width 0.1143)
		(layer "In15.Cu")
		(net "GMI_CPU0_G1_CPU1_G3_TX_DN<9>")
	)
	(segment
		(start 120.987566 -244.161818)
		(end 120.957086 -244.179598)
		(width 0.1143)
		(layer "In15.Cu")
		(net "GMI_CPU0_G1_CPU1_G3_TX_DN<9>")
	)
	(segment
		(start 156.897578 -188.729366)
		(end 156.704538 -188.710316)
		(width 0.14224)
		(layer "In15.Cu")
		(net "GMI_CPU0_G1_CPU1_G3_TX_DN<9>")
	)
	(segment
		(start 349.568262 -223.101662)
		(end 349.529146 -223.078802)
		(width 0.1143)
		(layer "In15.Cu")
		(net "GMI_CPU0_G1_CPU1_G3_TX_DN<9>")
	)
	(segment
		(start 350.508316 -229.58171)
		(end 350.471232 -229.560374)
		(width 0.1143)
		(layer "In15.Cu")
		(net "GMI_CPU0_G1_CPU1_G3_TX_DN<9>")
	)
	(segment
		(start 155.832302 -189.42558)
		(end 155.502356 -189.69609)
		(width 0.14224)
		(layer "In15.Cu")
		(net "GMI_CPU0_G1_CPU1_G3_TX_DN<9>")
	)
	(segment
		(start 350.540828 -231.220518)
		(end 350.508316 -231.201722)
		(width 0.1143)
		(layer "In15.Cu")
		(net "GMI_CPU0_G1_CPU1_G3_TX_DN<9>")
	)
	(segment
		(start 350.508316 -235.086652)
		(end 350.538796 -235.068872)
		(width 0.1143)
		(layer "In15.Cu")
		(net "GMI_CPU0_G1_CPU1_G3_TX_DN<9>")
	)
	(segment
		(start 350.538796 -240.93932)
		(end 350.508316 -240.92154)
		(width 0.1143)
		(layer "In15.Cu")
		(net "GMI_CPU0_G1_CPU1_G3_TX_DN<9>")
	)
	(segment
		(start 151.141176 -193.27241)
		(end 151.122126 -193.46545)
		(width 0.14224)
		(layer "In15.Cu")
		(net "GMI_CPU0_G1_CPU1_G3_TX_DN<9>")
	)
	(segment
		(start 120.987566 -223.101916)
		(end 120.957086 -223.119696)
		(width 0.1143)
		(layer "In15.Cu")
		(net "GMI_CPU0_G1_CPU1_G3_TX_DN<9>")
	)
	(segment
		(start 349.568262 -224.721674)
		(end 349.529146 -224.698814)
		(width 0.1143)
		(layer "In15.Cu")
		(net "GMI_CPU0_G1_CPU1_G3_TX_DN<9>")
	)
	(segment
		(start 152.013412 -192.557146)
		(end 151.994362 -192.750186)
		(width 0.14224)
		(layer "In15.Cu")
		(net "GMI_CPU0_G1_CPU1_G3_TX_DN<9>")
	)
	(segment
		(start 350.538796 -227.979478)
		(end 350.508316 -227.961698)
		(width 0.1143)
		(layer "In15.Cu")
		(net "GMI_CPU0_G1_CPU1_G3_TX_DN<9>")
	)
	(segment
		(start 120.799352 -221.22765)
		(end 120.799352 -221.804484)
		(width 0.1143)
		(layer "In15.Cu")
		(net "GMI_CPU0_G1_CPU1_G3_TX_DN<9>")
	)
	(segment
		(start 120.987566 -238.32693)
		(end 121.026682 -238.34979)
		(width 0.1143)
		(layer "In15.Cu")
		(net "GMI_CPU0_G1_CPU1_G3_TX_DN<9>")
	)
	(segment
		(start 154.63012 -190.411354)
		(end 154.61107 -190.604394)
		(width 0.14224)
		(layer "In15.Cu")
		(net "GMI_CPU0_G1_CPU1_G3_TX_DN<9>")
	)
	(segment
		(start 121.026682 -237.65891)
		(end 120.987566 -237.68177)
		(width 0.1143)
		(layer "In15.Cu")
		(net "GMI_CPU0_G1_CPU1_G3_TX_DN<9>")
	)
	(segment
		(start 120.987566 -228.607112)
		(end 121.026682 -228.629972)
		(width 0.1143)
		(layer "In15.Cu")
		(net "GMI_CPU0_G1_CPU1_G3_TX_DN<9>")
	)
	(segment
		(start 156.355542 -189.173866)
		(end 156.025342 -189.44463)
		(width 0.14224)
		(layer "In15.Cu")
		(net "GMI_CPU0_G1_CPU1_G3_TX_DN<9>")
	)
	(segment
		(start 349.598742 -224.739454)
		(end 349.568262 -224.721674)
		(width 0.1143)
		(layer "In15.Cu")
		(net "GMI_CPU0_G1_CPU1_G3_TX_DN<9>")
	)
	(segment
		(start 151.471122 -193.0019)
		(end 151.141176 -193.27241)
		(width 0.14224)
		(layer "In15.Cu")
		(net "GMI_CPU0_G1_CPU1_G3_TX_DN<9>")
	)
	(segment
		(start 120.957086 -236.689138)
		(end 120.987566 -236.706918)
		(width 0.1143)
		(layer "In15.Cu")
		(net "GMI_CPU0_G1_CPU1_G3_TX_DN<9>")
	)
	(segment
		(start 349.598742 -223.119442)
		(end 349.568262 -223.101662)
		(width 0.1143)
		(layer "In15.Cu")
		(net "GMI_CPU0_G1_CPU1_G3_TX_DN<9>")
	)
	(segment
		(start 155.483306 -189.88913)
		(end 155.153106 -190.159894)
		(width 0.14224)
		(layer "In15.Cu")
		(net "GMI_CPU0_G1_CPU1_G3_TX_DN<9>")
	)
	(segment
		(start 120.987566 -242.541806)
		(end 120.957086 -242.559586)
		(width 0.1143)
		(layer "In15.Cu")
		(net "GMI_CPU0_G1_CPU1_G3_TX_DN<9>")
	)
	(segment
		(start 151.122126 -193.46545)
		(end 150.791926 -193.736214)
		(width 0.14224)
		(layer "In15.Cu")
		(net "GMI_CPU0_G1_CPU1_G3_TX_DN<9>")
	)
	(segment
		(start 350.508316 -239.946688)
		(end 350.538796 -239.928908)
		(width 0.1143)
		(layer "In15.Cu")
		(net "GMI_CPU0_G1_CPU1_G3_TX_DN<9>")
	)
	(segment
		(start 350.538796 -234.459272)
		(end 350.508316 -234.441492)
		(width 0.1143)
		(layer "In15.Cu")
		(net "GMI_CPU0_G1_CPU1_G3_TX_DN<9>")
	)
	(segment
		(start 350.508316 -232.82148)
		(end 350.4692 -232.79862)
		(width 0.1143)
		(layer "In15.Cu")
		(net "GMI_CPU0_G1_CPU1_G3_TX_DN<9>")
	)
	(segment
		(start 350.4692 -241.58956)
		(end 350.508316 -241.5667)
		(width 0.1143)
		(layer "In15.Cu")
		(net "GMI_CPU0_G1_CPU1_G3_TX_DN<9>")
	)
	(segment
		(start 350.037146 -225.531172)
		(end 350.034606 -225.529648)
		(width 0.1143)
		(layer "In15.Cu")
		(net "GMI_CPU0_G1_CPU1_G3_TX_DN<9>")
	)
	(segment
		(start 153.738834 -191.319658)
		(end 153.408634 -191.590422)
		(width 0.14224)
		(layer "In15.Cu")
		(net "GMI_CPU0_G1_CPU1_G3_TX_DN<9>")
	)
	(segment
		(start 350.033844 -225.52914)
		(end 350.006666 -225.513392)
		(width 0.1143)
		(layer "In15.Cu")
		(net "GMI_CPU0_G1_CPU1_G3_TX_DN<9>")
	)
	(segment
		(start 350.508316 -238.326676)
		(end 350.538796 -238.308896)
		(width 0.1143)
		(layer "In15.Cu")
		(net "GMI_CPU0_G1_CPU1_G3_TX_DN<9>")
	)
	(segment
		(start 121.026682 -232.798874)
		(end 120.987566 -232.821734)
		(width 0.1143)
		(layer "In15.Cu")
		(net "GMI_CPU0_G1_CPU1_G3_TX_DN<9>")
	)
	(segment
		(start 121.026682 -226.31908)
		(end 120.987566 -226.34194)
		(width 0.1143)
		(layer "In15.Cu")
		(net "GMI_CPU0_G1_CPU1_G3_TX_DN<9>")
	)
	(segment
		(start 120.957086 -239.929162)
		(end 120.987566 -239.946942)
		(width 0.1143)
		(layer "In15.Cu")
		(net "GMI_CPU0_G1_CPU1_G3_TX_DN<9>")
	)
	(segment
		(start 120.957086 -230.20909)
		(end 121.024142 -230.248206)
		(width 0.1143)
		(layer "In15.Cu")
		(net "GMI_CPU0_G1_CPU1_G3_TX_DN<9>")
	)
	(segment
		(start 151.664162 -193.02095)
		(end 151.471122 -193.0019)
		(width 0.14224)
		(layer "In15.Cu")
		(net "GMI_CPU0_G1_CPU1_G3_TX_DN<9>")
	)
	(segment
		(start 152.885648 -191.841882)
		(end 152.866598 -192.034922)
		(width 0.14224)
		(layer "In15.Cu")
		(net "GMI_CPU0_G1_CPU1_G3_TX_DN<9>")
	)
	(segment
		(start 349.06077 -222.270066)
		(end 349.059754 -222.269304)
		(width 0.1143)
		(layer "In15.Cu")
		(net "GMI_CPU0_G1_CPU1_G3_TX_DN<9>")
	)
	(segment
		(start 120.957086 -233.449114)
		(end 120.987566 -233.466894)
		(width 0.1143)
		(layer "In15.Cu")
		(net "GMI_CPU0_G1_CPU1_G3_TX_DN<9>")
	)
	(segment
		(start 123.266708 -215.41994)
		(end 120.81637 -219.620338)
		(width 0.14224)
		(layer "In15.Cu")
		(net "GMI_CPU0_G1_CPU1_G3_TX_DN<9>")
	)
	(segment
		(start 350.034606 -225.529648)
		(end 350.033844 -225.52914)
		(width 0.1143)
		(layer "In15.Cu")
		(net "GMI_CPU0_G1_CPU1_G3_TX_DN<9>")
	)
	(segment
		(start 350.508316 -240.92154)
		(end 350.4692 -240.89868)
		(width 0.1143)
		(layer "In15.Cu")
		(net "GMI_CPU0_G1_CPU1_G3_TX_DN<9>")
	)
	(segment
		(start 120.987566 -239.946942)
		(end 121.026682 -239.969802)
		(width 0.1143)
		(layer "In15.Cu")
		(net "GMI_CPU0_G1_CPU1_G3_TX_DN<9>")
	)
	(arc
		(start 351.448116 -245.781576)
		(mid 351.250634 -245.583447)
		(end 351.178368 -245.3132)
		(width 0.1143)
		(layer "In15.Cu")
		(net "GMI_CPU0_G1_CPU1_G3_TX_DN<9>")
	)
	(arc
		(start 121.270014 -230.71455)
		(mid 121.205499 -230.976769)
		(end 121.026682 -231.179116)
		(width 0.1143)
		(layer "In15.Cu")
		(net "GMI_CPU0_G1_CPU1_G3_TX_DN<9>")
	)
	(arc
		(start 350.538796 -236.688884)
		(mid 350.695773 -236.384084)
		(end 350.538796 -236.079284)
		(width 0.1143)
		(layer "In15.Cu")
		(net "GMI_CPU0_G1_CPU1_G3_TX_DN<9>")
	)
	(arc
		(start 120.017032 -245.79961)
		(mid 119.919267 -245.902586)
		(end 119.866918 -246.03456)
		(width 0.1143)
		(layer "In15.Cu")
		(net "GMI_CPU0_G1_CPU1_G3_TX_DN<9>")
	)
	(arc
		(start 349.285814 -222.614236)
		(mid 349.244559 -222.443265)
		(end 349.129858 -222.309944)
		(width 0.1143)
		(layer "In15.Cu")
		(net "GMI_CPU0_G1_CPU1_G3_TX_DN<9>")
	)
	(arc
		(start 350.4692 -236.038644)
		(mid 350.225873 -235.574078)
		(end 350.4692 -235.109512)
		(width 0.1143)
		(layer "In15.Cu")
		(net "GMI_CPU0_G1_CPU1_G3_TX_DN<9>")
	)
	(arc
		(start 349.999046 -225.50882)
		(mid 349.820233 -225.30647)
		(end 349.755714 -225.044254)
		(width 0.1143)
		(layer "In15.Cu")
		(net "GMI_CPU0_G1_CPU1_G3_TX_DN<9>")
	)
	(arc
		(start 120.957086 -237.69955)
		(mid 120.800109 -238.00435)
		(end 120.957086 -238.30915)
		(width 0.1143)
		(layer "In15.Cu")
		(net "GMI_CPU0_G1_CPU1_G3_TX_DN<9>")
	)
	(arc
		(start 350.538796 -235.068872)
		(mid 350.695773 -234.764072)
		(end 350.538796 -234.459272)
		(width 0.1143)
		(layer "In15.Cu")
		(net "GMI_CPU0_G1_CPU1_G3_TX_DN<9>")
	)
	(arc
		(start 120.957086 -234.459526)
		(mid 120.800109 -234.764326)
		(end 120.957086 -235.069126)
		(width 0.1143)
		(layer "In15.Cu")
		(net "GMI_CPU0_G1_CPU1_G3_TX_DN<9>")
	)
	(arc
		(start 121.026682 -243.209826)
		(mid 121.270009 -243.674392)
		(end 121.026682 -244.138958)
		(width 0.1143)
		(layer "In15.Cu")
		(net "GMI_CPU0_G1_CPU1_G3_TX_DN<9>")
	)
	(arc
		(start 120.957086 -244.179598)
		(mid 120.841659 -244.312974)
		(end 120.800114 -244.484398)
		(width 0.1143)
		(layer "In15.Cu")
		(net "GMI_CPU0_G1_CPU1_G3_TX_DN<9>")
	)
	(arc
		(start 350.538796 -226.969066)
		(mid 350.695773 -226.664266)
		(end 350.538796 -226.359466)
		(width 0.1143)
		(layer "In15.Cu")
		(net "GMI_CPU0_G1_CPU1_G3_TX_DN<9>")
	)
	(arc
		(start 121.026682 -223.769936)
		(mid 121.270009 -224.234502)
		(end 121.026682 -224.699068)
		(width 0.1143)
		(layer "In15.Cu")
		(net "GMI_CPU0_G1_CPU1_G3_TX_DN<9>")
	)
	(arc
		(start 350.538796 -241.54892)
		(mid 350.695773 -241.24412)
		(end 350.538796 -240.93932)
		(width 0.1143)
		(layer "In15.Cu")
		(net "GMI_CPU0_G1_CPU1_G3_TX_DN<9>")
	)
	(arc
		(start 349.755714 -225.044254)
		(mid 349.714165 -224.872832)
		(end 349.598742 -224.739454)
		(width 0.1143)
		(layer "In15.Cu")
		(net "GMI_CPU0_G1_CPU1_G3_TX_DN<9>")
	)
	(arc
		(start 350.4692 -234.418632)
		(mid 350.225873 -233.954066)
		(end 350.4692 -233.4895)
		(width 0.1143)
		(layer "In15.Cu")
		(net "GMI_CPU0_G1_CPU1_G3_TX_DN<9>")
	)
	(arc
		(start 120.955054 -231.220772)
		(mid 120.841125 -231.353919)
		(end 120.800114 -231.524302)
		(width 0.1143)
		(layer "In15.Cu")
		(net "GMI_CPU0_G1_CPU1_G3_TX_DN<9>")
	)
	(arc
		(start 121.026682 -227.00996)
		(mid 121.270009 -227.474526)
		(end 121.026682 -227.939092)
		(width 0.1143)
		(layer "In15.Cu")
		(net "GMI_CPU0_G1_CPU1_G3_TX_DN<9>")
	)
	(arc
		(start 121.270014 -222.61449)
		(mid 121.205499 -222.876709)
		(end 121.026682 -223.079056)
		(width 0.1143)
		(layer "In15.Cu")
		(net "GMI_CPU0_G1_CPU1_G3_TX_DN<9>")
	)
	(arc
		(start 350.4692 -232.79862)
		(mid 350.225873 -232.334054)
		(end 350.4692 -231.869488)
		(width 0.1143)
		(layer "In15.Cu")
		(net "GMI_CPU0_G1_CPU1_G3_TX_DN<9>")
	)
	(arc
		(start 121.027698 -222.150686)
		(mid 121.205763 -222.352863)
		(end 121.270014 -222.61449)
		(width 0.1143)
		(layer "In15.Cu")
		(net "GMI_CPU0_G1_CPU1_G3_TX_DN<9>")
	)
	(arc
		(start 350.4692 -227.938838)
		(mid 350.225873 -227.474272)
		(end 350.4692 -227.009706)
		(width 0.1143)
		(layer "In15.Cu")
		(net "GMI_CPU0_G1_CPU1_G3_TX_DN<9>")
	)
	(arc
		(start 349.598742 -223.729042)
		(mid 349.755719 -223.424242)
		(end 349.598742 -223.119442)
		(width 0.1143)
		(layer "In15.Cu")
		(net "GMI_CPU0_G1_CPU1_G3_TX_DN<9>")
	)
	(arc
		(start 349.529146 -223.078802)
		(mid 349.350333 -222.876452)
		(end 349.285814 -222.614236)
		(width 0.1143)
		(layer "In15.Cu")
		(net "GMI_CPU0_G1_CPU1_G3_TX_DN<9>")
	)
	(arc
		(start 351.178368 -245.303548)
		(mid 351.128062 -245.11596)
		(end 350.990662 -244.978682)
		(width 0.1143)
		(layer "In15.Cu")
		(net "GMI_CPU0_G1_CPU1_G3_TX_DN<9>")
	)
	(arc
		(start 350.4692 -226.318826)
		(mid 350.290387 -226.116476)
		(end 350.225868 -225.85426)
		(width 0.1143)
		(layer "In15.Cu")
		(net "GMI_CPU0_G1_CPU1_G3_TX_DN<9>")
	)
	(arc
		(start 349.059754 -222.269304)
		(mid 348.880561 -222.066794)
		(end 348.815914 -221.80423)
		(width 0.1143)
		(layer "In15.Cu")
		(net "GMI_CPU0_G1_CPU1_G3_TX_DN<9>")
	)
	(arc
		(start 350.9391 -244.94871)
		(mid 350.760287 -244.74636)
		(end 350.695768 -244.484144)
		(width 0.1143)
		(layer "In15.Cu")
		(net "GMI_CPU0_G1_CPU1_G3_TX_DN<9>")
	)
	(arc
		(start 120.32996 -245.294404)
		(mid 120.265445 -245.556623)
		(end 120.086628 -245.75897)
		(width 0.1143)
		(layer "In15.Cu")
		(net "GMI_CPU0_G1_CPU1_G3_TX_DN<9>")
	)
	(arc
		(start 121.026682 -239.969802)
		(mid 121.270009 -240.434368)
		(end 121.026682 -240.898934)
		(width 0.1143)
		(layer "In15.Cu")
		(net "GMI_CPU0_G1_CPU1_G3_TX_DN<9>")
	)
	(arc
		(start 350.538796 -238.308896)
		(mid 350.695773 -238.004096)
		(end 350.538796 -237.699296)
		(width 0.1143)
		(layer "In15.Cu")
		(net "GMI_CPU0_G1_CPU1_G3_TX_DN<9>")
	)
	(arc
		(start 349.529146 -224.698814)
		(mid 349.285819 -224.234248)
		(end 349.529146 -223.769682)
		(width 0.1143)
		(layer "In15.Cu")
		(net "GMI_CPU0_G1_CPU1_G3_TX_DN<9>")
	)
	(arc
		(start 120.957086 -224.739708)
		(mid 120.800109 -225.044508)
		(end 120.957086 -225.349308)
		(width 0.1143)
		(layer "In15.Cu")
		(net "GMI_CPU0_G1_CPU1_G3_TX_DN<9>")
	)
	(arc
		(start 120.800114 -229.90429)
		(mid 120.841663 -230.075712)
		(end 120.957086 -230.20909)
		(width 0.1143)
		(layer "In15.Cu")
		(net "GMI_CPU0_G1_CPU1_G3_TX_DN<9>")
	)
	(arc
		(start 121.026682 -235.109766)
		(mid 121.270009 -235.574332)
		(end 121.026682 -236.038898)
		(width 0.1143)
		(layer "In15.Cu")
		(net "GMI_CPU0_G1_CPU1_G3_TX_DN<9>")
	)
	(arc
		(start 350.225868 -230.714296)
		(mid 350.291104 -230.450705)
		(end 350.47174 -230.247952)
		(width 0.1143)
		(layer "In15.Cu")
		(net "GMI_CPU0_G1_CPU1_G3_TX_DN<9>")
	)
	(arc
		(start 120.957086 -242.559586)
		(mid 120.800109 -242.864386)
		(end 120.957086 -243.169186)
		(width 0.1143)
		(layer "In15.Cu")
		(net "GMI_CPU0_G1_CPU1_G3_TX_DN<9>")
	)
	(arc
		(start 120.957086 -236.079538)
		(mid 120.800109 -236.384338)
		(end 120.957086 -236.689138)
		(width 0.1143)
		(layer "In15.Cu")
		(net "GMI_CPU0_G1_CPU1_G3_TX_DN<9>")
	)
	(arc
		(start 351.628964 -246.034306)
		(mid 351.576915 -245.902787)
		(end 351.479866 -245.799864)
		(width 0.1143)
		(layer "In15.Cu")
		(net "GMI_CPU0_G1_CPU1_G3_TX_DN<9>")
	)
	(arc
		(start 350.4692 -240.89868)
		(mid 350.225873 -240.434114)
		(end 350.4692 -239.969548)
		(width 0.1143)
		(layer "In15.Cu")
		(net "GMI_CPU0_G1_CPU1_G3_TX_DN<9>")
	)
	(arc
		(start 120.955054 -229.60076)
		(mid 120.841125 -229.733907)
		(end 120.800114 -229.90429)
		(width 0.1143)
		(layer "In15.Cu")
		(net "GMI_CPU0_G1_CPU1_G3_TX_DN<9>")
	)
	(arc
		(start 120.957086 -239.319562)
		(mid 120.800109 -239.624362)
		(end 120.957086 -239.929162)
		(width 0.1143)
		(layer "In15.Cu")
		(net "GMI_CPU0_G1_CPU1_G3_TX_DN<9>")
	)
	(arc
		(start 121.024142 -230.248206)
		(mid 121.204794 -230.450951)
		(end 121.270014 -230.71455)
		(width 0.1143)
		(layer "In15.Cu")
		(net "GMI_CPU0_G1_CPU1_G3_TX_DN<9>")
	)
	(arc
		(start 350.4692 -237.658656)
		(mid 350.225873 -237.19409)
		(end 350.4692 -236.729524)
		(width 0.1143)
		(layer "In15.Cu")
		(net "GMI_CPU0_G1_CPU1_G3_TX_DN<9>")
	)
	(arc
		(start 120.799352 -221.804484)
		(mid 120.840402 -221.974934)
		(end 120.954546 -222.108014)
		(width 0.1143)
		(layer "In15.Cu")
		(net "GMI_CPU0_G1_CPU1_G3_TX_DN<9>")
	)
	(arc
		(start 350.695768 -244.484144)
		(mid 350.654219 -244.312722)
		(end 350.538796 -244.179344)
		(width 0.1143)
		(layer "In15.Cu")
		(net "GMI_CPU0_G1_CPU1_G3_TX_DN<9>")
	)
	(arc
		(start 121.026682 -236.729778)
		(mid 121.270009 -237.194344)
		(end 121.026682 -237.65891)
		(width 0.1143)
		(layer "In15.Cu")
		(net "GMI_CPU0_G1_CPU1_G3_TX_DN<9>")
	)
	(arc
		(start 350.538796 -233.44886)
		(mid 350.695773 -233.14406)
		(end 350.538796 -232.83926)
		(width 0.1143)
		(layer "In15.Cu")
		(net "GMI_CPU0_G1_CPU1_G3_TX_DN<9>")
	)
	(arc
		(start 120.957086 -240.939574)
		(mid 120.800109 -241.244374)
		(end 120.957086 -241.549174)
		(width 0.1143)
		(layer "In15.Cu")
		(net "GMI_CPU0_G1_CPU1_G3_TX_DN<9>")
	)
	(arc
		(start 121.026682 -228.629972)
		(mid 121.270009 -229.094538)
		(end 121.026682 -229.559104)
		(width 0.1143)
		(layer "In15.Cu")
		(net "GMI_CPU0_G1_CPU1_G3_TX_DN<9>")
	)
	(arc
		(start 350.4692 -242.518692)
		(mid 350.225873 -242.054126)
		(end 350.4692 -241.58956)
		(width 0.1143)
		(layer "In15.Cu")
		(net "GMI_CPU0_G1_CPU1_G3_TX_DN<9>")
	)
	(arc
		(start 121.026682 -238.34979)
		(mid 121.270009 -238.814356)
		(end 121.026682 -239.278922)
		(width 0.1143)
		(layer "In15.Cu")
		(net "GMI_CPU0_G1_CPU1_G3_TX_DN<9>")
	)
	(arc
		(start 350.4692 -239.278668)
		(mid 350.225873 -238.814102)
		(end 350.4692 -238.349536)
		(width 0.1143)
		(layer "In15.Cu")
		(net "GMI_CPU0_G1_CPU1_G3_TX_DN<9>")
	)
	(arc
		(start 350.4692 -244.138704)
		(mid 350.225873 -243.674138)
		(end 350.4692 -243.209572)
		(width 0.1143)
		(layer "In15.Cu")
		(net "GMI_CPU0_G1_CPU1_G3_TX_DN<9>")
	)
	(arc
		(start 120.800114 -231.524302)
		(mid 120.841663 -231.695724)
		(end 120.957086 -231.829102)
		(width 0.1143)
		(layer "In15.Cu")
		(net "GMI_CPU0_G1_CPU1_G3_TX_DN<9>")
	)
	(arc
		(start 120.957086 -226.35972)
		(mid 120.800109 -226.66452)
		(end 120.957086 -226.96932)
		(width 0.1143)
		(layer "In15.Cu")
		(net "GMI_CPU0_G1_CPU1_G3_TX_DN<9>")
	)
	(arc
		(start 350.538796 -231.828848)
		(mid 350.654223 -231.695472)
		(end 350.695768 -231.524048)
		(width 0.1143)
		(layer "In15.Cu")
		(net "GMI_CPU0_G1_CPU1_G3_TX_DN<9>")
	)
	(arc
		(start 350.538796 -243.168932)
		(mid 350.695773 -242.864132)
		(end 350.538796 -242.559332)
		(width 0.1143)
		(layer "In15.Cu")
		(net "GMI_CPU0_G1_CPU1_G3_TX_DN<9>")
	)
	(arc
		(start 350.538796 -230.208836)
		(mid 350.654223 -230.07546)
		(end 350.695768 -229.904036)
		(width 0.1143)
		(layer "In15.Cu")
		(net "GMI_CPU0_G1_CPU1_G3_TX_DN<9>")
	)
	(arc
		(start 350.695768 -231.524048)
		(mid 350.654802 -231.353642)
		(end 350.540828 -231.220518)
		(width 0.1143)
		(layer "In15.Cu")
		(net "GMI_CPU0_G1_CPU1_G3_TX_DN<9>")
	)
	(arc
		(start 120.957086 -227.979732)
		(mid 120.800109 -228.284532)
		(end 120.957086 -228.589332)
		(width 0.1143)
		(layer "In15.Cu")
		(net "GMI_CPU0_G1_CPU1_G3_TX_DN<9>")
	)
	(arc
		(start 350.4692 -229.55885)
		(mid 350.225873 -229.094284)
		(end 350.4692 -228.629718)
		(width 0.1143)
		(layer "In15.Cu")
		(net "GMI_CPU0_G1_CPU1_G3_TX_DN<9>")
	)
	(arc
		(start 350.695768 -229.904036)
		(mid 350.654802 -229.73363)
		(end 350.540828 -229.600506)
		(width 0.1143)
		(layer "In15.Cu")
		(net "GMI_CPU0_G1_CPU1_G3_TX_DN<9>")
	)
	(arc
		(start 121.026682 -241.589814)
		(mid 121.270009 -242.05438)
		(end 121.026682 -242.518946)
		(width 0.1143)
		(layer "In15.Cu")
		(net "GMI_CPU0_G1_CPU1_G3_TX_DN<9>")
	)
	(arc
		(start 350.538796 -239.928908)
		(mid 350.695773 -239.624108)
		(end 350.538796 -239.319308)
		(width 0.1143)
		(layer "In15.Cu")
		(net "GMI_CPU0_G1_CPU1_G3_TX_DN<9>")
	)
	(arc
		(start 121.026682 -231.869742)
		(mid 121.270009 -232.334308)
		(end 121.026682 -232.798874)
		(width 0.1143)
		(layer "In15.Cu")
		(net "GMI_CPU0_G1_CPU1_G3_TX_DN<9>")
	)
	(arc
		(start 350.4692 -231.178862)
		(mid 350.290387 -230.976512)
		(end 350.225868 -230.714296)
		(width 0.1143)
		(layer "In15.Cu")
		(net "GMI_CPU0_G1_CPU1_G3_TX_DN<9>")
	)
	(arc
		(start 350.538796 -228.589078)
		(mid 350.695773 -228.284278)
		(end 350.538796 -227.979478)
		(width 0.1143)
		(layer "In15.Cu")
		(net "GMI_CPU0_G1_CPU1_G3_TX_DN<9>")
	)
	(arc
		(start 120.800114 -244.484398)
		(mid 120.735599 -244.746617)
		(end 120.556782 -244.948964)
		(width 0.1143)
		(layer "In15.Cu")
		(net "GMI_CPU0_G1_CPU1_G3_TX_DN<9>")
	)
	(arc
		(start 120.957086 -223.119696)
		(mid 120.800109 -223.424496)
		(end 120.957086 -223.729296)
		(width 0.1143)
		(layer "In15.Cu")
		(net "GMI_CPU0_G1_CPU1_G3_TX_DN<9>")
	)
	(arc
		(start 121.026682 -225.389948)
		(mid 121.270009 -225.854514)
		(end 121.026682 -226.31908)
		(width 0.1143)
		(layer "In15.Cu")
		(net "GMI_CPU0_G1_CPU1_G3_TX_DN<9>")
	)
	(arc
		(start 120.957086 -232.839514)
		(mid 120.800109 -233.144314)
		(end 120.957086 -233.449114)
		(width 0.1143)
		(layer "In15.Cu")
		(net "GMI_CPU0_G1_CPU1_G3_TX_DN<9>")
	)
	(arc
		(start 120.485916 -244.990112)
		(mid 120.37124 -245.123446)
		(end 120.32996 -245.294404)
		(width 0.1143)
		(layer "In15.Cu")
		(net "GMI_CPU0_G1_CPU1_G3_TX_DN<9>")
	)
	(arc
		(start 350.225868 -225.85426)
		(mid 350.184613 -225.683289)
		(end 350.069912 -225.549968)
		(width 0.1143)
		(layer "In15.Cu")
		(net "GMI_CPU0_G1_CPU1_G3_TX_DN<9>")
	)
	(arc
		(start 121.026682 -233.489754)
		(mid 121.270009 -233.95432)
		(end 121.026682 -234.418886)
		(width 0.1143)
		(layer "In15.Cu")
		(net "GMI_CPU0_G1_CPU1_G3_TX_DN<9>")
	)
	(segment
		(start 119.767858 -244.750336)
		(end 120.23471 -244.484398)
		(width 0.12954)
		(layer "F.Cu")
		(net "GMI_CPU0_G1_CPU1_G3_TX_DN<8>")
	)
	(segment
		(start 351.728024 -244.750082)
		(end 351.261172 -244.484144)
		(width 0.12954)
		(layer "F.Cu")
		(net "GMI_CPU0_G1_CPU1_G3_TX_DN<8>")
	)
	(segment
		(start 351.448878 -239.302036)
		(end 351.448116 -239.301528)
		(width 0.1143)
		(layer "In15.Cu")
		(net "GMI_CPU0_G1_CPU1_G3_TX_DN<8>")
	)
	(segment
		(start 119.82577 -221.066106)
		(end 119.82577 -221.198948)
		(width 0.1143)
		(layer "In15.Cu")
		(net "GMI_CPU0_G1_CPU1_G3_TX_DN<8>")
	)
	(segment
		(start 120.047512 -237.68177)
		(end 120.017032 -237.69955)
		(width 0.1143)
		(layer "In15.Cu")
		(net "GMI_CPU0_G1_CPU1_G3_TX_DN<8>")
	)
	(segment
		(start 351.479866 -244.179852)
		(end 351.448878 -244.162072)
		(width 0.1143)
		(layer "In15.Cu")
		(net "GMI_CPU0_G1_CPU1_G3_TX_DN<8>")
	)
	(segment
		(start 351.469198 -241.554508)
		(end 351.46996 -241.554)
		(width 0.1143)
		(layer "In15.Cu")
		(net "GMI_CPU0_G1_CPU1_G3_TX_DN<8>")
	)
	(segment
		(start 120.047512 -240.921794)
		(end 120.017032 -240.939574)
		(width 0.1143)
		(layer "In15.Cu")
		(net "GMI_CPU0_G1_CPU1_G3_TX_DN<8>")
	)
	(segment
		(start 350.032066 -222.2881)
		(end 350.02978 -222.28683)
		(width 0.1143)
		(layer "In15.Cu")
		(net "GMI_CPU0_G1_CPU1_G3_TX_DN<8>")
	)
	(segment
		(start 120.017032 -236.689138)
		(end 120.047512 -236.706918)
		(width 0.1143)
		(layer "In15.Cu")
		(net "GMI_CPU0_G1_CPU1_G3_TX_DN<8>")
	)
	(segment
		(start 350.034606 -222.289624)
		(end 350.033082 -222.288608)
		(width 0.1143)
		(layer "In15.Cu")
		(net "GMI_CPU0_G1_CPU1_G3_TX_DN<8>")
	)
	(segment
		(start 351.448116 -230.226616)
		(end 351.479866 -230.208328)
		(width 0.1143)
		(layer "In15.Cu")
		(net "GMI_CPU0_G1_CPU1_G3_TX_DN<8>")
	)
	(segment
		(start 351.450656 -237.68304)
		(end 351.449894 -237.682532)
		(width 0.1143)
		(layer "In15.Cu")
		(net "GMI_CPU0_G1_CPU1_G3_TX_DN<8>")
	)
	(segment
		(start 351.479866 -240.939828)
		(end 351.455482 -240.925858)
		(width 0.1143)
		(layer "In15.Cu")
		(net "GMI_CPU0_G1_CPU1_G3_TX_DN<8>")
	)
	(segment
		(start 351.448116 -236.061504)
		(end 351.447862 -236.061504)
		(width 0.1143)
		(layer "In15.Cu")
		(net "GMI_CPU0_G1_CPU1_G3_TX_DN<8>")
	)
	(segment
		(start 120.086628 -239.278922)
		(end 120.047512 -239.301782)
		(width 0.1143)
		(layer "In15.Cu")
		(net "GMI_CPU0_G1_CPU1_G3_TX_DN<8>")
	)
	(segment
		(start 351.479866 -239.319816)
		(end 351.455482 -239.305846)
		(width 0.1143)
		(layer "In15.Cu")
		(net "GMI_CPU0_G1_CPU1_G3_TX_DN<8>")
	)
	(segment
		(start 120.086628 -237.65891)
		(end 120.047512 -237.68177)
		(width 0.1143)
		(layer "In15.Cu")
		(net "GMI_CPU0_G1_CPU1_G3_TX_DN<8>")
	)
	(segment
		(start 351.448878 -227.962206)
		(end 351.448116 -227.961698)
		(width 0.1143)
		(layer "In15.Cu")
		(net "GMI_CPU0_G1_CPU1_G3_TX_DN<8>")
	)
	(segment
		(start 351.455482 -239.305846)
		(end 351.454212 -239.305084)
		(width 0.1143)
		(layer "In15.Cu")
		(net "GMI_CPU0_G1_CPU1_G3_TX_DN<8>")
	)
	(segment
		(start 351.479866 -227.979986)
		(end 351.448878 -227.962206)
		(width 0.1143)
		(layer "In15.Cu")
		(net "GMI_CPU0_G1_CPU1_G3_TX_DN<8>")
	)
	(segment
		(start 147.47113 -194.889374)
		(end 145.90903 -196.170296)
		(width 0.14224)
		(layer "In15.Cu")
		(net "GMI_CPU0_G1_CPU1_G3_TX_DN<8>")
	)
	(segment
		(start 351.469198 -235.07446)
		(end 351.46996 -235.073952)
		(width 0.1143)
		(layer "In15.Cu")
		(net "GMI_CPU0_G1_CPU1_G3_TX_DN<8>")
	)
	(segment
		(start 119.82577 -221.198948)
		(end 119.859552 -221.23273)
		(width 0.1143)
		(layer "In15.Cu")
		(net "GMI_CPU0_G1_CPU1_G3_TX_DN<8>")
	)
	(segment
		(start 149.18309 -193.66357)
		(end 148.99005 -193.644266)
		(width 0.14224)
		(layer "In15.Cu")
		(net "GMI_CPU0_G1_CPU1_G3_TX_DN<8>")
	)
	(segment
		(start 119.87149 -221.020386)
		(end 119.82577 -221.066106)
		(width 0.1143)
		(layer "In15.Cu")
		(net "GMI_CPU0_G1_CPU1_G3_TX_DN<8>")
	)
	(segment
		(start 148.99005 -193.644266)
		(end 147.471384 -194.889374)
		(width 0.14224)
		(layer "In15.Cu")
		(net "GMI_CPU0_G1_CPU1_G3_TX_DN<8>")
	)
	(segment
		(start 119.936768 -244.484398)
		(end 120.23471 -244.484398)
		(width 0.1143)
		(layer "In15.Cu")
		(net "GMI_CPU0_G1_CPU1_G3_TX_DN<8>")
	)
	(segment
		(start 120.017032 -235.069126)
		(end 120.047512 -235.086906)
		(width 0.1143)
		(layer "In15.Cu")
		(net "GMI_CPU0_G1_CPU1_G3_TX_DN<8>")
	)
	(segment
		(start 351.448878 -240.922048)
		(end 351.448116 -240.92154)
		(width 0.1143)
		(layer "In15.Cu")
		(net "GMI_CPU0_G1_CPU1_G3_TX_DN<8>")
	)
	(segment
		(start 351.445576 -230.22814)
		(end 351.4471 -230.227124)
		(width 0.1143)
		(layer "In15.Cu")
		(net "GMI_CPU0_G1_CPU1_G3_TX_DN<8>")
	)
	(segment
		(start 351.448116 -239.946688)
		(end 351.469198 -239.934496)
		(width 0.1143)
		(layer "In15.Cu")
		(net "GMI_CPU0_G1_CPU1_G3_TX_DN<8>")
	)
	(segment
		(start 120.047512 -228.607112)
		(end 120.086628 -228.629972)
		(width 0.1143)
		(layer "In15.Cu")
		(net "GMI_CPU0_G1_CPU1_G3_TX_DN<8>")
	)
	(segment
		(start 351.448116 -233.46664)
		(end 351.479866 -233.448352)
		(width 0.1143)
		(layer "In15.Cu")
		(net "GMI_CPU0_G1_CPU1_G3_TX_DN<8>")
	)
	(segment
		(start 351.448116 -243.186712)
		(end 351.479866 -243.168424)
		(width 0.1143)
		(layer "In15.Cu")
		(net "GMI_CPU0_G1_CPU1_G3_TX_DN<8>")
	)
	(segment
		(start 120.086628 -224.699068)
		(end 120.047512 -224.721928)
		(width 0.1143)
		(layer "In15.Cu")
		(net "GMI_CPU0_G1_CPU1_G3_TX_DN<8>")
	)
	(segment
		(start 120.047258 -222.127064)
		(end 120.087644 -222.150686)
		(width 0.1143)
		(layer "In15.Cu")
		(net "GMI_CPU0_G1_CPU1_G3_TX_DN<8>")
	)
	(segment
		(start 350.4692 -223.769682)
		(end 350.508316 -223.746822)
		(width 0.1143)
		(layer "In15.Cu")
		(net "GMI_CPU0_G1_CPU1_G3_TX_DN<8>")
	)
	(segment
		(start 120.047512 -234.441746)
		(end 120.017032 -234.459526)
		(width 0.1143)
		(layer "In15.Cu")
		(net "GMI_CPU0_G1_CPU1_G3_TX_DN<8>")
	)
	(segment
		(start 351.45345 -240.924588)
		(end 351.452434 -240.92408)
		(width 0.1143)
		(layer "In15.Cu")
		(net "GMI_CPU0_G1_CPU1_G3_TX_DN<8>")
	)
	(segment
		(start 351.414588 -229.562152)
		(end 351.411794 -229.560628)
		(width 0.1143)
		(layer "In15.Cu")
		(net "GMI_CPU0_G1_CPU1_G3_TX_DN<8>")
	)
	(segment
		(start 351.413318 -226.32162)
		(end 351.411794 -226.320604)
		(width 0.1143)
		(layer "In15.Cu")
		(net "GMI_CPU0_G1_CPU1_G3_TX_DN<8>")
	)
	(segment
		(start 145.90903 -196.170296)
		(end 144.86001 -196.487796)
		(width 0.14224)
		(layer "In15.Cu")
		(net "GMI_CPU0_G1_CPU1_G3_TX_DN<8>")
	)
	(segment
		(start 150.404576 -192.484756)
		(end 150.385526 -192.677796)
		(width 0.14224)
		(layer "In15.Cu")
		(net "GMI_CPU0_G1_CPU1_G3_TX_DN<8>")
	)
	(segment
		(start 351.480882 -229.60076)
		(end 351.448116 -229.58171)
		(width 0.1143)
		(layer "In15.Cu")
		(net "GMI_CPU0_G1_CPU1_G3_TX_DN<8>")
	)
	(segment
		(start 120.047512 -227.961952)
		(end 120.017032 -227.979732)
		(width 0.1143)
		(layer "In15.Cu")
		(net "GMI_CPU0_G1_CPU1_G3_TX_DN<8>")
	)
	(segment
		(start 351.448878 -236.062012)
		(end 351.448116 -236.061504)
		(width 0.1143)
		(layer "In15.Cu")
		(net "GMI_CPU0_G1_CPU1_G3_TX_DN<8>")
	)
	(segment
		(start 120.047512 -242.541806)
		(end 120.017032 -242.559586)
		(width 0.1143)
		(layer "In15.Cu")
		(net "GMI_CPU0_G1_CPU1_G3_TX_DN<8>")
	)
	(segment
		(start 119.859552 -221.23273)
		(end 119.859552 -221.804484)
		(width 0.1143)
		(layer "In15.Cu")
		(net "GMI_CPU0_G1_CPU1_G3_TX_DN<8>")
	)
	(segment
		(start 120.047512 -223.101916)
		(end 120.017032 -223.119696)
		(width 0.1143)
		(layer "In15.Cu")
		(net "GMI_CPU0_G1_CPU1_G3_TX_DN<8>")
	)
	(segment
		(start 349.755968 -221.128844)
		(end 349.710248 -221.083124)
		(width 0.1143)
		(layer "In15.Cu")
		(net "GMI_CPU0_G1_CPU1_G3_TX_DN<8>")
	)
	(segment
		(start 302.895 -182.593488)
		(end 166.433754 -181.798214)
		(width 0.14224)
		(layer "In15.Cu")
		(net "GMI_CPU0_G1_CPU1_G3_TX_DN<8>")
	)
	(segment
		(start 120.047512 -223.747076)
		(end 120.086628 -223.769936)
		(width 0.1143)
		(layer "In15.Cu")
		(net "GMI_CPU0_G1_CPU1_G3_TX_DN<8>")
	)
	(segment
		(start 149.53234 -193.199766)
		(end 149.51329 -193.392806)
		(width 0.14224)
		(layer "In15.Cu")
		(net "GMI_CPU0_G1_CPU1_G3_TX_DN<8>")
	)
	(segment
		(start 351.559114 -244.484144)
		(end 351.628964 -244.414294)
		(width 0.1143)
		(layer "In15.Cu")
		(net "GMI_CPU0_G1_CPU1_G3_TX_DN<8>")
	)
	(segment
		(start 351.479866 -236.079792)
		(end 351.454466 -236.065314)
		(width 0.1143)
		(layer "In15.Cu")
		(net "GMI_CPU0_G1_CPU1_G3_TX_DN<8>")
	)
	(segment
		(start 351.479866 -226.359974)
		(end 351.448116 -226.341686)
		(width 0.1143)
		(layer "In15.Cu")
		(net "GMI_CPU0_G1_CPU1_G3_TX_DN<8>")
	)
	(segment
		(start 351.45345 -239.304576)
		(end 351.452434 -239.304068)
		(width 0.1143)
		(layer "In15.Cu")
		(net "GMI_CPU0_G1_CPU1_G3_TX_DN<8>")
	)
	(segment
		(start 350.978216 -225.53168)
		(end 350.9772 -225.531172)
		(width 0.1143)
		(layer "In15.Cu")
		(net "GMI_CPU0_G1_CPU1_G3_TX_DN<8>")
	)
	(segment
		(start 151.606758 -191.498982)
		(end 151.276812 -191.769492)
		(width 0.14224)
		(layer "In15.Cu")
		(net "GMI_CPU0_G1_CPU1_G3_TX_DN<8>")
	)
	(segment
		(start 351.448878 -242.54206)
		(end 351.448116 -242.541552)
		(width 0.1143)
		(layer "In15.Cu")
		(net "GMI_CPU0_G1_CPU1_G3_TX_DN<8>")
	)
	(segment
		(start 120.017032 -231.829102)
		(end 120.047512 -231.846882)
		(width 0.1143)
		(layer "In15.Cu")
		(net "GMI_CPU0_G1_CPU1_G3_TX_DN<8>")
	)
	(segment
		(start 351.46996 -236.693964)
		(end 351.479866 -236.688376)
		(width 0.1143)
		(layer "In15.Cu")
		(net "GMI_CPU0_G1_CPU1_G3_TX_DN<8>")
	)
	(segment
		(start 153.021284 -190.338964)
		(end 153.021284 -190.339218)
		(width 0.14224)
		(layer "In15.Cu")
		(net "GMI_CPU0_G1_CPU1_G3_TX_DN<8>")
	)
	(segment
		(start 351.447862 -238.32693)
		(end 351.448116 -238.326676)
		(width 0.1143)
		(layer "In15.Cu")
		(net "GMI_CPU0_G1_CPU1_G3_TX_DN<8>")
	)
	(segment
		(start 152.149048 -191.054482)
		(end 152.129998 -191.247522)
		(width 0.14224)
		(layer "In15.Cu")
		(net "GMI_CPU0_G1_CPU1_G3_TX_DN<8>")
	)
	(segment
		(start 351.454212 -239.305084)
		(end 351.45345 -239.304576)
		(width 0.1143)
		(layer "In15.Cu")
		(net "GMI_CPU0_G1_CPU1_G3_TX_DN<8>")
	)
	(segment
		(start 351.46996 -238.313976)
		(end 351.479866 -238.308388)
		(width 0.1143)
		(layer "In15.Cu")
		(net "GMI_CPU0_G1_CPU1_G3_TX_DN<8>")
	)
	(segment
		(start 351.411794 -233.487722)
		(end 351.448116 -233.46664)
		(width 0.1143)
		(layer "In15.Cu")
		(net "GMI_CPU0_G1_CPU1_G3_TX_DN<8>")
	)
	(segment
		(start 120.017032 -230.20909)
		(end 120.084088 -230.248206)
		(width 0.1143)
		(layer "In15.Cu")
		(net "GMI_CPU0_G1_CPU1_G3_TX_DN<8>")
	)
	(segment
		(start 154.896566 -188.801248)
		(end 154.877516 -188.994288)
		(width 0.14224)
		(layer "In15.Cu")
		(net "GMI_CPU0_G1_CPU1_G3_TX_DN<8>")
	)
	(segment
		(start 351.411794 -231.86771)
		(end 351.448116 -231.846628)
		(width 0.1143)
		(layer "In15.Cu")
		(net "GMI_CPU0_G1_CPU1_G3_TX_DN<8>")
	)
	(segment
		(start 351.479866 -242.55984)
		(end 351.455482 -242.54587)
		(width 0.1143)
		(layer "In15.Cu")
		(net "GMI_CPU0_G1_CPU1_G3_TX_DN<8>")
	)
	(segment
		(start 351.450656 -242.543076)
		(end 351.449894 -242.542568)
		(width 0.1143)
		(layer "In15.Cu")
		(net "GMI_CPU0_G1_CPU1_G3_TX_DN<8>")
	)
	(segment
		(start 151.799798 -191.518286)
		(end 151.606758 -191.498982)
		(width 0.14224)
		(layer "In15.Cu")
		(net "GMI_CPU0_G1_CPU1_G3_TX_DN<8>")
	)
	(segment
		(start 350.9772 -225.531172)
		(end 350.9391 -225.50882)
		(width 0.1143)
		(layer "In15.Cu")
		(net "GMI_CPU0_G1_CPU1_G3_TX_DN<8>")
	)
	(segment
		(start 351.452434 -242.544092)
		(end 351.451672 -242.543584)
		(width 0.1143)
		(layer "In15.Cu")
		(net "GMI_CPU0_G1_CPU1_G3_TX_DN<8>")
	)
	(segment
		(start 351.454466 -236.065314)
		(end 351.452434 -236.064044)
		(width 0.1143)
		(layer "In15.Cu")
		(net "GMI_CPU0_G1_CPU1_G3_TX_DN<8>")
	)
	(segment
		(start 120.017032 -241.549174)
		(end 120.047512 -241.566954)
		(width 0.1143)
		(layer "In15.Cu")
		(net "GMI_CPU0_G1_CPU1_G3_TX_DN<8>")
	)
	(segment
		(start 351.46996 -235.073952)
		(end 351.479866 -235.068364)
		(width 0.1143)
		(layer "In15.Cu")
		(net "GMI_CPU0_G1_CPU1_G3_TX_DN<8>")
	)
	(segment
		(start 351.448116 -241.5667)
		(end 351.469198 -241.554508)
		(width 0.1143)
		(layer "In15.Cu")
		(net "GMI_CPU0_G1_CPU1_G3_TX_DN<8>")
	)
	(segment
		(start 351.452434 -236.064044)
		(end 351.451672 -236.063536)
		(width 0.1143)
		(layer "In15.Cu")
		(net "GMI_CPU0_G1_CPU1_G3_TX_DN<8>")
	)
	(segment
		(start 350.038162 -222.291656)
		(end 350.037146 -222.291148)
		(width 0.1143)
		(layer "In15.Cu")
		(net "GMI_CPU0_G1_CPU1_G3_TX_DN<8>")
	)
	(segment
		(start 350.037146 -222.291148)
		(end 350.035622 -222.290132)
		(width 0.1143)
		(layer "In15.Cu")
		(net "GMI_CPU0_G1_CPU1_G3_TX_DN<8>")
	)
	(segment
		(start 120.017032 -243.169186)
		(end 120.047512 -243.186966)
		(width 0.1143)
		(layer "In15.Cu")
		(net "GMI_CPU0_G1_CPU1_G3_TX_DN<8>")
	)
	(segment
		(start 166.433754 -181.798214)
		(end 161.119312 -183.698388)
		(width 0.14224)
		(layer "In15.Cu")
		(net "GMI_CPU0_G1_CPU1_G3_TX_DN<8>")
	)
	(segment
		(start 151.257762 -191.962532)
		(end 150.927562 -192.233296)
		(width 0.14224)
		(layer "In15.Cu")
		(net "GMI_CPU0_G1_CPU1_G3_TX_DN<8>")
	)
	(segment
		(start 351.452434 -228.604318)
		(end 351.454466 -228.603302)
		(width 0.1143)
		(layer "In15.Cu")
		(net "GMI_CPU0_G1_CPU1_G3_TX_DN<8>")
	)
	(segment
		(start 120.047512 -244.161818)
		(end 120.017032 -244.179598)
		(width 0.1143)
		(layer "In15.Cu")
		(net "GMI_CPU0_G1_CPU1_G3_TX_DN<8>")
	)
	(segment
		(start 120.047512 -238.32693)
		(end 120.086628 -238.34979)
		(width 0.1143)
		(layer "In15.Cu")
		(net "GMI_CPU0_G1_CPU1_G3_TX_DN<8>")
	)
	(segment
		(start 153.021284 -190.339218)
		(end 153.002234 -190.532258)
		(width 0.14224)
		(layer "In15.Cu")
		(net "GMI_CPU0_G1_CPU1_G3_TX_DN<8>")
	)
	(segment
		(start 351.411794 -243.207794)
		(end 351.448116 -243.186712)
		(width 0.1143)
		(layer "In15.Cu")
		(net "GMI_CPU0_G1_CPU1_G3_TX_DN<8>")
	)
	(segment
		(start 351.449894 -236.06252)
		(end 351.448878 -236.062012)
		(width 0.1143)
		(layer "In15.Cu")
		(net "GMI_CPU0_G1_CPU1_G3_TX_DN<8>")
	)
	(segment
		(start 153.002234 -190.532258)
		(end 152.672034 -190.803022)
		(width 0.14224)
		(layer "In15.Cu")
		(net "GMI_CPU0_G1_CPU1_G3_TX_DN<8>")
	)
	(segment
		(start 350.035622 -222.290132)
		(end 350.034606 -222.289624)
		(width 0.1143)
		(layer "In15.Cu")
		(net "GMI_CPU0_G1_CPU1_G3_TX_DN<8>")
	)
	(segment
		(start 346.936822 -213.1568)
		(end 314.47105 -186.536584)
		(width 0.14224)
		(layer "In15.Cu")
		(net "GMI_CPU0_G1_CPU1_G3_TX_DN<8>")
	)
	(segment
		(start 120.047512 -232.821734)
		(end 120.017032 -232.839514)
		(width 0.1143)
		(layer "In15.Cu")
		(net "GMI_CPU0_G1_CPU1_G3_TX_DN<8>")
	)
	(segment
		(start 119.87149 -219.380816)
		(end 119.87149 -220.991938)
		(width 0.14224)
		(layer "In15.Cu")
		(net "GMI_CPU0_G1_CPU1_G3_TX_DN<8>")
	)
	(segment
		(start 120.017032 -228.589332)
		(end 120.047512 -228.607112)
		(width 0.1143)
		(layer "In15.Cu")
		(net "GMI_CPU0_G1_CPU1_G3_TX_DN<8>")
	)
	(segment
		(start 120.047512 -231.201976)
		(end 120.015 -231.220772)
		(width 0.1143)
		(layer "In15.Cu")
		(net "GMI_CPU0_G1_CPU1_G3_TX_DN<8>")
	)
	(segment
		(start 351.448116 -236.706664)
		(end 351.469198 -236.694472)
		(width 0.1143)
		(layer "In15.Cu")
		(net "GMI_CPU0_G1_CPU1_G3_TX_DN<8>")
	)
	(segment
		(start 351.452434 -237.684056)
		(end 351.451672 -237.683548)
		(width 0.1143)
		(layer "In15.Cu")
		(net "GMI_CPU0_G1_CPU1_G3_TX_DN<8>")
	)
	(segment
		(start 351.479866 -237.699804)
		(end 351.455482 -237.685834)
		(width 0.1143)
		(layer "In15.Cu")
		(net "GMI_CPU0_G1_CPU1_G3_TX_DN<8>")
	)
	(segment
		(start 351.452434 -239.304068)
		(end 351.451672 -239.30356)
		(width 0.1143)
		(layer "In15.Cu")
		(net "GMI_CPU0_G1_CPU1_G3_TX_DN<8>")
	)
	(segment
		(start 120.047512 -224.721928)
		(end 120.017032 -224.739708)
		(width 0.1143)
		(layer "In15.Cu")
		(net "GMI_CPU0_G1_CPU1_G3_TX_DN<8>")
	)
	(segment
		(start 154.354276 -189.246002)
		(end 153.89352 -189.6237)
		(width 0.14224)
		(layer "In15.Cu")
		(net "GMI_CPU0_G1_CPU1_G3_TX_DN<8>")
	)
	(segment
		(start 351.448116 -235.086652)
		(end 351.469198 -235.07446)
		(width 0.1143)
		(layer "In15.Cu")
		(net "GMI_CPU0_G1_CPU1_G3_TX_DN<8>")
	)
	(segment
		(start 154.877516 -188.994288)
		(end 154.547316 -189.265052)
		(width 0.14224)
		(layer "In15.Cu")
		(net "GMI_CPU0_G1_CPU1_G3_TX_DN<8>")
	)
	(segment
		(start 122.566176 -214.768176)
		(end 119.87149 -219.380816)
		(width 0.14224)
		(layer "In15.Cu")
		(net "GMI_CPU0_G1_CPU1_G3_TX_DN<8>")
	)
	(segment
		(start 149.51329 -193.392806)
		(end 149.18309 -193.66357)
		(width 0.14224)
		(layer "In15.Cu")
		(net "GMI_CPU0_G1_CPU1_G3_TX_DN<8>")
	)
	(segment
		(start 120.086628 -242.518946)
		(end 120.047512 -242.541806)
		(width 0.1143)
		(layer "In15.Cu")
		(net "GMI_CPU0_G1_CPU1_G3_TX_DN<8>")
	)
	(segment
		(start 351.448116 -229.58171)
		(end 351.414588 -229.562152)
		(width 0.1143)
		(layer "In15.Cu")
		(net "GMI_CPU0_G1_CPU1_G3_TX_DN<8>")
	)
	(segment
		(start 350.981518 -225.533458)
		(end 350.978216 -225.53168)
		(width 0.1143)
		(layer "In15.Cu")
		(net "GMI_CPU0_G1_CPU1_G3_TX_DN<8>")
	)
	(segment
		(start 120.047512 -226.9871)
		(end 120.086628 -227.00996)
		(width 0.1143)
		(layer "In15.Cu")
		(net "GMI_CPU0_G1_CPU1_G3_TX_DN<8>")
	)
	(segment
		(start 120.047512 -243.186966)
		(end 120.086628 -243.209826)
		(width 0.1143)
		(layer "In15.Cu")
		(net "GMI_CPU0_G1_CPU1_G3_TX_DN<8>")
	)
	(segment
		(start 120.086628 -231.179116)
		(end 120.047512 -231.201976)
		(width 0.1143)
		(layer "In15.Cu")
		(net "GMI_CPU0_G1_CPU1_G3_TX_DN<8>")
	)
	(segment
		(start 153.87447 -189.81674)
		(end 153.54427 -190.087504)
		(width 0.14224)
		(layer "In15.Cu")
		(net "GMI_CPU0_G1_CPU1_G3_TX_DN<8>")
	)
	(segment
		(start 351.450656 -236.063028)
		(end 351.449894 -236.06252)
		(width 0.1143)
		(layer "In15.Cu")
		(net "GMI_CPU0_G1_CPU1_G3_TX_DN<8>")
	)
	(segment
		(start 152.478994 -190.783972)
		(end 152.149048 -191.054482)
		(width 0.14224)
		(layer "In15.Cu")
		(net "GMI_CPU0_G1_CPU1_G3_TX_DN<8>")
	)
	(segment
		(start 351.4471 -230.227124)
		(end 351.448116 -230.226616)
		(width 0.1143)
		(layer "In15.Cu")
		(net "GMI_CPU0_G1_CPU1_G3_TX_DN<8>")
	)
	(segment
		(start 120.047512 -236.061758)
		(end 120.017032 -236.079538)
		(width 0.1143)
		(layer "In15.Cu")
		(net "GMI_CPU0_G1_CPU1_G3_TX_DN<8>")
	)
	(segment
		(start 119.866918 -244.414548)
		(end 119.936768 -244.484398)
		(width 0.1143)
		(layer "In15.Cu")
		(net "GMI_CPU0_G1_CPU1_G3_TX_DN<8>")
	)
	(segment
		(start 120.047512 -239.301782)
		(end 120.017032 -239.319562)
		(width 0.1143)
		(layer "In15.Cu")
		(net "GMI_CPU0_G1_CPU1_G3_TX_DN<8>")
	)
	(segment
		(start 351.448878 -237.682024)
		(end 351.448116 -237.681516)
		(width 0.1143)
		(layer "In15.Cu")
		(net "GMI_CPU0_G1_CPU1_G3_TX_DN<8>")
	)
	(segment
		(start 351.451672 -239.30356)
		(end 351.450656 -239.303052)
		(width 0.1143)
		(layer "In15.Cu")
		(net "GMI_CPU0_G1_CPU1_G3_TX_DN<8>")
	)
	(segment
		(start 350.508316 -224.721674)
		(end 350.4692 -224.698814)
		(width 0.1143)
		(layer "In15.Cu")
		(net "GMI_CPU0_G1_CPU1_G3_TX_DN<8>")
	)
	(segment
		(start 351.448878 -228.60635)
		(end 351.451672 -228.604826)
		(width 0.1143)
		(layer "In15.Cu")
		(net "GMI_CPU0_G1_CPU1_G3_TX_DN<8>")
	)
	(segment
		(start 351.448878 -244.162072)
		(end 351.448116 -244.161564)
		(width 0.1143)
		(layer "In15.Cu")
		(net "GMI_CPU0_G1_CPU1_G3_TX_DN<8>")
	)
	(segment
		(start 351.449894 -242.542568)
		(end 351.448878 -242.54206)
		(width 0.1143)
		(layer "In15.Cu")
		(net "GMI_CPU0_G1_CPU1_G3_TX_DN<8>")
	)
	(segment
		(start 350.033082 -222.288608)
		(end 350.032066 -222.2881)
		(width 0.1143)
		(layer "In15.Cu")
		(net "GMI_CPU0_G1_CPU1_G3_TX_DN<8>")
	)
	(segment
		(start 120.017032 -238.30915)
		(end 120.047512 -238.32693)
		(width 0.1143)
		(layer "In15.Cu")
		(net "GMI_CPU0_G1_CPU1_G3_TX_DN<8>")
	)
	(segment
		(start 120.086628 -226.31908)
		(end 120.047512 -226.34194)
		(width 0.1143)
		(layer "In15.Cu")
		(net "GMI_CPU0_G1_CPU1_G3_TX_DN<8>")
	)
	(segment
		(start 120.047512 -231.846882)
		(end 120.086628 -231.869742)
		(width 0.1143)
		(layer "In15.Cu")
		(net "GMI_CPU0_G1_CPU1_G3_TX_DN<8>")
	)
	(segment
		(start 120.047512 -236.706918)
		(end 120.086628 -236.729778)
		(width 0.1143)
		(layer "In15.Cu")
		(net "GMI_CPU0_G1_CPU1_G3_TX_DN<8>")
	)
	(segment
		(start 351.261172 -244.484144)
		(end 351.559114 -244.484144)
		(width 0.1143)
		(layer "In15.Cu")
		(net "GMI_CPU0_G1_CPU1_G3_TX_DN<8>")
	)
	(segment
		(start 351.448116 -231.846628)
		(end 351.479866 -231.82834)
		(width 0.1143)
		(layer "In15.Cu")
		(net "GMI_CPU0_G1_CPU1_G3_TX_DN<8>")
	)
	(segment
		(start 351.45345 -237.684564)
		(end 351.452434 -237.684056)
		(width 0.1143)
		(layer "In15.Cu")
		(net "GMI_CPU0_G1_CPU1_G3_TX_DN<8>")
	)
	(segment
		(start 351.448116 -228.606858)
		(end 351.448878 -228.60635)
		(width 0.1143)
		(layer "In15.Cu")
		(net "GMI_CPU0_G1_CPU1_G3_TX_DN<8>")
	)
	(segment
		(start 351.450656 -239.303052)
		(end 351.449894 -239.302544)
		(width 0.1143)
		(layer "In15.Cu")
		(net "GMI_CPU0_G1_CPU1_G3_TX_DN<8>")
	)
	(segment
		(start 150.055326 -192.94856)
		(end 149.862286 -192.929256)
		(width 0.14224)
		(layer "In15.Cu")
		(net "GMI_CPU0_G1_CPU1_G3_TX_DN<8>")
	)
	(segment
		(start 351.454466 -228.603302)
		(end 351.479866 -228.58857)
		(width 0.1143)
		(layer "In15.Cu")
		(net "GMI_CPU0_G1_CPU1_G3_TX_DN<8>")
	)
	(segment
		(start 120.086628 -240.898934)
		(end 120.047512 -240.921794)
		(width 0.1143)
		(layer "In15.Cu")
		(net "GMI_CPU0_G1_CPU1_G3_TX_DN<8>")
	)
	(segment
		(start 351.451672 -236.063536)
		(end 351.450656 -236.063028)
		(width 0.1143)
		(layer "In15.Cu")
		(net "GMI_CPU0_G1_CPU1_G3_TX_DN<8>")
	)
	(segment
		(start 351.002092 -225.545396)
		(end 350.981518 -225.533458)
		(width 0.1143)
		(layer "In15.Cu")
		(net "GMI_CPU0_G1_CPU1_G3_TX_DN<8>")
	)
	(segment
		(start 350.02978 -222.28683)
		(end 349.999046 -222.268796)
		(width 0.1143)
		(layer "In15.Cu")
		(net "GMI_CPU0_G1_CPU1_G3_TX_DN<8>")
	)
	(segment
		(start 351.005394 -225.547428)
		(end 351.004378 -225.54692)
		(width 0.1143)
		(layer "In15.Cu")
		(net "GMI_CPU0_G1_CPU1_G3_TX_DN<8>")
	)
	(segment
		(start 350.538796 -223.119442)
		(end 350.508316 -223.101662)
		(width 0.1143)
		(layer "In15.Cu")
		(net "GMI_CPU0_G1_CPU1_G3_TX_DN<8>")
	)
	(segment
		(start 120.086628 -223.079056)
		(end 120.047512 -223.101916)
		(width 0.1143)
		(layer "In15.Cu")
		(net "GMI_CPU0_G1_CPU1_G3_TX_DN<8>")
	)
	(segment
		(start 153.89352 -189.6237)
		(end 153.87447 -189.81674)
		(width 0.14224)
		(layer "In15.Cu")
		(net "GMI_CPU0_G1_CPU1_G3_TX_DN<8>")
	)
	(segment
		(start 351.448116 -226.986846)
		(end 351.479866 -226.968558)
		(width 0.1143)
		(layer "In15.Cu")
		(net "GMI_CPU0_G1_CPU1_G3_TX_DN<8>")
	)
	(segment
		(start 351.451672 -228.604826)
		(end 351.452434 -228.604318)
		(width 0.1143)
		(layer "In15.Cu")
		(net "GMI_CPU0_G1_CPU1_G3_TX_DN<8>")
	)
	(segment
		(start 120.047512 -235.086906)
		(end 120.086628 -235.109766)
		(width 0.1143)
		(layer "In15.Cu")
		(net "GMI_CPU0_G1_CPU1_G3_TX_DN<8>")
	)
	(segment
		(start 351.45345 -242.5446)
		(end 351.452434 -242.544092)
		(width 0.1143)
		(layer "In15.Cu")
		(net "GMI_CPU0_G1_CPU1_G3_TX_DN<8>")
	)
	(segment
		(start 120.017032 -225.349308)
		(end 120.047512 -225.367088)
		(width 0.1143)
		(layer "In15.Cu")
		(net "GMI_CPU0_G1_CPU1_G3_TX_DN<8>")
	)
	(segment
		(start 351.481644 -229.601268)
		(end 351.480882 -229.60076)
		(width 0.1143)
		(layer "In15.Cu")
		(net "GMI_CPU0_G1_CPU1_G3_TX_DN<8>")
	)
	(segment
		(start 150.927562 -192.233296)
		(end 150.734522 -192.214246)
		(width 0.14224)
		(layer "In15.Cu")
		(net "GMI_CPU0_G1_CPU1_G3_TX_DN<8>")
	)
	(segment
		(start 349.755968 -221.80423)
		(end 349.755968 -221.128844)
		(width 0.1143)
		(layer "In15.Cu")
		(net "GMI_CPU0_G1_CPU1_G3_TX_DN<8>")
	)
	(segment
		(start 351.447862 -235.086906)
		(end 351.448116 -235.086652)
		(width 0.1143)
		(layer "In15.Cu")
		(net "GMI_CPU0_G1_CPU1_G3_TX_DN<8>")
	)
	(segment
		(start 151.276812 -191.769492)
		(end 151.257762 -191.962532)
		(width 0.14224)
		(layer "In15.Cu")
		(net "GMI_CPU0_G1_CPU1_G3_TX_DN<8>")
	)
	(segment
		(start 307.036724 -182.593488)
		(end 302.895 -182.593488)
		(width 0.14224)
		(layer "In15.Cu")
		(net "GMI_CPU0_G1_CPU1_G3_TX_DN<8>")
	)
	(segment
		(start 153.35123 -190.068454)
		(end 153.021284 -190.338964)
		(width 0.14224)
		(layer "In15.Cu")
		(net "GMI_CPU0_G1_CPU1_G3_TX_DN<8>")
	)
	(segment
		(start 351.447862 -241.566954)
		(end 351.448116 -241.5667)
		(width 0.1143)
		(layer "In15.Cu")
		(net "GMI_CPU0_G1_CPU1_G3_TX_DN<8>")
	)
	(segment
		(start 351.469198 -238.314484)
		(end 351.46996 -238.313976)
		(width 0.1143)
		(layer "In15.Cu")
		(net "GMI_CPU0_G1_CPU1_G3_TX_DN<8>")
	)
	(segment
		(start 120.015508 -222.108776)
		(end 120.047258 -222.127064)
		(width 0.1143)
		(layer "In15.Cu")
		(net "GMI_CPU0_G1_CPU1_G3_TX_DN<8>")
	)
	(segment
		(start 120.017032 -233.449114)
		(end 120.047512 -233.466894)
		(width 0.1143)
		(layer "In15.Cu")
		(net "GMI_CPU0_G1_CPU1_G3_TX_DN<8>")
	)
	(segment
		(start 351.452434 -240.92408)
		(end 351.451672 -240.923572)
		(width 0.1143)
		(layer "In15.Cu")
		(net "GMI_CPU0_G1_CPU1_G3_TX_DN<8>")
	)
	(segment
		(start 349.710248 -219.017342)
		(end 346.936822 -213.1568)
		(width 0.14224)
		(layer "In15.Cu")
		(net "GMI_CPU0_G1_CPU1_G3_TX_DN<8>")
	)
	(segment
		(start 351.44456 -230.228648)
		(end 351.445576 -230.22814)
		(width 0.1143)
		(layer "In15.Cu")
		(net "GMI_CPU0_G1_CPU1_G3_TX_DN<8>")
	)
	(segment
		(start 351.447862 -239.946942)
		(end 351.448116 -239.946688)
		(width 0.1143)
		(layer "In15.Cu")
		(net "GMI_CPU0_G1_CPU1_G3_TX_DN<8>")
	)
	(segment
		(start 351.448116 -232.82148)
		(end 351.411794 -232.800398)
		(width 0.1143)
		(layer "In15.Cu")
		(net "GMI_CPU0_G1_CPU1_G3_TX_DN<8>")
	)
	(segment
		(start 351.454212 -237.685072)
		(end 351.45345 -237.684564)
		(width 0.1143)
		(layer "In15.Cu")
		(net "GMI_CPU0_G1_CPU1_G3_TX_DN<8>")
	)
	(segment
		(start 120.047512 -233.466894)
		(end 120.086628 -233.489754)
		(width 0.1143)
		(layer "In15.Cu")
		(net "GMI_CPU0_G1_CPU1_G3_TX_DN<8>")
	)
	(segment
		(start 155.226512 -188.530738)
		(end 154.896566 -188.801248)
		(width 0.14224)
		(layer "In15.Cu")
		(net "GMI_CPU0_G1_CPU1_G3_TX_DN<8>")
	)
	(segment
		(start 120.047512 -241.566954)
		(end 120.086628 -241.589814)
		(width 0.1143)
		(layer "In15.Cu")
		(net "GMI_CPU0_G1_CPU1_G3_TX_DN<8>")
	)
	(segment
		(start 155.419552 -188.549788)
		(end 155.226512 -188.530738)
		(width 0.14224)
		(layer "In15.Cu")
		(net "GMI_CPU0_G1_CPU1_G3_TX_DN<8>")
	)
	(segment
		(start 351.448116 -227.961698)
		(end 351.411794 -227.940616)
		(width 0.1143)
		(layer "In15.Cu")
		(net "GMI_CPU0_G1_CPU1_G3_TX_DN<8>")
	)
	(segment
		(start 351.47885 -231.219248)
		(end 351.437956 -231.195372)
		(width 0.1143)
		(layer "In15.Cu")
		(net "GMI_CPU0_G1_CPU1_G3_TX_DN<8>")
	)
	(segment
		(start 153.54427 -190.087504)
		(end 153.35123 -190.068454)
		(width 0.14224)
		(layer "In15.Cu")
		(net "GMI_CPU0_G1_CPU1_G3_TX_DN<8>")
	)
	(segment
		(start 351.448116 -242.541552)
		(end 351.447862 -242.541552)
		(width 0.1143)
		(layer "In15.Cu")
		(net "GMI_CPU0_G1_CPU1_G3_TX_DN<8>")
	)
	(segment
		(start 351.455482 -240.925858)
		(end 351.454212 -240.925096)
		(width 0.1143)
		(layer "In15.Cu")
		(net "GMI_CPU0_G1_CPU1_G3_TX_DN<8>")
	)
	(segment
		(start 155.768802 -188.085984)
		(end 155.749752 -188.279024)
		(width 0.14224)
		(layer "In15.Cu")
		(net "GMI_CPU0_G1_CPU1_G3_TX_DN<8>")
	)
	(segment
		(start 351.454212 -242.545108)
		(end 351.45345 -242.5446)
		(width 0.1143)
		(layer "In15.Cu")
		(net "GMI_CPU0_G1_CPU1_G3_TX_DN<8>")
	)
	(segment
		(start 351.165922 -225.870516)
		(end 351.165922 -225.870262)
		(width 0.1143)
		(layer "In15.Cu")
		(net "GMI_CPU0_G1_CPU1_G3_TX_DN<8>")
	)
	(segment
		(start 161.119312 -183.698388)
		(end 155.768802 -188.085984)
		(width 0.14224)
		(layer "In15.Cu")
		(net "GMI_CPU0_G1_CPU1_G3_TX_DN<8>")
	)
	(segment
		(start 351.481644 -231.22128)
		(end 351.47885 -231.219248)
		(width 0.1143)
		(layer "In15.Cu")
		(net "GMI_CPU0_G1_CPU1_G3_TX_DN<8>")
	)
	(segment
		(start 120.017032 -239.929162)
		(end 120.047512 -239.946942)
		(width 0.1143)
		(layer "In15.Cu")
		(net "GMI_CPU0_G1_CPU1_G3_TX_DN<8>")
	)
	(segment
		(start 154.547316 -189.265052)
		(end 154.354276 -189.246002)
		(width 0.14224)
		(layer "In15.Cu")
		(net "GMI_CPU0_G1_CPU1_G3_TX_DN<8>")
	)
	(segment
		(start 150.734522 -192.214246)
		(end 150.404576 -192.484756)
		(width 0.14224)
		(layer "In15.Cu")
		(net "GMI_CPU0_G1_CPU1_G3_TX_DN<8>")
	)
	(segment
		(start 120.086628 -244.138958)
		(end 120.047512 -244.161818)
		(width 0.1143)
		(layer "In15.Cu")
		(net "GMI_CPU0_G1_CPU1_G3_TX_DN<8>")
	)
	(segment
		(start 119.87149 -220.991938)
		(end 119.87149 -221.020386)
		(width 0.1143)
		(layer "In15.Cu")
		(net "GMI_CPU0_G1_CPU1_G3_TX_DN<8>")
	)
	(segment
		(start 350.069912 -222.309944)
		(end 350.038162 -222.291656)
		(width 0.1143)
		(layer "In15.Cu")
		(net "GMI_CPU0_G1_CPU1_G3_TX_DN<8>")
	)
	(segment
		(start 351.448116 -234.441492)
		(end 351.411794 -234.42041)
		(width 0.1143)
		(layer "In15.Cu")
		(net "GMI_CPU0_G1_CPU1_G3_TX_DN<8>")
	)
	(segment
		(start 308.308502 -183.048148)
		(end 307.036724 -182.593488)
		(width 0.14224)
		(layer "In15.Cu")
		(net "GMI_CPU0_G1_CPU1_G3_TX_DN<8>")
	)
	(segment
		(start 120.086628 -234.418886)
		(end 120.047512 -234.441746)
		(width 0.1143)
		(layer "In15.Cu")
		(net "GMI_CPU0_G1_CPU1_G3_TX_DN<8>")
	)
	(segment
		(start 351.449894 -240.922556)
		(end 351.448878 -240.922048)
		(width 0.1143)
		(layer "In15.Cu")
		(net "GMI_CPU0_G1_CPU1_G3_TX_DN<8>")
	)
	(segment
		(start 155.749752 -188.279024)
		(end 155.419552 -188.549788)
		(width 0.14224)
		(layer "In15.Cu")
		(net "GMI_CPU0_G1_CPU1_G3_TX_DN<8>")
	)
	(segment
		(start 149.862286 -192.929256)
		(end 149.53234 -193.199766)
		(width 0.14224)
		(layer "In15.Cu")
		(net "GMI_CPU0_G1_CPU1_G3_TX_DN<8>")
	)
	(segment
		(start 351.450656 -240.923064)
		(end 351.449894 -240.922556)
		(width 0.1143)
		(layer "In15.Cu")
		(net "GMI_CPU0_G1_CPU1_G3_TX_DN<8>")
	)
	(segment
		(start 351.448116 -226.341686)
		(end 351.413318 -226.32162)
		(width 0.1143)
		(layer "In15.Cu")
		(net "GMI_CPU0_G1_CPU1_G3_TX_DN<8>")
	)
	(segment
		(start 351.469198 -239.934496)
		(end 351.46996 -239.933988)
		(width 0.1143)
		(layer "In15.Cu")
		(net "GMI_CPU0_G1_CPU1_G3_TX_DN<8>")
	)
	(segment
		(start 351.479866 -232.839768)
		(end 351.448116 -232.82148)
		(width 0.1143)
		(layer "In15.Cu")
		(net "GMI_CPU0_G1_CPU1_G3_TX_DN<8>")
	)
	(segment
		(start 351.454212 -240.925096)
		(end 351.45345 -240.924588)
		(width 0.1143)
		(layer "In15.Cu")
		(net "GMI_CPU0_G1_CPU1_G3_TX_DN<8>")
	)
	(segment
		(start 350.538796 -224.739454)
		(end 350.508316 -224.721674)
		(width 0.1143)
		(layer "In15.Cu")
		(net "GMI_CPU0_G1_CPU1_G3_TX_DN<8>")
	)
	(segment
		(start 150.385526 -192.677796)
		(end 150.055326 -192.94856)
		(width 0.14224)
		(layer "In15.Cu")
		(net "GMI_CPU0_G1_CPU1_G3_TX_DN<8>")
	)
	(segment
		(start 351.455482 -242.54587)
		(end 351.454212 -242.545108)
		(width 0.1143)
		(layer "In15.Cu")
		(net "GMI_CPU0_G1_CPU1_G3_TX_DN<8>")
	)
	(segment
		(start 350.508316 -223.746822)
		(end 350.538796 -223.729042)
		(width 0.1143)
		(layer "In15.Cu")
		(net "GMI_CPU0_G1_CPU1_G3_TX_DN<8>")
	)
	(segment
		(start 314.47105 -186.536584)
		(end 308.308502 -183.048148)
		(width 0.14224)
		(layer "In15.Cu")
		(net "GMI_CPU0_G1_CPU1_G3_TX_DN<8>")
	)
	(segment
		(start 351.449894 -239.302544)
		(end 351.448878 -239.302036)
		(width 0.1143)
		(layer "In15.Cu")
		(net "GMI_CPU0_G1_CPU1_G3_TX_DN<8>")
	)
	(segment
		(start 351.46996 -239.933988)
		(end 351.479866 -239.9284)
		(width 0.1143)
		(layer "In15.Cu")
		(net "GMI_CPU0_G1_CPU1_G3_TX_DN<8>")
	)
	(segment
		(start 120.047512 -225.367088)
		(end 120.086628 -225.389948)
		(width 0.1143)
		(layer "In15.Cu")
		(net "GMI_CPU0_G1_CPU1_G3_TX_DN<8>")
	)
	(segment
		(start 120.017032 -223.729296)
		(end 120.047512 -223.747076)
		(width 0.1143)
		(layer "In15.Cu")
		(net "GMI_CPU0_G1_CPU1_G3_TX_DN<8>")
	)
	(segment
		(start 120.086628 -236.038898)
		(end 120.047512 -236.061758)
		(width 0.1143)
		(layer "In15.Cu")
		(net "GMI_CPU0_G1_CPU1_G3_TX_DN<8>")
	)
	(segment
		(start 351.448116 -239.301528)
		(end 351.447862 -239.301528)
		(width 0.1143)
		(layer "In15.Cu")
		(net "GMI_CPU0_G1_CPU1_G3_TX_DN<8>")
	)
	(segment
		(start 351.411794 -227.007928)
		(end 351.448116 -226.986846)
		(width 0.1143)
		(layer "In15.Cu")
		(net "GMI_CPU0_G1_CPU1_G3_TX_DN<8>")
	)
	(segment
		(start 351.469198 -236.694472)
		(end 351.46996 -236.693964)
		(width 0.1143)
		(layer "In15.Cu")
		(net "GMI_CPU0_G1_CPU1_G3_TX_DN<8>")
	)
	(segment
		(start 351.451672 -237.683548)
		(end 351.450656 -237.68304)
		(width 0.1143)
		(layer "In15.Cu")
		(net "GMI_CPU0_G1_CPU1_G3_TX_DN<8>")
	)
	(segment
		(start 152.129998 -191.247522)
		(end 151.799798 -191.518286)
		(width 0.14224)
		(layer "In15.Cu")
		(net "GMI_CPU0_G1_CPU1_G3_TX_DN<8>")
	)
	(segment
		(start 351.004378 -225.54692)
		(end 351.002092 -225.545396)
		(width 0.1143)
		(layer "In15.Cu")
		(net "GMI_CPU0_G1_CPU1_G3_TX_DN<8>")
	)
	(segment
		(start 351.451672 -240.923572)
		(end 351.450656 -240.923064)
		(width 0.1143)
		(layer "In15.Cu")
		(net "GMI_CPU0_G1_CPU1_G3_TX_DN<8>")
	)
	(segment
		(start 351.447862 -236.706918)
		(end 351.448116 -236.706664)
		(width 0.1143)
		(layer "In15.Cu")
		(net "GMI_CPU0_G1_CPU1_G3_TX_DN<8>")
	)
	(segment
		(start 351.479866 -234.45978)
		(end 351.448116 -234.441492)
		(width 0.1143)
		(layer "In15.Cu")
		(net "GMI_CPU0_G1_CPU1_G3_TX_DN<8>")
	)
	(segment
		(start 351.448116 -244.161564)
		(end 351.411794 -244.140482)
		(width 0.1143)
		(layer "In15.Cu")
		(net "GMI_CPU0_G1_CPU1_G3_TX_DN<8>")
	)
	(segment
		(start 120.086628 -229.559104)
		(end 120.047512 -229.581964)
		(width 0.1143)
		(layer "In15.Cu")
		(net "GMI_CPU0_G1_CPU1_G3_TX_DN<8>")
	)
	(segment
		(start 351.416112 -230.245158)
		(end 351.44456 -230.228648)
		(width 0.1143)
		(layer "In15.Cu")
		(net "GMI_CPU0_G1_CPU1_G3_TX_DN<8>")
	)
	(segment
		(start 152.672034 -190.803022)
		(end 152.478994 -190.783972)
		(width 0.14224)
		(layer "In15.Cu")
		(net "GMI_CPU0_G1_CPU1_G3_TX_DN<8>")
	)
	(segment
		(start 351.455482 -237.685834)
		(end 351.454212 -237.685072)
		(width 0.1143)
		(layer "In15.Cu")
		(net "GMI_CPU0_G1_CPU1_G3_TX_DN<8>")
	)
	(segment
		(start 350.508316 -223.101662)
		(end 350.4692 -223.078802)
		(width 0.1143)
		(layer "In15.Cu")
		(net "GMI_CPU0_G1_CPU1_G3_TX_DN<8>")
	)
	(segment
		(start 144.86001 -196.487796)
		(end 122.566176 -214.768176)
		(width 0.14224)
		(layer "In15.Cu")
		(net "GMI_CPU0_G1_CPU1_G3_TX_DN<8>")
	)
	(segment
		(start 351.448116 -238.326676)
		(end 351.469198 -238.314484)
		(width 0.1143)
		(layer "In15.Cu")
		(net "GMI_CPU0_G1_CPU1_G3_TX_DN<8>")
	)
	(segment
		(start 147.471384 -194.889374)
		(end 147.47113 -194.889374)
		(width 0.14224)
		(layer "In15.Cu")
		(net "GMI_CPU0_G1_CPU1_G3_TX_DN<8>")
	)
	(segment
		(start 351.451672 -242.543584)
		(end 351.450656 -242.543076)
		(width 0.1143)
		(layer "In15.Cu")
		(net "GMI_CPU0_G1_CPU1_G3_TX_DN<8>")
	)
	(segment
		(start 349.710248 -221.083124)
		(end 349.710248 -219.017342)
		(width 0.14224)
		(layer "In15.Cu")
		(net "GMI_CPU0_G1_CPU1_G3_TX_DN<8>")
	)
	(segment
		(start 120.086628 -232.798874)
		(end 120.047512 -232.821734)
		(width 0.1143)
		(layer "In15.Cu")
		(net "GMI_CPU0_G1_CPU1_G3_TX_DN<8>")
	)
	(segment
		(start 351.448116 -240.92154)
		(end 351.447862 -240.92154)
		(width 0.1143)
		(layer "In15.Cu")
		(net "GMI_CPU0_G1_CPU1_G3_TX_DN<8>")
	)
	(segment
		(start 351.46996 -241.554)
		(end 351.479866 -241.548412)
		(width 0.1143)
		(layer "In15.Cu")
		(net "GMI_CPU0_G1_CPU1_G3_TX_DN<8>")
	)
	(segment
		(start 351.448116 -237.681516)
		(end 351.447862 -237.681516)
		(width 0.1143)
		(layer "In15.Cu")
		(net "GMI_CPU0_G1_CPU1_G3_TX_DN<8>")
	)
	(segment
		(start 351.449894 -237.682532)
		(end 351.448878 -237.682024)
		(width 0.1143)
		(layer "In15.Cu")
		(net "GMI_CPU0_G1_CPU1_G3_TX_DN<8>")
	)
	(segment
		(start 120.047512 -239.946942)
		(end 120.086628 -239.969802)
		(width 0.1143)
		(layer "In15.Cu")
		(net "GMI_CPU0_G1_CPU1_G3_TX_DN<8>")
	)
	(segment
		(start 120.047512 -226.34194)
		(end 120.017032 -226.35972)
		(width 0.1143)
		(layer "In15.Cu")
		(net "GMI_CPU0_G1_CPU1_G3_TX_DN<8>")
	)
	(segment
		(start 351.414588 -230.246174)
		(end 351.416112 -230.245158)
		(width 0.1143)
		(layer "In15.Cu")
		(net "GMI_CPU0_G1_CPU1_G3_TX_DN<8>")
	)
	(segment
		(start 120.017032 -226.96932)
		(end 120.047512 -226.9871)
		(width 0.1143)
		(layer "In15.Cu")
		(net "GMI_CPU0_G1_CPU1_G3_TX_DN<8>")
	)
	(segment
		(start 120.047512 -229.581964)
		(end 120.015 -229.60076)
		(width 0.1143)
		(layer "In15.Cu")
		(net "GMI_CPU0_G1_CPU1_G3_TX_DN<8>")
	)
	(segment
		(start 120.086628 -227.939092)
		(end 120.047512 -227.961952)
		(width 0.1143)
		(layer "In15.Cu")
		(net "GMI_CPU0_G1_CPU1_G3_TX_DN<8>")
	)
	(arc
		(start 120.017032 -232.839514)
		(mid 119.860055 -233.144314)
		(end 120.017032 -233.449114)
		(width 0.1143)
		(layer "In15.Cu")
		(net "GMI_CPU0_G1_CPU1_G3_TX_DN<8>")
	)
	(arc
		(start 120.017032 -242.559586)
		(mid 119.860055 -242.864386)
		(end 120.017032 -243.169186)
		(width 0.1143)
		(layer "In15.Cu")
		(net "GMI_CPU0_G1_CPU1_G3_TX_DN<8>")
	)
	(arc
		(start 351.411794 -244.140482)
		(mid 351.403616 -244.134839)
		(end 351.395538 -244.129052)
		(width 0.1143)
		(layer "In15.Cu")
		(net "GMI_CPU0_G1_CPU1_G3_TX_DN<8>")
	)
	(arc
		(start 351.16135 -225.826828)
		(mid 351.108466 -225.679618)
		(end 351.014538 -225.55454)
		(width 0.1143)
		(layer "In15.Cu")
		(net "GMI_CPU0_G1_CPU1_G3_TX_DN<8>")
	)
	(arc
		(start 120.017032 -224.739708)
		(mid 119.860055 -225.044508)
		(end 120.017032 -225.349308)
		(width 0.1143)
		(layer "In15.Cu")
		(net "GMI_CPU0_G1_CPU1_G3_TX_DN<8>")
	)
	(arc
		(start 351.437956 -231.195372)
		(mid 351.235892 -230.989975)
		(end 351.165922 -230.710486)
		(width 0.1143)
		(layer "In15.Cu")
		(net "GMI_CPU0_G1_CPU1_G3_TX_DN<8>")
	)
	(arc
		(start 350.225868 -222.614236)
		(mid 350.184613 -222.443265)
		(end 350.069912 -222.309944)
		(width 0.1143)
		(layer "In15.Cu")
		(net "GMI_CPU0_G1_CPU1_G3_TX_DN<8>")
	)
	(arc
		(start 351.479866 -228.58857)
		(mid 351.635794 -228.284278)
		(end 351.479866 -227.979986)
		(width 0.1143)
		(layer "In15.Cu")
		(net "GMI_CPU0_G1_CPU1_G3_TX_DN<8>")
	)
	(arc
		(start 351.411794 -234.42041)
		(mid 351.404644 -234.415512)
		(end 351.39757 -234.410504)
		(width 0.1143)
		(layer "In15.Cu")
		(net "GMI_CPU0_G1_CPU1_G3_TX_DN<8>")
	)
	(arc
		(start 351.395538 -231.87914)
		(mid 351.403616 -231.873354)
		(end 351.411794 -231.86771)
		(width 0.1143)
		(layer "In15.Cu")
		(net "GMI_CPU0_G1_CPU1_G3_TX_DN<8>")
	)
	(arc
		(start 120.084088 -230.248206)
		(mid 120.26474 -230.450951)
		(end 120.32996 -230.71455)
		(width 0.1143)
		(layer "In15.Cu")
		(net "GMI_CPU0_G1_CPU1_G3_TX_DN<8>")
	)
	(arc
		(start 120.32996 -230.71455)
		(mid 120.265445 -230.976769)
		(end 120.086628 -231.179116)
		(width 0.1143)
		(layer "In15.Cu")
		(net "GMI_CPU0_G1_CPU1_G3_TX_DN<8>")
	)
	(arc
		(start 351.395538 -232.788968)
		(mid 351.172654 -232.334054)
		(end 351.395538 -231.87914)
		(width 0.1143)
		(layer "In15.Cu")
		(net "GMI_CPU0_G1_CPU1_G3_TX_DN<8>")
	)
	(arc
		(start 351.479866 -243.168424)
		(mid 351.635794 -242.864132)
		(end 351.479866 -242.55984)
		(width 0.1143)
		(layer "In15.Cu")
		(net "GMI_CPU0_G1_CPU1_G3_TX_DN<8>")
	)
	(arc
		(start 351.479866 -226.968558)
		(mid 351.635794 -226.664266)
		(end 351.479866 -226.359974)
		(width 0.1143)
		(layer "In15.Cu")
		(net "GMI_CPU0_G1_CPU1_G3_TX_DN<8>")
	)
	(arc
		(start 351.39757 -234.410504)
		(mid 351.170187 -233.954066)
		(end 351.39757 -233.497628)
		(width 0.1143)
		(layer "In15.Cu")
		(net "GMI_CPU0_G1_CPU1_G3_TX_DN<8>")
	)
	(arc
		(start 351.397824 -230.257604)
		(mid 351.406154 -230.251813)
		(end 351.414588 -230.246174)
		(width 0.1143)
		(layer "In15.Cu")
		(net "GMI_CPU0_G1_CPU1_G3_TX_DN<8>")
	)
	(arc
		(start 120.017032 -244.179598)
		(mid 119.919267 -244.282574)
		(end 119.866918 -244.414548)
		(width 0.1143)
		(layer "In15.Cu")
		(net "GMI_CPU0_G1_CPU1_G3_TX_DN<8>")
	)
	(arc
		(start 120.017032 -223.119696)
		(mid 119.860055 -223.424496)
		(end 120.017032 -223.729296)
		(width 0.1143)
		(layer "In15.Cu")
		(net "GMI_CPU0_G1_CPU1_G3_TX_DN<8>")
	)
	(arc
		(start 351.447862 -242.541552)
		(mid 351.167435 -242.054316)
		(end 351.447862 -241.566954)
		(width 0.1143)
		(layer "In15.Cu")
		(net "GMI_CPU0_G1_CPU1_G3_TX_DN<8>")
	)
	(arc
		(start 351.165922 -230.710486)
		(mid 351.229679 -230.457323)
		(end 351.397824 -230.257604)
		(width 0.1143)
		(layer "In15.Cu")
		(net "GMI_CPU0_G1_CPU1_G3_TX_DN<8>")
	)
	(arc
		(start 120.086628 -231.869742)
		(mid 120.329955 -232.334308)
		(end 120.086628 -232.798874)
		(width 0.1143)
		(layer "In15.Cu")
		(net "GMI_CPU0_G1_CPU1_G3_TX_DN<8>")
	)
	(arc
		(start 120.015 -231.220772)
		(mid 119.901071 -231.353919)
		(end 119.86006 -231.524302)
		(width 0.1143)
		(layer "In15.Cu")
		(net "GMI_CPU0_G1_CPU1_G3_TX_DN<8>")
	)
	(arc
		(start 351.014538 -225.55454)
		(mid 351.009994 -225.550949)
		(end 351.005394 -225.547428)
		(width 0.1143)
		(layer "In15.Cu")
		(net "GMI_CPU0_G1_CPU1_G3_TX_DN<8>")
	)
	(arc
		(start 351.447862 -240.92154)
		(mid 351.167435 -240.434304)
		(end 351.447862 -239.946942)
		(width 0.1143)
		(layer "In15.Cu")
		(net "GMI_CPU0_G1_CPU1_G3_TX_DN<8>")
	)
	(arc
		(start 351.395538 -227.929186)
		(mid 351.172654 -227.474272)
		(end 351.395538 -227.019358)
		(width 0.1143)
		(layer "In15.Cu")
		(net "GMI_CPU0_G1_CPU1_G3_TX_DN<8>")
	)
	(arc
		(start 351.635822 -229.904036)
		(mid 351.59506 -229.734152)
		(end 351.481644 -229.601268)
		(width 0.1143)
		(layer "In15.Cu")
		(net "GMI_CPU0_G1_CPU1_G3_TX_DN<8>")
	)
	(arc
		(start 351.395538 -244.129052)
		(mid 351.172654 -243.674138)
		(end 351.395538 -243.219224)
		(width 0.1143)
		(layer "In15.Cu")
		(net "GMI_CPU0_G1_CPU1_G3_TX_DN<8>")
	)
	(arc
		(start 119.86006 -231.524302)
		(mid 119.901609 -231.695724)
		(end 120.017032 -231.829102)
		(width 0.1143)
		(layer "In15.Cu")
		(net "GMI_CPU0_G1_CPU1_G3_TX_DN<8>")
	)
	(arc
		(start 351.447862 -239.301528)
		(mid 351.167435 -238.814292)
		(end 351.447862 -238.32693)
		(width 0.1143)
		(layer "In15.Cu")
		(net "GMI_CPU0_G1_CPU1_G3_TX_DN<8>")
	)
	(arc
		(start 351.635822 -231.524048)
		(mid 351.59506 -231.354164)
		(end 351.481644 -231.22128)
		(width 0.1143)
		(layer "In15.Cu")
		(net "GMI_CPU0_G1_CPU1_G3_TX_DN<8>")
	)
	(arc
		(start 120.017032 -237.69955)
		(mid 119.860055 -238.00435)
		(end 120.017032 -238.30915)
		(width 0.1143)
		(layer "In15.Cu")
		(net "GMI_CPU0_G1_CPU1_G3_TX_DN<8>")
	)
	(arc
		(start 120.017032 -240.939574)
		(mid 119.860055 -241.244374)
		(end 120.017032 -241.549174)
		(width 0.1143)
		(layer "In15.Cu")
		(net "GMI_CPU0_G1_CPU1_G3_TX_DN<8>")
	)
	(arc
		(start 351.479866 -233.448352)
		(mid 351.635794 -233.14406)
		(end 351.479866 -232.839768)
		(width 0.1143)
		(layer "In15.Cu")
		(net "GMI_CPU0_G1_CPU1_G3_TX_DN<8>")
	)
	(arc
		(start 120.086628 -225.389948)
		(mid 120.329955 -225.854514)
		(end 120.086628 -226.31908)
		(width 0.1143)
		(layer "In15.Cu")
		(net "GMI_CPU0_G1_CPU1_G3_TX_DN<8>")
	)
	(arc
		(start 351.479866 -239.9284)
		(mid 351.635794 -239.624108)
		(end 351.479866 -239.319816)
		(width 0.1143)
		(layer "In15.Cu")
		(net "GMI_CPU0_G1_CPU1_G3_TX_DN<8>")
	)
	(arc
		(start 350.9391 -225.50882)
		(mid 350.760287 -225.30647)
		(end 350.695768 -225.044254)
		(width 0.1143)
		(layer "In15.Cu")
		(net "GMI_CPU0_G1_CPU1_G3_TX_DN<8>")
	)
	(arc
		(start 120.086628 -223.769936)
		(mid 120.329955 -224.234502)
		(end 120.086628 -224.699068)
		(width 0.1143)
		(layer "In15.Cu")
		(net "GMI_CPU0_G1_CPU1_G3_TX_DN<8>")
	)
	(arc
		(start 120.017032 -227.979732)
		(mid 119.860055 -228.284532)
		(end 120.017032 -228.589332)
		(width 0.1143)
		(layer "In15.Cu")
		(net "GMI_CPU0_G1_CPU1_G3_TX_DN<8>")
	)
	(arc
		(start 351.411794 -232.800398)
		(mid 351.403616 -232.794755)
		(end 351.395538 -232.788968)
		(width 0.1143)
		(layer "In15.Cu")
		(net "GMI_CPU0_G1_CPU1_G3_TX_DN<8>")
	)
	(arc
		(start 120.32996 -222.61449)
		(mid 120.265445 -222.876709)
		(end 120.086628 -223.079056)
		(width 0.1143)
		(layer "In15.Cu")
		(net "GMI_CPU0_G1_CPU1_G3_TX_DN<8>")
	)
	(arc
		(start 351.447862 -237.681516)
		(mid 351.167435 -237.19428)
		(end 351.447862 -236.706918)
		(width 0.1143)
		(layer "In15.Cu")
		(net "GMI_CPU0_G1_CPU1_G3_TX_DN<8>")
	)
	(arc
		(start 349.999046 -222.268796)
		(mid 349.926719 -222.209329)
		(end 349.865188 -222.138748)
		(width 0.1143)
		(layer "In15.Cu")
		(net "GMI_CPU0_G1_CPU1_G3_TX_DN<8>")
	)
	(arc
		(start 351.165922 -225.870262)
		(mid 351.164547 -225.848449)
		(end 351.16135 -225.826828)
		(width 0.1143)
		(layer "In15.Cu")
		(net "GMI_CPU0_G1_CPU1_G3_TX_DN<8>")
	)
	(arc
		(start 351.411794 -227.940616)
		(mid 351.403616 -227.934973)
		(end 351.395538 -227.929186)
		(width 0.1143)
		(layer "In15.Cu")
		(net "GMI_CPU0_G1_CPU1_G3_TX_DN<8>")
	)
	(arc
		(start 350.538796 -223.729042)
		(mid 350.695773 -223.424242)
		(end 350.538796 -223.119442)
		(width 0.1143)
		(layer "In15.Cu")
		(net "GMI_CPU0_G1_CPU1_G3_TX_DN<8>")
	)
	(arc
		(start 351.479866 -230.208328)
		(mid 351.594542 -230.074994)
		(end 351.635822 -229.904036)
		(width 0.1143)
		(layer "In15.Cu")
		(net "GMI_CPU0_G1_CPU1_G3_TX_DN<8>")
	)
	(arc
		(start 351.395538 -243.219224)
		(mid 351.403616 -243.213438)
		(end 351.411794 -243.207794)
		(width 0.1143)
		(layer "In15.Cu")
		(net "GMI_CPU0_G1_CPU1_G3_TX_DN<8>")
	)
	(arc
		(start 351.398332 -229.550976)
		(mid 351.227362 -229.350499)
		(end 351.165922 -229.094284)
		(width 0.1143)
		(layer "In15.Cu")
		(net "GMI_CPU0_G1_CPU1_G3_TX_DN<8>")
	)
	(arc
		(start 120.017032 -239.319562)
		(mid 119.860055 -239.624362)
		(end 120.017032 -239.929162)
		(width 0.1143)
		(layer "In15.Cu")
		(net "GMI_CPU0_G1_CPU1_G3_TX_DN<8>")
	)
	(arc
		(start 120.017032 -234.459526)
		(mid 119.860055 -234.764326)
		(end 120.017032 -235.069126)
		(width 0.1143)
		(layer "In15.Cu")
		(net "GMI_CPU0_G1_CPU1_G3_TX_DN<8>")
	)
	(arc
		(start 120.086628 -239.969802)
		(mid 120.329955 -240.434368)
		(end 120.086628 -240.898934)
		(width 0.1143)
		(layer "In15.Cu")
		(net "GMI_CPU0_G1_CPU1_G3_TX_DN<8>")
	)
	(arc
		(start 351.165922 -229.094284)
		(mid 351.241503 -228.812642)
		(end 351.448116 -228.606858)
		(width 0.1143)
		(layer "In15.Cu")
		(net "GMI_CPU0_G1_CPU1_G3_TX_DN<8>")
	)
	(arc
		(start 120.086628 -227.00996)
		(mid 120.329955 -227.474526)
		(end 120.086628 -227.939092)
		(width 0.1143)
		(layer "In15.Cu")
		(net "GMI_CPU0_G1_CPU1_G3_TX_DN<8>")
	)
	(arc
		(start 120.017032 -236.079538)
		(mid 119.860055 -236.384338)
		(end 120.017032 -236.689138)
		(width 0.1143)
		(layer "In15.Cu")
		(net "GMI_CPU0_G1_CPU1_G3_TX_DN<8>")
	)
	(arc
		(start 120.015 -229.60076)
		(mid 119.901071 -229.733907)
		(end 119.86006 -229.90429)
		(width 0.1143)
		(layer "In15.Cu")
		(net "GMI_CPU0_G1_CPU1_G3_TX_DN<8>")
	)
	(arc
		(start 351.479866 -235.068364)
		(mid 351.635794 -234.764072)
		(end 351.479866 -234.45978)
		(width 0.1143)
		(layer "In15.Cu")
		(net "GMI_CPU0_G1_CPU1_G3_TX_DN<8>")
	)
	(arc
		(start 351.479866 -241.548412)
		(mid 351.635794 -241.24412)
		(end 351.479866 -240.939828)
		(width 0.1143)
		(layer "In15.Cu")
		(net "GMI_CPU0_G1_CPU1_G3_TX_DN<8>")
	)
	(arc
		(start 119.86006 -229.90429)
		(mid 119.901609 -230.075712)
		(end 120.017032 -230.20909)
		(width 0.1143)
		(layer "In15.Cu")
		(net "GMI_CPU0_G1_CPU1_G3_TX_DN<8>")
	)
	(arc
		(start 351.479866 -238.308388)
		(mid 351.635794 -238.004096)
		(end 351.479866 -237.699804)
		(width 0.1143)
		(layer "In15.Cu")
		(net "GMI_CPU0_G1_CPU1_G3_TX_DN<8>")
	)
	(arc
		(start 350.4692 -224.698814)
		(mid 350.225873 -224.234248)
		(end 350.4692 -223.769682)
		(width 0.1143)
		(layer "In15.Cu")
		(net "GMI_CPU0_G1_CPU1_G3_TX_DN<8>")
	)
	(arc
		(start 350.695768 -225.044254)
		(mid 350.654219 -224.872832)
		(end 350.538796 -224.739454)
		(width 0.1143)
		(layer "In15.Cu")
		(net "GMI_CPU0_G1_CPU1_G3_TX_DN<8>")
	)
	(arc
		(start 351.411794 -229.560628)
		(mid 351.405028 -229.555851)
		(end 351.398332 -229.550976)
		(width 0.1143)
		(layer "In15.Cu")
		(net "GMI_CPU0_G1_CPU1_G3_TX_DN<8>")
	)
	(arc
		(start 350.4692 -223.078802)
		(mid 350.290387 -222.876452)
		(end 350.225868 -222.614236)
		(width 0.1143)
		(layer "In15.Cu")
		(net "GMI_CPU0_G1_CPU1_G3_TX_DN<8>")
	)
	(arc
		(start 351.479866 -231.82834)
		(mid 351.594542 -231.695006)
		(end 351.635822 -231.524048)
		(width 0.1143)
		(layer "In15.Cu")
		(net "GMI_CPU0_G1_CPU1_G3_TX_DN<8>")
	)
	(arc
		(start 351.39757 -233.497628)
		(mid 351.404643 -233.492619)
		(end 351.411794 -233.487722)
		(width 0.1143)
		(layer "In15.Cu")
		(net "GMI_CPU0_G1_CPU1_G3_TX_DN<8>")
	)
	(arc
		(start 120.017032 -226.35972)
		(mid 119.860055 -226.66452)
		(end 120.017032 -226.96932)
		(width 0.1143)
		(layer "In15.Cu")
		(net "GMI_CPU0_G1_CPU1_G3_TX_DN<8>")
	)
	(arc
		(start 120.086628 -236.729778)
		(mid 120.329955 -237.194344)
		(end 120.086628 -237.65891)
		(width 0.1143)
		(layer "In15.Cu")
		(net "GMI_CPU0_G1_CPU1_G3_TX_DN<8>")
	)
	(arc
		(start 120.086628 -243.209826)
		(mid 120.329955 -243.674392)
		(end 120.086628 -244.138958)
		(width 0.1143)
		(layer "In15.Cu")
		(net "GMI_CPU0_G1_CPU1_G3_TX_DN<8>")
	)
	(arc
		(start 351.479866 -236.688376)
		(mid 351.635794 -236.384084)
		(end 351.479866 -236.079792)
		(width 0.1143)
		(layer "In15.Cu")
		(net "GMI_CPU0_G1_CPU1_G3_TX_DN<8>")
	)
	(arc
		(start 351.395538 -227.019358)
		(mid 351.403616 -227.013572)
		(end 351.411794 -227.007928)
		(width 0.1143)
		(layer "In15.Cu")
		(net "GMI_CPU0_G1_CPU1_G3_TX_DN<8>")
	)
	(arc
		(start 120.086628 -233.489754)
		(mid 120.329955 -233.95432)
		(end 120.086628 -234.418886)
		(width 0.1143)
		(layer "In15.Cu")
		(net "GMI_CPU0_G1_CPU1_G3_TX_DN<8>")
	)
	(arc
		(start 351.411794 -226.320604)
		(mid 351.234894 -226.125041)
		(end 351.165922 -225.870516)
		(width 0.1143)
		(layer "In15.Cu")
		(net "GMI_CPU0_G1_CPU1_G3_TX_DN<8>")
	)
	(arc
		(start 119.859552 -221.804484)
		(mid 119.900807 -221.975455)
		(end 120.015508 -222.108776)
		(width 0.1143)
		(layer "In15.Cu")
		(net "GMI_CPU0_G1_CPU1_G3_TX_DN<8>")
	)
	(arc
		(start 120.086628 -238.34979)
		(mid 120.329955 -238.814356)
		(end 120.086628 -239.278922)
		(width 0.1143)
		(layer "In15.Cu")
		(net "GMI_CPU0_G1_CPU1_G3_TX_DN<8>")
	)
	(arc
		(start 120.086628 -235.109766)
		(mid 120.329955 -235.574332)
		(end 120.086628 -236.038898)
		(width 0.1143)
		(layer "In15.Cu")
		(net "GMI_CPU0_G1_CPU1_G3_TX_DN<8>")
	)
	(arc
		(start 120.086628 -228.629972)
		(mid 120.329955 -229.094538)
		(end 120.086628 -229.559104)
		(width 0.1143)
		(layer "In15.Cu")
		(net "GMI_CPU0_G1_CPU1_G3_TX_DN<8>")
	)
	(arc
		(start 349.865188 -222.138748)
		(mid 349.783897 -221.980201)
		(end 349.755968 -221.80423)
		(width 0.1143)
		(layer "In15.Cu")
		(net "GMI_CPU0_G1_CPU1_G3_TX_DN<8>")
	)
	(arc
		(start 120.087644 -222.150686)
		(mid 120.265709 -222.352863)
		(end 120.32996 -222.61449)
		(width 0.1143)
		(layer "In15.Cu")
		(net "GMI_CPU0_G1_CPU1_G3_TX_DN<8>")
	)
	(arc
		(start 351.447862 -236.061504)
		(mid 351.167435 -235.574268)
		(end 351.447862 -235.086906)
		(width 0.1143)
		(layer "In15.Cu")
		(net "GMI_CPU0_G1_CPU1_G3_TX_DN<8>")
	)
	(arc
		(start 120.086628 -241.589814)
		(mid 120.329955 -242.05438)
		(end 120.086628 -242.518946)
		(width 0.1143)
		(layer "In15.Cu")
		(net "GMI_CPU0_G1_CPU1_G3_TX_DN<8>")
	)
	(arc
		(start 351.628964 -244.414294)
		(mid 351.576915 -244.282775)
		(end 351.479866 -244.179852)
		(width 0.1143)
		(layer "In15.Cu")
		(net "GMI_CPU0_G1_CPU1_G3_TX_DN<8>")
	)
	(segment
		(start 351.728024 -247.990106)
		(end 351.261172 -247.724168)
		(width 0.12954)
		(layer "F.Cu")
		(net "GMI_CPU0_G1_CPU1_G3_TX_DN<7>")
	)
	(segment
		(start 119.767858 -247.99036)
		(end 120.23471 -247.724422)
		(width 0.12954)
		(layer "F.Cu")
		(net "GMI_CPU0_G1_CPU1_G3_TX_DN<7>")
	)
	(segment
		(start 352.388932 -235.086144)
		(end 352.38817 -235.086652)
		(width 0.1143)
		(layer "In15.Cu")
		(net "GMI_CPU0_G1_CPU1_G3_TX_DN<7>")
	)
	(segment
		(start 151.717248 -190.0174)
		(end 151.910288 -190.03645)
		(width 0.14224)
		(layer "In15.Cu")
		(net "GMI_CPU0_G1_CPU1_G3_TX_DN<7>")
	)
	(segment
		(start 352.373184 -237.672626)
		(end 352.37547 -237.67415)
		(width 0.1143)
		(layer "In15.Cu")
		(net "GMI_CPU0_G1_CPU1_G3_TX_DN<7>")
	)
	(segment
		(start 352.390202 -234.442762)
		(end 352.391726 -234.443524)
		(width 0.1143)
		(layer "In15.Cu")
		(net "GMI_CPU0_G1_CPU1_G3_TX_DN<7>")
	)
	(segment
		(start 352.38817 -234.441492)
		(end 352.388932 -234.442)
		(width 0.1143)
		(layer "In15.Cu")
		(net "GMI_CPU0_G1_CPU1_G3_TX_DN<7>")
	)
	(segment
		(start 352.38817 -228.606858)
		(end 352.349054 -228.629718)
		(width 0.1143)
		(layer "In15.Cu")
		(net "GMI_CPU0_G1_CPU1_G3_TX_DN<7>")
	)
	(segment
		(start 119.107712 -238.32693)
		(end 119.10695 -238.326422)
		(width 0.1143)
		(layer "In15.Cu")
		(net "GMI_CPU0_G1_CPU1_G3_TX_DN<7>")
	)
	(segment
		(start 352.376486 -242.534694)
		(end 352.377756 -242.535456)
		(width 0.1143)
		(layer "In15.Cu")
		(net "GMI_CPU0_G1_CPU1_G3_TX_DN<7>")
	)
	(segment
		(start 119.107712 -246.42699)
		(end 119.10695 -246.426482)
		(width 0.1143)
		(layer "In15.Cu")
		(net "GMI_CPU0_G1_CPU1_G3_TX_DN<7>")
	)
	(segment
		(start 352.377756 -237.67542)
		(end 352.37928 -237.676436)
		(width 0.1143)
		(layer "In15.Cu")
		(net "GMI_CPU0_G1_CPU1_G3_TX_DN<7>")
	)
	(segment
		(start 352.38563 -237.679992)
		(end 352.387154 -237.681008)
		(width 0.1143)
		(layer "In15.Cu")
		(net "GMI_CPU0_G1_CPU1_G3_TX_DN<7>")
	)
	(segment
		(start 352.377756 -244.81282)
		(end 352.376994 -244.813328)
		(width 0.1143)
		(layer "In15.Cu")
		(net "GMI_CPU0_G1_CPU1_G3_TX_DN<7>")
	)
	(segment
		(start 352.396806 -240.926366)
		(end 352.41992 -240.939828)
		(width 0.1143)
		(layer "In15.Cu")
		(net "GMI_CPU0_G1_CPU1_G3_TX_DN<7>")
	)
	(segment
		(start 352.387154 -235.08716)
		(end 352.38563 -235.088176)
		(width 0.1143)
		(layer "In15.Cu")
		(net "GMI_CPU0_G1_CPU1_G3_TX_DN<7>")
	)
	(segment
		(start 119.107712 -227.961952)
		(end 119.147336 -227.939092)
		(width 0.1143)
		(layer "In15.Cu")
		(net "GMI_CPU0_G1_CPU1_G3_TX_DN<7>")
	)
	(segment
		(start 119.105426 -226.34321)
		(end 119.106188 -226.342702)
		(width 0.1143)
		(layer "In15.Cu")
		(net "GMI_CPU0_G1_CPU1_G3_TX_DN<7>")
	)
	(segment
		(start 352.380042 -235.091478)
		(end 352.379026 -235.091986)
		(width 0.1143)
		(layer "In15.Cu")
		(net "GMI_CPU0_G1_CPU1_G3_TX_DN<7>")
	)
	(segment
		(start 352.388424 -226.986846)
		(end 352.349308 -227.009706)
		(width 0.1143)
		(layer "In15.Cu")
		(net "GMI_CPU0_G1_CPU1_G3_TX_DN<7>")
	)
	(segment
		(start 352.377756 -242.535456)
		(end 352.37928 -242.536472)
		(width 0.1143)
		(layer "In15.Cu")
		(net "GMI_CPU0_G1_CPU1_G3_TX_DN<7>")
	)
	(segment
		(start 308.692804 -182.186834)
		(end 315.301122 -185.927492)
		(width 0.14224)
		(layer "In15.Cu")
		(net "GMI_CPU0_G1_CPU1_G3_TX_DN<7>")
	)
	(segment
		(start 352.396806 -234.446318)
		(end 352.41992 -234.45978)
		(width 0.1143)
		(layer "In15.Cu")
		(net "GMI_CPU0_G1_CPU1_G3_TX_DN<7>")
	)
	(segment
		(start 119.10695 -228.606604)
		(end 119.10568 -228.605842)
		(width 0.1143)
		(layer "In15.Cu")
		(net "GMI_CPU0_G1_CPU1_G3_TX_DN<7>")
	)
	(segment
		(start 352.379026 -243.192046)
		(end 352.377756 -243.192808)
		(width 0.1143)
		(layer "In15.Cu")
		(net "GMI_CPU0_G1_CPU1_G3_TX_DN<7>")
	)
	(segment
		(start 352.38817 -236.061504)
		(end 352.388932 -236.062012)
		(width 0.1143)
		(layer "In15.Cu")
		(net "GMI_CPU0_G1_CPU1_G3_TX_DN<7>")
	)
	(segment
		(start 119.16537 -225.403156)
		(end 119.147082 -225.389948)
		(width 0.1143)
		(layer "In15.Cu")
		(net "GMI_CPU0_G1_CPU1_G3_TX_DN<7>")
	)
	(segment
		(start 119.110506 -223.748854)
		(end 119.107712 -223.747076)
		(width 0.1143)
		(layer "In15.Cu")
		(net "GMI_CPU0_G1_CPU1_G3_TX_DN<7>")
	)
	(segment
		(start 352.391726 -234.443524)
		(end 352.394266 -234.445048)
		(width 0.1143)
		(layer "In15.Cu")
		(net "GMI_CPU0_G1_CPU1_G3_TX_DN<7>")
	)
	(segment
		(start 352.377756 -245.77548)
		(end 352.37928 -245.776496)
		(width 0.1143)
		(layer "In15.Cu")
		(net "GMI_CPU0_G1_CPU1_G3_TX_DN<7>")
	)
	(segment
		(start 352.41992 -244.788436)
		(end 352.390202 -244.805454)
		(width 0.1143)
		(layer "In15.Cu")
		(net "GMI_CPU0_G1_CPU1_G3_TX_DN<7>")
	)
	(segment
		(start 351.63633 -221.579694)
		(end 351.636076 -221.579948)
		(width 0.1143)
		(layer "In15.Cu")
		(net "GMI_CPU0_G1_CPU1_G3_TX_DN<7>")
	)
	(segment
		(start 352.376994 -243.193316)
		(end 352.349054 -243.209572)
		(width 0.1143)
		(layer "In15.Cu")
		(net "GMI_CPU0_G1_CPU1_G3_TX_DN<7>")
	)
	(segment
		(start 119.170958 -222.167196)
		(end 119.146574 -222.14967)
		(width 0.1143)
		(layer "In15.Cu")
		(net "GMI_CPU0_G1_CPU1_G3_TX_DN<7>")
	)
	(segment
		(start 153.804112 -188.473588)
		(end 154.12847 -188.20765)
		(width 0.14224)
		(layer "In15.Cu")
		(net "GMI_CPU0_G1_CPU1_G3_TX_DN<7>")
	)
	(segment
		(start 119.147336 -243.209826)
		(end 119.110252 -243.188744)
		(width 0.1143)
		(layer "In15.Cu")
		(net "GMI_CPU0_G1_CPU1_G3_TX_DN<7>")
	)
	(segment
		(start 351.919032 -225.532188)
		(end 351.95002 -225.549968)
		(width 0.1143)
		(layer "In15.Cu")
		(net "GMI_CPU0_G1_CPU1_G3_TX_DN<7>")
	)
	(segment
		(start 151.387302 -190.28791)
		(end 151.717248 -190.0174)
		(width 0.14224)
		(layer "In15.Cu")
		(net "GMI_CPU0_G1_CPU1_G3_TX_DN<7>")
	)
	(segment
		(start 118.92661 -219.131134)
		(end 121.87682 -214.089742)
		(width 0.14224)
		(layer "In15.Cu")
		(net "GMI_CPU0_G1_CPU1_G3_TX_DN<7>")
	)
	(segment
		(start 352.390202 -239.945418)
		(end 352.388932 -239.94618)
		(width 0.1143)
		(layer "In15.Cu")
		(net "GMI_CPU0_G1_CPU1_G3_TX_DN<7>")
	)
	(segment
		(start 352.379026 -231.851962)
		(end 352.377756 -231.852724)
		(width 0.1143)
		(layer "In15.Cu")
		(net "GMI_CPU0_G1_CPU1_G3_TX_DN<7>")
	)
	(segment
		(start 351.601278 -221.387416)
		(end 351.63633 -221.422468)
		(width 0.1143)
		(layer "In15.Cu")
		(net "GMI_CPU0_G1_CPU1_G3_TX_DN<7>")
	)
	(segment
		(start 150.496016 -191.196214)
		(end 150.515066 -191.003174)
		(width 0.14224)
		(layer "In15.Cu")
		(net "GMI_CPU0_G1_CPU1_G3_TX_DN<7>")
	)
	(segment
		(start 119.10568 -244.163088)
		(end 119.10695 -244.162326)
		(width 0.1143)
		(layer "In15.Cu")
		(net "GMI_CPU0_G1_CPU1_G3_TX_DN<7>")
	)
	(segment
		(start 119.103648 -242.544092)
		(end 119.10441 -242.543584)
		(width 0.1143)
		(layer "In15.Cu")
		(net "GMI_CPU0_G1_CPU1_G3_TX_DN<7>")
	)
	(segment
		(start 119.107712 -232.821734)
		(end 119.14759 -232.798874)
		(width 0.1143)
		(layer "In15.Cu")
		(net "GMI_CPU0_G1_CPU1_G3_TX_DN<7>")
	)
	(segment
		(start 352.394266 -234.445048)
		(end 352.396806 -234.446318)
		(width 0.1143)
		(layer "In15.Cu")
		(net "GMI_CPU0_G1_CPU1_G3_TX_DN<7>")
	)
	(segment
		(start 119.105172 -236.705394)
		(end 119.076724 -236.689138)
		(width 0.1143)
		(layer "In15.Cu")
		(net "GMI_CPU0_G1_CPU1_G3_TX_DN<7>")
	)
	(segment
		(start 119.10568 -226.98583)
		(end 119.10314 -226.98456)
		(width 0.1143)
		(layer "In15.Cu")
		(net "GMI_CPU0_G1_CPU1_G3_TX_DN<7>")
	)
	(segment
		(start 352.388424 -226.341686)
		(end 352.418904 -226.359466)
		(width 0.1143)
		(layer "In15.Cu")
		(net "GMI_CPU0_G1_CPU1_G3_TX_DN<7>")
	)
	(segment
		(start 352.387154 -246.427244)
		(end 352.38563 -246.42826)
		(width 0.1143)
		(layer "In15.Cu")
		(net "GMI_CPU0_G1_CPU1_G3_TX_DN<7>")
	)
	(segment
		(start 119.162068 -231.880664)
		(end 119.14759 -231.869742)
		(width 0.1143)
		(layer "In15.Cu")
		(net "GMI_CPU0_G1_CPU1_G3_TX_DN<7>")
	)
	(segment
		(start 352.38563 -236.708188)
		(end 352.384614 -236.708696)
		(width 0.1143)
		(layer "In15.Cu")
		(net "GMI_CPU0_G1_CPU1_G3_TX_DN<7>")
	)
	(segment
		(start 151.910288 -190.03645)
		(end 152.240488 -189.765686)
		(width 0.14224)
		(layer "In15.Cu")
		(net "GMI_CPU0_G1_CPU1_G3_TX_DN<7>")
	)
	(segment
		(start 347.826076 -212.596984)
		(end 351.555558 -220.47835)
		(width 0.14224)
		(layer "In15.Cu")
		(net "GMI_CPU0_G1_CPU1_G3_TX_DN<7>")
	)
	(segment
		(start 351.91319 -225.528632)
		(end 351.914714 -225.529648)
		(width 0.1143)
		(layer "In15.Cu")
		(net "GMI_CPU0_G1_CPU1_G3_TX_DN<7>")
	)
	(segment
		(start 352.349308 -226.318826)
		(end 352.388424 -226.341686)
		(width 0.1143)
		(layer "In15.Cu")
		(net "GMI_CPU0_G1_CPU1_G3_TX_DN<7>")
	)
	(segment
		(start 352.376994 -235.093256)
		(end 352.349054 -235.109512)
		(width 0.1143)
		(layer "In15.Cu")
		(net "GMI_CPU0_G1_CPU1_G3_TX_DN<7>")
	)
	(segment
		(start 351.555558 -220.47835)
		(end 351.555558 -221.083124)
		(width 0.14224)
		(layer "In15.Cu")
		(net "GMI_CPU0_G1_CPU1_G3_TX_DN<7>")
	)
	(segment
		(start 119.107712 -233.466894)
		(end 119.10695 -233.466386)
		(width 0.1143)
		(layer "In15.Cu")
		(net "GMI_CPU0_G1_CPU1_G3_TX_DN<7>")
	)
	(segment
		(start 119.106188 -226.342702)
		(end 119.147082 -226.31908)
		(width 0.1143)
		(layer "In15.Cu")
		(net "GMI_CPU0_G1_CPU1_G3_TX_DN<7>")
	)
	(segment
		(start 119.107712 -230.22687)
		(end 119.10695 -230.226362)
		(width 0.1143)
		(layer "In15.Cu")
		(net "GMI_CPU0_G1_CPU1_G3_TX_DN<7>")
	)
	(segment
		(start 152.240488 -189.765686)
		(end 152.259538 -189.572646)
		(width 0.14224)
		(layer "In15.Cu")
		(net "GMI_CPU0_G1_CPU1_G3_TX_DN<7>")
	)
	(segment
		(start 352.382074 -235.090208)
		(end 352.380804 -235.09097)
		(width 0.1143)
		(layer "In15.Cu")
		(net "GMI_CPU0_G1_CPU1_G3_TX_DN<7>")
	)
	(segment
		(start 352.41992 -246.408448)
		(end 352.390202 -246.425466)
		(width 0.1143)
		(layer "In15.Cu")
		(net "GMI_CPU0_G1_CPU1_G3_TX_DN<7>")
	)
	(segment
		(start 351.641918 -247.641364)
		(end 351.559114 -247.724168)
		(width 0.1143)
		(layer "In15.Cu")
		(net "GMI_CPU0_G1_CPU1_G3_TX_DN<7>")
	)
	(segment
		(start 352.379026 -236.711998)
		(end 352.377756 -236.71276)
		(width 0.1143)
		(layer "In15.Cu")
		(net "GMI_CPU0_G1_CPU1_G3_TX_DN<7>")
	)
	(segment
		(start 119.101616 -223.74352)
		(end 119.075962 -223.728788)
		(width 0.1143)
		(layer "In15.Cu")
		(net "GMI_CPU0_G1_CPU1_G3_TX_DN<7>")
	)
	(segment
		(start 352.41992 -236.688376)
		(end 352.390202 -236.705394)
		(width 0.1143)
		(layer "In15.Cu")
		(net "GMI_CPU0_G1_CPU1_G3_TX_DN<7>")
	)
	(segment
		(start 352.38563 -246.42826)
		(end 352.384614 -246.428768)
		(width 0.1143)
		(layer "In15.Cu")
		(net "GMI_CPU0_G1_CPU1_G3_TX_DN<7>")
	)
	(segment
		(start 153.161492 -189.000638)
		(end 153.179526 -188.818266)
		(width 0.14224)
		(layer "In15.Cu")
		(net "GMI_CPU0_G1_CPU1_G3_TX_DN<7>")
	)
	(segment
		(start 352.376994 -244.813328)
		(end 352.349054 -244.829584)
		(width 0.1143)
		(layer "In15.Cu")
		(net "GMI_CPU0_G1_CPU1_G3_TX_DN<7>")
	)
	(segment
		(start 153.179526 -188.818266)
		(end 153.621994 -188.455554)
		(width 0.14224)
		(layer "In15.Cu")
		(net "GMI_CPU0_G1_CPU1_G3_TX_DN<7>")
	)
	(segment
		(start 119.101616 -241.563398)
		(end 119.075962 -241.548666)
		(width 0.1143)
		(layer "In15.Cu")
		(net "GMI_CPU0_G1_CPU1_G3_TX_DN<7>")
	)
	(segment
		(start 352.384614 -244.808756)
		(end 352.38309 -244.809772)
		(width 0.1143)
		(layer "In15.Cu")
		(net "GMI_CPU0_G1_CPU1_G3_TX_DN<7>")
	)
	(segment
		(start 352.380042 -231.851454)
		(end 352.379026 -231.851962)
		(width 0.1143)
		(layer "In15.Cu")
		(net "GMI_CPU0_G1_CPU1_G3_TX_DN<7>")
	)
	(segment
		(start 352.349054 -229.55885)
		(end 352.38817 -229.58171)
		(width 0.1143)
		(layer "In15.Cu")
		(net "GMI_CPU0_G1_CPU1_G3_TX_DN<7>")
	)
	(segment
		(start 119.10568 -239.303052)
		(end 119.10695 -239.30229)
		(width 0.1143)
		(layer "In15.Cu")
		(net "GMI_CPU0_G1_CPU1_G3_TX_DN<7>")
	)
	(segment
		(start 352.38563 -245.780052)
		(end 352.387154 -245.781068)
		(width 0.1143)
		(layer "In15.Cu")
		(net "GMI_CPU0_G1_CPU1_G3_TX_DN<7>")
	)
	(segment
		(start 352.381058 -242.537488)
		(end 352.38563 -242.540028)
		(width 0.1143)
		(layer "In15.Cu")
		(net "GMI_CPU0_G1_CPU1_G3_TX_DN<7>")
	)
	(segment
		(start 352.387154 -242.541044)
		(end 352.38817 -242.541552)
		(width 0.1143)
		(layer "In15.Cu")
		(net "GMI_CPU0_G1_CPU1_G3_TX_DN<7>")
	)
	(segment
		(start 352.38309 -233.469688)
		(end 352.382074 -233.470196)
		(width 0.1143)
		(layer "In15.Cu")
		(net "GMI_CPU0_G1_CPU1_G3_TX_DN<7>")
	)
	(segment
		(start 119.107712 -223.747076)
		(end 119.10695 -223.746568)
		(width 0.1143)
		(layer "In15.Cu")
		(net "GMI_CPU0_G1_CPU1_G3_TX_DN<7>")
	)
	(segment
		(start 352.38309 -235.0897)
		(end 352.382074 -235.090208)
		(width 0.1143)
		(layer "In15.Cu")
		(net "GMI_CPU0_G1_CPU1_G3_TX_DN<7>")
	)
	(segment
		(start 352.388932 -236.706156)
		(end 352.38817 -236.706664)
		(width 0.1143)
		(layer "In15.Cu")
		(net "GMI_CPU0_G1_CPU1_G3_TX_DN<7>")
	)
	(segment
		(start 352.37547 -237.67415)
		(end 352.376486 -237.674658)
		(width 0.1143)
		(layer "In15.Cu")
		(net "GMI_CPU0_G1_CPU1_G3_TX_DN<7>")
	)
	(segment
		(start 119.10695 -245.782338)
		(end 119.107712 -245.78183)
		(width 0.1143)
		(layer "In15.Cu")
		(net "GMI_CPU0_G1_CPU1_G3_TX_DN<7>")
	)
	(segment
		(start 119.101616 -243.18341)
		(end 119.075962 -243.168678)
		(width 0.1143)
		(layer "In15.Cu")
		(net "GMI_CPU0_G1_CPU1_G3_TX_DN<7>")
	)
	(segment
		(start 119.10568 -243.185696)
		(end 119.10314 -243.184426)
		(width 0.1143)
		(layer "In15.Cu")
		(net "GMI_CPU0_G1_CPU1_G3_TX_DN<7>")
	)
	(segment
		(start 119.107712 -225.367088)
		(end 119.10695 -225.36658)
		(width 0.1143)
		(layer "In15.Cu")
		(net "GMI_CPU0_G1_CPU1_G3_TX_DN<7>")
	)
	(segment
		(start 119.075962 -240.940082)
		(end 119.10568 -240.923064)
		(width 0.1143)
		(layer "In15.Cu")
		(net "GMI_CPU0_G1_CPU1_G3_TX_DN<7>")
	)
	(segment
		(start 352.382074 -233.470196)
		(end 352.380804 -233.470958)
		(width 0.1143)
		(layer "In15.Cu")
		(net "GMI_CPU0_G1_CPU1_G3_TX_DN<7>")
	)
	(segment
		(start 352.390202 -231.845358)
		(end 352.388932 -231.84612)
		(width 0.1143)
		(layer "In15.Cu")
		(net "GMI_CPU0_G1_CPU1_G3_TX_DN<7>")
	)
	(segment
		(start 352.355912 -244.142768)
		(end 352.356674 -244.143276)
		(width 0.1143)
		(layer "In15.Cu")
		(net "GMI_CPU0_G1_CPU1_G3_TX_DN<7>")
	)
	(segment
		(start 352.356674 -232.803192)
		(end 352.38817 -232.82148)
		(width 0.1143)
		(layer "In15.Cu")
		(net "GMI_CPU0_G1_CPU1_G3_TX_DN<7>")
	)
	(segment
		(start 352.384614 -236.708696)
		(end 352.38309 -236.709712)
		(width 0.1143)
		(layer "In15.Cu")
		(net "GMI_CPU0_G1_CPU1_G3_TX_DN<7>")
	)
	(segment
		(start 119.147082 -242.518946)
		(end 119.16537 -242.505992)
		(width 0.1143)
		(layer "In15.Cu")
		(net "GMI_CPU0_G1_CPU1_G3_TX_DN<7>")
	)
	(segment
		(start 119.075962 -239.32007)
		(end 119.10568 -239.303052)
		(width 0.1143)
		(layer "In15.Cu")
		(net "GMI_CPU0_G1_CPU1_G3_TX_DN<7>")
	)
	(segment
		(start 119.10568 -237.68304)
		(end 119.10695 -237.682278)
		(width 0.1143)
		(layer "In15.Cu")
		(net "GMI_CPU0_G1_CPU1_G3_TX_DN<7>")
	)
	(segment
		(start 352.379026 -241.572034)
		(end 352.377756 -241.572796)
		(width 0.1143)
		(layer "In15.Cu")
		(net "GMI_CPU0_G1_CPU1_G3_TX_DN<7>")
	)
	(segment
		(start 352.37928 -242.536472)
		(end 352.381058 -242.537488)
		(width 0.1143)
		(layer "In15.Cu")
		(net "GMI_CPU0_G1_CPU1_G3_TX_DN<7>")
	)
	(segment
		(start 352.391726 -236.063536)
		(end 352.394266 -236.06506)
		(width 0.1143)
		(layer "In15.Cu")
		(net "GMI_CPU0_G1_CPU1_G3_TX_DN<7>")
	)
	(segment
		(start 119.10314 -244.804438)
		(end 119.101616 -244.803422)
		(width 0.1143)
		(layer "In15.Cu")
		(net "GMI_CPU0_G1_CPU1_G3_TX_DN<7>")
	)
	(segment
		(start 119.10568 -228.605842)
		(end 119.10314 -228.604572)
		(width 0.1143)
		(layer "In15.Cu")
		(net "GMI_CPU0_G1_CPU1_G3_TX_DN<7>")
	)
	(segment
		(start 352.381058 -245.777512)
		(end 352.38563 -245.780052)
		(width 0.1143)
		(layer "In15.Cu")
		(net "GMI_CPU0_G1_CPU1_G3_TX_DN<7>")
	)
	(segment
		(start 352.387154 -237.681008)
		(end 352.38817 -237.681516)
		(width 0.1143)
		(layer "In15.Cu")
		(net "GMI_CPU0_G1_CPU1_G3_TX_DN<7>")
	)
	(segment
		(start 352.380042 -244.81155)
		(end 352.379026 -244.812058)
		(width 0.1143)
		(layer "In15.Cu")
		(net "GMI_CPU0_G1_CPU1_G3_TX_DN<7>")
	)
	(segment
		(start 352.382074 -243.190268)
		(end 352.380804 -243.19103)
		(width 0.1143)
		(layer "In15.Cu")
		(net "GMI_CPU0_G1_CPU1_G3_TX_DN<7>")
	)
	(segment
		(start 119.10568 -223.103186)
		(end 119.10695 -223.102424)
		(width 0.1143)
		(layer "In15.Cu")
		(net "GMI_CPU0_G1_CPU1_G3_TX_DN<7>")
	)
	(segment
		(start 352.38817 -231.201722)
		(end 352.421698 -231.22128)
		(width 0.1143)
		(layer "In15.Cu")
		(net "GMI_CPU0_G1_CPU1_G3_TX_DN<7>")
	)
	(segment
		(start 119.101616 -225.363532)
		(end 119.075962 -225.3488)
		(width 0.1143)
		(layer "In15.Cu")
		(net "GMI_CPU0_G1_CPU1_G3_TX_DN<7>")
	)
	(segment
		(start 119.10695 -240.922302)
		(end 119.107712 -240.921794)
		(width 0.1143)
		(layer "In15.Cu")
		(net "GMI_CPU0_G1_CPU1_G3_TX_DN<7>")
	)
	(segment
		(start 352.38817 -246.426736)
		(end 352.387154 -246.427244)
		(width 0.1143)
		(layer "In15.Cu")
		(net "GMI_CPU0_G1_CPU1_G3_TX_DN<7>")
	)
	(segment
		(start 352.380042 -236.71149)
		(end 352.379026 -236.711998)
		(width 0.1143)
		(layer "In15.Cu")
		(net "GMI_CPU0_G1_CPU1_G3_TX_DN<7>")
	)
	(segment
		(start 352.380042 -243.191538)
		(end 352.379026 -243.192046)
		(width 0.1143)
		(layer "In15.Cu")
		(net "GMI_CPU0_G1_CPU1_G3_TX_DN<7>")
	)
	(segment
		(start 119.121936 -246.435118)
		(end 119.107712 -246.42699)
		(width 0.1143)
		(layer "In15.Cu")
		(net "GMI_CPU0_G1_CPU1_G3_TX_DN<7>")
	)
	(segment
		(start 119.147336 -227.939092)
		(end 119.163592 -227.927154)
		(width 0.1143)
		(layer "In15.Cu")
		(net "GMI_CPU0_G1_CPU1_G3_TX_DN<7>")
	)
	(segment
		(start 352.38563 -244.808248)
		(end 352.384614 -244.808756)
		(width 0.1143)
		(layer "In15.Cu")
		(net "GMI_CPU0_G1_CPU1_G3_TX_DN<7>")
	)
	(segment
		(start 352.349054 -240.89868)
		(end 352.355912 -240.902744)
		(width 0.1143)
		(layer "In15.Cu")
		(net "GMI_CPU0_G1_CPU1_G3_TX_DN<7>")
	)
	(segment
		(start 151.368252 -190.48095)
		(end 151.387302 -190.28791)
		(width 0.14224)
		(layer "In15.Cu")
		(net "GMI_CPU0_G1_CPU1_G3_TX_DN<7>")
	)
	(segment
		(start 352.379026 -244.812058)
		(end 352.377756 -244.81282)
		(width 0.1143)
		(layer "In15.Cu")
		(net "GMI_CPU0_G1_CPU1_G3_TX_DN<7>")
	)
	(segment
		(start 119.110506 -241.568732)
		(end 119.107712 -241.566954)
		(width 0.1143)
		(layer "In15.Cu")
		(net "GMI_CPU0_G1_CPU1_G3_TX_DN<7>")
	)
	(segment
		(start 352.38817 -244.161564)
		(end 352.388932 -244.162072)
		(width 0.1143)
		(layer "In15.Cu")
		(net "GMI_CPU0_G1_CPU1_G3_TX_DN<7>")
	)
	(segment
		(start 352.37928 -245.776496)
		(end 352.381058 -245.777512)
		(width 0.1143)
		(layer "In15.Cu")
		(net "GMI_CPU0_G1_CPU1_G3_TX_DN<7>")
	)
	(segment
		(start 119.10568 -231.845612)
		(end 119.10314 -231.844342)
		(width 0.1143)
		(layer "In15.Cu")
		(net "GMI_CPU0_G1_CPU1_G3_TX_DN<7>")
	)
	(segment
		(start 352.390202 -244.805454)
		(end 352.388932 -244.806216)
		(width 0.1143)
		(layer "In15.Cu")
		(net "GMI_CPU0_G1_CPU1_G3_TX_DN<7>")
	)
	(segment
		(start 352.41992 -238.308388)
		(end 352.390202 -238.325406)
		(width 0.1143)
		(layer "In15.Cu")
		(net "GMI_CPU0_G1_CPU1_G3_TX_DN<7>")
	)
	(segment
		(start 352.37928 -237.676436)
		(end 352.381058 -237.677452)
		(width 0.1143)
		(layer "In15.Cu")
		(net "GMI_CPU0_G1_CPU1_G3_TX_DN<7>")
	)
	(segment
		(start 352.388932 -239.94618)
		(end 352.38817 -239.946688)
		(width 0.1143)
		(layer "In15.Cu")
		(net "GMI_CPU0_G1_CPU1_G3_TX_DN<7>")
	)
	(segment
		(start 119.101616 -238.323374)
		(end 119.075962 -238.308642)
		(width 0.1143)
		(layer "In15.Cu")
		(net "GMI_CPU0_G1_CPU1_G3_TX_DN<7>")
	)
	(segment
		(start 119.074946 -231.221026)
		(end 119.107712 -231.201976)
		(width 0.1143)
		(layer "In15.Cu")
		(net "GMI_CPU0_G1_CPU1_G3_TX_DN<7>")
	)
	(segment
		(start 351.555558 -221.083124)
		(end 351.601278 -221.128844)
		(width 0.1143)
		(layer "In15.Cu")
		(net "GMI_CPU0_G1_CPU1_G3_TX_DN<7>")
	)
	(segment
		(start 119.10695 -233.466386)
		(end 119.10568 -233.465624)
		(width 0.1143)
		(layer "In15.Cu")
		(net "GMI_CPU0_G1_CPU1_G3_TX_DN<7>")
	)
	(segment
		(start 352.373184 -245.772686)
		(end 352.37547 -245.77421)
		(width 0.1143)
		(layer "In15.Cu")
		(net "GMI_CPU0_G1_CPU1_G3_TX_DN<7>")
	)
	(segment
		(start 119.10568 -233.465624)
		(end 119.10314 -233.464354)
		(width 0.1143)
		(layer "In15.Cu")
		(net "GMI_CPU0_G1_CPU1_G3_TX_DN<7>")
	)
	(segment
		(start 352.388424 -227.961698)
		(end 352.418904 -227.979478)
		(width 0.1143)
		(layer "In15.Cu")
		(net "GMI_CPU0_G1_CPU1_G3_TX_DN<7>")
	)
	(segment
		(start 119.10695 -238.326422)
		(end 119.10568 -238.32566)
		(width 0.1143)
		(layer "In15.Cu")
		(net "GMI_CPU0_G1_CPU1_G3_TX_DN<7>")
	)
	(segment
		(start 150.845012 -190.732664)
		(end 151.038052 -190.751714)
		(width 0.14224)
		(layer "In15.Cu")
		(net "GMI_CPU0_G1_CPU1_G3_TX_DN<7>")
	)
	(segment
		(start 119.144034 -233.487976)
		(end 119.107712 -233.466894)
		(width 0.1143)
		(layer "In15.Cu")
		(net "GMI_CPU0_G1_CPU1_G3_TX_DN<7>")
	)
	(segment
		(start 352.387154 -245.781068)
		(end 352.38817 -245.781576)
		(width 0.1143)
		(layer "In15.Cu")
		(net "GMI_CPU0_G1_CPU1_G3_TX_DN<7>")
	)
	(segment
		(start 352.379026 -239.952022)
		(end 352.377756 -239.952784)
		(width 0.1143)
		(layer "In15.Cu")
		(net "GMI_CPU0_G1_CPU1_G3_TX_DN<7>")
	)
	(segment
		(start 352.41992 -241.548412)
		(end 352.390202 -241.56543)
		(width 0.1143)
		(layer "In15.Cu")
		(net "GMI_CPU0_G1_CPU1_G3_TX_DN<7>")
	)
	(segment
		(start 119.107712 -241.566954)
		(end 119.10695 -241.566446)
		(width 0.1143)
		(layer "In15.Cu")
		(net "GMI_CPU0_G1_CPU1_G3_TX_DN<7>")
	)
	(segment
		(start 352.390202 -243.185442)
		(end 352.388932 -243.186204)
		(width 0.1143)
		(layer "In15.Cu")
		(net "GMI_CPU0_G1_CPU1_G3_TX_DN<7>")
	)
	(segment
		(start 352.38817 -240.92154)
		(end 352.388932 -240.922048)
		(width 0.1143)
		(layer "In15.Cu")
		(net "GMI_CPU0_G1_CPU1_G3_TX_DN<7>")
	)
	(segment
		(start 119.402606 -246.934228)
		(end 119.402606 -246.922798)
		(width 0.1143)
		(layer "In15.Cu")
		(net "GMI_CPU0_G1_CPU1_G3_TX_DN<7>")
	)
	(segment
		(start 119.107712 -226.9871)
		(end 119.10695 -226.986592)
		(width 0.1143)
		(layer "In15.Cu")
		(net "GMI_CPU0_G1_CPU1_G3_TX_DN<7>")
	)
	(segment
		(start 352.384614 -241.568732)
		(end 352.38309 -241.569748)
		(width 0.1143)
		(layer "In15.Cu")
		(net "GMI_CPU0_G1_CPU1_G3_TX_DN<7>")
	)
	(segment
		(start 352.38817 -229.58171)
		(end 352.421698 -229.601268)
		(width 0.1143)
		(layer "In15.Cu")
		(net "GMI_CPU0_G1_CPU1_G3_TX_DN<7>")
	)
	(segment
		(start 119.107712 -244.161818)
		(end 119.147336 -244.138958)
		(width 0.1143)
		(layer "In15.Cu")
		(net "GMI_CPU0_G1_CPU1_G3_TX_DN<7>")
	)
	(segment
		(start 351.879154 -225.50882)
		(end 351.911666 -225.52787)
		(width 0.1143)
		(layer "In15.Cu")
		(net "GMI_CPU0_G1_CPU1_G3_TX_DN<7>")
	)
	(segment
		(start 315.301122 -185.927492)
		(end 347.826076 -212.596984)
		(width 0.14224)
		(layer "In15.Cu")
		(net "GMI_CPU0_G1_CPU1_G3_TX_DN<7>")
	)
	(segment
		(start 119.10314 -233.464354)
		(end 119.101616 -233.463338)
		(width 0.1143)
		(layer "In15.Cu")
		(net "GMI_CPU0_G1_CPU1_G3_TX_DN<7>")
	)
	(segment
		(start 352.384614 -231.84866)
		(end 352.38309 -231.849676)
		(width 0.1143)
		(layer "In15.Cu")
		(net "GMI_CPU0_G1_CPU1_G3_TX_DN<7>")
	)
	(segment
		(start 352.388932 -231.84612)
		(end 352.38817 -231.846628)
		(width 0.1143)
		(layer "In15.Cu")
		(net "GMI_CPU0_G1_CPU1_G3_TX_DN<7>")
	)
	(segment
		(start 352.418142 -228.589586)
		(end 352.38817 -228.606858)
		(width 0.1143)
		(layer "In15.Cu")
		(net "GMI_CPU0_G1_CPU1_G3_TX_DN<7>")
	)
	(segment
		(start 119.075962 -244.180106)
		(end 119.10568 -244.163088)
		(width 0.1143)
		(layer "In15.Cu")
		(net "GMI_CPU0_G1_CPU1_G3_TX_DN<7>")
	)
	(segment
		(start 150.165816 -191.466978)
		(end 150.496016 -191.196214)
		(width 0.14224)
		(layer "In15.Cu")
		(net "GMI_CPU0_G1_CPU1_G3_TX_DN<7>")
	)
	(segment
		(start 119.10695 -246.426482)
		(end 119.10568 -246.42572)
		(width 0.1143)
		(layer "In15.Cu")
		(net "GMI_CPU0_G1_CPU1_G3_TX_DN<7>")
	)
	(segment
		(start 352.349054 -237.658656)
		(end 352.373184 -237.672626)
		(width 0.1143)
		(layer "In15.Cu")
		(net "GMI_CPU0_G1_CPU1_G3_TX_DN<7>")
	)
	(segment
		(start 352.376486 -237.674658)
		(end 352.377756 -237.67542)
		(width 0.1143)
		(layer "In15.Cu")
		(net "GMI_CPU0_G1_CPU1_G3_TX_DN<7>")
	)
	(segment
		(start 119.10695 -226.986592)
		(end 119.10568 -226.98583)
		(width 0.1143)
		(layer "In15.Cu")
		(net "GMI_CPU0_G1_CPU1_G3_TX_DN<7>")
	)
	(segment
		(start 352.377756 -239.952784)
		(end 352.376994 -239.953292)
		(width 0.1143)
		(layer "In15.Cu")
		(net "GMI_CPU0_G1_CPU1_G3_TX_DN<7>")
	)
	(segment
		(start 119.110252 -231.84866)
		(end 119.107712 -231.846882)
		(width 0.1143)
		(layer "In15.Cu")
		(net "GMI_CPU0_G1_CPU1_G3_TX_DN<7>")
	)
	(segment
		(start 154.977084 -187.51169)
		(end 154.995118 -187.329318)
		(width 0.14224)
		(layer "In15.Cu")
		(net "GMI_CPU0_G1_CPU1_G3_TX_DN<7>")
	)
	(segment
		(start 352.376994 -241.573304)
		(end 352.349054 -241.58956)
		(width 0.1143)
		(layer "In15.Cu")
		(net "GMI_CPU0_G1_CPU1_G3_TX_DN<7>")
	)
	(segment
		(start 351.44837 -223.101662)
		(end 351.47885 -223.119442)
		(width 0.1143)
		(layer "In15.Cu")
		(net "GMI_CPU0_G1_CPU1_G3_TX_DN<7>")
	)
	(segment
		(start 352.38817 -238.326676)
		(end 352.387154 -238.327184)
		(width 0.1143)
		(layer "In15.Cu")
		(net "GMI_CPU0_G1_CPU1_G3_TX_DN<7>")
	)
	(segment
		(start 119.075962 -237.700058)
		(end 119.10568 -237.68304)
		(width 0.1143)
		(layer "In15.Cu")
		(net "GMI_CPU0_G1_CPU1_G3_TX_DN<7>")
	)
	(segment
		(start 119.107712 -231.846882)
		(end 119.10695 -231.846374)
		(width 0.1143)
		(layer "In15.Cu")
		(net "GMI_CPU0_G1_CPU1_G3_TX_DN<7>")
	)
	(segment
		(start 119.075962 -223.120204)
		(end 119.10568 -223.103186)
		(width 0.1143)
		(layer "In15.Cu")
		(net "GMI_CPU0_G1_CPU1_G3_TX_DN<7>")
	)
	(segment
		(start 351.44837 -222.12681)
		(end 351.448116 -222.127064)
		(width 0.1143)
		(layer "In15.Cu")
		(net "GMI_CPU0_G1_CPU1_G3_TX_DN<7>")
	)
	(segment
		(start 119.166386 -243.223796)
		(end 119.147336 -243.209826)
		(width 0.1143)
		(layer "In15.Cu")
		(net "GMI_CPU0_G1_CPU1_G3_TX_DN<7>")
	)
	(segment
		(start 119.10568 -245.7831)
		(end 119.10695 -245.782338)
		(width 0.1143)
		(layer "In15.Cu")
		(net "GMI_CPU0_G1_CPU1_G3_TX_DN<7>")
	)
	(segment
		(start 352.382074 -246.430292)
		(end 352.380804 -246.431054)
		(width 0.1143)
		(layer "In15.Cu")
		(net "GMI_CPU0_G1_CPU1_G3_TX_DN<7>")
	)
	(segment
		(start 155.825698 -186.81573)
		(end 155.843732 -186.633358)
		(width 0.14224)
		(layer "In15.Cu")
		(net "GMI_CPU0_G1_CPU1_G3_TX_DN<7>")
	)
	(segment
		(start 352.388932 -244.162072)
		(end 352.390202 -244.162834)
		(width 0.1143)
		(layer "In15.Cu")
		(net "GMI_CPU0_G1_CPU1_G3_TX_DN<7>")
	)
	(segment
		(start 119.147336 -227.00996)
		(end 119.110252 -226.988878)
		(width 0.1143)
		(layer "In15.Cu")
		(net "GMI_CPU0_G1_CPU1_G3_TX_DN<7>")
	)
	(segment
		(start 119.147082 -241.589814)
		(end 119.110506 -241.568732)
		(width 0.1143)
		(layer "In15.Cu")
		(net "GMI_CPU0_G1_CPU1_G3_TX_DN<7>")
	)
	(segment
		(start 352.388932 -232.821988)
		(end 352.390202 -232.82275)
		(width 0.1143)
		(layer "In15.Cu")
		(net "GMI_CPU0_G1_CPU1_G3_TX_DN<7>")
	)
	(segment
		(start 119.10314 -223.744536)
		(end 119.101616 -223.74352)
		(width 0.1143)
		(layer "In15.Cu")
		(net "GMI_CPU0_G1_CPU1_G3_TX_DN<7>")
	)
	(segment
		(start 119.147082 -226.31908)
		(end 119.16537 -226.306126)
		(width 0.1143)
		(layer "In15.Cu")
		(net "GMI_CPU0_G1_CPU1_G3_TX_DN<7>")
	)
	(segment
		(start 119.147082 -225.389948)
		(end 119.110506 -225.368866)
		(width 0.1143)
		(layer "In15.Cu")
		(net "GMI_CPU0_G1_CPU1_G3_TX_DN<7>")
	)
	(segment
		(start 119.075962 -236.080046)
		(end 119.107712 -236.061758)
		(width 0.1143)
		(layer "In15.Cu")
		(net "GMI_CPU0_G1_CPU1_G3_TX_DN<7>")
	)
	(segment
		(start 150.515066 -191.003174)
		(end 150.845012 -190.732664)
		(width 0.14224)
		(layer "In15.Cu")
		(net "GMI_CPU0_G1_CPU1_G3_TX_DN<7>")
	)
	(segment
		(start 352.377756 -235.092748)
		(end 352.376994 -235.093256)
		(width 0.1143)
		(layer "In15.Cu")
		(net "GMI_CPU0_G1_CPU1_G3_TX_DN<7>")
	)
	(segment
		(start 155.319222 -187.063888)
		(end 155.318968 -187.063634)
		(width 0.14224)
		(layer "In15.Cu")
		(net "GMI_CPU0_G1_CPU1_G3_TX_DN<7>")
	)
	(segment
		(start 352.396806 -244.16639)
		(end 352.41992 -244.179852)
		(width 0.1143)
		(layer "In15.Cu")
		(net "GMI_CPU0_G1_CPU1_G3_TX_DN<7>")
	)
	(segment
		(start 351.91573 -225.530156)
		(end 351.917254 -225.531172)
		(width 0.1143)
		(layer "In15.Cu")
		(net "GMI_CPU0_G1_CPU1_G3_TX_DN<7>")
	)
	(segment
		(start 352.390202 -244.162834)
		(end 352.391726 -244.163596)
		(width 0.1143)
		(layer "In15.Cu")
		(net "GMI_CPU0_G1_CPU1_G3_TX_DN<7>")
	)
	(segment
		(start 352.356674 -234.423204)
		(end 352.38817 -234.441492)
		(width 0.1143)
		(layer "In15.Cu")
		(net "GMI_CPU0_G1_CPU1_G3_TX_DN<7>")
	)
	(segment
		(start 352.388932 -236.062012)
		(end 352.390202 -236.062774)
		(width 0.1143)
		(layer "In15.Cu")
		(net "GMI_CPU0_G1_CPU1_G3_TX_DN<7>")
	)
	(segment
		(start 119.174514 -223.789748)
		(end 119.146574 -223.769682)
		(width 0.1143)
		(layer "In15.Cu")
		(net "GMI_CPU0_G1_CPU1_G3_TX_DN<7>")
	)
	(segment
		(start 149.10054 -192.162938)
		(end 149.29358 -192.182242)
		(width 0.14224)
		(layer "In15.Cu")
		(net "GMI_CPU0_G1_CPU1_G3_TX_DN<7>")
	)
	(segment
		(start 352.376994 -231.853232)
		(end 352.349054 -231.869488)
		(width 0.1143)
		(layer "In15.Cu")
		(net "GMI_CPU0_G1_CPU1_G3_TX_DN<7>")
	)
	(segment
		(start 119.110506 -244.808756)
		(end 119.107712 -244.806978)
		(width 0.1143)
		(layer "In15.Cu")
		(net "GMI_CPU0_G1_CPU1_G3_TX_DN<7>")
	)
	(segment
		(start 119.10695 -232.822242)
		(end 119.107712 -232.821734)
		(width 0.1143)
		(layer "In15.Cu")
		(net "GMI_CPU0_G1_CPU1_G3_TX_DN<7>")
	)
	(segment
		(start 352.388932 -239.302036)
		(end 352.390202 -239.302798)
		(width 0.1143)
		(layer "In15.Cu")
		(net "GMI_CPU0_G1_CPU1_G3_TX_DN<7>")
	)
	(segment
		(start 119.107712 -229.581964)
		(end 119.144034 -229.560882)
		(width 0.1143)
		(layer "In15.Cu")
		(net "GMI_CPU0_G1_CPU1_G3_TX_DN<7>")
	)
	(segment
		(start 352.349054 -234.418632)
		(end 352.355912 -234.422696)
		(width 0.1143)
		(layer "In15.Cu")
		(net "GMI_CPU0_G1_CPU1_G3_TX_DN<7>")
	)
	(segment
		(start 119.107712 -228.607112)
		(end 119.10695 -228.606604)
		(width 0.1143)
		(layer "In15.Cu")
		(net "GMI_CPU0_G1_CPU1_G3_TX_DN<7>")
	)
	(segment
		(start 352.38817 -239.301528)
		(end 352.388932 -239.302036)
		(width 0.1143)
		(layer "In15.Cu")
		(net "GMI_CPU0_G1_CPU1_G3_TX_DN<7>")
	)
	(segment
		(start 352.387154 -243.18722)
		(end 352.38563 -243.188236)
		(width 0.1143)
		(layer "In15.Cu")
		(net "GMI_CPU0_G1_CPU1_G3_TX_DN<7>")
	)
	(segment
		(start 352.390202 -238.325406)
		(end 352.388932 -238.326168)
		(width 0.1143)
		(layer "In15.Cu")
		(net "GMI_CPU0_G1_CPU1_G3_TX_DN<7>")
	)
	(segment
		(start 352.38817 -230.226616)
		(end 352.351594 -230.247952)
		(width 0.1143)
		(layer "In15.Cu")
		(net "GMI_CPU0_G1_CPU1_G3_TX_DN<7>")
	)
	(segment
		(start 352.38563 -231.848152)
		(end 352.384614 -231.84866)
		(width 0.1143)
		(layer "In15.Cu")
		(net "GMI_CPU0_G1_CPU1_G3_TX_DN<7>")
	)
	(segment
		(start 119.105426 -242.543076)
		(end 119.106188 -242.542568)
		(width 0.1143)
		(layer "In15.Cu")
		(net "GMI_CPU0_G1_CPU1_G3_TX_DN<7>")
	)
	(segment
		(start 119.14759 -232.798874)
		(end 119.162068 -232.788206)
		(width 0.1143)
		(layer "In15.Cu")
		(net "GMI_CPU0_G1_CPU1_G3_TX_DN<7>")
	)
	(segment
		(start 352.391726 -240.923572)
		(end 352.394266 -240.925096)
		(width 0.1143)
		(layer "In15.Cu")
		(net "GMI_CPU0_G1_CPU1_G3_TX_DN<7>")
	)
	(segment
		(start 352.376994 -246.43334)
		(end 352.349054 -246.449596)
		(width 0.1143)
		(layer "In15.Cu")
		(net "GMI_CPU0_G1_CPU1_G3_TX_DN<7>")
	)
	(segment
		(start 352.37547 -245.77421)
		(end 352.376486 -245.774718)
		(width 0.1143)
		(layer "In15.Cu")
		(net "GMI_CPU0_G1_CPU1_G3_TX_DN<7>")
	)
	(segment
		(start 352.380042 -239.951514)
		(end 352.379026 -239.952022)
		(width 0.1143)
		(layer "In15.Cu")
		(net "GMI_CPU0_G1_CPU1_G3_TX_DN<7>")
	)
	(segment
		(start 119.076724 -235.069126)
		(end 119.075962 -235.068618)
		(width 0.1143)
		(layer "In15.Cu")
		(net "GMI_CPU0_G1_CPU1_G3_TX_DN<7>")
	)
	(segment
		(start 144.357852 -195.656708)
		(end 145.12163 -195.42506)
		(width 0.14224)
		(layer "In15.Cu")
		(net "GMI_CPU0_G1_CPU1_G3_TX_DN<7>")
	)
	(segment
		(start 351.917254 -225.531172)
		(end 351.91827 -225.53168)
		(width 0.1143)
		(layer "In15.Cu")
		(net "GMI_CPU0_G1_CPU1_G3_TX_DN<7>")
	)
	(segment
		(start 119.107712 -234.441746)
		(end 119.144034 -234.420664)
		(width 0.1143)
		(layer "In15.Cu")
		(net "GMI_CPU0_G1_CPU1_G3_TX_DN<7>")
	)
	(segment
		(start 352.376994 -236.713268)
		(end 352.349054 -236.729524)
		(width 0.1143)
		(layer "In15.Cu")
		(net "GMI_CPU0_G1_CPU1_G3_TX_DN<7>")
	)
	(segment
		(start 153.621994 -188.455554)
		(end 153.804112 -188.473588)
		(width 0.14224)
		(layer "In15.Cu")
		(net "GMI_CPU0_G1_CPU1_G3_TX_DN<7>")
	)
	(segment
		(start 119.107712 -236.706918)
		(end 119.105172 -236.705394)
		(width 0.1143)
		(layer "In15.Cu")
		(net "GMI_CPU0_G1_CPU1_G3_TX_DN<7>")
	)
	(segment
		(start 352.38817 -231.846628)
		(end 352.387154 -231.847136)
		(width 0.1143)
		(layer "In15.Cu")
		(net "GMI_CPU0_G1_CPU1_G3_TX_DN<7>")
	)
	(segment
		(start 119.075962 -224.740216)
		(end 119.10568 -224.723198)
		(width 0.1143)
		(layer "In15.Cu")
		(net "GMI_CPU0_G1_CPU1_G3_TX_DN<7>")
	)
	(segment
		(start 352.41992 -233.448352)
		(end 352.390202 -233.46537)
		(width 0.1143)
		(layer "In15.Cu")
		(net "GMI_CPU0_G1_CPU1_G3_TX_DN<7>")
	)
	(segment
		(start 119.099584 -239.942116)
		(end 119.098822 -239.941608)
		(width 0.1143)
		(layer "In15.Cu")
		(net "GMI_CPU0_G1_CPU1_G3_TX_DN<7>")
	)
	(segment
		(start 352.390202 -233.46537)
		(end 352.388932 -233.466132)
		(width 0.1143)
		(layer "In15.Cu")
		(net "GMI_CPU0_G1_CPU1_G3_TX_DN<7>")
	)
	(segment
		(start 119.107712 -231.201976)
		(end 119.14124 -231.182418)
		(width 0.1143)
		(layer "In15.Cu")
		(net "GMI_CPU0_G1_CPU1_G3_TX_DN<7>")
	)
	(segment
		(start 352.41992 -239.9284)
		(end 352.390202 -239.945418)
		(width 0.1143)
		(layer "In15.Cu")
		(net "GMI_CPU0_G1_CPU1_G3_TX_DN<7>")
	)
	(segment
		(start 352.38563 -242.540028)
		(end 352.387154 -242.541044)
		(width 0.1143)
		(layer "In15.Cu")
		(net "GMI_CPU0_G1_CPU1_G3_TX_DN<7>")
	)
	(segment
		(start 352.356674 -244.143276)
		(end 352.38817 -244.161564)
		(width 0.1143)
		(layer "In15.Cu")
		(net "GMI_CPU0_G1_CPU1_G3_TX_DN<7>")
	)
	(segment
		(start 119.14759 -231.869742)
		(end 119.110252 -231.84866)
		(width 0.1143)
		(layer "In15.Cu")
		(net "GMI_CPU0_G1_CPU1_G3_TX_DN<7>")
	)
	(segment
		(start 119.10441 -226.343718)
		(end 119.105426 -226.34321)
		(width 0.1143)
		(layer "In15.Cu")
		(net "GMI_CPU0_G1_CPU1_G3_TX_DN<7>")
	)
	(segment
		(start 352.388932 -246.426228)
		(end 352.38817 -246.426736)
		(width 0.1143)
		(layer "In15.Cu")
		(net "GMI_CPU0_G1_CPU1_G3_TX_DN<7>")
	)
	(segment
		(start 352.38309 -236.709712)
		(end 352.382074 -236.71022)
		(width 0.1143)
		(layer "In15.Cu")
		(net "GMI_CPU0_G1_CPU1_G3_TX_DN<7>")
	)
	(segment
		(start 154.995118 -187.329318)
		(end 154.995118 -187.329572)
		(width 0.14224)
		(layer "In15.Cu")
		(net "GMI_CPU0_G1_CPU1_G3_TX_DN<7>")
	)
	(segment
		(start 352.418904 -226.969066)
		(end 352.388424 -226.986846)
		(width 0.1143)
		(layer "In15.Cu")
		(net "GMI_CPU0_G1_CPU1_G3_TX_DN<7>")
	)
	(segment
		(start 352.38309 -241.569748)
		(end 352.382074 -241.570256)
		(width 0.1143)
		(layer "In15.Cu")
		(net "GMI_CPU0_G1_CPU1_G3_TX_DN<7>")
	)
	(segment
		(start 119.10695 -230.226362)
		(end 119.10441 -230.224838)
		(width 0.1143)
		(layer "In15.Cu")
		(net "GMI_CPU0_G1_CPU1_G3_TX_DN<7>")
	)
	(segment
		(start 119.10695 -237.682278)
		(end 119.107712 -237.68177)
		(width 0.1143)
		(layer "In15.Cu")
		(net "GMI_CPU0_G1_CPU1_G3_TX_DN<7>")
	)
	(segment
		(start 352.38563 -239.948212)
		(end 352.384614 -239.94872)
		(width 0.1143)
		(layer "In15.Cu")
		(net "GMI_CPU0_G1_CPU1_G3_TX_DN<7>")
	)
	(segment
		(start 351.911666 -225.52787)
		(end 351.91319 -225.528632)
		(width 0.1143)
		(layer "In15.Cu")
		(net "GMI_CPU0_G1_CPU1_G3_TX_DN<7>")
	)
	(segment
		(start 352.355912 -234.422696)
		(end 352.356674 -234.423204)
		(width 0.1143)
		(layer "In15.Cu")
		(net "GMI_CPU0_G1_CPU1_G3_TX_DN<7>")
	)
	(segment
		(start 119.10695 -234.442254)
		(end 119.107712 -234.441746)
		(width 0.1143)
		(layer "In15.Cu")
		(net "GMI_CPU0_G1_CPU1_G3_TX_DN<7>")
	)
	(segment
		(start 352.349054 -244.138704)
		(end 352.355912 -244.142768)
		(width 0.1143)
		(layer "In15.Cu")
		(net "GMI_CPU0_G1_CPU1_G3_TX_DN<7>")
	)
	(segment
		(start 352.355912 -232.802684)
		(end 352.356674 -232.803192)
		(width 0.1143)
		(layer "In15.Cu")
		(net "GMI_CPU0_G1_CPU1_G3_TX_DN<7>")
	)
	(segment
		(start 118.88089 -221.198948)
		(end 118.88089 -221.066106)
		(width 0.1143)
		(layer "In15.Cu")
		(net "GMI_CPU0_G1_CPU1_G3_TX_DN<7>")
	)
	(segment
		(start 119.10695 -227.96246)
		(end 119.107712 -227.961952)
		(width 0.1143)
		(layer "In15.Cu")
		(net "GMI_CPU0_G1_CPU1_G3_TX_DN<7>")
	)
	(segment
		(start 118.88089 -221.066106)
		(end 118.92661 -221.020386)
		(width 0.1143)
		(layer "In15.Cu")
		(net "GMI_CPU0_G1_CPU1_G3_TX_DN<7>")
	)
	(segment
		(start 120.23471 -247.724422)
		(end 119.936768 -247.724422)
		(width 0.1143)
		(layer "In15.Cu")
		(net "GMI_CPU0_G1_CPU1_G3_TX_DN<7>")
	)
	(segment
		(start 352.394266 -240.925096)
		(end 352.396806 -240.926366)
		(width 0.1143)
		(layer "In15.Cu")
		(net "GMI_CPU0_G1_CPU1_G3_TX_DN<7>")
	)
	(segment
		(start 352.37547 -242.534186)
		(end 352.376486 -242.534694)
		(width 0.1143)
		(layer "In15.Cu")
		(net "GMI_CPU0_G1_CPU1_G3_TX_DN<7>")
	)
	(segment
		(start 119.10441 -230.224838)
		(end 119.075962 -230.208582)
		(width 0.1143)
		(layer "In15.Cu")
		(net "GMI_CPU0_G1_CPU1_G3_TX_DN<7>")
	)
	(segment
		(start 119.10695 -231.846374)
		(end 119.10568 -231.845612)
		(width 0.1143)
		(layer "In15.Cu")
		(net "GMI_CPU0_G1_CPU1_G3_TX_DN<7>")
	)
	(segment
		(start 352.38817 -236.706664)
		(end 352.387154 -236.707172)
		(width 0.1143)
		(layer "In15.Cu")
		(net "GMI_CPU0_G1_CPU1_G3_TX_DN<7>")
	)
	(segment
		(start 119.14632 -244.82933)
		(end 119.110506 -244.808756)
		(width 0.1143)
		(layer "In15.Cu")
		(net "GMI_CPU0_G1_CPU1_G3_TX_DN<7>")
	)
	(segment
		(start 351.479866 -223.728534)
		(end 351.448116 -223.746822)
		(width 0.1143)
		(layer "In15.Cu")
		(net "GMI_CPU0_G1_CPU1_G3_TX_DN<7>")
	)
	(segment
		(start 352.387154 -238.327184)
		(end 352.349054 -238.349536)
		(width 0.1143)
		(layer "In15.Cu")
		(net "GMI_CPU0_G1_CPU1_G3_TX_DN<7>")
	)
	(segment
		(start 352.380804 -235.09097)
		(end 352.380042 -235.091478)
		(width 0.1143)
		(layer "In15.Cu")
		(net "GMI_CPU0_G1_CPU1_G3_TX_DN<7>")
	)
	(segment
		(start 352.380804 -246.431054)
		(end 352.380042 -246.431562)
		(width 0.1143)
		(layer "In15.Cu")
		(net "GMI_CPU0_G1_CPU1_G3_TX_DN<7>")
	)
	(segment
		(start 352.390202 -241.56543)
		(end 352.388932 -241.566192)
		(width 0.1143)
		(layer "In15.Cu")
		(net "GMI_CPU0_G1_CPU1_G3_TX_DN<7>")
	)
	(segment
		(start 119.107712 -239.301782)
		(end 119.147082 -239.279176)
		(width 0.1143)
		(layer "In15.Cu")
		(net "GMI_CPU0_G1_CPU1_G3_TX_DN<7>")
	)
	(segment
		(start 352.394266 -232.825036)
		(end 352.396806 -232.826306)
		(width 0.1143)
		(layer "In15.Cu")
		(net "GMI_CPU0_G1_CPU1_G3_TX_DN<7>")
	)
	(segment
		(start 119.10695 -244.80647)
		(end 119.10568 -244.805708)
		(width 0.1143)
		(layer "In15.Cu")
		(net "GMI_CPU0_G1_CPU1_G3_TX_DN<7>")
	)
	(segment
		(start 119.101616 -246.423434)
		(end 119.075962 -246.408702)
		(width 0.1143)
		(layer "In15.Cu")
		(net "GMI_CPU0_G1_CPU1_G3_TX_DN<7>")
	)
	(segment
		(start 119.10568 -238.32566)
		(end 119.10314 -238.32439)
		(width 0.1143)
		(layer "In15.Cu")
		(net "GMI_CPU0_G1_CPU1_G3_TX_DN<7>")
	)
	(segment
		(start 352.355912 -240.902744)
		(end 352.356674 -240.903252)
		(width 0.1143)
		(layer "In15.Cu")
		(net "GMI_CPU0_G1_CPU1_G3_TX_DN<7>")
	)
	(segment
		(start 352.38817 -232.82148)
		(end 352.388932 -232.821988)
		(width 0.1143)
		(layer "In15.Cu")
		(net "GMI_CPU0_G1_CPU1_G3_TX_DN<7>")
	)
	(segment
		(start 119.107712 -235.086906)
		(end 119.076724 -235.069126)
		(width 0.1143)
		(layer "In15.Cu")
		(net "GMI_CPU0_G1_CPU1_G3_TX_DN<7>")
	)
	(segment
		(start 352.390202 -235.085382)
		(end 352.388932 -235.086144)
		(width 0.1143)
		(layer "In15.Cu")
		(net "GMI_CPU0_G1_CPU1_G3_TX_DN<7>")
	)
	(segment
		(start 119.146574 -223.769682)
		(end 119.110506 -223.748854)
		(width 0.1143)
		(layer "In15.Cu")
		(net "GMI_CPU0_G1_CPU1_G3_TX_DN<7>")
	)
	(segment
		(start 119.10568 -224.723198)
		(end 119.10695 -224.722436)
		(width 0.1143)
		(layer "In15.Cu")
		(net "GMI_CPU0_G1_CPU1_G3_TX_DN<7>")
	)
	(segment
		(start 119.146574 -224.699322)
		(end 119.174514 -224.679256)
		(width 0.1143)
		(layer "In15.Cu")
		(net "GMI_CPU0_G1_CPU1_G3_TX_DN<7>")
	)
	(segment
		(start 119.075962 -226.360228)
		(end 119.099076 -226.346766)
		(width 0.1143)
		(layer "In15.Cu")
		(net "GMI_CPU0_G1_CPU1_G3_TX_DN<7>")
	)
	(segment
		(start 351.63633 -221.422468)
		(end 351.63633 -221.579694)
		(width 0.1143)
		(layer "In15.Cu")
		(net "GMI_CPU0_G1_CPU1_G3_TX_DN<7>")
	)
	(segment
		(start 351.448116 -223.746822)
		(end 351.4471 -223.74733)
		(width 0.1143)
		(layer "In15.Cu")
		(net "GMI_CPU0_G1_CPU1_G3_TX_DN<7>")
	)
	(segment
		(start 119.101616 -228.603556)
		(end 119.075962 -228.588824)
		(width 0.1143)
		(layer "In15.Cu")
		(net "GMI_CPU0_G1_CPU1_G3_TX_DN<7>")
	)
	(segment
		(start 119.10695 -239.946434)
		(end 119.10568 -239.945672)
		(width 0.1143)
		(layer "In15.Cu")
		(net "GMI_CPU0_G1_CPU1_G3_TX_DN<7>")
	)
	(segment
		(start 352.394266 -239.305084)
		(end 352.396806 -239.306354)
		(width 0.1143)
		(layer "In15.Cu")
		(net "GMI_CPU0_G1_CPU1_G3_TX_DN<7>")
	)
	(segment
		(start 352.382074 -244.81028)
		(end 352.380804 -244.811042)
		(width 0.1143)
		(layer "In15.Cu")
		(net "GMI_CPU0_G1_CPU1_G3_TX_DN<7>")
	)
	(segment
		(start 119.101616 -226.983544)
		(end 119.075962 -226.968812)
		(width 0.1143)
		(layer "In15.Cu")
		(net "GMI_CPU0_G1_CPU1_G3_TX_DN<7>")
	)
	(segment
		(start 352.394266 -236.06506)
		(end 352.396806 -236.06633)
		(width 0.1143)
		(layer "In15.Cu")
		(net "GMI_CPU0_G1_CPU1_G3_TX_DN<7>")
	)
	(segment
		(start 352.373184 -242.532662)
		(end 352.37547 -242.534186)
		(width 0.1143)
		(layer "In15.Cu")
		(net "GMI_CPU0_G1_CPU1_G3_TX_DN<7>")
	)
	(segment
		(start 119.10314 -241.564414)
		(end 119.101616 -241.563398)
		(width 0.1143)
		(layer "In15.Cu")
		(net "GMI_CPU0_G1_CPU1_G3_TX_DN<7>")
	)
	(segment
		(start 121.87682 -214.089742)
		(end 144.357852 -195.656708)
		(width 0.14224)
		(layer "In15.Cu")
		(net "GMI_CPU0_G1_CPU1_G3_TX_DN<7>")
	)
	(segment
		(start 154.12847 -188.20765)
		(end 154.146504 -188.025278)
		(width 0.14224)
		(layer "In15.Cu")
		(net "GMI_CPU0_G1_CPU1_G3_TX_DN<7>")
	)
	(segment
		(start 119.107712 -223.101916)
		(end 119.147082 -223.079056)
		(width 0.1143)
		(layer "In15.Cu")
		(net "GMI_CPU0_G1_CPU1_G3_TX_DN<7>")
	)
	(segment
		(start 119.110252 -226.988878)
		(end 119.107712 -226.9871)
		(width 0.1143)
		(layer "In15.Cu")
		(net "GMI_CPU0_G1_CPU1_G3_TX_DN<7>")
	)
	(segment
		(start 119.168672 -238.365284)
		(end 119.147082 -238.349536)
		(width 0.1143)
		(layer "In15.Cu")
		(net "GMI_CPU0_G1_CPU1_G3_TX_DN<7>")
	)
	(segment
		(start 352.387154 -239.947196)
		(end 352.38563 -239.948212)
		(width 0.1143)
		(layer "In15.Cu")
		(net "GMI_CPU0_G1_CPU1_G3_TX_DN<7>")
	)
	(segment
		(start 119.1641 -244.841776)
		(end 119.14632 -244.82933)
		(width 0.1143)
		(layer "In15.Cu")
		(net "GMI_CPU0_G1_CPU1_G3_TX_DN<7>")
	)
	(segment
		(start 352.38817 -235.086652)
		(end 352.387154 -235.08716)
		(width 0.1143)
		(layer "In15.Cu")
		(net "GMI_CPU0_G1_CPU1_G3_TX_DN<7>")
	)
	(segment
		(start 352.396806 -236.06633)
		(end 352.41992 -236.079792)
		(width 0.1143)
		(layer "In15.Cu")
		(net "GMI_CPU0_G1_CPU1_G3_TX_DN<7>")
	)
	(segment
		(start 119.103648 -226.344226)
		(end 119.10441 -226.343718)
		(width 0.1143)
		(layer "In15.Cu")
		(net "GMI_CPU0_G1_CPU1_G3_TX_DN<7>")
	)
	(segment
		(start 352.349308 -227.938838)
		(end 352.388424 -227.961698)
		(width 0.1143)
		(layer "In15.Cu")
		(net "GMI_CPU0_G1_CPU1_G3_TX_DN<7>")
	)
	(segment
		(start 352.384614 -233.468672)
		(end 352.38309 -233.469688)
		(width 0.1143)
		(layer "In15.Cu")
		(net "GMI_CPU0_G1_CPU1_G3_TX_DN<7>")
	)
	(segment
		(start 352.41992 -235.068364)
		(end 352.390202 -235.085382)
		(width 0.1143)
		(layer "In15.Cu")
		(net "GMI_CPU0_G1_CPU1_G3_TX_DN<7>")
	)
	(segment
		(start 352.384614 -246.428768)
		(end 352.38309 -246.429784)
		(width 0.1143)
		(layer "In15.Cu")
		(net "GMI_CPU0_G1_CPU1_G3_TX_DN<7>")
	)
	(segment
		(start 352.390202 -246.425466)
		(end 352.388932 -246.426228)
		(width 0.1143)
		(layer "In15.Cu")
		(net "GMI_CPU0_G1_CPU1_G3_TX_DN<7>")
	)
	(segment
		(start 352.356674 -236.043216)
		(end 352.38817 -236.061504)
		(width 0.1143)
		(layer "In15.Cu")
		(net "GMI_CPU0_G1_CPU1_G3_TX_DN<7>")
	)
	(segment
		(start 302.898048 -181.659276)
		(end 307.21808 -181.659276)
		(width 0.14224)
		(layer "In15.Cu")
		(net "GMI_CPU0_G1_CPU1_G3_TX_DN<7>")
	)
	(segment
		(start 119.10187 -242.545108)
		(end 119.102632 -242.5446)
		(width 0.1143)
		(layer "In15.Cu")
		(net "GMI_CPU0_G1_CPU1_G3_TX_DN<7>")
	)
	(segment
		(start 119.10695 -223.746568)
		(end 119.10568 -223.745806)
		(width 0.1143)
		(layer "In15.Cu")
		(net "GMI_CPU0_G1_CPU1_G3_TX_DN<7>")
	)
	(segment
		(start 352.382074 -236.71022)
		(end 352.380804 -236.710982)
		(width 0.1143)
		(layer "In15.Cu")
		(net "GMI_CPU0_G1_CPU1_G3_TX_DN<7>")
	)
	(segment
		(start 352.384614 -235.088684)
		(end 352.38309 -235.0897)
		(width 0.1143)
		(layer "In15.Cu")
		(net "GMI_CPU0_G1_CPU1_G3_TX_DN<7>")
	)
	(segment
		(start 352.388932 -234.442)
		(end 352.390202 -234.442762)
		(width 0.1143)
		(layer "In15.Cu")
		(net "GMI_CPU0_G1_CPU1_G3_TX_DN<7>")
	)
	(segment
		(start 351.601278 -221.128844)
		(end 351.601278 -221.387416)
		(width 0.1143)
		(layer "In15.Cu")
		(net "GMI_CPU0_G1_CPU1_G3_TX_DN<7>")
	)
	(segment
		(start 119.087138 -239.935766)
		(end 119.087138 -239.93602)
		(width 0.1143)
		(layer "In15.Cu")
		(net "GMI_CPU0_G1_CPU1_G3_TX_DN<7>")
	)
	(segment
		(start 119.107712 -239.946942)
		(end 119.10695 -239.946434)
		(width 0.1143)
		(layer "In15.Cu")
		(net "GMI_CPU0_G1_CPU1_G3_TX_DN<7>")
	)
	(segment
		(start 119.099076 -226.346766)
		(end 119.100092 -226.346258)
		(width 0.1143)
		(layer "In15.Cu")
		(net "GMI_CPU0_G1_CPU1_G3_TX_DN<7>")
	)
	(segment
		(start 352.384614 -243.188744)
		(end 352.38309 -243.18976)
		(width 0.1143)
		(layer "In15.Cu")
		(net "GMI_CPU0_G1_CPU1_G3_TX_DN<7>")
	)
	(segment
		(start 352.387154 -231.847136)
		(end 352.38563 -231.848152)
		(width 0.1143)
		(layer "In15.Cu")
		(net "GMI_CPU0_G1_CPU1_G3_TX_DN<7>")
	)
	(segment
		(start 352.38817 -243.186712)
		(end 352.387154 -243.18722)
		(width 0.1143)
		(layer "In15.Cu")
		(net "GMI_CPU0_G1_CPU1_G3_TX_DN<7>")
	)
	(segment
		(start 352.394266 -244.16512)
		(end 352.396806 -244.16639)
		(width 0.1143)
		(layer "In15.Cu")
		(net "GMI_CPU0_G1_CPU1_G3_TX_DN<7>")
	)
	(segment
		(start 352.387154 -241.567208)
		(end 352.38563 -241.568224)
		(width 0.1143)
		(layer "In15.Cu")
		(net "GMI_CPU0_G1_CPU1_G3_TX_DN<7>")
	)
	(segment
		(start 152.837134 -189.266576)
		(end 153.161492 -189.000638)
		(width 0.14224)
		(layer "In15.Cu")
		(net "GMI_CPU0_G1_CPU1_G3_TX_DN<7>")
	)
	(segment
		(start 352.356674 -239.28324)
		(end 352.38817 -239.301528)
		(width 0.1143)
		(layer "In15.Cu")
		(net "GMI_CPU0_G1_CPU1_G3_TX_DN<7>")
	)
	(segment
		(start 119.107712 -243.186966)
		(end 119.10695 -243.186458)
		(width 0.1143)
		(layer "In15.Cu")
		(net "GMI_CPU0_G1_CPU1_G3_TX_DN<7>")
	)
	(segment
		(start 154.652726 -187.777628)
		(end 154.977084 -187.51169)
		(width 0.14224)
		(layer "In15.Cu")
		(net "GMI_CPU0_G1_CPU1_G3_TX_DN<7>")
	)
	(segment
		(start 352.38817 -242.541552)
		(end 352.41992 -242.55984)
		(width 0.1143)
		(layer "In15.Cu")
		(net "GMI_CPU0_G1_CPU1_G3_TX_DN<7>")
	)
	(segment
		(start 119.10441 -242.543584)
		(end 119.105426 -242.543076)
		(width 0.1143)
		(layer "In15.Cu")
		(net "GMI_CPU0_G1_CPU1_G3_TX_DN<7>")
	)
	(segment
		(start 352.382074 -241.570256)
		(end 352.380804 -241.571018)
		(width 0.1143)
		(layer "In15.Cu")
		(net "GMI_CPU0_G1_CPU1_G3_TX_DN<7>")
	)
	(segment
		(start 352.387154 -244.807232)
		(end 352.38563 -244.808248)
		(width 0.1143)
		(layer "In15.Cu")
		(net "GMI_CPU0_G1_CPU1_G3_TX_DN<7>")
	)
	(segment
		(start 352.349054 -239.278668)
		(end 352.355912 -239.282732)
		(width 0.1143)
		(layer "In15.Cu")
		(net "GMI_CPU0_G1_CPU1_G3_TX_DN<7>")
	)
	(segment
		(start 352.349054 -242.518692)
		(end 352.373184 -242.532662)
		(width 0.1143)
		(layer "In15.Cu")
		(net "GMI_CPU0_G1_CPU1_G3_TX_DN<7>")
	)
	(segment
		(start 352.38563 -235.088176)
		(end 352.384614 -235.088684)
		(width 0.1143)
		(layer "In15.Cu")
		(net "GMI_CPU0_G1_CPU1_G3_TX_DN<7>")
	)
	(segment
		(start 119.086376 -239.935512)
		(end 119.081296 -239.932464)
		(width 0.1143)
		(layer "In15.Cu")
		(net "GMI_CPU0_G1_CPU1_G3_TX_DN<7>")
	)
	(segment
		(start 119.10568 -223.745806)
		(end 119.10314 -223.744536)
		(width 0.1143)
		(layer "In15.Cu")
		(net "GMI_CPU0_G1_CPU1_G3_TX_DN<7>")
	)
	(segment
		(start 352.390202 -239.302798)
		(end 352.391726 -239.30356)
		(width 0.1143)
		(layer "In15.Cu")
		(net "GMI_CPU0_G1_CPU1_G3_TX_DN<7>")
	)
	(segment
		(start 352.38817 -241.5667)
		(end 352.387154 -241.567208)
		(width 0.1143)
		(layer "In15.Cu")
		(net "GMI_CPU0_G1_CPU1_G3_TX_DN<7>")
	)
	(segment
		(start 352.349054 -231.178862)
		(end 352.38817 -231.201722)
		(width 0.1143)
		(layer "In15.Cu")
		(net "GMI_CPU0_G1_CPU1_G3_TX_DN<7>")
	)
	(segment
		(start 352.380804 -236.710982)
		(end 352.380042 -236.71149)
		(width 0.1143)
		(layer "In15.Cu")
		(net "GMI_CPU0_G1_CPU1_G3_TX_DN<7>")
	)
	(segment
		(start 352.38309 -239.949736)
		(end 352.382074 -239.950244)
		(width 0.1143)
		(layer "In15.Cu")
		(net "GMI_CPU0_G1_CPU1_G3_TX_DN<7>")
	)
	(segment
		(start 352.396806 -232.826306)
		(end 352.41992 -232.839768)
		(width 0.1143)
		(layer "In15.Cu")
		(net "GMI_CPU0_G1_CPU1_G3_TX_DN<7>")
	)
	(segment
		(start 155.50134 -187.081668)
		(end 155.825698 -186.81573)
		(width 0.14224)
		(layer "In15.Cu")
		(net "GMI_CPU0_G1_CPU1_G3_TX_DN<7>")
	)
	(segment
		(start 119.101616 -231.843326)
		(end 119.075962 -231.828594)
		(width 0.1143)
		(layer "In15.Cu")
		(net "GMI_CPU0_G1_CPU1_G3_TX_DN<7>")
	)
	(segment
		(start 149.64283 -191.718438)
		(end 149.972776 -191.447928)
		(width 0.14224)
		(layer "In15.Cu")
		(net "GMI_CPU0_G1_CPU1_G3_TX_DN<7>")
	)
	(segment
		(start 352.377756 -231.852724)
		(end 352.376994 -231.853232)
		(width 0.1143)
		(layer "In15.Cu")
		(net "GMI_CPU0_G1_CPU1_G3_TX_DN<7>")
	)
	(segment
		(start 160.079182 -183.160416)
		(end 160.576768 -182.882794)
		(width 0.14224)
		(layer "In15.Cu")
		(net "GMI_CPU0_G1_CPU1_G3_TX_DN<7>")
	)
	(segment
		(start 119.10314 -243.184426)
		(end 119.101616 -243.18341)
		(width 0.1143)
		(layer "In15.Cu")
		(net "GMI_CPU0_G1_CPU1_G3_TX_DN<7>")
	)
	(segment
		(start 351.91827 -247.236742)
		(end 351.879154 -247.259602)
		(width 0.1143)
		(layer "In15.Cu")
		(net "GMI_CPU0_G1_CPU1_G3_TX_DN<7>")
	)
	(segment
		(start 351.448116 -224.721674)
		(end 351.47885 -224.739454)
		(width 0.1143)
		(layer "In15.Cu")
		(net "GMI_CPU0_G1_CPU1_G3_TX_DN<7>")
	)
	(segment
		(start 352.38817 -237.681516)
		(end 352.41992 -237.699804)
		(width 0.1143)
		(layer "In15.Cu")
		(net "GMI_CPU0_G1_CPU1_G3_TX_DN<7>")
	)
	(segment
		(start 352.41992 -231.82834)
		(end 352.390202 -231.845358)
		(width 0.1143)
		(layer "In15.Cu")
		(net "GMI_CPU0_G1_CPU1_G3_TX_DN<7>")
	)
	(segment
		(start 352.380804 -244.811042)
		(end 352.380042 -244.81155)
		(width 0.1143)
		(layer "In15.Cu")
		(net "GMI_CPU0_G1_CPU1_G3_TX_DN<7>")
	)
	(segment
		(start 352.380804 -239.951006)
		(end 352.380042 -239.951514)
		(width 0.1143)
		(layer "In15.Cu")
		(net "GMI_CPU0_G1_CPU1_G3_TX_DN<7>")
	)
	(segment
		(start 119.102632 -242.5446)
		(end 119.103648 -242.544092)
		(width 0.1143)
		(layer "In15.Cu")
		(net "GMI_CPU0_G1_CPU1_G3_TX_DN<7>")
	)
	(segment
		(start 119.10568 -239.945418)
		(end 119.09933 -239.94237)
		(width 0.1143)
		(layer "In15.Cu")
		(net "GMI_CPU0_G1_CPU1_G3_TX_DN<7>")
	)
	(segment
		(start 352.387154 -236.707172)
		(end 352.38563 -236.708188)
		(width 0.1143)
		(layer "In15.Cu")
		(net "GMI_CPU0_G1_CPU1_G3_TX_DN<7>")
	)
	(segment
		(start 352.38563 -233.468164)
		(end 352.384614 -233.468672)
		(width 0.1143)
		(layer "In15.Cu")
		(net "GMI_CPU0_G1_CPU1_G3_TX_DN<7>")
	)
	(segment
		(start 352.38309 -244.809772)
		(end 352.382074 -244.81028)
		(width 0.1143)
		(layer "In15.Cu")
		(net "GMI_CPU0_G1_CPU1_G3_TX_DN<7>")
	)
	(segment
		(start 352.380042 -233.471466)
		(end 352.379026 -233.471974)
		(width 0.1143)
		(layer "In15.Cu")
		(net "GMI_CPU0_G1_CPU1_G3_TX_DN<7>")
	)
	(segment
		(start 119.10568 -241.565684)
		(end 119.10314 -241.564414)
		(width 0.1143)
		(layer "In15.Cu")
		(net "GMI_CPU0_G1_CPU1_G3_TX_DN<7>")
	)
	(segment
		(start 352.396806 -239.306354)
		(end 352.41992 -239.319816)
		(width 0.1143)
		(layer "In15.Cu")
		(net "GMI_CPU0_G1_CPU1_G3_TX_DN<7>")
	)
	(segment
		(start 119.075962 -234.460034)
		(end 119.10568 -234.443016)
		(width 0.1143)
		(layer "In15.Cu")
		(net "GMI_CPU0_G1_CPU1_G3_TX_DN<7>")
	)
	(segment
		(start 119.101616 -244.803422)
		(end 119.075962 -244.78869)
		(width 0.1143)
		(layer "In15.Cu")
		(net "GMI_CPU0_G1_CPU1_G3_TX_DN<7>")
	)
	(segment
		(start 119.10695 -239.30229)
		(end 119.107712 -239.301782)
		(width 0.1143)
		(layer "In15.Cu")
		(net "GMI_CPU0_G1_CPU1_G3_TX_DN<7>")
	)
	(segment
		(start 149.29358 -192.182242)
		(end 149.62378 -191.911478)
		(width 0.14224)
		(layer "In15.Cu")
		(net "GMI_CPU0_G1_CPU1_G3_TX_DN<7>")
	)
	(segment
		(start 352.388932 -241.566192)
		(end 352.38817 -241.5667)
		(width 0.1143)
		(layer "In15.Cu")
		(net "GMI_CPU0_G1_CPU1_G3_TX_DN<7>")
	)
	(segment
		(start 351.914714 -225.529648)
		(end 351.91573 -225.530156)
		(width 0.1143)
		(layer "In15.Cu")
		(net "GMI_CPU0_G1_CPU1_G3_TX_DN<7>")
	)
	(segment
		(start 352.381058 -237.677452)
		(end 352.38563 -237.679992)
		(width 0.1143)
		(layer "In15.Cu")
		(net "GMI_CPU0_G1_CPU1_G3_TX_DN<7>")
	)
	(segment
		(start 119.10568 -227.963222)
		(end 119.10695 -227.96246)
		(width 0.1143)
		(layer "In15.Cu")
		(net "GMI_CPU0_G1_CPU1_G3_TX_DN<7>")
	)
	(segment
		(start 352.38817 -245.781576)
		(end 352.41992 -245.799864)
		(width 0.1143)
		(layer "In15.Cu")
		(net "GMI_CPU0_G1_CPU1_G3_TX_DN<7>")
	)
	(segment
		(start 119.101616 -233.463338)
		(end 119.075962 -233.448606)
		(width 0.1143)
		(layer "In15.Cu")
		(net "GMI_CPU0_G1_CPU1_G3_TX_DN<7>")
	)
	(segment
		(start 118.919752 -221.804484)
		(end 118.919752 -221.23781)
		(width 0.1143)
		(layer "In15.Cu")
		(net "GMI_CPU0_G1_CPU1_G3_TX_DN<7>")
	)
	(segment
		(start 119.110252 -238.328708)
		(end 119.107712 -238.32693)
		(width 0.1143)
		(layer "In15.Cu")
		(net "GMI_CPU0_G1_CPU1_G3_TX_DN<7>")
	)
	(segment
		(start 352.380042 -241.571526)
		(end 352.379026 -241.572034)
		(width 0.1143)
		(layer "In15.Cu")
		(net "GMI_CPU0_G1_CPU1_G3_TX_DN<7>")
	)
	(segment
		(start 352.388932 -240.922048)
		(end 352.390202 -240.92281)
		(width 0.1143)
		(layer "In15.Cu")
		(net "GMI_CPU0_G1_CPU1_G3_TX_DN<7>")
	)
	(segment
		(start 119.074184 -229.601522)
		(end 119.107712 -229.581964)
		(width 0.1143)
		(layer "In15.Cu")
		(net "GMI_CPU0_G1_CPU1_G3_TX_DN<7>")
	)
	(segment
		(start 119.10568 -246.42572)
		(end 119.10314 -246.42445)
		(width 0.1143)
		(layer "In15.Cu")
		(net "GMI_CPU0_G1_CPU1_G3_TX_DN<7>")
	)
	(segment
		(start 119.10314 -238.32439)
		(end 119.101616 -238.323374)
		(width 0.1143)
		(layer "In15.Cu")
		(net "GMI_CPU0_G1_CPU1_G3_TX_DN<7>")
	)
	(segment
		(start 352.38563 -243.188236)
		(end 352.384614 -243.188744)
		(width 0.1143)
		(layer "In15.Cu")
		(net "GMI_CPU0_G1_CPU1_G3_TX_DN<7>")
	)
	(segment
		(start 119.10568 -240.923064)
		(end 119.10695 -240.922302)
		(width 0.1143)
		(layer "In15.Cu")
		(net "GMI_CPU0_G1_CPU1_G3_TX_DN<7>")
	)
	(segment
		(start 351.636076 -221.579948)
		(end 351.636076 -221.80423)
		(width 0.1143)
		(layer "In15.Cu")
		(net "GMI_CPU0_G1_CPU1_G3_TX_DN<7>")
	)
	(segment
		(start 155.843986 -186.633612)
		(end 160.079182 -183.160416)
		(width 0.14224)
		(layer "In15.Cu")
		(net "GMI_CPU0_G1_CPU1_G3_TX_DN<7>")
	)
	(segment
		(start 119.075962 -242.560094)
		(end 119.10187 -242.545108)
		(width 0.1143)
		(layer "In15.Cu")
		(net "GMI_CPU0_G1_CPU1_G3_TX_DN<7>")
	)
	(segment
		(start 119.10695 -241.566446)
		(end 119.10568 -241.565684)
		(width 0.1143)
		(layer "In15.Cu")
		(net "GMI_CPU0_G1_CPU1_G3_TX_DN<7>")
	)
	(segment
		(start 152.259538 -189.572646)
		(end 152.654762 -189.248542)
		(width 0.14224)
		(layer "In15.Cu")
		(net "GMI_CPU0_G1_CPU1_G3_TX_DN<7>")
	)
	(segment
		(start 351.449132 -222.126302)
		(end 351.44837 -222.12681)
		(width 0.1143)
		(layer "In15.Cu")
		(net "GMI_CPU0_G1_CPU1_G3_TX_DN<7>")
	)
	(segment
		(start 352.38817 -239.946688)
		(end 352.387154 -239.947196)
		(width 0.1143)
		(layer "In15.Cu")
		(net "GMI_CPU0_G1_CPU1_G3_TX_DN<7>")
	)
	(segment
		(start 352.38817 -233.46664)
		(end 352.387154 -233.467148)
		(width 0.1143)
		(layer "In15.Cu")
		(net "GMI_CPU0_G1_CPU1_G3_TX_DN<7>")
	)
	(segment
		(start 119.10314 -226.98456)
		(end 119.101616 -226.983544)
		(width 0.1143)
		(layer "In15.Cu")
		(net "GMI_CPU0_G1_CPU1_G3_TX_DN<7>")
	)
	(segment
		(start 352.379026 -235.091986)
		(end 352.377756 -235.092748)
		(width 0.1143)
		(layer "In15.Cu")
		(net "GMI_CPU0_G1_CPU1_G3_TX_DN<7>")
	)
	(segment
		(start 119.100092 -226.346258)
		(end 119.100854 -226.34575)
		(width 0.1143)
		(layer "In15.Cu")
		(net "GMI_CPU0_G1_CPU1_G3_TX_DN<7>")
	)
	(segment
		(start 119.075962 -227.98024)
		(end 119.10568 -227.963222)
		(width 0.1143)
		(layer "In15.Cu")
		(net "GMI_CPU0_G1_CPU1_G3_TX_DN<7>")
	)
	(segment
		(start 119.10695 -224.722436)
		(end 119.109236 -224.720912)
		(width 0.1143)
		(layer "In15.Cu")
		(net "GMI_CPU0_G1_CPU1_G3_TX_DN<7>")
	)
	(segment
		(start 119.10695 -243.186458)
		(end 119.10568 -243.185696)
		(width 0.1143)
		(layer "In15.Cu")
		(net "GMI_CPU0_G1_CPU1_G3_TX_DN<7>")
	)
	(segment
		(start 351.94875 -247.218962)
		(end 351.91827 -247.236742)
		(width 0.1143)
		(layer "In15.Cu")
		(net "GMI_CPU0_G1_CPU1_G3_TX_DN<7>")
	)
	(segment
		(start 352.388932 -233.466132)
		(end 352.38817 -233.46664)
		(width 0.1143)
		(layer "In15.Cu")
		(net "GMI_CPU0_G1_CPU1_G3_TX_DN<7>")
	)
	(segment
		(start 352.355912 -236.042708)
		(end 352.356674 -236.043216)
		(width 0.1143)
		(layer "In15.Cu")
		(net "GMI_CPU0_G1_CPU1_G3_TX_DN<7>")
	)
	(segment
		(start 152.654762 -189.248542)
		(end 152.837134 -189.266576)
		(width 0.14224)
		(layer "In15.Cu")
		(net "GMI_CPU0_G1_CPU1_G3_TX_DN<7>")
	)
	(segment
		(start 119.10568 -225.365818)
		(end 119.10314 -225.364548)
		(width 0.1143)
		(layer "In15.Cu")
		(net "GMI_CPU0_G1_CPU1_G3_TX_DN<7>")
	)
	(segment
		(start 352.38309 -231.849676)
		(end 352.382074 -231.850184)
		(width 0.1143)
		(layer "In15.Cu")
		(net "GMI_CPU0_G1_CPU1_G3_TX_DN<7>")
	)
	(segment
		(start 352.390202 -232.82275)
		(end 352.391726 -232.823512)
		(width 0.1143)
		(layer "In15.Cu")
		(net "GMI_CPU0_G1_CPU1_G3_TX_DN<7>")
	)
	(segment
		(start 352.382074 -231.850184)
		(end 352.380804 -231.850946)
		(width 0.1143)
		(layer "In15.Cu")
		(net "GMI_CPU0_G1_CPU1_G3_TX_DN<7>")
	)
	(segment
		(start 352.349054 -236.038644)
		(end 352.355912 -236.042708)
		(width 0.1143)
		(layer "In15.Cu")
		(net "GMI_CPU0_G1_CPU1_G3_TX_DN<7>")
	)
	(segment
		(start 119.10695 -223.102424)
		(end 119.107712 -223.101916)
		(width 0.1143)
		(layer "In15.Cu")
		(net "GMI_CPU0_G1_CPU1_G3_TX_DN<7>")
	)
	(segment
		(start 352.349054 -245.758716)
		(end 352.373184 -245.772686)
		(width 0.1143)
		(layer "In15.Cu")
		(net "GMI_CPU0_G1_CPU1_G3_TX_DN<7>")
	)
	(segment
		(start 119.10568 -239.945672)
		(end 119.10568 -239.945418)
		(width 0.1143)
		(layer "In15.Cu")
		(net "GMI_CPU0_G1_CPU1_G3_TX_DN<7>")
	)
	(segment
		(start 119.147082 -239.279176)
		(end 119.168672 -239.263428)
		(width 0.1143)
		(layer "In15.Cu")
		(net "GMI_CPU0_G1_CPU1_G3_TX_DN<7>")
	)
	(segment
		(start 119.147082 -223.079056)
		(end 119.170958 -223.062038)
		(width 0.1143)
		(layer "In15.Cu")
		(net "GMI_CPU0_G1_CPU1_G3_TX_DN<7>")
	)
	(segment
		(start 149.972776 -191.447928)
		(end 150.165816 -191.466978)
		(width 0.14224)
		(layer "In15.Cu")
		(net "GMI_CPU0_G1_CPU1_G3_TX_DN<7>")
	)
	(segment
		(start 352.391726 -239.30356)
		(end 352.394266 -239.305084)
		(width 0.1143)
		(layer "In15.Cu")
		(net "GMI_CPU0_G1_CPU1_G3_TX_DN<7>")
	)
	(segment
		(start 352.356674 -240.903252)
		(end 352.38817 -240.92154)
		(width 0.1143)
		(layer "In15.Cu")
		(net "GMI_CPU0_G1_CPU1_G3_TX_DN<7>")
	)
	(segment
		(start 351.48012 -222.108522)
		(end 351.449132 -222.126302)
		(width 0.1143)
		(layer "In15.Cu")
		(net "GMI_CPU0_G1_CPU1_G3_TX_DN<7>")
	)
	(segment
		(start 351.445576 -223.748346)
		(end 351.409 -223.769682)
		(width 0.1143)
		(layer "In15.Cu")
		(net "GMI_CPU0_G1_CPU1_G3_TX_DN<7>")
	)
	(segment
		(start 119.10695 -225.36658)
		(end 119.10568 -225.365818)
		(width 0.1143)
		(layer "In15.Cu")
		(net "GMI_CPU0_G1_CPU1_G3_TX_DN<7>")
	)
	(segment
		(start 352.379026 -233.471974)
		(end 352.377756 -233.472736)
		(width 0.1143)
		(layer "In15.Cu")
		(net "GMI_CPU0_G1_CPU1_G3_TX_DN<7>")
	)
	(segment
		(start 119.09933 -239.94237)
		(end 119.099584 -239.942116)
		(width 0.1143)
		(layer "In15.Cu")
		(net "GMI_CPU0_G1_CPU1_G3_TX_DN<7>")
	)
	(segment
		(start 119.10568 -232.823004)
		(end 119.10695 -232.822242)
		(width 0.1143)
		(layer "In15.Cu")
		(net "GMI_CPU0_G1_CPU1_G3_TX_DN<7>")
	)
	(segment
		(start 119.163592 -227.021898)
		(end 119.147336 -227.00996)
		(width 0.1143)
		(layer "In15.Cu")
		(net "GMI_CPU0_G1_CPU1_G3_TX_DN<7>")
	)
	(segment
		(start 352.388932 -244.806216)
		(end 352.38817 -244.806724)
		(width 0.1143)
		(layer "In15.Cu")
		(net "GMI_CPU0_G1_CPU1_G3_TX_DN<7>")
	)
	(segment
		(start 352.376994 -233.473244)
		(end 352.349054 -233.4895)
		(width 0.1143)
		(layer "In15.Cu")
		(net "GMI_CPU0_G1_CPU1_G3_TX_DN<7>")
	)
	(segment
		(start 119.10314 -246.42445)
		(end 119.101616 -246.423434)
		(width 0.1143)
		(layer "In15.Cu")
		(net "GMI_CPU0_G1_CPU1_G3_TX_DN<7>")
	)
	(segment
		(start 351.4471 -223.74733)
		(end 351.445576 -223.748346)
		(width 0.1143)
		(layer "In15.Cu")
		(net "GMI_CPU0_G1_CPU1_G3_TX_DN<7>")
	)
	(segment
		(start 149.62378 -191.911478)
		(end 149.64283 -191.718438)
		(width 0.14224)
		(layer "In15.Cu")
		(net "GMI_CPU0_G1_CPU1_G3_TX_DN<7>")
	)
	(segment
		(start 351.559114 -247.724168)
		(end 351.261172 -247.724168)
		(width 0.1143)
		(layer "In15.Cu")
		(net "GMI_CPU0_G1_CPU1_G3_TX_DN<7>")
	)
	(segment
		(start 119.074184 -231.221534)
		(end 119.074946 -231.221026)
		(width 0.1143)
		(layer "In15.Cu")
		(net "GMI_CPU0_G1_CPU1_G3_TX_DN<7>")
	)
	(segment
		(start 160.576768 -182.882794)
		(end 166.226998 -180.862224)
		(width 0.14224)
		(layer "In15.Cu")
		(net "GMI_CPU0_G1_CPU1_G3_TX_DN<7>")
	)
	(segment
		(start 352.388932 -238.326168)
		(end 352.38817 -238.326676)
		(width 0.1143)
		(layer "In15.Cu")
		(net "GMI_CPU0_G1_CPU1_G3_TX_DN<7>")
	)
	(segment
		(start 352.382074 -239.950244)
		(end 352.380804 -239.951006)
		(width 0.1143)
		(layer "In15.Cu")
		(net "GMI_CPU0_G1_CPU1_G3_TX_DN<7>")
	)
	(segment
		(start 118.92661 -220.991938)
		(end 118.92661 -219.131134)
		(width 0.14224)
		(layer "In15.Cu")
		(net "GMI_CPU0_G1_CPU1_G3_TX_DN<7>")
	)
	(segment
		(start 119.616728 -247.259856)
		(end 119.577612 -247.236996)
		(width 0.1143)
		(layer "In15.Cu")
		(net "GMI_CPU0_G1_CPU1_G3_TX_DN<7>")
	)
	(segment
		(start 352.376486 -245.774718)
		(end 352.377756 -245.77548)
		(width 0.1143)
		(layer "In15.Cu")
		(net "GMI_CPU0_G1_CPU1_G3_TX_DN<7>")
	)
	(segment
		(start 119.10695 -244.162326)
		(end 119.107712 -244.161818)
		(width 0.1143)
		(layer "In15.Cu")
		(net "GMI_CPU0_G1_CPU1_G3_TX_DN<7>")
	)
	(segment
		(start 352.377756 -241.572796)
		(end 352.376994 -241.573304)
		(width 0.1143)
		(layer "In15.Cu")
		(net "GMI_CPU0_G1_CPU1_G3_TX_DN<7>")
	)
	(segment
		(start 352.355912 -239.282732)
		(end 352.356674 -239.28324)
		(width 0.1143)
		(layer "In15.Cu")
		(net "GMI_CPU0_G1_CPU1_G3_TX_DN<7>")
	)
	(segment
		(start 119.14632 -245.759478)
		(end 119.1641 -245.747032)
		(width 0.1143)
		(layer "In15.Cu")
		(net "GMI_CPU0_G1_CPU1_G3_TX_DN<7>")
	)
	(segment
		(start 352.380804 -231.850946)
		(end 352.380042 -231.851454)
		(width 0.1143)
		(layer "In15.Cu")
		(net "GMI_CPU0_G1_CPU1_G3_TX_DN<7>")
	)
	(segment
		(start 119.107458 -230.227124)
		(end 119.107712 -230.22687)
		(width 0.1143)
		(layer "In15.Cu")
		(net "GMI_CPU0_G1_CPU1_G3_TX_DN<7>")
	)
	(segment
		(start 119.087138 -239.93602)
		(end 119.086376 -239.935512)
		(width 0.1143)
		(layer "In15.Cu")
		(net "GMI_CPU0_G1_CPU1_G3_TX_DN<7>")
	)
	(segment
		(start 119.10568 -234.443016)
		(end 119.10695 -234.442254)
		(width 0.1143)
		(layer "In15.Cu")
		(net "GMI_CPU0_G1_CPU1_G3_TX_DN<7>")
	)
	(segment
		(start 352.390202 -236.062774)
		(end 352.391726 -236.063536)
		(width 0.1143)
		(layer "In15.Cu")
		(net "GMI_CPU0_G1_CPU1_G3_TX_DN<7>")
	)
	(segment
		(start 352.41992 -230.208328)
		(end 352.38817 -230.226616)
		(width 0.1143)
		(layer "In15.Cu")
		(net "GMI_CPU0_G1_CPU1_G3_TX_DN<7>")
	)
	(segment
		(start 119.14124 -231.182418)
		(end 119.144034 -231.180894)
		(width 0.1143)
		(layer "In15.Cu")
		(net "GMI_CPU0_G1_CPU1_G3_TX_DN<7>")
	)
	(segment
		(start 352.384614 -239.94872)
		(end 352.38309 -239.949736)
		(width 0.1143)
		(layer "In15.Cu")
		(net "GMI_CPU0_G1_CPU1_G3_TX_DN<7>")
	)
	(segment
		(start 352.390202 -236.705394)
		(end 352.388932 -236.706156)
		(width 0.1143)
		(layer "In15.Cu")
		(net "GMI_CPU0_G1_CPU1_G3_TX_DN<7>")
	)
	(segment
		(start 119.10314 -231.844342)
		(end 119.101616 -231.843326)
		(width 0.1143)
		(layer "In15.Cu")
		(net "GMI_CPU0_G1_CPU1_G3_TX_DN<7>")
	)
	(segment
		(start 352.349054 -232.79862)
		(end 352.355912 -232.802684)
		(width 0.1143)
		(layer "In15.Cu")
		(net "GMI_CPU0_G1_CPU1_G3_TX_DN<7>")
	)
	(segment
		(start 119.10568 -244.805708)
		(end 119.10314 -244.804438)
		(width 0.1143)
		(layer "In15.Cu")
		(net "GMI_CPU0_G1_CPU1_G3_TX_DN<7>")
	)
	(segment
		(start 119.16537 -241.603022)
		(end 119.147082 -241.589814)
		(width 0.1143)
		(layer "In15.Cu")
		(net "GMI_CPU0_G1_CPU1_G3_TX_DN<7>")
	)
	(segment
		(start 119.110252 -243.188744)
		(end 119.107712 -243.186966)
		(width 0.1143)
		(layer "In15.Cu")
		(net "GMI_CPU0_G1_CPU1_G3_TX_DN<7>")
	)
	(segment
		(start 352.388932 -243.186204)
		(end 352.38817 -243.186712)
		(width 0.1143)
		(layer "In15.Cu")
		(net "GMI_CPU0_G1_CPU1_G3_TX_DN<7>")
	)
	(segment
		(start 119.147082 -238.349536)
		(end 119.110252 -238.328708)
		(width 0.1143)
		(layer "In15.Cu")
		(net "GMI_CPU0_G1_CPU1_G3_TX_DN<7>")
	)
	(segment
		(start 351.448116 -223.101662)
		(end 351.44837 -223.101662)
		(width 0.1143)
		(layer "In15.Cu")
		(net "GMI_CPU0_G1_CPU1_G3_TX_DN<7>")
	)
	(segment
		(start 352.379026 -246.43207)
		(end 352.377756 -246.432832)
		(width 0.1143)
		(layer "In15.Cu")
		(net "GMI_CPU0_G1_CPU1_G3_TX_DN<7>")
	)
	(segment
		(start 119.110506 -225.368866)
		(end 119.107712 -225.367088)
		(width 0.1143)
		(layer "In15.Cu")
		(net "GMI_CPU0_G1_CPU1_G3_TX_DN<7>")
	)
	(segment
		(start 119.107712 -245.78183)
		(end 119.14632 -245.759478)
		(width 0.1143)
		(layer "In15.Cu")
		(net "GMI_CPU0_G1_CPU1_G3_TX_DN<7>")
	)
	(segment
		(start 352.38817 -244.806724)
		(end 352.387154 -244.807232)
		(width 0.1143)
		(layer "In15.Cu")
		(net "GMI_CPU0_G1_CPU1_G3_TX_DN<7>")
	)
	(segment
		(start 119.10314 -228.604572)
		(end 119.101616 -228.603556)
		(width 0.1143)
		(layer "In15.Cu")
		(net "GMI_CPU0_G1_CPU1_G3_TX_DN<7>")
	)
	(segment
		(start 119.10187 -226.345242)
		(end 119.102632 -226.344734)
		(width 0.1143)
		(layer "In15.Cu")
		(net "GMI_CPU0_G1_CPU1_G3_TX_DN<7>")
	)
	(segment
		(start 352.377756 -246.432832)
		(end 352.376994 -246.43334)
		(width 0.1143)
		(layer "In15.Cu")
		(net "GMI_CPU0_G1_CPU1_G3_TX_DN<7>")
	)
	(segment
		(start 352.380804 -243.19103)
		(end 352.380042 -243.191538)
		(width 0.1143)
		(layer "In15.Cu")
		(net "GMI_CPU0_G1_CPU1_G3_TX_DN<7>")
	)
	(segment
		(start 119.075962 -239.320324)
		(end 119.075962 -239.32007)
		(width 0.1143)
		(layer "In15.Cu")
		(net "GMI_CPU0_G1_CPU1_G3_TX_DN<7>")
	)
	(segment
		(start 119.107712 -244.806978)
		(end 119.10695 -244.80647)
		(width 0.1143)
		(layer "In15.Cu")
		(net "GMI_CPU0_G1_CPU1_G3_TX_DN<7>")
	)
	(segment
		(start 119.146574 -222.14967)
		(end 119.075708 -222.108776)
		(width 0.1143)
		(layer "In15.Cu")
		(net "GMI_CPU0_G1_CPU1_G3_TX_DN<7>")
	)
	(segment
		(start 119.10314 -225.364548)
		(end 119.101616 -225.363532)
		(width 0.1143)
		(layer "In15.Cu")
		(net "GMI_CPU0_G1_CPU1_G3_TX_DN<7>")
	)
	(segment
		(start 352.376994 -239.953292)
		(end 352.349054 -239.969548)
		(width 0.1143)
		(layer "In15.Cu")
		(net "GMI_CPU0_G1_CPU1_G3_TX_DN<7>")
	)
	(segment
		(start 151.038052 -190.751714)
		(end 151.368252 -190.48095)
		(width 0.14224)
		(layer "In15.Cu")
		(net "GMI_CPU0_G1_CPU1_G3_TX_DN<7>")
	)
	(segment
		(start 119.109236 -224.720912)
		(end 119.146574 -224.699322)
		(width 0.1143)
		(layer "In15.Cu")
		(net "GMI_CPU0_G1_CPU1_G3_TX_DN<7>")
	)
	(segment
		(start 119.075708 -239.320324)
		(end 119.075962 -239.320324)
		(width 0.1143)
		(layer "In15.Cu")
		(net "GMI_CPU0_G1_CPU1_G3_TX_DN<7>")
	)
	(segment
		(start 155.843732 -186.633358)
		(end 155.843986 -186.633612)
		(width 0.14224)
		(layer "In15.Cu")
		(net "GMI_CPU0_G1_CPU1_G3_TX_DN<7>")
	)
	(segment
		(start 119.100854 -226.34575)
		(end 119.10187 -226.345242)
		(width 0.1143)
		(layer "In15.Cu")
		(net "GMI_CPU0_G1_CPU1_G3_TX_DN<7>")
	)
	(segment
		(start 352.38309 -243.18976)
		(end 352.382074 -243.190268)
		(width 0.1143)
		(layer "In15.Cu")
		(net "GMI_CPU0_G1_CPU1_G3_TX_DN<7>")
	)
	(segment
		(start 352.418904 -228.589078)
		(end 352.418142 -228.589586)
		(width 0.1143)
		(layer "In15.Cu")
		(net "GMI_CPU0_G1_CPU1_G3_TX_DN<7>")
	)
	(segment
		(start 352.38563 -241.568224)
		(end 352.384614 -241.568732)
		(width 0.1143)
		(layer "In15.Cu")
		(net "GMI_CPU0_G1_CPU1_G3_TX_DN<7>")
	)
	(segment
		(start 352.380804 -241.571018)
		(end 352.380042 -241.571526)
		(width 0.1143)
		(layer "In15.Cu")
		(net "GMI_CPU0_G1_CPU1_G3_TX_DN<7>")
	)
	(segment
		(start 352.377756 -243.192808)
		(end 352.376994 -243.193316)
		(width 0.1143)
		(layer "In15.Cu")
		(net "GMI_CPU0_G1_CPU1_G3_TX_DN<7>")
	)
	(segment
		(start 119.102632 -226.344734)
		(end 119.103648 -226.344226)
		(width 0.1143)
		(layer "In15.Cu")
		(net "GMI_CPU0_G1_CPU1_G3_TX_DN<7>")
	)
	(segment
		(start 352.380804 -233.470958)
		(end 352.380042 -233.471466)
		(width 0.1143)
		(layer "In15.Cu")
		(net "GMI_CPU0_G1_CPU1_G3_TX_DN<7>")
	)
	(segment
		(start 352.390202 -240.92281)
		(end 352.391726 -240.923572)
		(width 0.1143)
		(layer "In15.Cu")
		(net "GMI_CPU0_G1_CPU1_G3_TX_DN<7>")
	)
	(segment
		(start 307.21808 -181.659276)
		(end 308.692804 -182.186834)
		(width 0.14224)
		(layer "In15.Cu")
		(net "GMI_CPU0_G1_CPU1_G3_TX_DN<7>")
	)
	(segment
		(start 352.377756 -236.71276)
		(end 352.376994 -236.713268)
		(width 0.1143)
		(layer "In15.Cu")
		(net "GMI_CPU0_G1_CPU1_G3_TX_DN<7>")
	)
	(segment
		(start 119.106188 -242.542568)
		(end 119.147082 -242.518946)
		(width 0.1143)
		(layer "In15.Cu")
		(net "GMI_CPU0_G1_CPU1_G3_TX_DN<7>")
	)
	(segment
		(start 119.10822 -230.227632)
		(end 119.107458 -230.227124)
		(width 0.1143)
		(layer "In15.Cu")
		(net "GMI_CPU0_G1_CPU1_G3_TX_DN<7>")
	)
	(segment
		(start 166.226998 -180.862224)
		(end 302.898048 -181.659276)
		(width 0.14224)
		(layer "In15.Cu")
		(net "GMI_CPU0_G1_CPU1_G3_TX_DN<7>")
	)
	(segment
		(start 351.409 -224.698814)
		(end 351.448116 -224.721674)
		(width 0.1143)
		(layer "In15.Cu")
		(net "GMI_CPU0_G1_CPU1_G3_TX_DN<7>")
	)
	(segment
		(start 154.995118 -187.329572)
		(end 155.319222 -187.063888)
		(width 0.14224)
		(layer "In15.Cu")
		(net "GMI_CPU0_G1_CPU1_G3_TX_DN<7>")
	)
	(segment
		(start 119.098822 -239.941608)
		(end 119.087138 -239.935766)
		(width 0.1143)
		(layer "In15.Cu")
		(net "GMI_CPU0_G1_CPU1_G3_TX_DN<7>")
	)
	(segment
		(start 154.146504 -188.025278)
		(end 154.470354 -187.759594)
		(width 0.14224)
		(layer "In15.Cu")
		(net "GMI_CPU0_G1_CPU1_G3_TX_DN<7>")
	)
	(segment
		(start 352.41992 -243.168424)
		(end 352.390202 -243.185442)
		(width 0.1143)
		(layer "In15.Cu")
		(net "GMI_CPU0_G1_CPU1_G3_TX_DN<7>")
	)
	(segment
		(start 145.12163 -195.42506)
		(end 149.10054 -192.162938)
		(width 0.14224)
		(layer "In15.Cu")
		(net "GMI_CPU0_G1_CPU1_G3_TX_DN<7>")
	)
	(segment
		(start 119.076724 -236.689138)
		(end 119.075962 -236.68863)
		(width 0.1143)
		(layer "In15.Cu")
		(net "GMI_CPU0_G1_CPU1_G3_TX_DN<7>")
	)
	(segment
		(start 118.919752 -221.23781)
		(end 118.88089 -221.198948)
		(width 0.1143)
		(layer "In15.Cu")
		(net "GMI_CPU0_G1_CPU1_G3_TX_DN<7>")
	)
	(segment
		(start 119.075962 -232.840022)
		(end 119.10568 -232.823004)
		(width 0.1143)
		(layer "In15.Cu")
		(net "GMI_CPU0_G1_CPU1_G3_TX_DN<7>")
	)
	(segment
		(start 119.075962 -245.800118)
		(end 119.10568 -245.7831)
		(width 0.1143)
		(layer "In15.Cu")
		(net "GMI_CPU0_G1_CPU1_G3_TX_DN<7>")
	)
	(segment
		(start 119.147336 -244.138958)
		(end 119.166386 -244.124988)
		(width 0.1143)
		(layer "In15.Cu")
		(net "GMI_CPU0_G1_CPU1_G3_TX_DN<7>")
	)
	(segment
		(start 118.92661 -221.020386)
		(end 118.92661 -220.991938)
		(width 0.1143)
		(layer "In15.Cu")
		(net "GMI_CPU0_G1_CPU1_G3_TX_DN<7>")
	)
	(segment
		(start 352.377756 -233.472736)
		(end 352.376994 -233.473244)
		(width 0.1143)
		(layer "In15.Cu")
		(net "GMI_CPU0_G1_CPU1_G3_TX_DN<7>")
	)
	(segment
		(start 352.387154 -233.467148)
		(end 352.38563 -233.468164)
		(width 0.1143)
		(layer "In15.Cu")
		(net "GMI_CPU0_G1_CPU1_G3_TX_DN<7>")
	)
	(segment
		(start 352.391726 -232.823512)
		(end 352.394266 -232.825036)
		(width 0.1143)
		(layer "In15.Cu")
		(net "GMI_CPU0_G1_CPU1_G3_TX_DN<7>")
	)
	(segment
		(start 352.380042 -246.431562)
		(end 352.379026 -246.43207)
		(width 0.1143)
		(layer "In15.Cu")
		(net "GMI_CPU0_G1_CPU1_G3_TX_DN<7>")
	)
	(segment
		(start 352.391726 -244.163596)
		(end 352.394266 -244.16512)
		(width 0.1143)
		(layer "In15.Cu")
		(net "GMI_CPU0_G1_CPU1_G3_TX_DN<7>")
	)
	(segment
		(start 154.470354 -187.759594)
		(end 154.652726 -187.777628)
		(width 0.14224)
		(layer "In15.Cu")
		(net "GMI_CPU0_G1_CPU1_G3_TX_DN<7>")
	)
	(segment
		(start 119.936768 -247.724422)
		(end 119.853964 -247.641618)
		(width 0.1143)
		(layer "In15.Cu")
		(net "GMI_CPU0_G1_CPU1_G3_TX_DN<7>")
	)
	(segment
		(start 155.318968 -187.063634)
		(end 155.50134 -187.081668)
		(width 0.14224)
		(layer "In15.Cu")
		(net "GMI_CPU0_G1_CPU1_G3_TX_DN<7>")
	)
	(segment
		(start 351.91827 -225.53168)
		(end 351.919032 -225.532188)
		(width 0.1143)
		(layer "In15.Cu")
		(net "GMI_CPU0_G1_CPU1_G3_TX_DN<7>")
	)
	(segment
		(start 352.38309 -246.429784)
		(end 352.382074 -246.430292)
		(width 0.1143)
		(layer "In15.Cu")
		(net "GMI_CPU0_G1_CPU1_G3_TX_DN<7>")
	)
	(arc
		(start 352.41992 -245.799864)
		(mid 352.575848 -246.104156)
		(end 352.41992 -246.408448)
		(width 0.1143)
		(layer "In15.Cu")
		(net "GMI_CPU0_G1_CPU1_G3_TX_DN<7>")
	)
	(arc
		(start 351.47885 -223.119442)
		(mid 351.594277 -223.252818)
		(end 351.635822 -223.424242)
		(width 0.1143)
		(layer "In15.Cu")
		(net "GMI_CPU0_G1_CPU1_G3_TX_DN<7>")
	)
	(arc
		(start 352.418904 -226.359466)
		(mid 352.575881 -226.664266)
		(end 352.418904 -226.969066)
		(width 0.1143)
		(layer "In15.Cu")
		(net "GMI_CPU0_G1_CPU1_G3_TX_DN<7>")
	)
	(arc
		(start 119.389906 -230.71455)
		(mid 119.314404 -230.433298)
		(end 119.10822 -230.227632)
		(width 0.1143)
		(layer "In15.Cu")
		(net "GMI_CPU0_G1_CPU1_G3_TX_DN<7>")
	)
	(arc
		(start 352.351594 -230.247952)
		(mid 352.170942 -230.450697)
		(end 352.105722 -230.714296)
		(width 0.1143)
		(layer "In15.Cu")
		(net "GMI_CPU0_G1_CPU1_G3_TX_DN<7>")
	)
	(arc
		(start 119.144034 -231.180894)
		(mid 119.1508 -231.176117)
		(end 119.157496 -231.171242)
		(width 0.1143)
		(layer "In15.Cu")
		(net "GMI_CPU0_G1_CPU1_G3_TX_DN<7>")
	)
	(arc
		(start 119.16537 -242.505992)
		(mid 119.396512 -242.05456)
		(end 119.16537 -241.603022)
		(width 0.1143)
		(layer "In15.Cu")
		(net "GMI_CPU0_G1_CPU1_G3_TX_DN<7>")
	)
	(arc
		(start 119.075962 -230.208582)
		(mid 118.961286 -230.075248)
		(end 118.920006 -229.90429)
		(width 0.1143)
		(layer "In15.Cu")
		(net "GMI_CPU0_G1_CPU1_G3_TX_DN<7>")
	)
	(arc
		(start 119.075962 -228.588824)
		(mid 118.920034 -228.284532)
		(end 119.075962 -227.98024)
		(width 0.1143)
		(layer "In15.Cu")
		(net "GMI_CPU0_G1_CPU1_G3_TX_DN<7>")
	)
	(arc
		(start 351.879154 -247.259602)
		(mid 351.727167 -247.41611)
		(end 351.645728 -247.618504)
		(width 0.1143)
		(layer "In15.Cu")
		(net "GMI_CPU0_G1_CPU1_G3_TX_DN<7>")
	)
	(arc
		(start 119.107712 -236.061758)
		(mid 119.388359 -235.574332)
		(end 119.107712 -235.086906)
		(width 0.1143)
		(layer "In15.Cu")
		(net "GMI_CPU0_G1_CPU1_G3_TX_DN<7>")
	)
	(arc
		(start 119.850154 -247.618758)
		(mid 119.800693 -247.472439)
		(end 119.713502 -247.344946)
		(width 0.1143)
		(layer "In15.Cu")
		(net "GMI_CPU0_G1_CPU1_G3_TX_DN<7>")
	)
	(arc
		(start 352.349054 -236.729524)
		(mid 352.105727 -237.19409)
		(end 352.349054 -237.658656)
		(width 0.1143)
		(layer "In15.Cu")
		(net "GMI_CPU0_G1_CPU1_G3_TX_DN<7>")
	)
	(arc
		(start 352.349054 -238.349536)
		(mid 352.105727 -238.814102)
		(end 352.349054 -239.278668)
		(width 0.1143)
		(layer "In15.Cu")
		(net "GMI_CPU0_G1_CPU1_G3_TX_DN<7>")
	)
	(arc
		(start 352.349054 -241.58956)
		(mid 352.105727 -242.054126)
		(end 352.349054 -242.518692)
		(width 0.1143)
		(layer "In15.Cu")
		(net "GMI_CPU0_G1_CPU1_G3_TX_DN<7>")
	)
	(arc
		(start 352.421698 -229.601268)
		(mid 352.535105 -229.734157)
		(end 352.575876 -229.904036)
		(width 0.1143)
		(layer "In15.Cu")
		(net "GMI_CPU0_G1_CPU1_G3_TX_DN<7>")
	)
	(arc
		(start 119.16537 -226.306126)
		(mid 119.396512 -225.854694)
		(end 119.16537 -225.403156)
		(width 0.1143)
		(layer "In15.Cu")
		(net "GMI_CPU0_G1_CPU1_G3_TX_DN<7>")
	)
	(arc
		(start 119.075962 -243.168678)
		(mid 118.920034 -242.864386)
		(end 119.075962 -242.560094)
		(width 0.1143)
		(layer "In15.Cu")
		(net "GMI_CPU0_G1_CPU1_G3_TX_DN<7>")
	)
	(arc
		(start 352.41992 -239.319816)
		(mid 352.575848 -239.624108)
		(end 352.41992 -239.9284)
		(width 0.1143)
		(layer "In15.Cu")
		(net "GMI_CPU0_G1_CPU1_G3_TX_DN<7>")
	)
	(arc
		(start 352.41992 -240.939828)
		(mid 352.575848 -241.24412)
		(end 352.41992 -241.548412)
		(width 0.1143)
		(layer "In15.Cu")
		(net "GMI_CPU0_G1_CPU1_G3_TX_DN<7>")
	)
	(arc
		(start 119.075962 -231.828594)
		(mid 118.961286 -231.69526)
		(end 118.920006 -231.524302)
		(width 0.1143)
		(layer "In15.Cu")
		(net "GMI_CPU0_G1_CPU1_G3_TX_DN<7>")
	)
	(arc
		(start 119.081296 -239.932464)
		(mid 118.919797 -239.627817)
		(end 119.075708 -239.320324)
		(width 0.1143)
		(layer "In15.Cu")
		(net "GMI_CPU0_G1_CPU1_G3_TX_DN<7>")
	)
	(arc
		(start 351.95002 -225.549968)
		(mid 352.064696 -225.683302)
		(end 352.105976 -225.85426)
		(width 0.1143)
		(layer "In15.Cu")
		(net "GMI_CPU0_G1_CPU1_G3_TX_DN<7>")
	)
	(arc
		(start 352.105722 -230.714296)
		(mid 352.170237 -230.976515)
		(end 352.349054 -231.178862)
		(width 0.1143)
		(layer "In15.Cu")
		(net "GMI_CPU0_G1_CPU1_G3_TX_DN<7>")
	)
	(arc
		(start 352.41992 -232.839768)
		(mid 352.575848 -233.14406)
		(end 352.41992 -233.448352)
		(width 0.1143)
		(layer "In15.Cu")
		(net "GMI_CPU0_G1_CPU1_G3_TX_DN<7>")
	)
	(arc
		(start 119.158258 -234.410758)
		(mid 119.385641 -233.95432)
		(end 119.158258 -233.497882)
		(width 0.1143)
		(layer "In15.Cu")
		(net "GMI_CPU0_G1_CPU1_G3_TX_DN<7>")
	)
	(arc
		(start 352.349054 -239.969548)
		(mid 352.105727 -240.434114)
		(end 352.349054 -240.89868)
		(width 0.1143)
		(layer "In15.Cu")
		(net "GMI_CPU0_G1_CPU1_G3_TX_DN<7>")
	)
	(arc
		(start 351.635822 -223.424242)
		(mid 351.594567 -223.595213)
		(end 351.479866 -223.728534)
		(width 0.1143)
		(layer "In15.Cu")
		(net "GMI_CPU0_G1_CPU1_G3_TX_DN<7>")
	)
	(arc
		(start 351.409 -223.769682)
		(mid 351.165673 -224.234248)
		(end 351.409 -224.698814)
		(width 0.1143)
		(layer "In15.Cu")
		(net "GMI_CPU0_G1_CPU1_G3_TX_DN<7>")
	)
	(arc
		(start 118.920006 -231.524302)
		(mid 118.960768 -231.354418)
		(end 119.074184 -231.221534)
		(width 0.1143)
		(layer "In15.Cu")
		(net "GMI_CPU0_G1_CPU1_G3_TX_DN<7>")
	)
	(arc
		(start 352.105976 -225.85426)
		(mid 352.170491 -226.116479)
		(end 352.349308 -226.318826)
		(width 0.1143)
		(layer "In15.Cu")
		(net "GMI_CPU0_G1_CPU1_G3_TX_DN<7>")
	)
	(arc
		(start 352.41992 -236.079792)
		(mid 352.575848 -236.384084)
		(end 352.41992 -236.688376)
		(width 0.1143)
		(layer "In15.Cu")
		(net "GMI_CPU0_G1_CPU1_G3_TX_DN<7>")
	)
	(arc
		(start 351.636076 -221.80423)
		(mid 351.593016 -221.974285)
		(end 351.48012 -222.108522)
		(width 0.1143)
		(layer "In15.Cu")
		(net "GMI_CPU0_G1_CPU1_G3_TX_DN<7>")
	)
	(arc
		(start 119.075962 -233.448606)
		(mid 118.920034 -233.144314)
		(end 119.075962 -232.840022)
		(width 0.1143)
		(layer "In15.Cu")
		(net "GMI_CPU0_G1_CPU1_G3_TX_DN<7>")
	)
	(arc
		(start 352.349054 -246.449596)
		(mid 352.170241 -246.651946)
		(end 352.105722 -246.914162)
		(width 0.1143)
		(layer "In15.Cu")
		(net "GMI_CPU0_G1_CPU1_G3_TX_DN<7>")
	)
	(arc
		(start 119.144034 -234.420664)
		(mid 119.151184 -234.415766)
		(end 119.158258 -234.410758)
		(width 0.1143)
		(layer "In15.Cu")
		(net "GMI_CPU0_G1_CPU1_G3_TX_DN<7>")
	)
	(arc
		(start 119.107712 -240.921794)
		(mid 119.388359 -240.434368)
		(end 119.107712 -239.946942)
		(width 0.1143)
		(layer "In15.Cu")
		(net "GMI_CPU0_G1_CPU1_G3_TX_DN<7>")
	)
	(arc
		(start 352.349308 -227.009706)
		(mid 352.105981 -227.474272)
		(end 352.349308 -227.938838)
		(width 0.1143)
		(layer "In15.Cu")
		(net "GMI_CPU0_G1_CPU1_G3_TX_DN<7>")
	)
	(arc
		(start 352.41992 -234.45978)
		(mid 352.575848 -234.764072)
		(end 352.41992 -235.068364)
		(width 0.1143)
		(layer "In15.Cu")
		(net "GMI_CPU0_G1_CPU1_G3_TX_DN<7>")
	)
	(arc
		(start 119.170958 -223.062038)
		(mid 119.399963 -222.61467)
		(end 119.170958 -222.167196)
		(width 0.1143)
		(layer "In15.Cu")
		(net "GMI_CPU0_G1_CPU1_G3_TX_DN<7>")
	)
	(arc
		(start 352.349054 -231.869488)
		(mid 352.105727 -232.334054)
		(end 352.349054 -232.79862)
		(width 0.1143)
		(layer "In15.Cu")
		(net "GMI_CPU0_G1_CPU1_G3_TX_DN<7>")
	)
	(arc
		(start 119.075962 -223.728788)
		(mid 118.920034 -223.424496)
		(end 119.075962 -223.120204)
		(width 0.1143)
		(layer "In15.Cu")
		(net "GMI_CPU0_G1_CPU1_G3_TX_DN<7>")
	)
	(arc
		(start 119.168672 -239.263428)
		(mid 119.398698 -238.814356)
		(end 119.168672 -238.365284)
		(width 0.1143)
		(layer "In15.Cu")
		(net "GMI_CPU0_G1_CPU1_G3_TX_DN<7>")
	)
	(arc
		(start 119.158258 -233.497882)
		(mid 119.151185 -233.492873)
		(end 119.144034 -233.487976)
		(width 0.1143)
		(layer "In15.Cu")
		(net "GMI_CPU0_G1_CPU1_G3_TX_DN<7>")
	)
	(arc
		(start 352.421698 -231.22128)
		(mid 352.535105 -231.354169)
		(end 352.575876 -231.524048)
		(width 0.1143)
		(layer "In15.Cu")
		(net "GMI_CPU0_G1_CPU1_G3_TX_DN<7>")
	)
	(arc
		(start 119.075962 -225.3488)
		(mid 118.920034 -225.044508)
		(end 119.075962 -224.740216)
		(width 0.1143)
		(layer "In15.Cu")
		(net "GMI_CPU0_G1_CPU1_G3_TX_DN<7>")
	)
	(arc
		(start 352.105722 -246.914162)
		(mid 352.064173 -247.085584)
		(end 351.94875 -247.218962)
		(width 0.1143)
		(layer "In15.Cu")
		(net "GMI_CPU0_G1_CPU1_G3_TX_DN<7>")
	)
	(arc
		(start 119.075962 -226.968812)
		(mid 118.920034 -226.66452)
		(end 119.075962 -226.360228)
		(width 0.1143)
		(layer "In15.Cu")
		(net "GMI_CPU0_G1_CPU1_G3_TX_DN<7>")
	)
	(arc
		(start 351.448116 -222.127064)
		(mid 351.168352 -222.614426)
		(end 351.448116 -223.101662)
		(width 0.1143)
		(layer "In15.Cu")
		(net "GMI_CPU0_G1_CPU1_G3_TX_DN<7>")
	)
	(arc
		(start 119.389906 -229.094538)
		(mid 119.314325 -228.812896)
		(end 119.107712 -228.607112)
		(width 0.1143)
		(layer "In15.Cu")
		(net "GMI_CPU0_G1_CPU1_G3_TX_DN<7>")
	)
	(arc
		(start 351.635822 -225.044254)
		(mid 351.700337 -225.306473)
		(end 351.879154 -225.50882)
		(width 0.1143)
		(layer "In15.Cu")
		(net "GMI_CPU0_G1_CPU1_G3_TX_DN<7>")
	)
	(arc
		(start 119.162068 -232.788206)
		(mid 119.394115 -232.334488)
		(end 119.162068 -231.880664)
		(width 0.1143)
		(layer "In15.Cu")
		(net "GMI_CPU0_G1_CPU1_G3_TX_DN<7>")
	)
	(arc
		(start 352.575876 -229.904036)
		(mid 352.534621 -230.075007)
		(end 352.41992 -230.208328)
		(width 0.1143)
		(layer "In15.Cu")
		(net "GMI_CPU0_G1_CPU1_G3_TX_DN<7>")
	)
	(arc
		(start 119.075962 -246.408702)
		(mid 118.920034 -246.10441)
		(end 119.075962 -245.800118)
		(width 0.1143)
		(layer "In15.Cu")
		(net "GMI_CPU0_G1_CPU1_G3_TX_DN<7>")
	)
	(arc
		(start 119.144034 -229.560882)
		(mid 119.324686 -229.358137)
		(end 119.389906 -229.094538)
		(width 0.1143)
		(layer "In15.Cu")
		(net "GMI_CPU0_G1_CPU1_G3_TX_DN<7>")
	)
	(arc
		(start 352.41992 -242.55984)
		(mid 352.575848 -242.864132)
		(end 352.41992 -243.168424)
		(width 0.1143)
		(layer "In15.Cu")
		(net "GMI_CPU0_G1_CPU1_G3_TX_DN<7>")
	)
	(arc
		(start 352.41992 -237.699804)
		(mid 352.575848 -238.004096)
		(end 352.41992 -238.308388)
		(width 0.1143)
		(layer "In15.Cu")
		(net "GMI_CPU0_G1_CPU1_G3_TX_DN<7>")
	)
	(arc
		(start 118.920006 -229.90429)
		(mid 118.960768 -229.734406)
		(end 119.074184 -229.601522)
		(width 0.1143)
		(layer "In15.Cu")
		(net "GMI_CPU0_G1_CPU1_G3_TX_DN<7>")
	)
	(arc
		(start 119.1641 -245.747032)
		(mid 119.396379 -245.294404)
		(end 119.1641 -244.841776)
		(width 0.1143)
		(layer "In15.Cu")
		(net "GMI_CPU0_G1_CPU1_G3_TX_DN<7>")
	)
	(arc
		(start 119.075708 -222.108776)
		(mid 118.961032 -221.975442)
		(end 118.919752 -221.804484)
		(width 0.1143)
		(layer "In15.Cu")
		(net "GMI_CPU0_G1_CPU1_G3_TX_DN<7>")
	)
	(arc
		(start 119.107712 -237.68177)
		(mid 119.388359 -237.194344)
		(end 119.107712 -236.706918)
		(width 0.1143)
		(layer "In15.Cu")
		(net "GMI_CPU0_G1_CPU1_G3_TX_DN<7>")
	)
	(arc
		(start 352.349054 -233.4895)
		(mid 352.105727 -233.954066)
		(end 352.349054 -234.418632)
		(width 0.1143)
		(layer "In15.Cu")
		(net "GMI_CPU0_G1_CPU1_G3_TX_DN<7>")
	)
	(arc
		(start 352.41992 -244.179852)
		(mid 352.575848 -244.484144)
		(end 352.41992 -244.788436)
		(width 0.1143)
		(layer "In15.Cu")
		(net "GMI_CPU0_G1_CPU1_G3_TX_DN<7>")
	)
	(arc
		(start 352.349054 -235.109512)
		(mid 352.105727 -235.574078)
		(end 352.349054 -236.038644)
		(width 0.1143)
		(layer "In15.Cu")
		(net "GMI_CPU0_G1_CPU1_G3_TX_DN<7>")
	)
	(arc
		(start 119.174514 -224.679256)
		(mid 119.402514 -224.234502)
		(end 119.174514 -223.789748)
		(width 0.1143)
		(layer "In15.Cu")
		(net "GMI_CPU0_G1_CPU1_G3_TX_DN<7>")
	)
	(arc
		(start 119.402606 -246.922798)
		(mid 119.327438 -246.641445)
		(end 119.121936 -246.435118)
		(width 0.1143)
		(layer "In15.Cu")
		(net "GMI_CPU0_G1_CPU1_G3_TX_DN<7>")
	)
	(arc
		(start 351.645728 -247.618504)
		(mid 351.643705 -247.629914)
		(end 351.641918 -247.641364)
		(width 0.1143)
		(layer "In15.Cu")
		(net "GMI_CPU0_G1_CPU1_G3_TX_DN<7>")
	)
	(arc
		(start 119.075962 -236.68863)
		(mid 118.920034 -236.384338)
		(end 119.075962 -236.080046)
		(width 0.1143)
		(layer "In15.Cu")
		(net "GMI_CPU0_G1_CPU1_G3_TX_DN<7>")
	)
	(arc
		(start 352.349054 -244.829584)
		(mid 352.105727 -245.29415)
		(end 352.349054 -245.758716)
		(width 0.1143)
		(layer "In15.Cu")
		(net "GMI_CPU0_G1_CPU1_G3_TX_DN<7>")
	)
	(arc
		(start 119.157496 -231.171242)
		(mid 119.328466 -230.970765)
		(end 119.389906 -230.71455)
		(width 0.1143)
		(layer "In15.Cu")
		(net "GMI_CPU0_G1_CPU1_G3_TX_DN<7>")
	)
	(arc
		(start 352.349054 -243.209572)
		(mid 352.105727 -243.674138)
		(end 352.349054 -244.138704)
		(width 0.1143)
		(layer "In15.Cu")
		(net "GMI_CPU0_G1_CPU1_G3_TX_DN<7>")
	)
	(arc
		(start 119.163592 -227.927154)
		(mid 119.395342 -227.474526)
		(end 119.163592 -227.021898)
		(width 0.1143)
		(layer "In15.Cu")
		(net "GMI_CPU0_G1_CPU1_G3_TX_DN<7>")
	)
	(arc
		(start 119.166386 -244.124988)
		(mid 119.397015 -243.674392)
		(end 119.166386 -243.223796)
		(width 0.1143)
		(layer "In15.Cu")
		(net "GMI_CPU0_G1_CPU1_G3_TX_DN<7>")
	)
	(arc
		(start 352.349054 -228.629718)
		(mid 352.105727 -229.094284)
		(end 352.349054 -229.55885)
		(width 0.1143)
		(layer "In15.Cu")
		(net "GMI_CPU0_G1_CPU1_G3_TX_DN<7>")
	)
	(arc
		(start 119.853964 -247.641618)
		(mid 119.852176 -247.630169)
		(end 119.850154 -247.618758)
		(width 0.1143)
		(layer "In15.Cu")
		(net "GMI_CPU0_G1_CPU1_G3_TX_DN<7>")
	)
	(arc
		(start 351.47885 -224.739454)
		(mid 351.594277 -224.87283)
		(end 351.635822 -225.044254)
		(width 0.1143)
		(layer "In15.Cu")
		(net "GMI_CPU0_G1_CPU1_G3_TX_DN<7>")
	)
	(arc
		(start 352.418904 -227.979478)
		(mid 352.575881 -228.284278)
		(end 352.418904 -228.589078)
		(width 0.1143)
		(layer "In15.Cu")
		(net "GMI_CPU0_G1_CPU1_G3_TX_DN<7>")
	)
	(arc
		(start 119.075962 -241.548666)
		(mid 118.920034 -241.244374)
		(end 119.075962 -240.940082)
		(width 0.1143)
		(layer "In15.Cu")
		(net "GMI_CPU0_G1_CPU1_G3_TX_DN<7>")
	)
	(arc
		(start 119.075962 -244.78869)
		(mid 118.920034 -244.484398)
		(end 119.075962 -244.180106)
		(width 0.1143)
		(layer "In15.Cu")
		(net "GMI_CPU0_G1_CPU1_G3_TX_DN<7>")
	)
	(arc
		(start 119.075962 -235.068618)
		(mid 118.920034 -234.764326)
		(end 119.075962 -234.460034)
		(width 0.1143)
		(layer "In15.Cu")
		(net "GMI_CPU0_G1_CPU1_G3_TX_DN<7>")
	)
	(arc
		(start 119.713502 -247.344946)
		(mid 119.667554 -247.299627)
		(end 119.616728 -247.259856)
		(width 0.1143)
		(layer "In15.Cu")
		(net "GMI_CPU0_G1_CPU1_G3_TX_DN<7>")
	)
	(arc
		(start 119.075962 -238.308642)
		(mid 118.920034 -238.00435)
		(end 119.075962 -237.700058)
		(width 0.1143)
		(layer "In15.Cu")
		(net "GMI_CPU0_G1_CPU1_G3_TX_DN<7>")
	)
	(arc
		(start 352.575876 -231.524048)
		(mid 352.534621 -231.695019)
		(end 352.41992 -231.82834)
		(width 0.1143)
		(layer "In15.Cu")
		(net "GMI_CPU0_G1_CPU1_G3_TX_DN<7>")
	)
	(arc
		(start 119.577612 -247.236996)
		(mid 119.44954 -247.109069)
		(end 119.402606 -246.934228)
		(width 0.1143)
		(layer "In15.Cu")
		(net "GMI_CPU0_G1_CPU1_G3_TX_DN<7>")
	)
	(segment
		(start 116.94795 -246.370348)
		(end 117.414802 -246.10441)
		(width 0.12954)
		(layer "F.Cu")
		(net "GMI_CPU0_G1_CPU1_G3_TX_DN<6>")
	)
	(segment
		(start 354.547932 -246.370094)
		(end 354.08108 -246.104156)
		(width 0.12954)
		(layer "F.Cu")
		(net "GMI_CPU0_G1_CPU1_G3_TX_DN<6>")
	)
	(segment
		(start 118.206774 -241.589814)
		(end 118.167658 -241.566954)
		(width 0.1143)
		(layer "In15.Cu")
		(net "GMI_CPU0_G1_CPU1_G3_TX_DN<6>")
	)
	(segment
		(start 353.328224 -226.341686)
		(end 353.358704 -226.359466)
		(width 0.1143)
		(layer "In15.Cu")
		(net "GMI_CPU0_G1_CPU1_G3_TX_DN<6>")
	)
	(segment
		(start 352.551492 -221.128844)
		(end 352.551492 -221.38767)
		(width 0.1143)
		(layer "In15.Cu")
		(net "GMI_CPU0_G1_CPU1_G3_TX_DN<6>")
	)
	(segment
		(start 352.575876 -221.579948)
		(end 352.575876 -221.80423)
		(width 0.1143)
		(layer "In15.Cu")
		(net "GMI_CPU0_G1_CPU1_G3_TX_DN<6>")
	)
	(segment
		(start 118.206774 -227.00996)
		(end 118.167658 -226.9871)
		(width 0.1143)
		(layer "In15.Cu")
		(net "GMI_CPU0_G1_CPU1_G3_TX_DN<6>")
	)
	(segment
		(start 118.167658 -228.607112)
		(end 118.137178 -228.589332)
		(width 0.1143)
		(layer "In15.Cu")
		(net "GMI_CPU0_G1_CPU1_G3_TX_DN<6>")
	)
	(segment
		(start 353.328224 -233.46664)
		(end 353.289108 -233.4895)
		(width 0.1143)
		(layer "In15.Cu")
		(net "GMI_CPU0_G1_CPU1_G3_TX_DN<6>")
	)
	(segment
		(start 118.167658 -232.821734)
		(end 118.206774 -232.798874)
		(width 0.1143)
		(layer "In15.Cu")
		(net "GMI_CPU0_G1_CPU1_G3_TX_DN<6>")
	)
	(segment
		(start 352.860102 -225.53295)
		(end 352.88982 -225.549968)
		(width 0.1143)
		(layer "In15.Cu")
		(net "GMI_CPU0_G1_CPU1_G3_TX_DN<6>")
	)
	(segment
		(start 118.135146 -231.220772)
		(end 118.167658 -231.201976)
		(width 0.1143)
		(layer "In15.Cu")
		(net "GMI_CPU0_G1_CPU1_G3_TX_DN<6>")
	)
	(segment
		(start 353.358704 -238.308896)
		(end 353.328224 -238.326676)
		(width 0.1143)
		(layer "In15.Cu")
		(net "GMI_CPU0_G1_CPU1_G3_TX_DN<6>")
	)
	(segment
		(start 152.571704 -187.925964)
		(end 152.764744 -187.945014)
		(width 0.14224)
		(layer "In15.Cu")
		(net "GMI_CPU0_G1_CPU1_G3_TX_DN<6>")
	)
	(segment
		(start 352.857054 -225.531172)
		(end 352.85807 -225.53168)
		(width 0.1143)
		(layer "In15.Cu")
		(net "GMI_CPU0_G1_CPU1_G3_TX_DN<6>")
	)
	(segment
		(start 118.206774 -238.34979)
		(end 118.167658 -238.32693)
		(width 0.1143)
		(layer "In15.Cu")
		(net "GMI_CPU0_G1_CPU1_G3_TX_DN<6>")
	)
	(segment
		(start 352.41992 -222.108522)
		(end 352.38817 -222.12681)
		(width 0.1143)
		(layer "In15.Cu")
		(net "GMI_CPU0_G1_CPU1_G3_TX_DN<6>")
	)
	(segment
		(start 118.137178 -237.69955)
		(end 118.167658 -237.68177)
		(width 0.1143)
		(layer "In15.Cu")
		(net "GMI_CPU0_G1_CPU1_G3_TX_DN<6>")
	)
	(segment
		(start 118.137178 -242.559586)
		(end 118.167658 -242.541806)
		(width 0.1143)
		(layer "In15.Cu")
		(net "GMI_CPU0_G1_CPU1_G3_TX_DN<6>")
	)
	(segment
		(start 118.167658 -244.161818)
		(end 118.206774 -244.138958)
		(width 0.1143)
		(layer "In15.Cu")
		(net "GMI_CPU0_G1_CPU1_G3_TX_DN<6>")
	)
	(segment
		(start 118.167658 -226.34194)
		(end 118.206774 -226.31908)
		(width 0.1143)
		(layer "In15.Cu")
		(net "GMI_CPU0_G1_CPU1_G3_TX_DN<6>")
	)
	(segment
		(start 353.328224 -232.82148)
		(end 353.358704 -232.83926)
		(width 0.1143)
		(layer "In15.Cu")
		(net "GMI_CPU0_G1_CPU1_G3_TX_DN<6>")
	)
	(segment
		(start 353.289108 -239.278668)
		(end 353.328224 -239.301528)
		(width 0.1143)
		(layer "In15.Cu")
		(net "GMI_CPU0_G1_CPU1_G3_TX_DN<6>")
	)
	(segment
		(start 117.11686 -246.10441)
		(end 117.04701 -246.03456)
		(width 0.1143)
		(layer "In15.Cu")
		(net "GMI_CPU0_G1_CPU1_G3_TX_DN<6>")
	)
	(segment
		(start 352.858832 -225.532188)
		(end 352.860102 -225.53295)
		(width 0.1143)
		(layer "In15.Cu")
		(net "GMI_CPU0_G1_CPU1_G3_TX_DN<6>")
	)
	(segment
		(start 353.358704 -226.969066)
		(end 353.328224 -226.986846)
		(width 0.1143)
		(layer "In15.Cu")
		(net "GMI_CPU0_G1_CPU1_G3_TX_DN<6>")
	)
	(segment
		(start 118.137178 -236.079538)
		(end 118.167658 -236.061758)
		(width 0.1143)
		(layer "In15.Cu")
		(net "GMI_CPU0_G1_CPU1_G3_TX_DN<6>")
	)
	(segment
		(start 152.764744 -187.945014)
		(end 153.094944 -187.67425)
		(width 0.14224)
		(layer "In15.Cu")
		(net "GMI_CPU0_G1_CPU1_G3_TX_DN<6>")
	)
	(segment
		(start 353.328224 -243.186712)
		(end 353.289108 -243.209572)
		(width 0.1143)
		(layer "In15.Cu")
		(net "GMI_CPU0_G1_CPU1_G3_TX_DN<6>")
	)
	(segment
		(start 118.167658 -241.566954)
		(end 118.137178 -241.549174)
		(width 0.1143)
		(layer "In15.Cu")
		(net "GMI_CPU0_G1_CPU1_G3_TX_DN<6>")
	)
	(segment
		(start 309.41137 -181.434486)
		(end 312.471308 -183.166766)
		(width 0.14224)
		(layer "In15.Cu")
		(net "GMI_CPU0_G1_CPU1_G3_TX_DN<6>")
	)
	(segment
		(start 118.137178 -239.319562)
		(end 118.167658 -239.301782)
		(width 0.1143)
		(layer "In15.Cu")
		(net "GMI_CPU0_G1_CPU1_G3_TX_DN<6>")
	)
	(segment
		(start 353.289108 -244.138704)
		(end 353.328224 -244.161564)
		(width 0.1143)
		(layer "In15.Cu")
		(net "GMI_CPU0_G1_CPU1_G3_TX_DN<6>")
	)
	(segment
		(start 353.328224 -227.961698)
		(end 353.358704 -227.979478)
		(width 0.1143)
		(layer "In15.Cu")
		(net "GMI_CPU0_G1_CPU1_G3_TX_DN<6>")
	)
	(segment
		(start 302.901096 -180.711348)
		(end 307.388006 -180.711348)
		(width 0.14224)
		(layer "In15.Cu")
		(net "GMI_CPU0_G1_CPU1_G3_TX_DN<6>")
	)
	(segment
		(start 353.289108 -237.658656)
		(end 353.328224 -237.681516)
		(width 0.1143)
		(layer "In15.Cu")
		(net "GMI_CPU0_G1_CPU1_G3_TX_DN<6>")
	)
	(segment
		(start 118.206774 -231.869742)
		(end 118.167658 -231.846882)
		(width 0.1143)
		(layer "In15.Cu")
		(net "GMI_CPU0_G1_CPU1_G3_TX_DN<6>")
	)
	(segment
		(start 117.696996 -244.972332)
		(end 117.697758 -244.971824)
		(width 0.1143)
		(layer "In15.Cu")
		(net "GMI_CPU0_G1_CPU1_G3_TX_DN<6>")
	)
	(segment
		(start 154.452066 -186.384184)
		(end 154.645106 -186.403234)
		(width 0.14224)
		(layer "In15.Cu")
		(net "GMI_CPU0_G1_CPU1_G3_TX_DN<6>")
	)
	(segment
		(start 353.289108 -240.89868)
		(end 353.328224 -240.92154)
		(width 0.1143)
		(layer "In15.Cu")
		(net "GMI_CPU0_G1_CPU1_G3_TX_DN<6>")
	)
	(segment
		(start 353.289108 -242.518692)
		(end 353.328224 -242.541552)
		(width 0.1143)
		(layer "In15.Cu")
		(net "GMI_CPU0_G1_CPU1_G3_TX_DN<6>")
	)
	(segment
		(start 144.408144 -194.620134)
		(end 146.330924 -193.043302)
		(width 0.14224)
		(layer "In15.Cu")
		(net "GMI_CPU0_G1_CPU1_G3_TX_DN<6>")
	)
	(segment
		(start 312.471308 -183.166512)
		(end 315.531246 -184.898792)
		(width 0.14224)
		(layer "In15.Cu")
		(net "GMI_CPU0_G1_CPU1_G3_TX_DN<6>")
	)
	(segment
		(start 118.167658 -227.961952)
		(end 118.206774 -227.939092)
		(width 0.1143)
		(layer "In15.Cu")
		(net "GMI_CPU0_G1_CPU1_G3_TX_DN<6>")
	)
	(segment
		(start 352.38817 -224.721674)
		(end 352.41865 -224.739454)
		(width 0.1143)
		(layer "In15.Cu")
		(net "GMI_CPU0_G1_CPU1_G3_TX_DN<6>")
	)
	(segment
		(start 151.350472 -189.104778)
		(end 151.369522 -188.911738)
		(width 0.14224)
		(layer "In15.Cu")
		(net "GMI_CPU0_G1_CPU1_G3_TX_DN<6>")
	)
	(segment
		(start 353.998276 -245.303548)
		(end 353.998276 -245.3132)
		(width 0.1143)
		(layer "In15.Cu")
		(net "GMI_CPU0_G1_CPU1_G3_TX_DN<6>")
	)
	(segment
		(start 118.137178 -240.939574)
		(end 118.167658 -240.921794)
		(width 0.1143)
		(layer "In15.Cu")
		(net "GMI_CPU0_G1_CPU1_G3_TX_DN<6>")
	)
	(segment
		(start 352.855276 -225.530156)
		(end 352.857054 -225.531172)
		(width 0.1143)
		(layer "In15.Cu")
		(net "GMI_CPU0_G1_CPU1_G3_TX_DN<6>")
	)
	(segment
		(start 154.994356 -185.93943)
		(end 159.441896 -182.292244)
		(width 0.14224)
		(layer "In15.Cu")
		(net "GMI_CPU0_G1_CPU1_G3_TX_DN<6>")
	)
	(segment
		(start 118.167658 -238.32693)
		(end 118.137178 -238.30915)
		(width 0.1143)
		(layer "In15.Cu")
		(net "GMI_CPU0_G1_CPU1_G3_TX_DN<6>")
	)
	(segment
		(start 148.752814 -191.05753)
		(end 149.08276 -190.78702)
		(width 0.14224)
		(layer "In15.Cu")
		(net "GMI_CPU0_G1_CPU1_G3_TX_DN<6>")
	)
	(segment
		(start 353.289108 -226.318826)
		(end 353.328224 -226.341686)
		(width 0.1143)
		(layer "In15.Cu")
		(net "GMI_CPU0_G1_CPU1_G3_TX_DN<6>")
	)
	(segment
		(start 352.853752 -225.52914)
		(end 352.855276 -225.530156)
		(width 0.1143)
		(layer "In15.Cu")
		(net "GMI_CPU0_G1_CPU1_G3_TX_DN<6>")
	)
	(segment
		(start 353.328224 -237.681516)
		(end 353.358704 -237.699296)
		(width 0.1143)
		(layer "In15.Cu")
		(net "GMI_CPU0_G1_CPU1_G3_TX_DN<6>")
	)
	(segment
		(start 352.38817 -223.101662)
		(end 352.41992 -223.11995)
		(width 0.1143)
		(layer "In15.Cu")
		(net "GMI_CPU0_G1_CPU1_G3_TX_DN<6>")
	)
	(segment
		(start 353.328224 -229.58171)
		(end 353.360736 -229.600506)
		(width 0.1143)
		(layer "In15.Cu")
		(net "GMI_CPU0_G1_CPU1_G3_TX_DN<6>")
	)
	(segment
		(start 118.167658 -223.747076)
		(end 118.137178 -223.729296)
		(width 0.1143)
		(layer "In15.Cu")
		(net "GMI_CPU0_G1_CPU1_G3_TX_DN<6>")
	)
	(segment
		(start 353.328224 -244.161564)
		(end 353.358704 -244.179344)
		(width 0.1143)
		(layer "In15.Cu")
		(net "GMI_CPU0_G1_CPU1_G3_TX_DN<6>")
	)
	(segment
		(start 353.358704 -239.928908)
		(end 353.328224 -239.946688)
		(width 0.1143)
		(layer "In15.Cu")
		(net "GMI_CPU0_G1_CPU1_G3_TX_DN<6>")
	)
	(segment
		(start 154.975306 -186.13247)
		(end 154.994356 -185.93943)
		(width 0.14224)
		(layer "In15.Cu")
		(net "GMI_CPU0_G1_CPU1_G3_TX_DN<6>")
	)
	(segment
		(start 153.094944 -187.67425)
		(end 153.113994 -187.48121)
		(width 0.14224)
		(layer "In15.Cu")
		(net "GMI_CPU0_G1_CPU1_G3_TX_DN<6>")
	)
	(segment
		(start 117.227604 -245.78183)
		(end 117.26672 -245.75897)
		(width 0.1143)
		(layer "In15.Cu")
		(net "GMI_CPU0_G1_CPU1_G3_TX_DN<6>")
	)
	(segment
		(start 352.351848 -223.76765)
		(end 352.349054 -223.769682)
		(width 0.1143)
		(layer "In15.Cu")
		(net "GMI_CPU0_G1_CPU1_G3_TX_DN<6>")
	)
	(segment
		(start 118.206774 -233.489754)
		(end 118.167658 -233.466894)
		(width 0.1143)
		(layer "In15.Cu")
		(net "GMI_CPU0_G1_CPU1_G3_TX_DN<6>")
	)
	(segment
		(start 118.167658 -242.541806)
		(end 118.206774 -242.518946)
		(width 0.1143)
		(layer "In15.Cu")
		(net "GMI_CPU0_G1_CPU1_G3_TX_DN<6>")
	)
	(segment
		(start 118.206774 -228.629972)
		(end 118.167658 -228.607112)
		(width 0.1143)
		(layer "In15.Cu")
		(net "GMI_CPU0_G1_CPU1_G3_TX_DN<6>")
	)
	(segment
		(start 150.497286 -189.627002)
		(end 150.827232 -189.356492)
		(width 0.14224)
		(layer "In15.Cu")
		(net "GMI_CPU0_G1_CPU1_G3_TX_DN<6>")
	)
	(segment
		(start 118.137178 -227.979732)
		(end 118.167658 -227.961952)
		(width 0.1143)
		(layer "In15.Cu")
		(net "GMI_CPU0_G1_CPU1_G3_TX_DN<6>")
	)
	(segment
		(start 149.62505 -190.342266)
		(end 149.954996 -190.071756)
		(width 0.14224)
		(layer "In15.Cu")
		(net "GMI_CPU0_G1_CPU1_G3_TX_DN<6>")
	)
	(segment
		(start 117.98173 -220.991938)
		(end 117.98173 -218.864434)
		(width 0.14224)
		(layer "In15.Cu")
		(net "GMI_CPU0_G1_CPU1_G3_TX_DN<6>")
	)
	(segment
		(start 166.094664 -179.913534)
		(end 302.901096 -180.711348)
		(width 0.14224)
		(layer "In15.Cu")
		(net "GMI_CPU0_G1_CPU1_G3_TX_DN<6>")
	)
	(segment
		(start 152.241758 -188.196474)
		(end 152.571704 -187.925964)
		(width 0.14224)
		(layer "In15.Cu")
		(net "GMI_CPU0_G1_CPU1_G3_TX_DN<6>")
	)
	(segment
		(start 117.979444 -221.242382)
		(end 117.93601 -221.198948)
		(width 0.1143)
		(layer "In15.Cu")
		(net "GMI_CPU0_G1_CPU1_G3_TX_DN<6>")
	)
	(segment
		(start 118.167658 -243.186966)
		(end 118.137178 -243.169186)
		(width 0.1143)
		(layer "In15.Cu")
		(net "GMI_CPU0_G1_CPU1_G3_TX_DN<6>")
	)
	(segment
		(start 353.289108 -232.79862)
		(end 353.328224 -232.82148)
		(width 0.1143)
		(layer "In15.Cu")
		(net "GMI_CPU0_G1_CPU1_G3_TX_DN<6>")
	)
	(segment
		(start 353.328224 -231.201722)
		(end 353.360736 -231.220518)
		(width 0.1143)
		(layer "In15.Cu")
		(net "GMI_CPU0_G1_CPU1_G3_TX_DN<6>")
	)
	(segment
		(start 353.29114 -229.560374)
		(end 353.328224 -229.58171)
		(width 0.1143)
		(layer "In15.Cu")
		(net "GMI_CPU0_G1_CPU1_G3_TX_DN<6>")
	)
	(segment
		(start 118.167658 -236.706918)
		(end 118.137178 -236.689138)
		(width 0.1143)
		(layer "In15.Cu")
		(net "GMI_CPU0_G1_CPU1_G3_TX_DN<6>")
	)
	(segment
		(start 352.551492 -221.38767)
		(end 352.57613 -221.412308)
		(width 0.1143)
		(layer "In15.Cu")
		(net "GMI_CPU0_G1_CPU1_G3_TX_DN<6>")
	)
	(segment
		(start 117.98173 -221.020386)
		(end 117.98173 -220.991938)
		(width 0.1143)
		(layer "In15.Cu")
		(net "GMI_CPU0_G1_CPU1_G3_TX_DN<6>")
	)
	(segment
		(start 149.606 -190.535306)
		(end 149.62505 -190.342266)
		(width 0.14224)
		(layer "In15.Cu")
		(net "GMI_CPU0_G1_CPU1_G3_TX_DN<6>")
	)
	(segment
		(start 150.827232 -189.356492)
		(end 151.020272 -189.375542)
		(width 0.14224)
		(layer "In15.Cu")
		(net "GMI_CPU0_G1_CPU1_G3_TX_DN<6>")
	)
	(segment
		(start 118.167658 -224.721928)
		(end 118.206774 -224.699068)
		(width 0.1143)
		(layer "In15.Cu")
		(net "GMI_CPU0_G1_CPU1_G3_TX_DN<6>")
	)
	(segment
		(start 354.268024 -245.781576)
		(end 354.299774 -245.799864)
		(width 0.1143)
		(layer "In15.Cu")
		(net "GMI_CPU0_G1_CPU1_G3_TX_DN<6>")
	)
	(segment
		(start 118.167658 -237.68177)
		(end 118.206774 -237.65891)
		(width 0.1143)
		(layer "In15.Cu")
		(net "GMI_CPU0_G1_CPU1_G3_TX_DN<6>")
	)
	(segment
		(start 118.206774 -243.209826)
		(end 118.167658 -243.186966)
		(width 0.1143)
		(layer "In15.Cu")
		(net "GMI_CPU0_G1_CPU1_G3_TX_DN<6>")
	)
	(segment
		(start 118.206774 -223.769936)
		(end 118.167658 -223.747076)
		(width 0.1143)
		(layer "In15.Cu")
		(net "GMI_CPU0_G1_CPU1_G3_TX_DN<6>")
	)
	(segment
		(start 118.137178 -226.35972)
		(end 118.167658 -226.34194)
		(width 0.1143)
		(layer "In15.Cu")
		(net "GMI_CPU0_G1_CPU1_G3_TX_DN<6>")
	)
	(segment
		(start 148.733764 -191.25057)
		(end 148.752814 -191.05753)
		(width 0.14224)
		(layer "In15.Cu")
		(net "GMI_CPU0_G1_CPU1_G3_TX_DN<6>")
	)
	(segment
		(start 154.645106 -186.403234)
		(end 154.975306 -186.13247)
		(width 0.14224)
		(layer "In15.Cu")
		(net "GMI_CPU0_G1_CPU1_G3_TX_DN<6>")
	)
	(segment
		(start 118.137178 -232.839514)
		(end 118.167658 -232.821734)
		(width 0.1143)
		(layer "In15.Cu")
		(net "GMI_CPU0_G1_CPU1_G3_TX_DN<6>")
	)
	(segment
		(start 352.826574 -225.513392)
		(end 352.853752 -225.52914)
		(width 0.1143)
		(layer "In15.Cu")
		(net "GMI_CPU0_G1_CPU1_G3_TX_DN<6>")
	)
	(segment
		(start 118.167658 -226.9871)
		(end 118.137178 -226.96932)
		(width 0.1143)
		(layer "In15.Cu")
		(net "GMI_CPU0_G1_CPU1_G3_TX_DN<6>")
	)
	(segment
		(start 151.020272 -189.375542)
		(end 151.350472 -189.104778)
		(width 0.14224)
		(layer "In15.Cu")
		(net "GMI_CPU0_G1_CPU1_G3_TX_DN<6>")
	)
	(segment
		(start 118.167658 -239.301782)
		(end 118.206774 -239.278922)
		(width 0.1143)
		(layer "In15.Cu")
		(net "GMI_CPU0_G1_CPU1_G3_TX_DN<6>")
	)
	(segment
		(start 153.77287 -187.118498)
		(end 154.10307 -186.847734)
		(width 0.14224)
		(layer "In15.Cu")
		(net "GMI_CPU0_G1_CPU1_G3_TX_DN<6>")
	)
	(segment
		(start 352.41992 -223.728534)
		(end 352.38817 -223.746822)
		(width 0.1143)
		(layer "In15.Cu")
		(net "GMI_CPU0_G1_CPU1_G3_TX_DN<6>")
	)
	(segment
		(start 159.441896 -182.292244)
		(end 166.094664 -179.913534)
		(width 0.14224)
		(layer "In15.Cu")
		(net "GMI_CPU0_G1_CPU1_G3_TX_DN<6>")
	)
	(segment
		(start 149.954996 -190.071756)
		(end 150.148036 -190.090806)
		(width 0.14224)
		(layer "In15.Cu")
		(net "GMI_CPU0_G1_CPU1_G3_TX_DN<6>")
	)
	(segment
		(start 117.697758 -244.971824)
		(end 117.736874 -244.948964)
		(width 0.1143)
		(layer "In15.Cu")
		(net "GMI_CPU0_G1_CPU1_G3_TX_DN<6>")
	)
	(segment
		(start 307.388006 -180.711348)
		(end 309.41137 -181.434486)
		(width 0.14224)
		(layer "In15.Cu")
		(net "GMI_CPU0_G1_CPU1_G3_TX_DN<6>")
	)
	(segment
		(start 118.167658 -231.846882)
		(end 118.137178 -231.829102)
		(width 0.1143)
		(layer "In15.Cu")
		(net "GMI_CPU0_G1_CPU1_G3_TX_DN<6>")
	)
	(segment
		(start 353.358704 -231.828848)
		(end 353.328224 -231.846628)
		(width 0.1143)
		(layer "In15.Cu")
		(net "GMI_CPU0_G1_CPU1_G3_TX_DN<6>")
	)
	(segment
		(start 352.349054 -224.698814)
		(end 352.38817 -224.721674)
		(width 0.1143)
		(layer "In15.Cu")
		(net "GMI_CPU0_G1_CPU1_G3_TX_DN<6>")
	)
	(segment
		(start 118.137178 -234.459526)
		(end 118.167658 -234.441746)
		(width 0.1143)
		(layer "In15.Cu")
		(net "GMI_CPU0_G1_CPU1_G3_TX_DN<6>")
	)
	(segment
		(start 353.289108 -231.178862)
		(end 353.328224 -231.201722)
		(width 0.1143)
		(layer "In15.Cu")
		(net "GMI_CPU0_G1_CPU1_G3_TX_DN<6>")
	)
	(segment
		(start 353.328224 -231.846628)
		(end 353.289108 -231.869488)
		(width 0.1143)
		(layer "In15.Cu")
		(net "GMI_CPU0_G1_CPU1_G3_TX_DN<6>")
	)
	(segment
		(start 144.000982 -194.743324)
		(end 144.408144 -194.620134)
		(width 0.14224)
		(layer "In15.Cu")
		(net "GMI_CPU0_G1_CPU1_G3_TX_DN<6>")
	)
	(segment
		(start 353.328224 -236.706664)
		(end 353.289108 -236.729524)
		(width 0.1143)
		(layer "In15.Cu")
		(net "GMI_CPU0_G1_CPU1_G3_TX_DN<6>")
	)
	(segment
		(start 352.505772 -220.22054)
		(end 352.505772 -221.083124)
		(width 0.14224)
		(layer "In15.Cu")
		(net "GMI_CPU0_G1_CPU1_G3_TX_DN<6>")
	)
	(segment
		(start 353.328224 -228.606858)
		(end 353.289108 -228.629718)
		(width 0.1143)
		(layer "In15.Cu")
		(net "GMI_CPU0_G1_CPU1_G3_TX_DN<6>")
	)
	(segment
		(start 117.93601 -221.066106)
		(end 117.98173 -221.020386)
		(width 0.1143)
		(layer "In15.Cu")
		(net "GMI_CPU0_G1_CPU1_G3_TX_DN<6>")
	)
	(segment
		(start 118.167658 -229.581964)
		(end 118.206774 -229.559104)
		(width 0.1143)
		(layer "In15.Cu")
		(net "GMI_CPU0_G1_CPU1_G3_TX_DN<6>")
	)
	(segment
		(start 353.759008 -244.94871)
		(end 353.81057 -244.978682)
		(width 0.1143)
		(layer "In15.Cu")
		(net "GMI_CPU0_G1_CPU1_G3_TX_DN<6>")
	)
	(segment
		(start 118.167658 -225.367088)
		(end 118.137178 -225.349308)
		(width 0.1143)
		(layer "In15.Cu")
		(net "GMI_CPU0_G1_CPU1_G3_TX_DN<6>")
	)
	(segment
		(start 353.358704 -236.688884)
		(end 353.328224 -236.706664)
		(width 0.1143)
		(layer "In15.Cu")
		(net "GMI_CPU0_G1_CPU1_G3_TX_DN<6>")
	)
	(segment
		(start 117.98173 -218.864434)
		(end 121.124726 -213.500208)
		(width 0.14224)
		(layer "In15.Cu")
		(net "GMI_CPU0_G1_CPU1_G3_TX_DN<6>")
	)
	(segment
		(start 352.38817 -223.746822)
		(end 352.351848 -223.76765)
		(width 0.1143)
		(layer "In15.Cu")
		(net "GMI_CPU0_G1_CPU1_G3_TX_DN<6>")
	)
	(segment
		(start 353.358704 -243.168932)
		(end 353.328224 -243.186712)
		(width 0.1143)
		(layer "In15.Cu")
		(net "GMI_CPU0_G1_CPU1_G3_TX_DN<6>")
	)
	(segment
		(start 148.210524 -191.502284)
		(end 148.403564 -191.521334)
		(width 0.14224)
		(layer "In15.Cu")
		(net "GMI_CPU0_G1_CPU1_G3_TX_DN<6>")
	)
	(segment
		(start 118.167658 -239.946942)
		(end 118.137178 -239.929162)
		(width 0.1143)
		(layer "In15.Cu")
		(net "GMI_CPU0_G1_CPU1_G3_TX_DN<6>")
	)
	(segment
		(start 149.08276 -190.78702)
		(end 149.2758 -190.80607)
		(width 0.14224)
		(layer "In15.Cu")
		(net "GMI_CPU0_G1_CPU1_G3_TX_DN<6>")
	)
	(segment
		(start 354.379022 -246.104156)
		(end 354.08108 -246.104156)
		(width 0.1143)
		(layer "In15.Cu")
		(net "GMI_CPU0_G1_CPU1_G3_TX_DN<6>")
	)
	(segment
		(start 151.892508 -188.660278)
		(end 152.222708 -188.389514)
		(width 0.14224)
		(layer "In15.Cu")
		(net "GMI_CPU0_G1_CPU1_G3_TX_DN<6>")
	)
	(segment
		(start 146.330924 -193.043302)
		(end 146.331178 -193.043302)
		(width 0.14224)
		(layer "In15.Cu")
		(net "GMI_CPU0_G1_CPU1_G3_TX_DN<6>")
	)
	(segment
		(start 117.197124 -245.79961)
		(end 117.227604 -245.78183)
		(width 0.1143)
		(layer "In15.Cu")
		(net "GMI_CPU0_G1_CPU1_G3_TX_DN<6>")
	)
	(segment
		(start 353.328224 -239.301528)
		(end 353.358704 -239.319308)
		(width 0.1143)
		(layer "In15.Cu")
		(net "GMI_CPU0_G1_CPU1_G3_TX_DN<6>")
	)
	(segment
		(start 118.206774 -225.389948)
		(end 118.167658 -225.367088)
		(width 0.1143)
		(layer "In15.Cu")
		(net "GMI_CPU0_G1_CPU1_G3_TX_DN<6>")
	)
	(segment
		(start 118.204234 -230.248206)
		(end 118.137178 -230.20909)
		(width 0.1143)
		(layer "In15.Cu")
		(net "GMI_CPU0_G1_CPU1_G3_TX_DN<6>")
	)
	(segment
		(start 118.167658 -231.201976)
		(end 118.206774 -231.179116)
		(width 0.1143)
		(layer "In15.Cu")
		(net "GMI_CPU0_G1_CPU1_G3_TX_DN<6>")
	)
	(segment
		(start 353.289108 -234.418632)
		(end 353.328224 -234.441492)
		(width 0.1143)
		(layer "In15.Cu")
		(net "GMI_CPU0_G1_CPU1_G3_TX_DN<6>")
	)
	(segment
		(start 118.135146 -229.60076)
		(end 118.167658 -229.581964)
		(width 0.1143)
		(layer "In15.Cu")
		(net "GMI_CPU0_G1_CPU1_G3_TX_DN<6>")
	)
	(segment
		(start 154.10307 -186.847734)
		(end 154.12212 -186.654694)
		(width 0.14224)
		(layer "In15.Cu")
		(net "GMI_CPU0_G1_CPU1_G3_TX_DN<6>")
	)
	(segment
		(start 118.167658 -240.921794)
		(end 118.206774 -240.898934)
		(width 0.1143)
		(layer "In15.Cu")
		(net "GMI_CPU0_G1_CPU1_G3_TX_DN<6>")
	)
	(segment
		(start 348.636082 -212.043518)
		(end 352.505772 -220.22054)
		(width 0.14224)
		(layer "In15.Cu")
		(net "GMI_CPU0_G1_CPU1_G3_TX_DN<6>")
	)
	(segment
		(start 353.289108 -229.55885)
		(end 353.29114 -229.560374)
		(width 0.1143)
		(layer "In15.Cu")
		(net "GMI_CPU0_G1_CPU1_G3_TX_DN<6>")
	)
	(segment
		(start 353.358704 -241.54892)
		(end 353.328224 -241.5667)
		(width 0.1143)
		(layer "In15.Cu")
		(net "GMI_CPU0_G1_CPU1_G3_TX_DN<6>")
	)
	(segment
		(start 151.369522 -188.911738)
		(end 151.699468 -188.641228)
		(width 0.14224)
		(layer "In15.Cu")
		(net "GMI_CPU0_G1_CPU1_G3_TX_DN<6>")
	)
	(segment
		(start 353.328224 -242.541552)
		(end 353.358704 -242.559332)
		(width 0.1143)
		(layer "In15.Cu")
		(net "GMI_CPU0_G1_CPU1_G3_TX_DN<6>")
	)
	(segment
		(start 353.328224 -234.441492)
		(end 353.358704 -234.459272)
		(width 0.1143)
		(layer "In15.Cu")
		(net "GMI_CPU0_G1_CPU1_G3_TX_DN<6>")
	)
	(segment
		(start 353.328224 -238.326676)
		(end 353.289108 -238.349536)
		(width 0.1143)
		(layer "In15.Cu")
		(net "GMI_CPU0_G1_CPU1_G3_TX_DN<6>")
	)
	(segment
		(start 352.818954 -225.50882)
		(end 352.825812 -225.512884)
		(width 0.1143)
		(layer "In15.Cu")
		(net "GMI_CPU0_G1_CPU1_G3_TX_DN<6>")
	)
	(segment
		(start 152.222708 -188.389514)
		(end 152.241758 -188.196474)
		(width 0.14224)
		(layer "In15.Cu")
		(net "GMI_CPU0_G1_CPU1_G3_TX_DN<6>")
	)
	(segment
		(start 118.167658 -236.061758)
		(end 118.206774 -236.038898)
		(width 0.1143)
		(layer "In15.Cu")
		(net "GMI_CPU0_G1_CPU1_G3_TX_DN<6>")
	)
	(segment
		(start 149.2758 -190.80607)
		(end 149.606 -190.535306)
		(width 0.14224)
		(layer "In15.Cu")
		(net "GMI_CPU0_G1_CPU1_G3_TX_DN<6>")
	)
	(segment
		(start 118.206774 -239.969802)
		(end 118.167658 -239.946942)
		(width 0.1143)
		(layer "In15.Cu")
		(net "GMI_CPU0_G1_CPU1_G3_TX_DN<6>")
	)
	(segment
		(start 118.137178 -224.739708)
		(end 118.167658 -224.721928)
		(width 0.1143)
		(layer "In15.Cu")
		(net "GMI_CPU0_G1_CPU1_G3_TX_DN<6>")
	)
	(segment
		(start 118.167658 -233.466894)
		(end 118.137178 -233.449114)
		(width 0.1143)
		(layer "In15.Cu")
		(net "GMI_CPU0_G1_CPU1_G3_TX_DN<6>")
	)
	(segment
		(start 354.448872 -246.034306)
		(end 354.379022 -246.104156)
		(width 0.1143)
		(layer "In15.Cu")
		(net "GMI_CPU0_G1_CPU1_G3_TX_DN<6>")
	)
	(segment
		(start 353.358704 -228.589078)
		(end 353.328224 -228.606858)
		(width 0.1143)
		(layer "In15.Cu")
		(net "GMI_CPU0_G1_CPU1_G3_TX_DN<6>")
	)
	(segment
		(start 353.328224 -235.086652)
		(end 353.289108 -235.109512)
		(width 0.1143)
		(layer "In15.Cu")
		(net "GMI_CPU0_G1_CPU1_G3_TX_DN<6>")
	)
	(segment
		(start 117.414802 -246.10441)
		(end 117.11686 -246.10441)
		(width 0.1143)
		(layer "In15.Cu")
		(net "GMI_CPU0_G1_CPU1_G3_TX_DN<6>")
	)
	(segment
		(start 353.358704 -235.068872)
		(end 353.328224 -235.086652)
		(width 0.1143)
		(layer "In15.Cu")
		(net "GMI_CPU0_G1_CPU1_G3_TX_DN<6>")
	)
	(segment
		(start 353.328224 -241.5667)
		(end 353.289108 -241.58956)
		(width 0.1143)
		(layer "In15.Cu")
		(net "GMI_CPU0_G1_CPU1_G3_TX_DN<6>")
	)
	(segment
		(start 353.289108 -236.038644)
		(end 353.328224 -236.061504)
		(width 0.1143)
		(layer "In15.Cu")
		(net "GMI_CPU0_G1_CPU1_G3_TX_DN<6>")
	)
	(segment
		(start 153.113994 -187.48121)
		(end 153.57983 -187.099448)
		(width 0.14224)
		(layer "In15.Cu")
		(net "GMI_CPU0_G1_CPU1_G3_TX_DN<6>")
	)
	(segment
		(start 353.328224 -239.946688)
		(end 353.289108 -239.969548)
		(width 0.1143)
		(layer "In15.Cu")
		(net "GMI_CPU0_G1_CPU1_G3_TX_DN<6>")
	)
	(segment
		(start 146.331178 -193.043302)
		(end 148.210524 -191.502284)
		(width 0.14224)
		(layer "In15.Cu")
		(net "GMI_CPU0_G1_CPU1_G3_TX_DN<6>")
	)
	(segment
		(start 118.137178 -223.119696)
		(end 118.167658 -223.101916)
		(width 0.1143)
		(layer "In15.Cu")
		(net "GMI_CPU0_G1_CPU1_G3_TX_DN<6>")
	)
	(segment
		(start 352.85807 -225.53168)
		(end 352.858832 -225.532188)
		(width 0.1143)
		(layer "In15.Cu")
		(net "GMI_CPU0_G1_CPU1_G3_TX_DN<6>")
	)
	(segment
		(start 121.124726 -213.500208)
		(end 144.000982 -194.743324)
		(width 0.14224)
		(layer "In15.Cu")
		(net "GMI_CPU0_G1_CPU1_G3_TX_DN<6>")
	)
	(segment
		(start 352.825812 -225.512884)
		(end 352.826574 -225.513392)
		(width 0.1143)
		(layer "In15.Cu")
		(net "GMI_CPU0_G1_CPU1_G3_TX_DN<6>")
	)
	(segment
		(start 353.328224 -240.92154)
		(end 353.358704 -240.93932)
		(width 0.1143)
		(layer "In15.Cu")
		(net "GMI_CPU0_G1_CPU1_G3_TX_DN<6>")
	)
	(segment
		(start 153.57983 -187.099448)
		(end 153.77287 -187.118498)
		(width 0.14224)
		(layer "In15.Cu")
		(net "GMI_CPU0_G1_CPU1_G3_TX_DN<6>")
	)
	(segment
		(start 151.699468 -188.641228)
		(end 151.892508 -188.660278)
		(width 0.14224)
		(layer "In15.Cu")
		(net "GMI_CPU0_G1_CPU1_G3_TX_DN<6>")
	)
	(segment
		(start 353.289108 -227.938838)
		(end 353.328224 -227.961698)
		(width 0.1143)
		(layer "In15.Cu")
		(net "GMI_CPU0_G1_CPU1_G3_TX_DN<6>")
	)
	(segment
		(start 150.148036 -190.090806)
		(end 150.478236 -189.820042)
		(width 0.14224)
		(layer "In15.Cu")
		(net "GMI_CPU0_G1_CPU1_G3_TX_DN<6>")
	)
	(segment
		(start 117.666008 -244.990112)
		(end 117.695726 -244.973094)
		(width 0.1143)
		(layer "In15.Cu")
		(net "GMI_CPU0_G1_CPU1_G3_TX_DN<6>")
	)
	(segment
		(start 353.358704 -230.208836)
		(end 353.291648 -230.247952)
		(width 0.1143)
		(layer "In15.Cu")
		(net "GMI_CPU0_G1_CPU1_G3_TX_DN<6>")
	)
	(segment
		(start 352.57613 -221.579694)
		(end 352.575876 -221.579948)
		(width 0.1143)
		(layer "In15.Cu")
		(net "GMI_CPU0_G1_CPU1_G3_TX_DN<6>")
	)
	(segment
		(start 154.12212 -186.654694)
		(end 154.452066 -186.384184)
		(width 0.14224)
		(layer "In15.Cu")
		(net "GMI_CPU0_G1_CPU1_G3_TX_DN<6>")
	)
	(segment
		(start 353.358704 -233.44886)
		(end 353.328224 -233.46664)
		(width 0.1143)
		(layer "In15.Cu")
		(net "GMI_CPU0_G1_CPU1_G3_TX_DN<6>")
	)
	(segment
		(start 118.167658 -234.441746)
		(end 118.206774 -234.418886)
		(width 0.1143)
		(layer "In15.Cu")
		(net "GMI_CPU0_G1_CPU1_G3_TX_DN<6>")
	)
	(segment
		(start 118.20779 -222.150686)
		(end 118.134638 -222.108014)
		(width 0.1143)
		(layer "In15.Cu")
		(net "GMI_CPU0_G1_CPU1_G3_TX_DN<6>")
	)
	(segment
		(start 148.403564 -191.521334)
		(end 148.733764 -191.25057)
		(width 0.14224)
		(layer "In15.Cu")
		(net "GMI_CPU0_G1_CPU1_G3_TX_DN<6>")
	)
	(segment
		(start 118.167658 -223.101916)
		(end 118.206774 -223.079056)
		(width 0.1143)
		(layer "In15.Cu")
		(net "GMI_CPU0_G1_CPU1_G3_TX_DN<6>")
	)
	(segment
		(start 118.206774 -236.729778)
		(end 118.167658 -236.706918)
		(width 0.1143)
		(layer "In15.Cu")
		(net "GMI_CPU0_G1_CPU1_G3_TX_DN<6>")
	)
	(segment
		(start 352.505772 -221.083124)
		(end 352.551492 -221.128844)
		(width 0.1143)
		(layer "In15.Cu")
		(net "GMI_CPU0_G1_CPU1_G3_TX_DN<6>")
	)
	(segment
		(start 353.328224 -226.986846)
		(end 353.289108 -227.009706)
		(width 0.1143)
		(layer "In15.Cu")
		(net "GMI_CPU0_G1_CPU1_G3_TX_DN<6>")
	)
	(segment
		(start 315.531246 -184.898792)
		(end 348.636082 -212.043518)
		(width 0.14224)
		(layer "In15.Cu")
		(net "GMI_CPU0_G1_CPU1_G3_TX_DN<6>")
	)
	(segment
		(start 117.93601 -221.198948)
		(end 117.93601 -221.066106)
		(width 0.1143)
		(layer "In15.Cu")
		(net "GMI_CPU0_G1_CPU1_G3_TX_DN<6>")
	)
	(segment
		(start 312.471308 -183.166766)
		(end 312.471308 -183.166512)
		(width 0.14224)
		(layer "In15.Cu")
		(net "GMI_CPU0_G1_CPU1_G3_TX_DN<6>")
	)
	(segment
		(start 118.167658 -235.086906)
		(end 118.137178 -235.069126)
		(width 0.1143)
		(layer "In15.Cu")
		(net "GMI_CPU0_G1_CPU1_G3_TX_DN<6>")
	)
	(segment
		(start 117.979444 -221.804484)
		(end 117.979444 -221.242382)
		(width 0.1143)
		(layer "In15.Cu")
		(net "GMI_CPU0_G1_CPU1_G3_TX_DN<6>")
	)
	(segment
		(start 352.57613 -221.412308)
		(end 352.57613 -221.579694)
		(width 0.1143)
		(layer "In15.Cu")
		(net "GMI_CPU0_G1_CPU1_G3_TX_DN<6>")
	)
	(segment
		(start 353.328224 -236.061504)
		(end 353.358704 -236.079284)
		(width 0.1143)
		(layer "In15.Cu")
		(net "GMI_CPU0_G1_CPU1_G3_TX_DN<6>")
	)
	(segment
		(start 150.478236 -189.820042)
		(end 150.497286 -189.627002)
		(width 0.14224)
		(layer "In15.Cu")
		(net "GMI_CPU0_G1_CPU1_G3_TX_DN<6>")
	)
	(segment
		(start 118.206774 -235.109766)
		(end 118.167658 -235.086906)
		(width 0.1143)
		(layer "In15.Cu")
		(net "GMI_CPU0_G1_CPU1_G3_TX_DN<6>")
	)
	(segment
		(start 117.695726 -244.973094)
		(end 117.696996 -244.972332)
		(width 0.1143)
		(layer "In15.Cu")
		(net "GMI_CPU0_G1_CPU1_G3_TX_DN<6>")
	)
	(segment
		(start 118.137178 -244.179598)
		(end 118.167658 -244.161818)
		(width 0.1143)
		(layer "In15.Cu")
		(net "GMI_CPU0_G1_CPU1_G3_TX_DN<6>")
	)
	(arc
		(start 118.206774 -234.418886)
		(mid 118.450101 -233.95432)
		(end 118.206774 -233.489754)
		(width 0.1143)
		(layer "In15.Cu")
		(net "GMI_CPU0_G1_CPU1_G3_TX_DN<6>")
	)
	(arc
		(start 352.575622 -225.044254)
		(mid 352.640137 -225.306473)
		(end 352.818954 -225.50882)
		(width 0.1143)
		(layer "In15.Cu")
		(net "GMI_CPU0_G1_CPU1_G3_TX_DN<6>")
	)
	(arc
		(start 353.358704 -232.83926)
		(mid 353.515681 -233.14406)
		(end 353.358704 -233.44886)
		(width 0.1143)
		(layer "In15.Cu")
		(net "GMI_CPU0_G1_CPU1_G3_TX_DN<6>")
	)
	(arc
		(start 118.206774 -227.939092)
		(mid 118.450101 -227.474526)
		(end 118.206774 -227.00996)
		(width 0.1143)
		(layer "In15.Cu")
		(net "GMI_CPU0_G1_CPU1_G3_TX_DN<6>")
	)
	(arc
		(start 353.358704 -234.459272)
		(mid 353.515681 -234.764072)
		(end 353.358704 -235.068872)
		(width 0.1143)
		(layer "In15.Cu")
		(net "GMI_CPU0_G1_CPU1_G3_TX_DN<6>")
	)
	(arc
		(start 118.450106 -222.61449)
		(mid 118.385813 -222.352885)
		(end 118.20779 -222.150686)
		(width 0.1143)
		(layer "In15.Cu")
		(net "GMI_CPU0_G1_CPU1_G3_TX_DN<6>")
	)
	(arc
		(start 118.206774 -226.31908)
		(mid 118.450101 -225.854514)
		(end 118.206774 -225.389948)
		(width 0.1143)
		(layer "In15.Cu")
		(net "GMI_CPU0_G1_CPU1_G3_TX_DN<6>")
	)
	(arc
		(start 118.206774 -236.038898)
		(mid 118.450101 -235.574332)
		(end 118.206774 -235.109766)
		(width 0.1143)
		(layer "In15.Cu")
		(net "GMI_CPU0_G1_CPU1_G3_TX_DN<6>")
	)
	(arc
		(start 117.510052 -245.294404)
		(mid 117.551307 -245.123433)
		(end 117.666008 -244.990112)
		(width 0.1143)
		(layer "In15.Cu")
		(net "GMI_CPU0_G1_CPU1_G3_TX_DN<6>")
	)
	(arc
		(start 118.206774 -239.278922)
		(mid 118.450101 -238.814356)
		(end 118.206774 -238.34979)
		(width 0.1143)
		(layer "In15.Cu")
		(net "GMI_CPU0_G1_CPU1_G3_TX_DN<6>")
	)
	(arc
		(start 353.289108 -241.58956)
		(mid 353.045781 -242.054126)
		(end 353.289108 -242.518692)
		(width 0.1143)
		(layer "In15.Cu")
		(net "GMI_CPU0_G1_CPU1_G3_TX_DN<6>")
	)
	(arc
		(start 353.998276 -245.3132)
		(mid 354.070532 -245.583453)
		(end 354.268024 -245.781576)
		(width 0.1143)
		(layer "In15.Cu")
		(net "GMI_CPU0_G1_CPU1_G3_TX_DN<6>")
	)
	(arc
		(start 117.736874 -244.948964)
		(mid 117.915687 -244.746614)
		(end 117.980206 -244.484398)
		(width 0.1143)
		(layer "In15.Cu")
		(net "GMI_CPU0_G1_CPU1_G3_TX_DN<6>")
	)
	(arc
		(start 353.045776 -225.85426)
		(mid 353.110291 -226.116479)
		(end 353.289108 -226.318826)
		(width 0.1143)
		(layer "In15.Cu")
		(net "GMI_CPU0_G1_CPU1_G3_TX_DN<6>")
	)
	(arc
		(start 118.206774 -240.898934)
		(mid 118.450101 -240.434368)
		(end 118.206774 -239.969802)
		(width 0.1143)
		(layer "In15.Cu")
		(net "GMI_CPU0_G1_CPU1_G3_TX_DN<6>")
	)
	(arc
		(start 118.206774 -223.079056)
		(mid 118.385587 -222.876706)
		(end 118.450106 -222.61449)
		(width 0.1143)
		(layer "In15.Cu")
		(net "GMI_CPU0_G1_CPU1_G3_TX_DN<6>")
	)
	(arc
		(start 118.137178 -243.169186)
		(mid 117.980201 -242.864386)
		(end 118.137178 -242.559586)
		(width 0.1143)
		(layer "In15.Cu")
		(net "GMI_CPU0_G1_CPU1_G3_TX_DN<6>")
	)
	(arc
		(start 353.358704 -239.319308)
		(mid 353.515681 -239.624108)
		(end 353.358704 -239.928908)
		(width 0.1143)
		(layer "In15.Cu")
		(net "GMI_CPU0_G1_CPU1_G3_TX_DN<6>")
	)
	(arc
		(start 118.137178 -238.30915)
		(mid 117.980201 -238.00435)
		(end 118.137178 -237.69955)
		(width 0.1143)
		(layer "In15.Cu")
		(net "GMI_CPU0_G1_CPU1_G3_TX_DN<6>")
	)
	(arc
		(start 354.299774 -245.799864)
		(mid 354.396909 -245.902733)
		(end 354.448872 -246.034306)
		(width 0.1143)
		(layer "In15.Cu")
		(net "GMI_CPU0_G1_CPU1_G3_TX_DN<6>")
	)
	(arc
		(start 118.137178 -230.20909)
		(mid 118.021751 -230.075714)
		(end 117.980206 -229.90429)
		(width 0.1143)
		(layer "In15.Cu")
		(net "GMI_CPU0_G1_CPU1_G3_TX_DN<6>")
	)
	(arc
		(start 352.38817 -222.12681)
		(mid 352.107523 -222.614236)
		(end 352.38817 -223.101662)
		(width 0.1143)
		(layer "In15.Cu")
		(net "GMI_CPU0_G1_CPU1_G3_TX_DN<6>")
	)
	(arc
		(start 353.289108 -238.349536)
		(mid 353.045781 -238.814102)
		(end 353.289108 -239.278668)
		(width 0.1143)
		(layer "In15.Cu")
		(net "GMI_CPU0_G1_CPU1_G3_TX_DN<6>")
	)
	(arc
		(start 118.137178 -239.929162)
		(mid 117.980201 -239.624362)
		(end 118.137178 -239.319562)
		(width 0.1143)
		(layer "In15.Cu")
		(net "GMI_CPU0_G1_CPU1_G3_TX_DN<6>")
	)
	(arc
		(start 118.206774 -232.798874)
		(mid 118.450101 -232.334308)
		(end 118.206774 -231.869742)
		(width 0.1143)
		(layer "In15.Cu")
		(net "GMI_CPU0_G1_CPU1_G3_TX_DN<6>")
	)
	(arc
		(start 353.289108 -228.629718)
		(mid 353.045781 -229.094284)
		(end 353.289108 -229.55885)
		(width 0.1143)
		(layer "In15.Cu")
		(net "GMI_CPU0_G1_CPU1_G3_TX_DN<6>")
	)
	(arc
		(start 352.88982 -225.549968)
		(mid 353.004496 -225.683302)
		(end 353.045776 -225.85426)
		(width 0.1143)
		(layer "In15.Cu")
		(net "GMI_CPU0_G1_CPU1_G3_TX_DN<6>")
	)
	(arc
		(start 118.206774 -237.65891)
		(mid 118.450101 -237.194344)
		(end 118.206774 -236.729778)
		(width 0.1143)
		(layer "In15.Cu")
		(net "GMI_CPU0_G1_CPU1_G3_TX_DN<6>")
	)
	(arc
		(start 353.515676 -229.904036)
		(mid 353.474127 -230.075458)
		(end 353.358704 -230.208836)
		(width 0.1143)
		(layer "In15.Cu")
		(net "GMI_CPU0_G1_CPU1_G3_TX_DN<6>")
	)
	(arc
		(start 117.980206 -229.90429)
		(mid 118.021172 -229.733884)
		(end 118.135146 -229.60076)
		(width 0.1143)
		(layer "In15.Cu")
		(net "GMI_CPU0_G1_CPU1_G3_TX_DN<6>")
	)
	(arc
		(start 353.358704 -236.079284)
		(mid 353.515681 -236.384084)
		(end 353.358704 -236.688884)
		(width 0.1143)
		(layer "In15.Cu")
		(net "GMI_CPU0_G1_CPU1_G3_TX_DN<6>")
	)
	(arc
		(start 117.980206 -231.524302)
		(mid 118.021172 -231.353896)
		(end 118.135146 -231.220772)
		(width 0.1143)
		(layer "In15.Cu")
		(net "GMI_CPU0_G1_CPU1_G3_TX_DN<6>")
	)
	(arc
		(start 118.137178 -228.589332)
		(mid 117.980201 -228.284532)
		(end 118.137178 -227.979732)
		(width 0.1143)
		(layer "In15.Cu")
		(net "GMI_CPU0_G1_CPU1_G3_TX_DN<6>")
	)
	(arc
		(start 353.289108 -243.209572)
		(mid 353.045781 -243.674138)
		(end 353.289108 -244.138704)
		(width 0.1143)
		(layer "In15.Cu")
		(net "GMI_CPU0_G1_CPU1_G3_TX_DN<6>")
	)
	(arc
		(start 353.289108 -235.109512)
		(mid 353.045781 -235.574078)
		(end 353.289108 -236.038644)
		(width 0.1143)
		(layer "In15.Cu")
		(net "GMI_CPU0_G1_CPU1_G3_TX_DN<6>")
	)
	(arc
		(start 353.360736 -229.600506)
		(mid 353.474665 -229.733653)
		(end 353.515676 -229.904036)
		(width 0.1143)
		(layer "In15.Cu")
		(net "GMI_CPU0_G1_CPU1_G3_TX_DN<6>")
	)
	(arc
		(start 353.289108 -227.009706)
		(mid 353.045781 -227.474272)
		(end 353.289108 -227.938838)
		(width 0.1143)
		(layer "In15.Cu")
		(net "GMI_CPU0_G1_CPU1_G3_TX_DN<6>")
	)
	(arc
		(start 118.206774 -242.518946)
		(mid 118.450101 -242.05438)
		(end 118.206774 -241.589814)
		(width 0.1143)
		(layer "In15.Cu")
		(net "GMI_CPU0_G1_CPU1_G3_TX_DN<6>")
	)
	(arc
		(start 353.358704 -244.179344)
		(mid 353.474131 -244.31272)
		(end 353.515676 -244.484144)
		(width 0.1143)
		(layer "In15.Cu")
		(net "GMI_CPU0_G1_CPU1_G3_TX_DN<6>")
	)
	(arc
		(start 117.26672 -245.75897)
		(mid 117.445533 -245.55662)
		(end 117.510052 -245.294404)
		(width 0.1143)
		(layer "In15.Cu")
		(net "GMI_CPU0_G1_CPU1_G3_TX_DN<6>")
	)
	(arc
		(start 353.358704 -242.559332)
		(mid 353.515681 -242.864132)
		(end 353.358704 -243.168932)
		(width 0.1143)
		(layer "In15.Cu")
		(net "GMI_CPU0_G1_CPU1_G3_TX_DN<6>")
	)
	(arc
		(start 118.450106 -230.71455)
		(mid 118.38487 -230.450959)
		(end 118.204234 -230.248206)
		(width 0.1143)
		(layer "In15.Cu")
		(net "GMI_CPU0_G1_CPU1_G3_TX_DN<6>")
	)
	(arc
		(start 353.289108 -231.869488)
		(mid 353.045781 -232.334054)
		(end 353.289108 -232.79862)
		(width 0.1143)
		(layer "In15.Cu")
		(net "GMI_CPU0_G1_CPU1_G3_TX_DN<6>")
	)
	(arc
		(start 353.358704 -227.979478)
		(mid 353.515681 -228.284278)
		(end 353.358704 -228.589078)
		(width 0.1143)
		(layer "In15.Cu")
		(net "GMI_CPU0_G1_CPU1_G3_TX_DN<6>")
	)
	(arc
		(start 118.137178 -225.349308)
		(mid 117.980201 -225.044508)
		(end 118.137178 -224.739708)
		(width 0.1143)
		(layer "In15.Cu")
		(net "GMI_CPU0_G1_CPU1_G3_TX_DN<6>")
	)
	(arc
		(start 353.289108 -236.729524)
		(mid 353.045781 -237.19409)
		(end 353.289108 -237.658656)
		(width 0.1143)
		(layer "In15.Cu")
		(net "GMI_CPU0_G1_CPU1_G3_TX_DN<6>")
	)
	(arc
		(start 118.137178 -226.96932)
		(mid 117.980201 -226.66452)
		(end 118.137178 -226.35972)
		(width 0.1143)
		(layer "In15.Cu")
		(net "GMI_CPU0_G1_CPU1_G3_TX_DN<6>")
	)
	(arc
		(start 118.137178 -231.829102)
		(mid 118.021751 -231.695726)
		(end 117.980206 -231.524302)
		(width 0.1143)
		(layer "In15.Cu")
		(net "GMI_CPU0_G1_CPU1_G3_TX_DN<6>")
	)
	(arc
		(start 118.137178 -233.449114)
		(mid 117.980201 -233.144314)
		(end 118.137178 -232.839514)
		(width 0.1143)
		(layer "In15.Cu")
		(net "GMI_CPU0_G1_CPU1_G3_TX_DN<6>")
	)
	(arc
		(start 352.41865 -224.739454)
		(mid 352.534077 -224.87283)
		(end 352.575622 -225.044254)
		(width 0.1143)
		(layer "In15.Cu")
		(net "GMI_CPU0_G1_CPU1_G3_TX_DN<6>")
	)
	(arc
		(start 353.360736 -231.220518)
		(mid 353.474665 -231.353665)
		(end 353.515676 -231.524048)
		(width 0.1143)
		(layer "In15.Cu")
		(net "GMI_CPU0_G1_CPU1_G3_TX_DN<6>")
	)
	(arc
		(start 118.134638 -222.108014)
		(mid 118.020485 -221.974938)
		(end 117.979444 -221.804484)
		(width 0.1143)
		(layer "In15.Cu")
		(net "GMI_CPU0_G1_CPU1_G3_TX_DN<6>")
	)
	(arc
		(start 118.206774 -224.699068)
		(mid 118.450101 -224.234502)
		(end 118.206774 -223.769936)
		(width 0.1143)
		(layer "In15.Cu")
		(net "GMI_CPU0_G1_CPU1_G3_TX_DN<6>")
	)
	(arc
		(start 118.137178 -235.069126)
		(mid 117.980201 -234.764326)
		(end 118.137178 -234.459526)
		(width 0.1143)
		(layer "In15.Cu")
		(net "GMI_CPU0_G1_CPU1_G3_TX_DN<6>")
	)
	(arc
		(start 353.291648 -230.247952)
		(mid 353.110996 -230.450697)
		(end 353.045776 -230.714296)
		(width 0.1143)
		(layer "In15.Cu")
		(net "GMI_CPU0_G1_CPU1_G3_TX_DN<6>")
	)
	(arc
		(start 118.206774 -229.559104)
		(mid 118.450101 -229.094538)
		(end 118.206774 -228.629972)
		(width 0.1143)
		(layer "In15.Cu")
		(net "GMI_CPU0_G1_CPU1_G3_TX_DN<6>")
	)
	(arc
		(start 118.137178 -236.689138)
		(mid 117.980201 -236.384338)
		(end 118.137178 -236.079538)
		(width 0.1143)
		(layer "In15.Cu")
		(net "GMI_CPU0_G1_CPU1_G3_TX_DN<6>")
	)
	(arc
		(start 353.81057 -244.978682)
		(mid 353.948002 -245.115941)
		(end 353.998276 -245.303548)
		(width 0.1143)
		(layer "In15.Cu")
		(net "GMI_CPU0_G1_CPU1_G3_TX_DN<6>")
	)
	(arc
		(start 117.980206 -244.484398)
		(mid 118.021755 -244.312976)
		(end 118.137178 -244.179598)
		(width 0.1143)
		(layer "In15.Cu")
		(net "GMI_CPU0_G1_CPU1_G3_TX_DN<6>")
	)
	(arc
		(start 353.289108 -233.4895)
		(mid 353.045781 -233.954066)
		(end 353.289108 -234.418632)
		(width 0.1143)
		(layer "In15.Cu")
		(net "GMI_CPU0_G1_CPU1_G3_TX_DN<6>")
	)
	(arc
		(start 353.045776 -230.714296)
		(mid 353.110291 -230.976515)
		(end 353.289108 -231.178862)
		(width 0.1143)
		(layer "In15.Cu")
		(net "GMI_CPU0_G1_CPU1_G3_TX_DN<6>")
	)
	(arc
		(start 118.137178 -241.549174)
		(mid 117.980201 -241.244374)
		(end 118.137178 -240.939574)
		(width 0.1143)
		(layer "In15.Cu")
		(net "GMI_CPU0_G1_CPU1_G3_TX_DN<6>")
	)
	(arc
		(start 353.515676 -231.524048)
		(mid 353.474127 -231.69547)
		(end 353.358704 -231.828848)
		(width 0.1143)
		(layer "In15.Cu")
		(net "GMI_CPU0_G1_CPU1_G3_TX_DN<6>")
	)
	(arc
		(start 352.349054 -223.769682)
		(mid 352.105727 -224.234248)
		(end 352.349054 -224.698814)
		(width 0.1143)
		(layer "In15.Cu")
		(net "GMI_CPU0_G1_CPU1_G3_TX_DN<6>")
	)
	(arc
		(start 353.289108 -239.969548)
		(mid 353.045781 -240.434114)
		(end 353.289108 -240.89868)
		(width 0.1143)
		(layer "In15.Cu")
		(net "GMI_CPU0_G1_CPU1_G3_TX_DN<6>")
	)
	(arc
		(start 118.137178 -223.729296)
		(mid 117.980201 -223.424496)
		(end 118.137178 -223.119696)
		(width 0.1143)
		(layer "In15.Cu")
		(net "GMI_CPU0_G1_CPU1_G3_TX_DN<6>")
	)
	(arc
		(start 117.04701 -246.03456)
		(mid 117.099427 -245.902629)
		(end 117.197124 -245.79961)
		(width 0.1143)
		(layer "In15.Cu")
		(net "GMI_CPU0_G1_CPU1_G3_TX_DN<6>")
	)
	(arc
		(start 352.41992 -223.11995)
		(mid 352.575848 -223.424242)
		(end 352.41992 -223.728534)
		(width 0.1143)
		(layer "In15.Cu")
		(net "GMI_CPU0_G1_CPU1_G3_TX_DN<6>")
	)
	(arc
		(start 118.206774 -244.138958)
		(mid 118.450101 -243.674392)
		(end 118.206774 -243.209826)
		(width 0.1143)
		(layer "In15.Cu")
		(net "GMI_CPU0_G1_CPU1_G3_TX_DN<6>")
	)
	(arc
		(start 352.575876 -221.80423)
		(mid 352.531805 -221.973766)
		(end 352.41992 -222.108522)
		(width 0.1143)
		(layer "In15.Cu")
		(net "GMI_CPU0_G1_CPU1_G3_TX_DN<6>")
	)
	(arc
		(start 118.206774 -231.179116)
		(mid 118.385587 -230.976766)
		(end 118.450106 -230.71455)
		(width 0.1143)
		(layer "In15.Cu")
		(net "GMI_CPU0_G1_CPU1_G3_TX_DN<6>")
	)
	(arc
		(start 353.358704 -226.359466)
		(mid 353.515681 -226.664266)
		(end 353.358704 -226.969066)
		(width 0.1143)
		(layer "In15.Cu")
		(net "GMI_CPU0_G1_CPU1_G3_TX_DN<6>")
	)
	(arc
		(start 353.358704 -237.699296)
		(mid 353.515681 -238.004096)
		(end 353.358704 -238.308896)
		(width 0.1143)
		(layer "In15.Cu")
		(net "GMI_CPU0_G1_CPU1_G3_TX_DN<6>")
	)
	(arc
		(start 353.515676 -244.484144)
		(mid 353.580191 -244.746363)
		(end 353.759008 -244.94871)
		(width 0.1143)
		(layer "In15.Cu")
		(net "GMI_CPU0_G1_CPU1_G3_TX_DN<6>")
	)
	(arc
		(start 353.358704 -240.93932)
		(mid 353.515681 -241.24412)
		(end 353.358704 -241.54892)
		(width 0.1143)
		(layer "In15.Cu")
		(net "GMI_CPU0_G1_CPU1_G3_TX_DN<6>")
	)
	(segment
		(start 354.547932 -244.750082)
		(end 354.08108 -244.484144)
		(width 0.12954)
		(layer "F.Cu")
		(net "GMI_CPU0_G1_CPU1_G3_TX_DN<5>")
	)
	(segment
		(start 116.94795 -244.750336)
		(end 117.414802 -244.484398)
		(width 0.12954)
		(layer "F.Cu")
		(net "GMI_CPU0_G1_CPU1_G3_TX_DN<5>")
	)
	(segment
		(start 117.197124 -238.30915)
		(end 117.227604 -238.32693)
		(width 0.1143)
		(layer "In15.Cu")
		(net "GMI_CPU0_G1_CPU1_G3_TX_DN<5>")
	)
	(segment
		(start 354.23602 -230.245158)
		(end 354.264468 -230.228648)
		(width 0.1143)
		(layer "In15.Cu")
		(net "GMI_CPU0_G1_CPU1_G3_TX_DN<5>")
	)
	(segment
		(start 117.22735 -222.127064)
		(end 117.267736 -222.150686)
		(width 0.1143)
		(layer "In15.Cu")
		(net "GMI_CPU0_G1_CPU1_G3_TX_DN<5>")
	)
	(segment
		(start 116.99113 -221.066106)
		(end 116.99113 -221.198948)
		(width 0.1143)
		(layer "In15.Cu")
		(net "GMI_CPU0_G1_CPU1_G3_TX_DN<5>")
	)
	(segment
		(start 117.03685 -218.58224)
		(end 117.03685 -220.991938)
		(width 0.14224)
		(layer "In15.Cu")
		(net "GMI_CPU0_G1_CPU1_G3_TX_DN<5>")
	)
	(segment
		(start 117.26672 -239.278922)
		(end 117.227604 -239.301782)
		(width 0.1143)
		(layer "In15.Cu")
		(net "GMI_CPU0_G1_CPU1_G3_TX_DN<5>")
	)
	(segment
		(start 353.358704 -224.739454)
		(end 353.328224 -224.721674)
		(width 0.1143)
		(layer "In15.Cu")
		(net "GMI_CPU0_G1_CPU1_G3_TX_DN<5>")
	)
	(segment
		(start 354.268786 -240.922048)
		(end 354.268024 -240.92154)
		(width 0.1143)
		(layer "In15.Cu")
		(net "GMI_CPU0_G1_CPU1_G3_TX_DN<5>")
	)
	(segment
		(start 354.27539 -239.305846)
		(end 354.27412 -239.305084)
		(width 0.1143)
		(layer "In15.Cu")
		(net "GMI_CPU0_G1_CPU1_G3_TX_DN<5>")
	)
	(segment
		(start 117.227604 -231.846882)
		(end 117.26672 -231.869742)
		(width 0.1143)
		(layer "In15.Cu")
		(net "GMI_CPU0_G1_CPU1_G3_TX_DN<5>")
	)
	(segment
		(start 353.296728 -223.083374)
		(end 353.295966 -223.082866)
		(width 0.1143)
		(layer "In15.Cu")
		(net "GMI_CPU0_G1_CPU1_G3_TX_DN<5>")
	)
	(segment
		(start 354.268786 -227.962206)
		(end 354.268024 -227.961698)
		(width 0.1143)
		(layer "In15.Cu")
		(net "GMI_CPU0_G1_CPU1_G3_TX_DN<5>")
	)
	(segment
		(start 354.268786 -244.162072)
		(end 354.268024 -244.161564)
		(width 0.1143)
		(layer "In15.Cu")
		(net "GMI_CPU0_G1_CPU1_G3_TX_DN<5>")
	)
	(segment
		(start 354.27539 -240.925858)
		(end 354.27412 -240.925096)
		(width 0.1143)
		(layer "In15.Cu")
		(net "GMI_CPU0_G1_CPU1_G3_TX_DN<5>")
	)
	(segment
		(start 354.268024 -235.086652)
		(end 354.289106 -235.07446)
		(width 0.1143)
		(layer "In15.Cu")
		(net "GMI_CPU0_G1_CPU1_G3_TX_DN<5>")
	)
	(segment
		(start 354.27412 -242.545108)
		(end 354.273358 -242.5446)
		(width 0.1143)
		(layer "In15.Cu")
		(net "GMI_CPU0_G1_CPU1_G3_TX_DN<5>")
	)
	(segment
		(start 117.26672 -237.65891)
		(end 117.227604 -237.68177)
		(width 0.1143)
		(layer "In15.Cu")
		(net "GMI_CPU0_G1_CPU1_G3_TX_DN<5>")
	)
	(segment
		(start 302.904144 -179.774088)
		(end 165.86581 -178.97475)
		(width 0.14224)
		(layer "In15.Cu")
		(net "GMI_CPU0_G1_CPU1_G3_TX_DN<5>")
	)
	(segment
		(start 354.27158 -236.063536)
		(end 354.270564 -236.063028)
		(width 0.1143)
		(layer "In15.Cu")
		(net "GMI_CPU0_G1_CPU1_G3_TX_DN<5>")
	)
	(segment
		(start 354.26777 -241.566954)
		(end 354.268024 -241.5667)
		(width 0.1143)
		(layer "In15.Cu")
		(net "GMI_CPU0_G1_CPU1_G3_TX_DN<5>")
	)
	(segment
		(start 117.11686 -244.484398)
		(end 117.414802 -244.484398)
		(width 0.1143)
		(layer "In15.Cu")
		(net "GMI_CPU0_G1_CPU1_G3_TX_DN<5>")
	)
	(segment
		(start 354.269802 -237.682532)
		(end 354.268786 -237.682024)
		(width 0.1143)
		(layer "In15.Cu")
		(net "GMI_CPU0_G1_CPU1_G3_TX_DN<5>")
	)
	(segment
		(start 354.270564 -240.923064)
		(end 354.269802 -240.922556)
		(width 0.1143)
		(layer "In15.Cu")
		(net "GMI_CPU0_G1_CPU1_G3_TX_DN<5>")
	)
	(segment
		(start 354.268024 -239.301528)
		(end 354.26777 -239.301528)
		(width 0.1143)
		(layer "In15.Cu")
		(net "GMI_CPU0_G1_CPU1_G3_TX_DN<5>")
	)
	(segment
		(start 117.197124 -241.549174)
		(end 117.227604 -241.566954)
		(width 0.1143)
		(layer "In15.Cu")
		(net "GMI_CPU0_G1_CPU1_G3_TX_DN<5>")
	)
	(segment
		(start 354.270564 -239.303052)
		(end 354.269802 -239.302544)
		(width 0.1143)
		(layer "In15.Cu")
		(net "GMI_CPU0_G1_CPU1_G3_TX_DN<5>")
	)
	(segment
		(start 149.860508 -188.757814)
		(end 149.860508 -188.758068)
		(width 0.14224)
		(layer "In15.Cu")
		(net "GMI_CPU0_G1_CPU1_G3_TX_DN<5>")
	)
	(segment
		(start 149.530562 -189.028324)
		(end 149.511512 -189.221364)
		(width 0.14224)
		(layer "In15.Cu")
		(net "GMI_CPU0_G1_CPU1_G3_TX_DN<5>")
	)
	(segment
		(start 353.450652 -219.930218)
		(end 349.471996 -211.522818)
		(width 0.14224)
		(layer "In15.Cu")
		(net "GMI_CPU0_G1_CPU1_G3_TX_DN<5>")
	)
	(segment
		(start 354.299774 -242.55984)
		(end 354.27539 -242.54587)
		(width 0.1143)
		(layer "In15.Cu")
		(net "GMI_CPU0_G1_CPU1_G3_TX_DN<5>")
	)
	(segment
		(start 117.26672 -231.179116)
		(end 117.227604 -231.201976)
		(width 0.1143)
		(layer "In15.Cu")
		(net "GMI_CPU0_G1_CPU1_G3_TX_DN<5>")
	)
	(segment
		(start 154.04084 -185.330338)
		(end 154.022806 -185.51271)
		(width 0.14224)
		(layer "In15.Cu")
		(net "GMI_CPU0_G1_CPU1_G3_TX_DN<5>")
	)
	(segment
		(start 353.323906 -223.099122)
		(end 353.32289 -223.098614)
		(width 0.1143)
		(layer "In15.Cu")
		(net "GMI_CPU0_G1_CPU1_G3_TX_DN<5>")
	)
	(segment
		(start 353.32289 -223.098614)
		(end 353.321366 -223.097598)
		(width 0.1143)
		(layer "In15.Cu")
		(net "GMI_CPU0_G1_CPU1_G3_TX_DN<5>")
	)
	(segment
		(start 149.530562 -189.028578)
		(end 149.530562 -189.028324)
		(width 0.14224)
		(layer "In15.Cu")
		(net "GMI_CPU0_G1_CPU1_G3_TX_DN<5>")
	)
	(segment
		(start 354.26777 -238.32693)
		(end 354.268024 -238.326676)
		(width 0.1143)
		(layer "In15.Cu")
		(net "GMI_CPU0_G1_CPU1_G3_TX_DN<5>")
	)
	(segment
		(start 117.197124 -233.449114)
		(end 117.227604 -233.466894)
		(width 0.1143)
		(layer "In15.Cu")
		(net "GMI_CPU0_G1_CPU1_G3_TX_DN<5>")
	)
	(segment
		(start 354.274374 -236.065314)
		(end 354.272342 -236.064044)
		(width 0.1143)
		(layer "In15.Cu")
		(net "GMI_CPU0_G1_CPU1_G3_TX_DN<5>")
	)
	(segment
		(start 354.268024 -230.226616)
		(end 354.271834 -230.22433)
		(width 0.1143)
		(layer "In15.Cu")
		(net "GMI_CPU0_G1_CPU1_G3_TX_DN<5>")
	)
	(segment
		(start 117.227604 -228.607112)
		(end 117.26672 -228.629972)
		(width 0.1143)
		(layer "In15.Cu")
		(net "GMI_CPU0_G1_CPU1_G3_TX_DN<5>")
	)
	(segment
		(start 354.268024 -243.186712)
		(end 354.299774 -243.168424)
		(width 0.1143)
		(layer "In15.Cu")
		(net "GMI_CPU0_G1_CPU1_G3_TX_DN<5>")
	)
	(segment
		(start 148.658326 -189.743588)
		(end 148.639276 -189.936628)
		(width 0.14224)
		(layer "In15.Cu")
		(net "GMI_CPU0_G1_CPU1_G3_TX_DN<5>")
	)
	(segment
		(start 117.197124 -243.169186)
		(end 117.227604 -243.186966)
		(width 0.1143)
		(layer "In15.Cu")
		(net "GMI_CPU0_G1_CPU1_G3_TX_DN<5>")
	)
	(segment
		(start 354.272342 -237.684056)
		(end 354.27158 -237.683548)
		(width 0.1143)
		(layer "In15.Cu")
		(net "GMI_CPU0_G1_CPU1_G3_TX_DN<5>")
	)
	(segment
		(start 354.268786 -228.60635)
		(end 354.270056 -228.605588)
		(width 0.1143)
		(layer "In15.Cu")
		(net "GMI_CPU0_G1_CPU1_G3_TX_DN<5>")
	)
	(segment
		(start 158.644082 -181.556914)
		(end 154.889454 -184.634632)
		(width 0.14224)
		(layer "In15.Cu")
		(net "GMI_CPU0_G1_CPU1_G3_TX_DN<5>")
	)
	(segment
		(start 117.227604 -239.946942)
		(end 117.26672 -239.969802)
		(width 0.1143)
		(layer "In15.Cu")
		(net "GMI_CPU0_G1_CPU1_G3_TX_DN<5>")
	)
	(segment
		(start 150.805388 -187.983368)
		(end 150.402798 -188.313314)
		(width 0.14224)
		(layer "In15.Cu")
		(net "GMI_CPU0_G1_CPU1_G3_TX_DN<5>")
	)
	(segment
		(start 354.268024 -228.606858)
		(end 354.268786 -228.60635)
		(width 0.1143)
		(layer "In15.Cu")
		(net "GMI_CPU0_G1_CPU1_G3_TX_DN<5>")
	)
	(segment
		(start 354.269802 -242.542568)
		(end 354.268786 -242.54206)
		(width 0.1143)
		(layer "In15.Cu")
		(net "GMI_CPU0_G1_CPU1_G3_TX_DN<5>")
	)
	(segment
		(start 354.231702 -227.007928)
		(end 354.268024 -226.986846)
		(width 0.1143)
		(layer "In15.Cu")
		(net "GMI_CPU0_G1_CPU1_G3_TX_DN<5>")
	)
	(segment
		(start 117.227604 -223.101916)
		(end 117.197124 -223.119696)
		(width 0.1143)
		(layer "In15.Cu")
		(net "GMI_CPU0_G1_CPU1_G3_TX_DN<5>")
	)
	(segment
		(start 354.289106 -239.934496)
		(end 354.289868 -239.933988)
		(width 0.1143)
		(layer "In15.Cu")
		(net "GMI_CPU0_G1_CPU1_G3_TX_DN<5>")
	)
	(segment
		(start 117.227604 -236.061758)
		(end 117.197124 -236.079538)
		(width 0.1143)
		(layer "In15.Cu")
		(net "GMI_CPU0_G1_CPU1_G3_TX_DN<5>")
	)
	(segment
		(start 150.053548 -188.777118)
		(end 149.860508 -188.757814)
		(width 0.14224)
		(layer "In15.Cu")
		(net "GMI_CPU0_G1_CPU1_G3_TX_DN<5>")
	)
	(segment
		(start 117.227604 -233.466894)
		(end 117.26672 -233.489754)
		(width 0.1143)
		(layer "In15.Cu")
		(net "GMI_CPU0_G1_CPU1_G3_TX_DN<5>")
	)
	(segment
		(start 354.299774 -239.319816)
		(end 354.27539 -239.305846)
		(width 0.1143)
		(layer "In15.Cu")
		(net "GMI_CPU0_G1_CPU1_G3_TX_DN<5>")
	)
	(segment
		(start 152.667716 -186.456574)
		(end 152.256998 -186.793378)
		(width 0.14224)
		(layer "In15.Cu")
		(net "GMI_CPU0_G1_CPU1_G3_TX_DN<5>")
	)
	(segment
		(start 354.299774 -240.939828)
		(end 354.27539 -240.925858)
		(width 0.1143)
		(layer "In15.Cu")
		(net "GMI_CPU0_G1_CPU1_G3_TX_DN<5>")
	)
	(segment
		(start 117.227604 -224.721928)
		(end 117.197124 -224.739708)
		(width 0.1143)
		(layer "In15.Cu")
		(net "GMI_CPU0_G1_CPU1_G3_TX_DN<5>")
	)
	(segment
		(start 117.227604 -243.186966)
		(end 117.26672 -243.209826)
		(width 0.1143)
		(layer "In15.Cu")
		(net "GMI_CPU0_G1_CPU1_G3_TX_DN<5>")
	)
	(segment
		(start 354.268024 -241.5667)
		(end 354.289106 -241.554508)
		(width 0.1143)
		(layer "In15.Cu")
		(net "GMI_CPU0_G1_CPU1_G3_TX_DN<5>")
	)
	(segment
		(start 354.30079 -229.60076)
		(end 354.268024 -229.58171)
		(width 0.1143)
		(layer "In15.Cu")
		(net "GMI_CPU0_G1_CPU1_G3_TX_DN<5>")
	)
	(segment
		(start 354.270564 -237.68304)
		(end 354.269802 -237.682532)
		(width 0.1143)
		(layer "In15.Cu")
		(net "GMI_CPU0_G1_CPU1_G3_TX_DN<5>")
	)
	(segment
		(start 353.289108 -222.14967)
		(end 353.36099 -222.10776)
		(width 0.1143)
		(layer "In15.Cu")
		(net "GMI_CPU0_G1_CPU1_G3_TX_DN<5>")
	)
	(segment
		(start 146.269202 -191.702182)
		(end 146.268948 -191.702436)
		(width 0.14224)
		(layer "In15.Cu")
		(net "GMI_CPU0_G1_CPU1_G3_TX_DN<5>")
	)
	(segment
		(start 354.26777 -235.086906)
		(end 354.268024 -235.086652)
		(width 0.1143)
		(layer "In15.Cu")
		(net "GMI_CPU0_G1_CPU1_G3_TX_DN<5>")
	)
	(segment
		(start 353.450652 -221.083124)
		(end 353.450652 -219.930218)
		(width 0.14224)
		(layer "In15.Cu")
		(net "GMI_CPU0_G1_CPU1_G3_TX_DN<5>")
	)
	(segment
		(start 354.289868 -238.313976)
		(end 354.299774 -238.308388)
		(width 0.1143)
		(layer "In15.Cu")
		(net "GMI_CPU0_G1_CPU1_G3_TX_DN<5>")
	)
	(segment
		(start 354.272342 -236.064044)
		(end 354.27158 -236.063536)
		(width 0.1143)
		(layer "In15.Cu")
		(net "GMI_CPU0_G1_CPU1_G3_TX_DN<5>")
	)
	(segment
		(start 354.27539 -237.685834)
		(end 354.27412 -237.685072)
		(width 0.1143)
		(layer "In15.Cu")
		(net "GMI_CPU0_G1_CPU1_G3_TX_DN<5>")
	)
	(segment
		(start 154.365198 -185.064908)
		(end 154.041094 -185.330846)
		(width 0.14224)
		(layer "In15.Cu")
		(net "GMI_CPU0_G1_CPU1_G3_TX_DN<5>")
	)
	(segment
		(start 354.265484 -230.22814)
		(end 354.267008 -230.227124)
		(width 0.1143)
		(layer "In15.Cu")
		(net "GMI_CPU0_G1_CPU1_G3_TX_DN<5>")
	)
	(segment
		(start 154.364944 -185.064654)
		(end 154.365198 -185.064908)
		(width 0.14224)
		(layer "In15.Cu")
		(net "GMI_CPU0_G1_CPU1_G3_TX_DN<5>")
	)
	(segment
		(start 354.268024 -242.541552)
		(end 354.26777 -242.541552)
		(width 0.1143)
		(layer "In15.Cu")
		(net "GMI_CPU0_G1_CPU1_G3_TX_DN<5>")
	)
	(segment
		(start 353.328224 -224.721674)
		(end 353.289108 -224.698814)
		(width 0.1143)
		(layer "In15.Cu")
		(net "GMI_CPU0_G1_CPU1_G3_TX_DN<5>")
	)
	(segment
		(start 117.03685 -221.020386)
		(end 116.99113 -221.066106)
		(width 0.1143)
		(layer "In15.Cu")
		(net "GMI_CPU0_G1_CPU1_G3_TX_DN<5>")
	)
	(segment
		(start 309.794656 -180.56987)
		(end 307.568854 -179.774088)
		(width 0.14224)
		(layer "In15.Cu")
		(net "GMI_CPU0_G1_CPU1_G3_TX_DN<5>")
	)
	(segment
		(start 354.289106 -235.07446)
		(end 354.289868 -235.073952)
		(width 0.1143)
		(layer "In15.Cu")
		(net "GMI_CPU0_G1_CPU1_G3_TX_DN<5>")
	)
	(segment
		(start 353.328224 -223.746822)
		(end 353.359974 -223.728534)
		(width 0.1143)
		(layer "In15.Cu")
		(net "GMI_CPU0_G1_CPU1_G3_TX_DN<5>")
	)
	(segment
		(start 148.116036 -190.188088)
		(end 146.269202 -191.702182)
		(width 0.14224)
		(layer "In15.Cu")
		(net "GMI_CPU0_G1_CPU1_G3_TX_DN<5>")
	)
	(segment
		(start 117.197124 -231.829102)
		(end 117.227604 -231.846882)
		(width 0.1143)
		(layer "In15.Cu")
		(net "GMI_CPU0_G1_CPU1_G3_TX_DN<5>")
	)
	(segment
		(start 349.471996 -211.522818)
		(end 316.022736 -184.09539)
		(width 0.14224)
		(layer "In15.Cu")
		(net "GMI_CPU0_G1_CPU1_G3_TX_DN<5>")
	)
	(segment
		(start 354.268024 -231.846628)
		(end 354.299774 -231.82834)
		(width 0.1143)
		(layer "In15.Cu")
		(net "GMI_CPU0_G1_CPU1_G3_TX_DN<5>")
	)
	(segment
		(start 354.231702 -233.487722)
		(end 354.268024 -233.46664)
		(width 0.1143)
		(layer "In15.Cu")
		(net "GMI_CPU0_G1_CPU1_G3_TX_DN<5>")
	)
	(segment
		(start 354.289868 -239.933988)
		(end 354.299774 -239.9284)
		(width 0.1143)
		(layer "In15.Cu")
		(net "GMI_CPU0_G1_CPU1_G3_TX_DN<5>")
	)
	(segment
		(start 354.299774 -226.359974)
		(end 354.268024 -226.341686)
		(width 0.1143)
		(layer "In15.Cu")
		(net "GMI_CPU0_G1_CPU1_G3_TX_DN<5>")
	)
	(segment
		(start 353.496372 -221.38767)
		(end 353.496372 -221.128844)
		(width 0.1143)
		(layer "In15.Cu")
		(net "GMI_CPU0_G1_CPU1_G3_TX_DN<5>")
	)
	(segment
		(start 117.197124 -235.069126)
		(end 117.227604 -235.086906)
		(width 0.1143)
		(layer "In15.Cu")
		(net "GMI_CPU0_G1_CPU1_G3_TX_DN<5>")
	)
	(segment
		(start 354.268024 -239.946688)
		(end 354.289106 -239.934496)
		(width 0.1143)
		(layer "In15.Cu")
		(net "GMI_CPU0_G1_CPU1_G3_TX_DN<5>")
	)
	(segment
		(start 117.197124 -223.729296)
		(end 117.227604 -223.747076)
		(width 0.1143)
		(layer "In15.Cu")
		(net "GMI_CPU0_G1_CPU1_G3_TX_DN<5>")
	)
	(segment
		(start 354.268786 -239.302036)
		(end 354.268024 -239.301528)
		(width 0.1143)
		(layer "In15.Cu")
		(net "GMI_CPU0_G1_CPU1_G3_TX_DN<5>")
	)
	(segment
		(start 117.197124 -230.20909)
		(end 117.26418 -230.248206)
		(width 0.1143)
		(layer "In15.Cu")
		(net "GMI_CPU0_G1_CPU1_G3_TX_DN<5>")
	)
	(segment
		(start 117.26672 -223.079056)
		(end 117.227604 -223.101916)
		(width 0.1143)
		(layer "In15.Cu")
		(net "GMI_CPU0_G1_CPU1_G3_TX_DN<5>")
	)
	(segment
		(start 152.256998 -186.793378)
		(end 152.256744 -186.793124)
		(width 0.14224)
		(layer "In15.Cu")
		(net "GMI_CPU0_G1_CPU1_G3_TX_DN<5>")
	)
	(segment
		(start 354.298758 -231.219248)
		(end 354.257864 -231.195372)
		(width 0.1143)
		(layer "In15.Cu")
		(net "GMI_CPU0_G1_CPU1_G3_TX_DN<5>")
	)
	(segment
		(start 354.270564 -236.063028)
		(end 354.269802 -236.06252)
		(width 0.1143)
		(layer "In15.Cu")
		(net "GMI_CPU0_G1_CPU1_G3_TX_DN<5>")
	)
	(segment
		(start 152.849834 -186.474354)
		(end 152.667462 -186.45632)
		(width 0.14224)
		(layer "In15.Cu")
		(net "GMI_CPU0_G1_CPU1_G3_TX_DN<5>")
	)
	(segment
		(start 354.273358 -239.304576)
		(end 354.272342 -239.304068)
		(width 0.1143)
		(layer "In15.Cu")
		(net "GMI_CPU0_G1_CPU1_G3_TX_DN<5>")
	)
	(segment
		(start 353.289108 -223.769682)
		(end 353.291902 -223.76765)
		(width 0.1143)
		(layer "In15.Cu")
		(net "GMI_CPU0_G1_CPU1_G3_TX_DN<5>")
	)
	(segment
		(start 354.27158 -242.543584)
		(end 354.270564 -242.543076)
		(width 0.1143)
		(layer "In15.Cu")
		(net "GMI_CPU0_G1_CPU1_G3_TX_DN<5>")
	)
	(segment
		(start 117.227604 -237.68177)
		(end 117.197124 -237.69955)
		(width 0.1143)
		(layer "In15.Cu")
		(net "GMI_CPU0_G1_CPU1_G3_TX_DN<5>")
	)
	(segment
		(start 353.51593 -221.407228)
		(end 353.496372 -221.38767)
		(width 0.1143)
		(layer "In15.Cu")
		(net "GMI_CPU0_G1_CPU1_G3_TX_DN<5>")
	)
	(segment
		(start 354.269802 -236.06252)
		(end 354.268786 -236.062012)
		(width 0.1143)
		(layer "In15.Cu")
		(net "GMI_CPU0_G1_CPU1_G3_TX_DN<5>")
	)
	(segment
		(start 354.264468 -230.228648)
		(end 354.265484 -230.22814)
		(width 0.1143)
		(layer "In15.Cu")
		(net "GMI_CPU0_G1_CPU1_G3_TX_DN<5>")
	)
	(segment
		(start 117.197124 -226.96932)
		(end 117.227604 -226.9871)
		(width 0.1143)
		(layer "In15.Cu")
		(net "GMI_CPU0_G1_CPU1_G3_TX_DN<5>")
	)
	(segment
		(start 353.328986 -223.10217)
		(end 353.328224 -223.101662)
		(width 0.1143)
		(layer "In15.Cu")
		(net "GMI_CPU0_G1_CPU1_G3_TX_DN<5>")
	)
	(segment
		(start 117.227604 -223.747076)
		(end 117.26672 -223.769936)
		(width 0.1143)
		(layer "In15.Cu")
		(net "GMI_CPU0_G1_CPU1_G3_TX_DN<5>")
	)
	(segment
		(start 354.26777 -236.706918)
		(end 354.268024 -236.706664)
		(width 0.1143)
		(layer "In15.Cu")
		(net "GMI_CPU0_G1_CPU1_G3_TX_DN<5>")
	)
	(segment
		(start 354.268024 -240.92154)
		(end 354.26777 -240.92154)
		(width 0.1143)
		(layer "In15.Cu")
		(net "GMI_CPU0_G1_CPU1_G3_TX_DN<5>")
	)
	(segment
		(start 353.822 -225.545396)
		(end 353.801426 -225.533458)
		(width 0.1143)
		(layer "In15.Cu")
		(net "GMI_CPU0_G1_CPU1_G3_TX_DN<5>")
	)
	(segment
		(start 117.227604 -232.821734)
		(end 117.197124 -232.839514)
		(width 0.1143)
		(layer "In15.Cu")
		(net "GMI_CPU0_G1_CPU1_G3_TX_DN<5>")
	)
	(segment
		(start 353.98583 -225.870516)
		(end 353.98583 -225.870262)
		(width 0.1143)
		(layer "In15.Cu")
		(net "GMI_CPU0_G1_CPU1_G3_TX_DN<5>")
	)
	(segment
		(start 117.227604 -241.566954)
		(end 117.26672 -241.589814)
		(width 0.1143)
		(layer "In15.Cu")
		(net "GMI_CPU0_G1_CPU1_G3_TX_DN<5>")
	)
	(segment
		(start 353.321366 -223.097598)
		(end 353.296728 -223.083374)
		(width 0.1143)
		(layer "In15.Cu")
		(net "GMI_CPU0_G1_CPU1_G3_TX_DN<5>")
	)
	(segment
		(start 117.227604 -235.086906)
		(end 117.26672 -235.109766)
		(width 0.1143)
		(layer "In15.Cu")
		(net "GMI_CPU0_G1_CPU1_G3_TX_DN<5>")
	)
	(segment
		(start 354.301552 -229.601268)
		(end 354.30079 -229.60076)
		(width 0.1143)
		(layer "In15.Cu")
		(net "GMI_CPU0_G1_CPU1_G3_TX_DN<5>")
	)
	(segment
		(start 353.824286 -225.54692)
		(end 353.822 -225.545396)
		(width 0.1143)
		(layer "In15.Cu")
		(net "GMI_CPU0_G1_CPU1_G3_TX_DN<5>")
	)
	(segment
		(start 354.27158 -239.30356)
		(end 354.270564 -239.303052)
		(width 0.1143)
		(layer "In15.Cu")
		(net "GMI_CPU0_G1_CPU1_G3_TX_DN<5>")
	)
	(segment
		(start 117.26672 -242.518946)
		(end 117.227604 -242.541806)
		(width 0.1143)
		(layer "In15.Cu")
		(net "GMI_CPU0_G1_CPU1_G3_TX_DN<5>")
	)
	(segment
		(start 117.26672 -229.559104)
		(end 117.227604 -229.581964)
		(width 0.1143)
		(layer "In15.Cu")
		(net "GMI_CPU0_G1_CPU1_G3_TX_DN<5>")
	)
	(segment
		(start 117.227604 -236.706918)
		(end 117.26672 -236.729778)
		(width 0.1143)
		(layer "In15.Cu")
		(net "GMI_CPU0_G1_CPU1_G3_TX_DN<5>")
	)
	(segment
		(start 307.568854 -179.774088)
		(end 302.904144 -179.774088)
		(width 0.14224)
		(layer "In15.Cu")
		(net "GMI_CPU0_G1_CPU1_G3_TX_DN<5>")
	)
	(segment
		(start 354.270056 -228.605588)
		(end 354.299774 -228.58857)
		(width 0.1143)
		(layer "In15.Cu")
		(net "GMI_CPU0_G1_CPU1_G3_TX_DN<5>")
	)
	(segment
		(start 354.233226 -226.32162)
		(end 354.231702 -226.320604)
		(width 0.1143)
		(layer "In15.Cu")
		(net "GMI_CPU0_G1_CPU1_G3_TX_DN<5>")
	)
	(segment
		(start 354.27539 -242.54587)
		(end 354.27412 -242.545108)
		(width 0.1143)
		(layer "In15.Cu")
		(net "GMI_CPU0_G1_CPU1_G3_TX_DN<5>")
	)
	(segment
		(start 316.022736 -184.09539)
		(end 312.908442 -182.33263)
		(width 0.14224)
		(layer "In15.Cu")
		(net "GMI_CPU0_G1_CPU1_G3_TX_DN<5>")
	)
	(segment
		(start 354.289106 -241.554508)
		(end 354.289868 -241.554)
		(width 0.1143)
		(layer "In15.Cu")
		(net "GMI_CPU0_G1_CPU1_G3_TX_DN<5>")
	)
	(segment
		(start 354.299774 -237.699804)
		(end 354.27539 -237.685834)
		(width 0.1143)
		(layer "In15.Cu")
		(net "GMI_CPU0_G1_CPU1_G3_TX_DN<5>")
	)
	(segment
		(start 354.268024 -229.58171)
		(end 354.234496 -229.562152)
		(width 0.1143)
		(layer "In15.Cu")
		(net "GMI_CPU0_G1_CPU1_G3_TX_DN<5>")
	)
	(segment
		(start 353.797108 -225.531172)
		(end 353.759008 -225.50882)
		(width 0.1143)
		(layer "In15.Cu")
		(net "GMI_CPU0_G1_CPU1_G3_TX_DN<5>")
	)
	(segment
		(start 150.402798 -188.313314)
		(end 150.383748 -188.506354)
		(width 0.14224)
		(layer "In15.Cu")
		(net "GMI_CPU0_G1_CPU1_G3_TX_DN<5>")
	)
	(segment
		(start 150.987506 -188.001402)
		(end 150.805388 -187.983368)
		(width 0.14224)
		(layer "In15.Cu")
		(net "GMI_CPU0_G1_CPU1_G3_TX_DN<5>")
	)
	(segment
		(start 353.32543 -223.100138)
		(end 353.323906 -223.099122)
		(width 0.1143)
		(layer "In15.Cu")
		(net "GMI_CPU0_G1_CPU1_G3_TX_DN<5>")
	)
	(segment
		(start 144.149318 -193.32194)
		(end 120.45569 -212.749638)
		(width 0.14224)
		(layer "In15.Cu")
		(net "GMI_CPU0_G1_CPU1_G3_TX_DN<5>")
	)
	(segment
		(start 354.272342 -239.304068)
		(end 354.27158 -239.30356)
		(width 0.1143)
		(layer "In15.Cu")
		(net "GMI_CPU0_G1_CPU1_G3_TX_DN<5>")
	)
	(segment
		(start 354.234496 -229.562152)
		(end 354.231702 -229.560628)
		(width 0.1143)
		(layer "In15.Cu")
		(net "GMI_CPU0_G1_CPU1_G3_TX_DN<5>")
	)
	(segment
		(start 148.309076 -190.207392)
		(end 148.116036 -190.188088)
		(width 0.14224)
		(layer "In15.Cu")
		(net "GMI_CPU0_G1_CPU1_G3_TX_DN<5>")
	)
	(segment
		(start 117.039644 -221.247462)
		(end 117.039644 -221.804484)
		(width 0.1143)
		(layer "In15.Cu")
		(net "GMI_CPU0_G1_CPU1_G3_TX_DN<5>")
	)
	(segment
		(start 354.231702 -243.207794)
		(end 354.268024 -243.186712)
		(width 0.1143)
		(layer "In15.Cu")
		(net "GMI_CPU0_G1_CPU1_G3_TX_DN<5>")
	)
	(segment
		(start 354.27412 -237.685072)
		(end 354.273358 -237.684564)
		(width 0.1143)
		(layer "In15.Cu")
		(net "GMI_CPU0_G1_CPU1_G3_TX_DN<5>")
	)
	(segment
		(start 117.1956 -222.108776)
		(end 117.22735 -222.127064)
		(width 0.1143)
		(layer "In15.Cu")
		(net "GMI_CPU0_G1_CPU1_G3_TX_DN<5>")
	)
	(segment
		(start 354.268786 -237.682024)
		(end 354.268024 -237.681516)
		(width 0.1143)
		(layer "In15.Cu")
		(net "GMI_CPU0_G1_CPU1_G3_TX_DN<5>")
	)
	(segment
		(start 354.379022 -244.484144)
		(end 354.448872 -244.414294)
		(width 0.1143)
		(layer "In15.Cu")
		(net "GMI_CPU0_G1_CPU1_G3_TX_DN<5>")
	)
	(segment
		(start 151.732234 -187.2234)
		(end 151.329898 -187.553092)
		(width 0.14224)
		(layer "In15.Cu")
		(net "GMI_CPU0_G1_CPU1_G3_TX_DN<5>")
	)
	(segment
		(start 354.269802 -240.922556)
		(end 354.268786 -240.922048)
		(width 0.1143)
		(layer "In15.Cu")
		(net "GMI_CPU0_G1_CPU1_G3_TX_DN<5>")
	)
	(segment
		(start 153.51633 -185.76036)
		(end 153.516584 -185.760614)
		(width 0.14224)
		(layer "In15.Cu")
		(net "GMI_CPU0_G1_CPU1_G3_TX_DN<5>")
	)
	(segment
		(start 117.227604 -242.541806)
		(end 117.197124 -242.559586)
		(width 0.1143)
		(layer "In15.Cu")
		(net "GMI_CPU0_G1_CPU1_G3_TX_DN<5>")
	)
	(segment
		(start 117.26672 -232.798874)
		(end 117.227604 -232.821734)
		(width 0.1143)
		(layer "In15.Cu")
		(net "GMI_CPU0_G1_CPU1_G3_TX_DN<5>")
	)
	(segment
		(start 117.26672 -244.138958)
		(end 117.227604 -244.161818)
		(width 0.1143)
		(layer "In15.Cu")
		(net "GMI_CPU0_G1_CPU1_G3_TX_DN<5>")
	)
	(segment
		(start 117.227604 -229.581964)
		(end 117.195092 -229.60076)
		(width 0.1143)
		(layer "In15.Cu")
		(net "GMI_CPU0_G1_CPU1_G3_TX_DN<5>")
	)
	(segment
		(start 149.181312 -189.492128)
		(end 148.988272 -189.473078)
		(width 0.14224)
		(layer "In15.Cu")
		(net "GMI_CPU0_G1_CPU1_G3_TX_DN<5>")
	)
	(segment
		(start 154.022806 -185.51271)
		(end 153.698448 -185.778648)
		(width 0.14224)
		(layer "In15.Cu")
		(net "GMI_CPU0_G1_CPU1_G3_TX_DN<5>")
	)
	(segment
		(start 354.234496 -230.246174)
		(end 354.23602 -230.245158)
		(width 0.1143)
		(layer "In15.Cu")
		(net "GMI_CPU0_G1_CPU1_G3_TX_DN<5>")
	)
	(segment
		(start 117.03685 -220.991938)
		(end 117.03685 -221.020386)
		(width 0.1143)
		(layer "In15.Cu")
		(net "GMI_CPU0_G1_CPU1_G3_TX_DN<5>")
	)
	(segment
		(start 154.547062 -185.082942)
		(end 154.364944 -185.064654)
		(width 0.14224)
		(layer "In15.Cu")
		(net "GMI_CPU0_G1_CPU1_G3_TX_DN<5>")
	)
	(segment
		(start 152.667462 -186.45632)
		(end 152.667716 -186.456574)
		(width 0.14224)
		(layer "In15.Cu")
		(net "GMI_CPU0_G1_CPU1_G3_TX_DN<5>")
	)
	(segment
		(start 353.801426 -225.533458)
		(end 353.798124 -225.53168)
		(width 0.1143)
		(layer "In15.Cu")
		(net "GMI_CPU0_G1_CPU1_G3_TX_DN<5>")
	)
	(segment
		(start 354.273358 -242.5446)
		(end 354.272342 -242.544092)
		(width 0.1143)
		(layer "In15.Cu")
		(net "GMI_CPU0_G1_CPU1_G3_TX_DN<5>")
	)
	(segment
		(start 154.041094 -185.330846)
		(end 154.04084 -185.330338)
		(width 0.14224)
		(layer "In15.Cu")
		(net "GMI_CPU0_G1_CPU1_G3_TX_DN<5>")
	)
	(segment
		(start 354.27158 -240.923572)
		(end 354.270564 -240.923064)
		(width 0.1143)
		(layer "In15.Cu")
		(net "GMI_CPU0_G1_CPU1_G3_TX_DN<5>")
	)
	(segment
		(start 354.27412 -240.925096)
		(end 354.273358 -240.924588)
		(width 0.1143)
		(layer "In15.Cu")
		(net "GMI_CPU0_G1_CPU1_G3_TX_DN<5>")
	)
	(segment
		(start 117.26672 -240.898934)
		(end 117.227604 -240.921794)
		(width 0.1143)
		(layer "In15.Cu")
		(net "GMI_CPU0_G1_CPU1_G3_TX_DN<5>")
	)
	(segment
		(start 354.301552 -231.22128)
		(end 354.298758 -231.219248)
		(width 0.1143)
		(layer "In15.Cu")
		(net "GMI_CPU0_G1_CPU1_G3_TX_DN<5>")
	)
	(segment
		(start 354.299774 -236.079792)
		(end 354.274374 -236.065314)
		(width 0.1143)
		(layer "In15.Cu")
		(net "GMI_CPU0_G1_CPU1_G3_TX_DN<5>")
	)
	(segment
		(start 354.268024 -236.706664)
		(end 354.289106 -236.694472)
		(width 0.1143)
		(layer "In15.Cu")
		(net "GMI_CPU0_G1_CPU1_G3_TX_DN<5>")
	)
	(segment
		(start 354.08108 -244.484144)
		(end 354.379022 -244.484144)
		(width 0.1143)
		(layer "In15.Cu")
		(net "GMI_CPU0_G1_CPU1_G3_TX_DN<5>")
	)
	(segment
		(start 354.268024 -234.441492)
		(end 354.231702 -234.42041)
		(width 0.1143)
		(layer "In15.Cu")
		(net "GMI_CPU0_G1_CPU1_G3_TX_DN<5>")
	)
	(segment
		(start 153.19248 -186.026552)
		(end 153.192226 -186.026044)
		(width 0.14224)
		(layer "In15.Cu")
		(net "GMI_CPU0_G1_CPU1_G3_TX_DN<5>")
	)
	(segment
		(start 117.197124 -236.689138)
		(end 117.227604 -236.706918)
		(width 0.1143)
		(layer "In15.Cu")
		(net "GMI_CPU0_G1_CPU1_G3_TX_DN<5>")
	)
	(segment
		(start 151.311864 -187.735464)
		(end 150.987506 -188.001402)
		(width 0.14224)
		(layer "In15.Cu")
		(net "GMI_CPU0_G1_CPU1_G3_TX_DN<5>")
	)
	(segment
		(start 353.291902 -223.76765)
		(end 353.328224 -223.746822)
		(width 0.1143)
		(layer "In15.Cu")
		(net "GMI_CPU0_G1_CPU1_G3_TX_DN<5>")
	)
	(segment
		(start 312.908696 -182.33263)
		(end 309.794656 -180.56987)
		(width 0.14224)
		(layer "In15.Cu")
		(net "GMI_CPU0_G1_CPU1_G3_TX_DN<5>")
	)
	(segment
		(start 354.272342 -240.92408)
		(end 354.27158 -240.923572)
		(width 0.1143)
		(layer "In15.Cu")
		(net "GMI_CPU0_G1_CPU1_G3_TX_DN<5>")
	)
	(segment
		(start 117.04701 -244.414548)
		(end 117.11686 -244.484398)
		(width 0.1143)
		(layer "In15.Cu")
		(net "GMI_CPU0_G1_CPU1_G3_TX_DN<5>")
	)
	(segment
		(start 154.889454 -184.634632)
		(end 154.87142 -184.817004)
		(width 0.14224)
		(layer "In15.Cu")
		(net "GMI_CPU0_G1_CPU1_G3_TX_DN<5>")
	)
	(segment
		(start 117.26672 -224.699068)
		(end 117.227604 -224.721928)
		(width 0.1143)
		(layer "In15.Cu")
		(net "GMI_CPU0_G1_CPU1_G3_TX_DN<5>")
	)
	(segment
		(start 117.227604 -231.201976)
		(end 117.195092 -231.220772)
		(width 0.1143)
		(layer "In15.Cu")
		(net "GMI_CPU0_G1_CPU1_G3_TX_DN<5>")
	)
	(segment
		(start 354.273358 -240.924588)
		(end 354.272342 -240.92408)
		(width 0.1143)
		(layer "In15.Cu")
		(net "GMI_CPU0_G1_CPU1_G3_TX_DN<5>")
	)
	(segment
		(start 117.26672 -227.939092)
		(end 117.227604 -227.961952)
		(width 0.1143)
		(layer "In15.Cu")
		(net "GMI_CPU0_G1_CPU1_G3_TX_DN<5>")
	)
	(segment
		(start 152.256744 -186.793124)
		(end 152.23871 -186.975496)
		(width 0.14224)
		(layer "In15.Cu")
		(net "GMI_CPU0_G1_CPU1_G3_TX_DN<5>")
	)
	(segment
		(start 117.227604 -226.34194)
		(end 117.197124 -226.35972)
		(width 0.1143)
		(layer "In15.Cu")
		(net "GMI_CPU0_G1_CPU1_G3_TX_DN<5>")
	)
	(segment
		(start 354.289868 -235.073952)
		(end 354.299774 -235.068364)
		(width 0.1143)
		(layer "In15.Cu")
		(net "GMI_CPU0_G1_CPU1_G3_TX_DN<5>")
	)
	(segment
		(start 354.27412 -239.305084)
		(end 354.273358 -239.304576)
		(width 0.1143)
		(layer "In15.Cu")
		(net "GMI_CPU0_G1_CPU1_G3_TX_DN<5>")
	)
	(segment
		(start 117.26672 -226.31908)
		(end 117.227604 -226.34194)
		(width 0.1143)
		(layer "In15.Cu")
		(net "GMI_CPU0_G1_CPU1_G3_TX_DN<5>")
	)
	(segment
		(start 354.272342 -242.544092)
		(end 354.27158 -242.543584)
		(width 0.1143)
		(layer "In15.Cu")
		(net "GMI_CPU0_G1_CPU1_G3_TX_DN<5>")
	)
	(segment
		(start 152.23871 -186.975496)
		(end 151.914352 -187.241434)
		(width 0.14224)
		(layer "In15.Cu")
		(net "GMI_CPU0_G1_CPU1_G3_TX_DN<5>")
	)
	(segment
		(start 117.227604 -238.32693)
		(end 117.26672 -238.34979)
		(width 0.1143)
		(layer "In15.Cu")
		(net "GMI_CPU0_G1_CPU1_G3_TX_DN<5>")
	)
	(segment
		(start 354.268786 -242.54206)
		(end 354.268024 -242.541552)
		(width 0.1143)
		(layer "In15.Cu")
		(net "GMI_CPU0_G1_CPU1_G3_TX_DN<5>")
	)
	(segment
		(start 354.299774 -232.839768)
		(end 354.268024 -232.82148)
		(width 0.1143)
		(layer "In15.Cu")
		(net "GMI_CPU0_G1_CPU1_G3_TX_DN<5>")
	)
	(segment
		(start 117.227604 -244.161818)
		(end 117.197124 -244.179598)
		(width 0.1143)
		(layer "In15.Cu")
		(net "GMI_CPU0_G1_CPU1_G3_TX_DN<5>")
	)
	(segment
		(start 148.639276 -189.936628)
		(end 148.309076 -190.207392)
		(width 0.14224)
		(layer "In15.Cu")
		(net "GMI_CPU0_G1_CPU1_G3_TX_DN<5>")
	)
	(segment
		(start 354.268024 -232.82148)
		(end 354.231702 -232.800398)
		(width 0.1143)
		(layer "In15.Cu")
		(net "GMI_CPU0_G1_CPU1_G3_TX_DN<5>")
	)
	(segment
		(start 354.268024 -237.681516)
		(end 354.26777 -237.681516)
		(width 0.1143)
		(layer "In15.Cu")
		(net "GMI_CPU0_G1_CPU1_G3_TX_DN<5>")
	)
	(segment
		(start 116.99113 -221.198948)
		(end 117.039644 -221.247462)
		(width 0.1143)
		(layer "In15.Cu")
		(net "GMI_CPU0_G1_CPU1_G3_TX_DN<5>")
	)
	(segment
		(start 354.268024 -226.341686)
		(end 354.233226 -226.32162)
		(width 0.1143)
		(layer "In15.Cu")
		(net "GMI_CPU0_G1_CPU1_G3_TX_DN<5>")
	)
	(segment
		(start 117.227604 -239.301782)
		(end 117.197124 -239.319562)
		(width 0.1143)
		(layer "In15.Cu")
		(net "GMI_CPU0_G1_CPU1_G3_TX_DN<5>")
	)
	(segment
		(start 354.299774 -234.45978)
		(end 354.268024 -234.441492)
		(width 0.1143)
		(layer "In15.Cu")
		(net "GMI_CPU0_G1_CPU1_G3_TX_DN<5>")
	)
	(segment
		(start 354.268024 -244.161564)
		(end 354.231702 -244.140482)
		(width 0.1143)
		(layer "In15.Cu")
		(net "GMI_CPU0_G1_CPU1_G3_TX_DN<5>")
	)
	(segment
		(start 354.289106 -238.314484)
		(end 354.289868 -238.313976)
		(width 0.1143)
		(layer "In15.Cu")
		(net "GMI_CPU0_G1_CPU1_G3_TX_DN<5>")
	)
	(segment
		(start 144.378426 -193.252344)
		(end 144.149318 -193.32194)
		(width 0.14224)
		(layer "In15.Cu")
		(net "GMI_CPU0_G1_CPU1_G3_TX_DN<5>")
	)
	(segment
		(start 353.825302 -225.547428)
		(end 353.824286 -225.54692)
		(width 0.1143)
		(layer "In15.Cu")
		(net "GMI_CPU0_G1_CPU1_G3_TX_DN<5>")
	)
	(segment
		(start 354.27158 -237.683548)
		(end 354.270564 -237.68304)
		(width 0.1143)
		(layer "In15.Cu")
		(net "GMI_CPU0_G1_CPU1_G3_TX_DN<5>")
	)
	(segment
		(start 151.329898 -187.553092)
		(end 151.311864 -187.735464)
		(width 0.14224)
		(layer "In15.Cu")
		(net "GMI_CPU0_G1_CPU1_G3_TX_DN<5>")
	)
	(segment
		(start 148.988272 -189.473078)
		(end 148.658326 -189.743588)
		(width 0.14224)
		(layer "In15.Cu")
		(net "GMI_CPU0_G1_CPU1_G3_TX_DN<5>")
	)
	(segment
		(start 354.289868 -236.693964)
		(end 354.299774 -236.688376)
		(width 0.1143)
		(layer "In15.Cu")
		(net "GMI_CPU0_G1_CPU1_G3_TX_DN<5>")
	)
	(segment
		(start 117.227604 -227.961952)
		(end 117.197124 -227.979732)
		(width 0.1143)
		(layer "In15.Cu")
		(net "GMI_CPU0_G1_CPU1_G3_TX_DN<5>")
	)
	(segment
		(start 149.860508 -188.758068)
		(end 149.530562 -189.028578)
		(width 0.14224)
		(layer "In15.Cu")
		(net "GMI_CPU0_G1_CPU1_G3_TX_DN<5>")
	)
	(segment
		(start 153.698448 -185.778648)
		(end 153.51633 -185.76036)
		(width 0.14224)
		(layer "In15.Cu")
		(net "GMI_CPU0_G1_CPU1_G3_TX_DN<5>")
	)
	(segment
		(start 354.270564 -242.543076)
		(end 354.269802 -242.542568)
		(width 0.1143)
		(layer "In15.Cu")
		(net "GMI_CPU0_G1_CPU1_G3_TX_DN<5>")
	)
	(segment
		(start 354.268786 -236.062012)
		(end 354.268024 -236.061504)
		(width 0.1143)
		(layer "In15.Cu")
		(net "GMI_CPU0_G1_CPU1_G3_TX_DN<5>")
	)
	(segment
		(start 120.45569 -212.749638)
		(end 117.03685 -218.58224)
		(width 0.14224)
		(layer "In15.Cu")
		(net "GMI_CPU0_G1_CPU1_G3_TX_DN<5>")
	)
	(segment
		(start 353.359974 -223.11995)
		(end 353.328986 -223.10217)
		(width 0.1143)
		(layer "In15.Cu")
		(net "GMI_CPU0_G1_CPU1_G3_TX_DN<5>")
	)
	(segment
		(start 117.227604 -234.441746)
		(end 117.197124 -234.459526)
		(width 0.1143)
		(layer "In15.Cu")
		(net "GMI_CPU0_G1_CPU1_G3_TX_DN<5>")
	)
	(segment
		(start 153.516584 -185.760614)
		(end 153.19248 -186.026552)
		(width 0.14224)
		(layer "In15.Cu")
		(net "GMI_CPU0_G1_CPU1_G3_TX_DN<5>")
	)
	(segment
		(start 151.914352 -187.241434)
		(end 151.732234 -187.2234)
		(width 0.14224)
		(layer "In15.Cu")
		(net "GMI_CPU0_G1_CPU1_G3_TX_DN<5>")
	)
	(segment
		(start 165.86581 -178.97475)
		(end 158.644082 -181.556914)
		(width 0.14224)
		(layer "In15.Cu")
		(net "GMI_CPU0_G1_CPU1_G3_TX_DN<5>")
	)
	(segment
		(start 150.383748 -188.506354)
		(end 150.053548 -188.777118)
		(width 0.14224)
		(layer "In15.Cu")
		(net "GMI_CPU0_G1_CPU1_G3_TX_DN<5>")
	)
	(segment
		(start 354.26777 -239.946942)
		(end 354.268024 -239.946688)
		(width 0.1143)
		(layer "In15.Cu")
		(net "GMI_CPU0_G1_CPU1_G3_TX_DN<5>")
	)
	(segment
		(start 117.227604 -240.921794)
		(end 117.197124 -240.939574)
		(width 0.1143)
		(layer "In15.Cu")
		(net "GMI_CPU0_G1_CPU1_G3_TX_DN<5>")
	)
	(segment
		(start 353.295966 -223.082866)
		(end 353.289108 -223.078802)
		(width 0.1143)
		(layer "In15.Cu")
		(net "GMI_CPU0_G1_CPU1_G3_TX_DN<5>")
	)
	(segment
		(start 354.268024 -236.061504)
		(end 354.26777 -236.061504)
		(width 0.1143)
		(layer "In15.Cu")
		(net "GMI_CPU0_G1_CPU1_G3_TX_DN<5>")
	)
	(segment
		(start 353.328224 -223.101662)
		(end 353.327208 -223.101154)
		(width 0.1143)
		(layer "In15.Cu")
		(net "GMI_CPU0_G1_CPU1_G3_TX_DN<5>")
	)
	(segment
		(start 354.269802 -239.302544)
		(end 354.268786 -239.302036)
		(width 0.1143)
		(layer "In15.Cu")
		(net "GMI_CPU0_G1_CPU1_G3_TX_DN<5>")
	)
	(segment
		(start 117.197124 -239.929162)
		(end 117.227604 -239.946942)
		(width 0.1143)
		(layer "In15.Cu")
		(net "GMI_CPU0_G1_CPU1_G3_TX_DN<5>")
	)
	(segment
		(start 354.289106 -236.694472)
		(end 354.289868 -236.693964)
		(width 0.1143)
		(layer "In15.Cu")
		(net "GMI_CPU0_G1_CPU1_G3_TX_DN<5>")
	)
	(segment
		(start 354.299774 -227.979986)
		(end 354.268786 -227.962206)
		(width 0.1143)
		(layer "In15.Cu")
		(net "GMI_CPU0_G1_CPU1_G3_TX_DN<5>")
	)
	(segment
		(start 354.268024 -227.961698)
		(end 354.231702 -227.940616)
		(width 0.1143)
		(layer "In15.Cu")
		(net "GMI_CPU0_G1_CPU1_G3_TX_DN<5>")
	)
	(segment
		(start 117.197124 -228.589332)
		(end 117.227604 -228.607112)
		(width 0.1143)
		(layer "In15.Cu")
		(net "GMI_CPU0_G1_CPU1_G3_TX_DN<5>")
	)
	(segment
		(start 354.271834 -230.22433)
		(end 354.299774 -230.208328)
		(width 0.1143)
		(layer "In15.Cu")
		(net "GMI_CPU0_G1_CPU1_G3_TX_DN<5>")
	)
	(segment
		(start 354.273358 -237.684564)
		(end 354.272342 -237.684056)
		(width 0.1143)
		(layer "In15.Cu")
		(net "GMI_CPU0_G1_CPU1_G3_TX_DN<5>")
	)
	(segment
		(start 354.268024 -233.46664)
		(end 354.299774 -233.448352)
		(width 0.1143)
		(layer "In15.Cu")
		(net "GMI_CPU0_G1_CPU1_G3_TX_DN<5>")
	)
	(segment
		(start 353.51593 -221.80423)
		(end 353.51593 -221.407228)
		(width 0.1143)
		(layer "In15.Cu")
		(net "GMI_CPU0_G1_CPU1_G3_TX_DN<5>")
	)
	(segment
		(start 149.511512 -189.221364)
		(end 149.181312 -189.492128)
		(width 0.14224)
		(layer "In15.Cu")
		(net "GMI_CPU0_G1_CPU1_G3_TX_DN<5>")
	)
	(segment
		(start 354.268024 -238.326676)
		(end 354.289106 -238.314484)
		(width 0.1143)
		(layer "In15.Cu")
		(net "GMI_CPU0_G1_CPU1_G3_TX_DN<5>")
	)
	(segment
		(start 354.268024 -226.986846)
		(end 354.299774 -226.968558)
		(width 0.1143)
		(layer "In15.Cu")
		(net "GMI_CPU0_G1_CPU1_G3_TX_DN<5>")
	)
	(segment
		(start 146.268948 -191.702436)
		(end 144.378426 -193.252344)
		(width 0.14224)
		(layer "In15.Cu")
		(net "GMI_CPU0_G1_CPU1_G3_TX_DN<5>")
	)
	(segment
		(start 353.496372 -221.128844)
		(end 353.450652 -221.083124)
		(width 0.1143)
		(layer "In15.Cu")
		(net "GMI_CPU0_G1_CPU1_G3_TX_DN<5>")
	)
	(segment
		(start 154.87142 -184.817004)
		(end 154.547062 -185.082942)
		(width 0.14224)
		(layer "In15.Cu")
		(net "GMI_CPU0_G1_CPU1_G3_TX_DN<5>")
	)
	(segment
		(start 117.227604 -225.367088)
		(end 117.26672 -225.389948)
		(width 0.1143)
		(layer "In15.Cu")
		(net "GMI_CPU0_G1_CPU1_G3_TX_DN<5>")
	)
	(segment
		(start 354.231702 -231.86771)
		(end 354.268024 -231.846628)
		(width 0.1143)
		(layer "In15.Cu")
		(net "GMI_CPU0_G1_CPU1_G3_TX_DN<5>")
	)
	(segment
		(start 117.26672 -234.418886)
		(end 117.227604 -234.441746)
		(width 0.1143)
		(layer "In15.Cu")
		(net "GMI_CPU0_G1_CPU1_G3_TX_DN<5>")
	)
	(segment
		(start 354.289868 -241.554)
		(end 354.299774 -241.548412)
		(width 0.1143)
		(layer "In15.Cu")
		(net "GMI_CPU0_G1_CPU1_G3_TX_DN<5>")
	)
	(segment
		(start 153.174192 -186.208416)
		(end 152.849834 -186.474354)
		(width 0.14224)
		(layer "In15.Cu")
		(net "GMI_CPU0_G1_CPU1_G3_TX_DN<5>")
	)
	(segment
		(start 312.908442 -182.33263)
		(end 312.908696 -182.33263)
		(width 0.14224)
		(layer "In15.Cu")
		(net "GMI_CPU0_G1_CPU1_G3_TX_DN<5>")
	)
	(segment
		(start 354.267008 -230.227124)
		(end 354.268024 -230.226616)
		(width 0.1143)
		(layer "In15.Cu")
		(net "GMI_CPU0_G1_CPU1_G3_TX_DN<5>")
	)
	(segment
		(start 353.798124 -225.53168)
		(end 353.797108 -225.531172)
		(width 0.1143)
		(layer "In15.Cu")
		(net "GMI_CPU0_G1_CPU1_G3_TX_DN<5>")
	)
	(segment
		(start 153.192226 -186.026044)
		(end 153.174192 -186.208416)
		(width 0.14224)
		(layer "In15.Cu")
		(net "GMI_CPU0_G1_CPU1_G3_TX_DN<5>")
	)
	(segment
		(start 117.227604 -226.9871)
		(end 117.26672 -227.00996)
		(width 0.1143)
		(layer "In15.Cu")
		(net "GMI_CPU0_G1_CPU1_G3_TX_DN<5>")
	)
	(segment
		(start 117.197124 -225.349308)
		(end 117.227604 -225.367088)
		(width 0.1143)
		(layer "In15.Cu")
		(net "GMI_CPU0_G1_CPU1_G3_TX_DN<5>")
	)
	(segment
		(start 117.26672 -236.038898)
		(end 117.227604 -236.061758)
		(width 0.1143)
		(layer "In15.Cu")
		(net "GMI_CPU0_G1_CPU1_G3_TX_DN<5>")
	)
	(segment
		(start 353.327208 -223.101154)
		(end 353.32543 -223.100138)
		(width 0.1143)
		(layer "In15.Cu")
		(net "GMI_CPU0_G1_CPU1_G3_TX_DN<5>")
	)
	(segment
		(start 354.299774 -244.179852)
		(end 354.268786 -244.162072)
		(width 0.1143)
		(layer "In15.Cu")
		(net "GMI_CPU0_G1_CPU1_G3_TX_DN<5>")
	)
	(arc
		(start 354.215446 -244.129052)
		(mid 353.992562 -243.674138)
		(end 354.215446 -243.219224)
		(width 0.1143)
		(layer "In15.Cu")
		(net "GMI_CPU0_G1_CPU1_G3_TX_DN<5>")
	)
	(arc
		(start 117.26672 -239.969802)
		(mid 117.510047 -240.434368)
		(end 117.26672 -240.898934)
		(width 0.1143)
		(layer "In15.Cu")
		(net "GMI_CPU0_G1_CPU1_G3_TX_DN<5>")
	)
	(arc
		(start 117.26672 -243.209826)
		(mid 117.510047 -243.674392)
		(end 117.26672 -244.138958)
		(width 0.1143)
		(layer "In15.Cu")
		(net "GMI_CPU0_G1_CPU1_G3_TX_DN<5>")
	)
	(arc
		(start 117.197124 -234.459526)
		(mid 117.040147 -234.764326)
		(end 117.197124 -235.069126)
		(width 0.1143)
		(layer "In15.Cu")
		(net "GMI_CPU0_G1_CPU1_G3_TX_DN<5>")
	)
	(arc
		(start 353.359974 -223.728534)
		(mid 353.515902 -223.424242)
		(end 353.359974 -223.11995)
		(width 0.1143)
		(layer "In15.Cu")
		(net "GMI_CPU0_G1_CPU1_G3_TX_DN<5>")
	)
	(arc
		(start 354.299774 -230.208328)
		(mid 354.41445 -230.074994)
		(end 354.45573 -229.904036)
		(width 0.1143)
		(layer "In15.Cu")
		(net "GMI_CPU0_G1_CPU1_G3_TX_DN<5>")
	)
	(arc
		(start 117.26672 -238.34979)
		(mid 117.510047 -238.814356)
		(end 117.26672 -239.278922)
		(width 0.1143)
		(layer "In15.Cu")
		(net "GMI_CPU0_G1_CPU1_G3_TX_DN<5>")
	)
	(arc
		(start 117.26672 -236.729778)
		(mid 117.510047 -237.194344)
		(end 117.26672 -237.65891)
		(width 0.1143)
		(layer "In15.Cu")
		(net "GMI_CPU0_G1_CPU1_G3_TX_DN<5>")
	)
	(arc
		(start 354.26777 -236.061504)
		(mid 353.987343 -235.574268)
		(end 354.26777 -235.086906)
		(width 0.1143)
		(layer "In15.Cu")
		(net "GMI_CPU0_G1_CPU1_G3_TX_DN<5>")
	)
	(arc
		(start 354.299774 -233.448352)
		(mid 354.455702 -233.14406)
		(end 354.299774 -232.839768)
		(width 0.1143)
		(layer "In15.Cu")
		(net "GMI_CPU0_G1_CPU1_G3_TX_DN<5>")
	)
	(arc
		(start 353.36099 -222.10776)
		(mid 353.474919 -221.974613)
		(end 353.51593 -221.80423)
		(width 0.1143)
		(layer "In15.Cu")
		(net "GMI_CPU0_G1_CPU1_G3_TX_DN<5>")
	)
	(arc
		(start 117.039644 -221.804484)
		(mid 117.080899 -221.975455)
		(end 117.1956 -222.108776)
		(width 0.1143)
		(layer "In15.Cu")
		(net "GMI_CPU0_G1_CPU1_G3_TX_DN<5>")
	)
	(arc
		(start 354.257864 -231.195372)
		(mid 354.0558 -230.989975)
		(end 353.98583 -230.710486)
		(width 0.1143)
		(layer "In15.Cu")
		(net "GMI_CPU0_G1_CPU1_G3_TX_DN<5>")
	)
	(arc
		(start 117.197124 -232.839514)
		(mid 117.040147 -233.144314)
		(end 117.197124 -233.449114)
		(width 0.1143)
		(layer "In15.Cu")
		(net "GMI_CPU0_G1_CPU1_G3_TX_DN<5>")
	)
	(arc
		(start 354.45573 -231.524048)
		(mid 354.414968 -231.354164)
		(end 354.301552 -231.22128)
		(width 0.1143)
		(layer "In15.Cu")
		(net "GMI_CPU0_G1_CPU1_G3_TX_DN<5>")
	)
	(arc
		(start 354.448872 -244.414294)
		(mid 354.396823 -244.282775)
		(end 354.299774 -244.179852)
		(width 0.1143)
		(layer "In15.Cu")
		(net "GMI_CPU0_G1_CPU1_G3_TX_DN<5>")
	)
	(arc
		(start 354.231702 -229.560628)
		(mid 354.224936 -229.555851)
		(end 354.21824 -229.550976)
		(width 0.1143)
		(layer "In15.Cu")
		(net "GMI_CPU0_G1_CPU1_G3_TX_DN<5>")
	)
	(arc
		(start 117.26672 -235.109766)
		(mid 117.510047 -235.574332)
		(end 117.26672 -236.038898)
		(width 0.1143)
		(layer "In15.Cu")
		(net "GMI_CPU0_G1_CPU1_G3_TX_DN<5>")
	)
	(arc
		(start 354.26777 -242.541552)
		(mid 353.987343 -242.054316)
		(end 354.26777 -241.566954)
		(width 0.1143)
		(layer "In15.Cu")
		(net "GMI_CPU0_G1_CPU1_G3_TX_DN<5>")
	)
	(arc
		(start 354.231702 -232.800398)
		(mid 354.223524 -232.794755)
		(end 354.215446 -232.788968)
		(width 0.1143)
		(layer "In15.Cu")
		(net "GMI_CPU0_G1_CPU1_G3_TX_DN<5>")
	)
	(arc
		(start 354.231702 -234.42041)
		(mid 354.224552 -234.415512)
		(end 354.217478 -234.410504)
		(width 0.1143)
		(layer "In15.Cu")
		(net "GMI_CPU0_G1_CPU1_G3_TX_DN<5>")
	)
	(arc
		(start 117.510052 -230.71455)
		(mid 117.445537 -230.976769)
		(end 117.26672 -231.179116)
		(width 0.1143)
		(layer "In15.Cu")
		(net "GMI_CPU0_G1_CPU1_G3_TX_DN<5>")
	)
	(arc
		(start 354.217478 -233.497628)
		(mid 354.224551 -233.492619)
		(end 354.231702 -233.487722)
		(width 0.1143)
		(layer "In15.Cu")
		(net "GMI_CPU0_G1_CPU1_G3_TX_DN<5>")
	)
	(arc
		(start 354.299774 -241.548412)
		(mid 354.455702 -241.24412)
		(end 354.299774 -240.939828)
		(width 0.1143)
		(layer "In15.Cu")
		(net "GMI_CPU0_G1_CPU1_G3_TX_DN<5>")
	)
	(arc
		(start 354.215446 -232.788968)
		(mid 353.992562 -232.334054)
		(end 354.215446 -231.87914)
		(width 0.1143)
		(layer "In15.Cu")
		(net "GMI_CPU0_G1_CPU1_G3_TX_DN<5>")
	)
	(arc
		(start 354.231702 -244.140482)
		(mid 354.223524 -244.134839)
		(end 354.215446 -244.129052)
		(width 0.1143)
		(layer "In15.Cu")
		(net "GMI_CPU0_G1_CPU1_G3_TX_DN<5>")
	)
	(arc
		(start 354.217732 -230.257604)
		(mid 354.226062 -230.251813)
		(end 354.234496 -230.246174)
		(width 0.1143)
		(layer "In15.Cu")
		(net "GMI_CPU0_G1_CPU1_G3_TX_DN<5>")
	)
	(arc
		(start 353.834446 -225.55454)
		(mid 353.829902 -225.550949)
		(end 353.825302 -225.547428)
		(width 0.1143)
		(layer "In15.Cu")
		(net "GMI_CPU0_G1_CPU1_G3_TX_DN<5>")
	)
	(arc
		(start 117.197124 -237.69955)
		(mid 117.040147 -238.00435)
		(end 117.197124 -238.30915)
		(width 0.1143)
		(layer "In15.Cu")
		(net "GMI_CPU0_G1_CPU1_G3_TX_DN<5>")
	)
	(arc
		(start 117.26418 -230.248206)
		(mid 117.444832 -230.450951)
		(end 117.510052 -230.71455)
		(width 0.1143)
		(layer "In15.Cu")
		(net "GMI_CPU0_G1_CPU1_G3_TX_DN<5>")
	)
	(arc
		(start 117.040152 -229.90429)
		(mid 117.081701 -230.075712)
		(end 117.197124 -230.20909)
		(width 0.1143)
		(layer "In15.Cu")
		(net "GMI_CPU0_G1_CPU1_G3_TX_DN<5>")
	)
	(arc
		(start 117.197124 -236.079538)
		(mid 117.040147 -236.384338)
		(end 117.197124 -236.689138)
		(width 0.1143)
		(layer "In15.Cu")
		(net "GMI_CPU0_G1_CPU1_G3_TX_DN<5>")
	)
	(arc
		(start 354.26777 -237.681516)
		(mid 353.987343 -237.19428)
		(end 354.26777 -236.706918)
		(width 0.1143)
		(layer "In15.Cu")
		(net "GMI_CPU0_G1_CPU1_G3_TX_DN<5>")
	)
	(arc
		(start 117.197124 -226.35972)
		(mid 117.040147 -226.66452)
		(end 117.197124 -226.96932)
		(width 0.1143)
		(layer "In15.Cu")
		(net "GMI_CPU0_G1_CPU1_G3_TX_DN<5>")
	)
	(arc
		(start 117.26672 -241.589814)
		(mid 117.510047 -242.05438)
		(end 117.26672 -242.518946)
		(width 0.1143)
		(layer "In15.Cu")
		(net "GMI_CPU0_G1_CPU1_G3_TX_DN<5>")
	)
	(arc
		(start 117.197124 -239.319562)
		(mid 117.040147 -239.624362)
		(end 117.197124 -239.929162)
		(width 0.1143)
		(layer "In15.Cu")
		(net "GMI_CPU0_G1_CPU1_G3_TX_DN<5>")
	)
	(arc
		(start 354.231702 -227.940616)
		(mid 354.223524 -227.934973)
		(end 354.215446 -227.929186)
		(width 0.1143)
		(layer "In15.Cu")
		(net "GMI_CPU0_G1_CPU1_G3_TX_DN<5>")
	)
	(arc
		(start 354.299774 -238.308388)
		(mid 354.455702 -238.004096)
		(end 354.299774 -237.699804)
		(width 0.1143)
		(layer "In15.Cu")
		(net "GMI_CPU0_G1_CPU1_G3_TX_DN<5>")
	)
	(arc
		(start 117.197124 -244.179598)
		(mid 117.099359 -244.282574)
		(end 117.04701 -244.414548)
		(width 0.1143)
		(layer "In15.Cu")
		(net "GMI_CPU0_G1_CPU1_G3_TX_DN<5>")
	)
	(arc
		(start 354.215446 -243.219224)
		(mid 354.223524 -243.213438)
		(end 354.231702 -243.207794)
		(width 0.1143)
		(layer "In15.Cu")
		(net "GMI_CPU0_G1_CPU1_G3_TX_DN<5>")
	)
	(arc
		(start 117.26672 -227.00996)
		(mid 117.510047 -227.474526)
		(end 117.26672 -227.939092)
		(width 0.1143)
		(layer "In15.Cu")
		(net "GMI_CPU0_G1_CPU1_G3_TX_DN<5>")
	)
	(arc
		(start 117.197124 -224.739708)
		(mid 117.040147 -225.044508)
		(end 117.197124 -225.349308)
		(width 0.1143)
		(layer "In15.Cu")
		(net "GMI_CPU0_G1_CPU1_G3_TX_DN<5>")
	)
	(arc
		(start 117.510052 -222.61449)
		(mid 117.445537 -222.876709)
		(end 117.26672 -223.079056)
		(width 0.1143)
		(layer "In15.Cu")
		(net "GMI_CPU0_G1_CPU1_G3_TX_DN<5>")
	)
	(arc
		(start 117.26672 -223.769936)
		(mid 117.510047 -224.234502)
		(end 117.26672 -224.699068)
		(width 0.1143)
		(layer "In15.Cu")
		(net "GMI_CPU0_G1_CPU1_G3_TX_DN<5>")
	)
	(arc
		(start 354.21824 -229.550976)
		(mid 354.04727 -229.350499)
		(end 353.98583 -229.094284)
		(width 0.1143)
		(layer "In15.Cu")
		(net "GMI_CPU0_G1_CPU1_G3_TX_DN<5>")
	)
	(arc
		(start 354.231702 -226.320604)
		(mid 354.054802 -226.125041)
		(end 353.98583 -225.870516)
		(width 0.1143)
		(layer "In15.Cu")
		(net "GMI_CPU0_G1_CPU1_G3_TX_DN<5>")
	)
	(arc
		(start 117.197124 -227.979732)
		(mid 117.040147 -228.284532)
		(end 117.197124 -228.589332)
		(width 0.1143)
		(layer "In15.Cu")
		(net "GMI_CPU0_G1_CPU1_G3_TX_DN<5>")
	)
	(arc
		(start 353.981258 -225.826828)
		(mid 353.928374 -225.679618)
		(end 353.834446 -225.55454)
		(width 0.1143)
		(layer "In15.Cu")
		(net "GMI_CPU0_G1_CPU1_G3_TX_DN<5>")
	)
	(arc
		(start 354.299774 -239.9284)
		(mid 354.455702 -239.624108)
		(end 354.299774 -239.319816)
		(width 0.1143)
		(layer "In15.Cu")
		(net "GMI_CPU0_G1_CPU1_G3_TX_DN<5>")
	)
	(arc
		(start 117.195092 -229.60076)
		(mid 117.081163 -229.733907)
		(end 117.040152 -229.90429)
		(width 0.1143)
		(layer "In15.Cu")
		(net "GMI_CPU0_G1_CPU1_G3_TX_DN<5>")
	)
	(arc
		(start 354.299774 -236.688376)
		(mid 354.455702 -236.384084)
		(end 354.299774 -236.079792)
		(width 0.1143)
		(layer "In15.Cu")
		(net "GMI_CPU0_G1_CPU1_G3_TX_DN<5>")
	)
	(arc
		(start 117.26672 -233.489754)
		(mid 117.510047 -233.95432)
		(end 117.26672 -234.418886)
		(width 0.1143)
		(layer "In15.Cu")
		(net "GMI_CPU0_G1_CPU1_G3_TX_DN<5>")
	)
	(arc
		(start 354.299774 -231.82834)
		(mid 354.41445 -231.695006)
		(end 354.45573 -231.524048)
		(width 0.1143)
		(layer "In15.Cu")
		(net "GMI_CPU0_G1_CPU1_G3_TX_DN<5>")
	)
	(arc
		(start 354.299774 -243.168424)
		(mid 354.455702 -242.864132)
		(end 354.299774 -242.55984)
		(width 0.1143)
		(layer "In15.Cu")
		(net "GMI_CPU0_G1_CPU1_G3_TX_DN<5>")
	)
	(arc
		(start 354.26777 -239.301528)
		(mid 353.987343 -238.814292)
		(end 354.26777 -238.32693)
		(width 0.1143)
		(layer "In15.Cu")
		(net "GMI_CPU0_G1_CPU1_G3_TX_DN<5>")
	)
	(arc
		(start 353.98583 -230.710486)
		(mid 354.049587 -230.457323)
		(end 354.217732 -230.257604)
		(width 0.1143)
		(layer "In15.Cu")
		(net "GMI_CPU0_G1_CPU1_G3_TX_DN<5>")
	)
	(arc
		(start 353.759008 -225.50882)
		(mid 353.580195 -225.30647)
		(end 353.515676 -225.044254)
		(width 0.1143)
		(layer "In15.Cu")
		(net "GMI_CPU0_G1_CPU1_G3_TX_DN<5>")
	)
	(arc
		(start 354.217478 -234.410504)
		(mid 353.990095 -233.954066)
		(end 354.217478 -233.497628)
		(width 0.1143)
		(layer "In15.Cu")
		(net "GMI_CPU0_G1_CPU1_G3_TX_DN<5>")
	)
	(arc
		(start 353.98583 -229.094284)
		(mid 354.061411 -228.812642)
		(end 354.268024 -228.606858)
		(width 0.1143)
		(layer "In15.Cu")
		(net "GMI_CPU0_G1_CPU1_G3_TX_DN<5>")
	)
	(arc
		(start 117.040152 -231.524302)
		(mid 117.081701 -231.695724)
		(end 117.197124 -231.829102)
		(width 0.1143)
		(layer "In15.Cu")
		(net "GMI_CPU0_G1_CPU1_G3_TX_DN<5>")
	)
	(arc
		(start 353.289108 -223.078802)
		(mid 353.045781 -222.614236)
		(end 353.289108 -222.14967)
		(width 0.1143)
		(layer "In15.Cu")
		(net "GMI_CPU0_G1_CPU1_G3_TX_DN<5>")
	)
	(arc
		(start 354.45573 -229.904036)
		(mid 354.414968 -229.734152)
		(end 354.301552 -229.601268)
		(width 0.1143)
		(layer "In15.Cu")
		(net "GMI_CPU0_G1_CPU1_G3_TX_DN<5>")
	)
	(arc
		(start 117.197124 -240.939574)
		(mid 117.040147 -241.244374)
		(end 117.197124 -241.549174)
		(width 0.1143)
		(layer "In15.Cu")
		(net "GMI_CPU0_G1_CPU1_G3_TX_DN<5>")
	)
	(arc
		(start 354.215446 -227.019358)
		(mid 354.223524 -227.013572)
		(end 354.231702 -227.007928)
		(width 0.1143)
		(layer "In15.Cu")
		(net "GMI_CPU0_G1_CPU1_G3_TX_DN<5>")
	)
	(arc
		(start 354.299774 -235.068364)
		(mid 354.455702 -234.764072)
		(end 354.299774 -234.45978)
		(width 0.1143)
		(layer "In15.Cu")
		(net "GMI_CPU0_G1_CPU1_G3_TX_DN<5>")
	)
	(arc
		(start 353.98583 -225.870262)
		(mid 353.984455 -225.848449)
		(end 353.981258 -225.826828)
		(width 0.1143)
		(layer "In15.Cu")
		(net "GMI_CPU0_G1_CPU1_G3_TX_DN<5>")
	)
	(arc
		(start 117.267736 -222.150686)
		(mid 117.445801 -222.352863)
		(end 117.510052 -222.61449)
		(width 0.1143)
		(layer "In15.Cu")
		(net "GMI_CPU0_G1_CPU1_G3_TX_DN<5>")
	)
	(arc
		(start 117.195092 -231.220772)
		(mid 117.081163 -231.353919)
		(end 117.040152 -231.524302)
		(width 0.1143)
		(layer "In15.Cu")
		(net "GMI_CPU0_G1_CPU1_G3_TX_DN<5>")
	)
	(arc
		(start 117.197124 -242.559586)
		(mid 117.040147 -242.864386)
		(end 117.197124 -243.169186)
		(width 0.1143)
		(layer "In15.Cu")
		(net "GMI_CPU0_G1_CPU1_G3_TX_DN<5>")
	)
	(arc
		(start 354.215446 -231.87914)
		(mid 354.223524 -231.873354)
		(end 354.231702 -231.86771)
		(width 0.1143)
		(layer "In15.Cu")
		(net "GMI_CPU0_G1_CPU1_G3_TX_DN<5>")
	)
	(arc
		(start 353.515676 -225.044254)
		(mid 353.474127 -224.872832)
		(end 353.358704 -224.739454)
		(width 0.1143)
		(layer "In15.Cu")
		(net "GMI_CPU0_G1_CPU1_G3_TX_DN<5>")
	)
	(arc
		(start 354.215446 -227.929186)
		(mid 353.992562 -227.474272)
		(end 354.215446 -227.019358)
		(width 0.1143)
		(layer "In15.Cu")
		(net "GMI_CPU0_G1_CPU1_G3_TX_DN<5>")
	)
	(arc
		(start 353.289108 -224.698814)
		(mid 353.045781 -224.234248)
		(end 353.289108 -223.769682)
		(width 0.1143)
		(layer "In15.Cu")
		(net "GMI_CPU0_G1_CPU1_G3_TX_DN<5>")
	)
	(arc
		(start 354.299774 -228.58857)
		(mid 354.455702 -228.284278)
		(end 354.299774 -227.979986)
		(width 0.1143)
		(layer "In15.Cu")
		(net "GMI_CPU0_G1_CPU1_G3_TX_DN<5>")
	)
	(arc
		(start 117.26672 -225.389948)
		(mid 117.510047 -225.854514)
		(end 117.26672 -226.31908)
		(width 0.1143)
		(layer "In15.Cu")
		(net "GMI_CPU0_G1_CPU1_G3_TX_DN<5>")
	)
	(arc
		(start 117.197124 -223.119696)
		(mid 117.040147 -223.424496)
		(end 117.197124 -223.729296)
		(width 0.1143)
		(layer "In15.Cu")
		(net "GMI_CPU0_G1_CPU1_G3_TX_DN<5>")
	)
	(arc
		(start 117.26672 -231.869742)
		(mid 117.510047 -232.334308)
		(end 117.26672 -232.798874)
		(width 0.1143)
		(layer "In15.Cu")
		(net "GMI_CPU0_G1_CPU1_G3_TX_DN<5>")
	)
	(arc
		(start 354.299774 -226.968558)
		(mid 354.455702 -226.664266)
		(end 354.299774 -226.359974)
		(width 0.1143)
		(layer "In15.Cu")
		(net "GMI_CPU0_G1_CPU1_G3_TX_DN<5>")
	)
	(arc
		(start 354.26777 -240.92154)
		(mid 353.987343 -240.434304)
		(end 354.26777 -239.946942)
		(width 0.1143)
		(layer "In15.Cu")
		(net "GMI_CPU0_G1_CPU1_G3_TX_DN<5>")
	)
	(arc
		(start 117.26672 -228.629972)
		(mid 117.510047 -229.094538)
		(end 117.26672 -229.559104)
		(width 0.1143)
		(layer "In15.Cu")
		(net "GMI_CPU0_G1_CPU1_G3_TX_DN<5>")
	)
	(segment
		(start 116.94795 -247.99036)
		(end 117.414802 -247.724422)
		(width 0.12954)
		(layer "F.Cu")
		(net "GMI_CPU0_G1_CPU1_G3_TX_DN<4>")
	)
	(segment
		(start 354.547932 -247.990106)
		(end 354.08108 -247.724168)
		(width 0.12954)
		(layer "F.Cu")
		(net "GMI_CPU0_G1_CPU1_G3_TX_DN<4>")
	)
	(segment
		(start 355.238812 -226.359466)
		(end 355.208332 -226.341686)
		(width 0.1143)
		(layer "In15.Cu")
		(net "GMI_CPU0_G1_CPU1_G3_TX_DN<4>")
	)
	(segment
		(start 116.26723 -239.93602)
		(end 116.279422 -239.942116)
		(width 0.1143)
		(layer "In15.Cu")
		(net "GMI_CPU0_G1_CPU1_G3_TX_DN<4>")
	)
	(segment
		(start 116.321332 -231.182418)
		(end 116.287804 -231.201976)
		(width 0.1143)
		(layer "In15.Cu")
		(net "GMI_CPU0_G1_CPU1_G3_TX_DN<4>")
	)
	(segment
		(start 151.721566 -185.834528)
		(end 151.702516 -186.027568)
		(width 0.14224)
		(layer "In15.Cu")
		(net "GMI_CPU0_G1_CPU1_G3_TX_DN<4>")
	)
	(segment
		(start 116.256054 -238.308642)
		(end 116.281708 -238.323374)
		(width 0.1143)
		(layer "In15.Cu")
		(net "GMI_CPU0_G1_CPU1_G3_TX_DN<4>")
	)
	(segment
		(start 116.285772 -236.705394)
		(end 116.285772 -236.705648)
		(width 0.1143)
		(layer "In15.Cu")
		(net "GMI_CPU0_G1_CPU1_G3_TX_DN<4>")
	)
	(segment
		(start 116.287804 -223.101916)
		(end 116.287042 -223.102424)
		(width 0.1143)
		(layer "In15.Cu")
		(net "GMI_CPU0_G1_CPU1_G3_TX_DN<4>")
	)
	(segment
		(start 116.279168 -226.346766)
		(end 116.256054 -226.360228)
		(width 0.1143)
		(layer "In15.Cu")
		(net "GMI_CPU0_G1_CPU1_G3_TX_DN<4>")
	)
	(segment
		(start 355.205538 -237.679992)
		(end 355.168962 -237.658656)
		(width 0.1143)
		(layer "In15.Cu")
		(net "GMI_CPU0_G1_CPU1_G3_TX_DN<4>")
	)
	(segment
		(start 116.256054 -230.208582)
		(end 116.284502 -230.224838)
		(width 0.1143)
		(layer "In15.Cu")
		(net "GMI_CPU0_G1_CPU1_G3_TX_DN<4>")
	)
	(segment
		(start 116.267992 -236.69625)
		(end 116.278914 -236.701584)
		(width 0.1143)
		(layer "In15.Cu")
		(net "GMI_CPU0_G1_CPU1_G3_TX_DN<4>")
	)
	(segment
		(start 116.256054 -233.448606)
		(end 116.281708 -233.463338)
		(width 0.1143)
		(layer "In15.Cu")
		(net "GMI_CPU0_G1_CPU1_G3_TX_DN<4>")
	)
	(segment
		(start 355.20122 -232.817416)
		(end 355.176582 -232.803192)
		(width 0.1143)
		(layer "In15.Cu")
		(net "GMI_CPU0_G1_CPU1_G3_TX_DN<4>")
	)
	(segment
		(start 355.238812 -227.979478)
		(end 355.208332 -227.961698)
		(width 0.1143)
		(layer "In15.Cu")
		(net "GMI_CPU0_G1_CPU1_G3_TX_DN<4>")
	)
	(segment
		(start 116.287804 -237.68177)
		(end 116.287042 -237.682278)
		(width 0.1143)
		(layer "In15.Cu")
		(net "GMI_CPU0_G1_CPU1_G3_TX_DN<4>")
	)
	(segment
		(start 116.287042 -236.70641)
		(end 116.287804 -236.706918)
		(width 0.1143)
		(layer "In15.Cu")
		(net "GMI_CPU0_G1_CPU1_G3_TX_DN<4>")
	)
	(segment
		(start 165.655244 -178.030886)
		(end 157.824932 -180.830728)
		(width 0.14224)
		(layer "In15.Cu")
		(net "GMI_CPU0_G1_CPU1_G3_TX_DN<4>")
	)
	(segment
		(start 116.285772 -240.923064)
		(end 116.256054 -240.940082)
		(width 0.1143)
		(layer "In15.Cu")
		(net "GMI_CPU0_G1_CPU1_G3_TX_DN<4>")
	)
	(segment
		(start 116.287804 -226.9871)
		(end 116.290344 -226.988878)
		(width 0.1143)
		(layer "In15.Cu")
		(net "GMI_CPU0_G1_CPU1_G3_TX_DN<4>")
	)
	(segment
		(start 116.287042 -231.846374)
		(end 116.287804 -231.846882)
		(width 0.1143)
		(layer "In15.Cu")
		(net "GMI_CPU0_G1_CPU1_G3_TX_DN<4>")
	)
	(segment
		(start 116.283232 -238.32439)
		(end 116.285772 -238.32566)
		(width 0.1143)
		(layer "In15.Cu")
		(net "GMI_CPU0_G1_CPU1_G3_TX_DN<4>")
	)
	(segment
		(start 355.211634 -236.704632)
		(end 355.212396 -236.704124)
		(width 0.1143)
		(layer "In15.Cu")
		(net "GMI_CPU0_G1_CPU1_G3_TX_DN<4>")
	)
	(segment
		(start 355.208332 -227.961698)
		(end 355.169216 -227.938838)
		(width 0.1143)
		(layer "In15.Cu")
		(net "GMI_CPU0_G1_CPU1_G3_TX_DN<4>")
	)
	(segment
		(start 354.769928 -225.549968)
		(end 354.73894 -225.532188)
		(width 0.1143)
		(layer "In15.Cu")
		(net "GMI_CPU0_G1_CPU1_G3_TX_DN<4>")
	)
	(segment
		(start 146.4691 -190.318644)
		(end 146.1389 -190.589408)
		(width 0.14224)
		(layer "In15.Cu")
		(net "GMI_CPU0_G1_CPU1_G3_TX_DN<4>")
	)
	(segment
		(start 355.214174 -243.183156)
		(end 355.21519 -243.182648)
		(width 0.1143)
		(layer "In15.Cu")
		(net "GMI_CPU0_G1_CPU1_G3_TX_DN<4>")
	)
	(segment
		(start 355.208078 -236.706664)
		(end 355.20884 -236.706156)
		(width 0.1143)
		(layer "In15.Cu")
		(net "GMI_CPU0_G1_CPU1_G3_TX_DN<4>")
	)
	(segment
		(start 354.39604 -219.5322)
		(end 350.39173 -211.070952)
		(width 0.14224)
		(layer "In15.Cu")
		(net "GMI_CPU0_G1_CPU1_G3_TX_DN<4>")
	)
	(segment
		(start 355.212396 -233.4641)
		(end 355.213412 -233.463592)
		(width 0.1143)
		(layer "In15.Cu")
		(net "GMI_CPU0_G1_CPU1_G3_TX_DN<4>")
	)
	(segment
		(start 116.281708 -233.463338)
		(end 116.283232 -233.464354)
		(width 0.1143)
		(layer "In15.Cu")
		(net "GMI_CPU0_G1_CPU1_G3_TX_DN<4>")
	)
	(segment
		(start 149.627844 -187.729114)
		(end 149.434804 -187.70981)
		(width 0.14224)
		(layer "In15.Cu")
		(net "GMI_CPU0_G1_CPU1_G3_TX_DN<4>")
	)
	(segment
		(start 116.261388 -239.932464)
		(end 116.266468 -239.935512)
		(width 0.1143)
		(layer "In15.Cu")
		(net "GMI_CPU0_G1_CPU1_G3_TX_DN<4>")
	)
	(segment
		(start 116.28374 -226.344226)
		(end 116.282724 -226.344734)
		(width 0.1143)
		(layer "In15.Cu")
		(net "GMI_CPU0_G1_CPU1_G3_TX_DN<4>")
	)
	(segment
		(start 355.20884 -233.466132)
		(end 355.211634 -233.464608)
		(width 0.1143)
		(layer "In15.Cu")
		(net "GMI_CPU0_G1_CPU1_G3_TX_DN<4>")
	)
	(segment
		(start 116.287042 -239.946434)
		(end 116.287804 -239.946942)
		(width 0.1143)
		(layer "In15.Cu")
		(net "GMI_CPU0_G1_CPU1_G3_TX_DN<4>")
	)
	(segment
		(start 355.20884 -241.566192)
		(end 355.211634 -241.564668)
		(width 0.1143)
		(layer "In15.Cu")
		(net "GMI_CPU0_G1_CPU1_G3_TX_DN<4>")
	)
	(segment
		(start 147.883372 -189.159134)
		(end 147.690332 -189.13983)
		(width 0.14224)
		(layer "In15.Cu")
		(net "GMI_CPU0_G1_CPU1_G3_TX_DN<4>")
	)
	(segment
		(start 354.268786 -222.126302)
		(end 354.27158 -222.124778)
		(width 0.1143)
		(layer "In15.Cu")
		(net "GMI_CPU0_G1_CPU1_G3_TX_DN<4>")
	)
	(segment
		(start 355.20884 -244.162072)
		(end 355.208078 -244.161564)
		(width 0.1143)
		(layer "In15.Cu")
		(net "GMI_CPU0_G1_CPU1_G3_TX_DN<4>")
	)
	(segment
		(start 116.09197 -218.226386)
		(end 116.09197 -220.991938)
		(width 0.14224)
		(layer "In15.Cu")
		(net "GMI_CPU0_G1_CPU1_G3_TX_DN<4>")
	)
	(segment
		(start 355.176582 -240.903252)
		(end 355.17582 -240.902744)
		(width 0.1143)
		(layer "In15.Cu")
		(net "GMI_CPU0_G1_CPU1_G3_TX_DN<4>")
	)
	(segment
		(start 355.207062 -245.781068)
		(end 355.205538 -245.780052)
		(width 0.1143)
		(layer "In15.Cu")
		(net "GMI_CPU0_G1_CPU1_G3_TX_DN<4>")
	)
	(segment
		(start 354.737162 -225.531172)
		(end 354.735638 -225.530156)
		(width 0.1143)
		(layer "In15.Cu")
		(net "GMI_CPU0_G1_CPU1_G3_TX_DN<4>")
	)
	(segment
		(start 116.285772 -246.42572)
		(end 116.287042 -246.426482)
		(width 0.1143)
		(layer "In15.Cu")
		(net "GMI_CPU0_G1_CPU1_G3_TX_DN<4>")
	)
	(segment
		(start 355.176582 -234.423204)
		(end 355.17582 -234.422696)
		(width 0.1143)
		(layer "In15.Cu")
		(net "GMI_CPU0_G1_CPU1_G3_TX_DN<4>")
	)
	(segment
		(start 355.241606 -229.601268)
		(end 355.208078 -229.58171)
		(width 0.1143)
		(layer "In15.Cu")
		(net "GMI_CPU0_G1_CPU1_G3_TX_DN<4>")
	)
	(segment
		(start 355.213412 -233.463592)
		(end 355.214174 -233.463084)
		(width 0.1143)
		(layer "In15.Cu")
		(net "GMI_CPU0_G1_CPU1_G3_TX_DN<4>")
	)
	(segment
		(start 116.26723 -236.695742)
		(end 116.267992 -236.69625)
		(width 0.1143)
		(layer "In15.Cu")
		(net "GMI_CPU0_G1_CPU1_G3_TX_DN<4>")
	)
	(segment
		(start 355.205538 -245.780052)
		(end 355.168962 -245.758716)
		(width 0.1143)
		(layer "In15.Cu")
		(net "GMI_CPU0_G1_CPU1_G3_TX_DN<4>")
	)
	(segment
		(start 116.28628 -242.542568)
		(end 116.285518 -242.543076)
		(width 0.1143)
		(layer "In15.Cu")
		(net "GMI_CPU0_G1_CPU1_G3_TX_DN<4>")
	)
	(segment
		(start 116.099844 -221.252542)
		(end 116.099844 -221.804484)
		(width 0.1143)
		(layer "In15.Cu")
		(net "GMI_CPU0_G1_CPU1_G3_TX_DN<4>")
	)
	(segment
		(start 116.283232 -228.604572)
		(end 116.285772 -228.605842)
		(width 0.1143)
		(layer "In15.Cu")
		(net "GMI_CPU0_G1_CPU1_G3_TX_DN<4>")
	)
	(segment
		(start 355.208078 -230.226616)
		(end 355.239828 -230.208328)
		(width 0.1143)
		(layer "In15.Cu")
		(net "GMI_CPU0_G1_CPU1_G3_TX_DN<4>")
	)
	(segment
		(start 116.348764 -239.263428)
		(end 116.327174 -239.279176)
		(width 0.1143)
		(layer "In15.Cu")
		(net "GMI_CPU0_G1_CPU1_G3_TX_DN<4>")
	)
	(segment
		(start 355.205792 -233.46791)
		(end 355.207062 -233.467148)
		(width 0.1143)
		(layer "In15.Cu")
		(net "GMI_CPU0_G1_CPU1_G3_TX_DN<4>")
	)
	(segment
		(start 355.212396 -241.56416)
		(end 355.213412 -241.563652)
		(width 0.1143)
		(layer "In15.Cu")
		(net "GMI_CPU0_G1_CPU1_G3_TX_DN<4>")
	)
	(segment
		(start 116.287042 -241.566446)
		(end 116.287804 -241.566954)
		(width 0.1143)
		(layer "In15.Cu")
		(net "GMI_CPU0_G1_CPU1_G3_TX_DN<4>")
	)
	(segment
		(start 116.281708 -243.18341)
		(end 116.283232 -243.184426)
		(width 0.1143)
		(layer "In15.Cu")
		(net "GMI_CPU0_G1_CPU1_G3_TX_DN<4>")
	)
	(segment
		(start 116.290598 -244.808756)
		(end 116.326412 -244.82933)
		(width 0.1143)
		(layer "In15.Cu")
		(net "GMI_CPU0_G1_CPU1_G3_TX_DN<4>")
	)
	(segment
		(start 355.17582 -240.902744)
		(end 355.168962 -240.89868)
		(width 0.1143)
		(layer "In15.Cu")
		(net "GMI_CPU0_G1_CPU1_G3_TX_DN<4>")
	)
	(segment
		(start 116.285772 -223.745806)
		(end 116.287042 -223.746568)
		(width 0.1143)
		(layer "In15.Cu")
		(net "GMI_CPU0_G1_CPU1_G3_TX_DN<4>")
	)
	(segment
		(start 147.341336 -189.60338)
		(end 147.011136 -189.874144)
		(width 0.14224)
		(layer "In15.Cu")
		(net "GMI_CPU0_G1_CPU1_G3_TX_DN<4>")
	)
	(segment
		(start 147.690332 -189.13983)
		(end 147.691094 -189.140592)
		(width 0.14224)
		(layer "In15.Cu")
		(net "GMI_CPU0_G1_CPU1_G3_TX_DN<4>")
	)
	(segment
		(start 116.757704 -247.236996)
		(end 116.79682 -247.259856)
		(width 0.1143)
		(layer "In15.Cu")
		(net "GMI_CPU0_G1_CPU1_G3_TX_DN<4>")
	)
	(segment
		(start 150.50008 -187.01385)
		(end 150.30704 -186.994546)
		(width 0.14224)
		(layer "In15.Cu")
		(net "GMI_CPU0_G1_CPU1_G3_TX_DN<4>")
	)
	(segment
		(start 354.267008 -222.127318)
		(end 354.268024 -222.12681)
		(width 0.1143)
		(layer "In15.Cu")
		(net "GMI_CPU0_G1_CPU1_G3_TX_DN<4>")
	)
	(segment
		(start 355.207062 -238.327184)
		(end 355.208078 -238.326676)
		(width 0.1143)
		(layer "In15.Cu")
		(net "GMI_CPU0_G1_CPU1_G3_TX_DN<4>")
	)
	(segment
		(start 355.202744 -244.158516)
		(end 355.20122 -244.1575)
		(width 0.1143)
		(layer "In15.Cu")
		(net "GMI_CPU0_G1_CPU1_G3_TX_DN<4>")
	)
	(segment
		(start 355.202744 -232.818432)
		(end 355.20122 -232.817416)
		(width 0.1143)
		(layer "In15.Cu")
		(net "GMI_CPU0_G1_CPU1_G3_TX_DN<4>")
	)
	(segment
		(start 355.212396 -231.844088)
		(end 355.213412 -231.84358)
		(width 0.1143)
		(layer "In15.Cu")
		(net "GMI_CPU0_G1_CPU1_G3_TX_DN<4>")
	)
	(segment
		(start 116.266468 -239.935512)
		(end 116.26723 -239.93602)
		(width 0.1143)
		(layer "In15.Cu")
		(net "GMI_CPU0_G1_CPU1_G3_TX_DN<4>")
	)
	(segment
		(start 354.298758 -223.119442)
		(end 354.268278 -223.101662)
		(width 0.1143)
		(layer "In15.Cu")
		(net "GMI_CPU0_G1_CPU1_G3_TX_DN<4>")
	)
	(segment
		(start 116.345462 -226.306126)
		(end 116.327174 -226.31908)
		(width 0.1143)
		(layer "In15.Cu")
		(net "GMI_CPU0_G1_CPU1_G3_TX_DN<4>")
	)
	(segment
		(start 151.702516 -186.027568)
		(end 151.372316 -186.298586)
		(width 0.14224)
		(layer "In15.Cu")
		(net "GMI_CPU0_G1_CPU1_G3_TX_DN<4>")
	)
	(segment
		(start 116.287042 -239.30229)
		(end 116.285772 -239.303052)
		(width 0.1143)
		(layer "In15.Cu")
		(net "GMI_CPU0_G1_CPU1_G3_TX_DN<4>")
	)
	(segment
		(start 355.168962 -246.449596)
		(end 355.203506 -246.42953)
		(width 0.1143)
		(layer "In15.Cu")
		(net "GMI_CPU0_G1_CPU1_G3_TX_DN<4>")
	)
	(segment
		(start 355.205284 -232.819956)
		(end 355.20376 -232.81894)
		(width 0.1143)
		(layer "In15.Cu")
		(net "GMI_CPU0_G1_CPU1_G3_TX_DN<4>")
	)
	(segment
		(start 116.287804 -231.201976)
		(end 116.255038 -231.221026)
		(width 0.1143)
		(layer "In15.Cu")
		(net "GMI_CPU0_G1_CPU1_G3_TX_DN<4>")
	)
	(segment
		(start 355.208078 -232.82148)
		(end 355.207062 -232.820972)
		(width 0.1143)
		(layer "In15.Cu")
		(net "GMI_CPU0_G1_CPU1_G3_TX_DN<4>")
	)
	(segment
		(start 355.20884 -238.326168)
		(end 355.21011 -238.325406)
		(width 0.1143)
		(layer "In15.Cu")
		(net "GMI_CPU0_G1_CPU1_G3_TX_DN<4>")
	)
	(segment
		(start 355.169216 -227.009706)
		(end 355.208332 -226.986846)
		(width 0.1143)
		(layer "In15.Cu")
		(net "GMI_CPU0_G1_CPU1_G3_TX_DN<4>")
	)
	(segment
		(start 116.287042 -245.782338)
		(end 116.285772 -245.7831)
		(width 0.1143)
		(layer "In15.Cu")
		(net "GMI_CPU0_G1_CPU1_G3_TX_DN<4>")
	)
	(segment
		(start 354.268278 -223.101662)
		(end 354.229162 -223.078802)
		(width 0.1143)
		(layer "In15.Cu")
		(net "GMI_CPU0_G1_CPU1_G3_TX_DN<4>")
	)
	(segment
		(start 355.207062 -237.681008)
		(end 355.205538 -237.679992)
		(width 0.1143)
		(layer "In15.Cu")
		(net "GMI_CPU0_G1_CPU1_G3_TX_DN<4>")
	)
	(segment
		(start 355.203506 -235.089446)
		(end 355.205792 -235.087922)
		(width 0.1143)
		(layer "In15.Cu")
		(net "GMI_CPU0_G1_CPU1_G3_TX_DN<4>")
	)
	(segment
		(start 116.279422 -236.702346)
		(end 116.285772 -236.705394)
		(width 0.1143)
		(layer "In15.Cu")
		(net "GMI_CPU0_G1_CPU1_G3_TX_DN<4>")
	)
	(segment
		(start 355.211634 -243.18468)
		(end 355.212396 -243.184172)
		(width 0.1143)
		(layer "In15.Cu")
		(net "GMI_CPU0_G1_CPU1_G3_TX_DN<4>")
	)
	(segment
		(start 116.327174 -238.349536)
		(end 116.348764 -238.365284)
		(width 0.1143)
		(layer "In15.Cu")
		(net "GMI_CPU0_G1_CPU1_G3_TX_DN<4>")
	)
	(segment
		(start 116.284502 -226.343718)
		(end 116.28374 -226.344226)
		(width 0.1143)
		(layer "In15.Cu")
		(net "GMI_CPU0_G1_CPU1_G3_TX_DN<4>")
	)
	(segment
		(start 355.239828 -234.45978)
		(end 355.212396 -234.444032)
		(width 0.1143)
		(layer "In15.Cu")
		(net "GMI_CPU0_G1_CPU1_G3_TX_DN<4>")
	)
	(segment
		(start 116.285772 -243.185696)
		(end 116.287042 -243.186458)
		(width 0.1143)
		(layer "In15.Cu")
		(net "GMI_CPU0_G1_CPU1_G3_TX_DN<4>")
	)
	(segment
		(start 117.034056 -247.641618)
		(end 117.11686 -247.724422)
		(width 0.1143)
		(layer "In15.Cu")
		(net "GMI_CPU0_G1_CPU1_G3_TX_DN<4>")
	)
	(segment
		(start 355.203506 -241.569494)
		(end 355.205792 -241.56797)
		(width 0.1143)
		(layer "In15.Cu")
		(net "GMI_CPU0_G1_CPU1_G3_TX_DN<4>")
	)
	(segment
		(start 355.211634 -234.443524)
		(end 355.20884 -234.442)
		(width 0.1143)
		(layer "In15.Cu")
		(net "GMI_CPU0_G1_CPU1_G3_TX_DN<4>")
	)
	(segment
		(start 116.266468 -236.695488)
		(end 116.26723 -236.695996)
		(width 0.1143)
		(layer "In15.Cu")
		(net "GMI_CPU0_G1_CPU1_G3_TX_DN<4>")
	)
	(segment
		(start 116.345462 -242.505992)
		(end 116.327174 -242.518946)
		(width 0.1143)
		(layer "In15.Cu")
		(net "GMI_CPU0_G1_CPU1_G3_TX_DN<4>")
	)
	(segment
		(start 116.287042 -226.986592)
		(end 116.287804 -226.9871)
		(width 0.1143)
		(layer "In15.Cu")
		(net "GMI_CPU0_G1_CPU1_G3_TX_DN<4>")
	)
	(segment
		(start 355.205284 -236.05998)
		(end 355.20376 -236.058964)
		(width 0.1143)
		(layer "In15.Cu")
		(net "GMI_CPU0_G1_CPU1_G3_TX_DN<4>")
	)
	(segment
		(start 355.212396 -236.064044)
		(end 355.211634 -236.063536)
		(width 0.1143)
		(layer "In15.Cu")
		(net "GMI_CPU0_G1_CPU1_G3_TX_DN<4>")
	)
	(segment
		(start 116.287804 -236.061758)
		(end 116.256054 -236.080046)
		(width 0.1143)
		(layer "In15.Cu")
		(net "GMI_CPU0_G1_CPU1_G3_TX_DN<4>")
	)
	(segment
		(start 355.168962 -244.829584)
		(end 355.203506 -244.809518)
		(width 0.1143)
		(layer "In15.Cu")
		(net "GMI_CPU0_G1_CPU1_G3_TX_DN<4>")
	)
	(segment
		(start 147.011136 -189.874144)
		(end 146.818096 -189.855094)
		(width 0.14224)
		(layer "In15.Cu")
		(net "GMI_CPU0_G1_CPU1_G3_TX_DN<4>")
	)
	(segment
		(start 355.21519 -239.942624)
		(end 355.239828 -239.9284)
		(width 0.1143)
		(layer "In15.Cu")
		(net "GMI_CPU0_G1_CPU1_G3_TX_DN<4>")
	)
	(segment
		(start 354.455984 -221.803976)
		(end 354.455984 -221.401894)
		(width 0.1143)
		(layer "In15.Cu")
		(net "GMI_CPU0_G1_CPU1_G3_TX_DN<4>")
	)
	(segment
		(start 151.722074 -185.83529)
		(end 151.721566 -185.834528)
		(width 0.14224)
		(layer "In15.Cu")
		(net "GMI_CPU0_G1_CPU1_G3_TX_DN<4>")
	)
	(segment
		(start 116.28374 -242.544092)
		(end 116.282724 -242.5446)
		(width 0.1143)
		(layer "In15.Cu")
		(net "GMI_CPU0_G1_CPU1_G3_TX_DN<4>")
	)
	(segment
		(start 147.360386 -189.41034)
		(end 147.341336 -189.60338)
		(width 0.14224)
		(layer "In15.Cu")
		(net "GMI_CPU0_G1_CPU1_G3_TX_DN<4>")
	)
	(segment
		(start 355.208078 -246.426736)
		(end 355.20884 -246.426228)
		(width 0.1143)
		(layer "In15.Cu")
		(net "GMI_CPU0_G1_CPU1_G3_TX_DN<4>")
	)
	(segment
		(start 116.28628 -226.342702)
		(end 116.285518 -226.34321)
		(width 0.1143)
		(layer "In15.Cu")
		(net "GMI_CPU0_G1_CPU1_G3_TX_DN<4>")
	)
	(segment
		(start 116.287042 -244.80647)
		(end 116.287804 -244.806978)
		(width 0.1143)
		(layer "In15.Cu")
		(net "GMI_CPU0_G1_CPU1_G3_TX_DN<4>")
	)
	(segment
		(start 354.274374 -222.123254)
		(end 354.299774 -222.108522)
		(width 0.1143)
		(layer "In15.Cu")
		(net "GMI_CPU0_G1_CPU1_G3_TX_DN<4>")
	)
	(segment
		(start 116.287804 -239.301782)
		(end 116.287042 -239.30229)
		(width 0.1143)
		(layer "In15.Cu")
		(net "GMI_CPU0_G1_CPU1_G3_TX_DN<4>")
	)
	(segment
		(start 355.20884 -243.186204)
		(end 355.211634 -243.18468)
		(width 0.1143)
		(layer "In15.Cu")
		(net "GMI_CPU0_G1_CPU1_G3_TX_DN<4>")
	)
	(segment
		(start 355.211634 -240.923572)
		(end 355.20884 -240.922048)
		(width 0.1143)
		(layer "In15.Cu")
		(net "GMI_CPU0_G1_CPU1_G3_TX_DN<4>")
	)
	(segment
		(start 355.212396 -243.184172)
		(end 355.213412 -243.183664)
		(width 0.1143)
		(layer "In15.Cu")
		(net "GMI_CPU0_G1_CPU1_G3_TX_DN<4>")
	)
	(segment
		(start 355.203506 -239.949482)
		(end 355.205792 -239.947958)
		(width 0.1143)
		(layer "In15.Cu")
		(net "GMI_CPU0_G1_CPU1_G3_TX_DN<4>")
	)
	(segment
		(start 355.208078 -238.326676)
		(end 355.20884 -238.326168)
		(width 0.1143)
		(layer "In15.Cu")
		(net "GMI_CPU0_G1_CPU1_G3_TX_DN<4>")
	)
	(segment
		(start 116.09197 -221.020386)
		(end 116.04625 -221.066106)
		(width 0.1143)
		(layer "In15.Cu")
		(net "GMI_CPU0_G1_CPU1_G3_TX_DN<4>")
	)
	(segment
		(start 355.20122 -244.1575)
		(end 355.176582 -244.143276)
		(width 0.1143)
		(layer "In15.Cu")
		(net "GMI_CPU0_G1_CPU1_G3_TX_DN<4>")
	)
	(segment
		(start 116.287804 -223.747076)
		(end 116.290598 -223.748854)
		(width 0.1143)
		(layer "In15.Cu")
		(net "GMI_CPU0_G1_CPU1_G3_TX_DN<4>")
	)
	(segment
		(start 148.23313 -188.696092)
		(end 148.232622 -188.69533)
		(width 0.14224)
		(layer "In15.Cu")
		(net "GMI_CPU0_G1_CPU1_G3_TX_DN<4>")
	)
	(segment
		(start 355.20376 -234.438952)
		(end 355.202744 -234.438444)
		(width 0.1143)
		(layer "In15.Cu")
		(net "GMI_CPU0_G1_CPU1_G3_TX_DN<4>")
	)
	(segment
		(start 355.211634 -232.823512)
		(end 355.20884 -232.821988)
		(width 0.1143)
		(layer "In15.Cu")
		(net "GMI_CPU0_G1_CPU1_G3_TX_DN<4>")
	)
	(segment
		(start 116.324126 -231.180894)
		(end 116.321332 -231.182418)
		(width 0.1143)
		(layer "In15.Cu")
		(net "GMI_CPU0_G1_CPU1_G3_TX_DN<4>")
	)
	(segment
		(start 355.212396 -239.304068)
		(end 355.211634 -239.30356)
		(width 0.1143)
		(layer "In15.Cu")
		(net "GMI_CPU0_G1_CPU1_G3_TX_DN<4>")
	)
	(segment
		(start 149.105366 -187.980828)
		(end 149.104858 -187.98032)
		(width 0.14224)
		(layer "In15.Cu")
		(net "GMI_CPU0_G1_CPU1_G3_TX_DN<4>")
	)
	(segment
		(start 116.281708 -246.423434)
		(end 116.283232 -246.42445)
		(width 0.1143)
		(layer "In15.Cu")
		(net "GMI_CPU0_G1_CPU1_G3_TX_DN<4>")
	)
	(segment
		(start 116.282724 -242.5446)
		(end 116.281962 -242.545108)
		(width 0.1143)
		(layer "In15.Cu")
		(net "GMI_CPU0_G1_CPU1_G3_TX_DN<4>")
	)
	(segment
		(start 355.213412 -231.84358)
		(end 355.214174 -231.843072)
		(width 0.1143)
		(layer "In15.Cu")
		(net "GMI_CPU0_G1_CPU1_G3_TX_DN<4>")
	)
	(segment
		(start 354.379022 -247.724168)
		(end 354.461826 -247.641364)
		(width 0.1143)
		(layer "In15.Cu")
		(net "GMI_CPU0_G1_CPU1_G3_TX_DN<4>")
	)
	(segment
		(start 116.281708 -244.803422)
		(end 116.283232 -244.804438)
		(width 0.1143)
		(layer "In15.Cu")
		(net "GMI_CPU0_G1_CPU1_G3_TX_DN<4>")
	)
	(segment
		(start 355.207062 -244.807232)
		(end 355.208078 -244.806724)
		(width 0.1143)
		(layer "In15.Cu")
		(net "GMI_CPU0_G1_CPU1_G3_TX_DN<4>")
	)
	(segment
		(start 355.20376 -240.919)
		(end 355.202744 -240.918492)
		(width 0.1143)
		(layer "In15.Cu")
		(net "GMI_CPU0_G1_CPU1_G3_TX_DN<4>")
	)
	(segment
		(start 148.755608 -188.444124)
		(end 148.562568 -188.42482)
		(width 0.14224)
		(layer "In15.Cu")
		(net "GMI_CPU0_G1_CPU1_G3_TX_DN<4>")
	)
	(segment
		(start 151.179784 -186.280044)
		(end 151.17953 -186.280044)
		(width 0.14224)
		(layer "In15.Cu")
		(net "GMI_CPU0_G1_CPU1_G3_TX_DN<4>")
	)
	(segment
		(start 355.214174 -235.083096)
		(end 355.21519 -235.082588)
		(width 0.1143)
		(layer "In15.Cu")
		(net "GMI_CPU0_G1_CPU1_G3_TX_DN<4>")
	)
	(segment
		(start 355.213412 -241.563652)
		(end 355.214174 -241.563144)
		(width 0.1143)
		(layer "In15.Cu")
		(net "GMI_CPU0_G1_CPU1_G3_TX_DN<4>")
	)
	(segment
		(start 355.212396 -244.164104)
		(end 355.211634 -244.163596)
		(width 0.1143)
		(layer "In15.Cu")
		(net "GMI_CPU0_G1_CPU1_G3_TX_DN<4>")
	)
	(segment
		(start 355.20884 -232.821988)
		(end 355.208078 -232.82148)
		(width 0.1143)
		(layer "In15.Cu")
		(net "GMI_CPU0_G1_CPU1_G3_TX_DN<4>")
	)
	(segment
		(start 355.21519 -244.80266)
		(end 355.239828 -244.788436)
		(width 0.1143)
		(layer "In15.Cu")
		(net "GMI_CPU0_G1_CPU1_G3_TX_DN<4>")
	)
	(segment
		(start 353.98583 -222.614236)
		(end 353.985576 -222.614236)
		(width 0.1143)
		(layer "In15.Cu")
		(net "GMI_CPU0_G1_CPU1_G3_TX_DN<4>")
	)
	(segment
		(start 355.20884 -246.426228)
		(end 355.211634 -246.424704)
		(width 0.1143)
		(layer "In15.Cu")
		(net "GMI_CPU0_G1_CPU1_G3_TX_DN<4>")
	)
	(segment
		(start 354.45573 -221.80423)
		(end 354.455984 -221.803976)
		(width 0.1143)
		(layer "In15.Cu")
		(net "GMI_CPU0_G1_CPU1_G3_TX_DN<4>")
	)
	(segment
		(start 116.287042 -246.426482)
		(end 116.287804 -246.42699)
		(width 0.1143)
		(layer "In15.Cu")
		(net "GMI_CPU0_G1_CPU1_G3_TX_DN<4>")
	)
	(segment
		(start 116.34216 -232.788206)
		(end 116.327682 -232.798874)
		(width 0.1143)
		(layer "In15.Cu")
		(net "GMI_CPU0_G1_CPU1_G3_TX_DN<4>")
	)
	(segment
		(start 355.205284 -234.439968)
		(end 355.20376 -234.438952)
		(width 0.1143)
		(layer "In15.Cu")
		(net "GMI_CPU0_G1_CPU1_G3_TX_DN<4>")
	)
	(segment
		(start 355.208078 -234.441492)
		(end 355.207062 -234.440984)
		(width 0.1143)
		(layer "In15.Cu")
		(net "GMI_CPU0_G1_CPU1_G3_TX_DN<4>")
	)
	(segment
		(start 116.287042 -243.186458)
		(end 116.287804 -243.186966)
		(width 0.1143)
		(layer "In15.Cu")
		(net "GMI_CPU0_G1_CPU1_G3_TX_DN<4>")
	)
	(segment
		(start 116.285772 -236.705648)
		(end 116.287042 -236.70641)
		(width 0.1143)
		(layer "In15.Cu")
		(net "GMI_CPU0_G1_CPU1_G3_TX_DN<4>")
	)
	(segment
		(start 116.285518 -242.543076)
		(end 116.284502 -242.543584)
		(width 0.1143)
		(layer "In15.Cu")
		(net "GMI_CPU0_G1_CPU1_G3_TX_DN<4>")
	)
	(segment
		(start 355.20376 -236.058964)
		(end 355.202744 -236.058456)
		(width 0.1143)
		(layer "In15.Cu")
		(net "GMI_CPU0_G1_CPU1_G3_TX_DN<4>")
	)
	(segment
		(start 355.213412 -239.94364)
		(end 355.214174 -239.943132)
		(width 0.1143)
		(layer "In15.Cu")
		(net "GMI_CPU0_G1_CPU1_G3_TX_DN<4>")
	)
	(segment
		(start 116.287804 -244.161818)
		(end 116.287042 -244.162326)
		(width 0.1143)
		(layer "In15.Cu")
		(net "GMI_CPU0_G1_CPU1_G3_TX_DN<4>")
	)
	(segment
		(start 354.268278 -224.721674)
		(end 354.229162 -224.698814)
		(width 0.1143)
		(layer "In15.Cu")
		(net "GMI_CPU0_G1_CPU1_G3_TX_DN<4>")
	)
	(segment
		(start 116.287042 -230.226362)
		(end 116.287804 -230.22687)
		(width 0.1143)
		(layer "In15.Cu")
		(net "GMI_CPU0_G1_CPU1_G3_TX_DN<4>")
	)
	(segment
		(start 116.256054 -246.408702)
		(end 116.281708 -246.423434)
		(width 0.1143)
		(layer "In15.Cu")
		(net "GMI_CPU0_G1_CPU1_G3_TX_DN<4>")
	)
	(segment
		(start 355.176582 -239.28324)
		(end 355.17582 -239.282732)
		(width 0.1143)
		(layer "In15.Cu")
		(net "GMI_CPU0_G1_CPU1_G3_TX_DN<4>")
	)
	(segment
		(start 355.211634 -239.944656)
		(end 355.212396 -239.944148)
		(width 0.1143)
		(layer "In15.Cu")
		(net "GMI_CPU0_G1_CPU1_G3_TX_DN<4>")
	)
	(segment
		(start 149.435058 -187.710318)
		(end 149.105366 -187.980828)
		(width 0.14224)
		(layer "In15.Cu")
		(net "GMI_CPU0_G1_CPU1_G3_TX_DN<4>")
	)
	(segment
		(start 355.205792 -235.087922)
		(end 355.207062 -235.08716)
		(width 0.1143)
		(layer "In15.Cu")
		(net "GMI_CPU0_G1_CPU1_G3_TX_DN<4>")
	)
	(segment
		(start 355.208078 -228.606858)
		(end 355.238812 -228.589078)
		(width 0.1143)
		(layer "In15.Cu")
		(net "GMI_CPU0_G1_CPU1_G3_TX_DN<4>")
	)
	(segment
		(start 355.176582 -244.143276)
		(end 355.17582 -244.142768)
		(width 0.1143)
		(layer "In15.Cu")
		(net "GMI_CPU0_G1_CPU1_G3_TX_DN<4>")
	)
	(segment
		(start 116.327428 -243.209826)
		(end 116.346478 -243.223796)
		(width 0.1143)
		(layer "In15.Cu")
		(net "GMI_CPU0_G1_CPU1_G3_TX_DN<4>")
	)
	(segment
		(start 355.239828 -245.799864)
		(end 355.208078 -245.781576)
		(width 0.1143)
		(layer "In15.Cu")
		(net "GMI_CPU0_G1_CPU1_G3_TX_DN<4>")
	)
	(segment
		(start 355.202744 -239.29848)
		(end 355.20122 -239.297464)
		(width 0.1143)
		(layer "In15.Cu")
		(net "GMI_CPU0_G1_CPU1_G3_TX_DN<4>")
	)
	(segment
		(start 116.287042 -234.442254)
		(end 116.285772 -234.443016)
		(width 0.1143)
		(layer "In15.Cu")
		(net "GMI_CPU0_G1_CPU1_G3_TX_DN<4>")
	)
	(segment
		(start 355.214174 -244.803168)
		(end 355.21519 -244.80266)
		(width 0.1143)
		(layer "In15.Cu")
		(net "GMI_CPU0_G1_CPU1_G3_TX_DN<4>")
	)
	(segment
		(start 116.287804 -245.78183)
		(end 116.287042 -245.782338)
		(width 0.1143)
		(layer "In15.Cu")
		(net "GMI_CPU0_G1_CPU1_G3_TX_DN<4>")
	)
	(segment
		(start 116.256054 -241.548666)
		(end 116.281708 -241.563398)
		(width 0.1143)
		(layer "In15.Cu")
		(net "GMI_CPU0_G1_CPU1_G3_TX_DN<4>")
	)
	(segment
		(start 116.324126 -229.560882)
		(end 116.287804 -229.581964)
		(width 0.1143)
		(layer "In15.Cu")
		(net "GMI_CPU0_G1_CPU1_G3_TX_DN<4>")
	)
	(segment
		(start 116.285772 -245.7831)
		(end 116.256054 -245.800118)
		(width 0.1143)
		(layer "In15.Cu")
		(net "GMI_CPU0_G1_CPU1_G3_TX_DN<4>")
	)
	(segment
		(start 355.211634 -244.163596)
		(end 355.20884 -244.162072)
		(width 0.1143)
		(layer "In15.Cu")
		(net "GMI_CPU0_G1_CPU1_G3_TX_DN<4>")
	)
	(segment
		(start 116.285772 -234.443016)
		(end 116.256054 -234.460034)
		(width 0.1143)
		(layer "In15.Cu")
		(net "GMI_CPU0_G1_CPU1_G3_TX_DN<4>")
	)
	(segment
		(start 355.20884 -239.94618)
		(end 355.211634 -239.944656)
		(width 0.1143)
		(layer "In15.Cu")
		(net "GMI_CPU0_G1_CPU1_G3_TX_DN<4>")
	)
	(segment
		(start 355.207062 -241.567208)
		(end 355.208078 -241.5667)
		(width 0.1143)
		(layer "In15.Cu")
		(net "GMI_CPU0_G1_CPU1_G3_TX_DN<4>")
	)
	(segment
		(start 116.327174 -239.279176)
		(end 116.287804 -239.301782)
		(width 0.1143)
		(layer "In15.Cu")
		(net "GMI_CPU0_G1_CPU1_G3_TX_DN<4>")
	)
	(segment
		(start 355.205284 -240.920016)
		(end 355.20376 -240.919)
		(width 0.1143)
		(layer "In15.Cu")
		(net "GMI_CPU0_G1_CPU1_G3_TX_DN<4>")
	)
	(segment
		(start 355.211634 -233.464608)
		(end 355.212396 -233.4641)
		(width 0.1143)
		(layer "In15.Cu")
		(net "GMI_CPU0_G1_CPU1_G3_TX_DN<4>")
	)
	(segment
		(start 355.203506 -233.469434)
		(end 355.205792 -233.46791)
		(width 0.1143)
		(layer "In15.Cu")
		(net "GMI_CPU0_G1_CPU1_G3_TX_DN<4>")
	)
	(segment
		(start 116.287804 -225.367088)
		(end 116.290598 -225.368866)
		(width 0.1143)
		(layer "In15.Cu")
		(net "GMI_CPU0_G1_CPU1_G3_TX_DN<4>")
	)
	(segment
		(start 302.907192 -178.831748)
		(end 165.655244 -178.030886)
		(width 0.14224)
		(layer "In15.Cu")
		(net "GMI_CPU0_G1_CPU1_G3_TX_DN<4>")
	)
	(segment
		(start 150.83028 -186.742832)
		(end 150.50008 -187.01385)
		(width 0.14224)
		(layer "In15.Cu")
		(net "GMI_CPU0_G1_CPU1_G3_TX_DN<4>")
	)
	(segment
		(start 355.20884 -234.442)
		(end 355.208078 -234.441492)
		(width 0.1143)
		(layer "In15.Cu")
		(net "GMI_CPU0_G1_CPU1_G3_TX_DN<4>")
	)
	(segment
		(start 157.824932 -180.830728)
		(end 152.593802 -185.119518)
		(width 0.14224)
		(layer "In15.Cu")
		(net "GMI_CPU0_G1_CPU1_G3_TX_DN<4>")
	)
	(segment
		(start 152.051512 -185.564018)
		(end 152.051766 -185.56478)
		(width 0.14224)
		(layer "In15.Cu")
		(net "GMI_CPU0_G1_CPU1_G3_TX_DN<4>")
	)
	(segment
		(start 116.280946 -226.34575)
		(end 116.280184 -226.346258)
		(width 0.1143)
		(layer "In15.Cu")
		(net "GMI_CPU0_G1_CPU1_G3_TX_DN<4>")
	)
	(segment
		(start 116.279422 -239.942116)
		(end 116.280184 -239.942624)
		(width 0.1143)
		(layer "In15.Cu")
		(net "GMI_CPU0_G1_CPU1_G3_TX_DN<4>")
	)
	(segment
		(start 355.20122 -234.437428)
		(end 355.176582 -234.423204)
		(width 0.1143)
		(layer "In15.Cu")
		(net "GMI_CPU0_G1_CPU1_G3_TX_DN<4>")
	)
	(segment
		(start 116.281962 -242.545108)
		(end 116.256054 -242.560094)
		(width 0.1143)
		(layer "In15.Cu")
		(net "GMI_CPU0_G1_CPU1_G3_TX_DN<4>")
	)
	(segment
		(start 355.208078 -240.92154)
		(end 355.207062 -240.921032)
		(width 0.1143)
		(layer "In15.Cu")
		(net "GMI_CPU0_G1_CPU1_G3_TX_DN<4>")
	)
	(segment
		(start 145.946876 -190.570358)
		(end 119.768874 -212.033866)
		(width 0.14224)
		(layer "In15.Cu")
		(net "GMI_CPU0_G1_CPU1_G3_TX_DN<4>")
	)
	(segment
		(start 116.256054 -239.32007)
		(end 116.256054 -239.320324)
		(width 0.1143)
		(layer "In15.Cu")
		(net "GMI_CPU0_G1_CPU1_G3_TX_DN<4>")
	)
	(segment
		(start 354.268024 -222.12681)
		(end 354.268786 -222.126302)
		(width 0.1143)
		(layer "In15.Cu")
		(net "GMI_CPU0_G1_CPU1_G3_TX_DN<4>")
	)
	(segment
		(start 116.281708 -238.323374)
		(end 116.283232 -238.32439)
		(width 0.1143)
		(layer "In15.Cu")
		(net "GMI_CPU0_G1_CPU1_G3_TX_DN<4>")
	)
	(segment
		(start 310.034432 -179.628546)
		(end 307.805836 -178.831748)
		(width 0.14224)
		(layer "In15.Cu")
		(net "GMI_CPU0_G1_CPU1_G3_TX_DN<4>")
	)
	(segment
		(start 355.212396 -240.92408)
		(end 355.211634 -240.923572)
		(width 0.1143)
		(layer "In15.Cu")
		(net "GMI_CPU0_G1_CPU1_G3_TX_DN<4>")
	)
	(segment
		(start 355.205792 -244.807994)
		(end 355.207062 -244.807232)
		(width 0.1143)
		(layer "In15.Cu")
		(net "GMI_CPU0_G1_CPU1_G3_TX_DN<4>")
	)
	(segment
		(start 355.239828 -237.699804)
		(end 355.208078 -237.681516)
		(width 0.1143)
		(layer "In15.Cu")
		(net "GMI_CPU0_G1_CPU1_G3_TX_DN<4>")
	)
	(segment
		(start 355.207062 -235.08716)
		(end 355.208078 -235.086652)
		(width 0.1143)
		(layer "In15.Cu")
		(net "GMI_CPU0_G1_CPU1_G3_TX_DN<4>")
	)
	(segment
		(start 116.287804 -241.566954)
		(end 116.290598 -241.568732)
		(width 0.1143)
		(layer "In15.Cu")
		(net "GMI_CPU0_G1_CPU1_G3_TX_DN<4>")
	)
	(segment
		(start 307.805836 -178.831748)
		(end 302.907192 -178.831748)
		(width 0.14224)
		(layer "In15.Cu")
		(net "GMI_CPU0_G1_CPU1_G3_TX_DN<4>")
	)
	(segment
		(start 149.977094 -187.265056)
		(end 149.958044 -187.458096)
		(width 0.14224)
		(layer "In15.Cu")
		(net "GMI_CPU0_G1_CPU1_G3_TX_DN<4>")
	)
	(segment
		(start 355.211634 -231.844596)
		(end 355.212396 -231.844088)
		(width 0.1143)
		(layer "In15.Cu")
		(net "GMI_CPU0_G1_CPU1_G3_TX_DN<4>")
	)
	(segment
		(start 355.205284 -239.300004)
		(end 355.20376 -239.298988)
		(width 0.1143)
		(layer "In15.Cu")
		(net "GMI_CPU0_G1_CPU1_G3_TX_DN<4>")
	)
	(segment
		(start 355.21519 -236.7026)
		(end 355.239828 -236.688376)
		(width 0.1143)
		(layer "In15.Cu")
		(net "GMI_CPU0_G1_CPU1_G3_TX_DN<4>")
	)
	(segment
		(start 355.208078 -241.5667)
		(end 355.20884 -241.566192)
		(width 0.1143)
		(layer "In15.Cu")
		(net "GMI_CPU0_G1_CPU1_G3_TX_DN<4>")
	)
	(segment
		(start 116.327174 -241.589814)
		(end 116.345462 -241.603022)
		(width 0.1143)
		(layer "In15.Cu")
		(net "GMI_CPU0_G1_CPU1_G3_TX_DN<4>")
	)
	(segment
		(start 116.287042 -238.326422)
		(end 116.287804 -238.32693)
		(width 0.1143)
		(layer "In15.Cu")
		(net "GMI_CPU0_G1_CPU1_G3_TX_DN<4>")
	)
	(segment
		(start 116.256054 -228.588824)
		(end 116.281708 -228.603556)
		(width 0.1143)
		(layer "In15.Cu")
		(net "GMI_CPU0_G1_CPU1_G3_TX_DN<4>")
	)
	(segment
		(start 116.283232 -241.564414)
		(end 116.285772 -241.565684)
		(width 0.1143)
		(layer "In15.Cu")
		(net "GMI_CPU0_G1_CPU1_G3_TX_DN<4>")
	)
	(segment
		(start 354.39604 -221.083124)
		(end 354.39604 -219.5322)
		(width 0.14224)
		(layer "In15.Cu")
		(net "GMI_CPU0_G1_CPU1_G3_TX_DN<4>")
	)
	(segment
		(start 116.287804 -244.806978)
		(end 116.290598 -244.808756)
		(width 0.1143)
		(layer "In15.Cu")
		(net "GMI_CPU0_G1_CPU1_G3_TX_DN<4>")
	)
	(segment
		(start 354.738178 -247.236742)
		(end 354.768658 -247.218962)
		(width 0.1143)
		(layer "In15.Cu")
		(net "GMI_CPU0_G1_CPU1_G3_TX_DN<4>")
	)
	(segment
		(start 116.283232 -226.98456)
		(end 116.285772 -226.98583)
		(width 0.1143)
		(layer "In15.Cu")
		(net "GMI_CPU0_G1_CPU1_G3_TX_DN<4>")
	)
	(segment
		(start 355.208078 -235.086652)
		(end 355.20884 -235.086144)
		(width 0.1143)
		(layer "In15.Cu")
		(net "GMI_CPU0_G1_CPU1_G3_TX_DN<4>")
	)
	(segment
		(start 354.268278 -223.746822)
		(end 354.298758 -223.729042)
		(width 0.1143)
		(layer "In15.Cu")
		(net "GMI_CPU0_G1_CPU1_G3_TX_DN<4>")
	)
	(segment
		(start 146.48815 -190.125604)
		(end 146.4691 -190.318644)
		(width 0.14224)
		(layer "In15.Cu")
		(net "GMI_CPU0_G1_CPU1_G3_TX_DN<4>")
	)
	(segment
		(start 116.26723 -236.695996)
		(end 116.26723 -236.695742)
		(width 0.1143)
		(layer "In15.Cu")
		(net "GMI_CPU0_G1_CPU1_G3_TX_DN<4>")
	)
	(segment
		(start 116.284502 -230.224838)
		(end 116.287042 -230.226362)
		(width 0.1143)
		(layer "In15.Cu")
		(net "GMI_CPU0_G1_CPU1_G3_TX_DN<4>")
	)
	(segment
		(start 148.562568 -188.42482)
		(end 148.563076 -188.425582)
		(width 0.14224)
		(layer "In15.Cu")
		(net "GMI_CPU0_G1_CPU1_G3_TX_DN<4>")
	)
	(segment
		(start 151.179276 -186.279282)
		(end 151.179784 -186.280044)
		(width 0.14224)
		(layer "In15.Cu")
		(net "GMI_CPU0_G1_CPU1_G3_TX_DN<4>")
	)
	(segment
		(start 149.977602 -187.265818)
		(end 149.977094 -187.265056)
		(width 0.14224)
		(layer "In15.Cu")
		(net "GMI_CPU0_G1_CPU1_G3_TX_DN<4>")
	)
	(segment
		(start 116.287804 -229.581964)
		(end 116.254276 -229.601522)
		(width 0.1143)
		(layer "In15.Cu")
		(net "GMI_CPU0_G1_CPU1_G3_TX_DN<4>")
	)
	(segment
		(start 116.285772 -238.32566)
		(end 116.287042 -238.326422)
		(width 0.1143)
		(layer "In15.Cu")
		(net "GMI_CPU0_G1_CPU1_G3_TX_DN<4>")
	)
	(segment
		(start 116.327682 -231.869742)
		(end 116.34216 -231.880664)
		(width 0.1143)
		(layer "In15.Cu")
		(net "GMI_CPU0_G1_CPU1_G3_TX_DN<4>")
	)
	(segment
		(start 116.285772 -224.723198)
		(end 116.256054 -224.740216)
		(width 0.1143)
		(layer "In15.Cu")
		(net "GMI_CPU0_G1_CPU1_G3_TX_DN<4>")
	)
	(segment
		(start 355.207062 -236.060996)
		(end 355.205284 -236.05998)
		(width 0.1143)
		(layer "In15.Cu")
		(net "GMI_CPU0_G1_CPU1_G3_TX_DN<4>")
	)
	(segment
		(start 355.176582 -232.803192)
		(end 355.17582 -232.802684)
		(width 0.1143)
		(layer "In15.Cu")
		(net "GMI_CPU0_G1_CPU1_G3_TX_DN<4>")
	)
	(segment
		(start 355.208332 -226.341686)
		(end 355.169216 -226.318826)
		(width 0.1143)
		(layer "In15.Cu")
		(net "GMI_CPU0_G1_CPU1_G3_TX_DN<4>")
	)
	(segment
		(start 116.281708 -241.563398)
		(end 116.283232 -241.564414)
		(width 0.1143)
		(layer "In15.Cu")
		(net "GMI_CPU0_G1_CPU1_G3_TX_DN<4>")
	)
	(segment
		(start 116.289328 -224.720912)
		(end 116.287042 -224.722436)
		(width 0.1143)
		(layer "In15.Cu")
		(net "GMI_CPU0_G1_CPU1_G3_TX_DN<4>")
	)
	(segment
		(start 116.290598 -223.748854)
		(end 116.326666 -223.769682)
		(width 0.1143)
		(layer "In15.Cu")
		(net "GMI_CPU0_G1_CPU1_G3_TX_DN<4>")
	)
	(segment
		(start 355.208078 -242.541552)
		(end 355.207062 -242.541044)
		(width 0.1143)
		(layer "In15.Cu")
		(net "GMI_CPU0_G1_CPU1_G3_TX_DN<4>")
	)
	(segment
		(start 116.287042 -223.102424)
		(end 116.285772 -223.103186)
		(width 0.1143)
		(layer "In15.Cu")
		(net "GMI_CPU0_G1_CPU1_G3_TX_DN<4>")
	)
	(segment
		(start 355.21519 -231.842564)
		(end 355.239828 -231.82834)
		(width 0.1143)
		(layer "In15.Cu")
		(net "GMI_CPU0_G1_CPU1_G3_TX_DN<4>")
	)
	(segment
		(start 116.290344 -243.188744)
		(end 116.327428 -243.209826)
		(width 0.1143)
		(layer "In15.Cu")
		(net "GMI_CPU0_G1_CPU1_G3_TX_DN<4>")
	)
	(segment
		(start 117.11686 -247.724422)
		(end 117.414802 -247.724422)
		(width 0.1143)
		(layer "In15.Cu")
		(net "GMI_CPU0_G1_CPU1_G3_TX_DN<4>")
	)
	(segment
		(start 354.229162 -223.769682)
		(end 354.268278 -223.746822)
		(width 0.1143)
		(layer "In15.Cu")
		(net "GMI_CPU0_G1_CPU1_G3_TX_DN<4>")
	)
	(segment
		(start 355.168962 -233.4895)
		(end 355.203506 -233.469434)
		(width 0.1143)
		(layer "In15.Cu")
		(net "GMI_CPU0_G1_CPU1_G3_TX_DN<4>")
	)
	(segment
		(start 355.214174 -231.843072)
		(end 355.21519 -231.842564)
		(width 0.1143)
		(layer "In15.Cu")
		(net "GMI_CPU0_G1_CPU1_G3_TX_DN<4>")
	)
	(segment
		(start 355.211634 -235.08462)
		(end 355.212396 -235.084112)
		(width 0.1143)
		(layer "In15.Cu")
		(net "GMI_CPU0_G1_CPU1_G3_TX_DN<4>")
	)
	(segment
		(start 355.212396 -234.444032)
		(end 355.211634 -234.443524)
		(width 0.1143)
		(layer "In15.Cu")
		(net "GMI_CPU0_G1_CPU1_G3_TX_DN<4>")
	)
	(segment
		(start 116.255038 -231.221026)
		(end 116.254276 -231.221534)
		(width 0.1143)
		(layer "In15.Cu")
		(net "GMI_CPU0_G1_CPU1_G3_TX_DN<4>")
	)
	(segment
		(start 116.256054 -239.320324)
		(end 116.2558 -239.320324)
		(width 0.1143)
		(layer "In15.Cu")
		(net "GMI_CPU0_G1_CPU1_G3_TX_DN<4>")
	)
	(segment
		(start 116.287804 -230.22687)
		(end 116.28755 -230.227124)
		(width 0.1143)
		(layer "In15.Cu")
		(net "GMI_CPU0_G1_CPU1_G3_TX_DN<4>")
	)
	(segment
		(start 350.39173 -211.070952)
		(end 316.529466 -183.305196)
		(width 0.14224)
		(layer "In15.Cu")
		(net "GMI_CPU0_G1_CPU1_G3_TX_DN<4>")
	)
	(segment
		(start 355.212396 -232.82402)
		(end 355.211634 -232.823512)
		(width 0.1143)
		(layer "In15.Cu")
		(net "GMI_CPU0_G1_CPU1_G3_TX_DN<4>")
	)
	(segment
		(start 355.207062 -246.427244)
		(end 355.208078 -246.426736)
		(width 0.1143)
		(layer "In15.Cu")
		(net "GMI_CPU0_G1_CPU1_G3_TX_DN<4>")
	)
	(segment
		(start 355.207062 -239.947196)
		(end 355.208078 -239.946688)
		(width 0.1143)
		(layer "In15.Cu")
		(net "GMI_CPU0_G1_CPU1_G3_TX_DN<4>")
	)
	(segment
		(start 116.287804 -231.846882)
		(end 116.290344 -231.84866)
		(width 0.1143)
		(layer "In15.Cu")
		(net "GMI_CPU0_G1_CPU1_G3_TX_DN<4>")
	)
	(segment
		(start 355.208078 -231.201722)
		(end 355.168962 -231.178862)
		(width 0.1143)
		(layer "In15.Cu")
		(net "GMI_CPU0_G1_CPU1_G3_TX_DN<4>")
	)
	(segment
		(start 355.208078 -244.806724)
		(end 355.20884 -244.806216)
		(width 0.1143)
		(layer "In15.Cu")
		(net "GMI_CPU0_G1_CPU1_G3_TX_DN<4>")
	)
	(segment
		(start 116.283232 -225.364548)
		(end 116.285772 -225.365818)
		(width 0.1143)
		(layer "In15.Cu")
		(net "GMI_CPU0_G1_CPU1_G3_TX_DN<4>")
	)
	(segment
		(start 355.211634 -239.30356)
		(end 355.20884 -239.302036)
		(width 0.1143)
		(layer "In15.Cu")
		(net "GMI_CPU0_G1_CPU1_G3_TX_DN<4>")
	)
	(segment
		(start 355.212396 -235.084112)
		(end 355.213412 -235.083604)
		(width 0.1143)
		(layer "In15.Cu")
		(net "GMI_CPU0_G1_CPU1_G3_TX_DN<4>")
	)
	(segment
		(start 355.212396 -239.944148)
		(end 355.213412 -239.94364)
		(width 0.1143)
		(layer "In15.Cu")
		(net "GMI_CPU0_G1_CPU1_G3_TX_DN<4>")
	)
	(segment
		(start 355.20884 -244.806216)
		(end 355.211634 -244.804692)
		(width 0.1143)
		(layer "In15.Cu")
		(net "GMI_CPU0_G1_CPU1_G3_TX_DN<4>")
	)
	(segment
		(start 355.211634 -236.063536)
		(end 355.20884 -236.062012)
		(width 0.1143)
		(layer "In15.Cu")
		(net "GMI_CPU0_G1_CPU1_G3_TX_DN<4>")
	)
	(segment
		(start 355.205792 -241.56797)
		(end 355.207062 -241.567208)
		(width 0.1143)
		(layer "In15.Cu")
		(net "GMI_CPU0_G1_CPU1_G3_TX_DN<4>")
	)
	(segment
		(start 355.213412 -244.803676)
		(end 355.214174 -244.803168)
		(width 0.1143)
		(layer "In15.Cu")
		(net "GMI_CPU0_G1_CPU1_G3_TX_DN<4>")
	)
	(segment
		(start 149.104858 -187.98032)
		(end 149.085808 -188.17336)
		(width 0.14224)
		(layer "In15.Cu")
		(net "GMI_CPU0_G1_CPU1_G3_TX_DN<4>")
	)
	(segment
		(start 116.290344 -231.84866)
		(end 116.327682 -231.869742)
		(width 0.1143)
		(layer "In15.Cu")
		(net "GMI_CPU0_G1_CPU1_G3_TX_DN<4>")
	)
	(segment
		(start 116.283232 -243.184426)
		(end 116.285772 -243.185696)
		(width 0.1143)
		(layer "In15.Cu")
		(net "GMI_CPU0_G1_CPU1_G3_TX_DN<4>")
	)
	(segment
		(start 116.283232 -223.744536)
		(end 116.285772 -223.745806)
		(width 0.1143)
		(layer "In15.Cu")
		(net "GMI_CPU0_G1_CPU1_G3_TX_DN<4>")
	)
	(segment
		(start 355.207062 -232.820972)
		(end 355.205284 -232.819956)
		(width 0.1143)
		(layer "In15.Cu")
		(net "GMI_CPU0_G1_CPU1_G3_TX_DN<4>")
	)
	(segment
		(start 146.818858 -189.85611)
		(end 146.488912 -190.126874)
		(width 0.14224)
		(layer "In15.Cu")
		(net "GMI_CPU0_G1_CPU1_G3_TX_DN<4>")
	)
	(segment
		(start 150.84933 -186.549792)
		(end 150.83028 -186.742832)
		(width 0.14224)
		(layer "In15.Cu")
		(net "GMI_CPU0_G1_CPU1_G3_TX_DN<4>")
	)
	(segment
		(start 116.285772 -239.945418)
		(end 116.285772 -239.945672)
		(width 0.1143)
		(layer "In15.Cu")
		(net "GMI_CPU0_G1_CPU1_G3_TX_DN<4>")
	)
	(segment
		(start 116.582698 -246.922798)
		(end 116.582698 -246.934228)
		(width 0.1143)
		(layer "In15.Cu")
		(net "GMI_CPU0_G1_CPU1_G3_TX_DN<4>")
	)
	(segment
		(start 116.281708 -223.74352)
		(end 116.283232 -223.744536)
		(width 0.1143)
		(layer "In15.Cu")
		(net "GMI_CPU0_G1_CPU1_G3_TX_DN<4>")
	)
	(segment
		(start 355.239828 -242.55984)
		(end 355.208078 -242.541552)
		(width 0.1143)
		(layer "In15.Cu")
		(net "GMI_CPU0_G1_CPU1_G3_TX_DN<4>")
	)
	(segment
		(start 355.208078 -231.846628)
		(end 355.20884 -231.84612)
		(width 0.1143)
		(layer "In15.Cu")
		(net "GMI_CPU0_G1_CPU1_G3_TX_DN<4>")
	)
	(segment
		(start 116.287804 -234.441746)
		(end 116.287042 -234.442254)
		(width 0.1143)
		(layer "In15.Cu")
		(net "GMI_CPU0_G1_CPU1_G3_TX_DN<4>")
	)
	(segment
		(start 355.202744 -240.918492)
		(end 355.20122 -240.917476)
		(width 0.1143)
		(layer "In15.Cu")
		(net "GMI_CPU0_G1_CPU1_G3_TX_DN<4>")
	)
	(segment
		(start 355.212396 -244.804184)
		(end 355.213412 -244.803676)
		(width 0.1143)
		(layer "In15.Cu")
		(net "GMI_CPU0_G1_CPU1_G3_TX_DN<4>")
	)
	(segment
		(start 355.20122 -240.917476)
		(end 355.176582 -240.903252)
		(width 0.1143)
		(layer "In15.Cu")
		(net "GMI_CPU0_G1_CPU1_G3_TX_DN<4>")
	)
	(segment
		(start 355.208078 -245.781576)
		(end 355.207062 -245.781068)
		(width 0.1143)
		(layer "In15.Cu")
		(net "GMI_CPU0_G1_CPU1_G3_TX_DN<4>")
	)
	(segment
		(start 355.171502 -230.247952)
		(end 355.208078 -230.226616)
		(width 0.1143)
		(layer "In15.Cu")
		(net "GMI_CPU0_G1_CPU1_G3_TX_DN<4>")
	)
	(segment
		(start 116.346478 -244.124988)
		(end 116.327428 -244.138958)
		(width 0.1143)
		(layer "In15.Cu")
		(net "GMI_CPU0_G1_CPU1_G3_TX_DN<4>")
	)
	(segment
		(start 355.205792 -239.947958)
		(end 355.207062 -239.947196)
		(width 0.1143)
		(layer "In15.Cu")
		(net "GMI_CPU0_G1_CPU1_G3_TX_DN<4>")
	)
	(segment
		(start 355.20376 -244.159024)
		(end 355.202744 -244.158516)
		(width 0.1143)
		(layer "In15.Cu")
		(net "GMI_CPU0_G1_CPU1_G3_TX_DN<4>")
	)
	(segment
		(start 355.20884 -239.302036)
		(end 355.208078 -239.301528)
		(width 0.1143)
		(layer "In15.Cu")
		(net "GMI_CPU0_G1_CPU1_G3_TX_DN<4>")
	)
	(segment
		(start 148.213572 -188.88837)
		(end 147.883372 -189.159134)
		(width 0.14224)
		(layer "In15.Cu")
		(net "GMI_CPU0_G1_CPU1_G3_TX_DN<4>")
	)
	(segment
		(start 355.20376 -232.81894)
		(end 355.202744 -232.818432)
		(width 0.1143)
		(layer "In15.Cu")
		(net "GMI_CPU0_G1_CPU1_G3_TX_DN<4>")
	)
	(segment
		(start 355.213412 -246.423688)
		(end 355.214174 -246.42318)
		(width 0.1143)
		(layer "In15.Cu")
		(net "GMI_CPU0_G1_CPU1_G3_TX_DN<4>")
	)
	(segment
		(start 116.35105 -223.062038)
		(end 116.327174 -223.079056)
		(width 0.1143)
		(layer "In15.Cu")
		(net "GMI_CPU0_G1_CPU1_G3_TX_DN<4>")
	)
	(segment
		(start 355.20376 -239.298988)
		(end 355.202744 -239.29848)
		(width 0.1143)
		(layer "In15.Cu")
		(net "GMI_CPU0_G1_CPU1_G3_TX_DN<4>")
	)
	(segment
		(start 355.208078 -244.161564)
		(end 355.207062 -244.161056)
		(width 0.1143)
		(layer "In15.Cu")
		(net "GMI_CPU0_G1_CPU1_G3_TX_DN<4>")
	)
	(segment
		(start 116.326666 -222.14967)
		(end 116.35105 -222.167196)
		(width 0.1143)
		(layer "In15.Cu")
		(net "GMI_CPU0_G1_CPU1_G3_TX_DN<4>")
	)
	(segment
		(start 355.17582 -234.422696)
		(end 355.168962 -234.418632)
		(width 0.1143)
		(layer "In15.Cu")
		(net "GMI_CPU0_G1_CPU1_G3_TX_DN<4>")
	)
	(segment
		(start 355.168962 -228.629718)
		(end 355.208078 -228.606858)
		(width 0.1143)
		(layer "In15.Cu")
		(net "GMI_CPU0_G1_CPU1_G3_TX_DN<4>")
	)
	(segment
		(start 355.20122 -236.05744)
		(end 355.176582 -236.043216)
		(width 0.1143)
		(layer "In15.Cu")
		(net "GMI_CPU0_G1_CPU1_G3_TX_DN<4>")
	)
	(segment
		(start 116.285772 -228.605842)
		(end 116.287042 -228.606604)
		(width 0.1143)
		(layer "In15.Cu")
		(net "GMI_CPU0_G1_CPU1_G3_TX_DN<4>")
	)
	(segment
		(start 116.287042 -240.922302)
		(end 116.285772 -240.923064)
		(width 0.1143)
		(layer "In15.Cu")
		(net "GMI_CPU0_G1_CPU1_G3_TX_DN<4>")
	)
	(segment
		(start 355.213412 -243.183664)
		(end 355.214174 -243.183156)
		(width 0.1143)
		(layer "In15.Cu")
		(net "GMI_CPU0_G1_CPU1_G3_TX_DN<4>")
	)
	(segment
		(start 116.290344 -226.988878)
		(end 116.327428 -227.00996)
		(width 0.1143)
		(layer "In15.Cu")
		(net "GMI_CPU0_G1_CPU1_G3_TX_DN<4>")
	)
	(segment
		(start 355.21011 -238.325406)
		(end 355.239828 -238.308388)
		(width 0.1143)
		(layer "In15.Cu")
		(net "GMI_CPU0_G1_CPU1_G3_TX_DN<4>")
	)
	(segment
		(start 116.280184 -226.346258)
		(end 116.279168 -226.346766)
		(width 0.1143)
		(layer "In15.Cu")
		(net "GMI_CPU0_G1_CPU1_G3_TX_DN<4>")
	)
	(segment
		(start 355.20884 -236.062012)
		(end 355.208078 -236.061504)
		(width 0.1143)
		(layer "In15.Cu")
		(net "GMI_CPU0_G1_CPU1_G3_TX_DN<4>")
	)
	(segment
		(start 116.285772 -233.465624)
		(end 116.287042 -233.466386)
		(width 0.1143)
		(layer "In15.Cu")
		(net "GMI_CPU0_G1_CPU1_G3_TX_DN<4>")
	)
	(segment
		(start 152.051766 -185.56478)
		(end 151.722074 -185.83529)
		(width 0.14224)
		(layer "In15.Cu")
		(net "GMI_CPU0_G1_CPU1_G3_TX_DN<4>")
	)
	(segment
		(start 355.203506 -236.709458)
		(end 355.205792 -236.707934)
		(width 0.1143)
		(layer "In15.Cu")
		(net "GMI_CPU0_G1_CPU1_G3_TX_DN<4>")
	)
	(segment
		(start 355.208078 -236.061504)
		(end 355.207062 -236.060996)
		(width 0.1143)
		(layer "In15.Cu")
		(net "GMI_CPU0_G1_CPU1_G3_TX_DN<4>")
	)
	(segment
		(start 116.283232 -233.464354)
		(end 116.285772 -233.465624)
		(width 0.1143)
		(layer "In15.Cu")
		(net "GMI_CPU0_G1_CPU1_G3_TX_DN<4>")
	)
	(segment
		(start 355.208078 -243.186712)
		(end 355.20884 -243.186204)
		(width 0.1143)
		(layer "In15.Cu")
		(net "GMI_CPU0_G1_CPU1_G3_TX_DN<4>")
	)
	(segment
		(start 116.256054 -235.068618)
		(end 116.286534 -235.086144)
		(width 0.1143)
		(layer "In15.Cu")
		(net "GMI_CPU0_G1_CPU1_G3_TX_DN<4>")
	)
	(segment
		(start 152.574752 -185.312304)
		(end 152.244552 -185.583322)
		(width 0.14224)
		(layer "In15.Cu")
		(net "GMI_CPU0_G1_CPU1_G3_TX_DN<4>")
	)
	(segment
		(start 116.327428 -227.00996)
		(end 116.343684 -227.021898)
		(width 0.1143)
		(layer "In15.Cu")
		(net "GMI_CPU0_G1_CPU1_G3_TX_DN<4>")
	)
	(segment
		(start 146.1389 -190.589408)
		(end 145.946876 -190.570358)
		(width 0.14224)
		(layer "In15.Cu")
		(net "GMI_CPU0_G1_CPU1_G3_TX_DN<4>")
	)
	(segment
		(start 116.290344 -238.328708)
		(end 116.327174 -238.349536)
		(width 0.1143)
		(layer "In15.Cu")
		(net "GMI_CPU0_G1_CPU1_G3_TX_DN<4>")
	)
	(segment
		(start 116.256054 -226.968812)
		(end 116.281708 -226.983544)
		(width 0.1143)
		(layer "In15.Cu")
		(net "GMI_CPU0_G1_CPU1_G3_TX_DN<4>")
	)
	(segment
		(start 354.27158 -222.124778)
		(end 354.272342 -222.12427)
		(width 0.1143)
		(layer "In15.Cu")
		(net "GMI_CPU0_G1_CPU1_G3_TX_DN<4>")
	)
	(segment
		(start 355.20884 -235.086144)
		(end 355.211634 -235.08462)
		(width 0.1143)
		(layer "In15.Cu")
		(net "GMI_CPU0_G1_CPU1_G3_TX_DN<4>")
	)
	(segment
		(start 355.213412 -235.083604)
		(end 355.214174 -235.083096)
		(width 0.1143)
		(layer "In15.Cu")
		(net "GMI_CPU0_G1_CPU1_G3_TX_DN<4>")
	)
	(segment
		(start 116.285772 -231.845612)
		(end 116.287042 -231.846374)
		(width 0.1143)
		(layer "In15.Cu")
		(net "GMI_CPU0_G1_CPU1_G3_TX_DN<4>")
	)
	(segment
		(start 116.286534 -235.086144)
		(end 116.287804 -235.086906)
		(width 0.1143)
		(layer "In15.Cu")
		(net "GMI_CPU0_G1_CPU1_G3_TX_DN<4>")
	)
	(segment
		(start 116.326666 -223.769682)
		(end 116.354606 -223.789748)
		(width 0.1143)
		(layer "In15.Cu")
		(net "GMI_CPU0_G1_CPU1_G3_TX_DN<4>")
	)
	(segment
		(start 355.207062 -236.707172)
		(end 355.208078 -236.706664)
		(width 0.1143)
		(layer "In15.Cu")
		(net "GMI_CPU0_G1_CPU1_G3_TX_DN<4>")
	)
	(segment
		(start 116.287804 -232.821734)
		(end 116.287042 -232.822242)
		(width 0.1143)
		(layer "In15.Cu")
		(net "GMI_CPU0_G1_CPU1_G3_TX_DN<4>")
	)
	(segment
		(start 116.285772 -241.565684)
		(end 116.287042 -241.566446)
		(width 0.1143)
		(layer "In15.Cu")
		(net "GMI_CPU0_G1_CPU1_G3_TX_DN<4>")
	)
	(segment
		(start 116.327174 -223.079056)
		(end 116.287804 -223.101916)
		(width 0.1143)
		(layer "In15.Cu")
		(net "GMI_CPU0_G1_CPU1_G3_TX_DN<4>")
	)
	(segment
		(start 355.207062 -240.921032)
		(end 355.205284 -240.920016)
		(width 0.1143)
		(layer "In15.Cu")
		(net "GMI_CPU0_G1_CPU1_G3_TX_DN<4>")
	)
	(segment
		(start 116.326412 -245.759478)
		(end 116.287804 -245.78183)
		(width 0.1143)
		(layer "In15.Cu")
		(net "GMI_CPU0_G1_CPU1_G3_TX_DN<4>")
	)
	(segment
		(start 150.849838 -186.550554)
		(end 150.84933 -186.549792)
		(width 0.14224)
		(layer "In15.Cu")
		(net "GMI_CPU0_G1_CPU1_G3_TX_DN<4>")
	)
	(segment
		(start 116.287042 -224.722436)
		(end 116.285772 -224.723198)
		(width 0.1143)
		(layer "In15.Cu")
		(net "GMI_CPU0_G1_CPU1_G3_TX_DN<4>")
	)
	(segment
		(start 355.214174 -241.563144)
		(end 355.21519 -241.562636)
		(width 0.1143)
		(layer "In15.Cu")
		(net "GMI_CPU0_G1_CPU1_G3_TX_DN<4>")
	)
	(segment
		(start 116.290598 -225.368866)
		(end 116.327174 -225.389948)
		(width 0.1143)
		(layer "In15.Cu")
		(net "GMI_CPU0_G1_CPU1_G3_TX_DN<4>")
	)
	(segment
		(start 116.285772 -226.98583)
		(end 116.287042 -226.986592)
		(width 0.1143)
		(layer "In15.Cu")
		(net "GMI_CPU0_G1_CPU1_G3_TX_DN<4>")
	)
	(segment
		(start 355.214174 -239.943132)
		(end 355.21519 -239.942624)
		(width 0.1143)
		(layer "In15.Cu")
		(net "GMI_CPU0_G1_CPU1_G3_TX_DN<4>")
	)
	(segment
		(start 116.285772 -232.823004)
		(end 116.256054 -232.840022)
		(width 0.1143)
		(layer "In15.Cu")
		(net "GMI_CPU0_G1_CPU1_G3_TX_DN<4>")
	)
	(segment
		(start 116.327682 -232.798874)
		(end 116.287804 -232.821734)
		(width 0.1143)
		(layer "In15.Cu")
		(net "GMI_CPU0_G1_CPU1_G3_TX_DN<4>")
	)
	(segment
		(start 116.256054 -231.828594)
		(end 116.281708 -231.843326)
		(width 0.1143)
		(layer "In15.Cu")
		(net "GMI_CPU0_G1_CPU1_G3_TX_DN<4>")
	)
	(segment
		(start 355.20884 -231.84612)
		(end 355.211634 -231.844596)
		(width 0.1143)
		(layer "In15.Cu")
		(net "GMI_CPU0_G1_CPU1_G3_TX_DN<4>")
	)
	(segment
		(start 316.529466 -183.305196)
		(end 310.034432 -179.628546)
		(width 0.14224)
		(layer "In15.Cu")
		(net "GMI_CPU0_G1_CPU1_G3_TX_DN<4>")
	)
	(segment
		(start 355.20884 -240.922048)
		(end 355.208078 -240.92154)
		(width 0.1143)
		(layer "In15.Cu")
		(net "GMI_CPU0_G1_CPU1_G3_TX_DN<4>")
	)
	(segment
		(start 355.17582 -244.142768)
		(end 355.168962 -244.138704)
		(width 0.1143)
		(layer "In15.Cu")
		(net "GMI_CPU0_G1_CPU1_G3_TX_DN<4>")
	)
	(segment
		(start 116.326666 -224.699322)
		(end 116.289328 -224.720912)
		(width 0.1143)
		(layer "In15.Cu")
		(net "GMI_CPU0_G1_CPU1_G3_TX_DN<4>")
	)
	(segment
		(start 116.287042 -244.162326)
		(end 116.285772 -244.163088)
		(width 0.1143)
		(layer "In15.Cu")
		(net "GMI_CPU0_G1_CPU1_G3_TX_DN<4>")
	)
	(segment
		(start 116.324126 -234.420664)
		(end 116.287804 -234.441746)
		(width 0.1143)
		(layer "In15.Cu")
		(net "GMI_CPU0_G1_CPU1_G3_TX_DN<4>")
	)
	(segment
		(start 116.287804 -246.42699)
		(end 116.302028 -246.435118)
		(width 0.1143)
		(layer "In15.Cu")
		(net "GMI_CPU0_G1_CPU1_G3_TX_DN<4>")
	)
	(segment
		(start 147.691094 -189.140592)
		(end 147.360894 -189.411356)
		(width 0.14224)
		(layer "In15.Cu")
		(net "GMI_CPU0_G1_CPU1_G3_TX_DN<4>")
	)
	(segment
		(start 354.44176 -221.128844)
		(end 354.39604 -221.083124)
		(width 0.1143)
		(layer "In15.Cu")
		(net "GMI_CPU0_G1_CPU1_G3_TX_DN<4>")
	)
	(segment
		(start 355.20884 -236.706156)
		(end 355.211634 -236.704632)
		(width 0.1143)
		(layer "In15.Cu")
		(net "GMI_CPU0_G1_CPU1_G3_TX_DN<4>")
	)
	(segment
		(start 119.768874 -212.033866)
		(end 116.09197 -218.226386)
		(width 0.14224)
		(layer "In15.Cu")
		(net "GMI_CPU0_G1_CPU1_G3_TX_DN<4>")
	)
	(segment
		(start 355.208078 -239.946688)
		(end 355.20884 -239.94618)
		(width 0.1143)
		(layer "In15.Cu")
		(net "GMI_CPU0_G1_CPU1_G3_TX_DN<4>")
	)
	(segment
		(start 116.285772 -223.103186)
		(end 116.256054 -223.120204)
		(width 0.1143)
		(layer "In15.Cu")
		(net "GMI_CPU0_G1_CPU1_G3_TX_DN<4>")
	)
	(segment
		(start 355.168962 -243.209572)
		(end 355.203506 -243.189506)
		(width 0.1143)
		(layer "In15.Cu")
		(net "GMI_CPU0_G1_CPU1_G3_TX_DN<4>")
	)
	(segment
		(start 355.213412 -236.703616)
		(end 355.214174 -236.703108)
		(width 0.1143)
		(layer "In15.Cu")
		(net "GMI_CPU0_G1_CPU1_G3_TX_DN<4>")
	)
	(segment
		(start 355.212396 -246.424196)
		(end 355.213412 -246.423688)
		(width 0.1143)
		(layer "In15.Cu")
		(net "GMI_CPU0_G1_CPU1_G3_TX_DN<4>")
	)
	(segment
		(start 116.09197 -220.991938)
		(end 116.09197 -221.020386)
		(width 0.1143)
		(layer "In15.Cu")
		(net "GMI_CPU0_G1_CPU1_G3_TX_DN<4>")
	)
	(segment
		(start 355.207062 -242.541044)
		(end 355.205538 -242.540028)
		(width 0.1143)
		(layer "In15.Cu")
		(net "GMI_CPU0_G1_CPU1_G3_TX_DN<4>")
	)
	(segment
		(start 116.283232 -244.804438)
		(end 116.285772 -244.805708)
		(width 0.1143)
		(layer "In15.Cu")
		(net "GMI_CPU0_G1_CPU1_G3_TX_DN<4>")
	)
	(segment
		(start 116.285772 -244.805708)
		(end 116.287042 -244.80647)
		(width 0.1143)
		(layer "In15.Cu")
		(net "GMI_CPU0_G1_CPU1_G3_TX_DN<4>")
	)
	(segment
		(start 116.261388 -236.69244)
		(end 116.266468 -236.695488)
		(width 0.1143)
		(layer "In15.Cu")
		(net "GMI_CPU0_G1_CPU1_G3_TX_DN<4>")
	)
	(segment
		(start 116.279676 -236.702092)
		(end 116.279422 -236.702346)
		(width 0.1143)
		(layer "In15.Cu")
		(net "GMI_CPU0_G1_CPU1_G3_TX_DN<4>")
	)
	(segment
		(start 150.307294 -186.995308)
		(end 149.977602 -187.265818)
		(width 0.14224)
		(layer "In15.Cu")
		(net "GMI_CPU0_G1_CPU1_G3_TX_DN<4>")
	)
	(segment
		(start 355.205538 -242.540028)
		(end 355.168962 -242.518692)
		(width 0.1143)
		(layer "In15.Cu")
		(net "GMI_CPU0_G1_CPU1_G3_TX_DN<4>")
	)
	(segment
		(start 355.212396 -236.704124)
		(end 355.213412 -236.703616)
		(width 0.1143)
		(layer "In15.Cu")
		(net "GMI_CPU0_G1_CPU1_G3_TX_DN<4>")
	)
	(segment
		(start 116.285772 -244.163088)
		(end 116.256054 -244.180106)
		(width 0.1143)
		(layer "In15.Cu")
		(net "GMI_CPU0_G1_CPU1_G3_TX_DN<4>")
	)
	(segment
		(start 152.593802 -185.119518)
		(end 152.574752 -185.312304)
		(width 0.14224)
		(layer "In15.Cu")
		(net "GMI_CPU0_G1_CPU1_G3_TX_DN<4>")
	)
	(segment
		(start 355.17582 -239.282732)
		(end 355.168962 -239.278668)
		(width 0.1143)
		(layer "In15.Cu")
		(net "GMI_CPU0_G1_CPU1_G3_TX_DN<4>")
	)
	(segment
		(start 354.699062 -247.259602)
		(end 354.738178 -247.236742)
		(width 0.1143)
		(layer "In15.Cu")
		(net "GMI_CPU0_G1_CPU1_G3_TX_DN<4>")
	)
	(segment
		(start 354.08108 -247.724168)
		(end 354.379022 -247.724168)
		(width 0.1143)
		(layer "In15.Cu")
		(net "GMI_CPU0_G1_CPU1_G3_TX_DN<4>")
	)
	(segment
		(start 116.284502 -242.543584)
		(end 116.28374 -242.544092)
		(width 0.1143)
		(layer "In15.Cu")
		(net "GMI_CPU0_G1_CPU1_G3_TX_DN<4>")
	)
	(segment
		(start 355.205792 -246.428006)
		(end 355.207062 -246.427244)
		(width 0.1143)
		(layer "In15.Cu")
		(net "GMI_CPU0_G1_CPU1_G3_TX_DN<4>")
	)
	(segment
		(start 355.21519 -243.182648)
		(end 355.239828 -243.168424)
		(width 0.1143)
		(layer "In15.Cu")
		(net "GMI_CPU0_G1_CPU1_G3_TX_DN<4>")
	)
	(segment
		(start 116.287042 -232.822242)
		(end 116.285772 -232.823004)
		(width 0.1143)
		(layer "In15.Cu")
		(net "GMI_CPU0_G1_CPU1_G3_TX_DN<4>")
	)
	(segment
		(start 116.281962 -226.345242)
		(end 116.280946 -226.34575)
		(width 0.1143)
		(layer "In15.Cu")
		(net "GMI_CPU0_G1_CPU1_G3_TX_DN<4>")
	)
	(segment
		(start 355.168962 -239.969548)
		(end 355.203506 -239.949482)
		(width 0.1143)
		(layer "In15.Cu")
		(net "GMI_CPU0_G1_CPU1_G3_TX_DN<4>")
	)
	(segment
		(start 355.207062 -233.467148)
		(end 355.208078 -233.46664)
		(width 0.1143)
		(layer "In15.Cu")
		(net "GMI_CPU0_G1_CPU1_G3_TX_DN<4>")
	)
	(segment
		(start 355.208078 -237.681516)
		(end 355.207062 -237.681008)
		(width 0.1143)
		(layer "In15.Cu")
		(net "GMI_CPU0_G1_CPU1_G3_TX_DN<4>")
	)
	(segment
		(start 116.327428 -244.138958)
		(end 116.287804 -244.161818)
		(width 0.1143)
		(layer "In15.Cu")
		(net "GMI_CPU0_G1_CPU1_G3_TX_DN<4>")
	)
	(segment
		(start 116.354606 -224.679256)
		(end 116.326666 -224.699322)
		(width 0.1143)
		(layer "In15.Cu")
		(net "GMI_CPU0_G1_CPU1_G3_TX_DN<4>")
	)
	(segment
		(start 354.735638 -225.530156)
		(end 354.699062 -225.50882)
		(width 0.1143)
		(layer "In15.Cu")
		(net "GMI_CPU0_G1_CPU1_G3_TX_DN<4>")
	)
	(segment
		(start 116.290598 -241.568732)
		(end 116.327174 -241.589814)
		(width 0.1143)
		(layer "In15.Cu")
		(net "GMI_CPU0_G1_CPU1_G3_TX_DN<4>")
	)
	(segment
		(start 116.256054 -223.728788)
		(end 116.281708 -223.74352)
		(width 0.1143)
		(layer "In15.Cu")
		(net "GMI_CPU0_G1_CPU1_G3_TX_DN<4>")
	)
	(segment
		(start 355.207062 -239.30102)
		(end 355.205284 -239.300004)
		(width 0.1143)
		(layer "In15.Cu")
		(net "GMI_CPU0_G1_CPU1_G3_TX_DN<4>")
	)
	(segment
		(start 354.272342 -222.12427)
		(end 354.274374 -222.123254)
		(width 0.1143)
		(layer "In15.Cu")
		(net "GMI_CPU0_G1_CPU1_G3_TX_DN<4>")
	)
	(segment
		(start 355.207062 -244.161056)
		(end 355.205284 -244.16004)
		(width 0.1143)
		(layer "In15.Cu")
		(net "GMI_CPU0_G1_CPU1_G3_TX_DN<4>")
	)
	(segment
		(start 355.239828 -236.079792)
		(end 355.212396 -236.064044)
		(width 0.1143)
		(layer "In15.Cu")
		(net "GMI_CPU0_G1_CPU1_G3_TX_DN<4>")
	)
	(segment
		(start 354.298758 -224.739454)
		(end 354.268278 -224.721674)
		(width 0.1143)
		(layer "In15.Cu")
		(net "GMI_CPU0_G1_CPU1_G3_TX_DN<4>")
	)
	(segment
		(start 147.360894 -189.411356)
		(end 147.360386 -189.41034)
		(width 0.14224)
		(layer "In15.Cu")
		(net "GMI_CPU0_G1_CPU1_G3_TX_DN<4>")
	)
	(segment
		(start 116.327174 -242.518946)
		(end 116.28628 -242.542568)
		(width 0.1143)
		(layer "In15.Cu")
		(net "GMI_CPU0_G1_CPU1_G3_TX_DN<4>")
	)
	(segment
		(start 355.205284 -244.16004)
		(end 355.20376 -244.159024)
		(width 0.1143)
		(layer "In15.Cu")
		(net "GMI_CPU0_G1_CPU1_G3_TX_DN<4>")
	)
	(segment
		(start 355.168962 -235.109512)
		(end 355.203506 -235.089446)
		(width 0.1143)
		(layer "In15.Cu")
		(net "GMI_CPU0_G1_CPU1_G3_TX_DN<4>")
	)
	(segment
		(start 149.434804 -187.70981)
		(end 149.435058 -187.710318)
		(width 0.14224)
		(layer "In15.Cu")
		(net "GMI_CPU0_G1_CPU1_G3_TX_DN<4>")
	)
	(segment
		(start 116.283232 -246.42445)
		(end 116.285772 -246.42572)
		(width 0.1143)
		(layer "In15.Cu")
		(net "GMI_CPU0_G1_CPU1_G3_TX_DN<4>")
	)
	(segment
		(start 116.287804 -233.466894)
		(end 116.324126 -233.487976)
		(width 0.1143)
		(layer "In15.Cu")
		(net "GMI_CPU0_G1_CPU1_G3_TX_DN<4>")
	)
	(segment
		(start 116.256054 -243.168678)
		(end 116.281708 -243.18341)
		(width 0.1143)
		(layer "In15.Cu")
		(net "GMI_CPU0_G1_CPU1_G3_TX_DN<4>")
	)
	(segment
		(start 116.282724 -226.344734)
		(end 116.281962 -226.345242)
		(width 0.1143)
		(layer "In15.Cu")
		(net "GMI_CPU0_G1_CPU1_G3_TX_DN<4>")
	)
	(segment
		(start 355.239828 -244.179852)
		(end 355.212396 -244.164104)
		(width 0.1143)
		(layer "In15.Cu")
		(net "GMI_CPU0_G1_CPU1_G3_TX_DN<4>")
	)
	(segment
		(start 151.372316 -186.298586)
		(end 151.179276 -186.279282)
		(width 0.14224)
		(layer "In15.Cu")
		(net "GMI_CPU0_G1_CPU1_G3_TX_DN<4>")
	)
	(segment
		(start 116.281708 -228.603556)
		(end 116.283232 -228.604572)
		(width 0.1143)
		(layer "In15.Cu")
		(net "GMI_CPU0_G1_CPU1_G3_TX_DN<4>")
	)
	(segment
		(start 355.21519 -241.562636)
		(end 355.239828 -241.548412)
		(width 0.1143)
		(layer "In15.Cu")
		(net "GMI_CPU0_G1_CPU1_G3_TX_DN<4>")
	)
	(segment
		(start 355.208078 -239.301528)
		(end 355.207062 -239.30102)
		(width 0.1143)
		(layer "In15.Cu")
		(net "GMI_CPU0_G1_CPU1_G3_TX_DN<4>")
	)
	(segment
		(start 355.17582 -232.802684)
		(end 355.168962 -232.79862)
		(width 0.1143)
		(layer "In15.Cu")
		(net "GMI_CPU0_G1_CPU1_G3_TX_DN<4>")
	)
	(segment
		(start 116.285772 -225.365818)
		(end 116.287042 -225.36658)
		(width 0.1143)
		(layer "In15.Cu")
		(net "GMI_CPU0_G1_CPU1_G3_TX_DN<4>")
	)
	(segment
		(start 355.211634 -246.424704)
		(end 355.212396 -246.424196)
		(width 0.1143)
		(layer "In15.Cu")
		(net "GMI_CPU0_G1_CPU1_G3_TX_DN<4>")
	)
	(segment
		(start 116.285518 -226.34321)
		(end 116.284502 -226.343718)
		(width 0.1143)
		(layer "In15.Cu")
		(net "GMI_CPU0_G1_CPU1_G3_TX_DN<4>")
	)
	(segment
		(start 149.085808 -188.17336)
		(end 148.755608 -188.444124)
		(width 0.14224)
		(layer "In15.Cu")
		(net "GMI_CPU0_G1_CPU1_G3_TX_DN<4>")
	)
	(segment
		(start 151.17953 -186.280044)
		(end 150.849838 -186.550554)
		(width 0.14224)
		(layer "In15.Cu")
		(net "GMI_CPU0_G1_CPU1_G3_TX_DN<4>")
	)
	(segment
		(start 148.232622 -188.69533)
		(end 148.213572 -188.88837)
		(width 0.14224)
		(layer "In15.Cu")
		(net "GMI_CPU0_G1_CPU1_G3_TX_DN<4>")
	)
	(segment
		(start 355.208332 -226.986846)
		(end 355.238812 -226.969066)
		(width 0.1143)
		(layer "In15.Cu")
		(net "GMI_CPU0_G1_CPU1_G3_TX_DN<4>")
	)
	(segment
		(start 146.488912 -190.126874)
		(end 146.48815 -190.125604)
		(width 0.14224)
		(layer "In15.Cu")
		(net "GMI_CPU0_G1_CPU1_G3_TX_DN<4>")
	)
	(segment
		(start 355.203506 -231.849422)
		(end 355.205792 -231.847898)
		(width 0.1143)
		(layer "In15.Cu")
		(net "GMI_CPU0_G1_CPU1_G3_TX_DN<4>")
	)
	(segment
		(start 355.168962 -238.349536)
		(end 355.207062 -238.327184)
		(width 0.1143)
		(layer "In15.Cu")
		(net "GMI_CPU0_G1_CPU1_G3_TX_DN<4>")
	)
	(segment
		(start 149.958044 -187.458096)
		(end 149.627844 -187.729114)
		(width 0.14224)
		(layer "In15.Cu")
		(net "GMI_CPU0_G1_CPU1_G3_TX_DN<4>")
	)
	(segment
		(start 116.344192 -245.747032)
		(end 116.326412 -245.759478)
		(width 0.1143)
		(layer "In15.Cu")
		(net "GMI_CPU0_G1_CPU1_G3_TX_DN<4>")
	)
	(segment
		(start 355.202744 -236.058456)
		(end 355.20122 -236.05744)
		(width 0.1143)
		(layer "In15.Cu")
		(net "GMI_CPU0_G1_CPU1_G3_TX_DN<4>")
	)
	(segment
		(start 116.256054 -244.78869)
		(end 116.281708 -244.803422)
		(width 0.1143)
		(layer "In15.Cu")
		(net "GMI_CPU0_G1_CPU1_G3_TX_DN<4>")
	)
	(segment
		(start 116.343684 -227.927154)
		(end 116.327428 -227.939092)
		(width 0.1143)
		(layer "In15.Cu")
		(net "GMI_CPU0_G1_CPU1_G3_TX_DN<4>")
	)
	(segment
		(start 116.28755 -230.227124)
		(end 116.288312 -230.227632)
		(width 0.1143)
		(layer "In15.Cu")
		(net "GMI_CPU0_G1_CPU1_G3_TX_DN<4>")
	)
	(segment
		(start 355.239828 -239.319816)
		(end 355.212396 -239.304068)
		(width 0.1143)
		(layer "In15.Cu")
		(net "GMI_CPU0_G1_CPU1_G3_TX_DN<4>")
	)
	(segment
		(start 116.287042 -233.466386)
		(end 116.287804 -233.466894)
		(width 0.1143)
		(layer "In15.Cu")
		(net "GMI_CPU0_G1_CPU1_G3_TX_DN<4>")
	)
	(segment
		(start 355.17582 -236.042708)
		(end 355.168962 -236.038644)
		(width 0.1143)
		(layer "In15.Cu")
		(net "GMI_CPU0_G1_CPU1_G3_TX_DN<4>")
	)
	(segment
		(start 116.287042 -237.682278)
		(end 116.285772 -237.68304)
		(width 0.1143)
		(layer "In15.Cu")
		(net "GMI_CPU0_G1_CPU1_G3_TX_DN<4>")
	)
	(segment
		(start 355.211634 -241.564668)
		(end 355.212396 -241.56416)
		(width 0.1143)
		(layer "In15.Cu")
		(net "GMI_CPU0_G1_CPU1_G3_TX_DN<4>")
	)
	(segment
		(start 150.307548 -186.995308)
		(end 150.307294 -186.995308)
		(width 0.14224)
		(layer "In15.Cu")
		(net "GMI_CPU0_G1_CPU1_G3_TX_DN<4>")
	)
	(segment
		(start 355.205792 -236.707934)
		(end 355.207062 -236.707172)
		(width 0.1143)
		(layer "In15.Cu")
		(net "GMI_CPU0_G1_CPU1_G3_TX_DN<4>")
	)
	(segment
		(start 116.281708 -225.363532)
		(end 116.283232 -225.364548)
		(width 0.1143)
		(layer "In15.Cu")
		(net "GMI_CPU0_G1_CPU1_G3_TX_DN<4>")
	)
	(segment
		(start 355.168962 -241.58956)
		(end 355.203506 -241.569494)
		(width 0.1143)
		(layer "In15.Cu")
		(net "GMI_CPU0_G1_CPU1_G3_TX_DN<4>")
	)
	(segment
		(start 116.287042 -228.606604)
		(end 116.287804 -228.607112)
		(width 0.1143)
		(layer "In15.Cu")
		(net "GMI_CPU0_G1_CPU1_G3_TX_DN<4>")
	)
	(segment
		(start 116.281708 -231.843326)
		(end 116.283232 -231.844342)
		(width 0.1143)
		(layer "In15.Cu")
		(net "GMI_CPU0_G1_CPU1_G3_TX_DN<4>")
	)
	(segment
		(start 355.21519 -233.462576)
		(end 355.239828 -233.448352)
		(width 0.1143)
		(layer "In15.Cu")
		(net "GMI_CPU0_G1_CPU1_G3_TX_DN<4>")
	)
	(segment
		(start 355.203506 -243.189506)
		(end 355.205792 -243.187982)
		(width 0.1143)
		(layer "In15.Cu")
		(net "GMI_CPU0_G1_CPU1_G3_TX_DN<4>")
	)
	(segment
		(start 116.04625 -221.198948)
		(end 116.099844 -221.252542)
		(width 0.1143)
		(layer "In15.Cu")
		(net "GMI_CPU0_G1_CPU1_G3_TX_DN<4>")
	)
	(segment
		(start 116.280184 -239.942624)
		(end 116.285772 -239.945418)
		(width 0.1143)
		(layer "In15.Cu")
		(net "GMI_CPU0_G1_CPU1_G3_TX_DN<4>")
	)
	(segment
		(start 116.285772 -239.945672)
		(end 116.287042 -239.946434)
		(width 0.1143)
		(layer "In15.Cu")
		(net "GMI_CPU0_G1_CPU1_G3_TX_DN<4>")
	)
	(segment
		(start 148.563076 -188.425582)
		(end 148.23313 -188.696092)
		(width 0.14224)
		(layer "In15.Cu")
		(net "GMI_CPU0_G1_CPU1_G3_TX_DN<4>")
	)
	(segment
		(start 354.73894 -225.532188)
		(end 354.738178 -225.53168)
		(width 0.1143)
		(layer "In15.Cu")
		(net "GMI_CPU0_G1_CPU1_G3_TX_DN<4>")
	)
	(segment
		(start 355.214174 -246.42318)
		(end 355.21519 -246.422672)
		(width 0.1143)
		(layer "In15.Cu")
		(net "GMI_CPU0_G1_CPU1_G3_TX_DN<4>")
	)
	(segment
		(start 355.21519 -235.082588)
		(end 355.239828 -235.068364)
		(width 0.1143)
		(layer "In15.Cu")
		(net "GMI_CPU0_G1_CPU1_G3_TX_DN<4>")
	)
	(segment
		(start 355.20122 -239.297464)
		(end 355.176582 -239.28324)
		(width 0.1143)
		(layer "In15.Cu")
		(net "GMI_CPU0_G1_CPU1_G3_TX_DN<4>")
	)
	(segment
		(start 116.327428 -227.939092)
		(end 116.287804 -227.961952)
		(width 0.1143)
		(layer "In15.Cu")
		(net "GMI_CPU0_G1_CPU1_G3_TX_DN<4>")
	)
	(segment
		(start 355.202744 -234.438444)
		(end 355.20122 -234.437428)
		(width 0.1143)
		(layer "In15.Cu")
		(net "GMI_CPU0_G1_CPU1_G3_TX_DN<4>")
	)
	(segment
		(start 116.287042 -223.746568)
		(end 116.287804 -223.747076)
		(width 0.1143)
		(layer "In15.Cu")
		(net "GMI_CPU0_G1_CPU1_G3_TX_DN<4>")
	)
	(segment
		(start 146.818096 -189.855094)
		(end 146.818858 -189.85611)
		(width 0.14224)
		(layer "In15.Cu")
		(net "GMI_CPU0_G1_CPU1_G3_TX_DN<4>")
	)
	(segment
		(start 116.285772 -237.68304)
		(end 116.256054 -237.700058)
		(width 0.1143)
		(layer "In15.Cu")
		(net "GMI_CPU0_G1_CPU1_G3_TX_DN<4>")
	)
	(segment
		(start 354.738178 -225.53168)
		(end 354.737162 -225.531172)
		(width 0.1143)
		(layer "In15.Cu")
		(net "GMI_CPU0_G1_CPU1_G3_TX_DN<4>")
	)
	(segment
		(start 116.287804 -238.32693)
		(end 116.290344 -238.328708)
		(width 0.1143)
		(layer "In15.Cu")
		(net "GMI_CPU0_G1_CPU1_G3_TX_DN<4>")
	)
	(segment
		(start 116.287804 -243.186966)
		(end 116.290344 -243.188744)
		(width 0.1143)
		(layer "In15.Cu")
		(net "GMI_CPU0_G1_CPU1_G3_TX_DN<4>")
	)
	(segment
		(start 355.168962 -231.869488)
		(end 355.203506 -231.849422)
		(width 0.1143)
		(layer "In15.Cu")
		(net "GMI_CPU0_G1_CPU1_G3_TX_DN<4>")
	)
	(segment
		(start 116.327174 -225.389948)
		(end 116.345462 -225.403156)
		(width 0.1143)
		(layer "In15.Cu")
		(net "GMI_CPU0_G1_CPU1_G3_TX_DN<4>")
	)
	(segment
		(start 116.287804 -227.961952)
		(end 116.287042 -227.96246)
		(width 0.1143)
		(layer "In15.Cu")
		(net "GMI_CPU0_G1_CPU1_G3_TX_DN<4>")
	)
	(segment
		(start 355.21519 -246.422672)
		(end 355.239828 -246.408448)
		(width 0.1143)
		(layer "In15.Cu")
		(net "GMI_CPU0_G1_CPU1_G3_TX_DN<4>")
	)
	(segment
		(start 355.176582 -236.043216)
		(end 355.17582 -236.042708)
		(width 0.1143)
		(layer "In15.Cu")
		(net "GMI_CPU0_G1_CPU1_G3_TX_DN<4>")
	)
	(segment
		(start 116.287042 -227.96246)
		(end 116.285772 -227.963222)
		(width 0.1143)
		(layer "In15.Cu")
		(net "GMI_CPU0_G1_CPU1_G3_TX_DN<4>")
	)
	(segment
		(start 355.205792 -243.187982)
		(end 355.207062 -243.18722)
		(width 0.1143)
		(layer "In15.Cu")
		(net "GMI_CPU0_G1_CPU1_G3_TX_DN<4>")
	)
	(segment
		(start 355.214174 -233.463084)
		(end 355.21519 -233.462576)
		(width 0.1143)
		(layer "In15.Cu")
		(net "GMI_CPU0_G1_CPU1_G3_TX_DN<4>")
	)
	(segment
		(start 355.214174 -236.703108)
		(end 355.21519 -236.7026)
		(width 0.1143)
		(layer "In15.Cu")
		(net "GMI_CPU0_G1_CPU1_G3_TX_DN<4>")
	)
	(segment
		(start 354.44176 -221.38767)
		(end 354.44176 -221.128844)
		(width 0.1143)
		(layer "In15.Cu")
		(net "GMI_CPU0_G1_CPU1_G3_TX_DN<4>")
	)
	(segment
		(start 355.211634 -244.804692)
		(end 355.212396 -244.804184)
		(width 0.1143)
		(layer "In15.Cu")
		(net "GMI_CPU0_G1_CPU1_G3_TX_DN<4>")
	)
	(segment
		(start 355.168962 -236.729524)
		(end 355.203506 -236.709458)
		(width 0.1143)
		(layer "In15.Cu")
		(net "GMI_CPU0_G1_CPU1_G3_TX_DN<4>")
	)
	(segment
		(start 355.239828 -240.939828)
		(end 355.212396 -240.92408)
		(width 0.1143)
		(layer "In15.Cu")
		(net "GMI_CPU0_G1_CPU1_G3_TX_DN<4>")
	)
	(segment
		(start 354.455984 -221.401894)
		(end 354.44176 -221.38767)
		(width 0.1143)
		(layer "In15.Cu")
		(net "GMI_CPU0_G1_CPU1_G3_TX_DN<4>")
	)
	(segment
		(start 116.287042 -225.36658)
		(end 116.287804 -225.367088)
		(width 0.1143)
		(layer "In15.Cu")
		(net "GMI_CPU0_G1_CPU1_G3_TX_DN<4>")
	)
	(segment
		(start 355.207062 -231.847136)
		(end 355.208078 -231.846628)
		(width 0.1143)
		(layer "In15.Cu")
		(net "GMI_CPU0_G1_CPU1_G3_TX_DN<4>")
	)
	(segment
		(start 355.207062 -243.18722)
		(end 355.208078 -243.186712)
		(width 0.1143)
		(layer "In15.Cu")
		(net "GMI_CPU0_G1_CPU1_G3_TX_DN<4>")
	)
	(segment
		(start 355.207062 -234.440984)
		(end 355.205284 -234.439968)
		(width 0.1143)
		(layer "In15.Cu")
		(net "GMI_CPU0_G1_CPU1_G3_TX_DN<4>")
	)
	(segment
		(start 116.256054 -225.3488)
		(end 116.281708 -225.363532)
		(width 0.1143)
		(layer "In15.Cu")
		(net "GMI_CPU0_G1_CPU1_G3_TX_DN<4>")
	)
	(segment
		(start 355.203506 -246.42953)
		(end 355.205792 -246.428006)
		(width 0.1143)
		(layer "In15.Cu")
		(net "GMI_CPU0_G1_CPU1_G3_TX_DN<4>")
	)
	(segment
		(start 116.327174 -226.31908)
		(end 116.28628 -226.342702)
		(width 0.1143)
		(layer "In15.Cu")
		(net "GMI_CPU0_G1_CPU1_G3_TX_DN<4>")
	)
	(segment
		(start 116.283232 -231.844342)
		(end 116.285772 -231.845612)
		(width 0.1143)
		(layer "In15.Cu")
		(net "GMI_CPU0_G1_CPU1_G3_TX_DN<4>")
	)
	(segment
		(start 355.208078 -229.58171)
		(end 355.168962 -229.55885)
		(width 0.1143)
		(layer "In15.Cu")
		(net "GMI_CPU0_G1_CPU1_G3_TX_DN<4>")
	)
	(segment
		(start 150.30704 -186.994546)
		(end 150.307548 -186.995308)
		(width 0.14224)
		(layer "In15.Cu")
		(net "GMI_CPU0_G1_CPU1_G3_TX_DN<4>")
	)
	(segment
		(start 116.285772 -227.963222)
		(end 116.256054 -227.98024)
		(width 0.1143)
		(layer "In15.Cu")
		(net "GMI_CPU0_G1_CPU1_G3_TX_DN<4>")
	)
	(segment
		(start 354.228908 -222.14967)
		(end 354.267008 -222.127318)
		(width 0.1143)
		(layer "In15.Cu")
		(net "GMI_CPU0_G1_CPU1_G3_TX_DN<4>")
	)
	(segment
		(start 355.241606 -231.22128)
		(end 355.208078 -231.201722)
		(width 0.1143)
		(layer "In15.Cu")
		(net "GMI_CPU0_G1_CPU1_G3_TX_DN<4>")
	)
	(segment
		(start 355.205792 -231.847898)
		(end 355.207062 -231.847136)
		(width 0.1143)
		(layer "In15.Cu")
		(net "GMI_CPU0_G1_CPU1_G3_TX_DN<4>")
	)
	(segment
		(start 116.287804 -240.921794)
		(end 116.287042 -240.922302)
		(width 0.1143)
		(layer "In15.Cu")
		(net "GMI_CPU0_G1_CPU1_G3_TX_DN<4>")
	)
	(segment
		(start 116.2558 -222.108776)
		(end 116.326666 -222.14967)
		(width 0.1143)
		(layer "In15.Cu")
		(net "GMI_CPU0_G1_CPU1_G3_TX_DN<4>")
	)
	(segment
		(start 116.281708 -226.983544)
		(end 116.283232 -226.98456)
		(width 0.1143)
		(layer "In15.Cu")
		(net "GMI_CPU0_G1_CPU1_G3_TX_DN<4>")
	)
	(segment
		(start 116.326412 -244.82933)
		(end 116.344192 -244.841776)
		(width 0.1143)
		(layer "In15.Cu")
		(net "GMI_CPU0_G1_CPU1_G3_TX_DN<4>")
	)
	(segment
		(start 355.239828 -232.839768)
		(end 355.212396 -232.82402)
		(width 0.1143)
		(layer "In15.Cu")
		(net "GMI_CPU0_G1_CPU1_G3_TX_DN<4>")
	)
	(segment
		(start 116.04625 -221.066106)
		(end 116.04625 -221.198948)
		(width 0.1143)
		(layer "In15.Cu")
		(net "GMI_CPU0_G1_CPU1_G3_TX_DN<4>")
	)
	(segment
		(start 355.208078 -233.46664)
		(end 355.20884 -233.466132)
		(width 0.1143)
		(layer "In15.Cu")
		(net "GMI_CPU0_G1_CPU1_G3_TX_DN<4>")
	)
	(segment
		(start 152.244552 -185.583322)
		(end 152.051512 -185.564018)
		(width 0.14224)
		(layer "In15.Cu")
		(net "GMI_CPU0_G1_CPU1_G3_TX_DN<4>")
	)
	(segment
		(start 355.203506 -244.809518)
		(end 355.205792 -244.807994)
		(width 0.1143)
		(layer "In15.Cu")
		(net "GMI_CPU0_G1_CPU1_G3_TX_DN<4>")
	)
	(segment
		(start 116.278914 -236.701584)
		(end 116.279676 -236.702092)
		(width 0.1143)
		(layer "In15.Cu")
		(net "GMI_CPU0_G1_CPU1_G3_TX_DN<4>")
	)
	(segment
		(start 116.285772 -239.303052)
		(end 116.256054 -239.32007)
		(width 0.1143)
		(layer "In15.Cu")
		(net "GMI_CPU0_G1_CPU1_G3_TX_DN<4>")
	)
	(arc
		(start 116.256054 -240.940082)
		(mid 116.100126 -241.244374)
		(end 116.256054 -241.548666)
		(width 0.1143)
		(layer "In15.Cu")
		(net "GMI_CPU0_G1_CPU1_G3_TX_DN<4>")
	)
	(arc
		(start 355.169216 -226.318826)
		(mid 354.990403 -226.116476)
		(end 354.925884 -225.85426)
		(width 0.1143)
		(layer "In15.Cu")
		(net "GMI_CPU0_G1_CPU1_G3_TX_DN<4>")
	)
	(arc
		(start 116.256054 -224.740216)
		(mid 116.100126 -225.044508)
		(end 116.256054 -225.3488)
		(width 0.1143)
		(layer "In15.Cu")
		(net "GMI_CPU0_G1_CPU1_G3_TX_DN<4>")
	)
	(arc
		(start 355.239828 -244.788436)
		(mid 355.395756 -244.484144)
		(end 355.239828 -244.179852)
		(width 0.1143)
		(layer "In15.Cu")
		(net "GMI_CPU0_G1_CPU1_G3_TX_DN<4>")
	)
	(arc
		(start 355.239828 -243.168424)
		(mid 355.395756 -242.864132)
		(end 355.239828 -242.55984)
		(width 0.1143)
		(layer "In15.Cu")
		(net "GMI_CPU0_G1_CPU1_G3_TX_DN<4>")
	)
	(arc
		(start 354.38969 -222.016574)
		(mid 354.421887 -221.959877)
		(end 354.443792 -221.898464)
		(width 0.1143)
		(layer "In15.Cu")
		(net "GMI_CPU0_G1_CPU1_G3_TX_DN<4>")
	)
	(arc
		(start 355.168962 -240.89868)
		(mid 354.925635 -240.434114)
		(end 355.168962 -239.969548)
		(width 0.1143)
		(layer "In15.Cu")
		(net "GMI_CPU0_G1_CPU1_G3_TX_DN<4>")
	)
	(arc
		(start 116.569998 -230.71455)
		(mid 116.508553 -230.970762)
		(end 116.337588 -231.171242)
		(width 0.1143)
		(layer "In15.Cu")
		(net "GMI_CPU0_G1_CPU1_G3_TX_DN<4>")
	)
	(arc
		(start 354.465636 -247.618504)
		(mid 354.547069 -247.416106)
		(end 354.699062 -247.259602)
		(width 0.1143)
		(layer "In15.Cu")
		(net "GMI_CPU0_G1_CPU1_G3_TX_DN<4>")
	)
	(arc
		(start 116.2558 -239.320324)
		(mid 116.099989 -239.627816)
		(end 116.261388 -239.932464)
		(width 0.1143)
		(layer "In15.Cu")
		(net "GMI_CPU0_G1_CPU1_G3_TX_DN<4>")
	)
	(arc
		(start 355.168962 -239.278668)
		(mid 354.925635 -238.814102)
		(end 355.168962 -238.349536)
		(width 0.1143)
		(layer "In15.Cu")
		(net "GMI_CPU0_G1_CPU1_G3_TX_DN<4>")
	)
	(arc
		(start 116.345462 -241.603022)
		(mid 116.57681 -242.05456)
		(end 116.345462 -242.505992)
		(width 0.1143)
		(layer "In15.Cu")
		(net "GMI_CPU0_G1_CPU1_G3_TX_DN<4>")
	)
	(arc
		(start 355.239828 -238.308388)
		(mid 355.395756 -238.004096)
		(end 355.239828 -237.699804)
		(width 0.1143)
		(layer "In15.Cu")
		(net "GMI_CPU0_G1_CPU1_G3_TX_DN<4>")
	)
	(arc
		(start 355.168962 -234.418632)
		(mid 354.925635 -233.954066)
		(end 355.168962 -233.4895)
		(width 0.1143)
		(layer "In15.Cu")
		(net "GMI_CPU0_G1_CPU1_G3_TX_DN<4>")
	)
	(arc
		(start 116.582698 -246.934228)
		(mid 116.629589 -247.109094)
		(end 116.757704 -247.236996)
		(width 0.1143)
		(layer "In15.Cu")
		(net "GMI_CPU0_G1_CPU1_G3_TX_DN<4>")
	)
	(arc
		(start 354.299774 -222.108522)
		(mid 354.348706 -222.066434)
		(end 354.38969 -222.016574)
		(width 0.1143)
		(layer "In15.Cu")
		(net "GMI_CPU0_G1_CPU1_G3_TX_DN<4>")
	)
	(arc
		(start 116.256054 -226.360228)
		(mid 116.100126 -226.66452)
		(end 116.256054 -226.968812)
		(width 0.1143)
		(layer "In15.Cu")
		(net "GMI_CPU0_G1_CPU1_G3_TX_DN<4>")
	)
	(arc
		(start 355.168962 -245.758716)
		(mid 354.925635 -245.29415)
		(end 355.168962 -244.829584)
		(width 0.1143)
		(layer "In15.Cu")
		(net "GMI_CPU0_G1_CPU1_G3_TX_DN<4>")
	)
	(arc
		(start 355.168962 -244.138704)
		(mid 354.925635 -243.674138)
		(end 355.168962 -243.209572)
		(width 0.1143)
		(layer "In15.Cu")
		(net "GMI_CPU0_G1_CPU1_G3_TX_DN<4>")
	)
	(arc
		(start 354.92563 -230.714296)
		(mid 354.990866 -230.450705)
		(end 355.171502 -230.247952)
		(width 0.1143)
		(layer "In15.Cu")
		(net "GMI_CPU0_G1_CPU1_G3_TX_DN<4>")
	)
	(arc
		(start 355.239828 -235.068364)
		(mid 355.395756 -234.764072)
		(end 355.239828 -234.45978)
		(width 0.1143)
		(layer "In15.Cu")
		(net "GMI_CPU0_G1_CPU1_G3_TX_DN<4>")
	)
	(arc
		(start 116.345462 -225.403156)
		(mid 116.57681 -225.854694)
		(end 116.345462 -226.306126)
		(width 0.1143)
		(layer "In15.Cu")
		(net "GMI_CPU0_G1_CPU1_G3_TX_DN<4>")
	)
	(arc
		(start 354.461826 -247.641364)
		(mid 354.463614 -247.629915)
		(end 354.465636 -247.618504)
		(width 0.1143)
		(layer "In15.Cu")
		(net "GMI_CPU0_G1_CPU1_G3_TX_DN<4>")
	)
	(arc
		(start 354.768658 -247.218962)
		(mid 354.884085 -247.085586)
		(end 354.92563 -246.914162)
		(width 0.1143)
		(layer "In15.Cu")
		(net "GMI_CPU0_G1_CPU1_G3_TX_DN<4>")
	)
	(arc
		(start 355.168962 -237.658656)
		(mid 354.925635 -237.19409)
		(end 355.168962 -236.729524)
		(width 0.1143)
		(layer "In15.Cu")
		(net "GMI_CPU0_G1_CPU1_G3_TX_DN<4>")
	)
	(arc
		(start 116.33835 -233.497882)
		(mid 116.565733 -233.95432)
		(end 116.33835 -234.410758)
		(width 0.1143)
		(layer "In15.Cu")
		(net "GMI_CPU0_G1_CPU1_G3_TX_DN<4>")
	)
	(arc
		(start 116.79682 -247.259856)
		(mid 116.847632 -247.299642)
		(end 116.893594 -247.344946)
		(width 0.1143)
		(layer "In15.Cu")
		(net "GMI_CPU0_G1_CPU1_G3_TX_DN<4>")
	)
	(arc
		(start 116.100098 -231.524302)
		(mid 116.141353 -231.695273)
		(end 116.256054 -231.828594)
		(width 0.1143)
		(layer "In15.Cu")
		(net "GMI_CPU0_G1_CPU1_G3_TX_DN<4>")
	)
	(arc
		(start 355.168962 -242.518692)
		(mid 354.925635 -242.054126)
		(end 355.168962 -241.58956)
		(width 0.1143)
		(layer "In15.Cu")
		(net "GMI_CPU0_G1_CPU1_G3_TX_DN<4>")
	)
	(arc
		(start 116.256054 -236.080046)
		(mid 116.099929 -236.387615)
		(end 116.261388 -236.69244)
		(width 0.1143)
		(layer "In15.Cu")
		(net "GMI_CPU0_G1_CPU1_G3_TX_DN<4>")
	)
	(arc
		(start 116.569998 -229.094538)
		(mid 116.504762 -229.358129)
		(end 116.324126 -229.560882)
		(width 0.1143)
		(layer "In15.Cu")
		(net "GMI_CPU0_G1_CPU1_G3_TX_DN<4>")
	)
	(arc
		(start 355.238812 -228.589078)
		(mid 355.395789 -228.284278)
		(end 355.238812 -227.979478)
		(width 0.1143)
		(layer "In15.Cu")
		(net "GMI_CPU0_G1_CPU1_G3_TX_DN<4>")
	)
	(arc
		(start 355.169216 -227.938838)
		(mid 354.925889 -227.474272)
		(end 355.169216 -227.009706)
		(width 0.1143)
		(layer "In15.Cu")
		(net "GMI_CPU0_G1_CPU1_G3_TX_DN<4>")
	)
	(arc
		(start 116.302028 -246.435118)
		(mid 116.507481 -246.641473)
		(end 116.582698 -246.922798)
		(width 0.1143)
		(layer "In15.Cu")
		(net "GMI_CPU0_G1_CPU1_G3_TX_DN<4>")
	)
	(arc
		(start 116.256054 -232.840022)
		(mid 116.100126 -233.144314)
		(end 116.256054 -233.448606)
		(width 0.1143)
		(layer "In15.Cu")
		(net "GMI_CPU0_G1_CPU1_G3_TX_DN<4>")
	)
	(arc
		(start 354.229162 -223.078802)
		(mid 354.050349 -222.876452)
		(end 353.98583 -222.614236)
		(width 0.1143)
		(layer "In15.Cu")
		(net "GMI_CPU0_G1_CPU1_G3_TX_DN<4>")
	)
	(arc
		(start 353.985576 -222.614236)
		(mid 354.050091 -222.352017)
		(end 354.228908 -222.14967)
		(width 0.1143)
		(layer "In15.Cu")
		(net "GMI_CPU0_G1_CPU1_G3_TX_DN<4>")
	)
	(arc
		(start 354.229162 -224.698814)
		(mid 353.985835 -224.234248)
		(end 354.229162 -223.769682)
		(width 0.1143)
		(layer "In15.Cu")
		(net "GMI_CPU0_G1_CPU1_G3_TX_DN<4>")
	)
	(arc
		(start 116.287804 -239.946942)
		(mid 116.568451 -240.434368)
		(end 116.287804 -240.921794)
		(width 0.1143)
		(layer "In15.Cu")
		(net "GMI_CPU0_G1_CPU1_G3_TX_DN<4>")
	)
	(arc
		(start 355.168962 -229.55885)
		(mid 354.925635 -229.094284)
		(end 355.168962 -228.629718)
		(width 0.1143)
		(layer "In15.Cu")
		(net "GMI_CPU0_G1_CPU1_G3_TX_DN<4>")
	)
	(arc
		(start 116.256054 -245.800118)
		(mid 116.100126 -246.10441)
		(end 116.256054 -246.408702)
		(width 0.1143)
		(layer "In15.Cu")
		(net "GMI_CPU0_G1_CPU1_G3_TX_DN<4>")
	)
	(arc
		(start 116.100098 -229.90429)
		(mid 116.141353 -230.075261)
		(end 116.256054 -230.208582)
		(width 0.1143)
		(layer "In15.Cu")
		(net "GMI_CPU0_G1_CPU1_G3_TX_DN<4>")
	)
	(arc
		(start 116.34216 -231.880664)
		(mid 116.574413 -232.334488)
		(end 116.34216 -232.788206)
		(width 0.1143)
		(layer "In15.Cu")
		(net "GMI_CPU0_G1_CPU1_G3_TX_DN<4>")
	)
	(arc
		(start 116.348764 -238.365284)
		(mid 116.57879 -238.814356)
		(end 116.348764 -239.263428)
		(width 0.1143)
		(layer "In15.Cu")
		(net "GMI_CPU0_G1_CPU1_G3_TX_DN<4>")
	)
	(arc
		(start 355.239828 -231.82834)
		(mid 355.354504 -231.695006)
		(end 355.395784 -231.524048)
		(width 0.1143)
		(layer "In15.Cu")
		(net "GMI_CPU0_G1_CPU1_G3_TX_DN<4>")
	)
	(arc
		(start 116.337588 -231.171242)
		(mid 116.330893 -231.176118)
		(end 116.324126 -231.180894)
		(width 0.1143)
		(layer "In15.Cu")
		(net "GMI_CPU0_G1_CPU1_G3_TX_DN<4>")
	)
	(arc
		(start 116.256054 -234.460034)
		(mid 116.100126 -234.764326)
		(end 116.256054 -235.068618)
		(width 0.1143)
		(layer "In15.Cu")
		(net "GMI_CPU0_G1_CPU1_G3_TX_DN<4>")
	)
	(arc
		(start 354.443792 -221.898464)
		(mid 354.452747 -221.851726)
		(end 354.45573 -221.80423)
		(width 0.1143)
		(layer "In15.Cu")
		(net "GMI_CPU0_G1_CPU1_G3_TX_DN<4>")
	)
	(arc
		(start 354.925884 -225.85426)
		(mid 354.884629 -225.683289)
		(end 354.769928 -225.549968)
		(width 0.1143)
		(layer "In15.Cu")
		(net "GMI_CPU0_G1_CPU1_G3_TX_DN<4>")
	)
	(arc
		(start 355.239828 -246.408448)
		(mid 355.395756 -246.104156)
		(end 355.239828 -245.799864)
		(width 0.1143)
		(layer "In15.Cu")
		(net "GMI_CPU0_G1_CPU1_G3_TX_DN<4>")
	)
	(arc
		(start 116.099844 -221.804484)
		(mid 116.141099 -221.975455)
		(end 116.2558 -222.108776)
		(width 0.1143)
		(layer "In15.Cu")
		(net "GMI_CPU0_G1_CPU1_G3_TX_DN<4>")
	)
	(arc
		(start 354.699062 -225.50882)
		(mid 354.520249 -225.30647)
		(end 354.45573 -225.044254)
		(width 0.1143)
		(layer "In15.Cu")
		(net "GMI_CPU0_G1_CPU1_G3_TX_DN<4>")
	)
	(arc
		(start 116.287804 -235.086906)
		(mid 116.568451 -235.574332)
		(end 116.287804 -236.061758)
		(width 0.1143)
		(layer "In15.Cu")
		(net "GMI_CPU0_G1_CPU1_G3_TX_DN<4>")
	)
	(arc
		(start 116.354606 -223.789748)
		(mid 116.582606 -224.234502)
		(end 116.354606 -224.679256)
		(width 0.1143)
		(layer "In15.Cu")
		(net "GMI_CPU0_G1_CPU1_G3_TX_DN<4>")
	)
	(arc
		(start 355.168962 -236.038644)
		(mid 354.925635 -235.574078)
		(end 355.168962 -235.109512)
		(width 0.1143)
		(layer "In15.Cu")
		(net "GMI_CPU0_G1_CPU1_G3_TX_DN<4>")
	)
	(arc
		(start 116.346478 -243.223796)
		(mid 116.577107 -243.674392)
		(end 116.346478 -244.124988)
		(width 0.1143)
		(layer "In15.Cu")
		(net "GMI_CPU0_G1_CPU1_G3_TX_DN<4>")
	)
	(arc
		(start 355.239828 -236.688376)
		(mid 355.395756 -236.384084)
		(end 355.239828 -236.079792)
		(width 0.1143)
		(layer "In15.Cu")
		(net "GMI_CPU0_G1_CPU1_G3_TX_DN<4>")
	)
	(arc
		(start 116.256054 -227.98024)
		(mid 116.100126 -228.284532)
		(end 116.256054 -228.588824)
		(width 0.1143)
		(layer "In15.Cu")
		(net "GMI_CPU0_G1_CPU1_G3_TX_DN<4>")
	)
	(arc
		(start 116.256054 -244.180106)
		(mid 116.100126 -244.484398)
		(end 116.256054 -244.78869)
		(width 0.1143)
		(layer "In15.Cu")
		(net "GMI_CPU0_G1_CPU1_G3_TX_DN<4>")
	)
	(arc
		(start 355.168962 -232.79862)
		(mid 354.925635 -232.334054)
		(end 355.168962 -231.869488)
		(width 0.1143)
		(layer "In15.Cu")
		(net "GMI_CPU0_G1_CPU1_G3_TX_DN<4>")
	)
	(arc
		(start 116.288312 -230.227632)
		(mid 116.494534 -230.433276)
		(end 116.569998 -230.71455)
		(width 0.1143)
		(layer "In15.Cu")
		(net "GMI_CPU0_G1_CPU1_G3_TX_DN<4>")
	)
	(arc
		(start 116.35105 -222.167196)
		(mid 116.580261 -222.61467)
		(end 116.35105 -223.062038)
		(width 0.1143)
		(layer "In15.Cu")
		(net "GMI_CPU0_G1_CPU1_G3_TX_DN<4>")
	)
	(arc
		(start 117.030246 -247.618758)
		(mid 117.032269 -247.630168)
		(end 117.034056 -247.641618)
		(width 0.1143)
		(layer "In15.Cu")
		(net "GMI_CPU0_G1_CPU1_G3_TX_DN<4>")
	)
	(arc
		(start 116.287804 -236.706918)
		(mid 116.568451 -237.194344)
		(end 116.287804 -237.68177)
		(width 0.1143)
		(layer "In15.Cu")
		(net "GMI_CPU0_G1_CPU1_G3_TX_DN<4>")
	)
	(arc
		(start 355.238812 -226.969066)
		(mid 355.395789 -226.664266)
		(end 355.238812 -226.359466)
		(width 0.1143)
		(layer "In15.Cu")
		(net "GMI_CPU0_G1_CPU1_G3_TX_DN<4>")
	)
	(arc
		(start 116.256054 -237.700058)
		(mid 116.100126 -238.00435)
		(end 116.256054 -238.308642)
		(width 0.1143)
		(layer "In15.Cu")
		(net "GMI_CPU0_G1_CPU1_G3_TX_DN<4>")
	)
	(arc
		(start 355.239828 -233.448352)
		(mid 355.395756 -233.14406)
		(end 355.239828 -232.839768)
		(width 0.1143)
		(layer "In15.Cu")
		(net "GMI_CPU0_G1_CPU1_G3_TX_DN<4>")
	)
	(arc
		(start 355.395784 -229.904036)
		(mid 355.355022 -229.734152)
		(end 355.241606 -229.601268)
		(width 0.1143)
		(layer "In15.Cu")
		(net "GMI_CPU0_G1_CPU1_G3_TX_DN<4>")
	)
	(arc
		(start 355.168962 -231.178862)
		(mid 354.990149 -230.976512)
		(end 354.92563 -230.714296)
		(width 0.1143)
		(layer "In15.Cu")
		(net "GMI_CPU0_G1_CPU1_G3_TX_DN<4>")
	)
	(arc
		(start 116.343684 -227.021898)
		(mid 116.575434 -227.474526)
		(end 116.343684 -227.927154)
		(width 0.1143)
		(layer "In15.Cu")
		(net "GMI_CPU0_G1_CPU1_G3_TX_DN<4>")
	)
	(arc
		(start 116.254276 -231.221534)
		(mid 116.140869 -231.354423)
		(end 116.100098 -231.524302)
		(width 0.1143)
		(layer "In15.Cu")
		(net "GMI_CPU0_G1_CPU1_G3_TX_DN<4>")
	)
	(arc
		(start 116.256054 -223.120204)
		(mid 116.100126 -223.424496)
		(end 116.256054 -223.728788)
		(width 0.1143)
		(layer "In15.Cu")
		(net "GMI_CPU0_G1_CPU1_G3_TX_DN<4>")
	)
	(arc
		(start 354.298758 -223.729042)
		(mid 354.455735 -223.424242)
		(end 354.298758 -223.119442)
		(width 0.1143)
		(layer "In15.Cu")
		(net "GMI_CPU0_G1_CPU1_G3_TX_DN<4>")
	)
	(arc
		(start 116.287804 -228.607112)
		(mid 116.494427 -228.812891)
		(end 116.569998 -229.094538)
		(width 0.1143)
		(layer "In15.Cu")
		(net "GMI_CPU0_G1_CPU1_G3_TX_DN<4>")
	)
	(arc
		(start 116.254276 -229.601522)
		(mid 116.140869 -229.734411)
		(end 116.100098 -229.90429)
		(width 0.1143)
		(layer "In15.Cu")
		(net "GMI_CPU0_G1_CPU1_G3_TX_DN<4>")
	)
	(arc
		(start 116.33835 -234.410758)
		(mid 116.331276 -234.415765)
		(end 116.324126 -234.420664)
		(width 0.1143)
		(layer "In15.Cu")
		(net "GMI_CPU0_G1_CPU1_G3_TX_DN<4>")
	)
	(arc
		(start 355.239828 -230.208328)
		(mid 355.354504 -230.074994)
		(end 355.395784 -229.904036)
		(width 0.1143)
		(layer "In15.Cu")
		(net "GMI_CPU0_G1_CPU1_G3_TX_DN<4>")
	)
	(arc
		(start 354.45573 -225.044254)
		(mid 354.414181 -224.872832)
		(end 354.298758 -224.739454)
		(width 0.1143)
		(layer "In15.Cu")
		(net "GMI_CPU0_G1_CPU1_G3_TX_DN<4>")
	)
	(arc
		(start 116.893594 -247.344946)
		(mid 116.980816 -247.472424)
		(end 117.030246 -247.618758)
		(width 0.1143)
		(layer "In15.Cu")
		(net "GMI_CPU0_G1_CPU1_G3_TX_DN<4>")
	)
	(arc
		(start 355.239828 -239.9284)
		(mid 355.395756 -239.624108)
		(end 355.239828 -239.319816)
		(width 0.1143)
		(layer "In15.Cu")
		(net "GMI_CPU0_G1_CPU1_G3_TX_DN<4>")
	)
	(arc
		(start 116.256054 -242.560094)
		(mid 116.100126 -242.864386)
		(end 116.256054 -243.168678)
		(width 0.1143)
		(layer "In15.Cu")
		(net "GMI_CPU0_G1_CPU1_G3_TX_DN<4>")
	)
	(arc
		(start 116.344192 -244.841776)
		(mid 116.576471 -245.294404)
		(end 116.344192 -245.747032)
		(width 0.1143)
		(layer "In15.Cu")
		(net "GMI_CPU0_G1_CPU1_G3_TX_DN<4>")
	)
	(arc
		(start 354.92563 -246.914162)
		(mid 354.990145 -246.651943)
		(end 355.168962 -246.449596)
		(width 0.1143)
		(layer "In15.Cu")
		(net "GMI_CPU0_G1_CPU1_G3_TX_DN<4>")
	)
	(arc
		(start 355.395784 -231.524048)
		(mid 355.355022 -231.354164)
		(end 355.241606 -231.22128)
		(width 0.1143)
		(layer "In15.Cu")
		(net "GMI_CPU0_G1_CPU1_G3_TX_DN<4>")
	)
	(arc
		(start 116.324126 -233.487976)
		(mid 116.331275 -233.492876)
		(end 116.33835 -233.497882)
		(width 0.1143)
		(layer "In15.Cu")
		(net "GMI_CPU0_G1_CPU1_G3_TX_DN<4>")
	)
	(arc
		(start 355.239828 -241.548412)
		(mid 355.395756 -241.24412)
		(end 355.239828 -240.939828)
		(width 0.1143)
		(layer "In15.Cu")
		(net "GMI_CPU0_G1_CPU1_G3_TX_DN<4>")
	)
	(segment
		(start 114.597942 -245.560342)
		(end 115.064794 -245.294404)
		(width 0.12954)
		(layer "F.Cu")
		(net "GMI_CPU0_G1_CPU1_G3_TX_DN<3>")
	)
	(segment
		(start 356.89794 -245.560088)
		(end 356.431088 -245.29415)
		(width 0.12954)
		(layer "F.Cu")
		(net "GMI_CPU0_G1_CPU1_G3_TX_DN<3>")
	)
	(segment
		(start 115.348766 -225.367596)
		(end 115.35029 -225.368612)
		(width 0.1143)
		(layer "In15.Cu")
		(net "GMI_CPU0_G1_CPU1_G3_TX_DN<3>")
	)
	(segment
		(start 353.889056 -215.896698)
		(end 353.709986 -215.517984)
		(width 0.14224)
		(layer "In15.Cu")
		(net "GMI_CPU0_G1_CPU1_G3_TX_DN<3>")
	)
	(segment
		(start 354.836476 -217.898726)
		(end 354.657406 -217.520012)
		(width 0.14224)
		(layer "In15.Cu")
		(net "GMI_CPU0_G1_CPU1_G3_TX_DN<3>")
	)
	(segment
		(start 115.34775 -233.466894)
		(end 115.348766 -233.467402)
		(width 0.1143)
		(layer "In15.Cu")
		(net "GMI_CPU0_G1_CPU1_G3_TX_DN<3>")
	)
	(segment
		(start 354.926138 -224.234248)
		(end 354.925884 -224.234248)
		(width 0.1143)
		(layer "In15.Cu")
		(net "GMI_CPU0_G1_CPU1_G3_TX_DN<3>")
	)
	(segment
		(start 356.145592 -236.05998)
		(end 356.142798 -236.058456)
		(width 0.1143)
		(layer "In15.Cu")
		(net "GMI_CPU0_G1_CPU1_G3_TX_DN<3>")
	)
	(segment
		(start 115.35537 -243.191538)
		(end 115.386866 -243.209826)
		(width 0.1143)
		(layer "In15.Cu")
		(net "GMI_CPU0_G1_CPU1_G3_TX_DN<3>")
	)
	(segment
		(start 356.148894 -239.94618)
		(end 356.150164 -239.945418)
		(width 0.1143)
		(layer "In15.Cu")
		(net "GMI_CPU0_G1_CPU1_G3_TX_DN<3>")
	)
	(segment
		(start 115.346988 -223.102424)
		(end 115.345718 -223.103186)
		(width 0.1143)
		(layer "In15.Cu")
		(net "GMI_CPU0_G1_CPU1_G3_TX_DN<3>")
	)
	(segment
		(start 115.346988 -241.566446)
		(end 115.34775 -241.566954)
		(width 0.1143)
		(layer "In15.Cu")
		(net "GMI_CPU0_G1_CPU1_G3_TX_DN<3>")
	)
	(segment
		(start 115.316 -223.728788)
		(end 115.345718 -223.745806)
		(width 0.1143)
		(layer "In15.Cu")
		(net "GMI_CPU0_G1_CPU1_G3_TX_DN<3>")
	)
	(segment
		(start 115.345718 -227.963222)
		(end 115.316 -227.98024)
		(width 0.1143)
		(layer "In15.Cu")
		(net "GMI_CPU0_G1_CPU1_G3_TX_DN<3>")
	)
	(segment
		(start 356.148132 -226.986846)
		(end 356.179882 -226.968558)
		(width 0.1143)
		(layer "In15.Cu")
		(net "GMI_CPU0_G1_CPU1_G3_TX_DN<3>")
	)
	(segment
		(start 115.35537 -238.331502)
		(end 115.386866 -238.34979)
		(width 0.1143)
		(layer "In15.Cu")
		(net "GMI_CPU0_G1_CPU1_G3_TX_DN<3>")
	)
	(segment
		(start 356.145592 -244.16004)
		(end 356.142798 -244.158516)
		(width 0.1143)
		(layer "In15.Cu")
		(net "GMI_CPU0_G1_CPU1_G3_TX_DN<3>")
	)
	(segment
		(start 115.353846 -238.330486)
		(end 115.35537 -238.331502)
		(width 0.1143)
		(layer "In15.Cu")
		(net "GMI_CPU0_G1_CPU1_G3_TX_DN<3>")
	)
	(segment
		(start 115.346988 -243.186458)
		(end 115.34775 -243.186966)
		(width 0.1143)
		(layer "In15.Cu")
		(net "GMI_CPU0_G1_CPU1_G3_TX_DN<3>")
	)
	(segment
		(start 115.34775 -226.34194)
		(end 115.346988 -226.342448)
		(width 0.1143)
		(layer "In15.Cu")
		(net "GMI_CPU0_G1_CPU1_G3_TX_DN<3>")
	)
	(segment
		(start 115.353846 -225.370644)
		(end 115.35537 -225.37166)
		(width 0.1143)
		(layer "In15.Cu")
		(net "GMI_CPU0_G1_CPU1_G3_TX_DN<3>")
	)
	(segment
		(start 356.147116 -243.18722)
		(end 356.148132 -243.186712)
		(width 0.1143)
		(layer "In15.Cu")
		(net "GMI_CPU0_G1_CPU1_G3_TX_DN<3>")
	)
	(segment
		(start 115.34775 -237.68177)
		(end 115.346988 -237.682278)
		(width 0.1143)
		(layer "In15.Cu")
		(net "GMI_CPU0_G1_CPU1_G3_TX_DN<3>")
	)
	(segment
		(start 115.345718 -224.723198)
		(end 115.316 -224.740216)
		(width 0.1143)
		(layer "In15.Cu")
		(net "GMI_CPU0_G1_CPU1_G3_TX_DN<3>")
	)
	(segment
		(start 115.35029 -233.468418)
		(end 115.351306 -233.468926)
		(width 0.1143)
		(layer "In15.Cu")
		(net "GMI_CPU0_G1_CPU1_G3_TX_DN<3>")
	)
	(segment
		(start 116.39296 -215.597232)
		(end 116.181124 -215.958674)
		(width 0.14224)
		(layer "In15.Cu")
		(net "GMI_CPU0_G1_CPU1_G3_TX_DN<3>")
	)
	(segment
		(start 356.145592 -226.340162)
		(end 356.144576 -226.339654)
		(width 0.1143)
		(layer "In15.Cu")
		(net "GMI_CPU0_G1_CPU1_G3_TX_DN<3>")
	)
	(segment
		(start 115.35537 -241.571526)
		(end 115.386866 -241.589814)
		(width 0.1143)
		(layer "In15.Cu")
		(net "GMI_CPU0_G1_CPU1_G3_TX_DN<3>")
	)
	(segment
		(start 115.35029 -228.608636)
		(end 115.351306 -228.609144)
		(width 0.1143)
		(layer "In15.Cu")
		(net "GMI_CPU0_G1_CPU1_G3_TX_DN<3>")
	)
	(segment
		(start 115.34775 -229.581964)
		(end 115.314222 -229.601522)
		(width 0.1143)
		(layer "In15.Cu")
		(net "GMI_CPU0_G1_CPU1_G3_TX_DN<3>")
	)
	(segment
		(start 115.10137 -221.198948)
		(end 115.160044 -221.257622)
		(width 0.1143)
		(layer "In15.Cu")
		(net "GMI_CPU0_G1_CPU1_G3_TX_DN<3>")
	)
	(segment
		(start 115.316 -238.308642)
		(end 115.346988 -238.326422)
		(width 0.1143)
		(layer "In15.Cu")
		(net "GMI_CPU0_G1_CPU1_G3_TX_DN<3>")
	)
	(segment
		(start 356.109016 -243.209572)
		(end 356.147116 -243.18722)
		(width 0.1143)
		(layer "In15.Cu")
		(net "GMI_CPU0_G1_CPU1_G3_TX_DN<3>")
	)
	(segment
		(start 115.345718 -223.103186)
		(end 115.316 -223.120204)
		(width 0.1143)
		(layer "In15.Cu")
		(net "GMI_CPU0_G1_CPU1_G3_TX_DN<3>")
	)
	(segment
		(start 356.109016 -235.109512)
		(end 356.147116 -235.08716)
		(width 0.1143)
		(layer "In15.Cu")
		(net "GMI_CPU0_G1_CPU1_G3_TX_DN<3>")
	)
	(segment
		(start 356.141528 -236.057694)
		(end 356.140004 -236.056678)
		(width 0.1143)
		(layer "In15.Cu")
		(net "GMI_CPU0_G1_CPU1_G3_TX_DN<3>")
	)
	(segment
		(start 356.148132 -236.706664)
		(end 356.148894 -236.706156)
		(width 0.1143)
		(layer "In15.Cu")
		(net "GMI_CPU0_G1_CPU1_G3_TX_DN<3>")
	)
	(segment
		(start 354.657406 -217.520012)
		(end 354.477828 -217.456004)
		(width 0.14224)
		(layer "In15.Cu")
		(net "GMI_CPU0_G1_CPU1_G3_TX_DN<3>")
	)
	(segment
		(start 115.348766 -239.94745)
		(end 115.35029 -239.948466)
		(width 0.1143)
		(layer "In15.Cu")
		(net "GMI_CPU0_G1_CPU1_G3_TX_DN<3>")
	)
	(segment
		(start 356.141528 -242.537742)
		(end 356.140004 -242.536726)
		(width 0.1143)
		(layer "In15.Cu")
		(net "GMI_CPU0_G1_CPU1_G3_TX_DN<3>")
	)
	(segment
		(start 115.34775 -230.22687)
		(end 115.384326 -230.248206)
		(width 0.1143)
		(layer "In15.Cu")
		(net "GMI_CPU0_G1_CPU1_G3_TX_DN<3>")
	)
	(segment
		(start 115.34775 -235.086906)
		(end 115.348766 -235.087414)
		(width 0.1143)
		(layer "In15.Cu")
		(net "GMI_CPU0_G1_CPU1_G3_TX_DN<3>")
	)
	(segment
		(start 355.240082 -223.728534)
		(end 355.260148 -223.714056)
		(width 0.1143)
		(layer "In15.Cu")
		(net "GMI_CPU0_G1_CPU1_G3_TX_DN<3>")
	)
	(segment
		(start 356.147116 -226.341178)
		(end 356.145592 -226.340162)
		(width 0.1143)
		(layer "In15.Cu")
		(net "GMI_CPU0_G1_CPU1_G3_TX_DN<3>")
	)
	(segment
		(start 114.697002 -245.224554)
		(end 114.766852 -245.294404)
		(width 0.1143)
		(layer "In15.Cu")
		(net "GMI_CPU0_G1_CPU1_G3_TX_DN<3>")
	)
	(segment
		(start 115.34775 -223.101916)
		(end 115.346988 -223.102424)
		(width 0.1143)
		(layer "In15.Cu")
		(net "GMI_CPU0_G1_CPU1_G3_TX_DN<3>")
	)
	(segment
		(start 354.927662 -224.258886)
		(end 354.926138 -224.234248)
		(width 0.1143)
		(layer "In15.Cu")
		(net "GMI_CPU0_G1_CPU1_G3_TX_DN<3>")
	)
	(segment
		(start 356.150164 -233.46537)
		(end 356.179882 -233.448352)
		(width 0.1143)
		(layer "In15.Cu")
		(net "GMI_CPU0_G1_CPU1_G3_TX_DN<3>")
	)
	(segment
		(start 355.13137 -218.521026)
		(end 354.951792 -218.457018)
		(width 0.14224)
		(layer "In15.Cu")
		(net "GMI_CPU0_G1_CPU1_G3_TX_DN<3>")
	)
	(segment
		(start 356.179882 -242.55984)
		(end 356.148894 -242.54206)
		(width 0.1143)
		(layer "In15.Cu")
		(net "GMI_CPU0_G1_CPU1_G3_TX_DN<3>")
	)
	(segment
		(start 356.148894 -242.54206)
		(end 356.148132 -242.541552)
		(width 0.1143)
		(layer "In15.Cu")
		(net "GMI_CPU0_G1_CPU1_G3_TX_DN<3>")
	)
	(segment
		(start 115.348766 -243.187474)
		(end 115.35029 -243.18849)
		(width 0.1143)
		(layer "In15.Cu")
		(net "GMI_CPU0_G1_CPU1_G3_TX_DN<3>")
	)
	(segment
		(start 115.34775 -243.186966)
		(end 115.348766 -243.187474)
		(width 0.1143)
		(layer "In15.Cu")
		(net "GMI_CPU0_G1_CPU1_G3_TX_DN<3>")
	)
	(segment
		(start 356.13975 -226.33686)
		(end 356.138226 -226.335844)
		(width 0.1143)
		(layer "In15.Cu")
		(net "GMI_CPU0_G1_CPU1_G3_TX_DN<3>")
	)
	(segment
		(start 356.147116 -238.327184)
		(end 356.148132 -238.326676)
		(width 0.1143)
		(layer "In15.Cu")
		(net "GMI_CPU0_G1_CPU1_G3_TX_DN<3>")
	)
	(segment
		(start 115.345718 -240.923064)
		(end 115.316 -240.940082)
		(width 0.1143)
		(layer "In15.Cu")
		(net "GMI_CPU0_G1_CPU1_G3_TX_DN<3>")
	)
	(segment
		(start 356.140004 -236.056678)
		(end 356.109016 -236.038644)
		(width 0.1143)
		(layer "In15.Cu")
		(net "GMI_CPU0_G1_CPU1_G3_TX_DN<3>")
	)
	(segment
		(start 356.145592 -242.540028)
		(end 356.142798 -242.538504)
		(width 0.1143)
		(layer "In15.Cu")
		(net "GMI_CPU0_G1_CPU1_G3_TX_DN<3>")
	)
	(segment
		(start 115.346988 -238.326422)
		(end 115.34775 -238.32693)
		(width 0.1143)
		(layer "In15.Cu")
		(net "GMI_CPU0_G1_CPU1_G3_TX_DN<3>")
	)
	(segment
		(start 356.140004 -242.536726)
		(end 356.109016 -242.518692)
		(width 0.1143)
		(layer "In15.Cu")
		(net "GMI_CPU0_G1_CPU1_G3_TX_DN<3>")
	)
	(segment
		(start 355.208332 -223.746822)
		(end 355.209094 -223.746314)
		(width 0.1143)
		(layer "In15.Cu")
		(net "GMI_CPU0_G1_CPU1_G3_TX_DN<3>")
	)
	(segment
		(start 356.150164 -239.945418)
		(end 356.179882 -239.9284)
		(width 0.1143)
		(layer "In15.Cu")
		(net "GMI_CPU0_G1_CPU1_G3_TX_DN<3>")
	)
	(segment
		(start 115.351306 -236.70895)
		(end 115.353846 -236.710474)
		(width 0.1143)
		(layer "In15.Cu")
		(net "GMI_CPU0_G1_CPU1_G3_TX_DN<3>")
	)
	(segment
		(start 356.109016 -236.729524)
		(end 356.147116 -236.707172)
		(width 0.1143)
		(layer "In15.Cu")
		(net "GMI_CPU0_G1_CPU1_G3_TX_DN<3>")
	)
	(segment
		(start 356.148132 -235.086652)
		(end 356.148894 -235.086144)
		(width 0.1143)
		(layer "In15.Cu")
		(net "GMI_CPU0_G1_CPU1_G3_TX_DN<3>")
	)
	(segment
		(start 356.147116 -237.681008)
		(end 356.145592 -237.679992)
		(width 0.1143)
		(layer "In15.Cu")
		(net "GMI_CPU0_G1_CPU1_G3_TX_DN<3>")
	)
	(segment
		(start 115.345718 -226.34321)
		(end 115.316 -226.360228)
		(width 0.1143)
		(layer "In15.Cu")
		(net "GMI_CPU0_G1_CPU1_G3_TX_DN<3>")
	)
	(segment
		(start 356.109016 -233.4895)
		(end 356.147116 -233.467148)
		(width 0.1143)
		(layer "In15.Cu")
		(net "GMI_CPU0_G1_CPU1_G3_TX_DN<3>")
	)
	(segment
		(start 115.35537 -236.71149)
		(end 115.386866 -236.729778)
		(width 0.1143)
		(layer "In15.Cu")
		(net "GMI_CPU0_G1_CPU1_G3_TX_DN<3>")
	)
	(segment
		(start 115.14709 -217.721688)
		(end 115.14709 -220.991938)
		(width 0.14224)
		(layer "In15.Cu")
		(net "GMI_CPU0_G1_CPU1_G3_TX_DN<3>")
	)
	(segment
		(start 356.18166 -229.601268)
		(end 356.148132 -229.58171)
		(width 0.1143)
		(layer "In15.Cu")
		(net "GMI_CPU0_G1_CPU1_G3_TX_DN<3>")
	)
	(segment
		(start 351.376742 -210.587844)
		(end 317.22949 -182.588154)
		(width 0.14224)
		(layer "In15.Cu")
		(net "GMI_CPU0_G1_CPU1_G3_TX_DN<3>")
	)
	(segment
		(start 356.148894 -232.821988)
		(end 356.148132 -232.82148)
		(width 0.1143)
		(layer "In15.Cu")
		(net "GMI_CPU0_G1_CPU1_G3_TX_DN<3>")
	)
	(segment
		(start 356.148132 -239.946688)
		(end 356.148894 -239.94618)
		(width 0.1143)
		(layer "In15.Cu")
		(net "GMI_CPU0_G1_CPU1_G3_TX_DN<3>")
	)
	(segment
		(start 115.386866 -236.038898)
		(end 115.348766 -236.06125)
		(width 0.1143)
		(layer "In15.Cu")
		(net "GMI_CPU0_G1_CPU1_G3_TX_DN<3>")
	)
	(segment
		(start 115.35537 -226.991672)
		(end 115.386866 -227.00996)
		(width 0.1143)
		(layer "In15.Cu")
		(net "GMI_CPU0_G1_CPU1_G3_TX_DN<3>")
	)
	(segment
		(start 115.35029 -235.08843)
		(end 115.351306 -235.088938)
		(width 0.1143)
		(layer "In15.Cu")
		(net "GMI_CPU0_G1_CPU1_G3_TX_DN<3>")
	)
	(segment
		(start 356.147116 -232.820972)
		(end 356.145592 -232.819956)
		(width 0.1143)
		(layer "In15.Cu")
		(net "GMI_CPU0_G1_CPU1_G3_TX_DN<3>")
	)
	(segment
		(start 355.386386 -221.38767)
		(end 355.386386 -221.128844)
		(width 0.1143)
		(layer "In15.Cu")
		(net "GMI_CPU0_G1_CPU1_G3_TX_DN<3>")
	)
	(segment
		(start 115.35029 -241.568478)
		(end 115.351306 -241.568986)
		(width 0.1143)
		(layer "In15.Cu")
		(net "GMI_CPU0_G1_CPU1_G3_TX_DN<3>")
	)
	(segment
		(start 115.346988 -240.922302)
		(end 115.345718 -240.923064)
		(width 0.1143)
		(layer "In15.Cu")
		(net "GMI_CPU0_G1_CPU1_G3_TX_DN<3>")
	)
	(segment
		(start 115.34775 -231.846882)
		(end 115.348766 -231.84739)
		(width 0.1143)
		(layer "In15.Cu")
		(net "GMI_CPU0_G1_CPU1_G3_TX_DN<3>")
	)
	(segment
		(start 356.179882 -244.179852)
		(end 356.148894 -244.162072)
		(width 0.1143)
		(layer "In15.Cu")
		(net "GMI_CPU0_G1_CPU1_G3_TX_DN<3>")
	)
	(segment
		(start 356.147116 -227.96119)
		(end 356.109016 -227.938838)
		(width 0.1143)
		(layer "In15.Cu")
		(net "GMI_CPU0_G1_CPU1_G3_TX_DN<3>")
	)
	(segment
		(start 115.348766 -228.60762)
		(end 115.35029 -228.608636)
		(width 0.1143)
		(layer "In15.Cu")
		(net "GMI_CPU0_G1_CPU1_G3_TX_DN<3>")
	)
	(segment
		(start 115.34775 -222.127064)
		(end 115.386866 -222.149924)
		(width 0.1143)
		(layer "In15.Cu")
		(net "GMI_CPU0_G1_CPU1_G3_TX_DN<3>")
	)
	(segment
		(start 355.131116 -218.521026)
		(end 355.13137 -218.521026)
		(width 0.14224)
		(layer "In15.Cu")
		(net "GMI_CPU0_G1_CPU1_G3_TX_DN<3>")
	)
	(segment
		(start 356.148894 -238.326168)
		(end 356.150164 -238.325406)
		(width 0.1143)
		(layer "In15.Cu")
		(net "GMI_CPU0_G1_CPU1_G3_TX_DN<3>")
	)
	(segment
		(start 115.35537 -235.091478)
		(end 115.386866 -235.109766)
		(width 0.1143)
		(layer "In15.Cu")
		(net "GMI_CPU0_G1_CPU1_G3_TX_DN<3>")
	)
	(segment
		(start 356.148894 -236.062012)
		(end 356.148132 -236.061504)
		(width 0.1143)
		(layer "In15.Cu")
		(net "GMI_CPU0_G1_CPU1_G3_TX_DN<3>")
	)
	(segment
		(start 115.34775 -225.367088)
		(end 115.348766 -225.367596)
		(width 0.1143)
		(layer "In15.Cu")
		(net "GMI_CPU0_G1_CPU1_G3_TX_DN<3>")
	)
	(segment
		(start 356.147116 -235.08716)
		(end 356.148132 -235.086652)
		(width 0.1143)
		(layer "In15.Cu")
		(net "GMI_CPU0_G1_CPU1_G3_TX_DN<3>")
	)
	(segment
		(start 356.140004 -244.156738)
		(end 356.109016 -244.138704)
		(width 0.1143)
		(layer "In15.Cu")
		(net "GMI_CPU0_G1_CPU1_G3_TX_DN<3>")
	)
	(segment
		(start 356.140004 -237.67669)
		(end 356.109016 -237.658656)
		(width 0.1143)
		(layer "In15.Cu")
		(net "GMI_CPU0_G1_CPU1_G3_TX_DN<3>")
	)
	(segment
		(start 356.148132 -243.186712)
		(end 356.148894 -243.186204)
		(width 0.1143)
		(layer "In15.Cu")
		(net "GMI_CPU0_G1_CPU1_G3_TX_DN<3>")
	)
	(segment
		(start 356.109016 -239.969548)
		(end 356.147116 -239.947196)
		(width 0.1143)
		(layer "In15.Cu")
		(net "GMI_CPU0_G1_CPU1_G3_TX_DN<3>")
	)
	(segment
		(start 355.260148 -223.134428)
		(end 355.240082 -223.11995)
		(width 0.1143)
		(layer "In15.Cu")
		(net "GMI_CPU0_G1_CPU1_G3_TX_DN<3>")
	)
	(segment
		(start 116.227352 -216.135966)
		(end 116.015262 -216.497662)
		(width 0.14224)
		(layer "In15.Cu")
		(net "GMI_CPU0_G1_CPU1_G3_TX_DN<3>")
	)
	(segment
		(start 354.951792 -218.457018)
		(end 354.772468 -218.07805)
		(width 0.14224)
		(layer "In15.Cu")
		(net "GMI_CPU0_G1_CPU1_G3_TX_DN<3>")
	)
	(segment
		(start 115.346988 -231.846374)
		(end 115.34775 -231.846882)
		(width 0.1143)
		(layer "In15.Cu")
		(net "GMI_CPU0_G1_CPU1_G3_TX_DN<3>")
	)
	(segment
		(start 356.148894 -239.302036)
		(end 356.148132 -239.301528)
		(width 0.1143)
		(layer "In15.Cu")
		(net "GMI_CPU0_G1_CPU1_G3_TX_DN<3>")
	)
	(segment
		(start 115.345718 -237.68304)
		(end 115.316 -237.700058)
		(width 0.1143)
		(layer "In15.Cu")
		(net "GMI_CPU0_G1_CPU1_G3_TX_DN<3>")
	)
	(segment
		(start 356.148894 -231.84612)
		(end 356.150164 -231.845358)
		(width 0.1143)
		(layer "In15.Cu")
		(net "GMI_CPU0_G1_CPU1_G3_TX_DN<3>")
	)
	(segment
		(start 356.140004 -240.916714)
		(end 356.109016 -240.89868)
		(width 0.1143)
		(layer "In15.Cu")
		(net "GMI_CPU0_G1_CPU1_G3_TX_DN<3>")
	)
	(segment
		(start 115.34775 -236.706918)
		(end 115.348766 -236.707426)
		(width 0.1143)
		(layer "In15.Cu")
		(net "GMI_CPU0_G1_CPU1_G3_TX_DN<3>")
	)
	(segment
		(start 354.362766 -216.897712)
		(end 354.183696 -216.518998)
		(width 0.14224)
		(layer "In15.Cu")
		(net "GMI_CPU0_G1_CPU1_G3_TX_DN<3>")
	)
	(segment
		(start 115.351306 -225.36912)
		(end 115.353846 -225.370644)
		(width 0.1143)
		(layer "In15.Cu")
		(net "GMI_CPU0_G1_CPU1_G3_TX_DN<3>")
	)
	(segment
		(start 115.345718 -232.823004)
		(end 115.316 -232.840022)
		(width 0.1143)
		(layer "In15.Cu")
		(net "GMI_CPU0_G1_CPU1_G3_TX_DN<3>")
	)
	(segment
		(start 356.148132 -231.201722)
		(end 356.109016 -231.178862)
		(width 0.1143)
		(layer "In15.Cu")
		(net "GMI_CPU0_G1_CPU1_G3_TX_DN<3>")
	)
	(segment
		(start 354.772468 -218.07805)
		(end 354.836476 -217.898726)
		(width 0.14224)
		(layer "In15.Cu")
		(net "GMI_CPU0_G1_CPU1_G3_TX_DN<3>")
	)
	(segment
		(start 115.346988 -244.162326)
		(end 115.345718 -244.163088)
		(width 0.1143)
		(layer "In15.Cu")
		(net "GMI_CPU0_G1_CPU1_G3_TX_DN<3>")
	)
	(segment
		(start 115.386866 -240.898934)
		(end 115.348766 -240.921286)
		(width 0.1143)
		(layer "In15.Cu")
		(net "GMI_CPU0_G1_CPU1_G3_TX_DN<3>")
	)
	(segment
		(start 115.35537 -231.851454)
		(end 115.386866 -231.869742)
		(width 0.1143)
		(layer "In15.Cu")
		(net "GMI_CPU0_G1_CPU1_G3_TX_DN<3>")
	)
	(segment
		(start 157.369002 -179.99202)
		(end 118.660164 -211.731606)
		(width 0.14224)
		(layer "In15.Cu")
		(net "GMI_CPU0_G1_CPU1_G3_TX_DN<3>")
	)
	(segment
		(start 356.141528 -237.677706)
		(end 356.140004 -237.67669)
		(width 0.1143)
		(layer "In15.Cu")
		(net "GMI_CPU0_G1_CPU1_G3_TX_DN<3>")
	)
	(segment
		(start 115.386866 -227.939092)
		(end 115.348766 -227.961444)
		(width 0.1143)
		(layer "In15.Cu")
		(net "GMI_CPU0_G1_CPU1_G3_TX_DN<3>")
	)
	(segment
		(start 115.14709 -220.991938)
		(end 115.14709 -221.020386)
		(width 0.1143)
		(layer "In15.Cu")
		(net "GMI_CPU0_G1_CPU1_G3_TX_DN<3>")
	)
	(segment
		(start 115.34775 -228.607112)
		(end 115.348766 -228.60762)
		(width 0.1143)
		(layer "In15.Cu")
		(net "GMI_CPU0_G1_CPU1_G3_TX_DN<3>")
	)
	(segment
		(start 356.142798 -244.158516)
		(end 356.141528 -244.157754)
		(width 0.1143)
		(layer "In15.Cu")
		(net "GMI_CPU0_G1_CPU1_G3_TX_DN<3>")
	)
	(segment
		(start 115.348766 -226.987608)
		(end 115.35029 -226.988624)
		(width 0.1143)
		(layer "In15.Cu")
		(net "GMI_CPU0_G1_CPU1_G3_TX_DN<3>")
	)
	(segment
		(start 356.142798 -237.678468)
		(end 356.141528 -237.677706)
		(width 0.1143)
		(layer "In15.Cu")
		(net "GMI_CPU0_G1_CPU1_G3_TX_DN<3>")
	)
	(segment
		(start 115.316 -225.3488)
		(end 115.346988 -225.36658)
		(width 0.1143)
		(layer "In15.Cu")
		(net "GMI_CPU0_G1_CPU1_G3_TX_DN<3>")
	)
	(segment
		(start 115.34775 -224.721928)
		(end 115.346988 -224.722436)
		(width 0.1143)
		(layer "In15.Cu")
		(net "GMI_CPU0_G1_CPU1_G3_TX_DN<3>")
	)
	(segment
		(start 115.35537 -239.951514)
		(end 115.386866 -239.969802)
		(width 0.1143)
		(layer "In15.Cu")
		(net "GMI_CPU0_G1_CPU1_G3_TX_DN<3>")
	)
	(segment
		(start 115.316 -243.168678)
		(end 115.346988 -243.186458)
		(width 0.1143)
		(layer "In15.Cu")
		(net "GMI_CPU0_G1_CPU1_G3_TX_DN<3>")
	)
	(segment
		(start 354.183696 -216.518998)
		(end 354.004118 -216.45499)
		(width 0.14224)
		(layer "In15.Cu")
		(net "GMI_CPU0_G1_CPU1_G3_TX_DN<3>")
	)
	(segment
		(start 115.34775 -238.32693)
		(end 115.348766 -238.327438)
		(width 0.1143)
		(layer "In15.Cu")
		(net "GMI_CPU0_G1_CPU1_G3_TX_DN<3>")
	)
	(segment
		(start 115.316 -233.448606)
		(end 115.346988 -233.466386)
		(width 0.1143)
		(layer "In15.Cu")
		(net "GMI_CPU0_G1_CPU1_G3_TX_DN<3>")
	)
	(segment
		(start 356.148894 -244.162072)
		(end 356.148132 -244.161564)
		(width 0.1143)
		(layer "In15.Cu")
		(net "GMI_CPU0_G1_CPU1_G3_TX_DN<3>")
	)
	(segment
		(start 356.145592 -232.819956)
		(end 356.142798 -232.818432)
		(width 0.1143)
		(layer "In15.Cu")
		(net "GMI_CPU0_G1_CPU1_G3_TX_DN<3>")
	)
	(segment
		(start 356.145592 -237.679992)
		(end 356.142798 -237.678468)
		(width 0.1143)
		(layer "In15.Cu")
		(net "GMI_CPU0_G1_CPU1_G3_TX_DN<3>")
	)
	(segment
		(start 115.14709 -221.020386)
		(end 115.10137 -221.066106)
		(width 0.1143)
		(layer "In15.Cu")
		(net "GMI_CPU0_G1_CPU1_G3_TX_DN<3>")
	)
	(segment
		(start 115.316 -236.68863)
		(end 115.346988 -236.70641)
		(width 0.1143)
		(layer "In15.Cu")
		(net "GMI_CPU0_G1_CPU1_G3_TX_DN<3>")
	)
	(segment
		(start 118.660164 -211.731606)
		(end 116.736368 -215.012016)
		(width 0.14224)
		(layer "In15.Cu")
		(net "GMI_CPU0_G1_CPU1_G3_TX_DN<3>")
	)
	(segment
		(start 355.39553 -221.80423)
		(end 355.395784 -221.804484)
		(width 0.1143)
		(layer "In15.Cu")
		(net "GMI_CPU0_G1_CPU1_G3_TX_DN<3>")
	)
	(segment
		(start 115.348766 -239.301274)
		(end 115.34775 -239.301782)
		(width 0.1143)
		(layer "In15.Cu")
		(net "GMI_CPU0_G1_CPU1_G3_TX_DN<3>")
	)
	(segment
		(start 356.144576 -226.339654)
		(end 356.13975 -226.33686)
		(width 0.1143)
		(layer "In15.Cu")
		(net "GMI_CPU0_G1_CPU1_G3_TX_DN<3>")
	)
	(segment
		(start 115.386866 -231.179116)
		(end 115.34775 -231.201976)
		(width 0.1143)
		(layer "In15.Cu")
		(net "GMI_CPU0_G1_CPU1_G3_TX_DN<3>")
	)
	(segment
		(start 115.348766 -236.06125)
		(end 115.34775 -236.061758)
		(width 0.1143)
		(layer "In15.Cu")
		(net "GMI_CPU0_G1_CPU1_G3_TX_DN<3>")
	)
	(segment
		(start 356.109016 -238.349536)
		(end 356.147116 -238.327184)
		(width 0.1143)
		(layer "In15.Cu")
		(net "GMI_CPU0_G1_CPU1_G3_TX_DN<3>")
	)
	(segment
		(start 115.351306 -238.328962)
		(end 115.353846 -238.330486)
		(width 0.1143)
		(layer "In15.Cu")
		(net "GMI_CPU0_G1_CPU1_G3_TX_DN<3>")
	)
	(segment
		(start 115.386866 -237.65891)
		(end 115.348766 -237.681262)
		(width 0.1143)
		(layer "In15.Cu")
		(net "GMI_CPU0_G1_CPU1_G3_TX_DN<3>")
	)
	(segment
		(start 115.386866 -232.798874)
		(end 115.348766 -232.821226)
		(width 0.1143)
		(layer "In15.Cu")
		(net "GMI_CPU0_G1_CPU1_G3_TX_DN<3>")
	)
	(segment
		(start 355.212904 -223.744028)
		(end 355.240082 -223.728534)
		(width 0.1143)
		(layer "In15.Cu")
		(net "GMI_CPU0_G1_CPU1_G3_TX_DN<3>")
	)
	(segment
		(start 115.346988 -226.986592)
		(end 115.34775 -226.9871)
		(width 0.1143)
		(layer "In15.Cu")
		(net "GMI_CPU0_G1_CPU1_G3_TX_DN<3>")
	)
	(segment
		(start 356.147116 -242.541044)
		(end 356.145592 -242.540028)
		(width 0.1143)
		(layer "In15.Cu")
		(net "GMI_CPU0_G1_CPU1_G3_TX_DN<3>")
	)
	(segment
		(start 115.160044 -221.257622)
		(end 115.160044 -221.804484)
		(width 0.1143)
		(layer "In15.Cu")
		(net "GMI_CPU0_G1_CPU1_G3_TX_DN<3>")
	)
	(segment
		(start 353.056698 -214.452962)
		(end 352.877374 -214.07374)
		(width 0.14224)
		(layer "In15.Cu")
		(net "GMI_CPU0_G1_CPU1_G3_TX_DN<3>")
	)
	(segment
		(start 355.708712 -225.54946)
		(end 355.678232 -225.53168)
		(width 0.1143)
		(layer "In15.Cu")
		(net "GMI_CPU0_G1_CPU1_G3_TX_DN<3>")
	)
	(segment
		(start 115.346988 -223.746568)
		(end 115.34775 -223.747076)
		(width 0.1143)
		(layer "In15.Cu")
		(net "GMI_CPU0_G1_CPU1_G3_TX_DN<3>")
	)
	(segment
		(start 356.140004 -234.436666)
		(end 356.109016 -234.418632)
		(width 0.1143)
		(layer "In15.Cu")
		(net "GMI_CPU0_G1_CPU1_G3_TX_DN<3>")
	)
	(segment
		(start 356.147116 -240.921032)
		(end 356.145592 -240.920016)
		(width 0.1143)
		(layer "In15.Cu")
		(net "GMI_CPU0_G1_CPU1_G3_TX_DN<3>")
	)
	(segment
		(start 355.17709 -223.083628)
		(end 355.170486 -223.079818)
		(width 0.1143)
		(layer "In15.Cu")
		(net "GMI_CPU0_G1_CPU1_G3_TX_DN<3>")
	)
	(segment
		(start 115.346988 -234.442254)
		(end 115.345718 -234.443016)
		(width 0.1143)
		(layer "In15.Cu")
		(net "GMI_CPU0_G1_CPU1_G3_TX_DN<3>")
	)
	(segment
		(start 353.709986 -215.517984)
		(end 353.530408 -215.453976)
		(width 0.14224)
		(layer "In15.Cu")
		(net "GMI_CPU0_G1_CPU1_G3_TX_DN<3>")
	)
	(segment
		(start 356.148894 -240.922048)
		(end 356.148132 -240.92154)
		(width 0.1143)
		(layer "In15.Cu")
		(net "GMI_CPU0_G1_CPU1_G3_TX_DN<3>")
	)
	(segment
		(start 115.353846 -235.090462)
		(end 115.35537 -235.091478)
		(width 0.1143)
		(layer "In15.Cu")
		(net "GMI_CPU0_G1_CPU1_G3_TX_DN<3>")
	)
	(segment
		(start 356.148132 -244.161564)
		(end 356.147116 -244.161056)
		(width 0.1143)
		(layer "In15.Cu")
		(net "GMI_CPU0_G1_CPU1_G3_TX_DN<3>")
	)
	(segment
		(start 317.22949 -182.588154)
		(end 310.47563 -178.764946)
		(width 0.14224)
		(layer "In15.Cu")
		(net "GMI_CPU0_G1_CPU1_G3_TX_DN<3>")
	)
	(segment
		(start 115.386866 -224.699068)
		(end 115.348766 -224.72142)
		(width 0.1143)
		(layer "In15.Cu")
		(net "GMI_CPU0_G1_CPU1_G3_TX_DN<3>")
	)
	(segment
		(start 115.348766 -241.567462)
		(end 115.35029 -241.568478)
		(width 0.1143)
		(layer "In15.Cu")
		(net "GMI_CPU0_G1_CPU1_G3_TX_DN<3>")
	)
	(segment
		(start 115.348766 -242.541298)
		(end 115.34775 -242.541806)
		(width 0.1143)
		(layer "In15.Cu")
		(net "GMI_CPU0_G1_CPU1_G3_TX_DN<3>")
	)
	(segment
		(start 308.042564 -177.894996)
		(end 302.91024 -177.894996)
		(width 0.14224)
		(layer "In15.Cu")
		(net "GMI_CPU0_G1_CPU1_G3_TX_DN<3>")
	)
	(segment
		(start 356.147116 -233.467148)
		(end 356.148132 -233.46664)
		(width 0.1143)
		(layer "In15.Cu")
		(net "GMI_CPU0_G1_CPU1_G3_TX_DN<3>")
	)
	(segment
		(start 116.181124 -215.958674)
		(end 116.227352 -216.135966)
		(width 0.14224)
		(layer "In15.Cu")
		(net "GMI_CPU0_G1_CPU1_G3_TX_DN<3>")
	)
	(segment
		(start 356.142798 -234.438444)
		(end 356.141528 -234.437682)
		(width 0.1143)
		(layer "In15.Cu")
		(net "GMI_CPU0_G1_CPU1_G3_TX_DN<3>")
	)
	(segment
		(start 352.941636 -213.89467)
		(end 352.762566 -213.515956)
		(width 0.14224)
		(layer "In15.Cu")
		(net "GMI_CPU0_G1_CPU1_G3_TX_DN<3>")
	)
	(segment
		(start 355.340666 -221.083124)
		(end 355.340666 -218.963748)
		(width 0.14224)
		(layer "In15.Cu")
		(net "GMI_CPU0_G1_CPU1_G3_TX_DN<3>")
	)
	(segment
		(start 115.353846 -226.990656)
		(end 115.35537 -226.991672)
		(width 0.1143)
		(layer "In15.Cu")
		(net "GMI_CPU0_G1_CPU1_G3_TX_DN<3>")
	)
	(segment
		(start 115.348766 -226.341432)
		(end 115.34775 -226.34194)
		(width 0.1143)
		(layer "In15.Cu")
		(net "GMI_CPU0_G1_CPU1_G3_TX_DN<3>")
	)
	(segment
		(start 115.34775 -239.301782)
		(end 115.316 -239.32007)
		(width 0.1143)
		(layer "In15.Cu")
		(net "GMI_CPU0_G1_CPU1_G3_TX_DN<3>")
	)
	(segment
		(start 115.351306 -239.948974)
		(end 115.353846 -239.950498)
		(width 0.1143)
		(layer "In15.Cu")
		(net "GMI_CPU0_G1_CPU1_G3_TX_DN<3>")
	)
	(segment
		(start 356.148132 -241.5667)
		(end 356.148894 -241.566192)
		(width 0.1143)
		(layer "In15.Cu")
		(net "GMI_CPU0_G1_CPU1_G3_TX_DN<3>")
	)
	(segment
		(start 115.348766 -232.821226)
		(end 115.34775 -232.821734)
		(width 0.1143)
		(layer "In15.Cu")
		(net "GMI_CPU0_G1_CPU1_G3_TX_DN<3>")
	)
	(segment
		(start 356.147116 -236.707172)
		(end 356.148132 -236.706664)
		(width 0.1143)
		(layer "In15.Cu")
		(net "GMI_CPU0_G1_CPU1_G3_TX_DN<3>")
	)
	(segment
		(start 115.345718 -234.443016)
		(end 115.316 -234.460034)
		(width 0.1143)
		(layer "In15.Cu")
		(net "GMI_CPU0_G1_CPU1_G3_TX_DN<3>")
	)
	(segment
		(start 356.142798 -236.058456)
		(end 356.141528 -236.057694)
		(width 0.1143)
		(layer "In15.Cu")
		(net "GMI_CPU0_G1_CPU1_G3_TX_DN<3>")
	)
	(segment
		(start 356.147116 -228.607366)
		(end 356.148132 -228.606858)
		(width 0.1143)
		(layer "In15.Cu")
		(net "GMI_CPU0_G1_CPU1_G3_TX_DN<3>")
	)
	(segment
		(start 115.837716 -216.54389)
		(end 115.14709 -217.721688)
		(width 0.14224)
		(layer "In15.Cu")
		(net "GMI_CPU0_G1_CPU1_G3_TX_DN<3>")
	)
	(segment
		(start 356.148132 -231.846628)
		(end 356.148894 -231.84612)
		(width 0.1143)
		(layer "In15.Cu")
		(net "GMI_CPU0_G1_CPU1_G3_TX_DN<3>")
	)
	(segment
		(start 115.348766 -227.961444)
		(end 115.34775 -227.961952)
		(width 0.1143)
		(layer "In15.Cu")
		(net "GMI_CPU0_G1_CPU1_G3_TX_DN<3>")
	)
	(segment
		(start 115.386866 -223.079056)
		(end 115.348766 -223.101408)
		(width 0.1143)
		(layer "In15.Cu")
		(net "GMI_CPU0_G1_CPU1_G3_TX_DN<3>")
	)
	(segment
		(start 165.477698 -177.09261)
		(end 157.369002 -179.99202)
		(width 0.14224)
		(layer "In15.Cu")
		(net "GMI_CPU0_G1_CPU1_G3_TX_DN<3>")
	)
	(segment
		(start 353.530408 -215.453976)
		(end 353.351084 -215.074754)
		(width 0.14224)
		(layer "In15.Cu")
		(net "GMI_CPU0_G1_CPU1_G3_TX_DN<3>")
	)
	(segment
		(start 115.348766 -236.707426)
		(end 115.35029 -236.708442)
		(width 0.1143)
		(layer "In15.Cu")
		(net "GMI_CPU0_G1_CPU1_G3_TX_DN<3>")
	)
	(segment
		(start 353.236276 -214.51697)
		(end 353.056698 -214.452962)
		(width 0.14224)
		(layer "In15.Cu")
		(net "GMI_CPU0_G1_CPU1_G3_TX_DN<3>")
	)
	(segment
		(start 352.582988 -213.451948)
		(end 352.403664 -213.072726)
		(width 0.14224)
		(layer "In15.Cu")
		(net "GMI_CPU0_G1_CPU1_G3_TX_DN<3>")
	)
	(segment
		(start 115.348766 -238.327438)
		(end 115.35029 -238.328454)
		(width 0.1143)
		(layer "In15.Cu")
		(net "GMI_CPU0_G1_CPU1_G3_TX_DN<3>")
	)
	(segment
		(start 355.177852 -223.084136)
		(end 355.17709 -223.083628)
		(width 0.1143)
		(layer "In15.Cu")
		(net "GMI_CPU0_G1_CPU1_G3_TX_DN<3>")
	)
	(segment
		(start 356.148132 -226.341686)
		(end 356.147116 -226.341178)
		(width 0.1143)
		(layer "In15.Cu")
		(net "GMI_CPU0_G1_CPU1_G3_TX_DN<3>")
	)
	(segment
		(start 115.351306 -241.568986)
		(end 115.353846 -241.57051)
		(width 0.1143)
		(layer "In15.Cu")
		(net "GMI_CPU0_G1_CPU1_G3_TX_DN<3>")
	)
	(segment
		(start 115.351306 -228.609144)
		(end 115.353846 -228.610668)
		(width 0.1143)
		(layer "In15.Cu")
		(net "GMI_CPU0_G1_CPU1_G3_TX_DN<3>")
	)
	(segment
		(start 115.316 -226.968812)
		(end 115.346988 -226.986592)
		(width 0.1143)
		(layer "In15.Cu")
		(net "GMI_CPU0_G1_CPU1_G3_TX_DN<3>")
	)
	(segment
		(start 356.148894 -233.466132)
		(end 356.150164 -233.46537)
		(width 0.1143)
		(layer "In15.Cu")
		(net "GMI_CPU0_G1_CPU1_G3_TX_DN<3>")
	)
	(segment
		(start 355.340412 -218.963748)
		(end 355.131116 -218.521026)
		(width 0.14224)
		(layer "In15.Cu")
		(net "GMI_CPU0_G1_CPU1_G3_TX_DN<3>")
	)
	(segment
		(start 356.148132 -242.541552)
		(end 356.147116 -242.541044)
		(width 0.1143)
		(layer "In15.Cu")
		(net "GMI_CPU0_G1_CPU1_G3_TX_DN<3>")
	)
	(segment
		(start 356.648766 -244.98935)
		(end 356.618286 -244.97157)
		(width 0.1143)
		(layer "In15.Cu")
		(net "GMI_CPU0_G1_CPU1_G3_TX_DN<3>")
	)
	(segment
		(start 356.141528 -244.157754)
		(end 356.140004 -244.156738)
		(width 0.1143)
		(layer "In15.Cu")
		(net "GMI_CPU0_G1_CPU1_G3_TX_DN<3>")
	)
	(segment
		(start 356.145592 -239.300004)
		(end 356.142798 -239.29848)
		(width 0.1143)
		(layer "In15.Cu")
		(net "GMI_CPU0_G1_CPU1_G3_TX_DN<3>")
	)
	(segment
		(start 115.346988 -227.96246)
		(end 115.345718 -227.963222)
		(width 0.1143)
		(layer "In15.Cu")
		(net "GMI_CPU0_G1_CPU1_G3_TX_DN<3>")
	)
	(segment
		(start 354.298504 -217.076782)
		(end 354.362766 -216.897712)
		(width 0.14224)
		(layer "In15.Cu")
		(net "GMI_CPU0_G1_CPU1_G3_TX_DN<3>")
	)
	(segment
		(start 115.35029 -239.948466)
		(end 115.351306 -239.948974)
		(width 0.1143)
		(layer "In15.Cu")
		(net "GMI_CPU0_G1_CPU1_G3_TX_DN<3>")
	)
	(segment
		(start 355.395784 -221.804484)
		(end 355.395784 -221.397068)
		(width 0.1143)
		(layer "In15.Cu")
		(net "GMI_CPU0_G1_CPU1_G3_TX_DN<3>")
	)
	(segment
		(start 115.351306 -243.188998)
		(end 115.353846 -243.190522)
		(width 0.1143)
		(layer "In15.Cu")
		(net "GMI_CPU0_G1_CPU1_G3_TX_DN<3>")
	)
	(segment
		(start 115.346988 -228.606604)
		(end 115.34775 -228.607112)
		(width 0.1143)
		(layer "In15.Cu")
		(net "GMI_CPU0_G1_CPU1_G3_TX_DN<3>")
	)
	(segment
		(start 354.477828 -217.456004)
		(end 354.298504 -217.076782)
		(width 0.14224)
		(layer "In15.Cu")
		(net "GMI_CPU0_G1_CPU1_G3_TX_DN<3>")
	)
	(segment
		(start 115.34775 -227.961952)
		(end 115.346988 -227.96246)
		(width 0.1143)
		(layer "In15.Cu")
		(net "GMI_CPU0_G1_CPU1_G3_TX_DN<3>")
	)
	(segment
		(start 116.015262 -216.497662)
		(end 115.837716 -216.54389)
		(width 0.14224)
		(layer "In15.Cu")
		(net "GMI_CPU0_G1_CPU1_G3_TX_DN<3>")
	)
	(segment
		(start 115.348766 -223.101408)
		(end 115.34775 -223.101916)
		(width 0.1143)
		(layer "In15.Cu")
		(net "GMI_CPU0_G1_CPU1_G3_TX_DN<3>")
	)
	(segment
		(start 356.151688 -226.343718)
		(end 356.148894 -226.342194)
		(width 0.1143)
		(layer "In15.Cu")
		(net "GMI_CPU0_G1_CPU1_G3_TX_DN<3>")
	)
	(segment
		(start 356.179882 -234.45978)
		(end 356.148894 -234.442)
		(width 0.1143)
		(layer "In15.Cu")
		(net "GMI_CPU0_G1_CPU1_G3_TX_DN<3>")
	)
	(segment
		(start 115.351306 -233.468926)
		(end 115.353846 -233.47045)
		(width 0.1143)
		(layer "In15.Cu")
		(net "GMI_CPU0_G1_CPU1_G3_TX_DN<3>")
	)
	(segment
		(start 356.431088 -245.29415)
		(end 356.72903 -245.29415)
		(width 0.1143)
		(layer "In15.Cu")
		(net "GMI_CPU0_G1_CPU1_G3_TX_DN<3>")
	)
	(segment
		(start 115.348766 -240.921286)
		(end 115.34775 -240.921794)
		(width 0.1143)
		(layer "In15.Cu")
		(net "GMI_CPU0_G1_CPU1_G3_TX_DN<3>")
	)
	(segment
		(start 115.348766 -224.72142)
		(end 115.34775 -224.721928)
		(width 0.1143)
		(layer "In15.Cu")
		(net "GMI_CPU0_G1_CPU1_G3_TX_DN<3>")
	)
	(segment
		(start 115.351306 -235.088938)
		(end 115.353846 -235.090462)
		(width 0.1143)
		(layer "In15.Cu")
		(net "GMI_CPU0_G1_CPU1_G3_TX_DN<3>")
	)
	(segment
		(start 115.35537 -225.37166)
		(end 115.386866 -225.389948)
		(width 0.1143)
		(layer "In15.Cu")
		(net "GMI_CPU0_G1_CPU1_G3_TX_DN<3>")
	)
	(segment
		(start 115.351306 -231.848914)
		(end 115.353846 -231.850438)
		(width 0.1143)
		(layer "In15.Cu")
		(net "GMI_CPU0_G1_CPU1_G3_TX_DN<3>")
	)
	(segment
		(start 356.148894 -243.186204)
		(end 356.150164 -243.185442)
		(width 0.1143)
		(layer "In15.Cu")
		(net "GMI_CPU0_G1_CPU1_G3_TX_DN<3>")
	)
	(segment
		(start 115.346988 -235.086398)
		(end 115.34775 -235.086906)
		(width 0.1143)
		(layer "In15.Cu")
		(net "GMI_CPU0_G1_CPU1_G3_TX_DN<3>")
	)
	(segment
		(start 352.467926 -212.893656)
		(end 351.376742 -210.587844)
		(width 0.14224)
		(layer "In15.Cu")
		(net "GMI_CPU0_G1_CPU1_G3_TX_DN<3>")
	)
	(segment
		(start 356.148132 -230.226616)
		(end 356.179882 -230.208328)
		(width 0.1143)
		(layer "In15.Cu")
		(net "GMI_CPU0_G1_CPU1_G3_TX_DN<3>")
	)
	(segment
		(start 355.395784 -221.397068)
		(end 355.386386 -221.38767)
		(width 0.1143)
		(layer "In15.Cu")
		(net "GMI_CPU0_G1_CPU1_G3_TX_DN<3>")
	)
	(segment
		(start 356.140004 -239.296702)
		(end 356.109016 -239.278668)
		(width 0.1143)
		(layer "In15.Cu")
		(net "GMI_CPU0_G1_CPU1_G3_TX_DN<3>")
	)
	(segment
		(start 115.353846 -233.47045)
		(end 115.35537 -233.471466)
		(width 0.1143)
		(layer "In15.Cu")
		(net "GMI_CPU0_G1_CPU1_G3_TX_DN<3>")
	)
	(segment
		(start 356.179882 -232.839768)
		(end 356.148894 -232.821988)
		(width 0.1143)
		(layer "In15.Cu")
		(net "GMI_CPU0_G1_CPU1_G3_TX_DN<3>")
	)
	(segment
		(start 115.35029 -243.18849)
		(end 115.351306 -243.188998)
		(width 0.1143)
		(layer "In15.Cu")
		(net "GMI_CPU0_G1_CPU1_G3_TX_DN<3>")
	)
	(segment
		(start 115.345718 -242.543076)
		(end 115.316 -242.560094)
		(width 0.1143)
		(layer "In15.Cu")
		(net "GMI_CPU0_G1_CPU1_G3_TX_DN<3>")
	)
	(segment
		(start 115.348766 -223.747584)
		(end 115.386866 -223.769936)
		(width 0.1143)
		(layer "In15.Cu")
		(net "GMI_CPU0_G1_CPU1_G3_TX_DN<3>")
	)
	(segment
		(start 356.141528 -239.297718)
		(end 356.140004 -239.296702)
		(width 0.1143)
		(layer "In15.Cu")
		(net "GMI_CPU0_G1_CPU1_G3_TX_DN<3>")
	)
	(segment
		(start 115.348766 -231.84739)
		(end 115.35029 -231.848406)
		(width 0.1143)
		(layer "In15.Cu")
		(net "GMI_CPU0_G1_CPU1_G3_TX_DN<3>")
	)
	(segment
		(start 115.348766 -233.467402)
		(end 115.35029 -233.468418)
		(width 0.1143)
		(layer "In15.Cu")
		(net "GMI_CPU0_G1_CPU1_G3_TX_DN<3>")
	)
	(segment
		(start 356.154228 -226.345242)
		(end 356.153466 -226.344734)
		(width 0.1143)
		(layer "In15.Cu")
		(net "GMI_CPU0_G1_CPU1_G3_TX_DN<3>")
	)
	(segment
		(start 356.150164 -235.085382)
		(end 356.179882 -235.068364)
		(width 0.1143)
		(layer "In15.Cu")
		(net "GMI_CPU0_G1_CPU1_G3_TX_DN<3>")
	)
	(segment
		(start 115.351306 -226.989132)
		(end 115.353846 -226.990656)
		(width 0.1143)
		(layer "In15.Cu")
		(net "GMI_CPU0_G1_CPU1_G3_TX_DN<3>")
	)
	(segment
		(start 356.147116 -241.567208)
		(end 356.148132 -241.5667)
		(width 0.1143)
		(layer "In15.Cu")
		(net "GMI_CPU0_G1_CPU1_G3_TX_DN<3>")
	)
	(segment
		(start 356.148132 -232.82148)
		(end 356.147116 -232.820972)
		(width 0.1143)
		(layer "In15.Cu")
		(net "GMI_CPU0_G1_CPU1_G3_TX_DN<3>")
	)
	(segment
		(start 115.346988 -233.466386)
		(end 115.34775 -233.466894)
		(width 0.1143)
		(layer "In15.Cu")
		(net "GMI_CPU0_G1_CPU1_G3_TX_DN<3>")
	)
	(segment
		(start 115.34775 -232.821734)
		(end 115.346988 -232.822242)
		(width 0.1143)
		(layer "In15.Cu")
		(net "GMI_CPU0_G1_CPU1_G3_TX_DN<3>")
	)
	(segment
		(start 115.386866 -226.31908)
		(end 115.348766 -226.341432)
		(width 0.1143)
		(layer "In15.Cu")
		(net "GMI_CPU0_G1_CPU1_G3_TX_DN<3>")
	)
	(segment
		(start 115.316 -230.208582)
		(end 115.34775 -230.22687)
		(width 0.1143)
		(layer "In15.Cu")
		(net "GMI_CPU0_G1_CPU1_G3_TX_DN<3>")
	)
	(segment
		(start 115.348766 -244.16131)
		(end 115.34775 -244.161818)
		(width 0.1143)
		(layer "In15.Cu")
		(net "GMI_CPU0_G1_CPU1_G3_TX_DN<3>")
	)
	(segment
		(start 356.148132 -236.061504)
		(end 356.147116 -236.060996)
		(width 0.1143)
		(layer "In15.Cu")
		(net "GMI_CPU0_G1_CPU1_G3_TX_DN<3>")
	)
	(segment
		(start 356.179882 -227.979986)
		(end 356.148894 -227.962206)
		(width 0.1143)
		(layer "In15.Cu")
		(net "GMI_CPU0_G1_CPU1_G3_TX_DN<3>")
	)
	(segment
		(start 356.179882 -240.939828)
		(end 356.148894 -240.922048)
		(width 0.1143)
		(layer "In15.Cu")
		(net "GMI_CPU0_G1_CPU1_G3_TX_DN<3>")
	)
	(segment
		(start 356.145592 -234.439968)
		(end 356.142798 -234.438444)
		(width 0.1143)
		(layer "In15.Cu")
		(net "GMI_CPU0_G1_CPU1_G3_TX_DN<3>")
	)
	(segment
		(start 115.345718 -236.063028)
		(end 115.316 -236.080046)
		(width 0.1143)
		(layer "In15.Cu")
		(net "GMI_CPU0_G1_CPU1_G3_TX_DN<3>")
	)
	(segment
		(start 356.18166 -231.22128)
		(end 356.148132 -231.201722)
		(width 0.1143)
		(layer "In15.Cu")
		(net "GMI_CPU0_G1_CPU1_G3_TX_DN<3>")
	)
	(segment
		(start 355.340666 -218.963748)
		(end 355.340412 -218.963748)
		(width 0.14224)
		(layer "In15.Cu")
		(net "GMI_CPU0_G1_CPU1_G3_TX_DN<3>")
	)
	(segment
		(start 115.316 -239.928654)
		(end 115.346988 -239.946434)
		(width 0.1143)
		(layer "In15.Cu")
		(net "GMI_CPU0_G1_CPU1_G3_TX_DN<3>")
	)
	(segment
		(start 356.142798 -242.538504)
		(end 356.141528 -242.537742)
		(width 0.1143)
		(layer "In15.Cu")
		(net "GMI_CPU0_G1_CPU1_G3_TX_DN<3>")
	)
	(segment
		(start 115.316 -235.068618)
		(end 115.346988 -235.086398)
		(width 0.1143)
		(layer "In15.Cu")
		(net "GMI_CPU0_G1_CPU1_G3_TX_DN<3>")
	)
	(segment
		(start 356.148894 -234.442)
		(end 356.148132 -234.441492)
		(width 0.1143)
		(layer "In15.Cu")
		(net "GMI_CPU0_G1_CPU1_G3_TX_DN<3>")
	)
	(segment
		(start 356.147116 -244.161056)
		(end 356.145592 -244.16004)
		(width 0.1143)
		(layer "In15.Cu")
		(net "GMI_CPU0_G1_CPU1_G3_TX_DN<3>")
	)
	(segment
		(start 302.91024 -177.894996)
		(end 165.477698 -177.09261)
		(width 0.14224)
		(layer "In15.Cu")
		(net "GMI_CPU0_G1_CPU1_G3_TX_DN<3>")
	)
	(segment
		(start 115.34775 -234.441746)
		(end 115.346988 -234.442254)
		(width 0.1143)
		(layer "In15.Cu")
		(net "GMI_CPU0_G1_CPU1_G3_TX_DN<3>")
	)
	(segment
		(start 356.147116 -231.847136)
		(end 356.148132 -231.846628)
		(width 0.1143)
		(layer "In15.Cu")
		(net "GMI_CPU0_G1_CPU1_G3_TX_DN<3>")
	)
	(segment
		(start 354.004118 -216.45499)
		(end 353.824794 -216.075768)
		(width 0.14224)
		(layer "In15.Cu")
		(net "GMI_CPU0_G1_CPU1_G3_TX_DN<3>")
	)
	(segment
		(start 356.148132 -233.46664)
		(end 356.148894 -233.466132)
		(width 0.1143)
		(layer "In15.Cu")
		(net "GMI_CPU0_G1_CPU1_G3_TX_DN<3>")
	)
	(segment
		(start 115.353846 -241.57051)
		(end 115.35537 -241.571526)
		(width 0.1143)
		(layer "In15.Cu")
		(net "GMI_CPU0_G1_CPU1_G3_TX_DN<3>")
	)
	(segment
		(start 356.148132 -228.606858)
		(end 356.148894 -228.60635)
		(width 0.1143)
		(layer "In15.Cu")
		(net "GMI_CPU0_G1_CPU1_G3_TX_DN<3>")
	)
	(segment
		(start 115.34775 -226.9871)
		(end 115.348766 -226.987608)
		(width 0.1143)
		(layer "In15.Cu")
		(net "GMI_CPU0_G1_CPU1_G3_TX_DN<3>")
	)
	(segment
		(start 356.148132 -238.326676)
		(end 356.148894 -238.326168)
		(width 0.1143)
		(layer "In15.Cu")
		(net "GMI_CPU0_G1_CPU1_G3_TX_DN<3>")
	)
	(segment
		(start 356.179882 -226.359974)
		(end 356.155752 -226.346004)
		(width 0.1143)
		(layer "In15.Cu")
		(net "GMI_CPU0_G1_CPU1_G3_TX_DN<3>")
	)
	(segment
		(start 356.147116 -239.947196)
		(end 356.148132 -239.946688)
		(width 0.1143)
		(layer "In15.Cu")
		(net "GMI_CPU0_G1_CPU1_G3_TX_DN<3>")
	)
	(segment
		(start 115.34775 -244.161818)
		(end 115.346988 -244.162326)
		(width 0.1143)
		(layer "In15.Cu")
		(net "GMI_CPU0_G1_CPU1_G3_TX_DN<3>")
	)
	(segment
		(start 356.138226 -226.335844)
		(end 356.109016 -226.318826)
		(width 0.1143)
		(layer "In15.Cu")
		(net "GMI_CPU0_G1_CPU1_G3_TX_DN<3>")
	)
	(segment
		(start 356.148894 -241.566192)
		(end 356.150164 -241.56543)
		(width 0.1143)
		(layer "In15.Cu")
		(net "GMI_CPU0_G1_CPU1_G3_TX_DN<3>")
	)
	(segment
		(start 356.141528 -234.437682)
		(end 356.140004 -234.436666)
		(width 0.1143)
		(layer "In15.Cu")
		(net "GMI_CPU0_G1_CPU1_G3_TX_DN<3>")
	)
	(segment
		(start 115.34775 -231.201976)
		(end 115.314222 -231.221534)
		(width 0.1143)
		(layer "In15.Cu")
		(net "GMI_CPU0_G1_CPU1_G3_TX_DN<3>")
	)
	(segment
		(start 356.109016 -227.009706)
		(end 356.148132 -226.986846)
		(width 0.1143)
		(layer "In15.Cu")
		(net "GMI_CPU0_G1_CPU1_G3_TX_DN<3>")
	)
	(segment
		(start 356.111556 -230.247952)
		(end 356.148132 -230.226616)
		(width 0.1143)
		(layer "In15.Cu")
		(net "GMI_CPU0_G1_CPU1_G3_TX_DN<3>")
	)
	(segment
		(start 115.35537 -233.471466)
		(end 115.386866 -233.489754)
		(width 0.1143)
		(layer "In15.Cu")
		(net "GMI_CPU0_G1_CPU1_G3_TX_DN<3>")
	)
	(segment
		(start 115.34775 -242.541806)
		(end 115.346988 -242.542314)
		(width 0.1143)
		(layer "In15.Cu")
		(net "GMI_CPU0_G1_CPU1_G3_TX_DN<3>")
	)
	(segment
		(start 356.148894 -235.086144)
		(end 356.150164 -235.085382)
		(width 0.1143)
		(layer "In15.Cu")
		(net "GMI_CPU0_G1_CPU1_G3_TX_DN<3>")
	)
	(segment
		(start 115.35029 -238.328454)
		(end 115.351306 -238.328962)
		(width 0.1143)
		(layer "In15.Cu")
		(net "GMI_CPU0_G1_CPU1_G3_TX_DN<3>")
	)
	(segment
		(start 356.148894 -228.60635)
		(end 356.150164 -228.605588)
		(width 0.1143)
		(layer "In15.Cu")
		(net "GMI_CPU0_G1_CPU1_G3_TX_DN<3>")
	)
	(segment
		(start 355.11613 -222.192596)
		(end 355.199696 -222.144336)
		(width 0.1143)
		(layer "In15.Cu")
		(net "GMI_CPU0_G1_CPU1_G3_TX_DN<3>")
	)
	(segment
		(start 356.109016 -241.58956)
		(end 356.147116 -241.567208)
		(width 0.1143)
		(layer "In15.Cu")
		(net "GMI_CPU0_G1_CPU1_G3_TX_DN<3>")
	)
	(segment
		(start 356.148132 -240.92154)
		(end 356.147116 -240.921032)
		(width 0.1143)
		(layer "In15.Cu")
		(net "GMI_CPU0_G1_CPU1_G3_TX_DN<3>")
	)
	(segment
		(start 356.142798 -240.918492)
		(end 356.141528 -240.91773)
		(width 0.1143)
		(layer "In15.Cu")
		(net "GMI_CPU0_G1_CPU1_G3_TX_DN<3>")
	)
	(segment
		(start 352.403664 -213.072726)
		(end 352.467926 -212.893656)
		(width 0.14224)
		(layer "In15.Cu")
		(net "GMI_CPU0_G1_CPU1_G3_TX_DN<3>")
	)
	(segment
		(start 115.35029 -225.368612)
		(end 115.351306 -225.36912)
		(width 0.1143)
		(layer "In15.Cu")
		(net "GMI_CPU0_G1_CPU1_G3_TX_DN<3>")
	)
	(segment
		(start 115.316 -241.548666)
		(end 115.346988 -241.566446)
		(width 0.1143)
		(layer "In15.Cu")
		(net "GMI_CPU0_G1_CPU1_G3_TX_DN<3>")
	)
	(segment
		(start 356.147116 -236.060996)
		(end 356.145592 -236.05998)
		(width 0.1143)
		(layer "In15.Cu")
		(net "GMI_CPU0_G1_CPU1_G3_TX_DN<3>")
	)
	(segment
		(start 115.353846 -236.710474)
		(end 115.35537 -236.71149)
		(width 0.1143)
		(layer "In15.Cu")
		(net "GMI_CPU0_G1_CPU1_G3_TX_DN<3>")
	)
	(segment
		(start 115.346988 -226.342448)
		(end 115.345718 -226.34321)
		(width 0.1143)
		(layer "In15.Cu")
		(net "GMI_CPU0_G1_CPU1_G3_TX_DN<3>")
	)
	(segment
		(start 115.35029 -236.708442)
		(end 115.351306 -236.70895)
		(width 0.1143)
		(layer "In15.Cu")
		(net "GMI_CPU0_G1_CPU1_G3_TX_DN<3>")
	)
	(segment
		(start 114.766852 -245.294404)
		(end 115.064794 -245.294404)
		(width 0.1143)
		(layer "In15.Cu")
		(net "GMI_CPU0_G1_CPU1_G3_TX_DN<3>")
	)
	(segment
		(start 356.150164 -231.845358)
		(end 356.179882 -231.82834)
		(width 0.1143)
		(layer "In15.Cu")
		(net "GMI_CPU0_G1_CPU1_G3_TX_DN<3>")
	)
	(segment
		(start 115.386866 -229.559104)
		(end 115.34775 -229.581964)
		(width 0.1143)
		(layer "In15.Cu")
		(net "GMI_CPU0_G1_CPU1_G3_TX_DN<3>")
	)
	(segment
		(start 356.155752 -226.346004)
		(end 356.154228 -226.345242)
		(width 0.1143)
		(layer "In15.Cu")
		(net "GMI_CPU0_G1_CPU1_G3_TX_DN<3>")
	)
	(segment
		(start 355.169216 -223.769682)
		(end 355.207316 -223.74733)
		(width 0.1143)
		(layer "In15.Cu")
		(net "GMI_CPU0_G1_CPU1_G3_TX_DN<3>")
	)
	(segment
		(start 353.351084 -215.074754)
		(end 353.415346 -214.895684)
		(width 0.14224)
		(layer "In15.Cu")
		(net "GMI_CPU0_G1_CPU1_G3_TX_DN<3>")
	)
	(segment
		(start 115.34775 -239.946942)
		(end 115.348766 -239.94745)
		(width 0.1143)
		(layer "In15.Cu")
		(net "GMI_CPU0_G1_CPU1_G3_TX_DN<3>")
	)
	(segment
		(start 356.150164 -241.56543)
		(end 356.179882 -241.548412)
		(width 0.1143)
		(layer "In15.Cu")
		(net "GMI_CPU0_G1_CPU1_G3_TX_DN<3>")
	)
	(segment
		(start 115.346988 -239.946434)
		(end 115.34775 -239.946942)
		(width 0.1143)
		(layer "In15.Cu")
		(net "GMI_CPU0_G1_CPU1_G3_TX_DN<3>")
	)
	(segment
		(start 115.345718 -223.745806)
		(end 115.346988 -223.746568)
		(width 0.1143)
		(layer "In15.Cu")
		(net "GMI_CPU0_G1_CPU1_G3_TX_DN<3>")
	)
	(segment
		(start 115.35029 -231.848406)
		(end 115.351306 -231.848914)
		(width 0.1143)
		(layer "In15.Cu")
		(net "GMI_CPU0_G1_CPU1_G3_TX_DN<3>")
	)
	(segment
		(start 116.570506 -215.551004)
		(end 116.39296 -215.597232)
		(width 0.14224)
		(layer "In15.Cu")
		(net "GMI_CPU0_G1_CPU1_G3_TX_DN<3>")
	)
	(segment
		(start 356.109016 -228.629718)
		(end 356.147116 -228.607366)
		(width 0.1143)
		(layer "In15.Cu")
		(net "GMI_CPU0_G1_CPU1_G3_TX_DN<3>")
	)
	(segment
		(start 356.148132 -234.441492)
		(end 356.147116 -234.440984)
		(width 0.1143)
		(layer "In15.Cu")
		(net "GMI_CPU0_G1_CPU1_G3_TX_DN<3>")
	)
	(segment
		(start 115.346988 -225.36658)
		(end 115.34775 -225.367088)
		(width 0.1143)
		(layer "In15.Cu")
		(net "GMI_CPU0_G1_CPU1_G3_TX_DN<3>")
	)
	(segment
		(start 356.142798 -239.29848)
		(end 356.141528 -239.297718)
		(width 0.1143)
		(layer "In15.Cu")
		(net "GMI_CPU0_G1_CPU1_G3_TX_DN<3>")
	)
	(segment
		(start 356.148894 -236.706156)
		(end 356.150164 -236.705394)
		(width 0.1143)
		(layer "In15.Cu")
		(net "GMI_CPU0_G1_CPU1_G3_TX_DN<3>")
	)
	(segment
		(start 115.34775 -241.566954)
		(end 115.348766 -241.567462)
		(width 0.1143)
		(layer "In15.Cu")
		(net "GMI_CPU0_G1_CPU1_G3_TX_DN<3>")
	)
	(segment
		(start 355.208586 -224.721674)
		(end 355.16947 -224.698814)
		(width 0.1143)
		(layer "In15.Cu")
		(net "GMI_CPU0_G1_CPU1_G3_TX_DN<3>")
	)
	(segment
		(start 355.210364 -223.745552)
		(end 355.212142 -223.744536)
		(width 0.1143)
		(layer "In15.Cu")
		(net "GMI_CPU0_G1_CPU1_G3_TX_DN<3>")
	)
	(segment
		(start 356.109016 -231.869488)
		(end 356.147116 -231.847136)
		(width 0.1143)
		(layer "In15.Cu")
		(net "GMI_CPU0_G1_CPU1_G3_TX_DN<3>")
	)
	(segment
		(start 115.34775 -223.747076)
		(end 115.348766 -223.747584)
		(width 0.1143)
		(layer "In15.Cu")
		(net "GMI_CPU0_G1_CPU1_G3_TX_DN<3>")
	)
	(segment
		(start 115.346988 -236.70641)
		(end 115.34775 -236.706918)
		(width 0.1143)
		(layer "In15.Cu")
		(net "GMI_CPU0_G1_CPU1_G3_TX_DN<3>")
	)
	(segment
		(start 114.916712 -244.948964)
		(end 114.877596 -244.971824)
		(width 0.1143)
		(layer "In15.Cu")
		(net "GMI_CPU0_G1_CPU1_G3_TX_DN<3>")
	)
	(segment
		(start 114.877596 -244.971824)
		(end 114.847116 -244.989604)
		(width 0.1143)
		(layer "In15.Cu")
		(net "GMI_CPU0_G1_CPU1_G3_TX_DN<3>")
	)
	(segment
		(start 356.141528 -232.81767)
		(end 356.140004 -232.816654)
		(width 0.1143)
		(layer "In15.Cu")
		(net "GMI_CPU0_G1_CPU1_G3_TX_DN<3>")
	)
	(segment
		(start 310.47563 -178.764946)
		(end 308.042564 -177.894996)
		(width 0.14224)
		(layer "In15.Cu")
		(net "GMI_CPU0_G1_CPU1_G3_TX_DN<3>")
	)
	(segment
		(start 115.353846 -243.190522)
		(end 115.35537 -243.191538)
		(width 0.1143)
		(layer "In15.Cu")
		(net "GMI_CPU0_G1_CPU1_G3_TX_DN<3>")
	)
	(segment
		(start 355.212142 -223.744536)
		(end 355.212904 -223.744028)
		(width 0.1143)
		(layer "In15.Cu")
		(net "GMI_CPU0_G1_CPU1_G3_TX_DN<3>")
	)
	(segment
		(start 355.239066 -224.739454)
		(end 355.208586 -224.721674)
		(width 0.1143)
		(layer "In15.Cu")
		(net "GMI_CPU0_G1_CPU1_G3_TX_DN<3>")
	)
	(segment
		(start 355.240082 -223.11995)
		(end 355.177852 -223.084136)
		(width 0.1143)
		(layer "In15.Cu")
		(net "GMI_CPU0_G1_CPU1_G3_TX_DN<3>")
	)
	(segment
		(start 115.346988 -237.682278)
		(end 115.345718 -237.68304)
		(width 0.1143)
		(layer "In15.Cu")
		(net "GMI_CPU0_G1_CPU1_G3_TX_DN<3>")
	)
	(segment
		(start 115.353846 -239.950498)
		(end 115.35537 -239.951514)
		(width 0.1143)
		(layer "In15.Cu")
		(net "GMI_CPU0_G1_CPU1_G3_TX_DN<3>")
	)
	(segment
		(start 115.316 -228.588824)
		(end 115.346988 -228.606604)
		(width 0.1143)
		(layer "In15.Cu")
		(net "GMI_CPU0_G1_CPU1_G3_TX_DN<3>")
	)
	(segment
		(start 353.824794 -216.075768)
		(end 353.889056 -215.896698)
		(width 0.14224)
		(layer "In15.Cu")
		(net "GMI_CPU0_G1_CPU1_G3_TX_DN<3>")
	)
	(segment
		(start 356.147116 -239.30102)
		(end 356.145592 -239.300004)
		(width 0.1143)
		(layer "In15.Cu")
		(net "GMI_CPU0_G1_CPU1_G3_TX_DN<3>")
	)
	(segment
		(start 115.34775 -240.921794)
		(end 115.346988 -240.922302)
		(width 0.1143)
		(layer "In15.Cu")
		(net "GMI_CPU0_G1_CPU1_G3_TX_DN<3>")
	)
	(segment
		(start 356.148894 -227.962206)
		(end 356.148132 -227.961698)
		(width 0.1143)
		(layer "In15.Cu")
		(net "GMI_CPU0_G1_CPU1_G3_TX_DN<3>")
	)
	(segment
		(start 115.348766 -234.441238)
		(end 115.34775 -234.441746)
		(width 0.1143)
		(layer "In15.Cu")
		(net "GMI_CPU0_G1_CPU1_G3_TX_DN<3>")
	)
	(segment
		(start 115.353846 -231.850438)
		(end 115.35537 -231.851454)
		(width 0.1143)
		(layer "In15.Cu")
		(net "GMI_CPU0_G1_CPU1_G3_TX_DN<3>")
	)
	(segment
		(start 115.348766 -235.087414)
		(end 115.35029 -235.08843)
		(width 0.1143)
		(layer "In15.Cu")
		(net "GMI_CPU0_G1_CPU1_G3_TX_DN<3>")
	)
	(segment
		(start 115.35029 -239.300258)
		(end 115.348766 -239.301274)
		(width 0.1143)
		(layer "In15.Cu")
		(net "GMI_CPU0_G1_CPU1_G3_TX_DN<3>")
	)
	(segment
		(start 115.34775 -236.061758)
		(end 115.346988 -236.062266)
		(width 0.1143)
		(layer "In15.Cu")
		(net "GMI_CPU0_G1_CPU1_G3_TX_DN<3>")
	)
	(segment
		(start 355.678232 -225.53168)
		(end 355.64191 -225.510598)
		(width 0.1143)
		(layer "In15.Cu")
		(net "GMI_CPU0_G1_CPU1_G3_TX_DN<3>")
	)
	(segment
		(start 115.35537 -228.611684)
		(end 115.386866 -228.629972)
		(width 0.1143)
		(layer "In15.Cu")
		(net "GMI_CPU0_G1_CPU1_G3_TX_DN<3>")
	)
	(segment
		(start 356.148132 -227.961698)
		(end 356.147116 -227.96119)
		(width 0.1143)
		(layer "In15.Cu")
		(net "GMI_CPU0_G1_CPU1_G3_TX_DN<3>")
	)
	(segment
		(start 352.877374 -214.07374)
		(end 352.941636 -213.89467)
		(width 0.14224)
		(layer "In15.Cu")
		(net "GMI_CPU0_G1_CPU1_G3_TX_DN<3>")
	)
	(segment
		(start 116.782596 -215.189308)
		(end 116.570506 -215.551004)
		(width 0.14224)
		(layer "In15.Cu")
		(net "GMI_CPU0_G1_CPU1_G3_TX_DN<3>")
	)
	(segment
		(start 356.148132 -237.681516)
		(end 356.147116 -237.681008)
		(width 0.1143)
		(layer "In15.Cu")
		(net "GMI_CPU0_G1_CPU1_G3_TX_DN<3>")
	)
	(segment
		(start 355.207316 -223.74733)
		(end 355.208332 -223.746822)
		(width 0.1143)
		(layer "In15.Cu")
		(net "GMI_CPU0_G1_CPU1_G3_TX_DN<3>")
	)
	(segment
		(start 115.35029 -226.988624)
		(end 115.351306 -226.989132)
		(width 0.1143)
		(layer "In15.Cu")
		(net "GMI_CPU0_G1_CPU1_G3_TX_DN<3>")
	)
	(segment
		(start 115.346988 -236.062266)
		(end 115.345718 -236.063028)
		(width 0.1143)
		(layer "In15.Cu")
		(net "GMI_CPU0_G1_CPU1_G3_TX_DN<3>")
	)
	(segment
		(start 115.348766 -237.681262)
		(end 115.34775 -237.68177)
		(width 0.1143)
		(layer "In15.Cu")
		(net "GMI_CPU0_G1_CPU1_G3_TX_DN<3>")
	)
	(segment
		(start 356.179882 -237.699804)
		(end 356.148894 -237.682024)
		(width 0.1143)
		(layer "In15.Cu")
		(net "GMI_CPU0_G1_CPU1_G3_TX_DN<3>")
	)
	(segment
		(start 356.179882 -236.079792)
		(end 356.148894 -236.062012)
		(width 0.1143)
		(layer "In15.Cu")
		(net "GMI_CPU0_G1_CPU1_G3_TX_DN<3>")
	)
	(segment
		(start 352.762566 -213.515956)
		(end 352.582988 -213.451948)
		(width 0.14224)
		(layer "In15.Cu")
		(net "GMI_CPU0_G1_CPU1_G3_TX_DN<3>")
	)
	(segment
		(start 115.346988 -224.722436)
		(end 115.345718 -224.723198)
		(width 0.1143)
		(layer "In15.Cu")
		(net "GMI_CPU0_G1_CPU1_G3_TX_DN<3>")
	)
	(segment
		(start 356.150164 -236.705394)
		(end 356.179882 -236.688376)
		(width 0.1143)
		(layer "In15.Cu")
		(net "GMI_CPU0_G1_CPU1_G3_TX_DN<3>")
	)
	(segment
		(start 356.179882 -239.319816)
		(end 356.148894 -239.302036)
		(width 0.1143)
		(layer "In15.Cu")
		(net "GMI_CPU0_G1_CPU1_G3_TX_DN<3>")
	)
	(segment
		(start 115.386866 -239.278922)
		(end 115.35029 -239.300258)
		(width 0.1143)
		(layer "In15.Cu")
		(net "GMI_CPU0_G1_CPU1_G3_TX_DN<3>")
	)
	(segment
		(start 116.736368 -215.012016)
		(end 116.782596 -215.189308)
		(width 0.14224)
		(layer "In15.Cu")
		(net "GMI_CPU0_G1_CPU1_G3_TX_DN<3>")
	)
	(segment
		(start 115.316 -222.108776)
		(end 115.34775 -222.127064)
		(width 0.1143)
		(layer "In15.Cu")
		(net "GMI_CPU0_G1_CPU1_G3_TX_DN<3>")
	)
	(segment
		(start 356.148894 -226.342194)
		(end 356.148132 -226.341686)
		(width 0.1143)
		(layer "In15.Cu")
		(net "GMI_CPU0_G1_CPU1_G3_TX_DN<3>")
	)
	(segment
		(start 356.141528 -240.91773)
		(end 356.140004 -240.916714)
		(width 0.1143)
		(layer "In15.Cu")
		(net "GMI_CPU0_G1_CPU1_G3_TX_DN<3>")
	)
	(segment
		(start 356.153466 -226.344734)
		(end 356.15245 -226.344226)
		(width 0.1143)
		(layer "In15.Cu")
		(net "GMI_CPU0_G1_CPU1_G3_TX_DN<3>")
	)
	(segment
		(start 356.72903 -245.29415)
		(end 356.79888 -245.2243)
		(width 0.1143)
		(layer "In15.Cu")
		(net "GMI_CPU0_G1_CPU1_G3_TX_DN<3>")
	)
	(segment
		(start 115.386866 -234.418886)
		(end 115.348766 -234.441238)
		(width 0.1143)
		(layer "In15.Cu")
		(net "GMI_CPU0_G1_CPU1_G3_TX_DN<3>")
	)
	(segment
		(start 115.386866 -242.518946)
		(end 115.348766 -242.541298)
		(width 0.1143)
		(layer "In15.Cu")
		(net "GMI_CPU0_G1_CPU1_G3_TX_DN<3>")
	)
	(segment
		(start 356.148132 -239.301528)
		(end 356.147116 -239.30102)
		(width 0.1143)
		(layer "In15.Cu")
		(net "GMI_CPU0_G1_CPU1_G3_TX_DN<3>")
	)
	(segment
		(start 353.415346 -214.895684)
		(end 353.236276 -214.51697)
		(width 0.14224)
		(layer "In15.Cu")
		(net "GMI_CPU0_G1_CPU1_G3_TX_DN<3>")
	)
	(segment
		(start 356.618286 -244.97157)
		(end 356.57917 -244.94871)
		(width 0.1143)
		(layer "In15.Cu")
		(net "GMI_CPU0_G1_CPU1_G3_TX_DN<3>")
	)
	(segment
		(start 115.346988 -242.542314)
		(end 115.345718 -242.543076)
		(width 0.1143)
		(layer "In15.Cu")
		(net "GMI_CPU0_G1_CPU1_G3_TX_DN<3>")
	)
	(segment
		(start 115.346988 -232.822242)
		(end 115.345718 -232.823004)
		(width 0.1143)
		(layer "In15.Cu")
		(net "GMI_CPU0_G1_CPU1_G3_TX_DN<3>")
	)
	(segment
		(start 115.345718 -244.163088)
		(end 115.316 -244.180106)
		(width 0.1143)
		(layer "In15.Cu")
		(net "GMI_CPU0_G1_CPU1_G3_TX_DN<3>")
	)
	(segment
		(start 356.150164 -228.605588)
		(end 356.179882 -228.58857)
		(width 0.1143)
		(layer "In15.Cu")
		(net "GMI_CPU0_G1_CPU1_G3_TX_DN<3>")
	)
	(segment
		(start 356.147116 -234.440984)
		(end 356.145592 -234.439968)
		(width 0.1143)
		(layer "In15.Cu")
		(net "GMI_CPU0_G1_CPU1_G3_TX_DN<3>")
	)
	(segment
		(start 355.209094 -223.746314)
		(end 355.210364 -223.745552)
		(width 0.1143)
		(layer "In15.Cu")
		(net "GMI_CPU0_G1_CPU1_G3_TX_DN<3>")
	)
	(segment
		(start 356.148894 -237.682024)
		(end 356.148132 -237.681516)
		(width 0.1143)
		(layer "In15.Cu")
		(net "GMI_CPU0_G1_CPU1_G3_TX_DN<3>")
	)
	(segment
		(start 355.386386 -221.128844)
		(end 355.340666 -221.083124)
		(width 0.1143)
		(layer "In15.Cu")
		(net "GMI_CPU0_G1_CPU1_G3_TX_DN<3>")
	)
	(segment
		(start 356.142798 -232.818432)
		(end 356.141528 -232.81767)
		(width 0.1143)
		(layer "In15.Cu")
		(net "GMI_CPU0_G1_CPU1_G3_TX_DN<3>")
	)
	(segment
		(start 356.140004 -232.816654)
		(end 356.109016 -232.79862)
		(width 0.1143)
		(layer "In15.Cu")
		(net "GMI_CPU0_G1_CPU1_G3_TX_DN<3>")
	)
	(segment
		(start 356.145592 -240.920016)
		(end 356.142798 -240.918492)
		(width 0.1143)
		(layer "In15.Cu")
		(net "GMI_CPU0_G1_CPU1_G3_TX_DN<3>")
	)
	(segment
		(start 356.150164 -243.185442)
		(end 356.179882 -243.168424)
		(width 0.1143)
		(layer "In15.Cu")
		(net "GMI_CPU0_G1_CPU1_G3_TX_DN<3>")
	)
	(segment
		(start 356.148132 -229.58171)
		(end 356.109016 -229.55885)
		(width 0.1143)
		(layer "In15.Cu")
		(net "GMI_CPU0_G1_CPU1_G3_TX_DN<3>")
	)
	(segment
		(start 115.316 -231.828594)
		(end 115.346988 -231.846374)
		(width 0.1143)
		(layer "In15.Cu")
		(net "GMI_CPU0_G1_CPU1_G3_TX_DN<3>")
	)
	(segment
		(start 356.150164 -238.325406)
		(end 356.179882 -238.308388)
		(width 0.1143)
		(layer "In15.Cu")
		(net "GMI_CPU0_G1_CPU1_G3_TX_DN<3>")
	)
	(segment
		(start 115.10137 -221.066106)
		(end 115.10137 -221.198948)
		(width 0.1143)
		(layer "In15.Cu")
		(net "GMI_CPU0_G1_CPU1_G3_TX_DN<3>")
	)
	(segment
		(start 356.15245 -226.344226)
		(end 356.151688 -226.343718)
		(width 0.1143)
		(layer "In15.Cu")
		(net "GMI_CPU0_G1_CPU1_G3_TX_DN<3>")
	)
	(segment
		(start 115.353846 -228.610668)
		(end 115.35537 -228.611684)
		(width 0.1143)
		(layer "In15.Cu")
		(net "GMI_CPU0_G1_CPU1_G3_TX_DN<3>")
	)
	(segment
		(start 115.386866 -244.138958)
		(end 115.348766 -244.16131)
		(width 0.1143)
		(layer "In15.Cu")
		(net "GMI_CPU0_G1_CPU1_G3_TX_DN<3>")
	)
	(arc
		(start 115.386866 -222.149924)
		(mid 115.630193 -222.61449)
		(end 115.386866 -223.079056)
		(width 0.1143)
		(layer "In15.Cu")
		(net "GMI_CPU0_G1_CPU1_G3_TX_DN<3>")
	)
	(arc
		(start 355.170486 -223.079818)
		(mid 355.163464 -223.074918)
		(end 355.156516 -223.069912)
		(width 0.1143)
		(layer "In15.Cu")
		(net "GMI_CPU0_G1_CPU1_G3_TX_DN<3>")
	)
	(arc
		(start 115.316 -224.740216)
		(mid 115.160072 -225.044508)
		(end 115.316 -225.3488)
		(width 0.1143)
		(layer "In15.Cu")
		(net "GMI_CPU0_G1_CPU1_G3_TX_DN<3>")
	)
	(arc
		(start 356.179882 -230.208328)
		(mid 356.294558 -230.074994)
		(end 356.335838 -229.904036)
		(width 0.1143)
		(layer "In15.Cu")
		(net "GMI_CPU0_G1_CPU1_G3_TX_DN<3>")
	)
	(arc
		(start 115.316 -242.560094)
		(mid 115.160072 -242.864386)
		(end 115.316 -243.168678)
		(width 0.1143)
		(layer "In15.Cu")
		(net "GMI_CPU0_G1_CPU1_G3_TX_DN<3>")
	)
	(arc
		(start 115.160044 -221.804484)
		(mid 115.201299 -221.975455)
		(end 115.316 -222.108776)
		(width 0.1143)
		(layer "In15.Cu")
		(net "GMI_CPU0_G1_CPU1_G3_TX_DN<3>")
	)
	(arc
		(start 356.109016 -227.938838)
		(mid 355.865689 -227.474272)
		(end 356.109016 -227.009706)
		(width 0.1143)
		(layer "In15.Cu")
		(net "GMI_CPU0_G1_CPU1_G3_TX_DN<3>")
	)
	(arc
		(start 356.109016 -234.418632)
		(mid 355.865689 -233.954066)
		(end 356.109016 -233.4895)
		(width 0.1143)
		(layer "In15.Cu")
		(net "GMI_CPU0_G1_CPU1_G3_TX_DN<3>")
	)
	(arc
		(start 356.109016 -239.278668)
		(mid 355.865689 -238.814102)
		(end 356.109016 -238.349536)
		(width 0.1143)
		(layer "In15.Cu")
		(net "GMI_CPU0_G1_CPU1_G3_TX_DN<3>")
	)
	(arc
		(start 115.386866 -223.769936)
		(mid 115.630193 -224.234502)
		(end 115.386866 -224.699068)
		(width 0.1143)
		(layer "In15.Cu")
		(net "GMI_CPU0_G1_CPU1_G3_TX_DN<3>")
	)
	(arc
		(start 356.109016 -242.518692)
		(mid 355.865689 -242.054126)
		(end 356.109016 -241.58956)
		(width 0.1143)
		(layer "In15.Cu")
		(net "GMI_CPU0_G1_CPU1_G3_TX_DN<3>")
	)
	(arc
		(start 355.199696 -222.144336)
		(mid 355.343086 -222.000477)
		(end 355.39553 -221.80423)
		(width 0.1143)
		(layer "In15.Cu")
		(net "GMI_CPU0_G1_CPU1_G3_TX_DN<3>")
	)
	(arc
		(start 356.109016 -229.55885)
		(mid 355.865689 -229.094284)
		(end 356.109016 -228.629718)
		(width 0.1143)
		(layer "In15.Cu")
		(net "GMI_CPU0_G1_CPU1_G3_TX_DN<3>")
	)
	(arc
		(start 115.160044 -244.484398)
		(mid 115.095529 -244.746617)
		(end 114.916712 -244.948964)
		(width 0.1143)
		(layer "In15.Cu")
		(net "GMI_CPU0_G1_CPU1_G3_TX_DN<3>")
	)
	(arc
		(start 115.386866 -233.489754)
		(mid 115.630193 -233.95432)
		(end 115.386866 -234.418886)
		(width 0.1143)
		(layer "In15.Cu")
		(net "GMI_CPU0_G1_CPU1_G3_TX_DN<3>")
	)
	(arc
		(start 355.64191 -225.510598)
		(mid 355.461258 -225.307853)
		(end 355.396038 -225.044254)
		(width 0.1143)
		(layer "In15.Cu")
		(net "GMI_CPU0_G1_CPU1_G3_TX_DN<3>")
	)
	(arc
		(start 356.109016 -236.038644)
		(mid 355.865689 -235.574078)
		(end 356.109016 -235.109512)
		(width 0.1143)
		(layer "In15.Cu")
		(net "GMI_CPU0_G1_CPU1_G3_TX_DN<3>")
	)
	(arc
		(start 115.316 -232.840022)
		(mid 115.160072 -233.144314)
		(end 115.316 -233.448606)
		(width 0.1143)
		(layer "In15.Cu")
		(net "GMI_CPU0_G1_CPU1_G3_TX_DN<3>")
	)
	(arc
		(start 115.386866 -227.00996)
		(mid 115.630193 -227.474526)
		(end 115.386866 -227.939092)
		(width 0.1143)
		(layer "In15.Cu")
		(net "GMI_CPU0_G1_CPU1_G3_TX_DN<3>")
	)
	(arc
		(start 356.109016 -240.89868)
		(mid 355.865689 -240.434114)
		(end 356.109016 -239.969548)
		(width 0.1143)
		(layer "In15.Cu")
		(net "GMI_CPU0_G1_CPU1_G3_TX_DN<3>")
	)
	(arc
		(start 355.865684 -230.714296)
		(mid 355.93092 -230.450705)
		(end 356.111556 -230.247952)
		(width 0.1143)
		(layer "In15.Cu")
		(net "GMI_CPU0_G1_CPU1_G3_TX_DN<3>")
	)
	(arc
		(start 115.160044 -231.524302)
		(mid 115.201299 -231.695273)
		(end 115.316 -231.828594)
		(width 0.1143)
		(layer "In15.Cu")
		(net "GMI_CPU0_G1_CPU1_G3_TX_DN<3>")
	)
	(arc
		(start 115.386866 -243.209826)
		(mid 115.630193 -243.674392)
		(end 115.386866 -244.138958)
		(width 0.1143)
		(layer "In15.Cu")
		(net "GMI_CPU0_G1_CPU1_G3_TX_DN<3>")
	)
	(arc
		(start 115.316 -237.700058)
		(mid 115.160072 -238.00435)
		(end 115.316 -238.308642)
		(width 0.1143)
		(layer "In15.Cu")
		(net "GMI_CPU0_G1_CPU1_G3_TX_DN<3>")
	)
	(arc
		(start 115.384326 -230.248206)
		(mid 115.564978 -230.450951)
		(end 115.630198 -230.71455)
		(width 0.1143)
		(layer "In15.Cu")
		(net "GMI_CPU0_G1_CPU1_G3_TX_DN<3>")
	)
	(arc
		(start 355.140006 -224.6757)
		(mid 355.000063 -224.489676)
		(end 354.928932 -224.26803)
		(width 0.1143)
		(layer "In15.Cu")
		(net "GMI_CPU0_G1_CPU1_G3_TX_DN<3>")
	)
	(arc
		(start 115.386866 -238.34979)
		(mid 115.630193 -238.814356)
		(end 115.386866 -239.278922)
		(width 0.1143)
		(layer "In15.Cu")
		(net "GMI_CPU0_G1_CPU1_G3_TX_DN<3>")
	)
	(arc
		(start 356.179882 -236.688376)
		(mid 356.33581 -236.384084)
		(end 356.179882 -236.079792)
		(width 0.1143)
		(layer "In15.Cu")
		(net "GMI_CPU0_G1_CPU1_G3_TX_DN<3>")
	)
	(arc
		(start 115.386866 -225.389948)
		(mid 115.630193 -225.854514)
		(end 115.386866 -226.31908)
		(width 0.1143)
		(layer "In15.Cu")
		(net "GMI_CPU0_G1_CPU1_G3_TX_DN<3>")
	)
	(arc
		(start 115.386866 -228.629972)
		(mid 115.630193 -229.094538)
		(end 115.386866 -229.559104)
		(width 0.1143)
		(layer "In15.Cu")
		(net "GMI_CPU0_G1_CPU1_G3_TX_DN<3>")
	)
	(arc
		(start 115.316 -244.180106)
		(mid 115.201324 -244.31344)
		(end 115.160044 -244.484398)
		(width 0.1143)
		(layer "In15.Cu")
		(net "GMI_CPU0_G1_CPU1_G3_TX_DN<3>")
	)
	(arc
		(start 115.314222 -231.221534)
		(mid 115.200815 -231.354423)
		(end 115.160044 -231.524302)
		(width 0.1143)
		(layer "In15.Cu")
		(net "GMI_CPU0_G1_CPU1_G3_TX_DN<3>")
	)
	(arc
		(start 356.179882 -238.308388)
		(mid 356.33581 -238.004096)
		(end 356.179882 -237.699804)
		(width 0.1143)
		(layer "In15.Cu")
		(net "GMI_CPU0_G1_CPU1_G3_TX_DN<3>")
	)
	(arc
		(start 356.109016 -232.79862)
		(mid 355.865689 -232.334054)
		(end 356.109016 -231.869488)
		(width 0.1143)
		(layer "In15.Cu")
		(net "GMI_CPU0_G1_CPU1_G3_TX_DN<3>")
	)
	(arc
		(start 115.316 -226.360228)
		(mid 115.160072 -226.66452)
		(end 115.316 -226.968812)
		(width 0.1143)
		(layer "In15.Cu")
		(net "GMI_CPU0_G1_CPU1_G3_TX_DN<3>")
	)
	(arc
		(start 115.386866 -239.969802)
		(mid 115.630193 -240.434368)
		(end 115.386866 -240.898934)
		(width 0.1143)
		(layer "In15.Cu")
		(net "GMI_CPU0_G1_CPU1_G3_TX_DN<3>")
	)
	(arc
		(start 356.57917 -244.94871)
		(mid 356.400357 -244.74636)
		(end 356.335838 -244.484144)
		(width 0.1143)
		(layer "In15.Cu")
		(net "GMI_CPU0_G1_CPU1_G3_TX_DN<3>")
	)
	(arc
		(start 356.335838 -244.484144)
		(mid 356.294583 -244.313173)
		(end 356.179882 -244.179852)
		(width 0.1143)
		(layer "In15.Cu")
		(net "GMI_CPU0_G1_CPU1_G3_TX_DN<3>")
	)
	(arc
		(start 115.160044 -229.90429)
		(mid 115.201299 -230.075261)
		(end 115.316 -230.208582)
		(width 0.1143)
		(layer "In15.Cu")
		(net "GMI_CPU0_G1_CPU1_G3_TX_DN<3>")
	)
	(arc
		(start 115.316 -236.080046)
		(mid 115.160072 -236.384338)
		(end 115.316 -236.68863)
		(width 0.1143)
		(layer "In15.Cu")
		(net "GMI_CPU0_G1_CPU1_G3_TX_DN<3>")
	)
	(arc
		(start 356.179882 -239.9284)
		(mid 356.33581 -239.624108)
		(end 356.179882 -239.319816)
		(width 0.1143)
		(layer "In15.Cu")
		(net "GMI_CPU0_G1_CPU1_G3_TX_DN<3>")
	)
	(arc
		(start 356.109016 -237.658656)
		(mid 355.865689 -237.19409)
		(end 356.109016 -236.729524)
		(width 0.1143)
		(layer "In15.Cu")
		(net "GMI_CPU0_G1_CPU1_G3_TX_DN<3>")
	)
	(arc
		(start 356.109016 -244.138704)
		(mid 355.865689 -243.674138)
		(end 356.109016 -243.209572)
		(width 0.1143)
		(layer "In15.Cu")
		(net "GMI_CPU0_G1_CPU1_G3_TX_DN<3>")
	)
	(arc
		(start 114.847116 -244.989604)
		(mid 114.749351 -245.09258)
		(end 114.697002 -245.224554)
		(width 0.1143)
		(layer "In15.Cu")
		(net "GMI_CPU0_G1_CPU1_G3_TX_DN<3>")
	)
	(arc
		(start 354.928932 -224.26803)
		(mid 354.928282 -224.26346)
		(end 354.927662 -224.258886)
		(width 0.1143)
		(layer "In15.Cu")
		(net "GMI_CPU0_G1_CPU1_G3_TX_DN<3>")
	)
	(arc
		(start 115.386866 -236.729778)
		(mid 115.630193 -237.194344)
		(end 115.386866 -237.65891)
		(width 0.1143)
		(layer "In15.Cu")
		(net "GMI_CPU0_G1_CPU1_G3_TX_DN<3>")
	)
	(arc
		(start 356.79888 -245.2243)
		(mid 356.746463 -245.092369)
		(end 356.648766 -244.98935)
		(width 0.1143)
		(layer "In15.Cu")
		(net "GMI_CPU0_G1_CPU1_G3_TX_DN<3>")
	)
	(arc
		(start 356.179882 -243.168424)
		(mid 356.33581 -242.864132)
		(end 356.179882 -242.55984)
		(width 0.1143)
		(layer "In15.Cu")
		(net "GMI_CPU0_G1_CPU1_G3_TX_DN<3>")
	)
	(arc
		(start 115.386866 -235.109766)
		(mid 115.630193 -235.574332)
		(end 115.386866 -236.038898)
		(width 0.1143)
		(layer "In15.Cu")
		(net "GMI_CPU0_G1_CPU1_G3_TX_DN<3>")
	)
	(arc
		(start 355.09581 -222.212408)
		(mid 355.105846 -222.202375)
		(end 355.11613 -222.192596)
		(width 0.1143)
		(layer "In15.Cu")
		(net "GMI_CPU0_G1_CPU1_G3_TX_DN<3>")
	)
	(arc
		(start 355.396038 -225.044254)
		(mid 355.354489 -224.872832)
		(end 355.239066 -224.739454)
		(width 0.1143)
		(layer "In15.Cu")
		(net "GMI_CPU0_G1_CPU1_G3_TX_DN<3>")
	)
	(arc
		(start 115.316 -223.120204)
		(mid 115.160072 -223.424496)
		(end 115.316 -223.728788)
		(width 0.1143)
		(layer "In15.Cu")
		(net "GMI_CPU0_G1_CPU1_G3_TX_DN<3>")
	)
	(arc
		(start 115.314222 -229.601522)
		(mid 115.200815 -229.734411)
		(end 115.160044 -229.90429)
		(width 0.1143)
		(layer "In15.Cu")
		(net "GMI_CPU0_G1_CPU1_G3_TX_DN<3>")
	)
	(arc
		(start 356.179882 -235.068364)
		(mid 356.33581 -234.764072)
		(end 356.179882 -234.45978)
		(width 0.1143)
		(layer "In15.Cu")
		(net "GMI_CPU0_G1_CPU1_G3_TX_DN<3>")
	)
	(arc
		(start 356.109016 -231.178862)
		(mid 355.930203 -230.976512)
		(end 355.865684 -230.714296)
		(width 0.1143)
		(layer "In15.Cu")
		(net "GMI_CPU0_G1_CPU1_G3_TX_DN<3>")
	)
	(arc
		(start 356.179882 -231.82834)
		(mid 356.294558 -231.695006)
		(end 356.335838 -231.524048)
		(width 0.1143)
		(layer "In15.Cu")
		(net "GMI_CPU0_G1_CPU1_G3_TX_DN<3>")
	)
	(arc
		(start 356.179882 -233.448352)
		(mid 356.33581 -233.14406)
		(end 356.179882 -232.839768)
		(width 0.1143)
		(layer "In15.Cu")
		(net "GMI_CPU0_G1_CPU1_G3_TX_DN<3>")
	)
	(arc
		(start 355.16947 -224.698814)
		(mid 355.1636 -224.694406)
		(end 355.157786 -224.689924)
		(width 0.1143)
		(layer "In15.Cu")
		(net "GMI_CPU0_G1_CPU1_G3_TX_DN<3>")
	)
	(arc
		(start 355.865684 -225.85426)
		(mid 355.824135 -225.682838)
		(end 355.708712 -225.54946)
		(width 0.1143)
		(layer "In15.Cu")
		(net "GMI_CPU0_G1_CPU1_G3_TX_DN<3>")
	)
	(arc
		(start 115.316 -239.32007)
		(mid 115.160072 -239.624362)
		(end 115.316 -239.928654)
		(width 0.1143)
		(layer "In15.Cu")
		(net "GMI_CPU0_G1_CPU1_G3_TX_DN<3>")
	)
	(arc
		(start 115.630198 -230.71455)
		(mid 115.565683 -230.976769)
		(end 115.386866 -231.179116)
		(width 0.1143)
		(layer "In15.Cu")
		(net "GMI_CPU0_G1_CPU1_G3_TX_DN<3>")
	)
	(arc
		(start 355.157786 -224.689924)
		(mid 355.148824 -224.682902)
		(end 355.140006 -224.6757)
		(width 0.1143)
		(layer "In15.Cu")
		(net "GMI_CPU0_G1_CPU1_G3_TX_DN<3>")
	)
	(arc
		(start 355.260148 -223.714056)
		(mid 355.408655 -223.424242)
		(end 355.260148 -223.134428)
		(width 0.1143)
		(layer "In15.Cu")
		(net "GMI_CPU0_G1_CPU1_G3_TX_DN<3>")
	)
	(arc
		(start 115.316 -227.98024)
		(mid 115.160072 -228.284532)
		(end 115.316 -228.588824)
		(width 0.1143)
		(layer "In15.Cu")
		(net "GMI_CPU0_G1_CPU1_G3_TX_DN<3>")
	)
	(arc
		(start 356.109016 -226.318826)
		(mid 355.930203 -226.116476)
		(end 355.865684 -225.85426)
		(width 0.1143)
		(layer "In15.Cu")
		(net "GMI_CPU0_G1_CPU1_G3_TX_DN<3>")
	)
	(arc
		(start 356.335838 -229.904036)
		(mid 356.295076 -229.734152)
		(end 356.18166 -229.601268)
		(width 0.1143)
		(layer "In15.Cu")
		(net "GMI_CPU0_G1_CPU1_G3_TX_DN<3>")
	)
	(arc
		(start 355.156516 -223.069912)
		(mid 354.932782 -222.654815)
		(end 355.09581 -222.212408)
		(width 0.1143)
		(layer "In15.Cu")
		(net "GMI_CPU0_G1_CPU1_G3_TX_DN<3>")
	)
	(arc
		(start 356.179882 -228.58857)
		(mid 356.33581 -228.284278)
		(end 356.179882 -227.979986)
		(width 0.1143)
		(layer "In15.Cu")
		(net "GMI_CPU0_G1_CPU1_G3_TX_DN<3>")
	)
	(arc
		(start 115.386866 -241.589814)
		(mid 115.630193 -242.05438)
		(end 115.386866 -242.518946)
		(width 0.1143)
		(layer "In15.Cu")
		(net "GMI_CPU0_G1_CPU1_G3_TX_DN<3>")
	)
	(arc
		(start 115.386866 -231.869742)
		(mid 115.630193 -232.334308)
		(end 115.386866 -232.798874)
		(width 0.1143)
		(layer "In15.Cu")
		(net "GMI_CPU0_G1_CPU1_G3_TX_DN<3>")
	)
	(arc
		(start 354.925884 -224.234248)
		(mid 354.990399 -223.972029)
		(end 355.169216 -223.769682)
		(width 0.1143)
		(layer "In15.Cu")
		(net "GMI_CPU0_G1_CPU1_G3_TX_DN<3>")
	)
	(arc
		(start 356.179882 -241.548412)
		(mid 356.33581 -241.24412)
		(end 356.179882 -240.939828)
		(width 0.1143)
		(layer "In15.Cu")
		(net "GMI_CPU0_G1_CPU1_G3_TX_DN<3>")
	)
	(arc
		(start 115.316 -240.940082)
		(mid 115.160072 -241.244374)
		(end 115.316 -241.548666)
		(width 0.1143)
		(layer "In15.Cu")
		(net "GMI_CPU0_G1_CPU1_G3_TX_DN<3>")
	)
	(arc
		(start 356.179882 -226.968558)
		(mid 356.33581 -226.664266)
		(end 356.179882 -226.359974)
		(width 0.1143)
		(layer "In15.Cu")
		(net "GMI_CPU0_G1_CPU1_G3_TX_DN<3>")
	)
	(arc
		(start 115.316 -234.460034)
		(mid 115.160072 -234.764326)
		(end 115.316 -235.068618)
		(width 0.1143)
		(layer "In15.Cu")
		(net "GMI_CPU0_G1_CPU1_G3_TX_DN<3>")
	)
	(arc
		(start 356.335838 -231.524048)
		(mid 356.295076 -231.354164)
		(end 356.18166 -231.22128)
		(width 0.1143)
		(layer "In15.Cu")
		(net "GMI_CPU0_G1_CPU1_G3_TX_DN<3>")
	)
	(segment
		(start 356.89794 -243.940076)
		(end 356.431088 -243.674138)
		(width 0.12954)
		(layer "F.Cu")
		(net "GMI_CPU0_G1_CPU1_G3_TX_DN<2>")
	)
	(segment
		(start 114.597942 -243.94033)
		(end 115.064794 -243.674392)
		(width 0.12954)
		(layer "F.Cu")
		(net "GMI_CPU0_G1_CPU1_G3_TX_DN<2>")
	)
	(segment
		(start 354.97897 -215.939116)
		(end 354.799646 -215.559894)
		(width 0.14224)
		(layer "In15.Cu")
		(net "GMI_CPU0_G1_CPU1_G3_TX_DN<2>")
	)
	(segment
		(start 114.375946 -225.3488)
		(end 114.446812 -225.389948)
		(width 0.1143)
		(layer "In15.Cu")
		(net "GMI_CPU0_G1_CPU1_G3_TX_DN<2>")
	)
	(segment
		(start 357.085646 -237.679992)
		(end 357.082852 -237.678468)
		(width 0.1143)
		(layer "In15.Cu")
		(net "GMI_CPU0_G1_CPU1_G3_TX_DN<2>")
	)
	(segment
		(start 354.031296 -213.936834)
		(end 353.851972 -213.557612)
		(width 0.14224)
		(layer "In15.Cu")
		(net "GMI_CPU0_G1_CPU1_G3_TX_DN<2>")
	)
	(segment
		(start 356.285292 -218.38412)
		(end 356.106222 -218.005406)
		(width 0.14224)
		(layer "In15.Cu")
		(net "GMI_CPU0_G1_CPU1_G3_TX_DN<2>")
	)
	(segment
		(start 357.086408 -227.960682)
		(end 357.085392 -227.960174)
		(width 0.1143)
		(layer "In15.Cu")
		(net "GMI_CPU0_G1_CPU1_G3_TX_DN<2>")
	)
	(segment
		(start 357.08717 -235.08716)
		(end 357.088186 -235.086652)
		(width 0.1143)
		(layer "In15.Cu")
		(net "GMI_CPU0_G1_CPU1_G3_TX_DN<2>")
	)
	(segment
		(start 357.08717 -236.060996)
		(end 357.085646 -236.05998)
		(width 0.1143)
		(layer "In15.Cu")
		(net "GMI_CPU0_G1_CPU1_G3_TX_DN<2>")
	)
	(segment
		(start 357.119936 -239.319816)
		(end 357.088948 -239.302036)
		(width 0.1143)
		(layer "In15.Cu")
		(net "GMI_CPU0_G1_CPU1_G3_TX_DN<2>")
	)
	(segment
		(start 115.990878 -214.429848)
		(end 115.813332 -214.475822)
		(width 0.14224)
		(layer "In15.Cu")
		(net "GMI_CPU0_G1_CPU1_G3_TX_DN<2>")
	)
	(segment
		(start 114.375946 -239.928654)
		(end 114.3762 -239.9284)
		(width 0.1143)
		(layer "In15.Cu")
		(net "GMI_CPU0_G1_CPU1_G3_TX_DN<2>")
	)
	(segment
		(start 114.684048 -243.591588)
		(end 114.766852 -243.674392)
		(width 0.1143)
		(layer "In15.Cu")
		(net "GMI_CPU0_G1_CPU1_G3_TX_DN<2>")
	)
	(segment
		(start 357.080058 -237.67669)
		(end 357.04907 -237.658656)
		(width 0.1143)
		(layer "In15.Cu")
		(net "GMI_CPU0_G1_CPU1_G3_TX_DN<2>")
	)
	(segment
		(start 357.085646 -232.819956)
		(end 357.082852 -232.818432)
		(width 0.1143)
		(layer "In15.Cu")
		(net "GMI_CPU0_G1_CPU1_G3_TX_DN<2>")
	)
	(segment
		(start 114.428524 -237.669578)
		(end 114.407188 -237.682024)
		(width 0.1143)
		(layer "In15.Cu")
		(net "GMI_CPU0_G1_CPU1_G3_TX_DN<2>")
	)
	(segment
		(start 114.375946 -234.460034)
		(end 114.357404 -234.473496)
		(width 0.1143)
		(layer "In15.Cu")
		(net "GMI_CPU0_G1_CPU1_G3_TX_DN<2>")
	)
	(segment
		(start 355.273356 -216.561162)
		(end 355.337618 -216.381838)
		(width 0.14224)
		(layer "In15.Cu")
		(net "GMI_CPU0_G1_CPU1_G3_TX_DN<2>")
	)
	(segment
		(start 356.096316 -222.158814)
		(end 356.107238 -222.150432)
		(width 0.1143)
		(layer "In15.Cu")
		(net "GMI_CPU0_G1_CPU1_G3_TX_DN<2>")
	)
	(segment
		(start 114.375946 -232.840022)
		(end 114.369088 -232.844848)
		(width 0.1143)
		(layer "In15.Cu")
		(net "GMI_CPU0_G1_CPU1_G3_TX_DN<2>")
	)
	(segment
		(start 114.21999 -221.262448)
		(end 114.21999 -221.804484)
		(width 0.1143)
		(layer "In15.Cu")
		(net "GMI_CPU0_G1_CPU1_G3_TX_DN<2>")
	)
	(segment
		(start 355.45268 -216.940384)
		(end 355.273356 -216.561162)
		(width 0.14224)
		(layer "In15.Cu")
		(net "GMI_CPU0_G1_CPU1_G3_TX_DN<2>")
	)
	(segment
		(start 356.147116 -222.127318)
		(end 356.148132 -222.12681)
		(width 0.1143)
		(layer "In15.Cu")
		(net "GMI_CPU0_G1_CPU1_G3_TX_DN<2>")
	)
	(segment
		(start 356.336092 -221.804484)
		(end 356.336092 -221.39275)
		(width 0.1143)
		(layer "In15.Cu")
		(net "GMI_CPU0_G1_CPU1_G3_TX_DN<2>")
	)
	(segment
		(start 114.369088 -226.963986)
		(end 114.375946 -226.968812)
		(width 0.1143)
		(layer "In15.Cu")
		(net "GMI_CPU0_G1_CPU1_G3_TX_DN<2>")
	)
	(segment
		(start 357.085646 -242.540028)
		(end 357.082852 -242.538504)
		(width 0.1143)
		(layer "In15.Cu")
		(net "GMI_CPU0_G1_CPU1_G3_TX_DN<2>")
	)
	(segment
		(start 114.446812 -236.038898)
		(end 114.407696 -236.061758)
		(width 0.1143)
		(layer "In15.Cu")
		(net "GMI_CPU0_G1_CPU1_G3_TX_DN<2>")
	)
	(segment
		(start 356.335838 -221.80423)
		(end 356.336092 -221.804484)
		(width 0.1143)
		(layer "In15.Cu")
		(net "GMI_CPU0_G1_CPU1_G3_TX_DN<2>")
	)
	(segment
		(start 114.407696 -226.34194)
		(end 114.375946 -226.360228)
		(width 0.1143)
		(layer "In15.Cu")
		(net "GMI_CPU0_G1_CPU1_G3_TX_DN<2>")
	)
	(segment
		(start 357.088948 -241.566192)
		(end 357.119936 -241.548412)
		(width 0.1143)
		(layer "In15.Cu")
		(net "GMI_CPU0_G1_CPU1_G3_TX_DN<2>")
	)
	(segment
		(start 357.088186 -233.46664)
		(end 357.088948 -233.466132)
		(width 0.1143)
		(layer "In15.Cu")
		(net "GMI_CPU0_G1_CPU1_G3_TX_DN<2>")
	)
	(segment
		(start 114.375946 -226.968812)
		(end 114.446812 -227.00996)
		(width 0.1143)
		(layer "In15.Cu")
		(net "GMI_CPU0_G1_CPU1_G3_TX_DN<2>")
	)
	(segment
		(start 357.139748 -236.094016)
		(end 357.119936 -236.079792)
		(width 0.1143)
		(layer "In15.Cu")
		(net "GMI_CPU0_G1_CPU1_G3_TX_DN<2>")
	)
	(segment
		(start 357.082852 -240.918492)
		(end 357.081582 -240.91773)
		(width 0.1143)
		(layer "In15.Cu")
		(net "GMI_CPU0_G1_CPU1_G3_TX_DN<2>")
	)
	(segment
		(start 114.407696 -228.607112)
		(end 114.446812 -228.629972)
		(width 0.1143)
		(layer "In15.Cu")
		(net "GMI_CPU0_G1_CPU1_G3_TX_DN<2>")
	)
	(segment
		(start 357.088186 -235.086652)
		(end 357.088948 -235.086144)
		(width 0.1143)
		(layer "In15.Cu")
		(net "GMI_CPU0_G1_CPU1_G3_TX_DN<2>")
	)
	(segment
		(start 114.446812 -232.798874)
		(end 114.407696 -232.821734)
		(width 0.1143)
		(layer "In15.Cu")
		(net "GMI_CPU0_G1_CPU1_G3_TX_DN<2>")
	)
	(segment
		(start 357.04907 -235.109512)
		(end 357.085646 -235.088176)
		(width 0.1143)
		(layer "In15.Cu")
		(net "GMI_CPU0_G1_CPU1_G3_TX_DN<2>")
	)
	(segment
		(start 356.148894 -222.126302)
		(end 356.150164 -222.12554)
		(width 0.1143)
		(layer "In15.Cu")
		(net "GMI_CPU0_G1_CPU1_G3_TX_DN<2>")
	)
	(segment
		(start 357.05669 -227.94341)
		(end 357.049832 -227.939346)
		(width 0.1143)
		(layer "In15.Cu")
		(net "GMI_CPU0_G1_CPU1_G3_TX_DN<2>")
	)
	(segment
		(start 356.106476 -223.770698)
		(end 356.180136 -223.728534)
		(width 0.1143)
		(layer "In15.Cu")
		(net "GMI_CPU0_G1_CPU1_G3_TX_DN<2>")
	)
	(segment
		(start 357.088948 -231.84612)
		(end 357.119936 -231.82834)
		(width 0.1143)
		(layer "In15.Cu")
		(net "GMI_CPU0_G1_CPU1_G3_TX_DN<2>")
	)
	(segment
		(start 357.04907 -227.009706)
		(end 357.08717 -226.987354)
		(width 0.1143)
		(layer "In15.Cu")
		(net "GMI_CPU0_G1_CPU1_G3_TX_DN<2>")
	)
	(segment
		(start 357.119936 -236.688376)
		(end 357.139748 -236.674152)
		(width 0.1143)
		(layer "In15.Cu")
		(net "GMI_CPU0_G1_CPU1_G3_TX_DN<2>")
	)
	(segment
		(start 357.088948 -236.706156)
		(end 357.119936 -236.688376)
		(width 0.1143)
		(layer "In15.Cu")
		(net "GMI_CPU0_G1_CPU1_G3_TX_DN<2>")
	)
	(segment
		(start 356.148132 -224.721674)
		(end 356.145846 -224.720404)
		(width 0.1143)
		(layer "In15.Cu")
		(net "GMI_CPU0_G1_CPU1_G3_TX_DN<2>")
	)
	(segment
		(start 114.446812 -227.939092)
		(end 114.407696 -227.961952)
		(width 0.1143)
		(layer "In15.Cu")
		(net "GMI_CPU0_G1_CPU1_G3_TX_DN<2>")
	)
	(segment
		(start 356.148894 -224.722182)
		(end 356.148132 -224.721674)
		(width 0.1143)
		(layer "In15.Cu")
		(net "GMI_CPU0_G1_CPU1_G3_TX_DN<2>")
	)
	(segment
		(start 114.370104 -225.344736)
		(end 114.375946 -225.3488)
		(width 0.1143)
		(layer "In15.Cu")
		(net "GMI_CPU0_G1_CPU1_G3_TX_DN<2>")
	)
	(segment
		(start 356.331012 -221.128844)
		(end 356.285292 -221.083124)
		(width 0.1143)
		(layer "In15.Cu")
		(net "GMI_CPU0_G1_CPU1_G3_TX_DN<2>")
	)
	(segment
		(start 357.119936 -242.55984)
		(end 357.088948 -242.54206)
		(width 0.1143)
		(layer "In15.Cu")
		(net "GMI_CPU0_G1_CPU1_G3_TX_DN<2>")
	)
	(segment
		(start 357.04907 -236.729524)
		(end 357.085646 -236.708188)
		(width 0.1143)
		(layer "In15.Cu")
		(net "GMI_CPU0_G1_CPU1_G3_TX_DN<2>")
	)
	(segment
		(start 114.446812 -231.179116)
		(end 114.374168 -231.221534)
		(width 0.1143)
		(layer "In15.Cu")
		(net "GMI_CPU0_G1_CPU1_G3_TX_DN<2>")
	)
	(segment
		(start 355.811328 -217.383106)
		(end 355.632258 -217.004392)
		(width 0.14224)
		(layer "In15.Cu")
		(net "GMI_CPU0_G1_CPU1_G3_TX_DN<2>")
	)
	(segment
		(start 357.08717 -243.18722)
		(end 357.088186 -243.186712)
		(width 0.1143)
		(layer "In15.Cu")
		(net "GMI_CPU0_G1_CPU1_G3_TX_DN<2>")
	)
	(segment
		(start 357.088186 -237.681516)
		(end 357.08717 -237.681008)
		(width 0.1143)
		(layer "In15.Cu")
		(net "GMI_CPU0_G1_CPU1_G3_TX_DN<2>")
	)
	(segment
		(start 357.085646 -231.848152)
		(end 357.08717 -231.847136)
		(width 0.1143)
		(layer "In15.Cu")
		(net "GMI_CPU0_G1_CPU1_G3_TX_DN<2>")
	)
	(segment
		(start 114.407696 -234.441746)
		(end 114.375946 -234.460034)
		(width 0.1143)
		(layer "In15.Cu")
		(net "GMI_CPU0_G1_CPU1_G3_TX_DN<2>")
	)
	(segment
		(start 114.406934 -236.70641)
		(end 114.407696 -236.706918)
		(width 0.1143)
		(layer "In15.Cu")
		(net "GMI_CPU0_G1_CPU1_G3_TX_DN<2>")
	)
	(segment
		(start 356.431088 -243.674138)
		(end 356.72903 -243.674138)
		(width 0.1143)
		(layer "In15.Cu")
		(net "GMI_CPU0_G1_CPU1_G3_TX_DN<2>")
	)
	(segment
		(start 357.119936 -237.699804)
		(end 357.088948 -237.682024)
		(width 0.1143)
		(layer "In15.Cu")
		(net "GMI_CPU0_G1_CPU1_G3_TX_DN<2>")
	)
	(segment
		(start 357.08717 -228.607366)
		(end 357.088186 -228.606858)
		(width 0.1143)
		(layer "In15.Cu")
		(net "GMI_CPU0_G1_CPU1_G3_TX_DN<2>")
	)
	(segment
		(start 357.088948 -237.682024)
		(end 357.088186 -237.681516)
		(width 0.1143)
		(layer "In15.Cu")
		(net "GMI_CPU0_G1_CPU1_G3_TX_DN<2>")
	)
	(segment
		(start 357.088186 -236.061504)
		(end 357.08717 -236.060996)
		(width 0.1143)
		(layer "In15.Cu")
		(net "GMI_CPU0_G1_CPU1_G3_TX_DN<2>")
	)
	(segment
		(start 114.407696 -223.747076)
		(end 114.446812 -223.769936)
		(width 0.1143)
		(layer "In15.Cu")
		(net "GMI_CPU0_G1_CPU1_G3_TX_DN<2>")
	)
	(segment
		(start 357.088186 -232.82148)
		(end 357.08717 -232.820972)
		(width 0.1143)
		(layer "In15.Cu")
		(net "GMI_CPU0_G1_CPU1_G3_TX_DN<2>")
	)
	(segment
		(start 114.446812 -226.31908)
		(end 114.407696 -226.34194)
		(width 0.1143)
		(layer "In15.Cu")
		(net "GMI_CPU0_G1_CPU1_G3_TX_DN<2>")
	)
	(segment
		(start 115.64747 -215.014556)
		(end 115.43538 -215.376252)
		(width 0.14224)
		(layer "In15.Cu")
		(net "GMI_CPU0_G1_CPU1_G3_TX_DN<2>")
	)
	(segment
		(start 357.080058 -240.916714)
		(end 357.04907 -240.89868)
		(width 0.1143)
		(layer "In15.Cu")
		(net "GMI_CPU0_G1_CPU1_G3_TX_DN<2>")
	)
	(segment
		(start 357.080058 -236.056678)
		(end 357.04907 -236.038644)
		(width 0.1143)
		(layer "In15.Cu")
		(net "GMI_CPU0_G1_CPU1_G3_TX_DN<2>")
	)
	(segment
		(start 357.08717 -231.847136)
		(end 357.088186 -231.846628)
		(width 0.1143)
		(layer "In15.Cu")
		(net "GMI_CPU0_G1_CPU1_G3_TX_DN<2>")
	)
	(segment
		(start 357.085392 -227.960174)
		(end 357.083868 -227.959158)
		(width 0.1143)
		(layer "In15.Cu")
		(net "GMI_CPU0_G1_CPU1_G3_TX_DN<2>")
	)
	(segment
		(start 357.081582 -242.537742)
		(end 357.080058 -242.536726)
		(width 0.1143)
		(layer "In15.Cu")
		(net "GMI_CPU0_G1_CPU1_G3_TX_DN<2>")
	)
	(segment
		(start 357.085646 -228.608382)
		(end 357.08717 -228.607366)
		(width 0.1143)
		(layer "In15.Cu")
		(net "GMI_CPU0_G1_CPU1_G3_TX_DN<2>")
	)
	(segment
		(start 114.446812 -239.278922)
		(end 114.407696 -239.301782)
		(width 0.1143)
		(layer "In15.Cu")
		(net "GMI_CPU0_G1_CPU1_G3_TX_DN<2>")
	)
	(segment
		(start 114.414808 -238.330994)
		(end 114.416332 -238.33201)
		(width 0.1143)
		(layer "In15.Cu")
		(net "GMI_CPU0_G1_CPU1_G3_TX_DN<2>")
	)
	(segment
		(start 114.15649 -221.066106)
		(end 114.15649 -221.198948)
		(width 0.1143)
		(layer "In15.Cu")
		(net "GMI_CPU0_G1_CPU1_G3_TX_DN<2>")
	)
	(segment
		(start 114.404902 -240.923318)
		(end 114.40287 -240.924588)
		(width 0.1143)
		(layer "In15.Cu")
		(net "GMI_CPU0_G1_CPU1_G3_TX_DN<2>")
	)
	(segment
		(start 114.766852 -243.674392)
		(end 115.064794 -243.674392)
		(width 0.1143)
		(layer "In15.Cu")
		(net "GMI_CPU0_G1_CPU1_G3_TX_DN<2>")
	)
	(segment
		(start 114.428778 -237.669578)
		(end 114.428524 -237.669578)
		(width 0.1143)
		(layer "In15.Cu")
		(net "GMI_CPU0_G1_CPU1_G3_TX_DN<2>")
	)
	(segment
		(start 114.375946 -223.728788)
		(end 114.407696 -223.747076)
		(width 0.1143)
		(layer "In15.Cu")
		(net "GMI_CPU0_G1_CPU1_G3_TX_DN<2>")
	)
	(segment
		(start 115.257834 -215.422226)
		(end 115.045744 -215.783668)
		(width 0.14224)
		(layer "In15.Cu")
		(net "GMI_CPU0_G1_CPU1_G3_TX_DN<2>")
	)
	(segment
		(start 357.088186 -231.846628)
		(end 357.088948 -231.84612)
		(width 0.1143)
		(layer "In15.Cu")
		(net "GMI_CPU0_G1_CPU1_G3_TX_DN<2>")
	)
	(segment
		(start 117.64772 -211.349844)
		(end 116.15674 -213.89086)
		(width 0.14224)
		(layer "In15.Cu")
		(net "GMI_CPU0_G1_CPU1_G3_TX_DN<2>")
	)
	(segment
		(start 357.080058 -239.296702)
		(end 357.04907 -239.278668)
		(width 0.1143)
		(layer "In15.Cu")
		(net "GMI_CPU0_G1_CPU1_G3_TX_DN<2>")
	)
	(segment
		(start 357.088186 -243.186712)
		(end 357.088948 -243.186204)
		(width 0.1143)
		(layer "In15.Cu")
		(net "GMI_CPU0_G1_CPU1_G3_TX_DN<2>")
	)
	(segment
		(start 357.055166 -229.562406)
		(end 357.04907 -229.55885)
		(width 0.1143)
		(layer "In15.Cu")
		(net "GMI_CPU0_G1_CPU1_G3_TX_DN<2>")
	)
	(segment
		(start 357.088948 -233.466132)
		(end 357.119936 -233.448352)
		(width 0.1143)
		(layer "In15.Cu")
		(net "GMI_CPU0_G1_CPU1_G3_TX_DN<2>")
	)
	(segment
		(start 114.438938 -239.96523)
		(end 114.446812 -239.969802)
		(width 0.1143)
		(layer "In15.Cu")
		(net "GMI_CPU0_G1_CPU1_G3_TX_DN<2>")
	)
	(segment
		(start 357.088948 -242.54206)
		(end 357.088186 -242.541552)
		(width 0.1143)
		(layer "In15.Cu")
		(net "GMI_CPU0_G1_CPU1_G3_TX_DN<2>")
	)
	(segment
		(start 114.375946 -236.68863)
		(end 114.406934 -236.70641)
		(width 0.1143)
		(layer "In15.Cu")
		(net "GMI_CPU0_G1_CPU1_G3_TX_DN<2>")
	)
	(segment
		(start 357.085646 -241.568224)
		(end 357.08717 -241.567208)
		(width 0.1143)
		(layer "In15.Cu")
		(net "GMI_CPU0_G1_CPU1_G3_TX_DN<2>")
	)
	(segment
		(start 114.407696 -236.706918)
		(end 114.408712 -236.707426)
		(width 0.1143)
		(layer "In15.Cu")
		(net "GMI_CPU0_G1_CPU1_G3_TX_DN<2>")
	)
	(segment
		(start 114.375946 -226.360228)
		(end 114.369088 -226.365054)
		(width 0.1143)
		(layer "In15.Cu")
		(net "GMI_CPU0_G1_CPU1_G3_TX_DN<2>")
	)
	(segment
		(start 357.081582 -240.91773)
		(end 357.080058 -240.916714)
		(width 0.1143)
		(layer "In15.Cu")
		(net "GMI_CPU0_G1_CPU1_G3_TX_DN<2>")
	)
	(segment
		(start 357.08717 -242.541044)
		(end 357.085646 -242.540028)
		(width 0.1143)
		(layer "In15.Cu")
		(net "GMI_CPU0_G1_CPU1_G3_TX_DN<2>")
	)
	(segment
		(start 357.081582 -239.297718)
		(end 357.080058 -239.296702)
		(width 0.1143)
		(layer "In15.Cu")
		(net "GMI_CPU0_G1_CPU1_G3_TX_DN<2>")
	)
	(segment
		(start 357.085646 -234.439968)
		(end 357.082852 -234.438444)
		(width 0.1143)
		(layer "In15.Cu")
		(net "GMI_CPU0_G1_CPU1_G3_TX_DN<2>")
	)
	(segment
		(start 357.119936 -236.079792)
		(end 357.088948 -236.062012)
		(width 0.1143)
		(layer "In15.Cu")
		(net "GMI_CPU0_G1_CPU1_G3_TX_DN<2>")
	)
	(segment
		(start 356.285292 -221.083124)
		(end 356.285292 -218.38412)
		(width 0.14224)
		(layer "In15.Cu")
		(net "GMI_CPU0_G1_CPU1_G3_TX_DN<2>")
	)
	(segment
		(start 357.082852 -232.818432)
		(end 357.081582 -232.81767)
		(width 0.1143)
		(layer "In15.Cu")
		(net "GMI_CPU0_G1_CPU1_G3_TX_DN<2>")
	)
	(segment
		(start 114.446812 -237.65891)
		(end 114.428778 -237.669578)
		(width 0.1143)
		(layer "In15.Cu")
		(net "GMI_CPU0_G1_CPU1_G3_TX_DN<2>")
	)
	(segment
		(start 354.389944 -214.379556)
		(end 354.210874 -214.000842)
		(width 0.14224)
		(layer "In15.Cu")
		(net "GMI_CPU0_G1_CPU1_G3_TX_DN<2>")
	)
	(segment
		(start 357.083868 -227.959158)
		(end 357.075232 -227.954332)
		(width 0.1143)
		(layer "In15.Cu")
		(net "GMI_CPU0_G1_CPU1_G3_TX_DN<2>")
	)
	(segment
		(start 114.407696 -224.721928)
		(end 114.375946 -224.740216)
		(width 0.1143)
		(layer "In15.Cu")
		(net "GMI_CPU0_G1_CPU1_G3_TX_DN<2>")
	)
	(segment
		(start 357.04907 -243.209572)
		(end 357.085646 -243.188236)
		(width 0.1143)
		(layer "In15.Cu")
		(net "GMI_CPU0_G1_CPU1_G3_TX_DN<2>")
	)
	(segment
		(start 354.799646 -215.559894)
		(end 354.863908 -215.38057)
		(width 0.14224)
		(layer "In15.Cu")
		(net "GMI_CPU0_G1_CPU1_G3_TX_DN<2>")
	)
	(segment
		(start 114.446812 -240.898934)
		(end 114.404902 -240.923318)
		(width 0.1143)
		(layer "In15.Cu")
		(net "GMI_CPU0_G1_CPU1_G3_TX_DN<2>")
	)
	(segment
		(start 114.404902 -241.56543)
		(end 114.44605 -241.589306)
		(width 0.1143)
		(layer "In15.Cu")
		(net "GMI_CPU0_G1_CPU1_G3_TX_DN<2>")
	)
	(segment
		(start 115.601242 -214.837264)
		(end 115.64747 -215.014556)
		(width 0.14224)
		(layer "In15.Cu")
		(net "GMI_CPU0_G1_CPU1_G3_TX_DN<2>")
	)
	(segment
		(start 357.08717 -240.921032)
		(end 357.085646 -240.920016)
		(width 0.1143)
		(layer "In15.Cu")
		(net "GMI_CPU0_G1_CPU1_G3_TX_DN<2>")
	)
	(segment
		(start 114.402616 -241.56416)
		(end 114.404902 -241.56543)
		(width 0.1143)
		(layer "In15.Cu")
		(net "GMI_CPU0_G1_CPU1_G3_TX_DN<2>")
	)
	(segment
		(start 357.085646 -236.708188)
		(end 357.08717 -236.707172)
		(width 0.1143)
		(layer "In15.Cu")
		(net "GMI_CPU0_G1_CPU1_G3_TX_DN<2>")
	)
	(segment
		(start 357.08717 -227.96119)
		(end 357.086408 -227.960682)
		(width 0.1143)
		(layer "In15.Cu")
		(net "GMI_CPU0_G1_CPU1_G3_TX_DN<2>")
	)
	(segment
		(start 357.082852 -234.438444)
		(end 357.081582 -234.437682)
		(width 0.1143)
		(layer "In15.Cu")
		(net "GMI_CPU0_G1_CPU1_G3_TX_DN<2>")
	)
	(segment
		(start 357.119936 -240.939828)
		(end 357.088948 -240.922048)
		(width 0.1143)
		(layer "In15.Cu")
		(net "GMI_CPU0_G1_CPU1_G3_TX_DN<2>")
	)
	(segment
		(start 156.917136 -179.151026)
		(end 117.64772 -211.349844)
		(width 0.14224)
		(layer "In15.Cu")
		(net "GMI_CPU0_G1_CPU1_G3_TX_DN<2>")
	)
	(segment
		(start 114.399822 -243.182394)
		(end 114.44605 -243.209318)
		(width 0.1143)
		(layer "In15.Cu")
		(net "GMI_CPU0_G1_CPU1_G3_TX_DN<2>")
	)
	(segment
		(start 357.08717 -236.707172)
		(end 357.088186 -236.706664)
		(width 0.1143)
		(layer "In15.Cu")
		(net "GMI_CPU0_G1_CPU1_G3_TX_DN<2>")
	)
	(segment
		(start 114.21999 -231.524302)
		(end 114.21999 -231.53116)
		(width 0.1143)
		(layer "In15.Cu")
		(net "GMI_CPU0_G1_CPU1_G3_TX_DN<2>")
	)
	(segment
		(start 357.085646 -240.920016)
		(end 357.082852 -240.918492)
		(width 0.1143)
		(layer "In15.Cu")
		(net "GMI_CPU0_G1_CPU1_G3_TX_DN<2>")
	)
	(segment
		(start 357.083614 -226.338892)
		(end 357.082852 -226.338384)
		(width 0.1143)
		(layer "In15.Cu")
		(net "GMI_CPU0_G1_CPU1_G3_TX_DN<2>")
	)
	(segment
		(start 353.851972 -213.557612)
		(end 353.916234 -213.378288)
		(width 0.14224)
		(layer "In15.Cu")
		(net "GMI_CPU0_G1_CPU1_G3_TX_DN<2>")
	)
	(segment
		(start 357.119936 -232.839768)
		(end 357.088948 -232.821988)
		(width 0.1143)
		(layer "In15.Cu")
		(net "GMI_CPU0_G1_CPU1_G3_TX_DN<2>")
	)
	(segment
		(start 115.045744 -215.783668)
		(end 115.091972 -215.96096)
		(width 0.14224)
		(layer "In15.Cu")
		(net "GMI_CPU0_G1_CPU1_G3_TX_DN<2>")
	)
	(segment
		(start 317.647828 -181.723284)
		(end 310.648096 -177.760884)
		(width 0.14224)
		(layer "In15.Cu")
		(net "GMI_CPU0_G1_CPU1_G3_TX_DN<2>")
	)
	(segment
		(start 114.399822 -238.322358)
		(end 114.414808 -238.330994)
		(width 0.1143)
		(layer "In15.Cu")
		(net "GMI_CPU0_G1_CPU1_G3_TX_DN<2>")
	)
	(segment
		(start 308.394862 -176.955196)
		(end 302.913288 -176.955196)
		(width 0.14224)
		(layer "In15.Cu")
		(net "GMI_CPU0_G1_CPU1_G3_TX_DN<2>")
	)
	(segment
		(start 357.085646 -239.300004)
		(end 357.082852 -239.29848)
		(width 0.1143)
		(layer "In15.Cu")
		(net "GMI_CPU0_G1_CPU1_G3_TX_DN<2>")
	)
	(segment
		(start 354.863908 -215.38057)
		(end 354.684838 -215.001856)
		(width 0.14224)
		(layer "In15.Cu")
		(net "GMI_CPU0_G1_CPU1_G3_TX_DN<2>")
	)
	(segment
		(start 357.085646 -238.3282)
		(end 357.08717 -238.327184)
		(width 0.1143)
		(layer "In15.Cu")
		(net "GMI_CPU0_G1_CPU1_G3_TX_DN<2>")
	)
	(segment
		(start 357.088186 -242.541552)
		(end 357.08717 -242.541044)
		(width 0.1143)
		(layer "In15.Cu")
		(net "GMI_CPU0_G1_CPU1_G3_TX_DN<2>")
	)
	(segment
		(start 357.088948 -240.922048)
		(end 357.088186 -240.92154)
		(width 0.1143)
		(layer "In15.Cu")
		(net "GMI_CPU0_G1_CPU1_G3_TX_DN<2>")
	)
	(segment
		(start 357.139748 -242.574064)
		(end 357.119936 -242.55984)
		(width 0.1143)
		(layer "In15.Cu")
		(net "GMI_CPU0_G1_CPU1_G3_TX_DN<2>")
	)
	(segment
		(start 356.18166 -224.741232)
		(end 356.179882 -224.739962)
		(width 0.1143)
		(layer "In15.Cu")
		(net "GMI_CPU0_G1_CPU1_G3_TX_DN<2>")
	)
	(segment
		(start 357.080058 -234.436666)
		(end 357.04907 -234.418632)
		(width 0.1143)
		(layer "In15.Cu")
		(net "GMI_CPU0_G1_CPU1_G3_TX_DN<2>")
	)
	(segment
		(start 114.419634 -239.954054)
		(end 114.438938 -239.96523)
		(width 0.1143)
		(layer "In15.Cu")
		(net "GMI_CPU0_G1_CPU1_G3_TX_DN<2>")
	)
	(segment
		(start 114.375946 -231.828594)
		(end 114.446812 -231.869742)
		(width 0.1143)
		(layer "In15.Cu")
		(net "GMI_CPU0_G1_CPU1_G3_TX_DN<2>")
	)
	(segment
		(start 357.088186 -240.92154)
		(end 357.08717 -240.921032)
		(width 0.1143)
		(layer "In15.Cu")
		(net "GMI_CPU0_G1_CPU1_G3_TX_DN<2>")
	)
	(segment
		(start 357.121714 -231.22128)
		(end 357.088186 -231.201722)
		(width 0.1143)
		(layer "In15.Cu")
		(net "GMI_CPU0_G1_CPU1_G3_TX_DN<2>")
	)
	(segment
		(start 357.080058 -242.536726)
		(end 357.04907 -242.518692)
		(width 0.1143)
		(layer "In15.Cu")
		(net "GMI_CPU0_G1_CPU1_G3_TX_DN<2>")
	)
	(segment
		(start 354.210874 -214.000842)
		(end 354.031296 -213.936834)
		(width 0.14224)
		(layer "In15.Cu")
		(net "GMI_CPU0_G1_CPU1_G3_TX_DN<2>")
	)
	(segment
		(start 357.073708 -227.953316)
		(end 357.057452 -227.943918)
		(width 0.1143)
		(layer "In15.Cu")
		(net "GMI_CPU0_G1_CPU1_G3_TX_DN<2>")
	)
	(segment
		(start 114.379248 -230.210614)
		(end 114.422682 -230.23576)
		(width 0.1143)
		(layer "In15.Cu")
		(net "GMI_CPU0_G1_CPU1_G3_TX_DN<2>")
	)
	(segment
		(start 357.099616 -227.968302)
		(end 357.08717 -227.96119)
		(width 0.1143)
		(layer "In15.Cu")
		(net "GMI_CPU0_G1_CPU1_G3_TX_DN<2>")
	)
	(segment
		(start 114.407696 -223.101916)
		(end 114.375946 -223.120204)
		(width 0.1143)
		(layer "In15.Cu")
		(net "GMI_CPU0_G1_CPU1_G3_TX_DN<2>")
	)
	(segment
		(start 116.15674 -213.89086)
		(end 116.202968 -214.068152)
		(width 0.14224)
		(layer "In15.Cu")
		(net "GMI_CPU0_G1_CPU1_G3_TX_DN<2>")
	)
	(segment
		(start 114.879882 -216.322656)
		(end 114.702336 -216.36863)
		(width 0.14224)
		(layer "In15.Cu")
		(net "GMI_CPU0_G1_CPU1_G3_TX_DN<2>")
	)
	(segment
		(start 114.428524 -242.529614)
		(end 114.407188 -242.54206)
		(width 0.1143)
		(layer "In15.Cu")
		(net "GMI_CPU0_G1_CPU1_G3_TX_DN<2>")
	)
	(segment
		(start 114.375946 -233.448606)
		(end 114.446812 -233.489754)
		(width 0.1143)
		(layer "In15.Cu")
		(net "GMI_CPU0_G1_CPU1_G3_TX_DN<2>")
	)
	(segment
		(start 114.370104 -231.82453)
		(end 114.375946 -231.828594)
		(width 0.1143)
		(layer "In15.Cu")
		(net "GMI_CPU0_G1_CPU1_G3_TX_DN<2>")
	)
	(segment
		(start 356.148132 -222.12681)
		(end 356.148894 -222.126302)
		(width 0.1143)
		(layer "In15.Cu")
		(net "GMI_CPU0_G1_CPU1_G3_TX_DN<2>")
	)
	(segment
		(start 356.107238 -223.07804)
		(end 356.096316 -223.069658)
		(width 0.1143)
		(layer "In15.Cu")
		(net "GMI_CPU0_G1_CPU1_G3_TX_DN<2>")
	)
	(segment
		(start 357.085646 -233.468164)
		(end 357.08717 -233.467148)
		(width 0.1143)
		(layer "In15.Cu")
		(net "GMI_CPU0_G1_CPU1_G3_TX_DN<2>")
	)
	(segment
		(start 114.407696 -239.301782)
		(end 114.375946 -239.32007)
		(width 0.1143)
		(layer "In15.Cu")
		(net "GMI_CPU0_G1_CPU1_G3_TX_DN<2>")
	)
	(segment
		(start 357.04907 -228.629718)
		(end 357.085646 -228.608382)
		(width 0.1143)
		(layer "In15.Cu")
		(net "GMI_CPU0_G1_CPU1_G3_TX_DN<2>")
	)
	(segment
		(start 114.375946 -222.108776)
		(end 114.446812 -222.149924)
		(width 0.1143)
		(layer "In15.Cu")
		(net "GMI_CPU0_G1_CPU1_G3_TX_DN<2>")
	)
	(segment
		(start 356.181406 -223.120966)
		(end 356.107238 -223.07804)
		(width 0.1143)
		(layer "In15.Cu")
		(net "GMI_CPU0_G1_CPU1_G3_TX_DN<2>")
	)
	(segment
		(start 357.137716 -240.952528)
		(end 357.119936 -240.939828)
		(width 0.1143)
		(layer "In15.Cu")
		(net "GMI_CPU0_G1_CPU1_G3_TX_DN<2>")
	)
	(segment
		(start 114.428778 -242.529614)
		(end 114.428524 -242.529614)
		(width 0.1143)
		(layer "In15.Cu")
		(net "GMI_CPU0_G1_CPU1_G3_TX_DN<2>")
	)
	(segment
		(start 357.089456 -226.342194)
		(end 357.084884 -226.339654)
		(width 0.1143)
		(layer "In15.Cu")
		(net "GMI_CPU0_G1_CPU1_G3_TX_DN<2>")
	)
	(segment
		(start 357.088186 -239.301528)
		(end 357.08717 -239.30102)
		(width 0.1143)
		(layer "In15.Cu")
		(net "GMI_CPU0_G1_CPU1_G3_TX_DN<2>")
	)
	(segment
		(start 356.648766 -225.54946)
		(end 356.57917 -225.50882)
		(width 0.1143)
		(layer "In15.Cu")
		(net "GMI_CPU0_G1_CPU1_G3_TX_DN<2>")
	)
	(segment
		(start 357.082852 -242.538504)
		(end 357.081582 -242.537742)
		(width 0.1143)
		(layer "In15.Cu")
		(net "GMI_CPU0_G1_CPU1_G3_TX_DN<2>")
	)
	(segment
		(start 356.179882 -224.739962)
		(end 356.148894 -224.722182)
		(width 0.1143)
		(layer "In15.Cu")
		(net "GMI_CPU0_G1_CPU1_G3_TX_DN<2>")
	)
	(segment
		(start 355.74732 -217.562176)
		(end 355.811328 -217.383106)
		(width 0.14224)
		(layer "In15.Cu")
		(net "GMI_CPU0_G1_CPU1_G3_TX_DN<2>")
	)
	(segment
		(start 357.075232 -227.954332)
		(end 357.073708 -227.953316)
		(width 0.1143)
		(layer "In15.Cu")
		(net "GMI_CPU0_G1_CPU1_G3_TX_DN<2>")
	)
	(segment
		(start 357.04907 -239.969548)
		(end 357.085646 -239.948212)
		(width 0.1143)
		(layer "In15.Cu")
		(net "GMI_CPU0_G1_CPU1_G3_TX_DN<2>")
	)
	(segment
		(start 354.50526 -214.937848)
		(end 354.325936 -214.558626)
		(width 0.14224)
		(layer "In15.Cu")
		(net "GMI_CPU0_G1_CPU1_G3_TX_DN<2>")
	)
	(segment
		(start 357.08717 -239.947196)
		(end 357.088186 -239.946688)
		(width 0.1143)
		(layer "In15.Cu")
		(net "GMI_CPU0_G1_CPU1_G3_TX_DN<2>")
	)
	(segment
		(start 114.446812 -223.079056)
		(end 114.407696 -223.101916)
		(width 0.1143)
		(layer "In15.Cu")
		(net "GMI_CPU0_G1_CPU1_G3_TX_DN<2>")
	)
	(segment
		(start 114.375946 -224.740216)
		(end 114.370104 -224.74428)
		(width 0.1143)
		(layer "In15.Cu")
		(net "GMI_CPU0_G1_CPU1_G3_TX_DN<2>")
	)
	(segment
		(start 357.119936 -234.45978)
		(end 357.088948 -234.442)
		(width 0.1143)
		(layer "In15.Cu")
		(net "GMI_CPU0_G1_CPU1_G3_TX_DN<2>")
	)
	(segment
		(start 357.08717 -239.30102)
		(end 357.085646 -239.300004)
		(width 0.1143)
		(layer "In15.Cu")
		(net "GMI_CPU0_G1_CPU1_G3_TX_DN<2>")
	)
	(segment
		(start 355.337618 -216.381838)
		(end 355.158548 -216.003124)
		(width 0.14224)
		(layer "In15.Cu")
		(net "GMI_CPU0_G1_CPU1_G3_TX_DN<2>")
	)
	(segment
		(start 357.082852 -237.678468)
		(end 357.081582 -237.677706)
		(width 0.1143)
		(layer "In15.Cu")
		(net "GMI_CPU0_G1_CPU1_G3_TX_DN<2>")
	)
	(segment
		(start 356.72903 -243.674138)
		(end 356.811834 -243.591334)
		(width 0.1143)
		(layer "In15.Cu")
		(net "GMI_CPU0_G1_CPU1_G3_TX_DN<2>")
	)
	(segment
		(start 357.119936 -241.548412)
		(end 357.137716 -241.535712)
		(width 0.1143)
		(layer "In15.Cu")
		(net "GMI_CPU0_G1_CPU1_G3_TX_DN<2>")
	)
	(segment
		(start 114.375946 -228.588824)
		(end 114.407696 -228.607112)
		(width 0.1143)
		(layer "In15.Cu")
		(net "GMI_CPU0_G1_CPU1_G3_TX_DN<2>")
	)
	(segment
		(start 114.369088 -233.44378)
		(end 114.375946 -233.448606)
		(width 0.1143)
		(layer "In15.Cu")
		(net "GMI_CPU0_G1_CPU1_G3_TX_DN<2>")
	)
	(segment
		(start 357.081582 -236.057694)
		(end 357.080058 -236.056678)
		(width 0.1143)
		(layer "In15.Cu")
		(net "GMI_CPU0_G1_CPU1_G3_TX_DN<2>")
	)
	(segment
		(start 114.446812 -242.518946)
		(end 114.428778 -242.529614)
		(width 0.1143)
		(layer "In15.Cu")
		(net "GMI_CPU0_G1_CPU1_G3_TX_DN<2>")
	)
	(segment
		(start 357.088948 -239.302036)
		(end 357.088186 -239.301528)
		(width 0.1143)
		(layer "In15.Cu")
		(net "GMI_CPU0_G1_CPU1_G3_TX_DN<2>")
	)
	(segment
		(start 356.335838 -225.044254)
		(end 356.335838 -225.042222)
		(width 0.1143)
		(layer "In15.Cu")
		(net "GMI_CPU0_G1_CPU1_G3_TX_DN<2>")
	)
	(segment
		(start 357.088948 -243.186204)
		(end 357.119936 -243.168424)
		(width 0.1143)
		(layer "In15.Cu")
		(net "GMI_CPU0_G1_CPU1_G3_TX_DN<2>")
	)
	(segment
		(start 114.407696 -227.961952)
		(end 114.375946 -227.98024)
		(width 0.1143)
		(layer "In15.Cu")
		(net "GMI_CPU0_G1_CPU1_G3_TX_DN<2>")
	)
	(segment
		(start 355.632258 -217.004392)
		(end 355.45268 -216.940384)
		(width 0.14224)
		(layer "In15.Cu")
		(net "GMI_CPU0_G1_CPU1_G3_TX_DN<2>")
	)
	(segment
		(start 357.088186 -238.326676)
		(end 357.088948 -238.326168)
		(width 0.1143)
		(layer "In15.Cu")
		(net "GMI_CPU0_G1_CPU1_G3_TX_DN<2>")
	)
	(segment
		(start 357.088948 -232.821988)
		(end 357.088186 -232.82148)
		(width 0.1143)
		(layer "In15.Cu")
		(net "GMI_CPU0_G1_CPU1_G3_TX_DN<2>")
	)
	(segment
		(start 356.107238 -222.150432)
		(end 356.147116 -222.127318)
		(width 0.1143)
		(layer "In15.Cu")
		(net "GMI_CPU0_G1_CPU1_G3_TX_DN<2>")
	)
	(segment
		(start 357.08717 -241.567208)
		(end 357.088186 -241.5667)
		(width 0.1143)
		(layer "In15.Cu")
		(net "GMI_CPU0_G1_CPU1_G3_TX_DN<2>")
	)
	(segment
		(start 357.08717 -238.327184)
		(end 357.088186 -238.326676)
		(width 0.1143)
		(layer "In15.Cu")
		(net "GMI_CPU0_G1_CPU1_G3_TX_DN<2>")
	)
	(segment
		(start 353.916234 -213.378288)
		(end 352.434144 -210.246214)
		(width 0.14224)
		(layer "In15.Cu")
		(net "GMI_CPU0_G1_CPU1_G3_TX_DN<2>")
	)
	(segment
		(start 114.363754 -239.920018)
		(end 114.375946 -239.928654)
		(width 0.1143)
		(layer "In15.Cu")
		(net "GMI_CPU0_G1_CPU1_G3_TX_DN<2>")
	)
	(segment
		(start 357.082852 -226.338384)
		(end 357.049832 -226.319334)
		(width 0.1143)
		(layer "In15.Cu")
		(net "GMI_CPU0_G1_CPU1_G3_TX_DN<2>")
	)
	(segment
		(start 115.43538 -215.376252)
		(end 115.257834 -215.422226)
		(width 0.14224)
		(layer "In15.Cu")
		(net "GMI_CPU0_G1_CPU1_G3_TX_DN<2>")
	)
	(segment
		(start 357.119936 -243.168424)
		(end 357.139748 -243.1542)
		(width 0.1143)
		(layer "In15.Cu")
		(net "GMI_CPU0_G1_CPU1_G3_TX_DN<2>")
	)
	(segment
		(start 356.094538 -223.780096)
		(end 356.106476 -223.770698)
		(width 0.1143)
		(layer "In15.Cu")
		(net "GMI_CPU0_G1_CPU1_G3_TX_DN<2>")
	)
	(segment
		(start 357.04907 -241.58956)
		(end 357.085646 -241.568224)
		(width 0.1143)
		(layer "In15.Cu")
		(net "GMI_CPU0_G1_CPU1_G3_TX_DN<2>")
	)
	(segment
		(start 357.088186 -234.441492)
		(end 357.08717 -234.440984)
		(width 0.1143)
		(layer "In15.Cu")
		(net "GMI_CPU0_G1_CPU1_G3_TX_DN<2>")
	)
	(segment
		(start 357.057452 -227.943918)
		(end 357.05669 -227.94341)
		(width 0.1143)
		(layer "In15.Cu")
		(net "GMI_CPU0_G1_CPU1_G3_TX_DN<2>")
	)
	(segment
		(start 357.088948 -236.062012)
		(end 357.088186 -236.061504)
		(width 0.1143)
		(layer "In15.Cu")
		(net "GMI_CPU0_G1_CPU1_G3_TX_DN<2>")
	)
	(segment
		(start 114.407696 -232.821734)
		(end 114.375946 -232.840022)
		(width 0.1143)
		(layer "In15.Cu")
		(net "GMI_CPU0_G1_CPU1_G3_TX_DN<2>")
	)
	(segment
		(start 357.04907 -233.4895)
		(end 357.085646 -233.468164)
		(width 0.1143)
		(layer "In15.Cu")
		(net "GMI_CPU0_G1_CPU1_G3_TX_DN<2>")
	)
	(segment
		(start 357.088948 -238.326168)
		(end 357.119936 -238.308388)
		(width 0.1143)
		(layer "In15.Cu")
		(net "GMI_CPU0_G1_CPU1_G3_TX_DN<2>")
	)
	(segment
		(start 357.08717 -237.681008)
		(end 357.085646 -237.679992)
		(width 0.1143)
		(layer "In15.Cu")
		(net "GMI_CPU0_G1_CPU1_G3_TX_DN<2>")
	)
	(segment
		(start 302.913288 -176.955196)
		(end 165.306502 -176.151286)
		(width 0.14224)
		(layer "In15.Cu")
		(net "GMI_CPU0_G1_CPU1_G3_TX_DN<2>")
	)
	(segment
		(start 114.375946 -235.068618)
		(end 114.446812 -235.109766)
		(width 0.1143)
		(layer "In15.Cu")
		(net "GMI_CPU0_G1_CPU1_G3_TX_DN<2>")
	)
	(segment
		(start 357.04907 -238.349536)
		(end 357.085646 -238.3282)
		(width 0.1143)
		(layer "In15.Cu")
		(net "GMI_CPU0_G1_CPU1_G3_TX_DN<2>")
	)
	(segment
		(start 357.085646 -235.088176)
		(end 357.08717 -235.08716)
		(width 0.1143)
		(layer "In15.Cu")
		(net "GMI_CPU0_G1_CPU1_G3_TX_DN<2>")
	)
	(segment
		(start 357.05542 -229.56266)
		(end 357.055166 -229.562406)
		(width 0.1143)
		(layer "In15.Cu")
		(net "GMI_CPU0_G1_CPU1_G3_TX_DN<2>")
	)
	(segment
		(start 114.20221 -220.991938)
		(end 114.20221 -221.020386)
		(width 0.1143)
		(layer "In15.Cu")
		(net "GMI_CPU0_G1_CPU1_G3_TX_DN<2>")
	)
	(segment
		(start 357.088186 -241.5667)
		(end 357.088948 -241.566192)
		(width 0.1143)
		(layer "In15.Cu")
		(net "GMI_CPU0_G1_CPU1_G3_TX_DN<2>")
	)
	(segment
		(start 357.088186 -239.946688)
		(end 357.088948 -239.94618)
		(width 0.1143)
		(layer "In15.Cu")
		(net "GMI_CPU0_G1_CPU1_G3_TX_DN<2>")
	)
	(segment
		(start 357.085646 -236.05998)
		(end 357.082852 -236.058456)
		(width 0.1143)
		(layer "In15.Cu")
		(net "GMI_CPU0_G1_CPU1_G3_TX_DN<2>")
	)
	(segment
		(start 114.408712 -236.707426)
		(end 114.446812 -236.729778)
		(width 0.1143)
		(layer "In15.Cu")
		(net "GMI_CPU0_G1_CPU1_G3_TX_DN<2>")
	)
	(segment
		(start 116.202968 -214.068152)
		(end 115.990878 -214.429848)
		(width 0.14224)
		(layer "In15.Cu")
		(net "GMI_CPU0_G1_CPU1_G3_TX_DN<2>")
	)
	(segment
		(start 114.20221 -221.020386)
		(end 114.15649 -221.066106)
		(width 0.1143)
		(layer "In15.Cu")
		(net "GMI_CPU0_G1_CPU1_G3_TX_DN<2>")
	)
	(segment
		(start 355.926644 -217.941398)
		(end 355.74732 -217.562176)
		(width 0.14224)
		(layer "In15.Cu")
		(net "GMI_CPU0_G1_CPU1_G3_TX_DN<2>")
	)
	(segment
		(start 115.813332 -214.475822)
		(end 115.601242 -214.837264)
		(width 0.14224)
		(layer "In15.Cu")
		(net "GMI_CPU0_G1_CPU1_G3_TX_DN<2>")
	)
	(segment
		(start 356.336092 -221.39275)
		(end 356.331012 -221.38767)
		(width 0.1143)
		(layer "In15.Cu")
		(net "GMI_CPU0_G1_CPU1_G3_TX_DN<2>")
	)
	(segment
		(start 357.084122 -226.339146)
		(end 357.083614 -226.338892)
		(width 0.1143)
		(layer "In15.Cu")
		(net "GMI_CPU0_G1_CPU1_G3_TX_DN<2>")
	)
	(segment
		(start 356.150164 -222.12554)
		(end 356.179882 -222.108522)
		(width 0.1143)
		(layer "In15.Cu")
		(net "GMI_CPU0_G1_CPU1_G3_TX_DN<2>")
	)
	(segment
		(start 115.091972 -215.96096)
		(end 114.879882 -216.322656)
		(width 0.14224)
		(layer "In15.Cu")
		(net "GMI_CPU0_G1_CPU1_G3_TX_DN<2>")
	)
	(segment
		(start 114.357404 -235.055156)
		(end 114.375946 -235.068618)
		(width 0.1143)
		(layer "In15.Cu")
		(net "GMI_CPU0_G1_CPU1_G3_TX_DN<2>")
	)
	(segment
		(start 114.416332 -238.33201)
		(end 114.44605 -238.349282)
		(width 0.1143)
		(layer "In15.Cu")
		(net "GMI_CPU0_G1_CPU1_G3_TX_DN<2>")
	)
	(segment
		(start 114.702336 -216.36863)
		(end 114.20221 -217.221054)
		(width 0.14224)
		(layer "In15.Cu")
		(net "GMI_CPU0_G1_CPU1_G3_TX_DN<2>")
	)
	(segment
		(start 357.080058 -232.816654)
		(end 357.04907 -232.79862)
		(width 0.1143)
		(layer "In15.Cu")
		(net "GMI_CPU0_G1_CPU1_G3_TX_DN<2>")
	)
	(segment
		(start 357.088186 -228.606858)
		(end 357.099616 -228.600254)
		(width 0.1143)
		(layer "In15.Cu")
		(net "GMI_CPU0_G1_CPU1_G3_TX_DN<2>")
	)
	(segment
		(start 357.082852 -236.058456)
		(end 357.081582 -236.057694)
		(width 0.1143)
		(layer "In15.Cu")
		(net "GMI_CPU0_G1_CPU1_G3_TX_DN<2>")
	)
	(segment
		(start 356.106222 -218.005406)
		(end 355.926644 -217.941398)
		(width 0.14224)
		(layer "In15.Cu")
		(net "GMI_CPU0_G1_CPU1_G3_TX_DN<2>")
	)
	(segment
		(start 357.088948 -235.086144)
		(end 357.119936 -235.068364)
		(width 0.1143)
		(layer "In15.Cu")
		(net "GMI_CPU0_G1_CPU1_G3_TX_DN<2>")
	)
	(segment
		(start 357.085646 -239.948212)
		(end 357.08717 -239.947196)
		(width 0.1143)
		(layer "In15.Cu")
		(net "GMI_CPU0_G1_CPU1_G3_TX_DN<2>")
	)
	(segment
		(start 357.081582 -237.677706)
		(end 357.080058 -237.67669)
		(width 0.1143)
		(layer "In15.Cu")
		(net "GMI_CPU0_G1_CPU1_G3_TX_DN<2>")
	)
	(segment
		(start 355.158548 -216.003124)
		(end 354.97897 -215.939116)
		(width 0.14224)
		(layer "In15.Cu")
		(net "GMI_CPU0_G1_CPU1_G3_TX_DN<2>")
	)
	(segment
		(start 357.08717 -234.440984)
		(end 357.085646 -234.439968)
		(width 0.1143)
		(layer "In15.Cu")
		(net "GMI_CPU0_G1_CPU1_G3_TX_DN<2>")
	)
	(segment
		(start 114.377724 -239.92967)
		(end 114.419634 -239.954054)
		(width 0.1143)
		(layer "In15.Cu")
		(net "GMI_CPU0_G1_CPU1_G3_TX_DN<2>")
	)
	(segment
		(start 354.325936 -214.558626)
		(end 354.389944 -214.379556)
		(width 0.14224)
		(layer "In15.Cu")
		(net "GMI_CPU0_G1_CPU1_G3_TX_DN<2>")
	)
	(segment
		(start 114.446812 -234.418886)
		(end 114.407696 -234.441746)
		(width 0.1143)
		(layer "In15.Cu")
		(net "GMI_CPU0_G1_CPU1_G3_TX_DN<2>")
	)
	(segment
		(start 357.082852 -239.29848)
		(end 357.081582 -239.297718)
		(width 0.1143)
		(layer "In15.Cu")
		(net "GMI_CPU0_G1_CPU1_G3_TX_DN<2>")
	)
	(segment
		(start 357.04907 -231.869488)
		(end 357.085646 -231.848152)
		(width 0.1143)
		(layer "In15.Cu")
		(net "GMI_CPU0_G1_CPU1_G3_TX_DN<2>")
	)
	(segment
		(start 114.15649 -221.198948)
		(end 114.21999 -221.262448)
		(width 0.1143)
		(layer "In15.Cu")
		(net "GMI_CPU0_G1_CPU1_G3_TX_DN<2>")
	)
	(segment
		(start 357.088948 -239.94618)
		(end 357.119936 -239.9284)
		(width 0.1143)
		(layer "In15.Cu")
		(net "GMI_CPU0_G1_CPU1_G3_TX_DN<2>")
	)
	(segment
		(start 357.08717 -233.467148)
		(end 357.088186 -233.46664)
		(width 0.1143)
		(layer "In15.Cu")
		(net "GMI_CPU0_G1_CPU1_G3_TX_DN<2>")
	)
	(segment
		(start 114.446812 -224.699068)
		(end 114.407696 -224.721928)
		(width 0.1143)
		(layer "In15.Cu")
		(net "GMI_CPU0_G1_CPU1_G3_TX_DN<2>")
	)
	(segment
		(start 357.081582 -232.81767)
		(end 357.080058 -232.816654)
		(width 0.1143)
		(layer "In15.Cu")
		(net "GMI_CPU0_G1_CPU1_G3_TX_DN<2>")
	)
	(segment
		(start 357.116634 -229.598474)
		(end 357.05542 -229.56266)
		(width 0.1143)
		(layer "In15.Cu")
		(net "GMI_CPU0_G1_CPU1_G3_TX_DN<2>")
	)
	(segment
		(start 357.081582 -234.437682)
		(end 357.080058 -234.436666)
		(width 0.1143)
		(layer "In15.Cu")
		(net "GMI_CPU0_G1_CPU1_G3_TX_DN<2>")
	)
	(segment
		(start 357.08717 -232.820972)
		(end 357.085646 -232.819956)
		(width 0.1143)
		(layer "In15.Cu")
		(net "GMI_CPU0_G1_CPU1_G3_TX_DN<2>")
	)
	(segment
		(start 356.331012 -221.38767)
		(end 356.331012 -221.128844)
		(width 0.1143)
		(layer "In15.Cu")
		(net "GMI_CPU0_G1_CPU1_G3_TX_DN<2>")
	)
	(segment
		(start 114.374676 -230.207566)
		(end 114.379248 -230.210614)
		(width 0.1143)
		(layer "In15.Cu")
		(net "GMI_CPU0_G1_CPU1_G3_TX_DN<2>")
	)
	(segment
		(start 352.434144 -210.246214)
		(end 317.647828 -181.723284)
		(width 0.14224)
		(layer "In15.Cu")
		(net "GMI_CPU0_G1_CPU1_G3_TX_DN<2>")
	)
	(segment
		(start 354.684838 -215.001856)
		(end 354.50526 -214.937848)
		(width 0.14224)
		(layer "In15.Cu")
		(net "GMI_CPU0_G1_CPU1_G3_TX_DN<2>")
	)
	(segment
		(start 357.088948 -234.442)
		(end 357.088186 -234.441492)
		(width 0.1143)
		(layer "In15.Cu")
		(net "GMI_CPU0_G1_CPU1_G3_TX_DN<2>")
	)
	(segment
		(start 310.648096 -177.760884)
		(end 308.394862 -176.955196)
		(width 0.14224)
		(layer "In15.Cu")
		(net "GMI_CPU0_G1_CPU1_G3_TX_DN<2>")
	)
	(segment
		(start 114.20221 -217.221054)
		(end 114.20221 -220.991938)
		(width 0.14224)
		(layer "In15.Cu")
		(net "GMI_CPU0_G1_CPU1_G3_TX_DN<2>")
	)
	(segment
		(start 165.306502 -176.151286)
		(end 156.917136 -179.151026)
		(width 0.14224)
		(layer "In15.Cu")
		(net "GMI_CPU0_G1_CPU1_G3_TX_DN<2>")
	)
	(segment
		(start 357.088186 -231.201722)
		(end 357.04907 -231.178862)
		(width 0.1143)
		(layer "In15.Cu")
		(net "GMI_CPU0_G1_CPU1_G3_TX_DN<2>")
	)
	(segment
		(start 357.05161 -230.247952)
		(end 357.116888 -230.210106)
		(width 0.1143)
		(layer "In15.Cu")
		(net "GMI_CPU0_G1_CPU1_G3_TX_DN<2>")
	)
	(segment
		(start 357.084884 -226.339654)
		(end 357.084122 -226.339146)
		(width 0.1143)
		(layer "In15.Cu")
		(net "GMI_CPU0_G1_CPU1_G3_TX_DN<2>")
	)
	(segment
		(start 114.407696 -236.061758)
		(end 114.375946 -236.080046)
		(width 0.1143)
		(layer "In15.Cu")
		(net "GMI_CPU0_G1_CPU1_G3_TX_DN<2>")
	)
	(segment
		(start 357.08717 -226.987354)
		(end 357.089202 -226.986338)
		(width 0.1143)
		(layer "In15.Cu")
		(net "GMI_CPU0_G1_CPU1_G3_TX_DN<2>")
	)
	(segment
		(start 357.085646 -243.188236)
		(end 357.08717 -243.18722)
		(width 0.1143)
		(layer "In15.Cu")
		(net "GMI_CPU0_G1_CPU1_G3_TX_DN<2>")
	)
	(segment
		(start 357.088186 -236.706664)
		(end 357.088948 -236.706156)
		(width 0.1143)
		(layer "In15.Cu")
		(net "GMI_CPU0_G1_CPU1_G3_TX_DN<2>")
	)
	(segment
		(start 114.446812 -229.559104)
		(end 114.392964 -229.590346)
		(width 0.1143)
		(layer "In15.Cu")
		(net "GMI_CPU0_G1_CPU1_G3_TX_DN<2>")
	)
	(segment
		(start 114.375946 -239.32007)
		(end 114.363754 -239.328706)
		(width 0.1143)
		(layer "In15.Cu")
		(net "GMI_CPU0_G1_CPU1_G3_TX_DN<2>")
	)
	(arc
		(start 355.865938 -224.234248)
		(mid 355.865925 -224.230311)
		(end 355.865938 -224.226374)
		(width 0.1143)
		(layer "In15.Cu")
		(net "GMI_CPU0_G1_CPU1_G3_TX_DN<2>")
	)
	(arc
		(start 356.815644 -243.568474)
		(mid 356.897077 -243.366076)
		(end 357.04907 -243.209572)
		(width 0.1143)
		(layer "In15.Cu")
		(net "GMI_CPU0_G1_CPU1_G3_TX_DN<2>")
	)
	(arc
		(start 357.139748 -236.674152)
		(mid 357.288462 -236.384084)
		(end 357.139748 -236.094016)
		(width 0.1143)
		(layer "In15.Cu")
		(net "GMI_CPU0_G1_CPU1_G3_TX_DN<2>")
	)
	(arc
		(start 114.446812 -223.769936)
		(mid 114.690139 -224.234502)
		(end 114.446812 -224.699068)
		(width 0.1143)
		(layer "In15.Cu")
		(net "GMI_CPU0_G1_CPU1_G3_TX_DN<2>")
	)
	(arc
		(start 357.099616 -228.600254)
		(mid 357.274566 -228.284278)
		(end 357.099616 -227.968302)
		(width 0.1143)
		(layer "In15.Cu")
		(net "GMI_CPU0_G1_CPU1_G3_TX_DN<2>")
	)
	(arc
		(start 114.446812 -243.209826)
		(mid 114.598799 -243.366334)
		(end 114.680238 -243.568728)
		(width 0.1143)
		(layer "In15.Cu")
		(net "GMI_CPU0_G1_CPU1_G3_TX_DN<2>")
	)
	(arc
		(start 357.04907 -231.178862)
		(mid 356.805746 -230.712746)
		(end 357.05161 -230.247952)
		(width 0.1143)
		(layer "In15.Cu")
		(net "GMI_CPU0_G1_CPU1_G3_TX_DN<2>")
	)
	(arc
		(start 114.485674 -230.279448)
		(mid 114.689626 -230.738935)
		(end 114.446812 -231.179116)
		(width 0.1143)
		(layer "In15.Cu")
		(net "GMI_CPU0_G1_CPU1_G3_TX_DN<2>")
	)
	(arc
		(start 356.3239 -221.898464)
		(mid 356.332855 -221.851726)
		(end 356.335838 -221.80423)
		(width 0.1143)
		(layer "In15.Cu")
		(net "GMI_CPU0_G1_CPU1_G3_TX_DN<2>")
	)
	(arc
		(start 114.407188 -237.682024)
		(mid 114.221668 -238.000081)
		(end 114.399822 -238.322358)
		(width 0.1143)
		(layer "In15.Cu")
		(net "GMI_CPU0_G1_CPU1_G3_TX_DN<2>")
	)
	(arc
		(start 357.04907 -234.418632)
		(mid 356.805743 -233.954066)
		(end 357.04907 -233.4895)
		(width 0.1143)
		(layer "In15.Cu")
		(net "GMI_CPU0_G1_CPU1_G3_TX_DN<2>")
	)
	(arc
		(start 114.375946 -227.98024)
		(mid 114.225561 -228.284532)
		(end 114.375946 -228.588824)
		(width 0.1143)
		(layer "In15.Cu")
		(net "GMI_CPU0_G1_CPU1_G3_TX_DN<2>")
	)
	(arc
		(start 114.369088 -226.365054)
		(mid 114.215598 -226.66452)
		(end 114.369088 -226.963986)
		(width 0.1143)
		(layer "In15.Cu")
		(net "GMI_CPU0_G1_CPU1_G3_TX_DN<2>")
	)
	(arc
		(start 356.145846 -224.720404)
		(mid 355.940901 -224.514742)
		(end 355.865938 -224.234248)
		(width 0.1143)
		(layer "In15.Cu")
		(net "GMI_CPU0_G1_CPU1_G3_TX_DN<2>")
	)
	(arc
		(start 357.139748 -243.1542)
		(mid 357.288462 -242.864132)
		(end 357.139748 -242.574064)
		(width 0.1143)
		(layer "In15.Cu")
		(net "GMI_CPU0_G1_CPU1_G3_TX_DN<2>")
	)
	(arc
		(start 114.336322 -229.633018)
		(mid 114.252496 -229.751322)
		(end 114.21999 -229.892606)
		(width 0.1143)
		(layer "In15.Cu")
		(net "GMI_CPU0_G1_CPU1_G3_TX_DN<2>")
	)
	(arc
		(start 357.27386 -229.908608)
		(mid 357.248879 -229.777698)
		(end 357.185976 -229.660196)
		(width 0.1143)
		(layer "In15.Cu")
		(net "GMI_CPU0_G1_CPU1_G3_TX_DN<2>")
	)
	(arc
		(start 357.04907 -239.278668)
		(mid 356.805743 -238.814102)
		(end 357.04907 -238.349536)
		(width 0.1143)
		(layer "In15.Cu")
		(net "GMI_CPU0_G1_CPU1_G3_TX_DN<2>")
	)
	(arc
		(start 114.370104 -224.74428)
		(mid 114.216207 -225.044508)
		(end 114.370104 -225.344736)
		(width 0.1143)
		(layer "In15.Cu")
		(net "GMI_CPU0_G1_CPU1_G3_TX_DN<2>")
	)
	(arc
		(start 357.119936 -238.308388)
		(mid 357.271525 -238.004096)
		(end 357.119936 -237.699804)
		(width 0.1143)
		(layer "In15.Cu")
		(net "GMI_CPU0_G1_CPU1_G3_TX_DN<2>")
	)
	(arc
		(start 357.04907 -232.79862)
		(mid 356.805743 -232.334054)
		(end 357.04907 -231.869488)
		(width 0.1143)
		(layer "In15.Cu")
		(net "GMI_CPU0_G1_CPU1_G3_TX_DN<2>")
	)
	(arc
		(start 356.57917 -225.50882)
		(mid 356.400357 -225.30647)
		(end 356.335838 -225.044254)
		(width 0.1143)
		(layer "In15.Cu")
		(net "GMI_CPU0_G1_CPU1_G3_TX_DN<2>")
	)
	(arc
		(start 114.446812 -241.589814)
		(mid 114.690139 -242.05438)
		(end 114.446812 -242.518946)
		(width 0.1143)
		(layer "In15.Cu")
		(net "GMI_CPU0_G1_CPU1_G3_TX_DN<2>")
	)
	(arc
		(start 114.40287 -240.924588)
		(mid 114.220021 -241.244265)
		(end 114.402616 -241.56416)
		(width 0.1143)
		(layer "In15.Cu")
		(net "GMI_CPU0_G1_CPU1_G3_TX_DN<2>")
	)
	(arc
		(start 114.363754 -239.328706)
		(mid 114.212195 -239.624362)
		(end 114.363754 -239.920018)
		(width 0.1143)
		(layer "In15.Cu")
		(net "GMI_CPU0_G1_CPU1_G3_TX_DN<2>")
	)
	(arc
		(start 114.680238 -243.568728)
		(mid 114.682261 -243.580138)
		(end 114.684048 -243.591588)
		(width 0.1143)
		(layer "In15.Cu")
		(net "GMI_CPU0_G1_CPU1_G3_TX_DN<2>")
	)
	(arc
		(start 114.3762 -239.9284)
		(mid 114.376961 -239.929036)
		(end 114.377724 -239.92967)
		(width 0.1143)
		(layer "In15.Cu")
		(net "GMI_CPU0_G1_CPU1_G3_TX_DN<2>")
	)
	(arc
		(start 357.119936 -231.82834)
		(mid 357.231733 -231.693539)
		(end 357.275892 -231.524048)
		(width 0.1143)
		(layer "In15.Cu")
		(net "GMI_CPU0_G1_CPU1_G3_TX_DN<2>")
	)
	(arc
		(start 114.44605 -243.209318)
		(mid 114.446431 -243.209572)
		(end 114.446812 -243.209826)
		(width 0.1143)
		(layer "In15.Cu")
		(net "GMI_CPU0_G1_CPU1_G3_TX_DN<2>")
	)
	(arc
		(start 114.446812 -235.109766)
		(mid 114.690139 -235.574332)
		(end 114.446812 -236.038898)
		(width 0.1143)
		(layer "In15.Cu")
		(net "GMI_CPU0_G1_CPU1_G3_TX_DN<2>")
	)
	(arc
		(start 357.04907 -236.038644)
		(mid 356.805743 -235.574078)
		(end 357.04907 -235.109512)
		(width 0.1143)
		(layer "In15.Cu")
		(net "GMI_CPU0_G1_CPU1_G3_TX_DN<2>")
	)
	(arc
		(start 357.04907 -237.658656)
		(mid 356.805743 -237.19409)
		(end 357.04907 -236.729524)
		(width 0.1143)
		(layer "In15.Cu")
		(net "GMI_CPU0_G1_CPU1_G3_TX_DN<2>")
	)
	(arc
		(start 114.44605 -241.589306)
		(mid 114.446431 -241.58956)
		(end 114.446812 -241.589814)
		(width 0.1143)
		(layer "In15.Cu")
		(net "GMI_CPU0_G1_CPU1_G3_TX_DN<2>")
	)
	(arc
		(start 356.180136 -223.728534)
		(mid 356.336063 -223.425054)
		(end 356.181406 -223.120966)
		(width 0.1143)
		(layer "In15.Cu")
		(net "GMI_CPU0_G1_CPU1_G3_TX_DN<2>")
	)
	(arc
		(start 357.04907 -227.938838)
		(mid 356.805743 -227.474272)
		(end 357.04907 -227.009706)
		(width 0.1143)
		(layer "In15.Cu")
		(net "GMI_CPU0_G1_CPU1_G3_TX_DN<2>")
	)
	(arc
		(start 114.446812 -225.389948)
		(mid 114.690139 -225.854514)
		(end 114.446812 -226.31908)
		(width 0.1143)
		(layer "In15.Cu")
		(net "GMI_CPU0_G1_CPU1_G3_TX_DN<2>")
	)
	(arc
		(start 114.375946 -236.080046)
		(mid 114.221798 -236.384338)
		(end 114.375946 -236.68863)
		(width 0.1143)
		(layer "In15.Cu")
		(net "GMI_CPU0_G1_CPU1_G3_TX_DN<2>")
	)
	(arc
		(start 357.119936 -239.9284)
		(mid 357.271525 -239.624108)
		(end 357.119936 -239.319816)
		(width 0.1143)
		(layer "In15.Cu")
		(net "GMI_CPU0_G1_CPU1_G3_TX_DN<2>")
	)
	(arc
		(start 357.275892 -231.524048)
		(mid 357.23513 -231.354164)
		(end 357.121714 -231.22128)
		(width 0.1143)
		(layer "In15.Cu")
		(net "GMI_CPU0_G1_CPU1_G3_TX_DN<2>")
	)
	(arc
		(start 114.407188 -242.54206)
		(mid 114.221668 -242.860117)
		(end 114.399822 -243.182394)
		(width 0.1143)
		(layer "In15.Cu")
		(net "GMI_CPU0_G1_CPU1_G3_TX_DN<2>")
	)
	(arc
		(start 114.446812 -233.489754)
		(mid 114.690139 -233.95432)
		(end 114.446812 -234.418886)
		(width 0.1143)
		(layer "In15.Cu")
		(net "GMI_CPU0_G1_CPU1_G3_TX_DN<2>")
	)
	(arc
		(start 357.185976 -229.660196)
		(mid 357.154387 -229.625868)
		(end 357.116634 -229.598474)
		(width 0.1143)
		(layer "In15.Cu")
		(net "GMI_CPU0_G1_CPU1_G3_TX_DN<2>")
	)
	(arc
		(start 357.137716 -241.535712)
		(mid 357.287138 -241.24412)
		(end 357.137716 -240.952528)
		(width 0.1143)
		(layer "In15.Cu")
		(net "GMI_CPU0_G1_CPU1_G3_TX_DN<2>")
	)
	(arc
		(start 356.096316 -223.069658)
		(mid 355.863985 -222.614236)
		(end 356.096316 -222.158814)
		(width 0.1143)
		(layer "In15.Cu")
		(net "GMI_CPU0_G1_CPU1_G3_TX_DN<2>")
	)
	(arc
		(start 356.179882 -222.108522)
		(mid 356.228814 -222.066434)
		(end 356.269798 -222.016574)
		(width 0.1143)
		(layer "In15.Cu")
		(net "GMI_CPU0_G1_CPU1_G3_TX_DN<2>")
	)
	(arc
		(start 357.089202 -226.986338)
		(mid 357.274654 -226.664376)
		(end 357.089456 -226.342194)
		(width 0.1143)
		(layer "In15.Cu")
		(net "GMI_CPU0_G1_CPU1_G3_TX_DN<2>")
	)
	(arc
		(start 356.811834 -243.591334)
		(mid 356.813622 -243.579885)
		(end 356.815644 -243.568474)
		(width 0.1143)
		(layer "In15.Cu")
		(net "GMI_CPU0_G1_CPU1_G3_TX_DN<2>")
	)
	(arc
		(start 114.21999 -229.892606)
		(mid 114.2202 -229.903946)
		(end 114.221514 -229.915212)
		(width 0.1143)
		(layer "In15.Cu")
		(net "GMI_CPU0_G1_CPU1_G3_TX_DN<2>")
	)
	(arc
		(start 114.44605 -238.349282)
		(mid 114.446431 -238.349536)
		(end 114.446812 -238.34979)
		(width 0.1143)
		(layer "In15.Cu")
		(net "GMI_CPU0_G1_CPU1_G3_TX_DN<2>")
	)
	(arc
		(start 356.269798 -222.016574)
		(mid 356.301995 -221.959877)
		(end 356.3239 -221.898464)
		(width 0.1143)
		(layer "In15.Cu")
		(net "GMI_CPU0_G1_CPU1_G3_TX_DN<2>")
	)
	(arc
		(start 357.04907 -242.518692)
		(mid 356.805743 -242.054126)
		(end 357.04907 -241.58956)
		(width 0.1143)
		(layer "In15.Cu")
		(net "GMI_CPU0_G1_CPU1_G3_TX_DN<2>")
	)
	(arc
		(start 114.446812 -222.149924)
		(mid 114.690139 -222.61449)
		(end 114.446812 -223.079056)
		(width 0.1143)
		(layer "In15.Cu")
		(net "GMI_CPU0_G1_CPU1_G3_TX_DN<2>")
	)
	(arc
		(start 355.865938 -224.226374)
		(mid 355.931284 -223.978151)
		(end 356.094538 -223.780096)
		(width 0.1143)
		(layer "In15.Cu")
		(net "GMI_CPU0_G1_CPU1_G3_TX_DN<2>")
	)
	(arc
		(start 357.049832 -226.319334)
		(mid 357.049451 -226.31908)
		(end 357.04907 -226.318826)
		(width 0.1143)
		(layer "In15.Cu")
		(net "GMI_CPU0_G1_CPU1_G3_TX_DN<2>")
	)
	(arc
		(start 357.116888 -230.210106)
		(mid 357.221414 -230.07292)
		(end 357.27386 -229.908608)
		(width 0.1143)
		(layer "In15.Cu")
		(net "GMI_CPU0_G1_CPU1_G3_TX_DN<2>")
	)
	(arc
		(start 114.446812 -227.00996)
		(mid 114.690139 -227.474526)
		(end 114.446812 -227.939092)
		(width 0.1143)
		(layer "In15.Cu")
		(net "GMI_CPU0_G1_CPU1_G3_TX_DN<2>")
	)
	(arc
		(start 356.805738 -225.85426)
		(mid 356.764189 -225.682838)
		(end 356.648766 -225.54946)
		(width 0.1143)
		(layer "In15.Cu")
		(net "GMI_CPU0_G1_CPU1_G3_TX_DN<2>")
	)
	(arc
		(start 114.357404 -234.473496)
		(mid 114.208389 -234.764326)
		(end 114.357404 -235.055156)
		(width 0.1143)
		(layer "In15.Cu")
		(net "GMI_CPU0_G1_CPU1_G3_TX_DN<2>")
	)
	(arc
		(start 114.446812 -238.34979)
		(mid 114.690139 -238.814356)
		(end 114.446812 -239.278922)
		(width 0.1143)
		(layer "In15.Cu")
		(net "GMI_CPU0_G1_CPU1_G3_TX_DN<2>")
	)
	(arc
		(start 114.21999 -221.804484)
		(mid 114.261245 -221.975455)
		(end 114.375946 -222.108776)
		(width 0.1143)
		(layer "In15.Cu")
		(net "GMI_CPU0_G1_CPU1_G3_TX_DN<2>")
	)
	(arc
		(start 114.446812 -228.629972)
		(mid 114.690139 -229.094538)
		(end 114.446812 -229.559104)
		(width 0.1143)
		(layer "In15.Cu")
		(net "GMI_CPU0_G1_CPU1_G3_TX_DN<2>")
	)
	(arc
		(start 357.049832 -227.939346)
		(mid 357.049451 -227.939092)
		(end 357.04907 -227.938838)
		(width 0.1143)
		(layer "In15.Cu")
		(net "GMI_CPU0_G1_CPU1_G3_TX_DN<2>")
	)
	(arc
		(start 114.446812 -239.969802)
		(mid 114.690139 -240.434368)
		(end 114.446812 -240.898934)
		(width 0.1143)
		(layer "In15.Cu")
		(net "GMI_CPU0_G1_CPU1_G3_TX_DN<2>")
	)
	(arc
		(start 114.446812 -236.729778)
		(mid 114.690139 -237.194344)
		(end 114.446812 -237.65891)
		(width 0.1143)
		(layer "In15.Cu")
		(net "GMI_CPU0_G1_CPU1_G3_TX_DN<2>")
	)
	(arc
		(start 357.119936 -233.448352)
		(mid 357.269033 -233.14406)
		(end 357.119936 -232.839768)
		(width 0.1143)
		(layer "In15.Cu")
		(net "GMI_CPU0_G1_CPU1_G3_TX_DN<2>")
	)
	(arc
		(start 114.446812 -231.869742)
		(mid 114.690139 -232.334308)
		(end 114.446812 -232.798874)
		(width 0.1143)
		(layer "In15.Cu")
		(net "GMI_CPU0_G1_CPU1_G3_TX_DN<2>")
	)
	(arc
		(start 114.422682 -230.23576)
		(mid 114.455112 -230.256256)
		(end 114.485674 -230.279448)
		(width 0.1143)
		(layer "In15.Cu")
		(net "GMI_CPU0_G1_CPU1_G3_TX_DN<2>")
	)
	(arc
		(start 356.335838 -225.042222)
		(mid 356.295047 -224.873137)
		(end 356.18166 -224.741232)
		(width 0.1143)
		(layer "In15.Cu")
		(net "GMI_CPU0_G1_CPU1_G3_TX_DN<2>")
	)
	(arc
		(start 114.374168 -231.221534)
		(mid 114.260761 -231.354423)
		(end 114.21999 -231.524302)
		(width 0.1143)
		(layer "In15.Cu")
		(net "GMI_CPU0_G1_CPU1_G3_TX_DN<2>")
	)
	(arc
		(start 114.375946 -223.120204)
		(mid 114.226849 -223.424496)
		(end 114.375946 -223.728788)
		(width 0.1143)
		(layer "In15.Cu")
		(net "GMI_CPU0_G1_CPU1_G3_TX_DN<2>")
	)
	(arc
		(start 357.04907 -226.318826)
		(mid 356.870257 -226.116476)
		(end 356.805738 -225.85426)
		(width 0.1143)
		(layer "In15.Cu")
		(net "GMI_CPU0_G1_CPU1_G3_TX_DN<2>")
	)
	(arc
		(start 357.04907 -240.89868)
		(mid 356.805743 -240.434114)
		(end 357.04907 -239.969548)
		(width 0.1143)
		(layer "In15.Cu")
		(net "GMI_CPU0_G1_CPU1_G3_TX_DN<2>")
	)
	(arc
		(start 357.119936 -235.068364)
		(mid 357.269033 -234.764072)
		(end 357.119936 -234.45978)
		(width 0.1143)
		(layer "In15.Cu")
		(net "GMI_CPU0_G1_CPU1_G3_TX_DN<2>")
	)
	(arc
		(start 114.21999 -231.53116)
		(mid 114.2597 -231.69593)
		(end 114.370104 -231.82453)
		(width 0.1143)
		(layer "In15.Cu")
		(net "GMI_CPU0_G1_CPU1_G3_TX_DN<2>")
	)
	(arc
		(start 357.04907 -229.55885)
		(mid 356.805743 -229.094284)
		(end 357.04907 -228.629718)
		(width 0.1143)
		(layer "In15.Cu")
		(net "GMI_CPU0_G1_CPU1_G3_TX_DN<2>")
	)
	(arc
		(start 114.369088 -232.844848)
		(mid 114.215598 -233.144314)
		(end 114.369088 -233.44378)
		(width 0.1143)
		(layer "In15.Cu")
		(net "GMI_CPU0_G1_CPU1_G3_TX_DN<2>")
	)
	(arc
		(start 114.221514 -229.915212)
		(mid 114.274709 -230.073635)
		(end 114.374676 -230.207566)
		(width 0.1143)
		(layer "In15.Cu")
		(net "GMI_CPU0_G1_CPU1_G3_TX_DN<2>")
	)
	(arc
		(start 114.392964 -229.590346)
		(mid 114.363427 -229.610067)
		(end 114.336322 -229.633018)
		(width 0.1143)
		(layer "In15.Cu")
		(net "GMI_CPU0_G1_CPU1_G3_TX_DN<2>")
	)
	(segment
		(start 356.89794 -247.1801)
		(end 356.431088 -246.914162)
		(width 0.12954)
		(layer "F.Cu")
		(net "GMI_CPU0_G1_CPU1_G3_TX_DN<1>")
	)
	(segment
		(start 114.597942 -247.180354)
		(end 115.064794 -246.914416)
		(width 0.12954)
		(layer "F.Cu")
		(net "GMI_CPU0_G1_CPU1_G3_TX_DN<1>")
	)
	(segment
		(start 358.063038 -239.322102)
		(end 358.061006 -239.320578)
		(width 0.1143)
		(layer "In15.Cu")
		(net "GMI_CPU0_G1_CPU1_G3_TX_DN<1>")
	)
	(segment
		(start 113.813336 -215.75395)
		(end 113.85931 -215.931242)
		(width 0.14224)
		(layer "In15.Cu")
		(net "GMI_CPU0_G1_CPU1_G3_TX_DN<1>")
	)
	(segment
		(start 358.05872 -227.979478)
		(end 358.02824 -227.961698)
		(width 0.1143)
		(layer "In15.Cu")
		(net "GMI_CPU0_G1_CPU1_G3_TX_DN<1>")
	)
	(segment
		(start 114.21999 -246.10441)
		(end 114.21999 -246.12727)
		(width 0.1143)
		(layer "In15.Cu")
		(net "GMI_CPU0_G1_CPU1_G3_TX_DN<1>")
	)
	(segment
		(start 113.506758 -244.138958)
		(end 113.44402 -244.175788)
		(width 0.1143)
		(layer "In15.Cu")
		(net "GMI_CPU0_G1_CPU1_G3_TX_DN<1>")
	)
	(segment
		(start 356.382574 -216.363804)
		(end 356.20325 -215.984582)
		(width 0.14224)
		(layer "In15.Cu")
		(net "GMI_CPU0_G1_CPU1_G3_TX_DN<1>")
	)
	(segment
		(start 358.02824 -231.201722)
		(end 357.989124 -231.178862)
		(width 0.1143)
		(layer "In15.Cu")
		(net "GMI_CPU0_G1_CPU1_G3_TX_DN<1>")
	)
	(segment
		(start 114.684048 -246.831612)
		(end 114.766852 -246.914416)
		(width 0.1143)
		(layer "In15.Cu")
		(net "GMI_CPU0_G1_CPU1_G3_TX_DN<1>")
	)
	(segment
		(start 358.061006 -238.307626)
		(end 358.063038 -238.306102)
		(width 0.1143)
		(layer "In15.Cu")
		(net "GMI_CPU0_G1_CPU1_G3_TX_DN<1>")
	)
	(segment
		(start 356.856284 -217.364818)
		(end 356.677214 -216.98585)
		(width 0.14224)
		(layer "In15.Cu")
		(net "GMI_CPU0_G1_CPU1_G3_TX_DN<1>")
	)
	(segment
		(start 357.085646 -224.72015)
		(end 357.08463 -224.719642)
		(width 0.1143)
		(layer "In15.Cu")
		(net "GMI_CPU0_G1_CPU1_G3_TX_DN<1>")
	)
	(segment
		(start 113.437162 -230.20909)
		(end 113.504218 -230.248206)
		(width 0.1143)
		(layer "In15.Cu")
		(net "GMI_CPU0_G1_CPU1_G3_TX_DN<1>")
	)
	(segment
		(start 357.08717 -222.127318)
		(end 357.088186 -222.12681)
		(width 0.1143)
		(layer "In15.Cu")
		(net "GMI_CPU0_G1_CPU1_G3_TX_DN<1>")
	)
	(segment
		(start 114.375946 -246.408702)
		(end 114.446812 -246.44985)
		(width 0.1143)
		(layer "In15.Cu")
		(net "GMI_CPU0_G1_CPU1_G3_TX_DN<1>")
	)
	(segment
		(start 357.589836 -244.989858)
		(end 357.589582 -244.989858)
		(width 0.1143)
		(layer "In15.Cu")
		(net "GMI_CPU0_G1_CPU1_G3_TX_DN<1>")
	)
	(segment
		(start 357.567738 -245.611142)
		(end 357.589836 -245.598442)
		(width 0.1143)
		(layer "In15.Cu")
		(net "GMI_CPU0_G1_CPU1_G3_TX_DN<1>")
	)
	(segment
		(start 357.086916 -223.103948)
		(end 357.086662 -223.103694)
		(width 0.1143)
		(layer "In15.Cu")
		(net "GMI_CPU0_G1_CPU1_G3_TX_DN<1>")
	)
	(segment
		(start 357.048054 -223.770444)
		(end 357.08844 -223.746822)
		(width 0.1143)
		(layer "In15.Cu")
		(net "GMI_CPU0_G1_CPU1_G3_TX_DN<1>")
	)
	(segment
		(start 357.989124 -238.349536)
		(end 358.061006 -238.307626)
		(width 0.1143)
		(layer "In15.Cu")
		(net "GMI_CPU0_G1_CPU1_G3_TX_DN<1>")
	)
	(segment
		(start 113.459768 -233.462068)
		(end 113.505234 -233.488738)
		(width 0.1143)
		(layer "In15.Cu")
		(net "GMI_CPU0_G1_CPU1_G3_TX_DN<1>")
	)
	(segment
		(start 358.061006 -232.84053)
		(end 358.02824 -232.82148)
		(width 0.1143)
		(layer "In15.Cu")
		(net "GMI_CPU0_G1_CPU1_G3_TX_DN<1>")
	)
	(segment
		(start 358.02824 -227.961698)
		(end 357.989124 -227.938838)
		(width 0.1143)
		(layer "In15.Cu")
		(net "GMI_CPU0_G1_CPU1_G3_TX_DN<1>")
	)
	(segment
		(start 357.276146 -221.804484)
		(end 357.276146 -221.387924)
		(width 0.1143)
		(layer "In15.Cu")
		(net "GMI_CPU0_G1_CPU1_G3_TX_DN<1>")
	)
	(segment
		(start 357.989124 -241.58956)
		(end 358.068118 -241.543586)
		(width 0.1143)
		(layer "In15.Cu")
		(net "GMI_CPU0_G1_CPU1_G3_TX_DN<1>")
	)
	(segment
		(start 358.02824 -234.441492)
		(end 357.989124 -234.418632)
		(width 0.1143)
		(layer "In15.Cu")
		(net "GMI_CPU0_G1_CPU1_G3_TX_DN<1>")
	)
	(segment
		(start 113.506758 -232.798874)
		(end 113.468658 -232.821226)
		(width 0.1143)
		(layer "In15.Cu")
		(net "GMI_CPU0_G1_CPU1_G3_TX_DN<1>")
	)
	(segment
		(start 357.500428 -244.03304)
		(end 357.517954 -244.020086)
		(width 0.1143)
		(layer "In15.Cu")
		(net "GMI_CPU0_G1_CPU1_G3_TX_DN<1>")
	)
	(segment
		(start 113.437162 -225.349308)
		(end 113.467642 -225.367088)
		(width 0.1143)
		(layer "In15.Cu")
		(net "GMI_CPU0_G1_CPU1_G3_TX_DN<1>")
	)
	(segment
		(start 358.215438 -229.911656)
		(end 358.21493 -229.90175)
		(width 0.1143)
		(layer "In15.Cu")
		(net "GMI_CPU0_G1_CPU1_G3_TX_DN<1>")
	)
	(segment
		(start 358.061006 -236.687614)
		(end 358.063038 -236.68609)
		(width 0.1143)
		(layer "In15.Cu")
		(net "GMI_CPU0_G1_CPU1_G3_TX_DN<1>")
	)
	(segment
		(start 357.275892 -221.128844)
		(end 357.230172 -221.083124)
		(width 0.1143)
		(layer "In15.Cu")
		(net "GMI_CPU0_G1_CPU1_G3_TX_DN<1>")
	)
	(segment
		(start 113.467642 -224.721928)
		(end 113.437162 -224.739708)
		(width 0.1143)
		(layer "In15.Cu")
		(net "GMI_CPU0_G1_CPU1_G3_TX_DN<1>")
	)
	(segment
		(start 357.589582 -244.989858)
		(end 357.517954 -244.948202)
		(width 0.1143)
		(layer "In15.Cu")
		(net "GMI_CPU0_G1_CPU1_G3_TX_DN<1>")
	)
	(segment
		(start 113.21161 -221.066106)
		(end 113.21161 -221.198948)
		(width 0.1143)
		(layer "In15.Cu")
		(net "GMI_CPU0_G1_CPU1_G3_TX_DN<1>")
	)
	(segment
		(start 114.357404 -246.39524)
		(end 114.375946 -246.408702)
		(width 0.1143)
		(layer "In15.Cu")
		(net "GMI_CPU0_G1_CPU1_G3_TX_DN<1>")
	)
	(segment
		(start 311.250584 -176.981104)
		(end 308.570376 -176.022762)
		(width 0.14224)
		(layer "In15.Cu")
		(net "GMI_CPU0_G1_CPU1_G3_TX_DN<1>")
	)
	(segment
		(start 113.506758 -223.079056)
		(end 113.467642 -223.101916)
		(width 0.1143)
		(layer "In15.Cu")
		(net "GMI_CPU0_G1_CPU1_G3_TX_DN<1>")
	)
	(segment
		(start 113.469674 -216.338912)
		(end 113.25733 -216.700354)
		(width 0.14224)
		(layer "In15.Cu")
		(net "GMI_CPU0_G1_CPU1_G3_TX_DN<1>")
	)
	(segment
		(start 113.506758 -240.898934)
		(end 113.44402 -240.93551)
		(width 0.1143)
		(layer "In15.Cu")
		(net "GMI_CPU0_G1_CPU1_G3_TX_DN<1>")
	)
	(segment
		(start 356.741222 -216.806526)
		(end 356.562152 -216.427812)
		(width 0.14224)
		(layer "In15.Cu")
		(net "GMI_CPU0_G1_CPU1_G3_TX_DN<1>")
	)
	(segment
		(start 357.088694 -223.104964)
		(end 357.086916 -223.103948)
		(width 0.1143)
		(layer "In15.Cu")
		(net "GMI_CPU0_G1_CPU1_G3_TX_DN<1>")
	)
	(segment
		(start 356.677214 -216.98585)
		(end 356.741222 -216.806526)
		(width 0.14224)
		(layer "In15.Cu")
		(net "GMI_CPU0_G1_CPU1_G3_TX_DN<1>")
	)
	(segment
		(start 358.061006 -234.460542)
		(end 358.02824 -234.441492)
		(width 0.1143)
		(layer "In15.Cu")
		(net "GMI_CPU0_G1_CPU1_G3_TX_DN<1>")
	)
	(segment
		(start 113.467642 -226.34194)
		(end 113.437162 -226.35972)
		(width 0.1143)
		(layer "In15.Cu")
		(net "GMI_CPU0_G1_CPU1_G3_TX_DN<1>")
	)
	(segment
		(start 113.85931 -215.931242)
		(end 113.646966 -216.292684)
		(width 0.14224)
		(layer "In15.Cu")
		(net "GMI_CPU0_G1_CPU1_G3_TX_DN<1>")
	)
	(segment
		(start 114.025426 -215.392762)
		(end 113.813336 -215.75395)
		(width 0.14224)
		(layer "In15.Cu")
		(net "GMI_CPU0_G1_CPU1_G3_TX_DN<1>")
	)
	(segment
		(start 355.614478 -214.42553)
		(end 355.4349 -214.361522)
		(width 0.14224)
		(layer "In15.Cu")
		(net "GMI_CPU0_G1_CPU1_G3_TX_DN<1>")
	)
	(segment
		(start 113.467642 -223.747076)
		(end 113.506758 -223.769936)
		(width 0.1143)
		(layer "In15.Cu")
		(net "GMI_CPU0_G1_CPU1_G3_TX_DN<1>")
	)
	(segment
		(start 358.063038 -232.842054)
		(end 358.061006 -232.84053)
		(width 0.1143)
		(layer "In15.Cu")
		(net "GMI_CPU0_G1_CPU1_G3_TX_DN<1>")
	)
	(segment
		(start 357.56215 -245.614444)
		(end 357.562912 -245.613936)
		(width 0.1143)
		(layer "In15.Cu")
		(net "GMI_CPU0_G1_CPU1_G3_TX_DN<1>")
	)
	(segment
		(start 357.989124 -239.969548)
		(end 358.061006 -239.927638)
		(width 0.1143)
		(layer "In15.Cu")
		(net "GMI_CPU0_G1_CPU1_G3_TX_DN<1>")
	)
	(segment
		(start 357.088948 -224.722182)
		(end 357.088186 -224.721674)
		(width 0.1143)
		(layer "In15.Cu")
		(net "GMI_CPU0_G1_CPU1_G3_TX_DN<1>")
	)
	(segment
		(start 113.467642 -243.186966)
		(end 113.506758 -243.209826)
		(width 0.1143)
		(layer "In15.Cu")
		(net "GMI_CPU0_G1_CPU1_G3_TX_DN<1>")
	)
	(segment
		(start 116.614956 -210.984338)
		(end 114.92484 -213.86165)
		(width 0.14224)
		(layer "In15.Cu")
		(net "GMI_CPU0_G1_CPU1_G3_TX_DN<1>")
	)
	(segment
		(start 113.467642 -227.961952)
		(end 113.437162 -227.979732)
		(width 0.1143)
		(layer "In15.Cu")
		(net "GMI_CPU0_G1_CPU1_G3_TX_DN<1>")
	)
	(segment
		(start 358.063038 -236.082078)
		(end 358.061006 -236.080554)
		(width 0.1143)
		(layer "In15.Cu")
		(net "GMI_CPU0_G1_CPU1_G3_TX_DN<1>")
	)
	(segment
		(start 113.437162 -238.30915)
		(end 113.467642 -238.32693)
		(width 0.1143)
		(layer "In15.Cu")
		(net "GMI_CPU0_G1_CPU1_G3_TX_DN<1>")
	)
	(segment
		(start 357.090218 -224.722944)
		(end 357.088948 -224.722182)
		(width 0.1143)
		(layer "In15.Cu")
		(net "GMI_CPU0_G1_CPU1_G3_TX_DN<1>")
	)
	(segment
		(start 357.564182 -245.613174)
		(end 357.56596 -245.612158)
		(width 0.1143)
		(layer "In15.Cu")
		(net "GMI_CPU0_G1_CPU1_G3_TX_DN<1>")
	)
	(segment
		(start 358.061006 -239.320578)
		(end 358.02824 -239.301528)
		(width 0.1143)
		(layer "In15.Cu")
		(net "GMI_CPU0_G1_CPU1_G3_TX_DN<1>")
	)
	(segment
		(start 357.04907 -222.14967)
		(end 357.08717 -222.127318)
		(width 0.1143)
		(layer "In15.Cu")
		(net "GMI_CPU0_G1_CPU1_G3_TX_DN<1>")
	)
	(segment
		(start 358.02824 -226.986846)
		(end 358.05872 -226.969066)
		(width 0.1143)
		(layer "In15.Cu")
		(net "GMI_CPU0_G1_CPU1_G3_TX_DN<1>")
	)
	(segment
		(start 354.781866 -212.981032)
		(end 354.846128 -212.801708)
		(width 0.14224)
		(layer "In15.Cu")
		(net "GMI_CPU0_G1_CPU1_G3_TX_DN<1>")
	)
	(segment
		(start 114.202972 -215.346534)
		(end 114.025426 -215.392762)
		(width 0.14224)
		(layer "In15.Cu")
		(net "GMI_CPU0_G1_CPU1_G3_TX_DN<1>")
	)
	(segment
		(start 302.916336 -176.022762)
		(end 165.049454 -175.21682)
		(width 0.14224)
		(layer "In15.Cu")
		(net "GMI_CPU0_G1_CPU1_G3_TX_DN<1>")
	)
	(segment
		(start 114.971068 -214.038942)
		(end 114.758724 -214.400384)
		(width 0.14224)
		(layer "In15.Cu")
		(net "GMI_CPU0_G1_CPU1_G3_TX_DN<1>")
	)
	(segment
		(start 113.468658 -234.441238)
		(end 113.467896 -234.441746)
		(width 0.1143)
		(layer "In15.Cu")
		(net "GMI_CPU0_G1_CPU1_G3_TX_DN<1>")
	)
	(segment
		(start 113.25733 -221.020386)
		(end 113.21161 -221.066106)
		(width 0.1143)
		(layer "In15.Cu")
		(net "GMI_CPU0_G1_CPU1_G3_TX_DN<1>")
	)
	(segment
		(start 113.467642 -222.127064)
		(end 113.506758 -222.149924)
		(width 0.1143)
		(layer "In15.Cu")
		(net "GMI_CPU0_G1_CPU1_G3_TX_DN<1>")
	)
	(segment
		(start 113.467642 -228.607112)
		(end 113.506758 -228.629972)
		(width 0.1143)
		(layer "In15.Cu")
		(net "GMI_CPU0_G1_CPU1_G3_TX_DN<1>")
	)
	(segment
		(start 358.063038 -237.70209)
		(end 358.061006 -237.700566)
		(width 0.1143)
		(layer "In15.Cu")
		(net "GMI_CPU0_G1_CPU1_G3_TX_DN<1>")
	)
	(segment
		(start 308.570376 -176.022762)
		(end 302.916336 -176.022762)
		(width 0.14224)
		(layer "In15.Cu")
		(net "GMI_CPU0_G1_CPU1_G3_TX_DN<1>")
	)
	(segment
		(start 358.05872 -226.359466)
		(end 358.02824 -226.341686)
		(width 0.1143)
		(layer "In15.Cu")
		(net "GMI_CPU0_G1_CPU1_G3_TX_DN<1>")
	)
	(segment
		(start 358.061006 -242.560602)
		(end 357.989124 -242.518692)
		(width 0.1143)
		(layer "In15.Cu")
		(net "GMI_CPU0_G1_CPU1_G3_TX_DN<1>")
	)
	(segment
		(start 113.46942 -216.338912)
		(end 113.469674 -216.338912)
		(width 0.14224)
		(layer "In15.Cu")
		(net "GMI_CPU0_G1_CPU1_G3_TX_DN<1>")
	)
	(segment
		(start 113.467642 -231.846882)
		(end 113.506758 -231.869742)
		(width 0.1143)
		(layer "In15.Cu")
		(net "GMI_CPU0_G1_CPU1_G3_TX_DN<1>")
	)
	(segment
		(start 358.215692 -242.867434)
		(end 358.215692 -242.864132)
		(width 0.1143)
		(layer "In15.Cu")
		(net "GMI_CPU0_G1_CPU1_G3_TX_DN<1>")
	)
	(segment
		(start 113.21161 -221.198948)
		(end 113.28019 -221.267528)
		(width 0.1143)
		(layer "In15.Cu")
		(net "GMI_CPU0_G1_CPU1_G3_TX_DN<1>")
	)
	(segment
		(start 358.02824 -236.061504)
		(end 357.989124 -236.038644)
		(width 0.1143)
		(layer "In15.Cu")
		(net "GMI_CPU0_G1_CPU1_G3_TX_DN<1>")
	)
	(segment
		(start 357.088186 -222.12681)
		(end 357.088948 -222.126302)
		(width 0.1143)
		(layer "In15.Cu")
		(net "GMI_CPU0_G1_CPU1_G3_TX_DN<1>")
	)
	(segment
		(start 357.276146 -221.387924)
		(end 357.275892 -221.38767)
		(width 0.1143)
		(layer "In15.Cu")
		(net "GMI_CPU0_G1_CPU1_G3_TX_DN<1>")
	)
	(segment
		(start 113.506758 -242.518946)
		(end 113.44402 -242.555522)
		(width 0.1143)
		(layer "In15.Cu")
		(net "GMI_CPU0_G1_CPU1_G3_TX_DN<1>")
	)
	(segment
		(start 114.766852 -246.914416)
		(end 115.064794 -246.914416)
		(width 0.1143)
		(layer "In15.Cu")
		(net "GMI_CPU0_G1_CPU1_G3_TX_DN<1>")
	)
	(segment
		(start 113.28019 -221.267528)
		(end 113.28019 -221.804484)
		(width 0.1143)
		(layer "In15.Cu")
		(net "GMI_CPU0_G1_CPU1_G3_TX_DN<1>")
	)
	(segment
		(start 113.506758 -227.939092)
		(end 113.467642 -227.961952)
		(width 0.1143)
		(layer "In15.Cu")
		(net "GMI_CPU0_G1_CPU1_G3_TX_DN<1>")
	)
	(segment
		(start 358.21493 -229.90175)
		(end 358.215184 -229.90175)
		(width 0.1143)
		(layer "In15.Cu")
		(net "GMI_CPU0_G1_CPU1_G3_TX_DN<1>")
	)
	(segment
		(start 357.275892 -221.38767)
		(end 357.275892 -221.128844)
		(width 0.1143)
		(layer "In15.Cu")
		(net "GMI_CPU0_G1_CPU1_G3_TX_DN<1>")
	)
	(segment
		(start 357.08209 -224.718118)
		(end 357.080566 -224.717102)
		(width 0.1143)
		(layer "In15.Cu")
		(net "GMI_CPU0_G1_CPU1_G3_TX_DN<1>")
	)
	(segment
		(start 357.989124 -233.4895)
		(end 358.061006 -233.44759)
		(width 0.1143)
		(layer "In15.Cu")
		(net "GMI_CPU0_G1_CPU1_G3_TX_DN<1>")
	)
	(segment
		(start 358.055418 -229.597458)
		(end 357.989124 -229.55885)
		(width 0.1143)
		(layer "In15.Cu")
		(net "GMI_CPU0_G1_CPU1_G3_TX_DN<1>")
	)
	(segment
		(start 357.230172 -221.083124)
		(end 357.230172 -217.839544)
		(width 0.14224)
		(layer "In15.Cu")
		(net "GMI_CPU0_G1_CPU1_G3_TX_DN<1>")
	)
	(segment
		(start 357.557578 -245.616984)
		(end 357.558086 -245.61673)
		(width 0.1143)
		(layer "In15.Cu")
		(net "GMI_CPU0_G1_CPU1_G3_TX_DN<1>")
	)
	(segment
		(start 357.989124 -235.109512)
		(end 358.061006 -235.067602)
		(width 0.1143)
		(layer "In15.Cu")
		(net "GMI_CPU0_G1_CPU1_G3_TX_DN<1>")
	)
	(segment
		(start 358.068118 -240.944654)
		(end 357.989124 -240.89868)
		(width 0.1143)
		(layer "In15.Cu")
		(net "GMI_CPU0_G1_CPU1_G3_TX_DN<1>")
	)
	(segment
		(start 354.846128 -212.801708)
		(end 353.46259 -209.878168)
		(width 0.14224)
		(layer "In15.Cu")
		(net "GMI_CPU0_G1_CPU1_G3_TX_DN<1>")
	)
	(segment
		(start 357.559864 -245.615714)
		(end 357.560626 -245.615206)
		(width 0.1143)
		(layer "In15.Cu")
		(net "GMI_CPU0_G1_CPU1_G3_TX_DN<1>")
	)
	(segment
		(start 357.119936 -224.739962)
		(end 357.090218 -224.722944)
		(width 0.1143)
		(layer "In15.Cu")
		(net "GMI_CPU0_G1_CPU1_G3_TX_DN<1>")
	)
	(segment
		(start 114.415316 -214.985092)
		(end 114.202972 -215.346534)
		(width 0.14224)
		(layer "In15.Cu")
		(net "GMI_CPU0_G1_CPU1_G3_TX_DN<1>")
	)
	(segment
		(start 357.989124 -227.009706)
		(end 358.02824 -226.986846)
		(width 0.1143)
		(layer "In15.Cu")
		(net "GMI_CPU0_G1_CPU1_G3_TX_DN<1>")
	)
	(segment
		(start 356.20325 -215.984582)
		(end 356.267512 -215.805258)
		(width 0.14224)
		(layer "In15.Cu")
		(net "GMI_CPU0_G1_CPU1_G3_TX_DN<1>")
	)
	(segment
		(start 113.459768 -235.08208)
		(end 113.505234 -235.10875)
		(width 0.1143)
		(layer "In15.Cu")
		(net "GMI_CPU0_G1_CPU1_G3_TX_DN<1>")
	)
	(segment
		(start 113.25733 -220.991938)
		(end 113.25733 -221.020386)
		(width 0.1143)
		(layer "In15.Cu")
		(net "GMI_CPU0_G1_CPU1_G3_TX_DN<1>")
	)
	(segment
		(start 357.230172 -217.839544)
		(end 357.035862 -217.428826)
		(width 0.14224)
		(layer "In15.Cu")
		(net "GMI_CPU0_G1_CPU1_G3_TX_DN<1>")
	)
	(segment
		(start 113.506758 -224.699068)
		(end 113.467642 -224.721928)
		(width 0.1143)
		(layer "In15.Cu")
		(net "GMI_CPU0_G1_CPU1_G3_TX_DN<1>")
	)
	(segment
		(start 357.088186 -224.721674)
		(end 357.08717 -224.721166)
		(width 0.1143)
		(layer "In15.Cu")
		(net "GMI_CPU0_G1_CPU1_G3_TX_DN<1>")
	)
	(segment
		(start 357.08844 -223.746822)
		(end 357.12019 -223.728534)
		(width 0.1143)
		(layer "In15.Cu")
		(net "GMI_CPU0_G1_CPU1_G3_TX_DN<1>")
	)
	(segment
		(start 113.468658 -239.301274)
		(end 113.467896 -239.301782)
		(width 0.1143)
		(layer "In15.Cu")
		(net "GMI_CPU0_G1_CPU1_G3_TX_DN<1>")
	)
	(segment
		(start 113.437162 -228.589332)
		(end 113.467642 -228.607112)
		(width 0.1143)
		(layer "In15.Cu")
		(net "GMI_CPU0_G1_CPU1_G3_TX_DN<1>")
	)
	(segment
		(start 113.506758 -239.278922)
		(end 113.468658 -239.301274)
		(width 0.1143)
		(layer "In15.Cu")
		(net "GMI_CPU0_G1_CPU1_G3_TX_DN<1>")
	)
	(segment
		(start 355.793548 -214.804244)
		(end 355.614478 -214.42553)
		(width 0.14224)
		(layer "In15.Cu")
		(net "GMI_CPU0_G1_CPU1_G3_TX_DN<1>")
	)
	(segment
		(start 357.275892 -221.80423)
		(end 357.276146 -221.804484)
		(width 0.1143)
		(layer "In15.Cu")
		(net "GMI_CPU0_G1_CPU1_G3_TX_DN<1>")
	)
	(segment
		(start 113.467642 -241.566954)
		(end 113.506758 -241.589814)
		(width 0.1143)
		(layer "In15.Cu")
		(net "GMI_CPU0_G1_CPU1_G3_TX_DN<1>")
	)
	(segment
		(start 354.96119 -213.360254)
		(end 354.781866 -212.981032)
		(width 0.14224)
		(layer "In15.Cu")
		(net "GMI_CPU0_G1_CPU1_G3_TX_DN<1>")
	)
	(segment
		(start 357.517954 -244.948202)
		(end 357.500428 -244.935248)
		(width 0.1143)
		(layer "In15.Cu")
		(net "GMI_CPU0_G1_CPU1_G3_TX_DN<1>")
	)
	(segment
		(start 357.558086 -245.61673)
		(end 357.558848 -245.616222)
		(width 0.1143)
		(layer "In15.Cu")
		(net "GMI_CPU0_G1_CPU1_G3_TX_DN<1>")
	)
	(segment
		(start 113.467642 -229.581964)
		(end 113.43513 -229.60076)
		(width 0.1143)
		(layer "In15.Cu")
		(net "GMI_CPU0_G1_CPU1_G3_TX_DN<1>")
	)
	(segment
		(start 358.02824 -231.846628)
		(end 358.05872 -231.828848)
		(width 0.1143)
		(layer "In15.Cu")
		(net "GMI_CPU0_G1_CPU1_G3_TX_DN<1>")
	)
	(segment
		(start 358.02824 -232.82148)
		(end 357.989124 -232.79862)
		(width 0.1143)
		(layer "In15.Cu")
		(net "GMI_CPU0_G1_CPU1_G3_TX_DN<1>")
	)
	(segment
		(start 357.08463 -224.719642)
		(end 357.08209 -224.718118)
		(width 0.1143)
		(layer "In15.Cu")
		(net "GMI_CPU0_G1_CPU1_G3_TX_DN<1>")
	)
	(segment
		(start 357.088948 -222.126302)
		(end 357.090218 -222.12554)
		(width 0.1143)
		(layer "In15.Cu")
		(net "GMI_CPU0_G1_CPU1_G3_TX_DN<1>")
	)
	(segment
		(start 113.459768 -239.942116)
		(end 113.505234 -239.968786)
		(width 0.1143)
		(layer "In15.Cu")
		(net "GMI_CPU0_G1_CPU1_G3_TX_DN<1>")
	)
	(segment
		(start 358.215692 -242.864132)
		(end 358.215946 -242.864132)
		(width 0.1143)
		(layer "In15.Cu")
		(net "GMI_CPU0_G1_CPU1_G3_TX_DN<1>")
	)
	(segment
		(start 113.506758 -226.31908)
		(end 113.467642 -226.34194)
		(width 0.1143)
		(layer "In15.Cu")
		(net "GMI_CPU0_G1_CPU1_G3_TX_DN<1>")
	)
	(segment
		(start 357.58882 -225.54946)
		(end 357.55834 -225.53168)
		(width 0.1143)
		(layer "In15.Cu")
		(net "GMI_CPU0_G1_CPU1_G3_TX_DN<1>")
	)
	(segment
		(start 355.319838 -213.802976)
		(end 355.140768 -213.424262)
		(width 0.14224)
		(layer "In15.Cu")
		(net "GMI_CPU0_G1_CPU1_G3_TX_DN<1>")
	)
	(segment
		(start 358.02824 -228.606858)
		(end 358.05872 -228.589078)
		(width 0.1143)
		(layer "In15.Cu")
		(net "GMI_CPU0_G1_CPU1_G3_TX_DN<1>")
	)
	(segment
		(start 114.369088 -214.8078)
		(end 114.415316 -214.985092)
		(width 0.14224)
		(layer "In15.Cu")
		(net "GMI_CPU0_G1_CPU1_G3_TX_DN<1>")
	)
	(segment
		(start 113.467642 -238.32693)
		(end 113.506758 -238.34979)
		(width 0.1143)
		(layer "In15.Cu")
		(net "GMI_CPU0_G1_CPU1_G3_TX_DN<1>")
	)
	(segment
		(start 113.506758 -236.038898)
		(end 113.44402 -236.075728)
		(width 0.1143)
		(layer "In15.Cu")
		(net "GMI_CPU0_G1_CPU1_G3_TX_DN<1>")
	)
	(segment
		(start 113.467642 -225.367088)
		(end 113.506758 -225.389948)
		(width 0.1143)
		(layer "In15.Cu")
		(net "GMI_CPU0_G1_CPU1_G3_TX_DN<1>")
	)
	(segment
		(start 356.72903 -246.914162)
		(end 356.811834 -246.831358)
		(width 0.1143)
		(layer "In15.Cu")
		(net "GMI_CPU0_G1_CPU1_G3_TX_DN<1>")
	)
	(segment
		(start 113.467642 -226.9871)
		(end 113.506758 -227.00996)
		(width 0.1143)
		(layer "In15.Cu")
		(net "GMI_CPU0_G1_CPU1_G3_TX_DN<1>")
	)
	(segment
		(start 358.05872 -243.168932)
		(end 358.061514 -243.1669)
		(width 0.1143)
		(layer "In15.Cu")
		(net "GMI_CPU0_G1_CPU1_G3_TX_DN<1>")
	)
	(segment
		(start 358.063038 -234.462066)
		(end 358.061006 -234.460542)
		(width 0.1143)
		(layer "In15.Cu")
		(net "GMI_CPU0_G1_CPU1_G3_TX_DN<1>")
	)
	(segment
		(start 357.08717 -224.721166)
		(end 357.085646 -224.72015)
		(width 0.1143)
		(layer "In15.Cu")
		(net "GMI_CPU0_G1_CPU1_G3_TX_DN<1>")
	)
	(segment
		(start 357.562912 -245.613936)
		(end 357.564182 -245.613174)
		(width 0.1143)
		(layer "In15.Cu")
		(net "GMI_CPU0_G1_CPU1_G3_TX_DN<1>")
	)
	(segment
		(start 113.467642 -223.101916)
		(end 113.437162 -223.119696)
		(width 0.1143)
		(layer "In15.Cu")
		(net "GMI_CPU0_G1_CPU1_G3_TX_DN<1>")
	)
	(segment
		(start 113.506758 -231.179116)
		(end 113.467642 -231.201976)
		(width 0.1143)
		(layer "In15.Cu")
		(net "GMI_CPU0_G1_CPU1_G3_TX_DN<1>")
	)
	(segment
		(start 113.468658 -232.821226)
		(end 113.467896 -232.821734)
		(width 0.1143)
		(layer "In15.Cu")
		(net "GMI_CPU0_G1_CPU1_G3_TX_DN<1>")
	)
	(segment
		(start 357.04907 -246.449596)
		(end 357.091742 -246.424704)
		(width 0.1143)
		(layer "In15.Cu")
		(net "GMI_CPU0_G1_CPU1_G3_TX_DN<1>")
	)
	(segment
		(start 357.080566 -224.717102)
		(end 357.04907 -224.698814)
		(width 0.1143)
		(layer "In15.Cu")
		(net "GMI_CPU0_G1_CPU1_G3_TX_DN<1>")
	)
	(segment
		(start 357.56596 -245.612158)
		(end 357.566976 -245.61165)
		(width 0.1143)
		(layer "In15.Cu")
		(net "GMI_CPU0_G1_CPU1_G3_TX_DN<1>")
	)
	(segment
		(start 357.517954 -244.020086)
		(end 357.589836 -243.97843)
		(width 0.1143)
		(layer "In15.Cu")
		(net "GMI_CPU0_G1_CPU1_G3_TX_DN<1>")
	)
	(segment
		(start 357.090218 -222.12554)
		(end 357.119936 -222.108522)
		(width 0.1143)
		(layer "In15.Cu")
		(net "GMI_CPU0_G1_CPU1_G3_TX_DN<1>")
	)
	(segment
		(start 358.061006 -233.44759)
		(end 358.063038 -233.446066)
		(width 0.1143)
		(layer "In15.Cu")
		(net "GMI_CPU0_G1_CPU1_G3_TX_DN<1>")
	)
	(segment
		(start 114.581178 -214.446612)
		(end 114.369088 -214.8078)
		(width 0.14224)
		(layer "In15.Cu")
		(net "GMI_CPU0_G1_CPU1_G3_TX_DN<1>")
	)
	(segment
		(start 156.513276 -178.269138)
		(end 116.614956 -210.984338)
		(width 0.14224)
		(layer "In15.Cu")
		(net "GMI_CPU0_G1_CPU1_G3_TX_DN<1>")
	)
	(segment
		(start 113.25733 -216.700354)
		(end 113.25733 -220.991938)
		(width 0.14224)
		(layer "In15.Cu")
		(net "GMI_CPU0_G1_CPU1_G3_TX_DN<1>")
	)
	(segment
		(start 356.267512 -215.805258)
		(end 356.088442 -215.426544)
		(width 0.14224)
		(layer "In15.Cu")
		(net "GMI_CPU0_G1_CPU1_G3_TX_DN<1>")
	)
	(segment
		(start 113.646966 -216.292684)
		(end 113.46942 -216.338912)
		(width 0.14224)
		(layer "In15.Cu")
		(net "GMI_CPU0_G1_CPU1_G3_TX_DN<1>")
	)
	(segment
		(start 113.467642 -236.706918)
		(end 113.506758 -236.729778)
		(width 0.1143)
		(layer "In15.Cu")
		(net "GMI_CPU0_G1_CPU1_G3_TX_DN<1>")
	)
	(segment
		(start 113.437162 -244.789198)
		(end 113.467642 -244.806978)
		(width 0.1143)
		(layer "In15.Cu")
		(net "GMI_CPU0_G1_CPU1_G3_TX_DN<1>")
	)
	(segment
		(start 358.02824 -226.341686)
		(end 357.989124 -226.318826)
		(width 0.1143)
		(layer "In15.Cu")
		(net "GMI_CPU0_G1_CPU1_G3_TX_DN<1>")
	)
	(segment
		(start 113.437162 -243.169186)
		(end 113.467642 -243.186966)
		(width 0.1143)
		(layer "In15.Cu")
		(net "GMI_CPU0_G1_CPU1_G3_TX_DN<1>")
	)
	(segment
		(start 114.92484 -213.86165)
		(end 114.971068 -214.038942)
		(width 0.14224)
		(layer "In15.Cu")
		(net "GMI_CPU0_G1_CPU1_G3_TX_DN<1>")
	)
	(segment
		(start 355.4349 -214.361522)
		(end 355.255576 -213.9823)
		(width 0.14224)
		(layer "In15.Cu")
		(net "GMI_CPU0_G1_CPU1_G3_TX_DN<1>")
	)
	(segment
		(start 113.937034 -245.616476)
		(end 113.937796 -245.616984)
		(width 0.1143)
		(layer "In15.Cu")
		(net "GMI_CPU0_G1_CPU1_G3_TX_DN<1>")
	)
	(segment
		(start 355.255576 -213.9823)
		(end 355.319838 -213.802976)
		(width 0.14224)
		(layer "In15.Cu")
		(net "GMI_CPU0_G1_CPU1_G3_TX_DN<1>")
	)
	(segment
		(start 357.558848 -245.616222)
		(end 357.559864 -245.615714)
		(width 0.1143)
		(layer "In15.Cu")
		(net "GMI_CPU0_G1_CPU1_G3_TX_DN<1>")
	)
	(segment
		(start 113.467642 -244.806978)
		(end 113.506758 -244.829838)
		(width 0.1143)
		(layer "In15.Cu")
		(net "GMI_CPU0_G1_CPU1_G3_TX_DN<1>")
	)
	(segment
		(start 318.00673 -180.805582)
		(end 311.250584 -176.981104)
		(width 0.14224)
		(layer "In15.Cu")
		(net "GMI_CPU0_G1_CPU1_G3_TX_DN<1>")
	)
	(segment
		(start 113.506758 -229.559104)
		(end 113.467642 -229.581964)
		(width 0.1143)
		(layer "In15.Cu")
		(net "GMI_CPU0_G1_CPU1_G3_TX_DN<1>")
	)
	(segment
		(start 113.506758 -234.418886)
		(end 113.468658 -234.441238)
		(width 0.1143)
		(layer "In15.Cu")
		(net "GMI_CPU0_G1_CPU1_G3_TX_DN<1>")
	)
	(segment
		(start 358.060752 -231.220518)
		(end 358.02824 -231.201722)
		(width 0.1143)
		(layer "In15.Cu")
		(net "GMI_CPU0_G1_CPU1_G3_TX_DN<1>")
	)
	(segment
		(start 113.437162 -223.729296)
		(end 113.467642 -223.747076)
		(width 0.1143)
		(layer "In15.Cu")
		(net "GMI_CPU0_G1_CPU1_G3_TX_DN<1>")
	)
	(segment
		(start 357.035862 -217.428826)
		(end 356.856284 -217.364818)
		(width 0.14224)
		(layer "In15.Cu")
		(net "GMI_CPU0_G1_CPU1_G3_TX_DN<1>")
	)
	(segment
		(start 357.989124 -231.869488)
		(end 358.02824 -231.846628)
		(width 0.1143)
		(layer "In15.Cu")
		(net "GMI_CPU0_G1_CPU1_G3_TX_DN<1>")
	)
	(segment
		(start 356.562152 -216.427812)
		(end 356.382574 -216.363804)
		(width 0.14224)
		(layer "In15.Cu")
		(net "GMI_CPU0_G1_CPU1_G3_TX_DN<1>")
	)
	(segment
		(start 355.140768 -213.424262)
		(end 354.96119 -213.360254)
		(width 0.14224)
		(layer "In15.Cu")
		(net "GMI_CPU0_G1_CPU1_G3_TX_DN<1>")
	)
	(segment
		(start 357.991664 -230.247952)
		(end 358.05872 -230.208836)
		(width 0.1143)
		(layer "In15.Cu")
		(net "GMI_CPU0_G1_CPU1_G3_TX_DN<1>")
	)
	(segment
		(start 356.431088 -246.914162)
		(end 356.72903 -246.914162)
		(width 0.1143)
		(layer "In15.Cu")
		(net "GMI_CPU0_G1_CPU1_G3_TX_DN<1>")
	)
	(segment
		(start 353.46259 -209.878168)
		(end 318.00673 -180.805582)
		(width 0.14224)
		(layer "In15.Cu")
		(net "GMI_CPU0_G1_CPU1_G3_TX_DN<1>")
	)
	(segment
		(start 113.467642 -231.201976)
		(end 113.43513 -231.220772)
		(width 0.1143)
		(layer "In15.Cu")
		(net "GMI_CPU0_G1_CPU1_G3_TX_DN<1>")
	)
	(segment
		(start 113.937796 -245.616984)
		(end 113.941098 -245.619016)
		(width 0.1143)
		(layer "In15.Cu")
		(net "GMI_CPU0_G1_CPU1_G3_TX_DN<1>")
	)
	(segment
		(start 113.941098 -245.619016)
		(end 113.974118 -245.638066)
		(width 0.1143)
		(layer "In15.Cu")
		(net "GMI_CPU0_G1_CPU1_G3_TX_DN<1>")
	)
	(segment
		(start 113.437162 -226.96932)
		(end 113.467642 -226.9871)
		(width 0.1143)
		(layer "In15.Cu")
		(net "GMI_CPU0_G1_CPU1_G3_TX_DN<1>")
	)
	(segment
		(start 358.061006 -239.927638)
		(end 358.063038 -239.926114)
		(width 0.1143)
		(layer "In15.Cu")
		(net "GMI_CPU0_G1_CPU1_G3_TX_DN<1>")
	)
	(segment
		(start 113.437162 -241.549174)
		(end 113.467642 -241.566954)
		(width 0.1143)
		(layer "In15.Cu")
		(net "GMI_CPU0_G1_CPU1_G3_TX_DN<1>")
	)
	(segment
		(start 165.049454 -175.21682)
		(end 156.513276 -178.269138)
		(width 0.14224)
		(layer "In15.Cu")
		(net "GMI_CPU0_G1_CPU1_G3_TX_DN<1>")
	)
	(segment
		(start 357.560626 -245.615206)
		(end 357.56215 -245.614444)
		(width 0.1143)
		(layer "In15.Cu")
		(net "GMI_CPU0_G1_CPU1_G3_TX_DN<1>")
	)
	(segment
		(start 358.02824 -239.301528)
		(end 357.989124 -239.278668)
		(width 0.1143)
		(layer "In15.Cu")
		(net "GMI_CPU0_G1_CPU1_G3_TX_DN<1>")
	)
	(segment
		(start 358.061006 -237.700566)
		(end 358.02824 -237.681516)
		(width 0.1143)
		(layer "In15.Cu")
		(net "GMI_CPU0_G1_CPU1_G3_TX_DN<1>")
	)
	(segment
		(start 357.989124 -228.629718)
		(end 358.02824 -228.606858)
		(width 0.1143)
		(layer "In15.Cu")
		(net "GMI_CPU0_G1_CPU1_G3_TX_DN<1>")
	)
	(segment
		(start 113.906046 -245.598696)
		(end 113.937034 -245.616476)
		(width 0.1143)
		(layer "In15.Cu")
		(net "GMI_CPU0_G1_CPU1_G3_TX_DN<1>")
	)
	(segment
		(start 358.02824 -237.681516)
		(end 357.989124 -237.658656)
		(width 0.1143)
		(layer "In15.Cu")
		(net "GMI_CPU0_G1_CPU1_G3_TX_DN<1>")
	)
	(segment
		(start 358.061006 -236.080554)
		(end 358.02824 -236.061504)
		(width 0.1143)
		(layer "In15.Cu")
		(net "GMI_CPU0_G1_CPU1_G3_TX_DN<1>")
	)
	(segment
		(start 114.758724 -214.400384)
		(end 114.581178 -214.446612)
		(width 0.14224)
		(layer "In15.Cu")
		(net "GMI_CPU0_G1_CPU1_G3_TX_DN<1>")
	)
	(segment
		(start 113.437162 -236.689138)
		(end 113.467642 -236.706918)
		(width 0.1143)
		(layer "In15.Cu")
		(net "GMI_CPU0_G1_CPU1_G3_TX_DN<1>")
	)
	(segment
		(start 113.506758 -237.65891)
		(end 113.439956 -237.698026)
		(width 0.1143)
		(layer "In15.Cu")
		(net "GMI_CPU0_G1_CPU1_G3_TX_DN<1>")
	)
	(segment
		(start 113.438178 -222.110046)
		(end 113.467642 -222.127064)
		(width 0.1143)
		(layer "In15.Cu")
		(net "GMI_CPU0_G1_CPU1_G3_TX_DN<1>")
	)
	(segment
		(start 113.437162 -231.829102)
		(end 113.467642 -231.846882)
		(width 0.1143)
		(layer "In15.Cu")
		(net "GMI_CPU0_G1_CPU1_G3_TX_DN<1>")
	)
	(segment
		(start 357.566976 -245.61165)
		(end 357.567738 -245.611142)
		(width 0.1143)
		(layer "In15.Cu")
		(net "GMI_CPU0_G1_CPU1_G3_TX_DN<1>")
	)
	(segment
		(start 357.989124 -236.729524)
		(end 358.061006 -236.687614)
		(width 0.1143)
		(layer "In15.Cu")
		(net "GMI_CPU0_G1_CPU1_G3_TX_DN<1>")
	)
	(segment
		(start 357.989124 -243.209572)
		(end 358.05872 -243.168932)
		(width 0.1143)
		(layer "In15.Cu")
		(net "GMI_CPU0_G1_CPU1_G3_TX_DN<1>")
	)
	(segment
		(start 356.088442 -215.426544)
		(end 355.908864 -215.362536)
		(width 0.14224)
		(layer "In15.Cu")
		(net "GMI_CPU0_G1_CPU1_G3_TX_DN<1>")
	)
	(segment
		(start 357.55834 -225.53168)
		(end 357.519224 -225.50882)
		(width 0.1143)
		(layer "In15.Cu")
		(net "GMI_CPU0_G1_CPU1_G3_TX_DN<1>")
	)
	(segment
		(start 358.061006 -235.067602)
		(end 358.063038 -235.066078)
		(width 0.1143)
		(layer "In15.Cu")
		(net "GMI_CPU0_G1_CPU1_G3_TX_DN<1>")
	)
	(segment
		(start 355.908864 -215.362536)
		(end 355.72954 -214.983314)
		(width 0.14224)
		(layer "In15.Cu")
		(net "GMI_CPU0_G1_CPU1_G3_TX_DN<1>")
	)
	(segment
		(start 355.72954 -214.983314)
		(end 355.793548 -214.804244)
		(width 0.14224)
		(layer "In15.Cu")
		(net "GMI_CPU0_G1_CPU1_G3_TX_DN<1>")
	)
	(arc
		(start 113.28146 -244.481096)
		(mid 113.280613 -244.491493)
		(end 113.280698 -244.501924)
		(width 0.1143)
		(layer "In15.Cu")
		(net "GMI_CPU0_G1_CPU1_G3_TX_DN<1>")
	)
	(arc
		(start 113.28146 -242.861338)
		(mid 113.280618 -242.871608)
		(end 113.280698 -242.881912)
		(width 0.1143)
		(layer "In15.Cu")
		(net "GMI_CPU0_G1_CPU1_G3_TX_DN<1>")
	)
	(arc
		(start 358.05872 -231.828848)
		(mid 358.174147 -231.695472)
		(end 358.215692 -231.524048)
		(width 0.1143)
		(layer "In15.Cu")
		(net "GMI_CPU0_G1_CPU1_G3_TX_DN<1>")
	)
	(arc
		(start 113.506758 -231.869742)
		(mid 113.750085 -232.334308)
		(end 113.506758 -232.798874)
		(width 0.1143)
		(layer "In15.Cu")
		(net "GMI_CPU0_G1_CPU1_G3_TX_DN<1>")
	)
	(arc
		(start 113.43513 -229.60076)
		(mid 113.321201 -229.733907)
		(end 113.28019 -229.90429)
		(width 0.1143)
		(layer "In15.Cu")
		(net "GMI_CPU0_G1_CPU1_G3_TX_DN<1>")
	)
	(arc
		(start 113.506758 -225.389948)
		(mid 113.750085 -225.854514)
		(end 113.506758 -226.31908)
		(width 0.1143)
		(layer "In15.Cu")
		(net "GMI_CPU0_G1_CPU1_G3_TX_DN<1>")
	)
	(arc
		(start 357.989124 -231.178862)
		(mid 357.810311 -230.976512)
		(end 357.745792 -230.714296)
		(width 0.1143)
		(layer "In15.Cu")
		(net "GMI_CPU0_G1_CPU1_G3_TX_DN<1>")
	)
	(arc
		(start 113.75009 -230.71455)
		(mid 113.685575 -230.976769)
		(end 113.506758 -231.179116)
		(width 0.1143)
		(layer "In15.Cu")
		(net "GMI_CPU0_G1_CPU1_G3_TX_DN<1>")
	)
	(arc
		(start 358.063038 -236.68609)
		(mid 358.217218 -236.384084)
		(end 358.063038 -236.082078)
		(width 0.1143)
		(layer "In15.Cu")
		(net "GMI_CPU0_G1_CPU1_G3_TX_DN<1>")
	)
	(arc
		(start 113.506758 -233.489754)
		(mid 113.750085 -233.95432)
		(end 113.506758 -234.418886)
		(width 0.1143)
		(layer "In15.Cu")
		(net "GMI_CPU0_G1_CPU1_G3_TX_DN<1>")
	)
	(arc
		(start 113.506758 -228.629972)
		(mid 113.750085 -229.094538)
		(end 113.506758 -229.559104)
		(width 0.1143)
		(layer "In15.Cu")
		(net "GMI_CPU0_G1_CPU1_G3_TX_DN<1>")
	)
	(arc
		(start 358.215692 -231.524048)
		(mid 358.174726 -231.353642)
		(end 358.060752 -231.220518)
		(width 0.1143)
		(layer "In15.Cu")
		(net "GMI_CPU0_G1_CPU1_G3_TX_DN<1>")
	)
	(arc
		(start 113.437162 -223.119696)
		(mid 113.280185 -223.424496)
		(end 113.437162 -223.729296)
		(width 0.1143)
		(layer "In15.Cu")
		(net "GMI_CPU0_G1_CPU1_G3_TX_DN<1>")
	)
	(arc
		(start 358.215946 -242.864132)
		(mid 358.17498 -242.693726)
		(end 358.061006 -242.560602)
		(width 0.1143)
		(layer "In15.Cu")
		(net "GMI_CPU0_G1_CPU1_G3_TX_DN<1>")
	)
	(arc
		(start 113.467896 -234.441746)
		(mid 113.282918 -234.7596)
		(end 113.459768 -235.08208)
		(width 0.1143)
		(layer "In15.Cu")
		(net "GMI_CPU0_G1_CPU1_G3_TX_DN<1>")
	)
	(arc
		(start 113.439956 -237.698026)
		(mid 113.327109 -237.834005)
		(end 113.28019 -238.00435)
		(width 0.1143)
		(layer "In15.Cu")
		(net "GMI_CPU0_G1_CPU1_G3_TX_DN<1>")
	)
	(arc
		(start 356.811834 -246.831358)
		(mid 356.813622 -246.819909)
		(end 356.815644 -246.808498)
		(width 0.1143)
		(layer "In15.Cu")
		(net "GMI_CPU0_G1_CPU1_G3_TX_DN<1>")
	)
	(arc
		(start 113.28019 -229.90429)
		(mid 113.321739 -230.075712)
		(end 113.437162 -230.20909)
		(width 0.1143)
		(layer "In15.Cu")
		(net "GMI_CPU0_G1_CPU1_G3_TX_DN<1>")
	)
	(arc
		(start 113.280698 -242.881912)
		(mid 113.32593 -243.043509)
		(end 113.437162 -243.169186)
		(width 0.1143)
		(layer "In15.Cu")
		(net "GMI_CPU0_G1_CPU1_G3_TX_DN<1>")
	)
	(arc
		(start 357.745792 -230.714296)
		(mid 357.811028 -230.450705)
		(end 357.991664 -230.247952)
		(width 0.1143)
		(layer "In15.Cu")
		(net "GMI_CPU0_G1_CPU1_G3_TX_DN<1>")
	)
	(arc
		(start 358.05872 -230.208836)
		(mid 358.172221 -230.078795)
		(end 358.215438 -229.911656)
		(width 0.1143)
		(layer "In15.Cu")
		(net "GMI_CPU0_G1_CPU1_G3_TX_DN<1>")
	)
	(arc
		(start 357.989124 -232.79862)
		(mid 357.745797 -232.334054)
		(end 357.989124 -231.869488)
		(width 0.1143)
		(layer "In15.Cu")
		(net "GMI_CPU0_G1_CPU1_G3_TX_DN<1>")
	)
	(arc
		(start 113.28019 -238.00435)
		(mid 113.321739 -238.175772)
		(end 113.437162 -238.30915)
		(width 0.1143)
		(layer "In15.Cu")
		(net "GMI_CPU0_G1_CPU1_G3_TX_DN<1>")
	)
	(arc
		(start 113.506758 -243.209826)
		(mid 113.750085 -243.674392)
		(end 113.506758 -244.138958)
		(width 0.1143)
		(layer "In15.Cu")
		(net "GMI_CPU0_G1_CPU1_G3_TX_DN<1>")
	)
	(arc
		(start 113.44402 -240.93551)
		(mid 113.335204 -241.073787)
		(end 113.28146 -241.241326)
		(width 0.1143)
		(layer "In15.Cu")
		(net "GMI_CPU0_G1_CPU1_G3_TX_DN<1>")
	)
	(arc
		(start 113.506758 -227.00996)
		(mid 113.750085 -227.474526)
		(end 113.506758 -227.939092)
		(width 0.1143)
		(layer "In15.Cu")
		(net "GMI_CPU0_G1_CPU1_G3_TX_DN<1>")
	)
	(arc
		(start 113.28019 -221.804484)
		(mid 113.32203 -221.97647)
		(end 113.438178 -222.110046)
		(width 0.1143)
		(layer "In15.Cu")
		(net "GMI_CPU0_G1_CPU1_G3_TX_DN<1>")
	)
	(arc
		(start 113.467896 -232.821734)
		(mid 113.282918 -233.139588)
		(end 113.459768 -233.462068)
		(width 0.1143)
		(layer "In15.Cu")
		(net "GMI_CPU0_G1_CPU1_G3_TX_DN<1>")
	)
	(arc
		(start 357.500428 -244.935248)
		(mid 357.269914 -244.484144)
		(end 357.500428 -244.03304)
		(width 0.1143)
		(layer "In15.Cu")
		(net "GMI_CPU0_G1_CPU1_G3_TX_DN<1>")
	)
	(arc
		(start 357.989124 -240.89868)
		(mid 357.745797 -240.434114)
		(end 357.989124 -239.969548)
		(width 0.1143)
		(layer "In15.Cu")
		(net "GMI_CPU0_G1_CPU1_G3_TX_DN<1>")
	)
	(arc
		(start 113.974118 -245.638066)
		(mid 114.15477 -245.840811)
		(end 114.21999 -246.10441)
		(width 0.1143)
		(layer "In15.Cu")
		(net "GMI_CPU0_G1_CPU1_G3_TX_DN<1>")
	)
	(arc
		(start 114.680238 -246.808752)
		(mid 114.682261 -246.820162)
		(end 114.684048 -246.831612)
		(width 0.1143)
		(layer "In15.Cu")
		(net "GMI_CPU0_G1_CPU1_G3_TX_DN<1>")
	)
	(arc
		(start 113.44402 -244.175788)
		(mid 113.335395 -244.31388)
		(end 113.28146 -244.481096)
		(width 0.1143)
		(layer "In15.Cu")
		(net "GMI_CPU0_G1_CPU1_G3_TX_DN<1>")
	)
	(arc
		(start 113.504218 -230.248206)
		(mid 113.68487 -230.450951)
		(end 113.75009 -230.71455)
		(width 0.1143)
		(layer "In15.Cu")
		(net "GMI_CPU0_G1_CPU1_G3_TX_DN<1>")
	)
	(arc
		(start 357.04907 -224.698814)
		(mid 356.870257 -224.496464)
		(end 356.805738 -224.234248)
		(width 0.1143)
		(layer "In15.Cu")
		(net "GMI_CPU0_G1_CPU1_G3_TX_DN<1>")
	)
	(arc
		(start 113.467896 -239.301782)
		(mid 113.282918 -239.619636)
		(end 113.459768 -239.942116)
		(width 0.1143)
		(layer "In15.Cu")
		(net "GMI_CPU0_G1_CPU1_G3_TX_DN<1>")
	)
	(arc
		(start 357.989124 -242.518692)
		(mid 357.745797 -242.054126)
		(end 357.989124 -241.58956)
		(width 0.1143)
		(layer "In15.Cu")
		(net "GMI_CPU0_G1_CPU1_G3_TX_DN<1>")
	)
	(arc
		(start 357.091742 -246.424704)
		(mid 357.229104 -246.287566)
		(end 357.279448 -246.100092)
		(width 0.1143)
		(layer "In15.Cu")
		(net "GMI_CPU0_G1_CPU1_G3_TX_DN<1>")
	)
	(arc
		(start 358.215184 -229.90175)
		(mid 358.164685 -229.740961)
		(end 358.065324 -229.604824)
		(width 0.1143)
		(layer "In15.Cu")
		(net "GMI_CPU0_G1_CPU1_G3_TX_DN<1>")
	)
	(arc
		(start 113.280698 -244.501924)
		(mid 113.32593 -244.663521)
		(end 113.437162 -244.789198)
		(width 0.1143)
		(layer "In15.Cu")
		(net "GMI_CPU0_G1_CPU1_G3_TX_DN<1>")
	)
	(arc
		(start 357.279448 -246.100092)
		(mid 357.353956 -245.821379)
		(end 357.557578 -245.616984)
		(width 0.1143)
		(layer "In15.Cu")
		(net "GMI_CPU0_G1_CPU1_G3_TX_DN<1>")
	)
	(arc
		(start 113.437162 -227.979732)
		(mid 113.280185 -228.284532)
		(end 113.437162 -228.589332)
		(width 0.1143)
		(layer "In15.Cu")
		(net "GMI_CPU0_G1_CPU1_G3_TX_DN<1>")
	)
	(arc
		(start 357.589836 -243.97843)
		(mid 357.704512 -243.845096)
		(end 357.745792 -243.674138)
		(width 0.1143)
		(layer "In15.Cu")
		(net "GMI_CPU0_G1_CPU1_G3_TX_DN<1>")
	)
	(arc
		(start 113.28019 -231.524302)
		(mid 113.321739 -231.695724)
		(end 113.437162 -231.829102)
		(width 0.1143)
		(layer "In15.Cu")
		(net "GMI_CPU0_G1_CPU1_G3_TX_DN<1>")
	)
	(arc
		(start 357.989124 -226.318826)
		(mid 357.810311 -226.116476)
		(end 357.745792 -225.85426)
		(width 0.1143)
		(layer "In15.Cu")
		(net "GMI_CPU0_G1_CPU1_G3_TX_DN<1>")
	)
	(arc
		(start 357.263954 -221.898464)
		(mid 357.272909 -221.851726)
		(end 357.275892 -221.80423)
		(width 0.1143)
		(layer "In15.Cu")
		(net "GMI_CPU0_G1_CPU1_G3_TX_DN<1>")
	)
	(arc
		(start 113.44402 -242.555522)
		(mid 113.335204 -242.693799)
		(end 113.28146 -242.861338)
		(width 0.1143)
		(layer "In15.Cu")
		(net "GMI_CPU0_G1_CPU1_G3_TX_DN<1>")
	)
	(arc
		(start 358.063038 -233.446066)
		(mid 358.217218 -233.14406)
		(end 358.063038 -232.842054)
		(width 0.1143)
		(layer "In15.Cu")
		(net "GMI_CPU0_G1_CPU1_G3_TX_DN<1>")
	)
	(arc
		(start 114.446812 -246.44985)
		(mid 114.598799 -246.606358)
		(end 114.680238 -246.808752)
		(width 0.1143)
		(layer "In15.Cu")
		(net "GMI_CPU0_G1_CPU1_G3_TX_DN<1>")
	)
	(arc
		(start 358.068118 -241.543586)
		(mid 358.239839 -241.24412)
		(end 358.068118 -240.944654)
		(width 0.1143)
		(layer "In15.Cu")
		(net "GMI_CPU0_G1_CPU1_G3_TX_DN<1>")
	)
	(arc
		(start 358.061514 -243.1669)
		(mid 358.167712 -243.04903)
		(end 358.214422 -242.897406)
		(width 0.1143)
		(layer "In15.Cu")
		(net "GMI_CPU0_G1_CPU1_G3_TX_DN<1>")
	)
	(arc
		(start 113.506758 -241.589814)
		(mid 113.750085 -242.05438)
		(end 113.506758 -242.518946)
		(width 0.1143)
		(layer "In15.Cu")
		(net "GMI_CPU0_G1_CPU1_G3_TX_DN<1>")
	)
	(arc
		(start 357.745792 -225.85426)
		(mid 357.704243 -225.682838)
		(end 357.58882 -225.54946)
		(width 0.1143)
		(layer "In15.Cu")
		(net "GMI_CPU0_G1_CPU1_G3_TX_DN<1>")
	)
	(arc
		(start 357.275892 -225.044254)
		(mid 357.234637 -224.873283)
		(end 357.119936 -224.739962)
		(width 0.1143)
		(layer "In15.Cu")
		(net "GMI_CPU0_G1_CPU1_G3_TX_DN<1>")
	)
	(arc
		(start 357.119936 -222.108522)
		(mid 357.168868 -222.066434)
		(end 357.209852 -222.016574)
		(width 0.1143)
		(layer "In15.Cu")
		(net "GMI_CPU0_G1_CPU1_G3_TX_DN<1>")
	)
	(arc
		(start 358.05872 -226.969066)
		(mid 358.215697 -226.664266)
		(end 358.05872 -226.359466)
		(width 0.1143)
		(layer "In15.Cu")
		(net "GMI_CPU0_G1_CPU1_G3_TX_DN<1>")
	)
	(arc
		(start 356.805738 -222.614236)
		(mid 356.870253 -222.352017)
		(end 357.04907 -222.14967)
		(width 0.1143)
		(layer "In15.Cu")
		(net "GMI_CPU0_G1_CPU1_G3_TX_DN<1>")
	)
	(arc
		(start 357.209852 -222.016574)
		(mid 357.242049 -221.959877)
		(end 357.263954 -221.898464)
		(width 0.1143)
		(layer "In15.Cu")
		(net "GMI_CPU0_G1_CPU1_G3_TX_DN<1>")
	)
	(arc
		(start 357.989124 -239.278668)
		(mid 357.745797 -238.814102)
		(end 357.989124 -238.349536)
		(width 0.1143)
		(layer "In15.Cu")
		(net "GMI_CPU0_G1_CPU1_G3_TX_DN<1>")
	)
	(arc
		(start 358.214422 -242.897406)
		(mid 358.21536 -242.882433)
		(end 358.215692 -242.867434)
		(width 0.1143)
		(layer "In15.Cu")
		(net "GMI_CPU0_G1_CPU1_G3_TX_DN<1>")
	)
	(arc
		(start 357.989124 -237.658656)
		(mid 357.745797 -237.19409)
		(end 357.989124 -236.729524)
		(width 0.1143)
		(layer "In15.Cu")
		(net "GMI_CPU0_G1_CPU1_G3_TX_DN<1>")
	)
	(arc
		(start 356.805738 -224.234248)
		(mid 356.870031 -223.972643)
		(end 357.048054 -223.770444)
		(width 0.1143)
		(layer "In15.Cu")
		(net "GMI_CPU0_G1_CPU1_G3_TX_DN<1>")
	)
	(arc
		(start 357.989124 -229.55885)
		(mid 357.745797 -229.094284)
		(end 357.989124 -228.629718)
		(width 0.1143)
		(layer "In15.Cu")
		(net "GMI_CPU0_G1_CPU1_G3_TX_DN<1>")
	)
	(arc
		(start 356.815644 -246.808498)
		(mid 356.865105 -246.662179)
		(end 356.952296 -246.534686)
		(width 0.1143)
		(layer "In15.Cu")
		(net "GMI_CPU0_G1_CPU1_G3_TX_DN<1>")
	)
	(arc
		(start 357.745792 -243.674138)
		(mid 357.810307 -243.411919)
		(end 357.989124 -243.209572)
		(width 0.1143)
		(layer "In15.Cu")
		(net "GMI_CPU0_G1_CPU1_G3_TX_DN<1>")
	)
	(arc
		(start 113.506758 -238.34979)
		(mid 113.750085 -238.814356)
		(end 113.506758 -239.278922)
		(width 0.1143)
		(layer "In15.Cu")
		(net "GMI_CPU0_G1_CPU1_G3_TX_DN<1>")
	)
	(arc
		(start 113.506758 -236.729778)
		(mid 113.750085 -237.194344)
		(end 113.506758 -237.65891)
		(width 0.1143)
		(layer "In15.Cu")
		(net "GMI_CPU0_G1_CPU1_G3_TX_DN<1>")
	)
	(arc
		(start 357.989124 -234.418632)
		(mid 357.745797 -233.954066)
		(end 357.989124 -233.4895)
		(width 0.1143)
		(layer "In15.Cu")
		(net "GMI_CPU0_G1_CPU1_G3_TX_DN<1>")
	)
	(arc
		(start 113.506758 -222.149924)
		(mid 113.750085 -222.61449)
		(end 113.506758 -223.079056)
		(width 0.1143)
		(layer "In15.Cu")
		(net "GMI_CPU0_G1_CPU1_G3_TX_DN<1>")
	)
	(arc
		(start 113.44402 -236.075728)
		(mid 113.335395 -236.21382)
		(end 113.28146 -236.381036)
		(width 0.1143)
		(layer "In15.Cu")
		(net "GMI_CPU0_G1_CPU1_G3_TX_DN<1>")
	)
	(arc
		(start 113.280698 -241.2619)
		(mid 113.32593 -241.423497)
		(end 113.437162 -241.549174)
		(width 0.1143)
		(layer "In15.Cu")
		(net "GMI_CPU0_G1_CPU1_G3_TX_DN<1>")
	)
	(arc
		(start 358.05872 -228.589078)
		(mid 358.215697 -228.284278)
		(end 358.05872 -227.979478)
		(width 0.1143)
		(layer "In15.Cu")
		(net "GMI_CPU0_G1_CPU1_G3_TX_DN<1>")
	)
	(arc
		(start 114.21999 -246.12727)
		(mid 114.25635 -246.27784)
		(end 114.357404 -246.39524)
		(width 0.1143)
		(layer "In15.Cu")
		(net "GMI_CPU0_G1_CPU1_G3_TX_DN<1>")
	)
	(arc
		(start 113.505234 -233.488738)
		(mid 113.505996 -233.489245)
		(end 113.506758 -233.489754)
		(width 0.1143)
		(layer "In15.Cu")
		(net "GMI_CPU0_G1_CPU1_G3_TX_DN<1>")
	)
	(arc
		(start 113.506758 -239.969802)
		(mid 113.750085 -240.434368)
		(end 113.506758 -240.898934)
		(width 0.1143)
		(layer "In15.Cu")
		(net "GMI_CPU0_G1_CPU1_G3_TX_DN<1>")
	)
	(arc
		(start 113.28146 -236.381036)
		(mid 113.280613 -236.391433)
		(end 113.280698 -236.401864)
		(width 0.1143)
		(layer "In15.Cu")
		(net "GMI_CPU0_G1_CPU1_G3_TX_DN<1>")
	)
	(arc
		(start 113.506758 -244.829838)
		(mid 113.685571 -245.032188)
		(end 113.75009 -245.294404)
		(width 0.1143)
		(layer "In15.Cu")
		(net "GMI_CPU0_G1_CPU1_G3_TX_DN<1>")
	)
	(arc
		(start 357.519224 -225.50882)
		(mid 357.340411 -225.30647)
		(end 357.275892 -225.044254)
		(width 0.1143)
		(layer "In15.Cu")
		(net "GMI_CPU0_G1_CPU1_G3_TX_DN<1>")
	)
	(arc
		(start 358.063038 -235.066078)
		(mid 358.217218 -234.764072)
		(end 358.063038 -234.462066)
		(width 0.1143)
		(layer "In15.Cu")
		(net "GMI_CPU0_G1_CPU1_G3_TX_DN<1>")
	)
	(arc
		(start 113.28146 -241.241326)
		(mid 113.280618 -241.251596)
		(end 113.280698 -241.2619)
		(width 0.1143)
		(layer "In15.Cu")
		(net "GMI_CPU0_G1_CPU1_G3_TX_DN<1>")
	)
	(arc
		(start 357.589836 -245.598442)
		(mid 357.745764 -245.29415)
		(end 357.589836 -244.989858)
		(width 0.1143)
		(layer "In15.Cu")
		(net "GMI_CPU0_G1_CPU1_G3_TX_DN<1>")
	)
	(arc
		(start 113.437162 -226.35972)
		(mid 113.280185 -226.66452)
		(end 113.437162 -226.96932)
		(width 0.1143)
		(layer "In15.Cu")
		(net "GMI_CPU0_G1_CPU1_G3_TX_DN<1>")
	)
	(arc
		(start 358.063038 -239.926114)
		(mid 358.217218 -239.624108)
		(end 358.063038 -239.322102)
		(width 0.1143)
		(layer "In15.Cu")
		(net "GMI_CPU0_G1_CPU1_G3_TX_DN<1>")
	)
	(arc
		(start 113.75009 -245.294404)
		(mid 113.791345 -245.465375)
		(end 113.906046 -245.598696)
		(width 0.1143)
		(layer "In15.Cu")
		(net "GMI_CPU0_G1_CPU1_G3_TX_DN<1>")
	)
	(arc
		(start 358.065324 -229.604824)
		(mid 358.060401 -229.6011)
		(end 358.055418 -229.597458)
		(width 0.1143)
		(layer "In15.Cu")
		(net "GMI_CPU0_G1_CPU1_G3_TX_DN<1>")
	)
	(arc
		(start 357.989124 -227.938838)
		(mid 357.745797 -227.474272)
		(end 357.989124 -227.009706)
		(width 0.1143)
		(layer "In15.Cu")
		(net "GMI_CPU0_G1_CPU1_G3_TX_DN<1>")
	)
	(arc
		(start 113.43513 -231.220772)
		(mid 113.321201 -231.353919)
		(end 113.28019 -231.524302)
		(width 0.1143)
		(layer "In15.Cu")
		(net "GMI_CPU0_G1_CPU1_G3_TX_DN<1>")
	)
	(arc
		(start 357.989124 -236.038644)
		(mid 357.745797 -235.574078)
		(end 357.989124 -235.109512)
		(width 0.1143)
		(layer "In15.Cu")
		(net "GMI_CPU0_G1_CPU1_G3_TX_DN<1>")
	)
	(arc
		(start 357.086662 -223.103694)
		(mid 356.880978 -222.89639)
		(end 356.805738 -222.614236)
		(width 0.1143)
		(layer "In15.Cu")
		(net "GMI_CPU0_G1_CPU1_G3_TX_DN<1>")
	)
	(arc
		(start 113.505234 -235.10875)
		(mid 113.505996 -235.109257)
		(end 113.506758 -235.109766)
		(width 0.1143)
		(layer "In15.Cu")
		(net "GMI_CPU0_G1_CPU1_G3_TX_DN<1>")
	)
	(arc
		(start 358.063038 -238.306102)
		(mid 358.217218 -238.004096)
		(end 358.063038 -237.70209)
		(width 0.1143)
		(layer "In15.Cu")
		(net "GMI_CPU0_G1_CPU1_G3_TX_DN<1>")
	)
	(arc
		(start 113.506758 -223.769936)
		(mid 113.750085 -224.234502)
		(end 113.506758 -224.699068)
		(width 0.1143)
		(layer "In15.Cu")
		(net "GMI_CPU0_G1_CPU1_G3_TX_DN<1>")
	)
	(arc
		(start 356.952296 -246.534686)
		(mid 356.998244 -246.489367)
		(end 357.04907 -246.449596)
		(width 0.1143)
		(layer "In15.Cu")
		(net "GMI_CPU0_G1_CPU1_G3_TX_DN<1>")
	)
	(arc
		(start 113.280698 -236.401864)
		(mid 113.32593 -236.563461)
		(end 113.437162 -236.689138)
		(width 0.1143)
		(layer "In15.Cu")
		(net "GMI_CPU0_G1_CPU1_G3_TX_DN<1>")
	)
	(arc
		(start 113.505234 -239.968786)
		(mid 113.505996 -239.969293)
		(end 113.506758 -239.969802)
		(width 0.1143)
		(layer "In15.Cu")
		(net "GMI_CPU0_G1_CPU1_G3_TX_DN<1>")
	)
	(arc
		(start 357.12019 -223.728534)
		(mid 357.274219 -223.408232)
		(end 357.088694 -223.104964)
		(width 0.1143)
		(layer "In15.Cu")
		(net "GMI_CPU0_G1_CPU1_G3_TX_DN<1>")
	)
	(arc
		(start 113.437162 -224.739708)
		(mid 113.280185 -225.044508)
		(end 113.437162 -225.349308)
		(width 0.1143)
		(layer "In15.Cu")
		(net "GMI_CPU0_G1_CPU1_G3_TX_DN<1>")
	)
	(arc
		(start 113.506758 -235.109766)
		(mid 113.750085 -235.574332)
		(end 113.506758 -236.038898)
		(width 0.1143)
		(layer "In15.Cu")
		(net "GMI_CPU0_G1_CPU1_G3_TX_DN<1>")
	)
	(segment
		(start 346.087954 -246.370094)
		(end 345.621102 -246.104156)
		(width 0.12954)
		(layer "F.Cu")
		(net "GMI_CPU0_G1_CPU1_G3_TX_DN<15>")
	)
	(segment
		(start 125.407928 -246.370348)
		(end 125.87478 -246.10441)
		(width 0.12954)
		(layer "F.Cu")
		(net "GMI_CPU0_G1_CPU1_G3_TX_DN<15>")
	)
	(segment
		(start 341.559896 -217.638122)
		(end 316.413896 -197.02018)
		(width 0.14224)
		(layer "In15.Cu")
		(net "GMI_CPU0_G1_CPU1_G3_TX_DN<15>")
	)
	(segment
		(start 160.7439 -193.746628)
		(end 160.72485 -193.939668)
		(width 0.14224)
		(layer "In15.Cu")
		(net "GMI_CPU0_G1_CPU1_G3_TX_DN<15>")
	)
	(segment
		(start 156.03347 -197.786752)
		(end 155.84043 -197.767702)
		(width 0.14224)
		(layer "In15.Cu")
		(net "GMI_CPU0_G1_CPU1_G3_TX_DN<15>")
	)
	(segment
		(start 343.889076 -223.769682)
		(end 343.928192 -223.746822)
		(width 0.1143)
		(layer "In15.Cu")
		(net "GMI_CPU0_G1_CPU1_G3_TX_DN<15>")
	)
	(segment
		(start 126.485396 -221.12605)
		(end 126.485396 -221.174564)
		(width 0.14224)
		(layer "In15.Cu")
		(net "GMI_CPU0_G1_CPU1_G3_TX_DN<15>")
	)
	(segment
		(start 126.160276 -244.9703)
		(end 126.158752 -244.971316)
		(width 0.1143)
		(layer "In15.Cu")
		(net "GMI_CPU0_G1_CPU1_G3_TX_DN<15>")
	)
	(segment
		(start 158.127192 -195.89242)
		(end 158.108142 -196.08546)
		(width 0.14224)
		(layer "In15.Cu")
		(net "GMI_CPU0_G1_CPU1_G3_TX_DN<15>")
	)
	(segment
		(start 343.958672 -224.739454)
		(end 343.928192 -224.721674)
		(width 0.1143)
		(layer "In15.Cu")
		(net "GMI_CPU0_G1_CPU1_G3_TX_DN<15>")
	)
	(segment
		(start 344.898726 -232.83926)
		(end 344.868246 -232.82148)
		(width 0.1143)
		(layer "In15.Cu")
		(net "GMI_CPU0_G1_CPU1_G3_TX_DN<15>")
	)
	(segment
		(start 343.928192 -223.746822)
		(end 343.958672 -223.729042)
		(width 0.1143)
		(layer "In15.Cu")
		(net "GMI_CPU0_G1_CPU1_G3_TX_DN<15>")
	)
	(segment
		(start 344.868246 -226.986846)
		(end 344.898726 -226.969066)
		(width 0.1143)
		(layer "In15.Cu")
		(net "GMI_CPU0_G1_CPU1_G3_TX_DN<15>")
	)
	(segment
		(start 160.39465 -194.210432)
		(end 160.20161 -194.191382)
		(width 0.14224)
		(layer "In15.Cu")
		(net "GMI_CPU0_G1_CPU1_G3_TX_DN<15>")
	)
	(segment
		(start 343.958672 -223.119442)
		(end 343.928192 -223.101662)
		(width 0.1143)
		(layer "In15.Cu")
		(net "GMI_CPU0_G1_CPU1_G3_TX_DN<15>")
	)
	(segment
		(start 126.627636 -223.747076)
		(end 126.666752 -223.769936)
		(width 0.1143)
		(layer "In15.Cu")
		(net "GMI_CPU0_G1_CPU1_G3_TX_DN<15>")
	)
	(segment
		(start 155.510484 -198.038212)
		(end 155.491434 -198.231252)
		(width 0.14224)
		(layer "In15.Cu")
		(net "GMI_CPU0_G1_CPU1_G3_TX_DN<15>")
	)
	(segment
		(start 344.868246 -229.58171)
		(end 344.831162 -229.560374)
		(width 0.1143)
		(layer "In15.Cu")
		(net "GMI_CPU0_G1_CPU1_G3_TX_DN<15>")
	)
	(segment
		(start 262.840216 -190.955168)
		(end 251.791724 -192.903094)
		(width 0.14224)
		(layer "In15.Cu")
		(net "GMI_CPU0_G1_CPU1_G3_TX_DN<15>")
	)
	(segment
		(start 148.74494 -202.834494)
		(end 148.74494 -202.83424)
		(width 0.14224)
		(layer "In15.Cu")
		(net "GMI_CPU0_G1_CPU1_G3_TX_DN<15>")
	)
	(segment
		(start 344.82913 -239.969548)
		(end 344.868246 -239.946688)
		(width 0.1143)
		(layer "In15.Cu")
		(net "GMI_CPU0_G1_CPU1_G3_TX_DN<15>")
	)
	(segment
		(start 343.11082 -221.143322)
		(end 343.0651 -221.097602)
		(width 0.1143)
		(layer "In15.Cu")
		(net "GMI_CPU0_G1_CPU1_G3_TX_DN<15>")
	)
	(segment
		(start 345.919044 -246.104156)
		(end 345.988894 -246.034306)
		(width 0.1143)
		(layer "In15.Cu")
		(net "GMI_CPU0_G1_CPU1_G3_TX_DN<15>")
	)
	(segment
		(start 344.365834 -225.512884)
		(end 344.358976 -225.50882)
		(width 0.1143)
		(layer "In15.Cu")
		(net "GMI_CPU0_G1_CPU1_G3_TX_DN<15>")
	)
	(segment
		(start 343.0651 -220.818964)
		(end 341.559896 -217.638122)
		(width 0.14224)
		(layer "In15.Cu")
		(net "GMI_CPU0_G1_CPU1_G3_TX_DN<15>")
	)
	(segment
		(start 126.666752 -229.559104)
		(end 126.627636 -229.581964)
		(width 0.1143)
		(layer "In15.Cu")
		(net "GMI_CPU0_G1_CPU1_G3_TX_DN<15>")
	)
	(segment
		(start 155.84043 -197.767702)
		(end 155.510484 -198.038212)
		(width 0.14224)
		(layer "In15.Cu")
		(net "GMI_CPU0_G1_CPU1_G3_TX_DN<15>")
	)
	(segment
		(start 126.597156 -243.169186)
		(end 126.627636 -243.186966)
		(width 0.1143)
		(layer "In15.Cu")
		(net "GMI_CPU0_G1_CPU1_G3_TX_DN<15>")
	)
	(segment
		(start 344.868246 -231.201722)
		(end 344.82913 -231.178862)
		(width 0.1143)
		(layer "In15.Cu")
		(net "GMI_CPU0_G1_CPU1_G3_TX_DN<15>")
	)
	(segment
		(start 126.627636 -244.161818)
		(end 126.597156 -244.179598)
		(width 0.1143)
		(layer "In15.Cu")
		(net "GMI_CPU0_G1_CPU1_G3_TX_DN<15>")
	)
	(segment
		(start 125.687582 -245.78183)
		(end 125.657102 -245.79961)
		(width 0.1143)
		(layer "In15.Cu")
		(net "GMI_CPU0_G1_CPU1_G3_TX_DN<15>")
	)
	(segment
		(start 344.868246 -227.961698)
		(end 344.82913 -227.938838)
		(width 0.1143)
		(layer "In15.Cu")
		(net "GMI_CPU0_G1_CPU1_G3_TX_DN<15>")
	)
	(segment
		(start 126.627636 -243.186966)
		(end 126.666752 -243.209826)
		(width 0.1143)
		(layer "In15.Cu")
		(net "GMI_CPU0_G1_CPU1_G3_TX_DN<15>")
	)
	(segment
		(start 344.82913 -228.629718)
		(end 344.868246 -228.606858)
		(width 0.1143)
		(layer "In15.Cu")
		(net "GMI_CPU0_G1_CPU1_G3_TX_DN<15>")
	)
	(segment
		(start 126.666752 -223.079056)
		(end 126.627636 -223.101916)
		(width 0.1143)
		(layer "In15.Cu")
		(net "GMI_CPU0_G1_CPU1_G3_TX_DN<15>")
	)
	(segment
		(start 126.627636 -239.946942)
		(end 126.666752 -239.969802)
		(width 0.1143)
		(layer "In15.Cu")
		(net "GMI_CPU0_G1_CPU1_G3_TX_DN<15>")
	)
	(segment
		(start 159.329374 -194.906646)
		(end 158.999428 -195.177156)
		(width 0.14224)
		(layer "In15.Cu")
		(net "GMI_CPU0_G1_CPU1_G3_TX_DN<15>")
	)
	(segment
		(start 344.393774 -225.52914)
		(end 344.366596 -225.513392)
		(width 0.1143)
		(layer "In15.Cu")
		(net "GMI_CPU0_G1_CPU1_G3_TX_DN<15>")
	)
	(segment
		(start 126.597156 -238.30915)
		(end 126.627636 -238.32693)
		(width 0.1143)
		(layer "In15.Cu")
		(net "GMI_CPU0_G1_CPU1_G3_TX_DN<15>")
	)
	(segment
		(start 126.666752 -226.31908)
		(end 126.627636 -226.34194)
		(width 0.1143)
		(layer "In15.Cu")
		(net "GMI_CPU0_G1_CPU1_G3_TX_DN<15>")
	)
	(segment
		(start 126.158752 -244.971316)
		(end 126.157736 -244.971824)
		(width 0.1143)
		(layer "In15.Cu")
		(net "GMI_CPU0_G1_CPU1_G3_TX_DN<15>")
	)
	(segment
		(start 158.457138 -195.62191)
		(end 158.127192 -195.89242)
		(width 0.14224)
		(layer "In15.Cu")
		(net "GMI_CPU0_G1_CPU1_G3_TX_DN<15>")
	)
	(segment
		(start 126.627636 -223.101916)
		(end 126.597156 -223.119696)
		(width 0.1143)
		(layer "In15.Cu")
		(net "GMI_CPU0_G1_CPU1_G3_TX_DN<15>")
	)
	(segment
		(start 344.400124 -225.53295)
		(end 344.398854 -225.532188)
		(width 0.1143)
		(layer "In15.Cu")
		(net "GMI_CPU0_G1_CPU1_G3_TX_DN<15>")
	)
	(segment
		(start 125.506988 -246.03456)
		(end 125.576838 -246.10441)
		(width 0.1143)
		(layer "In15.Cu")
		(net "GMI_CPU0_G1_CPU1_G3_TX_DN<15>")
	)
	(segment
		(start 156.905706 -197.071488)
		(end 156.712666 -197.052438)
		(width 0.14224)
		(layer "In15.Cu")
		(net "GMI_CPU0_G1_CPU1_G3_TX_DN<15>")
	)
	(segment
		(start 301.46498 -191.311022)
		(end 262.840216 -190.955168)
		(width 0.14224)
		(layer "In15.Cu")
		(net "GMI_CPU0_G1_CPU1_G3_TX_DN<15>")
	)
	(segment
		(start 126.156974 -244.972332)
		(end 126.155704 -244.973094)
		(width 0.1143)
		(layer "In15.Cu")
		(net "GMI_CPU0_G1_CPU1_G3_TX_DN<15>")
	)
	(segment
		(start 345.350592 -244.978682)
		(end 345.29903 -244.94871)
		(width 0.1143)
		(layer "In15.Cu")
		(net "GMI_CPU0_G1_CPU1_G3_TX_DN<15>")
	)
	(segment
		(start 231.94772 -200.883266)
		(end 209.706718 -191.670686)
		(width 0.14224)
		(layer "In15.Cu")
		(net "GMI_CPU0_G1_CPU1_G3_TX_DN<15>")
	)
	(segment
		(start 126.666752 -224.699068)
		(end 126.627636 -224.721928)
		(width 0.1143)
		(layer "In15.Cu")
		(net "GMI_CPU0_G1_CPU1_G3_TX_DN<15>")
	)
	(segment
		(start 160.20161 -194.191382)
		(end 159.871664 -194.461892)
		(width 0.14224)
		(layer "In15.Cu")
		(net "GMI_CPU0_G1_CPU1_G3_TX_DN<15>")
	)
	(segment
		(start 126.485396 -221.174564)
		(end 126.439422 -221.220538)
		(width 0.1143)
		(layer "In15.Cu")
		(net "GMI_CPU0_G1_CPU1_G3_TX_DN<15>")
	)
	(segment
		(start 148.745194 -202.83424)
		(end 148.74494 -202.834494)
		(width 0.14224)
		(layer "In15.Cu")
		(net "GMI_CPU0_G1_CPU1_G3_TX_DN<15>")
	)
	(segment
		(start 126.627636 -236.706918)
		(end 126.666752 -236.729778)
		(width 0.1143)
		(layer "In15.Cu")
		(net "GMI_CPU0_G1_CPU1_G3_TX_DN<15>")
	)
	(segment
		(start 345.839796 -245.799864)
		(end 345.808046 -245.781576)
		(width 0.1143)
		(layer "In15.Cu")
		(net "GMI_CPU0_G1_CPU1_G3_TX_DN<15>")
	)
	(segment
		(start 344.898726 -242.559332)
		(end 344.868246 -242.541552)
		(width 0.1143)
		(layer "In15.Cu")
		(net "GMI_CPU0_G1_CPU1_G3_TX_DN<15>")
	)
	(segment
		(start 345.621102 -246.104156)
		(end 345.919044 -246.104156)
		(width 0.1143)
		(layer "In15.Cu")
		(net "GMI_CPU0_G1_CPU1_G3_TX_DN<15>")
	)
	(segment
		(start 126.597156 -228.589332)
		(end 126.627636 -228.607112)
		(width 0.1143)
		(layer "In15.Cu")
		(net "GMI_CPU0_G1_CPU1_G3_TX_DN<15>")
	)
	(segment
		(start 344.398092 -225.53168)
		(end 344.397076 -225.531172)
		(width 0.1143)
		(layer "In15.Cu")
		(net "GMI_CPU0_G1_CPU1_G3_TX_DN<15>")
	)
	(segment
		(start 126.439422 -221.220538)
		(end 126.439422 -221.804484)
		(width 0.1143)
		(layer "In15.Cu")
		(net "GMI_CPU0_G1_CPU1_G3_TX_DN<15>")
	)
	(segment
		(start 161.266886 -193.495168)
		(end 161.073846 -193.476118)
		(width 0.14224)
		(layer "In15.Cu")
		(net "GMI_CPU0_G1_CPU1_G3_TX_DN<15>")
	)
	(segment
		(start 154.968194 -198.482966)
		(end 154.967686 -198.482966)
		(width 0.14224)
		(layer "In15.Cu")
		(net "GMI_CPU0_G1_CPU1_G3_TX_DN<15>")
	)
	(segment
		(start 343.928192 -223.101662)
		(end 343.889076 -223.078802)
		(width 0.1143)
		(layer "In15.Cu")
		(net "GMI_CPU0_G1_CPU1_G3_TX_DN<15>")
	)
	(segment
		(start 126.627636 -240.921794)
		(end 126.597156 -240.939574)
		(width 0.1143)
		(layer "In15.Cu")
		(net "GMI_CPU0_G1_CPU1_G3_TX_DN<15>")
	)
	(segment
		(start 126.666752 -237.65891)
		(end 126.627636 -237.68177)
		(width 0.1143)
		(layer "In15.Cu")
		(net "GMI_CPU0_G1_CPU1_G3_TX_DN<15>")
	)
	(segment
		(start 157.777942 -196.356224)
		(end 157.584902 -196.337174)
		(width 0.14224)
		(layer "In15.Cu")
		(net "GMI_CPU0_G1_CPU1_G3_TX_DN<15>")
	)
	(segment
		(start 126.627636 -229.581964)
		(end 126.595124 -229.60076)
		(width 0.1143)
		(layer "In15.Cu")
		(net "GMI_CPU0_G1_CPU1_G3_TX_DN<15>")
	)
	(segment
		(start 148.74494 -202.83424)
		(end 147.420584 -203.23556)
		(width 0.14224)
		(layer "In15.Cu")
		(net "GMI_CPU0_G1_CPU1_G3_TX_DN<15>")
	)
	(segment
		(start 158.650178 -195.64096)
		(end 158.457138 -195.62191)
		(width 0.14224)
		(layer "In15.Cu")
		(net "GMI_CPU0_G1_CPU1_G3_TX_DN<15>")
	)
	(segment
		(start 126.627636 -224.721928)
		(end 126.597156 -224.739708)
		(width 0.1143)
		(layer "In15.Cu")
		(net "GMI_CPU0_G1_CPU1_G3_TX_DN<15>")
	)
	(segment
		(start 162.981132 -191.402208)
		(end 162.490912 -191.804798)
		(width 0.14224)
		(layer "In15.Cu")
		(net "GMI_CPU0_G1_CPU1_G3_TX_DN<15>")
	)
	(segment
		(start 343.175844 -221.452694)
		(end 343.11082 -221.38767)
		(width 0.1143)
		(layer "In15.Cu")
		(net "GMI_CPU0_G1_CPU1_G3_TX_DN<15>")
	)
	(segment
		(start 126.627636 -237.68177)
		(end 126.597156 -237.69955)
		(width 0.1143)
		(layer "In15.Cu")
		(net "GMI_CPU0_G1_CPU1_G3_TX_DN<15>")
	)
	(segment
		(start 344.868246 -238.326676)
		(end 344.898726 -238.308896)
		(width 0.1143)
		(layer "In15.Cu")
		(net "GMI_CPU0_G1_CPU1_G3_TX_DN<15>")
	)
	(segment
		(start 126.627636 -234.441746)
		(end 126.597156 -234.459526)
		(width 0.1143)
		(layer "In15.Cu")
		(net "GMI_CPU0_G1_CPU1_G3_TX_DN<15>")
	)
	(segment
		(start 344.429842 -225.549968)
		(end 344.400124 -225.53295)
		(width 0.1143)
		(layer "In15.Cu")
		(net "GMI_CPU0_G1_CPU1_G3_TX_DN<15>")
	)
	(segment
		(start 343.421716 -222.270574)
		(end 343.4207 -222.270066)
		(width 0.1143)
		(layer "In15.Cu")
		(net "GMI_CPU0_G1_CPU1_G3_TX_DN<15>")
	)
	(segment
		(start 162.490912 -191.804798)
		(end 162.003232 -192.714118)
		(width 0.14224)
		(layer "In15.Cu")
		(net "GMI_CPU0_G1_CPU1_G3_TX_DN<15>")
	)
	(segment
		(start 126.627636 -236.061758)
		(end 126.597156 -236.079538)
		(width 0.1143)
		(layer "In15.Cu")
		(net "GMI_CPU0_G1_CPU1_G3_TX_DN<15>")
	)
	(segment
		(start 344.898726 -244.179344)
		(end 344.868246 -244.161564)
		(width 0.1143)
		(layer "In15.Cu")
		(net "GMI_CPU0_G1_CPU1_G3_TX_DN<15>")
	)
	(segment
		(start 127.32512 -219.712286)
		(end 126.485396 -221.12605)
		(width 0.14224)
		(layer "In15.Cu")
		(net "GMI_CPU0_G1_CPU1_G3_TX_DN<15>")
	)
	(segment
		(start 344.898726 -239.319308)
		(end 344.868246 -239.301528)
		(width 0.1143)
		(layer "In15.Cu")
		(net "GMI_CPU0_G1_CPU1_G3_TX_DN<15>")
	)
	(segment
		(start 126.597156 -223.729296)
		(end 126.627636 -223.747076)
		(width 0.1143)
		(layer "In15.Cu")
		(net "GMI_CPU0_G1_CPU1_G3_TX_DN<15>")
	)
	(segment
		(start 344.900758 -229.600506)
		(end 344.868246 -229.58171)
		(width 0.1143)
		(layer "In15.Cu")
		(net "GMI_CPU0_G1_CPU1_G3_TX_DN<15>")
	)
	(segment
		(start 343.0651 -221.097602)
		(end 343.0651 -221.083124)
		(width 0.1143)
		(layer "In15.Cu")
		(net "GMI_CPU0_G1_CPU1_G3_TX_DN<15>")
	)
	(segment
		(start 156.712666 -197.052438)
		(end 156.38272 -197.322948)
		(width 0.14224)
		(layer "In15.Cu")
		(net "GMI_CPU0_G1_CPU1_G3_TX_DN<15>")
	)
	(segment
		(start 126.597156 -235.069126)
		(end 126.627636 -235.086906)
		(width 0.1143)
		(layer "In15.Cu")
		(net "GMI_CPU0_G1_CPU1_G3_TX_DN<15>")
	)
	(segment
		(start 344.831162 -229.560374)
		(end 344.82913 -229.55885)
		(width 0.1143)
		(layer "In15.Cu")
		(net "GMI_CPU0_G1_CPU1_G3_TX_DN<15>")
	)
	(segment
		(start 126.597156 -239.929162)
		(end 126.627636 -239.946942)
		(width 0.1143)
		(layer "In15.Cu")
		(net "GMI_CPU0_G1_CPU1_G3_TX_DN<15>")
	)
	(segment
		(start 126.627636 -239.301782)
		(end 126.597156 -239.319562)
		(width 0.1143)
		(layer "In15.Cu")
		(net "GMI_CPU0_G1_CPU1_G3_TX_DN<15>")
	)
	(segment
		(start 343.11082 -221.38767)
		(end 343.11082 -221.143322)
		(width 0.1143)
		(layer "In15.Cu")
		(net "GMI_CPU0_G1_CPU1_G3_TX_DN<15>")
	)
	(segment
		(start 126.666752 -244.138958)
		(end 126.627636 -244.161818)
		(width 0.1143)
		(layer "In15.Cu")
		(net "GMI_CPU0_G1_CPU1_G3_TX_DN<15>")
	)
	(segment
		(start 344.868246 -234.441492)
		(end 344.82913 -234.418632)
		(width 0.1143)
		(layer "In15.Cu")
		(net "GMI_CPU0_G1_CPU1_G3_TX_DN<15>")
	)
	(segment
		(start 126.597156 -236.689138)
		(end 126.627636 -236.706918)
		(width 0.1143)
		(layer "In15.Cu")
		(net "GMI_CPU0_G1_CPU1_G3_TX_DN<15>")
	)
	(segment
		(start 344.82913 -235.109512)
		(end 344.868246 -235.086652)
		(width 0.1143)
		(layer "In15.Cu")
		(net "GMI_CPU0_G1_CPU1_G3_TX_DN<15>")
	)
	(segment
		(start 159.871664 -194.461892)
		(end 159.852614 -194.654932)
		(width 0.14224)
		(layer "In15.Cu")
		(net "GMI_CPU0_G1_CPU1_G3_TX_DN<15>")
	)
	(segment
		(start 126.666752 -236.038898)
		(end 126.627636 -236.061758)
		(width 0.1143)
		(layer "In15.Cu")
		(net "GMI_CPU0_G1_CPU1_G3_TX_DN<15>")
	)
	(segment
		(start 344.868246 -228.606858)
		(end 344.898726 -228.589078)
		(width 0.1143)
		(layer "In15.Cu")
		(net "GMI_CPU0_G1_CPU1_G3_TX_DN<15>")
	)
	(segment
		(start 343.0651 -221.083124)
		(end 343.0651 -220.818964)
		(width 0.14224)
		(layer "In15.Cu")
		(net "GMI_CPU0_G1_CPU1_G3_TX_DN<15>")
	)
	(segment
		(start 344.868246 -232.82148)
		(end 344.82913 -232.79862)
		(width 0.1143)
		(layer "In15.Cu")
		(net "GMI_CPU0_G1_CPU1_G3_TX_DN<15>")
	)
	(segment
		(start 157.235906 -196.800724)
		(end 156.905706 -197.071488)
		(width 0.14224)
		(layer "In15.Cu")
		(net "GMI_CPU0_G1_CPU1_G3_TX_DN<15>")
	)
	(segment
		(start 126.627636 -226.34194)
		(end 126.597156 -226.35972)
		(width 0.1143)
		(layer "In15.Cu")
		(net "GMI_CPU0_G1_CPU1_G3_TX_DN<15>")
	)
	(segment
		(start 344.868246 -239.946688)
		(end 344.898726 -239.928908)
		(width 0.1143)
		(layer "In15.Cu")
		(net "GMI_CPU0_G1_CPU1_G3_TX_DN<15>")
	)
	(segment
		(start 344.868246 -233.46664)
		(end 344.898726 -233.44886)
		(width 0.1143)
		(layer "In15.Cu")
		(net "GMI_CPU0_G1_CPU1_G3_TX_DN<15>")
	)
	(segment
		(start 344.898726 -234.459272)
		(end 344.868246 -234.441492)
		(width 0.1143)
		(layer "In15.Cu")
		(net "GMI_CPU0_G1_CPU1_G3_TX_DN<15>")
	)
	(segment
		(start 344.898726 -226.359466)
		(end 344.868246 -226.341686)
		(width 0.1143)
		(layer "In15.Cu")
		(net "GMI_CPU0_G1_CPU1_G3_TX_DN<15>")
	)
	(segment
		(start 344.82913 -241.58956)
		(end 344.868246 -241.5667)
		(width 0.1143)
		(layer "In15.Cu")
		(net "GMI_CPU0_G1_CPU1_G3_TX_DN<15>")
	)
	(segment
		(start 147.420584 -203.23556)
		(end 127.32512 -219.712286)
		(width 0.14224)
		(layer "In15.Cu")
		(net "GMI_CPU0_G1_CPU1_G3_TX_DN<15>")
	)
	(segment
		(start 344.82913 -233.4895)
		(end 344.868246 -233.46664)
		(width 0.1143)
		(layer "In15.Cu")
		(net "GMI_CPU0_G1_CPU1_G3_TX_DN<15>")
	)
	(segment
		(start 159.852614 -194.654932)
		(end 159.522414 -194.925696)
		(width 0.14224)
		(layer "In15.Cu")
		(net "GMI_CPU0_G1_CPU1_G3_TX_DN<15>")
	)
	(segment
		(start 236.351064 -201.65949)
		(end 231.94772 -200.883266)
		(width 0.14224)
		(layer "In15.Cu")
		(net "GMI_CPU0_G1_CPU1_G3_TX_DN<15>")
	)
	(segment
		(start 126.594616 -222.108014)
		(end 126.667768 -222.150686)
		(width 0.1143)
		(layer "In15.Cu")
		(net "GMI_CPU0_G1_CPU1_G3_TX_DN<15>")
	)
	(segment
		(start 344.366596 -225.513392)
		(end 344.365834 -225.512884)
		(width 0.1143)
		(layer "In15.Cu")
		(net "GMI_CPU0_G1_CPU1_G3_TX_DN<15>")
	)
	(segment
		(start 161.61639 -193.031364)
		(end 161.59734 -193.224404)
		(width 0.14224)
		(layer "In15.Cu")
		(net "GMI_CPU0_G1_CPU1_G3_TX_DN<15>")
	)
	(segment
		(start 158.658814 -195.633848)
		(end 158.650178 -195.64096)
		(width 0.14224)
		(layer "In15.Cu")
		(net "GMI_CPU0_G1_CPU1_G3_TX_DN<15>")
	)
	(segment
		(start 344.82913 -243.209572)
		(end 344.868246 -243.186712)
		(width 0.1143)
		(layer "In15.Cu")
		(net "GMI_CPU0_G1_CPU1_G3_TX_DN<15>")
	)
	(segment
		(start 251.791724 -192.903094)
		(end 240.275872 -200.96734)
		(width 0.14224)
		(layer "In15.Cu")
		(net "GMI_CPU0_G1_CPU1_G3_TX_DN<15>")
	)
	(segment
		(start 158.108142 -196.08546)
		(end 157.777942 -196.356224)
		(width 0.14224)
		(layer "In15.Cu")
		(net "GMI_CPU0_G1_CPU1_G3_TX_DN<15>")
	)
	(segment
		(start 344.868246 -235.086652)
		(end 344.898726 -235.068872)
		(width 0.1143)
		(layer "In15.Cu")
		(net "GMI_CPU0_G1_CPU1_G3_TX_DN<15>")
	)
	(segment
		(start 126.597156 -233.449114)
		(end 126.627636 -233.466894)
		(width 0.1143)
		(layer "In15.Cu")
		(net "GMI_CPU0_G1_CPU1_G3_TX_DN<15>")
	)
	(segment
		(start 344.868246 -236.061504)
		(end 344.82913 -236.038644)
		(width 0.1143)
		(layer "In15.Cu")
		(net "GMI_CPU0_G1_CPU1_G3_TX_DN<15>")
	)
	(segment
		(start 344.868246 -241.5667)
		(end 344.898726 -241.54892)
		(width 0.1143)
		(layer "In15.Cu")
		(net "GMI_CPU0_G1_CPU1_G3_TX_DN<15>")
	)
	(segment
		(start 344.868246 -239.301528)
		(end 344.82913 -239.278668)
		(width 0.1143)
		(layer "In15.Cu")
		(net "GMI_CPU0_G1_CPU1_G3_TX_DN<15>")
	)
	(segment
		(start 345.538298 -245.3132)
		(end 345.538298 -245.303548)
		(width 0.1143)
		(layer "In15.Cu")
		(net "GMI_CPU0_G1_CPU1_G3_TX_DN<15>")
	)
	(segment
		(start 344.394536 -225.529648)
		(end 344.393774 -225.52914)
		(width 0.1143)
		(layer "In15.Cu")
		(net "GMI_CPU0_G1_CPU1_G3_TX_DN<15>")
	)
	(segment
		(start 126.627636 -225.367088)
		(end 126.666752 -225.389948)
		(width 0.1143)
		(layer "In15.Cu")
		(net "GMI_CPU0_G1_CPU1_G3_TX_DN<15>")
	)
	(segment
		(start 150.197312 -202.394312)
		(end 148.745956 -202.833986)
		(width 0.14224)
		(layer "In15.Cu")
		(net "GMI_CPU0_G1_CPU1_G3_TX_DN<15>")
	)
	(segment
		(start 161.59734 -193.224404)
		(end 161.266886 -193.495168)
		(width 0.14224)
		(layer "In15.Cu")
		(net "GMI_CPU0_G1_CPU1_G3_TX_DN<15>")
	)
	(segment
		(start 209.706718 -191.670686)
		(end 207.126586 -191.215518)
		(width 0.14224)
		(layer "In15.Cu")
		(net "GMI_CPU0_G1_CPU1_G3_TX_DN<15>")
	)
	(segment
		(start 301.486062 -191.332104)
		(end 301.46498 -191.311022)
		(width 0.14224)
		(layer "In15.Cu")
		(net "GMI_CPU0_G1_CPU1_G3_TX_DN<15>")
	)
	(segment
		(start 344.898726 -236.079284)
		(end 344.868246 -236.061504)
		(width 0.1143)
		(layer "In15.Cu")
		(net "GMI_CPU0_G1_CPU1_G3_TX_DN<15>")
	)
	(segment
		(start 126.666752 -240.898934)
		(end 126.627636 -240.921794)
		(width 0.1143)
		(layer "In15.Cu")
		(net "GMI_CPU0_G1_CPU1_G3_TX_DN<15>")
	)
	(segment
		(start 344.868246 -242.541552)
		(end 344.82913 -242.518692)
		(width 0.1143)
		(layer "In15.Cu")
		(net "GMI_CPU0_G1_CPU1_G3_TX_DN<15>")
	)
	(segment
		(start 126.597156 -226.96932)
		(end 126.627636 -226.9871)
		(width 0.1143)
		(layer "In15.Cu")
		(net "GMI_CPU0_G1_CPU1_G3_TX_DN<15>")
	)
	(segment
		(start 126.597156 -231.829102)
		(end 126.627636 -231.846882)
		(width 0.1143)
		(layer "In15.Cu")
		(net "GMI_CPU0_G1_CPU1_G3_TX_DN<15>")
	)
	(segment
		(start 126.627636 -226.9871)
		(end 126.666752 -227.00996)
		(width 0.1143)
		(layer "In15.Cu")
		(net "GMI_CPU0_G1_CPU1_G3_TX_DN<15>")
	)
	(segment
		(start 344.868246 -226.341686)
		(end 344.82913 -226.318826)
		(width 0.1143)
		(layer "In15.Cu")
		(net "GMI_CPU0_G1_CPU1_G3_TX_DN<15>")
	)
	(segment
		(start 126.627636 -238.32693)
		(end 126.666752 -238.34979)
		(width 0.1143)
		(layer "In15.Cu")
		(net "GMI_CPU0_G1_CPU1_G3_TX_DN<15>")
	)
	(segment
		(start 344.868246 -236.706664)
		(end 344.898726 -236.688884)
		(width 0.1143)
		(layer "In15.Cu")
		(net "GMI_CPU0_G1_CPU1_G3_TX_DN<15>")
	)
	(segment
		(start 125.726698 -245.75897)
		(end 125.687582 -245.78183)
		(width 0.1143)
		(layer "In15.Cu")
		(net "GMI_CPU0_G1_CPU1_G3_TX_DN<15>")
	)
	(segment
		(start 344.397076 -225.531172)
		(end 344.394536 -225.529648)
		(width 0.1143)
		(layer "In15.Cu")
		(net "GMI_CPU0_G1_CPU1_G3_TX_DN<15>")
	)
	(segment
		(start 240.275872 -200.96734)
		(end 236.351064 -201.65949)
		(width 0.14224)
		(layer "In15.Cu")
		(net "GMI_CPU0_G1_CPU1_G3_TX_DN<15>")
	)
	(segment
		(start 344.868246 -243.186712)
		(end 344.898726 -243.168932)
		(width 0.1143)
		(layer "In15.Cu")
		(net "GMI_CPU0_G1_CPU1_G3_TX_DN<15>")
	)
	(segment
		(start 126.666752 -239.278922)
		(end 126.627636 -239.301782)
		(width 0.1143)
		(layer "In15.Cu")
		(net "GMI_CPU0_G1_CPU1_G3_TX_DN<15>")
	)
	(segment
		(start 154.967686 -198.482966)
		(end 150.197312 -202.394312)
		(width 0.14224)
		(layer "In15.Cu")
		(net "GMI_CPU0_G1_CPU1_G3_TX_DN<15>")
	)
	(segment
		(start 344.898726 -240.93932)
		(end 344.868246 -240.92154)
		(width 0.1143)
		(layer "In15.Cu")
		(net "GMI_CPU0_G1_CPU1_G3_TX_DN<15>")
	)
	(segment
		(start 344.82913 -238.349536)
		(end 344.868246 -238.326676)
		(width 0.1143)
		(layer "In15.Cu")
		(net "GMI_CPU0_G1_CPU1_G3_TX_DN<15>")
	)
	(segment
		(start 126.627636 -228.607112)
		(end 126.666752 -228.629972)
		(width 0.1143)
		(layer "In15.Cu")
		(net "GMI_CPU0_G1_CPU1_G3_TX_DN<15>")
	)
	(segment
		(start 126.627636 -231.846882)
		(end 126.666752 -231.869742)
		(width 0.1143)
		(layer "In15.Cu")
		(net "GMI_CPU0_G1_CPU1_G3_TX_DN<15>")
	)
	(segment
		(start 344.900758 -231.220518)
		(end 344.868246 -231.201722)
		(width 0.1143)
		(layer "In15.Cu")
		(net "GMI_CPU0_G1_CPU1_G3_TX_DN<15>")
	)
	(segment
		(start 344.82913 -227.009706)
		(end 344.868246 -226.986846)
		(width 0.1143)
		(layer "In15.Cu")
		(net "GMI_CPU0_G1_CPU1_G3_TX_DN<15>")
	)
	(segment
		(start 344.868246 -244.161564)
		(end 344.82913 -244.138704)
		(width 0.1143)
		(layer "In15.Cu")
		(net "GMI_CPU0_G1_CPU1_G3_TX_DN<15>")
	)
	(segment
		(start 159.522414 -194.925696)
		(end 159.329374 -194.906646)
		(width 0.14224)
		(layer "In15.Cu")
		(net "GMI_CPU0_G1_CPU1_G3_TX_DN<15>")
	)
	(segment
		(start 344.868246 -231.846628)
		(end 344.898726 -231.828848)
		(width 0.1143)
		(layer "In15.Cu")
		(net "GMI_CPU0_G1_CPU1_G3_TX_DN<15>")
	)
	(segment
		(start 344.868246 -237.681516)
		(end 344.82913 -237.658656)
		(width 0.1143)
		(layer "In15.Cu")
		(net "GMI_CPU0_G1_CPU1_G3_TX_DN<15>")
	)
	(segment
		(start 316.413896 -197.02018)
		(end 308.268116 -191.332104)
		(width 0.14224)
		(layer "In15.Cu")
		(net "GMI_CPU0_G1_CPU1_G3_TX_DN<15>")
	)
	(segment
		(start 207.126586 -191.215518)
		(end 162.981132 -191.402208)
		(width 0.14224)
		(layer "In15.Cu")
		(net "GMI_CPU0_G1_CPU1_G3_TX_DN<15>")
	)
	(segment
		(start 126.666752 -234.418886)
		(end 126.627636 -234.441746)
		(width 0.1143)
		(layer "In15.Cu")
		(net "GMI_CPU0_G1_CPU1_G3_TX_DN<15>")
	)
	(segment
		(start 343.928192 -224.721674)
		(end 343.889076 -224.698814)
		(width 0.1143)
		(layer "In15.Cu")
		(net "GMI_CPU0_G1_CPU1_G3_TX_DN<15>")
	)
	(segment
		(start 126.157736 -244.971824)
		(end 126.156974 -244.972332)
		(width 0.1143)
		(layer "In15.Cu")
		(net "GMI_CPU0_G1_CPU1_G3_TX_DN<15>")
	)
	(segment
		(start 344.898726 -237.699296)
		(end 344.868246 -237.681516)
		(width 0.1143)
		(layer "In15.Cu")
		(net "GMI_CPU0_G1_CPU1_G3_TX_DN<15>")
	)
	(segment
		(start 343.4207 -222.270066)
		(end 343.419684 -222.269304)
		(width 0.1143)
		(layer "In15.Cu")
		(net "GMI_CPU0_G1_CPU1_G3_TX_DN<15>")
	)
	(segment
		(start 155.161234 -198.502016)
		(end 154.968194 -198.482966)
		(width 0.14224)
		(layer "In15.Cu")
		(net "GMI_CPU0_G1_CPU1_G3_TX_DN<15>")
	)
	(segment
		(start 126.155704 -244.973094)
		(end 126.125986 -244.990112)
		(width 0.1143)
		(layer "In15.Cu")
		(net "GMI_CPU0_G1_CPU1_G3_TX_DN<15>")
	)
	(segment
		(start 162.003232 -192.714118)
		(end 161.61639 -193.031364)
		(width 0.14224)
		(layer "In15.Cu")
		(net "GMI_CPU0_G1_CPU1_G3_TX_DN<15>")
	)
	(segment
		(start 344.398854 -225.532188)
		(end 344.398092 -225.53168)
		(width 0.1143)
		(layer "In15.Cu")
		(net "GMI_CPU0_G1_CPU1_G3_TX_DN<15>")
	)
	(segment
		(start 126.666752 -231.179116)
		(end 126.627636 -231.201976)
		(width 0.1143)
		(layer "In15.Cu")
		(net "GMI_CPU0_G1_CPU1_G3_TX_DN<15>")
	)
	(segment
		(start 158.980378 -195.370196)
		(end 158.658814 -195.633848)
		(width 0.14224)
		(layer "In15.Cu")
		(net "GMI_CPU0_G1_CPU1_G3_TX_DN<15>")
	)
	(segment
		(start 126.627636 -235.086906)
		(end 126.666752 -235.109766)
		(width 0.1143)
		(layer "In15.Cu")
		(net "GMI_CPU0_G1_CPU1_G3_TX_DN<15>")
	)
	(segment
		(start 125.576838 -246.10441)
		(end 125.87478 -246.10441)
		(width 0.1143)
		(layer "In15.Cu")
		(net "GMI_CPU0_G1_CPU1_G3_TX_DN<15>")
	)
	(segment
		(start 126.196852 -244.948964)
		(end 126.160276 -244.9703)
		(width 0.1143)
		(layer "In15.Cu")
		(net "GMI_CPU0_G1_CPU1_G3_TX_DN<15>")
	)
	(segment
		(start 344.82913 -236.729524)
		(end 344.868246 -236.706664)
		(width 0.1143)
		(layer "In15.Cu")
		(net "GMI_CPU0_G1_CPU1_G3_TX_DN<15>")
	)
	(segment
		(start 156.38272 -197.322948)
		(end 156.36367 -197.515988)
		(width 0.14224)
		(layer "In15.Cu")
		(net "GMI_CPU0_G1_CPU1_G3_TX_DN<15>")
	)
	(segment
		(start 344.898726 -227.979478)
		(end 344.868246 -227.961698)
		(width 0.1143)
		(layer "In15.Cu")
		(net "GMI_CPU0_G1_CPU1_G3_TX_DN<15>")
	)
	(segment
		(start 126.627636 -242.541806)
		(end 126.597156 -242.559586)
		(width 0.1143)
		(layer "In15.Cu")
		(net "GMI_CPU0_G1_CPU1_G3_TX_DN<15>")
	)
	(segment
		(start 126.627636 -232.821734)
		(end 126.597156 -232.839514)
		(width 0.1143)
		(layer "In15.Cu")
		(net "GMI_CPU0_G1_CPU1_G3_TX_DN<15>")
	)
	(segment
		(start 126.666752 -242.518946)
		(end 126.627636 -242.541806)
		(width 0.1143)
		(layer "In15.Cu")
		(net "GMI_CPU0_G1_CPU1_G3_TX_DN<15>")
	)
	(segment
		(start 343.175844 -221.80423)
		(end 343.175844 -221.452694)
		(width 0.1143)
		(layer "In15.Cu")
		(net "GMI_CPU0_G1_CPU1_G3_TX_DN<15>")
	)
	(segment
		(start 343.489788 -222.309944)
		(end 343.421716 -222.270574)
		(width 0.1143)
		(layer "In15.Cu")
		(net "GMI_CPU0_G1_CPU1_G3_TX_DN<15>")
	)
	(segment
		(start 161.073846 -193.476118)
		(end 160.7439 -193.746628)
		(width 0.14224)
		(layer "In15.Cu")
		(net "GMI_CPU0_G1_CPU1_G3_TX_DN<15>")
	)
	(segment
		(start 158.999428 -195.177156)
		(end 158.980378 -195.370196)
		(width 0.14224)
		(layer "In15.Cu")
		(net "GMI_CPU0_G1_CPU1_G3_TX_DN<15>")
	)
	(segment
		(start 148.745956 -202.833986)
		(end 148.745194 -202.83424)
		(width 0.14224)
		(layer "In15.Cu")
		(net "GMI_CPU0_G1_CPU1_G3_TX_DN<15>")
	)
	(segment
		(start 160.72485 -193.939668)
		(end 160.39465 -194.210432)
		(width 0.14224)
		(layer "In15.Cu")
		(net "GMI_CPU0_G1_CPU1_G3_TX_DN<15>")
	)
	(segment
		(start 344.82913 -231.869488)
		(end 344.868246 -231.846628)
		(width 0.1143)
		(layer "In15.Cu")
		(net "GMI_CPU0_G1_CPU1_G3_TX_DN<15>")
	)
	(segment
		(start 157.584902 -196.337174)
		(end 157.254956 -196.607684)
		(width 0.14224)
		(layer "In15.Cu")
		(net "GMI_CPU0_G1_CPU1_G3_TX_DN<15>")
	)
	(segment
		(start 126.627636 -233.466894)
		(end 126.666752 -233.489754)
		(width 0.1143)
		(layer "In15.Cu")
		(net "GMI_CPU0_G1_CPU1_G3_TX_DN<15>")
	)
	(segment
		(start 126.627636 -227.961952)
		(end 126.597156 -227.979732)
		(width 0.1143)
		(layer "In15.Cu")
		(net "GMI_CPU0_G1_CPU1_G3_TX_DN<15>")
	)
	(segment
		(start 344.83167 -230.247952)
		(end 344.898726 -230.208836)
		(width 0.1143)
		(layer "In15.Cu")
		(net "GMI_CPU0_G1_CPU1_G3_TX_DN<15>")
	)
	(segment
		(start 344.868246 -240.92154)
		(end 344.82913 -240.89868)
		(width 0.1143)
		(layer "In15.Cu")
		(net "GMI_CPU0_G1_CPU1_G3_TX_DN<15>")
	)
	(segment
		(start 126.597156 -225.349308)
		(end 126.627636 -225.367088)
		(width 0.1143)
		(layer "In15.Cu")
		(net "GMI_CPU0_G1_CPU1_G3_TX_DN<15>")
	)
	(segment
		(start 126.666752 -232.798874)
		(end 126.627636 -232.821734)
		(width 0.1143)
		(layer "In15.Cu")
		(net "GMI_CPU0_G1_CPU1_G3_TX_DN<15>")
	)
	(segment
		(start 126.627636 -231.201976)
		(end 126.595124 -231.220772)
		(width 0.1143)
		(layer "In15.Cu")
		(net "GMI_CPU0_G1_CPU1_G3_TX_DN<15>")
	)
	(segment
		(start 126.627636 -241.566954)
		(end 126.666752 -241.589814)
		(width 0.1143)
		(layer "In15.Cu")
		(net "GMI_CPU0_G1_CPU1_G3_TX_DN<15>")
	)
	(segment
		(start 156.36367 -197.515988)
		(end 156.03347 -197.786752)
		(width 0.14224)
		(layer "In15.Cu")
		(net "GMI_CPU0_G1_CPU1_G3_TX_DN<15>")
	)
	(segment
		(start 126.597156 -230.20909)
		(end 126.664212 -230.248206)
		(width 0.1143)
		(layer "In15.Cu")
		(net "GMI_CPU0_G1_CPU1_G3_TX_DN<15>")
	)
	(segment
		(start 155.491434 -198.231252)
		(end 155.161234 -198.502016)
		(width 0.14224)
		(layer "In15.Cu")
		(net "GMI_CPU0_G1_CPU1_G3_TX_DN<15>")
	)
	(segment
		(start 126.666752 -227.939092)
		(end 126.627636 -227.961952)
		(width 0.1143)
		(layer "In15.Cu")
		(net "GMI_CPU0_G1_CPU1_G3_TX_DN<15>")
	)
	(segment
		(start 308.268116 -191.332104)
		(end 301.486062 -191.332104)
		(width 0.14224)
		(layer "In15.Cu")
		(net "GMI_CPU0_G1_CPU1_G3_TX_DN<15>")
	)
	(segment
		(start 126.597156 -241.549174)
		(end 126.627636 -241.566954)
		(width 0.1143)
		(layer "In15.Cu")
		(net "GMI_CPU0_G1_CPU1_G3_TX_DN<15>")
	)
	(segment
		(start 157.254956 -196.607684)
		(end 157.235906 -196.800724)
		(width 0.14224)
		(layer "In15.Cu")
		(net "GMI_CPU0_G1_CPU1_G3_TX_DN<15>")
	)
	(arc
		(start 126.664212 -230.248206)
		(mid 126.844864 -230.450951)
		(end 126.910084 -230.71455)
		(width 0.1143)
		(layer "In15.Cu")
		(net "GMI_CPU0_G1_CPU1_G3_TX_DN<15>")
	)
	(arc
		(start 344.898726 -230.208836)
		(mid 345.014153 -230.07546)
		(end 345.055698 -229.904036)
		(width 0.1143)
		(layer "In15.Cu")
		(net "GMI_CPU0_G1_CPU1_G3_TX_DN<15>")
	)
	(arc
		(start 344.82913 -236.038644)
		(mid 344.585803 -235.574078)
		(end 344.82913 -235.109512)
		(width 0.1143)
		(layer "In15.Cu")
		(net "GMI_CPU0_G1_CPU1_G3_TX_DN<15>")
	)
	(arc
		(start 126.666752 -235.109766)
		(mid 126.910079 -235.574332)
		(end 126.666752 -236.038898)
		(width 0.1143)
		(layer "In15.Cu")
		(net "GMI_CPU0_G1_CPU1_G3_TX_DN<15>")
	)
	(arc
		(start 343.889076 -223.078802)
		(mid 343.710263 -222.876452)
		(end 343.645744 -222.614236)
		(width 0.1143)
		(layer "In15.Cu")
		(net "GMI_CPU0_G1_CPU1_G3_TX_DN<15>")
	)
	(arc
		(start 126.666752 -231.869742)
		(mid 126.910079 -232.334308)
		(end 126.666752 -232.798874)
		(width 0.1143)
		(layer "In15.Cu")
		(net "GMI_CPU0_G1_CPU1_G3_TX_DN<15>")
	)
	(arc
		(start 345.988894 -246.034306)
		(mid 345.936845 -245.902787)
		(end 345.839796 -245.799864)
		(width 0.1143)
		(layer "In15.Cu")
		(net "GMI_CPU0_G1_CPU1_G3_TX_DN<15>")
	)
	(arc
		(start 126.440184 -231.524302)
		(mid 126.481733 -231.695724)
		(end 126.597156 -231.829102)
		(width 0.1143)
		(layer "In15.Cu")
		(net "GMI_CPU0_G1_CPU1_G3_TX_DN<15>")
	)
	(arc
		(start 126.666752 -228.629972)
		(mid 126.910079 -229.094538)
		(end 126.666752 -229.559104)
		(width 0.1143)
		(layer "In15.Cu")
		(net "GMI_CPU0_G1_CPU1_G3_TX_DN<15>")
	)
	(arc
		(start 126.910084 -222.61449)
		(mid 126.845569 -222.876709)
		(end 126.666752 -223.079056)
		(width 0.1143)
		(layer "In15.Cu")
		(net "GMI_CPU0_G1_CPU1_G3_TX_DN<15>")
	)
	(arc
		(start 126.597156 -224.739708)
		(mid 126.440179 -225.044508)
		(end 126.597156 -225.349308)
		(width 0.1143)
		(layer "In15.Cu")
		(net "GMI_CPU0_G1_CPU1_G3_TX_DN<15>")
	)
	(arc
		(start 126.597156 -239.319562)
		(mid 126.440179 -239.624362)
		(end 126.597156 -239.929162)
		(width 0.1143)
		(layer "In15.Cu")
		(net "GMI_CPU0_G1_CPU1_G3_TX_DN<15>")
	)
	(arc
		(start 343.958672 -223.729042)
		(mid 344.115649 -223.424242)
		(end 343.958672 -223.119442)
		(width 0.1143)
		(layer "In15.Cu")
		(net "GMI_CPU0_G1_CPU1_G3_TX_DN<15>")
	)
	(arc
		(start 126.666752 -227.00996)
		(mid 126.910079 -227.474526)
		(end 126.666752 -227.939092)
		(width 0.1143)
		(layer "In15.Cu")
		(net "GMI_CPU0_G1_CPU1_G3_TX_DN<15>")
	)
	(arc
		(start 345.055698 -231.524048)
		(mid 345.014732 -231.353642)
		(end 344.900758 -231.220518)
		(width 0.1143)
		(layer "In15.Cu")
		(net "GMI_CPU0_G1_CPU1_G3_TX_DN<15>")
	)
	(arc
		(start 126.597156 -226.35972)
		(mid 126.440179 -226.66452)
		(end 126.597156 -226.96932)
		(width 0.1143)
		(layer "In15.Cu")
		(net "GMI_CPU0_G1_CPU1_G3_TX_DN<15>")
	)
	(arc
		(start 344.898726 -233.44886)
		(mid 345.055703 -233.14406)
		(end 344.898726 -232.83926)
		(width 0.1143)
		(layer "In15.Cu")
		(net "GMI_CPU0_G1_CPU1_G3_TX_DN<15>")
	)
	(arc
		(start 126.666752 -238.34979)
		(mid 126.910079 -238.814356)
		(end 126.666752 -239.278922)
		(width 0.1143)
		(layer "In15.Cu")
		(net "GMI_CPU0_G1_CPU1_G3_TX_DN<15>")
	)
	(arc
		(start 344.898726 -226.969066)
		(mid 345.055703 -226.664266)
		(end 344.898726 -226.359466)
		(width 0.1143)
		(layer "In15.Cu")
		(net "GMI_CPU0_G1_CPU1_G3_TX_DN<15>")
	)
	(arc
		(start 345.538298 -245.303548)
		(mid 345.487992 -245.11596)
		(end 345.350592 -244.978682)
		(width 0.1143)
		(layer "In15.Cu")
		(net "GMI_CPU0_G1_CPU1_G3_TX_DN<15>")
	)
	(arc
		(start 344.898726 -235.068872)
		(mid 345.055703 -234.764072)
		(end 344.898726 -234.459272)
		(width 0.1143)
		(layer "In15.Cu")
		(net "GMI_CPU0_G1_CPU1_G3_TX_DN<15>")
	)
	(arc
		(start 126.666752 -241.589814)
		(mid 126.910079 -242.05438)
		(end 126.666752 -242.518946)
		(width 0.1143)
		(layer "In15.Cu")
		(net "GMI_CPU0_G1_CPU1_G3_TX_DN<15>")
	)
	(arc
		(start 344.82913 -239.278668)
		(mid 344.585803 -238.814102)
		(end 344.82913 -238.349536)
		(width 0.1143)
		(layer "In15.Cu")
		(net "GMI_CPU0_G1_CPU1_G3_TX_DN<15>")
	)
	(arc
		(start 126.597156 -242.559586)
		(mid 126.440179 -242.864386)
		(end 126.597156 -243.169186)
		(width 0.1143)
		(layer "In15.Cu")
		(net "GMI_CPU0_G1_CPU1_G3_TX_DN<15>")
	)
	(arc
		(start 345.055698 -244.484144)
		(mid 345.014149 -244.312722)
		(end 344.898726 -244.179344)
		(width 0.1143)
		(layer "In15.Cu")
		(net "GMI_CPU0_G1_CPU1_G3_TX_DN<15>")
	)
	(arc
		(start 344.898726 -241.54892)
		(mid 345.055703 -241.24412)
		(end 344.898726 -240.93932)
		(width 0.1143)
		(layer "In15.Cu")
		(net "GMI_CPU0_G1_CPU1_G3_TX_DN<15>")
	)
	(arc
		(start 126.440184 -244.484398)
		(mid 126.375669 -244.746617)
		(end 126.196852 -244.948964)
		(width 0.1143)
		(layer "In15.Cu")
		(net "GMI_CPU0_G1_CPU1_G3_TX_DN<15>")
	)
	(arc
		(start 126.667768 -222.150686)
		(mid 126.845833 -222.352863)
		(end 126.910084 -222.61449)
		(width 0.1143)
		(layer "In15.Cu")
		(net "GMI_CPU0_G1_CPU1_G3_TX_DN<15>")
	)
	(arc
		(start 344.82913 -231.178862)
		(mid 344.650317 -230.976512)
		(end 344.585798 -230.714296)
		(width 0.1143)
		(layer "In15.Cu")
		(net "GMI_CPU0_G1_CPU1_G3_TX_DN<15>")
	)
	(arc
		(start 344.358976 -225.50882)
		(mid 344.180163 -225.30647)
		(end 344.115644 -225.044254)
		(width 0.1143)
		(layer "In15.Cu")
		(net "GMI_CPU0_G1_CPU1_G3_TX_DN<15>")
	)
	(arc
		(start 126.597156 -244.179598)
		(mid 126.481729 -244.312974)
		(end 126.440184 -244.484398)
		(width 0.1143)
		(layer "In15.Cu")
		(net "GMI_CPU0_G1_CPU1_G3_TX_DN<15>")
	)
	(arc
		(start 343.419684 -222.269304)
		(mid 343.240491 -222.066794)
		(end 343.175844 -221.80423)
		(width 0.1143)
		(layer "In15.Cu")
		(net "GMI_CPU0_G1_CPU1_G3_TX_DN<15>")
	)
	(arc
		(start 344.82913 -234.418632)
		(mid 344.585803 -233.954066)
		(end 344.82913 -233.4895)
		(width 0.1143)
		(layer "In15.Cu")
		(net "GMI_CPU0_G1_CPU1_G3_TX_DN<15>")
	)
	(arc
		(start 344.82913 -237.658656)
		(mid 344.585803 -237.19409)
		(end 344.82913 -236.729524)
		(width 0.1143)
		(layer "In15.Cu")
		(net "GMI_CPU0_G1_CPU1_G3_TX_DN<15>")
	)
	(arc
		(start 344.82913 -242.518692)
		(mid 344.585803 -242.054126)
		(end 344.82913 -241.58956)
		(width 0.1143)
		(layer "In15.Cu")
		(net "GMI_CPU0_G1_CPU1_G3_TX_DN<15>")
	)
	(arc
		(start 126.666752 -223.769936)
		(mid 126.910079 -224.234502)
		(end 126.666752 -224.699068)
		(width 0.1143)
		(layer "In15.Cu")
		(net "GMI_CPU0_G1_CPU1_G3_TX_DN<15>")
	)
	(arc
		(start 126.595124 -231.220772)
		(mid 126.481195 -231.353919)
		(end 126.440184 -231.524302)
		(width 0.1143)
		(layer "In15.Cu")
		(net "GMI_CPU0_G1_CPU1_G3_TX_DN<15>")
	)
	(arc
		(start 344.115644 -225.044254)
		(mid 344.074095 -224.872832)
		(end 343.958672 -224.739454)
		(width 0.1143)
		(layer "In15.Cu")
		(net "GMI_CPU0_G1_CPU1_G3_TX_DN<15>")
	)
	(arc
		(start 344.585798 -225.85426)
		(mid 344.544543 -225.683289)
		(end 344.429842 -225.549968)
		(width 0.1143)
		(layer "In15.Cu")
		(net "GMI_CPU0_G1_CPU1_G3_TX_DN<15>")
	)
	(arc
		(start 345.055698 -229.904036)
		(mid 345.014732 -229.73363)
		(end 344.900758 -229.600506)
		(width 0.1143)
		(layer "In15.Cu")
		(net "GMI_CPU0_G1_CPU1_G3_TX_DN<15>")
	)
	(arc
		(start 344.898726 -238.308896)
		(mid 345.055703 -238.004096)
		(end 344.898726 -237.699296)
		(width 0.1143)
		(layer "In15.Cu")
		(net "GMI_CPU0_G1_CPU1_G3_TX_DN<15>")
	)
	(arc
		(start 126.910084 -230.71455)
		(mid 126.845569 -230.976769)
		(end 126.666752 -231.179116)
		(width 0.1143)
		(layer "In15.Cu")
		(net "GMI_CPU0_G1_CPU1_G3_TX_DN<15>")
	)
	(arc
		(start 126.597156 -234.459526)
		(mid 126.440179 -234.764326)
		(end 126.597156 -235.069126)
		(width 0.1143)
		(layer "In15.Cu")
		(net "GMI_CPU0_G1_CPU1_G3_TX_DN<15>")
	)
	(arc
		(start 344.898726 -236.688884)
		(mid 345.055703 -236.384084)
		(end 344.898726 -236.079284)
		(width 0.1143)
		(layer "In15.Cu")
		(net "GMI_CPU0_G1_CPU1_G3_TX_DN<15>")
	)
	(arc
		(start 126.595124 -229.60076)
		(mid 126.481195 -229.733907)
		(end 126.440184 -229.90429)
		(width 0.1143)
		(layer "In15.Cu")
		(net "GMI_CPU0_G1_CPU1_G3_TX_DN<15>")
	)
	(arc
		(start 126.125986 -244.990112)
		(mid 126.01131 -245.123446)
		(end 125.97003 -245.294404)
		(width 0.1143)
		(layer "In15.Cu")
		(net "GMI_CPU0_G1_CPU1_G3_TX_DN<15>")
	)
	(arc
		(start 126.666752 -233.489754)
		(mid 126.910079 -233.95432)
		(end 126.666752 -234.418886)
		(width 0.1143)
		(layer "In15.Cu")
		(net "GMI_CPU0_G1_CPU1_G3_TX_DN<15>")
	)
	(arc
		(start 126.597156 -240.939574)
		(mid 126.440179 -241.244374)
		(end 126.597156 -241.549174)
		(width 0.1143)
		(layer "In15.Cu")
		(net "GMI_CPU0_G1_CPU1_G3_TX_DN<15>")
	)
	(arc
		(start 344.82913 -232.79862)
		(mid 344.585803 -232.334054)
		(end 344.82913 -231.869488)
		(width 0.1143)
		(layer "In15.Cu")
		(net "GMI_CPU0_G1_CPU1_G3_TX_DN<15>")
	)
	(arc
		(start 126.666752 -225.389948)
		(mid 126.910079 -225.854514)
		(end 126.666752 -226.31908)
		(width 0.1143)
		(layer "In15.Cu")
		(net "GMI_CPU0_G1_CPU1_G3_TX_DN<15>")
	)
	(arc
		(start 345.808046 -245.781576)
		(mid 345.610564 -245.583447)
		(end 345.538298 -245.3132)
		(width 0.1143)
		(layer "In15.Cu")
		(net "GMI_CPU0_G1_CPU1_G3_TX_DN<15>")
	)
	(arc
		(start 343.889076 -224.698814)
		(mid 343.645749 -224.234248)
		(end 343.889076 -223.769682)
		(width 0.1143)
		(layer "In15.Cu")
		(net "GMI_CPU0_G1_CPU1_G3_TX_DN<15>")
	)
	(arc
		(start 126.597156 -237.69955)
		(mid 126.440179 -238.00435)
		(end 126.597156 -238.30915)
		(width 0.1143)
		(layer "In15.Cu")
		(net "GMI_CPU0_G1_CPU1_G3_TX_DN<15>")
	)
	(arc
		(start 344.898726 -239.928908)
		(mid 345.055703 -239.624108)
		(end 344.898726 -239.319308)
		(width 0.1143)
		(layer "In15.Cu")
		(net "GMI_CPU0_G1_CPU1_G3_TX_DN<15>")
	)
	(arc
		(start 344.585798 -230.714296)
		(mid 344.651034 -230.450705)
		(end 344.83167 -230.247952)
		(width 0.1143)
		(layer "In15.Cu")
		(net "GMI_CPU0_G1_CPU1_G3_TX_DN<15>")
	)
	(arc
		(start 126.597156 -232.839514)
		(mid 126.440179 -233.144314)
		(end 126.597156 -233.449114)
		(width 0.1143)
		(layer "In15.Cu")
		(net "GMI_CPU0_G1_CPU1_G3_TX_DN<15>")
	)
	(arc
		(start 126.597156 -227.979732)
		(mid 126.440179 -228.284532)
		(end 126.597156 -228.589332)
		(width 0.1143)
		(layer "In15.Cu")
		(net "GMI_CPU0_G1_CPU1_G3_TX_DN<15>")
	)
	(arc
		(start 125.97003 -245.294404)
		(mid 125.905515 -245.556623)
		(end 125.726698 -245.75897)
		(width 0.1143)
		(layer "In15.Cu")
		(net "GMI_CPU0_G1_CPU1_G3_TX_DN<15>")
	)
	(arc
		(start 126.597156 -236.079538)
		(mid 126.440179 -236.384338)
		(end 126.597156 -236.689138)
		(width 0.1143)
		(layer "In15.Cu")
		(net "GMI_CPU0_G1_CPU1_G3_TX_DN<15>")
	)
	(arc
		(start 344.82913 -229.55885)
		(mid 344.585803 -229.094284)
		(end 344.82913 -228.629718)
		(width 0.1143)
		(layer "In15.Cu")
		(net "GMI_CPU0_G1_CPU1_G3_TX_DN<15>")
	)
	(arc
		(start 344.898726 -243.168932)
		(mid 345.055703 -242.864132)
		(end 344.898726 -242.559332)
		(width 0.1143)
		(layer "In15.Cu")
		(net "GMI_CPU0_G1_CPU1_G3_TX_DN<15>")
	)
	(arc
		(start 126.666752 -243.209826)
		(mid 126.910079 -243.674392)
		(end 126.666752 -244.138958)
		(width 0.1143)
		(layer "In15.Cu")
		(net "GMI_CPU0_G1_CPU1_G3_TX_DN<15>")
	)
	(arc
		(start 126.666752 -239.969802)
		(mid 126.910079 -240.434368)
		(end 126.666752 -240.898934)
		(width 0.1143)
		(layer "In15.Cu")
		(net "GMI_CPU0_G1_CPU1_G3_TX_DN<15>")
	)
	(arc
		(start 344.898726 -231.828848)
		(mid 345.014153 -231.695472)
		(end 345.055698 -231.524048)
		(width 0.1143)
		(layer "In15.Cu")
		(net "GMI_CPU0_G1_CPU1_G3_TX_DN<15>")
	)
	(arc
		(start 345.29903 -244.94871)
		(mid 345.120217 -244.74636)
		(end 345.055698 -244.484144)
		(width 0.1143)
		(layer "In15.Cu")
		(net "GMI_CPU0_G1_CPU1_G3_TX_DN<15>")
	)
	(arc
		(start 344.82913 -226.318826)
		(mid 344.650317 -226.116476)
		(end 344.585798 -225.85426)
		(width 0.1143)
		(layer "In15.Cu")
		(net "GMI_CPU0_G1_CPU1_G3_TX_DN<15>")
	)
	(arc
		(start 125.657102 -245.79961)
		(mid 125.559337 -245.902586)
		(end 125.506988 -246.03456)
		(width 0.1143)
		(layer "In15.Cu")
		(net "GMI_CPU0_G1_CPU1_G3_TX_DN<15>")
	)
	(arc
		(start 344.898726 -228.589078)
		(mid 345.055703 -228.284278)
		(end 344.898726 -227.979478)
		(width 0.1143)
		(layer "In15.Cu")
		(net "GMI_CPU0_G1_CPU1_G3_TX_DN<15>")
	)
	(arc
		(start 126.666752 -236.729778)
		(mid 126.910079 -237.194344)
		(end 126.666752 -237.65891)
		(width 0.1143)
		(layer "In15.Cu")
		(net "GMI_CPU0_G1_CPU1_G3_TX_DN<15>")
	)
	(arc
		(start 126.439422 -221.804484)
		(mid 126.480472 -221.974934)
		(end 126.594616 -222.108014)
		(width 0.1143)
		(layer "In15.Cu")
		(net "GMI_CPU0_G1_CPU1_G3_TX_DN<15>")
	)
	(arc
		(start 126.440184 -229.90429)
		(mid 126.481733 -230.075712)
		(end 126.597156 -230.20909)
		(width 0.1143)
		(layer "In15.Cu")
		(net "GMI_CPU0_G1_CPU1_G3_TX_DN<15>")
	)
	(arc
		(start 126.597156 -223.119696)
		(mid 126.440179 -223.424496)
		(end 126.597156 -223.729296)
		(width 0.1143)
		(layer "In15.Cu")
		(net "GMI_CPU0_G1_CPU1_G3_TX_DN<15>")
	)
	(arc
		(start 344.82913 -227.938838)
		(mid 344.585803 -227.474272)
		(end 344.82913 -227.009706)
		(width 0.1143)
		(layer "In15.Cu")
		(net "GMI_CPU0_G1_CPU1_G3_TX_DN<15>")
	)
	(arc
		(start 344.82913 -244.138704)
		(mid 344.585803 -243.674138)
		(end 344.82913 -243.209572)
		(width 0.1143)
		(layer "In15.Cu")
		(net "GMI_CPU0_G1_CPU1_G3_TX_DN<15>")
	)
	(arc
		(start 343.645744 -222.614236)
		(mid 343.604489 -222.443265)
		(end 343.489788 -222.309944)
		(width 0.1143)
		(layer "In15.Cu")
		(net "GMI_CPU0_G1_CPU1_G3_TX_DN<15>")
	)
	(arc
		(start 344.82913 -240.89868)
		(mid 344.585803 -240.434114)
		(end 344.82913 -239.969548)
		(width 0.1143)
		(layer "In15.Cu")
		(net "GMI_CPU0_G1_CPU1_G3_TX_DN<15>")
	)
	(segment
		(start 125.407928 -244.750336)
		(end 125.87478 -244.484398)
		(width 0.12954)
		(layer "F.Cu")
		(net "GMI_CPU0_G1_CPU1_G3_TX_DN<14>")
	)
	(segment
		(start 346.087954 -244.750082)
		(end 345.621102 -244.484144)
		(width 0.12954)
		(layer "F.Cu")
		(net "GMI_CPU0_G1_CPU1_G3_TX_DN<14>")
	)
	(segment
		(start 125.726698 -236.038898)
		(end 125.687582 -236.061758)
		(width 0.1143)
		(layer "In15.Cu")
		(net "GMI_CPU0_G1_CPU1_G3_TX_DN<14>")
	)
	(segment
		(start 345.810586 -242.543076)
		(end 345.809824 -242.542568)
		(width 0.1143)
		(layer "In15.Cu")
		(net "GMI_CPU0_G1_CPU1_G3_TX_DN<14>")
	)
	(segment
		(start 345.338146 -225.53168)
		(end 345.33713 -225.531172)
		(width 0.1143)
		(layer "In15.Cu")
		(net "GMI_CPU0_G1_CPU1_G3_TX_DN<14>")
	)
	(segment
		(start 125.726698 -223.079056)
		(end 125.687582 -223.101916)
		(width 0.1143)
		(layer "In15.Cu")
		(net "GMI_CPU0_G1_CPU1_G3_TX_DN<14>")
	)
	(segment
		(start 125.687582 -223.101916)
		(end 125.657102 -223.119696)
		(width 0.1143)
		(layer "In15.Cu")
		(net "GMI_CPU0_G1_CPU1_G3_TX_DN<14>")
	)
	(segment
		(start 345.808046 -231.846628)
		(end 345.808808 -231.84612)
		(width 0.1143)
		(layer "In15.Cu")
		(net "GMI_CPU0_G1_CPU1_G3_TX_DN<14>")
	)
	(segment
		(start 125.687582 -239.301782)
		(end 125.657102 -239.319562)
		(width 0.1143)
		(layer "In15.Cu")
		(net "GMI_CPU0_G1_CPU1_G3_TX_DN<14>")
	)
	(segment
		(start 125.657102 -233.449114)
		(end 125.687582 -233.466894)
		(width 0.1143)
		(layer "In15.Cu")
		(net "GMI_CPU0_G1_CPU1_G3_TX_DN<14>")
	)
	(segment
		(start 345.621102 -244.484144)
		(end 345.919044 -244.484144)
		(width 0.1143)
		(layer "In15.Cu")
		(net "GMI_CPU0_G1_CPU1_G3_TX_DN<14>")
	)
	(segment
		(start 158.161482 -194.650868)
		(end 157.831282 -194.921886)
		(width 0.14224)
		(layer "In15.Cu")
		(net "GMI_CPU0_G1_CPU1_G3_TX_DN<14>")
	)
	(segment
		(start 345.341448 -225.533458)
		(end 345.338146 -225.53168)
		(width 0.1143)
		(layer "In15.Cu")
		(net "GMI_CPU0_G1_CPU1_G3_TX_DN<14>")
	)
	(segment
		(start 345.808046 -233.46664)
		(end 345.808808 -233.466132)
		(width 0.1143)
		(layer "In15.Cu")
		(net "GMI_CPU0_G1_CPU1_G3_TX_DN<14>")
	)
	(segment
		(start 345.809824 -239.302544)
		(end 345.808808 -239.302036)
		(width 0.1143)
		(layer "In15.Cu")
		(net "GMI_CPU0_G1_CPU1_G3_TX_DN<14>")
	)
	(segment
		(start 125.657102 -228.589332)
		(end 125.687582 -228.607112)
		(width 0.1143)
		(layer "In15.Cu")
		(net "GMI_CPU0_G1_CPU1_G3_TX_DN<14>")
	)
	(segment
		(start 345.839796 -232.839768)
		(end 345.808046 -232.82148)
		(width 0.1143)
		(layer "In15.Cu")
		(net "GMI_CPU0_G1_CPU1_G3_TX_DN<14>")
	)
	(segment
		(start 125.687582 -229.581964)
		(end 125.65507 -229.60076)
		(width 0.1143)
		(layer "In15.Cu")
		(net "GMI_CPU0_G1_CPU1_G3_TX_DN<14>")
	)
	(segment
		(start 125.687582 -224.721928)
		(end 125.657102 -224.739708)
		(width 0.1143)
		(layer "In15.Cu")
		(net "GMI_CPU0_G1_CPU1_G3_TX_DN<14>")
	)
	(segment
		(start 344.0557 -221.38767)
		(end 344.0557 -221.128844)
		(width 0.1143)
		(layer "In15.Cu")
		(net "GMI_CPU0_G1_CPU1_G3_TX_DN<14>")
	)
	(segment
		(start 345.808046 -232.82148)
		(end 345.771724 -232.800398)
		(width 0.1143)
		(layer "In15.Cu")
		(net "GMI_CPU0_G1_CPU1_G3_TX_DN<14>")
	)
	(segment
		(start 344.394536 -222.289624)
		(end 344.393012 -222.288608)
		(width 0.1143)
		(layer "In15.Cu")
		(net "GMI_CPU0_G1_CPU1_G3_TX_DN<14>")
	)
	(segment
		(start 125.687582 -232.821734)
		(end 125.657102 -232.839514)
		(width 0.1143)
		(layer "In15.Cu")
		(net "GMI_CPU0_G1_CPU1_G3_TX_DN<14>")
	)
	(segment
		(start 345.33713 -225.531172)
		(end 345.29903 -225.50882)
		(width 0.1143)
		(layer "In15.Cu")
		(net "GMI_CPU0_G1_CPU1_G3_TX_DN<14>")
	)
	(segment
		(start 239.90681 -200.078086)
		(end 236.351064 -200.705212)
		(width 0.14224)
		(layer "In15.Cu")
		(net "GMI_CPU0_G1_CPU1_G3_TX_DN<14>")
	)
	(segment
		(start 236.351064 -200.705212)
		(end 233.006646 -200.115678)
		(width 0.14224)
		(layer "In15.Cu")
		(net "GMI_CPU0_G1_CPU1_G3_TX_DN<14>")
	)
	(segment
		(start 345.808808 -244.162072)
		(end 345.808046 -244.161564)
		(width 0.1143)
		(layer "In15.Cu")
		(net "GMI_CPU0_G1_CPU1_G3_TX_DN<14>")
	)
	(segment
		(start 125.687582 -243.186966)
		(end 125.726698 -243.209826)
		(width 0.1143)
		(layer "In15.Cu")
		(net "GMI_CPU0_G1_CPU1_G3_TX_DN<14>")
	)
	(segment
		(start 345.811602 -239.30356)
		(end 345.810586 -239.303052)
		(width 0.1143)
		(layer "In15.Cu")
		(net "GMI_CPU0_G1_CPU1_G3_TX_DN<14>")
	)
	(segment
		(start 345.815412 -237.685834)
		(end 345.814142 -237.685072)
		(width 0.1143)
		(layer "In15.Cu")
		(net "GMI_CPU0_G1_CPU1_G3_TX_DN<14>")
	)
	(segment
		(start 125.687582 -241.566954)
		(end 125.726698 -241.589814)
		(width 0.1143)
		(layer "In15.Cu")
		(net "GMI_CPU0_G1_CPU1_G3_TX_DN<14>")
	)
	(segment
		(start 344.868246 -223.746822)
		(end 344.898726 -223.729042)
		(width 0.1143)
		(layer "In15.Cu")
		(net "GMI_CPU0_G1_CPU1_G3_TX_DN<14>")
	)
	(segment
		(start 345.811602 -236.063536)
		(end 345.810586 -236.063028)
		(width 0.1143)
		(layer "In15.Cu")
		(net "GMI_CPU0_G1_CPU1_G3_TX_DN<14>")
	)
	(segment
		(start 345.839796 -234.45978)
		(end 345.808046 -234.441492)
		(width 0.1143)
		(layer "In15.Cu")
		(net "GMI_CPU0_G1_CPU1_G3_TX_DN<14>")
	)
	(segment
		(start 125.726698 -239.278922)
		(end 125.687582 -239.301782)
		(width 0.1143)
		(layer "In15.Cu")
		(net "GMI_CPU0_G1_CPU1_G3_TX_DN<14>")
	)
	(segment
		(start 125.576838 -244.484398)
		(end 125.87478 -244.484398)
		(width 0.1143)
		(layer "In15.Cu")
		(net "GMI_CPU0_G1_CPU1_G3_TX_DN<14>")
	)
	(segment
		(start 344.393012 -222.288608)
		(end 344.391996 -222.2881)
		(width 0.1143)
		(layer "In15.Cu")
		(net "GMI_CPU0_G1_CPU1_G3_TX_DN<14>")
	)
	(segment
		(start 345.808046 -239.301528)
		(end 345.807792 -239.301528)
		(width 0.1143)
		(layer "In15.Cu")
		(net "GMI_CPU0_G1_CPU1_G3_TX_DN<14>")
	)
	(segment
		(start 125.687582 -242.541806)
		(end 125.657102 -242.559586)
		(width 0.1143)
		(layer "In15.Cu")
		(net "GMI_CPU0_G1_CPU1_G3_TX_DN<14>")
	)
	(segment
		(start 344.898726 -224.739454)
		(end 344.868246 -224.721674)
		(width 0.1143)
		(layer "In15.Cu")
		(net "GMI_CPU0_G1_CPU1_G3_TX_DN<14>")
	)
	(segment
		(start 156.435806 -195.888356)
		(end 156.435806 -195.888102)
		(width 0.14224)
		(layer "In15.Cu")
		(net "GMI_CPU0_G1_CPU1_G3_TX_DN<14>")
	)
	(segment
		(start 125.657102 -238.30915)
		(end 125.687582 -238.32693)
		(width 0.1143)
		(layer "In15.Cu")
		(net "GMI_CPU0_G1_CPU1_G3_TX_DN<14>")
	)
	(segment
		(start 125.657102 -243.169186)
		(end 125.687582 -243.186966)
		(width 0.1143)
		(layer "In15.Cu")
		(net "GMI_CPU0_G1_CPU1_G3_TX_DN<14>")
	)
	(segment
		(start 345.808808 -233.466132)
		(end 345.810078 -233.46537)
		(width 0.1143)
		(layer "In15.Cu")
		(net "GMI_CPU0_G1_CPU1_G3_TX_DN<14>")
	)
	(segment
		(start 345.808046 -243.186712)
		(end 345.808808 -243.186204)
		(width 0.1143)
		(layer "In15.Cu")
		(net "GMI_CPU0_G1_CPU1_G3_TX_DN<14>")
	)
	(segment
		(start 345.771724 -233.487722)
		(end 345.808046 -233.46664)
		(width 0.1143)
		(layer "In15.Cu")
		(net "GMI_CPU0_G1_CPU1_G3_TX_DN<14>")
	)
	(segment
		(start 345.810586 -237.68304)
		(end 345.809824 -237.682532)
		(width 0.1143)
		(layer "In15.Cu")
		(net "GMI_CPU0_G1_CPU1_G3_TX_DN<14>")
	)
	(segment
		(start 345.808046 -236.706664)
		(end 345.829128 -236.694472)
		(width 0.1143)
		(layer "In15.Cu")
		(net "GMI_CPU0_G1_CPU1_G3_TX_DN<14>")
	)
	(segment
		(start 159.905954 -193.220594)
		(end 159.575754 -193.491612)
		(width 0.14224)
		(layer "In15.Cu")
		(net "GMI_CPU0_G1_CPU1_G3_TX_DN<14>")
	)
	(segment
		(start 125.687582 -231.846882)
		(end 125.726698 -231.869742)
		(width 0.1143)
		(layer "In15.Cu")
		(net "GMI_CPU0_G1_CPU1_G3_TX_DN<14>")
	)
	(segment
		(start 158.180532 -194.457828)
		(end 158.161482 -194.650868)
		(width 0.14224)
		(layer "In15.Cu")
		(net "GMI_CPU0_G1_CPU1_G3_TX_DN<14>")
	)
	(segment
		(start 344.00998 -221.083124)
		(end 344.00998 -220.550232)
		(width 0.14224)
		(layer "In15.Cu")
		(net "GMI_CPU0_G1_CPU1_G3_TX_DN<14>")
	)
	(segment
		(start 344.429842 -222.309944)
		(end 344.398092 -222.291656)
		(width 0.1143)
		(layer "In15.Cu")
		(net "GMI_CPU0_G1_CPU1_G3_TX_DN<14>")
	)
	(segment
		(start 125.726698 -226.31908)
		(end 125.687582 -226.34194)
		(width 0.1143)
		(layer "In15.Cu")
		(net "GMI_CPU0_G1_CPU1_G3_TX_DN<14>")
	)
	(segment
		(start 125.726698 -240.898934)
		(end 125.687582 -240.921794)
		(width 0.1143)
		(layer "In15.Cu")
		(net "GMI_CPU0_G1_CPU1_G3_TX_DN<14>")
	)
	(segment
		(start 308.646068 -190.391796)
		(end 303.7332 -190.391796)
		(width 0.14224)
		(layer "In15.Cu")
		(net "GMI_CPU0_G1_CPU1_G3_TX_DN<14>")
	)
	(segment
		(start 344.115898 -221.80423)
		(end 344.115898 -221.447868)
		(width 0.1143)
		(layer "In15.Cu")
		(net "GMI_CPU0_G1_CPU1_G3_TX_DN<14>")
	)
	(segment
		(start 345.815412 -240.925858)
		(end 345.814142 -240.925096)
		(width 0.1143)
		(layer "In15.Cu")
		(net "GMI_CPU0_G1_CPU1_G3_TX_DN<14>")
	)
	(segment
		(start 157.288992 -195.366132)
		(end 156.958792 -195.636896)
		(width 0.14224)
		(layer "In15.Cu")
		(net "GMI_CPU0_G1_CPU1_G3_TX_DN<14>")
	)
	(segment
		(start 125.726698 -227.939092)
		(end 125.687582 -227.961952)
		(width 0.1143)
		(layer "In15.Cu")
		(net "GMI_CPU0_G1_CPU1_G3_TX_DN<14>")
	)
	(segment
		(start 345.808808 -236.062012)
		(end 345.808046 -236.061504)
		(width 0.1143)
		(layer "In15.Cu")
		(net "GMI_CPU0_G1_CPU1_G3_TX_DN<14>")
	)
	(segment
		(start 345.807792 -239.946942)
		(end 345.808046 -239.946688)
		(width 0.1143)
		(layer "In15.Cu")
		(net "GMI_CPU0_G1_CPU1_G3_TX_DN<14>")
	)
	(segment
		(start 345.839796 -227.979986)
		(end 345.808808 -227.962206)
		(width 0.1143)
		(layer "In15.Cu")
		(net "GMI_CPU0_G1_CPU1_G3_TX_DN<14>")
	)
	(segment
		(start 125.726698 -234.418886)
		(end 125.687582 -234.441746)
		(width 0.1143)
		(layer "In15.Cu")
		(net "GMI_CPU0_G1_CPU1_G3_TX_DN<14>")
	)
	(segment
		(start 160.77819 -192.505584)
		(end 160.44799 -192.776348)
		(width 0.14224)
		(layer "In15.Cu")
		(net "GMI_CPU0_G1_CPU1_G3_TX_DN<14>")
	)
	(segment
		(start 125.726698 -229.559104)
		(end 125.687582 -229.581964)
		(width 0.1143)
		(layer "In15.Cu")
		(net "GMI_CPU0_G1_CPU1_G3_TX_DN<14>")
	)
	(segment
		(start 345.815412 -239.305846)
		(end 345.814142 -239.305084)
		(width 0.1143)
		(layer "In15.Cu")
		(net "GMI_CPU0_G1_CPU1_G3_TX_DN<14>")
	)
	(segment
		(start 344.0557 -221.128844)
		(end 344.00998 -221.083124)
		(width 0.1143)
		(layer "In15.Cu")
		(net "GMI_CPU0_G1_CPU1_G3_TX_DN<14>")
	)
	(segment
		(start 210.794092 -190.91529)
		(end 207.154272 -190.273178)
		(width 0.14224)
		(layer "In15.Cu")
		(net "GMI_CPU0_G1_CPU1_G3_TX_DN<14>")
	)
	(segment
		(start 345.808046 -241.5667)
		(end 345.829128 -241.554508)
		(width 0.1143)
		(layer "In15.Cu")
		(net "GMI_CPU0_G1_CPU1_G3_TX_DN<14>")
	)
	(segment
		(start 345.814142 -242.545108)
		(end 345.81338 -242.5446)
		(width 0.1143)
		(layer "In15.Cu")
		(net "GMI_CPU0_G1_CPU1_G3_TX_DN<14>")
	)
	(segment
		(start 233.006646 -200.115678)
		(end 210.794092 -190.91529)
		(width 0.14224)
		(layer "In15.Cu")
		(net "GMI_CPU0_G1_CPU1_G3_TX_DN<14>")
	)
	(segment
		(start 345.81338 -240.924588)
		(end 345.812364 -240.92408)
		(width 0.1143)
		(layer "In15.Cu")
		(net "GMI_CPU0_G1_CPU1_G3_TX_DN<14>")
	)
	(segment
		(start 345.840812 -229.60076)
		(end 345.808046 -229.58171)
		(width 0.1143)
		(layer "In15.Cu")
		(net "GMI_CPU0_G1_CPU1_G3_TX_DN<14>")
	)
	(segment
		(start 345.829128 -241.554508)
		(end 345.82989 -241.554)
		(width 0.1143)
		(layer "In15.Cu")
		(net "GMI_CPU0_G1_CPU1_G3_TX_DN<14>")
	)
	(segment
		(start 345.82989 -236.693964)
		(end 345.839796 -236.688376)
		(width 0.1143)
		(layer "In15.Cu")
		(net "GMI_CPU0_G1_CPU1_G3_TX_DN<14>")
	)
	(segment
		(start 155.21432 -197.06717)
		(end 155.02128 -197.047866)
		(width 0.14224)
		(layer "In15.Cu")
		(net "GMI_CPU0_G1_CPU1_G3_TX_DN<14>")
	)
	(segment
		(start 345.810586 -236.063028)
		(end 345.809824 -236.06252)
		(width 0.1143)
		(layer "In15.Cu")
		(net "GMI_CPU0_G1_CPU1_G3_TX_DN<14>")
	)
	(segment
		(start 345.808046 -242.541552)
		(end 345.807792 -242.541552)
		(width 0.1143)
		(layer "In15.Cu")
		(net "GMI_CPU0_G1_CPU1_G3_TX_DN<14>")
	)
	(segment
		(start 159.382714 -193.472308)
		(end 159.052768 -193.742818)
		(width 0.14224)
		(layer "In15.Cu")
		(net "GMI_CPU0_G1_CPU1_G3_TX_DN<14>")
	)
	(segment
		(start 159.052768 -193.742818)
		(end 159.033718 -193.935604)
		(width 0.14224)
		(layer "In15.Cu")
		(net "GMI_CPU0_G1_CPU1_G3_TX_DN<14>")
	)
	(segment
		(start 344.398092 -222.291656)
		(end 344.397076 -222.291148)
		(width 0.1143)
		(layer "In15.Cu")
		(net "GMI_CPU0_G1_CPU1_G3_TX_DN<14>")
	)
	(segment
		(start 125.687582 -223.747076)
		(end 125.726698 -223.769936)
		(width 0.1143)
		(layer "In15.Cu")
		(net "GMI_CPU0_G1_CPU1_G3_TX_DN<14>")
	)
	(segment
		(start 345.839796 -242.55984)
		(end 345.815412 -242.54587)
		(width 0.1143)
		(layer "In15.Cu")
		(net "GMI_CPU0_G1_CPU1_G3_TX_DN<14>")
	)
	(segment
		(start 125.687582 -231.201976)
		(end 125.65507 -231.220772)
		(width 0.1143)
		(layer "In15.Cu")
		(net "GMI_CPU0_G1_CPU1_G3_TX_DN<14>")
	)
	(segment
		(start 207.154272 -190.273178)
		(end 162.653472 -190.4619)
		(width 0.14224)
		(layer "In15.Cu")
		(net "GMI_CPU0_G1_CPU1_G3_TX_DN<14>")
	)
	(segment
		(start 345.365324 -225.547428)
		(end 345.364308 -225.54692)
		(width 0.1143)
		(layer "In15.Cu")
		(net "GMI_CPU0_G1_CPU1_G3_TX_DN<14>")
	)
	(segment
		(start 345.814396 -236.065314)
		(end 345.812364 -236.064044)
		(width 0.1143)
		(layer "In15.Cu")
		(net "GMI_CPU0_G1_CPU1_G3_TX_DN<14>")
	)
	(segment
		(start 159.033718 -193.935604)
		(end 158.703518 -194.206622)
		(width 0.14224)
		(layer "In15.Cu")
		(net "GMI_CPU0_G1_CPU1_G3_TX_DN<14>")
	)
	(segment
		(start 125.657102 -223.729296)
		(end 125.687582 -223.747076)
		(width 0.1143)
		(layer "In15.Cu")
		(net "GMI_CPU0_G1_CPU1_G3_TX_DN<14>")
	)
	(segment
		(start 125.687582 -236.706918)
		(end 125.726698 -236.729778)
		(width 0.1143)
		(layer "In15.Cu")
		(net "GMI_CPU0_G1_CPU1_G3_TX_DN<14>")
	)
	(segment
		(start 154.342084 -197.78218)
		(end 154.149044 -197.76313)
		(width 0.14224)
		(layer "In15.Cu")
		(net "GMI_CPU0_G1_CPU1_G3_TX_DN<14>")
	)
	(segment
		(start 345.839542 -228.588316)
		(end 345.839796 -228.58857)
		(width 0.1143)
		(layer "In15.Cu")
		(net "GMI_CPU0_G1_CPU1_G3_TX_DN<14>")
	)
	(segment
		(start 345.812364 -236.064044)
		(end 345.811602 -236.063536)
		(width 0.1143)
		(layer "In15.Cu")
		(net "GMI_CPU0_G1_CPU1_G3_TX_DN<14>")
	)
	(segment
		(start 251.423424 -192.01384)
		(end 239.90681 -200.078086)
		(width 0.14224)
		(layer "In15.Cu")
		(net "GMI_CPU0_G1_CPU1_G3_TX_DN<14>")
	)
	(segment
		(start 345.808046 -228.606858)
		(end 345.808808 -228.60635)
		(width 0.1143)
		(layer "In15.Cu")
		(net "GMI_CPU0_G1_CPU1_G3_TX_DN<14>")
	)
	(segment
		(start 345.839796 -236.079792)
		(end 345.814396 -236.065314)
		(width 0.1143)
		(layer "In15.Cu")
		(net "GMI_CPU0_G1_CPU1_G3_TX_DN<14>")
	)
	(segment
		(start 156.766006 -195.617846)
		(end 156.435806 -195.888356)
		(width 0.14224)
		(layer "In15.Cu")
		(net "GMI_CPU0_G1_CPU1_G3_TX_DN<14>")
	)
	(segment
		(start 125.726698 -232.798874)
		(end 125.687582 -232.821734)
		(width 0.1143)
		(layer "In15.Cu")
		(net "GMI_CPU0_G1_CPU1_G3_TX_DN<14>")
	)
	(segment
		(start 344.115898 -221.447868)
		(end 344.0557 -221.38767)
		(width 0.1143)
		(layer "In15.Cu")
		(net "GMI_CPU0_G1_CPU1_G3_TX_DN<14>")
	)
	(segment
		(start 149.48027 -201.590656)
		(end 146.974814 -202.350116)
		(width 0.14224)
		(layer "In15.Cu")
		(net "GMI_CPU0_G1_CPU1_G3_TX_DN<14>")
	)
	(segment
		(start 345.814142 -240.925096)
		(end 345.81338 -240.924588)
		(width 0.1143)
		(layer "In15.Cu")
		(net "GMI_CPU0_G1_CPU1_G3_TX_DN<14>")
	)
	(segment
		(start 345.839796 -244.179852)
		(end 345.808808 -244.162072)
		(width 0.1143)
		(layer "In15.Cu")
		(net "GMI_CPU0_G1_CPU1_G3_TX_DN<14>")
	)
	(segment
		(start 345.839796 -237.699804)
		(end 345.815412 -237.685834)
		(width 0.1143)
		(layer "In15.Cu")
		(net "GMI_CPU0_G1_CPU1_G3_TX_DN<14>")
	)
	(segment
		(start 158.703518 -194.206622)
		(end 158.658814 -194.20205)
		(width 0.14224)
		(layer "In15.Cu")
		(net "GMI_CPU0_G1_CPU1_G3_TX_DN<14>")
	)
	(segment
		(start 125.687582 -225.367088)
		(end 125.726698 -225.389948)
		(width 0.1143)
		(layer "In15.Cu")
		(net "GMI_CPU0_G1_CPU1_G3_TX_DN<14>")
	)
	(segment
		(start 158.658814 -194.20205)
		(end 158.510478 -194.187318)
		(width 0.14224)
		(layer "In15.Cu")
		(net "GMI_CPU0_G1_CPU1_G3_TX_DN<14>")
	)
	(segment
		(start 345.811602 -237.683548)
		(end 345.810586 -237.68304)
		(width 0.1143)
		(layer "In15.Cu")
		(net "GMI_CPU0_G1_CPU1_G3_TX_DN<14>")
	)
	(segment
		(start 344.868246 -223.101662)
		(end 344.82913 -223.078802)
		(width 0.1143)
		(layer "In15.Cu")
		(net "GMI_CPU0_G1_CPU1_G3_TX_DN<14>")
	)
	(segment
		(start 345.809824 -237.682532)
		(end 345.808808 -237.682024)
		(width 0.1143)
		(layer "In15.Cu")
		(net "GMI_CPU0_G1_CPU1_G3_TX_DN<14>")
	)
	(segment
		(start 345.815412 -242.54587)
		(end 345.814142 -242.545108)
		(width 0.1143)
		(layer "In15.Cu")
		(net "GMI_CPU0_G1_CPU1_G3_TX_DN<14>")
	)
	(segment
		(start 125.545596 -220.88983)
		(end 125.545596 -221.174564)
		(width 0.14224)
		(layer "In15.Cu")
		(net "GMI_CPU0_G1_CPU1_G3_TX_DN<14>")
	)
	(segment
		(start 154.149044 -197.76313)
		(end 149.48027 -201.590656)
		(width 0.14224)
		(layer "In15.Cu")
		(net "GMI_CPU0_G1_CPU1_G3_TX_DN<14>")
	)
	(segment
		(start 125.657102 -236.689138)
		(end 125.687582 -236.706918)
		(width 0.1143)
		(layer "In15.Cu")
		(net "GMI_CPU0_G1_CPU1_G3_TX_DN<14>")
	)
	(segment
		(start 345.811856 -230.22433)
		(end 345.839796 -230.208328)
		(width 0.1143)
		(layer "In15.Cu")
		(net "GMI_CPU0_G1_CPU1_G3_TX_DN<14>")
	)
	(segment
		(start 345.823032 -228.598222)
		(end 345.839542 -228.588316)
		(width 0.1143)
		(layer "In15.Cu")
		(net "GMI_CPU0_G1_CPU1_G3_TX_DN<14>")
	)
	(segment
		(start 345.839796 -226.359974)
		(end 345.808046 -226.341686)
		(width 0.1143)
		(layer "In15.Cu")
		(net "GMI_CPU0_G1_CPU1_G3_TX_DN<14>")
	)
	(segment
		(start 125.657102 -230.20909)
		(end 125.724158 -230.248206)
		(width 0.1143)
		(layer "In15.Cu")
		(net "GMI_CPU0_G1_CPU1_G3_TX_DN<14>")
	)
	(segment
		(start 125.687582 -233.466894)
		(end 125.726698 -233.489754)
		(width 0.1143)
		(layer "In15.Cu")
		(net "GMI_CPU0_G1_CPU1_G3_TX_DN<14>")
	)
	(segment
		(start 345.362022 -225.545396)
		(end 345.341448 -225.533458)
		(width 0.1143)
		(layer "In15.Cu")
		(net "GMI_CPU0_G1_CPU1_G3_TX_DN<14>")
	)
	(segment
		(start 345.82989 -241.554)
		(end 345.839796 -241.548412)
		(width 0.1143)
		(layer "In15.Cu")
		(net "GMI_CPU0_G1_CPU1_G3_TX_DN<14>")
	)
	(segment
		(start 125.687328 -222.127064)
		(end 125.727714 -222.150686)
		(width 0.1143)
		(layer "In15.Cu")
		(net "GMI_CPU0_G1_CPU1_G3_TX_DN<14>")
	)
	(segment
		(start 345.811602 -240.923572)
		(end 345.810586 -240.923064)
		(width 0.1143)
		(layer "In15.Cu")
		(net "GMI_CPU0_G1_CPU1_G3_TX_DN<14>")
	)
	(segment
		(start 345.808046 -226.986846)
		(end 345.839796 -226.968558)
		(width 0.1143)
		(layer "In15.Cu")
		(net "GMI_CPU0_G1_CPU1_G3_TX_DN<14>")
	)
	(segment
		(start 159.925004 -193.027554)
		(end 159.905954 -193.220594)
		(width 0.14224)
		(layer "In15.Cu")
		(net "GMI_CPU0_G1_CPU1_G3_TX_DN<14>")
	)
	(segment
		(start 345.809824 -240.922556)
		(end 345.808808 -240.922048)
		(width 0.1143)
		(layer "In15.Cu")
		(net "GMI_CPU0_G1_CPU1_G3_TX_DN<14>")
	)
	(segment
		(start 342.35263 -217.04808)
		(end 317.09868 -196.341746)
		(width 0.14224)
		(layer "In15.Cu")
		(net "GMI_CPU0_G1_CPU1_G3_TX_DN<14>")
	)
	(segment
		(start 345.813126 -228.604064)
		(end 345.823032 -228.598222)
		(width 0.1143)
		(layer "In15.Cu")
		(net "GMI_CPU0_G1_CPU1_G3_TX_DN<14>")
	)
	(segment
		(start 345.771724 -227.007928)
		(end 345.808046 -226.986846)
		(width 0.1143)
		(layer "In15.Cu")
		(net "GMI_CPU0_G1_CPU1_G3_TX_DN<14>")
	)
	(segment
		(start 345.839796 -240.939828)
		(end 345.815412 -240.925858)
		(width 0.1143)
		(layer "In15.Cu")
		(net "GMI_CPU0_G1_CPU1_G3_TX_DN<14>")
	)
	(segment
		(start 154.672284 -197.511416)
		(end 154.342084 -197.78218)
		(width 0.14224)
		(layer "In15.Cu")
		(net "GMI_CPU0_G1_CPU1_G3_TX_DN<14>")
	)
	(segment
		(start 345.525852 -225.870516)
		(end 345.525852 -225.870262)
		(width 0.1143)
		(layer "In15.Cu")
		(net "GMI_CPU0_G1_CPU1_G3_TX_DN<14>")
	)
	(segment
		(start 156.086556 -196.351906)
		(end 155.89377 -196.332856)
		(width 0.14224)
		(layer "In15.Cu")
		(net "GMI_CPU0_G1_CPU1_G3_TX_DN<14>")
	)
	(segment
		(start 125.726698 -231.179116)
		(end 125.687582 -231.201976)
		(width 0.1143)
		(layer "In15.Cu")
		(net "GMI_CPU0_G1_CPU1_G3_TX_DN<14>")
	)
	(segment
		(start 125.687582 -238.32693)
		(end 125.726698 -238.34979)
		(width 0.1143)
		(layer "In15.Cu")
		(net "GMI_CPU0_G1_CPU1_G3_TX_DN<14>")
	)
	(segment
		(start 317.09868 -196.341746)
		(end 308.646068 -190.391796)
		(width 0.14224)
		(layer "In15.Cu")
		(net "GMI_CPU0_G1_CPU1_G3_TX_DN<14>")
	)
	(segment
		(start 345.808046 -244.161564)
		(end 345.771724 -244.140482)
		(width 0.1143)
		(layer "In15.Cu")
		(net "GMI_CPU0_G1_CPU1_G3_TX_DN<14>")
	)
	(segment
		(start 345.811602 -242.543584)
		(end 345.810586 -242.543076)
		(width 0.1143)
		(layer "In15.Cu")
		(net "GMI_CPU0_G1_CPU1_G3_TX_DN<14>")
	)
	(segment
		(start 125.499622 -221.677484)
		(end 125.499622 -221.804484)
		(width 0.1143)
		(layer "In15.Cu")
		(net "GMI_CPU0_G1_CPU1_G3_TX_DN<14>")
	)
	(segment
		(start 345.807792 -236.706918)
		(end 345.808046 -236.706664)
		(width 0.1143)
		(layer "In15.Cu")
		(net "GMI_CPU0_G1_CPU1_G3_TX_DN<14>")
	)
	(segment
		(start 155.54452 -196.796406)
		(end 155.21432 -197.06717)
		(width 0.14224)
		(layer "In15.Cu")
		(net "GMI_CPU0_G1_CPU1_G3_TX_DN<14>")
	)
	(segment
		(start 345.808046 -227.961698)
		(end 345.771724 -227.940616)
		(width 0.1143)
		(layer "In15.Cu")
		(net "GMI_CPU0_G1_CPU1_G3_TX_DN<14>")
	)
	(segment
		(start 345.808046 -239.946688)
		(end 345.829128 -239.934496)
		(width 0.1143)
		(layer "In15.Cu")
		(net "GMI_CPU0_G1_CPU1_G3_TX_DN<14>")
	)
	(segment
		(start 125.687582 -227.961952)
		(end 125.657102 -227.979732)
		(width 0.1143)
		(layer "In15.Cu")
		(net "GMI_CPU0_G1_CPU1_G3_TX_DN<14>")
	)
	(segment
		(start 156.435806 -195.888102)
		(end 156.416756 -196.081142)
		(width 0.14224)
		(layer "In15.Cu")
		(net "GMI_CPU0_G1_CPU1_G3_TX_DN<14>")
	)
	(segment
		(start 345.808046 -236.061504)
		(end 345.807792 -236.061504)
		(width 0.1143)
		(layer "In15.Cu")
		(net "GMI_CPU0_G1_CPU1_G3_TX_DN<14>")
	)
	(segment
		(start 156.765752 -195.617592)
		(end 156.766006 -195.617846)
		(width 0.14224)
		(layer "In15.Cu")
		(net "GMI_CPU0_G1_CPU1_G3_TX_DN<14>")
	)
	(segment
		(start 345.808046 -240.92154)
		(end 345.807792 -240.92154)
		(width 0.1143)
		(layer "In15.Cu")
		(net "GMI_CPU0_G1_CPU1_G3_TX_DN<14>")
	)
	(segment
		(start 158.510478 -194.187318)
		(end 158.180532 -194.457828)
		(width 0.14224)
		(layer "In15.Cu")
		(net "GMI_CPU0_G1_CPU1_G3_TX_DN<14>")
	)
	(segment
		(start 345.774518 -229.562152)
		(end 345.771724 -229.560628)
		(width 0.1143)
		(layer "In15.Cu")
		(net "GMI_CPU0_G1_CPU1_G3_TX_DN<14>")
	)
	(segment
		(start 125.657102 -241.549174)
		(end 125.687582 -241.566954)
		(width 0.1143)
		(layer "In15.Cu")
		(net "GMI_CPU0_G1_CPU1_G3_TX_DN<14>")
	)
	(segment
		(start 125.687582 -234.441746)
		(end 125.657102 -234.459526)
		(width 0.1143)
		(layer "In15.Cu")
		(net "GMI_CPU0_G1_CPU1_G3_TX_DN<14>")
	)
	(segment
		(start 345.810586 -240.923064)
		(end 345.809824 -240.922556)
		(width 0.1143)
		(layer "In15.Cu")
		(net "GMI_CPU0_G1_CPU1_G3_TX_DN<14>")
	)
	(segment
		(start 125.726698 -242.518946)
		(end 125.687582 -242.541806)
		(width 0.1143)
		(layer "In15.Cu")
		(net "GMI_CPU0_G1_CPU1_G3_TX_DN<14>")
	)
	(segment
		(start 303.7332 -190.391796)
		(end 262.765794 -190.013844)
		(width 0.14224)
		(layer "In15.Cu")
		(net "GMI_CPU0_G1_CPU1_G3_TX_DN<14>")
	)
	(segment
		(start 345.812364 -242.544092)
		(end 345.811602 -242.543584)
		(width 0.1143)
		(layer "In15.Cu")
		(net "GMI_CPU0_G1_CPU1_G3_TX_DN<14>")
	)
	(segment
		(start 345.808046 -226.341686)
		(end 345.773248 -226.32162)
		(width 0.1143)
		(layer "In15.Cu")
		(net "GMI_CPU0_G1_CPU1_G3_TX_DN<14>")
	)
	(segment
		(start 125.726698 -224.699068)
		(end 125.687582 -224.721928)
		(width 0.1143)
		(layer "In15.Cu")
		(net "GMI_CPU0_G1_CPU1_G3_TX_DN<14>")
	)
	(segment
		(start 345.841574 -231.22128)
		(end 345.83878 -231.219248)
		(width 0.1143)
		(layer "In15.Cu")
		(net "GMI_CPU0_G1_CPU1_G3_TX_DN<14>")
	)
	(segment
		(start 157.308042 -195.173092)
		(end 157.288992 -195.366132)
		(width 0.14224)
		(layer "In15.Cu")
		(net "GMI_CPU0_G1_CPU1_G3_TX_DN<14>")
	)
	(segment
		(start 345.808808 -227.962206)
		(end 345.808046 -227.961698)
		(width 0.1143)
		(layer "In15.Cu")
		(net "GMI_CPU0_G1_CPU1_G3_TX_DN<14>")
	)
	(segment
		(start 345.81338 -242.5446)
		(end 345.812364 -242.544092)
		(width 0.1143)
		(layer "In15.Cu")
		(net "GMI_CPU0_G1_CPU1_G3_TX_DN<14>")
	)
	(segment
		(start 345.839796 -239.319816)
		(end 345.815412 -239.305846)
		(width 0.1143)
		(layer "In15.Cu")
		(net "GMI_CPU0_G1_CPU1_G3_TX_DN<14>")
	)
	(segment
		(start 157.638242 -194.902582)
		(end 157.308296 -195.173092)
		(width 0.14224)
		(layer "In15.Cu")
		(net "GMI_CPU0_G1_CPU1_G3_TX_DN<14>")
	)
	(segment
		(start 125.687582 -226.9871)
		(end 125.726698 -227.00996)
		(width 0.1143)
		(layer "In15.Cu")
		(net "GMI_CPU0_G1_CPU1_G3_TX_DN<14>")
	)
	(segment
		(start 345.807792 -241.566954)
		(end 345.808046 -241.5667)
		(width 0.1143)
		(layer "In15.Cu")
		(net "GMI_CPU0_G1_CPU1_G3_TX_DN<14>")
	)
	(segment
		(start 125.687582 -239.946942)
		(end 125.726698 -239.969802)
		(width 0.1143)
		(layer "In15.Cu")
		(net "GMI_CPU0_G1_CPU1_G3_TX_DN<14>")
	)
	(segment
		(start 125.499876 -221.248732)
		(end 125.499876 -221.67723)
		(width 0.1143)
		(layer "In15.Cu")
		(net "GMI_CPU0_G1_CPU1_G3_TX_DN<14>")
	)
	(segment
		(start 345.808046 -237.681516)
		(end 345.807792 -237.681516)
		(width 0.1143)
		(layer "In15.Cu")
		(net "GMI_CPU0_G1_CPU1_G3_TX_DN<14>")
	)
	(segment
		(start 345.812618 -228.604064)
		(end 345.813126 -228.604064)
		(width 0.1143)
		(layer "In15.Cu")
		(net "GMI_CPU0_G1_CPU1_G3_TX_DN<14>")
	)
	(segment
		(start 345.829128 -238.314484)
		(end 345.82989 -238.313976)
		(width 0.1143)
		(layer "In15.Cu")
		(net "GMI_CPU0_G1_CPU1_G3_TX_DN<14>")
	)
	(segment
		(start 345.812364 -240.92408)
		(end 345.811602 -240.923572)
		(width 0.1143)
		(layer "In15.Cu")
		(net "GMI_CPU0_G1_CPU1_G3_TX_DN<14>")
	)
	(segment
		(start 155.56357 -196.603366)
		(end 155.54452 -196.796406)
		(width 0.14224)
		(layer "In15.Cu")
		(net "GMI_CPU0_G1_CPU1_G3_TX_DN<14>")
	)
	(segment
		(start 125.506988 -244.414548)
		(end 125.576838 -244.484398)
		(width 0.1143)
		(layer "In15.Cu")
		(net "GMI_CPU0_G1_CPU1_G3_TX_DN<14>")
	)
	(segment
		(start 345.771724 -243.207794)
		(end 345.808046 -243.186712)
		(width 0.1143)
		(layer "In15.Cu")
		(net "GMI_CPU0_G1_CPU1_G3_TX_DN<14>")
	)
	(segment
		(start 345.812364 -237.684056)
		(end 345.811602 -237.683548)
		(width 0.1143)
		(layer "In15.Cu")
		(net "GMI_CPU0_G1_CPU1_G3_TX_DN<14>")
	)
	(segment
		(start 345.80703 -230.227124)
		(end 345.808046 -230.226616)
		(width 0.1143)
		(layer "In15.Cu")
		(net "GMI_CPU0_G1_CPU1_G3_TX_DN<14>")
	)
	(segment
		(start 345.773248 -226.32162)
		(end 345.771724 -226.320604)
		(width 0.1143)
		(layer "In15.Cu")
		(net "GMI_CPU0_G1_CPU1_G3_TX_DN<14>")
	)
	(segment
		(start 344.868246 -224.721674)
		(end 344.82913 -224.698814)
		(width 0.1143)
		(layer "In15.Cu")
		(net "GMI_CPU0_G1_CPU1_G3_TX_DN<14>")
	)
	(segment
		(start 345.807792 -238.32693)
		(end 345.808046 -238.326676)
		(width 0.1143)
		(layer "In15.Cu")
		(net "GMI_CPU0_G1_CPU1_G3_TX_DN<14>")
	)
	(segment
		(start 345.80449 -230.228648)
		(end 345.805506 -230.22814)
		(width 0.1143)
		(layer "In15.Cu")
		(net "GMI_CPU0_G1_CPU1_G3_TX_DN<14>")
	)
	(segment
		(start 125.657102 -235.069126)
		(end 125.687582 -235.086906)
		(width 0.1143)
		(layer "In15.Cu")
		(net "GMI_CPU0_G1_CPU1_G3_TX_DN<14>")
	)
	(segment
		(start 345.82989 -238.313976)
		(end 345.839796 -238.308388)
		(width 0.1143)
		(layer "In15.Cu")
		(net "GMI_CPU0_G1_CPU1_G3_TX_DN<14>")
	)
	(segment
		(start 125.545596 -221.203012)
		(end 125.499876 -221.248732)
		(width 0.1143)
		(layer "In15.Cu")
		(net "GMI_CPU0_G1_CPU1_G3_TX_DN<14>")
	)
	(segment
		(start 125.655578 -222.108776)
		(end 125.687328 -222.127064)
		(width 0.1143)
		(layer "In15.Cu")
		(net "GMI_CPU0_G1_CPU1_G3_TX_DN<14>")
	)
	(segment
		(start 160.25495 -192.757044)
		(end 159.925004 -193.027554)
		(width 0.14224)
		(layer "In15.Cu")
		(net "GMI_CPU0_G1_CPU1_G3_TX_DN<14>")
	)
	(segment
		(start 125.545596 -221.174564)
		(end 125.545596 -221.203012)
		(width 0.1143)
		(layer "In15.Cu")
		(net "GMI_CPU0_G1_CPU1_G3_TX_DN<14>")
	)
	(segment
		(start 345.808046 -238.326676)
		(end 345.829128 -238.314484)
		(width 0.1143)
		(layer "In15.Cu")
		(net "GMI_CPU0_G1_CPU1_G3_TX_DN<14>")
	)
	(segment
		(start 159.575754 -193.491612)
		(end 159.382714 -193.472308)
		(width 0.14224)
		(layer "In15.Cu")
		(net "GMI_CPU0_G1_CPU1_G3_TX_DN<14>")
	)
	(segment
		(start 345.841574 -229.601268)
		(end 345.840812 -229.60076)
		(width 0.1143)
		(layer "In15.Cu")
		(net "GMI_CPU0_G1_CPU1_G3_TX_DN<14>")
	)
	(segment
		(start 345.808808 -237.682024)
		(end 345.808046 -237.681516)
		(width 0.1143)
		(layer "In15.Cu")
		(net "GMI_CPU0_G1_CPU1_G3_TX_DN<14>")
	)
	(segment
		(start 345.814142 -237.685072)
		(end 345.81338 -237.684564)
		(width 0.1143)
		(layer "In15.Cu")
		(net "GMI_CPU0_G1_CPU1_G3_TX_DN<14>")
	)
	(segment
		(start 344.397076 -222.291148)
		(end 344.395552 -222.290132)
		(width 0.1143)
		(layer "In15.Cu")
		(net "GMI_CPU0_G1_CPU1_G3_TX_DN<14>")
	)
	(segment
		(start 125.687582 -228.607112)
		(end 125.726698 -228.629972)
		(width 0.1143)
		(layer "In15.Cu")
		(net "GMI_CPU0_G1_CPU1_G3_TX_DN<14>")
	)
	(segment
		(start 345.829128 -236.694472)
		(end 345.82989 -236.693964)
		(width 0.1143)
		(layer "In15.Cu")
		(net "GMI_CPU0_G1_CPU1_G3_TX_DN<14>")
	)
	(segment
		(start 156.416756 -196.081142)
		(end 156.086556 -196.351906)
		(width 0.14224)
		(layer "In15.Cu")
		(net "GMI_CPU0_G1_CPU1_G3_TX_DN<14>")
	)
	(segment
		(start 345.809824 -236.06252)
		(end 345.808808 -236.062012)
		(width 0.1143)
		(layer "In15.Cu")
		(net "GMI_CPU0_G1_CPU1_G3_TX_DN<14>")
	)
	(segment
		(start 345.808808 -240.922048)
		(end 345.808046 -240.92154)
		(width 0.1143)
		(layer "In15.Cu")
		(net "GMI_CPU0_G1_CPU1_G3_TX_DN<14>")
	)
	(segment
		(start 345.364308 -225.54692)
		(end 345.362022 -225.545396)
		(width 0.1143)
		(layer "In15.Cu")
		(net "GMI_CPU0_G1_CPU1_G3_TX_DN<14>")
	)
	(segment
		(start 125.687582 -226.34194)
		(end 125.657102 -226.35972)
		(width 0.1143)
		(layer "In15.Cu")
		(net "GMI_CPU0_G1_CPU1_G3_TX_DN<14>")
	)
	(segment
		(start 162.653472 -190.4619)
		(end 161.691066 -191.251078)
		(width 0.14224)
		(layer "In15.Cu")
		(net "GMI_CPU0_G1_CPU1_G3_TX_DN<14>")
	)
	(segment
		(start 345.807792 -235.086906)
		(end 345.808046 -235.086652)
		(width 0.1143)
		(layer "In15.Cu")
		(net "GMI_CPU0_G1_CPU1_G3_TX_DN<14>")
	)
	(segment
		(start 125.657102 -225.349308)
		(end 125.687582 -225.367088)
		(width 0.1143)
		(layer "In15.Cu")
		(net "GMI_CPU0_G1_CPU1_G3_TX_DN<14>")
	)
	(segment
		(start 160.44799 -192.776348)
		(end 160.25495 -192.757044)
		(width 0.14224)
		(layer "In15.Cu")
		(net "GMI_CPU0_G1_CPU1_G3_TX_DN<14>")
	)
	(segment
		(start 125.687582 -240.921794)
		(end 125.657102 -240.939574)
		(width 0.1143)
		(layer "In15.Cu")
		(net "GMI_CPU0_G1_CPU1_G3_TX_DN<14>")
	)
	(segment
		(start 160.79724 -192.312544)
		(end 160.77819 -192.505584)
		(width 0.14224)
		(layer "In15.Cu")
		(net "GMI_CPU0_G1_CPU1_G3_TX_DN<14>")
	)
	(segment
		(start 146.974814 -202.350116)
		(end 126.56947 -219.08135)
		(width 0.14224)
		(layer "In15.Cu")
		(net "GMI_CPU0_G1_CPU1_G3_TX_DN<14>")
	)
	(segment
		(start 125.687582 -244.161818)
		(end 125.657102 -244.179598)
		(width 0.1143)
		(layer "In15.Cu")
		(net "GMI_CPU0_G1_CPU1_G3_TX_DN<14>")
	)
	(segment
		(start 125.687582 -236.061758)
		(end 125.657102 -236.079538)
		(width 0.1143)
		(layer "In15.Cu")
		(net "GMI_CPU0_G1_CPU1_G3_TX_DN<14>")
	)
	(segment
		(start 157.308296 -195.173092)
		(end 157.308042 -195.173092)
		(width 0.14224)
		(layer "In15.Cu")
		(net "GMI_CPU0_G1_CPU1_G3_TX_DN<14>")
	)
	(segment
		(start 344.82913 -223.769682)
		(end 344.868246 -223.746822)
		(width 0.1143)
		(layer "In15.Cu")
		(net "GMI_CPU0_G1_CPU1_G3_TX_DN<14>")
	)
	(segment
		(start 126.56947 -219.08135)
		(end 125.545596 -220.88983)
		(width 0.14224)
		(layer "In15.Cu")
		(net "GMI_CPU0_G1_CPU1_G3_TX_DN<14>")
	)
	(segment
		(start 345.829128 -235.07446)
		(end 345.82989 -235.073952)
		(width 0.1143)
		(layer "In15.Cu")
		(net "GMI_CPU0_G1_CPU1_G3_TX_DN<14>")
	)
	(segment
		(start 345.81338 -239.304576)
		(end 345.812364 -239.304068)
		(width 0.1143)
		(layer "In15.Cu")
		(net "GMI_CPU0_G1_CPU1_G3_TX_DN<14>")
	)
	(segment
		(start 157.831282 -194.921886)
		(end 157.638242 -194.902582)
		(width 0.14224)
		(layer "In15.Cu")
		(net "GMI_CPU0_G1_CPU1_G3_TX_DN<14>")
	)
	(segment
		(start 345.82989 -235.073952)
		(end 345.839796 -235.068364)
		(width 0.1143)
		(layer "In15.Cu")
		(net "GMI_CPU0_G1_CPU1_G3_TX_DN<14>")
	)
	(segment
		(start 345.808808 -242.54206)
		(end 345.808046 -242.541552)
		(width 0.1143)
		(layer "In15.Cu")
		(net "GMI_CPU0_G1_CPU1_G3_TX_DN<14>")
	)
	(segment
		(start 345.808808 -243.186204)
		(end 345.810078 -243.185442)
		(width 0.1143)
		(layer "In15.Cu")
		(net "GMI_CPU0_G1_CPU1_G3_TX_DN<14>")
	)
	(segment
		(start 345.808808 -239.302036)
		(end 345.808046 -239.301528)
		(width 0.1143)
		(layer "In15.Cu")
		(net "GMI_CPU0_G1_CPU1_G3_TX_DN<14>")
	)
	(segment
		(start 345.810078 -233.46537)
		(end 345.839796 -233.448352)
		(width 0.1143)
		(layer "In15.Cu")
		(net "GMI_CPU0_G1_CPU1_G3_TX_DN<14>")
	)
	(segment
		(start 345.919044 -244.484144)
		(end 345.988894 -244.414294)
		(width 0.1143)
		(layer "In15.Cu")
		(net "GMI_CPU0_G1_CPU1_G3_TX_DN<14>")
	)
	(segment
		(start 345.808808 -231.84612)
		(end 345.810078 -231.845358)
		(width 0.1143)
		(layer "In15.Cu")
		(net "GMI_CPU0_G1_CPU1_G3_TX_DN<14>")
	)
	(segment
		(start 345.808046 -234.441492)
		(end 345.771724 -234.42041)
		(width 0.1143)
		(layer "In15.Cu")
		(net "GMI_CPU0_G1_CPU1_G3_TX_DN<14>")
	)
	(segment
		(start 125.657102 -231.829102)
		(end 125.687582 -231.846882)
		(width 0.1143)
		(layer "In15.Cu")
		(net "GMI_CPU0_G1_CPU1_G3_TX_DN<14>")
	)
	(segment
		(start 155.89377 -196.332856)
		(end 155.56357 -196.603366)
		(width 0.14224)
		(layer "In15.Cu")
		(net "GMI_CPU0_G1_CPU1_G3_TX_DN<14>")
	)
	(segment
		(start 125.499876 -221.67723)
		(end 125.499622 -221.677484)
		(width 0.1143)
		(layer "In15.Cu")
		(net "GMI_CPU0_G1_CPU1_G3_TX_DN<14>")
	)
	(segment
		(start 344.00998 -220.550232)
		(end 342.35263 -217.04808)
		(width 0.14224)
		(layer "In15.Cu")
		(net "GMI_CPU0_G1_CPU1_G3_TX_DN<14>")
	)
	(segment
		(start 345.81338 -237.684564)
		(end 345.812364 -237.684056)
		(width 0.1143)
		(layer "In15.Cu")
		(net "GMI_CPU0_G1_CPU1_G3_TX_DN<14>")
	)
	(segment
		(start 344.898726 -223.119442)
		(end 344.868246 -223.101662)
		(width 0.1143)
		(layer "In15.Cu")
		(net "GMI_CPU0_G1_CPU1_G3_TX_DN<14>")
	)
	(segment
		(start 345.771724 -231.86771)
		(end 345.808046 -231.846628)
		(width 0.1143)
		(layer "In15.Cu")
		(net "GMI_CPU0_G1_CPU1_G3_TX_DN<14>")
	)
	(segment
		(start 345.83878 -231.219248)
		(end 345.797886 -231.195372)
		(width 0.1143)
		(layer "In15.Cu")
		(net "GMI_CPU0_G1_CPU1_G3_TX_DN<14>")
	)
	(segment
		(start 345.810078 -231.845358)
		(end 345.839796 -231.82834)
		(width 0.1143)
		(layer "In15.Cu")
		(net "GMI_CPU0_G1_CPU1_G3_TX_DN<14>")
	)
	(segment
		(start 155.02128 -197.047866)
		(end 154.691334 -197.318376)
		(width 0.14224)
		(layer "In15.Cu")
		(net "GMI_CPU0_G1_CPU1_G3_TX_DN<14>")
	)
	(segment
		(start 125.657102 -239.929162)
		(end 125.687582 -239.946942)
		(width 0.1143)
		(layer "In15.Cu")
		(net "GMI_CPU0_G1_CPU1_G3_TX_DN<14>")
	)
	(segment
		(start 344.391996 -222.2881)
		(end 344.38971 -222.28683)
		(width 0.1143)
		(layer "In15.Cu")
		(net "GMI_CPU0_G1_CPU1_G3_TX_DN<14>")
	)
	(segment
		(start 345.805506 -230.22814)
		(end 345.80703 -230.227124)
		(width 0.1143)
		(layer "In15.Cu")
		(net "GMI_CPU0_G1_CPU1_G3_TX_DN<14>")
	)
	(segment
		(start 345.814142 -239.305084)
		(end 345.81338 -239.304576)
		(width 0.1143)
		(layer "In15.Cu")
		(net "GMI_CPU0_G1_CPU1_G3_TX_DN<14>")
	)
	(segment
		(start 345.810078 -243.185442)
		(end 345.839796 -243.168424)
		(width 0.1143)
		(layer "In15.Cu")
		(net "GMI_CPU0_G1_CPU1_G3_TX_DN<14>")
	)
	(segment
		(start 345.808046 -235.086652)
		(end 345.829128 -235.07446)
		(width 0.1143)
		(layer "In15.Cu")
		(net "GMI_CPU0_G1_CPU1_G3_TX_DN<14>")
	)
	(segment
		(start 125.726698 -244.138958)
		(end 125.687582 -244.161818)
		(width 0.1143)
		(layer "In15.Cu")
		(net "GMI_CPU0_G1_CPU1_G3_TX_DN<14>")
	)
	(segment
		(start 345.808046 -230.226616)
		(end 345.811856 -230.22433)
		(width 0.1143)
		(layer "In15.Cu")
		(net "GMI_CPU0_G1_CPU1_G3_TX_DN<14>")
	)
	(segment
		(start 125.657102 -226.96932)
		(end 125.687582 -226.9871)
		(width 0.1143)
		(layer "In15.Cu")
		(net "GMI_CPU0_G1_CPU1_G3_TX_DN<14>")
	)
	(segment
		(start 262.765794 -190.013844)
		(end 251.423424 -192.01384)
		(width 0.14224)
		(layer "In15.Cu")
		(net "GMI_CPU0_G1_CPU1_G3_TX_DN<14>")
	)
	(segment
		(start 344.38971 -222.28683)
		(end 344.358976 -222.268796)
		(width 0.1143)
		(layer "In15.Cu")
		(net "GMI_CPU0_G1_CPU1_G3_TX_DN<14>")
	)
	(segment
		(start 345.776042 -230.245158)
		(end 345.80449 -230.228648)
		(width 0.1143)
		(layer "In15.Cu")
		(net "GMI_CPU0_G1_CPU1_G3_TX_DN<14>")
	)
	(segment
		(start 344.395552 -222.290132)
		(end 344.394536 -222.289624)
		(width 0.1143)
		(layer "In15.Cu")
		(net "GMI_CPU0_G1_CPU1_G3_TX_DN<14>")
	)
	(segment
		(start 345.812364 -239.304068)
		(end 345.811602 -239.30356)
		(width 0.1143)
		(layer "In15.Cu")
		(net "GMI_CPU0_G1_CPU1_G3_TX_DN<14>")
	)
	(segment
		(start 345.82989 -239.933988)
		(end 345.839796 -239.9284)
		(width 0.1143)
		(layer "In15.Cu")
		(net "GMI_CPU0_G1_CPU1_G3_TX_DN<14>")
	)
	(segment
		(start 161.691066 -191.251078)
		(end 161.377884 -191.836294)
		(width 0.14224)
		(layer "In15.Cu")
		(net "GMI_CPU0_G1_CPU1_G3_TX_DN<14>")
	)
	(segment
		(start 125.687582 -235.086906)
		(end 125.726698 -235.109766)
		(width 0.1143)
		(layer "In15.Cu")
		(net "GMI_CPU0_G1_CPU1_G3_TX_DN<14>")
	)
	(segment
		(start 154.691334 -197.318376)
		(end 154.672284 -197.511416)
		(width 0.14224)
		(layer "In15.Cu")
		(net "GMI_CPU0_G1_CPU1_G3_TX_DN<14>")
	)
	(segment
		(start 345.809824 -242.542568)
		(end 345.808808 -242.54206)
		(width 0.1143)
		(layer "In15.Cu")
		(net "GMI_CPU0_G1_CPU1_G3_TX_DN<14>")
	)
	(segment
		(start 345.808046 -229.58171)
		(end 345.774518 -229.562152)
		(width 0.1143)
		(layer "In15.Cu")
		(net "GMI_CPU0_G1_CPU1_G3_TX_DN<14>")
	)
	(segment
		(start 125.726698 -237.65891)
		(end 125.687582 -237.68177)
		(width 0.1143)
		(layer "In15.Cu")
		(net "GMI_CPU0_G1_CPU1_G3_TX_DN<14>")
	)
	(segment
		(start 345.808808 -228.60635)
		(end 345.812618 -228.604064)
		(width 0.1143)
		(layer "In15.Cu")
		(net "GMI_CPU0_G1_CPU1_G3_TX_DN<14>")
	)
	(segment
		(start 345.810586 -239.303052)
		(end 345.809824 -239.302544)
		(width 0.1143)
		(layer "In15.Cu")
		(net "GMI_CPU0_G1_CPU1_G3_TX_DN<14>")
	)
	(segment
		(start 156.958792 -195.636896)
		(end 156.765752 -195.617592)
		(width 0.14224)
		(layer "In15.Cu")
		(net "GMI_CPU0_G1_CPU1_G3_TX_DN<14>")
	)
	(segment
		(start 125.687582 -237.68177)
		(end 125.657102 -237.69955)
		(width 0.1143)
		(layer "In15.Cu")
		(net "GMI_CPU0_G1_CPU1_G3_TX_DN<14>")
	)
	(segment
		(start 161.377884 -191.836294)
		(end 160.79724 -192.312544)
		(width 0.14224)
		(layer "In15.Cu")
		(net "GMI_CPU0_G1_CPU1_G3_TX_DN<14>")
	)
	(segment
		(start 345.774518 -230.246174)
		(end 345.776042 -230.245158)
		(width 0.1143)
		(layer "In15.Cu")
		(net "GMI_CPU0_G1_CPU1_G3_TX_DN<14>")
	)
	(segment
		(start 345.829128 -239.934496)
		(end 345.82989 -239.933988)
		(width 0.1143)
		(layer "In15.Cu")
		(net "GMI_CPU0_G1_CPU1_G3_TX_DN<14>")
	)
	(arc
		(start 345.7575 -233.497628)
		(mid 345.764573 -233.492619)
		(end 345.771724 -233.487722)
		(width 0.1143)
		(layer "In15.Cu")
		(net "GMI_CPU0_G1_CPU1_G3_TX_DN<14>")
	)
	(arc
		(start 345.771724 -244.140482)
		(mid 345.763546 -244.134839)
		(end 345.755468 -244.129052)
		(width 0.1143)
		(layer "In15.Cu")
		(net "GMI_CPU0_G1_CPU1_G3_TX_DN<14>")
	)
	(arc
		(start 125.726698 -238.34979)
		(mid 125.970025 -238.814356)
		(end 125.726698 -239.278922)
		(width 0.1143)
		(layer "In15.Cu")
		(net "GMI_CPU0_G1_CPU1_G3_TX_DN<14>")
	)
	(arc
		(start 125.65507 -229.60076)
		(mid 125.541141 -229.733907)
		(end 125.50013 -229.90429)
		(width 0.1143)
		(layer "In15.Cu")
		(net "GMI_CPU0_G1_CPU1_G3_TX_DN<14>")
	)
	(arc
		(start 345.755468 -232.788968)
		(mid 345.532584 -232.334054)
		(end 345.755468 -231.87914)
		(width 0.1143)
		(layer "In15.Cu")
		(net "GMI_CPU0_G1_CPU1_G3_TX_DN<14>")
	)
	(arc
		(start 345.755468 -227.019358)
		(mid 345.763546 -227.013572)
		(end 345.771724 -227.007928)
		(width 0.1143)
		(layer "In15.Cu")
		(net "GMI_CPU0_G1_CPU1_G3_TX_DN<14>")
	)
	(arc
		(start 345.7575 -234.410504)
		(mid 345.530117 -233.954066)
		(end 345.7575 -233.497628)
		(width 0.1143)
		(layer "In15.Cu")
		(net "GMI_CPU0_G1_CPU1_G3_TX_DN<14>")
	)
	(arc
		(start 125.657102 -227.979732)
		(mid 125.500125 -228.284532)
		(end 125.657102 -228.589332)
		(width 0.1143)
		(layer "In15.Cu")
		(net "GMI_CPU0_G1_CPU1_G3_TX_DN<14>")
	)
	(arc
		(start 345.771724 -229.560628)
		(mid 345.764958 -229.555851)
		(end 345.758262 -229.550976)
		(width 0.1143)
		(layer "In15.Cu")
		(net "GMI_CPU0_G1_CPU1_G3_TX_DN<14>")
	)
	(arc
		(start 345.755468 -227.929186)
		(mid 345.532584 -227.474272)
		(end 345.755468 -227.019358)
		(width 0.1143)
		(layer "In15.Cu")
		(net "GMI_CPU0_G1_CPU1_G3_TX_DN<14>")
	)
	(arc
		(start 345.755468 -243.219224)
		(mid 345.763546 -243.213438)
		(end 345.771724 -243.207794)
		(width 0.1143)
		(layer "In15.Cu")
		(net "GMI_CPU0_G1_CPU1_G3_TX_DN<14>")
	)
	(arc
		(start 345.807792 -236.061504)
		(mid 345.527365 -235.574268)
		(end 345.807792 -235.086906)
		(width 0.1143)
		(layer "In15.Cu")
		(net "GMI_CPU0_G1_CPU1_G3_TX_DN<14>")
	)
	(arc
		(start 345.839796 -238.308388)
		(mid 345.995724 -238.004096)
		(end 345.839796 -237.699804)
		(width 0.1143)
		(layer "In15.Cu")
		(net "GMI_CPU0_G1_CPU1_G3_TX_DN<14>")
	)
	(arc
		(start 125.50013 -229.90429)
		(mid 125.541679 -230.075712)
		(end 125.657102 -230.20909)
		(width 0.1143)
		(layer "In15.Cu")
		(net "GMI_CPU0_G1_CPU1_G3_TX_DN<14>")
	)
	(arc
		(start 345.839796 -236.688376)
		(mid 345.995724 -236.384084)
		(end 345.839796 -236.079792)
		(width 0.1143)
		(layer "In15.Cu")
		(net "GMI_CPU0_G1_CPU1_G3_TX_DN<14>")
	)
	(arc
		(start 125.726698 -235.109766)
		(mid 125.970025 -235.574332)
		(end 125.726698 -236.038898)
		(width 0.1143)
		(layer "In15.Cu")
		(net "GMI_CPU0_G1_CPU1_G3_TX_DN<14>")
	)
	(arc
		(start 125.726698 -223.769936)
		(mid 125.970025 -224.234502)
		(end 125.726698 -224.699068)
		(width 0.1143)
		(layer "In15.Cu")
		(net "GMI_CPU0_G1_CPU1_G3_TX_DN<14>")
	)
	(arc
		(start 345.807792 -242.541552)
		(mid 345.527365 -242.054316)
		(end 345.807792 -241.566954)
		(width 0.1143)
		(layer "In15.Cu")
		(net "GMI_CPU0_G1_CPU1_G3_TX_DN<14>")
	)
	(arc
		(start 125.727714 -222.150686)
		(mid 125.905779 -222.352863)
		(end 125.97003 -222.61449)
		(width 0.1143)
		(layer "In15.Cu")
		(net "GMI_CPU0_G1_CPU1_G3_TX_DN<14>")
	)
	(arc
		(start 344.898726 -223.729042)
		(mid 345.055703 -223.424242)
		(end 344.898726 -223.119442)
		(width 0.1143)
		(layer "In15.Cu")
		(net "GMI_CPU0_G1_CPU1_G3_TX_DN<14>")
	)
	(arc
		(start 345.807792 -237.681516)
		(mid 345.527365 -237.19428)
		(end 345.807792 -236.706918)
		(width 0.1143)
		(layer "In15.Cu")
		(net "GMI_CPU0_G1_CPU1_G3_TX_DN<14>")
	)
	(arc
		(start 345.839796 -233.448352)
		(mid 345.995724 -233.14406)
		(end 345.839796 -232.839768)
		(width 0.1143)
		(layer "In15.Cu")
		(net "GMI_CPU0_G1_CPU1_G3_TX_DN<14>")
	)
	(arc
		(start 345.055698 -225.044254)
		(mid 345.014149 -224.872832)
		(end 344.898726 -224.739454)
		(width 0.1143)
		(layer "In15.Cu")
		(net "GMI_CPU0_G1_CPU1_G3_TX_DN<14>")
	)
	(arc
		(start 345.525852 -230.710486)
		(mid 345.589609 -230.457323)
		(end 345.757754 -230.257604)
		(width 0.1143)
		(layer "In15.Cu")
		(net "GMI_CPU0_G1_CPU1_G3_TX_DN<14>")
	)
	(arc
		(start 345.839796 -226.968558)
		(mid 345.995724 -226.664266)
		(end 345.839796 -226.359974)
		(width 0.1143)
		(layer "In15.Cu")
		(net "GMI_CPU0_G1_CPU1_G3_TX_DN<14>")
	)
	(arc
		(start 345.807792 -240.92154)
		(mid 345.527365 -240.434304)
		(end 345.807792 -239.946942)
		(width 0.1143)
		(layer "In15.Cu")
		(net "GMI_CPU0_G1_CPU1_G3_TX_DN<14>")
	)
	(arc
		(start 345.839796 -241.548412)
		(mid 345.995724 -241.24412)
		(end 345.839796 -240.939828)
		(width 0.1143)
		(layer "In15.Cu")
		(net "GMI_CPU0_G1_CPU1_G3_TX_DN<14>")
	)
	(arc
		(start 125.726698 -243.209826)
		(mid 125.970025 -243.674392)
		(end 125.726698 -244.138958)
		(width 0.1143)
		(layer "In15.Cu")
		(net "GMI_CPU0_G1_CPU1_G3_TX_DN<14>")
	)
	(arc
		(start 125.97003 -222.61449)
		(mid 125.905515 -222.876709)
		(end 125.726698 -223.079056)
		(width 0.1143)
		(layer "In15.Cu")
		(net "GMI_CPU0_G1_CPU1_G3_TX_DN<14>")
	)
	(arc
		(start 125.657102 -244.179598)
		(mid 125.559337 -244.282574)
		(end 125.506988 -244.414548)
		(width 0.1143)
		(layer "In15.Cu")
		(net "GMI_CPU0_G1_CPU1_G3_TX_DN<14>")
	)
	(arc
		(start 125.657102 -236.079538)
		(mid 125.500125 -236.384338)
		(end 125.657102 -236.689138)
		(width 0.1143)
		(layer "In15.Cu")
		(net "GMI_CPU0_G1_CPU1_G3_TX_DN<14>")
	)
	(arc
		(start 344.358976 -222.268796)
		(mid 344.286649 -222.209329)
		(end 344.225118 -222.138748)
		(width 0.1143)
		(layer "In15.Cu")
		(net "GMI_CPU0_G1_CPU1_G3_TX_DN<14>")
	)
	(arc
		(start 345.839796 -239.9284)
		(mid 345.995724 -239.624108)
		(end 345.839796 -239.319816)
		(width 0.1143)
		(layer "In15.Cu")
		(net "GMI_CPU0_G1_CPU1_G3_TX_DN<14>")
	)
	(arc
		(start 345.797886 -231.195372)
		(mid 345.595822 -230.989975)
		(end 345.525852 -230.710486)
		(width 0.1143)
		(layer "In15.Cu")
		(net "GMI_CPU0_G1_CPU1_G3_TX_DN<14>")
	)
	(arc
		(start 125.50013 -231.524302)
		(mid 125.541679 -231.695724)
		(end 125.657102 -231.829102)
		(width 0.1143)
		(layer "In15.Cu")
		(net "GMI_CPU0_G1_CPU1_G3_TX_DN<14>")
	)
	(arc
		(start 125.499622 -221.804484)
		(mid 125.540877 -221.975455)
		(end 125.655578 -222.108776)
		(width 0.1143)
		(layer "In15.Cu")
		(net "GMI_CPU0_G1_CPU1_G3_TX_DN<14>")
	)
	(arc
		(start 345.525852 -225.870262)
		(mid 345.524477 -225.848449)
		(end 345.52128 -225.826828)
		(width 0.1143)
		(layer "In15.Cu")
		(net "GMI_CPU0_G1_CPU1_G3_TX_DN<14>")
	)
	(arc
		(start 125.657102 -237.69955)
		(mid 125.500125 -238.00435)
		(end 125.657102 -238.30915)
		(width 0.1143)
		(layer "In15.Cu")
		(net "GMI_CPU0_G1_CPU1_G3_TX_DN<14>")
	)
	(arc
		(start 345.839796 -243.168424)
		(mid 345.995724 -242.864132)
		(end 345.839796 -242.55984)
		(width 0.1143)
		(layer "In15.Cu")
		(net "GMI_CPU0_G1_CPU1_G3_TX_DN<14>")
	)
	(arc
		(start 345.807792 -239.301528)
		(mid 345.527365 -238.814292)
		(end 345.807792 -238.32693)
		(width 0.1143)
		(layer "In15.Cu")
		(net "GMI_CPU0_G1_CPU1_G3_TX_DN<14>")
	)
	(arc
		(start 125.726698 -225.389948)
		(mid 125.970025 -225.854514)
		(end 125.726698 -226.31908)
		(width 0.1143)
		(layer "In15.Cu")
		(net "GMI_CPU0_G1_CPU1_G3_TX_DN<14>")
	)
	(arc
		(start 125.726698 -239.969802)
		(mid 125.970025 -240.434368)
		(end 125.726698 -240.898934)
		(width 0.1143)
		(layer "In15.Cu")
		(net "GMI_CPU0_G1_CPU1_G3_TX_DN<14>")
	)
	(arc
		(start 345.771724 -232.800398)
		(mid 345.763546 -232.794755)
		(end 345.755468 -232.788968)
		(width 0.1143)
		(layer "In15.Cu")
		(net "GMI_CPU0_G1_CPU1_G3_TX_DN<14>")
	)
	(arc
		(start 345.29903 -225.50882)
		(mid 345.120217 -225.30647)
		(end 345.055698 -225.044254)
		(width 0.1143)
		(layer "In15.Cu")
		(net "GMI_CPU0_G1_CPU1_G3_TX_DN<14>")
	)
	(arc
		(start 345.755468 -231.87914)
		(mid 345.763546 -231.873354)
		(end 345.771724 -231.86771)
		(width 0.1143)
		(layer "In15.Cu")
		(net "GMI_CPU0_G1_CPU1_G3_TX_DN<14>")
	)
	(arc
		(start 345.52128 -225.826828)
		(mid 345.468396 -225.679618)
		(end 345.374468 -225.55454)
		(width 0.1143)
		(layer "In15.Cu")
		(net "GMI_CPU0_G1_CPU1_G3_TX_DN<14>")
	)
	(arc
		(start 125.726698 -233.489754)
		(mid 125.970025 -233.95432)
		(end 125.726698 -234.418886)
		(width 0.1143)
		(layer "In15.Cu")
		(net "GMI_CPU0_G1_CPU1_G3_TX_DN<14>")
	)
	(arc
		(start 345.839796 -230.208328)
		(mid 345.954472 -230.074994)
		(end 345.995752 -229.904036)
		(width 0.1143)
		(layer "In15.Cu")
		(net "GMI_CPU0_G1_CPU1_G3_TX_DN<14>")
	)
	(arc
		(start 125.657102 -242.559586)
		(mid 125.500125 -242.864386)
		(end 125.657102 -243.169186)
		(width 0.1143)
		(layer "In15.Cu")
		(net "GMI_CPU0_G1_CPU1_G3_TX_DN<14>")
	)
	(arc
		(start 125.657102 -223.119696)
		(mid 125.500125 -223.424496)
		(end 125.657102 -223.729296)
		(width 0.1143)
		(layer "In15.Cu")
		(net "GMI_CPU0_G1_CPU1_G3_TX_DN<14>")
	)
	(arc
		(start 125.726698 -227.00996)
		(mid 125.970025 -227.474526)
		(end 125.726698 -227.939092)
		(width 0.1143)
		(layer "In15.Cu")
		(net "GMI_CPU0_G1_CPU1_G3_TX_DN<14>")
	)
	(arc
		(start 344.82913 -224.698814)
		(mid 344.585803 -224.234248)
		(end 344.82913 -223.769682)
		(width 0.1143)
		(layer "In15.Cu")
		(net "GMI_CPU0_G1_CPU1_G3_TX_DN<14>")
	)
	(arc
		(start 125.657102 -234.459526)
		(mid 125.500125 -234.764326)
		(end 125.657102 -235.069126)
		(width 0.1143)
		(layer "In15.Cu")
		(net "GMI_CPU0_G1_CPU1_G3_TX_DN<14>")
	)
	(arc
		(start 344.82913 -223.078802)
		(mid 344.650317 -222.876452)
		(end 344.585798 -222.614236)
		(width 0.1143)
		(layer "In15.Cu")
		(net "GMI_CPU0_G1_CPU1_G3_TX_DN<14>")
	)
	(arc
		(start 125.65507 -231.220772)
		(mid 125.541141 -231.353919)
		(end 125.50013 -231.524302)
		(width 0.1143)
		(layer "In15.Cu")
		(net "GMI_CPU0_G1_CPU1_G3_TX_DN<14>")
	)
	(arc
		(start 345.839796 -228.58857)
		(mid 345.995724 -228.284278)
		(end 345.839796 -227.979986)
		(width 0.1143)
		(layer "In15.Cu")
		(net "GMI_CPU0_G1_CPU1_G3_TX_DN<14>")
	)
	(arc
		(start 345.839796 -231.82834)
		(mid 345.954472 -231.695006)
		(end 345.995752 -231.524048)
		(width 0.1143)
		(layer "In15.Cu")
		(net "GMI_CPU0_G1_CPU1_G3_TX_DN<14>")
	)
	(arc
		(start 345.758262 -229.550976)
		(mid 345.587292 -229.350499)
		(end 345.525852 -229.094284)
		(width 0.1143)
		(layer "In15.Cu")
		(net "GMI_CPU0_G1_CPU1_G3_TX_DN<14>")
	)
	(arc
		(start 125.657102 -226.35972)
		(mid 125.500125 -226.66452)
		(end 125.657102 -226.96932)
		(width 0.1143)
		(layer "In15.Cu")
		(net "GMI_CPU0_G1_CPU1_G3_TX_DN<14>")
	)
	(arc
		(start 125.657102 -232.839514)
		(mid 125.500125 -233.144314)
		(end 125.657102 -233.449114)
		(width 0.1143)
		(layer "In15.Cu")
		(net "GMI_CPU0_G1_CPU1_G3_TX_DN<14>")
	)
	(arc
		(start 345.771724 -234.42041)
		(mid 345.764574 -234.415512)
		(end 345.7575 -234.410504)
		(width 0.1143)
		(layer "In15.Cu")
		(net "GMI_CPU0_G1_CPU1_G3_TX_DN<14>")
	)
	(arc
		(start 345.374468 -225.55454)
		(mid 345.369924 -225.550949)
		(end 345.365324 -225.547428)
		(width 0.1143)
		(layer "In15.Cu")
		(net "GMI_CPU0_G1_CPU1_G3_TX_DN<14>")
	)
	(arc
		(start 345.771724 -227.940616)
		(mid 345.763546 -227.934973)
		(end 345.755468 -227.929186)
		(width 0.1143)
		(layer "In15.Cu")
		(net "GMI_CPU0_G1_CPU1_G3_TX_DN<14>")
	)
	(arc
		(start 345.757754 -230.257604)
		(mid 345.766084 -230.251813)
		(end 345.774518 -230.246174)
		(width 0.1143)
		(layer "In15.Cu")
		(net "GMI_CPU0_G1_CPU1_G3_TX_DN<14>")
	)
	(arc
		(start 345.839796 -235.068364)
		(mid 345.995724 -234.764072)
		(end 345.839796 -234.45978)
		(width 0.1143)
		(layer "In15.Cu")
		(net "GMI_CPU0_G1_CPU1_G3_TX_DN<14>")
	)
	(arc
		(start 125.657102 -240.939574)
		(mid 125.500125 -241.244374)
		(end 125.657102 -241.549174)
		(width 0.1143)
		(layer "In15.Cu")
		(net "GMI_CPU0_G1_CPU1_G3_TX_DN<14>")
	)
	(arc
		(start 344.585798 -222.614236)
		(mid 344.544543 -222.443265)
		(end 344.429842 -222.309944)
		(width 0.1143)
		(layer "In15.Cu")
		(net "GMI_CPU0_G1_CPU1_G3_TX_DN<14>")
	)
	(arc
		(start 345.771724 -226.320604)
		(mid 345.594824 -226.125041)
		(end 345.525852 -225.870516)
		(width 0.1143)
		(layer "In15.Cu")
		(net "GMI_CPU0_G1_CPU1_G3_TX_DN<14>")
	)
	(arc
		(start 344.225118 -222.138748)
		(mid 344.143827 -221.980201)
		(end 344.115898 -221.80423)
		(width 0.1143)
		(layer "In15.Cu")
		(net "GMI_CPU0_G1_CPU1_G3_TX_DN<14>")
	)
	(arc
		(start 345.988894 -244.414294)
		(mid 345.936845 -244.282775)
		(end 345.839796 -244.179852)
		(width 0.1143)
		(layer "In15.Cu")
		(net "GMI_CPU0_G1_CPU1_G3_TX_DN<14>")
	)
	(arc
		(start 345.995752 -231.524048)
		(mid 345.95499 -231.354164)
		(end 345.841574 -231.22128)
		(width 0.1143)
		(layer "In15.Cu")
		(net "GMI_CPU0_G1_CPU1_G3_TX_DN<14>")
	)
	(arc
		(start 125.726698 -236.729778)
		(mid 125.970025 -237.194344)
		(end 125.726698 -237.65891)
		(width 0.1143)
		(layer "In15.Cu")
		(net "GMI_CPU0_G1_CPU1_G3_TX_DN<14>")
	)
	(arc
		(start 125.97003 -230.71455)
		(mid 125.905515 -230.976769)
		(end 125.726698 -231.179116)
		(width 0.1143)
		(layer "In15.Cu")
		(net "GMI_CPU0_G1_CPU1_G3_TX_DN<14>")
	)
	(arc
		(start 345.995752 -229.904036)
		(mid 345.95499 -229.734152)
		(end 345.841574 -229.601268)
		(width 0.1143)
		(layer "In15.Cu")
		(net "GMI_CPU0_G1_CPU1_G3_TX_DN<14>")
	)
	(arc
		(start 125.726698 -231.869742)
		(mid 125.970025 -232.334308)
		(end 125.726698 -232.798874)
		(width 0.1143)
		(layer "In15.Cu")
		(net "GMI_CPU0_G1_CPU1_G3_TX_DN<14>")
	)
	(arc
		(start 125.726698 -241.589814)
		(mid 125.970025 -242.05438)
		(end 125.726698 -242.518946)
		(width 0.1143)
		(layer "In15.Cu")
		(net "GMI_CPU0_G1_CPU1_G3_TX_DN<14>")
	)
	(arc
		(start 345.525852 -229.094284)
		(mid 345.601433 -228.812642)
		(end 345.808046 -228.606858)
		(width 0.1143)
		(layer "In15.Cu")
		(net "GMI_CPU0_G1_CPU1_G3_TX_DN<14>")
	)
	(arc
		(start 125.726698 -228.629972)
		(mid 125.970025 -229.094538)
		(end 125.726698 -229.559104)
		(width 0.1143)
		(layer "In15.Cu")
		(net "GMI_CPU0_G1_CPU1_G3_TX_DN<14>")
	)
	(arc
		(start 125.657102 -239.319562)
		(mid 125.500125 -239.624362)
		(end 125.657102 -239.929162)
		(width 0.1143)
		(layer "In15.Cu")
		(net "GMI_CPU0_G1_CPU1_G3_TX_DN<14>")
	)
	(arc
		(start 125.724158 -230.248206)
		(mid 125.90481 -230.450951)
		(end 125.97003 -230.71455)
		(width 0.1143)
		(layer "In15.Cu")
		(net "GMI_CPU0_G1_CPU1_G3_TX_DN<14>")
	)
	(arc
		(start 125.657102 -224.739708)
		(mid 125.500125 -225.044508)
		(end 125.657102 -225.349308)
		(width 0.1143)
		(layer "In15.Cu")
		(net "GMI_CPU0_G1_CPU1_G3_TX_DN<14>")
	)
	(arc
		(start 345.755468 -244.129052)
		(mid 345.532584 -243.674138)
		(end 345.755468 -243.219224)
		(width 0.1143)
		(layer "In15.Cu")
		(net "GMI_CPU0_G1_CPU1_G3_TX_DN<14>")
	)
	(segment
		(start 346.087954 -247.990106)
		(end 345.621102 -247.724168)
		(width 0.12954)
		(layer "F.Cu")
		(net "GMI_CPU0_G1_CPU1_G3_TX_DN<13>")
	)
	(segment
		(start 125.407928 -247.99036)
		(end 125.87478 -247.724422)
		(width 0.12954)
		(layer "F.Cu")
		(net "GMI_CPU0_G1_CPU1_G3_TX_DN<13>")
	)
	(segment
		(start 124.746512 -235.086144)
		(end 124.747782 -235.086906)
		(width 0.1143)
		(layer "In15.Cu")
		(net "GMI_CPU0_G1_CPU1_G3_TX_DN<13>")
	)
	(segment
		(start 124.74448 -242.543584)
		(end 124.743718 -242.544092)
		(width 0.1143)
		(layer "In15.Cu")
		(net "GMI_CPU0_G1_CPU1_G3_TX_DN<13>")
	)
	(segment
		(start 124.726446 -239.935512)
		(end 124.727208 -239.93602)
		(width 0.1143)
		(layer "In15.Cu")
		(net "GMI_CPU0_G1_CPU1_G3_TX_DN<13>")
	)
	(segment
		(start 124.716032 -235.068618)
		(end 124.746512 -235.086144)
		(width 0.1143)
		(layer "In15.Cu")
		(net "GMI_CPU0_G1_CPU1_G3_TX_DN<13>")
	)
	(segment
		(start 346.77985 -226.359974)
		(end 346.748862 -226.342194)
		(width 0.1143)
		(layer "In15.Cu")
		(net "GMI_CPU0_G1_CPU1_G3_TX_DN<13>")
	)
	(segment
		(start 124.74702 -223.746568)
		(end 124.747782 -223.747076)
		(width 0.1143)
		(layer "In15.Cu")
		(net "GMI_CPU0_G1_CPU1_G3_TX_DN<13>")
	)
	(segment
		(start 345.811602 -223.74479)
		(end 345.812872 -223.744028)
		(width 0.1143)
		(layer "In15.Cu")
		(net "GMI_CPU0_G1_CPU1_G3_TX_DN<13>")
	)
	(segment
		(start 157.045914 -194.172586)
		(end 156.852874 -194.153536)
		(width 0.14224)
		(layer "In15.Cu")
		(net "GMI_CPU0_G1_CPU1_G3_TX_DN<13>")
	)
	(segment
		(start 346.747084 -238.327184)
		(end 346.7481 -238.326676)
		(width 0.1143)
		(layer "In15.Cu")
		(net "GMI_CPU0_G1_CPU1_G3_TX_DN<13>")
	)
	(segment
		(start 124.750576 -241.568732)
		(end 124.787152 -241.589814)
		(width 0.1143)
		(layer "In15.Cu")
		(net "GMI_CPU0_G1_CPU1_G3_TX_DN<13>")
	)
	(segment
		(start 124.747782 -236.061758)
		(end 124.716032 -236.080046)
		(width 0.1143)
		(layer "In15.Cu")
		(net "GMI_CPU0_G1_CPU1_G3_TX_DN<13>")
	)
	(segment
		(start 124.747782 -246.42699)
		(end 124.762006 -246.435118)
		(width 0.1143)
		(layer "In15.Cu")
		(net "GMI_CPU0_G1_CPU1_G3_TX_DN<13>")
	)
	(segment
		(start 346.750132 -241.56543)
		(end 346.77985 -241.548412)
		(width 0.1143)
		(layer "In15.Cu")
		(net "GMI_CPU0_G1_CPU1_G3_TX_DN<13>")
	)
	(segment
		(start 345.00058 -221.38767)
		(end 345.00058 -221.128844)
		(width 0.1143)
		(layer "In15.Cu")
		(net "GMI_CPU0_G1_CPU1_G3_TX_DN<13>")
	)
	(segment
		(start 346.7481 -244.161564)
		(end 346.747084 -244.161056)
		(width 0.1143)
		(layer "In15.Cu")
		(net "GMI_CPU0_G1_CPU1_G3_TX_DN<13>")
	)
	(segment
		(start 346.747084 -232.820972)
		(end 346.74556 -232.819956)
		(width 0.1143)
		(layer "In15.Cu")
		(net "GMI_CPU0_G1_CPU1_G3_TX_DN<13>")
	)
	(segment
		(start 124.74321 -233.464354)
		(end 124.74575 -233.465624)
		(width 0.1143)
		(layer "In15.Cu")
		(net "GMI_CPU0_G1_CPU1_G3_TX_DN<13>")
	)
	(segment
		(start 346.748862 -239.302036)
		(end 346.7481 -239.301528)
		(width 0.1143)
		(layer "In15.Cu")
		(net "GMI_CPU0_G1_CPU1_G3_TX_DN<13>")
	)
	(segment
		(start 346.7481 -237.681516)
		(end 346.747084 -237.681008)
		(width 0.1143)
		(layer "In15.Cu")
		(net "GMI_CPU0_G1_CPU1_G3_TX_DN<13>")
	)
	(segment
		(start 124.74321 -243.184426)
		(end 124.74575 -243.185696)
		(width 0.1143)
		(layer "In15.Cu")
		(net "GMI_CPU0_G1_CPU1_G3_TX_DN<13>")
	)
	(segment
		(start 346.74556 -245.780052)
		(end 346.708984 -245.758716)
		(width 0.1143)
		(layer "In15.Cu")
		(net "GMI_CPU0_G1_CPU1_G3_TX_DN<13>")
	)
	(segment
		(start 346.781628 -231.22128)
		(end 346.7481 -231.201722)
		(width 0.1143)
		(layer "In15.Cu")
		(net "GMI_CPU0_G1_CPU1_G3_TX_DN<13>")
	)
	(segment
		(start 346.748862 -232.821988)
		(end 346.7481 -232.82148)
		(width 0.1143)
		(layer "In15.Cu")
		(net "GMI_CPU0_G1_CPU1_G3_TX_DN<13>")
	)
	(segment
		(start 345.83243 -223.732598)
		(end 345.834462 -223.731582)
		(width 0.1143)
		(layer "In15.Cu")
		(net "GMI_CPU0_G1_CPU1_G3_TX_DN<13>")
	)
	(segment
		(start 344.95486 -221.083124)
		(end 344.95486 -220.331538)
		(width 0.14224)
		(layer "In15.Cu")
		(net "GMI_CPU0_G1_CPU1_G3_TX_DN<13>")
	)
	(segment
		(start 346.750132 -233.46537)
		(end 346.77985 -233.448352)
		(width 0.1143)
		(layer "In15.Cu")
		(net "GMI_CPU0_G1_CPU1_G3_TX_DN<13>")
	)
	(segment
		(start 124.750322 -243.188744)
		(end 124.787406 -243.209826)
		(width 0.1143)
		(layer "In15.Cu")
		(net "GMI_CPU0_G1_CPU1_G3_TX_DN<13>")
	)
	(segment
		(start 346.747084 -234.440984)
		(end 346.74556 -234.439968)
		(width 0.1143)
		(layer "In15.Cu")
		(net "GMI_CPU0_G1_CPU1_G3_TX_DN<13>")
	)
	(segment
		(start 124.716032 -225.3488)
		(end 124.741686 -225.363532)
		(width 0.1143)
		(layer "In15.Cu")
		(net "GMI_CPU0_G1_CPU1_G3_TX_DN<13>")
	)
	(segment
		(start 124.787406 -243.209826)
		(end 124.806456 -243.223796)
		(width 0.1143)
		(layer "In15.Cu")
		(net "GMI_CPU0_G1_CPU1_G3_TX_DN<13>")
	)
	(segment
		(start 345.831668 -223.733106)
		(end 345.83243 -223.732598)
		(width 0.1143)
		(layer "In15.Cu")
		(net "GMI_CPU0_G1_CPU1_G3_TX_DN<13>")
	)
	(segment
		(start 346.7481 -245.781576)
		(end 346.747084 -245.781068)
		(width 0.1143)
		(layer "In15.Cu")
		(net "GMI_CPU0_G1_CPU1_G3_TX_DN<13>")
	)
	(segment
		(start 124.745496 -242.543076)
		(end 124.74448 -242.543584)
		(width 0.1143)
		(layer "In15.Cu")
		(net "GMI_CPU0_G1_CPU1_G3_TX_DN<13>")
	)
	(segment
		(start 206.99222 -189.289944)
		(end 162.355022 -189.479428)
		(width 0.14224)
		(layer "In15.Cu")
		(net "GMI_CPU0_G1_CPU1_G3_TX_DN<13>")
	)
	(segment
		(start 124.715016 -231.221026)
		(end 124.714254 -231.221534)
		(width 0.1143)
		(layer "In15.Cu")
		(net "GMI_CPU0_G1_CPU1_G3_TX_DN<13>")
	)
	(segment
		(start 124.74575 -226.98583)
		(end 124.74702 -226.986592)
		(width 0.1143)
		(layer "In15.Cu")
		(net "GMI_CPU0_G1_CPU1_G3_TX_DN<13>")
	)
	(segment
		(start 346.708984 -233.4895)
		(end 346.747084 -233.467148)
		(width 0.1143)
		(layer "In15.Cu")
		(net "GMI_CPU0_G1_CPU1_G3_TX_DN<13>")
	)
	(segment
		(start 346.754196 -228.603302)
		(end 346.757752 -228.601016)
		(width 0.1143)
		(layer "In15.Cu")
		(net "GMI_CPU0_G1_CPU1_G3_TX_DN<13>")
	)
	(segment
		(start 346.750132 -236.705394)
		(end 346.77985 -236.688376)
		(width 0.1143)
		(layer "In15.Cu")
		(net "GMI_CPU0_G1_CPU1_G3_TX_DN<13>")
	)
	(segment
		(start 346.748862 -243.186204)
		(end 346.750132 -243.185442)
		(width 0.1143)
		(layer "In15.Cu")
		(net "GMI_CPU0_G1_CPU1_G3_TX_DN<13>")
	)
	(segment
		(start 346.748862 -244.162072)
		(end 346.7481 -244.161564)
		(width 0.1143)
		(layer "In15.Cu")
		(net "GMI_CPU0_G1_CPU1_G3_TX_DN<13>")
	)
	(segment
		(start 124.741686 -246.423434)
		(end 124.74321 -246.42445)
		(width 0.1143)
		(layer "In15.Cu")
		(net "GMI_CPU0_G1_CPU1_G3_TX_DN<13>")
	)
	(segment
		(start 124.787152 -226.31908)
		(end 124.746258 -226.342702)
		(width 0.1143)
		(layer "In15.Cu")
		(net "GMI_CPU0_G1_CPU1_G3_TX_DN<13>")
	)
	(segment
		(start 124.74575 -231.845612)
		(end 124.74702 -231.846374)
		(width 0.1143)
		(layer "In15.Cu")
		(net "GMI_CPU0_G1_CPU1_G3_TX_DN<13>")
	)
	(segment
		(start 158.24835 -193.186558)
		(end 157.91815 -193.457322)
		(width 0.14224)
		(layer "In15.Cu")
		(net "GMI_CPU0_G1_CPU1_G3_TX_DN<13>")
	)
	(segment
		(start 346.748862 -235.086144)
		(end 346.750132 -235.085382)
		(width 0.1143)
		(layer "In15.Cu")
		(net "GMI_CPU0_G1_CPU1_G3_TX_DN<13>")
	)
	(segment
		(start 346.750132 -239.945418)
		(end 346.77985 -239.9284)
		(width 0.1143)
		(layer "In15.Cu")
		(net "GMI_CPU0_G1_CPU1_G3_TX_DN<13>")
	)
	(segment
		(start 160.855406 -190.70955)
		(end 160.700466 -190.998348)
		(width 0.14224)
		(layer "In15.Cu")
		(net "GMI_CPU0_G1_CPU1_G3_TX_DN<13>")
	)
	(segment
		(start 124.78766 -231.869742)
		(end 124.802138 -231.880664)
		(width 0.1143)
		(layer "In15.Cu")
		(net "GMI_CPU0_G1_CPU1_G3_TX_DN<13>")
	)
	(segment
		(start 124.74575 -224.723198)
		(end 124.716032 -224.740216)
		(width 0.1143)
		(layer "In15.Cu")
		(net "GMI_CPU0_G1_CPU1_G3_TX_DN<13>")
	)
	(segment
		(start 345.816174 -223.741996)
		(end 345.817952 -223.74098)
		(width 0.1143)
		(layer "In15.Cu")
		(net "GMI_CPU0_G1_CPU1_G3_TX_DN<13>")
	)
	(segment
		(start 155.980638 -194.8688)
		(end 155.650692 -195.13931)
		(width 0.14224)
		(layer "In15.Cu")
		(net "GMI_CPU0_G1_CPU1_G3_TX_DN<13>")
	)
	(segment
		(start 124.750576 -223.748854)
		(end 124.786644 -223.769682)
		(width 0.1143)
		(layer "In15.Cu")
		(net "GMI_CPU0_G1_CPU1_G3_TX_DN<13>")
	)
	(segment
		(start 157.395164 -193.708274)
		(end 157.395164 -193.708782)
		(width 0.14224)
		(layer "In15.Cu")
		(net "GMI_CPU0_G1_CPU1_G3_TX_DN<13>")
	)
	(segment
		(start 262.688832 -189.07252)
		(end 251.055378 -191.124078)
		(width 0.14224)
		(layer "In15.Cu")
		(net "GMI_CPU0_G1_CPU1_G3_TX_DN<13>")
	)
	(segment
		(start 124.74575 -228.605842)
		(end 124.74702 -228.606604)
		(width 0.1143)
		(layer "In15.Cu")
		(net "GMI_CPU0_G1_CPU1_G3_TX_DN<13>")
	)
	(segment
		(start 346.748862 -233.466132)
		(end 346.750132 -233.46537)
		(width 0.1143)
		(layer "In15.Cu")
		(net "GMI_CPU0_G1_CPU1_G3_TX_DN<13>")
	)
	(segment
		(start 158.597346 -192.723008)
		(end 158.2674 -192.993518)
		(width 0.14224)
		(layer "In15.Cu")
		(net "GMI_CPU0_G1_CPU1_G3_TX_DN<13>")
	)
	(segment
		(start 124.7394 -239.94237)
		(end 124.739908 -239.941608)
		(width 0.1143)
		(layer "In15.Cu")
		(net "GMI_CPU0_G1_CPU1_G3_TX_DN<13>")
	)
	(segment
		(start 346.7481 -228.606858)
		(end 346.748862 -228.60635)
		(width 0.1143)
		(layer "In15.Cu")
		(net "GMI_CPU0_G1_CPU1_G3_TX_DN<13>")
	)
	(segment
		(start 345.82735 -223.735646)
		(end 345.829636 -223.734376)
		(width 0.1143)
		(layer "In15.Cu")
		(net "GMI_CPU0_G1_CPU1_G3_TX_DN<13>")
	)
	(segment
		(start 154.429206 -196.318378)
		(end 154.236166 -196.299074)
		(width 0.14224)
		(layer "In15.Cu")
		(net "GMI_CPU0_G1_CPU1_G3_TX_DN<13>")
	)
	(segment
		(start 124.784104 -231.180894)
		(end 124.78131 -231.182418)
		(width 0.1143)
		(layer "In15.Cu")
		(net "GMI_CPU0_G1_CPU1_G3_TX_DN<13>")
	)
	(segment
		(start 345.808046 -223.746822)
		(end 345.808808 -223.746314)
		(width 0.1143)
		(layer "In15.Cu")
		(net "GMI_CPU0_G1_CPU1_G3_TX_DN<13>")
	)
	(segment
		(start 346.748862 -236.062012)
		(end 346.7481 -236.061504)
		(width 0.1143)
		(layer "In15.Cu")
		(net "GMI_CPU0_G1_CPU1_G3_TX_DN<13>")
	)
	(segment
		(start 346.750132 -235.085382)
		(end 346.77985 -235.068364)
		(width 0.1143)
		(layer "In15.Cu")
		(net "GMI_CPU0_G1_CPU1_G3_TX_DN<13>")
	)
	(segment
		(start 156.503878 -194.617086)
		(end 156.173678 -194.88785)
		(width 0.14224)
		(layer "In15.Cu")
		(net "GMI_CPU0_G1_CPU1_G3_TX_DN<13>")
	)
	(segment
		(start 124.74575 -245.7831)
		(end 124.716032 -245.800118)
		(width 0.1143)
		(layer "In15.Cu")
		(net "GMI_CPU0_G1_CPU1_G3_TX_DN<13>")
	)
	(segment
		(start 124.741686 -231.843326)
		(end 124.74321 -231.844342)
		(width 0.1143)
		(layer "In15.Cu")
		(net "GMI_CPU0_G1_CPU1_G3_TX_DN<13>")
	)
	(segment
		(start 124.74575 -223.103186)
		(end 124.716032 -223.120204)
		(width 0.1143)
		(layer "In15.Cu")
		(net "GMI_CPU0_G1_CPU1_G3_TX_DN<13>")
	)
	(segment
		(start 346.74556 -226.340162)
		(end 346.744544 -226.339654)
		(width 0.1143)
		(layer "In15.Cu")
		(net "GMI_CPU0_G1_CPU1_G3_TX_DN<13>")
	)
	(segment
		(start 124.74702 -234.442254)
		(end 124.74575 -234.443016)
		(width 0.1143)
		(layer "In15.Cu")
		(net "GMI_CPU0_G1_CPU1_G3_TX_DN<13>")
	)
	(segment
		(start 124.750576 -244.808756)
		(end 124.78639 -244.82933)
		(width 0.1143)
		(layer "In15.Cu")
		(net "GMI_CPU0_G1_CPU1_G3_TX_DN<13>")
	)
	(segment
		(start 157.376114 -193.901822)
		(end 157.045914 -194.172586)
		(width 0.14224)
		(layer "In15.Cu")
		(net "GMI_CPU0_G1_CPU1_G3_TX_DN<13>")
	)
	(segment
		(start 233.932476 -199.32396)
		(end 211.720684 -190.123318)
		(width 0.14224)
		(layer "In15.Cu")
		(net "GMI_CPU0_G1_CPU1_G3_TX_DN<13>")
	)
	(segment
		(start 346.747084 -242.541044)
		(end 346.74556 -242.540028)
		(width 0.1143)
		(layer "In15.Cu")
		(net "GMI_CPU0_G1_CPU1_G3_TX_DN<13>")
	)
	(segment
		(start 124.741686 -238.323374)
		(end 124.74321 -238.32439)
		(width 0.1143)
		(layer "In15.Cu")
		(net "GMI_CPU0_G1_CPU1_G3_TX_DN<13>")
	)
	(segment
		(start 124.741686 -228.603556)
		(end 124.74321 -228.604572)
		(width 0.1143)
		(layer "In15.Cu")
		(net "GMI_CPU0_G1_CPU1_G3_TX_DN<13>")
	)
	(segment
		(start 346.74556 -232.819956)
		(end 346.708984 -232.79862)
		(width 0.1143)
		(layer "In15.Cu")
		(net "GMI_CPU0_G1_CPU1_G3_TX_DN<13>")
	)
	(segment
		(start 345.83624 -223.730566)
		(end 345.837002 -223.730058)
		(width 0.1143)
		(layer "In15.Cu")
		(net "GMI_CPU0_G1_CPU1_G3_TX_DN<13>")
	)
	(segment
		(start 346.748862 -238.326168)
		(end 346.750132 -238.325406)
		(width 0.1143)
		(layer "In15.Cu")
		(net "GMI_CPU0_G1_CPU1_G3_TX_DN<13>")
	)
	(segment
		(start 124.74575 -244.163088)
		(end 124.716032 -244.180106)
		(width 0.1143)
		(layer "In15.Cu")
		(net "GMI_CPU0_G1_CPU1_G3_TX_DN<13>")
	)
	(segment
		(start 124.74194 -242.545108)
		(end 124.716032 -242.560094)
		(width 0.1143)
		(layer "In15.Cu")
		(net "GMI_CPU0_G1_CPU1_G3_TX_DN<13>")
	)
	(segment
		(start 124.747782 -225.367088)
		(end 124.750576 -225.368866)
		(width 0.1143)
		(layer "In15.Cu")
		(net "GMI_CPU0_G1_CPU1_G3_TX_DN<13>")
	)
	(segment
		(start 309.008272 -189.451488)
		(end 303.7332 -189.451488)
		(width 0.14224)
		(layer "In15.Cu")
		(net "GMI_CPU0_G1_CPU1_G3_TX_DN<13>")
	)
	(segment
		(start 343.027 -216.25814)
		(end 318.440054 -196.098922)
		(width 0.14224)
		(layer "In15.Cu")
		(net "GMI_CPU0_G1_CPU1_G3_TX_DN<13>")
	)
	(segment
		(start 303.7332 -189.451488)
		(end 303.707038 -189.451234)
		(width 0.14224)
		(layer "In15.Cu")
		(net "GMI_CPU0_G1_CPU1_G3_TX_DN<13>")
	)
	(segment
		(start 346.7481 -227.961698)
		(end 346.747084 -227.96119)
		(width 0.1143)
		(layer "In15.Cu")
		(net "GMI_CPU0_G1_CPU1_G3_TX_DN<13>")
	)
	(segment
		(start 124.74702 -230.226362)
		(end 124.747782 -230.22687)
		(width 0.1143)
		(layer "In15.Cu")
		(net "GMI_CPU0_G1_CPU1_G3_TX_DN<13>")
	)
	(segment
		(start 345.834462 -223.731582)
		(end 345.83624 -223.730566)
		(width 0.1143)
		(layer "In15.Cu")
		(net "GMI_CPU0_G1_CPU1_G3_TX_DN<13>")
	)
	(segment
		(start 124.78766 -232.798874)
		(end 124.747782 -232.821734)
		(width 0.1143)
		(layer "In15.Cu")
		(net "GMI_CPU0_G1_CPU1_G3_TX_DN<13>")
	)
	(segment
		(start 124.74702 -236.70641)
		(end 124.747782 -236.706918)
		(width 0.1143)
		(layer "In15.Cu")
		(net "GMI_CPU0_G1_CPU1_G3_TX_DN<13>")
	)
	(segment
		(start 346.744544 -226.339654)
		(end 346.74302 -226.338638)
		(width 0.1143)
		(layer "In15.Cu")
		(net "GMI_CPU0_G1_CPU1_G3_TX_DN<13>")
	)
	(segment
		(start 124.747782 -230.22687)
		(end 124.747528 -230.227124)
		(width 0.1143)
		(layer "In15.Cu")
		(net "GMI_CPU0_G1_CPU1_G3_TX_DN<13>")
	)
	(segment
		(start 346.74556 -234.439968)
		(end 346.708984 -234.418632)
		(width 0.1143)
		(layer "In15.Cu")
		(net "GMI_CPU0_G1_CPU1_G3_TX_DN<13>")
	)
	(segment
		(start 124.741686 -225.363532)
		(end 124.74321 -225.364548)
		(width 0.1143)
		(layer "In15.Cu")
		(net "GMI_CPU0_G1_CPU1_G3_TX_DN<13>")
	)
	(segment
		(start 345.055952 -221.80423)
		(end 345.055952 -221.443042)
		(width 0.1143)
		(layer "In15.Cu")
		(net "GMI_CPU0_G1_CPU1_G3_TX_DN<13>")
	)
	(segment
		(start 124.743718 -226.344226)
		(end 124.742702 -226.344734)
		(width 0.1143)
		(layer "In15.Cu")
		(net "GMI_CPU0_G1_CPU1_G3_TX_DN<13>")
	)
	(segment
		(start 157.72511 -193.438272)
		(end 157.724856 -193.438272)
		(width 0.14224)
		(layer "In15.Cu")
		(net "GMI_CPU0_G1_CPU1_G3_TX_DN<13>")
	)
	(segment
		(start 346.747084 -239.947196)
		(end 346.7481 -239.946688)
		(width 0.1143)
		(layer "In15.Cu")
		(net "GMI_CPU0_G1_CPU1_G3_TX_DN<13>")
	)
	(segment
		(start 346.748862 -246.426228)
		(end 346.750132 -246.425466)
		(width 0.1143)
		(layer "In15.Cu")
		(net "GMI_CPU0_G1_CPU1_G3_TX_DN<13>")
	)
	(segment
		(start 346.747084 -240.921032)
		(end 346.74556 -240.920016)
		(width 0.1143)
		(layer "In15.Cu")
		(net "GMI_CPU0_G1_CPU1_G3_TX_DN<13>")
	)
	(segment
		(start 124.74702 -233.466386)
		(end 124.747782 -233.466894)
		(width 0.1143)
		(layer "In15.Cu")
		(net "GMI_CPU0_G1_CPU1_G3_TX_DN<13>")
	)
	(segment
		(start 346.739718 -226.33686)
		(end 346.708984 -226.318826)
		(width 0.1143)
		(layer "In15.Cu")
		(net "GMI_CPU0_G1_CPU1_G3_TX_DN<13>")
	)
	(segment
		(start 236.351826 -199.750426)
		(end 233.932476 -199.32396)
		(width 0.14224)
		(layer "In15.Cu")
		(net "GMI_CPU0_G1_CPU1_G3_TX_DN<13>")
	)
	(segment
		(start 346.77985 -232.839768)
		(end 346.748862 -232.821988)
		(width 0.1143)
		(layer "In15.Cu")
		(net "GMI_CPU0_G1_CPU1_G3_TX_DN<13>")
	)
	(segment
		(start 124.716032 -231.828594)
		(end 124.741686 -231.843326)
		(width 0.1143)
		(layer "In15.Cu")
		(net "GMI_CPU0_G1_CPU1_G3_TX_DN<13>")
	)
	(segment
		(start 346.757752 -228.601016)
		(end 346.7608 -228.599238)
		(width 0.1143)
		(layer "In15.Cu")
		(net "GMI_CPU0_G1_CPU1_G3_TX_DN<13>")
	)
	(segment
		(start 346.748862 -240.922048)
		(end 346.7481 -240.92154)
		(width 0.1143)
		(layer "In15.Cu")
		(net "GMI_CPU0_G1_CPU1_G3_TX_DN<13>")
	)
	(segment
		(start 124.747782 -241.566954)
		(end 124.750576 -241.568732)
		(width 0.1143)
		(layer "In15.Cu")
		(net "GMI_CPU0_G1_CPU1_G3_TX_DN<13>")
	)
	(segment
		(start 346.7481 -232.82148)
		(end 346.747084 -232.820972)
		(width 0.1143)
		(layer "In15.Cu")
		(net "GMI_CPU0_G1_CPU1_G3_TX_DN<13>")
	)
	(segment
		(start 124.750322 -231.84866)
		(end 124.78766 -231.869742)
		(width 0.1143)
		(layer "In15.Cu")
		(net "GMI_CPU0_G1_CPU1_G3_TX_DN<13>")
	)
	(segment
		(start 124.743718 -242.544092)
		(end 124.742702 -242.5446)
		(width 0.1143)
		(layer "In15.Cu")
		(net "GMI_CPU0_G1_CPU1_G3_TX_DN<13>")
	)
	(segment
		(start 239.538764 -199.188578)
		(end 236.351826 -199.750426)
		(width 0.14224)
		(layer "In15.Cu")
		(net "GMI_CPU0_G1_CPU1_G3_TX_DN<13>")
	)
	(segment
		(start 124.74321 -226.98456)
		(end 124.74575 -226.98583)
		(width 0.1143)
		(layer "In15.Cu")
		(net "GMI_CPU0_G1_CPU1_G3_TX_DN<13>")
	)
	(segment
		(start 346.747084 -237.681008)
		(end 346.74556 -237.679992)
		(width 0.1143)
		(layer "In15.Cu")
		(net "GMI_CPU0_G1_CPU1_G3_TX_DN<13>")
	)
	(segment
		(start 124.787152 -223.079056)
		(end 124.747782 -223.101916)
		(width 0.1143)
		(layer "In15.Cu")
		(net "GMI_CPU0_G1_CPU1_G3_TX_DN<13>")
	)
	(segment
		(start 153.36393 -197.014338)
		(end 148.715984 -200.824846)
		(width 0.14224)
		(layer "In15.Cu")
		(net "GMI_CPU0_G1_CPU1_G3_TX_DN<13>")
	)
	(segment
		(start 346.708984 -231.869488)
		(end 346.747084 -231.847136)
		(width 0.1143)
		(layer "In15.Cu")
		(net "GMI_CPU0_G1_CPU1_G3_TX_DN<13>")
	)
	(segment
		(start 154.778456 -195.854574)
		(end 154.759406 -196.047614)
		(width 0.14224)
		(layer "In15.Cu")
		(net "GMI_CPU0_G1_CPU1_G3_TX_DN<13>")
	)
	(segment
		(start 124.787406 -227.939092)
		(end 124.747782 -227.961952)
		(width 0.1143)
		(layer "In15.Cu")
		(net "GMI_CPU0_G1_CPU1_G3_TX_DN<13>")
	)
	(segment
		(start 124.716032 -239.320324)
		(end 124.715778 -239.320324)
		(width 0.1143)
		(layer "In15.Cu")
		(net "GMI_CPU0_G1_CPU1_G3_TX_DN<13>")
	)
	(segment
		(start 124.605542 -221.174564)
		(end 124.605542 -221.203012)
		(width 0.1143)
		(layer "In15.Cu")
		(net "GMI_CPU0_G1_CPU1_G3_TX_DN<13>")
	)
	(segment
		(start 124.747782 -229.581964)
		(end 124.714254 -229.601522)
		(width 0.1143)
		(layer "In15.Cu")
		(net "GMI_CPU0_G1_CPU1_G3_TX_DN<13>")
	)
	(segment
		(start 146.501866 -201.495914)
		(end 125.872748 -218.410282)
		(width 0.14224)
		(layer "In15.Cu")
		(net "GMI_CPU0_G1_CPU1_G3_TX_DN<13>")
	)
	(segment
		(start 124.747782 -234.441746)
		(end 124.74702 -234.442254)
		(width 0.1143)
		(layer "In15.Cu")
		(net "GMI_CPU0_G1_CPU1_G3_TX_DN<13>")
	)
	(segment
		(start 303.682654 -189.45098)
		(end 262.688832 -189.07252)
		(width 0.14224)
		(layer "In15.Cu")
		(net "GMI_CPU0_G1_CPU1_G3_TX_DN<13>")
	)
	(segment
		(start 124.74321 -244.804438)
		(end 124.74575 -244.805708)
		(width 0.1143)
		(layer "In15.Cu")
		(net "GMI_CPU0_G1_CPU1_G3_TX_DN<13>")
	)
	(segment
		(start 345.829636 -223.734376)
		(end 345.831668 -223.733106)
		(width 0.1143)
		(layer "In15.Cu")
		(net "GMI_CPU0_G1_CPU1_G3_TX_DN<13>")
	)
	(segment
		(start 346.708984 -227.009706)
		(end 346.7481 -226.986846)
		(width 0.1143)
		(layer "In15.Cu")
		(net "GMI_CPU0_G1_CPU1_G3_TX_DN<13>")
	)
	(segment
		(start 124.747782 -226.9871)
		(end 124.750322 -226.988878)
		(width 0.1143)
		(layer "In15.Cu")
		(net "GMI_CPU0_G1_CPU1_G3_TX_DN<13>")
	)
	(segment
		(start 124.747782 -237.68177)
		(end 124.74702 -237.682278)
		(width 0.1143)
		(layer "In15.Cu")
		(net "GMI_CPU0_G1_CPU1_G3_TX_DN<13>")
	)
	(segment
		(start 124.746258 -226.342702)
		(end 124.745496 -226.34321)
		(width 0.1143)
		(layer "In15.Cu")
		(net "GMI_CPU0_G1_CPU1_G3_TX_DN<13>")
	)
	(segment
		(start 346.7481 -226.341686)
		(end 346.747084 -226.341178)
		(width 0.1143)
		(layer "In15.Cu")
		(net "GMI_CPU0_G1_CPU1_G3_TX_DN<13>")
	)
	(segment
		(start 124.74575 -232.823004)
		(end 124.716032 -232.840022)
		(width 0.1143)
		(layer "In15.Cu")
		(net "GMI_CPU0_G1_CPU1_G3_TX_DN<13>")
	)
	(segment
		(start 124.740924 -226.34575)
		(end 124.740162 -226.346258)
		(width 0.1143)
		(layer "In15.Cu")
		(net "GMI_CPU0_G1_CPU1_G3_TX_DN<13>")
	)
	(segment
		(start 124.605542 -221.203012)
		(end 124.559822 -221.248732)
		(width 0.1143)
		(layer "In15.Cu")
		(net "GMI_CPU0_G1_CPU1_G3_TX_DN<13>")
	)
	(segment
		(start 124.74575 -246.42572)
		(end 124.74702 -246.426482)
		(width 0.1143)
		(layer "In15.Cu")
		(net "GMI_CPU0_G1_CPU1_G3_TX_DN<13>")
	)
	(segment
		(start 124.741686 -241.563398)
		(end 124.74321 -241.564414)
		(width 0.1143)
		(layer "In15.Cu")
		(net "GMI_CPU0_G1_CPU1_G3_TX_DN<13>")
	)
	(segment
		(start 159.139636 -192.278254)
		(end 159.120586 -192.471294)
		(width 0.14224)
		(layer "In15.Cu")
		(net "GMI_CPU0_G1_CPU1_G3_TX_DN<13>")
	)
	(segment
		(start 345.822524 -223.738186)
		(end 345.824048 -223.737424)
		(width 0.1143)
		(layer "In15.Cu")
		(net "GMI_CPU0_G1_CPU1_G3_TX_DN<13>")
	)
	(segment
		(start 160.011872 -191.56299)
		(end 159.992822 -191.75603)
		(width 0.14224)
		(layer "In15.Cu")
		(net "GMI_CPU0_G1_CPU1_G3_TX_DN<13>")
	)
	(segment
		(start 124.750322 -226.988878)
		(end 124.787406 -227.00996)
		(width 0.1143)
		(layer "In15.Cu")
		(net "GMI_CPU0_G1_CPU1_G3_TX_DN<13>")
	)
	(segment
		(start 346.7481 -236.706664)
		(end 346.748862 -236.706156)
		(width 0.1143)
		(layer "In15.Cu")
		(net "GMI_CPU0_G1_CPU1_G3_TX_DN<13>")
	)
	(segment
		(start 159.120586 -192.471294)
		(end 158.790386 -192.742058)
		(width 0.14224)
		(layer "In15.Cu")
		(net "GMI_CPU0_G1_CPU1_G3_TX_DN<13>")
	)
	(segment
		(start 346.747084 -241.567208)
		(end 346.7481 -241.5667)
		(width 0.1143)
		(layer "In15.Cu")
		(net "GMI_CPU0_G1_CPU1_G3_TX_DN<13>")
	)
	(segment
		(start 346.77985 -244.179852)
		(end 346.748862 -244.162072)
		(width 0.1143)
		(layer "In15.Cu")
		(net "GMI_CPU0_G1_CPU1_G3_TX_DN<13>")
	)
	(segment
		(start 124.787152 -241.589814)
		(end 124.80544 -241.603022)
		(width 0.1143)
		(layer "In15.Cu")
		(net "GMI_CPU0_G1_CPU1_G3_TX_DN<13>")
	)
	(segment
		(start 345.808808 -224.722182)
		(end 345.808046 -224.721674)
		(width 0.1143)
		(layer "In15.Cu")
		(net "GMI_CPU0_G1_CPU1_G3_TX_DN<13>")
	)
	(segment
		(start 124.716032 -246.408702)
		(end 124.741686 -246.423434)
		(width 0.1143)
		(layer "In15.Cu")
		(net "GMI_CPU0_G1_CPU1_G3_TX_DN<13>")
	)
	(segment
		(start 345.808046 -224.721674)
		(end 345.771724 -224.700592)
		(width 0.1143)
		(layer "In15.Cu")
		(net "GMI_CPU0_G1_CPU1_G3_TX_DN<13>")
	)
	(segment
		(start 346.7481 -238.326676)
		(end 346.748862 -238.326168)
		(width 0.1143)
		(layer "In15.Cu")
		(net "GMI_CPU0_G1_CPU1_G3_TX_DN<13>")
	)
	(segment
		(start 124.74321 -231.844342)
		(end 124.74575 -231.845612)
		(width 0.1143)
		(layer "In15.Cu")
		(net "GMI_CPU0_G1_CPU1_G3_TX_DN<13>")
	)
	(segment
		(start 345.825826 -223.736408)
		(end 345.82735 -223.735646)
		(width 0.1143)
		(layer "In15.Cu")
		(net "GMI_CPU0_G1_CPU1_G3_TX_DN<13>")
	)
	(segment
		(start 346.747084 -227.96119)
		(end 346.708984 -227.938838)
		(width 0.1143)
		(layer "In15.Cu")
		(net "GMI_CPU0_G1_CPU1_G3_TX_DN<13>")
	)
	(segment
		(start 346.77985 -236.079792)
		(end 346.748862 -236.062012)
		(width 0.1143)
		(layer "In15.Cu")
		(net "GMI_CPU0_G1_CPU1_G3_TX_DN<13>")
	)
	(segment
		(start 346.74556 -242.540028)
		(end 346.708984 -242.518692)
		(width 0.1143)
		(layer "In15.Cu")
		(net "GMI_CPU0_G1_CPU1_G3_TX_DN<13>")
	)
	(segment
		(start 124.74321 -223.744536)
		(end 124.74575 -223.745806)
		(width 0.1143)
		(layer "In15.Cu")
		(net "GMI_CPU0_G1_CPU1_G3_TX_DN<13>")
	)
	(segment
		(start 124.814584 -224.679256)
		(end 124.786644 -224.699322)
		(width 0.1143)
		(layer "In15.Cu")
		(net "GMI_CPU0_G1_CPU1_G3_TX_DN<13>")
	)
	(segment
		(start 124.747782 -244.806978)
		(end 124.750576 -244.808756)
		(width 0.1143)
		(layer "In15.Cu")
		(net "GMI_CPU0_G1_CPU1_G3_TX_DN<13>")
	)
	(segment
		(start 346.708984 -244.829584)
		(end 346.747084 -244.807232)
		(width 0.1143)
		(layer "In15.Cu")
		(net "GMI_CPU0_G1_CPU1_G3_TX_DN<13>")
	)
	(segment
		(start 124.750576 -225.368866)
		(end 124.787152 -225.389948)
		(width 0.1143)
		(layer "In15.Cu")
		(net "GMI_CPU0_G1_CPU1_G3_TX_DN<13>")
	)
	(segment
		(start 124.74702 -239.30229)
		(end 124.74575 -239.303052)
		(width 0.1143)
		(layer "In15.Cu")
		(net "GMI_CPU0_G1_CPU1_G3_TX_DN<13>")
	)
	(segment
		(start 124.605542 -220.61678)
		(end 124.605542 -221.174564)
		(width 0.14224)
		(layer "In15.Cu")
		(net "GMI_CPU0_G1_CPU1_G3_TX_DN<13>")
	)
	(segment
		(start 346.708984 -228.629718)
		(end 346.747084 -228.607366)
		(width 0.1143)
		(layer "In15.Cu")
		(net "GMI_CPU0_G1_CPU1_G3_TX_DN<13>")
	)
	(segment
		(start 124.786644 -224.699322)
		(end 124.749306 -224.720912)
		(width 0.1143)
		(layer "In15.Cu")
		(net "GMI_CPU0_G1_CPU1_G3_TX_DN<13>")
	)
	(segment
		(start 345.839796 -224.739962)
		(end 345.808808 -224.722182)
		(width 0.1143)
		(layer "In15.Cu")
		(net "GMI_CPU0_G1_CPU1_G3_TX_DN<13>")
	)
	(segment
		(start 159.469582 -192.007744)
		(end 159.139636 -192.278254)
		(width 0.14224)
		(layer "In15.Cu")
		(net "GMI_CPU0_G1_CPU1_G3_TX_DN<13>")
	)
	(segment
		(start 124.80544 -226.306126)
		(end 124.787152 -226.31908)
		(width 0.1143)
		(layer "In15.Cu")
		(net "GMI_CPU0_G1_CPU1_G3_TX_DN<13>")
	)
	(segment
		(start 124.74702 -243.186458)
		(end 124.747782 -243.186966)
		(width 0.1143)
		(layer "In15.Cu")
		(net "GMI_CPU0_G1_CPU1_G3_TX_DN<13>")
	)
	(segment
		(start 124.7394 -239.942116)
		(end 124.7394 -239.94237)
		(width 0.1143)
		(layer "In15.Cu")
		(net "GMI_CPU0_G1_CPU1_G3_TX_DN<13>")
	)
	(segment
		(start 124.74702 -240.922302)
		(end 124.74575 -240.923064)
		(width 0.1143)
		(layer "In15.Cu")
		(net "GMI_CPU0_G1_CPU1_G3_TX_DN<13>")
	)
	(segment
		(start 346.742004 -226.33813)
		(end 346.739718 -226.33686)
		(width 0.1143)
		(layer "In15.Cu")
		(net "GMI_CPU0_G1_CPU1_G3_TX_DN<13>")
	)
	(segment
		(start 124.74575 -238.32566)
		(end 124.74702 -238.326422)
		(width 0.1143)
		(layer "In15.Cu")
		(net "GMI_CPU0_G1_CPU1_G3_TX_DN<13>")
	)
	(segment
		(start 124.784104 -229.560882)
		(end 124.747782 -229.581964)
		(width 0.1143)
		(layer "In15.Cu")
		(net "GMI_CPU0_G1_CPU1_G3_TX_DN<13>")
	)
	(segment
		(start 346.7481 -239.301528)
		(end 346.747084 -239.30102)
		(width 0.1143)
		(layer "In15.Cu")
		(net "GMI_CPU0_G1_CPU1_G3_TX_DN<13>")
	)
	(segment
		(start 124.741686 -243.18341)
		(end 124.74321 -243.184426)
		(width 0.1143)
		(layer "In15.Cu")
		(net "GMI_CPU0_G1_CPU1_G3_TX_DN<13>")
	)
	(segment
		(start 346.747084 -243.18722)
		(end 346.7481 -243.186712)
		(width 0.1143)
		(layer "In15.Cu")
		(net "GMI_CPU0_G1_CPU1_G3_TX_DN<13>")
	)
	(segment
		(start 346.708984 -238.349536)
		(end 346.747084 -238.327184)
		(width 0.1143)
		(layer "In15.Cu")
		(net "GMI_CPU0_G1_CPU1_G3_TX_DN<13>")
	)
	(segment
		(start 124.74321 -241.564414)
		(end 124.74575 -241.565684)
		(width 0.1143)
		(layer "In15.Cu")
		(net "GMI_CPU0_G1_CPU1_G3_TX_DN<13>")
	)
	(segment
		(start 124.74575 -225.365818)
		(end 124.74702 -225.36658)
		(width 0.1143)
		(layer "In15.Cu")
		(net "GMI_CPU0_G1_CPU1_G3_TX_DN<13>")
	)
	(segment
		(start 156.522928 -194.424046)
		(end 156.503878 -194.617086)
		(width 0.14224)
		(layer "In15.Cu")
		(net "GMI_CPU0_G1_CPU1_G3_TX_DN<13>")
	)
	(segment
		(start 158.790386 -192.742058)
		(end 158.597346 -192.723008)
		(width 0.14224)
		(layer "In15.Cu")
		(net "GMI_CPU0_G1_CPU1_G3_TX_DN<13>")
	)
	(segment
		(start 153.88717 -196.762624)
		(end 153.55697 -197.033388)
		(width 0.14224)
		(layer "In15.Cu")
		(net "GMI_CPU0_G1_CPU1_G3_TX_DN<13>")
	)
	(segment
		(start 346.711524 -230.247952)
		(end 346.7481 -230.226616)
		(width 0.1143)
		(layer "In15.Cu")
		(net "GMI_CPU0_G1_CPU1_G3_TX_DN<13>")
	)
	(segment
		(start 303.684432 -189.45098)
		(end 303.682654 -189.45098)
		(width 0.14224)
		(layer "In15.Cu")
		(net "GMI_CPU0_G1_CPU1_G3_TX_DN<13>")
	)
	(segment
		(start 346.751402 -228.604826)
		(end 346.754196 -228.603302)
		(width 0.1143)
		(layer "In15.Cu")
		(net "GMI_CPU0_G1_CPU1_G3_TX_DN<13>")
	)
	(segment
		(start 124.74702 -244.80647)
		(end 124.747782 -244.806978)
		(width 0.1143)
		(layer "In15.Cu")
		(net "GMI_CPU0_G1_CPU1_G3_TX_DN<13>")
	)
	(segment
		(start 346.7481 -226.986846)
		(end 346.748862 -226.986338)
		(width 0.1143)
		(layer "In15.Cu")
		(net "GMI_CPU0_G1_CPU1_G3_TX_DN<13>")
	)
	(segment
		(start 124.74321 -238.32439)
		(end 124.74575 -238.32566)
		(width 0.1143)
		(layer "In15.Cu")
		(net "GMI_CPU0_G1_CPU1_G3_TX_DN<13>")
	)
	(segment
		(start 124.74194 -226.345242)
		(end 124.740924 -226.34575)
		(width 0.1143)
		(layer "In15.Cu")
		(net "GMI_CPU0_G1_CPU1_G3_TX_DN<13>")
	)
	(segment
		(start 124.741686 -233.463338)
		(end 124.74321 -233.464354)
		(width 0.1143)
		(layer "In15.Cu")
		(net "GMI_CPU0_G1_CPU1_G3_TX_DN<13>")
	)
	(segment
		(start 124.721366 -239.932464)
		(end 124.726446 -239.935512)
		(width 0.1143)
		(layer "In15.Cu")
		(net "GMI_CPU0_G1_CPU1_G3_TX_DN<13>")
	)
	(segment
		(start 124.74448 -230.224838)
		(end 124.74702 -230.226362)
		(width 0.1143)
		(layer "In15.Cu")
		(net "GMI_CPU0_G1_CPU1_G3_TX_DN<13>")
	)
	(segment
		(start 346.748862 -236.706156)
		(end 346.750132 -236.705394)
		(width 0.1143)
		(layer "In15.Cu")
		(net "GMI_CPU0_G1_CPU1_G3_TX_DN<13>")
	)
	(segment
		(start 124.747528 -230.227124)
		(end 124.74829 -230.227632)
		(width 0.1143)
		(layer "In15.Cu")
		(net "GMI_CPU0_G1_CPU1_G3_TX_DN<13>")
	)
	(segment
		(start 125.872748 -218.410282)
		(end 124.605542 -220.61678)
		(width 0.14224)
		(layer "In15.Cu")
		(net "GMI_CPU0_G1_CPU1_G3_TX_DN<13>")
	)
	(segment
		(start 124.74575 -236.705648)
		(end 124.74702 -236.70641)
		(width 0.1143)
		(layer "In15.Cu")
		(net "GMI_CPU0_G1_CPU1_G3_TX_DN<13>")
	)
	(segment
		(start 124.74575 -243.185696)
		(end 124.74702 -243.186458)
		(width 0.1143)
		(layer "In15.Cu")
		(net "GMI_CPU0_G1_CPU1_G3_TX_DN<13>")
	)
	(segment
		(start 345.919044 -247.724168)
		(end 346.001848 -247.641364)
		(width 0.1143)
		(layer "In15.Cu")
		(net "GMI_CPU0_G1_CPU1_G3_TX_DN<13>")
	)
	(segment
		(start 346.77985 -242.55984)
		(end 346.7481 -242.541552)
		(width 0.1143)
		(layer "In15.Cu")
		(net "GMI_CPU0_G1_CPU1_G3_TX_DN<13>")
	)
	(segment
		(start 124.78639 -245.759478)
		(end 124.747782 -245.78183)
		(width 0.1143)
		(layer "In15.Cu")
		(net "GMI_CPU0_G1_CPU1_G3_TX_DN<13>")
	)
	(segment
		(start 346.747084 -246.427244)
		(end 346.7481 -246.426736)
		(width 0.1143)
		(layer "In15.Cu")
		(net "GMI_CPU0_G1_CPU1_G3_TX_DN<13>")
	)
	(segment
		(start 346.7481 -240.92154)
		(end 346.747084 -240.921032)
		(width 0.1143)
		(layer "In15.Cu")
		(net "GMI_CPU0_G1_CPU1_G3_TX_DN<13>")
	)
	(segment
		(start 124.747782 -243.186966)
		(end 124.750322 -243.188744)
		(width 0.1143)
		(layer "In15.Cu")
		(net "GMI_CPU0_G1_CPU1_G3_TX_DN<13>")
	)
	(segment
		(start 124.747782 -231.846882)
		(end 124.750322 -231.84866)
		(width 0.1143)
		(layer "In15.Cu")
		(net "GMI_CPU0_G1_CPU1_G3_TX_DN<13>")
	)
	(segment
		(start 346.239084 -247.259602)
		(end 346.2782 -247.236742)
		(width 0.1143)
		(layer "In15.Cu")
		(net "GMI_CPU0_G1_CPU1_G3_TX_DN<13>")
	)
	(segment
		(start 124.741686 -226.983544)
		(end 124.74321 -226.98456)
		(width 0.1143)
		(layer "In15.Cu")
		(net "GMI_CPU0_G1_CPU1_G3_TX_DN<13>")
	)
	(segment
		(start 124.715778 -222.108776)
		(end 124.786644 -222.14967)
		(width 0.1143)
		(layer "In15.Cu")
		(net "GMI_CPU0_G1_CPU1_G3_TX_DN<13>")
	)
	(segment
		(start 346.7608 -228.599238)
		(end 346.77985 -228.58857)
		(width 0.1143)
		(layer "In15.Cu")
		(net "GMI_CPU0_G1_CPU1_G3_TX_DN<13>")
	)
	(segment
		(start 160.700466 -190.998348)
		(end 160.011872 -191.56299)
		(width 0.14224)
		(layer "In15.Cu")
		(net "GMI_CPU0_G1_CPU1_G3_TX_DN<13>")
	)
	(segment
		(start 346.748862 -239.94618)
		(end 346.750132 -239.945418)
		(width 0.1143)
		(layer "In15.Cu")
		(net "GMI_CPU0_G1_CPU1_G3_TX_DN<13>")
	)
	(segment
		(start 303.707038 -189.451234)
		(end 303.696116 -189.451234)
		(width 0.14224)
		(layer "In15.Cu")
		(net "GMI_CPU0_G1_CPU1_G3_TX_DN<13>")
	)
	(segment
		(start 124.741686 -244.803422)
		(end 124.74321 -244.804438)
		(width 0.1143)
		(layer "In15.Cu")
		(net "GMI_CPU0_G1_CPU1_G3_TX_DN<13>")
	)
	(segment
		(start 124.74702 -226.986592)
		(end 124.747782 -226.9871)
		(width 0.1143)
		(layer "In15.Cu")
		(net "GMI_CPU0_G1_CPU1_G3_TX_DN<13>")
	)
	(segment
		(start 125.042676 -246.922798)
		(end 125.042676 -246.934228)
		(width 0.1143)
		(layer "In15.Cu")
		(net "GMI_CPU0_G1_CPU1_G3_TX_DN<13>")
	)
	(segment
		(start 346.748862 -244.806216)
		(end 346.750132 -244.805454)
		(width 0.1143)
		(layer "In15.Cu")
		(net "GMI_CPU0_G1_CPU1_G3_TX_DN<13>")
	)
	(segment
		(start 346.708984 -236.729524)
		(end 346.747084 -236.707172)
		(width 0.1143)
		(layer "In15.Cu")
		(net "GMI_CPU0_G1_CPU1_G3_TX_DN<13>")
	)
	(segment
		(start 345.839796 -223.11995)
		(end 345.80322 -223.098614)
		(width 0.1143)
		(layer "In15.Cu")
		(net "GMI_CPU0_G1_CPU1_G3_TX_DN<13>")
	)
	(segment
		(start 124.74575 -223.745806)
		(end 124.74702 -223.746568)
		(width 0.1143)
		(layer "In15.Cu")
		(net "GMI_CPU0_G1_CPU1_G3_TX_DN<13>")
	)
	(segment
		(start 124.721366 -236.69244)
		(end 124.726446 -236.695488)
		(width 0.1143)
		(layer "In15.Cu")
		(net "GMI_CPU0_G1_CPU1_G3_TX_DN<13>")
	)
	(segment
		(start 124.808742 -239.263428)
		(end 124.787152 -239.279176)
		(width 0.1143)
		(layer "In15.Cu")
		(net "GMI_CPU0_G1_CPU1_G3_TX_DN<13>")
	)
	(segment
		(start 346.708984 -239.969548)
		(end 346.747084 -239.947196)
		(width 0.1143)
		(layer "In15.Cu")
		(net "GMI_CPU0_G1_CPU1_G3_TX_DN<13>")
	)
	(segment
		(start 159.662622 -192.026794)
		(end 159.469582 -192.007744)
		(width 0.14224)
		(layer "In15.Cu")
		(net "GMI_CPU0_G1_CPU1_G3_TX_DN<13>")
	)
	(segment
		(start 346.74556 -236.05998)
		(end 346.708984 -236.038644)
		(width 0.1143)
		(layer "In15.Cu")
		(net "GMI_CPU0_G1_CPU1_G3_TX_DN<13>")
	)
	(segment
		(start 124.786644 -223.769682)
		(end 124.814584 -223.789748)
		(width 0.1143)
		(layer "In15.Cu")
		(net "GMI_CPU0_G1_CPU1_G3_TX_DN<13>")
	)
	(segment
		(start 346.74556 -237.679992)
		(end 346.708984 -237.658656)
		(width 0.1143)
		(layer "In15.Cu")
		(net "GMI_CPU0_G1_CPU1_G3_TX_DN<13>")
	)
	(segment
		(start 124.747782 -227.961952)
		(end 124.74702 -227.96246)
		(width 0.1143)
		(layer "In15.Cu")
		(net "GMI_CPU0_G1_CPU1_G3_TX_DN<13>")
	)
	(segment
		(start 124.750322 -238.328708)
		(end 124.787152 -238.349536)
		(width 0.1143)
		(layer "In15.Cu")
		(net "GMI_CPU0_G1_CPU1_G3_TX_DN<13>")
	)
	(segment
		(start 346.708984 -246.449596)
		(end 346.747084 -246.427244)
		(width 0.1143)
		(layer "In15.Cu")
		(net "GMI_CPU0_G1_CPU1_G3_TX_DN<13>")
	)
	(segment
		(start 158.2674 -192.993518)
		(end 158.24835 -193.186558)
		(width 0.14224)
		(layer "In15.Cu")
		(net "GMI_CPU0_G1_CPU1_G3_TX_DN<13>")
	)
	(segment
		(start 154.759406 -196.047614)
		(end 154.429206 -196.318378)
		(width 0.14224)
		(layer "In15.Cu")
		(net "GMI_CPU0_G1_CPU1_G3_TX_DN<13>")
	)
	(segment
		(start 124.787152 -238.349536)
		(end 124.808742 -238.365284)
		(width 0.1143)
		(layer "In15.Cu")
		(net "GMI_CPU0_G1_CPU1_G3_TX_DN<13>")
	)
	(segment
		(start 124.74575 -241.565684)
		(end 124.74702 -241.566446)
		(width 0.1143)
		(layer "In15.Cu")
		(net "GMI_CPU0_G1_CPU1_G3_TX_DN<13>")
	)
	(segment
		(start 155.301442 -195.603114)
		(end 155.108402 -195.584064)
		(width 0.14224)
		(layer "In15.Cu")
		(net "GMI_CPU0_G1_CPU1_G3_TX_DN<13>")
	)
	(segment
		(start 124.74702 -223.102424)
		(end 124.74575 -223.103186)
		(width 0.1143)
		(layer "In15.Cu")
		(net "GMI_CPU0_G1_CPU1_G3_TX_DN<13>")
	)
	(segment
		(start 124.802138 -232.788206)
		(end 124.78766 -232.798874)
		(width 0.1143)
		(layer "In15.Cu")
		(net "GMI_CPU0_G1_CPU1_G3_TX_DN<13>")
	)
	(segment
		(start 346.747084 -235.08716)
		(end 346.7481 -235.086652)
		(width 0.1143)
		(layer "In15.Cu")
		(net "GMI_CPU0_G1_CPU1_G3_TX_DN<13>")
	)
	(segment
		(start 346.7481 -235.086652)
		(end 346.748862 -235.086144)
		(width 0.1143)
		(layer "In15.Cu")
		(net "GMI_CPU0_G1_CPU1_G3_TX_DN<13>")
	)
	(segment
		(start 157.91815 -193.457322)
		(end 157.72511 -193.438272)
		(width 0.14224)
		(layer "In15.Cu")
		(net "GMI_CPU0_G1_CPU1_G3_TX_DN<13>")
	)
	(segment
		(start 345.812872 -223.744028)
		(end 345.813634 -223.74352)
		(width 0.1143)
		(layer "In15.Cu")
		(net "GMI_CPU0_G1_CPU1_G3_TX_DN<13>")
	)
	(segment
		(start 346.747084 -245.781068)
		(end 346.74556 -245.780052)
		(width 0.1143)
		(layer "In15.Cu")
		(net "GMI_CPU0_G1_CPU1_G3_TX_DN<13>")
	)
	(segment
		(start 124.716032 -239.32007)
		(end 124.716032 -239.320324)
		(width 0.1143)
		(layer "In15.Cu")
		(net "GMI_CPU0_G1_CPU1_G3_TX_DN<13>")
	)
	(segment
		(start 124.78639 -244.82933)
		(end 124.80417 -244.841776)
		(width 0.1143)
		(layer "In15.Cu")
		(net "GMI_CPU0_G1_CPU1_G3_TX_DN<13>")
	)
	(segment
		(start 345.810078 -223.745552)
		(end 345.811602 -223.74479)
		(width 0.1143)
		(layer "In15.Cu")
		(net "GMI_CPU0_G1_CPU1_G3_TX_DN<13>")
	)
	(segment
		(start 345.00058 -221.128844)
		(end 344.95486 -221.083124)
		(width 0.1143)
		(layer "In15.Cu")
		(net "GMI_CPU0_G1_CPU1_G3_TX_DN<13>")
	)
	(segment
		(start 156.173678 -194.88785)
		(end 155.980638 -194.8688)
		(width 0.14224)
		(layer "In15.Cu")
		(net "GMI_CPU0_G1_CPU1_G3_TX_DN<13>")
	)
	(segment
		(start 346.747084 -236.707172)
		(end 346.7481 -236.706664)
		(width 0.1143)
		(layer "In15.Cu")
		(net "GMI_CPU0_G1_CPU1_G3_TX_DN<13>")
	)
	(segment
		(start 346.7481 -229.58171)
		(end 346.708984 -229.55885)
		(width 0.1143)
		(layer "In15.Cu")
		(net "GMI_CPU0_G1_CPU1_G3_TX_DN<13>")
	)
	(segment
		(start 125.494034 -247.641618)
		(end 125.576838 -247.724422)
		(width 0.1143)
		(layer "In15.Cu")
		(net "GMI_CPU0_G1_CPU1_G3_TX_DN<13>")
	)
	(segment
		(start 345.80322 -223.098614)
		(end 345.802712 -223.098614)
		(width 0.1143)
		(layer "In15.Cu")
		(net "GMI_CPU0_G1_CPU1_G3_TX_DN<13>")
	)
	(segment
		(start 148.715984 -200.824846)
		(end 146.501866 -201.495914)
		(width 0.14224)
		(layer "In15.Cu")
		(net "GMI_CPU0_G1_CPU1_G3_TX_DN<13>")
	)
	(segment
		(start 124.727208 -239.93602)
		(end 124.7394 -239.942116)
		(width 0.1143)
		(layer "In15.Cu")
		(net "GMI_CPU0_G1_CPU1_G3_TX_DN<13>")
	)
	(segment
		(start 155.108402 -195.584064)
		(end 154.778456 -195.854574)
		(width 0.14224)
		(layer "In15.Cu")
		(net "GMI_CPU0_G1_CPU1_G3_TX_DN<13>")
	)
	(segment
		(start 159.992822 -191.75603)
		(end 159.662622 -192.026794)
		(width 0.14224)
		(layer "In15.Cu")
		(net "GMI_CPU0_G1_CPU1_G3_TX_DN<13>")
	)
	(segment
		(start 124.74575 -236.705394)
		(end 124.74575 -236.705648)
		(width 0.1143)
		(layer "In15.Cu")
		(net "GMI_CPU0_G1_CPU1_G3_TX_DN<13>")
	)
	(segment
		(start 153.55697 -197.033388)
		(end 153.36393 -197.014338)
		(width 0.14224)
		(layer "In15.Cu")
		(net "GMI_CPU0_G1_CPU1_G3_TX_DN<13>")
	)
	(segment
		(start 346.748862 -231.84612)
		(end 346.750132 -231.845358)
		(width 0.1143)
		(layer "In15.Cu")
		(net "GMI_CPU0_G1_CPU1_G3_TX_DN<13>")
	)
	(segment
		(start 124.716032 -226.968812)
		(end 124.741686 -226.983544)
		(width 0.1143)
		(layer "In15.Cu")
		(net "GMI_CPU0_G1_CPU1_G3_TX_DN<13>")
	)
	(segment
		(start 346.77985 -239.319816)
		(end 346.748862 -239.302036)
		(width 0.1143)
		(layer "In15.Cu")
		(net "GMI_CPU0_G1_CPU1_G3_TX_DN<13>")
	)
	(segment
		(start 124.74575 -237.68304)
		(end 124.716032 -237.700058)
		(width 0.1143)
		(layer "In15.Cu")
		(net "GMI_CPU0_G1_CPU1_G3_TX_DN<13>")
	)
	(segment
		(start 124.787406 -244.138958)
		(end 124.747782 -244.161818)
		(width 0.1143)
		(layer "In15.Cu")
		(net "GMI_CPU0_G1_CPU1_G3_TX_DN<13>")
	)
	(segment
		(start 345.621102 -247.724168)
		(end 345.919044 -247.724168)
		(width 0.1143)
		(layer "In15.Cu")
		(net "GMI_CPU0_G1_CPU1_G3_TX_DN<13>")
	)
	(segment
		(start 156.852874 -194.153536)
		(end 156.522928 -194.424046)
		(width 0.14224)
		(layer "In15.Cu")
		(net "GMI_CPU0_G1_CPU1_G3_TX_DN<13>")
	)
	(segment
		(start 346.7481 -234.441492)
		(end 346.747084 -234.440984)
		(width 0.1143)
		(layer "In15.Cu")
		(net "GMI_CPU0_G1_CPU1_G3_TX_DN<13>")
	)
	(segment
		(start 346.747084 -228.607366)
		(end 346.7481 -228.606858)
		(width 0.1143)
		(layer "In15.Cu")
		(net "GMI_CPU0_G1_CPU1_G3_TX_DN<13>")
	)
	(segment
		(start 124.78131 -231.182418)
		(end 124.747782 -231.201976)
		(width 0.1143)
		(layer "In15.Cu")
		(net "GMI_CPU0_G1_CPU1_G3_TX_DN<13>")
	)
	(segment
		(start 124.74321 -246.42445)
		(end 124.74575 -246.42572)
		(width 0.1143)
		(layer "In15.Cu")
		(net "GMI_CPU0_G1_CPU1_G3_TX_DN<13>")
	)
	(segment
		(start 124.742702 -242.5446)
		(end 124.74194 -242.545108)
		(width 0.1143)
		(layer "In15.Cu")
		(net "GMI_CPU0_G1_CPU1_G3_TX_DN<13>")
	)
	(segment
		(start 346.7481 -244.806724)
		(end 346.748862 -244.806216)
		(width 0.1143)
		(layer "In15.Cu")
		(net "GMI_CPU0_G1_CPU1_G3_TX_DN<13>")
	)
	(segment
		(start 124.74702 -238.326422)
		(end 124.747782 -238.32693)
		(width 0.1143)
		(layer "In15.Cu")
		(net "GMI_CPU0_G1_CPU1_G3_TX_DN<13>")
	)
	(segment
		(start 345.055952 -221.443042)
		(end 345.00058 -221.38767)
		(width 0.1143)
		(layer "In15.Cu")
		(net "GMI_CPU0_G1_CPU1_G3_TX_DN<13>")
	)
	(segment
		(start 124.806456 -244.124988)
		(end 124.787406 -244.138958)
		(width 0.1143)
		(layer "In15.Cu")
		(net "GMI_CPU0_G1_CPU1_G3_TX_DN<13>")
	)
	(segment
		(start 124.74575 -244.805708)
		(end 124.74702 -244.80647)
		(width 0.1143)
		(layer "In15.Cu")
		(net "GMI_CPU0_G1_CPU1_G3_TX_DN<13>")
	)
	(segment
		(start 124.74702 -241.566446)
		(end 124.747782 -241.566954)
		(width 0.1143)
		(layer "In15.Cu")
		(net "GMI_CPU0_G1_CPU1_G3_TX_DN<13>")
	)
	(segment
		(start 124.716032 -233.448606)
		(end 124.741686 -233.463338)
		(width 0.1143)
		(layer "In15.Cu")
		(net "GMI_CPU0_G1_CPU1_G3_TX_DN<13>")
	)
	(segment
		(start 345.824048 -223.737424)
		(end 345.825826 -223.736408)
		(width 0.1143)
		(layer "In15.Cu")
		(net "GMI_CPU0_G1_CPU1_G3_TX_DN<13>")
	)
	(segment
		(start 346.7481 -230.226616)
		(end 346.77985 -230.208328)
		(width 0.1143)
		(layer "In15.Cu")
		(net "GMI_CPU0_G1_CPU1_G3_TX_DN<13>")
	)
	(segment
		(start 345.34221 -222.293688)
		(end 345.299792 -222.269304)
		(width 0.1143)
		(layer "In15.Cu")
		(net "GMI_CPU0_G1_CPU1_G3_TX_DN<13>")
	)
	(segment
		(start 125.217682 -247.236996)
		(end 125.256798 -247.259856)
		(width 0.1143)
		(layer "In15.Cu")
		(net "GMI_CPU0_G1_CPU1_G3_TX_DN<13>")
	)
	(segment
		(start 124.74702 -245.782338)
		(end 124.74575 -245.7831)
		(width 0.1143)
		(layer "In15.Cu")
		(net "GMI_CPU0_G1_CPU1_G3_TX_DN<13>")
	)
	(segment
		(start 124.747782 -232.821734)
		(end 124.74702 -232.822242)
		(width 0.1143)
		(layer "In15.Cu")
		(net "GMI_CPU0_G1_CPU1_G3_TX_DN<13>")
	)
	(segment
		(start 124.716032 -243.168678)
		(end 124.741686 -243.18341)
		(width 0.1143)
		(layer "In15.Cu")
		(net "GMI_CPU0_G1_CPU1_G3_TX_DN<13>")
	)
	(segment
		(start 346.781628 -229.601268)
		(end 346.7481 -229.58171)
		(width 0.1143)
		(layer "In15.Cu")
		(net "GMI_CPU0_G1_CPU1_G3_TX_DN<13>")
	)
	(segment
		(start 346.7481 -236.061504)
		(end 346.747084 -236.060996)
		(width 0.1143)
		(layer "In15.Cu")
		(net "GMI_CPU0_G1_CPU1_G3_TX_DN<13>")
	)
	(segment
		(start 124.747782 -233.466894)
		(end 124.784104 -233.487976)
		(width 0.1143)
		(layer "In15.Cu")
		(net "GMI_CPU0_G1_CPU1_G3_TX_DN<13>")
	)
	(segment
		(start 346.748862 -227.962206)
		(end 346.7481 -227.961698)
		(width 0.1143)
		(layer "In15.Cu")
		(net "GMI_CPU0_G1_CPU1_G3_TX_DN<13>")
	)
	(segment
		(start 124.745496 -226.34321)
		(end 124.74448 -226.343718)
		(width 0.1143)
		(layer "In15.Cu")
		(net "GMI_CPU0_G1_CPU1_G3_TX_DN<13>")
	)
	(segment
		(start 124.787152 -242.518946)
		(end 124.746258 -242.542568)
		(width 0.1143)
		(layer "In15.Cu")
		(net "GMI_CPU0_G1_CPU1_G3_TX_DN<13>")
	)
	(segment
		(start 346.747084 -244.807232)
		(end 346.7481 -244.806724)
		(width 0.1143)
		(layer "In15.Cu")
		(net "GMI_CPU0_G1_CPU1_G3_TX_DN<13>")
	)
	(segment
		(start 346.747084 -231.847136)
		(end 346.7481 -231.846628)
		(width 0.1143)
		(layer "In15.Cu")
		(net "GMI_CPU0_G1_CPU1_G3_TX_DN<13>")
	)
	(segment
		(start 124.726446 -236.695488)
		(end 124.727208 -236.695996)
		(width 0.1143)
		(layer "In15.Cu")
		(net "GMI_CPU0_G1_CPU1_G3_TX_DN<13>")
	)
	(segment
		(start 346.708984 -243.209572)
		(end 346.747084 -243.18722)
		(width 0.1143)
		(layer "In15.Cu")
		(net "GMI_CPU0_G1_CPU1_G3_TX_DN<13>")
	)
	(segment
		(start 346.2782 -225.53168)
		(end 346.239084 -225.50882)
		(width 0.1143)
		(layer "In15.Cu")
		(net "GMI_CPU0_G1_CPU1_G3_TX_DN<13>")
	)
	(segment
		(start 124.74321 -225.364548)
		(end 124.74575 -225.365818)
		(width 0.1143)
		(layer "In15.Cu")
		(net "GMI_CPU0_G1_CPU1_G3_TX_DN<13>")
	)
	(segment
		(start 345.771724 -223.767904)
		(end 345.808046 -223.746822)
		(width 0.1143)
		(layer "In15.Cu")
		(net "GMI_CPU0_G1_CPU1_G3_TX_DN<13>")
	)
	(segment
		(start 124.787406 -227.00996)
		(end 124.803662 -227.021898)
		(width 0.1143)
		(layer "In15.Cu")
		(net "GMI_CPU0_G1_CPU1_G3_TX_DN<13>")
	)
	(segment
		(start 346.747084 -226.341178)
		(end 346.74556 -226.340162)
		(width 0.1143)
		(layer "In15.Cu")
		(net "GMI_CPU0_G1_CPU1_G3_TX_DN<13>")
	)
	(segment
		(start 124.787152 -225.389948)
		(end 124.80544 -225.403156)
		(width 0.1143)
		(layer "In15.Cu")
		(net "GMI_CPU0_G1_CPU1_G3_TX_DN<13>")
	)
	(segment
		(start 124.716032 -244.78869)
		(end 124.741686 -244.803422)
		(width 0.1143)
		(layer "In15.Cu")
		(net "GMI_CPU0_G1_CPU1_G3_TX_DN<13>")
	)
	(segment
		(start 346.2782 -247.236742)
		(end 346.30868 -247.218962)
		(width 0.1143)
		(layer "In15.Cu")
		(net "GMI_CPU0_G1_CPU1_G3_TX_DN<13>")
	)
	(segment
		(start 162.355022 -189.479428)
		(end 160.855406 -190.70955)
		(width 0.14224)
		(layer "In15.Cu")
		(net "GMI_CPU0_G1_CPU1_G3_TX_DN<13>")
	)
	(segment
		(start 346.748862 -241.566192)
		(end 346.750132 -241.56543)
		(width 0.1143)
		(layer "In15.Cu")
		(net "GMI_CPU0_G1_CPU1_G3_TX_DN<13>")
	)
	(segment
		(start 157.395164 -193.708782)
		(end 157.376114 -193.901822)
		(width 0.14224)
		(layer "In15.Cu")
		(net "GMI_CPU0_G1_CPU1_G3_TX_DN<13>")
	)
	(segment
		(start 346.747084 -239.30102)
		(end 346.74556 -239.300004)
		(width 0.1143)
		(layer "In15.Cu")
		(net "GMI_CPU0_G1_CPU1_G3_TX_DN<13>")
	)
	(segment
		(start 124.747782 -244.161818)
		(end 124.74702 -244.162326)
		(width 0.1143)
		(layer "In15.Cu")
		(net "GMI_CPU0_G1_CPU1_G3_TX_DN<13>")
	)
	(segment
		(start 124.784104 -234.420664)
		(end 124.747782 -234.441746)
		(width 0.1143)
		(layer "In15.Cu")
		(net "GMI_CPU0_G1_CPU1_G3_TX_DN<13>")
	)
	(segment
		(start 346.77985 -234.45978)
		(end 346.748862 -234.442)
		(width 0.1143)
		(layer "In15.Cu")
		(net "GMI_CPU0_G1_CPU1_G3_TX_DN<13>")
	)
	(segment
		(start 346.708984 -241.58956)
		(end 346.747084 -241.567208)
		(width 0.1143)
		(layer "In15.Cu")
		(net "GMI_CPU0_G1_CPU1_G3_TX_DN<13>")
	)
	(segment
		(start 124.786644 -222.14967)
		(end 124.811028 -222.167196)
		(width 0.1143)
		(layer "In15.Cu")
		(net "GMI_CPU0_G1_CPU1_G3_TX_DN<13>")
	)
	(segment
		(start 346.7481 -233.46664)
		(end 346.748862 -233.466132)
		(width 0.1143)
		(layer "In15.Cu")
		(net "GMI_CPU0_G1_CPU1_G3_TX_DN<13>")
	)
	(segment
		(start 124.747782 -231.201976)
		(end 124.715016 -231.221026)
		(width 0.1143)
		(layer "In15.Cu")
		(net "GMI_CPU0_G1_CPU1_G3_TX_DN<13>")
	)
	(segment
		(start 124.80544 -242.505992)
		(end 124.787152 -242.518946)
		(width 0.1143)
		(layer "In15.Cu")
		(net "GMI_CPU0_G1_CPU1_G3_TX_DN<13>")
	)
	(segment
		(start 124.803662 -227.927154)
		(end 124.787406 -227.939092)
		(width 0.1143)
		(layer "In15.Cu")
		(net "GMI_CPU0_G1_CPU1_G3_TX_DN<13>")
	)
	(segment
		(start 346.77985 -227.979986)
		(end 346.748862 -227.962206)
		(width 0.1143)
		(layer "In15.Cu")
		(net "GMI_CPU0_G1_CPU1_G3_TX_DN<13>")
	)
	(segment
		(start 124.74321 -228.604572)
		(end 124.74575 -228.605842)
		(width 0.1143)
		(layer "In15.Cu")
		(net "GMI_CPU0_G1_CPU1_G3_TX_DN<13>")
	)
	(segment
		(start 124.74702 -227.96246)
		(end 124.74575 -227.963222)
		(width 0.1143)
		(layer "In15.Cu")
		(net "GMI_CPU0_G1_CPU1_G3_TX_DN<13>")
	)
	(segment
		(start 251.055378 -191.124078)
		(end 239.538764 -199.188578)
		(width 0.14224)
		(layer "In15.Cu")
		(net "GMI_CPU0_G1_CPU1_G3_TX_DN<13>")
	)
	(segment
		(start 157.724856 -193.438272)
		(end 157.395164 -193.708274)
		(width 0.14224)
		(layer "In15.Cu")
		(net "GMI_CPU0_G1_CPU1_G3_TX_DN<13>")
	)
	(segment
		(start 346.750132 -243.185442)
		(end 346.77985 -243.168424)
		(width 0.1143)
		(layer "In15.Cu")
		(net "GMI_CPU0_G1_CPU1_G3_TX_DN<13>")
	)
	(segment
		(start 124.811028 -223.062038)
		(end 124.787152 -223.079056)
		(width 0.1143)
		(layer "In15.Cu")
		(net "GMI_CPU0_G1_CPU1_G3_TX_DN<13>")
	)
	(segment
		(start 124.716032 -228.588824)
		(end 124.741686 -228.603556)
		(width 0.1143)
		(layer "In15.Cu")
		(net "GMI_CPU0_G1_CPU1_G3_TX_DN<13>")
	)
	(segment
		(start 124.74702 -225.36658)
		(end 124.747782 -225.367088)
		(width 0.1143)
		(layer "In15.Cu")
		(net "GMI_CPU0_G1_CPU1_G3_TX_DN<13>")
	)
	(segment
		(start 346.7481 -243.186712)
		(end 346.748862 -243.186204)
		(width 0.1143)
		(layer "In15.Cu")
		(net "GMI_CPU0_G1_CPU1_G3_TX_DN<13>")
	)
	(segment
		(start 346.747084 -236.060996)
		(end 346.74556 -236.05998)
		(width 0.1143)
		(layer "In15.Cu")
		(net "GMI_CPU0_G1_CPU1_G3_TX_DN<13>")
	)
	(segment
		(start 124.727208 -236.695996)
		(end 124.7394 -236.702092)
		(width 0.1143)
		(layer "In15.Cu")
		(net "GMI_CPU0_G1_CPU1_G3_TX_DN<13>")
	)
	(segment
		(start 346.74556 -244.16004)
		(end 346.708984 -244.138704)
		(width 0.1143)
		(layer "In15.Cu")
		(net "GMI_CPU0_G1_CPU1_G3_TX_DN<13>")
	)
	(segment
		(start 124.80417 -245.747032)
		(end 124.78639 -245.759478)
		(width 0.1143)
		(layer "In15.Cu")
		(net "GMI_CPU0_G1_CPU1_G3_TX_DN<13>")
	)
	(segment
		(start 346.77985 -245.799864)
		(end 346.7481 -245.781576)
		(width 0.1143)
		(layer "In15.Cu")
		(net "GMI_CPU0_G1_CPU1_G3_TX_DN<13>")
	)
	(segment
		(start 124.74702 -231.846374)
		(end 124.747782 -231.846882)
		(width 0.1143)
		(layer "In15.Cu")
		(net "GMI_CPU0_G1_CPU1_G3_TX_DN<13>")
	)
	(segment
		(start 155.650692 -195.13931)
		(end 155.631642 -195.33235)
		(width 0.14224)
		(layer "In15.Cu")
		(net "GMI_CPU0_G1_CPU1_G3_TX_DN<13>")
	)
	(segment
		(start 124.747782 -223.747076)
		(end 124.750576 -223.748854)
		(width 0.1143)
		(layer "In15.Cu")
		(net "GMI_CPU0_G1_CPU1_G3_TX_DN<13>")
	)
	(segment
		(start 124.739146 -226.346766)
		(end 124.716032 -226.360228)
		(width 0.1143)
		(layer "In15.Cu")
		(net "GMI_CPU0_G1_CPU1_G3_TX_DN<13>")
	)
	(segment
		(start 124.747782 -245.78183)
		(end 124.74702 -245.782338)
		(width 0.1143)
		(layer "In15.Cu")
		(net "GMI_CPU0_G1_CPU1_G3_TX_DN<13>")
	)
	(segment
		(start 346.7481 -231.846628)
		(end 346.748862 -231.84612)
		(width 0.1143)
		(layer "In15.Cu")
		(net "GMI_CPU0_G1_CPU1_G3_TX_DN<13>")
	)
	(segment
		(start 346.708984 -235.109512)
		(end 346.747084 -235.08716)
		(width 0.1143)
		(layer "In15.Cu")
		(net "GMI_CPU0_G1_CPU1_G3_TX_DN<13>")
	)
	(segment
		(start 346.748862 -234.442)
		(end 346.7481 -234.441492)
		(width 0.1143)
		(layer "In15.Cu")
		(net "GMI_CPU0_G1_CPU1_G3_TX_DN<13>")
	)
	(segment
		(start 346.748862 -226.342194)
		(end 346.7481 -226.341686)
		(width 0.1143)
		(layer "In15.Cu")
		(net "GMI_CPU0_G1_CPU1_G3_TX_DN<13>")
	)
	(segment
		(start 346.74556 -240.920016)
		(end 346.708984 -240.89868)
		(width 0.1143)
		(layer "In15.Cu")
		(net "GMI_CPU0_G1_CPU1_G3_TX_DN<13>")
	)
	(segment
		(start 124.74448 -226.343718)
		(end 124.743718 -226.344226)
		(width 0.1143)
		(layer "In15.Cu")
		(net "GMI_CPU0_G1_CPU1_G3_TX_DN<13>")
	)
	(segment
		(start 124.746258 -242.542568)
		(end 124.745496 -242.543076)
		(width 0.1143)
		(layer "In15.Cu")
		(net "GMI_CPU0_G1_CPU1_G3_TX_DN<13>")
	)
	(segment
		(start 345.808808 -223.746314)
		(end 345.810078 -223.745552)
		(width 0.1143)
		(layer "In15.Cu")
		(net "GMI_CPU0_G1_CPU1_G3_TX_DN<13>")
	)
	(segment
		(start 124.747782 -239.301782)
		(end 124.74702 -239.30229)
		(width 0.1143)
		(layer "In15.Cu")
		(net "GMI_CPU0_G1_CPU1_G3_TX_DN<13>")
	)
	(segment
		(start 345.817952 -223.74098)
		(end 345.819984 -223.73971)
		(width 0.1143)
		(layer "In15.Cu")
		(net "GMI_CPU0_G1_CPU1_G3_TX_DN<13>")
	)
	(segment
		(start 346.7481 -239.946688)
		(end 346.748862 -239.94618)
		(width 0.1143)
		(layer "In15.Cu")
		(net "GMI_CPU0_G1_CPU1_G3_TX_DN<13>")
	)
	(segment
		(start 346.747084 -244.161056)
		(end 346.74556 -244.16004)
		(width 0.1143)
		(layer "In15.Cu")
		(net "GMI_CPU0_G1_CPU1_G3_TX_DN<13>")
	)
	(segment
		(start 346.750132 -246.425466)
		(end 346.77985 -246.408448)
		(width 0.1143)
		(layer "In15.Cu")
		(net "GMI_CPU0_G1_CPU1_G3_TX_DN<13>")
	)
	(segment
		(start 124.559822 -221.248732)
		(end 124.559822 -221.804484)
		(width 0.1143)
		(layer "In15.Cu")
		(net "GMI_CPU0_G1_CPU1_G3_TX_DN<13>")
	)
	(segment
		(start 346.748862 -228.60635)
		(end 346.751402 -228.604826)
		(width 0.1143)
		(layer "In15.Cu")
		(net "GMI_CPU0_G1_CPU1_G3_TX_DN<13>")
	)
	(segment
		(start 124.74575 -240.923064)
		(end 124.716032 -240.940082)
		(width 0.1143)
		(layer "In15.Cu")
		(net "GMI_CPU0_G1_CPU1_G3_TX_DN<13>")
	)
	(segment
		(start 155.631642 -195.33235)
		(end 155.301442 -195.603114)
		(width 0.14224)
		(layer "In15.Cu")
		(net "GMI_CPU0_G1_CPU1_G3_TX_DN<13>")
	)
	(segment
		(start 345.813634 -223.74352)
		(end 345.816174 -223.741996)
		(width 0.1143)
		(layer "In15.Cu")
		(net "GMI_CPU0_G1_CPU1_G3_TX_DN<13>")
	)
	(segment
		(start 346.7481 -231.201722)
		(end 346.708984 -231.178862)
		(width 0.1143)
		(layer "In15.Cu")
		(net "GMI_CPU0_G1_CPU1_G3_TX_DN<13>")
	)
	(segment
		(start 303.696116 -189.451234)
		(end 303.684432 -189.45098)
		(width 0.14224)
		(layer "In15.Cu")
		(net "GMI_CPU0_G1_CPU1_G3_TX_DN<13>")
	)
	(segment
		(start 346.77985 -240.939828)
		(end 346.748862 -240.922048)
		(width 0.1143)
		(layer "In15.Cu")
		(net "GMI_CPU0_G1_CPU1_G3_TX_DN<13>")
	)
	(segment
		(start 346.750132 -231.845358)
		(end 346.77985 -231.82834)
		(width 0.1143)
		(layer "In15.Cu")
		(net "GMI_CPU0_G1_CPU1_G3_TX_DN<13>")
	)
	(segment
		(start 124.716032 -230.208582)
		(end 124.74448 -230.224838)
		(width 0.1143)
		(layer "In15.Cu")
		(net "GMI_CPU0_G1_CPU1_G3_TX_DN<13>")
	)
	(segment
		(start 318.440054 -196.098922)
		(end 309.008272 -189.451488)
		(width 0.14224)
		(layer "In15.Cu")
		(net "GMI_CPU0_G1_CPU1_G3_TX_DN<13>")
	)
	(segment
		(start 346.7481 -242.541552)
		(end 346.747084 -242.541044)
		(width 0.1143)
		(layer "In15.Cu")
		(net "GMI_CPU0_G1_CPU1_G3_TX_DN<13>")
	)
	(segment
		(start 124.747782 -240.921794)
		(end 124.74702 -240.922302)
		(width 0.1143)
		(layer "In15.Cu")
		(net "GMI_CPU0_G1_CPU1_G3_TX_DN<13>")
	)
	(segment
		(start 124.74702 -244.162326)
		(end 124.74575 -244.163088)
		(width 0.1143)
		(layer "In15.Cu")
		(net "GMI_CPU0_G1_CPU1_G3_TX_DN<13>")
	)
	(segment
		(start 344.95486 -220.331538)
		(end 343.027 -216.25814)
		(width 0.14224)
		(layer "In15.Cu")
		(net "GMI_CPU0_G1_CPU1_G3_TX_DN<13>")
	)
	(segment
		(start 124.747782 -223.101916)
		(end 124.74702 -223.102424)
		(width 0.1143)
		(layer "In15.Cu")
		(net "GMI_CPU0_G1_CPU1_G3_TX_DN<13>")
	)
	(segment
		(start 154.236166 -196.299074)
		(end 153.90622 -196.569584)
		(width 0.14224)
		(layer "In15.Cu")
		(net "GMI_CPU0_G1_CPU1_G3_TX_DN<13>")
	)
	(segment
		(start 124.742702 -226.344734)
		(end 124.74194 -226.345242)
		(width 0.1143)
		(layer "In15.Cu")
		(net "GMI_CPU0_G1_CPU1_G3_TX_DN<13>")
	)
	(segment
		(start 124.787152 -239.279176)
		(end 124.747782 -239.301782)
		(width 0.1143)
		(layer "In15.Cu")
		(net "GMI_CPU0_G1_CPU1_G3_TX_DN<13>")
	)
	(segment
		(start 124.740162 -226.346258)
		(end 124.739146 -226.346766)
		(width 0.1143)
		(layer "In15.Cu")
		(net "GMI_CPU0_G1_CPU1_G3_TX_DN<13>")
	)
	(segment
		(start 124.74575 -233.465624)
		(end 124.74702 -233.466386)
		(width 0.1143)
		(layer "In15.Cu")
		(net "GMI_CPU0_G1_CPU1_G3_TX_DN<13>")
	)
	(segment
		(start 124.716032 -241.548666)
		(end 124.741686 -241.563398)
		(width 0.1143)
		(layer "In15.Cu")
		(net "GMI_CPU0_G1_CPU1_G3_TX_DN<13>")
	)
	(segment
		(start 124.7394 -236.702092)
		(end 124.74575 -236.705394)
		(width 0.1143)
		(layer "In15.Cu")
		(net "GMI_CPU0_G1_CPU1_G3_TX_DN<13>")
	)
	(segment
		(start 346.7481 -241.5667)
		(end 346.748862 -241.566192)
		(width 0.1143)
		(layer "In15.Cu")
		(net "GMI_CPU0_G1_CPU1_G3_TX_DN<13>")
	)
	(segment
		(start 124.74702 -228.606604)
		(end 124.747782 -228.607112)
		(width 0.1143)
		(layer "In15.Cu")
		(net "GMI_CPU0_G1_CPU1_G3_TX_DN<13>")
	)
	(segment
		(start 124.74575 -227.963222)
		(end 124.716032 -227.98024)
		(width 0.1143)
		(layer "In15.Cu")
		(net "GMI_CPU0_G1_CPU1_G3_TX_DN<13>")
	)
	(segment
		(start 124.716032 -223.728788)
		(end 124.741686 -223.74352)
		(width 0.1143)
		(layer "In15.Cu")
		(net "GMI_CPU0_G1_CPU1_G3_TX_DN<13>")
	)
	(segment
		(start 211.720684 -190.123318)
		(end 206.99222 -189.289944)
		(width 0.14224)
		(layer "In15.Cu")
		(net "GMI_CPU0_G1_CPU1_G3_TX_DN<13>")
	)
	(segment
		(start 124.74702 -232.822242)
		(end 124.74575 -232.823004)
		(width 0.1143)
		(layer "In15.Cu")
		(net "GMI_CPU0_G1_CPU1_G3_TX_DN<13>")
	)
	(segment
		(start 124.74702 -237.682278)
		(end 124.74575 -237.68304)
		(width 0.1143)
		(layer "In15.Cu")
		(net "GMI_CPU0_G1_CPU1_G3_TX_DN<13>")
	)
	(segment
		(start 124.716032 -238.308642)
		(end 124.741686 -238.323374)
		(width 0.1143)
		(layer "In15.Cu")
		(net "GMI_CPU0_G1_CPU1_G3_TX_DN<13>")
	)
	(segment
		(start 345.819984 -223.73971)
		(end 345.822524 -223.738186)
		(width 0.1143)
		(layer "In15.Cu")
		(net "GMI_CPU0_G1_CPU1_G3_TX_DN<13>")
	)
	(segment
		(start 125.576838 -247.724422)
		(end 125.87478 -247.724422)
		(width 0.1143)
		(layer "In15.Cu")
		(net "GMI_CPU0_G1_CPU1_G3_TX_DN<13>")
	)
	(segment
		(start 124.74575 -234.443016)
		(end 124.716032 -234.460034)
		(width 0.1143)
		(layer "In15.Cu")
		(net "GMI_CPU0_G1_CPU1_G3_TX_DN<13>")
	)
	(segment
		(start 124.74702 -224.722436)
		(end 124.74575 -224.723198)
		(width 0.1143)
		(layer "In15.Cu")
		(net "GMI_CPU0_G1_CPU1_G3_TX_DN<13>")
	)
	(segment
		(start 124.74702 -246.426482)
		(end 124.747782 -246.42699)
		(width 0.1143)
		(layer "In15.Cu")
		(net "GMI_CPU0_G1_CPU1_G3_TX_DN<13>")
	)
	(segment
		(start 124.74575 -239.303052)
		(end 124.716032 -239.32007)
		(width 0.1143)
		(layer "In15.Cu")
		(net "GMI_CPU0_G1_CPU1_G3_TX_DN<13>")
	)
	(segment
		(start 346.30868 -225.54946)
		(end 346.2782 -225.53168)
		(width 0.1143)
		(layer "In15.Cu")
		(net "GMI_CPU0_G1_CPU1_G3_TX_DN<13>")
	)
	(segment
		(start 346.748862 -226.986338)
		(end 346.77985 -226.968558)
		(width 0.1143)
		(layer "In15.Cu")
		(net "GMI_CPU0_G1_CPU1_G3_TX_DN<13>")
	)
	(segment
		(start 124.749306 -224.720912)
		(end 124.74702 -224.722436)
		(width 0.1143)
		(layer "In15.Cu")
		(net "GMI_CPU0_G1_CPU1_G3_TX_DN<13>")
	)
	(segment
		(start 346.750132 -244.805454)
		(end 346.77985 -244.788436)
		(width 0.1143)
		(layer "In15.Cu")
		(net "GMI_CPU0_G1_CPU1_G3_TX_DN<13>")
	)
	(segment
		(start 346.747084 -233.467148)
		(end 346.7481 -233.46664)
		(width 0.1143)
		(layer "In15.Cu")
		(net "GMI_CPU0_G1_CPU1_G3_TX_DN<13>")
	)
	(segment
		(start 346.750132 -238.325406)
		(end 346.77985 -238.308388)
		(width 0.1143)
		(layer "In15.Cu")
		(net "GMI_CPU0_G1_CPU1_G3_TX_DN<13>")
	)
	(segment
		(start 124.741686 -223.74352)
		(end 124.74321 -223.744536)
		(width 0.1143)
		(layer "In15.Cu")
		(net "GMI_CPU0_G1_CPU1_G3_TX_DN<13>")
	)
	(segment
		(start 346.74556 -239.300004)
		(end 346.708984 -239.278668)
		(width 0.1143)
		(layer "In15.Cu")
		(net "GMI_CPU0_G1_CPU1_G3_TX_DN<13>")
	)
	(segment
		(start 345.837002 -223.730058)
		(end 345.839796 -223.728534)
		(width 0.1143)
		(layer "In15.Cu")
		(net "GMI_CPU0_G1_CPU1_G3_TX_DN<13>")
	)
	(segment
		(start 346.74302 -226.338638)
		(end 346.742004 -226.33813)
		(width 0.1143)
		(layer "In15.Cu")
		(net "GMI_CPU0_G1_CPU1_G3_TX_DN<13>")
	)
	(segment
		(start 346.7481 -246.426736)
		(end 346.748862 -246.426228)
		(width 0.1143)
		(layer "In15.Cu")
		(net "GMI_CPU0_G1_CPU1_G3_TX_DN<13>")
	)
	(segment
		(start 124.747782 -238.32693)
		(end 124.750322 -238.328708)
		(width 0.1143)
		(layer "In15.Cu")
		(net "GMI_CPU0_G1_CPU1_G3_TX_DN<13>")
	)
	(segment
		(start 153.90622 -196.569584)
		(end 153.88717 -196.762624)
		(width 0.14224)
		(layer "In15.Cu")
		(net "GMI_CPU0_G1_CPU1_G3_TX_DN<13>")
	)
	(segment
		(start 124.739908 -239.941608)
		(end 124.747782 -239.946942)
		(width 0.1143)
		(layer "In15.Cu")
		(net "GMI_CPU0_G1_CPU1_G3_TX_DN<13>")
	)
	(segment
		(start 346.77985 -237.699804)
		(end 346.7481 -237.681516)
		(width 0.1143)
		(layer "In15.Cu")
		(net "GMI_CPU0_G1_CPU1_G3_TX_DN<13>")
	)
	(arc
		(start 124.716032 -234.460034)
		(mid 124.560104 -234.764326)
		(end 124.716032 -235.068618)
		(width 0.1143)
		(layer "In15.Cu")
		(net "GMI_CPU0_G1_CPU1_G3_TX_DN<13>")
	)
	(arc
		(start 124.716032 -227.98024)
		(mid 124.560104 -228.284532)
		(end 124.716032 -228.588824)
		(width 0.1143)
		(layer "In15.Cu")
		(net "GMI_CPU0_G1_CPU1_G3_TX_DN<13>")
	)
	(arc
		(start 346.77985 -241.548412)
		(mid 346.935778 -241.24412)
		(end 346.77985 -240.939828)
		(width 0.1143)
		(layer "In15.Cu")
		(net "GMI_CPU0_G1_CPU1_G3_TX_DN<13>")
	)
	(arc
		(start 345.995752 -225.044254)
		(mid 345.954497 -224.873283)
		(end 345.839796 -224.739962)
		(width 0.1143)
		(layer "In15.Cu")
		(net "GMI_CPU0_G1_CPU1_G3_TX_DN<13>")
	)
	(arc
		(start 345.299792 -222.269304)
		(mid 345.120599 -222.066794)
		(end 345.055952 -221.80423)
		(width 0.1143)
		(layer "In15.Cu")
		(net "GMI_CPU0_G1_CPU1_G3_TX_DN<13>")
	)
	(arc
		(start 346.005658 -247.618504)
		(mid 346.087091 -247.416106)
		(end 346.239084 -247.259602)
		(width 0.1143)
		(layer "In15.Cu")
		(net "GMI_CPU0_G1_CPU1_G3_TX_DN<13>")
	)
	(arc
		(start 124.716032 -244.180106)
		(mid 124.560104 -244.484398)
		(end 124.716032 -244.78869)
		(width 0.1143)
		(layer "In15.Cu")
		(net "GMI_CPU0_G1_CPU1_G3_TX_DN<13>")
	)
	(arc
		(start 346.77985 -233.448352)
		(mid 346.935778 -233.14406)
		(end 346.77985 -232.839768)
		(width 0.1143)
		(layer "In15.Cu")
		(net "GMI_CPU0_G1_CPU1_G3_TX_DN<13>")
	)
	(arc
		(start 124.803662 -227.021898)
		(mid 125.035412 -227.474526)
		(end 124.803662 -227.927154)
		(width 0.1143)
		(layer "In15.Cu")
		(net "GMI_CPU0_G1_CPU1_G3_TX_DN<13>")
	)
	(arc
		(start 346.77985 -243.168424)
		(mid 346.935778 -242.864132)
		(end 346.77985 -242.55984)
		(width 0.1143)
		(layer "In15.Cu")
		(net "GMI_CPU0_G1_CPU1_G3_TX_DN<13>")
	)
	(arc
		(start 346.77985 -230.208328)
		(mid 346.894526 -230.074994)
		(end 346.935806 -229.904036)
		(width 0.1143)
		(layer "In15.Cu")
		(net "GMI_CPU0_G1_CPU1_G3_TX_DN<13>")
	)
	(arc
		(start 124.806456 -243.223796)
		(mid 125.037085 -243.674392)
		(end 124.806456 -244.124988)
		(width 0.1143)
		(layer "In15.Cu")
		(net "GMI_CPU0_G1_CPU1_G3_TX_DN<13>")
	)
	(arc
		(start 346.77985 -235.068364)
		(mid 346.935778 -234.764072)
		(end 346.77985 -234.45978)
		(width 0.1143)
		(layer "In15.Cu")
		(net "GMI_CPU0_G1_CPU1_G3_TX_DN<13>")
	)
	(arc
		(start 124.798328 -233.497882)
		(mid 125.025711 -233.95432)
		(end 124.798328 -234.410758)
		(width 0.1143)
		(layer "In15.Cu")
		(net "GMI_CPU0_G1_CPU1_G3_TX_DN<13>")
	)
	(arc
		(start 124.714254 -231.221534)
		(mid 124.600847 -231.354423)
		(end 124.560076 -231.524302)
		(width 0.1143)
		(layer "In15.Cu")
		(net "GMI_CPU0_G1_CPU1_G3_TX_DN<13>")
	)
	(arc
		(start 124.716032 -240.940082)
		(mid 124.560104 -241.244374)
		(end 124.716032 -241.548666)
		(width 0.1143)
		(layer "In15.Cu")
		(net "GMI_CPU0_G1_CPU1_G3_TX_DN<13>")
	)
	(arc
		(start 346.239084 -225.50882)
		(mid 346.060271 -225.30647)
		(end 345.995752 -225.044254)
		(width 0.1143)
		(layer "In15.Cu")
		(net "GMI_CPU0_G1_CPU1_G3_TX_DN<13>")
	)
	(arc
		(start 345.756484 -224.689924)
		(mid 345.531313 -224.234248)
		(end 345.756484 -223.778572)
		(width 0.1143)
		(layer "In15.Cu")
		(net "GMI_CPU0_G1_CPU1_G3_TX_DN<13>")
	)
	(arc
		(start 124.798328 -234.410758)
		(mid 124.791254 -234.415765)
		(end 124.784104 -234.420664)
		(width 0.1143)
		(layer "In15.Cu")
		(net "GMI_CPU0_G1_CPU1_G3_TX_DN<13>")
	)
	(arc
		(start 124.762006 -246.435118)
		(mid 124.967459 -246.641473)
		(end 125.042676 -246.922798)
		(width 0.1143)
		(layer "In15.Cu")
		(net "GMI_CPU0_G1_CPU1_G3_TX_DN<13>")
	)
	(arc
		(start 346.77985 -238.308388)
		(mid 346.935778 -238.004096)
		(end 346.77985 -237.699804)
		(width 0.1143)
		(layer "In15.Cu")
		(net "GMI_CPU0_G1_CPU1_G3_TX_DN<13>")
	)
	(arc
		(start 346.708984 -239.278668)
		(mid 346.465657 -238.814102)
		(end 346.708984 -238.349536)
		(width 0.1143)
		(layer "In15.Cu")
		(net "GMI_CPU0_G1_CPU1_G3_TX_DN<13>")
	)
	(arc
		(start 346.001848 -247.641364)
		(mid 346.003636 -247.629915)
		(end 346.005658 -247.618504)
		(width 0.1143)
		(layer "In15.Cu")
		(net "GMI_CPU0_G1_CPU1_G3_TX_DN<13>")
	)
	(arc
		(start 346.708984 -231.178862)
		(mid 346.530171 -230.976512)
		(end 346.465652 -230.714296)
		(width 0.1143)
		(layer "In15.Cu")
		(net "GMI_CPU0_G1_CPU1_G3_TX_DN<13>")
	)
	(arc
		(start 124.802138 -231.880664)
		(mid 125.034391 -232.334488)
		(end 124.802138 -232.788206)
		(width 0.1143)
		(layer "In15.Cu")
		(net "GMI_CPU0_G1_CPU1_G3_TX_DN<13>")
	)
	(arc
		(start 125.042676 -246.934228)
		(mid 125.089567 -247.109094)
		(end 125.217682 -247.236996)
		(width 0.1143)
		(layer "In15.Cu")
		(net "GMI_CPU0_G1_CPU1_G3_TX_DN<13>")
	)
	(arc
		(start 124.716032 -226.360228)
		(mid 124.560104 -226.66452)
		(end 124.716032 -226.968812)
		(width 0.1143)
		(layer "In15.Cu")
		(net "GMI_CPU0_G1_CPU1_G3_TX_DN<13>")
	)
	(arc
		(start 125.353572 -247.344946)
		(mid 125.440794 -247.472424)
		(end 125.490224 -247.618758)
		(width 0.1143)
		(layer "In15.Cu")
		(net "GMI_CPU0_G1_CPU1_G3_TX_DN<13>")
	)
	(arc
		(start 124.747782 -236.706918)
		(mid 125.028429 -237.194344)
		(end 124.747782 -237.68177)
		(width 0.1143)
		(layer "In15.Cu")
		(net "GMI_CPU0_G1_CPU1_G3_TX_DN<13>")
	)
	(arc
		(start 346.708984 -229.55885)
		(mid 346.465657 -229.094284)
		(end 346.708984 -228.629718)
		(width 0.1143)
		(layer "In15.Cu")
		(net "GMI_CPU0_G1_CPU1_G3_TX_DN<13>")
	)
	(arc
		(start 346.708984 -232.79862)
		(mid 346.465657 -232.334054)
		(end 346.708984 -231.869488)
		(width 0.1143)
		(layer "In15.Cu")
		(net "GMI_CPU0_G1_CPU1_G3_TX_DN<13>")
	)
	(arc
		(start 124.715778 -239.320324)
		(mid 124.559967 -239.627816)
		(end 124.721366 -239.932464)
		(width 0.1143)
		(layer "In15.Cu")
		(net "GMI_CPU0_G1_CPU1_G3_TX_DN<13>")
	)
	(arc
		(start 346.708984 -227.938838)
		(mid 346.465657 -227.474272)
		(end 346.708984 -227.009706)
		(width 0.1143)
		(layer "In15.Cu")
		(net "GMI_CPU0_G1_CPU1_G3_TX_DN<13>")
	)
	(arc
		(start 346.30868 -247.218962)
		(mid 346.424107 -247.085586)
		(end 346.465652 -246.914162)
		(width 0.1143)
		(layer "In15.Cu")
		(net "GMI_CPU0_G1_CPU1_G3_TX_DN<13>")
	)
	(arc
		(start 124.716032 -224.740216)
		(mid 124.560104 -225.044508)
		(end 124.716032 -225.3488)
		(width 0.1143)
		(layer "In15.Cu")
		(net "GMI_CPU0_G1_CPU1_G3_TX_DN<13>")
	)
	(arc
		(start 124.74829 -230.227632)
		(mid 124.954512 -230.433276)
		(end 125.029976 -230.71455)
		(width 0.1143)
		(layer "In15.Cu")
		(net "GMI_CPU0_G1_CPU1_G3_TX_DN<13>")
	)
	(arc
		(start 124.714254 -229.601522)
		(mid 124.600847 -229.734411)
		(end 124.560076 -229.90429)
		(width 0.1143)
		(layer "In15.Cu")
		(net "GMI_CPU0_G1_CPU1_G3_TX_DN<13>")
	)
	(arc
		(start 346.465652 -246.914162)
		(mid 346.530167 -246.651943)
		(end 346.708984 -246.449596)
		(width 0.1143)
		(layer "In15.Cu")
		(net "GMI_CPU0_G1_CPU1_G3_TX_DN<13>")
	)
	(arc
		(start 124.716032 -223.120204)
		(mid 124.560104 -223.424496)
		(end 124.716032 -223.728788)
		(width 0.1143)
		(layer "In15.Cu")
		(net "GMI_CPU0_G1_CPU1_G3_TX_DN<13>")
	)
	(arc
		(start 345.771724 -224.700592)
		(mid 345.76406 -224.695321)
		(end 345.756484 -224.689924)
		(width 0.1143)
		(layer "In15.Cu")
		(net "GMI_CPU0_G1_CPU1_G3_TX_DN<13>")
	)
	(arc
		(start 346.465652 -225.85426)
		(mid 346.424103 -225.682838)
		(end 346.30868 -225.54946)
		(width 0.1143)
		(layer "In15.Cu")
		(net "GMI_CPU0_G1_CPU1_G3_TX_DN<13>")
	)
	(arc
		(start 124.560076 -231.524302)
		(mid 124.601331 -231.695273)
		(end 124.716032 -231.828594)
		(width 0.1143)
		(layer "In15.Cu")
		(net "GMI_CPU0_G1_CPU1_G3_TX_DN<13>")
	)
	(arc
		(start 346.708984 -236.038644)
		(mid 346.465657 -235.574078)
		(end 346.708984 -235.109512)
		(width 0.1143)
		(layer "In15.Cu")
		(net "GMI_CPU0_G1_CPU1_G3_TX_DN<13>")
	)
	(arc
		(start 124.560076 -229.90429)
		(mid 124.601331 -230.075261)
		(end 124.716032 -230.208582)
		(width 0.1143)
		(layer "In15.Cu")
		(net "GMI_CPU0_G1_CPU1_G3_TX_DN<13>")
	)
	(arc
		(start 346.465652 -230.714296)
		(mid 346.530888 -230.450705)
		(end 346.711524 -230.247952)
		(width 0.1143)
		(layer "In15.Cu")
		(net "GMI_CPU0_G1_CPU1_G3_TX_DN<13>")
	)
	(arc
		(start 124.716032 -236.080046)
		(mid 124.559907 -236.387615)
		(end 124.721366 -236.69244)
		(width 0.1143)
		(layer "In15.Cu")
		(net "GMI_CPU0_G1_CPU1_G3_TX_DN<13>")
	)
	(arc
		(start 124.716032 -237.700058)
		(mid 124.560104 -238.00435)
		(end 124.716032 -238.308642)
		(width 0.1143)
		(layer "In15.Cu")
		(net "GMI_CPU0_G1_CPU1_G3_TX_DN<13>")
	)
	(arc
		(start 345.756484 -223.778572)
		(mid 345.76406 -223.773176)
		(end 345.771724 -223.767904)
		(width 0.1143)
		(layer "In15.Cu")
		(net "GMI_CPU0_G1_CPU1_G3_TX_DN<13>")
	)
	(arc
		(start 124.80544 -225.403156)
		(mid 125.036788 -225.854694)
		(end 124.80544 -226.306126)
		(width 0.1143)
		(layer "In15.Cu")
		(net "GMI_CPU0_G1_CPU1_G3_TX_DN<13>")
	)
	(arc
		(start 346.708984 -226.318826)
		(mid 346.530171 -226.116476)
		(end 346.465652 -225.85426)
		(width 0.1143)
		(layer "In15.Cu")
		(net "GMI_CPU0_G1_CPU1_G3_TX_DN<13>")
	)
	(arc
		(start 124.808742 -238.365284)
		(mid 125.038768 -238.814356)
		(end 124.808742 -239.263428)
		(width 0.1143)
		(layer "In15.Cu")
		(net "GMI_CPU0_G1_CPU1_G3_TX_DN<13>")
	)
	(arc
		(start 345.525852 -222.614236)
		(mid 345.476691 -222.42952)
		(end 345.34221 -222.293688)
		(width 0.1143)
		(layer "In15.Cu")
		(net "GMI_CPU0_G1_CPU1_G3_TX_DN<13>")
	)
	(arc
		(start 124.814584 -223.789748)
		(mid 125.042584 -224.234502)
		(end 124.814584 -224.679256)
		(width 0.1143)
		(layer "In15.Cu")
		(net "GMI_CPU0_G1_CPU1_G3_TX_DN<13>")
	)
	(arc
		(start 346.935806 -231.524048)
		(mid 346.895044 -231.354164)
		(end 346.781628 -231.22128)
		(width 0.1143)
		(layer "In15.Cu")
		(net "GMI_CPU0_G1_CPU1_G3_TX_DN<13>")
	)
	(arc
		(start 124.784104 -233.487976)
		(mid 124.791253 -233.492876)
		(end 124.798328 -233.497882)
		(width 0.1143)
		(layer "In15.Cu")
		(net "GMI_CPU0_G1_CPU1_G3_TX_DN<13>")
	)
	(arc
		(start 346.708984 -244.138704)
		(mid 346.465657 -243.674138)
		(end 346.708984 -243.209572)
		(width 0.1143)
		(layer "In15.Cu")
		(net "GMI_CPU0_G1_CPU1_G3_TX_DN<13>")
	)
	(arc
		(start 124.797566 -231.171242)
		(mid 124.790871 -231.176118)
		(end 124.784104 -231.180894)
		(width 0.1143)
		(layer "In15.Cu")
		(net "GMI_CPU0_G1_CPU1_G3_TX_DN<13>")
	)
	(arc
		(start 124.80544 -241.603022)
		(mid 125.036788 -242.05456)
		(end 124.80544 -242.505992)
		(width 0.1143)
		(layer "In15.Cu")
		(net "GMI_CPU0_G1_CPU1_G3_TX_DN<13>")
	)
	(arc
		(start 346.77985 -228.58857)
		(mid 346.935778 -228.284278)
		(end 346.77985 -227.979986)
		(width 0.1143)
		(layer "In15.Cu")
		(net "GMI_CPU0_G1_CPU1_G3_TX_DN<13>")
	)
	(arc
		(start 346.708984 -237.658656)
		(mid 346.465657 -237.19409)
		(end 346.708984 -236.729524)
		(width 0.1143)
		(layer "In15.Cu")
		(net "GMI_CPU0_G1_CPU1_G3_TX_DN<13>")
	)
	(arc
		(start 346.708984 -234.418632)
		(mid 346.465657 -233.954066)
		(end 346.708984 -233.4895)
		(width 0.1143)
		(layer "In15.Cu")
		(net "GMI_CPU0_G1_CPU1_G3_TX_DN<13>")
	)
	(arc
		(start 346.77985 -246.408448)
		(mid 346.935778 -246.104156)
		(end 346.77985 -245.799864)
		(width 0.1143)
		(layer "In15.Cu")
		(net "GMI_CPU0_G1_CPU1_G3_TX_DN<13>")
	)
	(arc
		(start 345.839796 -223.728534)
		(mid 345.995724 -223.424242)
		(end 345.839796 -223.11995)
		(width 0.1143)
		(layer "In15.Cu")
		(net "GMI_CPU0_G1_CPU1_G3_TX_DN<13>")
	)
	(arc
		(start 124.747782 -239.946942)
		(mid 125.028429 -240.434368)
		(end 124.747782 -240.921794)
		(width 0.1143)
		(layer "In15.Cu")
		(net "GMI_CPU0_G1_CPU1_G3_TX_DN<13>")
	)
	(arc
		(start 346.77985 -226.968558)
		(mid 346.935778 -226.664266)
		(end 346.77985 -226.359974)
		(width 0.1143)
		(layer "In15.Cu")
		(net "GMI_CPU0_G1_CPU1_G3_TX_DN<13>")
	)
	(arc
		(start 346.708984 -242.518692)
		(mid 346.465657 -242.054126)
		(end 346.708984 -241.58956)
		(width 0.1143)
		(layer "In15.Cu")
		(net "GMI_CPU0_G1_CPU1_G3_TX_DN<13>")
	)
	(arc
		(start 124.716032 -232.840022)
		(mid 124.560104 -233.144314)
		(end 124.716032 -233.448606)
		(width 0.1143)
		(layer "In15.Cu")
		(net "GMI_CPU0_G1_CPU1_G3_TX_DN<13>")
	)
	(arc
		(start 124.559822 -221.804484)
		(mid 124.601077 -221.975455)
		(end 124.715778 -222.108776)
		(width 0.1143)
		(layer "In15.Cu")
		(net "GMI_CPU0_G1_CPU1_G3_TX_DN<13>")
	)
	(arc
		(start 346.708984 -240.89868)
		(mid 346.465657 -240.434114)
		(end 346.708984 -239.969548)
		(width 0.1143)
		(layer "In15.Cu")
		(net "GMI_CPU0_G1_CPU1_G3_TX_DN<13>")
	)
	(arc
		(start 125.256798 -247.259856)
		(mid 125.30761 -247.299642)
		(end 125.353572 -247.344946)
		(width 0.1143)
		(layer "In15.Cu")
		(net "GMI_CPU0_G1_CPU1_G3_TX_DN<13>")
	)
	(arc
		(start 124.716032 -245.800118)
		(mid 124.560104 -246.10441)
		(end 124.716032 -246.408702)
		(width 0.1143)
		(layer "In15.Cu")
		(net "GMI_CPU0_G1_CPU1_G3_TX_DN<13>")
	)
	(arc
		(start 125.029976 -230.71455)
		(mid 124.968531 -230.970762)
		(end 124.797566 -231.171242)
		(width 0.1143)
		(layer "In15.Cu")
		(net "GMI_CPU0_G1_CPU1_G3_TX_DN<13>")
	)
	(arc
		(start 124.80417 -244.841776)
		(mid 125.036449 -245.294404)
		(end 124.80417 -245.747032)
		(width 0.1143)
		(layer "In15.Cu")
		(net "GMI_CPU0_G1_CPU1_G3_TX_DN<13>")
	)
	(arc
		(start 346.77985 -231.82834)
		(mid 346.894526 -231.695006)
		(end 346.935806 -231.524048)
		(width 0.1143)
		(layer "In15.Cu")
		(net "GMI_CPU0_G1_CPU1_G3_TX_DN<13>")
	)
	(arc
		(start 124.747782 -235.086906)
		(mid 125.028429 -235.574332)
		(end 124.747782 -236.061758)
		(width 0.1143)
		(layer "In15.Cu")
		(net "GMI_CPU0_G1_CPU1_G3_TX_DN<13>")
	)
	(arc
		(start 124.811028 -222.167196)
		(mid 125.040239 -222.61467)
		(end 124.811028 -223.062038)
		(width 0.1143)
		(layer "In15.Cu")
		(net "GMI_CPU0_G1_CPU1_G3_TX_DN<13>")
	)
	(arc
		(start 124.747782 -228.607112)
		(mid 124.954405 -228.812891)
		(end 125.029976 -229.094538)
		(width 0.1143)
		(layer "In15.Cu")
		(net "GMI_CPU0_G1_CPU1_G3_TX_DN<13>")
	)
	(arc
		(start 124.716032 -242.560094)
		(mid 124.560104 -242.864386)
		(end 124.716032 -243.168678)
		(width 0.1143)
		(layer "In15.Cu")
		(net "GMI_CPU0_G1_CPU1_G3_TX_DN<13>")
	)
	(arc
		(start 346.935806 -229.904036)
		(mid 346.895044 -229.734152)
		(end 346.781628 -229.601268)
		(width 0.1143)
		(layer "In15.Cu")
		(net "GMI_CPU0_G1_CPU1_G3_TX_DN<13>")
	)
	(arc
		(start 346.77985 -244.788436)
		(mid 346.935778 -244.484144)
		(end 346.77985 -244.179852)
		(width 0.1143)
		(layer "In15.Cu")
		(net "GMI_CPU0_G1_CPU1_G3_TX_DN<13>")
	)
	(arc
		(start 346.77985 -239.9284)
		(mid 346.935778 -239.624108)
		(end 346.77985 -239.319816)
		(width 0.1143)
		(layer "In15.Cu")
		(net "GMI_CPU0_G1_CPU1_G3_TX_DN<13>")
	)
	(arc
		(start 346.77985 -236.688376)
		(mid 346.935778 -236.384084)
		(end 346.77985 -236.079792)
		(width 0.1143)
		(layer "In15.Cu")
		(net "GMI_CPU0_G1_CPU1_G3_TX_DN<13>")
	)
	(arc
		(start 345.802712 -223.098614)
		(mid 345.599853 -222.893243)
		(end 345.525852 -222.614236)
		(width 0.1143)
		(layer "In15.Cu")
		(net "GMI_CPU0_G1_CPU1_G3_TX_DN<13>")
	)
	(arc
		(start 125.490224 -247.618758)
		(mid 125.492247 -247.630168)
		(end 125.494034 -247.641618)
		(width 0.1143)
		(layer "In15.Cu")
		(net "GMI_CPU0_G1_CPU1_G3_TX_DN<13>")
	)
	(arc
		(start 346.708984 -245.758716)
		(mid 346.465657 -245.29415)
		(end 346.708984 -244.829584)
		(width 0.1143)
		(layer "In15.Cu")
		(net "GMI_CPU0_G1_CPU1_G3_TX_DN<13>")
	)
	(arc
		(start 125.029976 -229.094538)
		(mid 124.96474 -229.358129)
		(end 124.784104 -229.560882)
		(width 0.1143)
		(layer "In15.Cu")
		(net "GMI_CPU0_G1_CPU1_G3_TX_DN<13>")
	)
	(segment
		(start 348.907862 -246.370094)
		(end 348.44101 -246.104156)
		(width 0.12954)
		(layer "F.Cu")
		(net "GMI_CPU0_G1_CPU1_G3_TX_DN<12>")
	)
	(segment
		(start 122.587766 -246.370348)
		(end 123.054618 -246.10441)
		(width 0.12954)
		(layer "F.Cu")
		(net "GMI_CPU0_G1_CPU1_G3_TX_DN<12>")
	)
	(segment
		(start 347.688154 -236.706664)
		(end 347.718634 -236.688884)
		(width 0.1143)
		(layer "In15.Cu")
		(net "GMI_CPU0_G1_CPU1_G3_TX_DN<12>")
	)
	(segment
		(start 347.688154 -241.5667)
		(end 347.718634 -241.54892)
		(width 0.1143)
		(layer "In15.Cu")
		(net "GMI_CPU0_G1_CPU1_G3_TX_DN<12>")
	)
	(segment
		(start 347.649038 -239.969548)
		(end 347.688154 -239.946688)
		(width 0.1143)
		(layer "In15.Cu")
		(net "GMI_CPU0_G1_CPU1_G3_TX_DN<12>")
	)
	(segment
		(start 157.564328 -192.178178)
		(end 157.234382 -192.448688)
		(width 0.14224)
		(layer "In15.Cu")
		(net "GMI_CPU0_G1_CPU1_G3_TX_DN<12>")
	)
	(segment
		(start 345.995752 -221.80423)
		(end 345.995752 -221.437962)
		(width 0.1143)
		(layer "In15.Cu")
		(net "GMI_CPU0_G1_CPU1_G3_TX_DN<12>")
	)
	(segment
		(start 347.65107 -229.560374)
		(end 347.649038 -229.55885)
		(width 0.1143)
		(layer "In15.Cu")
		(net "GMI_CPU0_G1_CPU1_G3_TX_DN<12>")
	)
	(segment
		(start 158.959804 -191.2112)
		(end 158.658814 -191.458088)
		(width 0.14224)
		(layer "In15.Cu")
		(net "GMI_CPU0_G1_CPU1_G3_TX_DN<12>")
	)
	(segment
		(start 123.807728 -223.101916)
		(end 123.777248 -223.119696)
		(width 0.1143)
		(layer "In15.Cu")
		(net "GMI_CPU0_G1_CPU1_G3_TX_DN<12>")
	)
	(segment
		(start 123.846844 -234.418886)
		(end 123.807728 -234.441746)
		(width 0.1143)
		(layer "In15.Cu")
		(net "GMI_CPU0_G1_CPU1_G3_TX_DN<12>")
	)
	(segment
		(start 347.649038 -243.209572)
		(end 347.688154 -243.186712)
		(width 0.1143)
		(layer "In15.Cu")
		(net "GMI_CPU0_G1_CPU1_G3_TX_DN<12>")
	)
	(segment
		(start 239.169448 -198.29907)
		(end 236.351064 -198.796148)
		(width 0.14224)
		(layer "In15.Cu")
		(net "GMI_CPU0_G1_CPU1_G3_TX_DN<12>")
	)
	(segment
		(start 346.77858 -224.739454)
		(end 346.7481 -224.721674)
		(width 0.1143)
		(layer "In15.Cu")
		(net "GMI_CPU0_G1_CPU1_G3_TX_DN<12>")
	)
	(segment
		(start 123.807728 -243.186966)
		(end 123.846844 -243.209826)
		(width 0.1143)
		(layer "In15.Cu")
		(net "GMI_CPU0_G1_CPU1_G3_TX_DN<12>")
	)
	(segment
		(start 156.885132 -192.912492)
		(end 156.692092 -192.893188)
		(width 0.14224)
		(layer "In15.Cu")
		(net "GMI_CPU0_G1_CPU1_G3_TX_DN<12>")
	)
	(segment
		(start 347.718634 -237.699296)
		(end 347.688154 -237.681516)
		(width 0.1143)
		(layer "In15.Cu")
		(net "GMI_CPU0_G1_CPU1_G3_TX_DN<12>")
	)
	(segment
		(start 123.807728 -233.466894)
		(end 123.846844 -233.489754)
		(width 0.1143)
		(layer "In15.Cu")
		(net "GMI_CPU0_G1_CPU1_G3_TX_DN<12>")
	)
	(segment
		(start 123.807728 -229.581964)
		(end 123.775216 -229.60076)
		(width 0.1143)
		(layer "In15.Cu")
		(net "GMI_CPU0_G1_CPU1_G3_TX_DN<12>")
	)
	(segment
		(start 123.807728 -226.9871)
		(end 123.846844 -227.00996)
		(width 0.1143)
		(layer "In15.Cu")
		(net "GMI_CPU0_G1_CPU1_G3_TX_DN<12>")
	)
	(segment
		(start 346.309696 -222.309944)
		(end 346.241624 -222.270574)
		(width 0.1143)
		(layer "In15.Cu")
		(net "GMI_CPU0_G1_CPU1_G3_TX_DN<12>")
	)
	(segment
		(start 123.777248 -238.30915)
		(end 123.807728 -238.32693)
		(width 0.1143)
		(layer "In15.Cu")
		(net "GMI_CPU0_G1_CPU1_G3_TX_DN<12>")
	)
	(segment
		(start 154.145742 -195.158614)
		(end 153.815542 -195.429378)
		(width 0.14224)
		(layer "In15.Cu")
		(net "GMI_CPU0_G1_CPU1_G3_TX_DN<12>")
	)
	(segment
		(start 158.978854 -191.01816)
		(end 158.959804 -191.2112)
		(width 0.14224)
		(layer "In15.Cu")
		(net "GMI_CPU0_G1_CPU1_G3_TX_DN<12>")
	)
	(segment
		(start 347.688154 -227.961698)
		(end 347.649038 -227.938838)
		(width 0.1143)
		(layer "In15.Cu")
		(net "GMI_CPU0_G1_CPU1_G3_TX_DN<12>")
	)
	(segment
		(start 345.94546 -221.143322)
		(end 345.89974 -221.097602)
		(width 0.1143)
		(layer "In15.Cu")
		(net "GMI_CPU0_G1_CPU1_G3_TX_DN<12>")
	)
	(segment
		(start 347.24975 -225.549968)
		(end 347.220032 -225.53295)
		(width 0.1143)
		(layer "In15.Cu")
		(net "GMI_CPU0_G1_CPU1_G3_TX_DN<12>")
	)
	(segment
		(start 157.234382 -192.448688)
		(end 157.215332 -192.641728)
		(width 0.14224)
		(layer "In15.Cu")
		(net "GMI_CPU0_G1_CPU1_G3_TX_DN<12>")
	)
	(segment
		(start 123.777248 -241.549174)
		(end 123.807728 -241.566954)
		(width 0.1143)
		(layer "In15.Cu")
		(net "GMI_CPU0_G1_CPU1_G3_TX_DN<12>")
	)
	(segment
		(start 153.622502 -195.410328)
		(end 153.292556 -195.680838)
		(width 0.14224)
		(layer "In15.Cu")
		(net "GMI_CPU0_G1_CPU1_G3_TX_DN<12>")
	)
	(segment
		(start 345.995752 -221.437962)
		(end 345.94546 -221.38767)
		(width 0.1143)
		(layer "In15.Cu")
		(net "GMI_CPU0_G1_CPU1_G3_TX_DN<12>")
	)
	(segment
		(start 347.649038 -236.729524)
		(end 347.688154 -236.706664)
		(width 0.1143)
		(layer "In15.Cu")
		(net "GMI_CPU0_G1_CPU1_G3_TX_DN<12>")
	)
	(segment
		(start 347.718634 -234.459272)
		(end 347.688154 -234.441492)
		(width 0.1143)
		(layer "In15.Cu")
		(net "GMI_CPU0_G1_CPU1_G3_TX_DN<12>")
	)
	(segment
		(start 159.851344 -190.302896)
		(end 159.83204 -190.495936)
		(width 0.14224)
		(layer "In15.Cu")
		(net "GMI_CPU0_G1_CPU1_G3_TX_DN<12>")
	)
	(segment
		(start 123.807728 -223.747076)
		(end 123.846844 -223.769936)
		(width 0.1143)
		(layer "In15.Cu")
		(net "GMI_CPU0_G1_CPU1_G3_TX_DN<12>")
	)
	(segment
		(start 347.649038 -228.629718)
		(end 347.688154 -228.606858)
		(width 0.1143)
		(layer "In15.Cu")
		(net "GMI_CPU0_G1_CPU1_G3_TX_DN<12>")
	)
	(segment
		(start 213.034372 -189.400688)
		(end 207.113378 -188.356748)
		(width 0.14224)
		(layer "In15.Cu")
		(net "GMI_CPU0_G1_CPU1_G3_TX_DN<12>")
	)
	(segment
		(start 345.89974 -220.080078)
		(end 343.833196 -215.713564)
		(width 0.14224)
		(layer "In15.Cu")
		(net "GMI_CPU0_G1_CPU1_G3_TX_DN<12>")
	)
	(segment
		(start 347.688154 -240.92154)
		(end 347.649038 -240.89868)
		(width 0.1143)
		(layer "In15.Cu")
		(net "GMI_CPU0_G1_CPU1_G3_TX_DN<12>")
	)
	(segment
		(start 123.846844 -223.079056)
		(end 123.807728 -223.101916)
		(width 0.1143)
		(layer "In15.Cu")
		(net "GMI_CPU0_G1_CPU1_G3_TX_DN<12>")
	)
	(segment
		(start 152.943052 -196.144896)
		(end 152.750012 -196.125846)
		(width 0.14224)
		(layer "In15.Cu")
		(net "GMI_CPU0_G1_CPU1_G3_TX_DN<12>")
	)
	(segment
		(start 158.106618 -191.733424)
		(end 158.087568 -191.926464)
		(width 0.14224)
		(layer "In15.Cu")
		(net "GMI_CPU0_G1_CPU1_G3_TX_DN<12>")
	)
	(segment
		(start 347.688154 -235.086652)
		(end 347.718634 -235.068872)
		(width 0.1143)
		(layer "In15.Cu")
		(net "GMI_CPU0_G1_CPU1_G3_TX_DN<12>")
	)
	(segment
		(start 347.218762 -225.532188)
		(end 347.218 -225.53168)
		(width 0.1143)
		(layer "In15.Cu")
		(net "GMI_CPU0_G1_CPU1_G3_TX_DN<12>")
	)
	(segment
		(start 123.807728 -224.721928)
		(end 123.777248 -224.739708)
		(width 0.1143)
		(layer "In15.Cu")
		(net "GMI_CPU0_G1_CPU1_G3_TX_DN<12>")
	)
	(segment
		(start 155.560014 -193.99885)
		(end 155.366974 -193.9798)
		(width 0.14224)
		(layer "In15.Cu")
		(net "GMI_CPU0_G1_CPU1_G3_TX_DN<12>")
	)
	(segment
		(start 348.738952 -246.104156)
		(end 348.808802 -246.034306)
		(width 0.1143)
		(layer "In15.Cu")
		(net "GMI_CPU0_G1_CPU1_G3_TX_DN<12>")
	)
	(segment
		(start 123.846844 -240.898934)
		(end 123.807728 -240.921794)
		(width 0.1143)
		(layer "In15.Cu")
		(net "GMI_CPU0_G1_CPU1_G3_TX_DN<12>")
	)
	(segment
		(start 347.688154 -229.58171)
		(end 347.65107 -229.560374)
		(width 0.1143)
		(layer "In15.Cu")
		(net "GMI_CPU0_G1_CPU1_G3_TX_DN<12>")
	)
	(segment
		(start 123.807728 -238.32693)
		(end 123.846844 -238.34979)
		(width 0.1143)
		(layer "In15.Cu")
		(net "GMI_CPU0_G1_CPU1_G3_TX_DN<12>")
	)
	(segment
		(start 123.774708 -222.108014)
		(end 123.84786 -222.150686)
		(width 0.1143)
		(layer "In15.Cu")
		(net "GMI_CPU0_G1_CPU1_G3_TX_DN<12>")
	)
	(segment
		(start 347.688154 -239.946688)
		(end 347.718634 -239.928908)
		(width 0.1143)
		(layer "In15.Cu")
		(net "GMI_CPU0_G1_CPU1_G3_TX_DN<12>")
	)
	(segment
		(start 157.215332 -192.641728)
		(end 156.885132 -192.912492)
		(width 0.14224)
		(layer "In15.Cu")
		(net "GMI_CPU0_G1_CPU1_G3_TX_DN<12>")
	)
	(segment
		(start 123.807728 -225.367088)
		(end 123.846844 -225.389948)
		(width 0.1143)
		(layer "In15.Cu")
		(net "GMI_CPU0_G1_CPU1_G3_TX_DN<12>")
	)
	(segment
		(start 155.366974 -193.9798)
		(end 155.037028 -194.25031)
		(width 0.14224)
		(layer "In15.Cu")
		(net "GMI_CPU0_G1_CPU1_G3_TX_DN<12>")
	)
	(segment
		(start 153.815542 -195.429378)
		(end 153.622502 -195.410328)
		(width 0.14224)
		(layer "In15.Cu")
		(net "GMI_CPU0_G1_CPU1_G3_TX_DN<12>")
	)
	(segment
		(start 123.777248 -230.20909)
		(end 123.844304 -230.248206)
		(width 0.1143)
		(layer "In15.Cu")
		(net "GMI_CPU0_G1_CPU1_G3_TX_DN<12>")
	)
	(segment
		(start 345.89974 -221.097602)
		(end 345.89974 -221.083124)
		(width 0.1143)
		(layer "In15.Cu")
		(net "GMI_CPU0_G1_CPU1_G3_TX_DN<12>")
	)
	(segment
		(start 155.890214 -193.728086)
		(end 155.560014 -193.99885)
		(width 0.14224)
		(layer "In15.Cu")
		(net "GMI_CPU0_G1_CPU1_G3_TX_DN<12>")
	)
	(segment
		(start 347.718634 -232.83926)
		(end 347.688154 -232.82148)
		(width 0.1143)
		(layer "In15.Cu")
		(net "GMI_CPU0_G1_CPU1_G3_TX_DN<12>")
	)
	(segment
		(start 161.991548 -188.54801)
		(end 159.851344 -190.302642)
		(width 0.14224)
		(layer "In15.Cu")
		(net "GMI_CPU0_G1_CPU1_G3_TX_DN<12>")
	)
	(segment
		(start 347.718634 -236.079284)
		(end 347.688154 -236.061504)
		(width 0.1143)
		(layer "In15.Cu")
		(net "GMI_CPU0_G1_CPU1_G3_TX_DN<12>")
	)
	(segment
		(start 122.867674 -245.78183)
		(end 122.837194 -245.79961)
		(width 0.1143)
		(layer "In15.Cu")
		(net "GMI_CPU0_G1_CPU1_G3_TX_DN<12>")
	)
	(segment
		(start 123.807728 -244.161818)
		(end 123.777248 -244.179598)
		(width 0.1143)
		(layer "In15.Cu")
		(net "GMI_CPU0_G1_CPU1_G3_TX_DN<12>")
	)
	(segment
		(start 123.619768 -221.198948)
		(end 123.619514 -221.199202)
		(width 0.1143)
		(layer "In15.Cu")
		(net "GMI_CPU0_G1_CPU1_G3_TX_DN<12>")
	)
	(segment
		(start 159.50184 -190.7667)
		(end 159.3088 -190.74765)
		(width 0.14224)
		(layer "In15.Cu")
		(net "GMI_CPU0_G1_CPU1_G3_TX_DN<12>")
	)
	(segment
		(start 125.30328 -217.53068)
		(end 123.665488 -220.368622)
		(width 0.14224)
		(layer "In15.Cu")
		(net "GMI_CPU0_G1_CPU1_G3_TX_DN<12>")
	)
	(segment
		(start 347.220032 -225.53295)
		(end 347.218762 -225.532188)
		(width 0.1143)
		(layer "In15.Cu")
		(net "GMI_CPU0_G1_CPU1_G3_TX_DN<12>")
	)
	(segment
		(start 123.807728 -227.961952)
		(end 123.777248 -227.979732)
		(width 0.1143)
		(layer "In15.Cu")
		(net "GMI_CPU0_G1_CPU1_G3_TX_DN<12>")
	)
	(segment
		(start 123.777248 -243.169186)
		(end 123.807728 -243.186966)
		(width 0.1143)
		(layer "In15.Cu")
		(net "GMI_CPU0_G1_CPU1_G3_TX_DN<12>")
	)
	(segment
		(start 348.44101 -246.104156)
		(end 348.738952 -246.104156)
		(width 0.1143)
		(layer "In15.Cu")
		(net "GMI_CPU0_G1_CPU1_G3_TX_DN<12>")
	)
	(segment
		(start 235.246926 -198.601584)
		(end 213.034372 -189.400688)
		(width 0.14224)
		(layer "In15.Cu")
		(net "GMI_CPU0_G1_CPU1_G3_TX_DN<12>")
	)
	(segment
		(start 347.214444 -225.529648)
		(end 347.213682 -225.52914)
		(width 0.1143)
		(layer "In15.Cu")
		(net "GMI_CPU0_G1_CPU1_G3_TX_DN<12>")
	)
	(segment
		(start 123.665488 -220.368622)
		(end 123.665488 -220.991938)
		(width 0.14224)
		(layer "In15.Cu")
		(net "GMI_CPU0_G1_CPU1_G3_TX_DN<12>")
	)
	(segment
		(start 156.692092 -192.893188)
		(end 156.692092 -192.893442)
		(width 0.14224)
		(layer "In15.Cu")
		(net "GMI_CPU0_G1_CPU1_G3_TX_DN<12>")
	)
	(segment
		(start 236.351064 -198.796148)
		(end 235.246926 -198.601584)
		(width 0.14224)
		(layer "In15.Cu")
		(net "GMI_CPU0_G1_CPU1_G3_TX_DN<12>")
	)
	(segment
		(start 347.688154 -232.82148)
		(end 347.649038 -232.79862)
		(width 0.1143)
		(layer "In15.Cu")
		(net "GMI_CPU0_G1_CPU1_G3_TX_DN<12>")
	)
	(segment
		(start 346.7481 -223.101662)
		(end 346.708984 -223.078802)
		(width 0.1143)
		(layer "In15.Cu")
		(net "GMI_CPU0_G1_CPU1_G3_TX_DN<12>")
	)
	(segment
		(start 347.185742 -225.512884)
		(end 347.178884 -225.50882)
		(width 0.1143)
		(layer "In15.Cu")
		(net "GMI_CPU0_G1_CPU1_G3_TX_DN<12>")
	)
	(segment
		(start 343.833196 -215.713564)
		(end 318.759586 -195.154042)
		(width 0.14224)
		(layer "In15.Cu")
		(net "GMI_CPU0_G1_CPU1_G3_TX_DN<12>")
	)
	(segment
		(start 123.846844 -237.65891)
		(end 123.807728 -237.68177)
		(width 0.1143)
		(layer "In15.Cu")
		(net "GMI_CPU0_G1_CPU1_G3_TX_DN<12>")
	)
	(segment
		(start 347.688154 -231.201722)
		(end 347.649038 -231.178862)
		(width 0.1143)
		(layer "In15.Cu")
		(net "GMI_CPU0_G1_CPU1_G3_TX_DN<12>")
	)
	(segment
		(start 347.186504 -225.513392)
		(end 347.185742 -225.512884)
		(width 0.1143)
		(layer "In15.Cu")
		(net "GMI_CPU0_G1_CPU1_G3_TX_DN<12>")
	)
	(segment
		(start 123.846844 -232.798874)
		(end 123.807728 -232.821734)
		(width 0.1143)
		(layer "In15.Cu")
		(net "GMI_CPU0_G1_CPU1_G3_TX_DN<12>")
	)
	(segment
		(start 123.777248 -236.689138)
		(end 123.807728 -236.706918)
		(width 0.1143)
		(layer "In15.Cu")
		(net "GMI_CPU0_G1_CPU1_G3_TX_DN<12>")
	)
	(segment
		(start 347.720666 -229.600506)
		(end 347.688154 -229.58171)
		(width 0.1143)
		(layer "In15.Cu")
		(net "GMI_CPU0_G1_CPU1_G3_TX_DN<12>")
	)
	(segment
		(start 155.017978 -194.44335)
		(end 154.687778 -194.714114)
		(width 0.14224)
		(layer "In15.Cu")
		(net "GMI_CPU0_G1_CPU1_G3_TX_DN<12>")
	)
	(segment
		(start 347.218 -225.53168)
		(end 347.216984 -225.531172)
		(width 0.1143)
		(layer "In15.Cu")
		(net "GMI_CPU0_G1_CPU1_G3_TX_DN<12>")
	)
	(segment
		(start 250.68657 -190.234824)
		(end 239.169448 -198.29907)
		(width 0.14224)
		(layer "In15.Cu")
		(net "GMI_CPU0_G1_CPU1_G3_TX_DN<12>")
	)
	(segment
		(start 159.83204 -190.495936)
		(end 159.50184 -190.7667)
		(width 0.14224)
		(layer "In15.Cu")
		(net "GMI_CPU0_G1_CPU1_G3_TX_DN<12>")
	)
	(segment
		(start 348.1705 -244.978682)
		(end 348.118938 -244.94871)
		(width 0.1143)
		(layer "In15.Cu")
		(net "GMI_CPU0_G1_CPU1_G3_TX_DN<12>")
	)
	(segment
		(start 152.750012 -196.125846)
		(end 148.0058 -200.015856)
		(width 0.14224)
		(layer "In15.Cu")
		(net "GMI_CPU0_G1_CPU1_G3_TX_DN<12>")
	)
	(segment
		(start 346.708984 -223.769682)
		(end 346.7481 -223.746822)
		(width 0.1143)
		(layer "In15.Cu")
		(net "GMI_CPU0_G1_CPU1_G3_TX_DN<12>")
	)
	(segment
		(start 347.688154 -231.846628)
		(end 347.718634 -231.828848)
		(width 0.1143)
		(layer "In15.Cu")
		(net "GMI_CPU0_G1_CPU1_G3_TX_DN<12>")
	)
	(segment
		(start 347.651578 -230.247952)
		(end 347.718634 -230.208836)
		(width 0.1143)
		(layer "In15.Cu")
		(net "GMI_CPU0_G1_CPU1_G3_TX_DN<12>")
	)
	(segment
		(start 123.777248 -228.589332)
		(end 123.807728 -228.607112)
		(width 0.1143)
		(layer "In15.Cu")
		(net "GMI_CPU0_G1_CPU1_G3_TX_DN<12>")
	)
	(segment
		(start 158.629604 -191.481964)
		(end 158.436564 -191.462914)
		(width 0.14224)
		(layer "In15.Cu")
		(net "GMI_CPU0_G1_CPU1_G3_TX_DN<12>")
	)
	(segment
		(start 347.649038 -233.4895)
		(end 347.688154 -233.46664)
		(width 0.1143)
		(layer "In15.Cu")
		(net "GMI_CPU0_G1_CPU1_G3_TX_DN<12>")
	)
	(segment
		(start 123.376944 -244.948964)
		(end 123.337828 -244.971824)
		(width 0.1143)
		(layer "In15.Cu")
		(net "GMI_CPU0_G1_CPU1_G3_TX_DN<12>")
	)
	(segment
		(start 347.688154 -237.681516)
		(end 347.649038 -237.658656)
		(width 0.1143)
		(layer "In15.Cu")
		(net "GMI_CPU0_G1_CPU1_G3_TX_DN<12>")
	)
	(segment
		(start 345.89974 -221.083124)
		(end 345.89974 -220.080078)
		(width 0.14224)
		(layer "In15.Cu")
		(net "GMI_CPU0_G1_CPU1_G3_TX_DN<12>")
	)
	(segment
		(start 346.240608 -222.270066)
		(end 346.239592 -222.269304)
		(width 0.1143)
		(layer "In15.Cu")
		(net "GMI_CPU0_G1_CPU1_G3_TX_DN<12>")
	)
	(segment
		(start 153.273252 -195.873878)
		(end 152.943052 -196.144896)
		(width 0.14224)
		(layer "In15.Cu")
		(net "GMI_CPU0_G1_CPU1_G3_TX_DN<12>")
	)
	(segment
		(start 123.807728 -226.34194)
		(end 123.777248 -226.35972)
		(width 0.1143)
		(layer "In15.Cu")
		(net "GMI_CPU0_G1_CPU1_G3_TX_DN<12>")
	)
	(segment
		(start 123.846844 -244.138958)
		(end 123.807728 -244.161818)
		(width 0.1143)
		(layer "In15.Cu")
		(net "GMI_CPU0_G1_CPU1_G3_TX_DN<12>")
	)
	(segment
		(start 347.718634 -240.93932)
		(end 347.688154 -240.92154)
		(width 0.1143)
		(layer "In15.Cu")
		(net "GMI_CPU0_G1_CPU1_G3_TX_DN<12>")
	)
	(segment
		(start 123.846844 -239.278922)
		(end 123.807728 -239.301782)
		(width 0.1143)
		(layer "In15.Cu")
		(net "GMI_CPU0_G1_CPU1_G3_TX_DN<12>")
	)
	(segment
		(start 123.665488 -220.991938)
		(end 123.665488 -221.020386)
		(width 0.1143)
		(layer "In15.Cu")
		(net "GMI_CPU0_G1_CPU1_G3_TX_DN<12>")
	)
	(segment
		(start 123.807728 -242.541806)
		(end 123.777248 -242.559586)
		(width 0.1143)
		(layer "In15.Cu")
		(net "GMI_CPU0_G1_CPU1_G3_TX_DN<12>")
	)
	(segment
		(start 123.846844 -224.699068)
		(end 123.807728 -224.721928)
		(width 0.1143)
		(layer "In15.Cu")
		(net "GMI_CPU0_G1_CPU1_G3_TX_DN<12>")
	)
	(segment
		(start 347.649038 -235.109512)
		(end 347.688154 -235.086652)
		(width 0.1143)
		(layer "In15.Cu")
		(net "GMI_CPU0_G1_CPU1_G3_TX_DN<12>")
	)
	(segment
		(start 348.659704 -245.799864)
		(end 348.627954 -245.781576)
		(width 0.1143)
		(layer "In15.Cu")
		(net "GMI_CPU0_G1_CPU1_G3_TX_DN<12>")
	)
	(segment
		(start 347.688154 -243.186712)
		(end 347.718634 -243.168932)
		(width 0.1143)
		(layer "In15.Cu")
		(net "GMI_CPU0_G1_CPU1_G3_TX_DN<12>")
	)
	(segment
		(start 123.337066 -244.972332)
		(end 123.335796 -244.973094)
		(width 0.1143)
		(layer "In15.Cu")
		(net "GMI_CPU0_G1_CPU1_G3_TX_DN<12>")
	)
	(segment
		(start 158.658814 -191.458088)
		(end 158.629604 -191.481964)
		(width 0.14224)
		(layer "In15.Cu")
		(net "GMI_CPU0_G1_CPU1_G3_TX_DN<12>")
	)
	(segment
		(start 123.846844 -236.038898)
		(end 123.807728 -236.061758)
		(width 0.1143)
		(layer "In15.Cu")
		(net "GMI_CPU0_G1_CPU1_G3_TX_DN<12>")
	)
	(segment
		(start 346.7481 -224.721674)
		(end 346.708984 -224.698814)
		(width 0.1143)
		(layer "In15.Cu")
		(net "GMI_CPU0_G1_CPU1_G3_TX_DN<12>")
	)
	(segment
		(start 123.807728 -235.086906)
		(end 123.846844 -235.109766)
		(width 0.1143)
		(layer "In15.Cu")
		(net "GMI_CPU0_G1_CPU1_G3_TX_DN<12>")
	)
	(segment
		(start 347.718634 -239.319308)
		(end 347.688154 -239.301528)
		(width 0.1143)
		(layer "In15.Cu")
		(net "GMI_CPU0_G1_CPU1_G3_TX_DN<12>")
	)
	(segment
		(start 347.720666 -231.220518)
		(end 347.688154 -231.201722)
		(width 0.1143)
		(layer "In15.Cu")
		(net "GMI_CPU0_G1_CPU1_G3_TX_DN<12>")
	)
	(segment
		(start 123.807728 -231.846882)
		(end 123.846844 -231.869742)
		(width 0.1143)
		(layer "In15.Cu")
		(net "GMI_CPU0_G1_CPU1_G3_TX_DN<12>")
	)
	(segment
		(start 122.68708 -246.03456)
		(end 122.75693 -246.10441)
		(width 0.1143)
		(layer "In15.Cu")
		(net "GMI_CPU0_G1_CPU1_G3_TX_DN<12>")
	)
	(segment
		(start 158.436564 -191.462914)
		(end 158.106618 -191.733424)
		(width 0.14224)
		(layer "In15.Cu")
		(net "GMI_CPU0_G1_CPU1_G3_TX_DN<12>")
	)
	(segment
		(start 348.358206 -245.3132)
		(end 348.358206 -245.303548)
		(width 0.1143)
		(layer "In15.Cu")
		(net "GMI_CPU0_G1_CPU1_G3_TX_DN<12>")
	)
	(segment
		(start 347.718634 -242.559332)
		(end 347.688154 -242.541552)
		(width 0.1143)
		(layer "In15.Cu")
		(net "GMI_CPU0_G1_CPU1_G3_TX_DN<12>")
	)
	(segment
		(start 123.846844 -226.31908)
		(end 123.807728 -226.34194)
		(width 0.1143)
		(layer "In15.Cu")
		(net "GMI_CPU0_G1_CPU1_G3_TX_DN<12>")
	)
	(segment
		(start 122.90679 -245.75897)
		(end 122.867674 -245.78183)
		(width 0.1143)
		(layer "In15.Cu")
		(net "GMI_CPU0_G1_CPU1_G3_TX_DN<12>")
	)
	(segment
		(start 123.807728 -234.441746)
		(end 123.777248 -234.459526)
		(width 0.1143)
		(layer "In15.Cu")
		(net "GMI_CPU0_G1_CPU1_G3_TX_DN<12>")
	)
	(segment
		(start 123.337828 -244.971824)
		(end 123.337066 -244.972332)
		(width 0.1143)
		(layer "In15.Cu")
		(net "GMI_CPU0_G1_CPU1_G3_TX_DN<12>")
	)
	(segment
		(start 123.665488 -221.020386)
		(end 123.619768 -221.066106)
		(width 0.1143)
		(layer "In15.Cu")
		(net "GMI_CPU0_G1_CPU1_G3_TX_DN<12>")
	)
	(segment
		(start 123.777248 -239.929162)
		(end 123.807728 -239.946942)
		(width 0.1143)
		(layer "In15.Cu")
		(net "GMI_CPU0_G1_CPU1_G3_TX_DN<12>")
	)
	(segment
		(start 123.807728 -236.706918)
		(end 123.846844 -236.729778)
		(width 0.1143)
		(layer "In15.Cu")
		(net "GMI_CPU0_G1_CPU1_G3_TX_DN<12>")
	)
	(segment
		(start 347.688154 -226.986846)
		(end 347.718634 -226.969066)
		(width 0.1143)
		(layer "In15.Cu")
		(net "GMI_CPU0_G1_CPU1_G3_TX_DN<12>")
	)
	(segment
		(start 157.757368 -192.197228)
		(end 157.564328 -192.178178)
		(width 0.14224)
		(layer "In15.Cu")
		(net "GMI_CPU0_G1_CPU1_G3_TX_DN<12>")
	)
	(segment
		(start 347.216984 -225.531172)
		(end 347.214444 -225.529648)
		(width 0.1143)
		(layer "In15.Cu")
		(net "GMI_CPU0_G1_CPU1_G3_TX_DN<12>")
	)
	(segment
		(start 347.688154 -239.301528)
		(end 347.649038 -239.278668)
		(width 0.1143)
		(layer "In15.Cu")
		(net "GMI_CPU0_G1_CPU1_G3_TX_DN<12>")
	)
	(segment
		(start 159.851344 -190.302642)
		(end 159.851344 -190.302896)
		(width 0.14224)
		(layer "In15.Cu")
		(net "GMI_CPU0_G1_CPU1_G3_TX_DN<12>")
	)
	(segment
		(start 123.335796 -244.973094)
		(end 123.306078 -244.990112)
		(width 0.1143)
		(layer "In15.Cu")
		(net "GMI_CPU0_G1_CPU1_G3_TX_DN<12>")
	)
	(segment
		(start 123.846844 -229.559104)
		(end 123.807728 -229.581964)
		(width 0.1143)
		(layer "In15.Cu")
		(net "GMI_CPU0_G1_CPU1_G3_TX_DN<12>")
	)
	(segment
		(start 154.687778 -194.714114)
		(end 154.494738 -194.695064)
		(width 0.14224)
		(layer "In15.Cu")
		(net "GMI_CPU0_G1_CPU1_G3_TX_DN<12>")
	)
	(segment
		(start 347.688154 -236.061504)
		(end 347.649038 -236.038644)
		(width 0.1143)
		(layer "In15.Cu")
		(net "GMI_CPU0_G1_CPU1_G3_TX_DN<12>")
	)
	(segment
		(start 154.164792 -194.965574)
		(end 154.145742 -195.158614)
		(width 0.14224)
		(layer "In15.Cu")
		(net "GMI_CPU0_G1_CPU1_G3_TX_DN<12>")
	)
	(segment
		(start 346.241624 -222.270574)
		(end 346.240608 -222.270066)
		(width 0.1143)
		(layer "In15.Cu")
		(net "GMI_CPU0_G1_CPU1_G3_TX_DN<12>")
	)
	(segment
		(start 155.037028 -194.25031)
		(end 155.017978 -194.44335)
		(width 0.14224)
		(layer "In15.Cu")
		(net "GMI_CPU0_G1_CPU1_G3_TX_DN<12>")
	)
	(segment
		(start 123.777248 -235.069126)
		(end 123.807728 -235.086906)
		(width 0.1143)
		(layer "In15.Cu")
		(net "GMI_CPU0_G1_CPU1_G3_TX_DN<12>")
	)
	(segment
		(start 155.909264 -193.5353)
		(end 155.909264 -193.535046)
		(width 0.14224)
		(layer "In15.Cu")
		(net "GMI_CPU0_G1_CPU1_G3_TX_DN<12>")
	)
	(segment
		(start 155.909264 -193.535046)
		(end 155.890214 -193.728086)
		(width 0.14224)
		(layer "In15.Cu")
		(net "GMI_CPU0_G1_CPU1_G3_TX_DN<12>")
	)
	(segment
		(start 346.77858 -223.119442)
		(end 346.7481 -223.101662)
		(width 0.1143)
		(layer "In15.Cu")
		(net "GMI_CPU0_G1_CPU1_G3_TX_DN<12>")
	)
	(segment
		(start 123.846844 -227.939092)
		(end 123.807728 -227.961952)
		(width 0.1143)
		(layer "In15.Cu")
		(net "GMI_CPU0_G1_CPU1_G3_TX_DN<12>")
	)
	(segment
		(start 159.3088 -190.74765)
		(end 158.978854 -191.01816)
		(width 0.14224)
		(layer "In15.Cu")
		(net "GMI_CPU0_G1_CPU1_G3_TX_DN<12>")
	)
	(segment
		(start 346.7481 -223.746822)
		(end 346.77858 -223.729042)
		(width 0.1143)
		(layer "In15.Cu")
		(net "GMI_CPU0_G1_CPU1_G3_TX_DN<12>")
	)
	(segment
		(start 123.846844 -231.179116)
		(end 123.807728 -231.201976)
		(width 0.1143)
		(layer "In15.Cu")
		(net "GMI_CPU0_G1_CPU1_G3_TX_DN<12>")
	)
	(segment
		(start 123.619768 -221.066106)
		(end 123.619768 -221.198948)
		(width 0.1143)
		(layer "In15.Cu")
		(net "GMI_CPU0_G1_CPU1_G3_TX_DN<12>")
	)
	(segment
		(start 303.70526 -188.483748)
		(end 262.760968 -188.105542)
		(width 0.14224)
		(layer "In15.Cu")
		(net "GMI_CPU0_G1_CPU1_G3_TX_DN<12>")
	)
	(segment
		(start 123.807728 -239.301782)
		(end 123.777248 -239.319562)
		(width 0.1143)
		(layer "In15.Cu")
		(net "GMI_CPU0_G1_CPU1_G3_TX_DN<12>")
	)
	(segment
		(start 156.692092 -192.893442)
		(end 155.909264 -193.5353)
		(width 0.14224)
		(layer "In15.Cu")
		(net "GMI_CPU0_G1_CPU1_G3_TX_DN<12>")
	)
	(segment
		(start 347.718634 -244.179344)
		(end 347.688154 -244.161564)
		(width 0.1143)
		(layer "In15.Cu")
		(net "GMI_CPU0_G1_CPU1_G3_TX_DN<12>")
	)
	(segment
		(start 347.718634 -227.979478)
		(end 347.688154 -227.961698)
		(width 0.1143)
		(layer "In15.Cu")
		(net "GMI_CPU0_G1_CPU1_G3_TX_DN<12>")
	)
	(segment
		(start 122.75693 -246.10441)
		(end 123.054618 -246.10441)
		(width 0.1143)
		(layer "In15.Cu")
		(net "GMI_CPU0_G1_CPU1_G3_TX_DN<12>")
	)
	(segment
		(start 262.760968 -188.105542)
		(end 250.68657 -190.234824)
		(width 0.14224)
		(layer "In15.Cu")
		(net "GMI_CPU0_G1_CPU1_G3_TX_DN<12>")
	)
	(segment
		(start 347.649038 -238.349536)
		(end 347.688154 -238.326676)
		(width 0.1143)
		(layer "In15.Cu")
		(net "GMI_CPU0_G1_CPU1_G3_TX_DN<12>")
	)
	(segment
		(start 123.777248 -233.449114)
		(end 123.807728 -233.466894)
		(width 0.1143)
		(layer "In15.Cu")
		(net "GMI_CPU0_G1_CPU1_G3_TX_DN<12>")
	)
	(segment
		(start 347.688154 -238.326676)
		(end 347.718634 -238.308896)
		(width 0.1143)
		(layer "In15.Cu")
		(net "GMI_CPU0_G1_CPU1_G3_TX_DN<12>")
	)
	(segment
		(start 347.688154 -233.46664)
		(end 347.718634 -233.44886)
		(width 0.1143)
		(layer "In15.Cu")
		(net "GMI_CPU0_G1_CPU1_G3_TX_DN<12>")
	)
	(segment
		(start 347.213682 -225.52914)
		(end 347.186504 -225.513392)
		(width 0.1143)
		(layer "In15.Cu")
		(net "GMI_CPU0_G1_CPU1_G3_TX_DN<12>")
	)
	(segment
		(start 123.777248 -223.729296)
		(end 123.807728 -223.747076)
		(width 0.1143)
		(layer "In15.Cu")
		(net "GMI_CPU0_G1_CPU1_G3_TX_DN<12>")
	)
	(segment
		(start 123.777248 -231.829102)
		(end 123.807728 -231.846882)
		(width 0.1143)
		(layer "In15.Cu")
		(net "GMI_CPU0_G1_CPU1_G3_TX_DN<12>")
	)
	(segment
		(start 309.346346 -188.483748)
		(end 303.70526 -188.483748)
		(width 0.14224)
		(layer "In15.Cu")
		(net "GMI_CPU0_G1_CPU1_G3_TX_DN<12>")
	)
	(segment
		(start 123.807728 -236.061758)
		(end 123.777248 -236.079538)
		(width 0.1143)
		(layer "In15.Cu")
		(net "GMI_CPU0_G1_CPU1_G3_TX_DN<12>")
	)
	(segment
		(start 347.649038 -231.869488)
		(end 347.688154 -231.846628)
		(width 0.1143)
		(layer "In15.Cu")
		(net "GMI_CPU0_G1_CPU1_G3_TX_DN<12>")
	)
	(segment
		(start 123.777248 -226.96932)
		(end 123.807728 -226.9871)
		(width 0.1143)
		(layer "In15.Cu")
		(net "GMI_CPU0_G1_CPU1_G3_TX_DN<12>")
	)
	(segment
		(start 345.94546 -221.38767)
		(end 345.94546 -221.143322)
		(width 0.1143)
		(layer "In15.Cu")
		(net "GMI_CPU0_G1_CPU1_G3_TX_DN<12>")
	)
	(segment
		(start 123.807728 -240.921794)
		(end 123.777248 -240.939574)
		(width 0.1143)
		(layer "In15.Cu")
		(net "GMI_CPU0_G1_CPU1_G3_TX_DN<12>")
	)
	(segment
		(start 123.807728 -231.201976)
		(end 123.775216 -231.220772)
		(width 0.1143)
		(layer "In15.Cu")
		(net "GMI_CPU0_G1_CPU1_G3_TX_DN<12>")
	)
	(segment
		(start 347.688154 -234.441492)
		(end 347.649038 -234.418632)
		(width 0.1143)
		(layer "In15.Cu")
		(net "GMI_CPU0_G1_CPU1_G3_TX_DN<12>")
	)
	(segment
		(start 207.113378 -188.356748)
		(end 161.991548 -188.54801)
		(width 0.14224)
		(layer "In15.Cu")
		(net "GMI_CPU0_G1_CPU1_G3_TX_DN<12>")
	)
	(segment
		(start 318.759586 -195.154042)
		(end 318.637666 -195.032376)
		(width 0.14224)
		(layer "In15.Cu")
		(net "GMI_CPU0_G1_CPU1_G3_TX_DN<12>")
	)
	(segment
		(start 347.649038 -227.009706)
		(end 347.688154 -226.986846)
		(width 0.1143)
		(layer "In15.Cu")
		(net "GMI_CPU0_G1_CPU1_G3_TX_DN<12>")
	)
	(segment
		(start 145.878042 -200.66)
		(end 125.30328 -217.53068)
		(width 0.14224)
		(layer "In15.Cu")
		(net "GMI_CPU0_G1_CPU1_G3_TX_DN<12>")
	)
	(segment
		(start 347.649038 -241.58956)
		(end 347.688154 -241.5667)
		(width 0.1143)
		(layer "In15.Cu")
		(net "GMI_CPU0_G1_CPU1_G3_TX_DN<12>")
	)
	(segment
		(start 318.637666 -195.032376)
		(end 309.346346 -188.483748)
		(width 0.14224)
		(layer "In15.Cu")
		(net "GMI_CPU0_G1_CPU1_G3_TX_DN<12>")
	)
	(segment
		(start 123.777248 -225.349308)
		(end 123.807728 -225.367088)
		(width 0.1143)
		(layer "In15.Cu")
		(net "GMI_CPU0_G1_CPU1_G3_TX_DN<12>")
	)
	(segment
		(start 347.688154 -228.606858)
		(end 347.718634 -228.589078)
		(width 0.1143)
		(layer "In15.Cu")
		(net "GMI_CPU0_G1_CPU1_G3_TX_DN<12>")
	)
	(segment
		(start 148.0058 -200.015856)
		(end 145.878042 -200.66)
		(width 0.14224)
		(layer "In15.Cu")
		(net "GMI_CPU0_G1_CPU1_G3_TX_DN<12>")
	)
	(segment
		(start 153.292556 -195.680838)
		(end 153.273252 -195.873878)
		(width 0.14224)
		(layer "In15.Cu")
		(net "GMI_CPU0_G1_CPU1_G3_TX_DN<12>")
	)
	(segment
		(start 123.846844 -242.518946)
		(end 123.807728 -242.541806)
		(width 0.1143)
		(layer "In15.Cu")
		(net "GMI_CPU0_G1_CPU1_G3_TX_DN<12>")
	)
	(segment
		(start 347.688154 -244.161564)
		(end 347.649038 -244.138704)
		(width 0.1143)
		(layer "In15.Cu")
		(net "GMI_CPU0_G1_CPU1_G3_TX_DN<12>")
	)
	(segment
		(start 347.688154 -226.341686)
		(end 347.649038 -226.318826)
		(width 0.1143)
		(layer "In15.Cu")
		(net "GMI_CPU0_G1_CPU1_G3_TX_DN<12>")
	)
	(segment
		(start 347.688154 -242.541552)
		(end 347.649038 -242.518692)
		(width 0.1143)
		(layer "In15.Cu")
		(net "GMI_CPU0_G1_CPU1_G3_TX_DN<12>")
	)
	(segment
		(start 123.619514 -221.199202)
		(end 123.619514 -221.804484)
		(width 0.1143)
		(layer "In15.Cu")
		(net "GMI_CPU0_G1_CPU1_G3_TX_DN<12>")
	)
	(segment
		(start 123.807728 -237.68177)
		(end 123.777248 -237.69955)
		(width 0.1143)
		(layer "In15.Cu")
		(net "GMI_CPU0_G1_CPU1_G3_TX_DN<12>")
	)
	(segment
		(start 123.807728 -241.566954)
		(end 123.846844 -241.589814)
		(width 0.1143)
		(layer "In15.Cu")
		(net "GMI_CPU0_G1_CPU1_G3_TX_DN<12>")
	)
	(segment
		(start 123.807728 -228.607112)
		(end 123.846844 -228.629972)
		(width 0.1143)
		(layer "In15.Cu")
		(net "GMI_CPU0_G1_CPU1_G3_TX_DN<12>")
	)
	(segment
		(start 154.494738 -194.695064)
		(end 154.164792 -194.965574)
		(width 0.14224)
		(layer "In15.Cu")
		(net "GMI_CPU0_G1_CPU1_G3_TX_DN<12>")
	)
	(segment
		(start 158.087568 -191.926464)
		(end 157.757368 -192.197228)
		(width 0.14224)
		(layer "In15.Cu")
		(net "GMI_CPU0_G1_CPU1_G3_TX_DN<12>")
	)
	(segment
		(start 123.807728 -239.946942)
		(end 123.846844 -239.969802)
		(width 0.1143)
		(layer "In15.Cu")
		(net "GMI_CPU0_G1_CPU1_G3_TX_DN<12>")
	)
	(segment
		(start 347.718634 -226.359466)
		(end 347.688154 -226.341686)
		(width 0.1143)
		(layer "In15.Cu")
		(net "GMI_CPU0_G1_CPU1_G3_TX_DN<12>")
	)
	(segment
		(start 123.807728 -232.821734)
		(end 123.777248 -232.839514)
		(width 0.1143)
		(layer "In15.Cu")
		(net "GMI_CPU0_G1_CPU1_G3_TX_DN<12>")
	)
	(arc
		(start 123.306078 -244.990112)
		(mid 123.191402 -245.123446)
		(end 123.150122 -245.294404)
		(width 0.1143)
		(layer "In15.Cu")
		(net "GMI_CPU0_G1_CPU1_G3_TX_DN<12>")
	)
	(arc
		(start 347.649038 -231.178862)
		(mid 347.470225 -230.976512)
		(end 347.405706 -230.714296)
		(width 0.1143)
		(layer "In15.Cu")
		(net "GMI_CPU0_G1_CPU1_G3_TX_DN<12>")
	)
	(arc
		(start 346.708984 -223.078802)
		(mid 346.530171 -222.876452)
		(end 346.465652 -222.614236)
		(width 0.1143)
		(layer "In15.Cu")
		(net "GMI_CPU0_G1_CPU1_G3_TX_DN<12>")
	)
	(arc
		(start 347.718634 -235.068872)
		(mid 347.875611 -234.764072)
		(end 347.718634 -234.459272)
		(width 0.1143)
		(layer "In15.Cu")
		(net "GMI_CPU0_G1_CPU1_G3_TX_DN<12>")
	)
	(arc
		(start 347.649038 -227.938838)
		(mid 347.405711 -227.474272)
		(end 347.649038 -227.009706)
		(width 0.1143)
		(layer "In15.Cu")
		(net "GMI_CPU0_G1_CPU1_G3_TX_DN<12>")
	)
	(arc
		(start 347.718634 -239.928908)
		(mid 347.875611 -239.624108)
		(end 347.718634 -239.319308)
		(width 0.1143)
		(layer "In15.Cu")
		(net "GMI_CPU0_G1_CPU1_G3_TX_DN<12>")
	)
	(arc
		(start 123.846844 -227.00996)
		(mid 124.090171 -227.474526)
		(end 123.846844 -227.939092)
		(width 0.1143)
		(layer "In15.Cu")
		(net "GMI_CPU0_G1_CPU1_G3_TX_DN<12>")
	)
	(arc
		(start 123.846844 -239.969802)
		(mid 124.090171 -240.434368)
		(end 123.846844 -240.898934)
		(width 0.1143)
		(layer "In15.Cu")
		(net "GMI_CPU0_G1_CPU1_G3_TX_DN<12>")
	)
	(arc
		(start 347.178884 -225.50882)
		(mid 347.000071 -225.30647)
		(end 346.935552 -225.044254)
		(width 0.1143)
		(layer "In15.Cu")
		(net "GMI_CPU0_G1_CPU1_G3_TX_DN<12>")
	)
	(arc
		(start 123.777248 -239.319562)
		(mid 123.620271 -239.624362)
		(end 123.777248 -239.929162)
		(width 0.1143)
		(layer "In15.Cu")
		(net "GMI_CPU0_G1_CPU1_G3_TX_DN<12>")
	)
	(arc
		(start 123.846844 -238.34979)
		(mid 124.090171 -238.814356)
		(end 123.846844 -239.278922)
		(width 0.1143)
		(layer "In15.Cu")
		(net "GMI_CPU0_G1_CPU1_G3_TX_DN<12>")
	)
	(arc
		(start 347.649038 -239.278668)
		(mid 347.405711 -238.814102)
		(end 347.649038 -238.349536)
		(width 0.1143)
		(layer "In15.Cu")
		(net "GMI_CPU0_G1_CPU1_G3_TX_DN<12>")
	)
	(arc
		(start 347.649038 -240.89868)
		(mid 347.405711 -240.434114)
		(end 347.649038 -239.969548)
		(width 0.1143)
		(layer "In15.Cu")
		(net "GMI_CPU0_G1_CPU1_G3_TX_DN<12>")
	)
	(arc
		(start 347.405706 -230.714296)
		(mid 347.470942 -230.450705)
		(end 347.651578 -230.247952)
		(width 0.1143)
		(layer "In15.Cu")
		(net "GMI_CPU0_G1_CPU1_G3_TX_DN<12>")
	)
	(arc
		(start 123.775216 -231.220772)
		(mid 123.661287 -231.353919)
		(end 123.620276 -231.524302)
		(width 0.1143)
		(layer "In15.Cu")
		(net "GMI_CPU0_G1_CPU1_G3_TX_DN<12>")
	)
	(arc
		(start 123.150122 -245.294404)
		(mid 123.085607 -245.556623)
		(end 122.90679 -245.75897)
		(width 0.1143)
		(layer "In15.Cu")
		(net "GMI_CPU0_G1_CPU1_G3_TX_DN<12>")
	)
	(arc
		(start 347.875606 -244.484144)
		(mid 347.834057 -244.312722)
		(end 347.718634 -244.179344)
		(width 0.1143)
		(layer "In15.Cu")
		(net "GMI_CPU0_G1_CPU1_G3_TX_DN<12>")
	)
	(arc
		(start 346.77858 -223.729042)
		(mid 346.935557 -223.424242)
		(end 346.77858 -223.119442)
		(width 0.1143)
		(layer "In15.Cu")
		(net "GMI_CPU0_G1_CPU1_G3_TX_DN<12>")
	)
	(arc
		(start 347.649038 -242.518692)
		(mid 347.405711 -242.054126)
		(end 347.649038 -241.58956)
		(width 0.1143)
		(layer "In15.Cu")
		(net "GMI_CPU0_G1_CPU1_G3_TX_DN<12>")
	)
	(arc
		(start 123.777248 -223.119696)
		(mid 123.620271 -223.424496)
		(end 123.777248 -223.729296)
		(width 0.1143)
		(layer "In15.Cu")
		(net "GMI_CPU0_G1_CPU1_G3_TX_DN<12>")
	)
	(arc
		(start 348.808802 -246.034306)
		(mid 348.756753 -245.902787)
		(end 348.659704 -245.799864)
		(width 0.1143)
		(layer "In15.Cu")
		(net "GMI_CPU0_G1_CPU1_G3_TX_DN<12>")
	)
	(arc
		(start 347.649038 -237.658656)
		(mid 347.405711 -237.19409)
		(end 347.649038 -236.729524)
		(width 0.1143)
		(layer "In15.Cu")
		(net "GMI_CPU0_G1_CPU1_G3_TX_DN<12>")
	)
	(arc
		(start 123.844304 -230.248206)
		(mid 124.024956 -230.450951)
		(end 124.090176 -230.71455)
		(width 0.1143)
		(layer "In15.Cu")
		(net "GMI_CPU0_G1_CPU1_G3_TX_DN<12>")
	)
	(arc
		(start 123.846844 -225.389948)
		(mid 124.090171 -225.854514)
		(end 123.846844 -226.31908)
		(width 0.1143)
		(layer "In15.Cu")
		(net "GMI_CPU0_G1_CPU1_G3_TX_DN<12>")
	)
	(arc
		(start 347.649038 -232.79862)
		(mid 347.405711 -232.334054)
		(end 347.649038 -231.869488)
		(width 0.1143)
		(layer "In15.Cu")
		(net "GMI_CPU0_G1_CPU1_G3_TX_DN<12>")
	)
	(arc
		(start 347.649038 -226.318826)
		(mid 347.470225 -226.116476)
		(end 347.405706 -225.85426)
		(width 0.1143)
		(layer "In15.Cu")
		(net "GMI_CPU0_G1_CPU1_G3_TX_DN<12>")
	)
	(arc
		(start 123.777248 -226.35972)
		(mid 123.620271 -226.66452)
		(end 123.777248 -226.96932)
		(width 0.1143)
		(layer "In15.Cu")
		(net "GMI_CPU0_G1_CPU1_G3_TX_DN<12>")
	)
	(arc
		(start 123.846844 -235.109766)
		(mid 124.090171 -235.574332)
		(end 123.846844 -236.038898)
		(width 0.1143)
		(layer "In15.Cu")
		(net "GMI_CPU0_G1_CPU1_G3_TX_DN<12>")
	)
	(arc
		(start 122.837194 -245.79961)
		(mid 122.739429 -245.902586)
		(end 122.68708 -246.03456)
		(width 0.1143)
		(layer "In15.Cu")
		(net "GMI_CPU0_G1_CPU1_G3_TX_DN<12>")
	)
	(arc
		(start 123.620276 -231.524302)
		(mid 123.661825 -231.695724)
		(end 123.777248 -231.829102)
		(width 0.1143)
		(layer "In15.Cu")
		(net "GMI_CPU0_G1_CPU1_G3_TX_DN<12>")
	)
	(arc
		(start 346.935552 -225.044254)
		(mid 346.894003 -224.872832)
		(end 346.77858 -224.739454)
		(width 0.1143)
		(layer "In15.Cu")
		(net "GMI_CPU0_G1_CPU1_G3_TX_DN<12>")
	)
	(arc
		(start 347.649038 -229.55885)
		(mid 347.405711 -229.094284)
		(end 347.649038 -228.629718)
		(width 0.1143)
		(layer "In15.Cu")
		(net "GMI_CPU0_G1_CPU1_G3_TX_DN<12>")
	)
	(arc
		(start 123.777248 -244.179598)
		(mid 123.661821 -244.312974)
		(end 123.620276 -244.484398)
		(width 0.1143)
		(layer "In15.Cu")
		(net "GMI_CPU0_G1_CPU1_G3_TX_DN<12>")
	)
	(arc
		(start 347.875606 -229.904036)
		(mid 347.83464 -229.73363)
		(end 347.720666 -229.600506)
		(width 0.1143)
		(layer "In15.Cu")
		(net "GMI_CPU0_G1_CPU1_G3_TX_DN<12>")
	)
	(arc
		(start 123.777248 -224.739708)
		(mid 123.620271 -225.044508)
		(end 123.777248 -225.349308)
		(width 0.1143)
		(layer "In15.Cu")
		(net "GMI_CPU0_G1_CPU1_G3_TX_DN<12>")
	)
	(arc
		(start 347.718634 -226.969066)
		(mid 347.875611 -226.664266)
		(end 347.718634 -226.359466)
		(width 0.1143)
		(layer "In15.Cu")
		(net "GMI_CPU0_G1_CPU1_G3_TX_DN<12>")
	)
	(arc
		(start 347.405706 -225.85426)
		(mid 347.364451 -225.683289)
		(end 347.24975 -225.549968)
		(width 0.1143)
		(layer "In15.Cu")
		(net "GMI_CPU0_G1_CPU1_G3_TX_DN<12>")
	)
	(arc
		(start 123.84786 -222.150686)
		(mid 124.025925 -222.352863)
		(end 124.090176 -222.61449)
		(width 0.1143)
		(layer "In15.Cu")
		(net "GMI_CPU0_G1_CPU1_G3_TX_DN<12>")
	)
	(arc
		(start 347.718634 -230.208836)
		(mid 347.834061 -230.07546)
		(end 347.875606 -229.904036)
		(width 0.1143)
		(layer "In15.Cu")
		(net "GMI_CPU0_G1_CPU1_G3_TX_DN<12>")
	)
	(arc
		(start 123.620276 -244.484398)
		(mid 123.555761 -244.746617)
		(end 123.376944 -244.948964)
		(width 0.1143)
		(layer "In15.Cu")
		(net "GMI_CPU0_G1_CPU1_G3_TX_DN<12>")
	)
	(arc
		(start 123.846844 -233.489754)
		(mid 124.090171 -233.95432)
		(end 123.846844 -234.418886)
		(width 0.1143)
		(layer "In15.Cu")
		(net "GMI_CPU0_G1_CPU1_G3_TX_DN<12>")
	)
	(arc
		(start 123.777248 -232.839514)
		(mid 123.620271 -233.144314)
		(end 123.777248 -233.449114)
		(width 0.1143)
		(layer "In15.Cu")
		(net "GMI_CPU0_G1_CPU1_G3_TX_DN<12>")
	)
	(arc
		(start 124.090176 -230.71455)
		(mid 124.025661 -230.976769)
		(end 123.846844 -231.179116)
		(width 0.1143)
		(layer "In15.Cu")
		(net "GMI_CPU0_G1_CPU1_G3_TX_DN<12>")
	)
	(arc
		(start 123.777248 -236.079538)
		(mid 123.620271 -236.384338)
		(end 123.777248 -236.689138)
		(width 0.1143)
		(layer "In15.Cu")
		(net "GMI_CPU0_G1_CPU1_G3_TX_DN<12>")
	)
	(arc
		(start 346.708984 -224.698814)
		(mid 346.465657 -224.234248)
		(end 346.708984 -223.769682)
		(width 0.1143)
		(layer "In15.Cu")
		(net "GMI_CPU0_G1_CPU1_G3_TX_DN<12>")
	)
	(arc
		(start 348.118938 -244.94871)
		(mid 347.940125 -244.74636)
		(end 347.875606 -244.484144)
		(width 0.1143)
		(layer "In15.Cu")
		(net "GMI_CPU0_G1_CPU1_G3_TX_DN<12>")
	)
	(arc
		(start 123.777248 -240.939574)
		(mid 123.620271 -241.244374)
		(end 123.777248 -241.549174)
		(width 0.1143)
		(layer "In15.Cu")
		(net "GMI_CPU0_G1_CPU1_G3_TX_DN<12>")
	)
	(arc
		(start 347.649038 -244.138704)
		(mid 347.405711 -243.674138)
		(end 347.649038 -243.209572)
		(width 0.1143)
		(layer "In15.Cu")
		(net "GMI_CPU0_G1_CPU1_G3_TX_DN<12>")
	)
	(arc
		(start 347.875606 -231.524048)
		(mid 347.83464 -231.353642)
		(end 347.720666 -231.220518)
		(width 0.1143)
		(layer "In15.Cu")
		(net "GMI_CPU0_G1_CPU1_G3_TX_DN<12>")
	)
	(arc
		(start 123.846844 -236.729778)
		(mid 124.090171 -237.194344)
		(end 123.846844 -237.65891)
		(width 0.1143)
		(layer "In15.Cu")
		(net "GMI_CPU0_G1_CPU1_G3_TX_DN<12>")
	)
	(arc
		(start 347.718634 -243.168932)
		(mid 347.875611 -242.864132)
		(end 347.718634 -242.559332)
		(width 0.1143)
		(layer "In15.Cu")
		(net "GMI_CPU0_G1_CPU1_G3_TX_DN<12>")
	)
	(arc
		(start 123.777248 -227.979732)
		(mid 123.620271 -228.284532)
		(end 123.777248 -228.589332)
		(width 0.1143)
		(layer "In15.Cu")
		(net "GMI_CPU0_G1_CPU1_G3_TX_DN<12>")
	)
	(arc
		(start 123.619514 -221.804484)
		(mid 123.660564 -221.974934)
		(end 123.774708 -222.108014)
		(width 0.1143)
		(layer "In15.Cu")
		(net "GMI_CPU0_G1_CPU1_G3_TX_DN<12>")
	)
	(arc
		(start 347.718634 -231.828848)
		(mid 347.834061 -231.695472)
		(end 347.875606 -231.524048)
		(width 0.1143)
		(layer "In15.Cu")
		(net "GMI_CPU0_G1_CPU1_G3_TX_DN<12>")
	)
	(arc
		(start 347.718634 -241.54892)
		(mid 347.875611 -241.24412)
		(end 347.718634 -240.93932)
		(width 0.1143)
		(layer "In15.Cu")
		(net "GMI_CPU0_G1_CPU1_G3_TX_DN<12>")
	)
	(arc
		(start 348.627954 -245.781576)
		(mid 348.430472 -245.583447)
		(end 348.358206 -245.3132)
		(width 0.1143)
		(layer "In15.Cu")
		(net "GMI_CPU0_G1_CPU1_G3_TX_DN<12>")
	)
	(arc
		(start 346.465652 -222.614236)
		(mid 346.424397 -222.443265)
		(end 346.309696 -222.309944)
		(width 0.1143)
		(layer "In15.Cu")
		(net "GMI_CPU0_G1_CPU1_G3_TX_DN<12>")
	)
	(arc
		(start 123.846844 -223.769936)
		(mid 124.090171 -224.234502)
		(end 123.846844 -224.699068)
		(width 0.1143)
		(layer "In15.Cu")
		(net "GMI_CPU0_G1_CPU1_G3_TX_DN<12>")
	)
	(arc
		(start 347.649038 -234.418632)
		(mid 347.405711 -233.954066)
		(end 347.649038 -233.4895)
		(width 0.1143)
		(layer "In15.Cu")
		(net "GMI_CPU0_G1_CPU1_G3_TX_DN<12>")
	)
	(arc
		(start 123.846844 -231.869742)
		(mid 124.090171 -232.334308)
		(end 123.846844 -232.798874)
		(width 0.1143)
		(layer "In15.Cu")
		(net "GMI_CPU0_G1_CPU1_G3_TX_DN<12>")
	)
	(arc
		(start 123.620276 -229.90429)
		(mid 123.661825 -230.075712)
		(end 123.777248 -230.20909)
		(width 0.1143)
		(layer "In15.Cu")
		(net "GMI_CPU0_G1_CPU1_G3_TX_DN<12>")
	)
	(arc
		(start 346.239592 -222.269304)
		(mid 346.060399 -222.066794)
		(end 345.995752 -221.80423)
		(width 0.1143)
		(layer "In15.Cu")
		(net "GMI_CPU0_G1_CPU1_G3_TX_DN<12>")
	)
	(arc
		(start 123.846844 -228.629972)
		(mid 124.090171 -229.094538)
		(end 123.846844 -229.559104)
		(width 0.1143)
		(layer "In15.Cu")
		(net "GMI_CPU0_G1_CPU1_G3_TX_DN<12>")
	)
	(arc
		(start 347.718634 -233.44886)
		(mid 347.875611 -233.14406)
		(end 347.718634 -232.83926)
		(width 0.1143)
		(layer "In15.Cu")
		(net "GMI_CPU0_G1_CPU1_G3_TX_DN<12>")
	)
	(arc
		(start 123.846844 -243.209826)
		(mid 124.090171 -243.674392)
		(end 123.846844 -244.138958)
		(width 0.1143)
		(layer "In15.Cu")
		(net "GMI_CPU0_G1_CPU1_G3_TX_DN<12>")
	)
	(arc
		(start 123.777248 -234.459526)
		(mid 123.620271 -234.764326)
		(end 123.777248 -235.069126)
		(width 0.1143)
		(layer "In15.Cu")
		(net "GMI_CPU0_G1_CPU1_G3_TX_DN<12>")
	)
	(arc
		(start 348.358206 -245.303548)
		(mid 348.3079 -245.11596)
		(end 348.1705 -244.978682)
		(width 0.1143)
		(layer "In15.Cu")
		(net "GMI_CPU0_G1_CPU1_G3_TX_DN<12>")
	)
	(arc
		(start 124.090176 -222.61449)
		(mid 124.025661 -222.876709)
		(end 123.846844 -223.079056)
		(width 0.1143)
		(layer "In15.Cu")
		(net "GMI_CPU0_G1_CPU1_G3_TX_DN<12>")
	)
	(arc
		(start 347.649038 -236.038644)
		(mid 347.405711 -235.574078)
		(end 347.649038 -235.109512)
		(width 0.1143)
		(layer "In15.Cu")
		(net "GMI_CPU0_G1_CPU1_G3_TX_DN<12>")
	)
	(arc
		(start 123.777248 -242.559586)
		(mid 123.620271 -242.864386)
		(end 123.777248 -243.169186)
		(width 0.1143)
		(layer "In15.Cu")
		(net "GMI_CPU0_G1_CPU1_G3_TX_DN<12>")
	)
	(arc
		(start 347.718634 -238.308896)
		(mid 347.875611 -238.004096)
		(end 347.718634 -237.699296)
		(width 0.1143)
		(layer "In15.Cu")
		(net "GMI_CPU0_G1_CPU1_G3_TX_DN<12>")
	)
	(arc
		(start 347.718634 -236.688884)
		(mid 347.875611 -236.384084)
		(end 347.718634 -236.079284)
		(width 0.1143)
		(layer "In15.Cu")
		(net "GMI_CPU0_G1_CPU1_G3_TX_DN<12>")
	)
	(arc
		(start 347.718634 -228.589078)
		(mid 347.875611 -228.284278)
		(end 347.718634 -227.979478)
		(width 0.1143)
		(layer "In15.Cu")
		(net "GMI_CPU0_G1_CPU1_G3_TX_DN<12>")
	)
	(arc
		(start 123.777248 -237.69955)
		(mid 123.620271 -238.00435)
		(end 123.777248 -238.30915)
		(width 0.1143)
		(layer "In15.Cu")
		(net "GMI_CPU0_G1_CPU1_G3_TX_DN<12>")
	)
	(arc
		(start 123.846844 -241.589814)
		(mid 124.090171 -242.05438)
		(end 123.846844 -242.518946)
		(width 0.1143)
		(layer "In15.Cu")
		(net "GMI_CPU0_G1_CPU1_G3_TX_DN<12>")
	)
	(arc
		(start 123.775216 -229.60076)
		(mid 123.661287 -229.733907)
		(end 123.620276 -229.90429)
		(width 0.1143)
		(layer "In15.Cu")
		(net "GMI_CPU0_G1_CPU1_G3_TX_DN<12>")
	)
	(segment
		(start 122.587766 -244.750336)
		(end 123.054618 -244.484398)
		(width 0.12954)
		(layer "F.Cu")
		(net "GMI_CPU0_G1_CPU1_G3_TX_DN<11>")
	)
	(segment
		(start 348.907862 -244.750082)
		(end 348.44101 -244.484144)
		(width 0.12954)
		(layer "F.Cu")
		(net "GMI_CPU0_G1_CPU1_G3_TX_DN<11>")
	)
	(segment
		(start 156.74467 -191.459104)
		(end 156.727144 -191.63792)
		(width 0.14224)
		(layer "In15.Cu")
		(net "GMI_CPU0_G1_CPU1_G3_TX_DN<11>")
	)
	(segment
		(start 302.604932 -185.413142)
		(end 167.337232 -184.625742)
		(width 0.14224)
		(layer "In15.Cu")
		(net "GMI_CPU0_G1_CPU1_G3_TX_DN<11>")
	)
	(segment
		(start 122.837194 -239.929162)
		(end 122.867674 -239.946942)
		(width 0.1143)
		(layer "In15.Cu")
		(net "GMI_CPU0_G1_CPU1_G3_TX_DN<11>")
	)
	(segment
		(start 348.659704 -226.359974)
		(end 348.627954 -226.341686)
		(width 0.1143)
		(layer "In15.Cu")
		(net "GMI_CPU0_G1_CPU1_G3_TX_DN<11>")
	)
	(segment
		(start 348.633288 -240.924588)
		(end 348.632272 -240.92408)
		(width 0.1143)
		(layer "In15.Cu")
		(net "GMI_CPU0_G1_CPU1_G3_TX_DN<11>")
	)
	(segment
		(start 348.632272 -236.064044)
		(end 348.63151 -236.063536)
		(width 0.1143)
		(layer "In15.Cu")
		(net "GMI_CPU0_G1_CPU1_G3_TX_DN<11>")
	)
	(segment
		(start 122.867674 -226.34194)
		(end 122.837194 -226.35972)
		(width 0.1143)
		(layer "In15.Cu")
		(net "GMI_CPU0_G1_CPU1_G3_TX_DN<11>")
	)
	(segment
		(start 348.632272 -239.304068)
		(end 348.63151 -239.30356)
		(width 0.1143)
		(layer "In15.Cu")
		(net "GMI_CPU0_G1_CPU1_G3_TX_DN<11>")
	)
	(segment
		(start 156.233876 -191.878204)
		(end 155.230068 -192.701164)
		(width 0.14224)
		(layer "In15.Cu")
		(net "GMI_CPU0_G1_CPU1_G3_TX_DN<11>")
	)
	(segment
		(start 348.649036 -239.934496)
		(end 348.649798 -239.933988)
		(width 0.1143)
		(layer "In15.Cu")
		(net "GMI_CPU0_G1_CPU1_G3_TX_DN<11>")
	)
	(segment
		(start 348.661482 -231.22128)
		(end 348.658688 -231.219248)
		(width 0.1143)
		(layer "In15.Cu")
		(net "GMI_CPU0_G1_CPU1_G3_TX_DN<11>")
	)
	(segment
		(start 348.633288 -239.304576)
		(end 348.632272 -239.304068)
		(width 0.1143)
		(layer "In15.Cu")
		(net "GMI_CPU0_G1_CPU1_G3_TX_DN<11>")
	)
	(segment
		(start 348.627954 -240.92154)
		(end 348.6277 -240.92154)
		(width 0.1143)
		(layer "In15.Cu")
		(net "GMI_CPU0_G1_CPU1_G3_TX_DN<11>")
	)
	(segment
		(start 348.6277 -239.946942)
		(end 348.627954 -239.946688)
		(width 0.1143)
		(layer "In15.Cu")
		(net "GMI_CPU0_G1_CPU1_G3_TX_DN<11>")
	)
	(segment
		(start 348.628716 -227.962206)
		(end 348.627954 -227.961698)
		(width 0.1143)
		(layer "In15.Cu")
		(net "GMI_CPU0_G1_CPU1_G3_TX_DN<11>")
	)
	(segment
		(start 348.63405 -239.305084)
		(end 348.633288 -239.304576)
		(width 0.1143)
		(layer "In15.Cu")
		(net "GMI_CPU0_G1_CPU1_G3_TX_DN<11>")
	)
	(segment
		(start 348.629986 -231.845358)
		(end 348.659704 -231.82834)
		(width 0.1143)
		(layer "In15.Cu")
		(net "GMI_CPU0_G1_CPU1_G3_TX_DN<11>")
	)
	(segment
		(start 347.214444 -222.289624)
		(end 347.21292 -222.288608)
		(width 0.1143)
		(layer "In15.Cu")
		(net "GMI_CPU0_G1_CPU1_G3_TX_DN<11>")
	)
	(segment
		(start 154.880818 -193.164968)
		(end 154.687778 -193.145918)
		(width 0.14224)
		(layer "In15.Cu")
		(net "GMI_CPU0_G1_CPU1_G3_TX_DN<11>")
	)
	(segment
		(start 347.718634 -224.739454)
		(end 347.688154 -224.721674)
		(width 0.1143)
		(layer "In15.Cu")
		(net "GMI_CPU0_G1_CPU1_G3_TX_DN<11>")
	)
	(segment
		(start 346.89034 -221.128844)
		(end 346.84462 -221.083124)
		(width 0.1143)
		(layer "In15.Cu")
		(net "GMI_CPU0_G1_CPU1_G3_TX_DN<11>")
	)
	(segment
		(start 122.837194 -238.30915)
		(end 122.867674 -238.32693)
		(width 0.1143)
		(layer "In15.Cu")
		(net "GMI_CPU0_G1_CPU1_G3_TX_DN<11>")
	)
	(segment
		(start 348.63151 -242.543584)
		(end 348.630494 -242.543076)
		(width 0.1143)
		(layer "In15.Cu")
		(net "GMI_CPU0_G1_CPU1_G3_TX_DN<11>")
	)
	(segment
		(start 154.338782 -193.609468)
		(end 154.008582 -193.880232)
		(width 0.14224)
		(layer "In15.Cu")
		(net "GMI_CPU0_G1_CPU1_G3_TX_DN<11>")
	)
	(segment
		(start 348.6277 -236.706918)
		(end 348.627954 -236.706664)
		(width 0.1143)
		(layer "In15.Cu")
		(net "GMI_CPU0_G1_CPU1_G3_TX_DN<11>")
	)
	(segment
		(start 151.249634 -196.129402)
		(end 151.070818 -196.111622)
		(width 0.14224)
		(layer "In15.Cu")
		(net "GMI_CPU0_G1_CPU1_G3_TX_DN<11>")
	)
	(segment
		(start 348.6277 -241.566954)
		(end 348.627954 -241.5667)
		(width 0.1143)
		(layer "In15.Cu")
		(net "GMI_CPU0_G1_CPU1_G3_TX_DN<11>")
	)
	(segment
		(start 122.837194 -226.96932)
		(end 122.867674 -226.9871)
		(width 0.1143)
		(layer "In15.Cu")
		(net "GMI_CPU0_G1_CPU1_G3_TX_DN<11>")
	)
	(segment
		(start 348.629732 -237.682532)
		(end 348.628716 -237.682024)
		(width 0.1143)
		(layer "In15.Cu")
		(net "GMI_CPU0_G1_CPU1_G3_TX_DN<11>")
	)
	(segment
		(start 122.867674 -242.541806)
		(end 122.837194 -242.559586)
		(width 0.1143)
		(layer "In15.Cu")
		(net "GMI_CPU0_G1_CPU1_G3_TX_DN<11>")
	)
	(segment
		(start 347.688154 -223.746822)
		(end 347.718634 -223.729042)
		(width 0.1143)
		(layer "In15.Cu")
		(net "GMI_CPU0_G1_CPU1_G3_TX_DN<11>")
	)
	(segment
		(start 348.628716 -244.162072)
		(end 348.627954 -244.161564)
		(width 0.1143)
		(layer "In15.Cu")
		(net "GMI_CPU0_G1_CPU1_G3_TX_DN<11>")
	)
	(segment
		(start 348.628716 -231.84612)
		(end 348.629986 -231.845358)
		(width 0.1143)
		(layer "In15.Cu")
		(net "GMI_CPU0_G1_CPU1_G3_TX_DN<11>")
	)
	(segment
		(start 348.628716 -239.302036)
		(end 348.627954 -239.301528)
		(width 0.1143)
		(layer "In15.Cu")
		(net "GMI_CPU0_G1_CPU1_G3_TX_DN<11>")
	)
	(segment
		(start 157.552136 -190.961264)
		(end 157.237684 -191.219074)
		(width 0.14224)
		(layer "In15.Cu")
		(net "GMI_CPU0_G1_CPU1_G3_TX_DN<11>")
	)
	(segment
		(start 306.370736 -185.41492)
		(end 302.604932 -185.41492)
		(width 0.14224)
		(layer "In15.Cu")
		(net "GMI_CPU0_G1_CPU1_G3_TX_DN<11>")
	)
	(segment
		(start 122.90679 -234.418886)
		(end 122.867674 -234.441746)
		(width 0.1143)
		(layer "In15.Cu")
		(net "GMI_CPU0_G1_CPU1_G3_TX_DN<11>")
	)
	(segment
		(start 348.65945 -228.588316)
		(end 348.659704 -228.58857)
		(width 0.1143)
		(layer "In15.Cu")
		(net "GMI_CPU0_G1_CPU1_G3_TX_DN<11>")
	)
	(segment
		(start 151.070818 -196.111622)
		(end 149.194012 -197.6501)
		(width 0.14224)
		(layer "In15.Cu")
		(net "GMI_CPU0_G1_CPU1_G3_TX_DN<11>")
	)
	(segment
		(start 348.627954 -237.681516)
		(end 348.6277 -237.681516)
		(width 0.1143)
		(layer "In15.Cu")
		(net "GMI_CPU0_G1_CPU1_G3_TX_DN<11>")
	)
	(segment
		(start 348.627954 -238.326676)
		(end 348.649036 -238.314484)
		(width 0.1143)
		(layer "In15.Cu")
		(net "GMI_CPU0_G1_CPU1_G3_TX_DN<11>")
	)
	(segment
		(start 347.211904 -222.2881)
		(end 347.209618 -222.28683)
		(width 0.1143)
		(layer "In15.Cu")
		(net "GMI_CPU0_G1_CPU1_G3_TX_DN<11>")
	)
	(segment
		(start 348.627954 -233.46664)
		(end 348.628716 -233.466132)
		(width 0.1143)
		(layer "In15.Cu")
		(net "GMI_CPU0_G1_CPU1_G3_TX_DN<11>")
	)
	(segment
		(start 348.630494 -239.303052)
		(end 348.629732 -239.302544)
		(width 0.1143)
		(layer "In15.Cu")
		(net "GMI_CPU0_G1_CPU1_G3_TX_DN<11>")
	)
	(segment
		(start 348.594426 -230.246174)
		(end 348.59595 -230.245158)
		(width 0.1143)
		(layer "In15.Cu")
		(net "GMI_CPU0_G1_CPU1_G3_TX_DN<11>")
	)
	(segment
		(start 348.59595 -230.245158)
		(end 348.624398 -230.228648)
		(width 0.1143)
		(layer "In15.Cu")
		(net "GMI_CPU0_G1_CPU1_G3_TX_DN<11>")
	)
	(segment
		(start 348.658688 -231.219248)
		(end 348.617794 -231.195372)
		(width 0.1143)
		(layer "In15.Cu")
		(net "GMI_CPU0_G1_CPU1_G3_TX_DN<11>")
	)
	(segment
		(start 122.867674 -241.566954)
		(end 122.90679 -241.589814)
		(width 0.1143)
		(layer "In15.Cu")
		(net "GMI_CPU0_G1_CPU1_G3_TX_DN<11>")
	)
	(segment
		(start 122.83567 -222.108776)
		(end 122.86742 -222.127064)
		(width 0.1143)
		(layer "In15.Cu")
		(net "GMI_CPU0_G1_CPU1_G3_TX_DN<11>")
	)
	(segment
		(start 348.594426 -229.562152)
		(end 348.591632 -229.560628)
		(width 0.1143)
		(layer "In15.Cu")
		(net "GMI_CPU0_G1_CPU1_G3_TX_DN<11>")
	)
	(segment
		(start 346.89034 -221.38767)
		(end 346.89034 -221.128844)
		(width 0.1143)
		(layer "In15.Cu")
		(net "GMI_CPU0_G1_CPU1_G3_TX_DN<11>")
	)
	(segment
		(start 348.632272 -237.684056)
		(end 348.63151 -237.683548)
		(width 0.1143)
		(layer "In15.Cu")
		(net "GMI_CPU0_G1_CPU1_G3_TX_DN<11>")
	)
	(segment
		(start 348.630494 -242.543076)
		(end 348.629732 -242.542568)
		(width 0.1143)
		(layer "In15.Cu")
		(net "GMI_CPU0_G1_CPU1_G3_TX_DN<11>")
	)
	(segment
		(start 347.21546 -222.290132)
		(end 347.214444 -222.289624)
		(width 0.1143)
		(layer "In15.Cu")
		(net "GMI_CPU0_G1_CPU1_G3_TX_DN<11>")
	)
	(segment
		(start 348.659704 -239.319816)
		(end 348.63532 -239.305846)
		(width 0.1143)
		(layer "In15.Cu")
		(net "GMI_CPU0_G1_CPU1_G3_TX_DN<11>")
	)
	(segment
		(start 122.75693 -244.484398)
		(end 123.054618 -244.484398)
		(width 0.1143)
		(layer "In15.Cu")
		(net "GMI_CPU0_G1_CPU1_G3_TX_DN<11>")
	)
	(segment
		(start 346.84462 -221.083124)
		(end 346.84462 -219.846652)
		(width 0.14224)
		(layer "In15.Cu")
		(net "GMI_CPU0_G1_CPU1_G3_TX_DN<11>")
	)
	(segment
		(start 152.26411 -195.31076)
		(end 152.07107 -195.29171)
		(width 0.14224)
		(layer "In15.Cu")
		(net "GMI_CPU0_G1_CPU1_G3_TX_DN<11>")
	)
	(segment
		(start 348.161356 -225.533458)
		(end 348.158054 -225.53168)
		(width 0.1143)
		(layer "In15.Cu")
		(net "GMI_CPU0_G1_CPU1_G3_TX_DN<11>")
	)
	(segment
		(start 344.567764 -215.035638)
		(end 314.093606 -190.047626)
		(width 0.14224)
		(layer "In15.Cu")
		(net "GMI_CPU0_G1_CPU1_G3_TX_DN<11>")
	)
	(segment
		(start 347.24975 -222.309944)
		(end 347.218 -222.291656)
		(width 0.1143)
		(layer "In15.Cu")
		(net "GMI_CPU0_G1_CPU1_G3_TX_DN<11>")
	)
	(segment
		(start 348.628716 -240.922048)
		(end 348.627954 -240.92154)
		(width 0.1143)
		(layer "In15.Cu")
		(net "GMI_CPU0_G1_CPU1_G3_TX_DN<11>")
	)
	(segment
		(start 348.627954 -230.226616)
		(end 348.631764 -230.22433)
		(width 0.1143)
		(layer "In15.Cu")
		(net "GMI_CPU0_G1_CPU1_G3_TX_DN<11>")
	)
	(segment
		(start 348.633288 -237.684564)
		(end 348.632272 -237.684056)
		(width 0.1143)
		(layer "In15.Cu")
		(net "GMI_CPU0_G1_CPU1_G3_TX_DN<11>")
	)
	(segment
		(start 348.659704 -236.079792)
		(end 348.634304 -236.065314)
		(width 0.1143)
		(layer "In15.Cu")
		(net "GMI_CPU0_G1_CPU1_G3_TX_DN<11>")
	)
	(segment
		(start 348.649036 -241.554508)
		(end 348.649798 -241.554)
		(width 0.1143)
		(layer "In15.Cu")
		(net "GMI_CPU0_G1_CPU1_G3_TX_DN<11>")
	)
	(segment
		(start 122.867674 -231.201976)
		(end 122.835162 -231.220772)
		(width 0.1143)
		(layer "In15.Cu")
		(net "GMI_CPU0_G1_CPU1_G3_TX_DN<11>")
	)
	(segment
		(start 348.659704 -227.979986)
		(end 348.628716 -227.962206)
		(width 0.1143)
		(layer "In15.Cu")
		(net "GMI_CPU0_G1_CPU1_G3_TX_DN<11>")
	)
	(segment
		(start 348.628716 -243.186204)
		(end 348.629986 -243.185442)
		(width 0.1143)
		(layer "In15.Cu")
		(net "GMI_CPU0_G1_CPU1_G3_TX_DN<11>")
	)
	(segment
		(start 153.136346 -194.595496)
		(end 152.943306 -194.576446)
		(width 0.14224)
		(layer "In15.Cu")
		(net "GMI_CPU0_G1_CPU1_G3_TX_DN<11>")
	)
	(segment
		(start 157.058868 -191.201548)
		(end 156.74467 -191.459104)
		(width 0.14224)
		(layer "In15.Cu")
		(net "GMI_CPU0_G1_CPU1_G3_TX_DN<11>")
	)
	(segment
		(start 348.630494 -236.063028)
		(end 348.629732 -236.06252)
		(width 0.1143)
		(layer "In15.Cu")
		(net "GMI_CPU0_G1_CPU1_G3_TX_DN<11>")
	)
	(segment
		(start 122.867674 -234.441746)
		(end 122.837194 -234.459526)
		(width 0.1143)
		(layer "In15.Cu")
		(net "GMI_CPU0_G1_CPU1_G3_TX_DN<11>")
	)
	(segment
		(start 122.68708 -244.414548)
		(end 122.75693 -244.484398)
		(width 0.1143)
		(layer "In15.Cu")
		(net "GMI_CPU0_G1_CPU1_G3_TX_DN<11>")
	)
	(segment
		(start 347.21292 -222.288608)
		(end 347.211904 -222.2881)
		(width 0.1143)
		(layer "In15.Cu")
		(net "GMI_CPU0_G1_CPU1_G3_TX_DN<11>")
	)
	(segment
		(start 348.66072 -229.60076)
		(end 348.627954 -229.58171)
		(width 0.1143)
		(layer "In15.Cu")
		(net "GMI_CPU0_G1_CPU1_G3_TX_DN<11>")
	)
	(segment
		(start 122.867674 -223.747076)
		(end 122.90679 -223.769936)
		(width 0.1143)
		(layer "In15.Cu")
		(net "GMI_CPU0_G1_CPU1_G3_TX_DN<11>")
	)
	(segment
		(start 155.230068 -192.701164)
		(end 155.211018 -192.894204)
		(width 0.14224)
		(layer "In15.Cu")
		(net "GMI_CPU0_G1_CPU1_G3_TX_DN<11>")
	)
	(segment
		(start 348.628716 -233.466132)
		(end 348.629986 -233.46537)
		(width 0.1143)
		(layer "In15.Cu")
		(net "GMI_CPU0_G1_CPU1_G3_TX_DN<11>")
	)
	(segment
		(start 348.649036 -235.07446)
		(end 348.649798 -235.073952)
		(width 0.1143)
		(layer "In15.Cu")
		(net "GMI_CPU0_G1_CPU1_G3_TX_DN<11>")
	)
	(segment
		(start 157.237684 -191.219074)
		(end 157.058868 -191.201548)
		(width 0.14224)
		(layer "In15.Cu")
		(net "GMI_CPU0_G1_CPU1_G3_TX_DN<11>")
	)
	(segment
		(start 348.630494 -237.68304)
		(end 348.629732 -237.682532)
		(width 0.1143)
		(layer "In15.Cu")
		(net "GMI_CPU0_G1_CPU1_G3_TX_DN<11>")
	)
	(segment
		(start 122.867674 -239.946942)
		(end 122.90679 -239.969802)
		(width 0.1143)
		(layer "In15.Cu")
		(net "GMI_CPU0_G1_CPU1_G3_TX_DN<11>")
	)
	(segment
		(start 348.628716 -228.60635)
		(end 348.631002 -228.60508)
		(width 0.1143)
		(layer "In15.Cu")
		(net "GMI_CPU0_G1_CPU1_G3_TX_DN<11>")
	)
	(segment
		(start 348.591632 -227.007928)
		(end 348.627954 -226.986846)
		(width 0.1143)
		(layer "In15.Cu")
		(net "GMI_CPU0_G1_CPU1_G3_TX_DN<11>")
	)
	(segment
		(start 122.867674 -239.301782)
		(end 122.837194 -239.319562)
		(width 0.1143)
		(layer "In15.Cu")
		(net "GMI_CPU0_G1_CPU1_G3_TX_DN<11>")
	)
	(segment
		(start 348.628716 -242.54206)
		(end 348.627954 -242.541552)
		(width 0.1143)
		(layer "In15.Cu")
		(net "GMI_CPU0_G1_CPU1_G3_TX_DN<11>")
	)
	(segment
		(start 122.867674 -244.161818)
		(end 122.837194 -244.179598)
		(width 0.1143)
		(layer "In15.Cu")
		(net "GMI_CPU0_G1_CPU1_G3_TX_DN<11>")
	)
	(segment
		(start 348.627954 -232.82148)
		(end 348.591632 -232.800398)
		(width 0.1143)
		(layer "In15.Cu")
		(net "GMI_CPU0_G1_CPU1_G3_TX_DN<11>")
	)
	(segment
		(start 348.627954 -226.341686)
		(end 348.593156 -226.32162)
		(width 0.1143)
		(layer "In15.Cu")
		(net "GMI_CPU0_G1_CPU1_G3_TX_DN<11>")
	)
	(segment
		(start 348.659704 -234.45978)
		(end 348.627954 -234.441492)
		(width 0.1143)
		(layer "In15.Cu")
		(net "GMI_CPU0_G1_CPU1_G3_TX_DN<11>")
	)
	(segment
		(start 348.659704 -240.939828)
		(end 348.63532 -240.925858)
		(width 0.1143)
		(layer "In15.Cu")
		(net "GMI_CPU0_G1_CPU1_G3_TX_DN<11>")
	)
	(segment
		(start 122.66041 -221.066106)
		(end 122.66041 -221.198948)
		(width 0.1143)
		(layer "In15.Cu")
		(net "GMI_CPU0_G1_CPU1_G3_TX_DN<11>")
	)
	(segment
		(start 348.627954 -229.58171)
		(end 348.594426 -229.562152)
		(width 0.1143)
		(layer "In15.Cu")
		(net "GMI_CPU0_G1_CPU1_G3_TX_DN<11>")
	)
	(segment
		(start 145.36039 -199.804274)
		(end 124.659898 -216.777824)
		(width 0.14224)
		(layer "In15.Cu")
		(net "GMI_CPU0_G1_CPU1_G3_TX_DN<11>")
	)
	(segment
		(start 348.659704 -237.699804)
		(end 348.63532 -237.685834)
		(width 0.1143)
		(layer "In15.Cu")
		(net "GMI_CPU0_G1_CPU1_G3_TX_DN<11>")
	)
	(segment
		(start 122.90679 -232.798874)
		(end 122.867674 -232.821734)
		(width 0.1143)
		(layer "In15.Cu")
		(net "GMI_CPU0_G1_CPU1_G3_TX_DN<11>")
	)
	(segment
		(start 348.649798 -241.554)
		(end 348.659704 -241.548412)
		(width 0.1143)
		(layer "In15.Cu")
		(net "GMI_CPU0_G1_CPU1_G3_TX_DN<11>")
	)
	(segment
		(start 348.44101 -244.484144)
		(end 348.738952 -244.484144)
		(width 0.1143)
		(layer "In15.Cu")
		(net "GMI_CPU0_G1_CPU1_G3_TX_DN<11>")
	)
	(segment
		(start 154.008582 -193.880232)
		(end 153.815542 -193.861182)
		(width 0.14224)
		(layer "In15.Cu")
		(net "GMI_CPU0_G1_CPU1_G3_TX_DN<11>")
	)
	(segment
		(start 348.63151 -236.063536)
		(end 348.630494 -236.063028)
		(width 0.1143)
		(layer "In15.Cu")
		(net "GMI_CPU0_G1_CPU1_G3_TX_DN<11>")
	)
	(segment
		(start 122.867674 -240.921794)
		(end 122.837194 -240.939574)
		(width 0.1143)
		(layer "In15.Cu")
		(net "GMI_CPU0_G1_CPU1_G3_TX_DN<11>")
	)
	(segment
		(start 348.627954 -226.986846)
		(end 348.659704 -226.968558)
		(width 0.1143)
		(layer "In15.Cu")
		(net "GMI_CPU0_G1_CPU1_G3_TX_DN<11>")
	)
	(segment
		(start 348.649798 -236.693964)
		(end 348.659704 -236.688376)
		(width 0.1143)
		(layer "In15.Cu")
		(net "GMI_CPU0_G1_CPU1_G3_TX_DN<11>")
	)
	(segment
		(start 348.633288 -242.5446)
		(end 348.632272 -242.544092)
		(width 0.1143)
		(layer "In15.Cu")
		(net "GMI_CPU0_G1_CPU1_G3_TX_DN<11>")
	)
	(segment
		(start 122.867674 -224.721928)
		(end 122.837194 -224.739708)
		(width 0.1143)
		(layer "In15.Cu")
		(net "GMI_CPU0_G1_CPU1_G3_TX_DN<11>")
	)
	(segment
		(start 348.591632 -231.86771)
		(end 348.627954 -231.846628)
		(width 0.1143)
		(layer "In15.Cu")
		(net "GMI_CPU0_G1_CPU1_G3_TX_DN<11>")
	)
	(segment
		(start 348.627954 -234.441492)
		(end 348.591632 -234.42041)
		(width 0.1143)
		(layer "In15.Cu")
		(net "GMI_CPU0_G1_CPU1_G3_TX_DN<11>")
	)
	(segment
		(start 314.093606 -190.047626)
		(end 307.261006 -185.782966)
		(width 0.14224)
		(layer "In15.Cu")
		(net "GMI_CPU0_G1_CPU1_G3_TX_DN<11>")
	)
	(segment
		(start 122.837194 -235.069126)
		(end 122.867674 -235.086906)
		(width 0.1143)
		(layer "In15.Cu")
		(net "GMI_CPU0_G1_CPU1_G3_TX_DN<11>")
	)
	(segment
		(start 348.158054 -225.53168)
		(end 348.157038 -225.531172)
		(width 0.1143)
		(layer "In15.Cu")
		(net "GMI_CPU0_G1_CPU1_G3_TX_DN<11>")
	)
	(segment
		(start 122.837194 -236.689138)
		(end 122.867674 -236.706918)
		(width 0.1143)
		(layer "In15.Cu")
		(net "GMI_CPU0_G1_CPU1_G3_TX_DN<11>")
	)
	(segment
		(start 348.634304 -228.603302)
		(end 348.636336 -228.602032)
		(width 0.1143)
		(layer "In15.Cu")
		(net "GMI_CPU0_G1_CPU1_G3_TX_DN<11>")
	)
	(segment
		(start 122.90679 -237.65891)
		(end 122.867674 -237.68177)
		(width 0.1143)
		(layer "In15.Cu")
		(net "GMI_CPU0_G1_CPU1_G3_TX_DN<11>")
	)
	(segment
		(start 122.90679 -242.518946)
		(end 122.867674 -242.541806)
		(width 0.1143)
		(layer "In15.Cu")
		(net "GMI_CPU0_G1_CPU1_G3_TX_DN<11>")
	)
	(segment
		(start 348.6277 -238.32693)
		(end 348.627954 -238.326676)
		(width 0.1143)
		(layer "In15.Cu")
		(net "GMI_CPU0_G1_CPU1_G3_TX_DN<11>")
	)
	(segment
		(start 348.629986 -233.46537)
		(end 348.659704 -233.448352)
		(width 0.1143)
		(layer "In15.Cu")
		(net "GMI_CPU0_G1_CPU1_G3_TX_DN<11>")
	)
	(segment
		(start 152.07107 -195.29171)
		(end 151.581866 -195.692776)
		(width 0.14224)
		(layer "In15.Cu")
		(net "GMI_CPU0_G1_CPU1_G3_TX_DN<11>")
	)
	(segment
		(start 122.70613 -221.020386)
		(end 122.66041 -221.066106)
		(width 0.1143)
		(layer "In15.Cu")
		(net "GMI_CPU0_G1_CPU1_G3_TX_DN<11>")
	)
	(segment
		(start 122.867674 -227.961952)
		(end 122.837194 -227.979732)
		(width 0.1143)
		(layer "In15.Cu")
		(net "GMI_CPU0_G1_CPU1_G3_TX_DN<11>")
	)
	(segment
		(start 147.273772 -199.224646)
		(end 145.36039 -199.804274)
		(width 0.14224)
		(layer "In15.Cu")
		(net "GMI_CPU0_G1_CPU1_G3_TX_DN<11>")
	)
	(segment
		(start 302.604932 -185.41492)
		(end 302.604932 -185.413142)
		(width 0.14224)
		(layer "In15.Cu")
		(net "GMI_CPU0_G1_CPU1_G3_TX_DN<11>")
	)
	(segment
		(start 348.63405 -242.545108)
		(end 348.633288 -242.5446)
		(width 0.1143)
		(layer "In15.Cu")
		(net "GMI_CPU0_G1_CPU1_G3_TX_DN<11>")
	)
	(segment
		(start 156.727144 -191.63792)
		(end 156.412438 -191.89573)
		(width 0.14224)
		(layer "In15.Cu")
		(net "GMI_CPU0_G1_CPU1_G3_TX_DN<11>")
	)
	(segment
		(start 122.70613 -220.14688)
		(end 122.70613 -220.991938)
		(width 0.14224)
		(layer "In15.Cu")
		(net "GMI_CPU0_G1_CPU1_G3_TX_DN<11>")
	)
	(segment
		(start 348.649036 -236.694472)
		(end 348.649798 -236.693964)
		(width 0.1143)
		(layer "In15.Cu")
		(net "GMI_CPU0_G1_CPU1_G3_TX_DN<11>")
	)
	(segment
		(start 153.466546 -194.324732)
		(end 153.136346 -194.595496)
		(width 0.14224)
		(layer "In15.Cu")
		(net "GMI_CPU0_G1_CPU1_G3_TX_DN<11>")
	)
	(segment
		(start 122.867674 -243.186966)
		(end 122.90679 -243.209826)
		(width 0.1143)
		(layer "In15.Cu")
		(net "GMI_CPU0_G1_CPU1_G3_TX_DN<11>")
	)
	(segment
		(start 122.867674 -235.086906)
		(end 122.90679 -235.109766)
		(width 0.1143)
		(layer "In15.Cu")
		(net "GMI_CPU0_G1_CPU1_G3_TX_DN<11>")
	)
	(segment
		(start 348.591632 -233.487722)
		(end 348.627954 -233.46664)
		(width 0.1143)
		(layer "In15.Cu")
		(net "GMI_CPU0_G1_CPU1_G3_TX_DN<11>")
	)
	(segment
		(start 122.867674 -225.367088)
		(end 122.90679 -225.389948)
		(width 0.1143)
		(layer "In15.Cu")
		(net "GMI_CPU0_G1_CPU1_G3_TX_DN<11>")
	)
	(segment
		(start 122.837194 -230.20909)
		(end 122.90425 -230.248206)
		(width 0.1143)
		(layer "In15.Cu")
		(net "GMI_CPU0_G1_CPU1_G3_TX_DN<11>")
	)
	(segment
		(start 348.659704 -232.839768)
		(end 348.627954 -232.82148)
		(width 0.1143)
		(layer "In15.Cu")
		(net "GMI_CPU0_G1_CPU1_G3_TX_DN<11>")
	)
	(segment
		(start 122.90679 -236.038898)
		(end 122.867674 -236.061758)
		(width 0.1143)
		(layer "In15.Cu")
		(net "GMI_CPU0_G1_CPU1_G3_TX_DN<11>")
	)
	(segment
		(start 348.627954 -231.846628)
		(end 348.628716 -231.84612)
		(width 0.1143)
		(layer "In15.Cu")
		(net "GMI_CPU0_G1_CPU1_G3_TX_DN<11>")
	)
	(segment
		(start 347.718634 -223.119442)
		(end 347.688154 -223.101662)
		(width 0.1143)
		(layer "In15.Cu")
		(net "GMI_CPU0_G1_CPU1_G3_TX_DN<11>")
	)
	(segment
		(start 348.649036 -238.314484)
		(end 348.649798 -238.313976)
		(width 0.1143)
		(layer "In15.Cu")
		(net "GMI_CPU0_G1_CPU1_G3_TX_DN<11>")
	)
	(segment
		(start 167.337232 -184.625742)
		(end 163.330636 -186.058556)
		(width 0.14224)
		(layer "In15.Cu")
		(net "GMI_CPU0_G1_CPU1_G3_TX_DN<11>")
	)
	(segment
		(start 348.63151 -240.923572)
		(end 348.630494 -240.923064)
		(width 0.1143)
		(layer "In15.Cu")
		(net "GMI_CPU0_G1_CPU1_G3_TX_DN<11>")
	)
	(segment
		(start 348.636336 -228.602032)
		(end 348.637098 -228.601524)
		(width 0.1143)
		(layer "In15.Cu")
		(net "GMI_CPU0_G1_CPU1_G3_TX_DN<11>")
	)
	(segment
		(start 348.627954 -241.5667)
		(end 348.649036 -241.554508)
		(width 0.1143)
		(layer "In15.Cu")
		(net "GMI_CPU0_G1_CPU1_G3_TX_DN<11>")
	)
	(segment
		(start 348.627954 -228.606858)
		(end 348.628716 -228.60635)
		(width 0.1143)
		(layer "In15.Cu")
		(net "GMI_CPU0_G1_CPU1_G3_TX_DN<11>")
	)
	(segment
		(start 347.688154 -223.101662)
		(end 347.649038 -223.078802)
		(width 0.1143)
		(layer "In15.Cu")
		(net "GMI_CPU0_G1_CPU1_G3_TX_DN<11>")
	)
	(segment
		(start 348.659704 -244.179852)
		(end 348.628716 -244.162072)
		(width 0.1143)
		(layer "In15.Cu")
		(net "GMI_CPU0_G1_CPU1_G3_TX_DN<11>")
	)
	(segment
		(start 348.629732 -236.06252)
		(end 348.628716 -236.062012)
		(width 0.1143)
		(layer "In15.Cu")
		(net "GMI_CPU0_G1_CPU1_G3_TX_DN<11>")
	)
	(segment
		(start 348.631002 -228.60508)
		(end 348.632526 -228.604064)
		(width 0.1143)
		(layer "In15.Cu")
		(net "GMI_CPU0_G1_CPU1_G3_TX_DN<11>")
	)
	(segment
		(start 348.632272 -240.92408)
		(end 348.63151 -240.923572)
		(width 0.1143)
		(layer "In15.Cu")
		(net "GMI_CPU0_G1_CPU1_G3_TX_DN<11>")
	)
	(segment
		(start 124.659898 -216.777824)
		(end 122.70613 -220.14688)
		(width 0.14224)
		(layer "In15.Cu")
		(net "GMI_CPU0_G1_CPU1_G3_TX_DN<11>")
	)
	(segment
		(start 348.627954 -236.061504)
		(end 348.6277 -236.061504)
		(width 0.1143)
		(layer "In15.Cu")
		(net "GMI_CPU0_G1_CPU1_G3_TX_DN<11>")
	)
	(segment
		(start 154.357832 -193.416428)
		(end 154.338782 -193.609468)
		(width 0.14224)
		(layer "In15.Cu")
		(net "GMI_CPU0_G1_CPU1_G3_TX_DN<11>")
	)
	(segment
		(start 122.867674 -223.101916)
		(end 122.837194 -223.119696)
		(width 0.1143)
		(layer "In15.Cu")
		(net "GMI_CPU0_G1_CPU1_G3_TX_DN<11>")
	)
	(segment
		(start 152.59431 -195.039996)
		(end 152.26411 -195.31076)
		(width 0.14224)
		(layer "In15.Cu")
		(net "GMI_CPU0_G1_CPU1_G3_TX_DN<11>")
	)
	(segment
		(start 348.627954 -236.706664)
		(end 348.649036 -236.694472)
		(width 0.1143)
		(layer "In15.Cu")
		(net "GMI_CPU0_G1_CPU1_G3_TX_DN<11>")
	)
	(segment
		(start 348.591632 -243.207794)
		(end 348.627954 -243.186712)
		(width 0.1143)
		(layer "In15.Cu")
		(net "GMI_CPU0_G1_CPU1_G3_TX_DN<11>")
	)
	(segment
		(start 348.632272 -242.544092)
		(end 348.63151 -242.543584)
		(width 0.1143)
		(layer "In15.Cu")
		(net "GMI_CPU0_G1_CPU1_G3_TX_DN<11>")
	)
	(segment
		(start 122.70613 -220.991938)
		(end 122.70613 -221.020386)
		(width 0.1143)
		(layer "In15.Cu")
		(net "GMI_CPU0_G1_CPU1_G3_TX_DN<11>")
	)
	(segment
		(start 122.837194 -233.449114)
		(end 122.867674 -233.466894)
		(width 0.1143)
		(layer "In15.Cu")
		(net "GMI_CPU0_G1_CPU1_G3_TX_DN<11>")
	)
	(segment
		(start 348.632526 -228.604064)
		(end 348.633542 -228.60381)
		(width 0.1143)
		(layer "In15.Cu")
		(net "GMI_CPU0_G1_CPU1_G3_TX_DN<11>")
	)
	(segment
		(start 348.738952 -244.484144)
		(end 348.808802 -244.414294)
		(width 0.1143)
		(layer "In15.Cu")
		(net "GMI_CPU0_G1_CPU1_G3_TX_DN<11>")
	)
	(segment
		(start 155.211018 -192.894204)
		(end 154.880818 -193.164968)
		(width 0.14224)
		(layer "In15.Cu")
		(net "GMI_CPU0_G1_CPU1_G3_TX_DN<11>")
	)
	(segment
		(start 158.394908 -190.106046)
		(end 158.377128 -190.284608)
		(width 0.14224)
		(layer "In15.Cu")
		(net "GMI_CPU0_G1_CPU1_G3_TX_DN<11>")
	)
	(segment
		(start 122.867674 -236.061758)
		(end 122.837194 -236.079538)
		(width 0.1143)
		(layer "In15.Cu")
		(net "GMI_CPU0_G1_CPU1_G3_TX_DN<11>")
	)
	(segment
		(start 348.593156 -226.32162)
		(end 348.591632 -226.320604)
		(width 0.1143)
		(layer "In15.Cu")
		(net "GMI_CPU0_G1_CPU1_G3_TX_DN<11>")
	)
	(segment
		(start 346.935806 -221.80423)
		(end 346.935806 -221.433136)
		(width 0.1143)
		(layer "In15.Cu")
		(net "GMI_CPU0_G1_CPU1_G3_TX_DN<11>")
	)
	(segment
		(start 122.90679 -239.278922)
		(end 122.867674 -239.301782)
		(width 0.1143)
		(layer "In15.Cu")
		(net "GMI_CPU0_G1_CPU1_G3_TX_DN<11>")
	)
	(segment
		(start 122.867674 -238.32693)
		(end 122.90679 -238.34979)
		(width 0.1143)
		(layer "In15.Cu")
		(net "GMI_CPU0_G1_CPU1_G3_TX_DN<11>")
	)
	(segment
		(start 122.90679 -240.898934)
		(end 122.867674 -240.921794)
		(width 0.1143)
		(layer "In15.Cu")
		(net "GMI_CPU0_G1_CPU1_G3_TX_DN<11>")
	)
	(segment
		(start 122.867674 -236.706918)
		(end 122.90679 -236.729778)
		(width 0.1143)
		(layer "In15.Cu")
		(net "GMI_CPU0_G1_CPU1_G3_TX_DN<11>")
	)
	(segment
		(start 122.867674 -231.846882)
		(end 122.90679 -231.869742)
		(width 0.1143)
		(layer "In15.Cu")
		(net "GMI_CPU0_G1_CPU1_G3_TX_DN<11>")
	)
	(segment
		(start 122.867674 -226.9871)
		(end 122.90679 -227.00996)
		(width 0.1143)
		(layer "In15.Cu")
		(net "GMI_CPU0_G1_CPU1_G3_TX_DN<11>")
	)
	(segment
		(start 348.659704 -242.55984)
		(end 348.63532 -242.54587)
		(width 0.1143)
		(layer "In15.Cu")
		(net "GMI_CPU0_G1_CPU1_G3_TX_DN<11>")
	)
	(segment
		(start 348.650052 -228.594158)
		(end 348.65945 -228.588316)
		(width 0.1143)
		(layer "In15.Cu")
		(net "GMI_CPU0_G1_CPU1_G3_TX_DN<11>")
	)
	(segment
		(start 348.63532 -242.54587)
		(end 348.63405 -242.545108)
		(width 0.1143)
		(layer "In15.Cu")
		(net "GMI_CPU0_G1_CPU1_G3_TX_DN<11>")
	)
	(segment
		(start 348.627954 -243.186712)
		(end 348.628716 -243.186204)
		(width 0.1143)
		(layer "In15.Cu")
		(net "GMI_CPU0_G1_CPU1_G3_TX_DN<11>")
	)
	(segment
		(start 122.90679 -227.939092)
		(end 122.867674 -227.961952)
		(width 0.1143)
		(layer "In15.Cu")
		(net "GMI_CPU0_G1_CPU1_G3_TX_DN<11>")
	)
	(segment
		(start 348.629732 -240.922556)
		(end 348.628716 -240.922048)
		(width 0.1143)
		(layer "In15.Cu")
		(net "GMI_CPU0_G1_CPU1_G3_TX_DN<11>")
	)
	(segment
		(start 348.63405 -240.925096)
		(end 348.633288 -240.924588)
		(width 0.1143)
		(layer "In15.Cu")
		(net "GMI_CPU0_G1_CPU1_G3_TX_DN<11>")
	)
	(segment
		(start 348.627954 -244.161564)
		(end 348.591632 -244.140482)
		(width 0.1143)
		(layer "In15.Cu")
		(net "GMI_CPU0_G1_CPU1_G3_TX_DN<11>")
	)
	(segment
		(start 122.90679 -244.138958)
		(end 122.867674 -244.161818)
		(width 0.1143)
		(layer "In15.Cu")
		(net "GMI_CPU0_G1_CPU1_G3_TX_DN<11>")
	)
	(segment
		(start 163.330636 -186.058556)
		(end 158.394908 -190.106046)
		(width 0.14224)
		(layer "In15.Cu")
		(net "GMI_CPU0_G1_CPU1_G3_TX_DN<11>")
	)
	(segment
		(start 151.581866 -195.692776)
		(end 151.564086 -195.871592)
		(width 0.14224)
		(layer "In15.Cu")
		(net "GMI_CPU0_G1_CPU1_G3_TX_DN<11>")
	)
	(segment
		(start 122.837194 -225.349308)
		(end 122.867674 -225.367088)
		(width 0.1143)
		(layer "In15.Cu")
		(net "GMI_CPU0_G1_CPU1_G3_TX_DN<11>")
	)
	(segment
		(start 122.679714 -221.218252)
		(end 122.679714 -221.804484)
		(width 0.1143)
		(layer "In15.Cu")
		(net "GMI_CPU0_G1_CPU1_G3_TX_DN<11>")
	)
	(segment
		(start 348.625414 -230.22814)
		(end 348.626938 -230.227124)
		(width 0.1143)
		(layer "In15.Cu")
		(net "GMI_CPU0_G1_CPU1_G3_TX_DN<11>")
	)
	(segment
		(start 347.216984 -222.291148)
		(end 347.21546 -222.290132)
		(width 0.1143)
		(layer "In15.Cu")
		(net "GMI_CPU0_G1_CPU1_G3_TX_DN<11>")
	)
	(segment
		(start 348.63151 -237.683548)
		(end 348.630494 -237.68304)
		(width 0.1143)
		(layer "In15.Cu")
		(net "GMI_CPU0_G1_CPU1_G3_TX_DN<11>")
	)
	(segment
		(start 348.627954 -239.301528)
		(end 348.6277 -239.301528)
		(width 0.1143)
		(layer "In15.Cu")
		(net "GMI_CPU0_G1_CPU1_G3_TX_DN<11>")
	)
	(segment
		(start 348.626938 -230.227124)
		(end 348.627954 -230.226616)
		(width 0.1143)
		(layer "In15.Cu")
		(net "GMI_CPU0_G1_CPU1_G3_TX_DN<11>")
	)
	(segment
		(start 122.837194 -231.829102)
		(end 122.867674 -231.846882)
		(width 0.1143)
		(layer "In15.Cu")
		(net "GMI_CPU0_G1_CPU1_G3_TX_DN<11>")
	)
	(segment
		(start 348.624398 -230.228648)
		(end 348.625414 -230.22814)
		(width 0.1143)
		(layer "In15.Cu")
		(net "GMI_CPU0_G1_CPU1_G3_TX_DN<11>")
	)
	(segment
		(start 122.837194 -223.729296)
		(end 122.867674 -223.747076)
		(width 0.1143)
		(layer "In15.Cu")
		(net "GMI_CPU0_G1_CPU1_G3_TX_DN<11>")
	)
	(segment
		(start 347.688154 -224.721674)
		(end 347.649038 -224.698814)
		(width 0.1143)
		(layer "In15.Cu")
		(net "GMI_CPU0_G1_CPU1_G3_TX_DN<11>")
	)
	(segment
		(start 347.218 -222.291656)
		(end 347.216984 -222.291148)
		(width 0.1143)
		(layer "In15.Cu")
		(net "GMI_CPU0_G1_CPU1_G3_TX_DN<11>")
	)
	(segment
		(start 157.569662 -190.782448)
		(end 157.552136 -190.961264)
		(width 0.14224)
		(layer "In15.Cu")
		(net "GMI_CPU0_G1_CPU1_G3_TX_DN<11>")
	)
	(segment
		(start 122.90679 -223.079056)
		(end 122.867674 -223.101916)
		(width 0.1143)
		(layer "In15.Cu")
		(net "GMI_CPU0_G1_CPU1_G3_TX_DN<11>")
	)
	(segment
		(start 122.867674 -228.607112)
		(end 122.90679 -228.629972)
		(width 0.1143)
		(layer "In15.Cu")
		(net "GMI_CPU0_G1_CPU1_G3_TX_DN<11>")
	)
	(segment
		(start 346.935806 -221.433136)
		(end 346.89034 -221.38767)
		(width 0.1143)
		(layer "In15.Cu")
		(net "GMI_CPU0_G1_CPU1_G3_TX_DN<11>")
	)
	(segment
		(start 122.86742 -222.127064)
		(end 122.907806 -222.150686)
		(width 0.1143)
		(layer "In15.Cu")
		(net "GMI_CPU0_G1_CPU1_G3_TX_DN<11>")
	)
	(segment
		(start 348.637098 -228.601524)
		(end 348.650052 -228.594158)
		(width 0.1143)
		(layer "In15.Cu")
		(net "GMI_CPU0_G1_CPU1_G3_TX_DN<11>")
	)
	(segment
		(start 347.649038 -223.769682)
		(end 347.688154 -223.746822)
		(width 0.1143)
		(layer "In15.Cu")
		(net "GMI_CPU0_G1_CPU1_G3_TX_DN<11>")
	)
	(segment
		(start 348.649798 -239.933988)
		(end 348.659704 -239.9284)
		(width 0.1143)
		(layer "In15.Cu")
		(net "GMI_CPU0_G1_CPU1_G3_TX_DN<11>")
	)
	(segment
		(start 122.90679 -229.559104)
		(end 122.867674 -229.581964)
		(width 0.1143)
		(layer "In15.Cu")
		(net "GMI_CPU0_G1_CPU1_G3_TX_DN<11>")
	)
	(segment
		(start 122.867674 -233.466894)
		(end 122.90679 -233.489754)
		(width 0.1143)
		(layer "In15.Cu")
		(net "GMI_CPU0_G1_CPU1_G3_TX_DN<11>")
	)
	(segment
		(start 348.157038 -225.531172)
		(end 348.118938 -225.50882)
		(width 0.1143)
		(layer "In15.Cu")
		(net "GMI_CPU0_G1_CPU1_G3_TX_DN<11>")
	)
	(segment
		(start 122.90679 -231.179116)
		(end 122.867674 -231.201976)
		(width 0.1143)
		(layer "In15.Cu")
		(net "GMI_CPU0_G1_CPU1_G3_TX_DN<11>")
	)
	(segment
		(start 122.837194 -243.169186)
		(end 122.867674 -243.186966)
		(width 0.1143)
		(layer "In15.Cu")
		(net "GMI_CPU0_G1_CPU1_G3_TX_DN<11>")
	)
	(segment
		(start 149.193758 -197.6501)
		(end 147.273772 -199.224646)
		(width 0.14224)
		(layer "In15.Cu")
		(net "GMI_CPU0_G1_CPU1_G3_TX_DN<11>")
	)
	(segment
		(start 151.564086 -195.871592)
		(end 151.249634 -196.129402)
		(width 0.14224)
		(layer "In15.Cu")
		(net "GMI_CPU0_G1_CPU1_G3_TX_DN<11>")
	)
	(segment
		(start 122.837194 -228.589332)
		(end 122.867674 -228.607112)
		(width 0.1143)
		(layer "In15.Cu")
		(net "GMI_CPU0_G1_CPU1_G3_TX_DN<11>")
	)
	(segment
		(start 348.634304 -236.065314)
		(end 348.632272 -236.064044)
		(width 0.1143)
		(layer "In15.Cu")
		(net "GMI_CPU0_G1_CPU1_G3_TX_DN<11>")
	)
	(segment
		(start 152.61336 -194.846956)
		(end 152.59431 -195.039996)
		(width 0.14224)
		(layer "In15.Cu")
		(net "GMI_CPU0_G1_CPU1_G3_TX_DN<11>")
	)
	(segment
		(start 348.627954 -235.086652)
		(end 348.649036 -235.07446)
		(width 0.1143)
		(layer "In15.Cu")
		(net "GMI_CPU0_G1_CPU1_G3_TX_DN<11>")
	)
	(segment
		(start 348.18193 -225.545396)
		(end 348.161356 -225.533458)
		(width 0.1143)
		(layer "In15.Cu")
		(net "GMI_CPU0_G1_CPU1_G3_TX_DN<11>")
	)
	(segment
		(start 348.629986 -243.185442)
		(end 348.659704 -243.168424)
		(width 0.1143)
		(layer "In15.Cu")
		(net "GMI_CPU0_G1_CPU1_G3_TX_DN<11>")
	)
	(segment
		(start 307.261006 -185.782966)
		(end 306.370736 -185.41492)
		(width 0.14224)
		(layer "In15.Cu")
		(net "GMI_CPU0_G1_CPU1_G3_TX_DN<11>")
	)
	(segment
		(start 348.627954 -227.961698)
		(end 348.591632 -227.940616)
		(width 0.1143)
		(layer "In15.Cu")
		(net "GMI_CPU0_G1_CPU1_G3_TX_DN<11>")
	)
	(segment
		(start 154.687778 -193.145918)
		(end 154.357832 -193.416428)
		(width 0.14224)
		(layer "In15.Cu")
		(net "GMI_CPU0_G1_CPU1_G3_TX_DN<11>")
	)
	(segment
		(start 158.377128 -190.284608)
		(end 158.062676 -190.542672)
		(width 0.14224)
		(layer "In15.Cu")
		(net "GMI_CPU0_G1_CPU1_G3_TX_DN<11>")
	)
	(segment
		(start 153.815542 -193.861182)
		(end 153.485596 -194.131692)
		(width 0.14224)
		(layer "In15.Cu")
		(net "GMI_CPU0_G1_CPU1_G3_TX_DN<11>")
	)
	(segment
		(start 348.63532 -239.305846)
		(end 348.63405 -239.305084)
		(width 0.1143)
		(layer "In15.Cu")
		(net "GMI_CPU0_G1_CPU1_G3_TX_DN<11>")
	)
	(segment
		(start 348.629732 -242.542568)
		(end 348.628716 -242.54206)
		(width 0.1143)
		(layer "In15.Cu")
		(net "GMI_CPU0_G1_CPU1_G3_TX_DN<11>")
	)
	(segment
		(start 348.185232 -225.547428)
		(end 348.184216 -225.54692)
		(width 0.1143)
		(layer "In15.Cu")
		(net "GMI_CPU0_G1_CPU1_G3_TX_DN<11>")
	)
	(segment
		(start 122.867674 -232.821734)
		(end 122.837194 -232.839514)
		(width 0.1143)
		(layer "In15.Cu")
		(net "GMI_CPU0_G1_CPU1_G3_TX_DN<11>")
	)
	(segment
		(start 122.867674 -237.68177)
		(end 122.837194 -237.69955)
		(width 0.1143)
		(layer "In15.Cu")
		(net "GMI_CPU0_G1_CPU1_G3_TX_DN<11>")
	)
	(segment
		(start 122.90679 -224.699068)
		(end 122.867674 -224.721928)
		(width 0.1143)
		(layer "In15.Cu")
		(net "GMI_CPU0_G1_CPU1_G3_TX_DN<11>")
	)
	(segment
		(start 348.629732 -239.302544)
		(end 348.628716 -239.302036)
		(width 0.1143)
		(layer "In15.Cu")
		(net "GMI_CPU0_G1_CPU1_G3_TX_DN<11>")
	)
	(segment
		(start 346.84462 -219.846652)
		(end 344.567764 -215.035638)
		(width 0.14224)
		(layer "In15.Cu")
		(net "GMI_CPU0_G1_CPU1_G3_TX_DN<11>")
	)
	(segment
		(start 158.062676 -190.542672)
		(end 157.88386 -190.524892)
		(width 0.14224)
		(layer "In15.Cu")
		(net "GMI_CPU0_G1_CPU1_G3_TX_DN<11>")
	)
	(segment
		(start 348.628716 -236.062012)
		(end 348.627954 -236.061504)
		(width 0.1143)
		(layer "In15.Cu")
		(net "GMI_CPU0_G1_CPU1_G3_TX_DN<11>")
	)
	(segment
		(start 348.628716 -237.682024)
		(end 348.627954 -237.681516)
		(width 0.1143)
		(layer "In15.Cu")
		(net "GMI_CPU0_G1_CPU1_G3_TX_DN<11>")
	)
	(segment
		(start 348.63151 -239.30356)
		(end 348.630494 -239.303052)
		(width 0.1143)
		(layer "In15.Cu")
		(net "GMI_CPU0_G1_CPU1_G3_TX_DN<11>")
	)
	(segment
		(start 348.649798 -235.073952)
		(end 348.659704 -235.068364)
		(width 0.1143)
		(layer "In15.Cu")
		(net "GMI_CPU0_G1_CPU1_G3_TX_DN<11>")
	)
	(segment
		(start 149.194012 -197.6501)
		(end 149.193758 -197.6501)
		(width 0.14224)
		(layer "In15.Cu")
		(net "GMI_CPU0_G1_CPU1_G3_TX_DN<11>")
	)
	(segment
		(start 122.66041 -221.198948)
		(end 122.679714 -221.218252)
		(width 0.1143)
		(layer "In15.Cu")
		(net "GMI_CPU0_G1_CPU1_G3_TX_DN<11>")
	)
	(segment
		(start 348.661482 -229.601268)
		(end 348.66072 -229.60076)
		(width 0.1143)
		(layer "In15.Cu")
		(net "GMI_CPU0_G1_CPU1_G3_TX_DN<11>")
	)
	(segment
		(start 348.63532 -237.685834)
		(end 348.63405 -237.685072)
		(width 0.1143)
		(layer "In15.Cu")
		(net "GMI_CPU0_G1_CPU1_G3_TX_DN<11>")
	)
	(segment
		(start 348.34576 -225.870516)
		(end 348.34576 -225.870262)
		(width 0.1143)
		(layer "In15.Cu")
		(net "GMI_CPU0_G1_CPU1_G3_TX_DN<11>")
	)
	(segment
		(start 157.88386 -190.524892)
		(end 157.569662 -190.782448)
		(width 0.14224)
		(layer "In15.Cu")
		(net "GMI_CPU0_G1_CPU1_G3_TX_DN<11>")
	)
	(segment
		(start 348.649798 -238.313976)
		(end 348.659704 -238.308388)
		(width 0.1143)
		(layer "In15.Cu")
		(net "GMI_CPU0_G1_CPU1_G3_TX_DN<11>")
	)
	(segment
		(start 156.412438 -191.89573)
		(end 156.233876 -191.878204)
		(width 0.14224)
		(layer "In15.Cu")
		(net "GMI_CPU0_G1_CPU1_G3_TX_DN<11>")
	)
	(segment
		(start 348.627954 -242.541552)
		(end 348.6277 -242.541552)
		(width 0.1143)
		(layer "In15.Cu")
		(net "GMI_CPU0_G1_CPU1_G3_TX_DN<11>")
	)
	(segment
		(start 348.627954 -239.946688)
		(end 348.649036 -239.934496)
		(width 0.1143)
		(layer "In15.Cu")
		(net "GMI_CPU0_G1_CPU1_G3_TX_DN<11>")
	)
	(segment
		(start 348.630494 -240.923064)
		(end 348.629732 -240.922556)
		(width 0.1143)
		(layer "In15.Cu")
		(net "GMI_CPU0_G1_CPU1_G3_TX_DN<11>")
	)
	(segment
		(start 348.633542 -228.60381)
		(end 348.634304 -228.603302)
		(width 0.1143)
		(layer "In15.Cu")
		(net "GMI_CPU0_G1_CPU1_G3_TX_DN<11>")
	)
	(segment
		(start 348.184216 -225.54692)
		(end 348.18193 -225.545396)
		(width 0.1143)
		(layer "In15.Cu")
		(net "GMI_CPU0_G1_CPU1_G3_TX_DN<11>")
	)
	(segment
		(start 347.209618 -222.28683)
		(end 347.178884 -222.268796)
		(width 0.1143)
		(layer "In15.Cu")
		(net "GMI_CPU0_G1_CPU1_G3_TX_DN<11>")
	)
	(segment
		(start 153.485596 -194.131692)
		(end 153.466546 -194.324732)
		(width 0.14224)
		(layer "In15.Cu")
		(net "GMI_CPU0_G1_CPU1_G3_TX_DN<11>")
	)
	(segment
		(start 348.631764 -230.22433)
		(end 348.659704 -230.208328)
		(width 0.1143)
		(layer "In15.Cu")
		(net "GMI_CPU0_G1_CPU1_G3_TX_DN<11>")
	)
	(segment
		(start 348.63405 -237.685072)
		(end 348.633288 -237.684564)
		(width 0.1143)
		(layer "In15.Cu")
		(net "GMI_CPU0_G1_CPU1_G3_TX_DN<11>")
	)
	(segment
		(start 348.6277 -235.086906)
		(end 348.627954 -235.086652)
		(width 0.1143)
		(layer "In15.Cu")
		(net "GMI_CPU0_G1_CPU1_G3_TX_DN<11>")
	)
	(segment
		(start 348.63532 -240.925858)
		(end 348.63405 -240.925096)
		(width 0.1143)
		(layer "In15.Cu")
		(net "GMI_CPU0_G1_CPU1_G3_TX_DN<11>")
	)
	(segment
		(start 122.867674 -229.581964)
		(end 122.835162 -229.60076)
		(width 0.1143)
		(layer "In15.Cu")
		(net "GMI_CPU0_G1_CPU1_G3_TX_DN<11>")
	)
	(segment
		(start 122.90679 -226.31908)
		(end 122.867674 -226.34194)
		(width 0.1143)
		(layer "In15.Cu")
		(net "GMI_CPU0_G1_CPU1_G3_TX_DN<11>")
	)
	(segment
		(start 152.943306 -194.576446)
		(end 152.61336 -194.846956)
		(width 0.14224)
		(layer "In15.Cu")
		(net "GMI_CPU0_G1_CPU1_G3_TX_DN<11>")
	)
	(segment
		(start 122.837194 -241.549174)
		(end 122.867674 -241.566954)
		(width 0.1143)
		(layer "In15.Cu")
		(net "GMI_CPU0_G1_CPU1_G3_TX_DN<11>")
	)
	(arc
		(start 122.837194 -237.69955)
		(mid 122.680217 -238.00435)
		(end 122.837194 -238.30915)
		(width 0.1143)
		(layer "In15.Cu")
		(net "GMI_CPU0_G1_CPU1_G3_TX_DN<11>")
	)
	(arc
		(start 348.6277 -236.061504)
		(mid 348.347273 -235.574268)
		(end 348.6277 -235.086906)
		(width 0.1143)
		(layer "In15.Cu")
		(net "GMI_CPU0_G1_CPU1_G3_TX_DN<11>")
	)
	(arc
		(start 122.90679 -223.769936)
		(mid 123.150117 -224.234502)
		(end 122.90679 -224.699068)
		(width 0.1143)
		(layer "In15.Cu")
		(net "GMI_CPU0_G1_CPU1_G3_TX_DN<11>")
	)
	(arc
		(start 122.837194 -239.319562)
		(mid 122.680217 -239.624362)
		(end 122.837194 -239.929162)
		(width 0.1143)
		(layer "In15.Cu")
		(net "GMI_CPU0_G1_CPU1_G3_TX_DN<11>")
	)
	(arc
		(start 122.907806 -222.150686)
		(mid 123.085871 -222.352863)
		(end 123.150122 -222.61449)
		(width 0.1143)
		(layer "In15.Cu")
		(net "GMI_CPU0_G1_CPU1_G3_TX_DN<11>")
	)
	(arc
		(start 348.575376 -227.019358)
		(mid 348.583454 -227.013572)
		(end 348.591632 -227.007928)
		(width 0.1143)
		(layer "In15.Cu")
		(net "GMI_CPU0_G1_CPU1_G3_TX_DN<11>")
	)
	(arc
		(start 348.575376 -232.788968)
		(mid 348.352492 -232.334054)
		(end 348.575376 -231.87914)
		(width 0.1143)
		(layer "In15.Cu")
		(net "GMI_CPU0_G1_CPU1_G3_TX_DN<11>")
	)
	(arc
		(start 348.577662 -230.257604)
		(mid 348.585992 -230.251813)
		(end 348.594426 -230.246174)
		(width 0.1143)
		(layer "In15.Cu")
		(net "GMI_CPU0_G1_CPU1_G3_TX_DN<11>")
	)
	(arc
		(start 348.57817 -229.550976)
		(mid 348.4072 -229.350499)
		(end 348.34576 -229.094284)
		(width 0.1143)
		(layer "In15.Cu")
		(net "GMI_CPU0_G1_CPU1_G3_TX_DN<11>")
	)
	(arc
		(start 348.591632 -226.320604)
		(mid 348.414732 -226.125041)
		(end 348.34576 -225.870516)
		(width 0.1143)
		(layer "In15.Cu")
		(net "GMI_CPU0_G1_CPU1_G3_TX_DN<11>")
	)
	(arc
		(start 347.875606 -225.044254)
		(mid 347.834057 -224.872832)
		(end 347.718634 -224.739454)
		(width 0.1143)
		(layer "In15.Cu")
		(net "GMI_CPU0_G1_CPU1_G3_TX_DN<11>")
	)
	(arc
		(start 348.194376 -225.55454)
		(mid 348.189832 -225.550949)
		(end 348.185232 -225.547428)
		(width 0.1143)
		(layer "In15.Cu")
		(net "GMI_CPU0_G1_CPU1_G3_TX_DN<11>")
	)
	(arc
		(start 122.835162 -231.220772)
		(mid 122.721233 -231.353919)
		(end 122.680222 -231.524302)
		(width 0.1143)
		(layer "In15.Cu")
		(net "GMI_CPU0_G1_CPU1_G3_TX_DN<11>")
	)
	(arc
		(start 122.679714 -221.804484)
		(mid 122.720969 -221.975455)
		(end 122.83567 -222.108776)
		(width 0.1143)
		(layer "In15.Cu")
		(net "GMI_CPU0_G1_CPU1_G3_TX_DN<11>")
	)
	(arc
		(start 348.118938 -225.50882)
		(mid 347.940125 -225.30647)
		(end 347.875606 -225.044254)
		(width 0.1143)
		(layer "In15.Cu")
		(net "GMI_CPU0_G1_CPU1_G3_TX_DN<11>")
	)
	(arc
		(start 122.90679 -239.969802)
		(mid 123.150117 -240.434368)
		(end 122.90679 -240.898934)
		(width 0.1143)
		(layer "In15.Cu")
		(net "GMI_CPU0_G1_CPU1_G3_TX_DN<11>")
	)
	(arc
		(start 122.90425 -230.248206)
		(mid 123.084902 -230.450951)
		(end 123.150122 -230.71455)
		(width 0.1143)
		(layer "In15.Cu")
		(net "GMI_CPU0_G1_CPU1_G3_TX_DN<11>")
	)
	(arc
		(start 122.680222 -231.524302)
		(mid 122.721771 -231.695724)
		(end 122.837194 -231.829102)
		(width 0.1143)
		(layer "In15.Cu")
		(net "GMI_CPU0_G1_CPU1_G3_TX_DN<11>")
	)
	(arc
		(start 122.837194 -227.979732)
		(mid 122.680217 -228.284532)
		(end 122.837194 -228.589332)
		(width 0.1143)
		(layer "In15.Cu")
		(net "GMI_CPU0_G1_CPU1_G3_TX_DN<11>")
	)
	(arc
		(start 122.90679 -231.869742)
		(mid 123.150117 -232.334308)
		(end 122.90679 -232.798874)
		(width 0.1143)
		(layer "In15.Cu")
		(net "GMI_CPU0_G1_CPU1_G3_TX_DN<11>")
	)
	(arc
		(start 348.659704 -226.968558)
		(mid 348.815632 -226.664266)
		(end 348.659704 -226.359974)
		(width 0.1143)
		(layer "In15.Cu")
		(net "GMI_CPU0_G1_CPU1_G3_TX_DN<11>")
	)
	(arc
		(start 348.591632 -229.560628)
		(mid 348.584866 -229.555851)
		(end 348.57817 -229.550976)
		(width 0.1143)
		(layer "In15.Cu")
		(net "GMI_CPU0_G1_CPU1_G3_TX_DN<11>")
	)
	(arc
		(start 348.808802 -244.414294)
		(mid 348.756753 -244.282775)
		(end 348.659704 -244.179852)
		(width 0.1143)
		(layer "In15.Cu")
		(net "GMI_CPU0_G1_CPU1_G3_TX_DN<11>")
	)
	(arc
		(start 122.90679 -233.489754)
		(mid 123.150117 -233.95432)
		(end 122.90679 -234.418886)
		(width 0.1143)
		(layer "In15.Cu")
		(net "GMI_CPU0_G1_CPU1_G3_TX_DN<11>")
	)
	(arc
		(start 122.90679 -236.729778)
		(mid 123.150117 -237.194344)
		(end 122.90679 -237.65891)
		(width 0.1143)
		(layer "In15.Cu")
		(net "GMI_CPU0_G1_CPU1_G3_TX_DN<11>")
	)
	(arc
		(start 348.591632 -234.42041)
		(mid 348.584482 -234.415512)
		(end 348.577408 -234.410504)
		(width 0.1143)
		(layer "In15.Cu")
		(net "GMI_CPU0_G1_CPU1_G3_TX_DN<11>")
	)
	(arc
		(start 122.90679 -243.209826)
		(mid 123.150117 -243.674392)
		(end 122.90679 -244.138958)
		(width 0.1143)
		(layer "In15.Cu")
		(net "GMI_CPU0_G1_CPU1_G3_TX_DN<11>")
	)
	(arc
		(start 348.575376 -231.87914)
		(mid 348.583454 -231.873354)
		(end 348.591632 -231.86771)
		(width 0.1143)
		(layer "In15.Cu")
		(net "GMI_CPU0_G1_CPU1_G3_TX_DN<11>")
	)
	(arc
		(start 348.34576 -229.094284)
		(mid 348.421341 -228.812642)
		(end 348.627954 -228.606858)
		(width 0.1143)
		(layer "In15.Cu")
		(net "GMI_CPU0_G1_CPU1_G3_TX_DN<11>")
	)
	(arc
		(start 122.837194 -224.739708)
		(mid 122.680217 -225.044508)
		(end 122.837194 -225.349308)
		(width 0.1143)
		(layer "In15.Cu")
		(net "GMI_CPU0_G1_CPU1_G3_TX_DN<11>")
	)
	(arc
		(start 347.405706 -222.614236)
		(mid 347.364451 -222.443265)
		(end 347.24975 -222.309944)
		(width 0.1143)
		(layer "In15.Cu")
		(net "GMI_CPU0_G1_CPU1_G3_TX_DN<11>")
	)
	(arc
		(start 348.659704 -231.82834)
		(mid 348.77438 -231.695006)
		(end 348.81566 -231.524048)
		(width 0.1143)
		(layer "In15.Cu")
		(net "GMI_CPU0_G1_CPU1_G3_TX_DN<11>")
	)
	(arc
		(start 348.591632 -227.940616)
		(mid 348.583454 -227.934973)
		(end 348.575376 -227.929186)
		(width 0.1143)
		(layer "In15.Cu")
		(net "GMI_CPU0_G1_CPU1_G3_TX_DN<11>")
	)
	(arc
		(start 122.837194 -240.939574)
		(mid 122.680217 -241.244374)
		(end 122.837194 -241.549174)
		(width 0.1143)
		(layer "In15.Cu")
		(net "GMI_CPU0_G1_CPU1_G3_TX_DN<11>")
	)
	(arc
		(start 348.34576 -225.870262)
		(mid 348.344385 -225.848449)
		(end 348.341188 -225.826828)
		(width 0.1143)
		(layer "In15.Cu")
		(net "GMI_CPU0_G1_CPU1_G3_TX_DN<11>")
	)
	(arc
		(start 348.591632 -244.140482)
		(mid 348.583454 -244.134839)
		(end 348.575376 -244.129052)
		(width 0.1143)
		(layer "In15.Cu")
		(net "GMI_CPU0_G1_CPU1_G3_TX_DN<11>")
	)
	(arc
		(start 348.34576 -230.710486)
		(mid 348.409517 -230.457323)
		(end 348.577662 -230.257604)
		(width 0.1143)
		(layer "In15.Cu")
		(net "GMI_CPU0_G1_CPU1_G3_TX_DN<11>")
	)
	(arc
		(start 347.045026 -222.138748)
		(mid 346.963735 -221.980201)
		(end 346.935806 -221.80423)
		(width 0.1143)
		(layer "In15.Cu")
		(net "GMI_CPU0_G1_CPU1_G3_TX_DN<11>")
	)
	(arc
		(start 122.837194 -236.079538)
		(mid 122.680217 -236.384338)
		(end 122.837194 -236.689138)
		(width 0.1143)
		(layer "In15.Cu")
		(net "GMI_CPU0_G1_CPU1_G3_TX_DN<11>")
	)
	(arc
		(start 348.617794 -231.195372)
		(mid 348.41573 -230.989975)
		(end 348.34576 -230.710486)
		(width 0.1143)
		(layer "In15.Cu")
		(net "GMI_CPU0_G1_CPU1_G3_TX_DN<11>")
	)
	(arc
		(start 122.680222 -229.90429)
		(mid 122.721771 -230.075712)
		(end 122.837194 -230.20909)
		(width 0.1143)
		(layer "In15.Cu")
		(net "GMI_CPU0_G1_CPU1_G3_TX_DN<11>")
	)
	(arc
		(start 122.837194 -223.119696)
		(mid 122.680217 -223.424496)
		(end 122.837194 -223.729296)
		(width 0.1143)
		(layer "In15.Cu")
		(net "GMI_CPU0_G1_CPU1_G3_TX_DN<11>")
	)
	(arc
		(start 122.90679 -238.34979)
		(mid 123.150117 -238.814356)
		(end 122.90679 -239.278922)
		(width 0.1143)
		(layer "In15.Cu")
		(net "GMI_CPU0_G1_CPU1_G3_TX_DN<11>")
	)
	(arc
		(start 122.90679 -228.629972)
		(mid 123.150117 -229.094538)
		(end 122.90679 -229.559104)
		(width 0.1143)
		(layer "In15.Cu")
		(net "GMI_CPU0_G1_CPU1_G3_TX_DN<11>")
	)
	(arc
		(start 122.837194 -242.559586)
		(mid 122.680217 -242.864386)
		(end 122.837194 -243.169186)
		(width 0.1143)
		(layer "In15.Cu")
		(net "GMI_CPU0_G1_CPU1_G3_TX_DN<11>")
	)
	(arc
		(start 348.659704 -233.448352)
		(mid 348.815632 -233.14406)
		(end 348.659704 -232.839768)
		(width 0.1143)
		(layer "In15.Cu")
		(net "GMI_CPU0_G1_CPU1_G3_TX_DN<11>")
	)
	(arc
		(start 123.150122 -222.61449)
		(mid 123.085607 -222.876709)
		(end 122.90679 -223.079056)
		(width 0.1143)
		(layer "In15.Cu")
		(net "GMI_CPU0_G1_CPU1_G3_TX_DN<11>")
	)
	(arc
		(start 347.178884 -222.268796)
		(mid 347.106557 -222.209329)
		(end 347.045026 -222.138748)
		(width 0.1143)
		(layer "In15.Cu")
		(net "GMI_CPU0_G1_CPU1_G3_TX_DN<11>")
	)
	(arc
		(start 122.90679 -241.589814)
		(mid 123.150117 -242.05438)
		(end 122.90679 -242.518946)
		(width 0.1143)
		(layer "In15.Cu")
		(net "GMI_CPU0_G1_CPU1_G3_TX_DN<11>")
	)
	(arc
		(start 348.591632 -232.800398)
		(mid 348.583454 -232.794755)
		(end 348.575376 -232.788968)
		(width 0.1143)
		(layer "In15.Cu")
		(net "GMI_CPU0_G1_CPU1_G3_TX_DN<11>")
	)
	(arc
		(start 348.575376 -227.929186)
		(mid 348.352492 -227.474272)
		(end 348.575376 -227.019358)
		(width 0.1143)
		(layer "In15.Cu")
		(net "GMI_CPU0_G1_CPU1_G3_TX_DN<11>")
	)
	(arc
		(start 122.835162 -229.60076)
		(mid 122.721233 -229.733907)
		(end 122.680222 -229.90429)
		(width 0.1143)
		(layer "In15.Cu")
		(net "GMI_CPU0_G1_CPU1_G3_TX_DN<11>")
	)
	(arc
		(start 348.6277 -237.681516)
		(mid 348.347273 -237.19428)
		(end 348.6277 -236.706918)
		(width 0.1143)
		(layer "In15.Cu")
		(net "GMI_CPU0_G1_CPU1_G3_TX_DN<11>")
	)
	(arc
		(start 348.659704 -239.9284)
		(mid 348.815632 -239.624108)
		(end 348.659704 -239.319816)
		(width 0.1143)
		(layer "In15.Cu")
		(net "GMI_CPU0_G1_CPU1_G3_TX_DN<11>")
	)
	(arc
		(start 348.659704 -238.308388)
		(mid 348.815632 -238.004096)
		(end 348.659704 -237.699804)
		(width 0.1143)
		(layer "In15.Cu")
		(net "GMI_CPU0_G1_CPU1_G3_TX_DN<11>")
	)
	(arc
		(start 122.90679 -235.109766)
		(mid 123.150117 -235.574332)
		(end 122.90679 -236.038898)
		(width 0.1143)
		(layer "In15.Cu")
		(net "GMI_CPU0_G1_CPU1_G3_TX_DN<11>")
	)
	(arc
		(start 348.6277 -239.301528)
		(mid 348.347273 -238.814292)
		(end 348.6277 -238.32693)
		(width 0.1143)
		(layer "In15.Cu")
		(net "GMI_CPU0_G1_CPU1_G3_TX_DN<11>")
	)
	(arc
		(start 348.577408 -233.497628)
		(mid 348.584481 -233.492619)
		(end 348.591632 -233.487722)
		(width 0.1143)
		(layer "In15.Cu")
		(net "GMI_CPU0_G1_CPU1_G3_TX_DN<11>")
	)
	(arc
		(start 347.649038 -223.078802)
		(mid 347.470225 -222.876452)
		(end 347.405706 -222.614236)
		(width 0.1143)
		(layer "In15.Cu")
		(net "GMI_CPU0_G1_CPU1_G3_TX_DN<11>")
	)
	(arc
		(start 348.659704 -228.58857)
		(mid 348.815632 -228.284278)
		(end 348.659704 -227.979986)
		(width 0.1143)
		(layer "In15.Cu")
		(net "GMI_CPU0_G1_CPU1_G3_TX_DN<11>")
	)
	(arc
		(start 348.341188 -225.826828)
		(mid 348.288304 -225.679618)
		(end 348.194376 -225.55454)
		(width 0.1143)
		(layer "In15.Cu")
		(net "GMI_CPU0_G1_CPU1_G3_TX_DN<11>")
	)
	(arc
		(start 123.150122 -230.71455)
		(mid 123.085607 -230.976769)
		(end 122.90679 -231.179116)
		(width 0.1143)
		(layer "In15.Cu")
		(net "GMI_CPU0_G1_CPU1_G3_TX_DN<11>")
	)
	(arc
		(start 348.659704 -230.208328)
		(mid 348.77438 -230.074994)
		(end 348.81566 -229.904036)
		(width 0.1143)
		(layer "In15.Cu")
		(net "GMI_CPU0_G1_CPU1_G3_TX_DN<11>")
	)
	(arc
		(start 122.837194 -226.35972)
		(mid 122.680217 -226.66452)
		(end 122.837194 -226.96932)
		(width 0.1143)
		(layer "In15.Cu")
		(net "GMI_CPU0_G1_CPU1_G3_TX_DN<11>")
	)
	(arc
		(start 348.659704 -243.168424)
		(mid 348.815632 -242.864132)
		(end 348.659704 -242.55984)
		(width 0.1143)
		(layer "In15.Cu")
		(net "GMI_CPU0_G1_CPU1_G3_TX_DN<11>")
	)
	(arc
		(start 348.659704 -241.548412)
		(mid 348.815632 -241.24412)
		(end 348.659704 -240.939828)
		(width 0.1143)
		(layer "In15.Cu")
		(net "GMI_CPU0_G1_CPU1_G3_TX_DN<11>")
	)
	(arc
		(start 348.6277 -242.541552)
		(mid 348.347273 -242.054316)
		(end 348.6277 -241.566954)
		(width 0.1143)
		(layer "In15.Cu")
		(net "GMI_CPU0_G1_CPU1_G3_TX_DN<11>")
	)
	(arc
		(start 122.837194 -232.839514)
		(mid 122.680217 -233.144314)
		(end 122.837194 -233.449114)
		(width 0.1143)
		(layer "In15.Cu")
		(net "GMI_CPU0_G1_CPU1_G3_TX_DN<11>")
	)
	(arc
		(start 347.718634 -223.729042)
		(mid 347.875611 -223.424242)
		(end 347.718634 -223.119442)
		(width 0.1143)
		(layer "In15.Cu")
		(net "GMI_CPU0_G1_CPU1_G3_TX_DN<11>")
	)
	(arc
		(start 348.6277 -240.92154)
		(mid 348.347273 -240.434304)
		(end 348.6277 -239.946942)
		(width 0.1143)
		(layer "In15.Cu")
		(net "GMI_CPU0_G1_CPU1_G3_TX_DN<11>")
	)
	(arc
		(start 348.575376 -244.129052)
		(mid 348.352492 -243.674138)
		(end 348.575376 -243.219224)
		(width 0.1143)
		(layer "In15.Cu")
		(net "GMI_CPU0_G1_CPU1_G3_TX_DN<11>")
	)
	(arc
		(start 122.837194 -244.179598)
		(mid 122.739429 -244.282574)
		(end 122.68708 -244.414548)
		(width 0.1143)
		(layer "In15.Cu")
		(net "GMI_CPU0_G1_CPU1_G3_TX_DN<11>")
	)
	(arc
		(start 348.577408 -234.410504)
		(mid 348.350025 -233.954066)
		(end 348.577408 -233.497628)
		(width 0.1143)
		(layer "In15.Cu")
		(net "GMI_CPU0_G1_CPU1_G3_TX_DN<11>")
	)
	(arc
		(start 348.81566 -229.904036)
		(mid 348.774898 -229.734152)
		(end 348.661482 -229.601268)
		(width 0.1143)
		(layer "In15.Cu")
		(net "GMI_CPU0_G1_CPU1_G3_TX_DN<11>")
	)
	(arc
		(start 348.659704 -235.068364)
		(mid 348.815632 -234.764072)
		(end 348.659704 -234.45978)
		(width 0.1143)
		(layer "In15.Cu")
		(net "GMI_CPU0_G1_CPU1_G3_TX_DN<11>")
	)
	(arc
		(start 348.575376 -243.219224)
		(mid 348.583454 -243.213438)
		(end 348.591632 -243.207794)
		(width 0.1143)
		(layer "In15.Cu")
		(net "GMI_CPU0_G1_CPU1_G3_TX_DN<11>")
	)
	(arc
		(start 122.837194 -234.459526)
		(mid 122.680217 -234.764326)
		(end 122.837194 -235.069126)
		(width 0.1143)
		(layer "In15.Cu")
		(net "GMI_CPU0_G1_CPU1_G3_TX_DN<11>")
	)
	(arc
		(start 122.90679 -225.389948)
		(mid 123.150117 -225.854514)
		(end 122.90679 -226.31908)
		(width 0.1143)
		(layer "In15.Cu")
		(net "GMI_CPU0_G1_CPU1_G3_TX_DN<11>")
	)
	(arc
		(start 348.659704 -236.688376)
		(mid 348.815632 -236.384084)
		(end 348.659704 -236.079792)
		(width 0.1143)
		(layer "In15.Cu")
		(net "GMI_CPU0_G1_CPU1_G3_TX_DN<11>")
	)
	(arc
		(start 347.649038 -224.698814)
		(mid 347.405711 -224.234248)
		(end 347.649038 -223.769682)
		(width 0.1143)
		(layer "In15.Cu")
		(net "GMI_CPU0_G1_CPU1_G3_TX_DN<11>")
	)
	(arc
		(start 348.81566 -231.524048)
		(mid 348.774898 -231.354164)
		(end 348.661482 -231.22128)
		(width 0.1143)
		(layer "In15.Cu")
		(net "GMI_CPU0_G1_CPU1_G3_TX_DN<11>")
	)
	(arc
		(start 122.90679 -227.00996)
		(mid 123.150117 -227.474526)
		(end 122.90679 -227.939092)
		(width 0.1143)
		(layer "In15.Cu")
		(net "GMI_CPU0_G1_CPU1_G3_TX_DN<11>")
	)
	(segment
		(start 348.907862 -247.990106)
		(end 348.44101 -247.724168)
		(width 0.12954)
		(layer "F.Cu")
		(net "GMI_CPU0_G1_CPU1_G3_TX_DN<10>")
	)
	(segment
		(start 122.587766 -247.99036)
		(end 123.054618 -247.724422)
		(width 0.12954)
		(layer "F.Cu")
		(net "GMI_CPU0_G1_CPU1_G3_TX_DN<10>")
	)
	(segment
		(start 121.929144 -224.720912)
		(end 121.926858 -224.722436)
		(width 0.1143)
		(layer "In15.Cu")
		(net "GMI_CPU0_G1_CPU1_G3_TX_DN<10>")
	)
	(segment
		(start 349.57258 -236.704124)
		(end 349.599758 -236.688376)
		(width 0.1143)
		(layer "In15.Cu")
		(net "GMI_CPU0_G1_CPU1_G3_TX_DN<10>")
	)
	(segment
		(start 349.09887 -225.532188)
		(end 349.098108 -225.53168)
		(width 0.1143)
		(layer "In15.Cu")
		(net "GMI_CPU0_G1_CPU1_G3_TX_DN<10>")
	)
	(segment
		(start 121.92762 -227.961952)
		(end 121.926858 -227.96246)
		(width 0.1143)
		(layer "In15.Cu")
		(net "GMI_CPU0_G1_CPU1_G3_TX_DN<10>")
	)
	(segment
		(start 349.599758 -237.699804)
		(end 349.568008 -237.681516)
		(width 0.1143)
		(layer "In15.Cu")
		(net "GMI_CPU0_G1_CPU1_G3_TX_DN<10>")
	)
	(segment
		(start 121.924064 -238.324898)
		(end 121.925588 -238.32566)
		(width 0.1143)
		(layer "In15.Cu")
		(net "GMI_CPU0_G1_CPU1_G3_TX_DN<10>")
	)
	(segment
		(start 121.71553 -221.198948)
		(end 121.739914 -221.223332)
		(width 0.1143)
		(layer "In15.Cu")
		(net "GMI_CPU0_G1_CPU1_G3_TX_DN<10>")
	)
	(segment
		(start 121.894854 -231.221026)
		(end 121.894092 -231.221534)
		(width 0.1143)
		(layer "In15.Cu")
		(net "GMI_CPU0_G1_CPU1_G3_TX_DN<10>")
	)
	(segment
		(start 121.92762 -246.42699)
		(end 121.941844 -246.435118)
		(width 0.1143)
		(layer "In15.Cu")
		(net "GMI_CPU0_G1_CPU1_G3_TX_DN<10>")
	)
	(segment
		(start 121.925588 -228.605842)
		(end 121.926858 -228.606604)
		(width 0.1143)
		(layer "In15.Cu")
		(net "GMI_CPU0_G1_CPU1_G3_TX_DN<10>")
	)
	(segment
		(start 121.924318 -226.343718)
		(end 121.923556 -226.344226)
		(width 0.1143)
		(layer "In15.Cu")
		(net "GMI_CPU0_G1_CPU1_G3_TX_DN<10>")
	)
	(segment
		(start 347.794326 -219.482924)
		(end 345.421712 -214.469218)
		(width 0.14224)
		(layer "In15.Cu")
		(net "GMI_CPU0_G1_CPU1_G3_TX_DN<10>")
	)
	(segment
		(start 121.89587 -239.928654)
		(end 121.924064 -239.94491)
		(width 0.1143)
		(layer "In15.Cu")
		(net "GMI_CPU0_G1_CPU1_G3_TX_DN<10>")
	)
	(segment
		(start 349.565468 -236.05998)
		(end 349.564452 -236.059472)
		(width 0.1143)
		(layer "In15.Cu")
		(net "GMI_CPU0_G1_CPU1_G3_TX_DN<10>")
	)
	(segment
		(start 349.56877 -241.566192)
		(end 349.57004 -241.56543)
		(width 0.1143)
		(layer "In15.Cu")
		(net "GMI_CPU0_G1_CPU1_G3_TX_DN<10>")
	)
	(segment
		(start 121.966482 -224.699322)
		(end 121.929144 -224.720912)
		(width 0.1143)
		(layer "In15.Cu")
		(net "GMI_CPU0_G1_CPU1_G3_TX_DN<10>")
	)
	(segment
		(start 121.926858 -233.466386)
		(end 121.92762 -233.466894)
		(width 0.1143)
		(layer "In15.Cu")
		(net "GMI_CPU0_G1_CPU1_G3_TX_DN<10>")
	)
	(segment
		(start 157.61462 -189.522862)
		(end 157.432502 -189.504574)
		(width 0.14224)
		(layer "In15.Cu")
		(net "GMI_CPU0_G1_CPU1_G3_TX_DN<10>")
	)
	(segment
		(start 121.924064 -223.745044)
		(end 121.925588 -223.745806)
		(width 0.1143)
		(layer "In15.Cu")
		(net "GMI_CPU0_G1_CPU1_G3_TX_DN<10>")
	)
	(segment
		(start 121.76125 -221.020386)
		(end 121.71553 -221.066106)
		(width 0.1143)
		(layer "In15.Cu")
		(net "GMI_CPU0_G1_CPU1_G3_TX_DN<10>")
	)
	(segment
		(start 349.599758 -232.839768)
		(end 349.56877 -232.821988)
		(width 0.1143)
		(layer "In15.Cu")
		(net "GMI_CPU0_G1_CPU1_G3_TX_DN<10>")
	)
	(segment
		(start 349.568262 -226.986846)
		(end 349.598742 -226.969066)
		(width 0.1143)
		(layer "In15.Cu")
		(net "GMI_CPU0_G1_CPU1_G3_TX_DN<10>")
	)
	(segment
		(start 121.925588 -245.7831)
		(end 121.89587 -245.800118)
		(width 0.1143)
		(layer "In15.Cu")
		(net "GMI_CPU0_G1_CPU1_G3_TX_DN<10>")
	)
	(segment
		(start 121.895616 -222.108776)
		(end 121.966482 -222.14967)
		(width 0.1143)
		(layer "In15.Cu")
		(net "GMI_CPU0_G1_CPU1_G3_TX_DN<10>")
	)
	(segment
		(start 121.92254 -226.344734)
		(end 121.921778 -226.345242)
		(width 0.1143)
		(layer "In15.Cu")
		(net "GMI_CPU0_G1_CPU1_G3_TX_DN<10>")
	)
	(segment
		(start 121.930414 -225.368866)
		(end 121.96699 -225.389948)
		(width 0.1143)
		(layer "In15.Cu")
		(net "GMI_CPU0_G1_CPU1_G3_TX_DN<10>")
	)
	(segment
		(start 349.568008 -237.681516)
		(end 349.566992 -237.681008)
		(width 0.1143)
		(layer "In15.Cu")
		(net "GMI_CPU0_G1_CPU1_G3_TX_DN<10>")
	)
	(segment
		(start 349.565468 -237.679992)
		(end 349.528892 -237.658656)
		(width 0.1143)
		(layer "In15.Cu")
		(net "GMI_CPU0_G1_CPU1_G3_TX_DN<10>")
	)
	(segment
		(start 349.57258 -239.944148)
		(end 349.599758 -239.9284)
		(width 0.1143)
		(layer "In15.Cu")
		(net "GMI_CPU0_G1_CPU1_G3_TX_DN<10>")
	)
	(segment
		(start 121.961148 -231.182418)
		(end 121.92762 -231.201976)
		(width 0.1143)
		(layer "In15.Cu")
		(net "GMI_CPU0_G1_CPU1_G3_TX_DN<10>")
	)
	(segment
		(start 121.73966 -221.381828)
		(end 121.73966 -221.804484)
		(width 0.1143)
		(layer "In15.Cu")
		(net "GMI_CPU0_G1_CPU1_G3_TX_DN<10>")
	)
	(segment
		(start 349.568262 -229.58171)
		(end 349.531178 -229.560374)
		(width 0.1143)
		(layer "In15.Cu")
		(net "GMI_CPU0_G1_CPU1_G3_TX_DN<10>")
	)
	(segment
		(start 348.628208 -223.101662)
		(end 348.589092 -223.078802)
		(width 0.1143)
		(layer "In15.Cu")
		(net "GMI_CPU0_G1_CPU1_G3_TX_DN<10>")
	)
	(segment
		(start 121.924064 -226.985068)
		(end 121.925588 -226.98583)
		(width 0.1143)
		(layer "In15.Cu")
		(net "GMI_CPU0_G1_CPU1_G3_TX_DN<10>")
	)
	(segment
		(start 121.963942 -231.180894)
		(end 121.961148 -231.182418)
		(width 0.1143)
		(layer "In15.Cu")
		(net "GMI_CPU0_G1_CPU1_G3_TX_DN<10>")
	)
	(segment
		(start 308.421786 -185.28538)
		(end 306.652168 -184.474866)
		(width 0.14224)
		(layer "In15.Cu")
		(net "GMI_CPU0_G1_CPU1_G3_TX_DN<10>")
	)
	(segment
		(start 349.56877 -236.062012)
		(end 349.568008 -236.061504)
		(width 0.1143)
		(layer "In15.Cu")
		(net "GMI_CPU0_G1_CPU1_G3_TX_DN<10>")
	)
	(segment
		(start 121.93016 -226.988878)
		(end 121.967244 -227.00996)
		(width 0.1143)
		(layer "In15.Cu")
		(net "GMI_CPU0_G1_CPU1_G3_TX_DN<10>")
	)
	(segment
		(start 121.93016 -243.188744)
		(end 121.967244 -243.209826)
		(width 0.1143)
		(layer "In15.Cu")
		(net "GMI_CPU0_G1_CPU1_G3_TX_DN<10>")
	)
	(segment
		(start 121.96699 -242.518946)
		(end 121.926096 -242.542568)
		(width 0.1143)
		(layer "In15.Cu")
		(net "GMI_CPU0_G1_CPU1_G3_TX_DN<10>")
	)
	(segment
		(start 121.918984 -226.346766)
		(end 121.89587 -226.360228)
		(width 0.1143)
		(layer "In15.Cu")
		(net "GMI_CPU0_G1_CPU1_G3_TX_DN<10>")
	)
	(segment
		(start 348.44101 -247.724168)
		(end 348.738952 -247.724168)
		(width 0.1143)
		(layer "In15.Cu")
		(net "GMI_CPU0_G1_CPU1_G3_TX_DN<10>")
	)
	(segment
		(start 349.566992 -232.820972)
		(end 349.565468 -232.819956)
		(width 0.1143)
		(layer "In15.Cu")
		(net "GMI_CPU0_G1_CPU1_G3_TX_DN<10>")
	)
	(segment
		(start 121.92762 -244.806978)
		(end 121.930414 -244.808756)
		(width 0.1143)
		(layer "In15.Cu")
		(net "GMI_CPU0_G1_CPU1_G3_TX_DN<10>")
	)
	(segment
		(start 121.966482 -222.14967)
		(end 121.990866 -222.167196)
		(width 0.1143)
		(layer "In15.Cu")
		(net "GMI_CPU0_G1_CPU1_G3_TX_DN<10>")
	)
	(segment
		(start 153.666698 -192.59169)
		(end 153.647648 -192.78473)
		(width 0.14224)
		(layer "In15.Cu")
		(net "GMI_CPU0_G1_CPU1_G3_TX_DN<10>")
	)
	(segment
		(start 349.06585 -225.512884)
		(end 349.058992 -225.50882)
		(width 0.1143)
		(layer "In15.Cu")
		(net "GMI_CPU0_G1_CPU1_G3_TX_DN<10>")
	)
	(segment
		(start 349.57258 -241.56416)
		(end 349.599758 -241.548412)
		(width 0.1143)
		(layer "In15.Cu")
		(net "GMI_CPU0_G1_CPU1_G3_TX_DN<10>")
	)
	(segment
		(start 349.57004 -236.705394)
		(end 349.57258 -236.704124)
		(width 0.1143)
		(layer "In15.Cu")
		(net "GMI_CPU0_G1_CPU1_G3_TX_DN<10>")
	)
	(segment
		(start 121.930414 -241.568732)
		(end 121.96699 -241.589814)
		(width 0.1143)
		(layer "In15.Cu")
		(net "GMI_CPU0_G1_CPU1_G3_TX_DN<10>")
	)
	(segment
		(start 157.090364 -189.952376)
		(end 156.766006 -190.218568)
		(width 0.14224)
		(layer "In15.Cu")
		(net "GMI_CPU0_G1_CPU1_G3_TX_DN<10>")
	)
	(segment
		(start 349.57004 -246.425466)
		(end 349.57258 -246.424196)
		(width 0.1143)
		(layer "In15.Cu")
		(net "GMI_CPU0_G1_CPU1_G3_TX_DN<10>")
	)
	(segment
		(start 349.528892 -241.58956)
		(end 349.568008 -241.5667)
		(width 0.1143)
		(layer "In15.Cu")
		(net "GMI_CPU0_G1_CPU1_G3_TX_DN<10>")
	)
	(segment
		(start 349.528892 -244.829584)
		(end 349.568008 -244.806724)
		(width 0.1143)
		(layer "In15.Cu")
		(net "GMI_CPU0_G1_CPU1_G3_TX_DN<10>")
	)
	(segment
		(start 121.926858 -232.822242)
		(end 121.925588 -232.823004)
		(width 0.1143)
		(layer "In15.Cu")
		(net "GMI_CPU0_G1_CPU1_G3_TX_DN<10>")
	)
	(segment
		(start 349.565468 -242.540028)
		(end 349.528892 -242.518692)
		(width 0.1143)
		(layer "In15.Cu")
		(net "GMI_CPU0_G1_CPU1_G3_TX_DN<10>")
	)
	(segment
		(start 121.925588 -223.745806)
		(end 121.926858 -223.746568)
		(width 0.1143)
		(layer "In15.Cu")
		(net "GMI_CPU0_G1_CPU1_G3_TX_DN<10>")
	)
	(segment
		(start 349.599758 -242.55984)
		(end 349.568008 -242.541552)
		(width 0.1143)
		(layer "In15.Cu")
		(net "GMI_CPU0_G1_CPU1_G3_TX_DN<10>")
	)
	(segment
		(start 121.89587 -244.78869)
		(end 121.924064 -244.804946)
		(width 0.1143)
		(layer "In15.Cu")
		(net "GMI_CPU0_G1_CPU1_G3_TX_DN<10>")
	)
	(segment
		(start 121.926858 -245.782338)
		(end 121.925588 -245.7831)
		(width 0.1143)
		(layer "In15.Cu")
		(net "GMI_CPU0_G1_CPU1_G3_TX_DN<10>")
	)
	(segment
		(start 121.963942 -234.420664)
		(end 121.92762 -234.441746)
		(width 0.1143)
		(layer "In15.Cu")
		(net "GMI_CPU0_G1_CPU1_G3_TX_DN<10>")
	)
	(segment
		(start 156.766006 -190.218568)
		(end 156.583888 -190.20028)
		(width 0.14224)
		(layer "In15.Cu")
		(net "GMI_CPU0_G1_CPU1_G3_TX_DN<10>")
	)
	(segment
		(start 349.56877 -232.821988)
		(end 349.568008 -232.82148)
		(width 0.1143)
		(layer "In15.Cu")
		(net "GMI_CPU0_G1_CPU1_G3_TX_DN<10>")
	)
	(segment
		(start 349.57004 -238.325406)
		(end 349.599758 -238.308388)
		(width 0.1143)
		(layer "In15.Cu")
		(net "GMI_CPU0_G1_CPU1_G3_TX_DN<10>")
	)
	(segment
		(start 349.528892 -238.349536)
		(end 349.566992 -238.327184)
		(width 0.1143)
		(layer "In15.Cu")
		(net "GMI_CPU0_G1_CPU1_G3_TX_DN<10>")
	)
	(segment
		(start 121.926858 -244.80647)
		(end 121.92762 -244.806978)
		(width 0.1143)
		(layer "In15.Cu")
		(net "GMI_CPU0_G1_CPU1_G3_TX_DN<10>")
	)
	(segment
		(start 349.568262 -227.961698)
		(end 349.529146 -227.938838)
		(width 0.1143)
		(layer "In15.Cu")
		(net "GMI_CPU0_G1_CPU1_G3_TX_DN<10>")
	)
	(segment
		(start 121.924064 -228.60508)
		(end 121.925588 -228.605842)
		(width 0.1143)
		(layer "In15.Cu")
		(net "GMI_CPU0_G1_CPU1_G3_TX_DN<10>")
	)
	(segment
		(start 349.568008 -241.5667)
		(end 349.56877 -241.566192)
		(width 0.1143)
		(layer "In15.Cu")
		(net "GMI_CPU0_G1_CPU1_G3_TX_DN<10>")
	)
	(segment
		(start 121.984008 -245.747032)
		(end 121.966228 -245.759478)
		(width 0.1143)
		(layer "In15.Cu")
		(net "GMI_CPU0_G1_CPU1_G3_TX_DN<10>")
	)
	(segment
		(start 121.926858 -240.922302)
		(end 121.925588 -240.923064)
		(width 0.1143)
		(layer "In15.Cu")
		(net "GMI_CPU0_G1_CPU1_G3_TX_DN<10>")
	)
	(segment
		(start 121.926858 -243.186458)
		(end 121.92762 -243.186966)
		(width 0.1143)
		(layer "In15.Cu")
		(net "GMI_CPU0_G1_CPU1_G3_TX_DN<10>")
	)
	(segment
		(start 349.56877 -236.706156)
		(end 349.57004 -236.705394)
		(width 0.1143)
		(layer "In15.Cu")
		(net "GMI_CPU0_G1_CPU1_G3_TX_DN<10>")
	)
	(segment
		(start 121.985278 -242.505992)
		(end 121.96699 -242.518946)
		(width 0.1143)
		(layer "In15.Cu")
		(net "GMI_CPU0_G1_CPU1_G3_TX_DN<10>")
	)
	(segment
		(start 121.926858 -234.442254)
		(end 121.925588 -234.443016)
		(width 0.1143)
		(layer "In15.Cu")
		(net "GMI_CPU0_G1_CPU1_G3_TX_DN<10>")
	)
	(segment
		(start 121.920762 -226.34575)
		(end 121.92 -226.346258)
		(width 0.1143)
		(layer "In15.Cu")
		(net "GMI_CPU0_G1_CPU1_G3_TX_DN<10>")
	)
	(segment
		(start 153.996644 -192.32118)
		(end 153.666698 -192.59169)
		(width 0.14224)
		(layer "In15.Cu")
		(net "GMI_CPU0_G1_CPU1_G3_TX_DN<10>")
	)
	(segment
		(start 349.57004 -243.185442)
		(end 349.57258 -243.184172)
		(width 0.1143)
		(layer "In15.Cu")
		(net "GMI_CPU0_G1_CPU1_G3_TX_DN<10>")
	)
	(segment
		(start 348.589092 -223.769682)
		(end 348.628208 -223.746822)
		(width 0.1143)
		(layer "In15.Cu")
		(net "GMI_CPU0_G1_CPU1_G3_TX_DN<10>")
	)
	(segment
		(start 349.57004 -244.805454)
		(end 349.57258 -244.804184)
		(width 0.1143)
		(layer "In15.Cu")
		(net "GMI_CPU0_G1_CPU1_G3_TX_DN<10>")
	)
	(segment
		(start 349.56877 -238.326168)
		(end 349.57004 -238.325406)
		(width 0.1143)
		(layer "In15.Cu")
		(net "GMI_CPU0_G1_CPU1_G3_TX_DN<10>")
	)
	(segment
		(start 349.566992 -237.681008)
		(end 349.565468 -237.679992)
		(width 0.1143)
		(layer "In15.Cu")
		(net "GMI_CPU0_G1_CPU1_G3_TX_DN<10>")
	)
	(segment
		(start 121.89587 -230.208582)
		(end 121.924318 -230.224838)
		(width 0.1143)
		(layer "In15.Cu")
		(net "GMI_CPU0_G1_CPU1_G3_TX_DN<10>")
	)
	(segment
		(start 349.566992 -236.060996)
		(end 349.565468 -236.05998)
		(width 0.1143)
		(layer "In15.Cu")
		(net "GMI_CPU0_G1_CPU1_G3_TX_DN<10>")
	)
	(segment
		(start 121.92762 -231.201976)
		(end 121.894854 -231.221026)
		(width 0.1143)
		(layer "In15.Cu")
		(net "GMI_CPU0_G1_CPU1_G3_TX_DN<10>")
	)
	(segment
		(start 349.566992 -242.541044)
		(end 349.565468 -242.540028)
		(width 0.1143)
		(layer "In15.Cu")
		(net "GMI_CPU0_G1_CPU1_G3_TX_DN<10>")
	)
	(segment
		(start 349.565468 -239.300004)
		(end 349.564452 -239.299496)
		(width 0.1143)
		(layer "In15.Cu")
		(net "GMI_CPU0_G1_CPU1_G3_TX_DN<10>")
	)
	(segment
		(start 349.568008 -233.46664)
		(end 349.56877 -233.466132)
		(width 0.1143)
		(layer "In15.Cu")
		(net "GMI_CPU0_G1_CPU1_G3_TX_DN<10>")
	)
	(segment
		(start 153.317448 -193.055494)
		(end 153.124408 -193.03619)
		(width 0.14224)
		(layer "In15.Cu")
		(net "GMI_CPU0_G1_CPU1_G3_TX_DN<10>")
	)
	(segment
		(start 121.739914 -221.223332)
		(end 121.740168 -221.223332)
		(width 0.1143)
		(layer "In15.Cu")
		(net "GMI_CPU0_G1_CPU1_G3_TX_DN<10>")
	)
	(segment
		(start 349.57004 -241.56543)
		(end 349.57258 -241.56416)
		(width 0.1143)
		(layer "In15.Cu")
		(net "GMI_CPU0_G1_CPU1_G3_TX_DN<10>")
	)
	(segment
		(start 121.924064 -244.804946)
		(end 121.925588 -244.805708)
		(width 0.1143)
		(layer "In15.Cu")
		(net "GMI_CPU0_G1_CPU1_G3_TX_DN<10>")
	)
	(segment
		(start 121.926858 -228.606604)
		(end 121.92762 -228.607112)
		(width 0.1143)
		(layer "In15.Cu")
		(net "GMI_CPU0_G1_CPU1_G3_TX_DN<10>")
	)
	(segment
		(start 121.926858 -230.226362)
		(end 121.92762 -230.22687)
		(width 0.1143)
		(layer "In15.Cu")
		(net "GMI_CPU0_G1_CPU1_G3_TX_DN<10>")
	)
	(segment
		(start 349.098108 -247.236742)
		(end 349.128588 -247.218962)
		(width 0.1143)
		(layer "In15.Cu")
		(net "GMI_CPU0_G1_CPU1_G3_TX_DN<10>")
	)
	(segment
		(start 121.925588 -234.443016)
		(end 121.89587 -234.460034)
		(width 0.1143)
		(layer "In15.Cu")
		(net "GMI_CPU0_G1_CPU1_G3_TX_DN<10>")
	)
	(segment
		(start 121.990866 -223.062038)
		(end 121.96699 -223.079056)
		(width 0.1143)
		(layer "In15.Cu")
		(net "GMI_CPU0_G1_CPU1_G3_TX_DN<10>")
	)
	(segment
		(start 349.531432 -230.247952)
		(end 349.568008 -230.226616)
		(width 0.1143)
		(layer "In15.Cu")
		(net "GMI_CPU0_G1_CPU1_G3_TX_DN<10>")
	)
	(segment
		(start 349.57004 -231.845358)
		(end 349.57258 -231.844088)
		(width 0.1143)
		(layer "In15.Cu")
		(net "GMI_CPU0_G1_CPU1_G3_TX_DN<10>")
	)
	(segment
		(start 151.379936 -194.46621)
		(end 146.793712 -198.226172)
		(width 0.14224)
		(layer "In15.Cu")
		(net "GMI_CPU0_G1_CPU1_G3_TX_DN<10>")
	)
	(segment
		(start 145.905982 -198.495158)
		(end 145.905728 -198.495158)
		(width 0.14224)
		(layer "In15.Cu")
		(net "GMI_CPU0_G1_CPU1_G3_TX_DN<10>")
	)
	(segment
		(start 121.92762 -225.367088)
		(end 121.930414 -225.368866)
		(width 0.1143)
		(layer "In15.Cu")
		(net "GMI_CPU0_G1_CPU1_G3_TX_DN<10>")
	)
	(segment
		(start 121.92762 -234.441746)
		(end 121.926858 -234.442254)
		(width 0.1143)
		(layer "In15.Cu")
		(net "GMI_CPU0_G1_CPU1_G3_TX_DN<10>")
	)
	(segment
		(start 121.966228 -245.759478)
		(end 121.92762 -245.78183)
		(width 0.1143)
		(layer "In15.Cu")
		(net "GMI_CPU0_G1_CPU1_G3_TX_DN<10>")
	)
	(segment
		(start 349.57004 -235.085382)
		(end 349.57258 -235.084112)
		(width 0.1143)
		(layer "In15.Cu")
		(net "GMI_CPU0_G1_CPU1_G3_TX_DN<10>")
	)
	(segment
		(start 121.924064 -225.365056)
		(end 121.925588 -225.365818)
		(width 0.1143)
		(layer "In15.Cu")
		(net "GMI_CPU0_G1_CPU1_G3_TX_DN<10>")
	)
	(segment
		(start 121.92762 -223.101916)
		(end 121.926858 -223.102424)
		(width 0.1143)
		(layer "In15.Cu")
		(net "GMI_CPU0_G1_CPU1_G3_TX_DN<10>")
	)
	(segment
		(start 121.924064 -233.464862)
		(end 121.925588 -233.465624)
		(width 0.1143)
		(layer "In15.Cu")
		(net "GMI_CPU0_G1_CPU1_G3_TX_DN<10>")
	)
	(segment
		(start 349.564452 -244.159532)
		(end 349.528892 -244.138704)
		(width 0.1143)
		(layer "In15.Cu")
		(net "GMI_CPU0_G1_CPU1_G3_TX_DN<10>")
	)
	(segment
		(start 349.058992 -247.259602)
		(end 349.098108 -247.236742)
		(width 0.1143)
		(layer "In15.Cu")
		(net "GMI_CPU0_G1_CPU1_G3_TX_DN<10>")
	)
	(segment
		(start 121.89587 -243.168678)
		(end 121.924064 -243.184934)
		(width 0.1143)
		(layer "In15.Cu")
		(net "GMI_CPU0_G1_CPU1_G3_TX_DN<10>")
	)
	(segment
		(start 348.121732 -222.270574)
		(end 348.120716 -222.270066)
		(width 0.1143)
		(layer "In15.Cu")
		(net "GMI_CPU0_G1_CPU1_G3_TX_DN<10>")
	)
	(segment
		(start 121.926858 -238.326422)
		(end 121.92762 -238.32693)
		(width 0.1143)
		(layer "In15.Cu")
		(net "GMI_CPU0_G1_CPU1_G3_TX_DN<10>")
	)
	(segment
		(start 349.528892 -246.449596)
		(end 349.568008 -246.426736)
		(width 0.1143)
		(layer "In15.Cu")
		(net "GMI_CPU0_G1_CPU1_G3_TX_DN<10>")
	)
	(segment
		(start 349.09379 -225.52914)
		(end 349.066612 -225.513392)
		(width 0.1143)
		(layer "In15.Cu")
		(net "GMI_CPU0_G1_CPU1_G3_TX_DN<10>")
	)
	(segment
		(start 349.599758 -244.179852)
		(end 349.56877 -244.162072)
		(width 0.1143)
		(layer "In15.Cu")
		(net "GMI_CPU0_G1_CPU1_G3_TX_DN<10>")
	)
	(segment
		(start 154.189684 -192.340484)
		(end 153.996644 -192.32118)
		(width 0.14224)
		(layer "In15.Cu")
		(net "GMI_CPU0_G1_CPU1_G3_TX_DN<10>")
	)
	(segment
		(start 121.96699 -241.589814)
		(end 121.985278 -241.603022)
		(width 0.1143)
		(layer "In15.Cu")
		(net "GMI_CPU0_G1_CPU1_G3_TX_DN<10>")
	)
	(segment
		(start 122.756676 -247.724422)
		(end 123.054618 -247.724422)
		(width 0.1143)
		(layer "In15.Cu")
		(net "GMI_CPU0_G1_CPU1_G3_TX_DN<10>")
	)
	(segment
		(start 349.599758 -245.799864)
		(end 349.568008 -245.781576)
		(width 0.1143)
		(layer "In15.Cu")
		(net "GMI_CPU0_G1_CPU1_G3_TX_DN<10>")
	)
	(segment
		(start 349.57258 -246.424196)
		(end 349.599758 -246.408448)
		(width 0.1143)
		(layer "In15.Cu")
		(net "GMI_CPU0_G1_CPU1_G3_TX_DN<10>")
	)
	(segment
		(start 121.740168 -221.38132)
		(end 121.73966 -221.381828)
		(width 0.1143)
		(layer "In15.Cu")
		(net "GMI_CPU0_G1_CPU1_G3_TX_DN<10>")
	)
	(segment
		(start 121.89587 -235.068618)
		(end 121.924064 -235.084874)
		(width 0.1143)
		(layer "In15.Cu")
		(net "GMI_CPU0_G1_CPU1_G3_TX_DN<10>")
	)
	(segment
		(start 156.24175 -190.648082)
		(end 155.917392 -190.91402)
		(width 0.14224)
		(layer "In15.Cu")
		(net "GMI_CPU0_G1_CPU1_G3_TX_DN<10>")
	)
	(segment
		(start 121.76125 -220.991938)
		(end 121.76125 -221.020386)
		(width 0.1143)
		(layer "In15.Cu")
		(net "GMI_CPU0_G1_CPU1_G3_TX_DN<10>")
	)
	(segment
		(start 121.981976 -232.788206)
		(end 121.967498 -232.798874)
		(width 0.1143)
		(layer "In15.Cu")
		(net "GMI_CPU0_G1_CPU1_G3_TX_DN<10>")
	)
	(segment
		(start 121.740168 -221.223332)
		(end 121.740168 -221.38132)
		(width 0.1143)
		(layer "In15.Cu")
		(net "GMI_CPU0_G1_CPU1_G3_TX_DN<10>")
	)
	(segment
		(start 155.735274 -190.895986)
		(end 155.41117 -191.16167)
		(width 0.14224)
		(layer "In15.Cu")
		(net "GMI_CPU0_G1_CPU1_G3_TX_DN<10>")
	)
	(segment
		(start 347.840046 -221.128844)
		(end 347.794326 -221.083124)
		(width 0.1143)
		(layer "In15.Cu")
		(net "GMI_CPU0_G1_CPU1_G3_TX_DN<10>")
	)
	(segment
		(start 349.599758 -240.939828)
		(end 349.56877 -240.922048)
		(width 0.1143)
		(layer "In15.Cu")
		(net "GMI_CPU0_G1_CPU1_G3_TX_DN<10>")
	)
	(segment
		(start 121.96699 -225.389948)
		(end 121.985278 -225.403156)
		(width 0.1143)
		(layer "In15.Cu")
		(net "GMI_CPU0_G1_CPU1_G3_TX_DN<10>")
	)
	(segment
		(start 121.92762 -237.68177)
		(end 121.926858 -237.682278)
		(width 0.1143)
		(layer "In15.Cu")
		(net "GMI_CPU0_G1_CPU1_G3_TX_DN<10>")
	)
	(segment
		(start 122.673872 -247.641618)
		(end 122.756676 -247.724422)
		(width 0.1143)
		(layer "In15.Cu")
		(net "GMI_CPU0_G1_CPU1_G3_TX_DN<10>")
	)
	(segment
		(start 121.925588 -235.085636)
		(end 121.926858 -235.086398)
		(width 0.1143)
		(layer "In15.Cu")
		(net "GMI_CPU0_G1_CPU1_G3_TX_DN<10>")
	)
	(segment
		(start 121.963942 -229.560882)
		(end 121.92762 -229.581964)
		(width 0.1143)
		(layer "In15.Cu")
		(net "GMI_CPU0_G1_CPU1_G3_TX_DN<10>")
	)
	(segment
		(start 155.41117 -191.16167)
		(end 155.39212 -191.35471)
		(width 0.14224)
		(layer "In15.Cu")
		(net "GMI_CPU0_G1_CPU1_G3_TX_DN<10>")
	)
	(segment
		(start 154.86888 -191.60617)
		(end 154.538934 -191.87668)
		(width 0.14224)
		(layer "In15.Cu")
		(net "GMI_CPU0_G1_CPU1_G3_TX_DN<10>")
	)
	(segment
		(start 349.598742 -226.359466)
		(end 349.568262 -226.341686)
		(width 0.1143)
		(layer "In15.Cu")
		(net "GMI_CPU0_G1_CPU1_G3_TX_DN<10>")
	)
	(segment
		(start 349.10014 -225.53295)
		(end 349.09887 -225.532188)
		(width 0.1143)
		(layer "In15.Cu")
		(net "GMI_CPU0_G1_CPU1_G3_TX_DN<10>")
	)
	(segment
		(start 121.925588 -244.805708)
		(end 121.926858 -244.80647)
		(width 0.1143)
		(layer "In15.Cu")
		(net "GMI_CPU0_G1_CPU1_G3_TX_DN<10>")
	)
	(segment
		(start 349.599758 -236.079792)
		(end 349.56877 -236.062012)
		(width 0.1143)
		(layer "In15.Cu")
		(net "GMI_CPU0_G1_CPU1_G3_TX_DN<10>")
	)
	(segment
		(start 349.56877 -233.466132)
		(end 349.57004 -233.46537)
		(width 0.1143)
		(layer "In15.Cu")
		(net "GMI_CPU0_G1_CPU1_G3_TX_DN<10>")
	)
	(segment
		(start 121.925588 -226.98583)
		(end 121.926858 -226.986592)
		(width 0.1143)
		(layer "In15.Cu")
		(net "GMI_CPU0_G1_CPU1_G3_TX_DN<10>")
	)
	(segment
		(start 349.57258 -235.084112)
		(end 349.599758 -235.068364)
		(width 0.1143)
		(layer "In15.Cu")
		(net "GMI_CPU0_G1_CPU1_G3_TX_DN<10>")
	)
	(segment
		(start 349.566992 -240.921032)
		(end 349.565468 -240.920016)
		(width 0.1143)
		(layer "In15.Cu")
		(net "GMI_CPU0_G1_CPU1_G3_TX_DN<10>")
	)
	(segment
		(start 121.96699 -223.079056)
		(end 121.92762 -223.101916)
		(width 0.1143)
		(layer "In15.Cu")
		(net "GMI_CPU0_G1_CPU1_G3_TX_DN<10>")
	)
	(segment
		(start 349.528892 -231.869488)
		(end 349.568008 -231.846628)
		(width 0.1143)
		(layer "In15.Cu")
		(net "GMI_CPU0_G1_CPU1_G3_TX_DN<10>")
	)
	(segment
		(start 121.967244 -243.209826)
		(end 121.986294 -243.223796)
		(width 0.1143)
		(layer "In15.Cu")
		(net "GMI_CPU0_G1_CPU1_G3_TX_DN<10>")
	)
	(segment
		(start 349.601536 -231.22128)
		(end 349.568008 -231.201722)
		(width 0.1143)
		(layer "In15.Cu")
		(net "GMI_CPU0_G1_CPU1_G3_TX_DN<10>")
	)
	(segment
		(start 349.56877 -239.94618)
		(end 349.57004 -239.945418)
		(width 0.1143)
		(layer "In15.Cu")
		(net "GMI_CPU0_G1_CPU1_G3_TX_DN<10>")
	)
	(segment
		(start 121.92762 -245.78183)
		(end 121.926858 -245.782338)
		(width 0.1143)
		(layer "In15.Cu")
		(net "GMI_CPU0_G1_CPU1_G3_TX_DN<10>")
	)
	(segment
		(start 349.56877 -244.806216)
		(end 349.57004 -244.805454)
		(width 0.1143)
		(layer "In15.Cu")
		(net "GMI_CPU0_G1_CPU1_G3_TX_DN<10>")
	)
	(segment
		(start 121.926858 -235.086398)
		(end 121.92762 -235.086906)
		(width 0.1143)
		(layer "In15.Cu")
		(net "GMI_CPU0_G1_CPU1_G3_TX_DN<10>")
	)
	(segment
		(start 121.967244 -227.939092)
		(end 121.92762 -227.961952)
		(width 0.1143)
		(layer "In15.Cu")
		(net "GMI_CPU0_G1_CPU1_G3_TX_DN<10>")
	)
	(segment
		(start 349.568008 -236.706664)
		(end 349.56877 -236.706156)
		(width 0.1143)
		(layer "In15.Cu")
		(net "GMI_CPU0_G1_CPU1_G3_TX_DN<10>")
	)
	(segment
		(start 121.924064 -241.564922)
		(end 121.925588 -241.565684)
		(width 0.1143)
		(layer "In15.Cu")
		(net "GMI_CPU0_G1_CPU1_G3_TX_DN<10>")
	)
	(segment
		(start 302.888904 -184.474866)
		(end 167.042084 -183.68391)
		(width 0.14224)
		(layer "In15.Cu")
		(net "GMI_CPU0_G1_CPU1_G3_TX_DN<10>")
	)
	(segment
		(start 121.925588 -236.705648)
		(end 121.926858 -236.70641)
		(width 0.1143)
		(layer "In15.Cu")
		(net "GMI_CPU0_G1_CPU1_G3_TX_DN<10>")
	)
	(segment
		(start 349.564452 -234.43946)
		(end 349.528892 -234.418632)
		(width 0.1143)
		(layer "In15.Cu")
		(net "GMI_CPU0_G1_CPU1_G3_TX_DN<10>")
	)
	(segment
		(start 145.125186 -198.731886)
		(end 123.974098 -216.074498)
		(width 0.14224)
		(layer "In15.Cu")
		(net "GMI_CPU0_G1_CPU1_G3_TX_DN<10>")
	)
	(segment
		(start 155.39212 -191.35471)
		(end 155.06192 -191.625474)
		(width 0.14224)
		(layer "In15.Cu")
		(net "GMI_CPU0_G1_CPU1_G3_TX_DN<10>")
	)
	(segment
		(start 121.89587 -238.308642)
		(end 121.924064 -238.324898)
		(width 0.1143)
		(layer "In15.Cu")
		(net "GMI_CPU0_G1_CPU1_G3_TX_DN<10>")
	)
	(segment
		(start 121.89587 -241.548666)
		(end 121.924064 -241.564922)
		(width 0.1143)
		(layer "In15.Cu")
		(net "GMI_CPU0_G1_CPU1_G3_TX_DN<10>")
	)
	(segment
		(start 349.529146 -228.629718)
		(end 349.568262 -228.606858)
		(width 0.1143)
		(layer "In15.Cu")
		(net "GMI_CPU0_G1_CPU1_G3_TX_DN<10>")
	)
	(segment
		(start 121.925588 -244.163088)
		(end 121.89587 -244.180106)
		(width 0.1143)
		(layer "In15.Cu")
		(net "GMI_CPU0_G1_CPU1_G3_TX_DN<10>")
	)
	(segment
		(start 121.923556 -226.344226)
		(end 121.92254 -226.344734)
		(width 0.1143)
		(layer "In15.Cu")
		(net "GMI_CPU0_G1_CPU1_G3_TX_DN<10>")
	)
	(segment
		(start 121.89587 -228.588824)
		(end 121.924064 -228.60508)
		(width 0.1143)
		(layer "In15.Cu")
		(net "GMI_CPU0_G1_CPU1_G3_TX_DN<10>")
	)
	(segment
		(start 154.538934 -191.87668)
		(end 154.519884 -192.06972)
		(width 0.14224)
		(layer "In15.Cu")
		(net "GMI_CPU0_G1_CPU1_G3_TX_DN<10>")
	)
	(segment
		(start 121.924064 -246.424958)
		(end 121.925588 -246.42572)
		(width 0.1143)
		(layer "In15.Cu")
		(net "GMI_CPU0_G1_CPU1_G3_TX_DN<10>")
	)
	(segment
		(start 121.924064 -236.704886)
		(end 121.925588 -236.705648)
		(width 0.1143)
		(layer "In15.Cu")
		(net "GMI_CPU0_G1_CPU1_G3_TX_DN<10>")
	)
	(segment
		(start 349.568262 -228.606858)
		(end 349.598742 -228.589078)
		(width 0.1143)
		(layer "In15.Cu")
		(net "GMI_CPU0_G1_CPU1_G3_TX_DN<10>")
	)
	(segment
		(start 349.528892 -233.4895)
		(end 349.568008 -233.46664)
		(width 0.1143)
		(layer "In15.Cu")
		(net "GMI_CPU0_G1_CPU1_G3_TX_DN<10>")
	)
	(segment
		(start 349.565468 -244.16004)
		(end 349.564452 -244.159532)
		(width 0.1143)
		(layer "In15.Cu")
		(net "GMI_CPU0_G1_CPU1_G3_TX_DN<10>")
	)
	(segment
		(start 121.92762 -232.821734)
		(end 121.926858 -232.822242)
		(width 0.1143)
		(layer "In15.Cu")
		(net "GMI_CPU0_G1_CPU1_G3_TX_DN<10>")
	)
	(segment
		(start 349.568008 -238.326676)
		(end 349.56877 -238.326168)
		(width 0.1143)
		(layer "In15.Cu")
		(net "GMI_CPU0_G1_CPU1_G3_TX_DN<10>")
	)
	(segment
		(start 121.925334 -242.543076)
		(end 121.924318 -242.543584)
		(width 0.1143)
		(layer "In15.Cu")
		(net "GMI_CPU0_G1_CPU1_G3_TX_DN<10>")
	)
	(segment
		(start 121.925588 -239.945672)
		(end 121.926858 -239.946434)
		(width 0.1143)
		(layer "In15.Cu")
		(net "GMI_CPU0_G1_CPU1_G3_TX_DN<10>")
	)
	(segment
		(start 121.71553 -221.066106)
		(end 121.71553 -221.198948)
		(width 0.1143)
		(layer "In15.Cu")
		(net "GMI_CPU0_G1_CPU1_G3_TX_DN<10>")
	)
	(segment
		(start 121.926858 -227.96246)
		(end 121.925588 -227.963222)
		(width 0.1143)
		(layer "In15.Cu")
		(net "GMI_CPU0_G1_CPU1_G3_TX_DN<10>")
	)
	(segment
		(start 349.56877 -246.426228)
		(end 349.57004 -246.425466)
		(width 0.1143)
		(layer "In15.Cu")
		(net "GMI_CPU0_G1_CPU1_G3_TX_DN<10>")
	)
	(segment
		(start 349.57258 -244.804184)
		(end 349.599758 -244.788436)
		(width 0.1143)
		(layer "In15.Cu")
		(net "GMI_CPU0_G1_CPU1_G3_TX_DN<10>")
	)
	(segment
		(start 349.568008 -235.086652)
		(end 349.56877 -235.086144)
		(width 0.1143)
		(layer "In15.Cu")
		(net "GMI_CPU0_G1_CPU1_G3_TX_DN<10>")
	)
	(segment
		(start 349.566992 -239.30102)
		(end 349.565468 -239.300004)
		(width 0.1143)
		(layer "In15.Cu")
		(net "GMI_CPU0_G1_CPU1_G3_TX_DN<10>")
	)
	(segment
		(start 121.98858 -239.263428)
		(end 121.96699 -239.279176)
		(width 0.1143)
		(layer "In15.Cu")
		(net "GMI_CPU0_G1_CPU1_G3_TX_DN<10>")
	)
	(segment
		(start 349.568008 -244.806724)
		(end 349.56877 -244.806216)
		(width 0.1143)
		(layer "In15.Cu")
		(net "GMI_CPU0_G1_CPU1_G3_TX_DN<10>")
	)
	(segment
		(start 349.568008 -234.441492)
		(end 349.566992 -234.440984)
		(width 0.1143)
		(layer "In15.Cu")
		(net "GMI_CPU0_G1_CPU1_G3_TX_DN<10>")
	)
	(segment
		(start 121.926858 -223.102424)
		(end 121.925588 -223.103186)
		(width 0.1143)
		(layer "In15.Cu")
		(net "GMI_CPU0_G1_CPU1_G3_TX_DN<10>")
	)
	(segment
		(start 349.57258 -243.184172)
		(end 349.599758 -243.168424)
		(width 0.1143)
		(layer "In15.Cu")
		(net "GMI_CPU0_G1_CPU1_G3_TX_DN<10>")
	)
	(segment
		(start 121.925588 -237.68304)
		(end 121.89587 -237.700058)
		(width 0.1143)
		(layer "In15.Cu")
		(net "GMI_CPU0_G1_CPU1_G3_TX_DN<10>")
	)
	(segment
		(start 121.924064 -239.94491)
		(end 121.925588 -239.945672)
		(width 0.1143)
		(layer "In15.Cu")
		(net "GMI_CPU0_G1_CPU1_G3_TX_DN<10>")
	)
	(segment
		(start 349.566992 -244.161056)
		(end 349.565468 -244.16004)
		(width 0.1143)
		(layer "In15.Cu")
		(net "GMI_CPU0_G1_CPU1_G3_TX_DN<10>")
	)
	(segment
		(start 121.93016 -238.328708)
		(end 121.96699 -238.349536)
		(width 0.1143)
		(layer "In15.Cu")
		(net "GMI_CPU0_G1_CPU1_G3_TX_DN<10>")
	)
	(segment
		(start 348.628208 -224.721674)
		(end 348.589092 -224.698814)
		(width 0.1143)
		(layer "In15.Cu")
		(net "GMI_CPU0_G1_CPU1_G3_TX_DN<10>")
	)
	(segment
		(start 349.566992 -238.327184)
		(end 349.568008 -238.326676)
		(width 0.1143)
		(layer "In15.Cu")
		(net "GMI_CPU0_G1_CPU1_G3_TX_DN<10>")
	)
	(segment
		(start 349.57258 -231.844088)
		(end 349.599758 -231.82834)
		(width 0.1143)
		(layer "In15.Cu")
		(net "GMI_CPU0_G1_CPU1_G3_TX_DN<10>")
	)
	(segment
		(start 121.925588 -227.963222)
		(end 121.89587 -227.98024)
		(width 0.1143)
		(layer "In15.Cu")
		(net "GMI_CPU0_G1_CPU1_G3_TX_DN<10>")
	)
	(segment
		(start 347.840046 -221.38767)
		(end 347.840046 -221.128844)
		(width 0.1143)
		(layer "In15.Cu")
		(net "GMI_CPU0_G1_CPU1_G3_TX_DN<10>")
	)
	(segment
		(start 162.591242 -185.275474)
		(end 157.957012 -189.074552)
		(width 0.14224)
		(layer "In15.Cu")
		(net "GMI_CPU0_G1_CPU1_G3_TX_DN<10>")
	)
	(segment
		(start 121.925588 -240.923064)
		(end 121.89587 -240.940082)
		(width 0.1143)
		(layer "In15.Cu")
		(net "GMI_CPU0_G1_CPU1_G3_TX_DN<10>")
	)
	(segment
		(start 167.042084 -183.68391)
		(end 162.591242 -185.275474)
		(width 0.14224)
		(layer "In15.Cu")
		(net "GMI_CPU0_G1_CPU1_G3_TX_DN<10>")
	)
	(segment
		(start 121.92762 -239.301782)
		(end 121.926858 -239.30229)
		(width 0.1143)
		(layer "In15.Cu")
		(net "GMI_CPU0_G1_CPU1_G3_TX_DN<10>")
	)
	(segment
		(start 349.568008 -244.161564)
		(end 349.566992 -244.161056)
		(width 0.1143)
		(layer "In15.Cu")
		(net "GMI_CPU0_G1_CPU1_G3_TX_DN<10>")
	)
	(segment
		(start 349.129858 -225.549968)
		(end 349.10014 -225.53295)
		(width 0.1143)
		(layer "In15.Cu")
		(net "GMI_CPU0_G1_CPU1_G3_TX_DN<10>")
	)
	(segment
		(start 151.903176 -194.21475)
		(end 151.572976 -194.485514)
		(width 0.14224)
		(layer "In15.Cu")
		(net "GMI_CPU0_G1_CPU1_G3_TX_DN<10>")
	)
	(segment
		(start 347.794326 -221.083124)
		(end 347.794326 -219.482924)
		(width 0.14224)
		(layer "In15.Cu")
		(net "GMI_CPU0_G1_CPU1_G3_TX_DN<10>")
	)
	(segment
		(start 349.565468 -232.819956)
		(end 349.564452 -232.819448)
		(width 0.1143)
		(layer "In15.Cu")
		(net "GMI_CPU0_G1_CPU1_G3_TX_DN<10>")
	)
	(segment
		(start 349.56877 -244.162072)
		(end 349.568008 -244.161564)
		(width 0.1143)
		(layer "In15.Cu")
		(net "GMI_CPU0_G1_CPU1_G3_TX_DN<10>")
	)
	(segment
		(start 349.568008 -230.226616)
		(end 349.599758 -230.208328)
		(width 0.1143)
		(layer "In15.Cu")
		(net "GMI_CPU0_G1_CPU1_G3_TX_DN<10>")
	)
	(segment
		(start 121.967498 -232.798874)
		(end 121.92762 -232.821734)
		(width 0.1143)
		(layer "In15.Cu")
		(net "GMI_CPU0_G1_CPU1_G3_TX_DN<10>")
	)
	(segment
		(start 121.924318 -230.224838)
		(end 121.926858 -230.226362)
		(width 0.1143)
		(layer "In15.Cu")
		(net "GMI_CPU0_G1_CPU1_G3_TX_DN<10>")
	)
	(segment
		(start 349.568008 -239.946688)
		(end 349.56877 -239.94618)
		(width 0.1143)
		(layer "In15.Cu")
		(net "GMI_CPU0_G1_CPU1_G3_TX_DN<10>")
	)
	(segment
		(start 121.92762 -243.186966)
		(end 121.93016 -243.188744)
		(width 0.1143)
		(layer "In15.Cu")
		(net "GMI_CPU0_G1_CPU1_G3_TX_DN<10>")
	)
	(segment
		(start 121.925588 -241.565684)
		(end 121.926858 -241.566446)
		(width 0.1143)
		(layer "In15.Cu")
		(net "GMI_CPU0_G1_CPU1_G3_TX_DN<10>")
	)
	(segment
		(start 349.568008 -232.82148)
		(end 349.566992 -232.820972)
		(width 0.1143)
		(layer "In15.Cu")
		(net "GMI_CPU0_G1_CPU1_G3_TX_DN<10>")
	)
	(segment
		(start 121.924064 -235.084874)
		(end 121.925588 -235.085636)
		(width 0.1143)
		(layer "In15.Cu")
		(net "GMI_CPU0_G1_CPU1_G3_TX_DN<10>")
	)
	(segment
		(start 121.923556 -242.544092)
		(end 121.92254 -242.5446)
		(width 0.1143)
		(layer "In15.Cu")
		(net "GMI_CPU0_G1_CPU1_G3_TX_DN<10>")
	)
	(segment
		(start 157.938978 -189.25667)
		(end 157.61462 -189.522862)
		(width 0.14224)
		(layer "In15.Cu")
		(net "GMI_CPU0_G1_CPU1_G3_TX_DN<10>")
	)
	(segment
		(start 145.905728 -198.495158)
		(end 145.125186 -198.731886)
		(width 0.14224)
		(layer "In15.Cu")
		(net "GMI_CPU0_G1_CPU1_G3_TX_DN<10>")
	)
	(segment
		(start 349.528892 -243.209572)
		(end 349.568008 -243.186712)
		(width 0.1143)
		(layer "In15.Cu")
		(net "GMI_CPU0_G1_CPU1_G3_TX_DN<10>")
	)
	(segment
		(start 349.568008 -246.426736)
		(end 349.56877 -246.426228)
		(width 0.1143)
		(layer "In15.Cu")
		(net "GMI_CPU0_G1_CPU1_G3_TX_DN<10>")
	)
	(segment
		(start 121.96699 -226.31908)
		(end 121.926096 -226.342702)
		(width 0.1143)
		(layer "In15.Cu")
		(net "GMI_CPU0_G1_CPU1_G3_TX_DN<10>")
	)
	(segment
		(start 348.120716 -222.270066)
		(end 348.1197 -222.269304)
		(width 0.1143)
		(layer "In15.Cu")
		(net "GMI_CPU0_G1_CPU1_G3_TX_DN<10>")
	)
	(segment
		(start 121.926858 -239.30229)
		(end 121.925588 -239.303052)
		(width 0.1143)
		(layer "In15.Cu")
		(net "GMI_CPU0_G1_CPU1_G3_TX_DN<10>")
	)
	(segment
		(start 121.92762 -238.32693)
		(end 121.93016 -238.328708)
		(width 0.1143)
		(layer "In15.Cu")
		(net "GMI_CPU0_G1_CPU1_G3_TX_DN<10>")
	)
	(segment
		(start 154.519884 -192.06972)
		(end 154.189684 -192.340484)
		(width 0.14224)
		(layer "In15.Cu")
		(net "GMI_CPU0_G1_CPU1_G3_TX_DN<10>")
	)
	(segment
		(start 121.966482 -223.769682)
		(end 121.994422 -223.789748)
		(width 0.1143)
		(layer "In15.Cu")
		(net "GMI_CPU0_G1_CPU1_G3_TX_DN<10>")
	)
	(segment
		(start 349.57004 -239.945418)
		(end 349.57258 -239.944148)
		(width 0.1143)
		(layer "In15.Cu")
		(net "GMI_CPU0_G1_CPU1_G3_TX_DN<10>")
	)
	(segment
		(start 349.568262 -226.341686)
		(end 349.529146 -226.318826)
		(width 0.1143)
		(layer "In15.Cu")
		(net "GMI_CPU0_G1_CPU1_G3_TX_DN<10>")
	)
	(segment
		(start 121.89587 -231.828594)
		(end 121.924064 -231.84485)
		(width 0.1143)
		(layer "In15.Cu")
		(net "GMI_CPU0_G1_CPU1_G3_TX_DN<10>")
	)
	(segment
		(start 121.89587 -246.408702)
		(end 121.924064 -246.424958)
		(width 0.1143)
		(layer "In15.Cu")
		(net "GMI_CPU0_G1_CPU1_G3_TX_DN<10>")
	)
	(segment
		(start 156.259784 -190.465964)
		(end 156.24175 -190.648082)
		(width 0.14224)
		(layer "In15.Cu")
		(net "GMI_CPU0_G1_CPU1_G3_TX_DN<10>")
	)
	(segment
		(start 146.793712 -198.226172)
		(end 145.905982 -198.495158)
		(width 0.14224)
		(layer "In15.Cu")
		(net "GMI_CPU0_G1_CPU1_G3_TX_DN<10>")
	)
	(segment
		(start 121.92762 -229.581964)
		(end 121.894092 -229.601522)
		(width 0.1143)
		(layer "In15.Cu")
		(net "GMI_CPU0_G1_CPU1_G3_TX_DN<10>")
	)
	(segment
		(start 153.647648 -192.78473)
		(end 153.317448 -193.055494)
		(width 0.14224)
		(layer "In15.Cu")
		(net "GMI_CPU0_G1_CPU1_G3_TX_DN<10>")
	)
	(segment
		(start 349.097092 -225.531172)
		(end 349.094552 -225.529648)
		(width 0.1143)
		(layer "In15.Cu")
		(net "GMI_CPU0_G1_CPU1_G3_TX_DN<10>")
	)
	(segment
		(start 121.994422 -224.679256)
		(end 121.966482 -224.699322)
		(width 0.1143)
		(layer "In15.Cu")
		(net "GMI_CPU0_G1_CPU1_G3_TX_DN<10>")
	)
	(segment
		(start 121.986294 -244.124988)
		(end 121.967244 -244.138958)
		(width 0.1143)
		(layer "In15.Cu")
		(net "GMI_CPU0_G1_CPU1_G3_TX_DN<10>")
	)
	(segment
		(start 348.658688 -223.119442)
		(end 348.628208 -223.101662)
		(width 0.1143)
		(layer "In15.Cu")
		(net "GMI_CPU0_G1_CPU1_G3_TX_DN<10>")
	)
	(segment
		(start 349.066612 -225.513392)
		(end 349.06585 -225.512884)
		(width 0.1143)
		(layer "In15.Cu")
		(net "GMI_CPU0_G1_CPU1_G3_TX_DN<10>")
	)
	(segment
		(start 121.89587 -233.448606)
		(end 121.924064 -233.464862)
		(width 0.1143)
		(layer "In15.Cu")
		(net "GMI_CPU0_G1_CPU1_G3_TX_DN<10>")
	)
	(segment
		(start 349.568008 -245.781576)
		(end 349.566992 -245.781068)
		(width 0.1143)
		(layer "In15.Cu")
		(net "GMI_CPU0_G1_CPU1_G3_TX_DN<10>")
	)
	(segment
		(start 152.794462 -193.3067)
		(end 152.775412 -193.49974)
		(width 0.14224)
		(layer "In15.Cu")
		(net "GMI_CPU0_G1_CPU1_G3_TX_DN<10>")
	)
	(segment
		(start 345.421712 -214.469218)
		(end 312.968386 -187.859162)
		(width 0.14224)
		(layer "In15.Cu")
		(net "GMI_CPU0_G1_CPU1_G3_TX_DN<10>")
	)
	(segment
		(start 121.92762 -231.846882)
		(end 121.93016 -231.84866)
		(width 0.1143)
		(layer "In15.Cu")
		(net "GMI_CPU0_G1_CPU1_G3_TX_DN<10>")
	)
	(segment
		(start 121.927366 -230.227124)
		(end 121.928128 -230.227632)
		(width 0.1143)
		(layer "In15.Cu")
		(net "GMI_CPU0_G1_CPU1_G3_TX_DN<10>")
	)
	(segment
		(start 349.56877 -235.086144)
		(end 349.57004 -235.085382)
		(width 0.1143)
		(layer "In15.Cu")
		(net "GMI_CPU0_G1_CPU1_G3_TX_DN<10>")
	)
	(segment
		(start 121.967244 -227.00996)
		(end 121.9835 -227.021898)
		(width 0.1143)
		(layer "In15.Cu")
		(net "GMI_CPU0_G1_CPU1_G3_TX_DN<10>")
	)
	(segment
		(start 121.92762 -240.921794)
		(end 121.926858 -240.922302)
		(width 0.1143)
		(layer "In15.Cu")
		(net "GMI_CPU0_G1_CPU1_G3_TX_DN<10>")
	)
	(segment
		(start 157.432502 -189.504574)
		(end 157.108398 -189.770258)
		(width 0.14224)
		(layer "In15.Cu")
		(net "GMI_CPU0_G1_CPU1_G3_TX_DN<10>")
	)
	(segment
		(start 121.926858 -239.946434)
		(end 121.92762 -239.946942)
		(width 0.1143)
		(layer "In15.Cu")
		(net "GMI_CPU0_G1_CPU1_G3_TX_DN<10>")
	)
	(segment
		(start 121.926096 -242.542568)
		(end 121.925334 -242.543076)
		(width 0.1143)
		(layer "In15.Cu")
		(net "GMI_CPU0_G1_CPU1_G3_TX_DN<10>")
	)
	(segment
		(start 349.564452 -240.919508)
		(end 349.528892 -240.89868)
		(width 0.1143)
		(layer "In15.Cu")
		(net "GMI_CPU0_G1_CPU1_G3_TX_DN<10>")
	)
	(segment
		(start 121.92762 -233.466894)
		(end 121.963942 -233.487976)
		(width 0.1143)
		(layer "In15.Cu")
		(net "GMI_CPU0_G1_CPU1_G3_TX_DN<10>")
	)
	(segment
		(start 349.528892 -239.969548)
		(end 349.568008 -239.946688)
		(width 0.1143)
		(layer "In15.Cu")
		(net "GMI_CPU0_G1_CPU1_G3_TX_DN<10>")
	)
	(segment
		(start 349.566992 -245.781068)
		(end 349.565468 -245.780052)
		(width 0.1143)
		(layer "In15.Cu")
		(net "GMI_CPU0_G1_CPU1_G3_TX_DN<10>")
	)
	(segment
		(start 121.92762 -241.566954)
		(end 121.930414 -241.568732)
		(width 0.1143)
		(layer "In15.Cu")
		(net "GMI_CPU0_G1_CPU1_G3_TX_DN<10>")
	)
	(segment
		(start 151.922226 -194.02171)
		(end 151.903176 -194.21475)
		(width 0.14224)
		(layer "In15.Cu")
		(net "GMI_CPU0_G1_CPU1_G3_TX_DN<10>")
	)
	(segment
		(start 121.925588 -224.723198)
		(end 121.89587 -224.740216)
		(width 0.1143)
		(layer "In15.Cu")
		(net "GMI_CPU0_G1_CPU1_G3_TX_DN<10>")
	)
	(segment
		(start 349.568008 -242.541552)
		(end 349.566992 -242.541044)
		(width 0.1143)
		(layer "In15.Cu")
		(net "GMI_CPU0_G1_CPU1_G3_TX_DN<10>")
	)
	(segment
		(start 157.108398 -189.770258)
		(end 157.090364 -189.952376)
		(width 0.14224)
		(layer "In15.Cu")
		(net "GMI_CPU0_G1_CPU1_G3_TX_DN<10>")
	)
	(segment
		(start 121.92762 -223.747076)
		(end 121.930414 -223.748854)
		(width 0.1143)
		(layer "In15.Cu")
		(net "GMI_CPU0_G1_CPU1_G3_TX_DN<10>")
	)
	(segment
		(start 121.967498 -231.869742)
		(end 121.981976 -231.880664)
		(width 0.1143)
		(layer "In15.Cu")
		(net "GMI_CPU0_G1_CPU1_G3_TX_DN<10>")
	)
	(segment
		(start 121.926858 -231.846374)
		(end 121.92762 -231.846882)
		(width 0.1143)
		(layer "In15.Cu")
		(net "GMI_CPU0_G1_CPU1_G3_TX_DN<10>")
	)
	(segment
		(start 349.568008 -239.301528)
		(end 349.566992 -239.30102)
		(width 0.1143)
		(layer "In15.Cu")
		(net "GMI_CPU0_G1_CPU1_G3_TX_DN<10>")
	)
	(segment
		(start 123.974098 -216.074498)
		(end 121.76125 -219.878148)
		(width 0.14224)
		(layer "In15.Cu")
		(net "GMI_CPU0_G1_CPU1_G3_TX_DN<10>")
	)
	(segment
		(start 121.92762 -236.061758)
		(end 121.89587 -236.080046)
		(width 0.1143)
		(layer "In15.Cu")
		(net "GMI_CPU0_G1_CPU1_G3_TX_DN<10>")
	)
	(segment
		(start 349.528892 -235.109512)
		(end 349.568008 -235.086652)
		(width 0.1143)
		(layer "In15.Cu")
		(net "GMI_CPU0_G1_CPU1_G3_TX_DN<10>")
	)
	(segment
		(start 348.738952 -247.724168)
		(end 348.821756 -247.641364)
		(width 0.1143)
		(layer "In15.Cu")
		(net "GMI_CPU0_G1_CPU1_G3_TX_DN<10>")
	)
	(segment
		(start 121.926858 -225.36658)
		(end 121.92762 -225.367088)
		(width 0.1143)
		(layer "In15.Cu")
		(net "GMI_CPU0_G1_CPU1_G3_TX_DN<10>")
	)
	(segment
		(start 121.925334 -226.34321)
		(end 121.924318 -226.343718)
		(width 0.1143)
		(layer "In15.Cu")
		(net "GMI_CPU0_G1_CPU1_G3_TX_DN<10>")
	)
	(segment
		(start 121.924318 -242.543584)
		(end 121.923556 -242.544092)
		(width 0.1143)
		(layer "In15.Cu")
		(net "GMI_CPU0_G1_CPU1_G3_TX_DN<10>")
	)
	(segment
		(start 349.566992 -234.440984)
		(end 349.565468 -234.439968)
		(width 0.1143)
		(layer "In15.Cu")
		(net "GMI_CPU0_G1_CPU1_G3_TX_DN<10>")
	)
	(segment
		(start 121.967244 -244.138958)
		(end 121.92762 -244.161818)
		(width 0.1143)
		(layer "In15.Cu")
		(net "GMI_CPU0_G1_CPU1_G3_TX_DN<10>")
	)
	(segment
		(start 121.925588 -223.103186)
		(end 121.89587 -223.120204)
		(width 0.1143)
		(layer "In15.Cu")
		(net "GMI_CPU0_G1_CPU1_G3_TX_DN<10>")
	)
	(segment
		(start 121.921778 -226.345242)
		(end 121.920762 -226.34575)
		(width 0.1143)
		(layer "In15.Cu")
		(net "GMI_CPU0_G1_CPU1_G3_TX_DN<10>")
	)
	(segment
		(start 121.76125 -219.878148)
		(end 121.76125 -220.991938)
		(width 0.14224)
		(layer "In15.Cu")
		(net "GMI_CPU0_G1_CPU1_G3_TX_DN<10>")
	)
	(segment
		(start 121.92762 -244.161818)
		(end 121.926858 -244.162326)
		(width 0.1143)
		(layer "In15.Cu")
		(net "GMI_CPU0_G1_CPU1_G3_TX_DN<10>")
	)
	(segment
		(start 121.926858 -244.162326)
		(end 121.925588 -244.163088)
		(width 0.1143)
		(layer "In15.Cu")
		(net "GMI_CPU0_G1_CPU1_G3_TX_DN<10>")
	)
	(segment
		(start 121.9835 -227.927154)
		(end 121.967244 -227.939092)
		(width 0.1143)
		(layer "In15.Cu")
		(net "GMI_CPU0_G1_CPU1_G3_TX_DN<10>")
	)
	(segment
		(start 121.921778 -242.545108)
		(end 121.89587 -242.560094)
		(width 0.1143)
		(layer "In15.Cu")
		(net "GMI_CPU0_G1_CPU1_G3_TX_DN<10>")
	)
	(segment
		(start 121.925588 -238.32566)
		(end 121.926858 -238.326422)
		(width 0.1143)
		(layer "In15.Cu")
		(net "GMI_CPU0_G1_CPU1_G3_TX_DN<10>")
	)
	(segment
		(start 310.505602 -186.464956)
		(end 308.421786 -185.28538)
		(width 0.14224)
		(layer "In15.Cu")
		(net "GMI_CPU0_G1_CPU1_G3_TX_DN<10>")
	)
	(segment
		(start 152.252172 -193.7512)
		(end 151.922226 -194.02171)
		(width 0.14224)
		(layer "In15.Cu")
		(net "GMI_CPU0_G1_CPU1_G3_TX_DN<10>")
	)
	(segment
		(start 349.56877 -239.302036)
		(end 349.568008 -239.301528)
		(width 0.1143)
		(layer "In15.Cu")
		(net "GMI_CPU0_G1_CPU1_G3_TX_DN<10>")
	)
	(segment
		(start 155.06192 -191.625474)
		(end 154.86888 -191.60617)
		(width 0.14224)
		(layer "In15.Cu")
		(net "GMI_CPU0_G1_CPU1_G3_TX_DN<10>")
	)
	(segment
		(start 121.926858 -246.426482)
		(end 121.92762 -246.42699)
		(width 0.1143)
		(layer "In15.Cu")
		(net "GMI_CPU0_G1_CPU1_G3_TX_DN<10>")
	)
	(segment
		(start 121.92 -226.346258)
		(end 121.918984 -226.346766)
		(width 0.1143)
		(layer "In15.Cu")
		(net "GMI_CPU0_G1_CPU1_G3_TX_DN<10>")
	)
	(segment
		(start 122.39752 -247.236996)
		(end 122.436636 -247.259856)
		(width 0.1143)
		(layer "In15.Cu")
		(net "GMI_CPU0_G1_CPU1_G3_TX_DN<10>")
	)
	(segment
		(start 121.92762 -226.9871)
		(end 121.93016 -226.988878)
		(width 0.1143)
		(layer "In15.Cu")
		(net "GMI_CPU0_G1_CPU1_G3_TX_DN<10>")
	)
	(segment
		(start 121.925588 -246.42572)
		(end 121.926858 -246.426482)
		(width 0.1143)
		(layer "In15.Cu")
		(net "GMI_CPU0_G1_CPU1_G3_TX_DN<10>")
	)
	(segment
		(start 121.926858 -224.722436)
		(end 121.925588 -224.723198)
		(width 0.1143)
		(layer "In15.Cu")
		(net "GMI_CPU0_G1_CPU1_G3_TX_DN<10>")
	)
	(segment
		(start 153.124408 -193.03619)
		(end 152.794462 -193.3067)
		(width 0.14224)
		(layer "In15.Cu")
		(net "GMI_CPU0_G1_CPU1_G3_TX_DN<10>")
	)
	(segment
		(start 121.89587 -226.968812)
		(end 121.924064 -226.985068)
		(width 0.1143)
		(layer "In15.Cu")
		(net "GMI_CPU0_G1_CPU1_G3_TX_DN<10>")
	)
	(segment
		(start 349.565468 -245.780052)
		(end 349.528892 -245.758716)
		(width 0.1143)
		(layer "In15.Cu")
		(net "GMI_CPU0_G1_CPU1_G3_TX_DN<10>")
	)
	(segment
		(start 157.957012 -189.074552)
		(end 157.938978 -189.25667)
		(width 0.14224)
		(layer "In15.Cu")
		(net "GMI_CPU0_G1_CPU1_G3_TX_DN<10>")
	)
	(segment
		(start 121.924064 -231.84485)
		(end 121.925588 -231.845612)
		(width 0.1143)
		(layer "In15.Cu")
		(net "GMI_CPU0_G1_CPU1_G3_TX_DN<10>")
	)
	(segment
		(start 121.89587 -225.3488)
		(end 121.924064 -225.365056)
		(width 0.1143)
		(layer "In15.Cu")
		(net "GMI_CPU0_G1_CPU1_G3_TX_DN<10>")
	)
	(segment
		(start 349.56877 -231.84612)
		(end 349.57004 -231.845358)
		(width 0.1143)
		(layer "In15.Cu")
		(net "GMI_CPU0_G1_CPU1_G3_TX_DN<10>")
	)
	(segment
		(start 349.57258 -233.4641)
		(end 349.599758 -233.448352)
		(width 0.1143)
		(layer "In15.Cu")
		(net "GMI_CPU0_G1_CPU1_G3_TX_DN<10>")
	)
	(segment
		(start 121.930414 -244.808756)
		(end 121.966228 -244.82933)
		(width 0.1143)
		(layer "In15.Cu")
		(net "GMI_CPU0_G1_CPU1_G3_TX_DN<10>")
	)
	(segment
		(start 349.565468 -234.439968)
		(end 349.564452 -234.43946)
		(width 0.1143)
		(layer "In15.Cu")
		(net "GMI_CPU0_G1_CPU1_G3_TX_DN<10>")
	)
	(segment
		(start 349.56877 -240.922048)
		(end 349.568008 -240.92154)
		(width 0.1143)
		(layer "In15.Cu")
		(net "GMI_CPU0_G1_CPU1_G3_TX_DN<10>")
	)
	(segment
		(start 121.925588 -239.303052)
		(end 121.89587 -239.32007)
		(width 0.1143)
		(layer "In15.Cu")
		(net "GMI_CPU0_G1_CPU1_G3_TX_DN<10>")
	)
	(segment
		(start 121.926858 -236.70641)
		(end 121.92762 -236.706918)
		(width 0.1143)
		(layer "In15.Cu")
		(net "GMI_CPU0_G1_CPU1_G3_TX_DN<10>")
	)
	(segment
		(start 349.598742 -227.979478)
		(end 349.568262 -227.961698)
		(width 0.1143)
		(layer "In15.Cu")
		(net "GMI_CPU0_G1_CPU1_G3_TX_DN<10>")
	)
	(segment
		(start 347.87586 -221.80423)
		(end 347.87586 -221.423484)
		(width 0.1143)
		(layer "In15.Cu")
		(net "GMI_CPU0_G1_CPU1_G3_TX_DN<10>")
	)
	(segment
		(start 121.925588 -243.185696)
		(end 121.926858 -243.186458)
		(width 0.1143)
		(layer "In15.Cu")
		(net "GMI_CPU0_G1_CPU1_G3_TX_DN<10>")
	)
	(segment
		(start 121.926858 -226.986592)
		(end 121.92762 -226.9871)
		(width 0.1143)
		(layer "In15.Cu")
		(net "GMI_CPU0_G1_CPU1_G3_TX_DN<10>")
	)
	(segment
		(start 349.565468 -240.920016)
		(end 349.564452 -240.919508)
		(width 0.1143)
		(layer "In15.Cu")
		(net "GMI_CPU0_G1_CPU1_G3_TX_DN<10>")
	)
	(segment
		(start 349.56877 -243.186204)
		(end 349.57004 -243.185442)
		(width 0.1143)
		(layer "In15.Cu")
		(net "GMI_CPU0_G1_CPU1_G3_TX_DN<10>")
	)
	(segment
		(start 349.568008 -243.186712)
		(end 349.56877 -243.186204)
		(width 0.1143)
		(layer "In15.Cu")
		(net "GMI_CPU0_G1_CPU1_G3_TX_DN<10>")
	)
	(segment
		(start 349.57004 -233.46537)
		(end 349.57258 -233.4641)
		(width 0.1143)
		(layer "In15.Cu")
		(net "GMI_CPU0_G1_CPU1_G3_TX_DN<10>")
	)
	(segment
		(start 152.775412 -193.49974)
		(end 152.445212 -193.770504)
		(width 0.14224)
		(layer "In15.Cu")
		(net "GMI_CPU0_G1_CPU1_G3_TX_DN<10>")
	)
	(segment
		(start 347.87586 -221.423484)
		(end 347.840046 -221.38767)
		(width 0.1143)
		(layer "In15.Cu")
		(net "GMI_CPU0_G1_CPU1_G3_TX_DN<10>")
	)
	(segment
		(start 306.652168 -184.474866)
		(end 302.888904 -184.474866)
		(width 0.14224)
		(layer "In15.Cu")
		(net "GMI_CPU0_G1_CPU1_G3_TX_DN<10>")
	)
	(segment
		(start 121.96699 -239.279176)
		(end 121.92762 -239.301782)
		(width 0.1143)
		(layer "In15.Cu")
		(net "GMI_CPU0_G1_CPU1_G3_TX_DN<10>")
	)
	(segment
		(start 156.583888 -190.20028)
		(end 156.259784 -190.465964)
		(width 0.14224)
		(layer "In15.Cu")
		(net "GMI_CPU0_G1_CPU1_G3_TX_DN<10>")
	)
	(segment
		(start 349.098108 -225.53168)
		(end 349.097092 -225.531172)
		(width 0.1143)
		(layer "In15.Cu")
		(net "GMI_CPU0_G1_CPU1_G3_TX_DN<10>")
	)
	(segment
		(start 152.445212 -193.770504)
		(end 152.252172 -193.7512)
		(width 0.14224)
		(layer "In15.Cu")
		(net "GMI_CPU0_G1_CPU1_G3_TX_DN<10>")
	)
	(segment
		(start 121.924064 -243.184934)
		(end 121.925588 -243.185696)
		(width 0.1143)
		(layer "In15.Cu")
		(net "GMI_CPU0_G1_CPU1_G3_TX_DN<10>")
	)
	(segment
		(start 155.917392 -190.91402)
		(end 155.735274 -190.895986)
		(width 0.14224)
		(layer "In15.Cu")
		(net "GMI_CPU0_G1_CPU1_G3_TX_DN<10>")
	)
	(segment
		(start 310.505602 -186.465464)
		(end 310.505602 -186.464956)
		(width 0.14224)
		(layer "In15.Cu")
		(net "GMI_CPU0_G1_CPU1_G3_TX_DN<10>")
	)
	(segment
		(start 348.658688 -224.739454)
		(end 348.628208 -224.721674)
		(width 0.1143)
		(layer "In15.Cu")
		(net "GMI_CPU0_G1_CPU1_G3_TX_DN<10>")
	)
	(segment
		(start 349.529146 -227.009706)
		(end 349.568262 -226.986846)
		(width 0.1143)
		(layer "In15.Cu")
		(net "GMI_CPU0_G1_CPU1_G3_TX_DN<10>")
	)
	(segment
		(start 349.528892 -236.729524)
		(end 349.568008 -236.706664)
		(width 0.1143)
		(layer "In15.Cu")
		(net "GMI_CPU0_G1_CPU1_G3_TX_DN<10>")
	)
	(segment
		(start 349.568008 -231.201722)
		(end 349.528892 -231.178862)
		(width 0.1143)
		(layer "In15.Cu")
		(net "GMI_CPU0_G1_CPU1_G3_TX_DN<10>")
	)
	(segment
		(start 121.92762 -230.22687)
		(end 121.927366 -230.227124)
		(width 0.1143)
		(layer "In15.Cu")
		(net "GMI_CPU0_G1_CPU1_G3_TX_DN<10>")
	)
	(segment
		(start 121.925588 -233.465624)
		(end 121.926858 -233.466386)
		(width 0.1143)
		(layer "In15.Cu")
		(net "GMI_CPU0_G1_CPU1_G3_TX_DN<10>")
	)
	(segment
		(start 349.531178 -229.560374)
		(end 349.529146 -229.55885)
		(width 0.1143)
		(layer "In15.Cu")
		(net "GMI_CPU0_G1_CPU1_G3_TX_DN<10>")
	)
	(segment
		(start 121.93016 -231.84866)
		(end 121.967498 -231.869742)
		(width 0.1143)
		(layer "In15.Cu")
		(net "GMI_CPU0_G1_CPU1_G3_TX_DN<10>")
	)
	(segment
		(start 121.985278 -226.306126)
		(end 121.96699 -226.31908)
		(width 0.1143)
		(layer "In15.Cu")
		(net "GMI_CPU0_G1_CPU1_G3_TX_DN<10>")
	)
	(segment
		(start 121.925588 -231.845612)
		(end 121.926858 -231.846374)
		(width 0.1143)
		(layer "In15.Cu")
		(net "GMI_CPU0_G1_CPU1_G3_TX_DN<10>")
	)
	(segment
		(start 349.568008 -236.061504)
		(end 349.566992 -236.060996)
		(width 0.1143)
		(layer "In15.Cu")
		(net "GMI_CPU0_G1_CPU1_G3_TX_DN<10>")
	)
	(segment
		(start 121.926858 -241.566446)
		(end 121.92762 -241.566954)
		(width 0.1143)
		(layer "In15.Cu")
		(net "GMI_CPU0_G1_CPU1_G3_TX_DN<10>")
	)
	(segment
		(start 121.926858 -223.746568)
		(end 121.92762 -223.747076)
		(width 0.1143)
		(layer "In15.Cu")
		(net "GMI_CPU0_G1_CPU1_G3_TX_DN<10>")
	)
	(segment
		(start 121.925588 -225.365818)
		(end 121.926858 -225.36658)
		(width 0.1143)
		(layer "In15.Cu")
		(net "GMI_CPU0_G1_CPU1_G3_TX_DN<10>")
	)
	(segment
		(start 312.968386 -187.859162)
		(end 310.505602 -186.465464)
		(width 0.14224)
		(layer "In15.Cu")
		(net "GMI_CPU0_G1_CPU1_G3_TX_DN<10>")
	)
	(segment
		(start 348.189804 -222.309944)
		(end 348.121732 -222.270574)
		(width 0.1143)
		(layer "In15.Cu")
		(net "GMI_CPU0_G1_CPU1_G3_TX_DN<10>")
	)
	(segment
		(start 349.56877 -234.442)
		(end 349.568008 -234.441492)
		(width 0.1143)
		(layer "In15.Cu")
		(net "GMI_CPU0_G1_CPU1_G3_TX_DN<10>")
	)
	(segment
		(start 121.966228 -244.82933)
		(end 121.984008 -244.841776)
		(width 0.1143)
		(layer "In15.Cu")
		(net "GMI_CPU0_G1_CPU1_G3_TX_DN<10>")
	)
	(segment
		(start 121.89587 -236.68863)
		(end 121.924064 -236.704886)
		(width 0.1143)
		(layer "In15.Cu")
		(net "GMI_CPU0_G1_CPU1_G3_TX_DN<10>")
	)
	(segment
		(start 121.930414 -223.748854)
		(end 121.966482 -223.769682)
		(width 0.1143)
		(layer "In15.Cu")
		(net "GMI_CPU0_G1_CPU1_G3_TX_DN<10>")
	)
	(segment
		(start 121.96699 -238.349536)
		(end 121.98858 -238.365284)
		(width 0.1143)
		(layer "In15.Cu")
		(net "GMI_CPU0_G1_CPU1_G3_TX_DN<10>")
	)
	(segment
		(start 349.564452 -236.059472)
		(end 349.528892 -236.038644)
		(width 0.1143)
		(layer "In15.Cu")
		(net "GMI_CPU0_G1_CPU1_G3_TX_DN<10>")
	)
	(segment
		(start 121.925588 -232.823004)
		(end 121.89587 -232.840022)
		(width 0.1143)
		(layer "In15.Cu")
		(net "GMI_CPU0_G1_CPU1_G3_TX_DN<10>")
	)
	(segment
		(start 122.222514 -246.922798)
		(end 122.222514 -246.934228)
		(width 0.1143)
		(layer "In15.Cu")
		(net "GMI_CPU0_G1_CPU1_G3_TX_DN<10>")
	)
	(segment
		(start 349.564452 -239.299496)
		(end 349.528892 -239.278668)
		(width 0.1143)
		(layer "In15.Cu")
		(net "GMI_CPU0_G1_CPU1_G3_TX_DN<10>")
	)
	(segment
		(start 121.926858 -237.682278)
		(end 121.925588 -237.68304)
		(width 0.1143)
		(layer "In15.Cu")
		(net "GMI_CPU0_G1_CPU1_G3_TX_DN<10>")
	)
	(segment
		(start 348.628208 -223.746822)
		(end 348.658688 -223.729042)
		(width 0.1143)
		(layer "In15.Cu")
		(net "GMI_CPU0_G1_CPU1_G3_TX_DN<10>")
	)
	(segment
		(start 349.568008 -240.92154)
		(end 349.566992 -240.921032)
		(width 0.1143)
		(layer "In15.Cu")
		(net "GMI_CPU0_G1_CPU1_G3_TX_DN<10>")
	)
	(segment
		(start 349.599758 -234.45978)
		(end 349.56877 -234.442)
		(width 0.1143)
		(layer "In15.Cu")
		(net "GMI_CPU0_G1_CPU1_G3_TX_DN<10>")
	)
	(segment
		(start 121.89587 -223.728788)
		(end 121.924064 -223.745044)
		(width 0.1143)
		(layer "In15.Cu")
		(net "GMI_CPU0_G1_CPU1_G3_TX_DN<10>")
	)
	(segment
		(start 151.572976 -194.485514)
		(end 151.379936 -194.46621)
		(width 0.14224)
		(layer "In15.Cu")
		(net "GMI_CPU0_G1_CPU1_G3_TX_DN<10>")
	)
	(segment
		(start 349.568008 -231.846628)
		(end 349.56877 -231.84612)
		(width 0.1143)
		(layer "In15.Cu")
		(net "GMI_CPU0_G1_CPU1_G3_TX_DN<10>")
	)
	(segment
		(start 349.599758 -239.319816)
		(end 349.56877 -239.302036)
		(width 0.1143)
		(layer "In15.Cu")
		(net "GMI_CPU0_G1_CPU1_G3_TX_DN<10>")
	)
	(segment
		(start 349.564452 -232.819448)
		(end 349.528892 -232.79862)
		(width 0.1143)
		(layer "In15.Cu")
		(net "GMI_CPU0_G1_CPU1_G3_TX_DN<10>")
	)
	(segment
		(start 121.926096 -226.342702)
		(end 121.925334 -226.34321)
		(width 0.1143)
		(layer "In15.Cu")
		(net "GMI_CPU0_G1_CPU1_G3_TX_DN<10>")
	)
	(segment
		(start 121.92254 -242.5446)
		(end 121.921778 -242.545108)
		(width 0.1143)
		(layer "In15.Cu")
		(net "GMI_CPU0_G1_CPU1_G3_TX_DN<10>")
	)
	(segment
		(start 349.094552 -225.529648)
		(end 349.09379 -225.52914)
		(width 0.1143)
		(layer "In15.Cu")
		(net "GMI_CPU0_G1_CPU1_G3_TX_DN<10>")
	)
	(segment
		(start 349.600774 -229.600506)
		(end 349.568262 -229.58171)
		(width 0.1143)
		(layer "In15.Cu")
		(net "GMI_CPU0_G1_CPU1_G3_TX_DN<10>")
	)
	(arc
		(start 121.985278 -225.403156)
		(mid 122.216626 -225.854694)
		(end 121.985278 -226.306126)
		(width 0.1143)
		(layer "In15.Cu")
		(net "GMI_CPU0_G1_CPU1_G3_TX_DN<10>")
	)
	(arc
		(start 348.1197 -222.269304)
		(mid 347.940507 -222.066794)
		(end 347.87586 -221.80423)
		(width 0.1143)
		(layer "In15.Cu")
		(net "GMI_CPU0_G1_CPU1_G3_TX_DN<10>")
	)
	(arc
		(start 349.599758 -231.82834)
		(mid 349.714434 -231.695006)
		(end 349.755714 -231.524048)
		(width 0.1143)
		(layer "In15.Cu")
		(net "GMI_CPU0_G1_CPU1_G3_TX_DN<10>")
	)
	(arc
		(start 349.528892 -231.178862)
		(mid 349.350079 -230.976512)
		(end 349.28556 -230.714296)
		(width 0.1143)
		(layer "In15.Cu")
		(net "GMI_CPU0_G1_CPU1_G3_TX_DN<10>")
	)
	(arc
		(start 121.89587 -224.740216)
		(mid 121.739942 -225.044508)
		(end 121.89587 -225.3488)
		(width 0.1143)
		(layer "In15.Cu")
		(net "GMI_CPU0_G1_CPU1_G3_TX_DN<10>")
	)
	(arc
		(start 121.941844 -246.435118)
		(mid 122.147297 -246.641473)
		(end 122.222514 -246.922798)
		(width 0.1143)
		(layer "In15.Cu")
		(net "GMI_CPU0_G1_CPU1_G3_TX_DN<10>")
	)
	(arc
		(start 121.894092 -231.221534)
		(mid 121.780685 -231.354423)
		(end 121.739914 -231.524302)
		(width 0.1143)
		(layer "In15.Cu")
		(net "GMI_CPU0_G1_CPU1_G3_TX_DN<10>")
	)
	(arc
		(start 121.9835 -227.021898)
		(mid 122.21525 -227.474526)
		(end 121.9835 -227.927154)
		(width 0.1143)
		(layer "In15.Cu")
		(net "GMI_CPU0_G1_CPU1_G3_TX_DN<10>")
	)
	(arc
		(start 349.598742 -226.969066)
		(mid 349.755719 -226.664266)
		(end 349.598742 -226.359466)
		(width 0.1143)
		(layer "In15.Cu")
		(net "GMI_CPU0_G1_CPU1_G3_TX_DN<10>")
	)
	(arc
		(start 121.963942 -233.487976)
		(mid 121.971091 -233.492876)
		(end 121.978166 -233.497882)
		(width 0.1143)
		(layer "In15.Cu")
		(net "GMI_CPU0_G1_CPU1_G3_TX_DN<10>")
	)
	(arc
		(start 349.529146 -226.318826)
		(mid 349.350333 -226.116476)
		(end 349.285814 -225.85426)
		(width 0.1143)
		(layer "In15.Cu")
		(net "GMI_CPU0_G1_CPU1_G3_TX_DN<10>")
	)
	(arc
		(start 349.599758 -233.448352)
		(mid 349.755686 -233.14406)
		(end 349.599758 -232.839768)
		(width 0.1143)
		(layer "In15.Cu")
		(net "GMI_CPU0_G1_CPU1_G3_TX_DN<10>")
	)
	(arc
		(start 121.89587 -234.460034)
		(mid 121.739942 -234.764326)
		(end 121.89587 -235.068618)
		(width 0.1143)
		(layer "In15.Cu")
		(net "GMI_CPU0_G1_CPU1_G3_TX_DN<10>")
	)
	(arc
		(start 349.599758 -230.208328)
		(mid 349.714434 -230.074994)
		(end 349.755714 -229.904036)
		(width 0.1143)
		(layer "In15.Cu")
		(net "GMI_CPU0_G1_CPU1_G3_TX_DN<10>")
	)
	(arc
		(start 121.994422 -223.789748)
		(mid 122.222422 -224.234502)
		(end 121.994422 -224.679256)
		(width 0.1143)
		(layer "In15.Cu")
		(net "GMI_CPU0_G1_CPU1_G3_TX_DN<10>")
	)
	(arc
		(start 348.589092 -223.078802)
		(mid 348.410279 -222.876452)
		(end 348.34576 -222.614236)
		(width 0.1143)
		(layer "In15.Cu")
		(net "GMI_CPU0_G1_CPU1_G3_TX_DN<10>")
	)
	(arc
		(start 349.058992 -225.50882)
		(mid 348.880179 -225.30647)
		(end 348.81566 -225.044254)
		(width 0.1143)
		(layer "In15.Cu")
		(net "GMI_CPU0_G1_CPU1_G3_TX_DN<10>")
	)
	(arc
		(start 121.89587 -245.800118)
		(mid 121.739942 -246.10441)
		(end 121.89587 -246.408702)
		(width 0.1143)
		(layer "In15.Cu")
		(net "GMI_CPU0_G1_CPU1_G3_TX_DN<10>")
	)
	(arc
		(start 348.589092 -224.698814)
		(mid 348.345765 -224.234248)
		(end 348.589092 -223.769682)
		(width 0.1143)
		(layer "In15.Cu")
		(net "GMI_CPU0_G1_CPU1_G3_TX_DN<10>")
	)
	(arc
		(start 121.739914 -229.90429)
		(mid 121.781169 -230.075261)
		(end 121.89587 -230.208582)
		(width 0.1143)
		(layer "In15.Cu")
		(net "GMI_CPU0_G1_CPU1_G3_TX_DN<10>")
	)
	(arc
		(start 349.598742 -228.589078)
		(mid 349.755719 -228.284278)
		(end 349.598742 -227.979478)
		(width 0.1143)
		(layer "In15.Cu")
		(net "GMI_CPU0_G1_CPU1_G3_TX_DN<10>")
	)
	(arc
		(start 121.978166 -234.410758)
		(mid 121.971092 -234.415765)
		(end 121.963942 -234.420664)
		(width 0.1143)
		(layer "In15.Cu")
		(net "GMI_CPU0_G1_CPU1_G3_TX_DN<10>")
	)
	(arc
		(start 349.755714 -231.524048)
		(mid 349.714952 -231.354164)
		(end 349.601536 -231.22128)
		(width 0.1143)
		(layer "In15.Cu")
		(net "GMI_CPU0_G1_CPU1_G3_TX_DN<10>")
	)
	(arc
		(start 121.92762 -239.946942)
		(mid 122.208267 -240.434368)
		(end 121.92762 -240.921794)
		(width 0.1143)
		(layer "In15.Cu")
		(net "GMI_CPU0_G1_CPU1_G3_TX_DN<10>")
	)
	(arc
		(start 349.528892 -239.278668)
		(mid 349.285565 -238.814102)
		(end 349.528892 -238.349536)
		(width 0.1143)
		(layer "In15.Cu")
		(net "GMI_CPU0_G1_CPU1_G3_TX_DN<10>")
	)
	(arc
		(start 349.599758 -239.9284)
		(mid 349.755686 -239.624108)
		(end 349.599758 -239.319816)
		(width 0.1143)
		(layer "In15.Cu")
		(net "GMI_CPU0_G1_CPU1_G3_TX_DN<10>")
	)
	(arc
		(start 349.285814 -225.85426)
		(mid 349.244559 -225.683289)
		(end 349.129858 -225.549968)
		(width 0.1143)
		(layer "In15.Cu")
		(net "GMI_CPU0_G1_CPU1_G3_TX_DN<10>")
	)
	(arc
		(start 121.739914 -231.524302)
		(mid 121.781169 -231.695273)
		(end 121.89587 -231.828594)
		(width 0.1143)
		(layer "In15.Cu")
		(net "GMI_CPU0_G1_CPU1_G3_TX_DN<10>")
	)
	(arc
		(start 121.977404 -231.171242)
		(mid 121.970709 -231.176118)
		(end 121.963942 -231.180894)
		(width 0.1143)
		(layer "In15.Cu")
		(net "GMI_CPU0_G1_CPU1_G3_TX_DN<10>")
	)
	(arc
		(start 349.528892 -234.418632)
		(mid 349.285565 -233.954066)
		(end 349.528892 -233.4895)
		(width 0.1143)
		(layer "In15.Cu")
		(net "GMI_CPU0_G1_CPU1_G3_TX_DN<10>")
	)
	(arc
		(start 121.928128 -230.227632)
		(mid 122.13435 -230.433276)
		(end 122.209814 -230.71455)
		(width 0.1143)
		(layer "In15.Cu")
		(net "GMI_CPU0_G1_CPU1_G3_TX_DN<10>")
	)
	(arc
		(start 121.990866 -222.167196)
		(mid 122.220077 -222.61467)
		(end 121.990866 -223.062038)
		(width 0.1143)
		(layer "In15.Cu")
		(net "GMI_CPU0_G1_CPU1_G3_TX_DN<10>")
	)
	(arc
		(start 121.92762 -235.086906)
		(mid 122.208267 -235.574332)
		(end 121.92762 -236.061758)
		(width 0.1143)
		(layer "In15.Cu")
		(net "GMI_CPU0_G1_CPU1_G3_TX_DN<10>")
	)
	(arc
		(start 121.985278 -241.603022)
		(mid 122.216626 -242.05456)
		(end 121.985278 -242.505992)
		(width 0.1143)
		(layer "In15.Cu")
		(net "GMI_CPU0_G1_CPU1_G3_TX_DN<10>")
	)
	(arc
		(start 121.98858 -238.365284)
		(mid 122.218606 -238.814356)
		(end 121.98858 -239.263428)
		(width 0.1143)
		(layer "In15.Cu")
		(net "GMI_CPU0_G1_CPU1_G3_TX_DN<10>")
	)
	(arc
		(start 348.34576 -222.614236)
		(mid 348.304505 -222.443265)
		(end 348.189804 -222.309944)
		(width 0.1143)
		(layer "In15.Cu")
		(net "GMI_CPU0_G1_CPU1_G3_TX_DN<10>")
	)
	(arc
		(start 122.670062 -247.618758)
		(mid 122.672085 -247.630168)
		(end 122.673872 -247.641618)
		(width 0.1143)
		(layer "In15.Cu")
		(net "GMI_CPU0_G1_CPU1_G3_TX_DN<10>")
	)
	(arc
		(start 349.529146 -229.55885)
		(mid 349.285819 -229.094284)
		(end 349.529146 -228.629718)
		(width 0.1143)
		(layer "In15.Cu")
		(net "GMI_CPU0_G1_CPU1_G3_TX_DN<10>")
	)
	(arc
		(start 349.28556 -230.714296)
		(mid 349.350796 -230.450705)
		(end 349.531432 -230.247952)
		(width 0.1143)
		(layer "In15.Cu")
		(net "GMI_CPU0_G1_CPU1_G3_TX_DN<10>")
	)
	(arc
		(start 121.89587 -237.700058)
		(mid 121.739942 -238.00435)
		(end 121.89587 -238.308642)
		(width 0.1143)
		(layer "In15.Cu")
		(net "GMI_CPU0_G1_CPU1_G3_TX_DN<10>")
	)
	(arc
		(start 349.755714 -229.904036)
		(mid 349.714748 -229.73363)
		(end 349.600774 -229.600506)
		(width 0.1143)
		(layer "In15.Cu")
		(net "GMI_CPU0_G1_CPU1_G3_TX_DN<10>")
	)
	(arc
		(start 122.209814 -230.71455)
		(mid 122.148369 -230.970762)
		(end 121.977404 -231.171242)
		(width 0.1143)
		(layer "In15.Cu")
		(net "GMI_CPU0_G1_CPU1_G3_TX_DN<10>")
	)
	(arc
		(start 349.528892 -236.038644)
		(mid 349.285565 -235.574078)
		(end 349.528892 -235.109512)
		(width 0.1143)
		(layer "In15.Cu")
		(net "GMI_CPU0_G1_CPU1_G3_TX_DN<10>")
	)
	(arc
		(start 121.89587 -244.180106)
		(mid 121.739942 -244.484398)
		(end 121.89587 -244.78869)
		(width 0.1143)
		(layer "In15.Cu")
		(net "GMI_CPU0_G1_CPU1_G3_TX_DN<10>")
	)
	(arc
		(start 121.89587 -242.560094)
		(mid 121.739942 -242.864386)
		(end 121.89587 -243.168678)
		(width 0.1143)
		(layer "In15.Cu")
		(net "GMI_CPU0_G1_CPU1_G3_TX_DN<10>")
	)
	(arc
		(start 349.528892 -240.89868)
		(mid 349.285565 -240.434114)
		(end 349.528892 -239.969548)
		(width 0.1143)
		(layer "In15.Cu")
		(net "GMI_CPU0_G1_CPU1_G3_TX_DN<10>")
	)
	(arc
		(start 349.599758 -236.688376)
		(mid 349.755686 -236.384084)
		(end 349.599758 -236.079792)
		(width 0.1143)
		(layer "In15.Cu")
		(net "GMI_CPU0_G1_CPU1_G3_TX_DN<10>")
	)
	(arc
		(start 122.53341 -247.344946)
		(mid 122.620632 -247.472424)
		(end 122.670062 -247.618758)
		(width 0.1143)
		(layer "In15.Cu")
		(net "GMI_CPU0_G1_CPU1_G3_TX_DN<10>")
	)
	(arc
		(start 122.436636 -247.259856)
		(mid 122.487448 -247.299642)
		(end 122.53341 -247.344946)
		(width 0.1143)
		(layer "In15.Cu")
		(net "GMI_CPU0_G1_CPU1_G3_TX_DN<10>")
	)
	(arc
		(start 349.528892 -237.658656)
		(mid 349.285565 -237.19409)
		(end 349.528892 -236.729524)
		(width 0.1143)
		(layer "In15.Cu")
		(net "GMI_CPU0_G1_CPU1_G3_TX_DN<10>")
	)
	(arc
		(start 121.986294 -243.223796)
		(mid 122.216923 -243.674392)
		(end 121.986294 -244.124988)
		(width 0.1143)
		(layer "In15.Cu")
		(net "GMI_CPU0_G1_CPU1_G3_TX_DN<10>")
	)
	(arc
		(start 349.529146 -227.938838)
		(mid 349.285819 -227.474272)
		(end 349.529146 -227.009706)
		(width 0.1143)
		(layer "In15.Cu")
		(net "GMI_CPU0_G1_CPU1_G3_TX_DN<10>")
	)
	(arc
		(start 121.92762 -236.706918)
		(mid 122.208267 -237.194344)
		(end 121.92762 -237.68177)
		(width 0.1143)
		(layer "In15.Cu")
		(net "GMI_CPU0_G1_CPU1_G3_TX_DN<10>")
	)
	(arc
		(start 121.89587 -240.940082)
		(mid 121.739942 -241.244374)
		(end 121.89587 -241.548666)
		(width 0.1143)
		(layer "In15.Cu")
		(net "GMI_CPU0_G1_CPU1_G3_TX_DN<10>")
	)
	(arc
		(start 121.89587 -232.840022)
		(mid 121.739942 -233.144314)
		(end 121.89587 -233.448606)
		(width 0.1143)
		(layer "In15.Cu")
		(net "GMI_CPU0_G1_CPU1_G3_TX_DN<10>")
	)
	(arc
		(start 349.528892 -232.79862)
		(mid 349.285565 -232.334054)
		(end 349.528892 -231.869488)
		(width 0.1143)
		(layer "In15.Cu")
		(net "GMI_CPU0_G1_CPU1_G3_TX_DN<10>")
	)
	(arc
		(start 349.28556 -246.914162)
		(mid 349.350075 -246.651943)
		(end 349.528892 -246.449596)
		(width 0.1143)
		(layer "In15.Cu")
		(net "GMI_CPU0_G1_CPU1_G3_TX_DN<10>")
	)
	(arc
		(start 121.89587 -227.98024)
		(mid 121.739942 -228.284532)
		(end 121.89587 -228.588824)
		(width 0.1143)
		(layer "In15.Cu")
		(net "GMI_CPU0_G1_CPU1_G3_TX_DN<10>")
	)
	(arc
		(start 349.599758 -246.408448)
		(mid 349.755686 -246.104156)
		(end 349.599758 -245.799864)
		(width 0.1143)
		(layer "In15.Cu")
		(net "GMI_CPU0_G1_CPU1_G3_TX_DN<10>")
	)
	(arc
		(start 349.599758 -235.068364)
		(mid 349.755686 -234.764072)
		(end 349.599758 -234.45978)
		(width 0.1143)
		(layer "In15.Cu")
		(net "GMI_CPU0_G1_CPU1_G3_TX_DN<10>")
	)
	(arc
		(start 121.89587 -223.120204)
		(mid 121.739942 -223.424496)
		(end 121.89587 -223.728788)
		(width 0.1143)
		(layer "In15.Cu")
		(net "GMI_CPU0_G1_CPU1_G3_TX_DN<10>")
	)
	(arc
		(start 121.894092 -229.601522)
		(mid 121.780685 -229.734411)
		(end 121.739914 -229.90429)
		(width 0.1143)
		(layer "In15.Cu")
		(net "GMI_CPU0_G1_CPU1_G3_TX_DN<10>")
	)
	(arc
		(start 348.821756 -247.641364)
		(mid 348.823544 -247.629915)
		(end 348.825566 -247.618504)
		(width 0.1143)
		(layer "In15.Cu")
		(net "GMI_CPU0_G1_CPU1_G3_TX_DN<10>")
	)
	(arc
		(start 121.92762 -228.607112)
		(mid 122.134243 -228.812891)
		(end 122.209814 -229.094538)
		(width 0.1143)
		(layer "In15.Cu")
		(net "GMI_CPU0_G1_CPU1_G3_TX_DN<10>")
	)
	(arc
		(start 348.81566 -225.044254)
		(mid 348.774111 -224.872832)
		(end 348.658688 -224.739454)
		(width 0.1143)
		(layer "In15.Cu")
		(net "GMI_CPU0_G1_CPU1_G3_TX_DN<10>")
	)
	(arc
		(start 349.528892 -242.518692)
		(mid 349.285565 -242.054126)
		(end 349.528892 -241.58956)
		(width 0.1143)
		(layer "In15.Cu")
		(net "GMI_CPU0_G1_CPU1_G3_TX_DN<10>")
	)
	(arc
		(start 349.599758 -244.788436)
		(mid 349.755686 -244.484144)
		(end 349.599758 -244.179852)
		(width 0.1143)
		(layer "In15.Cu")
		(net "GMI_CPU0_G1_CPU1_G3_TX_DN<10>")
	)
	(arc
		(start 121.89587 -236.080046)
		(mid 121.739942 -236.384338)
		(end 121.89587 -236.68863)
		(width 0.1143)
		(layer "In15.Cu")
		(net "GMI_CPU0_G1_CPU1_G3_TX_DN<10>")
	)
	(arc
		(start 349.599758 -241.548412)
		(mid 349.755686 -241.24412)
		(end 349.599758 -240.939828)
		(width 0.1143)
		(layer "In15.Cu")
		(net "GMI_CPU0_G1_CPU1_G3_TX_DN<10>")
	)
	(arc
		(start 122.209814 -229.094538)
		(mid 122.144578 -229.358129)
		(end 121.963942 -229.560882)
		(width 0.1143)
		(layer "In15.Cu")
		(net "GMI_CPU0_G1_CPU1_G3_TX_DN<10>")
	)
	(arc
		(start 349.599758 -243.168424)
		(mid 349.755686 -242.864132)
		(end 349.599758 -242.55984)
		(width 0.1143)
		(layer "In15.Cu")
		(net "GMI_CPU0_G1_CPU1_G3_TX_DN<10>")
	)
	(arc
		(start 349.599758 -238.308388)
		(mid 349.755686 -238.004096)
		(end 349.599758 -237.699804)
		(width 0.1143)
		(layer "In15.Cu")
		(net "GMI_CPU0_G1_CPU1_G3_TX_DN<10>")
	)
	(arc
		(start 121.981976 -231.880664)
		(mid 122.214229 -232.334488)
		(end 121.981976 -232.788206)
		(width 0.1143)
		(layer "In15.Cu")
		(net "GMI_CPU0_G1_CPU1_G3_TX_DN<10>")
	)
	(arc
		(start 121.984008 -244.841776)
		(mid 122.216287 -245.294404)
		(end 121.984008 -245.747032)
		(width 0.1143)
		(layer "In15.Cu")
		(net "GMI_CPU0_G1_CPU1_G3_TX_DN<10>")
	)
	(arc
		(start 121.89587 -226.360228)
		(mid 121.739942 -226.66452)
		(end 121.89587 -226.968812)
		(width 0.1143)
		(layer "In15.Cu")
		(net "GMI_CPU0_G1_CPU1_G3_TX_DN<10>")
	)
	(arc
		(start 349.528892 -244.138704)
		(mid 349.285565 -243.674138)
		(end 349.528892 -243.209572)
		(width 0.1143)
		(layer "In15.Cu")
		(net "GMI_CPU0_G1_CPU1_G3_TX_DN<10>")
	)
	(arc
		(start 122.222514 -246.934228)
		(mid 122.269405 -247.109094)
		(end 122.39752 -247.236996)
		(width 0.1143)
		(layer "In15.Cu")
		(net "GMI_CPU0_G1_CPU1_G3_TX_DN<10>")
	)
	(arc
		(start 349.528892 -245.758716)
		(mid 349.285565 -245.29415)
		(end 349.528892 -244.829584)
		(width 0.1143)
		(layer "In15.Cu")
		(net "GMI_CPU0_G1_CPU1_G3_TX_DN<10>")
	)
	(arc
		(start 349.128588 -247.218962)
		(mid 349.244015 -247.085586)
		(end 349.28556 -246.914162)
		(width 0.1143)
		(layer "In15.Cu")
		(net "GMI_CPU0_G1_CPU1_G3_TX_DN<10>")
	)
	(arc
		(start 348.825566 -247.618504)
		(mid 348.906999 -247.416106)
		(end 349.058992 -247.259602)
		(width 0.1143)
		(layer "In15.Cu")
		(net "GMI_CPU0_G1_CPU1_G3_TX_DN<10>")
	)
	(arc
		(start 121.978166 -233.497882)
		(mid 122.205549 -233.95432)
		(end 121.978166 -234.410758)
		(width 0.1143)
		(layer "In15.Cu")
		(net "GMI_CPU0_G1_CPU1_G3_TX_DN<10>")
	)
	(arc
		(start 121.73966 -221.804484)
		(mid 121.780915 -221.975455)
		(end 121.895616 -222.108776)
		(width 0.1143)
		(layer "In15.Cu")
		(net "GMI_CPU0_G1_CPU1_G3_TX_DN<10>")
	)
	(arc
		(start 121.89587 -239.32007)
		(mid 121.739942 -239.624362)
		(end 121.89587 -239.928654)
		(width 0.1143)
		(layer "In15.Cu")
		(net "GMI_CPU0_G1_CPU1_G3_TX_DN<10>")
	)
	(arc
		(start 348.658688 -223.729042)
		(mid 348.815665 -223.424242)
		(end 348.658688 -223.119442)
		(width 0.1143)
		(layer "In15.Cu")
		(net "GMI_CPU0_G1_CPU1_G3_TX_DN<10>")
	)
	(segment
		(start 356.89794 -248.800112)
		(end 356.431088 -248.534174)
		(width 0.12954)
		(layer "F.Cu")
		(net "GMI_CPU0_G1_CPU1_G3_TX_DN<0>")
	)
	(segment
		(start 114.597942 -248.800366)
		(end 115.064794 -248.534428)
		(width 0.12954)
		(layer "F.Cu")
		(net "GMI_CPU0_G1_CPU1_G3_TX_DN<0>")
	)
	(segment
		(start 302.919384 -175.066452)
		(end 164.808408 -174.258224)
		(width 0.14224)
		(layer "In15.Cu")
		(net "GMI_CPU0_G1_CPU1_G3_TX_DN<0>")
	)
	(segment
		(start 358.48798 -245.622572)
		(end 358.498394 -245.61673)
		(width 0.1143)
		(layer "In15.Cu")
		(net "GMI_CPU0_G1_CPU1_G3_TX_DN<0>")
	)
	(segment
		(start 358.69118 -218.613736)
		(end 354.316792 -209.369406)
		(width 0.14224)
		(layer "In15.Cu")
		(net "GMI_CPU0_G1_CPU1_G3_TX_DN<0>")
	)
	(segment
		(start 308.674516 -175.066452)
		(end 302.919384 -175.066452)
		(width 0.14224)
		(layer "In15.Cu")
		(net "GMI_CPU0_G1_CPU1_G3_TX_DN<0>")
	)
	(segment
		(start 114.676428 -248.408698)
		(end 114.680238 -248.428764)
		(width 0.1143)
		(layer "In15.Cu")
		(net "GMI_CPU0_G1_CPU1_G3_TX_DN<0>")
	)
	(segment
		(start 357.557578 -247.236996)
		(end 357.558086 -247.236742)
		(width 0.1143)
		(layer "In15.Cu")
		(net "GMI_CPU0_G1_CPU1_G3_TX_DN<0>")
	)
	(segment
		(start 115.09375 -211.469478)
		(end 115.139724 -211.64677)
		(width 0.14224)
		(layer "In15.Cu")
		(net "GMI_CPU0_G1_CPU1_G3_TX_DN<0>")
	)
	(segment
		(start 114.766852 -248.534428)
		(end 115.064794 -248.534428)
		(width 0.1143)
		(layer "In15.Cu")
		(net "GMI_CPU0_G1_CPU1_G3_TX_DN<0>")
	)
	(segment
		(start 113.906046 -247.218708)
		(end 113.9317 -247.23344)
		(width 0.1143)
		(layer "In15.Cu")
		(net "GMI_CPU0_G1_CPU1_G3_TX_DN<0>")
	)
	(segment
		(start 358.627172 -218.792806)
		(end 358.69118 -218.613736)
		(width 0.14224)
		(layer "In15.Cu")
		(net "GMI_CPU0_G1_CPU1_G3_TX_DN<0>")
	)
	(segment
		(start 354.316792 -209.369406)
		(end 318.403732 -179.921662)
		(width 0.14224)
		(layer "In15.Cu")
		(net "GMI_CPU0_G1_CPU1_G3_TX_DN<0>")
	)
	(segment
		(start 359.048812 -221.46133)
		(end 359.183432 -221.32671)
		(width 0.14224)
		(layer "In15.Cu")
		(net "GMI_CPU0_G1_CPU1_G3_TX_DN<0>")
	)
	(segment
		(start 112.914684 -215.43137)
		(end 112.70234 -215.793066)
		(width 0.14224)
		(layer "In15.Cu")
		(net "GMI_CPU0_G1_CPU1_G3_TX_DN<0>")
	)
	(segment
		(start 112.997742 -245.616984)
		(end 113.035588 -245.638828)
		(width 0.1143)
		(layer "In15.Cu")
		(net "GMI_CPU0_G1_CPU1_G3_TX_DN<0>")
	)
	(segment
		(start 358.575102 -245.557802)
		(end 358.722676 -245.409974)
		(width 0.1143)
		(layer "In15.Cu")
		(net "GMI_CPU0_G1_CPU1_G3_TX_DN<0>")
	)
	(segment
		(start 113.933224 -247.234456)
		(end 113.935764 -247.235726)
		(width 0.1143)
		(layer "In15.Cu")
		(net "GMI_CPU0_G1_CPU1_G3_TX_DN<0>")
	)
	(segment
		(start 359.229152 -244.414548)
		(end 359.183432 -244.368828)
		(width 0.1143)
		(layer "In15.Cu")
		(net "GMI_CPU0_G1_CPU1_G3_TX_DN<0>")
	)
	(segment
		(start 115.627404 -210.561428)
		(end 115.09375 -211.469478)
		(width 0.14224)
		(layer "In15.Cu")
		(net "GMI_CPU0_G1_CPU1_G3_TX_DN<0>")
	)
	(segment
		(start 113.2586 -214.846916)
		(end 113.081054 -214.89289)
		(width 0.14224)
		(layer "In15.Cu")
		(net "GMI_CPU0_G1_CPU1_G3_TX_DN<0>")
	)
	(segment
		(start 358.722676 -245.409974)
		(end 359.229152 -244.903498)
		(width 0.1143)
		(layer "In15.Cu")
		(net "GMI_CPU0_G1_CPU1_G3_TX_DN<0>")
	)
	(segment
		(start 357.04907 -248.069608)
		(end 357.08717 -248.047256)
		(width 0.1143)
		(layer "In15.Cu")
		(net "GMI_CPU0_G1_CPU1_G3_TX_DN<0>")
	)
	(segment
		(start 357.088186 -248.046748)
		(end 357.088948 -248.04624)
		(width 0.1143)
		(layer "In15.Cu")
		(net "GMI_CPU0_G1_CPU1_G3_TX_DN<0>")
	)
	(segment
		(start 113.437162 -246.40921)
		(end 113.467642 -246.42699)
		(width 0.1143)
		(layer "In15.Cu")
		(net "GMI_CPU0_G1_CPU1_G3_TX_DN<0>")
	)
	(segment
		(start 359.183432 -220.90761)
		(end 359.048812 -220.77299)
		(width 0.14224)
		(layer "In15.Cu")
		(net "GMI_CPU0_G1_CPU1_G3_TX_DN<0>")
	)
	(segment
		(start 112.31245 -243.550948)
		(end 112.268 -243.595398)
		(width 0.1143)
		(layer "In15.Cu")
		(net "GMI_CPU0_G1_CPU1_G3_TX_DN<0>")
	)
	(segment
		(start 357.563928 -247.23344)
		(end 357.56469 -247.232932)
		(width 0.1143)
		(layer "In15.Cu")
		(net "GMI_CPU0_G1_CPU1_G3_TX_DN<0>")
	)
	(segment
		(start 112.86871 -215.254078)
		(end 112.914684 -215.43137)
		(width 0.14224)
		(layer "In15.Cu")
		(net "GMI_CPU0_G1_CPU1_G3_TX_DN<0>")
	)
	(segment
		(start 112.268 -244.905022)
		(end 112.921034 -245.558056)
		(width 0.1143)
		(layer "In15.Cu")
		(net "GMI_CPU0_G1_CPU1_G3_TX_DN<0>")
	)
	(segment
		(start 113.935764 -247.235726)
		(end 113.937034 -247.236488)
		(width 0.1143)
		(layer "In15.Cu")
		(net "GMI_CPU0_G1_CPU1_G3_TX_DN<0>")
	)
	(segment
		(start 359.183432 -221.32671)
		(end 359.183432 -220.90761)
		(width 0.14224)
		(layer "In15.Cu")
		(net "GMI_CPU0_G1_CPU1_G3_TX_DN<0>")
	)
	(segment
		(start 359.183432 -222.01505)
		(end 359.048812 -221.88043)
		(width 0.14224)
		(layer "In15.Cu")
		(net "GMI_CPU0_G1_CPU1_G3_TX_DN<0>")
	)
	(segment
		(start 114.749834 -212.05444)
		(end 114.53749 -212.415628)
		(width 0.14224)
		(layer "In15.Cu")
		(net "GMI_CPU0_G1_CPU1_G3_TX_DN<0>")
	)
	(segment
		(start 357.989124 -246.449596)
		(end 358.02824 -246.426736)
		(width 0.1143)
		(layer "In15.Cu")
		(net "GMI_CPU0_G1_CPU1_G3_TX_DN<0>")
	)
	(segment
		(start 358.48671 -245.623334)
		(end 358.48798 -245.622572)
		(width 0.1143)
		(layer "In15.Cu")
		(net "GMI_CPU0_G1_CPU1_G3_TX_DN<0>")
	)
	(segment
		(start 356.72903 -248.534174)
		(end 356.811834 -248.45137)
		(width 0.1143)
		(layer "In15.Cu")
		(net "GMI_CPU0_G1_CPU1_G3_TX_DN<0>")
	)
	(segment
		(start 113.939574 -247.238012)
		(end 113.952782 -247.245886)
		(width 0.1143)
		(layer "In15.Cu")
		(net "GMI_CPU0_G1_CPU1_G3_TX_DN<0>")
	)
	(segment
		(start 112.524794 -215.83904)
		(end 112.31245 -216.200228)
		(width 0.14224)
		(layer "In15.Cu")
		(net "GMI_CPU0_G1_CPU1_G3_TX_DN<0>")
	)
	(segment
		(start 113.9317 -247.23344)
		(end 113.933224 -247.234456)
		(width 0.1143)
		(layer "In15.Cu")
		(net "GMI_CPU0_G1_CPU1_G3_TX_DN<0>")
	)
	(segment
		(start 113.637314 -213.94674)
		(end 113.42497 -214.307928)
		(width 0.14224)
		(layer "In15.Cu")
		(net "GMI_CPU0_G1_CPU1_G3_TX_DN<0>")
	)
	(segment
		(start 113.81486 -213.900766)
		(end 113.637314 -213.94674)
		(width 0.14224)
		(layer "In15.Cu")
		(net "GMI_CPU0_G1_CPU1_G3_TX_DN<0>")
	)
	(segment
		(start 113.98123 -213.361778)
		(end 114.027204 -213.53907)
		(width 0.14224)
		(layer "In15.Cu")
		(net "GMI_CPU0_G1_CPU1_G3_TX_DN<0>")
	)
	(segment
		(start 112.70234 -215.793066)
		(end 112.524794 -215.83904)
		(width 0.14224)
		(layer "In15.Cu")
		(net "GMI_CPU0_G1_CPU1_G3_TX_DN<0>")
	)
	(segment
		(start 114.418364 -248.052844)
		(end 114.46129 -248.07799)
		(width 0.1143)
		(layer "In15.Cu")
		(net "GMI_CPU0_G1_CPU1_G3_TX_DN<0>")
	)
	(segment
		(start 358.806496 -219.172028)
		(end 358.627172 -218.792806)
		(width 0.14224)
		(layer "In15.Cu")
		(net "GMI_CPU0_G1_CPU1_G3_TX_DN<0>")
	)
	(segment
		(start 112.268 -243.595398)
		(end 112.268 -244.905022)
		(width 0.1143)
		(layer "In15.Cu")
		(net "GMI_CPU0_G1_CPU1_G3_TX_DN<0>")
	)
	(segment
		(start 359.183432 -220.21927)
		(end 359.183432 -219.653612)
		(width 0.14224)
		(layer "In15.Cu")
		(net "GMI_CPU0_G1_CPU1_G3_TX_DN<0>")
	)
	(segment
		(start 359.048812 -220.35389)
		(end 359.183432 -220.21927)
		(width 0.14224)
		(layer "In15.Cu")
		(net "GMI_CPU0_G1_CPU1_G3_TX_DN<0>")
	)
	(segment
		(start 358.481884 -245.625874)
		(end 358.4829 -245.625366)
		(width 0.1143)
		(layer "In15.Cu")
		(net "GMI_CPU0_G1_CPU1_G3_TX_DN<0>")
	)
	(segment
		(start 115.139724 -211.64677)
		(end 114.92738 -212.008466)
		(width 0.14224)
		(layer "In15.Cu")
		(net "GMI_CPU0_G1_CPU1_G3_TX_DN<0>")
	)
	(segment
		(start 114.37112 -212.954616)
		(end 114.193574 -213.00059)
		(width 0.14224)
		(layer "In15.Cu")
		(net "GMI_CPU0_G1_CPU1_G3_TX_DN<0>")
	)
	(segment
		(start 113.937796 -247.236996)
		(end 113.939574 -247.238012)
		(width 0.1143)
		(layer "In15.Cu")
		(net "GMI_CPU0_G1_CPU1_G3_TX_DN<0>")
	)
	(segment
		(start 113.470944 -214.48522)
		(end 113.2586 -214.846916)
		(width 0.14224)
		(layer "In15.Cu")
		(net "GMI_CPU0_G1_CPU1_G3_TX_DN<0>")
	)
	(segment
		(start 359.183432 -244.34038)
		(end 359.183432 -222.01505)
		(width 0.14224)
		(layer "In15.Cu")
		(net "GMI_CPU0_G1_CPU1_G3_TX_DN<0>")
	)
	(segment
		(start 113.937034 -247.236488)
		(end 113.937796 -247.236996)
		(width 0.1143)
		(layer "In15.Cu")
		(net "GMI_CPU0_G1_CPU1_G3_TX_DN<0>")
	)
	(segment
		(start 358.98582 -219.236036)
		(end 358.806496 -219.172028)
		(width 0.14224)
		(layer "In15.Cu")
		(net "GMI_CPU0_G1_CPU1_G3_TX_DN<0>")
	)
	(segment
		(start 359.229152 -244.903498)
		(end 359.229152 -244.414548)
		(width 0.1143)
		(layer "In15.Cu")
		(net "GMI_CPU0_G1_CPU1_G3_TX_DN<0>")
	)
	(segment
		(start 311.802526 -176.184814)
		(end 308.674516 -175.066452)
		(width 0.14224)
		(layer "In15.Cu")
		(net "GMI_CPU0_G1_CPU1_G3_TX_DN<0>")
	)
	(segment
		(start 357.56469 -247.232932)
		(end 357.56596 -247.23217)
		(width 0.1143)
		(layer "In15.Cu")
		(net "GMI_CPU0_G1_CPU1_G3_TX_DN<0>")
	)
	(segment
		(start 114.583464 -212.59292)
		(end 114.37112 -212.954616)
		(width 0.14224)
		(layer "In15.Cu")
		(net "GMI_CPU0_G1_CPU1_G3_TX_DN<0>")
	)
	(segment
		(start 357.562404 -247.234202)
		(end 357.563928 -247.23344)
		(width 0.1143)
		(layer "In15.Cu")
		(net "GMI_CPU0_G1_CPU1_G3_TX_DN<0>")
	)
	(segment
		(start 156.105352 -177.370486)
		(end 115.627404 -210.561428)
		(width 0.14224)
		(layer "In15.Cu")
		(net "GMI_CPU0_G1_CPU1_G3_TX_DN<0>")
	)
	(segment
		(start 357.558086 -247.236742)
		(end 357.558848 -247.236234)
		(width 0.1143)
		(layer "In15.Cu")
		(net "GMI_CPU0_G1_CPU1_G3_TX_DN<0>")
	)
	(segment
		(start 114.193574 -213.00059)
		(end 113.98123 -213.361778)
		(width 0.14224)
		(layer "In15.Cu")
		(net "GMI_CPU0_G1_CPU1_G3_TX_DN<0>")
	)
	(segment
		(start 112.31245 -216.200228)
		(end 112.31245 -243.550948)
		(width 0.14224)
		(layer "In15.Cu")
		(net "GMI_CPU0_G1_CPU1_G3_TX_DN<0>")
	)
	(segment
		(start 359.183432 -244.368828)
		(end 359.183432 -244.34038)
		(width 0.1143)
		(layer "In15.Cu")
		(net "GMI_CPU0_G1_CPU1_G3_TX_DN<0>")
	)
	(segment
		(start 164.808408 -174.258224)
		(end 156.105352 -177.370486)
		(width 0.14224)
		(layer "In15.Cu")
		(net "GMI_CPU0_G1_CPU1_G3_TX_DN<0>")
	)
	(segment
		(start 114.027204 -213.53907)
		(end 113.81486 -213.900766)
		(width 0.14224)
		(layer "In15.Cu")
		(net "GMI_CPU0_G1_CPU1_G3_TX_DN<0>")
	)
	(segment
		(start 113.42497 -214.307928)
		(end 113.470944 -214.48522)
		(width 0.14224)
		(layer "In15.Cu")
		(net "GMI_CPU0_G1_CPU1_G3_TX_DN<0>")
	)
	(segment
		(start 114.684048 -248.451624)
		(end 114.766852 -248.534428)
		(width 0.1143)
		(layer "In15.Cu")
		(net "GMI_CPU0_G1_CPU1_G3_TX_DN<0>")
	)
	(segment
		(start 113.081054 -214.89289)
		(end 112.86871 -215.254078)
		(width 0.14224)
		(layer "In15.Cu")
		(net "GMI_CPU0_G1_CPU1_G3_TX_DN<0>")
	)
	(segment
		(start 358.02824 -246.426736)
		(end 358.05872 -246.408956)
		(width 0.1143)
		(layer "In15.Cu")
		(net "GMI_CPU0_G1_CPU1_G3_TX_DN<0>")
	)
	(segment
		(start 357.558848 -247.236234)
		(end 357.561642 -247.23471)
		(width 0.1143)
		(layer "In15.Cu")
		(net "GMI_CPU0_G1_CPU1_G3_TX_DN<0>")
	)
	(segment
		(start 114.92738 -212.008466)
		(end 114.749834 -212.05444)
		(width 0.14224)
		(layer "In15.Cu")
		(net "GMI_CPU0_G1_CPU1_G3_TX_DN<0>")
	)
	(segment
		(start 359.048812 -221.88043)
		(end 359.048812 -221.46133)
		(width 0.14224)
		(layer "In15.Cu")
		(net "GMI_CPU0_G1_CPU1_G3_TX_DN<0>")
	)
	(segment
		(start 356.431088 -248.534174)
		(end 356.72903 -248.534174)
		(width 0.1143)
		(layer "In15.Cu")
		(net "GMI_CPU0_G1_CPU1_G3_TX_DN<0>")
	)
	(segment
		(start 359.183432 -219.653612)
		(end 358.98582 -219.236036)
		(width 0.14224)
		(layer "In15.Cu")
		(net "GMI_CPU0_G1_CPU1_G3_TX_DN<0>")
	)
	(segment
		(start 318.403732 -179.921662)
		(end 311.802526 -176.184814)
		(width 0.14224)
		(layer "In15.Cu")
		(net "GMI_CPU0_G1_CPU1_G3_TX_DN<0>")
	)
	(segment
		(start 357.561642 -247.23471)
		(end 357.562404 -247.234202)
		(width 0.1143)
		(layer "In15.Cu")
		(net "GMI_CPU0_G1_CPU1_G3_TX_DN<0>")
	)
	(segment
		(start 358.4829 -245.625366)
		(end 358.48671 -245.623334)
		(width 0.1143)
		(layer "In15.Cu")
		(net "GMI_CPU0_G1_CPU1_G3_TX_DN<0>")
	)
	(segment
		(start 358.479852 -245.627144)
		(end 358.481884 -245.625874)
		(width 0.1143)
		(layer "In15.Cu")
		(net "GMI_CPU0_G1_CPU1_G3_TX_DN<0>")
	)
	(segment
		(start 357.521764 -247.257824)
		(end 357.557578 -247.236996)
		(width 0.1143)
		(layer "In15.Cu")
		(net "GMI_CPU0_G1_CPU1_G3_TX_DN<0>")
	)
	(segment
		(start 113.467642 -246.42699)
		(end 113.506758 -246.44985)
		(width 0.1143)
		(layer "In15.Cu")
		(net "GMI_CPU0_G1_CPU1_G3_TX_DN<0>")
	)
	(segment
		(start 114.53749 -212.415628)
		(end 114.583464 -212.59292)
		(width 0.14224)
		(layer "In15.Cu")
		(net "GMI_CPU0_G1_CPU1_G3_TX_DN<0>")
	)
	(segment
		(start 358.478328 -245.62816)
		(end 358.479852 -245.627144)
		(width 0.1143)
		(layer "In15.Cu")
		(net "GMI_CPU0_G1_CPU1_G3_TX_DN<0>")
	)
	(segment
		(start 358.460294 -245.638574)
		(end 358.478328 -245.62816)
		(width 0.1143)
		(layer "In15.Cu")
		(net "GMI_CPU0_G1_CPU1_G3_TX_DN<0>")
	)
	(segment
		(start 357.56596 -247.23217)
		(end 357.589836 -247.218454)
		(width 0.1143)
		(layer "In15.Cu")
		(net "GMI_CPU0_G1_CPU1_G3_TX_DN<0>")
	)
	(segment
		(start 359.048812 -220.77299)
		(end 359.048812 -220.35389)
		(width 0.14224)
		(layer "In15.Cu")
		(net "GMI_CPU0_G1_CPU1_G3_TX_DN<0>")
	)
	(segment
		(start 357.08717 -248.047256)
		(end 357.088186 -248.046748)
		(width 0.1143)
		(layer "In15.Cu")
		(net "GMI_CPU0_G1_CPU1_G3_TX_DN<0>")
	)
	(segment
		(start 357.088948 -248.04624)
		(end 357.119936 -248.02846)
		(width 0.1143)
		(layer "In15.Cu")
		(net "GMI_CPU0_G1_CPU1_G3_TX_DN<0>")
	)
	(arc
		(start 357.275638 -247.725184)
		(mid 357.277019 -247.703928)
		(end 357.279448 -247.682766)
		(width 0.1143)
		(layer "In15.Cu")
		(net "GMI_CPU0_G1_CPU1_G3_TX_DN<0>")
	)
	(arc
		(start 357.49484 -247.278144)
		(mid 357.50815 -247.267782)
		(end 357.521764 -247.257824)
		(width 0.1143)
		(layer "In15.Cu")
		(net "GMI_CPU0_G1_CPU1_G3_TX_DN<0>")
	)
	(arc
		(start 357.279448 -247.682766)
		(mid 357.351523 -247.461495)
		(end 357.49484 -247.278144)
		(width 0.1143)
		(layer "In15.Cu")
		(net "GMI_CPU0_G1_CPU1_G3_TX_DN<0>")
	)
	(arc
		(start 112.921034 -245.558056)
		(mid 112.957462 -245.590029)
		(end 112.997742 -245.616984)
		(width 0.1143)
		(layer "In15.Cu")
		(net "GMI_CPU0_G1_CPU1_G3_TX_DN<0>")
	)
	(arc
		(start 356.811834 -248.45137)
		(mid 356.813622 -248.439921)
		(end 356.815644 -248.42851)
		(width 0.1143)
		(layer "In15.Cu")
		(net "GMI_CPU0_G1_CPU1_G3_TX_DN<0>")
	)
	(arc
		(start 114.46129 -248.07799)
		(mid 114.601348 -248.222202)
		(end 114.676428 -248.408698)
		(width 0.1143)
		(layer "In15.Cu")
		(net "GMI_CPU0_G1_CPU1_G3_TX_DN<0>")
	)
	(arc
		(start 357.745792 -246.914162)
		(mid 357.810307 -246.651943)
		(end 357.989124 -246.449596)
		(width 0.1143)
		(layer "In15.Cu")
		(net "GMI_CPU0_G1_CPU1_G3_TX_DN<0>")
	)
	(arc
		(start 113.28019 -246.10441)
		(mid 113.321739 -246.275832)
		(end 113.437162 -246.40921)
		(width 0.1143)
		(layer "In15.Cu")
		(net "GMI_CPU0_G1_CPU1_G3_TX_DN<0>")
	)
	(arc
		(start 358.498394 -245.61673)
		(mid 358.538671 -245.589768)
		(end 358.575102 -245.557802)
		(width 0.1143)
		(layer "In15.Cu")
		(net "GMI_CPU0_G1_CPU1_G3_TX_DN<0>")
	)
	(arc
		(start 356.815644 -248.42851)
		(mid 356.897077 -248.226112)
		(end 357.04907 -248.069608)
		(width 0.1143)
		(layer "In15.Cu")
		(net "GMI_CPU0_G1_CPU1_G3_TX_DN<0>")
	)
	(arc
		(start 358.05872 -246.408956)
		(mid 358.174147 -246.27558)
		(end 358.215692 -246.104156)
		(width 0.1143)
		(layer "In15.Cu")
		(net "GMI_CPU0_G1_CPU1_G3_TX_DN<0>")
	)
	(arc
		(start 113.75009 -246.914416)
		(mid 113.791345 -247.085387)
		(end 113.906046 -247.218708)
		(width 0.1143)
		(layer "In15.Cu")
		(net "GMI_CPU0_G1_CPU1_G3_TX_DN<0>")
	)
	(arc
		(start 113.035588 -245.638828)
		(mid 113.215317 -245.841448)
		(end 113.28019 -246.10441)
		(width 0.1143)
		(layer "In15.Cu")
		(net "GMI_CPU0_G1_CPU1_G3_TX_DN<0>")
	)
	(arc
		(start 113.506758 -246.44985)
		(mid 113.685571 -246.6522)
		(end 113.75009 -246.914416)
		(width 0.1143)
		(layer "In15.Cu")
		(net "GMI_CPU0_G1_CPU1_G3_TX_DN<0>")
	)
	(arc
		(start 113.952782 -247.245886)
		(mid 114.157746 -247.451396)
		(end 114.23269 -247.731788)
		(width 0.1143)
		(layer "In15.Cu")
		(net "GMI_CPU0_G1_CPU1_G3_TX_DN<0>")
	)
	(arc
		(start 357.589836 -247.218454)
		(mid 357.704512 -247.08512)
		(end 357.745792 -246.914162)
		(width 0.1143)
		(layer "In15.Cu")
		(net "GMI_CPU0_G1_CPU1_G3_TX_DN<0>")
	)
	(arc
		(start 114.680238 -248.428764)
		(mid 114.682261 -248.440174)
		(end 114.684048 -248.451624)
		(width 0.1143)
		(layer "In15.Cu")
		(net "GMI_CPU0_G1_CPU1_G3_TX_DN<0>")
	)
	(arc
		(start 358.215692 -246.104156)
		(mid 358.280564 -245.841193)
		(end 358.460294 -245.638574)
		(width 0.1143)
		(layer "In15.Cu")
		(net "GMI_CPU0_G1_CPU1_G3_TX_DN<0>")
	)
	(arc
		(start 114.23269 -247.731788)
		(mid 114.282458 -247.917218)
		(end 114.418364 -248.052844)
		(width 0.1143)
		(layer "In15.Cu")
		(net "GMI_CPU0_G1_CPU1_G3_TX_DN<0>")
	)
	(arc
		(start 357.119936 -248.02846)
		(mid 357.231499 -247.894115)
		(end 357.275638 -247.725184)
		(width 0.1143)
		(layer "In15.Cu")
		(net "GMI_CPU0_G1_CPU1_G3_TX_DN<0>")
	)
	(segment
		(start 118.827804 -241.510312)
		(end 119.294656 -241.244374)
		(width 0.12954)
		(layer "F.Cu")
		(net "GMI_CPU0_G0_CPU1_G2_TX_DP<9>")
	)
	(segment
		(start 352.668078 -241.510058)
		(end 352.201226 -241.24412)
		(width 0.12954)
		(layer "F.Cu")
		(net "GMI_CPU0_G0_CPU1_G2_TX_DP<9>")
	)
	(segment
		(start 351.576386 -240.77549)
		(end 351.575624 -240.774982)
		(width 0.1143)
		(layer "In13.Cu")
		(net "GMI_CPU0_G0_CPU1_G2_TX_DP<9>")
	)
	(segment
		(start 351.583244 -240.779554)
		(end 351.576386 -240.77549)
		(width 0.1143)
		(layer "In13.Cu")
		(net "GMI_CPU0_G0_CPU1_G2_TX_DP<9>")
	)
	(segment
		(start 120.891808 -225.531934)
		(end 120.922288 -225.549714)
		(width 0.1143)
		(layer "In13.Cu")
		(net "GMI_CPU0_G0_CPU1_G2_TX_DP<9>")
	)
	(segment
		(start 120.922288 -224.539302)
		(end 120.891808 -224.557082)
		(width 0.1143)
		(layer "In13.Cu")
		(net "GMI_CPU0_G0_CPU1_G2_TX_DP<9>")
	)
	(segment
		(start 350.573594 -232.029254)
		(end 350.64319 -231.988614)
		(width 0.1143)
		(layer "In13.Cu")
		(net "GMI_CPU0_G0_CPU1_G2_TX_DP<9>")
	)
	(segment
		(start 350.64319 -226.1997)
		(end 350.573594 -226.15906)
		(width 0.1143)
		(layer "In13.Cu")
		(net "GMI_CPU0_G0_CPU1_G2_TX_DP<9>")
	)
	(segment
		(start 350.573594 -225.54946)
		(end 350.64319 -225.50882)
		(width 0.1143)
		(layer "In13.Cu")
		(net "GMI_CPU0_G0_CPU1_G2_TX_DP<9>")
	)
	(segment
		(start 352.201226 -241.24412)
		(end 351.903284 -241.24412)
		(width 0.1143)
		(layer "In13.Cu")
		(net "GMI_CPU0_G0_CPU1_G2_TX_DP<9>")
	)
	(segment
		(start 120.891808 -234.2769)
		(end 120.852692 -234.29976)
		(width 0.1143)
		(layer "In13.Cu")
		(net "GMI_CPU0_G0_CPU1_G2_TX_DP<9>")
	)
	(segment
		(start 120.891808 -232.011728)
		(end 120.922288 -232.029508)
		(width 0.1143)
		(layer "In13.Cu")
		(net "GMI_CPU0_G0_CPU1_G2_TX_DP<9>")
	)
	(segment
		(start 120.53443 -221.071948)
		(end 120.53443 -221.100396)
		(width 0.1143)
		(layer "In13.Cu")
		(net "GMI_CPU0_G0_CPU1_G2_TX_DP<9>")
	)
	(segment
		(start 120.53443 -219.543884)
		(end 120.53443 -221.071948)
		(width 0.14224)
		(layer "In13.Cu")
		(net "GMI_CPU0_G0_CPU1_G2_TX_DP<9>")
	)
	(segment
		(start 119.983504 -240.73866)
		(end 119.952516 -240.75644)
		(width 0.1143)
		(layer "In13.Cu")
		(net "GMI_CPU0_G0_CPU1_G2_TX_DP<9>")
	)
	(segment
		(start 306.86756 -183.252872)
		(end 302.892968 -183.252872)
		(width 0.14224)
		(layer "In13.Cu")
		(net "GMI_CPU0_G0_CPU1_G2_TX_DP<9>")
	)
	(segment
		(start 120.852692 -222.26905)
		(end 120.922288 -222.30969)
		(width 0.1143)
		(layer "In13.Cu")
		(net "GMI_CPU0_G0_CPU1_G2_TX_DP<9>")
	)
	(segment
		(start 351.575624 -240.774982)
		(end 351.545144 -240.757202)
		(width 0.1143)
		(layer "In13.Cu")
		(net "GMI_CPU0_G0_CPU1_G2_TX_DP<9>")
	)
	(segment
		(start 350.64319 -234.299506)
		(end 350.573594 -234.258866)
		(width 0.1143)
		(layer "In13.Cu")
		(net "GMI_CPU0_G0_CPU1_G2_TX_DP<9>")
	)
	(segment
		(start 308.12994 -183.70423)
		(end 306.86756 -183.252872)
		(width 0.14224)
		(layer "In13.Cu")
		(net "GMI_CPU0_G0_CPU1_G2_TX_DP<9>")
	)
	(segment
		(start 350.64319 -239.159542)
		(end 350.573594 -239.118902)
		(width 0.1143)
		(layer "In13.Cu")
		(net "GMI_CPU0_G0_CPU1_G2_TX_DP<9>")
	)
	(segment
		(start 313.98718 -187.019946)
		(end 308.12994 -183.70423)
		(width 0.14224)
		(layer "In13.Cu")
		(net "GMI_CPU0_G0_CPU1_G2_TX_DP<9>")
	)
	(segment
		(start 120.891808 -237.516924)
		(end 120.852692 -237.539784)
		(width 0.1143)
		(layer "In13.Cu")
		(net "GMI_CPU0_G0_CPU1_G2_TX_DP<9>")
	)
	(segment
		(start 120.58015 -221.146116)
		(end 120.58015 -221.382336)
		(width 0.1143)
		(layer "In13.Cu")
		(net "GMI_CPU0_G0_CPU1_G2_TX_DP<9>")
	)
	(segment
		(start 123.048522 -215.234012)
		(end 120.53443 -219.543884)
		(width 0.14224)
		(layer "In13.Cu")
		(net "GMI_CPU0_G0_CPU1_G2_TX_DP<9>")
	)
	(segment
		(start 120.852692 -233.60888)
		(end 120.891808 -233.63174)
		(width 0.1143)
		(layer "In13.Cu")
		(net "GMI_CPU0_G0_CPU1_G2_TX_DP<9>")
	)
	(segment
		(start 120.58015 -221.382336)
		(end 120.609614 -221.4118)
		(width 0.1143)
		(layer "In13.Cu")
		(net "GMI_CPU0_G0_CPU1_G2_TX_DP<9>")
	)
	(segment
		(start 120.891808 -228.771958)
		(end 120.922288 -228.789738)
		(width 0.1143)
		(layer "In13.Cu")
		(net "GMI_CPU0_G0_CPU1_G2_TX_DP<9>")
	)
	(segment
		(start 120.922288 -234.25912)
		(end 120.891808 -234.2769)
		(width 0.1143)
		(layer "In13.Cu")
		(net "GMI_CPU0_G0_CPU1_G2_TX_DP<9>")
	)
	(segment
		(start 120.922288 -239.119156)
		(end 120.891808 -239.136936)
		(width 0.1143)
		(layer "In13.Cu")
		(net "GMI_CPU0_G0_CPU1_G2_TX_DP<9>")
	)
	(segment
		(start 120.852692 -223.889062)
		(end 120.891808 -223.911922)
		(width 0.1143)
		(layer "In13.Cu")
		(net "GMI_CPU0_G0_CPU1_G2_TX_DP<9>")
	)
	(segment
		(start 350.573594 -233.649266)
		(end 350.64319 -233.608626)
		(width 0.1143)
		(layer "In13.Cu")
		(net "GMI_CPU0_G0_CPU1_G2_TX_DP<9>")
	)
	(segment
		(start 350.573594 -238.509302)
		(end 350.64319 -238.468662)
		(width 0.1143)
		(layer "In13.Cu")
		(net "GMI_CPU0_G0_CPU1_G2_TX_DP<9>")
	)
	(segment
		(start 350.915732 -221.145862)
		(end 350.961452 -221.100142)
		(width 0.1143)
		(layer "In13.Cu")
		(net "GMI_CPU0_G0_CPU1_G2_TX_DP<9>")
	)
	(segment
		(start 120.891808 -222.93707)
		(end 120.852692 -222.95993)
		(width 0.1143)
		(layer "In13.Cu")
		(net "GMI_CPU0_G0_CPU1_G2_TX_DP<9>")
	)
	(segment
		(start 120.852692 -231.988868)
		(end 120.891808 -232.011728)
		(width 0.1143)
		(layer "In13.Cu")
		(net "GMI_CPU0_G0_CPU1_G2_TX_DP<9>")
	)
	(segment
		(start 161.749994 -184.208166)
		(end 157.068012 -188.047376)
		(width 0.14224)
		(layer "In13.Cu")
		(net "GMI_CPU0_G0_CPU1_G2_TX_DP<9>")
	)
	(segment
		(start 350.961452 -221.100142)
		(end 350.961452 -221.093538)
		(width 0.1143)
		(layer "In13.Cu")
		(net "GMI_CPU0_G0_CPU1_G2_TX_DP<9>")
	)
	(segment
		(start 350.573594 -222.309436)
		(end 350.64319 -222.268796)
		(width 0.1143)
		(layer "In13.Cu")
		(net "GMI_CPU0_G0_CPU1_G2_TX_DP<9>")
	)
	(segment
		(start 350.573594 -236.88929)
		(end 350.64319 -236.84865)
		(width 0.1143)
		(layer "In13.Cu")
		(net "GMI_CPU0_G0_CPU1_G2_TX_DP<9>")
	)
	(segment
		(start 351.11055 -239.96777)
		(end 351.075752 -239.94745)
		(width 0.1143)
		(layer "In13.Cu")
		(net "GMI_CPU0_G0_CPU1_G2_TX_DP<9>")
	)
	(segment
		(start 120.922288 -227.779326)
		(end 120.891808 -227.797106)
		(width 0.1143)
		(layer "In13.Cu")
		(net "GMI_CPU0_G0_CPU1_G2_TX_DP<9>")
	)
	(segment
		(start 350.64319 -237.53953)
		(end 350.573594 -237.49889)
		(width 0.1143)
		(layer "In13.Cu")
		(net "GMI_CPU0_G0_CPU1_G2_TX_DP<9>")
	)
	(segment
		(start 120.922288 -235.879132)
		(end 120.891808 -235.896912)
		(width 0.1143)
		(layer "In13.Cu")
		(net "GMI_CPU0_G0_CPU1_G2_TX_DP<9>")
	)
	(segment
		(start 120.922288 -232.639108)
		(end 120.891808 -232.656888)
		(width 0.1143)
		(layer "In13.Cu")
		(net "GMI_CPU0_G0_CPU1_G2_TX_DP<9>")
	)
	(segment
		(start 350.573594 -228.789484)
		(end 350.64319 -228.748844)
		(width 0.1143)
		(layer "In13.Cu")
		(net "GMI_CPU0_G0_CPU1_G2_TX_DP<9>")
	)
	(segment
		(start 120.852692 -225.509074)
		(end 120.891808 -225.531934)
		(width 0.1143)
		(layer "In13.Cu")
		(net "GMI_CPU0_G0_CPU1_G2_TX_DP<9>")
	)
	(segment
		(start 302.892968 -183.252872)
		(end 166.629588 -182.458868)
		(width 0.14224)
		(layer "In13.Cu")
		(net "GMI_CPU0_G0_CPU1_G2_TX_DP<9>")
	)
	(segment
		(start 351.075752 -239.94745)
		(end 351.074228 -239.946688)
		(width 0.1143)
		(layer "In13.Cu")
		(net "GMI_CPU0_G0_CPU1_G2_TX_DP<9>")
	)
	(segment
		(start 119.592598 -241.244374)
		(end 119.294656 -241.244374)
		(width 0.1143)
		(layer "In13.Cu")
		(net "GMI_CPU0_G0_CPU1_G2_TX_DP<9>")
	)
	(segment
		(start 120.852692 -228.749098)
		(end 120.891808 -228.771958)
		(width 0.1143)
		(layer "In13.Cu")
		(net "GMI_CPU0_G0_CPU1_G2_TX_DP<9>")
	)
	(segment
		(start 119.950738 -240.757456)
		(end 119.949214 -240.758472)
		(width 0.1143)
		(layer "In13.Cu")
		(net "GMI_CPU0_G0_CPU1_G2_TX_DP<9>")
	)
	(segment
		(start 350.64319 -224.579688)
		(end 350.573594 -224.539048)
		(width 0.1143)
		(layer "In13.Cu")
		(net "GMI_CPU0_G0_CPU1_G2_TX_DP<9>")
	)
	(segment
		(start 350.573594 -230.409496)
		(end 350.64065 -230.37038)
		(width 0.1143)
		(layer "In13.Cu")
		(net "GMI_CPU0_G0_CPU1_G2_TX_DP<9>")
	)
	(segment
		(start 144.859756 -197.349618)
		(end 123.048522 -215.234012)
		(width 0.14224)
		(layer "In13.Cu")
		(net "GMI_CPU0_G0_CPU1_G2_TX_DP<9>")
	)
	(segment
		(start 120.852692 -236.848904)
		(end 120.891808 -236.871764)
		(width 0.1143)
		(layer "In13.Cu")
		(net "GMI_CPU0_G0_CPU1_G2_TX_DP<9>")
	)
	(segment
		(start 350.64319 -227.819712)
		(end 350.573594 -227.779072)
		(width 0.1143)
		(layer "In13.Cu")
		(net "GMI_CPU0_G0_CPU1_G2_TX_DP<9>")
	)
	(segment
		(start 351.544128 -240.756694)
		(end 351.543366 -240.756186)
		(width 0.1143)
		(layer "In13.Cu")
		(net "GMI_CPU0_G0_CPU1_G2_TX_DP<9>")
	)
	(segment
		(start 351.073466 -239.94618)
		(end 351.072196 -239.945418)
		(width 0.1143)
		(layer "In13.Cu")
		(net "GMI_CPU0_G0_CPU1_G2_TX_DP<9>")
	)
	(segment
		(start 120.891808 -231.036876)
		(end 120.852692 -231.059736)
		(width 0.1143)
		(layer "In13.Cu")
		(net "GMI_CPU0_G0_CPU1_G2_TX_DP<9>")
	)
	(segment
		(start 120.891808 -232.656888)
		(end 120.852692 -232.679748)
		(width 0.1143)
		(layer "In13.Cu")
		(net "GMI_CPU0_G0_CPU1_G2_TX_DP<9>")
	)
	(segment
		(start 120.453404 -239.928654)
		(end 120.422416 -239.946434)
		(width 0.1143)
		(layer "In13.Cu")
		(net "GMI_CPU0_G0_CPU1_G2_TX_DP<9>")
	)
	(segment
		(start 350.961452 -221.093538)
		(end 350.961452 -219.420694)
		(width 0.14224)
		(layer "In13.Cu")
		(net "GMI_CPU0_G0_CPU1_G2_TX_DP<9>")
	)
	(segment
		(start 120.922288 -237.499144)
		(end 120.891808 -237.516924)
		(width 0.1143)
		(layer "In13.Cu")
		(net "GMI_CPU0_G0_CPU1_G2_TX_DP<9>")
	)
	(segment
		(start 350.573594 -227.169472)
		(end 350.64319 -227.128832)
		(width 0.1143)
		(layer "In13.Cu")
		(net "GMI_CPU0_G0_CPU1_G2_TX_DP<9>")
	)
	(segment
		(start 120.852692 -235.228892)
		(end 120.891808 -235.251752)
		(width 0.1143)
		(layer "In13.Cu")
		(net "GMI_CPU0_G0_CPU1_G2_TX_DP<9>")
	)
	(segment
		(start 120.891808 -235.251752)
		(end 120.922288 -235.269532)
		(width 0.1143)
		(layer "In13.Cu")
		(net "GMI_CPU0_G0_CPU1_G2_TX_DP<9>")
	)
	(segment
		(start 120.421654 -239.946942)
		(end 120.42013 -239.947704)
		(width 0.1143)
		(layer "In13.Cu")
		(net "GMI_CPU0_G0_CPU1_G2_TX_DP<9>")
	)
	(segment
		(start 120.92432 -229.398068)
		(end 120.891808 -229.416864)
		(width 0.1143)
		(layer "In13.Cu")
		(net "GMI_CPU0_G0_CPU1_G2_TX_DP<9>")
	)
	(segment
		(start 157.068012 -188.047376)
		(end 157.067758 -188.047376)
		(width 0.14224)
		(layer "In13.Cu")
		(net "GMI_CPU0_G0_CPU1_G2_TX_DP<9>")
	)
	(segment
		(start 119.949214 -240.758472)
		(end 119.912638 -240.779808)
		(width 0.1143)
		(layer "In13.Cu")
		(net "GMI_CPU0_G0_CPU1_G2_TX_DP<9>")
	)
	(segment
		(start 350.64319 -222.959676)
		(end 350.573594 -222.919036)
		(width 0.1143)
		(layer "In13.Cu")
		(net "GMI_CPU0_G0_CPU1_G2_TX_DP<9>")
	)
	(segment
		(start 120.922288 -226.159314)
		(end 120.891808 -226.177094)
		(width 0.1143)
		(layer "In13.Cu")
		(net "GMI_CPU0_G0_CPU1_G2_TX_DP<9>")
	)
	(segment
		(start 350.604074 -229.41661)
		(end 350.571562 -229.397814)
		(width 0.1143)
		(layer "In13.Cu")
		(net "GMI_CPU0_G0_CPU1_G2_TX_DP<9>")
	)
	(segment
		(start 120.42013 -239.947704)
		(end 120.385332 -239.968024)
		(width 0.1143)
		(layer "In13.Cu")
		(net "GMI_CPU0_G0_CPU1_G2_TX_DP<9>")
	)
	(segment
		(start 120.891808 -229.416864)
		(end 120.852692 -229.439724)
		(width 0.1143)
		(layer "In13.Cu")
		(net "GMI_CPU0_G0_CPU1_G2_TX_DP<9>")
	)
	(segment
		(start 351.072196 -239.945418)
		(end 351.042478 -239.9284)
		(width 0.1143)
		(layer "In13.Cu")
		(net "GMI_CPU0_G0_CPU1_G2_TX_DP<9>")
	)
	(segment
		(start 350.915732 -221.382082)
		(end 350.915732 -221.145862)
		(width 0.1143)
		(layer "In13.Cu")
		(net "GMI_CPU0_G0_CPU1_G2_TX_DP<9>")
	)
	(segment
		(start 120.891808 -223.911922)
		(end 120.922288 -223.929702)
		(width 0.1143)
		(layer "In13.Cu")
		(net "GMI_CPU0_G0_CPU1_G2_TX_DP<9>")
	)
	(segment
		(start 119.952516 -240.75644)
		(end 119.951754 -240.756948)
		(width 0.1143)
		(layer "In13.Cu")
		(net "GMI_CPU0_G0_CPU1_G2_TX_DP<9>")
	)
	(segment
		(start 157.067758 -188.047376)
		(end 146.22907 -196.93509)
		(width 0.14224)
		(layer "In13.Cu")
		(net "GMI_CPU0_G0_CPU1_G2_TX_DP<9>")
	)
	(segment
		(start 146.22907 -196.93509)
		(end 144.859756 -197.349618)
		(width 0.14224)
		(layer "In13.Cu")
		(net "GMI_CPU0_G0_CPU1_G2_TX_DP<9>")
	)
	(segment
		(start 119.675402 -241.16157)
		(end 119.592598 -241.244374)
		(width 0.1143)
		(layer "In13.Cu")
		(net "GMI_CPU0_G0_CPU1_G2_TX_DP<9>")
	)
	(segment
		(start 350.961452 -219.420694)
		(end 348.5515 -215.36152)
		(width 0.14224)
		(layer "In13.Cu")
		(net "GMI_CPU0_G0_CPU1_G2_TX_DP<9>")
	)
	(segment
		(start 350.604074 -231.036622)
		(end 350.571562 -231.017826)
		(width 0.1143)
		(layer "In13.Cu")
		(net "GMI_CPU0_G0_CPU1_G2_TX_DP<9>")
	)
	(segment
		(start 348.5515 -215.36152)
		(end 313.98718 -187.019946)
		(width 0.14224)
		(layer "In13.Cu")
		(net "GMI_CPU0_G0_CPU1_G2_TX_DP<9>")
	)
	(segment
		(start 120.852692 -238.468916)
		(end 120.891808 -238.491776)
		(width 0.1143)
		(layer "In13.Cu")
		(net "GMI_CPU0_G0_CPU1_G2_TX_DP<9>")
	)
	(segment
		(start 120.891808 -226.177094)
		(end 120.852692 -226.199954)
		(width 0.1143)
		(layer "In13.Cu")
		(net "GMI_CPU0_G0_CPU1_G2_TX_DP<9>")
	)
	(segment
		(start 351.074228 -239.946688)
		(end 351.073466 -239.94618)
		(width 0.1143)
		(layer "In13.Cu")
		(net "GMI_CPU0_G0_CPU1_G2_TX_DP<9>")
	)
	(segment
		(start 120.852692 -227.129086)
		(end 120.891808 -227.151946)
		(width 0.1143)
		(layer "In13.Cu")
		(net "GMI_CPU0_G0_CPU1_G2_TX_DP<9>")
	)
	(segment
		(start 120.891808 -236.871764)
		(end 120.922288 -236.889544)
		(width 0.1143)
		(layer "In13.Cu")
		(net "GMI_CPU0_G0_CPU1_G2_TX_DP<9>")
	)
	(segment
		(start 120.891808 -227.797106)
		(end 120.852692 -227.819966)
		(width 0.1143)
		(layer "In13.Cu")
		(net "GMI_CPU0_G0_CPU1_G2_TX_DP<9>")
	)
	(segment
		(start 350.886268 -221.80423)
		(end 350.886268 -221.411546)
		(width 0.1143)
		(layer "In13.Cu")
		(net "GMI_CPU0_G0_CPU1_G2_TX_DP<9>")
	)
	(segment
		(start 350.64319 -229.43947)
		(end 350.604074 -229.41661)
		(width 0.1143)
		(layer "In13.Cu")
		(net "GMI_CPU0_G0_CPU1_G2_TX_DP<9>")
	)
	(segment
		(start 166.629588 -182.458868)
		(end 161.749994 -184.208166)
		(width 0.14224)
		(layer "In13.Cu")
		(net "GMI_CPU0_G0_CPU1_G2_TX_DP<9>")
	)
	(segment
		(start 120.891808 -238.491776)
		(end 120.922288 -238.509556)
		(width 0.1143)
		(layer "In13.Cu")
		(net "GMI_CPU0_G0_CPU1_G2_TX_DP<9>")
	)
	(segment
		(start 351.543366 -240.756186)
		(end 351.512378 -240.738406)
		(width 0.1143)
		(layer "In13.Cu")
		(net "GMI_CPU0_G0_CPU1_G2_TX_DP<9>")
	)
	(segment
		(start 120.92432 -231.01808)
		(end 120.891808 -231.036876)
		(width 0.1143)
		(layer "In13.Cu")
		(net "GMI_CPU0_G0_CPU1_G2_TX_DP<9>")
	)
	(segment
		(start 120.891808 -227.151946)
		(end 120.922288 -227.169726)
		(width 0.1143)
		(layer "In13.Cu")
		(net "GMI_CPU0_G0_CPU1_G2_TX_DP<9>")
	)
	(segment
		(start 120.855232 -230.370634)
		(end 120.922288 -230.40975)
		(width 0.1143)
		(layer "In13.Cu")
		(net "GMI_CPU0_G0_CPU1_G2_TX_DP<9>")
	)
	(segment
		(start 120.891808 -235.896912)
		(end 120.852692 -235.919772)
		(width 0.1143)
		(layer "In13.Cu")
		(net "GMI_CPU0_G0_CPU1_G2_TX_DP<9>")
	)
	(segment
		(start 351.903284 -241.24412)
		(end 351.82048 -241.161316)
		(width 0.1143)
		(layer "In13.Cu")
		(net "GMI_CPU0_G0_CPU1_G2_TX_DP<9>")
	)
	(segment
		(start 120.922288 -222.91929)
		(end 120.891808 -222.93707)
		(width 0.1143)
		(layer "In13.Cu")
		(net "GMI_CPU0_G0_CPU1_G2_TX_DP<9>")
	)
	(segment
		(start 351.545144 -240.757202)
		(end 351.544128 -240.756694)
		(width 0.1143)
		(layer "In13.Cu")
		(net "GMI_CPU0_G0_CPU1_G2_TX_DP<9>")
	)
	(segment
		(start 120.891808 -233.63174)
		(end 120.922288 -233.64952)
		(width 0.1143)
		(layer "In13.Cu")
		(net "GMI_CPU0_G0_CPU1_G2_TX_DP<9>")
	)
	(segment
		(start 120.422416 -239.946434)
		(end 120.421654 -239.946942)
		(width 0.1143)
		(layer "In13.Cu")
		(net "GMI_CPU0_G0_CPU1_G2_TX_DP<9>")
	)
	(segment
		(start 350.64319 -235.919518)
		(end 350.573594 -235.878878)
		(width 0.1143)
		(layer "In13.Cu")
		(net "GMI_CPU0_G0_CPU1_G2_TX_DP<9>")
	)
	(segment
		(start 120.609614 -221.4118)
		(end 120.609614 -221.804484)
		(width 0.1143)
		(layer "In13.Cu")
		(net "GMI_CPU0_G0_CPU1_G2_TX_DP<9>")
	)
	(segment
		(start 350.64319 -232.679494)
		(end 350.573594 -232.638854)
		(width 0.1143)
		(layer "In13.Cu")
		(net "GMI_CPU0_G0_CPU1_G2_TX_DP<9>")
	)
	(segment
		(start 350.573594 -235.269278)
		(end 350.64319 -235.228638)
		(width 0.1143)
		(layer "In13.Cu")
		(net "GMI_CPU0_G0_CPU1_G2_TX_DP<9>")
	)
	(segment
		(start 350.64319 -231.059482)
		(end 350.604074 -231.036622)
		(width 0.1143)
		(layer "In13.Cu")
		(net "GMI_CPU0_G0_CPU1_G2_TX_DP<9>")
	)
	(segment
		(start 120.891808 -224.557082)
		(end 120.852692 -224.579942)
		(width 0.1143)
		(layer "In13.Cu")
		(net "GMI_CPU0_G0_CPU1_G2_TX_DP<9>")
	)
	(segment
		(start 350.573594 -223.929448)
		(end 350.64319 -223.888808)
		(width 0.1143)
		(layer "In13.Cu")
		(net "GMI_CPU0_G0_CPU1_G2_TX_DP<9>")
	)
	(segment
		(start 120.53443 -221.100396)
		(end 120.58015 -221.146116)
		(width 0.1143)
		(layer "In13.Cu")
		(net "GMI_CPU0_G0_CPU1_G2_TX_DP<9>")
	)
	(segment
		(start 120.891808 -239.136936)
		(end 120.852692 -239.159796)
		(width 0.1143)
		(layer "In13.Cu")
		(net "GMI_CPU0_G0_CPU1_G2_TX_DP<9>")
	)
	(segment
		(start 119.951754 -240.756948)
		(end 119.950738 -240.757456)
		(width 0.1143)
		(layer "In13.Cu")
		(net "GMI_CPU0_G0_CPU1_G2_TX_DP<9>")
	)
	(segment
		(start 350.886268 -221.411546)
		(end 350.915732 -221.382082)
		(width 0.1143)
		(layer "In13.Cu")
		(net "GMI_CPU0_G0_CPU1_G2_TX_DP<9>")
	)
	(arc
		(start 120.922288 -233.64952)
		(mid 121.079265 -233.95432)
		(end 120.922288 -234.25912)
		(width 0.1143)
		(layer "In13.Cu")
		(net "GMI_CPU0_G0_CPU1_G2_TX_DP<9>")
	)
	(arc
		(start 119.912638 -240.779808)
		(mid 119.760651 -240.936316)
		(end 119.679212 -241.13871)
		(width 0.1143)
		(layer "In13.Cu")
		(net "GMI_CPU0_G0_CPU1_G2_TX_DP<9>")
	)
	(arc
		(start 350.64319 -227.128832)
		(mid 350.886517 -226.664266)
		(end 350.64319 -226.1997)
		(width 0.1143)
		(layer "In13.Cu")
		(net "GMI_CPU0_G0_CPU1_G2_TX_DP<9>")
	)
	(arc
		(start 350.886522 -229.904036)
		(mid 350.822007 -229.641817)
		(end 350.64319 -229.43947)
		(width 0.1143)
		(layer "In13.Cu")
		(net "GMI_CPU0_G0_CPU1_G2_TX_DP<9>")
	)
	(arc
		(start 351.356422 -240.434114)
		(mid 351.356017 -240.420746)
		(end 351.354644 -240.407444)
		(width 0.1143)
		(layer "In13.Cu")
		(net "GMI_CPU0_G0_CPU1_G2_TX_DP<9>")
	)
	(arc
		(start 350.573594 -226.15906)
		(mid 350.416617 -225.85426)
		(end 350.573594 -225.54946)
		(width 0.1143)
		(layer "In13.Cu")
		(net "GMI_CPU0_G0_CPU1_G2_TX_DP<9>")
	)
	(arc
		(start 351.042478 -239.9284)
		(mid 350.927802 -239.795066)
		(end 350.886522 -239.624108)
		(width 0.1143)
		(layer "In13.Cu")
		(net "GMI_CPU0_G0_CPU1_G2_TX_DP<9>")
	)
	(arc
		(start 120.922288 -236.889544)
		(mid 121.079265 -237.194344)
		(end 120.922288 -237.499144)
		(width 0.1143)
		(layer "In13.Cu")
		(net "GMI_CPU0_G0_CPU1_G2_TX_DP<9>")
	)
	(arc
		(start 120.609614 -221.804484)
		(mid 120.673988 -222.066688)
		(end 120.852692 -222.26905)
		(width 0.1143)
		(layer "In13.Cu")
		(net "GMI_CPU0_G0_CPU1_G2_TX_DP<9>")
	)
	(arc
		(start 120.60936 -229.90429)
		(mid 120.674596 -230.167881)
		(end 120.855232 -230.370634)
		(width 0.1143)
		(layer "In13.Cu")
		(net "GMI_CPU0_G0_CPU1_G2_TX_DP<9>")
	)
	(arc
		(start 351.354644 -240.407444)
		(mid 351.2831 -240.182126)
		(end 351.142046 -239.992408)
		(width 0.1143)
		(layer "In13.Cu")
		(net "GMI_CPU0_G0_CPU1_G2_TX_DP<9>")
	)
	(arc
		(start 350.573594 -227.779072)
		(mid 350.416617 -227.474272)
		(end 350.573594 -227.169472)
		(width 0.1143)
		(layer "In13.Cu")
		(net "GMI_CPU0_G0_CPU1_G2_TX_DP<9>")
	)
	(arc
		(start 350.64319 -233.608626)
		(mid 350.886517 -233.14406)
		(end 350.64319 -232.679494)
		(width 0.1143)
		(layer "In13.Cu")
		(net "GMI_CPU0_G0_CPU1_G2_TX_DP<9>")
	)
	(arc
		(start 120.852692 -227.819966)
		(mid 120.609365 -228.284532)
		(end 120.852692 -228.749098)
		(width 0.1143)
		(layer "In13.Cu")
		(net "GMI_CPU0_G0_CPU1_G2_TX_DP<9>")
	)
	(arc
		(start 120.852692 -224.579942)
		(mid 120.609365 -225.044508)
		(end 120.852692 -225.509074)
		(width 0.1143)
		(layer "In13.Cu")
		(net "GMI_CPU0_G0_CPU1_G2_TX_DP<9>")
	)
	(arc
		(start 350.64319 -225.50882)
		(mid 350.886517 -225.044254)
		(end 350.64319 -224.579688)
		(width 0.1143)
		(layer "In13.Cu")
		(net "GMI_CPU0_G0_CPU1_G2_TX_DP<9>")
	)
	(arc
		(start 121.07926 -229.094538)
		(mid 121.038294 -229.264944)
		(end 120.92432 -229.398068)
		(width 0.1143)
		(layer "In13.Cu")
		(net "GMI_CPU0_G0_CPU1_G2_TX_DP<9>")
	)
	(arc
		(start 120.353836 -239.992662)
		(mid 120.212749 -240.182364)
		(end 120.141238 -240.407698)
		(width 0.1143)
		(layer "In13.Cu")
		(net "GMI_CPU0_G0_CPU1_G2_TX_DP<9>")
	)
	(arc
		(start 120.13946 -240.434368)
		(mid 120.095389 -240.603904)
		(end 119.983504 -240.73866)
		(width 0.1143)
		(layer "In13.Cu")
		(net "GMI_CPU0_G0_CPU1_G2_TX_DP<9>")
	)
	(arc
		(start 350.573594 -239.118902)
		(mid 350.416617 -238.814102)
		(end 350.573594 -238.509302)
		(width 0.1143)
		(layer "In13.Cu")
		(net "GMI_CPU0_G0_CPU1_G2_TX_DP<9>")
	)
	(arc
		(start 350.886522 -239.624108)
		(mid 350.822007 -239.361889)
		(end 350.64319 -239.159542)
		(width 0.1143)
		(layer "In13.Cu")
		(net "GMI_CPU0_G0_CPU1_G2_TX_DP<9>")
	)
	(arc
		(start 120.922288 -238.509556)
		(mid 121.079265 -238.814356)
		(end 120.922288 -239.119156)
		(width 0.1143)
		(layer "In13.Cu")
		(net "GMI_CPU0_G0_CPU1_G2_TX_DP<9>")
	)
	(arc
		(start 350.571562 -231.017826)
		(mid 350.457633 -230.884679)
		(end 350.416622 -230.714296)
		(width 0.1143)
		(layer "In13.Cu")
		(net "GMI_CPU0_G0_CPU1_G2_TX_DP<9>")
	)
	(arc
		(start 350.416622 -229.094284)
		(mid 350.458171 -228.922862)
		(end 350.573594 -228.789484)
		(width 0.1143)
		(layer "In13.Cu")
		(net "GMI_CPU0_G0_CPU1_G2_TX_DP<9>")
	)
	(arc
		(start 350.64319 -223.888808)
		(mid 350.886517 -223.424242)
		(end 350.64319 -222.959676)
		(width 0.1143)
		(layer "In13.Cu")
		(net "GMI_CPU0_G0_CPU1_G2_TX_DP<9>")
	)
	(arc
		(start 351.82048 -241.161316)
		(mid 351.818692 -241.149867)
		(end 351.81667 -241.138456)
		(width 0.1143)
		(layer "In13.Cu")
		(net "GMI_CPU0_G0_CPU1_G2_TX_DP<9>")
	)
	(arc
		(start 351.81667 -241.138456)
		(mid 351.735237 -240.936058)
		(end 351.583244 -240.779554)
		(width 0.1143)
		(layer "In13.Cu")
		(net "GMI_CPU0_G0_CPU1_G2_TX_DP<9>")
	)
	(arc
		(start 351.142046 -239.992408)
		(mid 351.126514 -239.979813)
		(end 351.11055 -239.96777)
		(width 0.1143)
		(layer "In13.Cu")
		(net "GMI_CPU0_G0_CPU1_G2_TX_DP<9>")
	)
	(arc
		(start 120.852692 -235.919772)
		(mid 120.609365 -236.384338)
		(end 120.852692 -236.848904)
		(width 0.1143)
		(layer "In13.Cu")
		(net "GMI_CPU0_G0_CPU1_G2_TX_DP<9>")
	)
	(arc
		(start 120.922288 -232.029508)
		(mid 121.079265 -232.334308)
		(end 120.922288 -232.639108)
		(width 0.1143)
		(layer "In13.Cu")
		(net "GMI_CPU0_G0_CPU1_G2_TX_DP<9>")
	)
	(arc
		(start 120.922288 -228.789738)
		(mid 121.037715 -228.923114)
		(end 121.07926 -229.094538)
		(width 0.1143)
		(layer "In13.Cu")
		(net "GMI_CPU0_G0_CPU1_G2_TX_DP<9>")
	)
	(arc
		(start 350.64319 -222.268796)
		(mid 350.821833 -222.066401)
		(end 350.886268 -221.80423)
		(width 0.1143)
		(layer "In13.Cu")
		(net "GMI_CPU0_G0_CPU1_G2_TX_DP<9>")
	)
	(arc
		(start 120.852692 -229.439724)
		(mid 120.673879 -229.642074)
		(end 120.60936 -229.90429)
		(width 0.1143)
		(layer "In13.Cu")
		(net "GMI_CPU0_G0_CPU1_G2_TX_DP<9>")
	)
	(arc
		(start 120.922288 -223.929702)
		(mid 121.079265 -224.234502)
		(end 120.922288 -224.539302)
		(width 0.1143)
		(layer "In13.Cu")
		(net "GMI_CPU0_G0_CPU1_G2_TX_DP<9>")
	)
	(arc
		(start 120.852692 -226.199954)
		(mid 120.609365 -226.66452)
		(end 120.852692 -227.129086)
		(width 0.1143)
		(layer "In13.Cu")
		(net "GMI_CPU0_G0_CPU1_G2_TX_DP<9>")
	)
	(arc
		(start 120.922288 -225.549714)
		(mid 121.079265 -225.854514)
		(end 120.922288 -226.159314)
		(width 0.1143)
		(layer "In13.Cu")
		(net "GMI_CPU0_G0_CPU1_G2_TX_DP<9>")
	)
	(arc
		(start 120.852692 -234.29976)
		(mid 120.609365 -234.764326)
		(end 120.852692 -235.228892)
		(width 0.1143)
		(layer "In13.Cu")
		(net "GMI_CPU0_G0_CPU1_G2_TX_DP<9>")
	)
	(arc
		(start 350.573594 -237.49889)
		(mid 350.416617 -237.19409)
		(end 350.573594 -236.88929)
		(width 0.1143)
		(layer "In13.Cu")
		(net "GMI_CPU0_G0_CPU1_G2_TX_DP<9>")
	)
	(arc
		(start 120.141238 -240.407698)
		(mid 120.139881 -240.421002)
		(end 120.13946 -240.434368)
		(width 0.1143)
		(layer "In13.Cu")
		(net "GMI_CPU0_G0_CPU1_G2_TX_DP<9>")
	)
	(arc
		(start 350.573594 -232.638854)
		(mid 350.416617 -232.334054)
		(end 350.573594 -232.029254)
		(width 0.1143)
		(layer "In13.Cu")
		(net "GMI_CPU0_G0_CPU1_G2_TX_DP<9>")
	)
	(arc
		(start 120.852692 -232.679748)
		(mid 120.609365 -233.144314)
		(end 120.852692 -233.60888)
		(width 0.1143)
		(layer "In13.Cu")
		(net "GMI_CPU0_G0_CPU1_G2_TX_DP<9>")
	)
	(arc
		(start 350.571562 -229.397814)
		(mid 350.457633 -229.264667)
		(end 350.416622 -229.094284)
		(width 0.1143)
		(layer "In13.Cu")
		(net "GMI_CPU0_G0_CPU1_G2_TX_DP<9>")
	)
	(arc
		(start 121.07926 -230.71455)
		(mid 121.038294 -230.884956)
		(end 120.92432 -231.01808)
		(width 0.1143)
		(layer "In13.Cu")
		(net "GMI_CPU0_G0_CPU1_G2_TX_DP<9>")
	)
	(arc
		(start 120.385332 -239.968024)
		(mid 120.369363 -239.980061)
		(end 120.353836 -239.992662)
		(width 0.1143)
		(layer "In13.Cu")
		(net "GMI_CPU0_G0_CPU1_G2_TX_DP<9>")
	)
	(arc
		(start 350.64319 -228.748844)
		(mid 350.886517 -228.284278)
		(end 350.64319 -227.819712)
		(width 0.1143)
		(layer "In13.Cu")
		(net "GMI_CPU0_G0_CPU1_G2_TX_DP<9>")
	)
	(arc
		(start 351.512378 -240.738406)
		(mid 351.400581 -240.603605)
		(end 351.356422 -240.434114)
		(width 0.1143)
		(layer "In13.Cu")
		(net "GMI_CPU0_G0_CPU1_G2_TX_DP<9>")
	)
	(arc
		(start 120.922288 -227.169726)
		(mid 121.079265 -227.474526)
		(end 120.922288 -227.779326)
		(width 0.1143)
		(layer "In13.Cu")
		(net "GMI_CPU0_G0_CPU1_G2_TX_DP<9>")
	)
	(arc
		(start 120.60936 -239.624362)
		(mid 120.568105 -239.795333)
		(end 120.453404 -239.928654)
		(width 0.1143)
		(layer "In13.Cu")
		(net "GMI_CPU0_G0_CPU1_G2_TX_DP<9>")
	)
	(arc
		(start 120.922288 -235.269532)
		(mid 121.079265 -235.574332)
		(end 120.922288 -235.879132)
		(width 0.1143)
		(layer "In13.Cu")
		(net "GMI_CPU0_G0_CPU1_G2_TX_DP<9>")
	)
	(arc
		(start 119.679212 -241.13871)
		(mid 119.677189 -241.15012)
		(end 119.675402 -241.16157)
		(width 0.1143)
		(layer "In13.Cu")
		(net "GMI_CPU0_G0_CPU1_G2_TX_DP<9>")
	)
	(arc
		(start 120.922288 -222.30969)
		(mid 121.079265 -222.61449)
		(end 120.922288 -222.91929)
		(width 0.1143)
		(layer "In13.Cu")
		(net "GMI_CPU0_G0_CPU1_G2_TX_DP<9>")
	)
	(arc
		(start 350.573594 -235.878878)
		(mid 350.416617 -235.574078)
		(end 350.573594 -235.269278)
		(width 0.1143)
		(layer "In13.Cu")
		(net "GMI_CPU0_G0_CPU1_G2_TX_DP<9>")
	)
	(arc
		(start 120.852692 -231.059736)
		(mid 120.609365 -231.524302)
		(end 120.852692 -231.988868)
		(width 0.1143)
		(layer "In13.Cu")
		(net "GMI_CPU0_G0_CPU1_G2_TX_DP<9>")
	)
	(arc
		(start 350.64065 -230.37038)
		(mid 350.821302 -230.167635)
		(end 350.886522 -229.904036)
		(width 0.1143)
		(layer "In13.Cu")
		(net "GMI_CPU0_G0_CPU1_G2_TX_DP<9>")
	)
	(arc
		(start 120.922288 -230.40975)
		(mid 121.037715 -230.543126)
		(end 121.07926 -230.71455)
		(width 0.1143)
		(layer "In13.Cu")
		(net "GMI_CPU0_G0_CPU1_G2_TX_DP<9>")
	)
	(arc
		(start 350.64319 -238.468662)
		(mid 350.886517 -238.004096)
		(end 350.64319 -237.53953)
		(width 0.1143)
		(layer "In13.Cu")
		(net "GMI_CPU0_G0_CPU1_G2_TX_DP<9>")
	)
	(arc
		(start 350.573594 -222.919036)
		(mid 350.416617 -222.614236)
		(end 350.573594 -222.309436)
		(width 0.1143)
		(layer "In13.Cu")
		(net "GMI_CPU0_G0_CPU1_G2_TX_DP<9>")
	)
	(arc
		(start 350.64319 -235.228638)
		(mid 350.886517 -234.764072)
		(end 350.64319 -234.299506)
		(width 0.1143)
		(layer "In13.Cu")
		(net "GMI_CPU0_G0_CPU1_G2_TX_DP<9>")
	)
	(arc
		(start 350.64319 -231.988614)
		(mid 350.886517 -231.524048)
		(end 350.64319 -231.059482)
		(width 0.1143)
		(layer "In13.Cu")
		(net "GMI_CPU0_G0_CPU1_G2_TX_DP<9>")
	)
	(arc
		(start 120.852692 -222.95993)
		(mid 120.609365 -223.424496)
		(end 120.852692 -223.889062)
		(width 0.1143)
		(layer "In13.Cu")
		(net "GMI_CPU0_G0_CPU1_G2_TX_DP<9>")
	)
	(arc
		(start 350.416622 -230.714296)
		(mid 350.458171 -230.542874)
		(end 350.573594 -230.409496)
		(width 0.1143)
		(layer "In13.Cu")
		(net "GMI_CPU0_G0_CPU1_G2_TX_DP<9>")
	)
	(arc
		(start 120.852692 -239.159796)
		(mid 120.673879 -239.362146)
		(end 120.60936 -239.624362)
		(width 0.1143)
		(layer "In13.Cu")
		(net "GMI_CPU0_G0_CPU1_G2_TX_DP<9>")
	)
	(arc
		(start 350.573594 -224.539048)
		(mid 350.416617 -224.234248)
		(end 350.573594 -223.929448)
		(width 0.1143)
		(layer "In13.Cu")
		(net "GMI_CPU0_G0_CPU1_G2_TX_DP<9>")
	)
	(arc
		(start 350.64319 -236.84865)
		(mid 350.886517 -236.384084)
		(end 350.64319 -235.919518)
		(width 0.1143)
		(layer "In13.Cu")
		(net "GMI_CPU0_G0_CPU1_G2_TX_DP<9>")
	)
	(arc
		(start 120.852692 -237.539784)
		(mid 120.609365 -238.00435)
		(end 120.852692 -238.468916)
		(width 0.1143)
		(layer "In13.Cu")
		(net "GMI_CPU0_G0_CPU1_G2_TX_DP<9>")
	)
	(arc
		(start 350.573594 -234.258866)
		(mid 350.416617 -233.954066)
		(end 350.573594 -233.649266)
		(width 0.1143)
		(layer "In13.Cu")
		(net "GMI_CPU0_G0_CPU1_G2_TX_DP<9>")
	)
	(segment
		(start 352.668078 -239.890046)
		(end 352.201226 -239.624108)
		(width 0.12954)
		(layer "F.Cu")
		(net "GMI_CPU0_G0_CPU1_G2_TX_DP<8>")
	)
	(segment
		(start 118.827804 -239.8903)
		(end 119.294656 -239.624362)
		(width 0.12954)
		(layer "F.Cu")
		(net "GMI_CPU0_G0_CPU1_G2_TX_DP<8>")
	)
	(segment
		(start 119.950738 -235.251244)
		(end 119.951754 -235.251752)
		(width 0.1143)
		(layer "In13.Cu")
		(net "GMI_CPU0_G0_CPU1_G2_TX_DP<8>")
	)
	(segment
		(start 119.956834 -231.034082)
		(end 119.912638 -231.059736)
		(width 0.1143)
		(layer "In13.Cu")
		(net "GMI_CPU0_G0_CPU1_G2_TX_DP<8>")
	)
	(segment
		(start 351.545144 -233.630978)
		(end 351.547684 -233.629454)
		(width 0.1143)
		(layer "In13.Cu")
		(net "GMI_CPU0_G0_CPU1_G2_TX_DP<8>")
	)
	(segment
		(start 351.503996 -222.302832)
		(end 351.582482 -222.256096)
		(width 0.1143)
		(layer "In13.Cu")
		(net "GMI_CPU0_G0_CPU1_G2_TX_DP<8>")
	)
	(segment
		(start 351.860612 -221.382082)
		(end 351.860612 -221.145862)
		(width 0.1143)
		(layer "In13.Cu")
		(net "GMI_CPU0_G0_CPU1_G2_TX_DP<8>")
	)
	(segment
		(start 119.951754 -237.516924)
		(end 119.950738 -237.517432)
		(width 0.1143)
		(layer "In13.Cu")
		(net "GMI_CPU0_G0_CPU1_G2_TX_DP<8>")
	)
	(segment
		(start 119.920258 -231.99344)
		(end 119.950738 -232.01122)
		(width 0.1143)
		(layer "In13.Cu")
		(net "GMI_CPU0_G0_CPU1_G2_TX_DP<8>")
	)
	(segment
		(start 119.952516 -232.65638)
		(end 119.951754 -232.656888)
		(width 0.1143)
		(layer "In13.Cu")
		(net "GMI_CPU0_G0_CPU1_G2_TX_DP<8>")
	)
	(segment
		(start 119.942864 -226.18192)
		(end 119.94134 -226.182936)
		(width 0.1143)
		(layer "In13.Cu")
		(net "GMI_CPU0_G0_CPU1_G2_TX_DP<8>")
	)
	(segment
		(start 119.952516 -234.276392)
		(end 119.951754 -234.2769)
		(width 0.1143)
		(layer "In13.Cu")
		(net "GMI_CPU0_G0_CPU1_G2_TX_DP<8>")
	)
	(segment
		(start 351.575624 -225.513392)
		(end 351.576386 -225.512884)
		(width 0.1143)
		(layer "In13.Cu")
		(net "GMI_CPU0_G0_CPU1_G2_TX_DP<8>")
	)
	(segment
		(start 119.951754 -235.251752)
		(end 119.952516 -235.25226)
		(width 0.1143)
		(layer "In13.Cu")
		(net "GMI_CPU0_G0_CPU1_G2_TX_DP<8>")
	)
	(segment
		(start 351.49282 -227.18395)
		(end 351.512378 -227.16998)
		(width 0.1143)
		(layer "In13.Cu")
		(net "GMI_CPU0_G0_CPU1_G2_TX_DP<8>")
	)
	(segment
		(start 351.544128 -222.936816)
		(end 351.543366 -222.936308)
		(width 0.1143)
		(layer "In13.Cu")
		(net "GMI_CPU0_G0_CPU1_G2_TX_DP<8>")
	)
	(segment
		(start 351.540572 -230.393748)
		(end 351.542096 -230.392986)
		(width 0.1143)
		(layer "In13.Cu")
		(net "GMI_CPU0_G0_CPU1_G2_TX_DP<8>")
	)
	(segment
		(start 119.675402 -239.541558)
		(end 119.592598 -239.624362)
		(width 0.1143)
		(layer "In13.Cu")
		(net "GMI_CPU0_G0_CPU1_G2_TX_DP<8>")
	)
	(segment
		(start 351.512378 -235.87837)
		(end 351.503996 -235.872274)
		(width 0.1143)
		(layer "In13.Cu")
		(net "GMI_CPU0_G0_CPU1_G2_TX_DP<8>")
	)
	(segment
		(start 166.384986 -181.515766)
		(end 160.978342 -183.449214)
		(width 0.14224)
		(layer "In13.Cu")
		(net "GMI_CPU0_G0_CPU1_G2_TX_DP<8>")
	)
	(segment
		(start 351.547684 -227.14966)
		(end 351.548446 -227.149152)
		(width 0.1143)
		(layer "In13.Cu")
		(net "GMI_CPU0_G0_CPU1_G2_TX_DP<8>")
	)
	(segment
		(start 351.503996 -235.275882)
		(end 351.512378 -235.269786)
		(width 0.1143)
		(layer "In13.Cu")
		(net "GMI_CPU0_G0_CPU1_G2_TX_DP<8>")
	)
	(segment
		(start 119.983504 -226.158806)
		(end 119.952516 -226.176586)
		(width 0.1143)
		(layer "In13.Cu")
		(net "GMI_CPU0_G0_CPU1_G2_TX_DP<8>")
	)
	(segment
		(start 351.545144 -235.25099)
		(end 351.547684 -235.249466)
		(width 0.1143)
		(layer "In13.Cu")
		(net "GMI_CPU0_G0_CPU1_G2_TX_DP<8>")
	)
	(segment
		(start 351.550732 -226.180396)
		(end 351.547938 -226.178872)
		(width 0.1143)
		(layer "In13.Cu")
		(net "GMI_CPU0_G0_CPU1_G2_TX_DP<8>")
	)
	(segment
		(start 351.50171 -225.557588)
		(end 351.512378 -225.549968)
		(width 0.1143)
		(layer "In13.Cu")
		(net "GMI_CPU0_G0_CPU1_G2_TX_DP<8>")
	)
	(segment
		(start 119.983504 -235.878624)
		(end 119.952516 -235.896404)
		(width 0.1143)
		(layer "In13.Cu")
		(net "GMI_CPU0_G0_CPU1_G2_TX_DP<8>")
	)
	(segment
		(start 119.912638 -225.509074)
		(end 119.919496 -225.513138)
		(width 0.1143)
		(layer "In13.Cu")
		(net "GMI_CPU0_G0_CPU1_G2_TX_DP<8>")
	)
	(segment
		(start 119.950738 -222.937578)
		(end 119.949214 -222.938594)
		(width 0.1143)
		(layer "In13.Cu")
		(net "GMI_CPU0_G0_CPU1_G2_TX_DP<8>")
	)
	(segment
		(start 351.575624 -231.993186)
		(end 351.576386 -231.992678)
		(width 0.1143)
		(layer "In13.Cu")
		(net "GMI_CPU0_G0_CPU1_G2_TX_DP<8>")
	)
	(segment
		(start 119.983504 -232.6386)
		(end 119.952516 -232.65638)
		(width 0.1143)
		(layer "In13.Cu")
		(net "GMI_CPU0_G0_CPU1_G2_TX_DP<8>")
	)
	(segment
		(start 351.545144 -225.531172)
		(end 351.547684 -225.529648)
		(width 0.1143)
		(layer "In13.Cu")
		(net "GMI_CPU0_G0_CPU1_G2_TX_DP<8>")
	)
	(segment
		(start 119.951754 -230.39197)
		(end 119.952516 -230.392478)
		(width 0.1143)
		(layer "In13.Cu")
		(net "GMI_CPU0_G0_CPU1_G2_TX_DP<8>")
	)
	(segment
		(start 119.994172 -226.151186)
		(end 119.983504 -226.158806)
		(width 0.1143)
		(layer "In13.Cu")
		(net "GMI_CPU0_G0_CPU1_G2_TX_DP<8>")
	)
	(segment
		(start 351.512378 -239.118394)
		(end 351.503996 -239.112298)
		(width 0.1143)
		(layer "In13.Cu")
		(net "GMI_CPU0_G0_CPU1_G2_TX_DP<8>")
	)
	(segment
		(start 351.545144 -234.277154)
		(end 351.544128 -234.276646)
		(width 0.1143)
		(layer "In13.Cu")
		(net "GMI_CPU0_G0_CPU1_G2_TX_DP<8>")
	)
	(segment
		(start 351.576386 -233.61269)
		(end 351.583244 -233.608626)
		(width 0.1143)
		(layer "In13.Cu")
		(net "GMI_CPU0_G0_CPU1_G2_TX_DP<8>")
	)
	(segment
		(start 351.544128 -227.796852)
		(end 351.543366 -227.796344)
		(width 0.1143)
		(layer "In13.Cu")
		(net "GMI_CPU0_G0_CPU1_G2_TX_DP<8>")
	)
	(segment
		(start 351.543366 -233.631994)
		(end 351.544128 -233.631486)
		(width 0.1143)
		(layer "In13.Cu")
		(net "GMI_CPU0_G0_CPU1_G2_TX_DP<8>")
	)
	(segment
		(start 351.575624 -227.133404)
		(end 351.576386 -227.132896)
		(width 0.1143)
		(layer "In13.Cu")
		(net "GMI_CPU0_G0_CPU1_G2_TX_DP<8>")
	)
	(segment
		(start 351.635822 -239.196118)
		(end 351.544128 -239.136682)
		(width 0.1143)
		(layer "In13.Cu")
		(net "GMI_CPU0_G0_CPU1_G2_TX_DP<8>")
	)
	(segment
		(start 119.983504 -239.118648)
		(end 119.952516 -239.136428)
		(width 0.1143)
		(layer "In13.Cu")
		(net "GMI_CPU0_G0_CPU1_G2_TX_DP<8>")
	)
	(segment
		(start 351.906332 -221.093538)
		(end 351.906332 -219.185998)
		(width 0.14224)
		(layer "In13.Cu")
		(net "GMI_CPU0_G0_CPU1_G2_TX_DP<8>")
	)
	(segment
		(start 119.951754 -239.136936)
		(end 119.86006 -239.196372)
		(width 0.1143)
		(layer "In13.Cu")
		(net "GMI_CPU0_G0_CPU1_G2_TX_DP<8>")
	)
	(segment
		(start 351.512378 -223.929956)
		(end 351.543366 -223.912176)
		(width 0.1143)
		(layer "In13.Cu")
		(net "GMI_CPU0_G0_CPU1_G2_TX_DP<8>")
	)
	(segment
		(start 119.951754 -235.896912)
		(end 119.950738 -235.89742)
		(width 0.1143)
		(layer "In13.Cu")
		(net "GMI_CPU0_G0_CPU1_G2_TX_DP<8>")
	)
	(segment
		(start 119.951754 -236.871764)
		(end 119.952516 -236.872272)
		(width 0.1143)
		(layer "In13.Cu")
		(net "GMI_CPU0_G0_CPU1_G2_TX_DP<8>")
	)
	(segment
		(start 119.94134 -226.182936)
		(end 119.912638 -226.199954)
		(width 0.1143)
		(layer "In13.Cu")
		(net "GMI_CPU0_G0_CPU1_G2_TX_DP<8>")
	)
	(segment
		(start 119.952516 -235.25226)
		(end 119.983504 -235.27004)
		(width 0.1143)
		(layer "In13.Cu")
		(net "GMI_CPU0_G0_CPU1_G2_TX_DP<8>")
	)
	(segment
		(start 351.356422 -229.094284)
		(end 351.356422 -229.093522)
		(width 0.1143)
		(layer "In13.Cu")
		(net "GMI_CPU0_G0_CPU1_G2_TX_DP<8>")
	)
	(segment
		(start 351.55124 -237.520734)
		(end 351.546668 -237.518194)
		(width 0.1143)
		(layer "In13.Cu")
		(net "GMI_CPU0_G0_CPU1_G2_TX_DP<8>")
	)
	(segment
		(start 119.919496 -236.852968)
		(end 119.920258 -236.853476)
		(width 0.1143)
		(layer "In13.Cu")
		(net "GMI_CPU0_G0_CPU1_G2_TX_DP<8>")
	)
	(segment
		(start 119.950738 -228.77145)
		(end 119.951754 -228.771958)
		(width 0.1143)
		(layer "In13.Cu")
		(net "GMI_CPU0_G0_CPU1_G2_TX_DP<8>")
	)
	(segment
		(start 314.625482 -186.298586)
		(end 308.433216 -182.793132)
		(width 0.14224)
		(layer "In13.Cu")
		(net "GMI_CPU0_G0_CPU1_G2_TX_DP<8>")
	)
	(segment
		(start 351.544128 -225.53168)
		(end 351.545144 -225.531172)
		(width 0.1143)
		(layer "In13.Cu")
		(net "GMI_CPU0_G0_CPU1_G2_TX_DP<8>")
	)
	(segment
		(start 351.512378 -234.258358)
		(end 351.503996 -234.252262)
		(width 0.1143)
		(layer "In13.Cu")
		(net "GMI_CPU0_G0_CPU1_G2_TX_DP<8>")
	)
	(segment
		(start 119.950738 -225.531426)
		(end 119.951754 -225.531934)
		(width 0.1143)
		(layer "In13.Cu")
		(net "GMI_CPU0_G0_CPU1_G2_TX_DP<8>")
	)
	(segment
		(start 119.908828 -235.22686)
		(end 119.950738 -235.251244)
		(width 0.1143)
		(layer "In13.Cu")
		(net "GMI_CPU0_G0_CPU1_G2_TX_DP<8>")
	)
	(segment
		(start 119.951754 -223.911922)
		(end 119.952516 -223.91243)
		(width 0.1143)
		(layer "In13.Cu")
		(net "GMI_CPU0_G0_CPU1_G2_TX_DP<8>")
	)
	(segment
		(start 351.601024 -235.215684)
		(end 351.620582 -235.199936)
		(width 0.1143)
		(layer "In13.Cu")
		(net "GMI_CPU0_G0_CPU1_G2_TX_DP<8>")
	)
	(segment
		(start 119.952516 -233.632248)
		(end 119.983504 -233.650028)
		(width 0.1143)
		(layer "In13.Cu")
		(net "GMI_CPU0_G0_CPU1_G2_TX_DP<8>")
	)
	(segment
		(start 119.944642 -222.941134)
		(end 119.912638 -222.95993)
		(width 0.1143)
		(layer "In13.Cu")
		(net "GMI_CPU0_G0_CPU1_G2_TX_DP<8>")
	)
	(segment
		(start 351.544128 -230.391716)
		(end 351.54743 -230.389684)
		(width 0.1143)
		(layer "In13.Cu")
		(net "GMI_CPU0_G0_CPU1_G2_TX_DP<8>")
	)
	(segment
		(start 351.543366 -232.656126)
		(end 351.512378 -232.638346)
		(width 0.1143)
		(layer "In13.Cu")
		(net "GMI_CPU0_G0_CPU1_G2_TX_DP<8>")
	)
	(segment
		(start 119.920258 -223.893634)
		(end 119.950738 -223.911414)
		(width 0.1143)
		(layer "In13.Cu")
		(net "GMI_CPU0_G0_CPU1_G2_TX_DP<8>")
	)
	(segment
		(start 351.545144 -227.151184)
		(end 351.547684 -227.14966)
		(width 0.1143)
		(layer "In13.Cu")
		(net "GMI_CPU0_G0_CPU1_G2_TX_DP<8>")
	)
	(segment
		(start 351.81667 -239.518444)
		(end 351.804732 -239.455452)
		(width 0.1143)
		(layer "In13.Cu")
		(net "GMI_CPU0_G0_CPU1_G2_TX_DP<8>")
	)
	(segment
		(start 351.860612 -221.145862)
		(end 351.906332 -221.100142)
		(width 0.1143)
		(layer "In13.Cu")
		(net "GMI_CPU0_G0_CPU1_G2_TX_DP<8>")
	)
	(segment
		(start 119.951754 -225.531934)
		(end 119.952516 -225.532442)
		(width 0.1143)
		(layer "In13.Cu")
		(net "GMI_CPU0_G0_CPU1_G2_TX_DP<8>")
	)
	(segment
		(start 351.538032 -239.133126)
		(end 351.512378 -239.118394)
		(width 0.1143)
		(layer "In13.Cu")
		(net "GMI_CPU0_G0_CPU1_G2_TX_DP<8>")
	)
	(segment
		(start 351.583244 -231.059482)
		(end 351.539048 -231.033828)
		(width 0.1143)
		(layer "In13.Cu")
		(net "GMI_CPU0_G0_CPU1_G2_TX_DP<8>")
	)
	(segment
		(start 351.576386 -227.132896)
		(end 351.583244 -227.128832)
		(width 0.1143)
		(layer "In13.Cu")
		(net "GMI_CPU0_G0_CPU1_G2_TX_DP<8>")
	)
	(segment
		(start 351.55124 -232.660698)
		(end 351.546668 -232.658158)
		(width 0.1143)
		(layer "In13.Cu")
		(net "GMI_CPU0_G0_CPU1_G2_TX_DP<8>")
	)
	(segment
		(start 119.949214 -237.518448)
		(end 119.944642 -237.520988)
		(width 0.1143)
		(layer "In13.Cu")
		(net "GMI_CPU0_G0_CPU1_G2_TX_DP<8>")
	)
	(segment
		(start 119.956326 -222.934276)
		(end 119.952516 -222.936562)
		(width 0.1143)
		(layer "In13.Cu")
		(net "GMI_CPU0_G0_CPU1_G2_TX_DP<8>")
	)
	(segment
		(start 351.903284 -239.624108)
		(end 351.82048 -239.541304)
		(width 0.1143)
		(layer "In13.Cu")
		(net "GMI_CPU0_G0_CPU1_G2_TX_DP<8>")
	)
	(segment
		(start 119.949214 -222.938594)
		(end 119.944642 -222.941134)
		(width 0.1143)
		(layer "In13.Cu")
		(net "GMI_CPU0_G0_CPU1_G2_TX_DP<8>")
	)
	(segment
		(start 119.919496 -228.753162)
		(end 119.920258 -228.75367)
		(width 0.1143)
		(layer "In13.Cu")
		(net "GMI_CPU0_G0_CPU1_G2_TX_DP<8>")
	)
	(segment
		(start 351.503996 -233.65587)
		(end 351.512378 -233.649774)
		(width 0.1143)
		(layer "In13.Cu")
		(net "GMI_CPU0_G0_CPU1_G2_TX_DP<8>")
	)
	(segment
		(start 351.512378 -230.410004)
		(end 351.540572 -230.393748)
		(width 0.1143)
		(layer "In13.Cu")
		(net "GMI_CPU0_G0_CPU1_G2_TX_DP<8>")
	)
	(segment
		(start 351.511616 -228.790246)
		(end 351.540064 -228.77399)
		(width 0.1143)
		(layer "In13.Cu")
		(net "GMI_CPU0_G0_CPU1_G2_TX_DP<8>")
	)
	(segment
		(start 351.598992 -235.217208)
		(end 351.601024 -235.215684)
		(width 0.1143)
		(layer "In13.Cu")
		(net "GMI_CPU0_G0_CPU1_G2_TX_DP<8>")
	)
	(segment
		(start 119.951754 -226.177094)
		(end 119.950738 -226.177602)
		(width 0.1143)
		(layer "In13.Cu")
		(net "GMI_CPU0_G0_CPU1_G2_TX_DP<8>")
	)
	(segment
		(start 119.94515 -226.18065)
		(end 119.942864 -226.18192)
		(width 0.1143)
		(layer "In13.Cu")
		(net "GMI_CPU0_G0_CPU1_G2_TX_DP<8>")
	)
	(segment
		(start 119.944642 -237.520988)
		(end 119.912638 -237.539784)
		(width 0.1143)
		(layer "In13.Cu")
		(net "GMI_CPU0_G0_CPU1_G2_TX_DP<8>")
	)
	(segment
		(start 119.912638 -227.129086)
		(end 119.919496 -227.13315)
		(width 0.1143)
		(layer "In13.Cu")
		(net "GMI_CPU0_G0_CPU1_G2_TX_DP<8>")
	)
	(segment
		(start 119.949214 -232.658412)
		(end 119.944642 -232.660952)
		(width 0.1143)
		(layer "In13.Cu")
		(net "GMI_CPU0_G0_CPU1_G2_TX_DP<8>")
	)
	(segment
		(start 351.512378 -237.498382)
		(end 351.504758 -237.493048)
		(width 0.1143)
		(layer "In13.Cu")
		(net "GMI_CPU0_G0_CPU1_G2_TX_DP<8>")
	)
	(segment
		(start 351.543366 -225.532188)
		(end 351.544128 -225.53168)
		(width 0.1143)
		(layer "In13.Cu")
		(net "GMI_CPU0_G0_CPU1_G2_TX_DP<8>")
	)
	(segment
		(start 351.620836 -234.328462)
		(end 351.599246 -234.31119)
		(width 0.1143)
		(layer "In13.Cu")
		(net "GMI_CPU0_G0_CPU1_G2_TX_DP<8>")
	)
	(segment
		(start 119.920258 -227.133658)
		(end 119.950738 -227.151438)
		(width 0.1143)
		(layer "In13.Cu")
		(net "GMI_CPU0_G0_CPU1_G2_TX_DP<8>")
	)
	(segment
		(start 122.348244 -214.582248)
		(end 119.58955 -219.304362)
		(width 0.14224)
		(layer "In13.Cu")
		(net "GMI_CPU0_G0_CPU1_G2_TX_DP<8>")
	)
	(segment
		(start 351.547938 -226.178872)
		(end 351.546922 -226.178364)
		(width 0.1143)
		(layer "In13.Cu")
		(net "GMI_CPU0_G0_CPU1_G2_TX_DP<8>")
	)
	(segment
		(start 351.544128 -228.771704)
		(end 351.545144 -228.771196)
		(width 0.1143)
		(layer "In13.Cu")
		(net "GMI_CPU0_G0_CPU1_G2_TX_DP<8>")
	)
	(segment
		(start 119.950738 -233.631232)
		(end 119.951754 -233.63174)
		(width 0.1143)
		(layer "In13.Cu")
		(net "GMI_CPU0_G0_CPU1_G2_TX_DP<8>")
	)
	(segment
		(start 119.943118 -232.661968)
		(end 119.907812 -232.682542)
		(width 0.1143)
		(layer "In13.Cu")
		(net "GMI_CPU0_G0_CPU1_G2_TX_DP<8>")
	)
	(segment
		(start 351.543366 -227.796344)
		(end 351.512378 -227.778564)
		(width 0.1143)
		(layer "In13.Cu")
		(net "GMI_CPU0_G0_CPU1_G2_TX_DP<8>")
	)
	(segment
		(start 119.952516 -236.872272)
		(end 119.983504 -236.890052)
		(width 0.1143)
		(layer "In13.Cu")
		(net "GMI_CPU0_G0_CPU1_G2_TX_DP<8>")
	)
	(segment
		(start 351.512378 -227.16998)
		(end 351.543366 -227.1522)
		(width 0.1143)
		(layer "In13.Cu")
		(net "GMI_CPU0_G0_CPU1_G2_TX_DP<8>")
	)
	(segment
		(start 351.546668 -237.518194)
		(end 351.545144 -237.517178)
		(width 0.1143)
		(layer "In13.Cu")
		(net "GMI_CPU0_G0_CPU1_G2_TX_DP<8>")
	)
	(segment
		(start 119.919496 -231.992932)
		(end 119.920258 -231.99344)
		(width 0.1143)
		(layer "In13.Cu")
		(net "GMI_CPU0_G0_CPU1_G2_TX_DP<8>")
	)
	(segment
		(start 119.952516 -232.012236)
		(end 119.983504 -232.030016)
		(width 0.1143)
		(layer "In13.Cu")
		(net "GMI_CPU0_G0_CPU1_G2_TX_DP<8>")
	)
	(segment
		(start 351.547684 -225.529648)
		(end 351.548446 -225.52914)
		(width 0.1143)
		(layer "In13.Cu")
		(net "GMI_CPU0_G0_CPU1_G2_TX_DP<8>")
	)
	(segment
		(start 119.983504 -237.498636)
		(end 119.952516 -237.516416)
		(width 0.1143)
		(layer "In13.Cu")
		(net "GMI_CPU0_G0_CPU1_G2_TX_DP<8>")
	)
	(segment
		(start 351.543366 -222.936308)
		(end 351.539556 -222.934022)
		(width 0.1143)
		(layer "In13.Cu")
		(net "GMI_CPU0_G0_CPU1_G2_TX_DP<8>")
	)
	(segment
		(start 119.944642 -234.280964)
		(end 119.943118 -234.28198)
		(width 0.1143)
		(layer "In13.Cu")
		(net "GMI_CPU0_G0_CPU1_G2_TX_DP<8>")
	)
	(segment
		(start 351.543366 -235.252006)
		(end 351.544128 -235.251498)
		(width 0.1143)
		(layer "In13.Cu")
		(net "GMI_CPU0_G0_CPU1_G2_TX_DP<8>")
	)
	(segment
		(start 351.539556 -222.934022)
		(end 351.536254 -222.932244)
		(width 0.1143)
		(layer "In13.Cu")
		(net "GMI_CPU0_G0_CPU1_G2_TX_DP<8>")
	)
	(segment
		(start 351.540064 -228.77399)
		(end 351.540318 -228.77399)
		(width 0.1143)
		(layer "In13.Cu")
		(net "GMI_CPU0_G0_CPU1_G2_TX_DP<8>")
	)
	(segment
		(start 351.512378 -236.889798)
		(end 351.543366 -236.872018)
		(width 0.1143)
		(layer "In13.Cu")
		(net "GMI_CPU0_G0_CPU1_G2_TX_DP<8>")
	)
	(segment
		(start 351.543366 -230.392224)
		(end 351.544128 -230.391716)
		(width 0.1143)
		(layer "In13.Cu")
		(net "GMI_CPU0_G0_CPU1_G2_TX_DP<8>")
	)
	(segment
		(start 351.512378 -238.50981)
		(end 351.543366 -238.49203)
		(width 0.1143)
		(layer "In13.Cu")
		(net "GMI_CPU0_G0_CPU1_G2_TX_DP<8>")
	)
	(segment
		(start 351.545652 -229.417372)
		(end 351.54489 -229.416864)
		(width 0.1143)
		(layer "In13.Cu")
		(net "GMI_CPU0_G0_CPU1_G2_TX_DP<8>")
	)
	(segment
		(start 351.544128 -235.251498)
		(end 351.545144 -235.25099)
		(width 0.1143)
		(layer "In13.Cu")
		(net "GMI_CPU0_G0_CPU1_G2_TX_DP<8>")
	)
	(segment
		(start 351.543366 -235.89615)
		(end 351.512378 -235.87837)
		(width 0.1143)
		(layer "In13.Cu")
		(net "GMI_CPU0_G0_CPU1_G2_TX_DP<8>")
	)
	(segment
		(start 119.58955 -221.100396)
		(end 119.63527 -221.146116)
		(width 0.1143)
		(layer "In13.Cu")
		(net "GMI_CPU0_G0_CPU1_G2_TX_DP<8>")
	)
	(segment
		(start 119.983504 -233.650028)
		(end 119.991886 -233.656124)
		(width 0.1143)
		(layer "In13.Cu")
		(net "GMI_CPU0_G0_CPU1_G2_TX_DP<8>")
	)
	(segment
		(start 351.545144 -224.557336)
		(end 351.544128 -224.556828)
		(width 0.1143)
		(layer "In13.Cu")
		(net "GMI_CPU0_G0_CPU1_G2_TX_DP<8>")
	)
	(segment
		(start 351.547684 -232.009442)
		(end 351.548446 -232.008934)
		(width 0.1143)
		(layer "In13.Cu")
		(net "GMI_CPU0_G0_CPU1_G2_TX_DP<8>")
	)
	(segment
		(start 351.575624 -228.753416)
		(end 351.576386 -228.752908)
		(width 0.1143)
		(layer "In13.Cu")
		(net "GMI_CPU0_G0_CPU1_G2_TX_DP<8>")
	)
	(segment
		(start 351.583244 -222.959676)
		(end 351.55124 -222.94088)
		(width 0.1143)
		(layer "In13.Cu")
		(net "GMI_CPU0_G0_CPU1_G2_TX_DP<8>")
	)
	(segment
		(start 119.944642 -232.660952)
		(end 119.943118 -232.661968)
		(width 0.1143)
		(layer "In13.Cu")
		(net "GMI_CPU0_G0_CPU1_G2_TX_DP<8>")
	)
	(segment
		(start 351.546668 -232.658158)
		(end 351.545144 -232.657142)
		(width 0.1143)
		(layer "In13.Cu")
		(net "GMI_CPU0_G0_CPU1_G2_TX_DP<8>")
	)
	(segment
		(start 351.545144 -236.871002)
		(end 351.547684 -236.869478)
		(width 0.1143)
		(layer "In13.Cu")
		(net "GMI_CPU0_G0_CPU1_G2_TX_DP<8>")
	)
	(segment
		(start 119.950738 -237.517432)
		(end 119.949214 -237.518448)
		(width 0.1143)
		(layer "In13.Cu")
		(net "GMI_CPU0_G0_CPU1_G2_TX_DP<8>")
	)
	(segment
		(start 351.548446 -235.248958)
		(end 351.575624 -235.23321)
		(width 0.1143)
		(layer "In13.Cu")
		(net "GMI_CPU0_G0_CPU1_G2_TX_DP<8>")
	)
	(segment
		(start 119.951754 -222.93707)
		(end 119.950738 -222.937578)
		(width 0.1143)
		(layer "In13.Cu")
		(net "GMI_CPU0_G0_CPU1_G2_TX_DP<8>")
	)
	(segment
		(start 351.583244 -226.1997)
		(end 351.550732 -226.180396)
		(width 0.1143)
		(layer "In13.Cu")
		(net "GMI_CPU0_G0_CPU1_G2_TX_DP<8>")
	)
	(segment
		(start 302.896016 -182.311548)
		(end 166.384986 -181.515766)
		(width 0.14224)
		(layer "In13.Cu")
		(net "GMI_CPU0_G0_CPU1_G2_TX_DP<8>")
	)
	(segment
		(start 351.576386 -236.852714)
		(end 351.583244 -236.84865)
		(width 0.1143)
		(layer "In13.Cu")
		(net "GMI_CPU0_G0_CPU1_G2_TX_DP<8>")
	)
	(segment
		(start 155.589986 -187.867544)
		(end 145.773648 -195.91655)
		(width 0.14224)
		(layer "In13.Cu")
		(net "GMI_CPU0_G0_CPU1_G2_TX_DP<8>")
	)
	(segment
		(start 119.952516 -225.532442)
		(end 119.983504 -225.550222)
		(width 0.1143)
		(layer "In13.Cu")
		(net "GMI_CPU0_G0_CPU1_G2_TX_DP<8>")
	)
	(segment
		(start 119.952516 -224.556574)
		(end 119.951754 -224.557082)
		(width 0.1143)
		(layer "In13.Cu")
		(net "GMI_CPU0_G0_CPU1_G2_TX_DP<8>")
	)
	(segment
		(start 351.543366 -223.912176)
		(end 351.544128 -223.911668)
		(width 0.1143)
		(layer "In13.Cu")
		(net "GMI_CPU0_G0_CPU1_G2_TX_DP<8>")
	)
	(segment
		(start 351.548446 -225.52914)
		(end 351.575624 -225.513392)
		(width 0.1143)
		(layer "In13.Cu")
		(net "GMI_CPU0_G0_CPU1_G2_TX_DP<8>")
	)
	(segment
		(start 119.950738 -234.277408)
		(end 119.949214 -234.278424)
		(width 0.1143)
		(layer "In13.Cu")
		(net "GMI_CPU0_G0_CPU1_G2_TX_DP<8>")
	)
	(segment
		(start 119.952516 -235.896404)
		(end 119.951754 -235.896912)
		(width 0.1143)
		(layer "In13.Cu")
		(net "GMI_CPU0_G0_CPU1_G2_TX_DP<8>")
	)
	(segment
		(start 351.512378 -232.029762)
		(end 351.543366 -232.011982)
		(width 0.1143)
		(layer "In13.Cu")
		(net "GMI_CPU0_G0_CPU1_G2_TX_DP<8>")
	)
	(segment
		(start 351.547684 -233.629454)
		(end 351.548446 -233.628946)
		(width 0.1143)
		(layer "In13.Cu")
		(net "GMI_CPU0_G0_CPU1_G2_TX_DP<8>")
	)
	(segment
		(start 119.944642 -235.900976)
		(end 119.912638 -235.919772)
		(width 0.1143)
		(layer "In13.Cu")
		(net "GMI_CPU0_G0_CPU1_G2_TX_DP<8>")
	)
	(segment
		(start 119.984266 -228.7905)
		(end 119.98452 -228.791008)
		(width 0.1143)
		(layer "In13.Cu")
		(net "GMI_CPU0_G0_CPU1_G2_TX_DP<8>")
	)
	(segment
		(start 119.984774 -229.397306)
		(end 119.912638 -229.439724)
		(width 0.1143)
		(layer "In13.Cu")
		(net "GMI_CPU0_G0_CPU1_G2_TX_DP<8>")
	)
	(segment
		(start 351.598992 -233.597196)
		(end 351.60204 -233.594656)
		(width 0.1143)
		(layer "In13.Cu")
		(net "GMI_CPU0_G0_CPU1_G2_TX_DP<8>")
	)
	(segment
		(start 119.983504 -227.170234)
		(end 120.003062 -227.184204)
		(width 0.1143)
		(layer "In13.Cu")
		(net "GMI_CPU0_G0_CPU1_G2_TX_DP<8>")
	)
	(segment
		(start 119.912638 -228.749098)
		(end 119.919496 -228.753162)
		(width 0.1143)
		(layer "In13.Cu")
		(net "GMI_CPU0_G0_CPU1_G2_TX_DP<8>")
	)
	(segment
		(start 351.543366 -239.136174)
		(end 351.538794 -239.133634)
		(width 0.1143)
		(layer "In13.Cu")
		(net "GMI_CPU0_G0_CPU1_G2_TX_DP<8>")
	)
	(segment
		(start 119.66956 -221.416626)
		(end 119.66956 -221.791276)
		(width 0.1143)
		(layer "In13.Cu")
		(net "GMI_CPU0_G0_CPU1_G2_TX_DP<8>")
	)
	(segment
		(start 119.952516 -226.176586)
		(end 119.951754 -226.177094)
		(width 0.1143)
		(layer "In13.Cu")
		(net "GMI_CPU0_G0_CPU1_G2_TX_DP<8>")
	)
	(segment
		(start 351.575624 -223.89338)
		(end 351.576386 -223.892872)
		(width 0.1143)
		(layer "In13.Cu")
		(net "GMI_CPU0_G0_CPU1_G2_TX_DP<8>")
	)
	(segment
		(start 119.955818 -228.774244)
		(end 119.984266 -228.7905)
		(width 0.1143)
		(layer "In13.Cu")
		(net "GMI_CPU0_G0_CPU1_G2_TX_DP<8>")
	)
	(segment
		(start 119.919496 -227.13315)
		(end 119.920258 -227.133658)
		(width 0.1143)
		(layer "In13.Cu")
		(net "GMI_CPU0_G0_CPU1_G2_TX_DP<8>")
	)
	(segment
		(start 351.826322 -221.791022)
		(end 351.826322 -221.416372)
		(width 0.1143)
		(layer "In13.Cu")
		(net "GMI_CPU0_G0_CPU1_G2_TX_DP<8>")
	)
	(segment
		(start 351.548446 -232.008934)
		(end 351.575624 -231.993186)
		(width 0.1143)
		(layer "In13.Cu")
		(net "GMI_CPU0_G0_CPU1_G2_TX_DP<8>")
	)
	(segment
		(start 308.433216 -182.793132)
		(end 307.086 -182.311548)
		(width 0.14224)
		(layer "In13.Cu")
		(net "GMI_CPU0_G0_CPU1_G2_TX_DP<8>")
	)
	(segment
		(start 119.950738 -227.797614)
		(end 119.946166 -227.800408)
		(width 0.1143)
		(layer "In13.Cu")
		(net "GMI_CPU0_G0_CPU1_G2_TX_DP<8>")
	)
	(segment
		(start 119.95531 -230.394002)
		(end 119.983504 -230.410258)
		(width 0.1143)
		(layer "In13.Cu")
		(net "GMI_CPU0_G0_CPU1_G2_TX_DP<8>")
	)
	(segment
		(start 351.549716 -227.800154)
		(end 351.545144 -227.79736)
		(width 0.1143)
		(layer "In13.Cu")
		(net "GMI_CPU0_G0_CPU1_G2_TX_DP<8>")
	)
	(segment
		(start 351.547684 -235.249466)
		(end 351.548446 -235.248958)
		(width 0.1143)
		(layer "In13.Cu")
		(net "GMI_CPU0_G0_CPU1_G2_TX_DP<8>")
	)
	(segment
		(start 349.223584 -214.667084)
		(end 314.625482 -186.298586)
		(width 0.14224)
		(layer "In13.Cu")
		(net "GMI_CPU0_G0_CPU1_G2_TX_DP<8>")
	)
	(segment
		(start 351.544128 -238.491522)
		(end 351.545144 -238.491014)
		(width 0.1143)
		(layer "In13.Cu")
		(net "GMI_CPU0_G0_CPU1_G2_TX_DP<8>")
	)
	(segment
		(start 351.512378 -233.649774)
		(end 351.543366 -233.631994)
		(width 0.1143)
		(layer "In13.Cu")
		(net "GMI_CPU0_G0_CPU1_G2_TX_DP<8>")
	)
	(segment
		(start 351.544128 -226.17684)
		(end 351.543366 -226.176332)
		(width 0.1143)
		(layer "In13.Cu")
		(net "GMI_CPU0_G0_CPU1_G2_TX_DP<8>")
	)
	(segment
		(start 351.576386 -228.752908)
		(end 351.583244 -228.748844)
		(width 0.1143)
		(layer "In13.Cu")
		(net "GMI_CPU0_G0_CPU1_G2_TX_DP<8>")
	)
	(segment
		(start 351.505012 -232.035096)
		(end 351.512378 -232.029762)
		(width 0.1143)
		(layer "In13.Cu")
		(net "GMI_CPU0_G0_CPU1_G2_TX_DP<8>")
	)
	(segment
		(start 119.948452 -230.389938)
		(end 119.951754 -230.39197)
		(width 0.1143)
		(layer "In13.Cu")
		(net "GMI_CPU0_G0_CPU1_G2_TX_DP<8>")
	)
	(segment
		(start 119.950738 -238.491268)
		(end 119.951754 -238.491776)
		(width 0.1143)
		(layer "In13.Cu")
		(net "GMI_CPU0_G0_CPU1_G2_TX_DP<8>")
	)
	(segment
		(start 119.920258 -238.473488)
		(end 119.950738 -238.491268)
		(width 0.1143)
		(layer "In13.Cu")
		(net "GMI_CPU0_G0_CPU1_G2_TX_DP<8>")
	)
	(segment
		(start 351.575624 -238.473234)
		(end 351.576386 -238.472726)
		(width 0.1143)
		(layer "In13.Cu")
		(net "GMI_CPU0_G0_CPU1_G2_TX_DP<8>")
	)
	(segment
		(start 119.920258 -228.75367)
		(end 119.950738 -228.77145)
		(width 0.1143)
		(layer "In13.Cu")
		(net "GMI_CPU0_G0_CPU1_G2_TX_DP<8>")
	)
	(segment
		(start 351.55124 -222.94088)
		(end 351.546668 -222.93834)
		(width 0.1143)
		(layer "In13.Cu")
		(net "GMI_CPU0_G0_CPU1_G2_TX_DP<8>")
	)
	(segment
		(start 119.951754 -233.63174)
		(end 119.952516 -233.632248)
		(width 0.1143)
		(layer "In13.Cu")
		(net "GMI_CPU0_G0_CPU1_G2_TX_DP<8>")
	)
	(segment
		(start 119.94896 -226.178618)
		(end 119.947944 -226.179126)
		(width 0.1143)
		(layer "In13.Cu")
		(net "GMI_CPU0_G0_CPU1_G2_TX_DP<8>")
	)
	(segment
		(start 119.950738 -236.871256)
		(end 119.951754 -236.871764)
		(width 0.1143)
		(layer "In13.Cu")
		(net "GMI_CPU0_G0_CPU1_G2_TX_DP<8>")
	)
	(segment
		(start 119.919496 -238.47298)
		(end 119.920258 -238.473488)
		(width 0.1143)
		(layer "In13.Cu")
		(net "GMI_CPU0_G0_CPU1_G2_TX_DP<8>")
	)
	(segment
		(start 119.983504 -238.510064)
		(end 119.991886 -238.51616)
		(width 0.1143)
		(layer "In13.Cu")
		(net "GMI_CPU0_G0_CPU1_G2_TX_DP<8>")
	)
	(segment
		(start 119.876062 -233.58094)
		(end 119.908828 -233.606848)
		(width 0.1143)
		(layer "In13.Cu")
		(net "GMI_CPU0_G0_CPU1_G2_TX_DP<8>")
	)
	(segment
		(start 351.544128 -234.276646)
		(end 351.543366 -234.276138)
		(width 0.1143)
		(layer "In13.Cu")
		(net "GMI_CPU0_G0_CPU1_G2_TX_DP<8>")
	)
	(segment
		(start 119.919496 -225.513138)
		(end 119.920258 -225.513646)
		(width 0.1143)
		(layer "In13.Cu")
		(net "GMI_CPU0_G0_CPU1_G2_TX_DP<8>")
	)
	(segment
		(start 351.544128 -239.136682)
		(end 351.543366 -239.136174)
		(width 0.1143)
		(layer "In13.Cu")
		(net "GMI_CPU0_G0_CPU1_G2_TX_DP<8>")
	)
	(segment
		(start 351.544128 -227.151692)
		(end 351.545144 -227.151184)
		(width 0.1143)
		(layer "In13.Cu")
		(net "GMI_CPU0_G0_CPU1_G2_TX_DP<8>")
	)
	(segment
		(start 351.599246 -234.31119)
		(end 351.598992 -234.310936)
		(width 0.1143)
		(layer "In13.Cu")
		(net "GMI_CPU0_G0_CPU1_G2_TX_DP<8>")
	)
	(segment
		(start 351.602294 -232.693718)
		(end 351.599246 -232.691178)
		(width 0.1143)
		(layer "In13.Cu")
		(net "GMI_CPU0_G0_CPU1_G2_TX_DP<8>")
	)
	(segment
		(start 351.548446 -228.769164)
		(end 351.575624 -228.753416)
		(width 0.1143)
		(layer "In13.Cu")
		(net "GMI_CPU0_G0_CPU1_G2_TX_DP<8>")
	)
	(segment
		(start 351.543366 -227.1522)
		(end 351.544128 -227.151692)
		(width 0.1143)
		(layer "In13.Cu")
		(net "GMI_CPU0_G0_CPU1_G2_TX_DP<8>")
	)
	(segment
		(start 351.552764 -232.661714)
		(end 351.55124 -232.660698)
		(width 0.1143)
		(layer "In13.Cu")
		(net "GMI_CPU0_G0_CPU1_G2_TX_DP<8>")
	)
	(segment
		(start 119.950738 -232.657396)
		(end 119.949214 -232.658412)
		(width 0.1143)
		(layer "In13.Cu")
		(net "GMI_CPU0_G0_CPU1_G2_TX_DP<8>")
	)
	(segment
		(start 119.951754 -224.557082)
		(end 119.950738 -224.55759)
		(width 0.1143)
		(layer "In13.Cu")
		(net "GMI_CPU0_G0_CPU1_G2_TX_DP<8>")
	)
	(segment
		(start 119.951754 -228.771958)
		(end 119.952516 -228.772466)
		(width 0.1143)
		(layer "In13.Cu")
		(net "GMI_CPU0_G0_CPU1_G2_TX_DP<8>")
	)
	(segment
		(start 351.544128 -235.896658)
		(end 351.543366 -235.89615)
		(width 0.1143)
		(layer "In13.Cu")
		(net "GMI_CPU0_G0_CPU1_G2_TX_DP<8>")
	)
	(segment
		(start 119.952516 -223.91243)
		(end 119.983504 -223.93021)
		(width 0.1143)
		(layer "In13.Cu")
		(net "GMI_CPU0_G0_CPU1_G2_TX_DP<8>")
	)
	(segment
		(start 351.544128 -233.631486)
		(end 351.545144 -233.630978)
		(width 0.1143)
		(layer "In13.Cu")
		(net "GMI_CPU0_G0_CPU1_G2_TX_DP<8>")
	)
	(segment
		(start 119.983504 -225.550222)
		(end 119.994172 -225.557842)
		(width 0.1143)
		(layer "In13.Cu")
		(net "GMI_CPU0_G0_CPU1_G2_TX_DP<8>")
	)
	(segment
		(start 351.576386 -225.512884)
		(end 351.583244 -225.50882)
		(width 0.1143)
		(layer "In13.Cu")
		(net "GMI_CPU0_G0_CPU1_G2_TX_DP<8>")
	)
	(segment
		(start 351.546922 -226.178364)
		(end 351.545144 -226.177348)
		(width 0.1143)
		(layer "In13.Cu")
		(net "GMI_CPU0_G0_CPU1_G2_TX_DP<8>")
	)
	(segment
		(start 351.599246 -232.691178)
		(end 351.598992 -232.690924)
		(width 0.1143)
		(layer "In13.Cu")
		(net "GMI_CPU0_G0_CPU1_G2_TX_DP<8>")
	)
	(segment
		(start 351.545144 -238.491014)
		(end 351.547684 -238.48949)
		(width 0.1143)
		(layer "In13.Cu")
		(net "GMI_CPU0_G0_CPU1_G2_TX_DP<8>")
	)
	(segment
		(start 351.547684 -228.769672)
		(end 351.548446 -228.769164)
		(width 0.1143)
		(layer "In13.Cu")
		(net "GMI_CPU0_G0_CPU1_G2_TX_DP<8>")
	)
	(segment
		(start 351.511362 -228.790754)
		(end 351.511616 -228.790246)
		(width 0.1143)
		(layer "In13.Cu")
		(net "GMI_CPU0_G0_CPU1_G2_TX_DP<8>")
	)
	(segment
		(start 351.583244 -224.579688)
		(end 351.545144 -224.557336)
		(width 0.1143)
		(layer "In13.Cu")
		(net "GMI_CPU0_G0_CPU1_G2_TX_DP<8>")
	)
	(segment
		(start 119.951754 -232.656888)
		(end 119.950738 -232.657396)
		(width 0.1143)
		(layer "In13.Cu")
		(net "GMI_CPU0_G0_CPU1_G2_TX_DP<8>")
	)
	(segment
		(start 119.907812 -232.682542)
		(end 119.875554 -232.707942)
		(width 0.1143)
		(layer "In13.Cu")
		(net "GMI_CPU0_G0_CPU1_G2_TX_DP<8>")
	)
	(segment
		(start 119.950738 -227.151438)
		(end 119.951754 -227.151946)
		(width 0.1143)
		(layer "In13.Cu")
		(net "GMI_CPU0_G0_CPU1_G2_TX_DP<8>")
	)
	(segment
		(start 351.548446 -233.628946)
		(end 351.575624 -233.613198)
		(width 0.1143)
		(layer "In13.Cu")
		(net "GMI_CPU0_G0_CPU1_G2_TX_DP<8>")
	)
	(segment
		(start 119.951754 -227.151946)
		(end 119.952516 -227.152454)
		(width 0.1143)
		(layer "In13.Cu")
		(net "GMI_CPU0_G0_CPU1_G2_TX_DP<8>")
	)
	(segment
		(start 120.139206 -229.09403)
		(end 120.13946 -229.093776)
		(width 0.1143)
		(layer "In13.Cu")
		(net "GMI_CPU0_G0_CPU1_G2_TX_DP<8>")
	)
	(segment
		(start 119.983504 -234.258612)
		(end 119.952516 -234.276392)
		(width 0.1143)
		(layer "In13.Cu")
		(net "GMI_CPU0_G0_CPU1_G2_TX_DP<8>")
	)
	(segment
		(start 351.548446 -227.149152)
		(end 351.575624 -227.133404)
		(width 0.1143)
		(layer "In13.Cu")
		(net "GMI_CPU0_G0_CPU1_G2_TX_DP<8>")
	)
	(segment
		(start 119.9134 -222.25635)
		(end 119.991886 -222.303086)
		(width 0.1143)
		(layer "In13.Cu")
		(net "GMI_CPU0_G0_CPU1_G2_TX_DP<8>")
	)
	(segment
		(start 119.952516 -238.492284)
		(end 119.983504 -238.510064)
		(width 0.1143)
		(layer "In13.Cu")
		(net "GMI_CPU0_G0_CPU1_G2_TX_DP<8>")
	)
	(segment
		(start 119.912638 -223.889062)
		(end 119.919496 -223.893126)
		(width 0.1143)
		(layer "In13.Cu")
		(net "GMI_CPU0_G0_CPU1_G2_TX_DP<8>")
	)
	(segment
		(start 119.919496 -223.893126)
		(end 119.920258 -223.893634)
		(width 0.1143)
		(layer "In13.Cu")
		(net "GMI_CPU0_G0_CPU1_G2_TX_DP<8>")
	)
	(segment
		(start 351.575624 -235.23321)
		(end 351.576386 -235.232702)
		(width 0.1143)
		(layer "In13.Cu")
		(net "GMI_CPU0_G0_CPU1_G2_TX_DP<8>")
	)
	(segment
		(start 351.512378 -235.269786)
		(end 351.543366 -235.252006)
		(width 0.1143)
		(layer "In13.Cu")
		(net "GMI_CPU0_G0_CPU1_G2_TX_DP<8>")
	)
	(segment
		(start 351.583244 -227.819712)
		(end 351.549716 -227.800154)
		(width 0.1143)
		(layer "In13.Cu")
		(net "GMI_CPU0_G0_CPU1_G2_TX_DP<8>")
	)
	(segment
		(start 351.548446 -238.488982)
		(end 351.575624 -238.473234)
		(width 0.1143)
		(layer "In13.Cu")
		(net "GMI_CPU0_G0_CPU1_G2_TX_DP<8>")
	)
	(segment
		(start 351.583244 -235.919518)
		(end 351.55124 -235.900722)
		(width 0.1143)
		(layer "In13.Cu")
		(net "GMI_CPU0_G0_CPU1_G2_TX_DP<8>")
	)
	(segment
		(start 351.512378 -225.549968)
		(end 351.543366 -225.532188)
		(width 0.1143)
		(layer "In13.Cu")
		(net "GMI_CPU0_G0_CPU1_G2_TX_DP<8>")
	)
	(segment
		(start 307.086 -182.311548)
		(end 302.896016 -182.311548)
		(width 0.14224)
		(layer "In13.Cu")
		(net "GMI_CPU0_G0_CPU1_G2_TX_DP<8>")
	)
	(segment
		(start 351.543366 -224.55632)
		(end 351.512378 -224.53854)
		(width 0.1143)
		(layer "In13.Cu")
		(net "GMI_CPU0_G0_CPU1_G2_TX_DP<8>")
	)
	(segment
		(start 119.950738 -235.89742)
		(end 119.949214 -235.898436)
		(width 0.1143)
		(layer "In13.Cu")
		(net "GMI_CPU0_G0_CPU1_G2_TX_DP<8>")
	)
	(segment
		(start 119.69115 -239.455706)
		(end 119.679212 -239.518698)
		(width 0.1143)
		(layer "In13.Cu")
		(net "GMI_CPU0_G0_CPU1_G2_TX_DP<8>")
	)
	(segment
		(start 119.983504 -235.27004)
		(end 119.991886 -235.276136)
		(width 0.1143)
		(layer "In13.Cu")
		(net "GMI_CPU0_G0_CPU1_G2_TX_DP<8>")
	)
	(segment
		(start 351.356422 -229.093522)
		(end 351.356676 -229.093776)
		(width 0.1143)
		(layer "In13.Cu")
		(net "GMI_CPU0_G0_CPU1_G2_TX_DP<8>")
	)
	(segment
		(start 351.544128 -232.656634)
		(end 351.543366 -232.656126)
		(width 0.1143)
		(layer "In13.Cu")
		(net "GMI_CPU0_G0_CPU1_G2_TX_DP<8>")
	)
	(segment
		(start 119.983504 -236.890052)
		(end 119.991124 -236.895386)
		(width 0.1143)
		(layer "In13.Cu")
		(net "GMI_CPU0_G0_CPU1_G2_TX_DP<8>")
	)
	(segment
		(start 351.906332 -219.185998)
		(end 349.223584 -214.667084)
		(width 0.14224)
		(layer "In13.Cu")
		(net "GMI_CPU0_G0_CPU1_G2_TX_DP<8>")
	)
	(segment
		(start 144.724628 -196.23405)
		(end 122.348244 -214.582248)
		(width 0.14224)
		(layer "In13.Cu")
		(net "GMI_CPU0_G0_CPU1_G2_TX_DP<8>")
	)
	(segment
		(start 119.669306 -229.90429)
		(end 119.669306 -229.904544)
		(width 0.1143)
		(layer "In13.Cu")
		(net "GMI_CPU0_G0_CPU1_G2_TX_DP<8>")
	)
	(segment
		(start 119.920258 -225.513646)
		(end 119.950738 -225.531426)
		(width 0.1143)
		(layer "In13.Cu")
		(net "GMI_CPU0_G0_CPU1_G2_TX_DP<8>")
	)
	(segment
		(start 119.952516 -222.936562)
		(end 119.951754 -222.93707)
		(width 0.1143)
		(layer "In13.Cu")
		(net "GMI_CPU0_G0_CPU1_G2_TX_DP<8>")
	)
	(segment
		(start 351.544128 -223.911668)
		(end 351.545144 -223.91116)
		(width 0.1143)
		(layer "In13.Cu")
		(net "GMI_CPU0_G0_CPU1_G2_TX_DP<8>")
	)
	(segment
		(start 351.548446 -236.86897)
		(end 351.575624 -236.853222)
		(width 0.1143)
		(layer "In13.Cu")
		(net "GMI_CPU0_G0_CPU1_G2_TX_DP<8>")
	)
	(segment
		(start 119.951754 -232.011728)
		(end 119.952516 -232.012236)
		(width 0.1143)
		(layer "In13.Cu")
		(net "GMI_CPU0_G0_CPU1_G2_TX_DP<8>")
	)
	(segment
		(start 351.583244 -234.299506)
		(end 351.552764 -234.281726)
		(width 0.1143)
		(layer "In13.Cu")
		(net "GMI_CPU0_G0_CPU1_G2_TX_DP<8>")
	)
	(segment
		(start 351.546668 -222.93834)
		(end 351.545144 -222.937324)
		(width 0.1143)
		(layer "In13.Cu")
		(net "GMI_CPU0_G0_CPU1_G2_TX_DP<8>")
	)
	(segment
		(start 120.13946 -229.093776)
		(end 120.13946 -229.094538)
		(width 0.1143)
		(layer "In13.Cu")
		(net "GMI_CPU0_G0_CPU1_G2_TX_DP<8>")
	)
	(segment
		(start 351.576386 -235.232702)
		(end 351.583244 -235.228638)
		(width 0.1143)
		(layer "In13.Cu")
		(net "GMI_CPU0_G0_CPU1_G2_TX_DP<8>")
	)
	(segment
		(start 119.983504 -232.030016)
		(end 119.99087 -232.03535)
		(width 0.1143)
		(layer "In13.Cu")
		(net "GMI_CPU0_G0_CPU1_G2_TX_DP<8>")
	)
	(segment
		(start 351.542096 -230.392986)
		(end 351.543366 -230.392224)
		(width 0.1143)
		(layer "In13.Cu")
		(net "GMI_CPU0_G0_CPU1_G2_TX_DP<8>")
	)
	(segment
		(start 351.547684 -236.869478)
		(end 351.548446 -236.86897)
		(width 0.1143)
		(layer "In13.Cu")
		(net "GMI_CPU0_G0_CPU1_G2_TX_DP<8>")
	)
	(segment
		(start 119.58955 -219.304362)
		(end 119.58955 -221.071948)
		(width 0.14224)
		(layer "In13.Cu")
		(net "GMI_CPU0_G0_CPU1_G2_TX_DP<8>")
	)
	(segment
		(start 119.943118 -234.28198)
		(end 119.907812 -234.302554)
		(width 0.1143)
		(layer "In13.Cu")
		(net "GMI_CPU0_G0_CPU1_G2_TX_DP<8>")
	)
	(segment
		(start 119.63527 -221.382336)
		(end 119.66956 -221.416626)
		(width 0.1143)
		(layer "In13.Cu")
		(net "GMI_CPU0_G0_CPU1_G2_TX_DP<8>")
	)
	(segment
		(start 351.547684 -238.48949)
		(end 351.548446 -238.488982)
		(width 0.1143)
		(layer "In13.Cu")
		(net "GMI_CPU0_G0_CPU1_G2_TX_DP<8>")
	)
	(segment
		(start 119.983504 -224.538794)
		(end 119.952516 -224.556574)
		(width 0.1143)
		(layer "In13.Cu")
		(net "GMI_CPU0_G0_CPU1_G2_TX_DP<8>")
	)
	(segment
		(start 351.576386 -223.892872)
		(end 351.583244 -223.888808)
		(width 0.1143)
		(layer "In13.Cu")
		(net "GMI_CPU0_G0_CPU1_G2_TX_DP<8>")
	)
	(segment
		(start 351.54489 -229.416864)
		(end 351.511108 -229.397052)
		(width 0.1143)
		(layer "In13.Cu")
		(net "GMI_CPU0_G0_CPU1_G2_TX_DP<8>")
	)
	(segment
		(start 351.543366 -228.772212)
		(end 351.544128 -228.771704)
		(width 0.1143)
		(layer "In13.Cu")
		(net "GMI_CPU0_G0_CPU1_G2_TX_DP<8>")
	)
	(segment
		(start 119.908828 -233.606848)
		(end 119.950738 -233.631232)
		(width 0.1143)
		(layer "In13.Cu")
		(net "GMI_CPU0_G0_CPU1_G2_TX_DP<8>")
	)
	(segment
		(start 351.55124 -235.900722)
		(end 351.546668 -235.898182)
		(width 0.1143)
		(layer "In13.Cu")
		(net "GMI_CPU0_G0_CPU1_G2_TX_DP<8>")
	)
	(segment
		(start 119.952516 -228.772466)
		(end 119.955564 -228.774244)
		(width 0.1143)
		(layer "In13.Cu")
		(net "GMI_CPU0_G0_CPU1_G2_TX_DP<8>")
	)
	(segment
		(start 351.576386 -231.992678)
		(end 351.583244 -231.988614)
		(width 0.1143)
		(layer "In13.Cu")
		(net "GMI_CPU0_G0_CPU1_G2_TX_DP<8>")
	)
	(segment
		(start 351.575624 -236.853222)
		(end 351.576386 -236.852714)
		(width 0.1143)
		(layer "In13.Cu")
		(net "GMI_CPU0_G0_CPU1_G2_TX_DP<8>")
	)
	(segment
		(start 119.912638 -238.468916)
		(end 119.919496 -238.47298)
		(width 0.1143)
		(layer "In13.Cu")
		(net "GMI_CPU0_G0_CPU1_G2_TX_DP<8>")
	)
	(segment
		(start 119.952516 -239.136428)
		(end 119.951754 -239.136936)
		(width 0.1143)
		(layer "In13.Cu")
		(net "GMI_CPU0_G0_CPU1_G2_TX_DP<8>")
	)
	(segment
		(start 351.545144 -232.657142)
		(end 351.544128 -232.656634)
		(width 0.1143)
		(layer "In13.Cu")
		(net "GMI_CPU0_G0_CPU1_G2_TX_DP<8>")
	)
	(segment
		(start 119.58955 -221.071948)
		(end 119.58955 -221.100396)
		(width 0.1143)
		(layer "In13.Cu")
		(net "GMI_CPU0_G0_CPU1_G2_TX_DP<8>")
	)
	(segment
		(start 119.950738 -224.55759)
		(end 119.912638 -224.579942)
		(width 0.1143)
		(layer "In13.Cu")
		(net "GMI_CPU0_G0_CPU1_G2_TX_DP<8>")
	)
	(segment
		(start 351.583244 -229.43947)
		(end 351.545652 -229.417372)
		(width 0.1143)
		(layer "In13.Cu")
		(net "GMI_CPU0_G0_CPU1_G2_TX_DP<8>")
	)
	(segment
		(start 351.545144 -222.937324)
		(end 351.544128 -222.936816)
		(width 0.1143)
		(layer "In13.Cu")
		(net "GMI_CPU0_G0_CPU1_G2_TX_DP<8>")
	)
	(segment
		(start 119.949214 -235.898436)
		(end 119.944642 -235.900976)
		(width 0.1143)
		(layer "In13.Cu")
		(net "GMI_CPU0_G0_CPU1_G2_TX_DP<8>")
	)
	(segment
		(start 351.545144 -237.517178)
		(end 351.544128 -237.51667)
		(width 0.1143)
		(layer "In13.Cu")
		(net "GMI_CPU0_G0_CPU1_G2_TX_DP<8>")
	)
	(segment
		(start 351.504758 -236.895132)
		(end 351.512378 -236.889798)
		(width 0.1143)
		(layer "In13.Cu")
		(net "GMI_CPU0_G0_CPU1_G2_TX_DP<8>")
	)
	(segment
		(start 119.952516 -230.392478)
		(end 119.953786 -230.39324)
		(width 0.1143)
		(layer "In13.Cu")
		(net "GMI_CPU0_G0_CPU1_G2_TX_DP<8>")
	)
	(segment
		(start 352.201226 -239.624108)
		(end 351.903284 -239.624108)
		(width 0.1143)
		(layer "In13.Cu")
		(net "GMI_CPU0_G0_CPU1_G2_TX_DP<8>")
	)
	(segment
		(start 351.546668 -234.27817)
		(end 351.545144 -234.277154)
		(width 0.1143)
		(layer "In13.Cu")
		(net "GMI_CPU0_G0_CPU1_G2_TX_DP<8>")
	)
	(segment
		(start 119.952516 -237.516416)
		(end 119.951754 -237.516924)
		(width 0.1143)
		(layer "In13.Cu")
		(net "GMI_CPU0_G0_CPU1_G2_TX_DP<8>")
	)
	(segment
		(start 119.912638 -236.848904)
		(end 119.919496 -236.852968)
		(width 0.1143)
		(layer "In13.Cu")
		(net "GMI_CPU0_G0_CPU1_G2_TX_DP<8>")
	)
	(segment
		(start 119.953786 -230.39324)
		(end 119.95531 -230.394002)
		(width 0.1143)
		(layer "In13.Cu")
		(net "GMI_CPU0_G0_CPU1_G2_TX_DP<8>")
	)
	(segment
		(start 351.543366 -238.49203)
		(end 351.544128 -238.491522)
		(width 0.1143)
		(layer "In13.Cu")
		(net "GMI_CPU0_G0_CPU1_G2_TX_DP<8>")
	)
	(segment
		(start 119.952516 -227.796598)
		(end 119.951754 -227.797106)
		(width 0.1143)
		(layer "In13.Cu")
		(net "GMI_CPU0_G0_CPU1_G2_TX_DP<8>")
	)
	(segment
		(start 119.991886 -234.252516)
		(end 119.983504 -234.258612)
		(width 0.1143)
		(layer "In13.Cu")
		(net "GMI_CPU0_G0_CPU1_G2_TX_DP<8>")
	)
	(segment
		(start 351.544128 -236.87151)
		(end 351.545144 -236.871002)
		(width 0.1143)
		(layer "In13.Cu")
		(net "GMI_CPU0_G0_CPU1_G2_TX_DP<8>")
	)
	(segment
		(start 119.991124 -237.493302)
		(end 119.983504 -237.498636)
		(width 0.1143)
		(layer "In13.Cu")
		(net "GMI_CPU0_G0_CPU1_G2_TX_DP<8>")
	)
	(segment
		(start 351.575624 -233.613198)
		(end 351.576386 -233.61269)
		(width 0.1143)
		(layer "In13.Cu")
		(net "GMI_CPU0_G0_CPU1_G2_TX_DP<8>")
	)
	(segment
		(start 120.003062 -227.764848)
		(end 119.983504 -227.778818)
		(width 0.1143)
		(layer "In13.Cu")
		(net "GMI_CPU0_G0_CPU1_G2_TX_DP<8>")
	)
	(segment
		(start 119.946166 -227.800408)
		(end 119.912638 -227.819966)
		(width 0.1143)
		(layer "In13.Cu")
		(net "GMI_CPU0_G0_CPU1_G2_TX_DP<8>")
	)
	(segment
		(start 351.543366 -226.176332)
		(end 351.512378 -226.158552)
		(width 0.1143)
		(layer "In13.Cu")
		(net "GMI_CPU0_G0_CPU1_G2_TX_DP<8>")
	)
	(segment
		(start 351.540318 -228.77399)
		(end 351.543366 -228.772212)
		(width 0.1143)
		(layer "In13.Cu")
		(net "GMI_CPU0_G0_CPU1_G2_TX_DP<8>")
	)
	(segment
		(start 351.544128 -232.011474)
		(end 351.545144 -232.010966)
		(width 0.1143)
		(layer "In13.Cu")
		(net "GMI_CPU0_G0_CPU1_G2_TX_DP<8>")
	)
	(segment
		(start 351.543366 -234.276138)
		(end 351.512378 -234.258358)
		(width 0.1143)
		(layer "In13.Cu")
		(net "GMI_CPU0_G0_CPU1_G2_TX_DP<8>")
	)
	(segment
		(start 351.826576 -229.90429)
		(end 351.826576 -229.904036)
		(width 0.1143)
		(layer "In13.Cu")
		(net "GMI_CPU0_G0_CPU1_G2_TX_DP<8>")
	)
	(segment
		(start 351.548446 -223.909128)
		(end 351.575624 -223.89338)
		(width 0.1143)
		(layer "In13.Cu")
		(net "GMI_CPU0_G0_CPU1_G2_TX_DP<8>")
	)
	(segment
		(start 119.991886 -235.872528)
		(end 119.983504 -235.878624)
		(width 0.1143)
		(layer "In13.Cu")
		(net "GMI_CPU0_G0_CPU1_G2_TX_DP<8>")
	)
	(segment
		(start 351.826322 -221.416372)
		(end 351.860612 -221.382082)
		(width 0.1143)
		(layer "In13.Cu")
		(net "GMI_CPU0_G0_CPU1_G2_TX_DP<8>")
	)
	(segment
		(start 351.55124 -234.28071)
		(end 351.546668 -234.27817)
		(width 0.1143)
		(layer "In13.Cu")
		(net "GMI_CPU0_G0_CPU1_G2_TX_DP<8>")
	)
	(segment
		(start 351.512378 -232.638346)
		(end 351.505012 -232.633012)
		(width 0.1143)
		(layer "In13.Cu")
		(net "GMI_CPU0_G0_CPU1_G2_TX_DP<8>")
	)
	(segment
		(start 351.545144 -232.010966)
		(end 351.547684 -232.009442)
		(width 0.1143)
		(layer "In13.Cu")
		(net "GMI_CPU0_G0_CPU1_G2_TX_DP<8>")
	)
	(segment
		(start 351.583244 -232.679494)
		(end 351.552764 -232.661714)
		(width 0.1143)
		(layer "In13.Cu")
		(net "GMI_CPU0_G0_CPU1_G2_TX_DP<8>")
	)
	(segment
		(start 119.950738 -223.911414)
		(end 119.951754 -223.911922)
		(width 0.1143)
		(layer "In13.Cu")
		(net "GMI_CPU0_G0_CPU1_G2_TX_DP<8>")
	)
	(segment
		(start 119.592598 -239.624362)
		(end 119.294656 -239.624362)
		(width 0.1143)
		(layer "In13.Cu")
		(net "GMI_CPU0_G0_CPU1_G2_TX_DP<8>")
	)
	(segment
		(start 351.503996 -238.515906)
		(end 351.512378 -238.50981)
		(width 0.1143)
		(layer "In13.Cu")
		(net "GMI_CPU0_G0_CPU1_G2_TX_DP<8>")
	)
	(segment
		(start 119.952516 -227.152454)
		(end 119.983504 -227.170234)
		(width 0.1143)
		(layer "In13.Cu")
		(net "GMI_CPU0_G0_CPU1_G2_TX_DP<8>")
	)
	(segment
		(start 351.545144 -223.91116)
		(end 351.547684 -223.909636)
		(width 0.1143)
		(layer "In13.Cu")
		(net "GMI_CPU0_G0_CPU1_G2_TX_DP<8>")
	)
	(segment
		(start 119.63527 -221.146116)
		(end 119.63527 -221.382336)
		(width 0.1143)
		(layer "In13.Cu")
		(net "GMI_CPU0_G0_CPU1_G2_TX_DP<8>")
	)
	(segment
		(start 351.906332 -221.100142)
		(end 351.906332 -221.093538)
		(width 0.1143)
		(layer "In13.Cu")
		(net "GMI_CPU0_G0_CPU1_G2_TX_DP<8>")
	)
	(segment
		(start 351.583244 -237.53953)
		(end 351.55124 -237.520734)
		(width 0.1143)
		(layer "In13.Cu")
		(net "GMI_CPU0_G0_CPU1_G2_TX_DP<8>")
	)
	(segment
		(start 351.543366 -236.872018)
		(end 351.544128 -236.87151)
		(width 0.1143)
		(layer "In13.Cu")
		(net "GMI_CPU0_G0_CPU1_G2_TX_DP<8>")
	)
	(segment
		(start 351.512378 -227.778564)
		(end 351.49282 -227.764594)
		(width 0.1143)
		(layer "In13.Cu")
		(net "GMI_CPU0_G0_CPU1_G2_TX_DP<8>")
	)
	(segment
		(start 119.955564 -228.774244)
		(end 119.955818 -228.774244)
		(width 0.1143)
		(layer "In13.Cu")
		(net "GMI_CPU0_G0_CPU1_G2_TX_DP<8>")
	)
	(segment
		(start 160.978342 -183.449214)
		(end 155.589986 -187.867798)
		(width 0.14224)
		(layer "In13.Cu")
		(net "GMI_CPU0_G0_CPU1_G2_TX_DP<8>")
	)
	(segment
		(start 351.547684 -223.909636)
		(end 351.548446 -223.909128)
		(width 0.1143)
		(layer "In13.Cu")
		(net "GMI_CPU0_G0_CPU1_G2_TX_DP<8>")
	)
	(segment
		(start 351.545144 -227.79736)
		(end 351.544128 -227.796852)
		(width 0.1143)
		(layer "In13.Cu")
		(net "GMI_CPU0_G0_CPU1_G2_TX_DP<8>")
	)
	(segment
		(start 119.983504 -227.778818)
		(end 119.952516 -227.796598)
		(width 0.1143)
		(layer "In13.Cu")
		(net "GMI_CPU0_G0_CPU1_G2_TX_DP<8>")
	)
	(segment
		(start 155.589986 -187.867798)
		(end 155.589986 -187.867544)
		(width 0.14224)
		(layer "In13.Cu")
		(net "GMI_CPU0_G0_CPU1_G2_TX_DP<8>")
	)
	(segment
		(start 119.950738 -226.177602)
		(end 119.94896 -226.178618)
		(width 0.1143)
		(layer "In13.Cu")
		(net "GMI_CPU0_G0_CPU1_G2_TX_DP<8>")
	)
	(segment
		(start 351.538794 -239.133634)
		(end 351.538032 -239.133126)
		(width 0.1143)
		(layer "In13.Cu")
		(net "GMI_CPU0_G0_CPU1_G2_TX_DP<8>")
	)
	(segment
		(start 145.773648 -195.91655)
		(end 144.724628 -196.23405)
		(width 0.14224)
		(layer "In13.Cu")
		(net "GMI_CPU0_G0_CPU1_G2_TX_DP<8>")
	)
	(segment
		(start 119.959628 -222.932498)
		(end 119.956326 -222.934276)
		(width 0.1143)
		(layer "In13.Cu")
		(net "GMI_CPU0_G0_CPU1_G2_TX_DP<8>")
	)
	(segment
		(start 119.951754 -238.491776)
		(end 119.952516 -238.492284)
		(width 0.1143)
		(layer "In13.Cu")
		(net "GMI_CPU0_G0_CPU1_G2_TX_DP<8>")
	)
	(segment
		(start 351.545144 -226.177348)
		(end 351.544128 -226.17684)
		(width 0.1143)
		(layer "In13.Cu")
		(net "GMI_CPU0_G0_CPU1_G2_TX_DP<8>")
	)
	(segment
		(start 119.947944 -226.179126)
		(end 119.94515 -226.18065)
		(width 0.1143)
		(layer "In13.Cu")
		(net "GMI_CPU0_G0_CPU1_G2_TX_DP<8>")
	)
	(segment
		(start 351.512378 -226.158552)
		(end 351.50171 -226.150932)
		(width 0.1143)
		(layer "In13.Cu")
		(net "GMI_CPU0_G0_CPU1_G2_TX_DP<8>")
	)
	(segment
		(start 119.951754 -227.797106)
		(end 119.950738 -227.797614)
		(width 0.1143)
		(layer "In13.Cu")
		(net "GMI_CPU0_G0_CPU1_G2_TX_DP<8>")
	)
	(segment
		(start 351.576386 -238.472726)
		(end 351.583244 -238.468662)
		(width 0.1143)
		(layer "In13.Cu")
		(net "GMI_CPU0_G0_CPU1_G2_TX_DP<8>")
	)
	(segment
		(start 119.950738 -232.01122)
		(end 119.951754 -232.011728)
		(width 0.1143)
		(layer "In13.Cu")
		(net "GMI_CPU0_G0_CPU1_G2_TX_DP<8>")
	)
	(segment
		(start 351.544128 -224.556828)
		(end 351.543366 -224.55632)
		(width 0.1143)
		(layer "In13.Cu")
		(net "GMI_CPU0_G0_CPU1_G2_TX_DP<8>")
	)
	(segment
		(start 119.920258 -236.853476)
		(end 119.950738 -236.871256)
		(width 0.1143)
		(layer "In13.Cu")
		(net "GMI_CPU0_G0_CPU1_G2_TX_DP<8>")
	)
	(segment
		(start 351.552764 -234.281726)
		(end 351.55124 -234.28071)
		(width 0.1143)
		(layer "In13.Cu")
		(net "GMI_CPU0_G0_CPU1_G2_TX_DP<8>")
	)
	(segment
		(start 351.545144 -235.897166)
		(end 351.544128 -235.896658)
		(width 0.1143)
		(layer "In13.Cu")
		(net "GMI_CPU0_G0_CPU1_G2_TX_DP<8>")
	)
	(segment
		(start 351.545144 -228.771196)
		(end 351.547684 -228.769672)
		(width 0.1143)
		(layer "In13.Cu")
		(net "GMI_CPU0_G0_CPU1_G2_TX_DP<8>")
	)
	(segment
		(start 119.949214 -234.278424)
		(end 119.944642 -234.280964)
		(width 0.1143)
		(layer "In13.Cu")
		(net "GMI_CPU0_G0_CPU1_G2_TX_DP<8>")
	)
	(segment
		(start 119.912638 -231.988868)
		(end 119.919496 -231.992932)
		(width 0.1143)
		(layer "In13.Cu")
		(net "GMI_CPU0_G0_CPU1_G2_TX_DP<8>")
	)
	(segment
		(start 351.546668 -235.898182)
		(end 351.545144 -235.897166)
		(width 0.1143)
		(layer "In13.Cu")
		(net "GMI_CPU0_G0_CPU1_G2_TX_DP<8>")
	)
	(segment
		(start 119.991886 -239.112552)
		(end 119.983504 -239.118648)
		(width 0.1143)
		(layer "In13.Cu")
		(net "GMI_CPU0_G0_CPU1_G2_TX_DP<8>")
	)
	(segment
		(start 119.907812 -234.302554)
		(end 119.875554 -234.327954)
		(width 0.1143)
		(layer "In13.Cu")
		(net "GMI_CPU0_G0_CPU1_G2_TX_DP<8>")
	)
	(segment
		(start 119.99087 -232.633266)
		(end 119.983504 -232.6386)
		(width 0.1143)
		(layer "In13.Cu")
		(net "GMI_CPU0_G0_CPU1_G2_TX_DP<8>")
	)
	(segment
		(start 119.951754 -234.2769)
		(end 119.950738 -234.277408)
		(width 0.1143)
		(layer "In13.Cu")
		(net "GMI_CPU0_G0_CPU1_G2_TX_DP<8>")
	)
	(segment
		(start 351.543366 -237.516162)
		(end 351.512378 -237.498382)
		(width 0.1143)
		(layer "In13.Cu")
		(net "GMI_CPU0_G0_CPU1_G2_TX_DP<8>")
	)
	(segment
		(start 351.544128 -237.51667)
		(end 351.543366 -237.516162)
		(width 0.1143)
		(layer "In13.Cu")
		(net "GMI_CPU0_G0_CPU1_G2_TX_DP<8>")
	)
	(segment
		(start 351.543366 -232.011982)
		(end 351.544128 -232.011474)
		(width 0.1143)
		(layer "In13.Cu")
		(net "GMI_CPU0_G0_CPU1_G2_TX_DP<8>")
	)
	(segment
		(start 119.876062 -235.200952)
		(end 119.908828 -235.22686)
		(width 0.1143)
		(layer "In13.Cu")
		(net "GMI_CPU0_G0_CPU1_G2_TX_DP<8>")
	)
	(arc
		(start 119.98452 -228.791008)
		(mid 120.098374 -228.923895)
		(end 120.139206 -229.09403)
		(width 0.1143)
		(layer "In13.Cu")
		(net "GMI_CPU0_G0_CPU1_G2_TX_DP<8>")
	)
	(arc
		(start 119.669306 -229.904544)
		(mid 119.744122 -230.184488)
		(end 119.948452 -230.389938)
		(width 0.1143)
		(layer "In13.Cu")
		(net "GMI_CPU0_G0_CPU1_G2_TX_DP<8>")
	)
	(arc
		(start 351.583244 -227.128832)
		(mid 351.826571 -226.664266)
		(end 351.583244 -226.1997)
		(width 0.1143)
		(layer "In13.Cu")
		(net "GMI_CPU0_G0_CPU1_G2_TX_DP<8>")
	)
	(arc
		(start 351.598992 -234.310936)
		(mid 351.591168 -234.305153)
		(end 351.583244 -234.299506)
		(width 0.1143)
		(layer "In13.Cu")
		(net "GMI_CPU0_G0_CPU1_G2_TX_DP<8>")
	)
	(arc
		(start 351.598992 -232.690924)
		(mid 351.591168 -232.685141)
		(end 351.583244 -232.679494)
		(width 0.1143)
		(layer "In13.Cu")
		(net "GMI_CPU0_G0_CPU1_G2_TX_DP<8>")
	)
	(arc
		(start 119.912638 -224.579942)
		(mid 119.669311 -225.044508)
		(end 119.912638 -225.509074)
		(width 0.1143)
		(layer "In13.Cu")
		(net "GMI_CPU0_G0_CPU1_G2_TX_DP<8>")
	)
	(arc
		(start 351.505012 -232.633012)
		(mid 351.351829 -232.334054)
		(end 351.505012 -232.035096)
		(width 0.1143)
		(layer "In13.Cu")
		(net "GMI_CPU0_G0_CPU1_G2_TX_DP<8>")
	)
	(arc
		(start 119.912638 -231.059736)
		(mid 119.669311 -231.524302)
		(end 119.912638 -231.988868)
		(width 0.1143)
		(layer "In13.Cu")
		(net "GMI_CPU0_G0_CPU1_G2_TX_DP<8>")
	)
	(arc
		(start 119.912638 -237.539784)
		(mid 119.669311 -238.00435)
		(end 119.912638 -238.468916)
		(width 0.1143)
		(layer "In13.Cu")
		(net "GMI_CPU0_G0_CPU1_G2_TX_DP<8>")
	)
	(arc
		(start 351.503996 -235.872274)
		(mid 351.351115 -235.574078)
		(end 351.503996 -235.275882)
		(width 0.1143)
		(layer "In13.Cu")
		(net "GMI_CPU0_G0_CPU1_G2_TX_DP<8>")
	)
	(arc
		(start 119.991886 -238.51616)
		(mid 120.144767 -238.814356)
		(end 119.991886 -239.112552)
		(width 0.1143)
		(layer "In13.Cu")
		(net "GMI_CPU0_G0_CPU1_G2_TX_DP<8>")
	)
	(arc
		(start 120.13946 -229.094538)
		(mid 120.098494 -229.264507)
		(end 119.984774 -229.397306)
		(width 0.1143)
		(layer "In13.Cu")
		(net "GMI_CPU0_G0_CPU1_G2_TX_DP<8>")
	)
	(arc
		(start 351.620582 -235.199936)
		(mid 351.830145 -234.764251)
		(end 351.620836 -234.328462)
		(width 0.1143)
		(layer "In13.Cu")
		(net "GMI_CPU0_G0_CPU1_G2_TX_DP<8>")
	)
	(arc
		(start 119.875554 -232.707942)
		(mid 119.66588 -233.144592)
		(end 119.876062 -233.58094)
		(width 0.1143)
		(layer "In13.Cu")
		(net "GMI_CPU0_G0_CPU1_G2_TX_DP<8>")
	)
	(arc
		(start 351.512378 -224.53854)
		(mid 351.360688 -224.234248)
		(end 351.512378 -223.929956)
		(width 0.1143)
		(layer "In13.Cu")
		(net "GMI_CPU0_G0_CPU1_G2_TX_DP<8>")
	)
	(arc
		(start 351.50171 -226.150932)
		(mid 351.349643 -225.85426)
		(end 351.50171 -225.557588)
		(width 0.1143)
		(layer "In13.Cu")
		(net "GMI_CPU0_G0_CPU1_G2_TX_DP<8>")
	)
	(arc
		(start 119.912638 -229.439724)
		(mid 119.733825 -229.642074)
		(end 119.669306 -229.90429)
		(width 0.1143)
		(layer "In13.Cu")
		(net "GMI_CPU0_G0_CPU1_G2_TX_DP<8>")
	)
	(arc
		(start 351.504758 -237.493048)
		(mid 351.351575 -237.19409)
		(end 351.504758 -236.895132)
		(width 0.1143)
		(layer "In13.Cu")
		(net "GMI_CPU0_G0_CPU1_G2_TX_DP<8>")
	)
	(arc
		(start 119.991886 -235.276136)
		(mid 120.144767 -235.574332)
		(end 119.991886 -235.872528)
		(width 0.1143)
		(layer "In13.Cu")
		(net "GMI_CPU0_G0_CPU1_G2_TX_DP<8>")
	)
	(arc
		(start 119.994172 -225.557842)
		(mid 120.146239 -225.854514)
		(end 119.994172 -226.151186)
		(width 0.1143)
		(layer "In13.Cu")
		(net "GMI_CPU0_G0_CPU1_G2_TX_DP<8>")
	)
	(arc
		(start 119.912638 -235.919772)
		(mid 119.669311 -236.384338)
		(end 119.912638 -236.848904)
		(width 0.1143)
		(layer "In13.Cu")
		(net "GMI_CPU0_G0_CPU1_G2_TX_DP<8>")
	)
	(arc
		(start 351.826576 -229.904036)
		(mid 351.762061 -229.641817)
		(end 351.583244 -229.43947)
		(width 0.1143)
		(layer "In13.Cu")
		(net "GMI_CPU0_G0_CPU1_G2_TX_DP<8>")
	)
	(arc
		(start 119.991886 -222.303086)
		(mid 120.147322 -222.626576)
		(end 119.959628 -222.932498)
		(width 0.1143)
		(layer "In13.Cu")
		(net "GMI_CPU0_G0_CPU1_G2_TX_DP<8>")
	)
	(arc
		(start 119.66956 -221.791276)
		(mid 119.734219 -222.053833)
		(end 119.9134 -222.25635)
		(width 0.1143)
		(layer "In13.Cu")
		(net "GMI_CPU0_G0_CPU1_G2_TX_DP<8>")
	)
	(arc
		(start 351.583244 -228.748844)
		(mid 351.826571 -228.284278)
		(end 351.583244 -227.819712)
		(width 0.1143)
		(layer "In13.Cu")
		(net "GMI_CPU0_G0_CPU1_G2_TX_DP<8>")
	)
	(arc
		(start 351.582482 -222.256096)
		(mid 351.761675 -222.053586)
		(end 351.826322 -221.791022)
		(width 0.1143)
		(layer "In13.Cu")
		(net "GMI_CPU0_G0_CPU1_G2_TX_DP<8>")
	)
	(arc
		(start 351.511108 -229.397052)
		(mid 351.397387 -229.264254)
		(end 351.356422 -229.094284)
		(width 0.1143)
		(layer "In13.Cu")
		(net "GMI_CPU0_G0_CPU1_G2_TX_DP<8>")
	)
	(arc
		(start 351.583244 -225.50882)
		(mid 351.826571 -225.044254)
		(end 351.583244 -224.579688)
		(width 0.1143)
		(layer "In13.Cu")
		(net "GMI_CPU0_G0_CPU1_G2_TX_DP<8>")
	)
	(arc
		(start 119.679212 -239.518698)
		(mid 119.677189 -239.530108)
		(end 119.675402 -239.541558)
		(width 0.1143)
		(layer "In13.Cu")
		(net "GMI_CPU0_G0_CPU1_G2_TX_DP<8>")
	)
	(arc
		(start 351.49282 -227.764594)
		(mid 351.344006 -227.474272)
		(end 351.49282 -227.18395)
		(width 0.1143)
		(layer "In13.Cu")
		(net "GMI_CPU0_G0_CPU1_G2_TX_DP<8>")
	)
	(arc
		(start 351.503996 -234.252262)
		(mid 351.351115 -233.954066)
		(end 351.503996 -233.65587)
		(width 0.1143)
		(layer "In13.Cu")
		(net "GMI_CPU0_G0_CPU1_G2_TX_DP<8>")
	)
	(arc
		(start 351.60204 -233.594656)
		(mid 351.818627 -233.144239)
		(end 351.602294 -232.693718)
		(width 0.1143)
		(layer "In13.Cu")
		(net "GMI_CPU0_G0_CPU1_G2_TX_DP<8>")
	)
	(arc
		(start 351.54743 -230.389684)
		(mid 351.751729 -230.184216)
		(end 351.826576 -229.90429)
		(width 0.1143)
		(layer "In13.Cu")
		(net "GMI_CPU0_G0_CPU1_G2_TX_DP<8>")
	)
	(arc
		(start 351.583244 -235.228638)
		(mid 351.591167 -235.22299)
		(end 351.598992 -235.217208)
		(width 0.1143)
		(layer "In13.Cu")
		(net "GMI_CPU0_G0_CPU1_G2_TX_DP<8>")
	)
	(arc
		(start 119.912638 -227.819966)
		(mid 119.669311 -228.284532)
		(end 119.912638 -228.749098)
		(width 0.1143)
		(layer "In13.Cu")
		(net "GMI_CPU0_G0_CPU1_G2_TX_DP<8>")
	)
	(arc
		(start 351.583244 -223.888808)
		(mid 351.826571 -223.424242)
		(end 351.583244 -222.959676)
		(width 0.1143)
		(layer "In13.Cu")
		(net "GMI_CPU0_G0_CPU1_G2_TX_DP<8>")
	)
	(arc
		(start 351.356422 -230.714296)
		(mid 351.398015 -230.543508)
		(end 351.512378 -230.410004)
		(width 0.1143)
		(layer "In13.Cu")
		(net "GMI_CPU0_G0_CPU1_G2_TX_DP<8>")
	)
	(arc
		(start 119.875554 -234.327954)
		(mid 119.665785 -234.764604)
		(end 119.876062 -235.200952)
		(width 0.1143)
		(layer "In13.Cu")
		(net "GMI_CPU0_G0_CPU1_G2_TX_DP<8>")
	)
	(arc
		(start 351.583244 -233.608626)
		(mid 351.591167 -233.602978)
		(end 351.598992 -233.597196)
		(width 0.1143)
		(layer "In13.Cu")
		(net "GMI_CPU0_G0_CPU1_G2_TX_DP<8>")
	)
	(arc
		(start 351.82048 -239.541304)
		(mid 351.818692 -239.529855)
		(end 351.81667 -239.518444)
		(width 0.1143)
		(layer "In13.Cu")
		(net "GMI_CPU0_G0_CPU1_G2_TX_DP<8>")
	)
	(arc
		(start 351.804732 -239.455452)
		(mid 351.745808 -239.309143)
		(end 351.635822 -239.196118)
		(width 0.1143)
		(layer "In13.Cu")
		(net "GMI_CPU0_G0_CPU1_G2_TX_DP<8>")
	)
	(arc
		(start 351.539048 -231.033828)
		(mid 351.404898 -230.898535)
		(end 351.356422 -230.714296)
		(width 0.1143)
		(layer "In13.Cu")
		(net "GMI_CPU0_G0_CPU1_G2_TX_DP<8>")
	)
	(arc
		(start 119.991886 -233.656124)
		(mid 120.144767 -233.95432)
		(end 119.991886 -234.252516)
		(width 0.1143)
		(layer "In13.Cu")
		(net "GMI_CPU0_G0_CPU1_G2_TX_DP<8>")
	)
	(arc
		(start 351.583244 -231.988614)
		(mid 351.826571 -231.524048)
		(end 351.583244 -231.059482)
		(width 0.1143)
		(layer "In13.Cu")
		(net "GMI_CPU0_G0_CPU1_G2_TX_DP<8>")
	)
	(arc
		(start 119.99087 -232.03535)
		(mid 120.144053 -232.334308)
		(end 119.99087 -232.633266)
		(width 0.1143)
		(layer "In13.Cu")
		(net "GMI_CPU0_G0_CPU1_G2_TX_DP<8>")
	)
	(arc
		(start 351.583244 -238.468662)
		(mid 351.826571 -238.004096)
		(end 351.583244 -237.53953)
		(width 0.1143)
		(layer "In13.Cu")
		(net "GMI_CPU0_G0_CPU1_G2_TX_DP<8>")
	)
	(arc
		(start 120.13946 -230.71455)
		(mid 120.090926 -230.898755)
		(end 119.956834 -231.034082)
		(width 0.1143)
		(layer "In13.Cu")
		(net "GMI_CPU0_G0_CPU1_G2_TX_DP<8>")
	)
	(arc
		(start 351.583244 -236.84865)
		(mid 351.826571 -236.384084)
		(end 351.583244 -235.919518)
		(width 0.1143)
		(layer "In13.Cu")
		(net "GMI_CPU0_G0_CPU1_G2_TX_DP<8>")
	)
	(arc
		(start 119.912638 -222.95993)
		(mid 119.669311 -223.424496)
		(end 119.912638 -223.889062)
		(width 0.1143)
		(layer "In13.Cu")
		(net "GMI_CPU0_G0_CPU1_G2_TX_DP<8>")
	)
	(arc
		(start 119.991124 -236.895386)
		(mid 120.144307 -237.194344)
		(end 119.991124 -237.493302)
		(width 0.1143)
		(layer "In13.Cu")
		(net "GMI_CPU0_G0_CPU1_G2_TX_DP<8>")
	)
	(arc
		(start 120.003062 -227.184204)
		(mid 120.151876 -227.474526)
		(end 120.003062 -227.764848)
		(width 0.1143)
		(layer "In13.Cu")
		(net "GMI_CPU0_G0_CPU1_G2_TX_DP<8>")
	)
	(arc
		(start 351.356676 -229.093776)
		(mid 351.397603 -228.92369)
		(end 351.511362 -228.790754)
		(width 0.1143)
		(layer "In13.Cu")
		(net "GMI_CPU0_G0_CPU1_G2_TX_DP<8>")
	)
	(arc
		(start 119.912638 -226.199954)
		(mid 119.669311 -226.66452)
		(end 119.912638 -227.129086)
		(width 0.1143)
		(layer "In13.Cu")
		(net "GMI_CPU0_G0_CPU1_G2_TX_DP<8>")
	)
	(arc
		(start 351.536254 -222.932244)
		(mid 351.348528 -222.626324)
		(end 351.503996 -222.302832)
		(width 0.1143)
		(layer "In13.Cu")
		(net "GMI_CPU0_G0_CPU1_G2_TX_DP<8>")
	)
	(arc
		(start 119.983504 -223.93021)
		(mid 120.135194 -224.234502)
		(end 119.983504 -224.538794)
		(width 0.1143)
		(layer "In13.Cu")
		(net "GMI_CPU0_G0_CPU1_G2_TX_DP<8>")
	)
	(arc
		(start 119.86006 -239.196372)
		(mid 119.750165 -239.309457)
		(end 119.69115 -239.455706)
		(width 0.1143)
		(layer "In13.Cu")
		(net "GMI_CPU0_G0_CPU1_G2_TX_DP<8>")
	)
	(arc
		(start 119.983504 -230.410258)
		(mid 120.097908 -230.543741)
		(end 120.13946 -230.71455)
		(width 0.1143)
		(layer "In13.Cu")
		(net "GMI_CPU0_G0_CPU1_G2_TX_DP<8>")
	)
	(arc
		(start 351.503996 -239.112298)
		(mid 351.351115 -238.814102)
		(end 351.503996 -238.515906)
		(width 0.1143)
		(layer "In13.Cu")
		(net "GMI_CPU0_G0_CPU1_G2_TX_DP<8>")
	)
	(segment
		(start 352.668078 -243.13007)
		(end 352.201226 -242.864132)
		(width 0.12954)
		(layer "F.Cu")
		(net "GMI_CPU0_G0_CPU1_G2_TX_DP<7>")
	)
	(segment
		(start 118.827804 -243.130324)
		(end 119.294656 -242.864386)
		(width 0.12954)
		(layer "F.Cu")
		(net "GMI_CPU0_G0_CPU1_G2_TX_DP<7>")
	)
	(segment
		(start 119.027194 -230.400606)
		(end 119.02694 -230.400606)
		(width 0.1143)
		(layer "In13.Cu")
		(net "GMI_CPU0_G0_CPU1_G2_TX_DP<7>")
	)
	(segment
		(start 119.015256 -223.913954)
		(end 119.016018 -223.914462)
		(width 0.1143)
		(layer "In13.Cu")
		(net "GMI_CPU0_G0_CPU1_G2_TX_DP<7>")
	)
	(segment
		(start 352.523806 -237.539784)
		(end 352.452432 -237.498382)
		(width 0.1143)
		(layer "In13.Cu")
		(net "GMI_CPU0_G0_CPU1_G2_TX_DP<7>")
	)
	(segment
		(start 119.04345 -222.918782)
		(end 119.033544 -222.92437)
		(width 0.1143)
		(layer "In13.Cu")
		(net "GMI_CPU0_G0_CPU1_G2_TX_DP<7>")
	)
	(segment
		(start 119.016018 -223.914462)
		(end 119.017034 -223.91497)
		(width 0.1143)
		(layer "In13.Cu")
		(net "GMI_CPU0_G0_CPU1_G2_TX_DP<7>")
	)
	(segment
		(start 157.890464 -184.590436)
		(end 157.889956 -184.59069)
		(width 0.14224)
		(layer "In13.Cu")
		(net "GMI_CPU0_G0_CPU1_G2_TX_DP<7>")
	)
	(segment
		(start 352.455734 -230.408226)
		(end 352.45929 -230.406194)
		(width 0.1143)
		(layer "In13.Cu")
		(net "GMI_CPU0_G0_CPU1_G2_TX_DP<7>")
	)
	(segment
		(start 352.805492 -221.382082)
		(end 352.805492 -221.145862)
		(width 0.1143)
		(layer "In13.Cu")
		(net "GMI_CPU0_G0_CPU1_G2_TX_DP<7>")
	)
	(segment
		(start 119.012462 -223.91243)
		(end 119.013478 -223.912938)
		(width 0.1143)
		(layer "In13.Cu")
		(net "GMI_CPU0_G0_CPU1_G2_TX_DP<7>")
	)
	(segment
		(start 352.476816 -235.255816)
		(end 352.478086 -235.255054)
		(width 0.1143)
		(layer "In13.Cu")
		(net "GMI_CPU0_G0_CPU1_G2_TX_DP<7>")
	)
	(segment
		(start 119.04345 -232.6386)
		(end 118.973346 -232.67924)
		(width 0.1143)
		(layer "In13.Cu")
		(net "GMI_CPU0_G0_CPU1_G2_TX_DP<7>")
	)
	(segment
		(start 119.04345 -240.73866)
		(end 118.972584 -240.779554)
		(width 0.1143)
		(layer "In13.Cu")
		(net "GMI_CPU0_G0_CPU1_G2_TX_DP<7>")
	)
	(segment
		(start 352.452432 -235.269786)
		(end 352.476816 -235.255816)
		(width 0.1143)
		(layer "In13.Cu")
		(net "GMI_CPU0_G0_CPU1_G2_TX_DP<7>")
	)
	(segment
		(start 119.04345 -224.538794)
		(end 118.972076 -224.580196)
		(width 0.1143)
		(layer "In13.Cu")
		(net "GMI_CPU0_G0_CPU1_G2_TX_DP<7>")
	)
	(segment
		(start 352.482404 -223.912684)
		(end 352.48342 -223.912176)
		(width 0.1143)
		(layer "In13.Cu")
		(net "GMI_CPU0_G0_CPU1_G2_TX_DP<7>")
	)
	(segment
		(start 352.452432 -232.029762)
		(end 352.483928 -232.011728)
		(width 0.1143)
		(layer "In13.Cu")
		(net "GMI_CPU0_G0_CPU1_G2_TX_DP<7>")
	)
	(segment
		(start 352.481642 -235.253022)
		(end 352.482404 -235.252514)
		(width 0.1143)
		(layer "In13.Cu")
		(net "GMI_CPU0_G0_CPU1_G2_TX_DP<7>")
	)
	(segment
		(start 119.042434 -229.399338)
		(end 118.970552 -229.441248)
		(width 0.1143)
		(layer "In13.Cu")
		(net "GMI_CPU0_G0_CPU1_G2_TX_DP<7>")
	)
	(segment
		(start 118.975378 -227.130864)
		(end 119.0117 -227.151946)
		(width 0.1143)
		(layer "In13.Cu")
		(net "GMI_CPU0_G0_CPU1_G2_TX_DP<7>")
	)
	(segment
		(start 352.766122 -221.421452)
		(end 352.805492 -221.382082)
		(width 0.1143)
		(layer "In13.Cu")
		(net "GMI_CPU0_G0_CPU1_G2_TX_DP<7>")
	)
	(segment
		(start 352.465894 -230.402384)
		(end 352.467164 -230.401622)
		(width 0.1143)
		(layer "In13.Cu")
		(net "GMI_CPU0_G0_CPU1_G2_TX_DP<7>")
	)
	(segment
		(start 121.658888 -213.903814)
		(end 118.64467 -219.05468)
		(width 0.14224)
		(layer "In13.Cu")
		(net "GMI_CPU0_G0_CPU1_G2_TX_DP<7>")
	)
	(segment
		(start 352.504756 -227.80879)
		(end 352.484182 -227.796852)
		(width 0.1143)
		(layer "In13.Cu")
		(net "GMI_CPU0_G0_CPU1_G2_TX_DP<7>")
	)
	(segment
		(start 352.483928 -232.011728)
		(end 352.48469 -232.01122)
		(width 0.1143)
		(layer "In13.Cu")
		(net "GMI_CPU0_G0_CPU1_G2_TX_DP<7>")
	)
	(segment
		(start 119.043196 -225.550222)
		(end 119.04345 -225.550222)
		(width 0.1143)
		(layer "In13.Cu")
		(net "GMI_CPU0_G0_CPU1_G2_TX_DP<7>")
	)
	(segment
		(start 352.452432 -223.929956)
		(end 352.478086 -223.915224)
		(width 0.1143)
		(layer "In13.Cu")
		(net "GMI_CPU0_G0_CPU1_G2_TX_DP<7>")
	)
	(segment
		(start 119.592598 -242.864386)
		(end 119.294656 -242.864386)
		(width 0.1143)
		(layer "In13.Cu")
		(net "GMI_CPU0_G0_CPU1_G2_TX_DP<7>")
	)
	(segment
		(start 119.020336 -223.916748)
		(end 119.04345 -223.93021)
		(width 0.1143)
		(layer "In13.Cu")
		(net "GMI_CPU0_G0_CPU1_G2_TX_DP<7>")
	)
	(segment
		(start 119.036592 -230.406448)
		(end 119.040148 -230.40848)
		(width 0.1143)
		(layer "In13.Cu")
		(net "GMI_CPU0_G0_CPU1_G2_TX_DP<7>")
	)
	(segment
		(start 352.523806 -224.579942)
		(end 352.452432 -224.53854)
		(width 0.1143)
		(layer "In13.Cu")
		(net "GMI_CPU0_G0_CPU1_G2_TX_DP<7>")
	)
	(segment
		(start 352.467926 -230.40086)
		(end 352.523552 -230.368856)
		(width 0.1143)
		(layer "In13.Cu")
		(net "GMI_CPU0_G0_CPU1_G2_TX_DP<7>")
	)
	(segment
		(start 352.452432 -230.410004)
		(end 352.455734 -230.408226)
		(width 0.1143)
		(layer "In13.Cu")
		(net "GMI_CPU0_G0_CPU1_G2_TX_DP<7>")
	)
	(segment
		(start 352.452686 -236.889798)
		(end 352.522536 -236.849158)
		(width 0.1143)
		(layer "In13.Cu")
		(net "GMI_CPU0_G0_CPU1_G2_TX_DP<7>")
	)
	(segment
		(start 119.033544 -222.92437)
		(end 119.032782 -222.924878)
		(width 0.1143)
		(layer "In13.Cu")
		(net "GMI_CPU0_G0_CPU1_G2_TX_DP<7>")
	)
	(segment
		(start 352.452432 -240.129822)
		(end 352.484182 -240.111534)
		(width 0.1143)
		(layer "In13.Cu")
		(net "GMI_CPU0_G0_CPU1_G2_TX_DP<7>")
	)
	(segment
		(start 352.452432 -233.649774)
		(end 352.452686 -233.649774)
		(width 0.1143)
		(layer "In13.Cu")
		(net "GMI_CPU0_G0_CPU1_G2_TX_DP<7>")
	)
	(segment
		(start 352.522536 -235.91901)
		(end 352.452432 -235.87837)
		(width 0.1143)
		(layer "In13.Cu")
		(net "GMI_CPU0_G0_CPU1_G2_TX_DP<7>")
	)
	(segment
		(start 352.523298 -240.7793)
		(end 352.452432 -240.738406)
		(width 0.1143)
		(layer "In13.Cu")
		(net "GMI_CPU0_G0_CPU1_G2_TX_DP<7>")
	)
	(segment
		(start 118.94566 -238.449866)
		(end 118.972076 -238.468662)
		(width 0.1143)
		(layer "In13.Cu")
		(net "GMI_CPU0_G0_CPU1_G2_TX_DP<7>")
	)
	(segment
		(start 118.90756 -230.311706)
		(end 118.96471 -230.364538)
		(width 0.1143)
		(layer "In13.Cu")
		(net "GMI_CPU0_G0_CPU1_G2_TX_DP<7>")
	)
	(segment
		(start 119.04345 -227.778818)
		(end 119.0117 -227.797106)
		(width 0.1143)
		(layer "In13.Cu")
		(net "GMI_CPU0_G0_CPU1_G2_TX_DP<7>")
	)
	(segment
		(start 119.019066 -235.25607)
		(end 119.04345 -235.27004)
		(width 0.1143)
		(layer "In13.Cu")
		(net "GMI_CPU0_G0_CPU1_G2_TX_DP<7>")
	)
	(segment
		(start 119.0117 -222.93707)
		(end 119.011446 -222.937324)
		(width 0.1143)
		(layer "In13.Cu")
		(net "GMI_CPU0_G0_CPU1_G2_TX_DP<7>")
	)
	(segment
		(start 352.452686 -225.549968)
		(end 352.523806 -225.508566)
		(width 0.1143)
		(layer "In13.Cu")
		(net "GMI_CPU0_G0_CPU1_G2_TX_DP<7>")
	)
	(segment
		(start 119.011192 -232.011474)
		(end 119.011954 -232.011982)
		(width 0.1143)
		(layer "In13.Cu")
		(net "GMI_CPU0_G0_CPU1_G2_TX_DP<7>")
	)
	(segment
		(start 119.033544 -234.2642)
		(end 119.032782 -234.264708)
		(width 0.1143)
		(layer "In13.Cu")
		(net "GMI_CPU0_G0_CPU1_G2_TX_DP<7>")
	)
	(segment
		(start 352.522536 -232.678986)
		(end 352.452432 -232.638346)
		(width 0.1143)
		(layer "In13.Cu")
		(net "GMI_CPU0_G0_CPU1_G2_TX_DP<7>")
	)
	(segment
		(start 352.484182 -240.111534)
		(end 352.520504 -240.090452)
		(width 0.1143)
		(layer "In13.Cu")
		(net "GMI_CPU0_G0_CPU1_G2_TX_DP<7>")
	)
	(segment
		(start 119.028718 -230.401876)
		(end 119.029988 -230.402638)
		(width 0.1143)
		(layer "In13.Cu")
		(net "GMI_CPU0_G0_CPU1_G2_TX_DP<7>")
	)
	(segment
		(start 119.027956 -230.401368)
		(end 119.028718 -230.401876)
		(width 0.1143)
		(layer "In13.Cu")
		(net "GMI_CPU0_G0_CPU1_G2_TX_DP<7>")
	)
	(segment
		(start 352.484182 -235.251498)
		(end 352.484436 -235.251498)
		(width 0.1143)
		(layer "In13.Cu")
		(net "GMI_CPU0_G0_CPU1_G2_TX_DP<7>")
	)
	(segment
		(start 152.080722 -189.35446)
		(end 152.080468 -189.353952)
		(width 0.14224)
		(layer "In13.Cu")
		(net "GMI_CPU0_G0_CPU1_G2_TX_DP<7>")
	)
	(segment
		(start 119.017034 -223.91497)
		(end 119.017796 -223.915478)
		(width 0.1143)
		(layer "In13.Cu")
		(net "GMI_CPU0_G0_CPU1_G2_TX_DP<7>")
	)
	(segment
		(start 118.972838 -222.26905)
		(end 119.042434 -222.30969)
		(width 0.1143)
		(layer "In13.Cu")
		(net "GMI_CPU0_G0_CPU1_G2_TX_DP<7>")
	)
	(segment
		(start 352.478848 -235.254546)
		(end 352.479864 -235.254038)
		(width 0.1143)
		(layer "In13.Cu")
		(net "GMI_CPU0_G0_CPU1_G2_TX_DP<7>")
	)
	(segment
		(start 118.990364 -228.759512)
		(end 119.04345 -228.790246)
		(width 0.1143)
		(layer "In13.Cu")
		(net "GMI_CPU0_G0_CPU1_G2_TX_DP<7>")
	)
	(segment
		(start 352.478848 -223.914716)
		(end 352.479864 -223.914208)
		(width 0.1143)
		(layer "In13.Cu")
		(net "GMI_CPU0_G0_CPU1_G2_TX_DP<7>")
	)
	(segment
		(start 352.484182 -227.151692)
		(end 352.520504 -227.13061)
		(width 0.1143)
		(layer "In13.Cu")
		(net "GMI_CPU0_G0_CPU1_G2_TX_DP<7>")
	)
	(segment
		(start 118.69039 -221.146116)
		(end 118.69039 -221.382336)
		(width 0.1143)
		(layer "In13.Cu")
		(net "GMI_CPU0_G0_CPU1_G2_TX_DP<7>")
	)
	(segment
		(start 118.973346 -232.67924)
		(end 118.952518 -232.693972)
		(width 0.1143)
		(layer "In13.Cu")
		(net "GMI_CPU0_G0_CPU1_G2_TX_DP<7>")
	)
	(segment
		(start 352.452432 -238.50981)
		(end 352.452686 -238.50981)
		(width 0.1143)
		(layer "In13.Cu")
		(net "GMI_CPU0_G0_CPU1_G2_TX_DP<7>")
	)
	(segment
		(start 119.043196 -236.890052)
		(end 119.04345 -236.890052)
		(width 0.1143)
		(layer "In13.Cu")
		(net "GMI_CPU0_G0_CPU1_G2_TX_DP<7>")
	)
	(segment
		(start 352.452432 -241.750088)
		(end 352.523298 -241.70894)
		(width 0.1143)
		(layer "In13.Cu")
		(net "GMI_CPU0_G0_CPU1_G2_TX_DP<7>")
	)
	(segment
		(start 352.520504 -226.197922)
		(end 352.484182 -226.17684)
		(width 0.1143)
		(layer "In13.Cu")
		(net "GMI_CPU0_G0_CPU1_G2_TX_DP<7>")
	)
	(segment
		(start 119.0117 -234.2769)
		(end 119.011446 -234.277154)
		(width 0.1143)
		(layer "In13.Cu")
		(net "GMI_CPU0_G0_CPU1_G2_TX_DP<7>")
	)
	(segment
		(start 352.484182 -227.796852)
		(end 352.452432 -227.778564)
		(width 0.1143)
		(layer "In13.Cu")
		(net "GMI_CPU0_G0_CPU1_G2_TX_DP<7>")
	)
	(segment
		(start 119.045228 -231.017318)
		(end 119.0117 -231.036876)
		(width 0.1143)
		(layer "In13.Cu")
		(net "GMI_CPU0_G0_CPU1_G2_TX_DP<7>")
	)
	(segment
		(start 118.952518 -233.594656)
		(end 118.973346 -233.609388)
		(width 0.1143)
		(layer "In13.Cu")
		(net "GMI_CPU0_G0_CPU1_G2_TX_DP<7>")
	)
	(segment
		(start 118.94566 -225.490024)
		(end 118.972076 -225.50882)
		(width 0.1143)
		(layer "In13.Cu")
		(net "GMI_CPU0_G0_CPU1_G2_TX_DP<7>")
	)
	(segment
		(start 118.972584 -240.779554)
		(end 118.944898 -240.79962)
		(width 0.1143)
		(layer "In13.Cu")
		(net "GMI_CPU0_G0_CPU1_G2_TX_DP<7>")
	)
	(segment
		(start 144.985994 -195.171314)
		(end 144.222216 -195.402962)
		(width 0.14224)
		(layer "In13.Cu")
		(net "GMI_CPU0_G0_CPU1_G2_TX_DP<7>")
	)
	(segment
		(start 146.953732 -193.557906)
		(end 146.953986 -193.557906)
		(width 0.14224)
		(layer "In13.Cu")
		(net "GMI_CPU0_G0_CPU1_G2_TX_DP<7>")
	)
	(segment
		(start 119.02694 -230.400606)
		(end 119.027956 -230.401114)
		(width 0.1143)
		(layer "In13.Cu")
		(net "GMI_CPU0_G0_CPU1_G2_TX_DP<7>")
	)
	(segment
		(start 119.04345 -226.158806)
		(end 119.0117 -226.177094)
		(width 0.1143)
		(layer "In13.Cu")
		(net "GMI_CPU0_G0_CPU1_G2_TX_DP<7>")
	)
	(segment
		(start 146.953986 -193.557906)
		(end 144.985994 -195.171314)
		(width 0.14224)
		(layer "In13.Cu")
		(net "GMI_CPU0_G0_CPU1_G2_TX_DP<7>")
	)
	(segment
		(start 351.983548 -242.559332)
		(end 352.053144 -242.518692)
		(width 0.1143)
		(layer "In13.Cu")
		(net "GMI_CPU0_G0_CPU1_G2_TX_DP<7>")
	)
	(segment
		(start 352.452686 -233.649774)
		(end 352.522536 -233.609134)
		(width 0.1143)
		(layer "In13.Cu")
		(net "GMI_CPU0_G0_CPU1_G2_TX_DP<7>")
	)
	(segment
		(start 119.027956 -230.401114)
		(end 119.027956 -230.401368)
		(width 0.1143)
		(layer "In13.Cu")
		(net "GMI_CPU0_G0_CPU1_G2_TX_DP<7>")
	)
	(segment
		(start 119.031512 -230.4034)
		(end 119.033798 -230.404924)
		(width 0.1143)
		(layer "In13.Cu")
		(net "GMI_CPU0_G0_CPU1_G2_TX_DP<7>")
	)
	(segment
		(start 352.523298 -241.70894)
		(end 352.550984 -241.688874)
		(width 0.1143)
		(layer "In13.Cu")
		(net "GMI_CPU0_G0_CPU1_G2_TX_DP<7>")
	)
	(segment
		(start 352.805492 -221.145862)
		(end 352.851212 -221.100142)
		(width 0.1143)
		(layer "In13.Cu")
		(net "GMI_CPU0_G0_CPU1_G2_TX_DP<7>")
	)
	(segment
		(start 119.662448 -242.794536)
		(end 119.592598 -242.864386)
		(width 0.1143)
		(layer "In13.Cu")
		(net "GMI_CPU0_G0_CPU1_G2_TX_DP<7>")
	)
	(segment
		(start 119.011446 -235.251752)
		(end 119.0117 -235.251752)
		(width 0.1143)
		(layer "In13.Cu")
		(net "GMI_CPU0_G0_CPU1_G2_TX_DP<7>")
	)
	(segment
		(start 352.484182 -223.911668)
		(end 352.484436 -223.911668)
		(width 0.1143)
		(layer "In13.Cu")
		(net "GMI_CPU0_G0_CPU1_G2_TX_DP<7>")
	)
	(segment
		(start 352.484182 -222.936816)
		(end 352.4631 -222.924624)
		(width 0.1143)
		(layer "In13.Cu")
		(net "GMI_CPU0_G0_CPU1_G2_TX_DP<7>")
	)
	(segment
		(start 157.889956 -184.59069)
		(end 152.080722 -189.35446)
		(width 0.14224)
		(layer "In13.Cu")
		(net "GMI_CPU0_G0_CPU1_G2_TX_DP<7>")
	)
	(segment
		(start 119.033798 -230.404924)
		(end 119.036592 -230.406448)
		(width 0.1143)
		(layer "In13.Cu")
		(net "GMI_CPU0_G0_CPU1_G2_TX_DP<7>")
	)
	(segment
		(start 152.080468 -189.353952)
		(end 146.953732 -193.557906)
		(width 0.14224)
		(layer "In13.Cu")
		(net "GMI_CPU0_G0_CPU1_G2_TX_DP<7>")
	)
	(segment
		(start 118.72976 -221.421706)
		(end 118.72976 -221.804484)
		(width 0.1143)
		(layer "In13.Cu")
		(net "GMI_CPU0_G0_CPU1_G2_TX_DP<7>")
	)
	(segment
		(start 352.462084 -230.40467)
		(end 352.46437 -230.403146)
		(width 0.1143)
		(layer "In13.Cu")
		(net "GMI_CPU0_G0_CPU1_G2_TX_DP<7>")
	)
	(segment
		(start 352.484436 -234.2769)
		(end 352.484182 -234.276646)
		(width 0.1143)
		(layer "In13.Cu")
		(net "GMI_CPU0_G0_CPU1_G2_TX_DP<7>")
	)
	(segment
		(start 119.013478 -223.912938)
		(end 119.01424 -223.913446)
		(width 0.1143)
		(layer "In13.Cu")
		(net "GMI_CPU0_G0_CPU1_G2_TX_DP<7>")
	)
	(segment
		(start 119.043196 -238.510064)
		(end 119.04345 -238.510064)
		(width 0.1143)
		(layer "In13.Cu")
		(net "GMI_CPU0_G0_CPU1_G2_TX_DP<7>")
	)
	(segment
		(start 119.0117 -240.111788)
		(end 119.04345 -240.130076)
		(width 0.1143)
		(layer "In13.Cu")
		(net "GMI_CPU0_G0_CPU1_G2_TX_DP<7>")
	)
	(segment
		(start 118.972076 -237.540038)
		(end 118.94566 -237.559088)
		(width 0.1143)
		(layer "In13.Cu")
		(net "GMI_CPU0_G0_CPU1_G2_TX_DP<7>")
	)
	(segment
		(start 118.973346 -233.609388)
		(end 119.043196 -233.650028)
		(width 0.1143)
		(layer "In13.Cu")
		(net "GMI_CPU0_G0_CPU1_G2_TX_DP<7>")
	)
	(segment
		(start 119.0117 -231.036876)
		(end 119.005858 -231.040178)
		(width 0.1143)
		(layer "In13.Cu")
		(net "GMI_CPU0_G0_CPU1_G2_TX_DP<7>")
	)
	(segment
		(start 352.851212 -218.951048)
		(end 349.845376 -213.888066)
		(width 0.14224)
		(layer "In13.Cu")
		(net "GMI_CPU0_G0_CPU1_G2_TX_DP<7>")
	)
	(segment
		(start 119.0117 -227.797106)
		(end 118.991126 -227.809044)
		(width 0.1143)
		(layer "In13.Cu")
		(net "GMI_CPU0_G0_CPU1_G2_TX_DP<7>")
	)
	(segment
		(start 352.766122 -221.80423)
		(end 352.766122 -221.421452)
		(width 0.1143)
		(layer "In13.Cu")
		(net "GMI_CPU0_G0_CPU1_G2_TX_DP<7>")
	)
	(segment
		(start 119.0117 -227.151946)
		(end 119.04345 -227.170234)
		(width 0.1143)
		(layer "In13.Cu")
		(net "GMI_CPU0_G0_CPU1_G2_TX_DP<7>")
	)
	(segment
		(start 119.01424 -235.253276)
		(end 119.015256 -235.253784)
		(width 0.1143)
		(layer "In13.Cu")
		(net "GMI_CPU0_G0_CPU1_G2_TX_DP<7>")
	)
	(segment
		(start 352.4631 -234.264454)
		(end 352.462338 -234.263946)
		(width 0.1143)
		(layer "In13.Cu")
		(net "GMI_CPU0_G0_CPU1_G2_TX_DP<7>")
	)
	(segment
		(start 352.543364 -235.933742)
		(end 352.522536 -235.91901)
		(width 0.1143)
		(layer "In13.Cu")
		(net "GMI_CPU0_G0_CPU1_G2_TX_DP<7>")
	)
	(segment
		(start 119.012462 -235.25226)
		(end 119.013478 -235.252768)
		(width 0.1143)
		(layer "In13.Cu")
		(net "GMI_CPU0_G0_CPU1_G2_TX_DP<7>")
	)
	(segment
		(start 308.876446 -181.953154)
		(end 307.267102 -181.377336)
		(width 0.14224)
		(layer "In13.Cu")
		(net "GMI_CPU0_G0_CPU1_G2_TX_DP<7>")
	)
	(segment
		(start 352.467164 -230.401622)
		(end 352.467926 -230.401114)
		(width 0.1143)
		(layer "In13.Cu")
		(net "GMI_CPU0_G0_CPU1_G2_TX_DP<7>")
	)
	(segment
		(start 352.484182 -231.036622)
		(end 352.450654 -231.017064)
		(width 0.1143)
		(layer "In13.Cu")
		(net "GMI_CPU0_G0_CPU1_G2_TX_DP<7>")
	)
	(segment
		(start 352.4631 -222.924624)
		(end 352.462338 -222.924116)
		(width 0.1143)
		(layer "In13.Cu")
		(net "GMI_CPU0_G0_CPU1_G2_TX_DP<7>")
	)
	(segment
		(start 118.64467 -221.100396)
		(end 118.69039 -221.146116)
		(width 0.1143)
		(layer "In13.Cu")
		(net "GMI_CPU0_G0_CPU1_G2_TX_DP<7>")
	)
	(segment
		(start 118.991126 -227.809044)
		(end 118.990364 -227.809552)
		(width 0.1143)
		(layer "In13.Cu")
		(net "GMI_CPU0_G0_CPU1_G2_TX_DP<7>")
	)
	(segment
		(start 119.016018 -235.254292)
		(end 119.017034 -235.2548)
		(width 0.1143)
		(layer "In13.Cu")
		(net "GMI_CPU0_G0_CPU1_G2_TX_DP<7>")
	)
	(segment
		(start 352.45929 -230.406194)
		(end 352.462084 -230.40467)
		(width 0.1143)
		(layer "In13.Cu")
		(net "GMI_CPU0_G0_CPU1_G2_TX_DP<7>")
	)
	(segment
		(start 166.178738 -180.58003)
		(end 160.153858 -182.734458)
		(width 0.14224)
		(layer "In13.Cu")
		(net "GMI_CPU0_G0_CPU1_G2_TX_DP<7>")
	)
	(segment
		(start 352.550984 -240.799366)
		(end 352.523298 -240.7793)
		(width 0.1143)
		(layer "In13.Cu")
		(net "GMI_CPU0_G0_CPU1_G2_TX_DP<7>")
	)
	(segment
		(start 144.222216 -195.402962)
		(end 121.658888 -213.903814)
		(width 0.14224)
		(layer "In13.Cu")
		(net "GMI_CPU0_G0_CPU1_G2_TX_DP<7>")
	)
	(segment
		(start 352.520504 -239.157764)
		(end 352.484182 -239.136682)
		(width 0.1143)
		(layer "In13.Cu")
		(net "GMI_CPU0_G0_CPU1_G2_TX_DP<7>")
	)
	(segment
		(start 119.029988 -230.402638)
		(end 119.031512 -230.4034)
		(width 0.1143)
		(layer "In13.Cu")
		(net "GMI_CPU0_G0_CPU1_G2_TX_DP<7>")
	)
	(segment
		(start 352.481642 -223.913192)
		(end 352.482404 -223.912684)
		(width 0.1143)
		(layer "In13.Cu")
		(net "GMI_CPU0_G0_CPU1_G2_TX_DP<7>")
	)
	(segment
		(start 352.550222 -224.598992)
		(end 352.523806 -224.579942)
		(width 0.1143)
		(layer "In13.Cu")
		(net "GMI_CPU0_G0_CPU1_G2_TX_DP<7>")
	)
	(segment
		(start 352.523806 -225.508566)
		(end 352.550222 -225.48977)
		(width 0.1143)
		(layer "In13.Cu")
		(net "GMI_CPU0_G0_CPU1_G2_TX_DP<7>")
	)
	(segment
		(start 118.64467 -219.05468)
		(end 118.64467 -221.071948)
		(width 0.14224)
		(layer "In13.Cu")
		(net "GMI_CPU0_G0_CPU1_G2_TX_DP<7>")
	)
	(segment
		(start 352.46437 -230.403146)
		(end 352.465894 -230.402384)
		(width 0.1143)
		(layer "In13.Cu")
		(net "GMI_CPU0_G0_CPU1_G2_TX_DP<7>")
	)
	(segment
		(start 352.478086 -223.915224)
		(end 352.478848 -223.914716)
		(width 0.1143)
		(layer "In13.Cu")
		(net "GMI_CPU0_G0_CPU1_G2_TX_DP<7>")
	)
	(segment
		(start 119.0117 -223.911922)
		(end 119.012462 -223.91243)
		(width 0.1143)
		(layer "In13.Cu")
		(net "GMI_CPU0_G0_CPU1_G2_TX_DP<7>")
	)
	(segment
		(start 352.467926 -230.401114)
		(end 352.467926 -230.40086)
		(width 0.1143)
		(layer "In13.Cu")
		(net "GMI_CPU0_G0_CPU1_G2_TX_DP<7>")
	)
	(segment
		(start 352.484436 -222.93707)
		(end 352.484182 -222.936816)
		(width 0.1143)
		(layer "In13.Cu")
		(net "GMI_CPU0_G0_CPU1_G2_TX_DP<7>")
	)
	(segment
		(start 352.480626 -223.9137)
		(end 352.481642 -223.913192)
		(width 0.1143)
		(layer "In13.Cu")
		(net "GMI_CPU0_G0_CPU1_G2_TX_DP<7>")
	)
	(segment
		(start 119.040148 -230.40848)
		(end 119.04345 -230.410258)
		(width 0.1143)
		(layer "In13.Cu")
		(net "GMI_CPU0_G0_CPU1_G2_TX_DP<7>")
	)
	(segment
		(start 352.505518 -227.809298)
		(end 352.504756 -227.80879)
		(width 0.1143)
		(layer "In13.Cu")
		(net "GMI_CPU0_G0_CPU1_G2_TX_DP<7>")
	)
	(segment
		(start 352.484182 -234.276646)
		(end 352.4631 -234.264454)
		(width 0.1143)
		(layer "In13.Cu")
		(net "GMI_CPU0_G0_CPU1_G2_TX_DP<7>")
	)
	(segment
		(start 118.64467 -221.071948)
		(end 118.64467 -221.100396)
		(width 0.1143)
		(layer "In13.Cu")
		(net "GMI_CPU0_G0_CPU1_G2_TX_DP<7>")
	)
	(segment
		(start 352.479864 -235.254038)
		(end 352.480626 -235.25353)
		(width 0.1143)
		(layer "In13.Cu")
		(net "GMI_CPU0_G0_CPU1_G2_TX_DP<7>")
	)
	(segment
		(start 352.522536 -236.849158)
		(end 352.543364 -236.834426)
		(width 0.1143)
		(layer "In13.Cu")
		(net "GMI_CPU0_G0_CPU1_G2_TX_DP<7>")
	)
	(segment
		(start 352.462338 -234.263946)
		(end 352.452432 -234.258358)
		(width 0.1143)
		(layer "In13.Cu")
		(net "GMI_CPU0_G0_CPU1_G2_TX_DP<7>")
	)
	(segment
		(start 352.452432 -228.789992)
		(end 352.505518 -228.759258)
		(width 0.1143)
		(layer "In13.Cu")
		(net "GMI_CPU0_G0_CPU1_G2_TX_DP<7>")
	)
	(segment
		(start 119.032782 -234.264708)
		(end 119.0117 -234.2769)
		(width 0.1143)
		(layer "In13.Cu")
		(net "GMI_CPU0_G0_CPU1_G2_TX_DP<7>")
	)
	(segment
		(start 352.533966 -230.361236)
		(end 352.575114 -230.325168)
		(width 0.1143)
		(layer "In13.Cu")
		(net "GMI_CPU0_G0_CPU1_G2_TX_DP<7>")
	)
	(segment
		(start 302.899064 -181.377336)
		(end 166.178738 -180.58003)
		(width 0.14224)
		(layer "In13.Cu")
		(net "GMI_CPU0_G0_CPU1_G2_TX_DP<7>")
	)
	(segment
		(start 352.484182 -226.17684)
		(end 352.452432 -226.158552)
		(width 0.1143)
		(layer "In13.Cu")
		(net "GMI_CPU0_G0_CPU1_G2_TX_DP<7>")
	)
	(segment
		(start 118.975378 -240.090706)
		(end 119.0117 -240.111788)
		(width 0.1143)
		(layer "In13.Cu")
		(net "GMI_CPU0_G0_CPU1_G2_TX_DP<7>")
	)
	(segment
		(start 352.522536 -233.609134)
		(end 352.543364 -233.594402)
		(width 0.1143)
		(layer "In13.Cu")
		(net "GMI_CPU0_G0_CPU1_G2_TX_DP<7>")
	)
	(segment
		(start 119.017034 -235.2548)
		(end 119.017796 -235.255308)
		(width 0.1143)
		(layer "In13.Cu")
		(net "GMI_CPU0_G0_CPU1_G2_TX_DP<7>")
	)
	(segment
		(start 119.017796 -235.255308)
		(end 119.019066 -235.25607)
		(width 0.1143)
		(layer "In13.Cu")
		(net "GMI_CPU0_G0_CPU1_G2_TX_DP<7>")
	)
	(segment
		(start 119.442738 -242.518946)
		(end 119.481854 -242.541806)
		(width 0.1143)
		(layer "In13.Cu")
		(net "GMI_CPU0_G0_CPU1_G2_TX_DP<7>")
	)
	(segment
		(start 349.845376 -213.888066)
		(end 315.40704 -185.64987)
		(width 0.14224)
		(layer "In13.Cu")
		(net "GMI_CPU0_G0_CPU1_G2_TX_DP<7>")
	)
	(segment
		(start 352.478086 -235.255054)
		(end 352.478848 -235.254546)
		(width 0.1143)
		(layer "In13.Cu")
		(net "GMI_CPU0_G0_CPU1_G2_TX_DP<7>")
	)
	(segment
		(start 160.153858 -182.734458)
		(end 157.890464 -184.590436)
		(width 0.14224)
		(layer "In13.Cu")
		(net "GMI_CPU0_G0_CPU1_G2_TX_DP<7>")
	)
	(segment
		(start 352.452432 -236.889798)
		(end 352.452686 -236.889798)
		(width 0.1143)
		(layer "In13.Cu")
		(net "GMI_CPU0_G0_CPU1_G2_TX_DP<7>")
	)
	(segment
		(start 118.729506 -229.905052)
		(end 118.736872 -229.972108)
		(width 0.1143)
		(layer "In13.Cu")
		(net "GMI_CPU0_G0_CPU1_G2_TX_DP<7>")
	)
	(segment
		(start 352.490024 -231.039924)
		(end 352.484182 -231.036622)
		(width 0.1143)
		(layer "In13.Cu")
		(net "GMI_CPU0_G0_CPU1_G2_TX_DP<7>")
	)
	(segment
		(start 118.972076 -224.580196)
		(end 118.94566 -224.599246)
		(width 0.1143)
		(layer "In13.Cu")
		(net "GMI_CPU0_G0_CPU1_G2_TX_DP<7>")
	)
	(segment
		(start 351.903284 -242.864132)
		(end 351.833434 -242.794282)
		(width 0.1143)
		(layer "In13.Cu")
		(net "GMI_CPU0_G0_CPU1_G2_TX_DP<7>")
	)
	(segment
		(start 118.972076 -238.468662)
		(end 119.043196 -238.510064)
		(width 0.1143)
		(layer "In13.Cu")
		(net "GMI_CPU0_G0_CPU1_G2_TX_DP<7>")
	)
	(segment
		(start 352.48342 -235.252006)
		(end 352.484182 -235.251498)
		(width 0.1143)
		(layer "In13.Cu")
		(net "GMI_CPU0_G0_CPU1_G2_TX_DP<7>")
	)
	(segment
		(start 352.482404 -235.252514)
		(end 352.48342 -235.252006)
		(width 0.1143)
		(layer "In13.Cu")
		(net "GMI_CPU0_G0_CPU1_G2_TX_DP<7>")
	)
	(segment
		(start 119.015256 -235.253784)
		(end 119.016018 -235.254292)
		(width 0.1143)
		(layer "In13.Cu")
		(net "GMI_CPU0_G0_CPU1_G2_TX_DP<7>")
	)
	(segment
		(start 119.481854 -242.541806)
		(end 119.512334 -242.559586)
		(width 0.1143)
		(layer "In13.Cu")
		(net "GMI_CPU0_G0_CPU1_G2_TX_DP<7>")
	)
	(segment
		(start 352.452686 -238.50981)
		(end 352.523806 -238.468408)
		(width 0.1143)
		(layer "In13.Cu")
		(net "GMI_CPU0_G0_CPU1_G2_TX_DP<7>")
	)
	(segment
		(start 119.04345 -237.498636)
		(end 118.972076 -237.540038)
		(width 0.1143)
		(layer "In13.Cu")
		(net "GMI_CPU0_G0_CPU1_G2_TX_DP<7>")
	)
	(segment
		(start 119.011954 -232.011982)
		(end 119.04345 -232.030016)
		(width 0.1143)
		(layer "In13.Cu")
		(net "GMI_CPU0_G0_CPU1_G2_TX_DP<7>")
	)
	(segment
		(start 118.944898 -241.689128)
		(end 118.972584 -241.709194)
		(width 0.1143)
		(layer "In13.Cu")
		(net "GMI_CPU0_G0_CPU1_G2_TX_DP<7>")
	)
	(segment
		(start 118.973346 -236.849412)
		(end 119.043196 -236.890052)
		(width 0.1143)
		(layer "In13.Cu")
		(net "GMI_CPU0_G0_CPU1_G2_TX_DP<7>")
	)
	(segment
		(start 119.01424 -223.913446)
		(end 119.015256 -223.913954)
		(width 0.1143)
		(layer "In13.Cu")
		(net "GMI_CPU0_G0_CPU1_G2_TX_DP<7>")
	)
	(segment
		(start 352.48469 -232.01122)
		(end 352.490024 -232.008172)
		(width 0.1143)
		(layer "In13.Cu")
		(net "GMI_CPU0_G0_CPU1_G2_TX_DP<7>")
	)
	(segment
		(start 352.462338 -222.924116)
		(end 352.452432 -222.918528)
		(width 0.1143)
		(layer "In13.Cu")
		(net "GMI_CPU0_G0_CPU1_G2_TX_DP<7>")
	)
	(segment
		(start 352.484182 -239.136682)
		(end 352.452432 -239.118394)
		(width 0.1143)
		(layer "In13.Cu")
		(net "GMI_CPU0_G0_CPU1_G2_TX_DP<7>")
	)
	(segment
		(start 119.0117 -239.136936)
		(end 118.975378 -239.158018)
		(width 0.1143)
		(layer "In13.Cu")
		(net "GMI_CPU0_G0_CPU1_G2_TX_DP<7>")
	)
	(segment
		(start 119.011446 -223.911922)
		(end 119.0117 -223.911922)
		(width 0.1143)
		(layer "In13.Cu")
		(net "GMI_CPU0_G0_CPU1_G2_TX_DP<7>")
	)
	(segment
		(start 118.96471 -230.364538)
		(end 119.027194 -230.400606)
		(width 0.1143)
		(layer "In13.Cu")
		(net "GMI_CPU0_G0_CPU1_G2_TX_DP<7>")
	)
	(segment
		(start 119.04345 -239.118648)
		(end 119.0117 -239.136936)
		(width 0.1143)
		(layer "In13.Cu")
		(net "GMI_CPU0_G0_CPU1_G2_TX_DP<7>")
	)
	(segment
		(start 315.40704 -185.64987)
		(end 308.876446 -181.953154)
		(width 0.14224)
		(layer "In13.Cu")
		(net "GMI_CPU0_G0_CPU1_G2_TX_DP<7>")
	)
	(segment
		(start 119.04345 -234.258612)
		(end 119.033544 -234.2642)
		(width 0.1143)
		(layer "In13.Cu")
		(net "GMI_CPU0_G0_CPU1_G2_TX_DP<7>")
	)
	(segment
		(start 307.267102 -181.377336)
		(end 302.899064 -181.377336)
		(width 0.14224)
		(layer "In13.Cu")
		(net "GMI_CPU0_G0_CPU1_G2_TX_DP<7>")
	)
	(segment
		(start 352.52533 -229.440994)
		(end 352.450654 -229.397052)
		(width 0.1143)
		(layer "In13.Cu")
		(net "GMI_CPU0_G0_CPU1_G2_TX_DP<7>")
	)
	(segment
		(start 119.013478 -235.252768)
		(end 119.01424 -235.253276)
		(width 0.1143)
		(layer "In13.Cu")
		(net "GMI_CPU0_G0_CPU1_G2_TX_DP<7>")
	)
	(segment
		(start 118.972584 -241.709194)
		(end 119.04345 -241.750342)
		(width 0.1143)
		(layer "In13.Cu")
		(net "GMI_CPU0_G0_CPU1_G2_TX_DP<7>")
	)
	(segment
		(start 118.952518 -236.83468)
		(end 118.973346 -236.849412)
		(width 0.1143)
		(layer "In13.Cu")
		(net "GMI_CPU0_G0_CPU1_G2_TX_DP<7>")
	)
	(segment
		(start 352.851212 -221.100142)
		(end 352.851212 -221.093538)
		(width 0.1143)
		(layer "In13.Cu")
		(net "GMI_CPU0_G0_CPU1_G2_TX_DP<7>")
	)
	(segment
		(start 352.523552 -230.368856)
		(end 352.533966 -230.361236)
		(width 0.1143)
		(layer "In13.Cu")
		(net "GMI_CPU0_G0_CPU1_G2_TX_DP<7>")
	)
	(segment
		(start 352.76155 -229.958392)
		(end 352.766376 -229.904036)
		(width 0.1143)
		(layer "In13.Cu")
		(net "GMI_CPU0_G0_CPU1_G2_TX_DP<7>")
	)
	(segment
		(start 118.973346 -235.919264)
		(end 118.952518 -235.933996)
		(width 0.1143)
		(layer "In13.Cu")
		(net "GMI_CPU0_G0_CPU1_G2_TX_DP<7>")
	)
	(segment
		(start 352.201226 -242.864132)
		(end 351.903284 -242.864132)
		(width 0.1143)
		(layer "In13.Cu")
		(net "GMI_CPU0_G0_CPU1_G2_TX_DP<7>")
	)
	(segment
		(start 119.045228 -229.397306)
		(end 119.042434 -229.399338)
		(width 0.1143)
		(layer "In13.Cu")
		(net "GMI_CPU0_G0_CPU1_G2_TX_DP<7>")
	)
	(segment
		(start 118.972076 -225.50882)
		(end 119.043196 -225.550222)
		(width 0.1143)
		(layer "In13.Cu")
		(net "GMI_CPU0_G0_CPU1_G2_TX_DP<7>")
	)
	(segment
		(start 352.550222 -237.558834)
		(end 352.523806 -237.539784)
		(width 0.1143)
		(layer "In13.Cu")
		(net "GMI_CPU0_G0_CPU1_G2_TX_DP<7>")
	)
	(segment
		(start 352.48342 -223.912176)
		(end 352.484182 -223.911668)
		(width 0.1143)
		(layer "In13.Cu")
		(net "GMI_CPU0_G0_CPU1_G2_TX_DP<7>")
	)
	(segment
		(start 352.452432 -225.549968)
		(end 352.452686 -225.549968)
		(width 0.1143)
		(layer "In13.Cu")
		(net "GMI_CPU0_G0_CPU1_G2_TX_DP<7>")
	)
	(segment
		(start 352.523806 -238.468408)
		(end 352.550222 -238.449612)
		(width 0.1143)
		(layer "In13.Cu")
		(net "GMI_CPU0_G0_CPU1_G2_TX_DP<7>")
	)
	(segment
		(start 119.017796 -223.915478)
		(end 119.020336 -223.916748)
		(width 0.1143)
		(layer "In13.Cu")
		(net "GMI_CPU0_G0_CPU1_G2_TX_DP<7>")
	)
	(segment
		(start 119.032782 -222.924878)
		(end 119.0117 -222.93707)
		(width 0.1143)
		(layer "In13.Cu")
		(net "GMI_CPU0_G0_CPU1_G2_TX_DP<7>")
	)
	(segment
		(start 119.005858 -232.008426)
		(end 119.011192 -232.011474)
		(width 0.1143)
		(layer "In13.Cu")
		(net "GMI_CPU0_G0_CPU1_G2_TX_DP<7>")
	)
	(segment
		(start 352.452432 -227.16998)
		(end 352.484182 -227.151692)
		(width 0.1143)
		(layer "In13.Cu")
		(net "GMI_CPU0_G0_CPU1_G2_TX_DP<7>")
	)
	(segment
		(start 352.453448 -222.309436)
		(end 352.523044 -222.268796)
		(width 0.1143)
		(layer "In13.Cu")
		(net "GMI_CPU0_G0_CPU1_G2_TX_DP<7>")
	)
	(segment
		(start 352.543364 -232.693718)
		(end 352.522536 -232.678986)
		(width 0.1143)
		(layer "In13.Cu")
		(net "GMI_CPU0_G0_CPU1_G2_TX_DP<7>")
	)
	(segment
		(start 352.480626 -235.25353)
		(end 352.481642 -235.253022)
		(width 0.1143)
		(layer "In13.Cu")
		(net "GMI_CPU0_G0_CPU1_G2_TX_DP<7>")
	)
	(segment
		(start 119.0117 -235.251752)
		(end 119.012462 -235.25226)
		(width 0.1143)
		(layer "In13.Cu")
		(net "GMI_CPU0_G0_CPU1_G2_TX_DP<7>")
	)
	(segment
		(start 352.479864 -223.914208)
		(end 352.480626 -223.9137)
		(width 0.1143)
		(layer "In13.Cu")
		(net "GMI_CPU0_G0_CPU1_G2_TX_DP<7>")
	)
	(segment
		(start 119.0117 -226.177094)
		(end 118.975378 -226.198176)
		(width 0.1143)
		(layer "In13.Cu")
		(net "GMI_CPU0_G0_CPU1_G2_TX_DP<7>")
	)
	(segment
		(start 118.69039 -221.382336)
		(end 118.72976 -221.421706)
		(width 0.1143)
		(layer "In13.Cu")
		(net "GMI_CPU0_G0_CPU1_G2_TX_DP<7>")
	)
	(segment
		(start 119.04345 -235.878624)
		(end 118.973346 -235.919264)
		(width 0.1143)
		(layer "In13.Cu")
		(net "GMI_CPU0_G0_CPU1_G2_TX_DP<7>")
	)
	(segment
		(start 352.851212 -221.093538)
		(end 352.851212 -218.951048)
		(width 0.14224)
		(layer "In13.Cu")
		(net "GMI_CPU0_G0_CPU1_G2_TX_DP<7>")
	)
	(segment
		(start 119.043196 -233.650028)
		(end 119.04345 -233.650028)
		(width 0.1143)
		(layer "In13.Cu")
		(net "GMI_CPU0_G0_CPU1_G2_TX_DP<7>")
	)
	(arc
		(start 118.94566 -237.559088)
		(mid 118.717464 -238.00453)
		(end 118.94566 -238.449866)
		(width 0.1143)
		(layer "In13.Cu")
		(net "GMI_CPU0_G0_CPU1_G2_TX_DP<7>")
	)
	(arc
		(start 352.490024 -232.008172)
		(mid 352.768827 -231.524048)
		(end 352.490024 -231.039924)
		(width 0.1143)
		(layer "In13.Cu")
		(net "GMI_CPU0_G0_CPU1_G2_TX_DP<7>")
	)
	(arc
		(start 118.72976 -221.804484)
		(mid 118.794134 -222.066688)
		(end 118.972838 -222.26905)
		(width 0.1143)
		(layer "In13.Cu")
		(net "GMI_CPU0_G0_CPU1_G2_TX_DP<7>")
	)
	(arc
		(start 352.575114 -230.325168)
		(mid 352.703593 -230.159704)
		(end 352.76155 -229.958392)
		(width 0.1143)
		(layer "In13.Cu")
		(net "GMI_CPU0_G0_CPU1_G2_TX_DP<7>")
	)
	(arc
		(start 352.452432 -237.498382)
		(mid 352.296504 -237.19409)
		(end 352.452432 -236.889798)
		(width 0.1143)
		(layer "In13.Cu")
		(net "GMI_CPU0_G0_CPU1_G2_TX_DP<7>")
	)
	(arc
		(start 352.452432 -239.118394)
		(mid 352.296504 -238.814102)
		(end 352.452432 -238.50981)
		(width 0.1143)
		(layer "In13.Cu")
		(net "GMI_CPU0_G0_CPU1_G2_TX_DP<7>")
	)
	(arc
		(start 352.452432 -232.638346)
		(mid 352.296504 -232.334054)
		(end 352.452432 -232.029762)
		(width 0.1143)
		(layer "In13.Cu")
		(net "GMI_CPU0_G0_CPU1_G2_TX_DP<7>")
	)
	(arc
		(start 118.952518 -232.693972)
		(mid 118.721249 -233.144314)
		(end 118.952518 -233.594656)
		(width 0.1143)
		(layer "In13.Cu")
		(net "GMI_CPU0_G0_CPU1_G2_TX_DP<7>")
	)
	(arc
		(start 118.990364 -227.809552)
		(mid 118.716813 -228.284532)
		(end 118.990364 -228.759512)
		(width 0.1143)
		(layer "In13.Cu")
		(net "GMI_CPU0_G0_CPU1_G2_TX_DP<7>")
	)
	(arc
		(start 119.199406 -229.094538)
		(mid 119.158644 -229.264422)
		(end 119.045228 -229.397306)
		(width 0.1143)
		(layer "In13.Cu")
		(net "GMI_CPU0_G0_CPU1_G2_TX_DP<7>")
	)
	(arc
		(start 118.736872 -229.972108)
		(mid 118.791455 -230.157363)
		(end 118.90756 -230.311706)
		(width 0.1143)
		(layer "In13.Cu")
		(net "GMI_CPU0_G0_CPU1_G2_TX_DP<7>")
	)
	(arc
		(start 352.296476 -230.714296)
		(mid 352.337731 -230.543325)
		(end 352.452432 -230.410004)
		(width 0.1143)
		(layer "In13.Cu")
		(net "GMI_CPU0_G0_CPU1_G2_TX_DP<7>")
	)
	(arc
		(start 118.975378 -226.198176)
		(mid 118.9672 -226.203819)
		(end 118.959122 -226.209606)
		(width 0.1143)
		(layer "In13.Cu")
		(net "GMI_CPU0_G0_CPU1_G2_TX_DP<7>")
	)
	(arc
		(start 352.452432 -235.87837)
		(mid 352.296504 -235.574078)
		(end 352.452432 -235.269786)
		(width 0.1143)
		(layer "In13.Cu")
		(net "GMI_CPU0_G0_CPU1_G2_TX_DP<7>")
	)
	(arc
		(start 352.534728 -240.080546)
		(mid 352.762111 -239.624108)
		(end 352.534728 -239.16767)
		(width 0.1143)
		(layer "In13.Cu")
		(net "GMI_CPU0_G0_CPU1_G2_TX_DP<7>")
	)
	(arc
		(start 119.04345 -233.650028)
		(mid 119.199378 -233.95432)
		(end 119.04345 -234.258612)
		(width 0.1143)
		(layer "In13.Cu")
		(net "GMI_CPU0_G0_CPU1_G2_TX_DP<7>")
	)
	(arc
		(start 352.520504 -240.090452)
		(mid 352.527654 -240.085554)
		(end 352.534728 -240.080546)
		(width 0.1143)
		(layer "In13.Cu")
		(net "GMI_CPU0_G0_CPU1_G2_TX_DP<7>")
	)
	(arc
		(start 118.961154 -240.0808)
		(mid 118.968228 -240.085807)
		(end 118.975378 -240.090706)
		(width 0.1143)
		(layer "In13.Cu")
		(net "GMI_CPU0_G0_CPU1_G2_TX_DP<7>")
	)
	(arc
		(start 352.543364 -233.594402)
		(mid 352.774633 -233.14406)
		(end 352.543364 -232.693718)
		(width 0.1143)
		(layer "In13.Cu")
		(net "GMI_CPU0_G0_CPU1_G2_TX_DP<7>")
	)
	(arc
		(start 119.04345 -230.410258)
		(mid 119.158126 -230.543592)
		(end 119.199406 -230.71455)
		(width 0.1143)
		(layer "In13.Cu")
		(net "GMI_CPU0_G0_CPU1_G2_TX_DP<7>")
	)
	(arc
		(start 118.944898 -240.79962)
		(mid 118.716898 -241.244374)
		(end 118.944898 -241.689128)
		(width 0.1143)
		(layer "In13.Cu")
		(net "GMI_CPU0_G0_CPU1_G2_TX_DP<7>")
	)
	(arc
		(start 118.961154 -239.167924)
		(mid 118.733771 -239.624362)
		(end 118.961154 -240.0808)
		(width 0.1143)
		(layer "In13.Cu")
		(net "GMI_CPU0_G0_CPU1_G2_TX_DP<7>")
	)
	(arc
		(start 352.550222 -225.48977)
		(mid 352.778212 -225.044434)
		(end 352.550222 -224.598992)
		(width 0.1143)
		(layer "In13.Cu")
		(net "GMI_CPU0_G0_CPU1_G2_TX_DP<7>")
	)
	(arc
		(start 118.975378 -239.158018)
		(mid 118.968229 -239.162918)
		(end 118.961154 -239.167924)
		(width 0.1143)
		(layer "In13.Cu")
		(net "GMI_CPU0_G0_CPU1_G2_TX_DP<7>")
	)
	(arc
		(start 118.959122 -226.209606)
		(mid 118.736238 -226.66452)
		(end 118.959122 -227.119434)
		(width 0.1143)
		(layer "In13.Cu")
		(net "GMI_CPU0_G0_CPU1_G2_TX_DP<7>")
	)
	(arc
		(start 119.04345 -228.790246)
		(mid 119.158126 -228.92358)
		(end 119.199406 -229.094538)
		(width 0.1143)
		(layer "In13.Cu")
		(net "GMI_CPU0_G0_CPU1_G2_TX_DP<7>")
	)
	(arc
		(start 119.04345 -223.93021)
		(mid 119.199378 -224.234502)
		(end 119.04345 -224.538794)
		(width 0.1143)
		(layer "In13.Cu")
		(net "GMI_CPU0_G0_CPU1_G2_TX_DP<7>")
	)
	(arc
		(start 119.133366 -241.842036)
		(mid 119.18245 -241.943205)
		(end 119.199406 -242.05438)
		(width 0.1143)
		(layer "In13.Cu")
		(net "GMI_CPU0_G0_CPU1_G2_TX_DP<7>")
	)
	(arc
		(start 352.296476 -229.094284)
		(mid 352.337731 -228.923313)
		(end 352.452432 -228.789992)
		(width 0.1143)
		(layer "In13.Cu")
		(net "GMI_CPU0_G0_CPU1_G2_TX_DP<7>")
	)
	(arc
		(start 352.450654 -231.017064)
		(mid 352.337247 -230.884175)
		(end 352.296476 -230.714296)
		(width 0.1143)
		(layer "In13.Cu")
		(net "GMI_CPU0_G0_CPU1_G2_TX_DP<7>")
	)
	(arc
		(start 352.534728 -239.16767)
		(mid 352.527655 -239.162661)
		(end 352.520504 -239.157764)
		(width 0.1143)
		(layer "In13.Cu")
		(net "GMI_CPU0_G0_CPU1_G2_TX_DP<7>")
	)
	(arc
		(start 352.53676 -227.11918)
		(mid 352.759644 -226.664266)
		(end 352.53676 -226.209352)
		(width 0.1143)
		(layer "In13.Cu")
		(net "GMI_CPU0_G0_CPU1_G2_TX_DP<7>")
	)
	(arc
		(start 352.452432 -226.158552)
		(mid 352.296504 -225.85426)
		(end 352.452432 -225.549968)
		(width 0.1143)
		(layer "In13.Cu")
		(net "GMI_CPU0_G0_CPU1_G2_TX_DP<7>")
	)
	(arc
		(start 352.550222 -238.449612)
		(mid 352.778212 -238.004276)
		(end 352.550222 -237.558834)
		(width 0.1143)
		(layer "In13.Cu")
		(net "GMI_CPU0_G0_CPU1_G2_TX_DP<7>")
	)
	(arc
		(start 352.53676 -226.209352)
		(mid 352.528682 -226.203566)
		(end 352.520504 -226.197922)
		(width 0.1143)
		(layer "In13.Cu")
		(net "GMI_CPU0_G0_CPU1_G2_TX_DP<7>")
	)
	(arc
		(start 119.011446 -222.937324)
		(mid 118.730799 -223.424686)
		(end 119.011446 -223.911922)
		(width 0.1143)
		(layer "In13.Cu")
		(net "GMI_CPU0_G0_CPU1_G2_TX_DP<7>")
	)
	(arc
		(start 352.766376 -229.904036)
		(mid 352.70257 -229.642983)
		(end 352.52533 -229.440994)
		(width 0.1143)
		(layer "In13.Cu")
		(net "GMI_CPU0_G0_CPU1_G2_TX_DP<7>")
	)
	(arc
		(start 119.04345 -225.550222)
		(mid 119.199378 -225.854514)
		(end 119.04345 -226.158806)
		(width 0.1143)
		(layer "In13.Cu")
		(net "GMI_CPU0_G0_CPU1_G2_TX_DP<7>")
	)
	(arc
		(start 118.959122 -227.119434)
		(mid 118.9672 -227.12522)
		(end 118.975378 -227.130864)
		(width 0.1143)
		(layer "In13.Cu")
		(net "GMI_CPU0_G0_CPU1_G2_TX_DP<7>")
	)
	(arc
		(start 352.296476 -242.054126)
		(mid 352.313347 -241.942925)
		(end 352.362516 -241.841782)
		(width 0.1143)
		(layer "In13.Cu")
		(net "GMI_CPU0_G0_CPU1_G2_TX_DP<7>")
	)
	(arc
		(start 119.04345 -235.27004)
		(mid 119.199378 -235.574332)
		(end 119.04345 -235.878624)
		(width 0.1143)
		(layer "In13.Cu")
		(net "GMI_CPU0_G0_CPU1_G2_TX_DP<7>")
	)
	(arc
		(start 352.452432 -234.258358)
		(mid 352.296504 -233.954066)
		(end 352.452432 -233.649774)
		(width 0.1143)
		(layer "In13.Cu")
		(net "GMI_CPU0_G0_CPU1_G2_TX_DP<7>")
	)
	(arc
		(start 352.520504 -227.13061)
		(mid 352.528682 -227.124967)
		(end 352.53676 -227.11918)
		(width 0.1143)
		(layer "In13.Cu")
		(net "GMI_CPU0_G0_CPU1_G2_TX_DP<7>")
	)
	(arc
		(start 119.005858 -231.040178)
		(mid 118.727055 -231.524302)
		(end 119.005858 -232.008426)
		(width 0.1143)
		(layer "In13.Cu")
		(net "GMI_CPU0_G0_CPU1_G2_TX_DP<7>")
	)
	(arc
		(start 118.94566 -224.599246)
		(mid 118.717464 -225.044688)
		(end 118.94566 -225.490024)
		(width 0.1143)
		(layer "In13.Cu")
		(net "GMI_CPU0_G0_CPU1_G2_TX_DP<7>")
	)
	(arc
		(start 119.042434 -222.30969)
		(mid 119.157861 -222.443066)
		(end 119.199406 -222.61449)
		(width 0.1143)
		(layer "In13.Cu")
		(net "GMI_CPU0_G0_CPU1_G2_TX_DP<7>")
	)
	(arc
		(start 119.199406 -230.71455)
		(mid 119.158644 -230.884434)
		(end 119.045228 -231.017318)
		(width 0.1143)
		(layer "In13.Cu")
		(net "GMI_CPU0_G0_CPU1_G2_TX_DP<7>")
	)
	(arc
		(start 352.550984 -241.688874)
		(mid 352.778984 -241.24412)
		(end 352.550984 -240.799366)
		(width 0.1143)
		(layer "In13.Cu")
		(net "GMI_CPU0_G0_CPU1_G2_TX_DP<7>")
	)
	(arc
		(start 352.053144 -242.518692)
		(mid 352.231957 -242.316342)
		(end 352.296476 -242.054126)
		(width 0.1143)
		(layer "In13.Cu")
		(net "GMI_CPU0_G0_CPU1_G2_TX_DP<7>")
	)
	(arc
		(start 352.296476 -222.614236)
		(mid 352.338025 -222.442814)
		(end 352.453448 -222.309436)
		(width 0.1143)
		(layer "In13.Cu")
		(net "GMI_CPU0_G0_CPU1_G2_TX_DP<7>")
	)
	(arc
		(start 118.952518 -235.933996)
		(mid 118.721249 -236.384338)
		(end 118.952518 -236.83468)
		(width 0.1143)
		(layer "In13.Cu")
		(net "GMI_CPU0_G0_CPU1_G2_TX_DP<7>")
	)
	(arc
		(start 352.523044 -222.268796)
		(mid 352.701687 -222.066401)
		(end 352.766122 -221.80423)
		(width 0.1143)
		(layer "In13.Cu")
		(net "GMI_CPU0_G0_CPU1_G2_TX_DP<7>")
	)
	(arc
		(start 119.04345 -236.890052)
		(mid 119.199378 -237.194344)
		(end 119.04345 -237.498636)
		(width 0.1143)
		(layer "In13.Cu")
		(net "GMI_CPU0_G0_CPU1_G2_TX_DP<7>")
	)
	(arc
		(start 119.199406 -222.61449)
		(mid 119.158151 -222.785461)
		(end 119.04345 -222.918782)
		(width 0.1143)
		(layer "In13.Cu")
		(net "GMI_CPU0_G0_CPU1_G2_TX_DP<7>")
	)
	(arc
		(start 352.452432 -240.738406)
		(mid 352.296504 -240.434114)
		(end 352.452432 -240.129822)
		(width 0.1143)
		(layer "In13.Cu")
		(net "GMI_CPU0_G0_CPU1_G2_TX_DP<7>")
	)
	(arc
		(start 119.04345 -238.510064)
		(mid 119.199378 -238.814356)
		(end 119.04345 -239.118648)
		(width 0.1143)
		(layer "In13.Cu")
		(net "GMI_CPU0_G0_CPU1_G2_TX_DP<7>")
	)
	(arc
		(start 118.970552 -229.441248)
		(mid 118.79318 -229.643598)
		(end 118.729506 -229.905052)
		(width 0.1143)
		(layer "In13.Cu")
		(net "GMI_CPU0_G0_CPU1_G2_TX_DP<7>")
	)
	(arc
		(start 119.04345 -240.130076)
		(mid 119.199378 -240.434368)
		(end 119.04345 -240.73866)
		(width 0.1143)
		(layer "In13.Cu")
		(net "GMI_CPU0_G0_CPU1_G2_TX_DP<7>")
	)
	(arc
		(start 352.452432 -227.778564)
		(mid 352.296504 -227.474272)
		(end 352.452432 -227.16998)
		(width 0.1143)
		(layer "In13.Cu")
		(net "GMI_CPU0_G0_CPU1_G2_TX_DP<7>")
	)
	(arc
		(start 119.199406 -242.05438)
		(mid 119.263921 -242.316599)
		(end 119.442738 -242.518946)
		(width 0.1143)
		(layer "In13.Cu")
		(net "GMI_CPU0_G0_CPU1_G2_TX_DP<7>")
	)
	(arc
		(start 351.833434 -242.794282)
		(mid 351.885851 -242.662351)
		(end 351.983548 -242.559332)
		(width 0.1143)
		(layer "In13.Cu")
		(net "GMI_CPU0_G0_CPU1_G2_TX_DP<7>")
	)
	(arc
		(start 119.04345 -227.170234)
		(mid 119.199378 -227.474526)
		(end 119.04345 -227.778818)
		(width 0.1143)
		(layer "In13.Cu")
		(net "GMI_CPU0_G0_CPU1_G2_TX_DP<7>")
	)
	(arc
		(start 352.484436 -235.251498)
		(mid 352.764863 -234.764262)
		(end 352.484436 -234.2769)
		(width 0.1143)
		(layer "In13.Cu")
		(net "GMI_CPU0_G0_CPU1_G2_TX_DP<7>")
	)
	(arc
		(start 352.543364 -236.834426)
		(mid 352.774633 -236.384084)
		(end 352.543364 -235.933742)
		(width 0.1143)
		(layer "In13.Cu")
		(net "GMI_CPU0_G0_CPU1_G2_TX_DP<7>")
	)
	(arc
		(start 352.362516 -241.841782)
		(mid 352.403505 -241.792041)
		(end 352.452432 -241.750088)
		(width 0.1143)
		(layer "In13.Cu")
		(net "GMI_CPU0_G0_CPU1_G2_TX_DP<7>")
	)
	(arc
		(start 352.505518 -228.759258)
		(mid 352.779069 -228.284278)
		(end 352.505518 -227.809298)
		(width 0.1143)
		(layer "In13.Cu")
		(net "GMI_CPU0_G0_CPU1_G2_TX_DP<7>")
	)
	(arc
		(start 119.04345 -241.750342)
		(mid 119.09236 -241.792313)
		(end 119.133366 -241.842036)
		(width 0.1143)
		(layer "In13.Cu")
		(net "GMI_CPU0_G0_CPU1_G2_TX_DP<7>")
	)
	(arc
		(start 352.450654 -229.397052)
		(mid 352.337247 -229.264163)
		(end 352.296476 -229.094284)
		(width 0.1143)
		(layer "In13.Cu")
		(net "GMI_CPU0_G0_CPU1_G2_TX_DP<7>")
	)
	(arc
		(start 119.011446 -234.277154)
		(mid 118.730799 -234.764516)
		(end 119.011446 -235.251752)
		(width 0.1143)
		(layer "In13.Cu")
		(net "GMI_CPU0_G0_CPU1_G2_TX_DP<7>")
	)
	(arc
		(start 352.452432 -222.918528)
		(mid 352.337756 -222.785194)
		(end 352.296476 -222.614236)
		(width 0.1143)
		(layer "In13.Cu")
		(net "GMI_CPU0_G0_CPU1_G2_TX_DP<7>")
	)
	(arc
		(start 119.512334 -242.559586)
		(mid 119.610099 -242.662562)
		(end 119.662448 -242.794536)
		(width 0.1143)
		(layer "In13.Cu")
		(net "GMI_CPU0_G0_CPU1_G2_TX_DP<7>")
	)
	(arc
		(start 352.452432 -224.53854)
		(mid 352.296504 -224.234248)
		(end 352.452432 -223.929956)
		(width 0.1143)
		(layer "In13.Cu")
		(net "GMI_CPU0_G0_CPU1_G2_TX_DP<7>")
	)
	(arc
		(start 119.04345 -232.030016)
		(mid 119.199378 -232.334308)
		(end 119.04345 -232.6386)
		(width 0.1143)
		(layer "In13.Cu")
		(net "GMI_CPU0_G0_CPU1_G2_TX_DP<7>")
	)
	(arc
		(start 352.484436 -223.911668)
		(mid 352.764863 -223.424432)
		(end 352.484436 -222.93707)
		(width 0.1143)
		(layer "In13.Cu")
		(net "GMI_CPU0_G0_CPU1_G2_TX_DP<7>")
	)
	(segment
		(start 355.487986 -241.510058)
		(end 355.021134 -241.24412)
		(width 0.12954)
		(layer "F.Cu")
		(net "GMI_CPU0_G0_CPU1_G2_TX_DP<6>")
	)
	(segment
		(start 116.007896 -241.510312)
		(end 116.474748 -241.244374)
		(width 0.12954)
		(layer "F.Cu")
		(net "GMI_CPU0_G0_CPU1_G2_TX_DP<6>")
	)
	(segment
		(start 116.159534 -227.13315)
		(end 116.160296 -227.133658)
		(width 0.1143)
		(layer "In13.Cu")
		(net "GMI_CPU0_G0_CPU1_G2_TX_DP<6>")
	)
	(segment
		(start 355.30663 -227.798376)
		(end 355.305106 -227.79736)
		(width 0.1143)
		(layer "In13.Cu")
		(net "GMI_CPU0_G0_CPU1_G2_TX_DP<6>")
	)
	(segment
		(start 355.335586 -230.373428)
		(end 355.336348 -230.37292)
		(width 0.1143)
		(layer "In13.Cu")
		(net "GMI_CPU0_G0_CPU1_G2_TX_DP<6>")
	)
	(segment
		(start 355.30409 -232.011474)
		(end 355.305106 -232.010966)
		(width 0.1143)
		(layer "In13.Cu")
		(net "GMI_CPU0_G0_CPU1_G2_TX_DP<6>")
	)
	(segment
		(start 355.27234 -227.778564)
		(end 355.252528 -227.76434)
		(width 0.1143)
		(layer "In13.Cu")
		(net "GMI_CPU0_G0_CPU1_G2_TX_DP<6>")
	)
	(segment
		(start 115.81003 -218.148916)
		(end 115.81003 -221.071948)
		(width 0.14224)
		(layer "In13.Cu")
		(net "GMI_CPU0_G0_CPU1_G2_TX_DP<6>")
	)
	(segment
		(start 355.27234 -238.50981)
		(end 355.303328 -238.49203)
		(width 0.1143)
		(layer "In13.Cu")
		(net "GMI_CPU0_G0_CPU1_G2_TX_DP<6>")
	)
	(segment
		(start 116.191792 -239.136936)
		(end 116.190776 -239.137444)
		(width 0.1143)
		(layer "In13.Cu")
		(net "GMI_CPU0_G0_CPU1_G2_TX_DP<6>")
	)
	(segment
		(start 116.192554 -224.556574)
		(end 116.191792 -224.557082)
		(width 0.1143)
		(layer "In13.Cu")
		(net "GMI_CPU0_G0_CPU1_G2_TX_DP<6>")
	)
	(segment
		(start 116.62537 -240.900712)
		(end 116.661692 -240.921794)
		(width 0.1143)
		(layer "In13.Cu")
		(net "GMI_CPU0_G0_CPU1_G2_TX_DP<6>")
	)
	(segment
		(start 355.305106 -227.79736)
		(end 355.30409 -227.796852)
		(width 0.1143)
		(layer "In13.Cu")
		(net "GMI_CPU0_G0_CPU1_G2_TX_DP<6>")
	)
	(segment
		(start 355.30409 -227.796852)
		(end 355.303328 -227.796344)
		(width 0.1143)
		(layer "In13.Cu")
		(net "GMI_CPU0_G0_CPU1_G2_TX_DP<6>")
	)
	(segment
		(start 355.116384 -240.434114)
		(end 355.116384 -240.432082)
		(width 0.1143)
		(layer "In13.Cu")
		(net "GMI_CPU0_G0_CPU1_G2_TX_DP<6>")
	)
	(segment
		(start 116.160296 -231.99344)
		(end 116.191792 -232.011728)
		(width 0.1143)
		(layer "In13.Cu")
		(net "GMI_CPU0_G0_CPU1_G2_TX_DP<6>")
	)
	(segment
		(start 355.305106 -233.630978)
		(end 355.30663 -233.629962)
		(width 0.1143)
		(layer "In13.Cu")
		(net "GMI_CPU0_G0_CPU1_G2_TX_DP<6>")
	)
	(segment
		(start 116.150644 -229.441248)
		(end 116.15039 -229.441248)
		(width 0.1143)
		(layer "In13.Cu")
		(net "GMI_CPU0_G0_CPU1_G2_TX_DP<6>")
	)
	(segment
		(start 116.190776 -224.55759)
		(end 116.189252 -224.558606)
		(width 0.1143)
		(layer "In13.Cu")
		(net "GMI_CPU0_G0_CPU1_G2_TX_DP<6>")
	)
	(segment
		(start 116.152676 -227.129086)
		(end 116.159534 -227.13315)
		(width 0.1143)
		(layer "In13.Cu")
		(net "GMI_CPU0_G0_CPU1_G2_TX_DP<6>")
	)
	(segment
		(start 355.305106 -235.25099)
		(end 355.30663 -235.249974)
		(width 0.1143)
		(layer "In13.Cu")
		(net "GMI_CPU0_G0_CPU1_G2_TX_DP<6>")
	)
	(segment
		(start 116.159534 -233.612944)
		(end 116.160296 -233.613452)
		(width 0.1143)
		(layer "In13.Cu")
		(net "GMI_CPU0_G0_CPU1_G2_TX_DP<6>")
	)
	(segment
		(start 316.69863 -183.07939)
		(end 310.141112 -179.36718)
		(width 0.14224)
		(layer "In13.Cu")
		(net "GMI_CPU0_G0_CPU1_G2_TX_DP<6>")
	)
	(segment
		(start 116.243354 -239.104424)
		(end 116.223542 -239.118648)
		(width 0.1143)
		(layer "In13.Cu")
		(net "GMI_CPU0_G0_CPU1_G2_TX_DP<6>")
	)
	(segment
		(start 116.191792 -227.797106)
		(end 116.190776 -227.797614)
		(width 0.1143)
		(layer "In13.Cu")
		(net "GMI_CPU0_G0_CPU1_G2_TX_DP<6>")
	)
	(segment
		(start 116.191792 -235.896912)
		(end 116.190776 -235.89742)
		(width 0.1143)
		(layer "In13.Cu")
		(net "GMI_CPU0_G0_CPU1_G2_TX_DP<6>")
	)
	(segment
		(start 116.192554 -238.492284)
		(end 116.223542 -238.510064)
		(width 0.1143)
		(layer "In13.Cu")
		(net "GMI_CPU0_G0_CPU1_G2_TX_DP<6>")
	)
	(segment
		(start 116.152676 -228.749098)
		(end 116.159534 -228.753162)
		(width 0.1143)
		(layer "In13.Cu")
		(net "GMI_CPU0_G0_CPU1_G2_TX_DP<6>")
	)
	(segment
		(start 355.303328 -234.276138)
		(end 355.27234 -234.258358)
		(width 0.1143)
		(layer "In13.Cu")
		(net "GMI_CPU0_G0_CPU1_G2_TX_DP<6>")
	)
	(segment
		(start 116.153438 -225.509582)
		(end 116.174774 -225.522028)
		(width 0.1143)
		(layer "In13.Cu")
		(net "GMI_CPU0_G0_CPU1_G2_TX_DP<6>")
	)
	(segment
		(start 116.223542 -239.118648)
		(end 116.192554 -239.136428)
		(width 0.1143)
		(layer "In13.Cu")
		(net "GMI_CPU0_G0_CPU1_G2_TX_DP<6>")
	)
	(segment
		(start 116.192554 -227.796598)
		(end 116.191792 -227.797106)
		(width 0.1143)
		(layer "In13.Cu")
		(net "GMI_CPU0_G0_CPU1_G2_TX_DP<6>")
	)
	(segment
		(start 355.305106 -228.771196)
		(end 355.30663 -228.77018)
		(width 0.1143)
		(layer "In13.Cu")
		(net "GMI_CPU0_G0_CPU1_G2_TX_DP<6>")
	)
	(segment
		(start 355.303328 -232.011982)
		(end 355.30409 -232.011474)
		(width 0.1143)
		(layer "In13.Cu")
		(net "GMI_CPU0_G0_CPU1_G2_TX_DP<6>")
	)
	(segment
		(start 355.27234 -222.309944)
		(end 355.343206 -222.268796)
		(width 0.1143)
		(layer "In13.Cu")
		(net "GMI_CPU0_G0_CPU1_G2_TX_DP<6>")
	)
	(segment
		(start 355.30663 -240.11001)
		(end 355.343206 -240.088674)
		(width 0.1143)
		(layer "In13.Cu")
		(net "GMI_CPU0_G0_CPU1_G2_TX_DP<6>")
	)
	(segment
		(start 355.30663 -237.518194)
		(end 355.305106 -237.517178)
		(width 0.1143)
		(layer "In13.Cu")
		(net "GMI_CPU0_G0_CPU1_G2_TX_DP<6>")
	)
	(segment
		(start 116.192554 -223.91243)
		(end 116.223542 -223.93021)
		(width 0.1143)
		(layer "In13.Cu")
		(net "GMI_CPU0_G0_CPU1_G2_TX_DP<6>")
	)
	(segment
		(start 355.303328 -226.176332)
		(end 355.27234 -226.158552)
		(width 0.1143)
		(layer "In13.Cu")
		(net "GMI_CPU0_G0_CPU1_G2_TX_DP<6>")
	)
	(segment
		(start 116.160296 -228.75367)
		(end 116.191792 -228.771958)
		(width 0.1143)
		(layer "In13.Cu")
		(net "GMI_CPU0_G0_CPU1_G2_TX_DP<6>")
	)
	(segment
		(start 355.021134 -241.24412)
		(end 354.723192 -241.24412)
		(width 0.1143)
		(layer "In13.Cu")
		(net "GMI_CPU0_G0_CPU1_G2_TX_DP<6>")
	)
	(segment
		(start 116.189252 -232.658412)
		(end 116.152676 -232.679748)
		(width 0.1143)
		(layer "In13.Cu")
		(net "GMI_CPU0_G0_CPU1_G2_TX_DP<6>")
	)
	(segment
		(start 355.343206 -235.919518)
		(end 355.30663 -235.898182)
		(width 0.1143)
		(layer "In13.Cu")
		(net "GMI_CPU0_G0_CPU1_G2_TX_DP<6>")
	)
	(segment
		(start 355.27234 -236.889798)
		(end 355.303328 -236.872018)
		(width 0.1143)
		(layer "In13.Cu")
		(net "GMI_CPU0_G0_CPU1_G2_TX_DP<6>")
	)
	(segment
		(start 116.190776 -239.137444)
		(end 116.189252 -239.13846)
		(width 0.1143)
		(layer "In13.Cu")
		(net "GMI_CPU0_G0_CPU1_G2_TX_DP<6>")
	)
	(segment
		(start 116.192554 -240.112296)
		(end 116.223542 -240.130076)
		(width 0.1143)
		(layer "In13.Cu")
		(net "GMI_CPU0_G0_CPU1_G2_TX_DP<6>")
	)
	(segment
		(start 116.152676 -223.889062)
		(end 116.159534 -223.893126)
		(width 0.1143)
		(layer "In13.Cu")
		(net "GMI_CPU0_G0_CPU1_G2_TX_DP<6>")
	)
	(segment
		(start 355.30663 -238.489998)
		(end 355.343206 -238.468662)
		(width 0.1143)
		(layer "In13.Cu")
		(net "GMI_CPU0_G0_CPU1_G2_TX_DP<6>")
	)
	(segment
		(start 116.190776 -227.797614)
		(end 116.189252 -227.79863)
		(width 0.1143)
		(layer "In13.Cu")
		(net "GMI_CPU0_G0_CPU1_G2_TX_DP<6>")
	)
	(segment
		(start 116.192554 -227.152454)
		(end 116.223542 -227.170234)
		(width 0.1143)
		(layer "In13.Cu")
		(net "GMI_CPU0_G0_CPU1_G2_TX_DP<6>")
	)
	(segment
		(start 116.160296 -227.133658)
		(end 116.191792 -227.151946)
		(width 0.1143)
		(layer "In13.Cu")
		(net "GMI_CPU0_G0_CPU1_G2_TX_DP<6>")
	)
	(segment
		(start 355.343206 -239.159542)
		(end 355.30663 -239.138206)
		(width 0.1143)
		(layer "In13.Cu")
		(net "GMI_CPU0_G0_CPU1_G2_TX_DP<6>")
	)
	(segment
		(start 116.152676 -231.988868)
		(end 116.159534 -231.992932)
		(width 0.1143)
		(layer "In13.Cu")
		(net "GMI_CPU0_G0_CPU1_G2_TX_DP<6>")
	)
	(segment
		(start 116.189252 -235.898436)
		(end 116.152676 -235.919772)
		(width 0.1143)
		(layer "In13.Cu")
		(net "GMI_CPU0_G0_CPU1_G2_TX_DP<6>")
	)
	(segment
		(start 116.191792 -232.656888)
		(end 116.190776 -232.657396)
		(width 0.1143)
		(layer "In13.Cu")
		(net "GMI_CPU0_G0_CPU1_G2_TX_DP<6>")
	)
	(segment
		(start 355.30409 -240.111534)
		(end 355.305106 -240.111026)
		(width 0.1143)
		(layer "In13.Cu")
		(net "GMI_CPU0_G0_CPU1_G2_TX_DP<6>")
	)
	(segment
		(start 116.213128 -228.784404)
		(end 116.213382 -228.784404)
		(width 0.1143)
		(layer "In13.Cu")
		(net "GMI_CPU0_G0_CPU1_G2_TX_DP<6>")
	)
	(segment
		(start 116.223542 -232.6386)
		(end 116.192554 -232.65638)
		(width 0.1143)
		(layer "In13.Cu")
		(net "GMI_CPU0_G0_CPU1_G2_TX_DP<6>")
	)
	(segment
		(start 354.723192 -241.24412)
		(end 354.653342 -241.17427)
		(width 0.1143)
		(layer "In13.Cu")
		(net "GMI_CPU0_G0_CPU1_G2_TX_DP<6>")
	)
	(segment
		(start 355.30409 -239.136682)
		(end 355.303328 -239.136174)
		(width 0.1143)
		(layer "In13.Cu")
		(net "GMI_CPU0_G0_CPU1_G2_TX_DP<6>")
	)
	(segment
		(start 116.152676 -222.26905)
		(end 116.223542 -222.310198)
		(width 0.1143)
		(layer "In13.Cu")
		(net "GMI_CPU0_G0_CPU1_G2_TX_DP<6>")
	)
	(segment
		(start 355.282754 -229.404418)
		(end 355.282246 -229.404418)
		(width 0.1143)
		(layer "In13.Cu")
		(net "GMI_CPU0_G0_CPU1_G2_TX_DP<6>")
	)
	(segment
		(start 355.27234 -223.929956)
		(end 355.303328 -223.912176)
		(width 0.1143)
		(layer "In13.Cu")
		(net "GMI_CPU0_G0_CPU1_G2_TX_DP<6>")
	)
	(segment
		(start 116.159534 -235.232956)
		(end 116.160296 -235.233464)
		(width 0.1143)
		(layer "In13.Cu")
		(net "GMI_CPU0_G0_CPU1_G2_TX_DP<6>")
	)
	(segment
		(start 116.223542 -233.650028)
		(end 116.243354 -233.664252)
		(width 0.1143)
		(layer "In13.Cu")
		(net "GMI_CPU0_G0_CPU1_G2_TX_DP<6>")
	)
	(segment
		(start 355.343206 -234.299506)
		(end 355.30663 -234.27817)
		(width 0.1143)
		(layer "In13.Cu")
		(net "GMI_CPU0_G0_CPU1_G2_TX_DP<6>")
	)
	(segment
		(start 355.305106 -230.391208)
		(end 355.335586 -230.373428)
		(width 0.1143)
		(layer "In13.Cu")
		(net "GMI_CPU0_G0_CPU1_G2_TX_DP<6>")
	)
	(segment
		(start 355.282754 -228.78415)
		(end 355.284278 -228.783134)
		(width 0.1143)
		(layer "In13.Cu")
		(net "GMI_CPU0_G0_CPU1_G2_TX_DP<6>")
	)
	(segment
		(start 116.191792 -235.251752)
		(end 116.192554 -235.25226)
		(width 0.1143)
		(layer "In13.Cu")
		(net "GMI_CPU0_G0_CPU1_G2_TX_DP<6>")
	)
	(segment
		(start 354.83419 -240.92154)
		(end 354.870512 -240.900458)
		(width 0.1143)
		(layer "In13.Cu")
		(net "GMI_CPU0_G0_CPU1_G2_TX_DP<6>")
	)
	(segment
		(start 355.305106 -237.517178)
		(end 355.30409 -237.51667)
		(width 0.1143)
		(layer "In13.Cu")
		(net "GMI_CPU0_G0_CPU1_G2_TX_DP<6>")
	)
	(segment
		(start 355.30663 -233.629962)
		(end 355.343206 -233.608626)
		(width 0.1143)
		(layer "In13.Cu")
		(net "GMI_CPU0_G0_CPU1_G2_TX_DP<6>")
	)
	(segment
		(start 355.30409 -227.151692)
		(end 355.305106 -227.151184)
		(width 0.1143)
		(layer "In13.Cu")
		(net "GMI_CPU0_G0_CPU1_G2_TX_DP<6>")
	)
	(segment
		(start 116.223542 -227.170234)
		(end 116.243354 -227.184458)
		(width 0.1143)
		(layer "In13.Cu")
		(net "GMI_CPU0_G0_CPU1_G2_TX_DP<6>")
	)
	(segment
		(start 116.151914 -224.580196)
		(end 116.141246 -224.58807)
		(width 0.1143)
		(layer "In13.Cu")
		(net "GMI_CPU0_G0_CPU1_G2_TX_DP<6>")
	)
	(segment
		(start 116.19103 -225.531426)
		(end 116.192554 -225.532442)
		(width 0.1143)
		(layer "In13.Cu")
		(net "GMI_CPU0_G0_CPU1_G2_TX_DP<6>")
	)
	(segment
		(start 355.303328 -227.1522)
		(end 355.30409 -227.151692)
		(width 0.1143)
		(layer "In13.Cu")
		(net "GMI_CPU0_G0_CPU1_G2_TX_DP<6>")
	)
	(segment
		(start 355.304852 -225.531172)
		(end 355.321108 -225.521774)
		(width 0.1143)
		(layer "In13.Cu")
		(net "GMI_CPU0_G0_CPU1_G2_TX_DP<6>")
	)
	(segment
		(start 355.270562 -240.131092)
		(end 355.27234 -240.129822)
		(width 0.1143)
		(layer "In13.Cu")
		(net "GMI_CPU0_G0_CPU1_G2_TX_DP<6>")
	)
	(segment
		(start 354.80244 -240.939828)
		(end 354.83419 -240.92154)
		(width 0.1143)
		(layer "In13.Cu")
		(net "GMI_CPU0_G0_CPU1_G2_TX_DP<6>")
	)
	(segment
		(start 355.305106 -235.897166)
		(end 355.30409 -235.896658)
		(width 0.1143)
		(layer "In13.Cu")
		(net "GMI_CPU0_G0_CPU1_G2_TX_DP<6>")
	)
	(segment
		(start 116.191792 -231.036876)
		(end 116.152676 -231.059736)
		(width 0.1143)
		(layer "In13.Cu")
		(net "GMI_CPU0_G0_CPU1_G2_TX_DP<6>")
	)
	(segment
		(start 116.223542 -224.538794)
		(end 116.192554 -224.556574)
		(width 0.1143)
		(layer "In13.Cu")
		(net "GMI_CPU0_G0_CPU1_G2_TX_DP<6>")
	)
	(segment
		(start 116.190776 -230.391462)
		(end 116.19357 -230.392986)
		(width 0.1143)
		(layer "In13.Cu")
		(net "GMI_CPU0_G0_CPU1_G2_TX_DP<6>")
	)
	(segment
		(start 355.343206 -231.059482)
		(end 355.270562 -231.017064)
		(width 0.1143)
		(layer "In13.Cu")
		(net "GMI_CPU0_G0_CPU1_G2_TX_DP<6>")
	)
	(segment
		(start 355.343206 -226.1997)
		(end 355.30663 -226.178364)
		(width 0.1143)
		(layer "In13.Cu")
		(net "GMI_CPU0_G0_CPU1_G2_TX_DP<6>")
	)
	(segment
		(start 355.305106 -226.177348)
		(end 355.30409 -226.17684)
		(width 0.1143)
		(layer "In13.Cu")
		(net "GMI_CPU0_G0_CPU1_G2_TX_DP<6>")
	)
	(segment
		(start 355.303328 -233.631994)
		(end 355.30409 -233.631486)
		(width 0.1143)
		(layer "In13.Cu")
		(net "GMI_CPU0_G0_CPU1_G2_TX_DP<6>")
	)
	(segment
		(start 355.303328 -239.136174)
		(end 355.27234 -239.118394)
		(width 0.1143)
		(layer "In13.Cu")
		(net "GMI_CPU0_G0_CPU1_G2_TX_DP<6>")
	)
	(segment
		(start 355.305106 -223.91116)
		(end 355.30663 -223.910144)
		(width 0.1143)
		(layer "In13.Cu")
		(net "GMI_CPU0_G0_CPU1_G2_TX_DP<6>")
	)
	(segment
		(start 115.81003 -221.100396)
		(end 115.85575 -221.146116)
		(width 0.1143)
		(layer "In13.Cu")
		(net "GMI_CPU0_G0_CPU1_G2_TX_DP<6>")
	)
	(segment
		(start 355.252528 -238.524034)
		(end 355.27234 -238.50981)
		(width 0.1143)
		(layer "In13.Cu")
		(net "GMI_CPU0_G0_CPU1_G2_TX_DP<6>")
	)
	(segment
		(start 355.284278 -228.783134)
		(end 355.30155 -228.772974)
		(width 0.1143)
		(layer "In13.Cu")
		(net "GMI_CPU0_G0_CPU1_G2_TX_DP<6>")
	)
	(segment
		(start 116.192554 -225.532442)
		(end 116.223542 -225.550222)
		(width 0.1143)
		(layer "In13.Cu")
		(net "GMI_CPU0_G0_CPU1_G2_TX_DP<6>")
	)
	(segment
		(start 116.159534 -240.092992)
		(end 116.160296 -240.0935)
		(width 0.1143)
		(layer "In13.Cu")
		(net "GMI_CPU0_G0_CPU1_G2_TX_DP<6>")
	)
	(segment
		(start 355.30663 -234.27817)
		(end 355.305106 -234.277154)
		(width 0.1143)
		(layer "In13.Cu")
		(net "GMI_CPU0_G0_CPU1_G2_TX_DP<6>")
	)
	(segment
		(start 355.30409 -235.896658)
		(end 355.303328 -235.89615)
		(width 0.1143)
		(layer "In13.Cu")
		(net "GMI_CPU0_G0_CPU1_G2_TX_DP<6>")
	)
	(segment
		(start 355.30409 -238.491522)
		(end 355.305106 -238.491014)
		(width 0.1143)
		(layer "In13.Cu")
		(net "GMI_CPU0_G0_CPU1_G2_TX_DP<6>")
	)
	(segment
		(start 116.194332 -228.773228)
		(end 116.213128 -228.784404)
		(width 0.1143)
		(layer "In13.Cu")
		(net "GMI_CPU0_G0_CPU1_G2_TX_DP<6>")
	)
	(segment
		(start 355.303328 -236.872018)
		(end 355.30409 -236.87151)
		(width 0.1143)
		(layer "In13.Cu")
		(net "GMI_CPU0_G0_CPU1_G2_TX_DP<6>")
	)
	(segment
		(start 355.30409 -223.911668)
		(end 355.305106 -223.91116)
		(width 0.1143)
		(layer "In13.Cu")
		(net "GMI_CPU0_G0_CPU1_G2_TX_DP<6>")
	)
	(segment
		(start 355.303328 -227.796344)
		(end 355.27234 -227.778564)
		(width 0.1143)
		(layer "In13.Cu")
		(net "GMI_CPU0_G0_CPU1_G2_TX_DP<6>")
	)
	(segment
		(start 116.189252 -227.79863)
		(end 116.152676 -227.819966)
		(width 0.1143)
		(layer "In13.Cu")
		(net "GMI_CPU0_G0_CPU1_G2_TX_DP<6>")
	)
	(segment
		(start 355.303328 -238.49203)
		(end 355.30409 -238.491522)
		(width 0.1143)
		(layer "In13.Cu")
		(net "GMI_CPU0_G0_CPU1_G2_TX_DP<6>")
	)
	(segment
		(start 355.27234 -225.549968)
		(end 355.303328 -225.532188)
		(width 0.1143)
		(layer "In13.Cu")
		(net "GMI_CPU0_G0_CPU1_G2_TX_DP<6>")
	)
	(segment
		(start 116.243354 -227.764594)
		(end 116.223542 -227.778818)
		(width 0.1143)
		(layer "In13.Cu")
		(net "GMI_CPU0_G0_CPU1_G2_TX_DP<6>")
	)
	(segment
		(start 116.223542 -237.498636)
		(end 116.192554 -237.516416)
		(width 0.1143)
		(layer "In13.Cu")
		(net "GMI_CPU0_G0_CPU1_G2_TX_DP<6>")
	)
	(segment
		(start 355.30409 -222.936816)
		(end 355.303328 -222.936308)
		(width 0.1143)
		(layer "In13.Cu")
		(net "GMI_CPU0_G0_CPU1_G2_TX_DP<6>")
	)
	(segment
		(start 116.160296 -240.0935)
		(end 116.191792 -240.111788)
		(width 0.1143)
		(layer "In13.Cu")
		(net "GMI_CPU0_G0_CPU1_G2_TX_DP<6>")
	)
	(segment
		(start 116.192554 -232.012236)
		(end 116.223542 -232.030016)
		(width 0.1143)
		(layer "In13.Cu")
		(net "GMI_CPU0_G0_CPU1_G2_TX_DP<6>")
	)
	(segment
		(start 355.30663 -232.00995)
		(end 355.343206 -231.988614)
		(width 0.1143)
		(layer "In13.Cu")
		(net "GMI_CPU0_G0_CPU1_G2_TX_DP<6>")
	)
	(segment
		(start 116.160296 -238.473488)
		(end 116.191792 -238.491776)
		(width 0.1143)
		(layer "In13.Cu")
		(net "GMI_CPU0_G0_CPU1_G2_TX_DP<6>")
	)
	(segment
		(start 116.223542 -226.158806)
		(end 116.192554 -226.176586)
		(width 0.1143)
		(layer "In13.Cu")
		(net "GMI_CPU0_G0_CPU1_G2_TX_DP<6>")
	)
	(segment
		(start 116.213636 -229.404672)
		(end 116.213128 -229.404672)
		(width 0.1143)
		(layer "In13.Cu")
		(net "GMI_CPU0_G0_CPU1_G2_TX_DP<6>")
	)
	(segment
		(start 116.190776 -234.277408)
		(end 116.189252 -234.278424)
		(width 0.1143)
		(layer "In13.Cu")
		(net "GMI_CPU0_G0_CPU1_G2_TX_DP<6>")
	)
	(segment
		(start 116.191792 -236.871764)
		(end 116.192554 -236.872272)
		(width 0.1143)
		(layer "In13.Cu")
		(net "GMI_CPU0_G0_CPU1_G2_TX_DP<6>")
	)
	(segment
		(start 355.343206 -232.679494)
		(end 355.30663 -232.658158)
		(width 0.1143)
		(layer "In13.Cu")
		(net "GMI_CPU0_G0_CPU1_G2_TX_DP<6>")
	)
	(segment
		(start 116.189252 -226.178618)
		(end 116.152676 -226.199954)
		(width 0.1143)
		(layer "In13.Cu")
		(net "GMI_CPU0_G0_CPU1_G2_TX_DP<6>")
	)
	(segment
		(start 116.160296 -223.893634)
		(end 116.191792 -223.911922)
		(width 0.1143)
		(layer "In13.Cu")
		(net "GMI_CPU0_G0_CPU1_G2_TX_DP<6>")
	)
	(segment
		(start 157.683962 -180.581554)
		(end 152.414986 -184.901332)
		(width 0.14224)
		(layer "In13.Cu")
		(net "GMI_CPU0_G0_CPU1_G2_TX_DP<6>")
	)
	(segment
		(start 116.191792 -223.911922)
		(end 116.192554 -223.91243)
		(width 0.1143)
		(layer "In13.Cu")
		(net "GMI_CPU0_G0_CPU1_G2_TX_DP<6>")
	)
	(segment
		(start 116.141246 -225.500946)
		(end 116.153438 -225.509582)
		(width 0.1143)
		(layer "In13.Cu")
		(net "GMI_CPU0_G0_CPU1_G2_TX_DP<6>")
	)
	(segment
		(start 116.192554 -232.65638)
		(end 116.191792 -232.656888)
		(width 0.1143)
		(layer "In13.Cu")
		(net "GMI_CPU0_G0_CPU1_G2_TX_DP<6>")
	)
	(segment
		(start 355.2825 -228.78415)
		(end 355.282754 -228.78415)
		(width 0.1143)
		(layer "In13.Cu")
		(net "GMI_CPU0_G0_CPU1_G2_TX_DP<6>")
	)
	(segment
		(start 355.303328 -235.252006)
		(end 355.30409 -235.251498)
		(width 0.1143)
		(layer "In13.Cu")
		(net "GMI_CPU0_G0_CPU1_G2_TX_DP<6>")
	)
	(segment
		(start 355.302312 -230.392732)
		(end 355.305106 -230.391208)
		(width 0.1143)
		(layer "In13.Cu")
		(net "GMI_CPU0_G0_CPU1_G2_TX_DP<6>")
	)
	(segment
		(start 355.27234 -227.16998)
		(end 355.303328 -227.1522)
		(width 0.1143)
		(layer "In13.Cu")
		(net "GMI_CPU0_G0_CPU1_G2_TX_DP<6>")
	)
	(segment
		(start 116.223542 -235.878624)
		(end 116.192554 -235.896404)
		(width 0.1143)
		(layer "In13.Cu")
		(net "GMI_CPU0_G0_CPU1_G2_TX_DP<6>")
	)
	(segment
		(start 355.342444 -225.509328)
		(end 355.354636 -225.500692)
		(width 0.1143)
		(layer "In13.Cu")
		(net "GMI_CPU0_G0_CPU1_G2_TX_DP<6>")
	)
	(segment
		(start 355.30409 -237.51667)
		(end 355.303328 -237.516162)
		(width 0.1143)
		(layer "In13.Cu")
		(net "GMI_CPU0_G0_CPU1_G2_TX_DP<6>")
	)
	(segment
		(start 355.640132 -221.382082)
		(end 355.640132 -221.145862)
		(width 0.1143)
		(layer "In13.Cu")
		(net "GMI_CPU0_G0_CPU1_G2_TX_DP<6>")
	)
	(segment
		(start 115.909598 -221.436184)
		(end 115.909598 -221.804484)
		(width 0.1143)
		(layer "In13.Cu")
		(net "GMI_CPU0_G0_CPU1_G2_TX_DP<6>")
	)
	(segment
		(start 355.305106 -224.557336)
		(end 355.30409 -224.556828)
		(width 0.1143)
		(layer "In13.Cu")
		(net "GMI_CPU0_G0_CPU1_G2_TX_DP<6>")
	)
	(segment
		(start 355.303328 -235.89615)
		(end 355.27234 -235.87837)
		(width 0.1143)
		(layer "In13.Cu")
		(net "GMI_CPU0_G0_CPU1_G2_TX_DP<6>")
	)
	(segment
		(start 355.303328 -222.936308)
		(end 355.27234 -222.918528)
		(width 0.1143)
		(layer "In13.Cu")
		(net "GMI_CPU0_G0_CPU1_G2_TX_DP<6>")
	)
	(segment
		(start 355.685852 -221.100142)
		(end 355.685852 -221.093538)
		(width 0.1143)
		(layer "In13.Cu")
		(net "GMI_CPU0_G0_CPU1_G2_TX_DP<6>")
	)
	(segment
		(start 355.27234 -235.269786)
		(end 355.303328 -235.252006)
		(width 0.1143)
		(layer "In13.Cu")
		(net "GMI_CPU0_G0_CPU1_G2_TX_DP<6>")
	)
	(segment
		(start 116.159534 -231.992932)
		(end 116.160296 -231.99344)
		(width 0.1143)
		(layer "In13.Cu")
		(net "GMI_CPU0_G0_CPU1_G2_TX_DP<6>")
	)
	(segment
		(start 355.586284 -221.80423)
		(end 355.586284 -221.43593)
		(width 0.1143)
		(layer "In13.Cu")
		(net "GMI_CPU0_G0_CPU1_G2_TX_DP<6>")
	)
	(segment
		(start 116.152676 -238.468916)
		(end 116.159534 -238.47298)
		(width 0.1143)
		(layer "In13.Cu")
		(net "GMI_CPU0_G0_CPU1_G2_TX_DP<6>")
	)
	(segment
		(start 165.608254 -177.748438)
		(end 157.683962 -180.581554)
		(width 0.14224)
		(layer "In13.Cu")
		(net "GMI_CPU0_G0_CPU1_G2_TX_DP<6>")
	)
	(segment
		(start 116.192554 -233.632248)
		(end 116.223542 -233.650028)
		(width 0.1143)
		(layer "In13.Cu")
		(net "GMI_CPU0_G0_CPU1_G2_TX_DP<6>")
	)
	(segment
		(start 116.159534 -230.373174)
		(end 116.160296 -230.373682)
		(width 0.1143)
		(layer "In13.Cu")
		(net "GMI_CPU0_G0_CPU1_G2_TX_DP<6>")
	)
	(segment
		(start 355.27234 -233.649774)
		(end 355.303328 -233.631994)
		(width 0.1143)
		(layer "In13.Cu")
		(net "GMI_CPU0_G0_CPU1_G2_TX_DP<6>")
	)
	(segment
		(start 310.141112 -179.36718)
		(end 307.854858 -178.549808)
		(width 0.14224)
		(layer "In13.Cu")
		(net "GMI_CPU0_G0_CPU1_G2_TX_DP<6>")
	)
	(segment
		(start 116.159534 -236.852968)
		(end 116.160296 -236.853476)
		(width 0.1143)
		(layer "In13.Cu")
		(net "GMI_CPU0_G0_CPU1_G2_TX_DP<6>")
	)
	(segment
		(start 116.189252 -237.518448)
		(end 116.152676 -237.539784)
		(width 0.1143)
		(layer "In13.Cu")
		(net "GMI_CPU0_G0_CPU1_G2_TX_DP<6>")
	)
	(segment
		(start 355.30409 -226.17684)
		(end 355.303328 -226.176332)
		(width 0.1143)
		(layer "In13.Cu")
		(net "GMI_CPU0_G0_CPU1_G2_TX_DP<6>")
	)
	(segment
		(start 116.243354 -234.244388)
		(end 116.223542 -234.258612)
		(width 0.1143)
		(layer "In13.Cu")
		(net "GMI_CPU0_G0_CPU1_G2_TX_DP<6>")
	)
	(segment
		(start 116.191792 -240.111788)
		(end 116.192554 -240.112296)
		(width 0.1143)
		(layer "In13.Cu")
		(net "GMI_CPU0_G0_CPU1_G2_TX_DP<6>")
	)
	(segment
		(start 355.343206 -237.53953)
		(end 355.30663 -237.518194)
		(width 0.1143)
		(layer "In13.Cu")
		(net "GMI_CPU0_G0_CPU1_G2_TX_DP<6>")
	)
	(segment
		(start 116.213128 -229.404672)
		(end 116.150644 -229.441248)
		(width 0.1143)
		(layer "In13.Cu")
		(net "GMI_CPU0_G0_CPU1_G2_TX_DP<6>")
	)
	(segment
		(start 116.192554 -239.136428)
		(end 116.191792 -239.136936)
		(width 0.1143)
		(layer "In13.Cu")
		(net "GMI_CPU0_G0_CPU1_G2_TX_DP<6>")
	)
	(segment
		(start 116.191792 -227.151946)
		(end 116.192554 -227.152454)
		(width 0.1143)
		(layer "In13.Cu")
		(net "GMI_CPU0_G0_CPU1_G2_TX_DP<6>")
	)
	(segment
		(start 355.27234 -234.258358)
		(end 355.252528 -234.244134)
		(width 0.1143)
		(layer "In13.Cu")
		(net "GMI_CPU0_G0_CPU1_G2_TX_DP<6>")
	)
	(segment
		(start 355.343206 -222.959676)
		(end 355.305106 -222.937324)
		(width 0.1143)
		(layer "In13.Cu")
		(net "GMI_CPU0_G0_CPU1_G2_TX_DP<6>")
	)
	(segment
		(start 355.30409 -235.251498)
		(end 355.305106 -235.25099)
		(width 0.1143)
		(layer "In13.Cu")
		(net "GMI_CPU0_G0_CPU1_G2_TX_DP<6>")
	)
	(segment
		(start 355.27234 -232.029762)
		(end 355.303328 -232.011982)
		(width 0.1143)
		(layer "In13.Cu")
		(net "GMI_CPU0_G0_CPU1_G2_TX_DP<6>")
	)
	(segment
		(start 355.30409 -236.87151)
		(end 355.305106 -236.871002)
		(width 0.1143)
		(layer "In13.Cu")
		(net "GMI_CPU0_G0_CPU1_G2_TX_DP<6>")
	)
	(segment
		(start 116.160296 -236.853476)
		(end 116.191792 -236.871764)
		(width 0.1143)
		(layer "In13.Cu")
		(net "GMI_CPU0_G0_CPU1_G2_TX_DP<6>")
	)
	(segment
		(start 355.30409 -224.556828)
		(end 355.303328 -224.55632)
		(width 0.1143)
		(layer "In13.Cu")
		(net "GMI_CPU0_G0_CPU1_G2_TX_DP<6>")
	)
	(segment
		(start 355.305106 -227.151184)
		(end 355.30663 -227.150168)
		(width 0.1143)
		(layer "In13.Cu")
		(net "GMI_CPU0_G0_CPU1_G2_TX_DP<6>")
	)
	(segment
		(start 116.191792 -234.2769)
		(end 116.190776 -234.277408)
		(width 0.1143)
		(layer "In13.Cu")
		(net "GMI_CPU0_G0_CPU1_G2_TX_DP<6>")
	)
	(segment
		(start 116.84254 -241.174524)
		(end 116.77269 -241.244374)
		(width 0.1143)
		(layer "In13.Cu")
		(net "GMI_CPU0_G0_CPU1_G2_TX_DP<6>")
	)
	(segment
		(start 116.191792 -224.557082)
		(end 116.190776 -224.55759)
		(width 0.1143)
		(layer "In13.Cu")
		(net "GMI_CPU0_G0_CPU1_G2_TX_DP<6>")
	)
	(segment
		(start 116.191792 -237.516924)
		(end 116.190776 -237.517432)
		(width 0.1143)
		(layer "In13.Cu")
		(net "GMI_CPU0_G0_CPU1_G2_TX_DP<6>")
	)
	(segment
		(start 116.191792 -233.63174)
		(end 116.192554 -233.632248)
		(width 0.1143)
		(layer "In13.Cu")
		(net "GMI_CPU0_G0_CPU1_G2_TX_DP<6>")
	)
	(segment
		(start 355.30409 -232.656634)
		(end 355.303328 -232.656126)
		(width 0.1143)
		(layer "In13.Cu")
		(net "GMI_CPU0_G0_CPU1_G2_TX_DP<6>")
	)
	(segment
		(start 116.159534 -223.893126)
		(end 116.160296 -223.893634)
		(width 0.1143)
		(layer "In13.Cu")
		(net "GMI_CPU0_G0_CPU1_G2_TX_DP<6>")
	)
	(segment
		(start 119.551704 -211.847176)
		(end 115.81003 -218.148916)
		(width 0.14224)
		(layer "In13.Cu")
		(net "GMI_CPU0_G0_CPU1_G2_TX_DP<6>")
	)
	(segment
		(start 115.81003 -221.071948)
		(end 115.81003 -221.100396)
		(width 0.1143)
		(layer "In13.Cu")
		(net "GMI_CPU0_G0_CPU1_G2_TX_DP<6>")
	)
	(segment
		(start 355.586284 -221.43593)
		(end 355.640132 -221.382082)
		(width 0.1143)
		(layer "In13.Cu")
		(net "GMI_CPU0_G0_CPU1_G2_TX_DP<6>")
	)
	(segment
		(start 307.854858 -178.549808)
		(end 302.908208 -178.549808)
		(width 0.14224)
		(layer "In13.Cu")
		(net "GMI_CPU0_G0_CPU1_G2_TX_DP<6>")
	)
	(segment
		(start 116.223542 -222.918782)
		(end 116.192554 -222.936562)
		(width 0.1143)
		(layer "In13.Cu")
		(net "GMI_CPU0_G0_CPU1_G2_TX_DP<6>")
	)
	(segment
		(start 116.174774 -225.522028)
		(end 116.19103 -225.531426)
		(width 0.1143)
		(layer "In13.Cu")
		(net "GMI_CPU0_G0_CPU1_G2_TX_DP<6>")
	)
	(segment
		(start 115.85575 -221.382336)
		(end 115.909598 -221.436184)
		(width 0.1143)
		(layer "In13.Cu")
		(net "GMI_CPU0_G0_CPU1_G2_TX_DP<6>")
	)
	(segment
		(start 116.152676 -236.848904)
		(end 116.159534 -236.852968)
		(width 0.1143)
		(layer "In13.Cu")
		(net "GMI_CPU0_G0_CPU1_G2_TX_DP<6>")
	)
	(segment
		(start 116.189252 -224.558606)
		(end 116.151914 -224.580196)
		(width 0.1143)
		(layer "In13.Cu")
		(net "GMI_CPU0_G0_CPU1_G2_TX_DP<6>")
	)
	(segment
		(start 355.30663 -236.869986)
		(end 355.343206 -236.84865)
		(width 0.1143)
		(layer "In13.Cu")
		(net "GMI_CPU0_G0_CPU1_G2_TX_DP<6>")
	)
	(segment
		(start 116.192554 -235.896404)
		(end 116.191792 -235.896912)
		(width 0.1143)
		(layer "In13.Cu")
		(net "GMI_CPU0_G0_CPU1_G2_TX_DP<6>")
	)
	(segment
		(start 116.190776 -232.657396)
		(end 116.189252 -232.658412)
		(width 0.1143)
		(layer "In13.Cu")
		(net "GMI_CPU0_G0_CPU1_G2_TX_DP<6>")
	)
	(segment
		(start 116.189252 -239.13846)
		(end 116.152676 -239.159796)
		(width 0.1143)
		(layer "In13.Cu")
		(net "GMI_CPU0_G0_CPU1_G2_TX_DP<6>")
	)
	(segment
		(start 355.305106 -240.111026)
		(end 355.30663 -240.11001)
		(width 0.1143)
		(layer "In13.Cu")
		(net "GMI_CPU0_G0_CPU1_G2_TX_DP<6>")
	)
	(segment
		(start 355.303328 -232.656126)
		(end 355.27234 -232.638346)
		(width 0.1143)
		(layer "In13.Cu")
		(net "GMI_CPU0_G0_CPU1_G2_TX_DP<6>")
	)
	(segment
		(start 355.685852 -221.093538)
		(end 355.685852 -218.24442)
		(width 0.14224)
		(layer "In13.Cu")
		(net "GMI_CPU0_G0_CPU1_G2_TX_DP<6>")
	)
	(segment
		(start 355.305106 -232.657142)
		(end 355.30409 -232.656634)
		(width 0.1143)
		(layer "In13.Cu")
		(net "GMI_CPU0_G0_CPU1_G2_TX_DP<6>")
	)
	(segment
		(start 355.30663 -235.249974)
		(end 355.343206 -235.228638)
		(width 0.1143)
		(layer "In13.Cu")
		(net "GMI_CPU0_G0_CPU1_G2_TX_DP<6>")
	)
	(segment
		(start 355.303328 -237.516162)
		(end 355.27234 -237.498382)
		(width 0.1143)
		(layer "In13.Cu")
		(net "GMI_CPU0_G0_CPU1_G2_TX_DP<6>")
	)
	(segment
		(start 116.223542 -227.778818)
		(end 116.192554 -227.796598)
		(width 0.1143)
		(layer "In13.Cu")
		(net "GMI_CPU0_G0_CPU1_G2_TX_DP<6>")
	)
	(segment
		(start 116.190776 -222.937578)
		(end 116.152676 -222.95993)
		(width 0.1143)
		(layer "In13.Cu")
		(net "GMI_CPU0_G0_CPU1_G2_TX_DP<6>")
	)
	(segment
		(start 355.640132 -221.145862)
		(end 355.685852 -221.100142)
		(width 0.1143)
		(layer "In13.Cu")
		(net "GMI_CPU0_G0_CPU1_G2_TX_DP<6>")
	)
	(segment
		(start 355.336348 -230.37292)
		(end 355.340666 -230.37038)
		(width 0.1143)
		(layer "In13.Cu")
		(net "GMI_CPU0_G0_CPU1_G2_TX_DP<6>")
	)
	(segment
		(start 355.305106 -222.937324)
		(end 355.30409 -222.936816)
		(width 0.1143)
		(layer "In13.Cu")
		(net "GMI_CPU0_G0_CPU1_G2_TX_DP<6>")
	)
	(segment
		(start 355.321108 -225.521774)
		(end 355.342444 -225.509328)
		(width 0.1143)
		(layer "In13.Cu")
		(net "GMI_CPU0_G0_CPU1_G2_TX_DP<6>")
	)
	(segment
		(start 116.152676 -240.088928)
		(end 116.159534 -240.092992)
		(width 0.1143)
		(layer "In13.Cu")
		(net "GMI_CPU0_G0_CPU1_G2_TX_DP<6>")
	)
	(segment
		(start 116.191792 -228.771958)
		(end 116.194332 -228.773228)
		(width 0.1143)
		(layer "In13.Cu")
		(net "GMI_CPU0_G0_CPU1_G2_TX_DP<6>")
	)
	(segment
		(start 116.189252 -234.278424)
		(end 116.152676 -234.29976)
		(width 0.1143)
		(layer "In13.Cu")
		(net "GMI_CPU0_G0_CPU1_G2_TX_DP<6>")
	)
	(segment
		(start 355.305106 -238.491014)
		(end 355.30663 -238.489998)
		(width 0.1143)
		(layer "In13.Cu")
		(net "GMI_CPU0_G0_CPU1_G2_TX_DP<6>")
	)
	(segment
		(start 302.908208 -178.549808)
		(end 165.608254 -177.748438)
		(width 0.14224)
		(layer "In13.Cu")
		(net "GMI_CPU0_G0_CPU1_G2_TX_DP<6>")
	)
	(segment
		(start 355.343206 -227.819712)
		(end 355.30663 -227.798376)
		(width 0.1143)
		(layer "In13.Cu")
		(net "GMI_CPU0_G0_CPU1_G2_TX_DP<6>")
	)
	(segment
		(start 116.192554 -236.872272)
		(end 116.223542 -236.890052)
		(width 0.1143)
		(layer "In13.Cu")
		(net "GMI_CPU0_G0_CPU1_G2_TX_DP<6>")
	)
	(segment
		(start 355.305106 -232.010966)
		(end 355.30663 -232.00995)
		(width 0.1143)
		(layer "In13.Cu")
		(net "GMI_CPU0_G0_CPU1_G2_TX_DP<6>")
	)
	(segment
		(start 116.152676 -235.228892)
		(end 116.159534 -235.232956)
		(width 0.1143)
		(layer "In13.Cu")
		(net "GMI_CPU0_G0_CPU1_G2_TX_DP<6>")
	)
	(segment
		(start 116.191792 -232.011728)
		(end 116.192554 -232.012236)
		(width 0.1143)
		(layer "In13.Cu")
		(net "GMI_CPU0_G0_CPU1_G2_TX_DP<6>")
	)
	(segment
		(start 355.354636 -224.587816)
		(end 355.343968 -224.579942)
		(width 0.1143)
		(layer "In13.Cu")
		(net "GMI_CPU0_G0_CPU1_G2_TX_DP<6>")
	)
	(segment
		(start 355.30663 -235.898182)
		(end 355.305106 -235.897166)
		(width 0.1143)
		(layer "In13.Cu")
		(net "GMI_CPU0_G0_CPU1_G2_TX_DP<6>")
	)
	(segment
		(start 116.22532 -231.017318)
		(end 116.191792 -231.036876)
		(width 0.1143)
		(layer "In13.Cu")
		(net "GMI_CPU0_G0_CPU1_G2_TX_DP<6>")
	)
	(segment
		(start 116.192554 -234.276392)
		(end 116.191792 -234.2769)
		(width 0.1143)
		(layer "In13.Cu")
		(net "GMI_CPU0_G0_CPU1_G2_TX_DP<6>")
	)
	(segment
		(start 355.27234 -239.118394)
		(end 355.252528 -239.10417)
		(width 0.1143)
		(layer "In13.Cu")
		(net "GMI_CPU0_G0_CPU1_G2_TX_DP<6>")
	)
	(segment
		(start 355.252528 -227.184204)
		(end 355.27234 -227.16998)
		(width 0.1143)
		(layer "In13.Cu")
		(net "GMI_CPU0_G0_CPU1_G2_TX_DP<6>")
	)
	(segment
		(start 355.303328 -224.55632)
		(end 355.27234 -224.53854)
		(width 0.1143)
		(layer "In13.Cu")
		(net "GMI_CPU0_G0_CPU1_G2_TX_DP<6>")
	)
	(segment
		(start 355.305106 -236.871002)
		(end 355.30663 -236.869986)
		(width 0.1143)
		(layer "In13.Cu")
		(net "GMI_CPU0_G0_CPU1_G2_TX_DP<6>")
	)
	(segment
		(start 116.77269 -241.244374)
		(end 116.474748 -241.244374)
		(width 0.1143)
		(layer "In13.Cu")
		(net "GMI_CPU0_G0_CPU1_G2_TX_DP<6>")
	)
	(segment
		(start 116.190776 -226.177602)
		(end 116.189252 -226.178618)
		(width 0.1143)
		(layer "In13.Cu")
		(net "GMI_CPU0_G0_CPU1_G2_TX_DP<6>")
	)
	(segment
		(start 355.30409 -233.631486)
		(end 355.305106 -233.630978)
		(width 0.1143)
		(layer "In13.Cu")
		(net "GMI_CPU0_G0_CPU1_G2_TX_DP<6>")
	)
	(segment
		(start 355.30155 -228.772974)
		(end 355.305106 -228.771196)
		(width 0.1143)
		(layer "In13.Cu")
		(net "GMI_CPU0_G0_CPU1_G2_TX_DP<6>")
	)
	(segment
		(start 355.685852 -218.24442)
		(end 351.986342 -212.0138)
		(width 0.14224)
		(layer "In13.Cu")
		(net "GMI_CPU0_G0_CPU1_G2_TX_DP<6>")
	)
	(segment
		(start 116.152676 -233.60888)
		(end 116.159534 -233.612944)
		(width 0.1143)
		(layer "In13.Cu")
		(net "GMI_CPU0_G0_CPU1_G2_TX_DP<6>")
	)
	(segment
		(start 355.305106 -234.277154)
		(end 355.30409 -234.276646)
		(width 0.1143)
		(layer "In13.Cu")
		(net "GMI_CPU0_G0_CPU1_G2_TX_DP<6>")
	)
	(segment
		(start 116.159534 -228.753162)
		(end 116.160296 -228.75367)
		(width 0.1143)
		(layer "In13.Cu")
		(net "GMI_CPU0_G0_CPU1_G2_TX_DP<6>")
	)
	(segment
		(start 116.191792 -238.491776)
		(end 116.192554 -238.492284)
		(width 0.1143)
		(layer "In13.Cu")
		(net "GMI_CPU0_G0_CPU1_G2_TX_DP<6>")
	)
	(segment
		(start 116.192554 -237.516416)
		(end 116.191792 -237.516924)
		(width 0.1143)
		(layer "In13.Cu")
		(net "GMI_CPU0_G0_CPU1_G2_TX_DP<6>")
	)
	(segment
		(start 355.30663 -232.658158)
		(end 355.305106 -232.657142)
		(width 0.1143)
		(layer "In13.Cu")
		(net "GMI_CPU0_G0_CPU1_G2_TX_DP<6>")
	)
	(segment
		(start 116.160296 -230.373682)
		(end 116.190776 -230.391462)
		(width 0.1143)
		(layer "In13.Cu")
		(net "GMI_CPU0_G0_CPU1_G2_TX_DP<6>")
	)
	(segment
		(start 355.30663 -226.178364)
		(end 355.305106 -226.177348)
		(width 0.1143)
		(layer "In13.Cu")
		(net "GMI_CPU0_G0_CPU1_G2_TX_DP<6>")
	)
	(segment
		(start 116.190776 -237.517432)
		(end 116.189252 -237.518448)
		(width 0.1143)
		(layer "In13.Cu")
		(net "GMI_CPU0_G0_CPU1_G2_TX_DP<6>")
	)
	(segment
		(start 355.345238 -229.440994)
		(end 355.282754 -229.404418)
		(width 0.1143)
		(layer "In13.Cu")
		(net "GMI_CPU0_G0_CPU1_G2_TX_DP<6>")
	)
	(segment
		(start 116.191792 -226.177094)
		(end 116.190776 -226.177602)
		(width 0.1143)
		(layer "In13.Cu")
		(net "GMI_CPU0_G0_CPU1_G2_TX_DP<6>")
	)
	(segment
		(start 355.303328 -240.112042)
		(end 355.30409 -240.111534)
		(width 0.1143)
		(layer "In13.Cu")
		(net "GMI_CPU0_G0_CPU1_G2_TX_DP<6>")
	)
	(segment
		(start 355.30663 -239.138206)
		(end 355.305106 -239.13719)
		(width 0.1143)
		(layer "In13.Cu")
		(net "GMI_CPU0_G0_CPU1_G2_TX_DP<6>")
	)
	(segment
		(start 355.305106 -239.13719)
		(end 355.30409 -239.136682)
		(width 0.1143)
		(layer "In13.Cu")
		(net "GMI_CPU0_G0_CPU1_G2_TX_DP<6>")
	)
	(segment
		(start 355.252528 -233.663998)
		(end 355.27234 -233.649774)
		(width 0.1143)
		(layer "In13.Cu")
		(net "GMI_CPU0_G0_CPU1_G2_TX_DP<6>")
	)
	(segment
		(start 351.986342 -212.0138)
		(end 316.69863 -183.07939)
		(width 0.14224)
		(layer "In13.Cu")
		(net "GMI_CPU0_G0_CPU1_G2_TX_DP<6>")
	)
	(segment
		(start 116.223542 -234.258612)
		(end 116.192554 -234.276392)
		(width 0.1143)
		(layer "In13.Cu")
		(net "GMI_CPU0_G0_CPU1_G2_TX_DP<6>")
	)
	(segment
		(start 116.192554 -222.936562)
		(end 116.191792 -222.93707)
		(width 0.1143)
		(layer "In13.Cu")
		(net "GMI_CPU0_G0_CPU1_G2_TX_DP<6>")
	)
	(segment
		(start 116.190776 -235.89742)
		(end 116.189252 -235.898436)
		(width 0.1143)
		(layer "In13.Cu")
		(net "GMI_CPU0_G0_CPU1_G2_TX_DP<6>")
	)
	(segment
		(start 355.303328 -225.532188)
		(end 355.304852 -225.531172)
		(width 0.1143)
		(layer "In13.Cu")
		(net "GMI_CPU0_G0_CPU1_G2_TX_DP<6>")
	)
	(segment
		(start 116.223542 -240.130076)
		(end 116.22532 -240.131346)
		(width 0.1143)
		(layer "In13.Cu")
		(net "GMI_CPU0_G0_CPU1_G2_TX_DP<6>")
	)
	(segment
		(start 116.159534 -238.47298)
		(end 116.160296 -238.473488)
		(width 0.1143)
		(layer "In13.Cu")
		(net "GMI_CPU0_G0_CPU1_G2_TX_DP<6>")
	)
	(segment
		(start 116.379498 -240.432336)
		(end 116.379498 -240.434368)
		(width 0.1143)
		(layer "In13.Cu")
		(net "GMI_CPU0_G0_CPU1_G2_TX_DP<6>")
	)
	(segment
		(start 355.343968 -224.579942)
		(end 355.30663 -224.558352)
		(width 0.1143)
		(layer "In13.Cu")
		(net "GMI_CPU0_G0_CPU1_G2_TX_DP<6>")
	)
	(segment
		(start 355.30663 -228.77018)
		(end 355.343206 -228.748844)
		(width 0.1143)
		(layer "In13.Cu")
		(net "GMI_CPU0_G0_CPU1_G2_TX_DP<6>")
	)
	(segment
		(start 355.30663 -223.910144)
		(end 355.343206 -223.888808)
		(width 0.1143)
		(layer "In13.Cu")
		(net "GMI_CPU0_G0_CPU1_G2_TX_DP<6>")
	)
	(segment
		(start 116.223542 -238.510064)
		(end 116.243354 -238.524288)
		(width 0.1143)
		(layer "In13.Cu")
		(net "GMI_CPU0_G0_CPU1_G2_TX_DP<6>")
	)
	(segment
		(start 116.191792 -222.93707)
		(end 116.190776 -222.937578)
		(width 0.1143)
		(layer "In13.Cu")
		(net "GMI_CPU0_G0_CPU1_G2_TX_DP<6>")
	)
	(segment
		(start 355.303328 -223.912176)
		(end 355.30409 -223.911668)
		(width 0.1143)
		(layer "In13.Cu")
		(net "GMI_CPU0_G0_CPU1_G2_TX_DP<6>")
	)
	(segment
		(start 152.414986 -184.901332)
		(end 152.41524 -184.90184)
		(width 0.14224)
		(layer "In13.Cu")
		(net "GMI_CPU0_G0_CPU1_G2_TX_DP<6>")
	)
	(segment
		(start 152.41524 -184.90184)
		(end 119.551704 -211.847176)
		(width 0.14224)
		(layer "In13.Cu")
		(net "GMI_CPU0_G0_CPU1_G2_TX_DP<6>")
	)
	(segment
		(start 116.155216 -230.370634)
		(end 116.159534 -230.373174)
		(width 0.1143)
		(layer "In13.Cu")
		(net "GMI_CPU0_G0_CPU1_G2_TX_DP<6>")
	)
	(segment
		(start 355.30409 -234.276646)
		(end 355.303328 -234.276138)
		(width 0.1143)
		(layer "In13.Cu")
		(net "GMI_CPU0_G0_CPU1_G2_TX_DP<6>")
	)
	(segment
		(start 115.85575 -221.146116)
		(end 115.85575 -221.382336)
		(width 0.1143)
		(layer "In13.Cu")
		(net "GMI_CPU0_G0_CPU1_G2_TX_DP<6>")
	)
	(segment
		(start 116.192554 -226.176586)
		(end 116.191792 -226.177094)
		(width 0.1143)
		(layer "In13.Cu")
		(net "GMI_CPU0_G0_CPU1_G2_TX_DP<6>")
	)
	(segment
		(start 116.160296 -233.613452)
		(end 116.191792 -233.63174)
		(width 0.1143)
		(layer "In13.Cu")
		(net "GMI_CPU0_G0_CPU1_G2_TX_DP<6>")
	)
	(segment
		(start 116.160296 -235.233464)
		(end 116.191792 -235.251752)
		(width 0.1143)
		(layer "In13.Cu")
		(net "GMI_CPU0_G0_CPU1_G2_TX_DP<6>")
	)
	(segment
		(start 116.192554 -235.25226)
		(end 116.223542 -235.27004)
		(width 0.1143)
		(layer "In13.Cu")
		(net "GMI_CPU0_G0_CPU1_G2_TX_DP<6>")
	)
	(segment
		(start 355.30663 -224.558352)
		(end 355.305106 -224.557336)
		(width 0.1143)
		(layer "In13.Cu")
		(net "GMI_CPU0_G0_CPU1_G2_TX_DP<6>")
	)
	(segment
		(start 116.661692 -240.921794)
		(end 116.693442 -240.940082)
		(width 0.1143)
		(layer "In13.Cu")
		(net "GMI_CPU0_G0_CPU1_G2_TX_DP<6>")
	)
	(segment
		(start 355.27234 -240.129822)
		(end 355.303328 -240.112042)
		(width 0.1143)
		(layer "In13.Cu")
		(net "GMI_CPU0_G0_CPU1_G2_TX_DP<6>")
	)
	(segment
		(start 355.30663 -227.150168)
		(end 355.343206 -227.128832)
		(width 0.1143)
		(layer "In13.Cu")
		(net "GMI_CPU0_G0_CPU1_G2_TX_DP<6>")
	)
	(segment
		(start 355.345492 -229.440994)
		(end 355.345238 -229.440994)
		(width 0.1143)
		(layer "In13.Cu")
		(net "GMI_CPU0_G0_CPU1_G2_TX_DP<6>")
	)
	(arc
		(start 355.343206 -233.608626)
		(mid 355.586533 -233.14406)
		(end 355.343206 -232.679494)
		(width 0.1143)
		(layer "In13.Cu")
		(net "GMI_CPU0_G0_CPU1_G2_TX_DP<6>")
	)
	(arc
		(start 116.213382 -228.784404)
		(mid 116.391924 -229.094428)
		(end 116.213636 -229.404672)
		(width 0.1143)
		(layer "In13.Cu")
		(net "GMI_CPU0_G0_CPU1_G2_TX_DP<6>")
	)
	(arc
		(start 355.340666 -230.37038)
		(mid 355.586549 -229.90696)
		(end 355.345492 -229.440994)
		(width 0.1143)
		(layer "In13.Cu")
		(net "GMI_CPU0_G0_CPU1_G2_TX_DP<6>")
	)
	(arc
		(start 355.343206 -238.468662)
		(mid 355.586533 -238.004096)
		(end 355.343206 -237.53953)
		(width 0.1143)
		(layer "In13.Cu")
		(net "GMI_CPU0_G0_CPU1_G2_TX_DP<6>")
	)
	(arc
		(start 116.152676 -222.95993)
		(mid 115.909349 -223.424496)
		(end 116.152676 -223.889062)
		(width 0.1143)
		(layer "In13.Cu")
		(net "GMI_CPU0_G0_CPU1_G2_TX_DP<6>")
	)
	(arc
		(start 355.252528 -227.76434)
		(mid 355.103814 -227.474272)
		(end 355.252528 -227.184204)
		(width 0.1143)
		(layer "In13.Cu")
		(net "GMI_CPU0_G0_CPU1_G2_TX_DP<6>")
	)
	(arc
		(start 116.152676 -226.199954)
		(mid 115.909349 -226.66452)
		(end 116.152676 -227.129086)
		(width 0.1143)
		(layer "In13.Cu")
		(net "GMI_CPU0_G0_CPU1_G2_TX_DP<6>")
	)
	(arc
		(start 355.343206 -222.268796)
		(mid 355.521864 -222.066396)
		(end 355.586284 -221.80423)
		(width 0.1143)
		(layer "In13.Cu")
		(net "GMI_CPU0_G0_CPU1_G2_TX_DP<6>")
	)
	(arc
		(start 116.152676 -237.539784)
		(mid 115.909349 -238.00435)
		(end 116.152676 -238.468916)
		(width 0.1143)
		(layer "In13.Cu")
		(net "GMI_CPU0_G0_CPU1_G2_TX_DP<6>")
	)
	(arc
		(start 355.252528 -239.10417)
		(mid 355.103814 -238.814102)
		(end 355.252528 -238.524034)
		(width 0.1143)
		(layer "In13.Cu")
		(net "GMI_CPU0_G0_CPU1_G2_TX_DP<6>")
	)
	(arc
		(start 116.223542 -235.27004)
		(mid 116.375232 -235.574332)
		(end 116.223542 -235.878624)
		(width 0.1143)
		(layer "In13.Cu")
		(net "GMI_CPU0_G0_CPU1_G2_TX_DP<6>")
	)
	(arc
		(start 355.27234 -226.158552)
		(mid 355.121955 -225.85426)
		(end 355.27234 -225.549968)
		(width 0.1143)
		(layer "In13.Cu")
		(net "GMI_CPU0_G0_CPU1_G2_TX_DP<6>")
	)
	(arc
		(start 116.223542 -225.550222)
		(mid 116.373927 -225.854514)
		(end 116.223542 -226.158806)
		(width 0.1143)
		(layer "In13.Cu")
		(net "GMI_CPU0_G0_CPU1_G2_TX_DP<6>")
	)
	(arc
		(start 355.343206 -240.088674)
		(mid 355.586533 -239.624108)
		(end 355.343206 -239.159542)
		(width 0.1143)
		(layer "In13.Cu")
		(net "GMI_CPU0_G0_CPU1_G2_TX_DP<6>")
	)
	(arc
		(start 116.243354 -227.184458)
		(mid 116.392068 -227.474526)
		(end 116.243354 -227.764594)
		(width 0.1143)
		(layer "In13.Cu")
		(net "GMI_CPU0_G0_CPU1_G2_TX_DP<6>")
	)
	(arc
		(start 116.152676 -235.919772)
		(mid 115.909349 -236.384338)
		(end 116.152676 -236.848904)
		(width 0.1143)
		(layer "In13.Cu")
		(net "GMI_CPU0_G0_CPU1_G2_TX_DP<6>")
	)
	(arc
		(start 355.343206 -223.888808)
		(mid 355.586533 -223.424242)
		(end 355.343206 -222.959676)
		(width 0.1143)
		(layer "In13.Cu")
		(net "GMI_CPU0_G0_CPU1_G2_TX_DP<6>")
	)
	(arc
		(start 116.152676 -239.159796)
		(mid 115.909349 -239.624362)
		(end 116.152676 -240.088928)
		(width 0.1143)
		(layer "In13.Cu")
		(net "GMI_CPU0_G0_CPU1_G2_TX_DP<6>")
	)
	(arc
		(start 116.152676 -234.29976)
		(mid 115.909349 -234.764326)
		(end 116.152676 -235.228892)
		(width 0.1143)
		(layer "In13.Cu")
		(net "GMI_CPU0_G0_CPU1_G2_TX_DP<6>")
	)
	(arc
		(start 116.141246 -224.58807)
		(mid 115.906825 -225.044508)
		(end 116.141246 -225.500946)
		(width 0.1143)
		(layer "In13.Cu")
		(net "GMI_CPU0_G0_CPU1_G2_TX_DP<6>")
	)
	(arc
		(start 116.223542 -222.310198)
		(mid 116.375131 -222.61449)
		(end 116.223542 -222.918782)
		(width 0.1143)
		(layer "In13.Cu")
		(net "GMI_CPU0_G0_CPU1_G2_TX_DP<6>")
	)
	(arc
		(start 355.343206 -235.228638)
		(mid 355.586533 -234.764072)
		(end 355.343206 -234.299506)
		(width 0.1143)
		(layer "In13.Cu")
		(net "GMI_CPU0_G0_CPU1_G2_TX_DP<6>")
	)
	(arc
		(start 355.27234 -232.638346)
		(mid 355.12065 -232.334054)
		(end 355.27234 -232.029762)
		(width 0.1143)
		(layer "In13.Cu")
		(net "GMI_CPU0_G0_CPU1_G2_TX_DP<6>")
	)
	(arc
		(start 355.354636 -225.500692)
		(mid 355.589057 -225.044254)
		(end 355.354636 -224.587816)
		(width 0.1143)
		(layer "In13.Cu")
		(net "GMI_CPU0_G0_CPU1_G2_TX_DP<6>")
	)
	(arc
		(start 116.223542 -232.030016)
		(mid 116.375232 -232.334308)
		(end 116.223542 -232.6386)
		(width 0.1143)
		(layer "In13.Cu")
		(net "GMI_CPU0_G0_CPU1_G2_TX_DP<6>")
	)
	(arc
		(start 116.379498 -230.71455)
		(mid 116.338736 -230.884434)
		(end 116.22532 -231.017318)
		(width 0.1143)
		(layer "In13.Cu")
		(net "GMI_CPU0_G0_CPU1_G2_TX_DP<6>")
	)
	(arc
		(start 116.223542 -223.93021)
		(mid 116.375131 -224.234502)
		(end 116.223542 -224.538794)
		(width 0.1143)
		(layer "In13.Cu")
		(net "GMI_CPU0_G0_CPU1_G2_TX_DP<6>")
	)
	(arc
		(start 116.223542 -236.890052)
		(mid 116.375232 -237.194344)
		(end 116.223542 -237.498636)
		(width 0.1143)
		(layer "In13.Cu")
		(net "GMI_CPU0_G0_CPU1_G2_TX_DP<6>")
	)
	(arc
		(start 116.152676 -227.819966)
		(mid 115.909349 -228.284532)
		(end 116.152676 -228.749098)
		(width 0.1143)
		(layer "In13.Cu")
		(net "GMI_CPU0_G0_CPU1_G2_TX_DP<6>")
	)
	(arc
		(start 116.61013 -240.890044)
		(mid 116.617706 -240.89544)
		(end 116.62537 -240.900712)
		(width 0.1143)
		(layer "In13.Cu")
		(net "GMI_CPU0_G0_CPU1_G2_TX_DP<6>")
	)
	(arc
		(start 355.27234 -237.498382)
		(mid 355.12065 -237.19409)
		(end 355.27234 -236.889798)
		(width 0.1143)
		(layer "In13.Cu")
		(net "GMI_CPU0_G0_CPU1_G2_TX_DP<6>")
	)
	(arc
		(start 355.116384 -240.439448)
		(mid 355.11639 -240.436781)
		(end 355.116384 -240.434114)
		(width 0.1143)
		(layer "In13.Cu")
		(net "GMI_CPU0_G0_CPU1_G2_TX_DP<6>")
	)
	(arc
		(start 355.343206 -227.128832)
		(mid 355.586533 -226.664266)
		(end 355.343206 -226.1997)
		(width 0.1143)
		(layer "In13.Cu")
		(net "GMI_CPU0_G0_CPU1_G2_TX_DP<6>")
	)
	(arc
		(start 116.693442 -240.940082)
		(mid 116.790577 -241.042951)
		(end 116.84254 -241.174524)
		(width 0.1143)
		(layer "In13.Cu")
		(net "GMI_CPU0_G0_CPU1_G2_TX_DP<6>")
	)
	(arc
		(start 116.152676 -232.679748)
		(mid 115.909349 -233.144314)
		(end 116.152676 -233.60888)
		(width 0.1143)
		(layer "In13.Cu")
		(net "GMI_CPU0_G0_CPU1_G2_TX_DP<6>")
	)
	(arc
		(start 116.15039 -229.441248)
		(mid 115.909301 -229.907214)
		(end 116.155216 -230.370634)
		(width 0.1143)
		(layer "In13.Cu")
		(net "GMI_CPU0_G0_CPU1_G2_TX_DP<6>")
	)
	(arc
		(start 116.379498 -240.434368)
		(mid 116.379491 -240.437035)
		(end 116.379498 -240.439702)
		(width 0.1143)
		(layer "In13.Cu")
		(net "GMI_CPU0_G0_CPU1_G2_TX_DP<6>")
	)
	(arc
		(start 355.282246 -229.404418)
		(mid 355.10383 -229.094174)
		(end 355.2825 -228.78415)
		(width 0.1143)
		(layer "In13.Cu")
		(net "GMI_CPU0_G0_CPU1_G2_TX_DP<6>")
	)
	(arc
		(start 355.343206 -228.748844)
		(mid 355.586533 -228.284278)
		(end 355.343206 -227.819712)
		(width 0.1143)
		(layer "In13.Cu")
		(net "GMI_CPU0_G0_CPU1_G2_TX_DP<6>")
	)
	(arc
		(start 116.243354 -238.524288)
		(mid 116.392068 -238.814356)
		(end 116.243354 -239.104424)
		(width 0.1143)
		(layer "In13.Cu")
		(net "GMI_CPU0_G0_CPU1_G2_TX_DP<6>")
	)
	(arc
		(start 355.252528 -234.244134)
		(mid 355.103814 -233.954066)
		(end 355.252528 -233.663998)
		(width 0.1143)
		(layer "In13.Cu")
		(net "GMI_CPU0_G0_CPU1_G2_TX_DP<6>")
	)
	(arc
		(start 355.343206 -231.988614)
		(mid 355.586533 -231.524048)
		(end 355.343206 -231.059482)
		(width 0.1143)
		(layer "In13.Cu")
		(net "GMI_CPU0_G0_CPU1_G2_TX_DP<6>")
	)
	(arc
		(start 354.870512 -240.900458)
		(mid 354.878176 -240.895187)
		(end 354.885752 -240.88979)
		(width 0.1143)
		(layer "In13.Cu")
		(net "GMI_CPU0_G0_CPU1_G2_TX_DP<6>")
	)
	(arc
		(start 355.270562 -231.017064)
		(mid 355.157155 -230.884175)
		(end 355.116384 -230.714296)
		(width 0.1143)
		(layer "In13.Cu")
		(net "GMI_CPU0_G0_CPU1_G2_TX_DP<6>")
	)
	(arc
		(start 355.27234 -224.53854)
		(mid 355.120751 -224.234248)
		(end 355.27234 -223.929956)
		(width 0.1143)
		(layer "In13.Cu")
		(net "GMI_CPU0_G0_CPU1_G2_TX_DP<6>")
	)
	(arc
		(start 355.27234 -235.87837)
		(mid 355.12065 -235.574078)
		(end 355.27234 -235.269786)
		(width 0.1143)
		(layer "In13.Cu")
		(net "GMI_CPU0_G0_CPU1_G2_TX_DP<6>")
	)
	(arc
		(start 116.152676 -231.059736)
		(mid 115.909349 -231.524302)
		(end 116.152676 -231.988868)
		(width 0.1143)
		(layer "In13.Cu")
		(net "GMI_CPU0_G0_CPU1_G2_TX_DP<6>")
	)
	(arc
		(start 355.27234 -222.918528)
		(mid 355.120751 -222.614236)
		(end 355.27234 -222.309944)
		(width 0.1143)
		(layer "In13.Cu")
		(net "GMI_CPU0_G0_CPU1_G2_TX_DP<6>")
	)
	(arc
		(start 355.116384 -240.432082)
		(mid 355.157175 -240.262997)
		(end 355.270562 -240.131092)
		(width 0.1143)
		(layer "In13.Cu")
		(net "GMI_CPU0_G0_CPU1_G2_TX_DP<6>")
	)
	(arc
		(start 116.22532 -240.131346)
		(mid 116.338725 -240.263241)
		(end 116.379498 -240.432336)
		(width 0.1143)
		(layer "In13.Cu")
		(net "GMI_CPU0_G0_CPU1_G2_TX_DP<6>")
	)
	(arc
		(start 355.343206 -236.84865)
		(mid 355.586533 -236.384084)
		(end 355.343206 -235.919518)
		(width 0.1143)
		(layer "In13.Cu")
		(net "GMI_CPU0_G0_CPU1_G2_TX_DP<6>")
	)
	(arc
		(start 354.885752 -240.88979)
		(mid 355.051997 -240.69069)
		(end 355.116384 -240.439448)
		(width 0.1143)
		(layer "In13.Cu")
		(net "GMI_CPU0_G0_CPU1_G2_TX_DP<6>")
	)
	(arc
		(start 116.243354 -233.664252)
		(mid 116.392068 -233.95432)
		(end 116.243354 -234.244388)
		(width 0.1143)
		(layer "In13.Cu")
		(net "GMI_CPU0_G0_CPU1_G2_TX_DP<6>")
	)
	(arc
		(start 355.116384 -230.714296)
		(mid 355.166207 -230.528566)
		(end 355.302312 -230.392732)
		(width 0.1143)
		(layer "In13.Cu")
		(net "GMI_CPU0_G0_CPU1_G2_TX_DP<6>")
	)
	(arc
		(start 115.909598 -221.804484)
		(mid 115.974045 -222.066636)
		(end 116.152676 -222.26905)
		(width 0.1143)
		(layer "In13.Cu")
		(net "GMI_CPU0_G0_CPU1_G2_TX_DP<6>")
	)
	(arc
		(start 354.653342 -241.17427)
		(mid 354.705391 -241.042751)
		(end 354.80244 -240.939828)
		(width 0.1143)
		(layer "In13.Cu")
		(net "GMI_CPU0_G0_CPU1_G2_TX_DP<6>")
	)
	(arc
		(start 116.379498 -240.439702)
		(mid 116.44396 -240.690906)
		(end 116.61013 -240.890044)
		(width 0.1143)
		(layer "In13.Cu")
		(net "GMI_CPU0_G0_CPU1_G2_TX_DP<6>")
	)
	(arc
		(start 116.19357 -230.392986)
		(mid 116.329651 -230.528834)
		(end 116.379498 -230.71455)
		(width 0.1143)
		(layer "In13.Cu")
		(net "GMI_CPU0_G0_CPU1_G2_TX_DP<6>")
	)
	(segment
		(start 355.487986 -239.890046)
		(end 355.021134 -239.624108)
		(width 0.12954)
		(layer "F.Cu")
		(net "GMI_CPU0_G0_CPU1_G2_TX_DP<5>")
	)
	(segment
		(start 116.007896 -239.8903)
		(end 116.474748 -239.624362)
		(width 0.12954)
		(layer "F.Cu")
		(net "GMI_CPU0_G0_CPU1_G2_TX_DP<5>")
	)
	(segment
		(start 353.393502 -232.029254)
		(end 353.463098 -231.988614)
		(width 0.1143)
		(layer "In13.Cu")
		(net "GMI_CPU0_G0_CPU1_G2_TX_DP<5>")
	)
	(segment
		(start 353.463098 -227.819712)
		(end 353.393502 -227.779072)
		(width 0.1143)
		(layer "In13.Cu")
		(net "GMI_CPU0_G0_CPU1_G2_TX_DP<5>")
	)
	(segment
		(start 118.032784 -235.228892)
		(end 118.0719 -235.251752)
		(width 0.1143)
		(layer "In13.Cu")
		(net "GMI_CPU0_G0_CPU1_G2_TX_DP<5>")
	)
	(segment
		(start 354.723192 -239.624108)
		(end 354.640388 -239.541304)
		(width 0.1143)
		(layer "In13.Cu")
		(net "GMI_CPU0_G0_CPU1_G2_TX_DP<5>")
	)
	(segment
		(start 353.463098 -226.1997)
		(end 353.393502 -226.15906)
		(width 0.1143)
		(layer "In13.Cu")
		(net "GMI_CPU0_G0_CPU1_G2_TX_DP<5>")
	)
	(segment
		(start 353.750372 -221.382082)
		(end 353.750372 -221.145862)
		(width 0.1143)
		(layer "In13.Cu")
		(net "GMI_CPU0_G0_CPU1_G2_TX_DP<5>")
	)
	(segment
		(start 144.272762 -194.366388)
		(end 143.8656 -194.489578)
		(width 0.14224)
		(layer "In13.Cu")
		(net "GMI_CPU0_G0_CPU1_G2_TX_DP<5>")
	)
	(segment
		(start 353.463098 -237.53953)
		(end 353.393502 -237.49889)
		(width 0.1143)
		(layer "In13.Cu")
		(net "GMI_CPU0_G0_CPU1_G2_TX_DP<5>")
	)
	(segment
		(start 118.0719 -225.531934)
		(end 118.10238 -225.549714)
		(width 0.1143)
		(layer "In13.Cu")
		(net "GMI_CPU0_G0_CPU1_G2_TX_DP<5>")
	)
	(segment
		(start 117.69979 -221.071948)
		(end 117.69979 -221.100396)
		(width 0.1143)
		(layer "In13.Cu")
		(net "GMI_CPU0_G0_CPU1_G2_TX_DP<5>")
	)
	(segment
		(start 118.032784 -223.889062)
		(end 118.0719 -223.911922)
		(width 0.1143)
		(layer "In13.Cu")
		(net "GMI_CPU0_G0_CPU1_G2_TX_DP<5>")
	)
	(segment
		(start 355.021134 -239.624108)
		(end 354.723192 -239.624108)
		(width 0.1143)
		(layer "In13.Cu")
		(net "GMI_CPU0_G0_CPU1_G2_TX_DP<5>")
	)
	(segment
		(start 117.74551 -221.382336)
		(end 117.789706 -221.426532)
		(width 0.1143)
		(layer "In13.Cu")
		(net "GMI_CPU0_G0_CPU1_G2_TX_DP<5>")
	)
	(segment
		(start 353.393502 -227.169472)
		(end 353.463098 -227.128832)
		(width 0.1143)
		(layer "In13.Cu")
		(net "GMI_CPU0_G0_CPU1_G2_TX_DP<5>")
	)
	(segment
		(start 353.796092 -221.093538)
		(end 353.796092 -218.71559)
		(width 0.14224)
		(layer "In13.Cu")
		(net "GMI_CPU0_G0_CPU1_G2_TX_DP<5>")
	)
	(segment
		(start 353.423982 -229.41661)
		(end 353.39147 -229.397814)
		(width 0.1143)
		(layer "In13.Cu")
		(net "GMI_CPU0_G0_CPU1_G2_TX_DP<5>")
	)
	(segment
		(start 350.549972 -213.247986)
		(end 315.691266 -184.665366)
		(width 0.14224)
		(layer "In13.Cu")
		(net "GMI_CPU0_G0_CPU1_G2_TX_DP<5>")
	)
	(segment
		(start 118.10238 -234.25912)
		(end 118.0719 -234.2769)
		(width 0.1143)
		(layer "In13.Cu")
		(net "GMI_CPU0_G0_CPU1_G2_TX_DP<5>")
	)
	(segment
		(start 118.0719 -237.516924)
		(end 118.032784 -237.539784)
		(width 0.1143)
		(layer "In13.Cu")
		(net "GMI_CPU0_G0_CPU1_G2_TX_DP<5>")
	)
	(segment
		(start 353.393502 -235.269278)
		(end 353.463098 -235.228638)
		(width 0.1143)
		(layer "In13.Cu")
		(net "GMI_CPU0_G0_CPU1_G2_TX_DP<5>")
	)
	(segment
		(start 353.933252 -238.349536)
		(end 353.894136 -238.326676)
		(width 0.1143)
		(layer "In13.Cu")
		(net "GMI_CPU0_G0_CPU1_G2_TX_DP<5>")
	)
	(segment
		(start 118.104412 -231.01808)
		(end 118.0719 -231.036876)
		(width 0.1143)
		(layer "In13.Cu")
		(net "GMI_CPU0_G0_CPU1_G2_TX_DP<5>")
	)
	(segment
		(start 353.463098 -224.579688)
		(end 353.393502 -224.539048)
		(width 0.1143)
		(layer "In13.Cu")
		(net "GMI_CPU0_G0_CPU1_G2_TX_DP<5>")
	)
	(segment
		(start 315.691266 -184.665366)
		(end 309.529226 -181.177184)
		(width 0.14224)
		(layer "In13.Cu")
		(net "GMI_CPU0_G0_CPU1_G2_TX_DP<5>")
	)
	(segment
		(start 154.81554 -185.721244)
		(end 154.815286 -185.72099)
		(width 0.14224)
		(layer "In13.Cu")
		(net "GMI_CPU0_G0_CPU1_G2_TX_DP<5>")
	)
	(segment
		(start 353.796092 -221.100142)
		(end 353.796092 -221.093538)
		(width 0.1143)
		(layer "In13.Cu")
		(net "GMI_CPU0_G0_CPU1_G2_TX_DP<5>")
	)
	(segment
		(start 117.60073 -238.327438)
		(end 117.599206 -238.328454)
		(width 0.1143)
		(layer "In13.Cu")
		(net "GMI_CPU0_G0_CPU1_G2_TX_DP<5>")
	)
	(segment
		(start 353.393502 -225.54946)
		(end 353.463098 -225.50882)
		(width 0.1143)
		(layer "In13.Cu")
		(net "GMI_CPU0_G0_CPU1_G2_TX_DP<5>")
	)
	(segment
		(start 118.032784 -228.749098)
		(end 118.0719 -228.771958)
		(width 0.1143)
		(layer "In13.Cu")
		(net "GMI_CPU0_G0_CPU1_G2_TX_DP<5>")
	)
	(segment
		(start 353.463098 -235.919518)
		(end 353.393502 -235.878878)
		(width 0.1143)
		(layer "In13.Cu")
		(net "GMI_CPU0_G0_CPU1_G2_TX_DP<5>")
	)
	(segment
		(start 116.77269 -239.624362)
		(end 116.474748 -239.624362)
		(width 0.1143)
		(layer "In13.Cu")
		(net "GMI_CPU0_G0_CPU1_G2_TX_DP<5>")
	)
	(segment
		(start 118.035324 -230.370634)
		(end 118.10238 -230.40975)
		(width 0.1143)
		(layer "In13.Cu")
		(net "GMI_CPU0_G0_CPU1_G2_TX_DP<5>")
	)
	(segment
		(start 118.0719 -229.416864)
		(end 118.032784 -229.439724)
		(width 0.1143)
		(layer "In13.Cu")
		(net "GMI_CPU0_G0_CPU1_G2_TX_DP<5>")
	)
	(segment
		(start 353.393502 -233.649266)
		(end 353.463098 -233.608626)
		(width 0.1143)
		(layer "In13.Cu")
		(net "GMI_CPU0_G0_CPU1_G2_TX_DP<5>")
	)
	(segment
		(start 118.032784 -222.26905)
		(end 118.10238 -222.30969)
		(width 0.1143)
		(layer "In13.Cu")
		(net "GMI_CPU0_G0_CPU1_G2_TX_DP<5>")
	)
	(segment
		(start 116.855494 -239.541558)
		(end 116.77269 -239.624362)
		(width 0.1143)
		(layer "In13.Cu")
		(net "GMI_CPU0_G0_CPU1_G2_TX_DP<5>")
	)
	(segment
		(start 118.032784 -231.988868)
		(end 118.0719 -232.011728)
		(width 0.1143)
		(layer "In13.Cu")
		(net "GMI_CPU0_G0_CPU1_G2_TX_DP<5>")
	)
	(segment
		(start 117.789706 -221.426532)
		(end 117.789706 -221.804484)
		(width 0.1143)
		(layer "In13.Cu")
		(net "GMI_CPU0_G0_CPU1_G2_TX_DP<5>")
	)
	(segment
		(start 117.69979 -218.787726)
		(end 117.69979 -221.071948)
		(width 0.14224)
		(layer "In13.Cu")
		(net "GMI_CPU0_G0_CPU1_G2_TX_DP<5>")
	)
	(segment
		(start 353.463098 -229.43947)
		(end 353.423982 -229.41661)
		(width 0.1143)
		(layer "In13.Cu")
		(net "GMI_CPU0_G0_CPU1_G2_TX_DP<5>")
	)
	(segment
		(start 353.463098 -232.679494)
		(end 353.393502 -232.638854)
		(width 0.1143)
		(layer "In13.Cu")
		(net "GMI_CPU0_G0_CPU1_G2_TX_DP<5>")
	)
	(segment
		(start 309.529226 -181.177184)
		(end 307.437028 -180.429408)
		(width 0.14224)
		(layer "In13.Cu")
		(net "GMI_CPU0_G0_CPU1_G2_TX_DP<5>")
	)
	(segment
		(start 118.104412 -229.398068)
		(end 118.0719 -229.416864)
		(width 0.1143)
		(layer "In13.Cu")
		(net "GMI_CPU0_G0_CPU1_G2_TX_DP<5>")
	)
	(segment
		(start 166.04615 -179.631086)
		(end 159.300672 -182.04307)
		(width 0.14224)
		(layer "In13.Cu")
		(net "GMI_CPU0_G0_CPU1_G2_TX_DP<5>")
	)
	(segment
		(start 353.750372 -221.145862)
		(end 353.796092 -221.100142)
		(width 0.1143)
		(layer "In13.Cu")
		(net "GMI_CPU0_G0_CPU1_G2_TX_DP<5>")
	)
	(segment
		(start 353.393502 -223.929448)
		(end 353.463098 -223.888808)
		(width 0.1143)
		(layer "In13.Cu")
		(net "GMI_CPU0_G0_CPU1_G2_TX_DP<5>")
	)
	(segment
		(start 118.032784 -236.848904)
		(end 118.0719 -236.871764)
		(width 0.1143)
		(layer "In13.Cu")
		(net "GMI_CPU0_G0_CPU1_G2_TX_DP<5>")
	)
	(segment
		(start 353.463098 -222.959676)
		(end 353.393502 -222.919036)
		(width 0.1143)
		(layer "In13.Cu")
		(net "GMI_CPU0_G0_CPU1_G2_TX_DP<5>")
	)
	(segment
		(start 353.892104 -238.325406)
		(end 353.862386 -238.308388)
		(width 0.1143)
		(layer "In13.Cu")
		(net "GMI_CPU0_G0_CPU1_G2_TX_DP<5>")
	)
	(segment
		(start 118.0719 -228.771958)
		(end 118.10238 -228.789738)
		(width 0.1143)
		(layer "In13.Cu")
		(net "GMI_CPU0_G0_CPU1_G2_TX_DP<5>")
	)
	(segment
		(start 353.393502 -222.309436)
		(end 353.463098 -222.268796)
		(width 0.1143)
		(layer "In13.Cu")
		(net "GMI_CPU0_G0_CPU1_G2_TX_DP<5>")
	)
	(segment
		(start 118.0719 -235.896912)
		(end 118.032784 -235.919772)
		(width 0.1143)
		(layer "In13.Cu")
		(net "GMI_CPU0_G0_CPU1_G2_TX_DP<5>")
	)
	(segment
		(start 118.0719 -226.177094)
		(end 118.032784 -226.199954)
		(width 0.1143)
		(layer "In13.Cu")
		(net "GMI_CPU0_G0_CPU1_G2_TX_DP<5>")
	)
	(segment
		(start 118.10238 -237.499144)
		(end 118.0719 -237.516924)
		(width 0.1143)
		(layer "In13.Cu")
		(net "GMI_CPU0_G0_CPU1_G2_TX_DP<5>")
	)
	(segment
		(start 118.0719 -233.63174)
		(end 118.10238 -233.64952)
		(width 0.1143)
		(layer "In13.Cu")
		(net "GMI_CPU0_G0_CPU1_G2_TX_DP<5>")
	)
	(segment
		(start 118.0719 -227.797106)
		(end 118.032784 -227.819966)
		(width 0.1143)
		(layer "In13.Cu")
		(net "GMI_CPU0_G0_CPU1_G2_TX_DP<5>")
	)
	(segment
		(start 118.032784 -233.60888)
		(end 118.0719 -233.63174)
		(width 0.1143)
		(layer "In13.Cu")
		(net "GMI_CPU0_G0_CPU1_G2_TX_DP<5>")
	)
	(segment
		(start 118.10238 -227.779326)
		(end 118.0719 -227.797106)
		(width 0.1143)
		(layer "In13.Cu")
		(net "GMI_CPU0_G0_CPU1_G2_TX_DP<5>")
	)
	(segment
		(start 118.0719 -232.011728)
		(end 118.10238 -232.029508)
		(width 0.1143)
		(layer "In13.Cu")
		(net "GMI_CPU0_G0_CPU1_G2_TX_DP<5>")
	)
	(segment
		(start 118.0719 -223.911922)
		(end 118.10238 -223.929702)
		(width 0.1143)
		(layer "In13.Cu")
		(net "GMI_CPU0_G0_CPU1_G2_TX_DP<5>")
	)
	(segment
		(start 353.423982 -231.036622)
		(end 353.39147 -231.017826)
		(width 0.1143)
		(layer "In13.Cu")
		(net "GMI_CPU0_G0_CPU1_G2_TX_DP<5>")
	)
	(segment
		(start 118.0719 -234.2769)
		(end 118.032784 -234.29976)
		(width 0.1143)
		(layer "In13.Cu")
		(net "GMI_CPU0_G0_CPU1_G2_TX_DP<5>")
	)
	(segment
		(start 302.902112 -180.429408)
		(end 166.04615 -179.631086)
		(width 0.14224)
		(layer "In13.Cu")
		(net "GMI_CPU0_G0_CPU1_G2_TX_DP<5>")
	)
	(segment
		(start 118.0719 -232.656888)
		(end 118.032784 -232.679748)
		(width 0.1143)
		(layer "In13.Cu")
		(net "GMI_CPU0_G0_CPU1_G2_TX_DP<5>")
	)
	(segment
		(start 118.0719 -235.251752)
		(end 118.10238 -235.269532)
		(width 0.1143)
		(layer "In13.Cu")
		(net "GMI_CPU0_G0_CPU1_G2_TX_DP<5>")
	)
	(segment
		(start 118.0719 -236.871764)
		(end 118.10238 -236.889544)
		(width 0.1143)
		(layer "In13.Cu")
		(net "GMI_CPU0_G0_CPU1_G2_TX_DP<5>")
	)
	(segment
		(start 118.10238 -224.539302)
		(end 118.0719 -224.557082)
		(width 0.1143)
		(layer "In13.Cu")
		(net "GMI_CPU0_G0_CPU1_G2_TX_DP<5>")
	)
	(segment
		(start 117.633496 -238.308642)
		(end 117.602508 -238.326422)
		(width 0.1143)
		(layer "In13.Cu")
		(net "GMI_CPU0_G0_CPU1_G2_TX_DP<5>")
	)
	(segment
		(start 117.74551 -221.146116)
		(end 117.74551 -221.382336)
		(width 0.1143)
		(layer "In13.Cu")
		(net "GMI_CPU0_G0_CPU1_G2_TX_DP<5>")
	)
	(segment
		(start 118.10238 -235.879132)
		(end 118.0719 -235.896912)
		(width 0.1143)
		(layer "In13.Cu")
		(net "GMI_CPU0_G0_CPU1_G2_TX_DP<5>")
	)
	(segment
		(start 117.599206 -238.328454)
		(end 117.56263 -238.34979)
		(width 0.1143)
		(layer "In13.Cu")
		(net "GMI_CPU0_G0_CPU1_G2_TX_DP<5>")
	)
	(segment
		(start 353.706176 -221.426278)
		(end 353.750372 -221.382082)
		(width 0.1143)
		(layer "In13.Cu")
		(net "GMI_CPU0_G0_CPU1_G2_TX_DP<5>")
	)
	(segment
		(start 118.032784 -225.509074)
		(end 118.0719 -225.531934)
		(width 0.1143)
		(layer "In13.Cu")
		(net "GMI_CPU0_G0_CPU1_G2_TX_DP<5>")
	)
	(segment
		(start 120.906794 -213.314026)
		(end 117.69979 -218.787726)
		(width 0.14224)
		(layer "In13.Cu")
		(net "GMI_CPU0_G0_CPU1_G2_TX_DP<5>")
	)
	(segment
		(start 353.894136 -238.326676)
		(end 353.893374 -238.326168)
		(width 0.1143)
		(layer "In13.Cu")
		(net "GMI_CPU0_G0_CPU1_G2_TX_DP<5>")
	)
	(segment
		(start 118.10238 -222.91929)
		(end 118.0719 -222.93707)
		(width 0.1143)
		(layer "In13.Cu")
		(net "GMI_CPU0_G0_CPU1_G2_TX_DP<5>")
	)
	(segment
		(start 354.403152 -239.159542)
		(end 354.333556 -239.118902)
		(width 0.1143)
		(layer "In13.Cu")
		(net "GMI_CPU0_G0_CPU1_G2_TX_DP<5>")
	)
	(segment
		(start 118.0719 -224.557082)
		(end 118.032784 -224.579942)
		(width 0.1143)
		(layer "In13.Cu")
		(net "GMI_CPU0_G0_CPU1_G2_TX_DP<5>")
	)
	(segment
		(start 118.10238 -232.639108)
		(end 118.0719 -232.656888)
		(width 0.1143)
		(layer "In13.Cu")
		(net "GMI_CPU0_G0_CPU1_G2_TX_DP<5>")
	)
	(segment
		(start 117.162326 -239.119156)
		(end 117.131846 -239.136936)
		(width 0.1143)
		(layer "In13.Cu")
		(net "GMI_CPU0_G0_CPU1_G2_TX_DP<5>")
	)
	(segment
		(start 117.601746 -238.32693)
		(end 117.60073 -238.327438)
		(width 0.1143)
		(layer "In13.Cu")
		(net "GMI_CPU0_G0_CPU1_G2_TX_DP<5>")
	)
	(segment
		(start 117.602508 -238.326422)
		(end 117.601746 -238.32693)
		(width 0.1143)
		(layer "In13.Cu")
		(net "GMI_CPU0_G0_CPU1_G2_TX_DP<5>")
	)
	(segment
		(start 353.706176 -221.80423)
		(end 353.706176 -221.426278)
		(width 0.1143)
		(layer "In13.Cu")
		(net "GMI_CPU0_G0_CPU1_G2_TX_DP<5>")
	)
	(segment
		(start 154.815286 -185.72099)
		(end 144.272762 -194.366388)
		(width 0.14224)
		(layer "In13.Cu")
		(net "GMI_CPU0_G0_CPU1_G2_TX_DP<5>")
	)
	(segment
		(start 118.10238 -226.159314)
		(end 118.0719 -226.177094)
		(width 0.1143)
		(layer "In13.Cu")
		(net "GMI_CPU0_G0_CPU1_G2_TX_DP<5>")
	)
	(segment
		(start 353.893374 -238.326168)
		(end 353.892104 -238.325406)
		(width 0.1143)
		(layer "In13.Cu")
		(net "GMI_CPU0_G0_CPU1_G2_TX_DP<5>")
	)
	(segment
		(start 118.0719 -227.151946)
		(end 118.10238 -227.169726)
		(width 0.1143)
		(layer "In13.Cu")
		(net "GMI_CPU0_G0_CPU1_G2_TX_DP<5>")
	)
	(segment
		(start 159.300672 -182.04307)
		(end 154.81554 -185.721244)
		(width 0.14224)
		(layer "In13.Cu")
		(net "GMI_CPU0_G0_CPU1_G2_TX_DP<5>")
	)
	(segment
		(start 118.0719 -222.93707)
		(end 118.032784 -222.95993)
		(width 0.1143)
		(layer "In13.Cu")
		(net "GMI_CPU0_G0_CPU1_G2_TX_DP<5>")
	)
	(segment
		(start 353.393502 -228.789484)
		(end 353.463098 -228.748844)
		(width 0.1143)
		(layer "In13.Cu")
		(net "GMI_CPU0_G0_CPU1_G2_TX_DP<5>")
	)
	(segment
		(start 353.463098 -231.059482)
		(end 353.423982 -231.036622)
		(width 0.1143)
		(layer "In13.Cu")
		(net "GMI_CPU0_G0_CPU1_G2_TX_DP<5>")
	)
	(segment
		(start 353.463098 -234.299506)
		(end 353.393502 -234.258866)
		(width 0.1143)
		(layer "In13.Cu")
		(net "GMI_CPU0_G0_CPU1_G2_TX_DP<5>")
	)
	(segment
		(start 118.032784 -227.129086)
		(end 118.0719 -227.151946)
		(width 0.1143)
		(layer "In13.Cu")
		(net "GMI_CPU0_G0_CPU1_G2_TX_DP<5>")
	)
	(segment
		(start 307.437028 -180.429408)
		(end 302.902112 -180.429408)
		(width 0.14224)
		(layer "In13.Cu")
		(net "GMI_CPU0_G0_CPU1_G2_TX_DP<5>")
	)
	(segment
		(start 117.69979 -221.100396)
		(end 117.74551 -221.146116)
		(width 0.1143)
		(layer "In13.Cu")
		(net "GMI_CPU0_G0_CPU1_G2_TX_DP<5>")
	)
	(segment
		(start 353.393502 -236.88929)
		(end 353.463098 -236.84865)
		(width 0.1143)
		(layer "In13.Cu")
		(net "GMI_CPU0_G0_CPU1_G2_TX_DP<5>")
	)
	(segment
		(start 118.0719 -231.036876)
		(end 118.032784 -231.059736)
		(width 0.1143)
		(layer "In13.Cu")
		(net "GMI_CPU0_G0_CPU1_G2_TX_DP<5>")
	)
	(segment
		(start 117.131846 -239.136936)
		(end 117.09273 -239.159796)
		(width 0.1143)
		(layer "In13.Cu")
		(net "GMI_CPU0_G0_CPU1_G2_TX_DP<5>")
	)
	(segment
		(start 353.796092 -218.71559)
		(end 350.549972 -213.247986)
		(width 0.14224)
		(layer "In13.Cu")
		(net "GMI_CPU0_G0_CPU1_G2_TX_DP<5>")
	)
	(segment
		(start 143.8656 -194.489578)
		(end 120.906794 -213.314026)
		(width 0.14224)
		(layer "In13.Cu")
		(net "GMI_CPU0_G0_CPU1_G2_TX_DP<5>")
	)
	(segment
		(start 353.393502 -230.409496)
		(end 353.460558 -230.37038)
		(width 0.1143)
		(layer "In13.Cu")
		(net "GMI_CPU0_G0_CPU1_G2_TX_DP<5>")
	)
	(arc
		(start 117.09273 -239.159796)
		(mid 116.940743 -239.316304)
		(end 116.859304 -239.518698)
		(width 0.1143)
		(layer "In13.Cu")
		(net "GMI_CPU0_G0_CPU1_G2_TX_DP<5>")
	)
	(arc
		(start 118.259352 -229.094538)
		(mid 118.218386 -229.264944)
		(end 118.104412 -229.398068)
		(width 0.1143)
		(layer "In13.Cu")
		(net "GMI_CPU0_G0_CPU1_G2_TX_DP<5>")
	)
	(arc
		(start 118.10238 -236.889544)
		(mid 118.259357 -237.194344)
		(end 118.10238 -237.499144)
		(width 0.1143)
		(layer "In13.Cu")
		(net "GMI_CPU0_G0_CPU1_G2_TX_DP<5>")
	)
	(arc
		(start 118.032784 -234.29976)
		(mid 117.789457 -234.764326)
		(end 118.032784 -235.228892)
		(width 0.1143)
		(layer "In13.Cu")
		(net "GMI_CPU0_G0_CPU1_G2_TX_DP<5>")
	)
	(arc
		(start 118.032784 -224.579942)
		(mid 117.789457 -225.044508)
		(end 118.032784 -225.509074)
		(width 0.1143)
		(layer "In13.Cu")
		(net "GMI_CPU0_G0_CPU1_G2_TX_DP<5>")
	)
	(arc
		(start 353.393502 -232.638854)
		(mid 353.236525 -232.334054)
		(end 353.393502 -232.029254)
		(width 0.1143)
		(layer "In13.Cu")
		(net "GMI_CPU0_G0_CPU1_G2_TX_DP<5>")
	)
	(arc
		(start 117.789452 -238.00435)
		(mid 117.748197 -238.175321)
		(end 117.633496 -238.308642)
		(width 0.1143)
		(layer "In13.Cu")
		(net "GMI_CPU0_G0_CPU1_G2_TX_DP<5>")
	)
	(arc
		(start 353.463098 -222.268796)
		(mid 353.641741 -222.066401)
		(end 353.706176 -221.80423)
		(width 0.1143)
		(layer "In13.Cu")
		(net "GMI_CPU0_G0_CPU1_G2_TX_DP<5>")
	)
	(arc
		(start 118.10238 -233.64952)
		(mid 118.259357 -233.95432)
		(end 118.10238 -234.25912)
		(width 0.1143)
		(layer "In13.Cu")
		(net "GMI_CPU0_G0_CPU1_G2_TX_DP<5>")
	)
	(arc
		(start 353.463098 -231.988614)
		(mid 353.706425 -231.524048)
		(end 353.463098 -231.059482)
		(width 0.1143)
		(layer "In13.Cu")
		(net "GMI_CPU0_G0_CPU1_G2_TX_DP<5>")
	)
	(arc
		(start 118.10238 -227.169726)
		(mid 118.259357 -227.474526)
		(end 118.10238 -227.779326)
		(width 0.1143)
		(layer "In13.Cu")
		(net "GMI_CPU0_G0_CPU1_G2_TX_DP<5>")
	)
	(arc
		(start 118.032784 -227.819966)
		(mid 117.789457 -228.284532)
		(end 118.032784 -228.749098)
		(width 0.1143)
		(layer "In13.Cu")
		(net "GMI_CPU0_G0_CPU1_G2_TX_DP<5>")
	)
	(arc
		(start 353.23653 -229.094284)
		(mid 353.278079 -228.922862)
		(end 353.393502 -228.789484)
		(width 0.1143)
		(layer "In13.Cu")
		(net "GMI_CPU0_G0_CPU1_G2_TX_DP<5>")
	)
	(arc
		(start 117.789706 -221.804484)
		(mid 117.85408 -222.066688)
		(end 118.032784 -222.26905)
		(width 0.1143)
		(layer "In13.Cu")
		(net "GMI_CPU0_G0_CPU1_G2_TX_DP<5>")
	)
	(arc
		(start 353.463098 -227.128832)
		(mid 353.706425 -226.664266)
		(end 353.463098 -226.1997)
		(width 0.1143)
		(layer "In13.Cu")
		(net "GMI_CPU0_G0_CPU1_G2_TX_DP<5>")
	)
	(arc
		(start 118.10238 -232.029508)
		(mid 118.259357 -232.334308)
		(end 118.10238 -232.639108)
		(width 0.1143)
		(layer "In13.Cu")
		(net "GMI_CPU0_G0_CPU1_G2_TX_DP<5>")
	)
	(arc
		(start 353.463098 -236.84865)
		(mid 353.706425 -236.384084)
		(end 353.463098 -235.919518)
		(width 0.1143)
		(layer "In13.Cu")
		(net "GMI_CPU0_G0_CPU1_G2_TX_DP<5>")
	)
	(arc
		(start 353.460558 -230.37038)
		(mid 353.64121 -230.167635)
		(end 353.70643 -229.904036)
		(width 0.1143)
		(layer "In13.Cu")
		(net "GMI_CPU0_G0_CPU1_G2_TX_DP<5>")
	)
	(arc
		(start 118.032784 -235.919772)
		(mid 117.789457 -236.384338)
		(end 118.032784 -236.848904)
		(width 0.1143)
		(layer "In13.Cu")
		(net "GMI_CPU0_G0_CPU1_G2_TX_DP<5>")
	)
	(arc
		(start 353.70643 -238.004096)
		(mid 353.641915 -237.741877)
		(end 353.463098 -237.53953)
		(width 0.1143)
		(layer "In13.Cu")
		(net "GMI_CPU0_G0_CPU1_G2_TX_DP<5>")
	)
	(arc
		(start 117.56263 -238.34979)
		(mid 117.383817 -238.55214)
		(end 117.319298 -238.814356)
		(width 0.1143)
		(layer "In13.Cu")
		(net "GMI_CPU0_G0_CPU1_G2_TX_DP<5>")
	)
	(arc
		(start 353.39147 -229.397814)
		(mid 353.277541 -229.264667)
		(end 353.23653 -229.094284)
		(width 0.1143)
		(layer "In13.Cu")
		(net "GMI_CPU0_G0_CPU1_G2_TX_DP<5>")
	)
	(arc
		(start 353.463098 -228.748844)
		(mid 353.706425 -228.284278)
		(end 353.463098 -227.819712)
		(width 0.1143)
		(layer "In13.Cu")
		(net "GMI_CPU0_G0_CPU1_G2_TX_DP<5>")
	)
	(arc
		(start 118.10238 -225.549714)
		(mid 118.259357 -225.854514)
		(end 118.10238 -226.159314)
		(width 0.1143)
		(layer "In13.Cu")
		(net "GMI_CPU0_G0_CPU1_G2_TX_DP<5>")
	)
	(arc
		(start 118.10238 -230.40975)
		(mid 118.217807 -230.543126)
		(end 118.259352 -230.71455)
		(width 0.1143)
		(layer "In13.Cu")
		(net "GMI_CPU0_G0_CPU1_G2_TX_DP<5>")
	)
	(arc
		(start 353.463098 -233.608626)
		(mid 353.706425 -233.14406)
		(end 353.463098 -232.679494)
		(width 0.1143)
		(layer "In13.Cu")
		(net "GMI_CPU0_G0_CPU1_G2_TX_DP<5>")
	)
	(arc
		(start 117.789452 -229.90429)
		(mid 117.854688 -230.167881)
		(end 118.035324 -230.370634)
		(width 0.1143)
		(layer "In13.Cu")
		(net "GMI_CPU0_G0_CPU1_G2_TX_DP<5>")
	)
	(arc
		(start 353.393502 -226.15906)
		(mid 353.236525 -225.85426)
		(end 353.393502 -225.54946)
		(width 0.1143)
		(layer "In13.Cu")
		(net "GMI_CPU0_G0_CPU1_G2_TX_DP<5>")
	)
	(arc
		(start 118.032784 -222.95993)
		(mid 117.789457 -223.424496)
		(end 118.032784 -223.889062)
		(width 0.1143)
		(layer "In13.Cu")
		(net "GMI_CPU0_G0_CPU1_G2_TX_DP<5>")
	)
	(arc
		(start 118.032784 -232.679748)
		(mid 117.789457 -233.144314)
		(end 118.032784 -233.60888)
		(width 0.1143)
		(layer "In13.Cu")
		(net "GMI_CPU0_G0_CPU1_G2_TX_DP<5>")
	)
	(arc
		(start 353.393502 -237.49889)
		(mid 353.236525 -237.19409)
		(end 353.393502 -236.88929)
		(width 0.1143)
		(layer "In13.Cu")
		(net "GMI_CPU0_G0_CPU1_G2_TX_DP<5>")
	)
	(arc
		(start 354.333556 -239.118902)
		(mid 354.218129 -238.985526)
		(end 354.176584 -238.814102)
		(width 0.1143)
		(layer "In13.Cu")
		(net "GMI_CPU0_G0_CPU1_G2_TX_DP<5>")
	)
	(arc
		(start 117.319298 -238.814356)
		(mid 117.277749 -238.985778)
		(end 117.162326 -239.119156)
		(width 0.1143)
		(layer "In13.Cu")
		(net "GMI_CPU0_G0_CPU1_G2_TX_DP<5>")
	)
	(arc
		(start 354.176584 -238.814102)
		(mid 354.112069 -238.551883)
		(end 353.933252 -238.349536)
		(width 0.1143)
		(layer "In13.Cu")
		(net "GMI_CPU0_G0_CPU1_G2_TX_DP<5>")
	)
	(arc
		(start 353.39147 -231.017826)
		(mid 353.277541 -230.884679)
		(end 353.23653 -230.714296)
		(width 0.1143)
		(layer "In13.Cu")
		(net "GMI_CPU0_G0_CPU1_G2_TX_DP<5>")
	)
	(arc
		(start 118.032784 -231.059736)
		(mid 117.789457 -231.524302)
		(end 118.032784 -231.988868)
		(width 0.1143)
		(layer "In13.Cu")
		(net "GMI_CPU0_G0_CPU1_G2_TX_DP<5>")
	)
	(arc
		(start 353.23653 -230.714296)
		(mid 353.278079 -230.542874)
		(end 353.393502 -230.409496)
		(width 0.1143)
		(layer "In13.Cu")
		(net "GMI_CPU0_G0_CPU1_G2_TX_DP<5>")
	)
	(arc
		(start 353.393502 -222.919036)
		(mid 353.236525 -222.614236)
		(end 353.393502 -222.309436)
		(width 0.1143)
		(layer "In13.Cu")
		(net "GMI_CPU0_G0_CPU1_G2_TX_DP<5>")
	)
	(arc
		(start 353.463098 -223.888808)
		(mid 353.706425 -223.424242)
		(end 353.463098 -222.959676)
		(width 0.1143)
		(layer "In13.Cu")
		(net "GMI_CPU0_G0_CPU1_G2_TX_DP<5>")
	)
	(arc
		(start 353.463098 -235.228638)
		(mid 353.706425 -234.764072)
		(end 353.463098 -234.299506)
		(width 0.1143)
		(layer "In13.Cu")
		(net "GMI_CPU0_G0_CPU1_G2_TX_DP<5>")
	)
	(arc
		(start 354.636578 -239.518444)
		(mid 354.555145 -239.316046)
		(end 354.403152 -239.159542)
		(width 0.1143)
		(layer "In13.Cu")
		(net "GMI_CPU0_G0_CPU1_G2_TX_DP<5>")
	)
	(arc
		(start 353.393502 -235.878878)
		(mid 353.236525 -235.574078)
		(end 353.393502 -235.269278)
		(width 0.1143)
		(layer "In13.Cu")
		(net "GMI_CPU0_G0_CPU1_G2_TX_DP<5>")
	)
	(arc
		(start 118.032784 -229.439724)
		(mid 117.853971 -229.642074)
		(end 117.789452 -229.90429)
		(width 0.1143)
		(layer "In13.Cu")
		(net "GMI_CPU0_G0_CPU1_G2_TX_DP<5>")
	)
	(arc
		(start 353.393502 -234.258866)
		(mid 353.236525 -233.954066)
		(end 353.393502 -233.649266)
		(width 0.1143)
		(layer "In13.Cu")
		(net "GMI_CPU0_G0_CPU1_G2_TX_DP<5>")
	)
	(arc
		(start 118.10238 -222.30969)
		(mid 118.259357 -222.61449)
		(end 118.10238 -222.91929)
		(width 0.1143)
		(layer "In13.Cu")
		(net "GMI_CPU0_G0_CPU1_G2_TX_DP<5>")
	)
	(arc
		(start 353.393502 -224.539048)
		(mid 353.236525 -224.234248)
		(end 353.393502 -223.929448)
		(width 0.1143)
		(layer "In13.Cu")
		(net "GMI_CPU0_G0_CPU1_G2_TX_DP<5>")
	)
	(arc
		(start 353.862386 -238.308388)
		(mid 353.74771 -238.175054)
		(end 353.70643 -238.004096)
		(width 0.1143)
		(layer "In13.Cu")
		(net "GMI_CPU0_G0_CPU1_G2_TX_DP<5>")
	)
	(arc
		(start 118.10238 -223.929702)
		(mid 118.259357 -224.234502)
		(end 118.10238 -224.539302)
		(width 0.1143)
		(layer "In13.Cu")
		(net "GMI_CPU0_G0_CPU1_G2_TX_DP<5>")
	)
	(arc
		(start 118.10238 -235.269532)
		(mid 118.259357 -235.574332)
		(end 118.10238 -235.879132)
		(width 0.1143)
		(layer "In13.Cu")
		(net "GMI_CPU0_G0_CPU1_G2_TX_DP<5>")
	)
	(arc
		(start 118.032784 -226.199954)
		(mid 117.789457 -226.66452)
		(end 118.032784 -227.129086)
		(width 0.1143)
		(layer "In13.Cu")
		(net "GMI_CPU0_G0_CPU1_G2_TX_DP<5>")
	)
	(arc
		(start 354.640388 -239.541304)
		(mid 354.6386 -239.529855)
		(end 354.636578 -239.518444)
		(width 0.1143)
		(layer "In13.Cu")
		(net "GMI_CPU0_G0_CPU1_G2_TX_DP<5>")
	)
	(arc
		(start 116.859304 -239.518698)
		(mid 116.857281 -239.530108)
		(end 116.855494 -239.541558)
		(width 0.1143)
		(layer "In13.Cu")
		(net "GMI_CPU0_G0_CPU1_G2_TX_DP<5>")
	)
	(arc
		(start 118.10238 -228.789738)
		(mid 118.217807 -228.923114)
		(end 118.259352 -229.094538)
		(width 0.1143)
		(layer "In13.Cu")
		(net "GMI_CPU0_G0_CPU1_G2_TX_DP<5>")
	)
	(arc
		(start 118.259352 -230.71455)
		(mid 118.218386 -230.884956)
		(end 118.104412 -231.01808)
		(width 0.1143)
		(layer "In13.Cu")
		(net "GMI_CPU0_G0_CPU1_G2_TX_DP<5>")
	)
	(arc
		(start 353.393502 -227.779072)
		(mid 353.236525 -227.474272)
		(end 353.393502 -227.169472)
		(width 0.1143)
		(layer "In13.Cu")
		(net "GMI_CPU0_G0_CPU1_G2_TX_DP<5>")
	)
	(arc
		(start 353.463098 -225.50882)
		(mid 353.706425 -225.044254)
		(end 353.463098 -224.579688)
		(width 0.1143)
		(layer "In13.Cu")
		(net "GMI_CPU0_G0_CPU1_G2_TX_DP<5>")
	)
	(arc
		(start 353.70643 -229.904036)
		(mid 353.641915 -229.641817)
		(end 353.463098 -229.43947)
		(width 0.1143)
		(layer "In13.Cu")
		(net "GMI_CPU0_G0_CPU1_G2_TX_DP<5>")
	)
	(arc
		(start 118.032784 -237.539784)
		(mid 117.853971 -237.742134)
		(end 117.789452 -238.00435)
		(width 0.1143)
		(layer "In13.Cu")
		(net "GMI_CPU0_G0_CPU1_G2_TX_DP<5>")
	)
	(segment
		(start 116.007896 -238.270288)
		(end 116.474748 -238.00435)
		(width 0.12954)
		(layer "F.Cu")
		(net "GMI_CPU0_G0_CPU1_G2_TX_DP<4>")
	)
	(segment
		(start 355.487986 -238.270034)
		(end 355.021134 -238.004096)
		(width 0.12954)
		(layer "F.Cu")
		(net "GMI_CPU0_G0_CPU1_G2_TX_DP<4>")
	)
	(segment
		(start 117.131846 -232.656888)
		(end 117.09273 -232.679748)
		(width 0.1143)
		(layer "In13.Cu")
		(net "GMI_CPU0_G0_CPU1_G2_TX_DP<4>")
	)
	(segment
		(start 354.403152 -222.959676)
		(end 354.333556 -222.919036)
		(width 0.1143)
		(layer "In13.Cu")
		(net "GMI_CPU0_G0_CPU1_G2_TX_DP<4>")
	)
	(segment
		(start 354.723192 -238.004096)
		(end 354.640388 -237.921292)
		(width 0.1143)
		(layer "In13.Cu")
		(net "GMI_CPU0_G0_CPU1_G2_TX_DP<4>")
	)
	(segment
		(start 117.09273 -236.848904)
		(end 117.131846 -236.871764)
		(width 0.1143)
		(layer "In13.Cu")
		(net "GMI_CPU0_G0_CPU1_G2_TX_DP<4>")
	)
	(segment
		(start 154.710638 -184.416446)
		(end 154.710892 -184.4167)
		(width 0.14224)
		(layer "In13.Cu")
		(net "GMI_CPU0_G0_CPU1_G2_TX_DP<4>")
	)
	(segment
		(start 117.131846 -227.797106)
		(end 117.09273 -227.819966)
		(width 0.1143)
		(layer "In13.Cu")
		(net "GMI_CPU0_G0_CPU1_G2_TX_DP<4>")
	)
	(segment
		(start 117.162326 -237.499144)
		(end 117.131846 -237.516924)
		(width 0.1143)
		(layer "In13.Cu")
		(net "GMI_CPU0_G0_CPU1_G2_TX_DP<4>")
	)
	(segment
		(start 354.403152 -231.059482)
		(end 354.364036 -231.036622)
		(width 0.1143)
		(layer "In13.Cu")
		(net "GMI_CPU0_G0_CPU1_G2_TX_DP<4>")
	)
	(segment
		(start 117.131846 -232.011728)
		(end 117.162326 -232.029508)
		(width 0.1143)
		(layer "In13.Cu")
		(net "GMI_CPU0_G0_CPU1_G2_TX_DP<4>")
	)
	(segment
		(start 354.403152 -224.579688)
		(end 354.333556 -224.539048)
		(width 0.1143)
		(layer "In13.Cu")
		(net "GMI_CPU0_G0_CPU1_G2_TX_DP<4>")
	)
	(segment
		(start 117.131846 -237.516924)
		(end 117.09273 -237.539784)
		(width 0.1143)
		(layer "In13.Cu")
		(net "GMI_CPU0_G0_CPU1_G2_TX_DP<4>")
	)
	(segment
		(start 117.162326 -226.159314)
		(end 117.131846 -226.177094)
		(width 0.1143)
		(layer "In13.Cu")
		(net "GMI_CPU0_G0_CPU1_G2_TX_DP<4>")
	)
	(segment
		(start 354.403152 -229.43947)
		(end 354.364036 -229.41661)
		(width 0.1143)
		(layer "In13.Cu")
		(net "GMI_CPU0_G0_CPU1_G2_TX_DP<4>")
	)
	(segment
		(start 116.75491 -221.100396)
		(end 116.80063 -221.146116)
		(width 0.1143)
		(layer "In13.Cu")
		(net "GMI_CPU0_G0_CPU1_G2_TX_DP<4>")
	)
	(segment
		(start 354.333556 -228.789484)
		(end 354.403152 -228.748844)
		(width 0.1143)
		(layer "In13.Cu")
		(net "GMI_CPU0_G0_CPU1_G2_TX_DP<4>")
	)
	(segment
		(start 354.740972 -221.093538)
		(end 354.740972 -218.479878)
		(width 0.14224)
		(layer "In13.Cu")
		(net "GMI_CPU0_G0_CPU1_G2_TX_DP<4>")
	)
	(segment
		(start 165.816788 -178.692302)
		(end 158.503112 -181.30774)
		(width 0.14224)
		(layer "In13.Cu")
		(net "GMI_CPU0_G0_CPU1_G2_TX_DP<4>")
	)
	(segment
		(start 354.333556 -235.269278)
		(end 354.403152 -235.228638)
		(width 0.1143)
		(layer "In13.Cu")
		(net "GMI_CPU0_G0_CPU1_G2_TX_DP<4>")
	)
	(segment
		(start 354.333556 -232.029254)
		(end 354.403152 -231.988614)
		(width 0.1143)
		(layer "In13.Cu")
		(net "GMI_CPU0_G0_CPU1_G2_TX_DP<4>")
	)
	(segment
		(start 351.26803 -212.630766)
		(end 316.182756 -183.861964)
		(width 0.14224)
		(layer "In13.Cu")
		(net "GMI_CPU0_G0_CPU1_G2_TX_DP<4>")
	)
	(segment
		(start 354.740972 -221.100142)
		(end 354.740972 -221.093538)
		(width 0.1143)
		(layer "In13.Cu")
		(net "GMI_CPU0_G0_CPU1_G2_TX_DP<4>")
	)
	(segment
		(start 117.09273 -233.60888)
		(end 117.131846 -233.63174)
		(width 0.1143)
		(layer "In13.Cu")
		(net "GMI_CPU0_G0_CPU1_G2_TX_DP<4>")
	)
	(segment
		(start 354.403152 -226.1997)
		(end 354.333556 -226.15906)
		(width 0.1143)
		(layer "In13.Cu")
		(net "GMI_CPU0_G0_CPU1_G2_TX_DP<4>")
	)
	(segment
		(start 117.131846 -225.531934)
		(end 117.162326 -225.549714)
		(width 0.1143)
		(layer "In13.Cu")
		(net "GMI_CPU0_G0_CPU1_G2_TX_DP<4>")
	)
	(segment
		(start 117.131846 -224.557082)
		(end 117.09273 -224.579942)
		(width 0.1143)
		(layer "In13.Cu")
		(net "GMI_CPU0_G0_CPU1_G2_TX_DP<4>")
	)
	(segment
		(start 117.131846 -228.771958)
		(end 117.162326 -228.789738)
		(width 0.1143)
		(layer "In13.Cu")
		(net "GMI_CPU0_G0_CPU1_G2_TX_DP<4>")
	)
	(segment
		(start 354.333556 -236.88929)
		(end 354.403152 -236.84865)
		(width 0.1143)
		(layer "In13.Cu")
		(net "GMI_CPU0_G0_CPU1_G2_TX_DP<4>")
	)
	(segment
		(start 117.131846 -235.896912)
		(end 117.09273 -235.919772)
		(width 0.1143)
		(layer "In13.Cu")
		(net "GMI_CPU0_G0_CPU1_G2_TX_DP<4>")
	)
	(segment
		(start 144.013682 -193.068194)
		(end 120.238012 -212.563456)
		(width 0.14224)
		(layer "In13.Cu")
		(net "GMI_CPU0_G0_CPU1_G2_TX_DP<4>")
	)
	(segment
		(start 354.403152 -234.299506)
		(end 354.333556 -234.258866)
		(width 0.1143)
		(layer "In13.Cu")
		(net "GMI_CPU0_G0_CPU1_G2_TX_DP<4>")
	)
	(segment
		(start 116.75491 -221.071948)
		(end 116.75491 -221.100396)
		(width 0.1143)
		(layer "In13.Cu")
		(net "GMI_CPU0_G0_CPU1_G2_TX_DP<4>")
	)
	(segment
		(start 116.75491 -218.505532)
		(end 116.75491 -221.071948)
		(width 0.14224)
		(layer "In13.Cu")
		(net "GMI_CPU0_G0_CPU1_G2_TX_DP<4>")
	)
	(segment
		(start 117.164358 -229.398068)
		(end 117.131846 -229.416864)
		(width 0.1143)
		(layer "In13.Cu")
		(net "GMI_CPU0_G0_CPU1_G2_TX_DP<4>")
	)
	(segment
		(start 354.333556 -223.929448)
		(end 354.403152 -223.888808)
		(width 0.1143)
		(layer "In13.Cu")
		(net "GMI_CPU0_G0_CPU1_G2_TX_DP<4>")
	)
	(segment
		(start 117.131846 -227.151946)
		(end 117.162326 -227.169726)
		(width 0.1143)
		(layer "In13.Cu")
		(net "GMI_CPU0_G0_CPU1_G2_TX_DP<4>")
	)
	(segment
		(start 354.333556 -222.309436)
		(end 354.403152 -222.268796)
		(width 0.1143)
		(layer "In13.Cu")
		(net "GMI_CPU0_G0_CPU1_G2_TX_DP<4>")
	)
	(segment
		(start 117.09273 -222.26905)
		(end 117.162326 -222.30969)
		(width 0.1143)
		(layer "In13.Cu")
		(net "GMI_CPU0_G0_CPU1_G2_TX_DP<4>")
	)
	(segment
		(start 354.403152 -235.919518)
		(end 354.333556 -235.878878)
		(width 0.1143)
		(layer "In13.Cu")
		(net "GMI_CPU0_G0_CPU1_G2_TX_DP<4>")
	)
	(segment
		(start 158.503112 -181.30774)
		(end 154.710638 -184.416446)
		(width 0.14224)
		(layer "In13.Cu")
		(net "GMI_CPU0_G0_CPU1_G2_TX_DP<4>")
	)
	(segment
		(start 116.849652 -221.431358)
		(end 116.849652 -221.804484)
		(width 0.1143)
		(layer "In13.Cu")
		(net "GMI_CPU0_G0_CPU1_G2_TX_DP<4>")
	)
	(segment
		(start 117.09527 -230.370634)
		(end 117.162326 -230.40975)
		(width 0.1143)
		(layer "In13.Cu")
		(net "GMI_CPU0_G0_CPU1_G2_TX_DP<4>")
	)
	(segment
		(start 354.333556 -230.409496)
		(end 354.400612 -230.37038)
		(width 0.1143)
		(layer "In13.Cu")
		(net "GMI_CPU0_G0_CPU1_G2_TX_DP<4>")
	)
	(segment
		(start 117.09273 -231.988868)
		(end 117.131846 -232.011728)
		(width 0.1143)
		(layer "In13.Cu")
		(net "GMI_CPU0_G0_CPU1_G2_TX_DP<4>")
	)
	(segment
		(start 354.740972 -218.479878)
		(end 351.26803 -212.630766)
		(width 0.14224)
		(layer "In13.Cu")
		(net "GMI_CPU0_G0_CPU1_G2_TX_DP<4>")
	)
	(segment
		(start 355.021134 -238.004096)
		(end 354.723192 -238.004096)
		(width 0.1143)
		(layer "In13.Cu")
		(net "GMI_CPU0_G0_CPU1_G2_TX_DP<4>")
	)
	(segment
		(start 354.364036 -229.41661)
		(end 354.331524 -229.397814)
		(width 0.1143)
		(layer "In13.Cu")
		(net "GMI_CPU0_G0_CPU1_G2_TX_DP<4>")
	)
	(segment
		(start 154.710892 -184.4167)
		(end 150.223982 -188.095128)
		(width 0.14224)
		(layer "In13.Cu")
		(net "GMI_CPU0_G0_CPU1_G2_TX_DP<4>")
	)
	(segment
		(start 117.162326 -232.639108)
		(end 117.131846 -232.656888)
		(width 0.1143)
		(layer "In13.Cu")
		(net "GMI_CPU0_G0_CPU1_G2_TX_DP<4>")
	)
	(segment
		(start 354.364036 -231.036622)
		(end 354.331524 -231.017826)
		(width 0.1143)
		(layer "In13.Cu")
		(net "GMI_CPU0_G0_CPU1_G2_TX_DP<4>")
	)
	(segment
		(start 117.164358 -231.01808)
		(end 117.131846 -231.036876)
		(width 0.1143)
		(layer "In13.Cu")
		(net "GMI_CPU0_G0_CPU1_G2_TX_DP<4>")
	)
	(segment
		(start 354.403152 -237.53953)
		(end 354.333556 -237.49889)
		(width 0.1143)
		(layer "In13.Cu")
		(net "GMI_CPU0_G0_CPU1_G2_TX_DP<4>")
	)
	(segment
		(start 117.131846 -222.93707)
		(end 117.09273 -222.95993)
		(width 0.1143)
		(layer "In13.Cu")
		(net "GMI_CPU0_G0_CPU1_G2_TX_DP<4>")
	)
	(segment
		(start 354.333556 -233.649266)
		(end 354.403152 -233.608626)
		(width 0.1143)
		(layer "In13.Cu")
		(net "GMI_CPU0_G0_CPU1_G2_TX_DP<4>")
	)
	(segment
		(start 354.64623 -221.431104)
		(end 354.695252 -221.382082)
		(width 0.1143)
		(layer "In13.Cu")
		(net "GMI_CPU0_G0_CPU1_G2_TX_DP<4>")
	)
	(segment
		(start 117.131846 -235.251752)
		(end 117.162326 -235.269532)
		(width 0.1143)
		(layer "In13.Cu")
		(net "GMI_CPU0_G0_CPU1_G2_TX_DP<4>")
	)
	(segment
		(start 117.131846 -234.2769)
		(end 117.09273 -234.29976)
		(width 0.1143)
		(layer "In13.Cu")
		(net "GMI_CPU0_G0_CPU1_G2_TX_DP<4>")
	)
	(segment
		(start 116.80063 -221.146116)
		(end 116.80063 -221.382336)
		(width 0.1143)
		(layer "In13.Cu")
		(net "GMI_CPU0_G0_CPU1_G2_TX_DP<4>")
	)
	(segment
		(start 354.333556 -227.169472)
		(end 354.403152 -227.128832)
		(width 0.1143)
		(layer "In13.Cu")
		(net "GMI_CPU0_G0_CPU1_G2_TX_DP<4>")
	)
	(segment
		(start 117.09273 -223.889062)
		(end 117.131846 -223.911922)
		(width 0.1143)
		(layer "In13.Cu")
		(net "GMI_CPU0_G0_CPU1_G2_TX_DP<4>")
	)
	(segment
		(start 117.09273 -228.749098)
		(end 117.131846 -228.771958)
		(width 0.1143)
		(layer "In13.Cu")
		(net "GMI_CPU0_G0_CPU1_G2_TX_DP<4>")
	)
	(segment
		(start 117.162326 -235.879132)
		(end 117.131846 -235.896912)
		(width 0.1143)
		(layer "In13.Cu")
		(net "GMI_CPU0_G0_CPU1_G2_TX_DP<4>")
	)
	(segment
		(start 117.162326 -234.25912)
		(end 117.131846 -234.2769)
		(width 0.1143)
		(layer "In13.Cu")
		(net "GMI_CPU0_G0_CPU1_G2_TX_DP<4>")
	)
	(segment
		(start 117.131846 -226.177094)
		(end 117.09273 -226.199954)
		(width 0.1143)
		(layer "In13.Cu")
		(net "GMI_CPU0_G0_CPU1_G2_TX_DP<4>")
	)
	(segment
		(start 117.09273 -235.228892)
		(end 117.131846 -235.251752)
		(width 0.1143)
		(layer "In13.Cu")
		(net "GMI_CPU0_G0_CPU1_G2_TX_DP<4>")
	)
	(segment
		(start 354.403152 -227.819712)
		(end 354.333556 -227.779072)
		(width 0.1143)
		(layer "In13.Cu")
		(net "GMI_CPU0_G0_CPU1_G2_TX_DP<4>")
	)
	(segment
		(start 354.695252 -221.145862)
		(end 354.740972 -221.100142)
		(width 0.1143)
		(layer "In13.Cu")
		(net "GMI_CPU0_G0_CPU1_G2_TX_DP<4>")
	)
	(segment
		(start 117.131846 -229.416864)
		(end 117.09273 -229.439724)
		(width 0.1143)
		(layer "In13.Cu")
		(net "GMI_CPU0_G0_CPU1_G2_TX_DP<4>")
	)
	(segment
		(start 150.223982 -188.095382)
		(end 144.24279 -192.998598)
		(width 0.14224)
		(layer "In13.Cu")
		(net "GMI_CPU0_G0_CPU1_G2_TX_DP<4>")
	)
	(segment
		(start 116.855494 -237.921546)
		(end 116.77269 -238.00435)
		(width 0.1143)
		(layer "In13.Cu")
		(net "GMI_CPU0_G0_CPU1_G2_TX_DP<4>")
	)
	(segment
		(start 117.09273 -227.129086)
		(end 117.131846 -227.151946)
		(width 0.1143)
		(layer "In13.Cu")
		(net "GMI_CPU0_G0_CPU1_G2_TX_DP<4>")
	)
	(segment
		(start 144.24279 -192.998598)
		(end 144.013682 -193.068194)
		(width 0.14224)
		(layer "In13.Cu")
		(net "GMI_CPU0_G0_CPU1_G2_TX_DP<4>")
	)
	(segment
		(start 117.162326 -227.779326)
		(end 117.131846 -227.797106)
		(width 0.1143)
		(layer "In13.Cu")
		(net "GMI_CPU0_G0_CPU1_G2_TX_DP<4>")
	)
	(segment
		(start 117.131846 -231.036876)
		(end 117.09273 -231.059736)
		(width 0.1143)
		(layer "In13.Cu")
		(net "GMI_CPU0_G0_CPU1_G2_TX_DP<4>")
	)
	(segment
		(start 316.182756 -183.861964)
		(end 309.912512 -180.312568)
		(width 0.14224)
		(layer "In13.Cu")
		(net "GMI_CPU0_G0_CPU1_G2_TX_DP<4>")
	)
	(segment
		(start 117.09273 -225.509074)
		(end 117.131846 -225.531934)
		(width 0.1143)
		(layer "In13.Cu")
		(net "GMI_CPU0_G0_CPU1_G2_TX_DP<4>")
	)
	(segment
		(start 150.223982 -188.095128)
		(end 150.223982 -188.095382)
		(width 0.14224)
		(layer "In13.Cu")
		(net "GMI_CPU0_G0_CPU1_G2_TX_DP<4>")
	)
	(segment
		(start 354.695252 -221.382082)
		(end 354.695252 -221.145862)
		(width 0.1143)
		(layer "In13.Cu")
		(net "GMI_CPU0_G0_CPU1_G2_TX_DP<4>")
	)
	(segment
		(start 354.403152 -232.679494)
		(end 354.333556 -232.638854)
		(width 0.1143)
		(layer "In13.Cu")
		(net "GMI_CPU0_G0_CPU1_G2_TX_DP<4>")
	)
	(segment
		(start 117.131846 -233.63174)
		(end 117.162326 -233.64952)
		(width 0.1143)
		(layer "In13.Cu")
		(net "GMI_CPU0_G0_CPU1_G2_TX_DP<4>")
	)
	(segment
		(start 117.162326 -222.91929)
		(end 117.131846 -222.93707)
		(width 0.1143)
		(layer "In13.Cu")
		(net "GMI_CPU0_G0_CPU1_G2_TX_DP<4>")
	)
	(segment
		(start 354.64623 -221.80423)
		(end 354.64623 -221.431104)
		(width 0.1143)
		(layer "In13.Cu")
		(net "GMI_CPU0_G0_CPU1_G2_TX_DP<4>")
	)
	(segment
		(start 302.90516 -179.492148)
		(end 165.816788 -178.692302)
		(width 0.14224)
		(layer "In13.Cu")
		(net "GMI_CPU0_G0_CPU1_G2_TX_DP<4>")
	)
	(segment
		(start 354.333556 -225.54946)
		(end 354.403152 -225.50882)
		(width 0.1143)
		(layer "In13.Cu")
		(net "GMI_CPU0_G0_CPU1_G2_TX_DP<4>")
	)
	(segment
		(start 117.162326 -224.539302)
		(end 117.131846 -224.557082)
		(width 0.1143)
		(layer "In13.Cu")
		(net "GMI_CPU0_G0_CPU1_G2_TX_DP<4>")
	)
	(segment
		(start 116.80063 -221.382336)
		(end 116.849652 -221.431358)
		(width 0.1143)
		(layer "In13.Cu")
		(net "GMI_CPU0_G0_CPU1_G2_TX_DP<4>")
	)
	(segment
		(start 307.617876 -179.492148)
		(end 302.90516 -179.492148)
		(width 0.14224)
		(layer "In13.Cu")
		(net "GMI_CPU0_G0_CPU1_G2_TX_DP<4>")
	)
	(segment
		(start 117.131846 -236.871764)
		(end 117.162326 -236.889544)
		(width 0.1143)
		(layer "In13.Cu")
		(net "GMI_CPU0_G0_CPU1_G2_TX_DP<4>")
	)
	(segment
		(start 117.131846 -223.911922)
		(end 117.162326 -223.929702)
		(width 0.1143)
		(layer "In13.Cu")
		(net "GMI_CPU0_G0_CPU1_G2_TX_DP<4>")
	)
	(segment
		(start 116.77269 -238.00435)
		(end 116.474748 -238.00435)
		(width 0.1143)
		(layer "In13.Cu")
		(net "GMI_CPU0_G0_CPU1_G2_TX_DP<4>")
	)
	(segment
		(start 120.238012 -212.563456)
		(end 116.75491 -218.505532)
		(width 0.14224)
		(layer "In13.Cu")
		(net "GMI_CPU0_G0_CPU1_G2_TX_DP<4>")
	)
	(segment
		(start 309.912512 -180.312568)
		(end 307.617876 -179.492148)
		(width 0.14224)
		(layer "In13.Cu")
		(net "GMI_CPU0_G0_CPU1_G2_TX_DP<4>")
	)
	(arc
		(start 354.333556 -235.878878)
		(mid 354.176579 -235.574078)
		(end 354.333556 -235.269278)
		(width 0.1143)
		(layer "In13.Cu")
		(net "GMI_CPU0_G0_CPU1_G2_TX_DP<4>")
	)
	(arc
		(start 117.162326 -232.029508)
		(mid 117.319303 -232.334308)
		(end 117.162326 -232.639108)
		(width 0.1143)
		(layer "In13.Cu")
		(net "GMI_CPU0_G0_CPU1_G2_TX_DP<4>")
	)
	(arc
		(start 354.640388 -237.921292)
		(mid 354.6386 -237.909843)
		(end 354.636578 -237.898432)
		(width 0.1143)
		(layer "In13.Cu")
		(net "GMI_CPU0_G0_CPU1_G2_TX_DP<4>")
	)
	(arc
		(start 117.09273 -232.679748)
		(mid 116.849403 -233.144314)
		(end 117.09273 -233.60888)
		(width 0.1143)
		(layer "In13.Cu")
		(net "GMI_CPU0_G0_CPU1_G2_TX_DP<4>")
	)
	(arc
		(start 117.319298 -230.71455)
		(mid 117.278332 -230.884956)
		(end 117.164358 -231.01808)
		(width 0.1143)
		(layer "In13.Cu")
		(net "GMI_CPU0_G0_CPU1_G2_TX_DP<4>")
	)
	(arc
		(start 117.09273 -227.819966)
		(mid 116.849403 -228.284532)
		(end 117.09273 -228.749098)
		(width 0.1143)
		(layer "In13.Cu")
		(net "GMI_CPU0_G0_CPU1_G2_TX_DP<4>")
	)
	(arc
		(start 117.162326 -223.929702)
		(mid 117.319303 -224.234502)
		(end 117.162326 -224.539302)
		(width 0.1143)
		(layer "In13.Cu")
		(net "GMI_CPU0_G0_CPU1_G2_TX_DP<4>")
	)
	(arc
		(start 117.09273 -235.919772)
		(mid 116.849403 -236.384338)
		(end 117.09273 -236.848904)
		(width 0.1143)
		(layer "In13.Cu")
		(net "GMI_CPU0_G0_CPU1_G2_TX_DP<4>")
	)
	(arc
		(start 354.333556 -227.779072)
		(mid 354.176579 -227.474272)
		(end 354.333556 -227.169472)
		(width 0.1143)
		(layer "In13.Cu")
		(net "GMI_CPU0_G0_CPU1_G2_TX_DP<4>")
	)
	(arc
		(start 354.403152 -231.988614)
		(mid 354.646479 -231.524048)
		(end 354.403152 -231.059482)
		(width 0.1143)
		(layer "In13.Cu")
		(net "GMI_CPU0_G0_CPU1_G2_TX_DP<4>")
	)
	(arc
		(start 354.400612 -230.37038)
		(mid 354.581264 -230.167635)
		(end 354.646484 -229.904036)
		(width 0.1143)
		(layer "In13.Cu")
		(net "GMI_CPU0_G0_CPU1_G2_TX_DP<4>")
	)
	(arc
		(start 116.849652 -221.804484)
		(mid 116.914026 -222.066688)
		(end 117.09273 -222.26905)
		(width 0.1143)
		(layer "In13.Cu")
		(net "GMI_CPU0_G0_CPU1_G2_TX_DP<4>")
	)
	(arc
		(start 354.403152 -227.128832)
		(mid 354.646479 -226.664266)
		(end 354.403152 -226.1997)
		(width 0.1143)
		(layer "In13.Cu")
		(net "GMI_CPU0_G0_CPU1_G2_TX_DP<4>")
	)
	(arc
		(start 116.859304 -237.898686)
		(mid 116.857281 -237.910096)
		(end 116.855494 -237.921546)
		(width 0.1143)
		(layer "In13.Cu")
		(net "GMI_CPU0_G0_CPU1_G2_TX_DP<4>")
	)
	(arc
		(start 354.403152 -223.888808)
		(mid 354.646479 -223.424242)
		(end 354.403152 -222.959676)
		(width 0.1143)
		(layer "In13.Cu")
		(net "GMI_CPU0_G0_CPU1_G2_TX_DP<4>")
	)
	(arc
		(start 354.403152 -236.84865)
		(mid 354.646479 -236.384084)
		(end 354.403152 -235.919518)
		(width 0.1143)
		(layer "In13.Cu")
		(net "GMI_CPU0_G0_CPU1_G2_TX_DP<4>")
	)
	(arc
		(start 117.162326 -228.789738)
		(mid 117.277753 -228.923114)
		(end 117.319298 -229.094538)
		(width 0.1143)
		(layer "In13.Cu")
		(net "GMI_CPU0_G0_CPU1_G2_TX_DP<4>")
	)
	(arc
		(start 354.333556 -226.15906)
		(mid 354.176579 -225.85426)
		(end 354.333556 -225.54946)
		(width 0.1143)
		(layer "In13.Cu")
		(net "GMI_CPU0_G0_CPU1_G2_TX_DP<4>")
	)
	(arc
		(start 354.331524 -231.017826)
		(mid 354.217595 -230.884679)
		(end 354.176584 -230.714296)
		(width 0.1143)
		(layer "In13.Cu")
		(net "GMI_CPU0_G0_CPU1_G2_TX_DP<4>")
	)
	(arc
		(start 117.162326 -233.64952)
		(mid 117.319303 -233.95432)
		(end 117.162326 -234.25912)
		(width 0.1143)
		(layer "In13.Cu")
		(net "GMI_CPU0_G0_CPU1_G2_TX_DP<4>")
	)
	(arc
		(start 354.333556 -222.919036)
		(mid 354.176579 -222.614236)
		(end 354.333556 -222.309436)
		(width 0.1143)
		(layer "In13.Cu")
		(net "GMI_CPU0_G0_CPU1_G2_TX_DP<4>")
	)
	(arc
		(start 117.162326 -235.269532)
		(mid 117.319303 -235.574332)
		(end 117.162326 -235.879132)
		(width 0.1143)
		(layer "In13.Cu")
		(net "GMI_CPU0_G0_CPU1_G2_TX_DP<4>")
	)
	(arc
		(start 354.331524 -229.397814)
		(mid 354.217595 -229.264667)
		(end 354.176584 -229.094284)
		(width 0.1143)
		(layer "In13.Cu")
		(net "GMI_CPU0_G0_CPU1_G2_TX_DP<4>")
	)
	(arc
		(start 354.333556 -232.638854)
		(mid 354.176579 -232.334054)
		(end 354.333556 -232.029254)
		(width 0.1143)
		(layer "In13.Cu")
		(net "GMI_CPU0_G0_CPU1_G2_TX_DP<4>")
	)
	(arc
		(start 354.646484 -229.904036)
		(mid 354.581969 -229.641817)
		(end 354.403152 -229.43947)
		(width 0.1143)
		(layer "In13.Cu")
		(net "GMI_CPU0_G0_CPU1_G2_TX_DP<4>")
	)
	(arc
		(start 354.403152 -235.228638)
		(mid 354.646479 -234.764072)
		(end 354.403152 -234.299506)
		(width 0.1143)
		(layer "In13.Cu")
		(net "GMI_CPU0_G0_CPU1_G2_TX_DP<4>")
	)
	(arc
		(start 117.162326 -236.889544)
		(mid 117.319303 -237.194344)
		(end 117.162326 -237.499144)
		(width 0.1143)
		(layer "In13.Cu")
		(net "GMI_CPU0_G0_CPU1_G2_TX_DP<4>")
	)
	(arc
		(start 117.319298 -229.094538)
		(mid 117.278332 -229.264944)
		(end 117.164358 -229.398068)
		(width 0.1143)
		(layer "In13.Cu")
		(net "GMI_CPU0_G0_CPU1_G2_TX_DP<4>")
	)
	(arc
		(start 354.333556 -237.49889)
		(mid 354.176579 -237.19409)
		(end 354.333556 -236.88929)
		(width 0.1143)
		(layer "In13.Cu")
		(net "GMI_CPU0_G0_CPU1_G2_TX_DP<4>")
	)
	(arc
		(start 117.162326 -225.549714)
		(mid 117.319303 -225.854514)
		(end 117.162326 -226.159314)
		(width 0.1143)
		(layer "In13.Cu")
		(net "GMI_CPU0_G0_CPU1_G2_TX_DP<4>")
	)
	(arc
		(start 354.403152 -222.268796)
		(mid 354.581795 -222.066401)
		(end 354.64623 -221.80423)
		(width 0.1143)
		(layer "In13.Cu")
		(net "GMI_CPU0_G0_CPU1_G2_TX_DP<4>")
	)
	(arc
		(start 354.176584 -230.714296)
		(mid 354.218133 -230.542874)
		(end 354.333556 -230.409496)
		(width 0.1143)
		(layer "In13.Cu")
		(net "GMI_CPU0_G0_CPU1_G2_TX_DP<4>")
	)
	(arc
		(start 354.636578 -237.898432)
		(mid 354.555145 -237.696034)
		(end 354.403152 -237.53953)
		(width 0.1143)
		(layer "In13.Cu")
		(net "GMI_CPU0_G0_CPU1_G2_TX_DP<4>")
	)
	(arc
		(start 354.403152 -228.748844)
		(mid 354.646479 -228.284278)
		(end 354.403152 -227.819712)
		(width 0.1143)
		(layer "In13.Cu")
		(net "GMI_CPU0_G0_CPU1_G2_TX_DP<4>")
	)
	(arc
		(start 117.09273 -222.95993)
		(mid 116.849403 -223.424496)
		(end 117.09273 -223.889062)
		(width 0.1143)
		(layer "In13.Cu")
		(net "GMI_CPU0_G0_CPU1_G2_TX_DP<4>")
	)
	(arc
		(start 117.09273 -229.439724)
		(mid 116.913917 -229.642074)
		(end 116.849398 -229.90429)
		(width 0.1143)
		(layer "In13.Cu")
		(net "GMI_CPU0_G0_CPU1_G2_TX_DP<4>")
	)
	(arc
		(start 354.333556 -224.539048)
		(mid 354.176579 -224.234248)
		(end 354.333556 -223.929448)
		(width 0.1143)
		(layer "In13.Cu")
		(net "GMI_CPU0_G0_CPU1_G2_TX_DP<4>")
	)
	(arc
		(start 117.09273 -237.539784)
		(mid 116.940743 -237.696292)
		(end 116.859304 -237.898686)
		(width 0.1143)
		(layer "In13.Cu")
		(net "GMI_CPU0_G0_CPU1_G2_TX_DP<4>")
	)
	(arc
		(start 354.403152 -233.608626)
		(mid 354.646479 -233.14406)
		(end 354.403152 -232.679494)
		(width 0.1143)
		(layer "In13.Cu")
		(net "GMI_CPU0_G0_CPU1_G2_TX_DP<4>")
	)
	(arc
		(start 117.09273 -231.059736)
		(mid 116.849403 -231.524302)
		(end 117.09273 -231.988868)
		(width 0.1143)
		(layer "In13.Cu")
		(net "GMI_CPU0_G0_CPU1_G2_TX_DP<4>")
	)
	(arc
		(start 116.849398 -229.90429)
		(mid 116.914634 -230.167881)
		(end 117.09527 -230.370634)
		(width 0.1143)
		(layer "In13.Cu")
		(net "GMI_CPU0_G0_CPU1_G2_TX_DP<4>")
	)
	(arc
		(start 354.403152 -225.50882)
		(mid 354.646479 -225.044254)
		(end 354.403152 -224.579688)
		(width 0.1143)
		(layer "In13.Cu")
		(net "GMI_CPU0_G0_CPU1_G2_TX_DP<4>")
	)
	(arc
		(start 117.09273 -224.579942)
		(mid 116.849403 -225.044508)
		(end 117.09273 -225.509074)
		(width 0.1143)
		(layer "In13.Cu")
		(net "GMI_CPU0_G0_CPU1_G2_TX_DP<4>")
	)
	(arc
		(start 117.162326 -230.40975)
		(mid 117.277753 -230.543126)
		(end 117.319298 -230.71455)
		(width 0.1143)
		(layer "In13.Cu")
		(net "GMI_CPU0_G0_CPU1_G2_TX_DP<4>")
	)
	(arc
		(start 354.176584 -229.094284)
		(mid 354.218133 -228.922862)
		(end 354.333556 -228.789484)
		(width 0.1143)
		(layer "In13.Cu")
		(net "GMI_CPU0_G0_CPU1_G2_TX_DP<4>")
	)
	(arc
		(start 117.09273 -234.29976)
		(mid 116.849403 -234.764326)
		(end 117.09273 -235.228892)
		(width 0.1143)
		(layer "In13.Cu")
		(net "GMI_CPU0_G0_CPU1_G2_TX_DP<4>")
	)
	(arc
		(start 117.09273 -226.199954)
		(mid 116.849403 -226.66452)
		(end 117.09273 -227.129086)
		(width 0.1143)
		(layer "In13.Cu")
		(net "GMI_CPU0_G0_CPU1_G2_TX_DP<4>")
	)
	(arc
		(start 117.162326 -222.30969)
		(mid 117.319303 -222.61449)
		(end 117.162326 -222.91929)
		(width 0.1143)
		(layer "In13.Cu")
		(net "GMI_CPU0_G0_CPU1_G2_TX_DP<4>")
	)
	(arc
		(start 117.162326 -227.169726)
		(mid 117.319303 -227.474526)
		(end 117.162326 -227.779326)
		(width 0.1143)
		(layer "In13.Cu")
		(net "GMI_CPU0_G0_CPU1_G2_TX_DP<4>")
	)
	(arc
		(start 354.333556 -234.258866)
		(mid 354.176579 -233.954066)
		(end 354.333556 -233.649266)
		(width 0.1143)
		(layer "In13.Cu")
		(net "GMI_CPU0_G0_CPU1_G2_TX_DP<4>")
	)
	(segment
		(start 116.007896 -243.130324)
		(end 116.474748 -242.864386)
		(width 0.12954)
		(layer "F.Cu")
		(net "GMI_CPU0_G0_CPU1_G2_TX_DP<3>")
	)
	(segment
		(start 355.487986 -243.13007)
		(end 355.021134 -242.864132)
		(width 0.12954)
		(layer "F.Cu")
		(net "GMI_CPU0_G0_CPU1_G2_TX_DP<3>")
	)
	(segment
		(start 115.251738 -240.111788)
		(end 115.2525 -240.112296)
		(width 0.1143)
		(layer "In13.Cu")
		(net "GMI_CPU0_G0_CPU1_G2_TX_DP<3>")
	)
	(segment
		(start 115.259358 -225.536252)
		(end 115.283488 -225.550222)
		(width 0.1143)
		(layer "In13.Cu")
		(net "GMI_CPU0_G0_CPU1_G2_TX_DP<3>")
	)
	(segment
		(start 356.212394 -222.309944)
		(end 356.28326 -222.268796)
		(width 0.1143)
		(layer "In13.Cu")
		(net "GMI_CPU0_G0_CPU1_G2_TX_DP<3>")
	)
	(segment
		(start 356.246684 -237.518194)
		(end 356.24516 -237.517178)
		(width 0.1143)
		(layer "In13.Cu")
		(net "GMI_CPU0_G0_CPU1_G2_TX_DP<3>")
	)
	(segment
		(start 356.244144 -222.936816)
		(end 356.243382 -222.936308)
		(width 0.1143)
		(layer "In13.Cu")
		(net "GMI_CPU0_G0_CPU1_G2_TX_DP<3>")
	)
	(segment
		(start 356.212394 -228.789992)
		(end 356.223316 -228.783642)
		(width 0.1143)
		(layer "In13.Cu")
		(net "GMI_CPU0_G0_CPU1_G2_TX_DP<3>")
	)
	(segment
		(start 115.25758 -240.11509)
		(end 115.258342 -240.115598)
		(width 0.1143)
		(layer "In13.Cu")
		(net "GMI_CPU0_G0_CPU1_G2_TX_DP<3>")
	)
	(segment
		(start 356.526338 -221.440756)
		(end 356.585012 -221.382082)
		(width 0.1143)
		(layer "In13.Cu")
		(net "GMI_CPU0_G0_CPU1_G2_TX_DP<3>")
	)
	(segment
		(start 302.911256 -177.613056)
		(end 165.429946 -176.810416)
		(width 0.14224)
		(layer "In13.Cu")
		(net "GMI_CPU0_G0_CPU1_G2_TX_DP<3>")
	)
	(segment
		(start 356.242112 -239.135412)
		(end 356.212394 -239.118394)
		(width 0.1143)
		(layer "In13.Cu")
		(net "GMI_CPU0_G0_CPU1_G2_TX_DP<3>")
	)
	(segment
		(start 116.84254 -242.794536)
		(end 116.77269 -242.864386)
		(width 0.1143)
		(layer "In13.Cu")
		(net "GMI_CPU0_G0_CPU1_G2_TX_DP<3>")
	)
	(segment
		(start 115.251738 -230.39197)
		(end 115.283488 -230.410258)
		(width 0.1143)
		(layer "In13.Cu")
		(net "GMI_CPU0_G0_CPU1_G2_TX_DP<3>")
	)
	(segment
		(start 115.259358 -235.25607)
		(end 115.283488 -235.27004)
		(width 0.1143)
		(layer "In13.Cu")
		(net "GMI_CPU0_G0_CPU1_G2_TX_DP<3>")
	)
	(segment
		(start 356.275386 -233.613198)
		(end 356.28326 -233.608626)
		(width 0.1143)
		(layer "In13.Cu")
		(net "GMI_CPU0_G0_CPU1_G2_TX_DP<3>")
	)
	(segment
		(start 115.251738 -233.63174)
		(end 115.2525 -233.632248)
		(width 0.1143)
		(layer "In13.Cu")
		(net "GMI_CPU0_G0_CPU1_G2_TX_DP<3>")
	)
	(segment
		(start 115.25377 -238.493046)
		(end 115.255294 -238.493808)
		(width 0.1143)
		(layer "In13.Cu")
		(net "GMI_CPU0_G0_CPU1_G2_TX_DP<3>")
	)
	(segment
		(start 356.215442 -225.54819)
		(end 356.28326 -225.50882)
		(width 0.1143)
		(layer "In13.Cu")
		(net "GMI_CPU0_G0_CPU1_G2_TX_DP<3>")
	)
	(segment
		(start 115.25758 -235.255054)
		(end 115.258342 -235.255562)
		(width 0.1143)
		(layer "In13.Cu")
		(net "GMI_CPU0_G0_CPU1_G2_TX_DP<3>")
	)
	(segment
		(start 356.242112 -222.935546)
		(end 356.212394 -222.918528)
		(width 0.1143)
		(layer "In13.Cu")
		(net "GMI_CPU0_G0_CPU1_G2_TX_DP<3>")
	)
	(segment
		(start 115.21948 -228.753162)
		(end 115.220242 -228.75367)
		(width 0.1143)
		(layer "In13.Cu")
		(net "GMI_CPU0_G0_CPU1_G2_TX_DP<3>")
	)
	(segment
		(start 115.250722 -235.89742)
		(end 115.249198 -235.898436)
		(width 0.1143)
		(layer "In13.Cu")
		(net "GMI_CPU0_G0_CPU1_G2_TX_DP<3>")
	)
	(segment
		(start 115.258342 -236.875574)
		(end 115.259358 -236.876082)
		(width 0.1143)
		(layer "In13.Cu")
		(net "GMI_CPU0_G0_CPU1_G2_TX_DP<3>")
	)
	(segment
		(start 115.2525 -227.796598)
		(end 115.251738 -227.797106)
		(width 0.1143)
		(layer "In13.Cu")
		(net "GMI_CPU0_G0_CPU1_G2_TX_DP<3>")
	)
	(segment
		(start 355.021134 -242.864132)
		(end 354.723192 -242.864132)
		(width 0.1143)
		(layer "In13.Cu")
		(net "GMI_CPU0_G0_CPU1_G2_TX_DP<3>")
	)
	(segment
		(start 115.251738 -229.416864)
		(end 115.212622 -229.439724)
		(width 0.1143)
		(layer "In13.Cu")
		(net "GMI_CPU0_G0_CPU1_G2_TX_DP<3>")
	)
	(segment
		(start 356.585012 -221.145862)
		(end 356.630732 -221.100142)
		(width 0.1143)
		(layer "In13.Cu")
		(net "GMI_CPU0_G0_CPU1_G2_TX_DP<3>")
	)
	(segment
		(start 356.212394 -227.16998)
		(end 356.244144 -227.151692)
		(width 0.1143)
		(layer "In13.Cu")
		(net "GMI_CPU0_G0_CPU1_G2_TX_DP<3>")
	)
	(segment
		(start 115.251738 -234.2769)
		(end 115.250722 -234.277408)
		(width 0.1143)
		(layer "In13.Cu")
		(net "GMI_CPU0_G0_CPU1_G2_TX_DP<3>")
	)
	(segment
		(start 115.215162 -230.370634)
		(end 115.251738 -230.39197)
		(width 0.1143)
		(layer "In13.Cu")
		(net "GMI_CPU0_G0_CPU1_G2_TX_DP<3>")
	)
	(segment
		(start 115.2525 -232.012236)
		(end 115.25377 -232.012998)
		(width 0.1143)
		(layer "In13.Cu")
		(net "GMI_CPU0_G0_CPU1_G2_TX_DP<3>")
	)
	(segment
		(start 115.256056 -238.494316)
		(end 115.25758 -238.495078)
		(width 0.1143)
		(layer "In13.Cu")
		(net "GMI_CPU0_G0_CPU1_G2_TX_DP<3>")
	)
	(segment
		(start 355.586284 -241.246152)
		(end 355.586284 -241.24412)
		(width 0.1143)
		(layer "In13.Cu")
		(net "GMI_CPU0_G0_CPU1_G2_TX_DP<3>")
	)
	(segment
		(start 115.25758 -238.495078)
		(end 115.258342 -238.495586)
		(width 0.1143)
		(layer "In13.Cu")
		(net "GMI_CPU0_G0_CPU1_G2_TX_DP<3>")
	)
	(segment
		(start 356.630732 -221.100142)
		(end 356.630732 -221.093538)
		(width 0.1143)
		(layer "In13.Cu")
		(net "GMI_CPU0_G0_CPU1_G2_TX_DP<3>")
	)
	(segment
		(start 356.283514 -235.228892)
		(end 356.28326 -235.228638)
		(width 0.1143)
		(layer "In13.Cu")
		(net "GMI_CPU0_G0_CPU1_G2_TX_DP<3>")
	)
	(segment
		(start 115.21948 -223.893126)
		(end 115.220242 -223.893634)
		(width 0.1143)
		(layer "In13.Cu")
		(net "GMI_CPU0_G0_CPU1_G2_TX_DP<3>")
	)
	(segment
		(start 115.2525 -237.516416)
		(end 115.251738 -237.516924)
		(width 0.1143)
		(layer "In13.Cu")
		(net "GMI_CPU0_G0_CPU1_G2_TX_DP<3>")
	)
	(segment
		(start 115.285266 -231.017318)
		(end 115.251738 -231.036876)
		(width 0.1143)
		(layer "In13.Cu")
		(net "GMI_CPU0_G0_CPU1_G2_TX_DP<3>")
	)
	(segment
		(start 356.585012 -221.382082)
		(end 356.585012 -221.145862)
		(width 0.1143)
		(layer "In13.Cu")
		(net "GMI_CPU0_G0_CPU1_G2_TX_DP<3>")
	)
	(segment
		(start 115.2525 -226.176586)
		(end 115.251738 -226.177094)
		(width 0.1143)
		(layer "In13.Cu")
		(net "GMI_CPU0_G0_CPU1_G2_TX_DP<3>")
	)
	(segment
		(start 116.15293 -241.709194)
		(end 116.186966 -241.728752)
		(width 0.1143)
		(layer "In13.Cu")
		(net "GMI_CPU0_G0_CPU1_G2_TX_DP<3>")
	)
	(segment
		(start 356.243382 -226.176332)
		(end 356.242112 -226.17557)
		(width 0.1143)
		(layer "In13.Cu")
		(net "GMI_CPU0_G0_CPU1_G2_TX_DP<3>")
	)
	(segment
		(start 165.429946 -176.810416)
		(end 157.228032 -179.742846)
		(width 0.14224)
		(layer "In13.Cu")
		(net "GMI_CPU0_G0_CPU1_G2_TX_DP<3>")
	)
	(segment
		(start 356.246684 -239.138206)
		(end 356.24516 -239.13719)
		(width 0.1143)
		(layer "In13.Cu")
		(net "GMI_CPU0_G0_CPU1_G2_TX_DP<3>")
	)
	(segment
		(start 115.258342 -235.255562)
		(end 115.259358 -235.25607)
		(width 0.1143)
		(layer "In13.Cu")
		(net "GMI_CPU0_G0_CPU1_G2_TX_DP<3>")
	)
	(segment
		(start 115.251738 -237.516924)
		(end 115.250722 -237.517432)
		(width 0.1143)
		(layer "In13.Cu")
		(net "GMI_CPU0_G0_CPU1_G2_TX_DP<3>")
	)
	(segment
		(start 115.283488 -235.878624)
		(end 115.2525 -235.896404)
		(width 0.1143)
		(layer "In13.Cu")
		(net "GMI_CPU0_G0_CPU1_G2_TX_DP<3>")
	)
	(segment
		(start 116.190776 -241.731292)
		(end 116.191792 -241.7318)
		(width 0.1143)
		(layer "In13.Cu")
		(net "GMI_CPU0_G0_CPU1_G2_TX_DP<3>")
	)
	(segment
		(start 115.249198 -226.178618)
		(end 115.212622 -226.199954)
		(width 0.1143)
		(layer "In13.Cu")
		(net "GMI_CPU0_G0_CPU1_G2_TX_DP<3>")
	)
	(segment
		(start 116.191792 -241.7318)
		(end 116.192554 -241.732308)
		(width 0.1143)
		(layer "In13.Cu")
		(net "GMI_CPU0_G0_CPU1_G2_TX_DP<3>")
	)
	(segment
		(start 356.24516 -237.517178)
		(end 356.244144 -237.51667)
		(width 0.1143)
		(layer "In13.Cu")
		(net "GMI_CPU0_G0_CPU1_G2_TX_DP<3>")
	)
	(segment
		(start 115.220242 -225.513646)
		(end 115.251738 -225.531934)
		(width 0.1143)
		(layer "In13.Cu")
		(net "GMI_CPU0_G0_CPU1_G2_TX_DP<3>")
	)
	(segment
		(start 356.214172 -223.92894)
		(end 356.274624 -223.893888)
		(width 0.1143)
		(layer "In13.Cu")
		(net "GMI_CPU0_G0_CPU1_G2_TX_DP<3>")
	)
	(segment
		(start 356.212394 -223.929956)
		(end 356.214172 -223.92894)
		(width 0.1143)
		(layer "In13.Cu")
		(net "GMI_CPU0_G0_CPU1_G2_TX_DP<3>")
	)
	(segment
		(start 115.283488 -224.538794)
		(end 115.25377 -224.555812)
		(width 0.1143)
		(layer "In13.Cu")
		(net "GMI_CPU0_G0_CPU1_G2_TX_DP<3>")
	)
	(segment
		(start 115.220242 -240.0935)
		(end 115.251738 -240.111788)
		(width 0.1143)
		(layer "In13.Cu")
		(net "GMI_CPU0_G0_CPU1_G2_TX_DP<3>")
	)
	(segment
		(start 115.251738 -222.93707)
		(end 115.250722 -222.937578)
		(width 0.1143)
		(layer "In13.Cu")
		(net "GMI_CPU0_G0_CPU1_G2_TX_DP<3>")
	)
	(segment
		(start 115.25758 -236.875066)
		(end 115.258342 -236.875574)
		(width 0.1143)
		(layer "In13.Cu")
		(net "GMI_CPU0_G0_CPU1_G2_TX_DP<3>")
	)
	(segment
		(start 115.283488 -234.258612)
		(end 115.2525 -234.276392)
		(width 0.1143)
		(layer "In13.Cu")
		(net "GMI_CPU0_G0_CPU1_G2_TX_DP<3>")
	)
	(segment
		(start 115.21948 -236.852968)
		(end 115.220242 -236.853476)
		(width 0.1143)
		(layer "In13.Cu")
		(net "GMI_CPU0_G0_CPU1_G2_TX_DP<3>")
	)
	(segment
		(start 115.21948 -238.47298)
		(end 115.220242 -238.473488)
		(width 0.1143)
		(layer "In13.Cu")
		(net "GMI_CPU0_G0_CPU1_G2_TX_DP<3>")
	)
	(segment
		(start 115.682776 -240.898934)
		(end 115.753642 -240.94059)
		(width 0.1143)
		(layer "In13.Cu")
		(net "GMI_CPU0_G0_CPU1_G2_TX_DP<3>")
	)
	(segment
		(start 356.24516 -222.937324)
		(end 356.244144 -222.936816)
		(width 0.1143)
		(layer "In13.Cu")
		(net "GMI_CPU0_G0_CPU1_G2_TX_DP<3>")
	)
	(segment
		(start 356.28326 -224.579688)
		(end 356.24516 -224.557336)
		(width 0.1143)
		(layer "In13.Cu")
		(net "GMI_CPU0_G0_CPU1_G2_TX_DP<3>")
	)
	(segment
		(start 356.274624 -223.893888)
		(end 356.275386 -223.89338)
		(width 0.1143)
		(layer "In13.Cu")
		(net "GMI_CPU0_G0_CPU1_G2_TX_DP<3>")
	)
	(segment
		(start 310.593486 -178.507644)
		(end 308.091586 -177.613056)
		(width 0.14224)
		(layer "In13.Cu")
		(net "GMI_CPU0_G0_CPU1_G2_TX_DP<3>")
	)
	(segment
		(start 115.283488 -232.6386)
		(end 115.2525 -232.65638)
		(width 0.1143)
		(layer "In13.Cu")
		(net "GMI_CPU0_G0_CPU1_G2_TX_DP<3>")
	)
	(segment
		(start 355.308916 -241.728498)
		(end 355.342952 -241.70894)
		(width 0.1143)
		(layer "In13.Cu")
		(net "GMI_CPU0_G0_CPU1_G2_TX_DP<3>")
	)
	(segment
		(start 115.256056 -235.254292)
		(end 115.25758 -235.255054)
		(width 0.1143)
		(layer "In13.Cu")
		(net "GMI_CPU0_G0_CPU1_G2_TX_DP<3>")
	)
	(segment
		(start 356.212394 -236.889798)
		(end 356.212394 -236.890052)
		(width 0.1143)
		(layer "In13.Cu")
		(net "GMI_CPU0_G0_CPU1_G2_TX_DP<3>")
	)
	(segment
		(start 356.246684 -232.658158)
		(end 356.24516 -232.657142)
		(width 0.1143)
		(layer "In13.Cu")
		(net "GMI_CPU0_G0_CPU1_G2_TX_DP<3>")
	)
	(segment
		(start 354.80244 -242.55984)
		(end 354.83419 -242.541552)
		(width 0.1143)
		(layer "In13.Cu")
		(net "GMI_CPU0_G0_CPU1_G2_TX_DP<3>")
	)
	(segment
		(start 115.220242 -235.233464)
		(end 115.251738 -235.251752)
		(width 0.1143)
		(layer "In13.Cu")
		(net "GMI_CPU0_G0_CPU1_G2_TX_DP<3>")
	)
	(segment
		(start 356.243382 -235.89615)
		(end 356.242112 -235.895388)
		(width 0.1143)
		(layer "In13.Cu")
		(net "GMI_CPU0_G0_CPU1_G2_TX_DP<3>")
	)
	(segment
		(start 115.255294 -223.913954)
		(end 115.256056 -223.914462)
		(width 0.1143)
		(layer "In13.Cu")
		(net "GMI_CPU0_G0_CPU1_G2_TX_DP<3>")
	)
	(segment
		(start 317.38951 -182.354728)
		(end 310.593486 -178.507644)
		(width 0.14224)
		(layer "In13.Cu")
		(net "GMI_CPU0_G0_CPU1_G2_TX_DP<3>")
	)
	(segment
		(start 356.243382 -224.55632)
		(end 356.242112 -224.555558)
		(width 0.1143)
		(layer "In13.Cu")
		(net "GMI_CPU0_G0_CPU1_G2_TX_DP<3>")
	)
	(segment
		(start 115.212622 -227.129086)
		(end 115.249198 -227.150422)
		(width 0.1143)
		(layer "In13.Cu")
		(net "GMI_CPU0_G0_CPU1_G2_TX_DP<3>")
	)
	(segment
		(start 115.258342 -223.915732)
		(end 115.259358 -223.91624)
		(width 0.1143)
		(layer "In13.Cu")
		(net "GMI_CPU0_G0_CPU1_G2_TX_DP<3>")
	)
	(segment
		(start 115.250722 -234.277408)
		(end 115.249198 -234.278424)
		(width 0.1143)
		(layer "In13.Cu")
		(net "GMI_CPU0_G0_CPU1_G2_TX_DP<3>")
	)
	(segment
		(start 137.835132 -195.644008)
		(end 118.442486 -211.545424)
		(width 0.14224)
		(layer "In13.Cu")
		(net "GMI_CPU0_G0_CPU1_G2_TX_DP<3>")
	)
	(segment
		(start 115.259358 -223.91624)
		(end 115.283488 -223.93021)
		(width 0.1143)
		(layer "In13.Cu")
		(net "GMI_CPU0_G0_CPU1_G2_TX_DP<3>")
	)
	(segment
		(start 115.283488 -237.498636)
		(end 115.2525 -237.516416)
		(width 0.1143)
		(layer "In13.Cu")
		(net "GMI_CPU0_G0_CPU1_G2_TX_DP<3>")
	)
	(segment
		(start 115.2525 -224.556574)
		(end 115.251738 -224.557082)
		(width 0.1143)
		(layer "In13.Cu")
		(net "GMI_CPU0_G0_CPU1_G2_TX_DP<3>")
	)
	(segment
		(start 355.342952 -241.70894)
		(end 355.352604 -241.702082)
		(width 0.1143)
		(layer "In13.Cu")
		(net "GMI_CPU0_G0_CPU1_G2_TX_DP<3>")
	)
	(segment
		(start 356.630732 -221.093538)
		(end 356.630732 -217.740738)
		(width 0.14224)
		(layer "In13.Cu")
		(net "GMI_CPU0_G0_CPU1_G2_TX_DP<3>")
	)
	(segment
		(start 356.28326 -227.819712)
		(end 356.246684 -227.798376)
		(width 0.1143)
		(layer "In13.Cu")
		(net "GMI_CPU0_G0_CPU1_G2_TX_DP<3>")
	)
	(segment
		(start 115.2525 -232.65638)
		(end 115.251738 -232.656888)
		(width 0.1143)
		(layer "In13.Cu")
		(net "GMI_CPU0_G0_CPU1_G2_TX_DP<3>")
	)
	(segment
		(start 114.86515 -217.64498)
		(end 114.86515 -221.071948)
		(width 0.14224)
		(layer "In13.Cu")
		(net "GMI_CPU0_G0_CPU1_G2_TX_DP<3>")
	)
	(segment
		(start 115.256056 -228.774498)
		(end 115.25758 -228.77526)
		(width 0.1143)
		(layer "In13.Cu")
		(net "GMI_CPU0_G0_CPU1_G2_TX_DP<3>")
	)
	(segment
		(start 115.2525 -234.276392)
		(end 115.251738 -234.2769)
		(width 0.1143)
		(layer "In13.Cu")
		(net "GMI_CPU0_G0_CPU1_G2_TX_DP<3>")
	)
	(segment
		(start 115.220242 -238.473488)
		(end 115.251738 -238.491776)
		(width 0.1143)
		(layer "In13.Cu")
		(net "GMI_CPU0_G0_CPU1_G2_TX_DP<3>")
	)
	(segment
		(start 115.21948 -233.612944)
		(end 115.220242 -233.613452)
		(width 0.1143)
		(layer "In13.Cu")
		(net "GMI_CPU0_G0_CPU1_G2_TX_DP<3>")
	)
	(segment
		(start 356.526338 -221.80423)
		(end 356.526338 -221.440756)
		(width 0.1143)
		(layer "In13.Cu")
		(net "GMI_CPU0_G0_CPU1_G2_TX_DP<3>")
	)
	(segment
		(start 115.25758 -232.01503)
		(end 115.258342 -232.015538)
		(width 0.1143)
		(layer "In13.Cu")
		(net "GMI_CPU0_G0_CPU1_G2_TX_DP<3>")
	)
	(segment
		(start 115.2525 -223.91243)
		(end 115.25377 -223.913192)
		(width 0.1143)
		(layer "In13.Cu")
		(net "GMI_CPU0_G0_CPU1_G2_TX_DP<3>")
	)
	(segment
		(start 355.110542 -242.061746)
		(end 355.110542 -242.059968)
		(width 0.1143)
		(layer "In13.Cu")
		(net "GMI_CPU0_G0_CPU1_G2_TX_DP<3>")
	)
	(segment
		(start 115.212622 -235.228892)
		(end 115.21948 -235.232956)
		(width 0.1143)
		(layer "In13.Cu")
		(net "GMI_CPU0_G0_CPU1_G2_TX_DP<3>")
	)
	(segment
		(start 355.303328 -241.732054)
		(end 355.30409 -241.731546)
		(width 0.1143)
		(layer "In13.Cu")
		(net "GMI_CPU0_G0_CPU1_G2_TX_DP<3>")
	)
	(segment
		(start 118.442486 -211.545424)
		(end 114.86515 -217.64498)
		(width 0.14224)
		(layer "In13.Cu")
		(net "GMI_CPU0_G0_CPU1_G2_TX_DP<3>")
	)
	(segment
		(start 356.28326 -234.299506)
		(end 356.246684 -234.27817)
		(width 0.1143)
		(layer "In13.Cu")
		(net "GMI_CPU0_G0_CPU1_G2_TX_DP<3>")
	)
	(segment
		(start 115.249198 -232.658412)
		(end 115.212622 -232.679748)
		(width 0.1143)
		(layer "In13.Cu")
		(net "GMI_CPU0_G0_CPU1_G2_TX_DP<3>")
	)
	(segment
		(start 115.259358 -240.116106)
		(end 115.283488 -240.130076)
		(width 0.1143)
		(layer "In13.Cu")
		(net "GMI_CPU0_G0_CPU1_G2_TX_DP<3>")
	)
	(segment
		(start 115.258342 -238.495586)
		(end 115.259358 -238.496094)
		(width 0.1143)
		(layer "In13.Cu")
		(net "GMI_CPU0_G0_CPU1_G2_TX_DP<3>")
	)
	(segment
		(start 355.298756 -241.734594)
		(end 355.303328 -241.732054)
		(width 0.1143)
		(layer "In13.Cu")
		(net "GMI_CPU0_G0_CPU1_G2_TX_DP<3>")
	)
	(segment
		(start 356.283006 -235.229146)
		(end 356.283514 -235.228892)
		(width 0.1143)
		(layer "In13.Cu")
		(net "GMI_CPU0_G0_CPU1_G2_TX_DP<3>")
	)
	(segment
		(start 115.220242 -233.613452)
		(end 115.251738 -233.63174)
		(width 0.1143)
		(layer "In13.Cu")
		(net "GMI_CPU0_G0_CPU1_G2_TX_DP<3>")
	)
	(segment
		(start 115.250722 -227.151438)
		(end 115.251738 -227.151946)
		(width 0.1143)
		(layer "In13.Cu")
		(net "GMI_CPU0_G0_CPU1_G2_TX_DP<3>")
	)
	(segment
		(start 115.250722 -239.137444)
		(end 115.249198 -239.13846)
		(width 0.1143)
		(layer "In13.Cu")
		(net "GMI_CPU0_G0_CPU1_G2_TX_DP<3>")
	)
	(segment
		(start 115.249198 -234.278424)
		(end 115.212622 -234.29976)
		(width 0.1143)
		(layer "In13.Cu")
		(net "GMI_CPU0_G0_CPU1_G2_TX_DP<3>")
	)
	(segment
		(start 356.226364 -240.121694)
		(end 356.28326 -240.088674)
		(width 0.1143)
		(layer "In13.Cu")
		(net "GMI_CPU0_G0_CPU1_G2_TX_DP<3>")
	)
	(segment
		(start 356.28326 -232.679494)
		(end 356.246684 -232.658158)
		(width 0.1143)
		(layer "In13.Cu")
		(net "GMI_CPU0_G0_CPU1_G2_TX_DP<3>")
	)
	(segment
		(start 115.2525 -233.632248)
		(end 115.25377 -233.63301)
		(width 0.1143)
		(layer "In13.Cu")
		(net "GMI_CPU0_G0_CPU1_G2_TX_DP<3>")
	)
	(segment
		(start 115.251738 -235.251752)
		(end 115.2525 -235.25226)
		(width 0.1143)
		(layer "In13.Cu")
		(net "GMI_CPU0_G0_CPU1_G2_TX_DP<3>")
	)
	(segment
		(start 115.255294 -240.11382)
		(end 115.256056 -240.114328)
		(width 0.1143)
		(layer "In13.Cu")
		(net "GMI_CPU0_G0_CPU1_G2_TX_DP<3>")
	)
	(segment
		(start 355.30409 -241.731546)
		(end 355.305106 -241.731038)
		(width 0.1143)
		(layer "In13.Cu")
		(net "GMI_CPU0_G0_CPU1_G2_TX_DP<3>")
	)
	(segment
		(start 356.243382 -227.796344)
		(end 356.242112 -227.795582)
		(width 0.1143)
		(layer "In13.Cu")
		(net "GMI_CPU0_G0_CPU1_G2_TX_DP<3>")
	)
	(segment
		(start 115.255294 -233.633772)
		(end 115.256056 -233.63428)
		(width 0.1143)
		(layer "In13.Cu")
		(net "GMI_CPU0_G0_CPU1_G2_TX_DP<3>")
	)
	(segment
		(start 115.212622 -223.889062)
		(end 115.21948 -223.893126)
		(width 0.1143)
		(layer "In13.Cu")
		(net "GMI_CPU0_G0_CPU1_G2_TX_DP<3>")
	)
	(segment
		(start 114.91087 -221.146116)
		(end 114.91087 -221.382336)
		(width 0.1143)
		(layer "In13.Cu")
		(net "GMI_CPU0_G0_CPU1_G2_TX_DP<3>")
	)
	(segment
		(start 115.251738 -238.491776)
		(end 115.2525 -238.492284)
		(width 0.1143)
		(layer "In13.Cu")
		(net "GMI_CPU0_G0_CPU1_G2_TX_DP<3>")
	)
	(segment
		(start 115.212622 -233.60888)
		(end 115.21948 -233.612944)
		(width 0.1143)
		(layer "In13.Cu")
		(net "GMI_CPU0_G0_CPU1_G2_TX_DP<3>")
	)
	(segment
		(start 115.212622 -236.848904)
		(end 115.21948 -236.852968)
		(width 0.1143)
		(layer "In13.Cu")
		(net "GMI_CPU0_G0_CPU1_G2_TX_DP<3>")
	)
	(segment
		(start 115.251738 -227.797106)
		(end 115.250722 -227.797614)
		(width 0.1143)
		(layer "In13.Cu")
		(net "GMI_CPU0_G0_CPU1_G2_TX_DP<3>")
	)
	(segment
		(start 116.661692 -242.541806)
		(end 116.693442 -242.560094)
		(width 0.1143)
		(layer "In13.Cu")
		(net "GMI_CPU0_G0_CPU1_G2_TX_DP<3>")
	)
	(segment
		(start 115.220242 -231.99344)
		(end 115.251738 -232.011728)
		(width 0.1143)
		(layer "In13.Cu")
		(net "GMI_CPU0_G0_CPU1_G2_TX_DP<3>")
	)
	(segment
		(start 115.250722 -226.177602)
		(end 115.249198 -226.178618)
		(width 0.1143)
		(layer "In13.Cu")
		(net "GMI_CPU0_G0_CPU1_G2_TX_DP<3>")
	)
	(segment
		(start 356.223316 -228.783642)
		(end 356.28326 -228.748844)
		(width 0.1143)
		(layer "In13.Cu")
		(net "GMI_CPU0_G0_CPU1_G2_TX_DP<3>")
	)
	(segment
		(start 115.212622 -228.749098)
		(end 115.21948 -228.753162)
		(width 0.1143)
		(layer "In13.Cu")
		(net "GMI_CPU0_G0_CPU1_G2_TX_DP<3>")
	)
	(segment
		(start 115.21948 -235.232956)
		(end 115.220242 -235.233464)
		(width 0.1143)
		(layer "In13.Cu")
		(net "GMI_CPU0_G0_CPU1_G2_TX_DP<3>")
	)
	(segment
		(start 115.251738 -232.011728)
		(end 115.2525 -232.012236)
		(width 0.1143)
		(layer "In13.Cu")
		(net "GMI_CPU0_G0_CPU1_G2_TX_DP<3>")
	)
	(segment
		(start 115.25758 -223.915224)
		(end 115.258342 -223.915732)
		(width 0.1143)
		(layer "In13.Cu")
		(net "GMI_CPU0_G0_CPU1_G2_TX_DP<3>")
	)
	(segment
		(start 115.256056 -236.874304)
		(end 115.25758 -236.875066)
		(width 0.1143)
		(layer "In13.Cu")
		(net "GMI_CPU0_G0_CPU1_G2_TX_DP<3>")
	)
	(segment
		(start 137.83564 -195.643754)
		(end 137.835132 -195.644008)
		(width 0.14224)
		(layer "In13.Cu")
		(net "GMI_CPU0_G0_CPU1_G2_TX_DP<3>")
	)
	(segment
		(start 115.220242 -236.853476)
		(end 115.251738 -236.871764)
		(width 0.1143)
		(layer "In13.Cu")
		(net "GMI_CPU0_G0_CPU1_G2_TX_DP<3>")
	)
	(segment
		(start 115.25377 -235.253022)
		(end 115.255294 -235.253784)
		(width 0.1143)
		(layer "In13.Cu")
		(net "GMI_CPU0_G0_CPU1_G2_TX_DP<3>")
	)
	(segment
		(start 116.192554 -241.732308)
		(end 116.197126 -241.734848)
		(width 0.1143)
		(layer "In13.Cu")
		(net "GMI_CPU0_G0_CPU1_G2_TX_DP<3>")
	)
	(segment
		(start 356.213156 -236.88929)
		(end 356.282752 -236.849158)
		(width 0.1143)
		(layer "In13.Cu")
		(net "GMI_CPU0_G0_CPU1_G2_TX_DP<3>")
	)
	(segment
		(start 115.2525 -228.772466)
		(end 115.25377 -228.773228)
		(width 0.1143)
		(layer "In13.Cu")
		(net "GMI_CPU0_G0_CPU1_G2_TX_DP<3>")
	)
	(segment
		(start 356.243382 -234.276138)
		(end 356.242112 -234.275376)
		(width 0.1143)
		(layer "In13.Cu")
		(net "GMI_CPU0_G0_CPU1_G2_TX_DP<3>")
	)
	(segment
		(start 115.259358 -236.876082)
		(end 115.283488 -236.890052)
		(width 0.1143)
		(layer "In13.Cu")
		(net "GMI_CPU0_G0_CPU1_G2_TX_DP<3>")
	)
	(segment
		(start 356.242112 -237.5154)
		(end 356.212394 -237.498382)
		(width 0.1143)
		(layer "In13.Cu")
		(net "GMI_CPU0_G0_CPU1_G2_TX_DP<3>")
	)
	(segment
		(start 115.283488 -227.778818)
		(end 115.2525 -227.796598)
		(width 0.1143)
		(layer "In13.Cu")
		(net "GMI_CPU0_G0_CPU1_G2_TX_DP<3>")
	)
	(segment
		(start 356.24516 -227.79736)
		(end 356.244144 -227.796852)
		(width 0.1143)
		(layer "In13.Cu")
		(net "GMI_CPU0_G0_CPU1_G2_TX_DP<3>")
	)
	(segment
		(start 356.244144 -239.136682)
		(end 356.243382 -239.136174)
		(width 0.1143)
		(layer "In13.Cu")
		(net "GMI_CPU0_G0_CPU1_G2_TX_DP<3>")
	)
	(segment
		(start 356.242112 -226.17557)
		(end 356.212394 -226.158552)
		(width 0.1143)
		(layer "In13.Cu")
		(net "GMI_CPU0_G0_CPU1_G2_TX_DP<3>")
	)
	(segment
		(start 116.186966 -241.728752)
		(end 116.190776 -241.731292)
		(width 0.1143)
		(layer "In13.Cu")
		(net "GMI_CPU0_G0_CPU1_G2_TX_DP<3>")
	)
	(segment
		(start 115.249198 -227.79863)
		(end 115.212622 -227.819966)
		(width 0.1143)
		(layer "In13.Cu")
		(net "GMI_CPU0_G0_CPU1_G2_TX_DP<3>")
	)
	(segment
		(start 356.243382 -232.656126)
		(end 356.242112 -232.655364)
		(width 0.1143)
		(layer "In13.Cu")
		(net "GMI_CPU0_G0_CPU1_G2_TX_DP<3>")
	)
	(segment
		(start 308.091586 -177.613056)
		(end 302.911256 -177.613056)
		(width 0.14224)
		(layer "In13.Cu")
		(net "GMI_CPU0_G0_CPU1_G2_TX_DP<3>")
	)
	(segment
		(start 115.251738 -224.557082)
		(end 115.250722 -224.55759)
		(width 0.1143)
		(layer "In13.Cu")
		(net "GMI_CPU0_G0_CPU1_G2_TX_DP<3>")
	)
	(segment
		(start 115.250722 -232.657396)
		(end 115.249198 -232.658412)
		(width 0.1143)
		(layer "In13.Cu")
		(net "GMI_CPU0_G0_CPU1_G2_TX_DP<3>")
	)
	(segment
		(start 115.250722 -227.797614)
		(end 115.249198 -227.79863)
		(width 0.1143)
		(layer "In13.Cu")
		(net "GMI_CPU0_G0_CPU1_G2_TX_DP<3>")
	)
	(segment
		(start 115.256056 -232.014268)
		(end 115.25758 -232.01503)
		(width 0.1143)
		(layer "In13.Cu")
		(net "GMI_CPU0_G0_CPU1_G2_TX_DP<3>")
	)
	(segment
		(start 356.24516 -234.277154)
		(end 356.244144 -234.276646)
		(width 0.1143)
		(layer "In13.Cu")
		(net "GMI_CPU0_G0_CPU1_G2_TX_DP<3>")
	)
	(segment
		(start 115.249198 -235.898436)
		(end 115.212622 -235.919772)
		(width 0.1143)
		(layer "In13.Cu")
		(net "GMI_CPU0_G0_CPU1_G2_TX_DP<3>")
	)
	(segment
		(start 356.24516 -226.177348)
		(end 356.244144 -226.17684)
		(width 0.1143)
		(layer "In13.Cu")
		(net "GMI_CPU0_G0_CPU1_G2_TX_DP<3>")
	)
	(segment
		(start 356.246684 -227.798376)
		(end 356.24516 -227.79736)
		(width 0.1143)
		(layer "In13.Cu")
		(net "GMI_CPU0_G0_CPU1_G2_TX_DP<3>")
	)
	(segment
		(start 356.28326 -237.53953)
		(end 356.246684 -237.518194)
		(width 0.1143)
		(layer "In13.Cu")
		(net "GMI_CPU0_G0_CPU1_G2_TX_DP<3>")
	)
	(segment
		(start 115.220242 -228.75367)
		(end 115.251738 -228.771958)
		(width 0.1143)
		(layer "In13.Cu")
		(net "GMI_CPU0_G0_CPU1_G2_TX_DP<3>")
	)
	(segment
		(start 115.909598 -241.244374)
		(end 115.909598 -241.246406)
		(width 0.1143)
		(layer "In13.Cu")
		(net "GMI_CPU0_G0_CPU1_G2_TX_DP<3>")
	)
	(segment
		(start 356.242112 -235.895388)
		(end 356.212394 -235.87837)
		(width 0.1143)
		(layer "In13.Cu")
		(net "GMI_CPU0_G0_CPU1_G2_TX_DP<3>")
	)
	(segment
		(start 352.91776 -211.486496)
		(end 317.38951 -182.354728)
		(width 0.14224)
		(layer "In13.Cu")
		(net "GMI_CPU0_G0_CPU1_G2_TX_DP<3>")
	)
	(segment
		(start 356.246684 -234.27817)
		(end 356.24516 -234.277154)
		(width 0.1143)
		(layer "In13.Cu")
		(net "GMI_CPU0_G0_CPU1_G2_TX_DP<3>")
	)
	(segment
		(start 115.251738 -236.871764)
		(end 115.2525 -236.872272)
		(width 0.1143)
		(layer "In13.Cu")
		(net "GMI_CPU0_G0_CPU1_G2_TX_DP<3>")
	)
	(segment
		(start 115.25377 -224.555812)
		(end 115.2525 -224.556574)
		(width 0.1143)
		(layer "In13.Cu")
		(net "GMI_CPU0_G0_CPU1_G2_TX_DP<3>")
	)
	(segment
		(start 115.250722 -222.937578)
		(end 115.212622 -222.95993)
		(width 0.1143)
		(layer "In13.Cu")
		(net "GMI_CPU0_G0_CPU1_G2_TX_DP<3>")
	)
	(segment
		(start 115.2525 -225.532442)
		(end 115.25377 -225.533204)
		(width 0.1143)
		(layer "In13.Cu")
		(net "GMI_CPU0_G0_CPU1_G2_TX_DP<3>")
	)
	(segment
		(start 356.246684 -227.150168)
		(end 356.28326 -227.128832)
		(width 0.1143)
		(layer "In13.Cu")
		(net "GMI_CPU0_G0_CPU1_G2_TX_DP<3>")
	)
	(segment
		(start 356.212394 -230.410004)
		(end 356.244144 -230.391716)
		(width 0.1143)
		(layer "In13.Cu")
		(net "GMI_CPU0_G0_CPU1_G2_TX_DP<3>")
	)
	(segment
		(start 356.28326 -229.43947)
		(end 356.210616 -229.397052)
		(width 0.1143)
		(layer "In13.Cu")
		(net "GMI_CPU0_G0_CPU1_G2_TX_DP<3>")
	)
	(segment
		(start 356.223316 -232.023412)
		(end 356.28326 -231.988614)
		(width 0.1143)
		(layer "In13.Cu")
		(net "GMI_CPU0_G0_CPU1_G2_TX_DP<3>")
	)
	(segment
		(start 114.86515 -221.100396)
		(end 114.91087 -221.146116)
		(width 0.1143)
		(layer "In13.Cu")
		(net "GMI_CPU0_G0_CPU1_G2_TX_DP<3>")
	)
	(segment
		(start 115.258342 -232.015538)
		(end 115.259358 -232.016046)
		(width 0.1143)
		(layer "In13.Cu")
		(net "GMI_CPU0_G0_CPU1_G2_TX_DP<3>")
	)
	(segment
		(start 356.212394 -233.649774)
		(end 356.228904 -233.640122)
		(width 0.1143)
		(layer "In13.Cu")
		(net "GMI_CPU0_G0_CPU1_G2_TX_DP<3>")
	)
	(segment
		(start 354.723192 -242.864132)
		(end 354.653342 -242.794282)
		(width 0.1143)
		(layer "In13.Cu")
		(net "GMI_CPU0_G0_CPU1_G2_TX_DP<3>")
	)
	(segment
		(start 356.24516 -235.897166)
		(end 356.244144 -235.896658)
		(width 0.1143)
		(layer "In13.Cu")
		(net "GMI_CPU0_G0_CPU1_G2_TX_DP<3>")
	)
	(segment
		(start 115.25758 -233.635042)
		(end 115.258342 -233.63555)
		(width 0.1143)
		(layer "In13.Cu")
		(net "GMI_CPU0_G0_CPU1_G2_TX_DP<3>")
	)
	(segment
		(start 114.969544 -221.44101)
		(end 114.969544 -221.804484)
		(width 0.1143)
		(layer "In13.Cu")
		(net "GMI_CPU0_G0_CPU1_G2_TX_DP<3>")
	)
	(segment
		(start 115.285266 -229.397306)
		(end 115.251738 -229.416864)
		(width 0.1143)
		(layer "In13.Cu")
		(net "GMI_CPU0_G0_CPU1_G2_TX_DP<3>")
	)
	(segment
		(start 115.2525 -239.136428)
		(end 115.251738 -239.136936)
		(width 0.1143)
		(layer "In13.Cu")
		(net "GMI_CPU0_G0_CPU1_G2_TX_DP<3>")
	)
	(segment
		(start 115.249198 -227.150422)
		(end 115.250722 -227.151438)
		(width 0.1143)
		(layer "In13.Cu")
		(net "GMI_CPU0_G0_CPU1_G2_TX_DP<3>")
	)
	(segment
		(start 115.251738 -231.036876)
		(end 115.212622 -231.059736)
		(width 0.1143)
		(layer "In13.Cu")
		(net "GMI_CPU0_G0_CPU1_G2_TX_DP<3>")
	)
	(segment
		(start 115.256056 -223.914462)
		(end 115.25758 -223.915224)
		(width 0.1143)
		(layer "In13.Cu")
		(net "GMI_CPU0_G0_CPU1_G2_TX_DP<3>")
	)
	(segment
		(start 115.249198 -239.13846)
		(end 115.212622 -239.159796)
		(width 0.1143)
		(layer "In13.Cu")
		(net "GMI_CPU0_G0_CPU1_G2_TX_DP<3>")
	)
	(segment
		(start 115.283488 -226.158806)
		(end 115.2525 -226.176586)
		(width 0.1143)
		(layer "In13.Cu")
		(net "GMI_CPU0_G0_CPU1_G2_TX_DP<3>")
	)
	(segment
		(start 356.244144 -235.896658)
		(end 356.243382 -235.89615)
		(width 0.1143)
		(layer "In13.Cu")
		(net "GMI_CPU0_G0_CPU1_G2_TX_DP<3>")
	)
	(segment
		(start 115.259358 -232.016046)
		(end 115.283488 -232.030016)
		(width 0.1143)
		(layer "In13.Cu")
		(net "GMI_CPU0_G0_CPU1_G2_TX_DP<3>")
	)
	(segment
		(start 356.243382 -237.516162)
		(end 356.242112 -237.5154)
		(width 0.1143)
		(layer "In13.Cu")
		(net "GMI_CPU0_G0_CPU1_G2_TX_DP<3>")
	)
	(segment
		(start 356.213664 -238.509048)
		(end 356.28326 -238.468662)
		(width 0.1143)
		(layer "In13.Cu")
		(net "GMI_CPU0_G0_CPU1_G2_TX_DP<3>")
	)
	(segment
		(start 356.212394 -235.269786)
		(end 356.224078 -235.27004)
		(width 0.1143)
		(layer "In13.Cu")
		(net "GMI_CPU0_G0_CPU1_G2_TX_DP<3>")
	)
	(segment
		(start 115.2525 -235.25226)
		(end 115.25377 -235.253022)
		(width 0.1143)
		(layer "In13.Cu")
		(net "GMI_CPU0_G0_CPU1_G2_TX_DP<3>")
	)
	(segment
		(start 356.242112 -227.795582)
		(end 356.212394 -227.778564)
		(width 0.1143)
		(layer "In13.Cu")
		(net "GMI_CPU0_G0_CPU1_G2_TX_DP<3>")
	)
	(segment
		(start 356.242112 -224.555558)
		(end 356.212394 -224.53854)
		(width 0.1143)
		(layer "In13.Cu")
		(net "GMI_CPU0_G0_CPU1_G2_TX_DP<3>")
	)
	(segment
		(start 356.212394 -238.50981)
		(end 356.213664 -238.509048)
		(width 0.1143)
		(layer "In13.Cu")
		(net "GMI_CPU0_G0_CPU1_G2_TX_DP<3>")
	)
	(segment
		(start 356.28326 -236.848904)
		(end 356.28326 -236.84865)
		(width 0.1143)
		(layer "In13.Cu")
		(net "GMI_CPU0_G0_CPU1_G2_TX_DP<3>")
	)
	(segment
		(start 356.24516 -224.557336)
		(end 356.244144 -224.556828)
		(width 0.1143)
		(layer "In13.Cu")
		(net "GMI_CPU0_G0_CPU1_G2_TX_DP<3>")
	)
	(segment
		(start 115.251738 -227.151946)
		(end 115.283488 -227.170234)
		(width 0.1143)
		(layer "In13.Cu")
		(net "GMI_CPU0_G0_CPU1_G2_TX_DP<3>")
	)
	(segment
		(start 115.256056 -240.114328)
		(end 115.25758 -240.11509)
		(width 0.1143)
		(layer "In13.Cu")
		(net "GMI_CPU0_G0_CPU1_G2_TX_DP<3>")
	)
	(segment
		(start 356.282752 -236.849158)
		(end 356.28326 -236.848904)
		(width 0.1143)
		(layer "In13.Cu")
		(net "GMI_CPU0_G0_CPU1_G2_TX_DP<3>")
	)
	(segment
		(start 115.2525 -222.936562)
		(end 115.251738 -222.93707)
		(width 0.1143)
		(layer "In13.Cu")
		(net "GMI_CPU0_G0_CPU1_G2_TX_DP<3>")
	)
	(segment
		(start 356.212394 -232.029762)
		(end 356.223316 -232.023412)
		(width 0.1143)
		(layer "In13.Cu")
		(net "GMI_CPU0_G0_CPU1_G2_TX_DP<3>")
	)
	(segment
		(start 115.251738 -239.136936)
		(end 115.250722 -239.137444)
		(width 0.1143)
		(layer "In13.Cu")
		(net "GMI_CPU0_G0_CPU1_G2_TX_DP<3>")
	)
	(segment
		(start 115.250722 -237.517432)
		(end 115.249198 -237.518448)
		(width 0.1143)
		(layer "In13.Cu")
		(net "GMI_CPU0_G0_CPU1_G2_TX_DP<3>")
	)
	(segment
		(start 356.24516 -239.13719)
		(end 356.244144 -239.136682)
		(width 0.1143)
		(layer "In13.Cu")
		(net "GMI_CPU0_G0_CPU1_G2_TX_DP<3>")
	)
	(segment
		(start 356.242112 -234.275376)
		(end 356.212394 -234.258358)
		(width 0.1143)
		(layer "In13.Cu")
		(net "GMI_CPU0_G0_CPU1_G2_TX_DP<3>")
	)
	(segment
		(start 115.258342 -225.535744)
		(end 115.259358 -225.536252)
		(width 0.1143)
		(layer "In13.Cu")
		(net "GMI_CPU0_G0_CPU1_G2_TX_DP<3>")
	)
	(segment
		(start 115.249198 -237.518448)
		(end 115.212622 -237.539784)
		(width 0.1143)
		(layer "In13.Cu")
		(net "GMI_CPU0_G0_CPU1_G2_TX_DP<3>")
	)
	(segment
		(start 116.143278 -241.702336)
		(end 116.15293 -241.709194)
		(width 0.1143)
		(layer "In13.Cu")
		(net "GMI_CPU0_G0_CPU1_G2_TX_DP<3>")
	)
	(segment
		(start 356.243382 -239.136174)
		(end 356.242112 -239.135412)
		(width 0.1143)
		(layer "In13.Cu")
		(net "GMI_CPU0_G0_CPU1_G2_TX_DP<3>")
	)
	(segment
		(start 116.77269 -242.864386)
		(end 116.474748 -242.864386)
		(width 0.1143)
		(layer "In13.Cu")
		(net "GMI_CPU0_G0_CPU1_G2_TX_DP<3>")
	)
	(segment
		(start 115.258342 -228.775768)
		(end 115.259358 -228.776276)
		(width 0.1143)
		(layer "In13.Cu")
		(net "GMI_CPU0_G0_CPU1_G2_TX_DP<3>")
	)
	(segment
		(start 115.259358 -233.636058)
		(end 115.283488 -233.650028)
		(width 0.1143)
		(layer "In13.Cu")
		(net "GMI_CPU0_G0_CPU1_G2_TX_DP<3>")
	)
	(segment
		(start 115.255294 -228.77399)
		(end 115.256056 -228.774498)
		(width 0.1143)
		(layer "In13.Cu")
		(net "GMI_CPU0_G0_CPU1_G2_TX_DP<3>")
	)
	(segment
		(start 115.251738 -228.771958)
		(end 115.2525 -228.772466)
		(width 0.1143)
		(layer "In13.Cu")
		(net "GMI_CPU0_G0_CPU1_G2_TX_DP<3>")
	)
	(segment
		(start 115.212622 -240.088928)
		(end 115.21948 -240.092992)
		(width 0.1143)
		(layer "In13.Cu")
		(net "GMI_CPU0_G0_CPU1_G2_TX_DP<3>")
	)
	(segment
		(start 115.212622 -225.509074)
		(end 115.21948 -225.513138)
		(width 0.1143)
		(layer "In13.Cu")
		(net "GMI_CPU0_G0_CPU1_G2_TX_DP<3>")
	)
	(segment
		(start 356.274624 -233.613706)
		(end 356.275386 -233.613198)
		(width 0.1143)
		(layer "In13.Cu")
		(net "GMI_CPU0_G0_CPU1_G2_TX_DP<3>")
	)
	(segment
		(start 115.25758 -225.535236)
		(end 115.258342 -225.535744)
		(width 0.1143)
		(layer "In13.Cu")
		(net "GMI_CPU0_G0_CPU1_G2_TX_DP<3>")
	)
	(segment
		(start 115.251738 -235.896912)
		(end 115.250722 -235.89742)
		(width 0.1143)
		(layer "In13.Cu")
		(net "GMI_CPU0_G0_CPU1_G2_TX_DP<3>")
	)
	(segment
		(start 115.251738 -226.177094)
		(end 115.250722 -226.177602)
		(width 0.1143)
		(layer "In13.Cu")
		(net "GMI_CPU0_G0_CPU1_G2_TX_DP<3>")
	)
	(segment
		(start 115.255294 -225.533966)
		(end 115.256056 -225.534474)
		(width 0.1143)
		(layer "In13.Cu")
		(net "GMI_CPU0_G0_CPU1_G2_TX_DP<3>")
	)
	(segment
		(start 356.242112 -232.655364)
		(end 356.212394 -232.638346)
		(width 0.1143)
		(layer "In13.Cu")
		(net "GMI_CPU0_G0_CPU1_G2_TX_DP<3>")
	)
	(segment
		(start 116.38534 -242.060222)
		(end 116.38534 -242.062)
		(width 0.1143)
		(layer "In13.Cu")
		(net "GMI_CPU0_G0_CPU1_G2_TX_DP<3>")
	)
	(segment
		(start 356.244144 -227.151692)
		(end 356.24516 -227.151184)
		(width 0.1143)
		(layer "In13.Cu")
		(net "GMI_CPU0_G0_CPU1_G2_TX_DP<3>")
	)
	(segment
		(start 115.255294 -232.01376)
		(end 115.256056 -232.014268)
		(width 0.1143)
		(layer "In13.Cu")
		(net "GMI_CPU0_G0_CPU1_G2_TX_DP<3>")
	)
	(segment
		(start 356.224078 -235.27004)
		(end 356.283006 -235.229146)
		(width 0.1143)
		(layer "In13.Cu")
		(net "GMI_CPU0_G0_CPU1_G2_TX_DP<3>")
	)
	(segment
		(start 115.25377 -232.012998)
		(end 115.255294 -232.01376)
		(width 0.1143)
		(layer "In13.Cu")
		(net "GMI_CPU0_G0_CPU1_G2_TX_DP<3>")
	)
	(segment
		(start 356.243382 -222.936308)
		(end 356.242112 -222.935546)
		(width 0.1143)
		(layer "In13.Cu")
		(net "GMI_CPU0_G0_CPU1_G2_TX_DP<3>")
	)
	(segment
		(start 115.2525 -238.492284)
		(end 115.25377 -238.493046)
		(width 0.1143)
		(layer "In13.Cu")
		(net "GMI_CPU0_G0_CPU1_G2_TX_DP<3>")
	)
	(segment
		(start 115.25377 -223.913192)
		(end 115.255294 -223.913954)
		(width 0.1143)
		(layer "In13.Cu")
		(net "GMI_CPU0_G0_CPU1_G2_TX_DP<3>")
	)
	(segment
		(start 115.212622 -231.988868)
		(end 115.21948 -231.992932)
		(width 0.1143)
		(layer "In13.Cu")
		(net "GMI_CPU0_G0_CPU1_G2_TX_DP<3>")
	)
	(segment
		(start 356.244144 -226.17684)
		(end 356.243382 -226.176332)
		(width 0.1143)
		(layer "In13.Cu")
		(net "GMI_CPU0_G0_CPU1_G2_TX_DP<3>")
	)
	(segment
		(start 157.228032 -179.742846)
		(end 137.83564 -195.643754)
		(width 0.14224)
		(layer "In13.Cu")
		(net "GMI_CPU0_G0_CPU1_G2_TX_DP<3>")
	)
	(segment
		(start 115.25377 -225.533204)
		(end 115.255294 -225.533966)
		(width 0.1143)
		(layer "In13.Cu")
		(net "GMI_CPU0_G0_CPU1_G2_TX_DP<3>")
	)
	(segment
		(start 355.74224 -240.940336)
		(end 355.813106 -240.89868)
		(width 0.1143)
		(layer "In13.Cu")
		(net "GMI_CPU0_G0_CPU1_G2_TX_DP<3>")
	)
	(segment
		(start 115.259358 -238.496094)
		(end 115.283488 -238.510064)
		(width 0.1143)
		(layer "In13.Cu")
		(net "GMI_CPU0_G0_CPU1_G2_TX_DP<3>")
	)
	(segment
		(start 356.244144 -232.656634)
		(end 356.243382 -232.656126)
		(width 0.1143)
		(layer "In13.Cu")
		(net "GMI_CPU0_G0_CPU1_G2_TX_DP<3>")
	)
	(segment
		(start 356.28326 -235.919518)
		(end 356.246684 -235.898182)
		(width 0.1143)
		(layer "In13.Cu")
		(net "GMI_CPU0_G0_CPU1_G2_TX_DP<3>")
	)
	(segment
		(start 356.244144 -237.51667)
		(end 356.243382 -237.516162)
		(width 0.1143)
		(layer "In13.Cu")
		(net "GMI_CPU0_G0_CPU1_G2_TX_DP<3>")
	)
	(segment
		(start 115.251738 -232.656888)
		(end 115.250722 -232.657396)
		(width 0.1143)
		(layer "In13.Cu")
		(net "GMI_CPU0_G0_CPU1_G2_TX_DP<3>")
	)
	(segment
		(start 115.255294 -238.493808)
		(end 115.256056 -238.494316)
		(width 0.1143)
		(layer "In13.Cu")
		(net "GMI_CPU0_G0_CPU1_G2_TX_DP<3>")
	)
	(segment
		(start 115.21948 -225.513138)
		(end 115.220242 -225.513646)
		(width 0.1143)
		(layer "In13.Cu")
		(net "GMI_CPU0_G0_CPU1_G2_TX_DP<3>")
	)
	(segment
		(start 114.86515 -221.071948)
		(end 114.86515 -221.100396)
		(width 0.1143)
		(layer "In13.Cu")
		(net "GMI_CPU0_G0_CPU1_G2_TX_DP<3>")
	)
	(segment
		(start 356.24516 -232.657142)
		(end 356.244144 -232.656634)
		(width 0.1143)
		(layer "In13.Cu")
		(net "GMI_CPU0_G0_CPU1_G2_TX_DP<3>")
	)
	(segment
		(start 356.244144 -227.796852)
		(end 356.243382 -227.796344)
		(width 0.1143)
		(layer "In13.Cu")
		(net "GMI_CPU0_G0_CPU1_G2_TX_DP<3>")
	)
	(segment
		(start 356.630732 -217.740738)
		(end 352.91776 -211.486496)
		(width 0.14224)
		(layer "In13.Cu")
		(net "GMI_CPU0_G0_CPU1_G2_TX_DP<3>")
	)
	(segment
		(start 115.2525 -235.896404)
		(end 115.251738 -235.896912)
		(width 0.1143)
		(layer "In13.Cu")
		(net "GMI_CPU0_G0_CPU1_G2_TX_DP<3>")
	)
	(segment
		(start 356.28326 -226.1997)
		(end 356.246684 -226.178364)
		(width 0.1143)
		(layer "In13.Cu")
		(net "GMI_CPU0_G0_CPU1_G2_TX_DP<3>")
	)
	(segment
		(start 115.25377 -228.773228)
		(end 115.255294 -228.77399)
		(width 0.1143)
		(layer "In13.Cu")
		(net "GMI_CPU0_G0_CPU1_G2_TX_DP<3>")
	)
	(segment
		(start 115.25377 -222.9358)
		(end 115.2525 -222.936562)
		(width 0.1143)
		(layer "In13.Cu")
		(net "GMI_CPU0_G0_CPU1_G2_TX_DP<3>")
	)
	(segment
		(start 115.283488 -222.918782)
		(end 115.25377 -222.9358)
		(width 0.1143)
		(layer "In13.Cu")
		(net "GMI_CPU0_G0_CPU1_G2_TX_DP<3>")
	)
	(segment
		(start 115.220242 -223.893634)
		(end 115.251738 -223.911922)
		(width 0.1143)
		(layer "In13.Cu")
		(net "GMI_CPU0_G0_CPU1_G2_TX_DP<3>")
	)
	(segment
		(start 356.212394 -225.549968)
		(end 356.215442 -225.54819)
		(width 0.1143)
		(layer "In13.Cu")
		(net "GMI_CPU0_G0_CPU1_G2_TX_DP<3>")
	)
	(segment
		(start 356.244144 -234.276646)
		(end 356.243382 -234.276138)
		(width 0.1143)
		(layer "In13.Cu")
		(net "GMI_CPU0_G0_CPU1_G2_TX_DP<3>")
	)
	(segment
		(start 115.25377 -240.113058)
		(end 115.255294 -240.11382)
		(width 0.1143)
		(layer "In13.Cu")
		(net "GMI_CPU0_G0_CPU1_G2_TX_DP<3>")
	)
	(segment
		(start 356.28326 -222.959676)
		(end 356.24516 -222.937324)
		(width 0.1143)
		(layer "In13.Cu")
		(net "GMI_CPU0_G0_CPU1_G2_TX_DP<3>")
	)
	(segment
		(start 356.246684 -235.898182)
		(end 356.24516 -235.897166)
		(width 0.1143)
		(layer "In13.Cu")
		(net "GMI_CPU0_G0_CPU1_G2_TX_DP<3>")
	)
	(segment
		(start 115.258342 -233.63555)
		(end 115.259358 -233.636058)
		(width 0.1143)
		(layer "In13.Cu")
		(net "GMI_CPU0_G0_CPU1_G2_TX_DP<3>")
	)
	(segment
		(start 115.2525 -240.112296)
		(end 115.25377 -240.113058)
		(width 0.1143)
		(layer "In13.Cu")
		(net "GMI_CPU0_G0_CPU1_G2_TX_DP<3>")
	)
	(segment
		(start 115.212622 -238.468916)
		(end 115.21948 -238.47298)
		(width 0.1143)
		(layer "In13.Cu")
		(net "GMI_CPU0_G0_CPU1_G2_TX_DP<3>")
	)
	(segment
		(start 356.244144 -230.391716)
		(end 356.28072 -230.37038)
		(width 0.1143)
		(layer "In13.Cu")
		(net "GMI_CPU0_G0_CPU1_G2_TX_DP<3>")
	)
	(segment
		(start 114.91087 -221.382336)
		(end 114.969544 -221.44101)
		(width 0.1143)
		(layer "In13.Cu")
		(net "GMI_CPU0_G0_CPU1_G2_TX_DP<3>")
	)
	(segment
		(start 115.250722 -224.55759)
		(end 115.212622 -224.579942)
		(width 0.1143)
		(layer "In13.Cu")
		(net "GMI_CPU0_G0_CPU1_G2_TX_DP<3>")
	)
	(segment
		(start 115.25758 -228.77526)
		(end 115.258342 -228.775768)
		(width 0.1143)
		(layer "In13.Cu")
		(net "GMI_CPU0_G0_CPU1_G2_TX_DP<3>")
	)
	(segment
		(start 356.212394 -236.890052)
		(end 356.213156 -236.88929)
		(width 0.1143)
		(layer "In13.Cu")
		(net "GMI_CPU0_G0_CPU1_G2_TX_DP<3>")
	)
	(segment
		(start 356.28326 -231.059482)
		(end 356.210616 -231.017064)
		(width 0.1143)
		(layer "In13.Cu")
		(net "GMI_CPU0_G0_CPU1_G2_TX_DP<3>")
	)
	(segment
		(start 115.256056 -225.534474)
		(end 115.25758 -225.535236)
		(width 0.1143)
		(layer "In13.Cu")
		(net "GMI_CPU0_G0_CPU1_G2_TX_DP<3>")
	)
	(segment
		(start 115.2525 -236.872272)
		(end 115.25377 -236.873034)
		(width 0.1143)
		(layer "In13.Cu")
		(net "GMI_CPU0_G0_CPU1_G2_TX_DP<3>")
	)
	(segment
		(start 115.255294 -235.253784)
		(end 115.256056 -235.254292)
		(width 0.1143)
		(layer "In13.Cu")
		(net "GMI_CPU0_G0_CPU1_G2_TX_DP<3>")
	)
	(segment
		(start 115.212622 -222.26905)
		(end 115.283488 -222.310198)
		(width 0.1143)
		(layer "In13.Cu")
		(net "GMI_CPU0_G0_CPU1_G2_TX_DP<3>")
	)
	(segment
		(start 356.275386 -223.89338)
		(end 356.28326 -223.888808)
		(width 0.1143)
		(layer "In13.Cu")
		(net "GMI_CPU0_G0_CPU1_G2_TX_DP<3>")
	)
	(segment
		(start 356.244144 -224.556828)
		(end 356.243382 -224.55632)
		(width 0.1143)
		(layer "In13.Cu")
		(net "GMI_CPU0_G0_CPU1_G2_TX_DP<3>")
	)
	(segment
		(start 115.25377 -233.63301)
		(end 115.255294 -233.633772)
		(width 0.1143)
		(layer "In13.Cu")
		(net "GMI_CPU0_G0_CPU1_G2_TX_DP<3>")
	)
	(segment
		(start 115.251738 -225.531934)
		(end 115.2525 -225.532442)
		(width 0.1143)
		(layer "In13.Cu")
		(net "GMI_CPU0_G0_CPU1_G2_TX_DP<3>")
	)
	(segment
		(start 356.228904 -233.640122)
		(end 356.274624 -233.613706)
		(width 0.1143)
		(layer "In13.Cu")
		(net "GMI_CPU0_G0_CPU1_G2_TX_DP<3>")
	)
	(segment
		(start 115.21948 -231.992932)
		(end 115.220242 -231.99344)
		(width 0.1143)
		(layer "In13.Cu")
		(net "GMI_CPU0_G0_CPU1_G2_TX_DP<3>")
	)
	(segment
		(start 356.212394 -240.129822)
		(end 356.226364 -240.121694)
		(width 0.1143)
		(layer "In13.Cu")
		(net "GMI_CPU0_G0_CPU1_G2_TX_DP<3>")
	)
	(segment
		(start 115.21948 -240.092992)
		(end 115.220242 -240.0935)
		(width 0.1143)
		(layer "In13.Cu")
		(net "GMI_CPU0_G0_CPU1_G2_TX_DP<3>")
	)
	(segment
		(start 115.259358 -228.776276)
		(end 115.283488 -228.790246)
		(width 0.1143)
		(layer "In13.Cu")
		(net "GMI_CPU0_G0_CPU1_G2_TX_DP<3>")
	)
	(segment
		(start 356.246684 -226.178364)
		(end 356.24516 -226.177348)
		(width 0.1143)
		(layer "In13.Cu")
		(net "GMI_CPU0_G0_CPU1_G2_TX_DP<3>")
	)
	(segment
		(start 355.305106 -241.731038)
		(end 355.308916 -241.728498)
		(width 0.1143)
		(layer "In13.Cu")
		(net "GMI_CPU0_G0_CPU1_G2_TX_DP<3>")
	)
	(segment
		(start 115.256056 -233.63428)
		(end 115.25758 -233.635042)
		(width 0.1143)
		(layer "In13.Cu")
		(net "GMI_CPU0_G0_CPU1_G2_TX_DP<3>")
	)
	(segment
		(start 115.251738 -223.911922)
		(end 115.2525 -223.91243)
		(width 0.1143)
		(layer "In13.Cu")
		(net "GMI_CPU0_G0_CPU1_G2_TX_DP<3>")
	)
	(segment
		(start 115.255294 -236.873796)
		(end 115.256056 -236.874304)
		(width 0.1143)
		(layer "In13.Cu")
		(net "GMI_CPU0_G0_CPU1_G2_TX_DP<3>")
	)
	(segment
		(start 356.24516 -227.151184)
		(end 356.246684 -227.150168)
		(width 0.1143)
		(layer "In13.Cu")
		(net "GMI_CPU0_G0_CPU1_G2_TX_DP<3>")
	)
	(segment
		(start 115.283488 -239.118648)
		(end 115.2525 -239.136428)
		(width 0.1143)
		(layer "In13.Cu")
		(net "GMI_CPU0_G0_CPU1_G2_TX_DP<3>")
	)
	(segment
		(start 356.28326 -239.159542)
		(end 356.246684 -239.138206)
		(width 0.1143)
		(layer "In13.Cu")
		(net "GMI_CPU0_G0_CPU1_G2_TX_DP<3>")
	)
	(segment
		(start 115.25377 -236.873034)
		(end 115.255294 -236.873796)
		(width 0.1143)
		(layer "In13.Cu")
		(net "GMI_CPU0_G0_CPU1_G2_TX_DP<3>")
	)
	(segment
		(start 115.258342 -240.115598)
		(end 115.259358 -240.116106)
		(width 0.1143)
		(layer "In13.Cu")
		(net "GMI_CPU0_G0_CPU1_G2_TX_DP<3>")
	)
	(arc
		(start 115.283488 -232.030016)
		(mid 115.439416 -232.334308)
		(end 115.283488 -232.6386)
		(width 0.1143)
		(layer "In13.Cu")
		(net "GMI_CPU0_G0_CPU1_G2_TX_DP<3>")
	)
	(arc
		(start 356.28326 -223.888808)
		(mid 356.526587 -223.424242)
		(end 356.28326 -222.959676)
		(width 0.1143)
		(layer "In13.Cu")
		(net "GMI_CPU0_G0_CPU1_G2_TX_DP<3>")
	)
	(arc
		(start 114.969544 -221.804484)
		(mid 115.033991 -222.066636)
		(end 115.212622 -222.26905)
		(width 0.1143)
		(layer "In13.Cu")
		(net "GMI_CPU0_G0_CPU1_G2_TX_DP<3>")
	)
	(arc
		(start 355.586284 -241.24412)
		(mid 355.627601 -241.073404)
		(end 355.74224 -240.940336)
		(width 0.1143)
		(layer "In13.Cu")
		(net "GMI_CPU0_G0_CPU1_G2_TX_DP<3>")
	)
	(arc
		(start 115.212622 -224.579942)
		(mid 114.969295 -225.044508)
		(end 115.212622 -225.509074)
		(width 0.1143)
		(layer "In13.Cu")
		(net "GMI_CPU0_G0_CPU1_G2_TX_DP<3>")
	)
	(arc
		(start 116.38534 -242.062)
		(mid 116.459365 -242.338855)
		(end 116.661692 -242.541806)
		(width 0.1143)
		(layer "In13.Cu")
		(net "GMI_CPU0_G0_CPU1_G2_TX_DP<3>")
	)
	(arc
		(start 115.283488 -235.27004)
		(mid 115.439416 -235.574332)
		(end 115.283488 -235.878624)
		(width 0.1143)
		(layer "In13.Cu")
		(net "GMI_CPU0_G0_CPU1_G2_TX_DP<3>")
	)
	(arc
		(start 356.212394 -224.53854)
		(mid 356.056466 -224.234248)
		(end 356.212394 -223.929956)
		(width 0.1143)
		(layer "In13.Cu")
		(net "GMI_CPU0_G0_CPU1_G2_TX_DP<3>")
	)
	(arc
		(start 115.753642 -240.94059)
		(mid 115.868261 -241.073668)
		(end 115.909598 -241.244374)
		(width 0.1143)
		(layer "In13.Cu")
		(net "GMI_CPU0_G0_CPU1_G2_TX_DP<3>")
	)
	(arc
		(start 356.212394 -237.498382)
		(mid 356.056466 -237.19409)
		(end 356.212394 -236.889798)
		(width 0.1143)
		(layer "In13.Cu")
		(net "GMI_CPU0_G0_CPU1_G2_TX_DP<3>")
	)
	(arc
		(start 115.283488 -228.790246)
		(mid 115.398164 -228.92358)
		(end 115.439444 -229.094538)
		(width 0.1143)
		(layer "In13.Cu")
		(net "GMI_CPU0_G0_CPU1_G2_TX_DP<3>")
	)
	(arc
		(start 356.28326 -225.50882)
		(mid 356.526587 -225.044254)
		(end 356.28326 -224.579688)
		(width 0.1143)
		(layer "In13.Cu")
		(net "GMI_CPU0_G0_CPU1_G2_TX_DP<3>")
	)
	(arc
		(start 115.439444 -230.71455)
		(mid 115.398682 -230.884434)
		(end 115.285266 -231.017318)
		(width 0.1143)
		(layer "In13.Cu")
		(net "GMI_CPU0_G0_CPU1_G2_TX_DP<3>")
	)
	(arc
		(start 115.283488 -223.93021)
		(mid 115.439416 -224.234502)
		(end 115.283488 -224.538794)
		(width 0.1143)
		(layer "In13.Cu")
		(net "GMI_CPU0_G0_CPU1_G2_TX_DP<3>")
	)
	(arc
		(start 356.212394 -235.87837)
		(mid 356.056466 -235.574078)
		(end 356.212394 -235.269786)
		(width 0.1143)
		(layer "In13.Cu")
		(net "GMI_CPU0_G0_CPU1_G2_TX_DP<3>")
	)
	(arc
		(start 115.283488 -240.130076)
		(mid 115.398164 -240.26341)
		(end 115.439444 -240.434368)
		(width 0.1143)
		(layer "In13.Cu")
		(net "GMI_CPU0_G0_CPU1_G2_TX_DP<3>")
	)
	(arc
		(start 356.28326 -222.268796)
		(mid 356.461918 -222.066396)
		(end 356.526338 -221.80423)
		(width 0.1143)
		(layer "In13.Cu")
		(net "GMI_CPU0_G0_CPU1_G2_TX_DP<3>")
	)
	(arc
		(start 356.28326 -228.748844)
		(mid 356.526587 -228.284278)
		(end 356.28326 -227.819712)
		(width 0.1143)
		(layer "In13.Cu")
		(net "GMI_CPU0_G0_CPU1_G2_TX_DP<3>")
	)
	(arc
		(start 356.28326 -238.468662)
		(mid 356.526587 -238.004096)
		(end 356.28326 -237.53953)
		(width 0.1143)
		(layer "In13.Cu")
		(net "GMI_CPU0_G0_CPU1_G2_TX_DP<3>")
	)
	(arc
		(start 115.283488 -233.650028)
		(mid 115.439416 -233.95432)
		(end 115.283488 -234.258612)
		(width 0.1143)
		(layer "In13.Cu")
		(net "GMI_CPU0_G0_CPU1_G2_TX_DP<3>")
	)
	(arc
		(start 356.526592 -229.904036)
		(mid 356.462077 -229.641817)
		(end 356.28326 -229.43947)
		(width 0.1143)
		(layer "In13.Cu")
		(net "GMI_CPU0_G0_CPU1_G2_TX_DP<3>")
	)
	(arc
		(start 115.283488 -225.550222)
		(mid 115.439416 -225.854514)
		(end 115.283488 -226.158806)
		(width 0.1143)
		(layer "In13.Cu")
		(net "GMI_CPU0_G0_CPU1_G2_TX_DP<3>")
	)
	(arc
		(start 115.212622 -226.199954)
		(mid 114.969295 -226.66452)
		(end 115.212622 -227.129086)
		(width 0.1143)
		(layer "In13.Cu")
		(net "GMI_CPU0_G0_CPU1_G2_TX_DP<3>")
	)
	(arc
		(start 356.28326 -240.088674)
		(mid 356.526587 -239.624108)
		(end 356.28326 -239.159542)
		(width 0.1143)
		(layer "In13.Cu")
		(net "GMI_CPU0_G0_CPU1_G2_TX_DP<3>")
	)
	(arc
		(start 355.813106 -240.89868)
		(mid 355.991919 -240.69633)
		(end 356.056438 -240.434114)
		(width 0.1143)
		(layer "In13.Cu")
		(net "GMI_CPU0_G0_CPU1_G2_TX_DP<3>")
	)
	(arc
		(start 355.110542 -242.059968)
		(mid 355.160927 -241.87199)
		(end 355.298756 -241.734594)
		(width 0.1143)
		(layer "In13.Cu")
		(net "GMI_CPU0_G0_CPU1_G2_TX_DP<3>")
	)
	(arc
		(start 115.909598 -241.246406)
		(mid 115.971423 -241.502567)
		(end 116.143278 -241.702336)
		(width 0.1143)
		(layer "In13.Cu")
		(net "GMI_CPU0_G0_CPU1_G2_TX_DP<3>")
	)
	(arc
		(start 115.283488 -222.310198)
		(mid 115.439416 -222.61449)
		(end 115.283488 -222.918782)
		(width 0.1143)
		(layer "In13.Cu")
		(net "GMI_CPU0_G0_CPU1_G2_TX_DP<3>")
	)
	(arc
		(start 115.212622 -231.059736)
		(mid 114.969295 -231.524302)
		(end 115.212622 -231.988868)
		(width 0.1143)
		(layer "In13.Cu")
		(net "GMI_CPU0_G0_CPU1_G2_TX_DP<3>")
	)
	(arc
		(start 115.212622 -222.95993)
		(mid 114.969295 -223.424496)
		(end 115.212622 -223.889062)
		(width 0.1143)
		(layer "In13.Cu")
		(net "GMI_CPU0_G0_CPU1_G2_TX_DP<3>")
	)
	(arc
		(start 356.210616 -229.397052)
		(mid 356.097209 -229.264163)
		(end 356.056438 -229.094284)
		(width 0.1143)
		(layer "In13.Cu")
		(net "GMI_CPU0_G0_CPU1_G2_TX_DP<3>")
	)
	(arc
		(start 355.352604 -241.702082)
		(mid 355.524469 -241.502318)
		(end 355.586284 -241.246152)
		(width 0.1143)
		(layer "In13.Cu")
		(net "GMI_CPU0_G0_CPU1_G2_TX_DP<3>")
	)
	(arc
		(start 116.197126 -241.734848)
		(mid 116.334959 -241.872242)
		(end 116.38534 -242.060222)
		(width 0.1143)
		(layer "In13.Cu")
		(net "GMI_CPU0_G0_CPU1_G2_TX_DP<3>")
	)
	(arc
		(start 116.693442 -242.560094)
		(mid 116.790577 -242.662963)
		(end 116.84254 -242.794536)
		(width 0.1143)
		(layer "In13.Cu")
		(net "GMI_CPU0_G0_CPU1_G2_TX_DP<3>")
	)
	(arc
		(start 115.212622 -239.159796)
		(mid 114.969295 -239.624362)
		(end 115.212622 -240.088928)
		(width 0.1143)
		(layer "In13.Cu")
		(net "GMI_CPU0_G0_CPU1_G2_TX_DP<3>")
	)
	(arc
		(start 356.212394 -239.118394)
		(mid 356.056466 -238.814102)
		(end 356.212394 -238.50981)
		(width 0.1143)
		(layer "In13.Cu")
		(net "GMI_CPU0_G0_CPU1_G2_TX_DP<3>")
	)
	(arc
		(start 115.283488 -238.510064)
		(mid 115.439416 -238.814356)
		(end 115.283488 -239.118648)
		(width 0.1143)
		(layer "In13.Cu")
		(net "GMI_CPU0_G0_CPU1_G2_TX_DP<3>")
	)
	(arc
		(start 356.212394 -227.778564)
		(mid 356.056466 -227.474272)
		(end 356.212394 -227.16998)
		(width 0.1143)
		(layer "In13.Cu")
		(net "GMI_CPU0_G0_CPU1_G2_TX_DP<3>")
	)
	(arc
		(start 356.056438 -230.714296)
		(mid 356.097693 -230.543325)
		(end 356.212394 -230.410004)
		(width 0.1143)
		(layer "In13.Cu")
		(net "GMI_CPU0_G0_CPU1_G2_TX_DP<3>")
	)
	(arc
		(start 356.28326 -236.84865)
		(mid 356.526587 -236.384084)
		(end 356.28326 -235.919518)
		(width 0.1143)
		(layer "In13.Cu")
		(net "GMI_CPU0_G0_CPU1_G2_TX_DP<3>")
	)
	(arc
		(start 356.210616 -231.017064)
		(mid 356.097209 -230.884175)
		(end 356.056438 -230.714296)
		(width 0.1143)
		(layer "In13.Cu")
		(net "GMI_CPU0_G0_CPU1_G2_TX_DP<3>")
	)
	(arc
		(start 115.439444 -229.094538)
		(mid 115.398682 -229.264422)
		(end 115.285266 -229.397306)
		(width 0.1143)
		(layer "In13.Cu")
		(net "GMI_CPU0_G0_CPU1_G2_TX_DP<3>")
	)
	(arc
		(start 356.212394 -232.638346)
		(mid 356.056466 -232.334054)
		(end 356.212394 -232.029762)
		(width 0.1143)
		(layer "In13.Cu")
		(net "GMI_CPU0_G0_CPU1_G2_TX_DP<3>")
	)
	(arc
		(start 356.056438 -240.434114)
		(mid 356.097693 -240.263143)
		(end 356.212394 -240.129822)
		(width 0.1143)
		(layer "In13.Cu")
		(net "GMI_CPU0_G0_CPU1_G2_TX_DP<3>")
	)
	(arc
		(start 356.212394 -222.918528)
		(mid 356.056466 -222.614236)
		(end 356.212394 -222.309944)
		(width 0.1143)
		(layer "In13.Cu")
		(net "GMI_CPU0_G0_CPU1_G2_TX_DP<3>")
	)
	(arc
		(start 115.283488 -236.890052)
		(mid 115.439416 -237.194344)
		(end 115.283488 -237.498636)
		(width 0.1143)
		(layer "In13.Cu")
		(net "GMI_CPU0_G0_CPU1_G2_TX_DP<3>")
	)
	(arc
		(start 356.212394 -226.158552)
		(mid 356.056466 -225.85426)
		(end 356.212394 -225.549968)
		(width 0.1143)
		(layer "In13.Cu")
		(net "GMI_CPU0_G0_CPU1_G2_TX_DP<3>")
	)
	(arc
		(start 115.212622 -235.919772)
		(mid 114.969295 -236.384338)
		(end 115.212622 -236.848904)
		(width 0.1143)
		(layer "In13.Cu")
		(net "GMI_CPU0_G0_CPU1_G2_TX_DP<3>")
	)
	(arc
		(start 356.28326 -227.128832)
		(mid 356.526587 -226.664266)
		(end 356.28326 -226.1997)
		(width 0.1143)
		(layer "In13.Cu")
		(net "GMI_CPU0_G0_CPU1_G2_TX_DP<3>")
	)
	(arc
		(start 115.439444 -240.434368)
		(mid 115.503959 -240.696587)
		(end 115.682776 -240.898934)
		(width 0.1143)
		(layer "In13.Cu")
		(net "GMI_CPU0_G0_CPU1_G2_TX_DP<3>")
	)
	(arc
		(start 354.653342 -242.794282)
		(mid 354.705391 -242.662763)
		(end 354.80244 -242.55984)
		(width 0.1143)
		(layer "In13.Cu")
		(net "GMI_CPU0_G0_CPU1_G2_TX_DP<3>")
	)
	(arc
		(start 356.056438 -229.094284)
		(mid 356.097693 -228.923313)
		(end 356.212394 -228.789992)
		(width 0.1143)
		(layer "In13.Cu")
		(net "GMI_CPU0_G0_CPU1_G2_TX_DP<3>")
	)
	(arc
		(start 114.96929 -229.90429)
		(mid 115.034526 -230.167881)
		(end 115.215162 -230.370634)
		(width 0.1143)
		(layer "In13.Cu")
		(net "GMI_CPU0_G0_CPU1_G2_TX_DP<3>")
	)
	(arc
		(start 356.28326 -231.988614)
		(mid 356.526587 -231.524048)
		(end 356.28326 -231.059482)
		(width 0.1143)
		(layer "In13.Cu")
		(net "GMI_CPU0_G0_CPU1_G2_TX_DP<3>")
	)
	(arc
		(start 354.83419 -242.541552)
		(mid 355.036501 -242.338592)
		(end 355.110542 -242.061746)
		(width 0.1143)
		(layer "In13.Cu")
		(net "GMI_CPU0_G0_CPU1_G2_TX_DP<3>")
	)
	(arc
		(start 115.212622 -234.29976)
		(mid 114.969295 -234.764326)
		(end 115.212622 -235.228892)
		(width 0.1143)
		(layer "In13.Cu")
		(net "GMI_CPU0_G0_CPU1_G2_TX_DP<3>")
	)
	(arc
		(start 356.28326 -235.228638)
		(mid 356.526587 -234.764072)
		(end 356.28326 -234.299506)
		(width 0.1143)
		(layer "In13.Cu")
		(net "GMI_CPU0_G0_CPU1_G2_TX_DP<3>")
	)
	(arc
		(start 356.28326 -233.608626)
		(mid 356.526587 -233.14406)
		(end 356.28326 -232.679494)
		(width 0.1143)
		(layer "In13.Cu")
		(net "GMI_CPU0_G0_CPU1_G2_TX_DP<3>")
	)
	(arc
		(start 115.212622 -232.679748)
		(mid 114.969295 -233.144314)
		(end 115.212622 -233.60888)
		(width 0.1143)
		(layer "In13.Cu")
		(net "GMI_CPU0_G0_CPU1_G2_TX_DP<3>")
	)
	(arc
		(start 115.283488 -230.410258)
		(mid 115.398164 -230.543592)
		(end 115.439444 -230.71455)
		(width 0.1143)
		(layer "In13.Cu")
		(net "GMI_CPU0_G0_CPU1_G2_TX_DP<3>")
	)
	(arc
		(start 115.212622 -237.539784)
		(mid 114.969295 -238.00435)
		(end 115.212622 -238.468916)
		(width 0.1143)
		(layer "In13.Cu")
		(net "GMI_CPU0_G0_CPU1_G2_TX_DP<3>")
	)
	(arc
		(start 115.212622 -227.819966)
		(mid 114.969295 -228.284532)
		(end 115.212622 -228.749098)
		(width 0.1143)
		(layer "In13.Cu")
		(net "GMI_CPU0_G0_CPU1_G2_TX_DP<3>")
	)
	(arc
		(start 115.283488 -227.170234)
		(mid 115.439416 -227.474526)
		(end 115.283488 -227.778818)
		(width 0.1143)
		(layer "In13.Cu")
		(net "GMI_CPU0_G0_CPU1_G2_TX_DP<3>")
	)
	(arc
		(start 115.212622 -229.439724)
		(mid 115.033809 -229.642074)
		(end 114.96929 -229.90429)
		(width 0.1143)
		(layer "In13.Cu")
		(net "GMI_CPU0_G0_CPU1_G2_TX_DP<3>")
	)
	(arc
		(start 356.212394 -234.258358)
		(mid 356.056466 -233.954066)
		(end 356.212394 -233.649774)
		(width 0.1143)
		(layer "In13.Cu")
		(net "GMI_CPU0_G0_CPU1_G2_TX_DP<3>")
	)
	(arc
		(start 356.28072 -230.37038)
		(mid 356.461372 -230.167635)
		(end 356.526592 -229.904036)
		(width 0.1143)
		(layer "In13.Cu")
		(net "GMI_CPU0_G0_CPU1_G2_TX_DP<3>")
	)
	(segment
		(start 113.657888 -239.080294)
		(end 114.12474 -238.814356)
		(width 0.12954)
		(layer "F.Cu")
		(net "GMI_CPU0_G0_CPU1_G2_TX_DP<2>")
	)
	(segment
		(start 357.837994 -239.08004)
		(end 357.371142 -238.814102)
		(width 0.12954)
		(layer "F.Cu")
		(net "GMI_CPU0_G0_CPU1_G2_TX_DP<2>")
	)
	(segment
		(start 357.18242 -233.632502)
		(end 357.183436 -233.631994)
		(width 0.1143)
		(layer "In13.Cu")
		(net "GMI_CPU0_G0_CPU1_G2_TX_DP<2>")
	)
	(segment
		(start 357.180642 -235.25353)
		(end 357.181658 -235.253022)
		(width 0.1143)
		(layer "In13.Cu")
		(net "GMI_CPU0_G0_CPU1_G2_TX_DP<2>")
	)
	(segment
		(start 114.31143 -235.251752)
		(end 114.311684 -235.251752)
		(width 0.1143)
		(layer "In13.Cu")
		(net "GMI_CPU0_G0_CPU1_G2_TX_DP<2>")
	)
	(segment
		(start 357.178102 -232.01503)
		(end 357.178864 -232.014522)
		(width 0.1143)
		(layer "In13.Cu")
		(net "GMI_CPU0_G0_CPU1_G2_TX_DP<2>")
	)
	(segment
		(start 114.316002 -228.774498)
		(end 114.317018 -228.775006)
		(width 0.1143)
		(layer "In13.Cu")
		(net "GMI_CPU0_G0_CPU1_G2_TX_DP<2>")
	)
	(segment
		(start 317.807848 -181.489858)
		(end 310.765952 -177.503582)
		(width 0.14224)
		(layer "In13.Cu")
		(net "GMI_CPU0_G0_CPU1_G2_TX_DP<2>")
	)
	(segment
		(start 357.184198 -226.17684)
		(end 357.163116 -226.164648)
		(width 0.1143)
		(layer "In13.Cu")
		(net "GMI_CPU0_G0_CPU1_G2_TX_DP<2>")
	)
	(segment
		(start 357.184198 -231.036622)
		(end 357.15067 -231.017064)
		(width 0.1143)
		(layer "In13.Cu")
		(net "GMI_CPU0_G0_CPU1_G2_TX_DP<2>")
	)
	(segment
		(start 114.31397 -236.873034)
		(end 114.343434 -236.890052)
		(width 0.1143)
		(layer "In13.Cu")
		(net "GMI_CPU0_G0_CPU1_G2_TX_DP<2>")
	)
	(segment
		(start 114.31524 -227.153978)
		(end 114.316002 -227.154486)
		(width 0.1143)
		(layer "In13.Cu")
		(net "GMI_CPU0_G0_CPU1_G2_TX_DP<2>")
	)
	(segment
		(start 357.184452 -222.93707)
		(end 357.184198 -222.936816)
		(width 0.1143)
		(layer "In13.Cu")
		(net "GMI_CPU0_G0_CPU1_G2_TX_DP<2>")
	)
	(segment
		(start 114.334036 -222.924116)
		(end 114.311684 -222.93707)
		(width 0.1143)
		(layer "In13.Cu")
		(net "GMI_CPU0_G0_CPU1_G2_TX_DP<2>")
	)
	(segment
		(start 357.216456 -222.27286)
		(end 357.223314 -222.268796)
		(width 0.1143)
		(layer "In13.Cu")
		(net "GMI_CPU0_G0_CPU1_G2_TX_DP<2>")
	)
	(segment
		(start 357.251 -235.93933)
		(end 357.223314 -235.919264)
		(width 0.1143)
		(layer "In13.Cu")
		(net "GMI_CPU0_G0_CPU1_G2_TX_DP<2>")
	)
	(segment
		(start 114.31905 -232.016046)
		(end 114.343434 -232.030016)
		(width 0.1143)
		(layer "In13.Cu")
		(net "GMI_CPU0_G0_CPU1_G2_TX_DP<2>")
	)
	(segment
		(start 357.163116 -234.264454)
		(end 357.162354 -234.263946)
		(width 0.1143)
		(layer "In13.Cu")
		(net "GMI_CPU0_G0_CPU1_G2_TX_DP<2>")
	)
	(segment
		(start 114.313462 -227.152962)
		(end 114.314224 -227.15347)
		(width 0.1143)
		(layer "In13.Cu")
		(net "GMI_CPU0_G0_CPU1_G2_TX_DP<2>")
	)
	(segment
		(start 114.311684 -229.416864)
		(end 114.275362 -229.437946)
		(width 0.1143)
		(layer "In13.Cu")
		(net "GMI_CPU0_G0_CPU1_G2_TX_DP<2>")
	)
	(segment
		(start 357.181658 -227.153216)
		(end 357.18242 -227.152708)
		(width 0.1143)
		(layer "In13.Cu")
		(net "GMI_CPU0_G0_CPU1_G2_TX_DP<2>")
	)
	(segment
		(start 357.181658 -228.773228)
		(end 357.18242 -228.77272)
		(width 0.1143)
		(layer "In13.Cu")
		(net "GMI_CPU0_G0_CPU1_G2_TX_DP<2>")
	)
	(segment
		(start 357.178864 -232.014522)
		(end 357.17988 -232.014014)
		(width 0.1143)
		(layer "In13.Cu")
		(net "GMI_CPU0_G0_CPU1_G2_TX_DP<2>")
	)
	(segment
		(start 357.178102 -233.635042)
		(end 357.178864 -233.634534)
		(width 0.1143)
		(layer "In13.Cu")
		(net "GMI_CPU0_G0_CPU1_G2_TX_DP<2>")
	)
	(segment
		(start 357.163116 -227.78466)
		(end 357.162354 -227.784152)
		(width 0.1143)
		(layer "In13.Cu")
		(net "GMI_CPU0_G0_CPU1_G2_TX_DP<2>")
	)
	(segment
		(start 137.103104 -195.03263)
		(end 117.430042 -211.163662)
		(width 0.14224)
		(layer "In13.Cu")
		(net "GMI_CPU0_G0_CPU1_G2_TX_DP<2>")
	)
	(segment
		(start 357.178102 -228.77526)
		(end 357.178864 -228.774752)
		(width 0.1143)
		(layer "In13.Cu")
		(net "GMI_CPU0_G0_CPU1_G2_TX_DP<2>")
	)
	(segment
		(start 357.529892 -221.382082)
		(end 357.529892 -221.145862)
		(width 0.1143)
		(layer "In13.Cu")
		(net "GMI_CPU0_G0_CPU1_G2_TX_DP<2>")
	)
	(segment
		(start 114.311684 -232.656888)
		(end 114.31143 -232.657142)
		(width 0.1143)
		(layer "In13.Cu")
		(net "GMI_CPU0_G0_CPU1_G2_TX_DP<2>")
	)
	(segment
		(start 113.92027 -217.144346)
		(end 113.92027 -221.071948)
		(width 0.14224)
		(layer "In13.Cu")
		(net "GMI_CPU0_G0_CPU1_G2_TX_DP<2>")
	)
	(segment
		(start 357.163116 -224.544636)
		(end 357.162354 -224.544128)
		(width 0.1143)
		(layer "In13.Cu")
		(net "GMI_CPU0_G0_CPU1_G2_TX_DP<2>")
	)
	(segment
		(start 114.31778 -228.775514)
		(end 114.31905 -228.776276)
		(width 0.1143)
		(layer "In13.Cu")
		(net "GMI_CPU0_G0_CPU1_G2_TX_DP<2>")
	)
	(segment
		(start 357.184452 -227.797106)
		(end 357.184198 -227.796852)
		(width 0.1143)
		(layer "In13.Cu")
		(net "GMI_CPU0_G0_CPU1_G2_TX_DP<2>")
	)
	(segment
		(start 114.310668 -222.291402)
		(end 114.3127 -222.292418)
		(width 0.1143)
		(layer "In13.Cu")
		(net "GMI_CPU0_G0_CPU1_G2_TX_DP<2>")
	)
	(segment
		(start 357.22052 -229.437692)
		(end 357.184198 -229.41661)
		(width 0.1143)
		(layer "In13.Cu")
		(net "GMI_CPU0_G0_CPU1_G2_TX_DP<2>")
	)
	(segment
		(start 114.314224 -228.773482)
		(end 114.31524 -228.77399)
		(width 0.1143)
		(layer "In13.Cu")
		(net "GMI_CPU0_G0_CPU1_G2_TX_DP<2>")
	)
	(segment
		(start 113.96599 -221.146116)
		(end 113.96599 -221.382336)
		(width 0.1143)
		(layer "In13.Cu")
		(net "GMI_CPU0_G0_CPU1_G2_TX_DP<2>")
	)
	(segment
		(start 114.31143 -233.63174)
		(end 114.311684 -233.63174)
		(width 0.1143)
		(layer "In13.Cu")
		(net "GMI_CPU0_G0_CPU1_G2_TX_DP<2>")
	)
	(segment
		(start 114.317018 -227.154994)
		(end 114.31778 -227.155502)
		(width 0.1143)
		(layer "In13.Cu")
		(net "GMI_CPU0_G0_CPU1_G2_TX_DP<2>")
	)
	(segment
		(start 357.184452 -234.2769)
		(end 357.184198 -234.276646)
		(width 0.1143)
		(layer "In13.Cu")
		(net "GMI_CPU0_G0_CPU1_G2_TX_DP<2>")
	)
	(segment
		(start 357.183436 -227.1522)
		(end 357.184198 -227.151692)
		(width 0.1143)
		(layer "In13.Cu")
		(net "GMI_CPU0_G0_CPU1_G2_TX_DP<2>")
	)
	(segment
		(start 310.765952 -177.503582)
		(end 308.443884 -176.673256)
		(width 0.14224)
		(layer "In13.Cu")
		(net "GMI_CPU0_G0_CPU1_G2_TX_DP<2>")
	)
	(segment
		(start 357.178864 -228.774752)
		(end 357.17988 -228.774244)
		(width 0.1143)
		(layer "In13.Cu")
		(net "GMI_CPU0_G0_CPU1_G2_TX_DP<2>")
	)
	(segment
		(start 114.343434 -232.6386)
		(end 114.333528 -232.644188)
		(width 0.1143)
		(layer "In13.Cu")
		(net "GMI_CPU0_G0_CPU1_G2_TX_DP<2>")
	)
	(segment
		(start 114.31524 -232.01376)
		(end 114.316002 -232.014268)
		(width 0.1143)
		(layer "In13.Cu")
		(net "GMI_CPU0_G0_CPU1_G2_TX_DP<2>")
	)
	(segment
		(start 357.181658 -232.012998)
		(end 357.18242 -232.01249)
		(width 0.1143)
		(layer "In13.Cu")
		(net "GMI_CPU0_G0_CPU1_G2_TX_DP<2>")
	)
	(segment
		(start 114.314224 -235.253276)
		(end 114.31524 -235.253784)
		(width 0.1143)
		(layer "In13.Cu")
		(net "GMI_CPU0_G0_CPU1_G2_TX_DP<2>")
	)
	(segment
		(start 114.311684 -233.63174)
		(end 114.312446 -233.632248)
		(width 0.1143)
		(layer "In13.Cu")
		(net "GMI_CPU0_G0_CPU1_G2_TX_DP<2>")
	)
	(segment
		(start 114.422682 -238.814356)
		(end 114.12474 -238.814356)
		(width 0.1143)
		(layer "In13.Cu")
		(net "GMI_CPU0_G0_CPU1_G2_TX_DP<2>")
	)
	(segment
		(start 357.180642 -236.873542)
		(end 357.181912 -236.87278)
		(width 0.1143)
		(layer "In13.Cu")
		(net "GMI_CPU0_G0_CPU1_G2_TX_DP<2>")
	)
	(segment
		(start 357.181658 -233.63301)
		(end 357.18242 -233.632502)
		(width 0.1143)
		(layer "In13.Cu")
		(net "GMI_CPU0_G0_CPU1_G2_TX_DP<2>")
	)
	(segment
		(start 357.575612 -221.093538)
		(end 357.575612 -217.241882)
		(width 0.14224)
		(layer "In13.Cu")
		(net "GMI_CPU0_G0_CPU1_G2_TX_DP<2>")
	)
	(segment
		(start 114.343434 -226.158806)
		(end 114.333528 -226.164394)
		(width 0.1143)
		(layer "In13.Cu")
		(net "GMI_CPU0_G0_CPU1_G2_TX_DP<2>")
	)
	(segment
		(start 114.244882 -236.829092)
		(end 114.272822 -236.849158)
		(width 0.1143)
		(layer "In13.Cu")
		(net "GMI_CPU0_G0_CPU1_G2_TX_DP<2>")
	)
	(segment
		(start 357.178864 -227.15474)
		(end 357.17988 -227.154232)
		(width 0.1143)
		(layer "In13.Cu")
		(net "GMI_CPU0_G0_CPU1_G2_TX_DP<2>")
	)
	(segment
		(start 357.184198 -229.41661)
		(end 357.15067 -229.397052)
		(width 0.1143)
		(layer "In13.Cu")
		(net "GMI_CPU0_G0_CPU1_G2_TX_DP<2>")
	)
	(segment
		(start 357.183436 -235.252006)
		(end 357.184198 -235.251498)
		(width 0.1143)
		(layer "In13.Cu")
		(net "GMI_CPU0_G0_CPU1_G2_TX_DP<2>")
	)
	(segment
		(start 114.333528 -232.644188)
		(end 114.332766 -232.644696)
		(width 0.1143)
		(layer "In13.Cu")
		(net "GMI_CPU0_G0_CPU1_G2_TX_DP<2>")
	)
	(segment
		(start 114.311684 -227.151946)
		(end 114.312446 -227.152454)
		(width 0.1143)
		(layer "In13.Cu")
		(net "GMI_CPU0_G0_CPU1_G2_TX_DP<2>")
	)
	(segment
		(start 114.333528 -234.2642)
		(end 114.332766 -234.264708)
		(width 0.1143)
		(layer "In13.Cu")
		(net "GMI_CPU0_G0_CPU1_G2_TX_DP<2>")
	)
	(segment
		(start 357.183182 -222.292164)
		(end 357.185214 -222.291148)
		(width 0.1143)
		(layer "In13.Cu")
		(net "GMI_CPU0_G0_CPU1_G2_TX_DP<2>")
	)
	(segment
		(start 357.184198 -235.251498)
		(end 357.184452 -235.251498)
		(width 0.1143)
		(layer "In13.Cu")
		(net "GMI_CPU0_G0_CPU1_G2_TX_DP<2>")
	)
	(segment
		(start 357.152448 -223.929956)
		(end 357.181658 -223.913192)
		(width 0.1143)
		(layer "In13.Cu")
		(net "GMI_CPU0_G0_CPU1_G2_TX_DP<2>")
	)
	(segment
		(start 114.311684 -230.39197)
		(end 114.343434 -230.410258)
		(width 0.1143)
		(layer "In13.Cu")
		(net "GMI_CPU0_G0_CPU1_G2_TX_DP<2>")
	)
	(segment
		(start 357.162354 -224.544128)
		(end 357.152448 -224.53854)
		(width 0.1143)
		(layer "In13.Cu")
		(net "GMI_CPU0_G0_CPU1_G2_TX_DP<2>")
	)
	(segment
		(start 357.180642 -227.153724)
		(end 357.181658 -227.153216)
		(width 0.1143)
		(layer "In13.Cu")
		(net "GMI_CPU0_G0_CPU1_G2_TX_DP<2>")
	)
	(segment
		(start 114.31524 -228.77399)
		(end 114.316002 -228.774498)
		(width 0.1143)
		(layer "In13.Cu")
		(net "GMI_CPU0_G0_CPU1_G2_TX_DP<2>")
	)
	(segment
		(start 114.317018 -233.634788)
		(end 114.31778 -233.635296)
		(width 0.1143)
		(layer "In13.Cu")
		(net "GMI_CPU0_G0_CPU1_G2_TX_DP<2>")
	)
	(segment
		(start 114.313462 -233.632756)
		(end 114.314224 -233.633264)
		(width 0.1143)
		(layer "In13.Cu")
		(net "GMI_CPU0_G0_CPU1_G2_TX_DP<2>")
	)
	(segment
		(start 114.311684 -224.557082)
		(end 114.31143 -224.557336)
		(width 0.1143)
		(layer "In13.Cu")
		(net "GMI_CPU0_G0_CPU1_G2_TX_DP<2>")
	)
	(segment
		(start 114.312446 -227.152454)
		(end 114.313462 -227.152962)
		(width 0.1143)
		(layer "In13.Cu")
		(net "GMI_CPU0_G0_CPU1_G2_TX_DP<2>")
	)
	(segment
		(start 357.162354 -234.263946)
		(end 357.152448 -234.258358)
		(width 0.1143)
		(layer "In13.Cu")
		(net "GMI_CPU0_G0_CPU1_G2_TX_DP<2>")
	)
	(segment
		(start 357.162354 -232.643934)
		(end 357.152448 -232.638346)
		(width 0.1143)
		(layer "In13.Cu")
		(net "GMI_CPU0_G0_CPU1_G2_TX_DP<2>")
	)
	(segment
		(start 114.31778 -232.015284)
		(end 114.31905 -232.016046)
		(width 0.1143)
		(layer "In13.Cu")
		(net "GMI_CPU0_G0_CPU1_G2_TX_DP<2>")
	)
	(segment
		(start 114.31905 -233.636058)
		(end 114.343434 -233.650028)
		(width 0.1143)
		(layer "In13.Cu")
		(net "GMI_CPU0_G0_CPU1_G2_TX_DP<2>")
	)
	(segment
		(start 114.313462 -235.252768)
		(end 114.314224 -235.253276)
		(width 0.1143)
		(layer "In13.Cu")
		(net "GMI_CPU0_G0_CPU1_G2_TX_DP<2>")
	)
	(segment
		(start 114.272822 -236.849158)
		(end 114.295936 -236.86262)
		(width 0.1143)
		(layer "In13.Cu")
		(net "GMI_CPU0_G0_CPU1_G2_TX_DP<2>")
	)
	(segment
		(start 114.311684 -226.177094)
		(end 114.31143 -226.177348)
		(width 0.1143)
		(layer "In13.Cu")
		(net "GMI_CPU0_G0_CPU1_G2_TX_DP<2>")
	)
	(segment
		(start 353.937824 -211.114386)
		(end 317.807848 -181.489858)
		(width 0.14224)
		(layer "In13.Cu")
		(net "GMI_CPU0_G0_CPU1_G2_TX_DP<2>")
	)
	(segment
		(start 114.02949 -221.445836)
		(end 114.02949 -221.804738)
		(width 0.1143)
		(layer "In13.Cu")
		(net "GMI_CPU0_G0_CPU1_G2_TX_DP<2>")
	)
	(segment
		(start 357.18242 -228.77272)
		(end 357.183436 -228.772212)
		(width 0.1143)
		(layer "In13.Cu")
		(net "GMI_CPU0_G0_CPU1_G2_TX_DP<2>")
	)
	(segment
		(start 114.31143 -228.771958)
		(end 114.311684 -228.771958)
		(width 0.1143)
		(layer "In13.Cu")
		(net "GMI_CPU0_G0_CPU1_G2_TX_DP<2>")
	)
	(segment
		(start 302.914304 -176.673256)
		(end 165.25748 -175.869092)
		(width 0.14224)
		(layer "In13.Cu")
		(net "GMI_CPU0_G0_CPU1_G2_TX_DP<2>")
	)
	(segment
		(start 114.31524 -233.633772)
		(end 114.316002 -233.63428)
		(width 0.1143)
		(layer "In13.Cu")
		(net "GMI_CPU0_G0_CPU1_G2_TX_DP<2>")
	)
	(segment
		(start 357.162354 -226.16414)
		(end 357.152448 -226.158552)
		(width 0.1143)
		(layer "In13.Cu")
		(net "GMI_CPU0_G0_CPU1_G2_TX_DP<2>")
	)
	(segment
		(start 114.312446 -228.772466)
		(end 114.313462 -228.772974)
		(width 0.1143)
		(layer "In13.Cu")
		(net "GMI_CPU0_G0_CPU1_G2_TX_DP<2>")
	)
	(segment
		(start 114.31778 -233.635296)
		(end 114.31905 -233.636058)
		(width 0.1143)
		(layer "In13.Cu")
		(net "GMI_CPU0_G0_CPU1_G2_TX_DP<2>")
	)
	(segment
		(start 113.96599 -221.382336)
		(end 114.02949 -221.445836)
		(width 0.1143)
		(layer "In13.Cu")
		(net "GMI_CPU0_G0_CPU1_G2_TX_DP<2>")
	)
	(segment
		(start 357.162354 -227.784152)
		(end 357.152448 -227.778564)
		(width 0.1143)
		(layer "In13.Cu")
		(net "GMI_CPU0_G0_CPU1_G2_TX_DP<2>")
	)
	(segment
		(start 357.180642 -232.013506)
		(end 357.181658 -232.012998)
		(width 0.1143)
		(layer "In13.Cu")
		(net "GMI_CPU0_G0_CPU1_G2_TX_DP<2>")
	)
	(segment
		(start 357.183436 -233.631994)
		(end 357.184198 -233.631486)
		(width 0.1143)
		(layer "In13.Cu")
		(net "GMI_CPU0_G0_CPU1_G2_TX_DP<2>")
	)
	(segment
		(start 357.163116 -226.164648)
		(end 357.162354 -226.16414)
		(width 0.1143)
		(layer "In13.Cu")
		(net "GMI_CPU0_G0_CPU1_G2_TX_DP<2>")
	)
	(segment
		(start 357.184198 -227.796852)
		(end 357.163116 -227.78466)
		(width 0.1143)
		(layer "In13.Cu")
		(net "GMI_CPU0_G0_CPU1_G2_TX_DP<2>")
	)
	(segment
		(start 114.311684 -231.036876)
		(end 114.31143 -231.03713)
		(width 0.1143)
		(layer "In13.Cu")
		(net "GMI_CPU0_G0_CPU1_G2_TX_DP<2>")
	)
	(segment
		(start 114.317018 -235.2548)
		(end 114.31778 -235.255308)
		(width 0.1143)
		(layer "In13.Cu")
		(net "GMI_CPU0_G0_CPU1_G2_TX_DP<2>")
	)
	(segment
		(start 114.31524 -223.913954)
		(end 114.316002 -223.914462)
		(width 0.1143)
		(layer "In13.Cu")
		(net "GMI_CPU0_G0_CPU1_G2_TX_DP<2>")
	)
	(segment
		(start 114.31524 -235.253784)
		(end 114.316002 -235.254292)
		(width 0.1143)
		(layer "In13.Cu")
		(net "GMI_CPU0_G0_CPU1_G2_TX_DP<2>")
	)
	(segment
		(start 357.184198 -222.936816)
		(end 357.159306 -222.922338)
		(width 0.1143)
		(layer "In13.Cu")
		(net "GMI_CPU0_G0_CPU1_G2_TX_DP<2>")
	)
	(segment
		(start 114.313462 -223.912938)
		(end 114.314224 -223.913446)
		(width 0.1143)
		(layer "In13.Cu")
		(net "GMI_CPU0_G0_CPU1_G2_TX_DP<2>")
	)
	(segment
		(start 357.183436 -232.011982)
		(end 357.184198 -232.011474)
		(width 0.1143)
		(layer "In13.Cu")
		(net "GMI_CPU0_G0_CPU1_G2_TX_DP<2>")
	)
	(segment
		(start 156.776166 -178.901852)
		(end 137.103612 -195.032376)
		(width 0.14224)
		(layer "In13.Cu")
		(net "GMI_CPU0_G0_CPU1_G2_TX_DP<2>")
	)
	(segment
		(start 357.188516 -222.289116)
		(end 357.215694 -222.273368)
		(width 0.1143)
		(layer "In13.Cu")
		(net "GMI_CPU0_G0_CPU1_G2_TX_DP<2>")
	)
	(segment
		(start 357.18242 -232.01249)
		(end 357.183436 -232.011982)
		(width 0.1143)
		(layer "In13.Cu")
		(net "GMI_CPU0_G0_CPU1_G2_TX_DP<2>")
	)
	(segment
		(start 357.184198 -223.911668)
		(end 357.184452 -223.911668)
		(width 0.1143)
		(layer "In13.Cu")
		(net "GMI_CPU0_G0_CPU1_G2_TX_DP<2>")
	)
	(segment
		(start 114.31143 -232.011728)
		(end 114.311684 -232.011728)
		(width 0.1143)
		(layer "In13.Cu")
		(net "GMI_CPU0_G0_CPU1_G2_TX_DP<2>")
	)
	(segment
		(start 114.343434 -235.878624)
		(end 114.272568 -235.919518)
		(width 0.1143)
		(layer "In13.Cu")
		(net "GMI_CPU0_G0_CPU1_G2_TX_DP<2>")
	)
	(segment
		(start 114.313208 -236.872526)
		(end 114.31397 -236.873034)
		(width 0.1143)
		(layer "In13.Cu")
		(net "GMI_CPU0_G0_CPU1_G2_TX_DP<2>")
	)
	(segment
		(start 137.103612 -195.032376)
		(end 137.103104 -195.03263)
		(width 0.14224)
		(layer "In13.Cu")
		(net "GMI_CPU0_G0_CPU1_G2_TX_DP<2>")
	)
	(segment
		(start 114.31778 -227.155502)
		(end 114.31905 -227.156264)
		(width 0.1143)
		(layer "In13.Cu")
		(net "GMI_CPU0_G0_CPU1_G2_TX_DP<2>")
	)
	(segment
		(start 114.314224 -232.013252)
		(end 114.31524 -232.01376)
		(width 0.1143)
		(layer "In13.Cu")
		(net "GMI_CPU0_G0_CPU1_G2_TX_DP<2>")
	)
	(segment
		(start 357.18242 -227.152708)
		(end 357.183436 -227.1522)
		(width 0.1143)
		(layer "In13.Cu")
		(net "GMI_CPU0_G0_CPU1_G2_TX_DP<2>")
	)
	(segment
		(start 114.31143 -223.911922)
		(end 114.311684 -223.911922)
		(width 0.1143)
		(layer "In13.Cu")
		(net "GMI_CPU0_G0_CPU1_G2_TX_DP<2>")
	)
	(segment
		(start 114.316002 -233.63428)
		(end 114.317018 -233.634788)
		(width 0.1143)
		(layer "In13.Cu")
		(net "GMI_CPU0_G0_CPU1_G2_TX_DP<2>")
	)
	(segment
		(start 114.332766 -234.264708)
		(end 114.311684 -234.2769)
		(width 0.1143)
		(layer "In13.Cu")
		(net "GMI_CPU0_G0_CPU1_G2_TX_DP<2>")
	)
	(segment
		(start 357.185214 -222.291148)
		(end 357.187754 -222.289624)
		(width 0.1143)
		(layer "In13.Cu")
		(net "GMI_CPU0_G0_CPU1_G2_TX_DP<2>")
	)
	(segment
		(start 114.311684 -232.011728)
		(end 114.312446 -232.012236)
		(width 0.1143)
		(layer "In13.Cu")
		(net "GMI_CPU0_G0_CPU1_G2_TX_DP<2>")
	)
	(segment
		(start 114.313462 -228.772974)
		(end 114.314224 -228.773482)
		(width 0.1143)
		(layer "In13.Cu")
		(net "GMI_CPU0_G0_CPU1_G2_TX_DP<2>")
	)
	(segment
		(start 114.317018 -223.91497)
		(end 114.31778 -223.915478)
		(width 0.1143)
		(layer "In13.Cu")
		(net "GMI_CPU0_G0_CPU1_G2_TX_DP<2>")
	)
	(segment
		(start 308.443884 -176.673256)
		(end 302.914304 -176.673256)
		(width 0.14224)
		(layer "In13.Cu")
		(net "GMI_CPU0_G0_CPU1_G2_TX_DP<2>")
	)
	(segment
		(start 114.279426 -222.273114)
		(end 114.280188 -222.273622)
		(width 0.1143)
		(layer "In13.Cu")
		(net "GMI_CPU0_G0_CPU1_G2_TX_DP<2>")
	)
	(segment
		(start 357.17988 -235.254038)
		(end 357.180642 -235.25353)
		(width 0.1143)
		(layer "In13.Cu")
		(net "GMI_CPU0_G0_CPU1_G2_TX_DP<2>")
	)
	(segment
		(start 357.182674 -236.872272)
		(end 357.199946 -236.862366)
		(width 0.1143)
		(layer "In13.Cu")
		(net "GMI_CPU0_G0_CPU1_G2_TX_DP<2>")
	)
	(segment
		(start 357.152448 -228.789992)
		(end 357.176832 -228.776022)
		(width 0.1143)
		(layer "In13.Cu")
		(net "GMI_CPU0_G0_CPU1_G2_TX_DP<2>")
	)
	(segment
		(start 114.317018 -228.775006)
		(end 114.31778 -228.775514)
		(width 0.1143)
		(layer "In13.Cu")
		(net "GMI_CPU0_G0_CPU1_G2_TX_DP<2>")
	)
	(segment
		(start 114.333528 -227.784406)
		(end 114.332766 -227.784914)
		(width 0.1143)
		(layer "In13.Cu")
		(net "GMI_CPU0_G0_CPU1_G2_TX_DP<2>")
	)
	(segment
		(start 114.332766 -227.784914)
		(end 114.311684 -227.797106)
		(width 0.1143)
		(layer "In13.Cu")
		(net "GMI_CPU0_G0_CPU1_G2_TX_DP<2>")
	)
	(segment
		(start 114.314224 -227.15347)
		(end 114.31524 -227.153978)
		(width 0.1143)
		(layer "In13.Cu")
		(net "GMI_CPU0_G0_CPU1_G2_TX_DP<2>")
	)
	(segment
		(start 114.312446 -232.012236)
		(end 114.313462 -232.012744)
		(width 0.1143)
		(layer "In13.Cu")
		(net "GMI_CPU0_G0_CPU1_G2_TX_DP<2>")
	)
	(segment
		(start 357.181912 -236.87278)
		(end 357.182674 -236.872272)
		(width 0.1143)
		(layer "In13.Cu")
		(net "GMI_CPU0_G0_CPU1_G2_TX_DP<2>")
	)
	(segment
		(start 357.180642 -228.773736)
		(end 357.181658 -228.773228)
		(width 0.1143)
		(layer "In13.Cu")
		(net "GMI_CPU0_G0_CPU1_G2_TX_DP<2>")
	)
	(segment
		(start 117.430042 -211.163662)
		(end 113.92027 -217.144346)
		(width 0.14224)
		(layer "In13.Cu")
		(net "GMI_CPU0_G0_CPU1_G2_TX_DP<2>")
	)
	(segment
		(start 357.152448 -235.269786)
		(end 357.176832 -235.255816)
		(width 0.1143)
		(layer "In13.Cu")
		(net "GMI_CPU0_G0_CPU1_G2_TX_DP<2>")
	)
	(segment
		(start 357.187754 -222.289624)
		(end 357.188516 -222.289116)
		(width 0.1143)
		(layer "In13.Cu")
		(net "GMI_CPU0_G0_CPU1_G2_TX_DP<2>")
	)
	(segment
		(start 357.215694 -222.273368)
		(end 357.216456 -222.27286)
		(width 0.1143)
		(layer "In13.Cu")
		(net "GMI_CPU0_G0_CPU1_G2_TX_DP<2>")
	)
	(segment
		(start 357.17988 -232.014014)
		(end 357.180642 -232.013506)
		(width 0.1143)
		(layer "In13.Cu")
		(net "GMI_CPU0_G0_CPU1_G2_TX_DP<2>")
	)
	(segment
		(start 114.280188 -222.273622)
		(end 114.310668 -222.291402)
		(width 0.1143)
		(layer "In13.Cu")
		(net "GMI_CPU0_G0_CPU1_G2_TX_DP<2>")
	)
	(segment
		(start 357.152448 -238.50981)
		(end 357.184198 -238.491522)
		(width 0.1143)
		(layer "In13.Cu")
		(net "GMI_CPU0_G0_CPU1_G2_TX_DP<2>")
	)
	(segment
		(start 114.3127 -222.292418)
		(end 114.33175 -222.303594)
		(width 0.1143)
		(layer "In13.Cu")
		(net "GMI_CPU0_G0_CPU1_G2_TX_DP<2>")
	)
	(segment
		(start 114.33937 -222.920814)
		(end 114.336576 -222.922592)
		(width 0.1143)
		(layer "In13.Cu")
		(net "GMI_CPU0_G0_CPU1_G2_TX_DP<2>")
	)
	(segment
		(start 114.311684 -222.93707)
		(end 114.31143 -222.937324)
		(width 0.1143)
		(layer "In13.Cu")
		(net "GMI_CPU0_G0_CPU1_G2_TX_DP<2>")
	)
	(segment
		(start 357.184452 -226.177094)
		(end 357.184198 -226.17684)
		(width 0.1143)
		(layer "In13.Cu")
		(net "GMI_CPU0_G0_CPU1_G2_TX_DP<2>")
	)
	(segment
		(start 357.163116 -232.644442)
		(end 357.162354 -232.643934)
		(width 0.1143)
		(layer "In13.Cu")
		(net "GMI_CPU0_G0_CPU1_G2_TX_DP<2>")
	)
	(segment
		(start 114.343434 -237.498636)
		(end 114.311684 -237.516924)
		(width 0.1143)
		(layer "In13.Cu")
		(net "GMI_CPU0_G0_CPU1_G2_TX_DP<2>")
	)
	(segment
		(start 114.312446 -235.25226)
		(end 114.313462 -235.252768)
		(width 0.1143)
		(layer "In13.Cu")
		(net "GMI_CPU0_G0_CPU1_G2_TX_DP<2>")
	)
	(segment
		(start 114.311684 -228.771958)
		(end 114.312446 -228.772466)
		(width 0.1143)
		(layer "In13.Cu")
		(net "GMI_CPU0_G0_CPU1_G2_TX_DP<2>")
	)
	(segment
		(start 357.184452 -232.656888)
		(end 357.184198 -232.656634)
		(width 0.1143)
		(layer "In13.Cu")
		(net "GMI_CPU0_G0_CPU1_G2_TX_DP<2>")
	)
	(segment
		(start 357.184198 -228.771704)
		(end 357.184452 -228.771704)
		(width 0.1143)
		(layer "In13.Cu")
		(net "GMI_CPU0_G0_CPU1_G2_TX_DP<2>")
	)
	(segment
		(start 114.343434 -224.538794)
		(end 114.333528 -224.544382)
		(width 0.1143)
		(layer "In13.Cu")
		(net "GMI_CPU0_G0_CPU1_G2_TX_DP<2>")
	)
	(segment
		(start 357.180642 -233.633518)
		(end 357.181658 -233.63301)
		(width 0.1143)
		(layer "In13.Cu")
		(net "GMI_CPU0_G0_CPU1_G2_TX_DP<2>")
	)
	(segment
		(start 357.184198 -237.51667)
		(end 357.152448 -237.498382)
		(width 0.1143)
		(layer "In13.Cu")
		(net "GMI_CPU0_G0_CPU1_G2_TX_DP<2>")
	)
	(segment
		(start 114.316002 -235.254292)
		(end 114.317018 -235.2548)
		(width 0.1143)
		(layer "In13.Cu")
		(net "GMI_CPU0_G0_CPU1_G2_TX_DP<2>")
	)
	(segment
		(start 357.223314 -235.919264)
		(end 357.152448 -235.87837)
		(width 0.1143)
		(layer "In13.Cu")
		(net "GMI_CPU0_G0_CPU1_G2_TX_DP<2>")
	)
	(segment
		(start 357.184198 -230.391716)
		(end 357.217726 -230.372158)
		(width 0.1143)
		(layer "In13.Cu")
		(net "GMI_CPU0_G0_CPU1_G2_TX_DP<2>")
	)
	(segment
		(start 357.178102 -235.255054)
		(end 357.178864 -235.254546)
		(width 0.1143)
		(layer "In13.Cu")
		(net "GMI_CPU0_G0_CPU1_G2_TX_DP<2>")
	)
	(segment
		(start 114.313462 -232.012744)
		(end 114.314224 -232.013252)
		(width 0.1143)
		(layer "In13.Cu")
		(net "GMI_CPU0_G0_CPU1_G2_TX_DP<2>")
	)
	(segment
		(start 357.17988 -233.634026)
		(end 357.180642 -233.633518)
		(width 0.1143)
		(layer "In13.Cu")
		(net "GMI_CPU0_G0_CPU1_G2_TX_DP<2>")
	)
	(segment
		(start 357.164132 -222.30334)
		(end 357.183182 -222.292164)
		(width 0.1143)
		(layer "In13.Cu")
		(net "GMI_CPU0_G0_CPU1_G2_TX_DP<2>")
	)
	(segment
		(start 357.184452 -231.036876)
		(end 357.184198 -231.036622)
		(width 0.1143)
		(layer "In13.Cu")
		(net "GMI_CPU0_G0_CPU1_G2_TX_DP<2>")
	)
	(segment
		(start 114.31905 -227.156264)
		(end 114.343434 -227.170234)
		(width 0.1143)
		(layer "In13.Cu")
		(net "GMI_CPU0_G0_CPU1_G2_TX_DP<2>")
	)
	(segment
		(start 357.184198 -232.656634)
		(end 357.163116 -232.644442)
		(width 0.1143)
		(layer "In13.Cu")
		(net "GMI_CPU0_G0_CPU1_G2_TX_DP<2>")
	)
	(segment
		(start 114.336576 -222.922592)
		(end 114.334036 -222.924116)
		(width 0.1143)
		(layer "In13.Cu")
		(net "GMI_CPU0_G0_CPU1_G2_TX_DP<2>")
	)
	(segment
		(start 114.31143 -227.151946)
		(end 114.311684 -227.151946)
		(width 0.1143)
		(layer "In13.Cu")
		(net "GMI_CPU0_G0_CPU1_G2_TX_DP<2>")
	)
	(segment
		(start 357.184198 -227.151692)
		(end 357.184452 -227.151692)
		(width 0.1143)
		(layer "In13.Cu")
		(net "GMI_CPU0_G0_CPU1_G2_TX_DP<2>")
	)
	(segment
		(start 357.18242 -235.252514)
		(end 357.183436 -235.252006)
		(width 0.1143)
		(layer "In13.Cu")
		(net "GMI_CPU0_G0_CPU1_G2_TX_DP<2>")
	)
	(segment
		(start 357.184198 -232.011474)
		(end 357.184452 -232.011474)
		(width 0.1143)
		(layer "In13.Cu")
		(net "GMI_CPU0_G0_CPU1_G2_TX_DP<2>")
	)
	(segment
		(start 357.159306 -222.922338)
		(end 357.156512 -222.92056)
		(width 0.1143)
		(layer "In13.Cu")
		(net "GMI_CPU0_G0_CPU1_G2_TX_DP<2>")
	)
	(segment
		(start 114.316002 -232.014268)
		(end 114.317018 -232.014776)
		(width 0.1143)
		(layer "In13.Cu")
		(net "GMI_CPU0_G0_CPU1_G2_TX_DP<2>")
	)
	(segment
		(start 114.311684 -238.491776)
		(end 114.343434 -238.510064)
		(width 0.1143)
		(layer "In13.Cu")
		(net "GMI_CPU0_G0_CPU1_G2_TX_DP<2>")
	)
	(segment
		(start 357.181658 -223.913192)
		(end 357.18242 -223.912684)
		(width 0.1143)
		(layer "In13.Cu")
		(net "GMI_CPU0_G0_CPU1_G2_TX_DP<2>")
	)
	(segment
		(start 114.343434 -227.778818)
		(end 114.333528 -227.784406)
		(width 0.1143)
		(layer "In13.Cu")
		(net "GMI_CPU0_G0_CPU1_G2_TX_DP<2>")
	)
	(segment
		(start 357.152448 -227.16998)
		(end 357.178102 -227.155248)
		(width 0.1143)
		(layer "In13.Cu")
		(net "GMI_CPU0_G0_CPU1_G2_TX_DP<2>")
	)
	(segment
		(start 114.311684 -227.797106)
		(end 114.31143 -227.79736)
		(width 0.1143)
		(layer "In13.Cu")
		(net "GMI_CPU0_G0_CPU1_G2_TX_DP<2>")
	)
	(segment
		(start 357.152448 -232.029762)
		(end 357.176832 -232.015792)
		(width 0.1143)
		(layer "In13.Cu")
		(net "GMI_CPU0_G0_CPU1_G2_TX_DP<2>")
	)
	(segment
		(start 357.529892 -221.145862)
		(end 357.575612 -221.100142)
		(width 0.1143)
		(layer "In13.Cu")
		(net "GMI_CPU0_G0_CPU1_G2_TX_DP<2>")
	)
	(segment
		(start 114.311684 -234.2769)
		(end 114.31143 -234.277154)
		(width 0.1143)
		(layer "In13.Cu")
		(net "GMI_CPU0_G0_CPU1_G2_TX_DP<2>")
	)
	(segment
		(start 114.314224 -223.913446)
		(end 114.31524 -223.913954)
		(width 0.1143)
		(layer "In13.Cu")
		(net "GMI_CPU0_G0_CPU1_G2_TX_DP<2>")
	)
	(segment
		(start 114.31778 -223.915478)
		(end 114.343434 -223.93021)
		(width 0.1143)
		(layer "In13.Cu")
		(net "GMI_CPU0_G0_CPU1_G2_TX_DP<2>")
	)
	(segment
		(start 357.152448 -230.410004)
		(end 357.184198 -230.391716)
		(width 0.1143)
		(layer "In13.Cu")
		(net "GMI_CPU0_G0_CPU1_G2_TX_DP<2>")
	)
	(segment
		(start 114.312446 -223.91243)
		(end 114.313462 -223.912938)
		(width 0.1143)
		(layer "In13.Cu")
		(net "GMI_CPU0_G0_CPU1_G2_TX_DP<2>")
	)
	(segment
		(start 114.31905 -235.25607)
		(end 114.343434 -235.27004)
		(width 0.1143)
		(layer "In13.Cu")
		(net "GMI_CPU0_G0_CPU1_G2_TX_DP<2>")
	)
	(segment
		(start 357.176832 -233.635804)
		(end 357.178102 -233.635042)
		(width 0.1143)
		(layer "In13.Cu")
		(net "GMI_CPU0_G0_CPU1_G2_TX_DP<2>")
	)
	(segment
		(start 357.0732 -238.814102)
		(end 357.00335 -238.744252)
		(width 0.1143)
		(layer "In13.Cu")
		(net "GMI_CPU0_G0_CPU1_G2_TX_DP<2>")
	)
	(segment
		(start 114.317018 -232.014776)
		(end 114.31778 -232.015284)
		(width 0.1143)
		(layer "In13.Cu")
		(net "GMI_CPU0_G0_CPU1_G2_TX_DP<2>")
	)
	(segment
		(start 114.311684 -225.531934)
		(end 114.343434 -225.550222)
		(width 0.1143)
		(layer "In13.Cu")
		(net "GMI_CPU0_G0_CPU1_G2_TX_DP<2>")
	)
	(segment
		(start 114.332766 -232.644696)
		(end 114.311684 -232.656888)
		(width 0.1143)
		(layer "In13.Cu")
		(net "GMI_CPU0_G0_CPU1_G2_TX_DP<2>")
	)
	(segment
		(start 114.31778 -235.255308)
		(end 114.31905 -235.25607)
		(width 0.1143)
		(layer "In13.Cu")
		(net "GMI_CPU0_G0_CPU1_G2_TX_DP<2>")
	)
	(segment
		(start 357.17988 -236.87405)
		(end 357.180642 -236.873542)
		(width 0.1143)
		(layer "In13.Cu")
		(net "GMI_CPU0_G0_CPU1_G2_TX_DP<2>")
	)
	(segment
		(start 113.92027 -221.100396)
		(end 113.96599 -221.146116)
		(width 0.1143)
		(layer "In13.Cu")
		(net "GMI_CPU0_G0_CPU1_G2_TX_DP<2>")
	)
	(segment
		(start 357.17988 -227.154232)
		(end 357.180642 -227.153724)
		(width 0.1143)
		(layer "In13.Cu")
		(net "GMI_CPU0_G0_CPU1_G2_TX_DP<2>")
	)
	(segment
		(start 114.272568 -222.26905)
		(end 114.279426 -222.273114)
		(width 0.1143)
		(layer "In13.Cu")
		(net "GMI_CPU0_G0_CPU1_G2_TX_DP<2>")
	)
	(segment
		(start 357.199946 -236.862366)
		(end 357.22306 -236.848904)
		(width 0.1143)
		(layer "In13.Cu")
		(net "GMI_CPU0_G0_CPU1_G2_TX_DP<2>")
	)
	(segment
		(start 357.466392 -221.445582)
		(end 357.529892 -221.382082)
		(width 0.1143)
		(layer "In13.Cu")
		(net "GMI_CPU0_G0_CPU1_G2_TX_DP<2>")
	)
	(segment
		(start 357.181658 -235.253022)
		(end 357.18242 -235.252514)
		(width 0.1143)
		(layer "In13.Cu")
		(net "GMI_CPU0_G0_CPU1_G2_TX_DP<2>")
	)
	(segment
		(start 357.184198 -233.631486)
		(end 357.184452 -233.631486)
		(width 0.1143)
		(layer "In13.Cu")
		(net "GMI_CPU0_G0_CPU1_G2_TX_DP<2>")
	)
	(segment
		(start 114.333528 -226.164394)
		(end 114.332766 -226.164902)
		(width 0.1143)
		(layer "In13.Cu")
		(net "GMI_CPU0_G0_CPU1_G2_TX_DP<2>")
	)
	(segment
		(start 114.332766 -226.164902)
		(end 114.311684 -226.177094)
		(width 0.1143)
		(layer "In13.Cu")
		(net "GMI_CPU0_G0_CPU1_G2_TX_DP<2>")
	)
	(segment
		(start 357.176832 -235.255816)
		(end 357.178102 -235.255054)
		(width 0.1143)
		(layer "In13.Cu")
		(net "GMI_CPU0_G0_CPU1_G2_TX_DP<2>")
	)
	(segment
		(start 114.31143 -225.531934)
		(end 114.311684 -225.531934)
		(width 0.1143)
		(layer "In13.Cu")
		(net "GMI_CPU0_G0_CPU1_G2_TX_DP<2>")
	)
	(segment
		(start 357.183436 -223.912176)
		(end 357.184198 -223.911668)
		(width 0.1143)
		(layer "In13.Cu")
		(net "GMI_CPU0_G0_CPU1_G2_TX_DP<2>")
	)
	(segment
		(start 114.333528 -224.544382)
		(end 114.332766 -224.54489)
		(width 0.1143)
		(layer "In13.Cu")
		(net "GMI_CPU0_G0_CPU1_G2_TX_DP<2>")
	)
	(segment
		(start 357.176832 -228.776022)
		(end 357.178102 -228.77526)
		(width 0.1143)
		(layer "In13.Cu")
		(net "GMI_CPU0_G0_CPU1_G2_TX_DP<2>")
	)
	(segment
		(start 357.184198 -225.53168)
		(end 357.184452 -225.53168)
		(width 0.1143)
		(layer "In13.Cu")
		(net "GMI_CPU0_G0_CPU1_G2_TX_DP<2>")
	)
	(segment
		(start 357.152448 -236.889798)
		(end 357.17988 -236.87405)
		(width 0.1143)
		(layer "In13.Cu")
		(net "GMI_CPU0_G0_CPU1_G2_TX_DP<2>")
	)
	(segment
		(start 357.575612 -221.100142)
		(end 357.575612 -221.093538)
		(width 0.1143)
		(layer "In13.Cu")
		(net "GMI_CPU0_G0_CPU1_G2_TX_DP<2>")
	)
	(segment
		(start 114.311684 -235.251752)
		(end 114.312446 -235.25226)
		(width 0.1143)
		(layer "In13.Cu")
		(net "GMI_CPU0_G0_CPU1_G2_TX_DP<2>")
	)
	(segment
		(start 357.183436 -228.772212)
		(end 357.184198 -228.771704)
		(width 0.1143)
		(layer "In13.Cu")
		(net "GMI_CPU0_G0_CPU1_G2_TX_DP<2>")
	)
	(segment
		(start 113.92027 -221.071948)
		(end 113.92027 -221.100396)
		(width 0.1143)
		(layer "In13.Cu")
		(net "GMI_CPU0_G0_CPU1_G2_TX_DP<2>")
	)
	(segment
		(start 114.311684 -223.911922)
		(end 114.312446 -223.91243)
		(width 0.1143)
		(layer "In13.Cu")
		(net "GMI_CPU0_G0_CPU1_G2_TX_DP<2>")
	)
	(segment
		(start 357.152448 -225.549968)
		(end 357.184198 -225.53168)
		(width 0.1143)
		(layer "In13.Cu")
		(net "GMI_CPU0_G0_CPU1_G2_TX_DP<2>")
	)
	(segment
		(start 114.295936 -236.86262)
		(end 114.313208 -236.872526)
		(width 0.1143)
		(layer "In13.Cu")
		(net "GMI_CPU0_G0_CPU1_G2_TX_DP<2>")
	)
	(segment
		(start 357.152448 -233.649774)
		(end 357.176832 -233.635804)
		(width 0.1143)
		(layer "In13.Cu")
		(net "GMI_CPU0_G0_CPU1_G2_TX_DP<2>")
	)
	(segment
		(start 357.178864 -235.254546)
		(end 357.17988 -235.254038)
		(width 0.1143)
		(layer "In13.Cu")
		(net "GMI_CPU0_G0_CPU1_G2_TX_DP<2>")
	)
	(segment
		(start 114.332766 -224.54489)
		(end 114.311684 -224.557082)
		(width 0.1143)
		(layer "In13.Cu")
		(net "GMI_CPU0_G0_CPU1_G2_TX_DP<2>")
	)
	(segment
		(start 114.492532 -238.744506)
		(end 114.422682 -238.814356)
		(width 0.1143)
		(layer "In13.Cu")
		(net "GMI_CPU0_G0_CPU1_G2_TX_DP<2>")
	)
	(segment
		(start 357.178864 -233.634534)
		(end 357.17988 -233.634026)
		(width 0.1143)
		(layer "In13.Cu")
		(net "GMI_CPU0_G0_CPU1_G2_TX_DP<2>")
	)
	(segment
		(start 357.371142 -238.814102)
		(end 357.0732 -238.814102)
		(width 0.1143)
		(layer "In13.Cu")
		(net "GMI_CPU0_G0_CPU1_G2_TX_DP<2>")
	)
	(segment
		(start 114.345212 -229.397306)
		(end 114.311684 -229.416864)
		(width 0.1143)
		(layer "In13.Cu")
		(net "GMI_CPU0_G0_CPU1_G2_TX_DP<2>")
	)
	(segment
		(start 114.272568 -235.919518)
		(end 114.244882 -235.939584)
		(width 0.1143)
		(layer "In13.Cu")
		(net "GMI_CPU0_G0_CPU1_G2_TX_DP<2>")
	)
	(segment
		(start 357.17988 -228.774244)
		(end 357.180642 -228.773736)
		(width 0.1143)
		(layer "In13.Cu")
		(net "GMI_CPU0_G0_CPU1_G2_TX_DP<2>")
	)
	(segment
		(start 114.314224 -233.633264)
		(end 114.31524 -233.633772)
		(width 0.1143)
		(layer "In13.Cu")
		(net "GMI_CPU0_G0_CPU1_G2_TX_DP<2>")
	)
	(segment
		(start 114.343434 -234.258612)
		(end 114.333528 -234.2642)
		(width 0.1143)
		(layer "In13.Cu")
		(net "GMI_CPU0_G0_CPU1_G2_TX_DP<2>")
	)
	(segment
		(start 357.575612 -217.241882)
		(end 353.937824 -211.114386)
		(width 0.14224)
		(layer "In13.Cu")
		(net "GMI_CPU0_G0_CPU1_G2_TX_DP<2>")
	)
	(segment
		(start 357.466392 -221.804484)
		(end 357.466392 -221.445582)
		(width 0.1143)
		(layer "In13.Cu")
		(net "GMI_CPU0_G0_CPU1_G2_TX_DP<2>")
	)
	(segment
		(start 357.184198 -224.556828)
		(end 357.163116 -224.544636)
		(width 0.1143)
		(layer "In13.Cu")
		(net "GMI_CPU0_G0_CPU1_G2_TX_DP<2>")
	)
	(segment
		(start 357.178102 -227.155248)
		(end 357.178864 -227.15474)
		(width 0.1143)
		(layer "In13.Cu")
		(net "GMI_CPU0_G0_CPU1_G2_TX_DP<2>")
	)
	(segment
		(start 114.31905 -228.776276)
		(end 114.343434 -228.790246)
		(width 0.1143)
		(layer "In13.Cu")
		(net "GMI_CPU0_G0_CPU1_G2_TX_DP<2>")
	)
	(segment
		(start 357.18242 -223.912684)
		(end 357.183436 -223.912176)
		(width 0.1143)
		(layer "In13.Cu")
		(net "GMI_CPU0_G0_CPU1_G2_TX_DP<2>")
	)
	(segment
		(start 165.25748 -175.869092)
		(end 156.776166 -178.901852)
		(width 0.14224)
		(layer "In13.Cu")
		(net "GMI_CPU0_G0_CPU1_G2_TX_DP<2>")
	)
	(segment
		(start 114.316002 -223.914462)
		(end 114.317018 -223.91497)
		(width 0.1143)
		(layer "In13.Cu")
		(net "GMI_CPU0_G0_CPU1_G2_TX_DP<2>")
	)
	(segment
		(start 114.345212 -231.017318)
		(end 114.311684 -231.036876)
		(width 0.1143)
		(layer "In13.Cu")
		(net "GMI_CPU0_G0_CPU1_G2_TX_DP<2>")
	)
	(segment
		(start 114.278156 -230.372412)
		(end 114.311684 -230.39197)
		(width 0.1143)
		(layer "In13.Cu")
		(net "GMI_CPU0_G0_CPU1_G2_TX_DP<2>")
	)
	(segment
		(start 357.184198 -234.276646)
		(end 357.163116 -234.264454)
		(width 0.1143)
		(layer "In13.Cu")
		(net "GMI_CPU0_G0_CPU1_G2_TX_DP<2>")
	)
	(segment
		(start 357.176832 -232.015792)
		(end 357.178102 -232.01503)
		(width 0.1143)
		(layer "In13.Cu")
		(net "GMI_CPU0_G0_CPU1_G2_TX_DP<2>")
	)
	(segment
		(start 114.312446 -233.632248)
		(end 114.313462 -233.632756)
		(width 0.1143)
		(layer "In13.Cu")
		(net "GMI_CPU0_G0_CPU1_G2_TX_DP<2>")
	)
	(segment
		(start 114.316002 -227.154486)
		(end 114.317018 -227.154994)
		(width 0.1143)
		(layer "In13.Cu")
		(net "GMI_CPU0_G0_CPU1_G2_TX_DP<2>")
	)
	(segment
		(start 357.184452 -224.557082)
		(end 357.184198 -224.556828)
		(width 0.1143)
		(layer "In13.Cu")
		(net "GMI_CPU0_G0_CPU1_G2_TX_DP<2>")
	)
	(segment
		(start 357.22306 -236.848904)
		(end 357.251 -236.828838)
		(width 0.1143)
		(layer "In13.Cu")
		(net "GMI_CPU0_G0_CPU1_G2_TX_DP<2>")
	)
	(arc
		(start 114.31143 -224.557336)
		(mid 114.030783 -225.044698)
		(end 114.31143 -225.531934)
		(width 0.1143)
		(layer "In13.Cu")
		(net "GMI_CPU0_G0_CPU1_G2_TX_DP<2>")
	)
	(arc
		(start 357.233982 -229.447344)
		(mid 357.227287 -229.442468)
		(end 357.22052 -229.437692)
		(width 0.1143)
		(layer "In13.Cu")
		(net "GMI_CPU0_G0_CPU1_G2_TX_DP<2>")
	)
	(arc
		(start 114.31143 -231.03713)
		(mid 114.030783 -231.524492)
		(end 114.31143 -232.011728)
		(width 0.1143)
		(layer "In13.Cu")
		(net "GMI_CPU0_G0_CPU1_G2_TX_DP<2>")
	)
	(arc
		(start 114.311684 -237.516924)
		(mid 114.031037 -238.00435)
		(end 114.311684 -238.491776)
		(width 0.1143)
		(layer "In13.Cu")
		(net "GMI_CPU0_G0_CPU1_G2_TX_DP<2>")
	)
	(arc
		(start 114.343434 -235.27004)
		(mid 114.499362 -235.574332)
		(end 114.343434 -235.878624)
		(width 0.1143)
		(layer "In13.Cu")
		(net "GMI_CPU0_G0_CPU1_G2_TX_DP<2>")
	)
	(arc
		(start 357.184452 -228.771704)
		(mid 357.464879 -228.284468)
		(end 357.184452 -227.797106)
		(width 0.1143)
		(layer "In13.Cu")
		(net "GMI_CPU0_G0_CPU1_G2_TX_DP<2>")
	)
	(arc
		(start 357.152448 -227.778564)
		(mid 356.99652 -227.474272)
		(end 357.152448 -227.16998)
		(width 0.1143)
		(layer "In13.Cu")
		(net "GMI_CPU0_G0_CPU1_G2_TX_DP<2>")
	)
	(arc
		(start 357.00335 -238.744252)
		(mid 357.055399 -238.612733)
		(end 357.152448 -238.50981)
		(width 0.1143)
		(layer "In13.Cu")
		(net "GMI_CPU0_G0_CPU1_G2_TX_DP<2>")
	)
	(arc
		(start 357.184452 -233.631486)
		(mid 357.464879 -233.14425)
		(end 357.184452 -232.656888)
		(width 0.1143)
		(layer "In13.Cu")
		(net "GMI_CPU0_G0_CPU1_G2_TX_DP<2>")
	)
	(arc
		(start 114.343434 -230.410258)
		(mid 114.45811 -230.543592)
		(end 114.49939 -230.71455)
		(width 0.1143)
		(layer "In13.Cu")
		(net "GMI_CPU0_G0_CPU1_G2_TX_DP<2>")
	)
	(arc
		(start 357.152448 -224.53854)
		(mid 356.99652 -224.234248)
		(end 357.152448 -223.929956)
		(width 0.1143)
		(layer "In13.Cu")
		(net "GMI_CPU0_G0_CPU1_G2_TX_DP<2>")
	)
	(arc
		(start 114.343434 -228.790246)
		(mid 114.45811 -228.92358)
		(end 114.49939 -229.094538)
		(width 0.1143)
		(layer "In13.Cu")
		(net "GMI_CPU0_G0_CPU1_G2_TX_DP<2>")
	)
	(arc
		(start 114.343434 -233.650028)
		(mid 114.499362 -233.95432)
		(end 114.343434 -234.258612)
		(width 0.1143)
		(layer "In13.Cu")
		(net "GMI_CPU0_G0_CPU1_G2_TX_DP<2>")
	)
	(arc
		(start 357.152448 -237.498382)
		(mid 356.99652 -237.19409)
		(end 357.152448 -236.889798)
		(width 0.1143)
		(layer "In13.Cu")
		(net "GMI_CPU0_G0_CPU1_G2_TX_DP<2>")
	)
	(arc
		(start 114.343434 -225.550222)
		(mid 114.499362 -225.854514)
		(end 114.343434 -226.158806)
		(width 0.1143)
		(layer "In13.Cu")
		(net "GMI_CPU0_G0_CPU1_G2_TX_DP<2>")
	)
	(arc
		(start 114.275362 -229.437946)
		(mid 114.268596 -229.442723)
		(end 114.2619 -229.447598)
		(width 0.1143)
		(layer "In13.Cu")
		(net "GMI_CPU0_G0_CPU1_G2_TX_DP<2>")
	)
	(arc
		(start 357.184452 -232.011474)
		(mid 357.464879 -231.524238)
		(end 357.184452 -231.036876)
		(width 0.1143)
		(layer "In13.Cu")
		(net "GMI_CPU0_G0_CPU1_G2_TX_DP<2>")
	)
	(arc
		(start 356.996492 -229.094284)
		(mid 357.037747 -228.923313)
		(end 357.152448 -228.789992)
		(width 0.1143)
		(layer "In13.Cu")
		(net "GMI_CPU0_G0_CPU1_G2_TX_DP<2>")
	)
	(arc
		(start 357.223314 -222.268796)
		(mid 357.295641 -222.209329)
		(end 357.357172 -222.138748)
		(width 0.1143)
		(layer "In13.Cu")
		(net "GMI_CPU0_G0_CPU1_G2_TX_DP<2>")
	)
	(arc
		(start 357.251 -236.828838)
		(mid 357.479 -236.384084)
		(end 357.251 -235.93933)
		(width 0.1143)
		(layer "In13.Cu")
		(net "GMI_CPU0_G0_CPU1_G2_TX_DP<2>")
	)
	(arc
		(start 114.343434 -236.890052)
		(mid 114.499362 -237.194344)
		(end 114.343434 -237.498636)
		(width 0.1143)
		(layer "In13.Cu")
		(net "GMI_CPU0_G0_CPU1_G2_TX_DP<2>")
	)
	(arc
		(start 114.02949 -229.90429)
		(mid 114.106392 -230.163553)
		(end 114.278156 -230.372412)
		(width 0.1143)
		(layer "In13.Cu")
		(net "GMI_CPU0_G0_CPU1_G2_TX_DP<2>")
	)
	(arc
		(start 357.184198 -238.491522)
		(mid 357.464845 -238.004096)
		(end 357.184198 -237.51667)
		(width 0.1143)
		(layer "In13.Cu")
		(net "GMI_CPU0_G0_CPU1_G2_TX_DP<2>")
	)
	(arc
		(start 114.343434 -232.030016)
		(mid 114.499362 -232.334308)
		(end 114.343434 -232.6386)
		(width 0.1143)
		(layer "In13.Cu")
		(net "GMI_CPU0_G0_CPU1_G2_TX_DP<2>")
	)
	(arc
		(start 114.31143 -234.277154)
		(mid 114.030783 -234.764516)
		(end 114.31143 -235.251752)
		(width 0.1143)
		(layer "In13.Cu")
		(net "GMI_CPU0_G0_CPU1_G2_TX_DP<2>")
	)
	(arc
		(start 357.357172 -222.138748)
		(mid 357.438423 -221.980322)
		(end 357.466392 -221.804484)
		(width 0.1143)
		(layer "In13.Cu")
		(net "GMI_CPU0_G0_CPU1_G2_TX_DP<2>")
	)
	(arc
		(start 357.152448 -226.158552)
		(mid 356.99652 -225.85426)
		(end 357.152448 -225.549968)
		(width 0.1143)
		(layer "In13.Cu")
		(net "GMI_CPU0_G0_CPU1_G2_TX_DP<2>")
	)
	(arc
		(start 114.13871 -222.139002)
		(mid 114.200229 -222.209596)
		(end 114.272568 -222.26905)
		(width 0.1143)
		(layer "In13.Cu")
		(net "GMI_CPU0_G0_CPU1_G2_TX_DP<2>")
	)
	(arc
		(start 114.31143 -226.177348)
		(mid 114.030783 -226.66471)
		(end 114.31143 -227.151946)
		(width 0.1143)
		(layer "In13.Cu")
		(net "GMI_CPU0_G0_CPU1_G2_TX_DP<2>")
	)
	(arc
		(start 114.33175 -222.303594)
		(mid 114.509664 -222.610047)
		(end 114.33937 -222.920814)
		(width 0.1143)
		(layer "In13.Cu")
		(net "GMI_CPU0_G0_CPU1_G2_TX_DP<2>")
	)
	(arc
		(start 357.184452 -223.911668)
		(mid 357.464879 -223.424432)
		(end 357.184452 -222.93707)
		(width 0.1143)
		(layer "In13.Cu")
		(net "GMI_CPU0_G0_CPU1_G2_TX_DP<2>")
	)
	(arc
		(start 114.343434 -223.93021)
		(mid 114.499362 -224.234502)
		(end 114.343434 -224.538794)
		(width 0.1143)
		(layer "In13.Cu")
		(net "GMI_CPU0_G0_CPU1_G2_TX_DP<2>")
	)
	(arc
		(start 357.152448 -232.638346)
		(mid 356.99652 -232.334054)
		(end 357.152448 -232.029762)
		(width 0.1143)
		(layer "In13.Cu")
		(net "GMI_CPU0_G0_CPU1_G2_TX_DP<2>")
	)
	(arc
		(start 357.152448 -234.258358)
		(mid 356.99652 -233.954066)
		(end 357.152448 -233.649774)
		(width 0.1143)
		(layer "In13.Cu")
		(net "GMI_CPU0_G0_CPU1_G2_TX_DP<2>")
	)
	(arc
		(start 357.184452 -235.251498)
		(mid 357.464879 -234.764262)
		(end 357.184452 -234.2769)
		(width 0.1143)
		(layer "In13.Cu")
		(net "GMI_CPU0_G0_CPU1_G2_TX_DP<2>")
	)
	(arc
		(start 114.343434 -238.510064)
		(mid 114.440569 -238.612933)
		(end 114.492532 -238.744506)
		(width 0.1143)
		(layer "In13.Cu")
		(net "GMI_CPU0_G0_CPU1_G2_TX_DP<2>")
	)
	(arc
		(start 357.184452 -227.151692)
		(mid 357.464879 -226.664456)
		(end 357.184452 -226.177094)
		(width 0.1143)
		(layer "In13.Cu")
		(net "GMI_CPU0_G0_CPU1_G2_TX_DP<2>")
	)
	(arc
		(start 114.49939 -229.094538)
		(mid 114.458628 -229.264422)
		(end 114.345212 -229.397306)
		(width 0.1143)
		(layer "In13.Cu")
		(net "GMI_CPU0_G0_CPU1_G2_TX_DP<2>")
	)
	(arc
		(start 357.15067 -229.397052)
		(mid 357.037263 -229.264163)
		(end 356.996492 -229.094284)
		(width 0.1143)
		(layer "In13.Cu")
		(net "GMI_CPU0_G0_CPU1_G2_TX_DP<2>")
	)
	(arc
		(start 356.996492 -230.714296)
		(mid 357.037747 -230.543325)
		(end 357.152448 -230.410004)
		(width 0.1143)
		(layer "In13.Cu")
		(net "GMI_CPU0_G0_CPU1_G2_TX_DP<2>")
	)
	(arc
		(start 357.217726 -230.372158)
		(mid 357.389443 -230.163273)
		(end 357.466392 -229.904036)
		(width 0.1143)
		(layer "In13.Cu")
		(net "GMI_CPU0_G0_CPU1_G2_TX_DP<2>")
	)
	(arc
		(start 114.343434 -227.170234)
		(mid 114.499362 -227.474526)
		(end 114.343434 -227.778818)
		(width 0.1143)
		(layer "In13.Cu")
		(net "GMI_CPU0_G0_CPU1_G2_TX_DP<2>")
	)
	(arc
		(start 114.31143 -222.937324)
		(mid 114.030783 -223.424686)
		(end 114.31143 -223.911922)
		(width 0.1143)
		(layer "In13.Cu")
		(net "GMI_CPU0_G0_CPU1_G2_TX_DP<2>")
	)
	(arc
		(start 357.466392 -229.904036)
		(mid 357.404947 -229.647824)
		(end 357.233982 -229.447344)
		(width 0.1143)
		(layer "In13.Cu")
		(net "GMI_CPU0_G0_CPU1_G2_TX_DP<2>")
	)
	(arc
		(start 114.31143 -227.79736)
		(mid 114.030783 -228.284722)
		(end 114.31143 -228.771958)
		(width 0.1143)
		(layer "In13.Cu")
		(net "GMI_CPU0_G0_CPU1_G2_TX_DP<2>")
	)
	(arc
		(start 114.2619 -229.447598)
		(mid 114.09093 -229.648075)
		(end 114.02949 -229.90429)
		(width 0.1143)
		(layer "In13.Cu")
		(net "GMI_CPU0_G0_CPU1_G2_TX_DP<2>")
	)
	(arc
		(start 357.184452 -225.53168)
		(mid 357.464879 -225.044444)
		(end 357.184452 -224.557082)
		(width 0.1143)
		(layer "In13.Cu")
		(net "GMI_CPU0_G0_CPU1_G2_TX_DP<2>")
	)
	(arc
		(start 357.152448 -235.87837)
		(mid 356.99652 -235.574078)
		(end 357.152448 -235.269786)
		(width 0.1143)
		(layer "In13.Cu")
		(net "GMI_CPU0_G0_CPU1_G2_TX_DP<2>")
	)
	(arc
		(start 357.156512 -222.92056)
		(mid 356.986192 -222.609793)
		(end 357.164132 -222.30334)
		(width 0.1143)
		(layer "In13.Cu")
		(net "GMI_CPU0_G0_CPU1_G2_TX_DP<2>")
	)
	(arc
		(start 114.244882 -235.939584)
		(mid 114.016882 -236.384338)
		(end 114.244882 -236.829092)
		(width 0.1143)
		(layer "In13.Cu")
		(net "GMI_CPU0_G0_CPU1_G2_TX_DP<2>")
	)
	(arc
		(start 114.02949 -221.804738)
		(mid 114.057446 -221.98058)
		(end 114.13871 -222.139002)
		(width 0.1143)
		(layer "In13.Cu")
		(net "GMI_CPU0_G0_CPU1_G2_TX_DP<2>")
	)
	(arc
		(start 357.15067 -231.017064)
		(mid 357.037263 -230.884175)
		(end 356.996492 -230.714296)
		(width 0.1143)
		(layer "In13.Cu")
		(net "GMI_CPU0_G0_CPU1_G2_TX_DP<2>")
	)
	(arc
		(start 114.31143 -232.657142)
		(mid 114.030783 -233.144504)
		(end 114.31143 -233.63174)
		(width 0.1143)
		(layer "In13.Cu")
		(net "GMI_CPU0_G0_CPU1_G2_TX_DP<2>")
	)
	(arc
		(start 114.49939 -230.71455)
		(mid 114.458628 -230.884434)
		(end 114.345212 -231.017318)
		(width 0.1143)
		(layer "In13.Cu")
		(net "GMI_CPU0_G0_CPU1_G2_TX_DP<2>")
	)
	(segment
		(start 113.657888 -240.700306)
		(end 114.12474 -240.434368)
		(width 0.12954)
		(layer "F.Cu")
		(net "GMI_CPU0_G0_CPU1_G2_TX_DP<1>")
	)
	(segment
		(start 357.837994 -240.700052)
		(end 357.371142 -240.434114)
		(width 0.12954)
		(layer "F.Cu")
		(net "GMI_CPU0_G0_CPU1_G2_TX_DP<1>")
	)
	(segment
		(start 113.371884 -238.491776)
		(end 113.402364 -238.509556)
		(width 0.1143)
		(layer "In13.Cu")
		(net "GMI_CPU0_G0_CPU1_G2_TX_DP<1>")
	)
	(segment
		(start 358.093518 -230.409496)
		(end 358.157526 -230.372158)
		(width 0.1143)
		(layer "In13.Cu")
		(net "GMI_CPU0_G0_CPU1_G2_TX_DP<1>")
	)
	(segment
		(start 358.520492 -221.100142)
		(end 358.520492 -221.093538)
		(width 0.1143)
		(layer "In13.Cu")
		(net "GMI_CPU0_G0_CPU1_G2_TX_DP<1>")
	)
	(segment
		(start 358.123998 -235.896658)
		(end 358.093518 -235.878878)
		(width 0.1143)
		(layer "In13.Cu")
		(net "GMI_CPU0_G0_CPU1_G2_TX_DP<1>")
	)
	(segment
		(start 358.16159 -229.438454)
		(end 358.091486 -229.397814)
		(width 0.1143)
		(layer "In13.Cu")
		(net "GMI_CPU0_G0_CPU1_G2_TX_DP<1>")
	)
	(segment
		(start 357.660194 -239.297972)
		(end 357.685594 -239.28324)
		(width 0.1143)
		(layer "In13.Cu")
		(net "GMI_CPU0_G0_CPU1_G2_TX_DP<1>")
	)
	(segment
		(start 358.093518 -225.54946)
		(end 358.123998 -225.53168)
		(width 0.1143)
		(layer "In13.Cu")
		(net "GMI_CPU0_G0_CPU1_G2_TX_DP<1>")
	)
	(segment
		(start 358.123998 -224.556828)
		(end 358.093518 -224.539048)
		(width 0.1143)
		(layer "In13.Cu")
		(net "GMI_CPU0_G0_CPU1_G2_TX_DP<1>")
	)
	(segment
		(start 112.97539 -221.100396)
		(end 113.02111 -221.146116)
		(width 0.1143)
		(layer "In13.Cu")
		(net "GMI_CPU0_G0_CPU1_G2_TX_DP<1>")
	)
	(segment
		(start 357.685594 -239.28324)
		(end 357.686356 -239.282732)
		(width 0.1143)
		(layer "In13.Cu")
		(net "GMI_CPU0_G0_CPU1_G2_TX_DP<1>")
	)
	(segment
		(start 358.520492 -216.744804)
		(end 354.9523 -210.734656)
		(width 0.14224)
		(layer "In13.Cu")
		(net "GMI_CPU0_G0_CPU1_G2_TX_DP<1>")
	)
	(segment
		(start 113.335562 -223.89084)
		(end 113.371884 -223.911922)
		(width 0.1143)
		(layer "In13.Cu")
		(net "GMI_CPU0_G0_CPU1_G2_TX_DP<1>")
	)
	(segment
		(start 113.402364 -237.499144)
		(end 113.371884 -237.516924)
		(width 0.1143)
		(layer "In13.Cu")
		(net "GMI_CPU0_G0_CPU1_G2_TX_DP<1>")
	)
	(segment
		(start 113.371884 -231.036876)
		(end 113.35131 -231.048814)
		(width 0.1143)
		(layer "In13.Cu")
		(net "GMI_CPU0_G0_CPU1_G2_TX_DP<1>")
	)
	(segment
		(start 358.145334 -231.049068)
		(end 358.144572 -231.04856)
		(width 0.1143)
		(layer "In13.Cu")
		(net "GMI_CPU0_G0_CPU1_G2_TX_DP<1>")
	)
	(segment
		(start 357.622348 -239.319816)
		(end 357.653336 -239.302036)
		(width 0.1143)
		(layer "In13.Cu")
		(net "GMI_CPU0_G0_CPU1_G2_TX_DP<1>")
	)
	(segment
		(start 358.16032 -222.957898)
		(end 358.093518 -222.919036)
		(width 0.1143)
		(layer "In13.Cu")
		(net "GMI_CPU0_G0_CPU1_G2_TX_DP<1>")
	)
	(segment
		(start 113.370868 -222.29318)
		(end 113.373916 -222.294958)
		(width 0.1143)
		(layer "In13.Cu")
		(net "GMI_CPU0_G0_CPU1_G2_TX_DP<1>")
	)
	(segment
		(start 113.371884 -235.251752)
		(end 113.402364 -235.269532)
		(width 0.1143)
		(layer "In13.Cu")
		(net "GMI_CPU0_G0_CPU1_G2_TX_DP<1>")
	)
	(segment
		(start 358.406446 -221.450408)
		(end 358.474772 -221.382082)
		(width 0.1143)
		(layer "In13.Cu")
		(net "GMI_CPU0_G0_CPU1_G2_TX_DP<1>")
	)
	(segment
		(start 354.9523 -210.734656)
		(end 318.16675 -180.572156)
		(width 0.14224)
		(layer "In13.Cu")
		(net "GMI_CPU0_G0_CPU1_G2_TX_DP<1>")
	)
	(segment
		(start 113.335562 -238.470694)
		(end 113.371884 -238.491776)
		(width 0.1143)
		(layer "In13.Cu")
		(net "GMI_CPU0_G0_CPU1_G2_TX_DP<1>")
	)
	(segment
		(start 113.371884 -237.516924)
		(end 113.335562 -237.538006)
		(width 0.1143)
		(layer "In13.Cu")
		(net "GMI_CPU0_G0_CPU1_G2_TX_DP<1>")
	)
	(segment
		(start 358.406446 -221.80423)
		(end 358.406446 -221.450408)
		(width 0.1143)
		(layer "In13.Cu")
		(net "GMI_CPU0_G0_CPU1_G2_TX_DP<1>")
	)
	(segment
		(start 358.16032 -226.197922)
		(end 358.123998 -226.17684)
		(width 0.1143)
		(layer "In13.Cu")
		(net "GMI_CPU0_G0_CPU1_G2_TX_DP<1>")
	)
	(segment
		(start 113.335562 -236.850682)
		(end 113.371884 -236.871764)
		(width 0.1143)
		(layer "In13.Cu")
		(net "GMI_CPU0_G0_CPU1_G2_TX_DP<1>")
	)
	(segment
		(start 358.123998 -238.491522)
		(end 358.16032 -238.47044)
		(width 0.1143)
		(layer "In13.Cu")
		(net "GMI_CPU0_G0_CPU1_G2_TX_DP<1>")
	)
	(segment
		(start 114.422682 -240.434368)
		(end 114.12474 -240.434368)
		(width 0.1143)
		(layer "In13.Cu")
		(net "GMI_CPU0_G0_CPU1_G2_TX_DP<1>")
	)
	(segment
		(start 114.275362 -240.090706)
		(end 114.343434 -240.130076)
		(width 0.1143)
		(layer "In13.Cu")
		(net "GMI_CPU0_G0_CPU1_G2_TX_DP<1>")
	)
	(segment
		(start 357.654098 -239.301528)
		(end 357.655114 -239.30102)
		(width 0.1143)
		(layer "In13.Cu")
		(net "GMI_CPU0_G0_CPU1_G2_TX_DP<1>")
	)
	(segment
		(start 113.371884 -234.2769)
		(end 113.335562 -234.297982)
		(width 0.1143)
		(layer "In13.Cu")
		(net "GMI_CPU0_G0_CPU1_G2_TX_DP<1>")
	)
	(segment
		(start 113.371884 -223.911922)
		(end 113.402364 -223.929702)
		(width 0.1143)
		(layer "In13.Cu")
		(net "GMI_CPU0_G0_CPU1_G2_TX_DP<1>")
	)
	(segment
		(start 113.402364 -222.91929)
		(end 113.335562 -222.958152)
		(width 0.1143)
		(layer "In13.Cu")
		(net "GMI_CPU0_G0_CPU1_G2_TX_DP<1>")
	)
	(segment
		(start 113.402364 -224.539302)
		(end 113.371884 -224.557082)
		(width 0.1143)
		(layer "In13.Cu")
		(net "GMI_CPU0_G0_CPU1_G2_TX_DP<1>")
	)
	(segment
		(start 358.121966 -222.294704)
		(end 358.125014 -222.292926)
		(width 0.1143)
		(layer "In13.Cu")
		(net "GMI_CPU0_G0_CPU1_G2_TX_DP<1>")
	)
	(segment
		(start 113.371884 -236.871764)
		(end 113.402364 -236.889544)
		(width 0.1143)
		(layer "In13.Cu")
		(net "GMI_CPU0_G0_CPU1_G2_TX_DP<1>")
	)
	(segment
		(start 358.520492 -221.093538)
		(end 358.520492 -216.744804)
		(width 0.14224)
		(layer "In13.Cu")
		(net "GMI_CPU0_G0_CPU1_G2_TX_DP<1>")
	)
	(segment
		(start 113.371884 -226.177094)
		(end 113.335562 -226.198176)
		(width 0.1143)
		(layer "In13.Cu")
		(net "GMI_CPU0_G0_CPU1_G2_TX_DP<1>")
	)
	(segment
		(start 358.144572 -231.04856)
		(end 358.123998 -231.036622)
		(width 0.1143)
		(layer "In13.Cu")
		(net "GMI_CPU0_G0_CPU1_G2_TX_DP<1>")
	)
	(segment
		(start 113.371884 -225.531934)
		(end 113.402364 -225.549714)
		(width 0.1143)
		(layer "In13.Cu")
		(net "GMI_CPU0_G0_CPU1_G2_TX_DP<1>")
	)
	(segment
		(start 165.00094 -174.934372)
		(end 156.372306 -178.019964)
		(width 0.14224)
		(layer "In13.Cu")
		(net "GMI_CPU0_G0_CPU1_G2_TX_DP<1>")
	)
	(segment
		(start 358.123998 -234.276646)
		(end 358.093518 -234.258866)
		(width 0.1143)
		(layer "In13.Cu")
		(net "GMI_CPU0_G0_CPU1_G2_TX_DP<1>")
	)
	(segment
		(start 113.335562 -228.750876)
		(end 113.371884 -228.771958)
		(width 0.1143)
		(layer "In13.Cu")
		(net "GMI_CPU0_G0_CPU1_G2_TX_DP<1>")
	)
	(segment
		(start 358.123998 -235.251498)
		(end 358.16032 -235.230416)
		(width 0.1143)
		(layer "In13.Cu")
		(net "GMI_CPU0_G0_CPU1_G2_TX_DP<1>")
	)
	(segment
		(start 358.123998 -223.911668)
		(end 358.16032 -223.890586)
		(width 0.1143)
		(layer "In13.Cu")
		(net "GMI_CPU0_G0_CPU1_G2_TX_DP<1>")
	)
	(segment
		(start 113.841784 -239.301782)
		(end 113.842546 -239.30229)
		(width 0.1143)
		(layer "In13.Cu")
		(net "GMI_CPU0_G0_CPU1_G2_TX_DP<1>")
	)
	(segment
		(start 113.02111 -221.382336)
		(end 113.089436 -221.450662)
		(width 0.1143)
		(layer "In13.Cu")
		(net "GMI_CPU0_G0_CPU1_G2_TX_DP<1>")
	)
	(segment
		(start 358.16032 -235.91774)
		(end 358.123998 -235.896658)
		(width 0.1143)
		(layer "In13.Cu")
		(net "GMI_CPU0_G0_CPU1_G2_TX_DP<1>")
	)
	(segment
		(start 358.123998 -225.53168)
		(end 358.16032 -225.510598)
		(width 0.1143)
		(layer "In13.Cu")
		(net "GMI_CPU0_G0_CPU1_G2_TX_DP<1>")
	)
	(segment
		(start 113.810288 -239.283494)
		(end 113.840768 -239.301274)
		(width 0.1143)
		(layer "In13.Cu")
		(net "GMI_CPU0_G0_CPU1_G2_TX_DP<1>")
	)
	(segment
		(start 113.404396 -229.398068)
		(end 113.334292 -229.438708)
		(width 0.1143)
		(layer "In13.Cu")
		(net "GMI_CPU0_G0_CPU1_G2_TX_DP<1>")
	)
	(segment
		(start 358.474772 -221.145862)
		(end 358.520492 -221.100142)
		(width 0.1143)
		(layer "In13.Cu")
		(net "GMI_CPU0_G0_CPU1_G2_TX_DP<1>")
	)
	(segment
		(start 358.123998 -237.51667)
		(end 358.093518 -237.49889)
		(width 0.1143)
		(layer "In13.Cu")
		(net "GMI_CPU0_G0_CPU1_G2_TX_DP<1>")
	)
	(segment
		(start 113.371884 -228.771958)
		(end 113.402364 -228.789738)
		(width 0.1143)
		(layer "In13.Cu")
		(net "GMI_CPU0_G0_CPU1_G2_TX_DP<1>")
	)
	(segment
		(start 358.093518 -232.029254)
		(end 358.145334 -231.999028)
		(width 0.1143)
		(layer "In13.Cu")
		(net "GMI_CPU0_G0_CPU1_G2_TX_DP<1>")
	)
	(segment
		(start 113.809526 -239.282986)
		(end 113.810288 -239.283494)
		(width 0.1143)
		(layer "In13.Cu")
		(net "GMI_CPU0_G0_CPU1_G2_TX_DP<1>")
	)
	(segment
		(start 358.093518 -238.509302)
		(end 358.123998 -238.491522)
		(width 0.1143)
		(layer "In13.Cu")
		(net "GMI_CPU0_G0_CPU1_G2_TX_DP<1>")
	)
	(segment
		(start 358.123998 -232.656634)
		(end 358.093518 -232.638854)
		(width 0.1143)
		(layer "In13.Cu")
		(net "GMI_CPU0_G0_CPU1_G2_TX_DP<1>")
	)
	(segment
		(start 113.402364 -227.779326)
		(end 113.371884 -227.797106)
		(width 0.1143)
		(layer "In13.Cu")
		(net "GMI_CPU0_G0_CPU1_G2_TX_DP<1>")
	)
	(segment
		(start 113.404396 -231.01808)
		(end 113.371884 -231.036876)
		(width 0.1143)
		(layer "In13.Cu")
		(net "GMI_CPU0_G0_CPU1_G2_TX_DP<1>")
	)
	(segment
		(start 358.093518 -223.929448)
		(end 358.123998 -223.911668)
		(width 0.1143)
		(layer "In13.Cu")
		(net "GMI_CPU0_G0_CPU1_G2_TX_DP<1>")
	)
	(segment
		(start 358.16032 -227.817934)
		(end 358.123998 -227.796852)
		(width 0.1143)
		(layer "In13.Cu")
		(net "GMI_CPU0_G0_CPU1_G2_TX_DP<1>")
	)
	(segment
		(start 311.36844 -176.723802)
		(end 308.619652 -175.740822)
		(width 0.14224)
		(layer "In13.Cu")
		(net "GMI_CPU0_G0_CPU1_G2_TX_DP<1>")
	)
	(segment
		(start 357.0732 -240.434114)
		(end 357.00335 -240.364264)
		(width 0.1143)
		(layer "In13.Cu")
		(net "GMI_CPU0_G0_CPU1_G2_TX_DP<1>")
	)
	(segment
		(start 358.093518 -236.88929)
		(end 358.123998 -236.87151)
		(width 0.1143)
		(layer "In13.Cu")
		(net "GMI_CPU0_G0_CPU1_G2_TX_DP<1>")
	)
	(segment
		(start 358.093518 -228.789484)
		(end 358.123998 -228.771704)
		(width 0.1143)
		(layer "In13.Cu")
		(net "GMI_CPU0_G0_CPU1_G2_TX_DP<1>")
	)
	(segment
		(start 308.619652 -175.740822)
		(end 302.917352 -175.740822)
		(width 0.14224)
		(layer "In13.Cu")
		(net "GMI_CPU0_G0_CPU1_G2_TX_DP<1>")
	)
	(segment
		(start 358.093518 -235.269278)
		(end 358.123998 -235.251498)
		(width 0.1143)
		(layer "In13.Cu")
		(net "GMI_CPU0_G0_CPU1_G2_TX_DP<1>")
	)
	(segment
		(start 358.16032 -232.677716)
		(end 358.123998 -232.656634)
		(width 0.1143)
		(layer "In13.Cu")
		(net "GMI_CPU0_G0_CPU1_G2_TX_DP<1>")
	)
	(segment
		(start 113.371884 -232.656888)
		(end 113.335562 -232.67797)
		(width 0.1143)
		(layer "In13.Cu")
		(net "GMI_CPU0_G0_CPU1_G2_TX_DP<1>")
	)
	(segment
		(start 113.840768 -239.301274)
		(end 113.841784 -239.301782)
		(width 0.1143)
		(layer "In13.Cu")
		(net "GMI_CPU0_G0_CPU1_G2_TX_DP<1>")
	)
	(segment
		(start 358.093518 -233.649266)
		(end 358.123998 -233.631486)
		(width 0.1143)
		(layer "In13.Cu")
		(net "GMI_CPU0_G0_CPU1_G2_TX_DP<1>")
	)
	(segment
		(start 358.123998 -233.631486)
		(end 358.16032 -233.610404)
		(width 0.1143)
		(layer "In13.Cu")
		(net "GMI_CPU0_G0_CPU1_G2_TX_DP<1>")
	)
	(segment
		(start 113.371884 -235.896912)
		(end 113.335562 -235.917994)
		(width 0.1143)
		(layer "In13.Cu")
		(net "GMI_CPU0_G0_CPU1_G2_TX_DP<1>")
	)
	(segment
		(start 113.402364 -232.639108)
		(end 113.371884 -232.656888)
		(width 0.1143)
		(layer "In13.Cu")
		(net "GMI_CPU0_G0_CPU1_G2_TX_DP<1>")
	)
	(segment
		(start 357.686356 -239.282732)
		(end 357.693214 -239.278668)
		(width 0.1143)
		(layer "In13.Cu")
		(net "GMI_CPU0_G0_CPU1_G2_TX_DP<1>")
	)
	(segment
		(start 358.123998 -228.771704)
		(end 358.16032 -228.750622)
		(width 0.1143)
		(layer "In13.Cu")
		(net "GMI_CPU0_G0_CPU1_G2_TX_DP<1>")
	)
	(segment
		(start 113.371884 -224.557082)
		(end 113.335562 -224.578164)
		(width 0.1143)
		(layer "In13.Cu")
		(net "GMI_CPU0_G0_CPU1_G2_TX_DP<1>")
	)
	(segment
		(start 357.659432 -239.29848)
		(end 357.660194 -239.297972)
		(width 0.1143)
		(layer "In13.Cu")
		(net "GMI_CPU0_G0_CPU1_G2_TX_DP<1>")
	)
	(segment
		(start 358.16032 -237.537752)
		(end 358.123998 -237.51667)
		(width 0.1143)
		(layer "In13.Cu")
		(net "GMI_CPU0_G0_CPU1_G2_TX_DP<1>")
	)
	(segment
		(start 357.371142 -240.434114)
		(end 357.0732 -240.434114)
		(width 0.1143)
		(layer "In13.Cu")
		(net "GMI_CPU0_G0_CPU1_G2_TX_DP<1>")
	)
	(segment
		(start 113.371884 -227.797106)
		(end 113.335562 -227.818188)
		(width 0.1143)
		(layer "In13.Cu")
		(net "GMI_CPU0_G0_CPU1_G2_TX_DP<1>")
	)
	(segment
		(start 113.350548 -231.999282)
		(end 113.402364 -232.029508)
		(width 0.1143)
		(layer "In13.Cu")
		(net "GMI_CPU0_G0_CPU1_G2_TX_DP<1>")
	)
	(segment
		(start 302.917352 -175.740822)
		(end 165.00094 -174.934372)
		(width 0.14224)
		(layer "In13.Cu")
		(net "GMI_CPU0_G0_CPU1_G2_TX_DP<1>")
	)
	(segment
		(start 358.123998 -226.17684)
		(end 358.093518 -226.15906)
		(width 0.1143)
		(layer "In13.Cu")
		(net "GMI_CPU0_G0_CPU1_G2_TX_DP<1>")
	)
	(segment
		(start 358.123998 -236.87151)
		(end 358.16032 -236.850428)
		(width 0.1143)
		(layer "In13.Cu")
		(net "GMI_CPU0_G0_CPU1_G2_TX_DP<1>")
	)
	(segment
		(start 112.97539 -221.071948)
		(end 112.97539 -221.100396)
		(width 0.1143)
		(layer "In13.Cu")
		(net "GMI_CPU0_G0_CPU1_G2_TX_DP<1>")
	)
	(segment
		(start 113.371884 -227.151946)
		(end 113.402364 -227.169726)
		(width 0.1143)
		(layer "In13.Cu")
		(net "GMI_CPU0_G0_CPU1_G2_TX_DP<1>")
	)
	(segment
		(start 358.16032 -224.57791)
		(end 358.123998 -224.556828)
		(width 0.1143)
		(layer "In13.Cu")
		(net "GMI_CPU0_G0_CPU1_G2_TX_DP<1>")
	)
	(segment
		(start 113.02111 -221.146116)
		(end 113.02111 -221.382336)
		(width 0.1143)
		(layer "In13.Cu")
		(net "GMI_CPU0_G0_CPU1_G2_TX_DP<1>")
	)
	(segment
		(start 113.402364 -226.159314)
		(end 113.371884 -226.177094)
		(width 0.1143)
		(layer "In13.Cu")
		(net "GMI_CPU0_G0_CPU1_G2_TX_DP<1>")
	)
	(segment
		(start 357.653336 -239.302036)
		(end 357.654098 -239.301528)
		(width 0.1143)
		(layer "In13.Cu")
		(net "GMI_CPU0_G0_CPU1_G2_TX_DP<1>")
	)
	(segment
		(start 357.152448 -240.129822)
		(end 357.22052 -240.090452)
		(width 0.1143)
		(layer "In13.Cu")
		(net "GMI_CPU0_G0_CPU1_G2_TX_DP<1>")
	)
	(segment
		(start 113.842546 -239.30229)
		(end 113.873534 -239.32007)
		(width 0.1143)
		(layer "In13.Cu")
		(net "GMI_CPU0_G0_CPU1_G2_TX_DP<1>")
	)
	(segment
		(start 113.335562 -233.610658)
		(end 113.371884 -233.63174)
		(width 0.1143)
		(layer "In13.Cu")
		(net "GMI_CPU0_G0_CPU1_G2_TX_DP<1>")
	)
	(segment
		(start 358.16032 -234.297728)
		(end 358.123998 -234.276646)
		(width 0.1143)
		(layer "In13.Cu")
		(net "GMI_CPU0_G0_CPU1_G2_TX_DP<1>")
	)
	(segment
		(start 358.123998 -231.036622)
		(end 358.091486 -231.017826)
		(width 0.1143)
		(layer "In13.Cu")
		(net "GMI_CPU0_G0_CPU1_G2_TX_DP<1>")
	)
	(segment
		(start 358.093518 -227.169472)
		(end 358.123998 -227.151692)
		(width 0.1143)
		(layer "In13.Cu")
		(net "GMI_CPU0_G0_CPU1_G2_TX_DP<1>")
	)
	(segment
		(start 112.97539 -216.623392)
		(end 112.97539 -221.071948)
		(width 0.14224)
		(layer "In13.Cu")
		(net "GMI_CPU0_G0_CPU1_G2_TX_DP<1>")
	)
	(segment
		(start 156.372306 -178.019964)
		(end 116.397278 -210.798156)
		(width 0.14224)
		(layer "In13.Cu")
		(net "GMI_CPU0_G0_CPU1_G2_TX_DP<1>")
	)
	(segment
		(start 318.16675 -180.572156)
		(end 311.36844 -176.723802)
		(width 0.14224)
		(layer "In13.Cu")
		(net "GMI_CPU0_G0_CPU1_G2_TX_DP<1>")
	)
	(segment
		(start 114.492532 -240.364518)
		(end 114.422682 -240.434368)
		(width 0.1143)
		(layer "In13.Cu")
		(net "GMI_CPU0_G0_CPU1_G2_TX_DP<1>")
	)
	(segment
		(start 358.123998 -227.151692)
		(end 358.16032 -227.13061)
		(width 0.1143)
		(layer "In13.Cu")
		(net "GMI_CPU0_G0_CPU1_G2_TX_DP<1>")
	)
	(segment
		(start 116.397278 -210.798156)
		(end 112.97539 -216.623392)
		(width 0.14224)
		(layer "In13.Cu")
		(net "GMI_CPU0_G0_CPU1_G2_TX_DP<1>")
	)
	(segment
		(start 113.089436 -221.450662)
		(end 113.089436 -221.804484)
		(width 0.1143)
		(layer "In13.Cu")
		(net "GMI_CPU0_G0_CPU1_G2_TX_DP<1>")
	)
	(segment
		(start 113.35131 -231.048814)
		(end 113.350548 -231.049322)
		(width 0.1143)
		(layer "In13.Cu")
		(net "GMI_CPU0_G0_CPU1_G2_TX_DP<1>")
	)
	(segment
		(start 113.335562 -227.130864)
		(end 113.371884 -227.151946)
		(width 0.1143)
		(layer "In13.Cu")
		(net "GMI_CPU0_G0_CPU1_G2_TX_DP<1>")
	)
	(segment
		(start 113.371884 -233.63174)
		(end 113.402364 -233.64952)
		(width 0.1143)
		(layer "In13.Cu")
		(net "GMI_CPU0_G0_CPU1_G2_TX_DP<1>")
	)
	(segment
		(start 357.655114 -239.30102)
		(end 357.659432 -239.29848)
		(width 0.1143)
		(layer "In13.Cu")
		(net "GMI_CPU0_G0_CPU1_G2_TX_DP<1>")
	)
	(segment
		(start 358.123998 -227.796852)
		(end 358.093518 -227.779072)
		(width 0.1143)
		(layer "In13.Cu")
		(net "GMI_CPU0_G0_CPU1_G2_TX_DP<1>")
	)
	(segment
		(start 113.802668 -239.278922)
		(end 113.809526 -239.282986)
		(width 0.1143)
		(layer "In13.Cu")
		(net "GMI_CPU0_G0_CPU1_G2_TX_DP<1>")
	)
	(segment
		(start 113.335562 -225.510852)
		(end 113.371884 -225.531934)
		(width 0.1143)
		(layer "In13.Cu")
		(net "GMI_CPU0_G0_CPU1_G2_TX_DP<1>")
	)
	(segment
		(start 113.402364 -234.25912)
		(end 113.371884 -234.2769)
		(width 0.1143)
		(layer "In13.Cu")
		(net "GMI_CPU0_G0_CPU1_G2_TX_DP<1>")
	)
	(segment
		(start 113.335562 -235.23067)
		(end 113.371884 -235.251752)
		(width 0.1143)
		(layer "In13.Cu")
		(net "GMI_CPU0_G0_CPU1_G2_TX_DP<1>")
	)
	(segment
		(start 113.402364 -235.879132)
		(end 113.371884 -235.896912)
		(width 0.1143)
		(layer "In13.Cu")
		(net "GMI_CPU0_G0_CPU1_G2_TX_DP<1>")
	)
	(segment
		(start 358.474772 -221.382082)
		(end 358.474772 -221.145862)
		(width 0.1143)
		(layer "In13.Cu")
		(net "GMI_CPU0_G0_CPU1_G2_TX_DP<1>")
	)
	(segment
		(start 113.338356 -230.372412)
		(end 113.402364 -230.40975)
		(width 0.1143)
		(layer "In13.Cu")
		(net "GMI_CPU0_G0_CPU1_G2_TX_DP<1>")
	)
	(arc
		(start 113.335562 -222.958152)
		(mid 113.089672 -223.424496)
		(end 113.335562 -223.89084)
		(width 0.1143)
		(layer "In13.Cu")
		(net "GMI_CPU0_G0_CPU1_G2_TX_DP<1>")
	)
	(arc
		(start 113.165128 -230.186738)
		(mid 113.241169 -230.289441)
		(end 113.338356 -230.372412)
		(width 0.1143)
		(layer "In13.Cu")
		(net "GMI_CPU0_G0_CPU1_G2_TX_DP<1>")
	)
	(arc
		(start 113.335562 -224.578164)
		(mid 113.089672 -225.044508)
		(end 113.335562 -225.510852)
		(width 0.1143)
		(layer "In13.Cu")
		(net "GMI_CPU0_G0_CPU1_G2_TX_DP<1>")
	)
	(arc
		(start 113.373916 -222.294958)
		(mid 113.509619 -222.429775)
		(end 113.559336 -222.61449)
		(width 0.1143)
		(layer "In13.Cu")
		(net "GMI_CPU0_G0_CPU1_G2_TX_DP<1>")
	)
	(arc
		(start 357.22052 -240.090452)
		(mid 357.381588 -239.897754)
		(end 357.462328 -239.659922)
		(width 0.1143)
		(layer "In13.Cu")
		(net "GMI_CPU0_G0_CPU1_G2_TX_DP<1>")
	)
	(arc
		(start 358.093518 -224.539048)
		(mid 357.936541 -224.234248)
		(end 358.093518 -223.929448)
		(width 0.1143)
		(layer "In13.Cu")
		(net "GMI_CPU0_G0_CPU1_G2_TX_DP<1>")
	)
	(arc
		(start 358.093518 -222.919036)
		(mid 357.978091 -222.78566)
		(end 357.936546 -222.614236)
		(width 0.1143)
		(layer "In13.Cu")
		(net "GMI_CPU0_G0_CPU1_G2_TX_DP<1>")
	)
	(arc
		(start 357.936546 -222.614236)
		(mid 357.986257 -222.429517)
		(end 358.121966 -222.294704)
		(width 0.1143)
		(layer "In13.Cu")
		(net "GMI_CPU0_G0_CPU1_G2_TX_DP<1>")
	)
	(arc
		(start 113.402364 -227.169726)
		(mid 113.559341 -227.474526)
		(end 113.402364 -227.779326)
		(width 0.1143)
		(layer "In13.Cu")
		(net "GMI_CPU0_G0_CPU1_G2_TX_DP<1>")
	)
	(arc
		(start 113.335562 -237.538006)
		(mid 113.089672 -238.00435)
		(end 113.335562 -238.470694)
		(width 0.1143)
		(layer "In13.Cu")
		(net "GMI_CPU0_G0_CPU1_G2_TX_DP<1>")
	)
	(arc
		(start 113.350548 -231.049322)
		(mid 113.076997 -231.524302)
		(end 113.350548 -231.999282)
		(width 0.1143)
		(layer "In13.Cu")
		(net "GMI_CPU0_G0_CPU1_G2_TX_DP<1>")
	)
	(arc
		(start 114.033554 -239.660176)
		(mid 114.114222 -239.898048)
		(end 114.275362 -240.090706)
		(width 0.1143)
		(layer "In13.Cu")
		(net "GMI_CPU0_G0_CPU1_G2_TX_DP<1>")
	)
	(arc
		(start 113.402364 -238.509556)
		(mid 113.517791 -238.642932)
		(end 113.559336 -238.814356)
		(width 0.1143)
		(layer "In13.Cu")
		(net "GMI_CPU0_G0_CPU1_G2_TX_DP<1>")
	)
	(arc
		(start 357.693214 -239.278668)
		(mid 357.872027 -239.076318)
		(end 357.936546 -238.814102)
		(width 0.1143)
		(layer "In13.Cu")
		(net "GMI_CPU0_G0_CPU1_G2_TX_DP<1>")
	)
	(arc
		(start 113.559336 -229.094538)
		(mid 113.51837 -229.264944)
		(end 113.404396 -229.398068)
		(width 0.1143)
		(layer "In13.Cu")
		(net "GMI_CPU0_G0_CPU1_G2_TX_DP<1>")
	)
	(arc
		(start 358.16032 -225.510598)
		(mid 358.40621 -225.044254)
		(end 358.16032 -224.57791)
		(width 0.1143)
		(layer "In13.Cu")
		(net "GMI_CPU0_G0_CPU1_G2_TX_DP<1>")
	)
	(arc
		(start 357.936546 -230.714296)
		(mid 357.978095 -230.542874)
		(end 358.093518 -230.409496)
		(width 0.1143)
		(layer "In13.Cu")
		(net "GMI_CPU0_G0_CPU1_G2_TX_DP<1>")
	)
	(arc
		(start 358.093518 -237.49889)
		(mid 357.936541 -237.19409)
		(end 358.093518 -236.88929)
		(width 0.1143)
		(layer "In13.Cu")
		(net "GMI_CPU0_G0_CPU1_G2_TX_DP<1>")
	)
	(arc
		(start 113.559336 -222.61449)
		(mid 113.517787 -222.785912)
		(end 113.402364 -222.91929)
		(width 0.1143)
		(layer "In13.Cu")
		(net "GMI_CPU0_G0_CPU1_G2_TX_DP<1>")
	)
	(arc
		(start 358.16032 -228.750622)
		(mid 358.40621 -228.284278)
		(end 358.16032 -227.817934)
		(width 0.1143)
		(layer "In13.Cu")
		(net "GMI_CPU0_G0_CPU1_G2_TX_DP<1>")
	)
	(arc
		(start 113.402364 -223.929702)
		(mid 113.559341 -224.234502)
		(end 113.402364 -224.539302)
		(width 0.1143)
		(layer "In13.Cu")
		(net "GMI_CPU0_G0_CPU1_G2_TX_DP<1>")
	)
	(arc
		(start 358.16032 -238.47044)
		(mid 358.40621 -238.004096)
		(end 358.16032 -237.537752)
		(width 0.1143)
		(layer "In13.Cu")
		(net "GMI_CPU0_G0_CPU1_G2_TX_DP<1>")
	)
	(arc
		(start 113.402364 -236.889544)
		(mid 113.559341 -237.194344)
		(end 113.402364 -237.499144)
		(width 0.1143)
		(layer "In13.Cu")
		(net "GMI_CPU0_G0_CPU1_G2_TX_DP<1>")
	)
	(arc
		(start 358.093518 -235.878878)
		(mid 357.936541 -235.574078)
		(end 358.093518 -235.269278)
		(width 0.1143)
		(layer "In13.Cu")
		(net "GMI_CPU0_G0_CPU1_G2_TX_DP<1>")
	)
	(arc
		(start 113.873534 -239.32007)
		(mid 113.984976 -239.446712)
		(end 114.029744 -239.609376)
		(width 0.1143)
		(layer "In13.Cu")
		(net "GMI_CPU0_G0_CPU1_G2_TX_DP<1>")
	)
	(arc
		(start 357.936546 -229.094284)
		(mid 357.978095 -228.922862)
		(end 358.093518 -228.789484)
		(width 0.1143)
		(layer "In13.Cu")
		(net "GMI_CPU0_G0_CPU1_G2_TX_DP<1>")
	)
	(arc
		(start 357.936546 -238.814102)
		(mid 357.978095 -238.64268)
		(end 358.093518 -238.509302)
		(width 0.1143)
		(layer "In13.Cu")
		(net "GMI_CPU0_G0_CPU1_G2_TX_DP<1>")
	)
	(arc
		(start 113.402364 -230.40975)
		(mid 113.517791 -230.543126)
		(end 113.559336 -230.71455)
		(width 0.1143)
		(layer "In13.Cu")
		(net "GMI_CPU0_G0_CPU1_G2_TX_DP<1>")
	)
	(arc
		(start 358.16032 -223.890586)
		(mid 358.40621 -223.424242)
		(end 358.16032 -222.957898)
		(width 0.1143)
		(layer "In13.Cu")
		(net "GMI_CPU0_G0_CPU1_G2_TX_DP<1>")
	)
	(arc
		(start 113.08969 -229.90683)
		(mid 113.109126 -230.051715)
		(end 113.165128 -230.186738)
		(width 0.1143)
		(layer "In13.Cu")
		(net "GMI_CPU0_G0_CPU1_G2_TX_DP<1>")
	)
	(arc
		(start 358.091486 -229.397814)
		(mid 357.977557 -229.264667)
		(end 357.936546 -229.094284)
		(width 0.1143)
		(layer "In13.Cu")
		(net "GMI_CPU0_G0_CPU1_G2_TX_DP<1>")
	)
	(arc
		(start 358.093518 -232.638854)
		(mid 357.936541 -232.334054)
		(end 358.093518 -232.029254)
		(width 0.1143)
		(layer "In13.Cu")
		(net "GMI_CPU0_G0_CPU1_G2_TX_DP<1>")
	)
	(arc
		(start 358.406192 -229.906576)
		(mid 358.331068 -229.647872)
		(end 358.16159 -229.438454)
		(width 0.1143)
		(layer "In13.Cu")
		(net "GMI_CPU0_G0_CPU1_G2_TX_DP<1>")
	)
	(arc
		(start 113.402364 -232.029508)
		(mid 113.559341 -232.334308)
		(end 113.402364 -232.639108)
		(width 0.1143)
		(layer "In13.Cu")
		(net "GMI_CPU0_G0_CPU1_G2_TX_DP<1>")
	)
	(arc
		(start 358.16032 -233.610404)
		(mid 358.40621 -233.14406)
		(end 358.16032 -232.677716)
		(width 0.1143)
		(layer "In13.Cu")
		(net "GMI_CPU0_G0_CPU1_G2_TX_DP<1>")
	)
	(arc
		(start 358.145334 -231.999028)
		(mid 358.418885 -231.524048)
		(end 358.145334 -231.049068)
		(width 0.1143)
		(layer "In13.Cu")
		(net "GMI_CPU0_G0_CPU1_G2_TX_DP<1>")
	)
	(arc
		(start 358.16032 -227.13061)
		(mid 358.40621 -226.664266)
		(end 358.16032 -226.197922)
		(width 0.1143)
		(layer "In13.Cu")
		(net "GMI_CPU0_G0_CPU1_G2_TX_DP<1>")
	)
	(arc
		(start 113.335562 -232.67797)
		(mid 113.089672 -233.144314)
		(end 113.335562 -233.610658)
		(width 0.1143)
		(layer "In13.Cu")
		(net "GMI_CPU0_G0_CPU1_G2_TX_DP<1>")
	)
	(arc
		(start 114.343434 -240.130076)
		(mid 114.440569 -240.232945)
		(end 114.492532 -240.364518)
		(width 0.1143)
		(layer "In13.Cu")
		(net "GMI_CPU0_G0_CPU1_G2_TX_DP<1>")
	)
	(arc
		(start 113.559336 -238.814356)
		(mid 113.623851 -239.076575)
		(end 113.802668 -239.278922)
		(width 0.1143)
		(layer "In13.Cu")
		(net "GMI_CPU0_G0_CPU1_G2_TX_DP<1>")
	)
	(arc
		(start 358.093518 -234.258866)
		(mid 357.936541 -233.954066)
		(end 358.093518 -233.649266)
		(width 0.1143)
		(layer "In13.Cu")
		(net "GMI_CPU0_G0_CPU1_G2_TX_DP<1>")
	)
	(arc
		(start 113.335562 -235.917994)
		(mid 113.089672 -236.384338)
		(end 113.335562 -236.850682)
		(width 0.1143)
		(layer "In13.Cu")
		(net "GMI_CPU0_G0_CPU1_G2_TX_DP<1>")
	)
	(arc
		(start 358.330754 -230.186484)
		(mid 358.386712 -230.051449)
		(end 358.406192 -229.906576)
		(width 0.1143)
		(layer "In13.Cu")
		(net "GMI_CPU0_G0_CPU1_G2_TX_DP<1>")
	)
	(arc
		(start 358.16032 -235.230416)
		(mid 358.40621 -234.764072)
		(end 358.16032 -234.297728)
		(width 0.1143)
		(layer "In13.Cu")
		(net "GMI_CPU0_G0_CPU1_G2_TX_DP<1>")
	)
	(arc
		(start 358.093518 -227.779072)
		(mid 357.936541 -227.474272)
		(end 358.093518 -227.169472)
		(width 0.1143)
		(layer "In13.Cu")
		(net "GMI_CPU0_G0_CPU1_G2_TX_DP<1>")
	)
	(arc
		(start 113.334292 -229.438708)
		(mid 113.164752 -229.648094)
		(end 113.08969 -229.90683)
		(width 0.1143)
		(layer "In13.Cu")
		(net "GMI_CPU0_G0_CPU1_G2_TX_DP<1>")
	)
	(arc
		(start 113.335562 -234.297982)
		(mid 113.089672 -234.764326)
		(end 113.335562 -235.23067)
		(width 0.1143)
		(layer "In13.Cu")
		(net "GMI_CPU0_G0_CPU1_G2_TX_DP<1>")
	)
	(arc
		(start 113.402364 -235.269532)
		(mid 113.559341 -235.574332)
		(end 113.402364 -235.879132)
		(width 0.1143)
		(layer "In13.Cu")
		(net "GMI_CPU0_G0_CPU1_G2_TX_DP<1>")
	)
	(arc
		(start 358.125014 -222.292926)
		(mid 358.331101 -222.086215)
		(end 358.406446 -221.80423)
		(width 0.1143)
		(layer "In13.Cu")
		(net "GMI_CPU0_G0_CPU1_G2_TX_DP<1>")
	)
	(arc
		(start 113.559336 -230.71455)
		(mid 113.51837 -230.884956)
		(end 113.404396 -231.01808)
		(width 0.1143)
		(layer "In13.Cu")
		(net "GMI_CPU0_G0_CPU1_G2_TX_DP<1>")
	)
	(arc
		(start 113.335562 -226.198176)
		(mid 113.089672 -226.66452)
		(end 113.335562 -227.130864)
		(width 0.1143)
		(layer "In13.Cu")
		(net "GMI_CPU0_G0_CPU1_G2_TX_DP<1>")
	)
	(arc
		(start 113.402364 -233.64952)
		(mid 113.559341 -233.95432)
		(end 113.402364 -234.25912)
		(width 0.1143)
		(layer "In13.Cu")
		(net "GMI_CPU0_G0_CPU1_G2_TX_DP<1>")
	)
	(arc
		(start 358.093518 -226.15906)
		(mid 357.936541 -225.85426)
		(end 358.093518 -225.54946)
		(width 0.1143)
		(layer "In13.Cu")
		(net "GMI_CPU0_G0_CPU1_G2_TX_DP<1>")
	)
	(arc
		(start 357.462328 -239.659922)
		(mid 357.464981 -239.634578)
		(end 357.466138 -239.609122)
		(width 0.1143)
		(layer "In13.Cu")
		(net "GMI_CPU0_G0_CPU1_G2_TX_DP<1>")
	)
	(arc
		(start 357.466138 -239.609122)
		(mid 357.510832 -239.446418)
		(end 357.622348 -239.319816)
		(width 0.1143)
		(layer "In13.Cu")
		(net "GMI_CPU0_G0_CPU1_G2_TX_DP<1>")
	)
	(arc
		(start 113.402364 -228.789738)
		(mid 113.517791 -228.923114)
		(end 113.559336 -229.094538)
		(width 0.1143)
		(layer "In13.Cu")
		(net "GMI_CPU0_G0_CPU1_G2_TX_DP<1>")
	)
	(arc
		(start 113.089436 -221.804484)
		(mid 113.164833 -222.086439)
		(end 113.370868 -222.29318)
		(width 0.1143)
		(layer "In13.Cu")
		(net "GMI_CPU0_G0_CPU1_G2_TX_DP<1>")
	)
	(arc
		(start 113.335562 -227.818188)
		(mid 113.089672 -228.284532)
		(end 113.335562 -228.750876)
		(width 0.1143)
		(layer "In13.Cu")
		(net "GMI_CPU0_G0_CPU1_G2_TX_DP<1>")
	)
	(arc
		(start 357.00335 -240.364264)
		(mid 357.055399 -240.232745)
		(end 357.152448 -240.129822)
		(width 0.1143)
		(layer "In13.Cu")
		(net "GMI_CPU0_G0_CPU1_G2_TX_DP<1>")
	)
	(arc
		(start 113.402364 -225.549714)
		(mid 113.559341 -225.854514)
		(end 113.402364 -226.159314)
		(width 0.1143)
		(layer "In13.Cu")
		(net "GMI_CPU0_G0_CPU1_G2_TX_DP<1>")
	)
	(arc
		(start 358.16032 -236.850428)
		(mid 358.40621 -236.384084)
		(end 358.16032 -235.91774)
		(width 0.1143)
		(layer "In13.Cu")
		(net "GMI_CPU0_G0_CPU1_G2_TX_DP<1>")
	)
	(arc
		(start 358.091486 -231.017826)
		(mid 357.977557 -230.884679)
		(end 357.936546 -230.714296)
		(width 0.1143)
		(layer "In13.Cu")
		(net "GMI_CPU0_G0_CPU1_G2_TX_DP<1>")
	)
	(arc
		(start 114.029744 -239.609376)
		(mid 114.030916 -239.634831)
		(end 114.033554 -239.660176)
		(width 0.1143)
		(layer "In13.Cu")
		(net "GMI_CPU0_G0_CPU1_G2_TX_DP<1>")
	)
	(arc
		(start 358.157526 -230.372158)
		(mid 358.254698 -230.289173)
		(end 358.330754 -230.186484)
		(width 0.1143)
		(layer "In13.Cu")
		(net "GMI_CPU0_G0_CPU1_G2_TX_DP<1>")
	)
	(segment
		(start 347.028008 -241.510058)
		(end 346.561156 -241.24412)
		(width 0.12954)
		(layer "F.Cu")
		(net "GMI_CPU0_G0_CPU1_G2_TX_DP<15>")
	)
	(segment
		(start 124.467874 -241.510312)
		(end 124.934726 -241.244374)
		(width 0.12954)
		(layer "F.Cu")
		(net "GMI_CPU0_G0_CPU1_G2_TX_DP<15>")
	)
	(segment
		(start 345.00312 -234.299506)
		(end 344.933524 -234.258866)
		(width 0.1143)
		(layer "In13.Cu")
		(net "GMI_CPU0_G0_CPU1_G2_TX_DP<15>")
	)
	(segment
		(start 148.664676 -202.563984)
		(end 148.664168 -202.563984)
		(width 0.14224)
		(layer "In13.Cu")
		(net "GMI_CPU0_G0_CPU1_G2_TX_DP<15>")
	)
	(segment
		(start 126.203964 -221.244922)
		(end 126.203964 -221.263464)
		(width 0.14224)
		(layer "In13.Cu")
		(net "GMI_CPU0_G0_CPU1_G2_TX_DP<15>")
	)
	(segment
		(start 126.531878 -227.797106)
		(end 126.492762 -227.819966)
		(width 0.1143)
		(layer "In13.Cu")
		(net "GMI_CPU0_G0_CPU1_G2_TX_DP<15>")
	)
	(segment
		(start 345.936316 -240.77549)
		(end 345.935554 -240.774982)
		(width 0.1143)
		(layer "In13.Cu")
		(net "GMI_CPU0_G0_CPU1_G2_TX_DP<15>")
	)
	(segment
		(start 149.343364 -202.358244)
		(end 148.68398 -202.557888)
		(width 0.14224)
		(layer "In13.Cu")
		(net "GMI_CPU0_G0_CPU1_G2_TX_DP<15>")
	)
	(segment
		(start 345.00312 -239.159542)
		(end 344.933524 -239.118902)
		(width 0.1143)
		(layer "In13.Cu")
		(net "GMI_CPU0_G0_CPU1_G2_TX_DP<15>")
	)
	(segment
		(start 345.432126 -239.945418)
		(end 345.402408 -239.9284)
		(width 0.1143)
		(layer "In13.Cu")
		(net "GMI_CPU0_G0_CPU1_G2_TX_DP<15>")
	)
	(segment
		(start 308.356762 -191.04991)
		(end 303.734724 -191.04991)
		(width 0.14224)
		(layer "In13.Cu")
		(net "GMI_CPU0_G0_CPU1_G2_TX_DP<15>")
	)
	(segment
		(start 126.562358 -237.499144)
		(end 126.531878 -237.516924)
		(width 0.1143)
		(layer "In13.Cu")
		(net "GMI_CPU0_G0_CPU1_G2_TX_DP<15>")
	)
	(segment
		(start 126.562358 -224.539302)
		(end 126.531878 -224.557082)
		(width 0.1143)
		(layer "In13.Cu")
		(net "GMI_CPU0_G0_CPU1_G2_TX_DP<15>")
	)
	(segment
		(start 344.933524 -228.789484)
		(end 345.00312 -228.748844)
		(width 0.1143)
		(layer "In13.Cu")
		(net "GMI_CPU0_G0_CPU1_G2_TX_DP<15>")
	)
	(segment
		(start 125.591824 -240.756948)
		(end 125.590808 -240.757456)
		(width 0.1143)
		(layer "In13.Cu")
		(net "GMI_CPU0_G0_CPU1_G2_TX_DP<15>")
	)
	(segment
		(start 345.47048 -239.96777)
		(end 345.435682 -239.94745)
		(width 0.1143)
		(layer "In13.Cu")
		(net "GMI_CPU0_G0_CPU1_G2_TX_DP<15>")
	)
	(segment
		(start 345.935554 -240.774982)
		(end 345.905074 -240.757202)
		(width 0.1143)
		(layer "In13.Cu")
		(net "GMI_CPU0_G0_CPU1_G2_TX_DP<15>")
	)
	(segment
		(start 126.531878 -229.416864)
		(end 126.492762 -229.439724)
		(width 0.1143)
		(layer "In13.Cu")
		(net "GMI_CPU0_G0_CPU1_G2_TX_DP<15>")
	)
	(segment
		(start 126.203964 -221.263464)
		(end 126.203964 -221.291912)
		(width 0.1143)
		(layer "In13.Cu")
		(net "GMI_CPU0_G0_CPU1_G2_TX_DP<15>")
	)
	(segment
		(start 344.933524 -230.409496)
		(end 345.00058 -230.37038)
		(width 0.1143)
		(layer "In13.Cu")
		(net "GMI_CPU0_G0_CPU1_G2_TX_DP<15>")
	)
	(segment
		(start 162.410648 -191.505586)
		(end 161.922714 -192.415414)
		(width 0.14224)
		(layer "In13.Cu")
		(net "GMI_CPU0_G0_CPU1_G2_TX_DP<15>")
	)
	(segment
		(start 126.531878 -235.251752)
		(end 126.562358 -235.269532)
		(width 0.1143)
		(layer "In13.Cu")
		(net "GMI_CPU0_G0_CPU1_G2_TX_DP<15>")
	)
	(segment
		(start 125.315472 -241.16157)
		(end 125.232668 -241.244374)
		(width 0.1143)
		(layer "In13.Cu")
		(net "GMI_CPU0_G0_CPU1_G2_TX_DP<15>")
	)
	(segment
		(start 236.278928 -201.360278)
		(end 232.027222 -200.61047)
		(width 0.14224)
		(layer "In13.Cu")
		(net "GMI_CPU0_G0_CPU1_G2_TX_DP<15>")
	)
	(segment
		(start 126.492762 -236.848904)
		(end 126.531878 -236.871764)
		(width 0.1143)
		(layer "In13.Cu")
		(net "GMI_CPU0_G0_CPU1_G2_TX_DP<15>")
	)
	(segment
		(start 346.263214 -241.24412)
		(end 346.18041 -241.161316)
		(width 0.1143)
		(layer "In13.Cu")
		(net "GMI_CPU0_G0_CPU1_G2_TX_DP<15>")
	)
	(segment
		(start 125.232668 -241.244374)
		(end 124.934726 -241.244374)
		(width 0.1143)
		(layer "In13.Cu")
		(net "GMI_CPU0_G0_CPU1_G2_TX_DP<15>")
	)
	(segment
		(start 126.492762 -225.509074)
		(end 126.531878 -225.531934)
		(width 0.1143)
		(layer "In13.Cu")
		(net "GMI_CPU0_G0_CPU1_G2_TX_DP<15>")
	)
	(segment
		(start 345.00312 -224.579688)
		(end 344.933524 -224.539048)
		(width 0.1143)
		(layer "In13.Cu")
		(net "GMI_CPU0_G0_CPU1_G2_TX_DP<15>")
	)
	(segment
		(start 251.681234 -192.63614)
		(end 240.213642 -200.66635)
		(width 0.14224)
		(layer "In13.Cu")
		(net "GMI_CPU0_G0_CPU1_G2_TX_DP<15>")
	)
	(segment
		(start 126.203964 -221.291912)
		(end 126.249684 -221.337632)
		(width 0.1143)
		(layer "In13.Cu")
		(net "GMI_CPU0_G0_CPU1_G2_TX_DP<15>")
	)
	(segment
		(start 126.531878 -226.177094)
		(end 126.492762 -226.199954)
		(width 0.1143)
		(layer "In13.Cu")
		(net "GMI_CPU0_G0_CPU1_G2_TX_DP<15>")
	)
	(segment
		(start 345.905074 -240.757202)
		(end 345.904058 -240.756694)
		(width 0.1143)
		(layer "In13.Cu")
		(net "GMI_CPU0_G0_CPU1_G2_TX_DP<15>")
	)
	(segment
		(start 345.246198 -221.337378)
		(end 345.291918 -221.291658)
		(width 0.1143)
		(layer "In13.Cu")
		(net "GMI_CPU0_G0_CPU1_G2_TX_DP<15>")
	)
	(segment
		(start 209.814922 -191.410336)
		(end 207.188308 -190.946786)
		(width 0.14224)
		(layer "In13.Cu")
		(net "GMI_CPU0_G0_CPU1_G2_TX_DP<15>")
	)
	(segment
		(start 344.933524 -223.929448)
		(end 345.00312 -223.888808)
		(width 0.1143)
		(layer "In13.Cu")
		(net "GMI_CPU0_G0_CPU1_G2_TX_DP<15>")
	)
	(segment
		(start 345.00312 -231.059482)
		(end 344.964004 -231.036622)
		(width 0.1143)
		(layer "In13.Cu")
		(net "GMI_CPU0_G0_CPU1_G2_TX_DP<15>")
	)
	(segment
		(start 150.061676 -202.140566)
		(end 149.343364 -202.35799)
		(width 0.14224)
		(layer "In13.Cu")
		(net "GMI_CPU0_G0_CPU1_G2_TX_DP<15>")
	)
	(segment
		(start 345.292172 -220.885258)
		(end 344.65387 -219.810584)
		(width 0.14224)
		(layer "In13.Cu")
		(net "GMI_CPU0_G0_CPU1_G2_TX_DP<15>")
	)
	(segment
		(start 126.531878 -222.93707)
		(end 126.492762 -222.95993)
		(width 0.1143)
		(layer "In13.Cu")
		(net "GMI_CPU0_G0_CPU1_G2_TX_DP<15>")
	)
	(segment
		(start 345.291918 -221.244668)
		(end 345.292426 -221.24416)
		(width 0.14224)
		(layer "In13.Cu")
		(net "GMI_CPU0_G0_CPU1_G2_TX_DP<15>")
	)
	(segment
		(start 126.562358 -234.25912)
		(end 126.531878 -234.2769)
		(width 0.1143)
		(layer "In13.Cu")
		(net "GMI_CPU0_G0_CPU1_G2_TX_DP<15>")
	)
	(segment
		(start 148.663406 -202.564238)
		(end 147.284948 -202.981814)
		(width 0.14224)
		(layer "In13.Cu")
		(net "GMI_CPU0_G0_CPU1_G2_TX_DP<15>")
	)
	(segment
		(start 162.862514 -191.134238)
		(end 162.410648 -191.505586)
		(width 0.14224)
		(layer "In13.Cu")
		(net "GMI_CPU0_G0_CPU1_G2_TX_DP<15>")
	)
	(segment
		(start 344.933524 -238.509302)
		(end 345.00312 -238.468662)
		(width 0.1143)
		(layer "In13.Cu")
		(net "GMI_CPU0_G0_CPU1_G2_TX_DP<15>")
	)
	(segment
		(start 344.933524 -235.269278)
		(end 345.00312 -235.228638)
		(width 0.1143)
		(layer "In13.Cu")
		(net "GMI_CPU0_G0_CPU1_G2_TX_DP<15>")
	)
	(segment
		(start 126.56439 -231.01808)
		(end 126.531878 -231.036876)
		(width 0.1143)
		(layer "In13.Cu")
		(net "GMI_CPU0_G0_CPU1_G2_TX_DP<15>")
	)
	(segment
		(start 126.562358 -239.119156)
		(end 126.531878 -239.136936)
		(width 0.1143)
		(layer "In13.Cu")
		(net "GMI_CPU0_G0_CPU1_G2_TX_DP<15>")
	)
	(segment
		(start 344.933524 -227.169472)
		(end 345.00312 -227.128832)
		(width 0.1143)
		(layer "In13.Cu")
		(net "GMI_CPU0_G0_CPU1_G2_TX_DP<15>")
	)
	(segment
		(start 126.492762 -223.889062)
		(end 126.531878 -223.911922)
		(width 0.1143)
		(layer "In13.Cu")
		(net "GMI_CPU0_G0_CPU1_G2_TX_DP<15>")
	)
	(segment
		(start 126.531878 -234.2769)
		(end 126.492762 -234.29976)
		(width 0.1143)
		(layer "In13.Cu")
		(net "GMI_CPU0_G0_CPU1_G2_TX_DP<15>")
	)
	(segment
		(start 316.58433 -196.795136)
		(end 308.356762 -191.04991)
		(width 0.14224)
		(layer "In13.Cu")
		(net "GMI_CPU0_G0_CPU1_G2_TX_DP<15>")
	)
	(segment
		(start 126.531878 -235.896912)
		(end 126.492762 -235.919772)
		(width 0.1143)
		(layer "In13.Cu")
		(net "GMI_CPU0_G0_CPU1_G2_TX_DP<15>")
	)
	(segment
		(start 345.903296 -240.756186)
		(end 345.872308 -240.738406)
		(width 0.1143)
		(layer "In13.Cu")
		(net "GMI_CPU0_G0_CPU1_G2_TX_DP<15>")
	)
	(segment
		(start 345.904058 -240.756694)
		(end 345.903296 -240.756186)
		(width 0.1143)
		(layer "In13.Cu")
		(net "GMI_CPU0_G0_CPU1_G2_TX_DP<15>")
	)
	(segment
		(start 126.492762 -222.26905)
		(end 126.562358 -222.30969)
		(width 0.1143)
		(layer "In13.Cu")
		(net "GMI_CPU0_G0_CPU1_G2_TX_DP<15>")
	)
	(segment
		(start 148.68398 -202.557888)
		(end 148.664676 -202.563984)
		(width 0.14224)
		(layer "In13.Cu")
		(net "GMI_CPU0_G0_CPU1_G2_TX_DP<15>")
	)
	(segment
		(start 345.246198 -221.80423)
		(end 345.246198 -221.337378)
		(width 0.1143)
		(layer "In13.Cu")
		(net "GMI_CPU0_G0_CPU1_G2_TX_DP<15>")
	)
	(segment
		(start 240.213642 -200.66635)
		(end 236.278928 -201.360278)
		(width 0.14224)
		(layer "In13.Cu")
		(net "GMI_CPU0_G0_CPU1_G2_TX_DP<15>")
	)
	(segment
		(start 126.531878 -227.151946)
		(end 126.562358 -227.169726)
		(width 0.1143)
		(layer "In13.Cu")
		(net "GMI_CPU0_G0_CPU1_G2_TX_DP<15>")
	)
	(segment
		(start 126.492762 -233.60888)
		(end 126.531878 -233.63174)
		(width 0.1143)
		(layer "In13.Cu")
		(net "GMI_CPU0_G0_CPU1_G2_TX_DP<15>")
	)
	(segment
		(start 344.933524 -222.309436)
		(end 345.00312 -222.268796)
		(width 0.1143)
		(layer "In13.Cu")
		(net "GMI_CPU0_G0_CPU1_G2_TX_DP<15>")
	)
	(segment
		(start 126.531878 -232.656888)
		(end 126.492762 -232.679748)
		(width 0.1143)
		(layer "In13.Cu")
		(net "GMI_CPU0_G0_CPU1_G2_TX_DP<15>")
	)
	(segment
		(start 127.10795 -219.525596)
		(end 126.203456 -221.04858)
		(width 0.14224)
		(layer "In13.Cu")
		(net "GMI_CPU0_G0_CPU1_G2_TX_DP<15>")
	)
	(segment
		(start 126.063756 -239.945672)
		(end 126.062486 -239.946434)
		(width 0.1143)
		(layer "In13.Cu")
		(net "GMI_CPU0_G0_CPU1_G2_TX_DP<15>")
	)
	(segment
		(start 126.562358 -232.639108)
		(end 126.531878 -232.656888)
		(width 0.1143)
		(layer "In13.Cu")
		(net "GMI_CPU0_G0_CPU1_G2_TX_DP<15>")
	)
	(segment
		(start 344.964004 -229.41661)
		(end 344.931492 -229.397814)
		(width 0.1143)
		(layer "In13.Cu")
		(net "GMI_CPU0_G0_CPU1_G2_TX_DP<15>")
	)
	(segment
		(start 344.933524 -233.649266)
		(end 345.00312 -233.608626)
		(width 0.1143)
		(layer "In13.Cu")
		(net "GMI_CPU0_G0_CPU1_G2_TX_DP<15>")
	)
	(segment
		(start 345.292426 -221.093792)
		(end 345.292172 -221.093538)
		(width 0.14224)
		(layer "In13.Cu")
		(net "GMI_CPU0_G0_CPU1_G2_TX_DP<15>")
	)
	(segment
		(start 126.249684 -221.337632)
		(end 126.249684 -221.804484)
		(width 0.1143)
		(layer "In13.Cu")
		(net "GMI_CPU0_G0_CPU1_G2_TX_DP<15>")
	)
	(segment
		(start 345.00312 -226.1997)
		(end 344.933524 -226.15906)
		(width 0.1143)
		(layer "In13.Cu")
		(net "GMI_CPU0_G0_CPU1_G2_TX_DP<15>")
	)
	(segment
		(start 126.492762 -238.468916)
		(end 126.531878 -238.491776)
		(width 0.1143)
		(layer "In13.Cu")
		(net "GMI_CPU0_G0_CPU1_G2_TX_DP<15>")
	)
	(segment
		(start 344.933524 -236.88929)
		(end 345.00312 -236.84865)
		(width 0.1143)
		(layer "In13.Cu")
		(net "GMI_CPU0_G0_CPU1_G2_TX_DP<15>")
	)
	(segment
		(start 126.492762 -231.988868)
		(end 126.531878 -232.011728)
		(width 0.1143)
		(layer "In13.Cu")
		(net "GMI_CPU0_G0_CPU1_G2_TX_DP<15>")
	)
	(segment
		(start 149.343364 -202.35799)
		(end 149.343364 -202.358244)
		(width 0.14224)
		(layer "In13.Cu")
		(net "GMI_CPU0_G0_CPU1_G2_TX_DP<15>")
	)
	(segment
		(start 126.492762 -227.129086)
		(end 126.531878 -227.151946)
		(width 0.1143)
		(layer "In13.Cu")
		(net "GMI_CPU0_G0_CPU1_G2_TX_DP<15>")
	)
	(segment
		(start 161.922714 -192.415414)
		(end 150.061676 -202.140566)
		(width 0.14224)
		(layer "In13.Cu")
		(net "GMI_CPU0_G0_CPU1_G2_TX_DP<15>")
	)
	(segment
		(start 126.531878 -223.911922)
		(end 126.562358 -223.929702)
		(width 0.1143)
		(layer "In13.Cu")
		(net "GMI_CPU0_G0_CPU1_G2_TX_DP<15>")
	)
	(segment
		(start 344.933524 -225.54946)
		(end 345.00312 -225.50882)
		(width 0.1143)
		(layer "In13.Cu")
		(net "GMI_CPU0_G0_CPU1_G2_TX_DP<15>")
	)
	(segment
		(start 126.492762 -235.228892)
		(end 126.531878 -235.251752)
		(width 0.1143)
		(layer "In13.Cu")
		(net "GMI_CPU0_G0_CPU1_G2_TX_DP<15>")
	)
	(segment
		(start 126.093474 -239.928654)
		(end 126.063756 -239.945672)
		(width 0.1143)
		(layer "In13.Cu")
		(net "GMI_CPU0_G0_CPU1_G2_TX_DP<15>")
	)
	(segment
		(start 126.203456 -221.244414)
		(end 126.203964 -221.244922)
		(width 0.14224)
		(layer "In13.Cu")
		(net "GMI_CPU0_G0_CPU1_G2_TX_DP<15>")
	)
	(segment
		(start 345.00312 -237.53953)
		(end 344.933524 -237.49889)
		(width 0.1143)
		(layer "In13.Cu")
		(net "GMI_CPU0_G0_CPU1_G2_TX_DP<15>")
	)
	(segment
		(start 126.531878 -239.136936)
		(end 126.492762 -239.159796)
		(width 0.1143)
		(layer "In13.Cu")
		(net "GMI_CPU0_G0_CPU1_G2_TX_DP<15>")
	)
	(segment
		(start 345.00312 -229.43947)
		(end 344.964004 -229.41661)
		(width 0.1143)
		(layer "In13.Cu")
		(net "GMI_CPU0_G0_CPU1_G2_TX_DP<15>")
	)
	(segment
		(start 345.00312 -222.959676)
		(end 344.933524 -222.919036)
		(width 0.1143)
		(layer "In13.Cu")
		(net "GMI_CPU0_G0_CPU1_G2_TX_DP<15>")
	)
	(segment
		(start 303.734724 -191.04991)
		(end 262.818118 -190.67272)
		(width 0.14224)
		(layer "In13.Cu")
		(net "GMI_CPU0_G0_CPU1_G2_TX_DP<15>")
	)
	(segment
		(start 345.435682 -239.94745)
		(end 345.434158 -239.946688)
		(width 0.1143)
		(layer "In13.Cu")
		(net "GMI_CPU0_G0_CPU1_G2_TX_DP<15>")
	)
	(segment
		(start 126.531878 -225.531934)
		(end 126.562358 -225.549714)
		(width 0.1143)
		(layer "In13.Cu")
		(net "GMI_CPU0_G0_CPU1_G2_TX_DP<15>")
	)
	(segment
		(start 126.492762 -228.749098)
		(end 126.531878 -228.771958)
		(width 0.1143)
		(layer "In13.Cu")
		(net "GMI_CPU0_G0_CPU1_G2_TX_DP<15>")
	)
	(segment
		(start 126.203456 -221.04858)
		(end 126.203456 -221.244414)
		(width 0.14224)
		(layer "In13.Cu")
		(net "GMI_CPU0_G0_CPU1_G2_TX_DP<15>")
	)
	(segment
		(start 126.531878 -231.036876)
		(end 126.492762 -231.059736)
		(width 0.1143)
		(layer "In13.Cu")
		(net "GMI_CPU0_G0_CPU1_G2_TX_DP<15>")
	)
	(segment
		(start 126.495302 -230.370634)
		(end 126.562358 -230.40975)
		(width 0.1143)
		(layer "In13.Cu")
		(net "GMI_CPU0_G0_CPU1_G2_TX_DP<15>")
	)
	(segment
		(start 345.291918 -221.291658)
		(end 345.291918 -221.26321)
		(width 0.1143)
		(layer "In13.Cu")
		(net "GMI_CPU0_G0_CPU1_G2_TX_DP<15>")
	)
	(segment
		(start 126.531878 -232.011728)
		(end 126.562358 -232.029508)
		(width 0.1143)
		(layer "In13.Cu")
		(net "GMI_CPU0_G0_CPU1_G2_TX_DP<15>")
	)
	(segment
		(start 345.292426 -221.24416)
		(end 345.292426 -221.093792)
		(width 0.14224)
		(layer "In13.Cu")
		(net "GMI_CPU0_G0_CPU1_G2_TX_DP<15>")
	)
	(segment
		(start 207.188308 -190.946786)
		(end 162.862514 -191.134238)
		(width 0.14224)
		(layer "In13.Cu")
		(net "GMI_CPU0_G0_CPU1_G2_TX_DP<15>")
	)
	(segment
		(start 345.00312 -232.679494)
		(end 344.933524 -232.638854)
		(width 0.1143)
		(layer "In13.Cu")
		(net "GMI_CPU0_G0_CPU1_G2_TX_DP<15>")
	)
	(segment
		(start 125.592586 -240.75644)
		(end 125.591824 -240.756948)
		(width 0.1143)
		(layer "In13.Cu")
		(net "GMI_CPU0_G0_CPU1_G2_TX_DP<15>")
	)
	(segment
		(start 345.00312 -227.819712)
		(end 344.933524 -227.779072)
		(width 0.1143)
		(layer "In13.Cu")
		(net "GMI_CPU0_G0_CPU1_G2_TX_DP<15>")
	)
	(segment
		(start 345.434158 -239.946688)
		(end 345.433396 -239.94618)
		(width 0.1143)
		(layer "In13.Cu")
		(net "GMI_CPU0_G0_CPU1_G2_TX_DP<15>")
	)
	(segment
		(start 344.65387 -219.810584)
		(end 316.58433 -196.795136)
		(width 0.14224)
		(layer "In13.Cu")
		(net "GMI_CPU0_G0_CPU1_G2_TX_DP<15>")
	)
	(segment
		(start 345.943174 -240.779554)
		(end 345.936316 -240.77549)
		(width 0.1143)
		(layer "In13.Cu")
		(net "GMI_CPU0_G0_CPU1_G2_TX_DP<15>")
	)
	(segment
		(start 126.531878 -238.491776)
		(end 126.562358 -238.509556)
		(width 0.1143)
		(layer "In13.Cu")
		(net "GMI_CPU0_G0_CPU1_G2_TX_DP<15>")
	)
	(segment
		(start 126.562358 -227.779326)
		(end 126.531878 -227.797106)
		(width 0.1143)
		(layer "In13.Cu")
		(net "GMI_CPU0_G0_CPU1_G2_TX_DP<15>")
	)
	(segment
		(start 345.292172 -221.093538)
		(end 345.292172 -220.885258)
		(width 0.14224)
		(layer "In13.Cu")
		(net "GMI_CPU0_G0_CPU1_G2_TX_DP<15>")
	)
	(segment
		(start 346.561156 -241.24412)
		(end 346.263214 -241.24412)
		(width 0.1143)
		(layer "In13.Cu")
		(net "GMI_CPU0_G0_CPU1_G2_TX_DP<15>")
	)
	(segment
		(start 126.531878 -224.557082)
		(end 126.492762 -224.579942)
		(width 0.1143)
		(layer "In13.Cu")
		(net "GMI_CPU0_G0_CPU1_G2_TX_DP<15>")
	)
	(segment
		(start 126.562358 -222.91929)
		(end 126.531878 -222.93707)
		(width 0.1143)
		(layer "In13.Cu")
		(net "GMI_CPU0_G0_CPU1_G2_TX_DP<15>")
	)
	(segment
		(start 125.623574 -240.73866)
		(end 125.592586 -240.75644)
		(width 0.1143)
		(layer "In13.Cu")
		(net "GMI_CPU0_G0_CPU1_G2_TX_DP<15>")
	)
	(segment
		(start 262.818118 -190.67272)
		(end 251.681234 -192.63614)
		(width 0.14224)
		(layer "In13.Cu")
		(net "GMI_CPU0_G0_CPU1_G2_TX_DP<15>")
	)
	(segment
		(start 125.590808 -240.757456)
		(end 125.589284 -240.758472)
		(width 0.1143)
		(layer "In13.Cu")
		(net "GMI_CPU0_G0_CPU1_G2_TX_DP<15>")
	)
	(segment
		(start 126.061724 -239.946942)
		(end 126.0602 -239.947704)
		(width 0.1143)
		(layer "In13.Cu")
		(net "GMI_CPU0_G0_CPU1_G2_TX_DP<15>")
	)
	(segment
		(start 345.433396 -239.94618)
		(end 345.432126 -239.945418)
		(width 0.1143)
		(layer "In13.Cu")
		(net "GMI_CPU0_G0_CPU1_G2_TX_DP<15>")
	)
	(segment
		(start 125.589284 -240.758472)
		(end 125.552708 -240.779808)
		(width 0.1143)
		(layer "In13.Cu")
		(net "GMI_CPU0_G0_CPU1_G2_TX_DP<15>")
	)
	(segment
		(start 126.062486 -239.946434)
		(end 126.061724 -239.946942)
		(width 0.1143)
		(layer "In13.Cu")
		(net "GMI_CPU0_G0_CPU1_G2_TX_DP<15>")
	)
	(segment
		(start 345.00312 -235.919518)
		(end 344.933524 -235.878878)
		(width 0.1143)
		(layer "In13.Cu")
		(net "GMI_CPU0_G0_CPU1_G2_TX_DP<15>")
	)
	(segment
		(start 126.531878 -233.63174)
		(end 126.562358 -233.64952)
		(width 0.1143)
		(layer "In13.Cu")
		(net "GMI_CPU0_G0_CPU1_G2_TX_DP<15>")
	)
	(segment
		(start 148.664168 -202.563984)
		(end 148.663406 -202.564238)
		(width 0.14224)
		(layer "In13.Cu")
		(net "GMI_CPU0_G0_CPU1_G2_TX_DP<15>")
	)
	(segment
		(start 126.531878 -236.871764)
		(end 126.562358 -236.889544)
		(width 0.1143)
		(layer "In13.Cu")
		(net "GMI_CPU0_G0_CPU1_G2_TX_DP<15>")
	)
	(segment
		(start 344.964004 -231.036622)
		(end 344.931492 -231.017826)
		(width 0.1143)
		(layer "In13.Cu")
		(net "GMI_CPU0_G0_CPU1_G2_TX_DP<15>")
	)
	(segment
		(start 126.531878 -237.516924)
		(end 126.492762 -237.539784)
		(width 0.1143)
		(layer "In13.Cu")
		(net "GMI_CPU0_G0_CPU1_G2_TX_DP<15>")
	)
	(segment
		(start 126.562358 -235.879132)
		(end 126.531878 -235.896912)
		(width 0.1143)
		(layer "In13.Cu")
		(net "GMI_CPU0_G0_CPU1_G2_TX_DP<15>")
	)
	(segment
		(start 126.56439 -229.398068)
		(end 126.531878 -229.416864)
		(width 0.1143)
		(layer "In13.Cu")
		(net "GMI_CPU0_G0_CPU1_G2_TX_DP<15>")
	)
	(segment
		(start 232.027222 -200.61047)
		(end 209.814922 -191.410336)
		(width 0.14224)
		(layer "In13.Cu")
		(net "GMI_CPU0_G0_CPU1_G2_TX_DP<15>")
	)
	(segment
		(start 126.562358 -226.159314)
		(end 126.531878 -226.177094)
		(width 0.1143)
		(layer "In13.Cu")
		(net "GMI_CPU0_G0_CPU1_G2_TX_DP<15>")
	)
	(segment
		(start 344.933524 -232.029254)
		(end 345.00312 -231.988614)
		(width 0.1143)
		(layer "In13.Cu")
		(net "GMI_CPU0_G0_CPU1_G2_TX_DP<15>")
	)
	(segment
		(start 147.284948 -202.981814)
		(end 127.10795 -219.525596)
		(width 0.14224)
		(layer "In13.Cu")
		(net "GMI_CPU0_G0_CPU1_G2_TX_DP<15>")
	)
	(segment
		(start 126.0602 -239.947704)
		(end 126.025402 -239.968024)
		(width 0.1143)
		(layer "In13.Cu")
		(net "GMI_CPU0_G0_CPU1_G2_TX_DP<15>")
	)
	(segment
		(start 126.531878 -228.771958)
		(end 126.562358 -228.789738)
		(width 0.1143)
		(layer "In13.Cu")
		(net "GMI_CPU0_G0_CPU1_G2_TX_DP<15>")
	)
	(segment
		(start 345.291918 -221.26321)
		(end 345.291918 -221.244668)
		(width 0.14224)
		(layer "In13.Cu")
		(net "GMI_CPU0_G0_CPU1_G2_TX_DP<15>")
	)
	(arc
		(start 345.00312 -235.228638)
		(mid 345.246447 -234.764072)
		(end 345.00312 -234.299506)
		(width 0.1143)
		(layer "In13.Cu")
		(net "GMI_CPU0_G0_CPU1_G2_TX_DP<15>")
	)
	(arc
		(start 126.492762 -232.679748)
		(mid 126.249435 -233.144314)
		(end 126.492762 -233.60888)
		(width 0.1143)
		(layer "In13.Cu")
		(net "GMI_CPU0_G0_CPU1_G2_TX_DP<15>")
	)
	(arc
		(start 126.492762 -231.059736)
		(mid 126.249435 -231.524302)
		(end 126.492762 -231.988868)
		(width 0.1143)
		(layer "In13.Cu")
		(net "GMI_CPU0_G0_CPU1_G2_TX_DP<15>")
	)
	(arc
		(start 345.246452 -239.624108)
		(mid 345.181937 -239.361889)
		(end 345.00312 -239.159542)
		(width 0.1143)
		(layer "In13.Cu")
		(net "GMI_CPU0_G0_CPU1_G2_TX_DP<15>")
	)
	(arc
		(start 346.1766 -241.138456)
		(mid 346.095167 -240.936058)
		(end 345.943174 -240.779554)
		(width 0.1143)
		(layer "In13.Cu")
		(net "GMI_CPU0_G0_CPU1_G2_TX_DP<15>")
	)
	(arc
		(start 125.552708 -240.779808)
		(mid 125.400721 -240.936316)
		(end 125.319282 -241.13871)
		(width 0.1143)
		(layer "In13.Cu")
		(net "GMI_CPU0_G0_CPU1_G2_TX_DP<15>")
	)
	(arc
		(start 125.781308 -240.407698)
		(mid 125.779951 -240.421002)
		(end 125.77953 -240.434368)
		(width 0.1143)
		(layer "In13.Cu")
		(net "GMI_CPU0_G0_CPU1_G2_TX_DP<15>")
	)
	(arc
		(start 126.025402 -239.968024)
		(mid 126.009433 -239.980061)
		(end 125.993906 -239.992662)
		(width 0.1143)
		(layer "In13.Cu")
		(net "GMI_CPU0_G0_CPU1_G2_TX_DP<15>")
	)
	(arc
		(start 126.24943 -239.624362)
		(mid 126.208175 -239.795333)
		(end 126.093474 -239.928654)
		(width 0.1143)
		(layer "In13.Cu")
		(net "GMI_CPU0_G0_CPU1_G2_TX_DP<15>")
	)
	(arc
		(start 345.00312 -236.84865)
		(mid 345.246447 -236.384084)
		(end 345.00312 -235.919518)
		(width 0.1143)
		(layer "In13.Cu")
		(net "GMI_CPU0_G0_CPU1_G2_TX_DP<15>")
	)
	(arc
		(start 126.492762 -229.439724)
		(mid 126.313949 -229.642074)
		(end 126.24943 -229.90429)
		(width 0.1143)
		(layer "In13.Cu")
		(net "GMI_CPU0_G0_CPU1_G2_TX_DP<15>")
	)
	(arc
		(start 126.492762 -227.819966)
		(mid 126.249435 -228.284532)
		(end 126.492762 -228.749098)
		(width 0.1143)
		(layer "In13.Cu")
		(net "GMI_CPU0_G0_CPU1_G2_TX_DP<15>")
	)
	(arc
		(start 126.24943 -229.90429)
		(mid 126.314666 -230.167881)
		(end 126.495302 -230.370634)
		(width 0.1143)
		(layer "In13.Cu")
		(net "GMI_CPU0_G0_CPU1_G2_TX_DP<15>")
	)
	(arc
		(start 126.492762 -237.539784)
		(mid 126.249435 -238.00435)
		(end 126.492762 -238.468916)
		(width 0.1143)
		(layer "In13.Cu")
		(net "GMI_CPU0_G0_CPU1_G2_TX_DP<15>")
	)
	(arc
		(start 126.71933 -229.094538)
		(mid 126.678364 -229.264944)
		(end 126.56439 -229.398068)
		(width 0.1143)
		(layer "In13.Cu")
		(net "GMI_CPU0_G0_CPU1_G2_TX_DP<15>")
	)
	(arc
		(start 344.931492 -229.397814)
		(mid 344.817563 -229.264667)
		(end 344.776552 -229.094284)
		(width 0.1143)
		(layer "In13.Cu")
		(net "GMI_CPU0_G0_CPU1_G2_TX_DP<15>")
	)
	(arc
		(start 345.402408 -239.9284)
		(mid 345.287732 -239.795066)
		(end 345.246452 -239.624108)
		(width 0.1143)
		(layer "In13.Cu")
		(net "GMI_CPU0_G0_CPU1_G2_TX_DP<15>")
	)
	(arc
		(start 344.776552 -230.714296)
		(mid 344.818101 -230.542874)
		(end 344.933524 -230.409496)
		(width 0.1143)
		(layer "In13.Cu")
		(net "GMI_CPU0_G0_CPU1_G2_TX_DP<15>")
	)
	(arc
		(start 126.492762 -222.95993)
		(mid 126.249435 -223.424496)
		(end 126.492762 -223.889062)
		(width 0.1143)
		(layer "In13.Cu")
		(net "GMI_CPU0_G0_CPU1_G2_TX_DP<15>")
	)
	(arc
		(start 126.492762 -239.159796)
		(mid 126.313949 -239.362146)
		(end 126.24943 -239.624362)
		(width 0.1143)
		(layer "In13.Cu")
		(net "GMI_CPU0_G0_CPU1_G2_TX_DP<15>")
	)
	(arc
		(start 345.00312 -225.50882)
		(mid 345.246447 -225.044254)
		(end 345.00312 -224.579688)
		(width 0.1143)
		(layer "In13.Cu")
		(net "GMI_CPU0_G0_CPU1_G2_TX_DP<15>")
	)
	(arc
		(start 344.933524 -224.539048)
		(mid 344.776547 -224.234248)
		(end 344.933524 -223.929448)
		(width 0.1143)
		(layer "In13.Cu")
		(net "GMI_CPU0_G0_CPU1_G2_TX_DP<15>")
	)
	(arc
		(start 126.562358 -235.269532)
		(mid 126.719335 -235.574332)
		(end 126.562358 -235.879132)
		(width 0.1143)
		(layer "In13.Cu")
		(net "GMI_CPU0_G0_CPU1_G2_TX_DP<15>")
	)
	(arc
		(start 345.00058 -230.37038)
		(mid 345.181232 -230.167635)
		(end 345.246452 -229.904036)
		(width 0.1143)
		(layer "In13.Cu")
		(net "GMI_CPU0_G0_CPU1_G2_TX_DP<15>")
	)
	(arc
		(start 125.77953 -240.434368)
		(mid 125.735459 -240.603904)
		(end 125.623574 -240.73866)
		(width 0.1143)
		(layer "In13.Cu")
		(net "GMI_CPU0_G0_CPU1_G2_TX_DP<15>")
	)
	(arc
		(start 344.931492 -231.017826)
		(mid 344.817563 -230.884679)
		(end 344.776552 -230.714296)
		(width 0.1143)
		(layer "In13.Cu")
		(net "GMI_CPU0_G0_CPU1_G2_TX_DP<15>")
	)
	(arc
		(start 345.246452 -229.904036)
		(mid 345.181937 -229.641817)
		(end 345.00312 -229.43947)
		(width 0.1143)
		(layer "In13.Cu")
		(net "GMI_CPU0_G0_CPU1_G2_TX_DP<15>")
	)
	(arc
		(start 344.933524 -235.878878)
		(mid 344.776547 -235.574078)
		(end 344.933524 -235.269278)
		(width 0.1143)
		(layer "In13.Cu")
		(net "GMI_CPU0_G0_CPU1_G2_TX_DP<15>")
	)
	(arc
		(start 126.492762 -224.579942)
		(mid 126.249435 -225.044508)
		(end 126.492762 -225.509074)
		(width 0.1143)
		(layer "In13.Cu")
		(net "GMI_CPU0_G0_CPU1_G2_TX_DP<15>")
	)
	(arc
		(start 344.933524 -237.49889)
		(mid 344.776547 -237.19409)
		(end 344.933524 -236.88929)
		(width 0.1143)
		(layer "In13.Cu")
		(net "GMI_CPU0_G0_CPU1_G2_TX_DP<15>")
	)
	(arc
		(start 126.492762 -235.919772)
		(mid 126.249435 -236.384338)
		(end 126.492762 -236.848904)
		(width 0.1143)
		(layer "In13.Cu")
		(net "GMI_CPU0_G0_CPU1_G2_TX_DP<15>")
	)
	(arc
		(start 344.933524 -232.638854)
		(mid 344.776547 -232.334054)
		(end 344.933524 -232.029254)
		(width 0.1143)
		(layer "In13.Cu")
		(net "GMI_CPU0_G0_CPU1_G2_TX_DP<15>")
	)
	(arc
		(start 345.00312 -222.268796)
		(mid 345.181763 -222.066401)
		(end 345.246198 -221.80423)
		(width 0.1143)
		(layer "In13.Cu")
		(net "GMI_CPU0_G0_CPU1_G2_TX_DP<15>")
	)
	(arc
		(start 126.562358 -228.789738)
		(mid 126.677785 -228.923114)
		(end 126.71933 -229.094538)
		(width 0.1143)
		(layer "In13.Cu")
		(net "GMI_CPU0_G0_CPU1_G2_TX_DP<15>")
	)
	(arc
		(start 126.562358 -230.40975)
		(mid 126.677785 -230.543126)
		(end 126.71933 -230.71455)
		(width 0.1143)
		(layer "In13.Cu")
		(net "GMI_CPU0_G0_CPU1_G2_TX_DP<15>")
	)
	(arc
		(start 345.00312 -228.748844)
		(mid 345.246447 -228.284278)
		(end 345.00312 -227.819712)
		(width 0.1143)
		(layer "In13.Cu")
		(net "GMI_CPU0_G0_CPU1_G2_TX_DP<15>")
	)
	(arc
		(start 126.492762 -226.199954)
		(mid 126.249435 -226.66452)
		(end 126.492762 -227.129086)
		(width 0.1143)
		(layer "In13.Cu")
		(net "GMI_CPU0_G0_CPU1_G2_TX_DP<15>")
	)
	(arc
		(start 344.776552 -229.094284)
		(mid 344.818101 -228.922862)
		(end 344.933524 -228.789484)
		(width 0.1143)
		(layer "In13.Cu")
		(net "GMI_CPU0_G0_CPU1_G2_TX_DP<15>")
	)
	(arc
		(start 345.872308 -240.738406)
		(mid 345.760511 -240.603605)
		(end 345.716352 -240.434114)
		(width 0.1143)
		(layer "In13.Cu")
		(net "GMI_CPU0_G0_CPU1_G2_TX_DP<15>")
	)
	(arc
		(start 345.716352 -240.434114)
		(mid 345.715947 -240.420746)
		(end 345.714574 -240.407444)
		(width 0.1143)
		(layer "In13.Cu")
		(net "GMI_CPU0_G0_CPU1_G2_TX_DP<15>")
	)
	(arc
		(start 126.562358 -223.929702)
		(mid 126.719335 -224.234502)
		(end 126.562358 -224.539302)
		(width 0.1143)
		(layer "In13.Cu")
		(net "GMI_CPU0_G0_CPU1_G2_TX_DP<15>")
	)
	(arc
		(start 345.00312 -227.128832)
		(mid 345.246447 -226.664266)
		(end 345.00312 -226.1997)
		(width 0.1143)
		(layer "In13.Cu")
		(net "GMI_CPU0_G0_CPU1_G2_TX_DP<15>")
	)
	(arc
		(start 125.993906 -239.992662)
		(mid 125.852819 -240.182364)
		(end 125.781308 -240.407698)
		(width 0.1143)
		(layer "In13.Cu")
		(net "GMI_CPU0_G0_CPU1_G2_TX_DP<15>")
	)
	(arc
		(start 344.933524 -239.118902)
		(mid 344.776547 -238.814102)
		(end 344.933524 -238.509302)
		(width 0.1143)
		(layer "In13.Cu")
		(net "GMI_CPU0_G0_CPU1_G2_TX_DP<15>")
	)
	(arc
		(start 345.00312 -231.988614)
		(mid 345.246447 -231.524048)
		(end 345.00312 -231.059482)
		(width 0.1143)
		(layer "In13.Cu")
		(net "GMI_CPU0_G0_CPU1_G2_TX_DP<15>")
	)
	(arc
		(start 344.933524 -227.779072)
		(mid 344.776547 -227.474272)
		(end 344.933524 -227.169472)
		(width 0.1143)
		(layer "In13.Cu")
		(net "GMI_CPU0_G0_CPU1_G2_TX_DP<15>")
	)
	(arc
		(start 344.933524 -234.258866)
		(mid 344.776547 -233.954066)
		(end 344.933524 -233.649266)
		(width 0.1143)
		(layer "In13.Cu")
		(net "GMI_CPU0_G0_CPU1_G2_TX_DP<15>")
	)
	(arc
		(start 344.933524 -222.919036)
		(mid 344.776547 -222.614236)
		(end 344.933524 -222.309436)
		(width 0.1143)
		(layer "In13.Cu")
		(net "GMI_CPU0_G0_CPU1_G2_TX_DP<15>")
	)
	(arc
		(start 345.501976 -239.992408)
		(mid 345.486444 -239.979813)
		(end 345.47048 -239.96777)
		(width 0.1143)
		(layer "In13.Cu")
		(net "GMI_CPU0_G0_CPU1_G2_TX_DP<15>")
	)
	(arc
		(start 346.18041 -241.161316)
		(mid 346.178622 -241.149867)
		(end 346.1766 -241.138456)
		(width 0.1143)
		(layer "In13.Cu")
		(net "GMI_CPU0_G0_CPU1_G2_TX_DP<15>")
	)
	(arc
		(start 125.319282 -241.13871)
		(mid 125.317259 -241.15012)
		(end 125.315472 -241.16157)
		(width 0.1143)
		(layer "In13.Cu")
		(net "GMI_CPU0_G0_CPU1_G2_TX_DP<15>")
	)
	(arc
		(start 126.249684 -221.804484)
		(mid 126.314058 -222.066688)
		(end 126.492762 -222.26905)
		(width 0.1143)
		(layer "In13.Cu")
		(net "GMI_CPU0_G0_CPU1_G2_TX_DP<15>")
	)
	(arc
		(start 126.492762 -234.29976)
		(mid 126.249435 -234.764326)
		(end 126.492762 -235.228892)
		(width 0.1143)
		(layer "In13.Cu")
		(net "GMI_CPU0_G0_CPU1_G2_TX_DP<15>")
	)
	(arc
		(start 345.00312 -233.608626)
		(mid 345.246447 -233.14406)
		(end 345.00312 -232.679494)
		(width 0.1143)
		(layer "In13.Cu")
		(net "GMI_CPU0_G0_CPU1_G2_TX_DP<15>")
	)
	(arc
		(start 345.00312 -238.468662)
		(mid 345.246447 -238.004096)
		(end 345.00312 -237.53953)
		(width 0.1143)
		(layer "In13.Cu")
		(net "GMI_CPU0_G0_CPU1_G2_TX_DP<15>")
	)
	(arc
		(start 345.00312 -223.888808)
		(mid 345.246447 -223.424242)
		(end 345.00312 -222.959676)
		(width 0.1143)
		(layer "In13.Cu")
		(net "GMI_CPU0_G0_CPU1_G2_TX_DP<15>")
	)
	(arc
		(start 345.714574 -240.407444)
		(mid 345.64303 -240.182126)
		(end 345.501976 -239.992408)
		(width 0.1143)
		(layer "In13.Cu")
		(net "GMI_CPU0_G0_CPU1_G2_TX_DP<15>")
	)
	(arc
		(start 344.933524 -226.15906)
		(mid 344.776547 -225.85426)
		(end 344.933524 -225.54946)
		(width 0.1143)
		(layer "In13.Cu")
		(net "GMI_CPU0_G0_CPU1_G2_TX_DP<15>")
	)
	(arc
		(start 126.562358 -236.889544)
		(mid 126.719335 -237.194344)
		(end 126.562358 -237.499144)
		(width 0.1143)
		(layer "In13.Cu")
		(net "GMI_CPU0_G0_CPU1_G2_TX_DP<15>")
	)
	(arc
		(start 126.562358 -225.549714)
		(mid 126.719335 -225.854514)
		(end 126.562358 -226.159314)
		(width 0.1143)
		(layer "In13.Cu")
		(net "GMI_CPU0_G0_CPU1_G2_TX_DP<15>")
	)
	(arc
		(start 126.562358 -238.509556)
		(mid 126.719335 -238.814356)
		(end 126.562358 -239.119156)
		(width 0.1143)
		(layer "In13.Cu")
		(net "GMI_CPU0_G0_CPU1_G2_TX_DP<15>")
	)
	(arc
		(start 126.562358 -222.30969)
		(mid 126.719335 -222.61449)
		(end 126.562358 -222.91929)
		(width 0.1143)
		(layer "In13.Cu")
		(net "GMI_CPU0_G0_CPU1_G2_TX_DP<15>")
	)
	(arc
		(start 126.71933 -230.71455)
		(mid 126.678364 -230.884956)
		(end 126.56439 -231.01808)
		(width 0.1143)
		(layer "In13.Cu")
		(net "GMI_CPU0_G0_CPU1_G2_TX_DP<15>")
	)
	(arc
		(start 126.562358 -232.029508)
		(mid 126.719335 -232.334308)
		(end 126.562358 -232.639108)
		(width 0.1143)
		(layer "In13.Cu")
		(net "GMI_CPU0_G0_CPU1_G2_TX_DP<15>")
	)
	(arc
		(start 126.562358 -227.169726)
		(mid 126.719335 -227.474526)
		(end 126.562358 -227.779326)
		(width 0.1143)
		(layer "In13.Cu")
		(net "GMI_CPU0_G0_CPU1_G2_TX_DP<15>")
	)
	(arc
		(start 126.562358 -233.64952)
		(mid 126.719335 -233.95432)
		(end 126.562358 -234.25912)
		(width 0.1143)
		(layer "In13.Cu")
		(net "GMI_CPU0_G0_CPU1_G2_TX_DP<15>")
	)
	(segment
		(start 124.467874 -239.8903)
		(end 124.934726 -239.624362)
		(width 0.12954)
		(layer "F.Cu")
		(net "GMI_CPU0_G0_CPU1_G2_TX_DP<14>")
	)
	(segment
		(start 347.028008 -239.890046)
		(end 346.561156 -239.624108)
		(width 0.12954)
		(layer "F.Cu")
		(net "GMI_CPU0_G0_CPU1_G2_TX_DP<14>")
	)
	(segment
		(start 125.59157 -224.557336)
		(end 125.554232 -224.578926)
		(width 0.1143)
		(layer "In13.Cu")
		(net "GMI_CPU0_G0_CPU1_G2_TX_DP<14>")
	)
	(segment
		(start 345.91117 -222.94088)
		(end 345.906598 -222.93834)
		(width 0.1143)
		(layer "In13.Cu")
		(net "GMI_CPU0_G0_CPU1_G2_TX_DP<14>")
	)
	(segment
		(start 345.872308 -239.118394)
		(end 345.863926 -239.112298)
		(width 0.1143)
		(layer "In13.Cu")
		(net "GMI_CPU0_G0_CPU1_G2_TX_DP<14>")
	)
	(segment
		(start 345.943174 -234.299506)
		(end 345.936316 -234.295442)
		(width 0.1143)
		(layer "In13.Cu")
		(net "GMI_CPU0_G0_CPU1_G2_TX_DP<14>")
	)
	(segment
		(start 345.903296 -227.796344)
		(end 345.872308 -227.778564)
		(width 0.1143)
		(layer "In13.Cu")
		(net "GMI_CPU0_G0_CPU1_G2_TX_DP<14>")
	)
	(segment
		(start 345.995752 -239.196118)
		(end 345.904058 -239.136682)
		(width 0.1143)
		(layer "In13.Cu")
		(net "GMI_CPU0_G0_CPU1_G2_TX_DP<14>")
	)
	(segment
		(start 345.943174 -222.959676)
		(end 345.91117 -222.94088)
		(width 0.1143)
		(layer "In13.Cu")
		(net "GMI_CPU0_G0_CPU1_G2_TX_DP<14>")
	)
	(segment
		(start 125.591824 -231.03713)
		(end 125.551946 -231.05999)
		(width 0.1143)
		(layer "In13.Cu")
		(net "GMI_CPU0_G0_CPU1_G2_TX_DP<14>")
	)
	(segment
		(start 125.59157 -235.251498)
		(end 125.623574 -235.270294)
		(width 0.1143)
		(layer "In13.Cu")
		(net "GMI_CPU0_G0_CPU1_G2_TX_DP<14>")
	)
	(segment
		(start 345.904058 -225.53168)
		(end 345.905074 -225.531172)
		(width 0.1143)
		(layer "In13.Cu")
		(net "GMI_CPU0_G0_CPU1_G2_TX_DP<14>")
	)
	(segment
		(start 345.935554 -238.473234)
		(end 345.936316 -238.472726)
		(width 0.1143)
		(layer "In13.Cu")
		(net "GMI_CPU0_G0_CPU1_G2_TX_DP<14>")
	)
	(segment
		(start 345.872308 -232.029762)
		(end 345.94038 -231.990646)
		(width 0.1143)
		(layer "In13.Cu")
		(net "GMI_CPU0_G0_CPU1_G2_TX_DP<14>")
	)
	(segment
		(start 125.554232 -236.84992)
		(end 125.59157 -236.87151)
		(width 0.1143)
		(layer "In13.Cu")
		(net "GMI_CPU0_G0_CPU1_G2_TX_DP<14>")
	)
	(segment
		(start 239.845088 -199.777096)
		(end 239.844834 -199.777096)
		(width 0.14224)
		(layer "In13.Cu")
		(net "GMI_CPU0_G0_CPU1_G2_TX_DP<14>")
	)
	(segment
		(start 125.315472 -239.541558)
		(end 125.232668 -239.624362)
		(width 0.1143)
		(layer "In13.Cu")
		(net "GMI_CPU0_G0_CPU1_G2_TX_DP<14>")
	)
	(segment
		(start 346.186252 -221.253558)
		(end 346.231972 -221.207838)
		(width 0.1143)
		(layer "In13.Cu")
		(net "GMI_CPU0_G0_CPU1_G2_TX_DP<14>")
	)
	(segment
		(start 308.735476 -190.109856)
		(end 303.734724 -190.109856)
		(width 0.14224)
		(layer "In13.Cu")
		(net "GMI_CPU0_G0_CPU1_G2_TX_DP<14>")
	)
	(segment
		(start 345.905074 -227.151184)
		(end 345.906852 -227.150168)
		(width 0.1143)
		(layer "In13.Cu")
		(net "GMI_CPU0_G0_CPU1_G2_TX_DP<14>")
	)
	(segment
		(start 345.904058 -227.151692)
		(end 345.905074 -227.151184)
		(width 0.1143)
		(layer "In13.Cu")
		(net "GMI_CPU0_G0_CPU1_G2_TX_DP<14>")
	)
	(segment
		(start 345.910154 -223.908112)
		(end 345.935554 -223.89338)
		(width 0.1143)
		(layer "In13.Cu")
		(net "GMI_CPU0_G0_CPU1_G2_TX_DP<14>")
	)
	(segment
		(start 345.909392 -227.148644)
		(end 345.910154 -227.148136)
		(width 0.1143)
		(layer "In13.Cu")
		(net "GMI_CPU0_G0_CPU1_G2_TX_DP<14>")
	)
	(segment
		(start 125.554232 -230.369872)
		(end 125.621542 -230.408988)
		(width 0.1143)
		(layer "In13.Cu")
		(net "GMI_CPU0_G0_CPU1_G2_TX_DP<14>")
	)
	(segment
		(start 346.186506 -229.90429)
		(end 346.186506 -229.904036)
		(width 0.1143)
		(layer "In13.Cu")
		(net "GMI_CPU0_G0_CPU1_G2_TX_DP<14>")
	)
	(segment
		(start 317.269622 -196.116956)
		(end 308.735476 -190.109856)
		(width 0.14224)
		(layer "In13.Cu")
		(net "GMI_CPU0_G0_CPU1_G2_TX_DP<14>")
	)
	(segment
		(start 345.871546 -228.790246)
		(end 345.899994 -228.77399)
		(width 0.1143)
		(layer "In13.Cu")
		(net "GMI_CPU0_G0_CPU1_G2_TX_DP<14>")
	)
	(segment
		(start 345.943174 -227.819712)
		(end 345.909646 -227.800154)
		(width 0.1143)
		(layer "In13.Cu")
		(net "GMI_CPU0_G0_CPU1_G2_TX_DP<14>")
	)
	(segment
		(start 345.863926 -222.302832)
		(end 345.942412 -222.256096)
		(width 0.1143)
		(layer "In13.Cu")
		(net "GMI_CPU0_G0_CPU1_G2_TX_DP<14>")
	)
	(segment
		(start 346.263214 -239.624108)
		(end 346.18041 -239.541304)
		(width 0.1143)
		(layer "In13.Cu")
		(net "GMI_CPU0_G0_CPU1_G2_TX_DP<14>")
	)
	(segment
		(start 345.943174 -224.579688)
		(end 345.905074 -224.557336)
		(width 0.1143)
		(layer "In13.Cu")
		(net "GMI_CPU0_G0_CPU1_G2_TX_DP<14>")
	)
	(segment
		(start 345.903296 -236.872018)
		(end 345.904058 -236.87151)
		(width 0.1143)
		(layer "In13.Cu")
		(net "GMI_CPU0_G0_CPU1_G2_TX_DP<14>")
	)
	(segment
		(start 345.935554 -234.294934)
		(end 345.904058 -234.276646)
		(width 0.1143)
		(layer "In13.Cu")
		(net "GMI_CPU0_G0_CPU1_G2_TX_DP<14>")
	)
	(segment
		(start 345.716352 -229.094284)
		(end 345.716352 -229.093522)
		(width 0.1143)
		(layer "In13.Cu")
		(net "GMI_CPU0_G0_CPU1_G2_TX_DP<14>")
	)
	(segment
		(start 345.905074 -235.897166)
		(end 345.904058 -235.896658)
		(width 0.1143)
		(layer "In13.Cu")
		(net "GMI_CPU0_G0_CPU1_G2_TX_DP<14>")
	)
	(segment
		(start 125.554232 -238.469932)
		(end 125.59157 -238.491522)
		(width 0.1143)
		(layer "In13.Cu")
		(net "GMI_CPU0_G0_CPU1_G2_TX_DP<14>")
	)
	(segment
		(start 125.26391 -221.157038)
		(end 125.263402 -221.157546)
		(width 0.14224)
		(layer "In13.Cu")
		(net "GMI_CPU0_G0_CPU1_G2_TX_DP<14>")
	)
	(segment
		(start 345.906598 -235.898182)
		(end 345.905074 -235.897166)
		(width 0.1143)
		(layer "In13.Cu")
		(net "GMI_CPU0_G0_CPU1_G2_TX_DP<14>")
	)
	(segment
		(start 126.350014 -218.896692)
		(end 125.26391 -220.813884)
		(width 0.14224)
		(layer "In13.Cu")
		(net "GMI_CPU0_G0_CPU1_G2_TX_DP<14>")
	)
	(segment
		(start 236.278928 -200.406)
		(end 233.086148 -199.843136)
		(width 0.14224)
		(layer "In13.Cu")
		(net "GMI_CPU0_G0_CPU1_G2_TX_DP<14>")
	)
	(segment
		(start 345.872308 -225.549968)
		(end 345.903296 -225.532188)
		(width 0.1143)
		(layer "In13.Cu")
		(net "GMI_CPU0_G0_CPU1_G2_TX_DP<14>")
	)
	(segment
		(start 125.59157 -223.911668)
		(end 125.623574 -223.930464)
		(width 0.1143)
		(layer "In13.Cu")
		(net "GMI_CPU0_G0_CPU1_G2_TX_DP<14>")
	)
	(segment
		(start 345.903296 -228.772212)
		(end 345.904058 -228.771704)
		(width 0.1143)
		(layer "In13.Cu")
		(net "GMI_CPU0_G0_CPU1_G2_TX_DP<14>")
	)
	(segment
		(start 345.909392 -238.488474)
		(end 345.910154 -238.487966)
		(width 0.1143)
		(layer "In13.Cu")
		(net "GMI_CPU0_G0_CPU1_G2_TX_DP<14>")
	)
	(segment
		(start 345.906598 -237.518194)
		(end 345.905074 -237.517178)
		(width 0.1143)
		(layer "In13.Cu")
		(net "GMI_CPU0_G0_CPU1_G2_TX_DP<14>")
	)
	(segment
		(start 345.872308 -237.498382)
		(end 345.864688 -237.493048)
		(width 0.1143)
		(layer "In13.Cu")
		(net "GMI_CPU0_G0_CPU1_G2_TX_DP<14>")
	)
	(segment
		(start 345.910662 -226.180396)
		(end 345.907868 -226.178872)
		(width 0.1143)
		(layer "In13.Cu")
		(net "GMI_CPU0_G0_CPU1_G2_TX_DP<14>")
	)
	(segment
		(start 345.943174 -226.1997)
		(end 345.937332 -226.196144)
		(width 0.1143)
		(layer "In13.Cu")
		(net "GMI_CPU0_G0_CPU1_G2_TX_DP<14>")
	)
	(segment
		(start 149.344634 -201.33691)
		(end 146.839178 -202.09637)
		(width 0.14224)
		(layer "In13.Cu")
		(net "GMI_CPU0_G0_CPU1_G2_TX_DP<14>")
	)
	(segment
		(start 345.903296 -224.55632)
		(end 345.872308 -224.53854)
		(width 0.1143)
		(layer "In13.Cu")
		(net "GMI_CPU0_G0_CPU1_G2_TX_DP<14>")
	)
	(segment
		(start 345.903296 -239.136174)
		(end 345.898724 -239.133634)
		(width 0.1143)
		(layer "In13.Cu")
		(net "GMI_CPU0_G0_CPU1_G2_TX_DP<14>")
	)
	(segment
		(start 345.904058 -224.556828)
		(end 345.903296 -224.55632)
		(width 0.1143)
		(layer "In13.Cu")
		(net "GMI_CPU0_G0_CPU1_G2_TX_DP<14>")
	)
	(segment
		(start 125.62332 -235.87837)
		(end 125.59157 -235.897166)
		(width 0.1143)
		(layer "In13.Cu")
		(net "GMI_CPU0_G0_CPU1_G2_TX_DP<14>")
	)
	(segment
		(start 239.84204 -199.77735)
		(end 236.278928 -200.406)
		(width 0.14224)
		(layer "In13.Cu")
		(net "GMI_CPU0_G0_CPU1_G2_TX_DP<14>")
	)
	(segment
		(start 345.872308 -227.16998)
		(end 345.903296 -227.1522)
		(width 0.1143)
		(layer "In13.Cu")
		(net "GMI_CPU0_G0_CPU1_G2_TX_DP<14>")
	)
	(segment
		(start 346.236544 -220.97746)
		(end 346.236544 -220.639894)
		(width 0.14224)
		(layer "In13.Cu")
		(net "GMI_CPU0_G0_CPU1_G2_TX_DP<14>")
	)
	(segment
		(start 345.899486 -222.934022)
		(end 345.896184 -222.932244)
		(width 0.1143)
		(layer "In13.Cu")
		(net "GMI_CPU0_G0_CPU1_G2_TX_DP<14>")
	)
	(segment
		(start 345.900502 -230.393748)
		(end 345.902026 -230.392986)
		(width 0.1143)
		(layer "In13.Cu")
		(net "GMI_CPU0_G0_CPU1_G2_TX_DP<14>")
	)
	(segment
		(start 303.734724 -190.109856)
		(end 262.742426 -189.73165)
		(width 0.14224)
		(layer "In13.Cu")
		(net "GMI_CPU0_G0_CPU1_G2_TX_DP<14>")
	)
	(segment
		(start 345.902026 -230.392986)
		(end 345.903296 -230.392224)
		(width 0.1143)
		(layer "In13.Cu")
		(net "GMI_CPU0_G0_CPU1_G2_TX_DP<14>")
	)
	(segment
		(start 345.943174 -232.679494)
		(end 345.936316 -232.67543)
		(width 0.1143)
		(layer "In13.Cu")
		(net "GMI_CPU0_G0_CPU1_G2_TX_DP<14>")
	)
	(segment
		(start 345.910154 -236.867954)
		(end 345.935554 -236.853222)
		(width 0.1143)
		(layer "In13.Cu")
		(net "GMI_CPU0_G0_CPU1_G2_TX_DP<14>")
	)
	(segment
		(start 345.936316 -232.67543)
		(end 345.935554 -232.674922)
		(width 0.1143)
		(layer "In13.Cu")
		(net "GMI_CPU0_G0_CPU1_G2_TX_DP<14>")
	)
	(segment
		(start 125.62332 -222.918528)
		(end 125.59157 -222.937324)
		(width 0.1143)
		(layer "In13.Cu")
		(net "GMI_CPU0_G0_CPU1_G2_TX_DP<14>")
	)
	(segment
		(start 345.936316 -227.132896)
		(end 345.943174 -227.128832)
		(width 0.1143)
		(layer "In13.Cu")
		(net "GMI_CPU0_G0_CPU1_G2_TX_DP<14>")
	)
	(segment
		(start 345.716352 -229.093522)
		(end 345.716606 -229.093776)
		(width 0.1143)
		(layer "In13.Cu")
		(net "GMI_CPU0_G0_CPU1_G2_TX_DP<14>")
	)
	(segment
		(start 125.554232 -228.750114)
		(end 125.59157 -228.771704)
		(width 0.1143)
		(layer "In13.Cu")
		(net "GMI_CPU0_G0_CPU1_G2_TX_DP<14>")
	)
	(segment
		(start 125.59157 -232.011474)
		(end 125.623574 -232.03027)
		(width 0.1143)
		(layer "In13.Cu")
		(net "GMI_CPU0_G0_CPU1_G2_TX_DP<14>")
	)
	(segment
		(start 345.903296 -238.49203)
		(end 345.904058 -238.491522)
		(width 0.1143)
		(layer "In13.Cu")
		(net "GMI_CPU0_G0_CPU1_G2_TX_DP<14>")
	)
	(segment
		(start 125.62332 -229.398576)
		(end 125.591824 -229.417118)
		(width 0.1143)
		(layer "In13.Cu")
		(net "GMI_CPU0_G0_CPU1_G2_TX_DP<14>")
	)
	(segment
		(start 146.839178 -202.09637)
		(end 136.593326 -210.49742)
		(width 0.14224)
		(layer "In13.Cu")
		(net "GMI_CPU0_G0_CPU1_G2_TX_DP<14>")
	)
	(segment
		(start 125.59157 -239.13719)
		(end 125.554232 -239.15878)
		(width 0.1143)
		(layer "In13.Cu")
		(net "GMI_CPU0_G0_CPU1_G2_TX_DP<14>")
	)
	(segment
		(start 345.904058 -237.51667)
		(end 345.903296 -237.516162)
		(width 0.1143)
		(layer "In13.Cu")
		(net "GMI_CPU0_G0_CPU1_G2_TX_DP<14>")
	)
	(segment
		(start 125.59157 -227.151692)
		(end 125.623574 -227.170488)
		(width 0.1143)
		(layer "In13.Cu")
		(net "GMI_CPU0_G0_CPU1_G2_TX_DP<14>")
	)
	(segment
		(start 345.906852 -236.869986)
		(end 345.908376 -236.86897)
		(width 0.1143)
		(layer "In13.Cu")
		(net "GMI_CPU0_G0_CPU1_G2_TX_DP<14>")
	)
	(segment
		(start 345.904058 -230.391716)
		(end 345.90736 -230.389684)
		(width 0.1143)
		(layer "In13.Cu")
		(net "GMI_CPU0_G0_CPU1_G2_TX_DP<14>")
	)
	(segment
		(start 125.62332 -224.53854)
		(end 125.59157 -224.557336)
		(width 0.1143)
		(layer "In13.Cu")
		(net "GMI_CPU0_G0_CPU1_G2_TX_DP<14>")
	)
	(segment
		(start 345.909646 -227.800154)
		(end 345.905074 -227.79736)
		(width 0.1143)
		(layer "In13.Cu")
		(net "GMI_CPU0_G0_CPU1_G2_TX_DP<14>")
	)
	(segment
		(start 162.529266 -190.198756)
		(end 161.468816 -191.068706)
		(width 0.14224)
		(layer "In13.Cu")
		(net "GMI_CPU0_G0_CPU1_G2_TX_DP<14>")
	)
	(segment
		(start 345.943174 -237.53953)
		(end 345.91117 -237.520734)
		(width 0.1143)
		(layer "In13.Cu")
		(net "GMI_CPU0_G0_CPU1_G2_TX_DP<14>")
	)
	(segment
		(start 125.62332 -234.258358)
		(end 125.59157 -234.277154)
		(width 0.1143)
		(layer "In13.Cu")
		(net "GMI_CPU0_G0_CPU1_G2_TX_DP<14>")
	)
	(segment
		(start 345.906852 -228.77018)
		(end 345.908376 -228.769164)
		(width 0.1143)
		(layer "In13.Cu")
		(net "GMI_CPU0_G0_CPU1_G2_TX_DP<14>")
	)
	(segment
		(start 345.910154 -227.148136)
		(end 345.935554 -227.133404)
		(width 0.1143)
		(layer "In13.Cu")
		(net "GMI_CPU0_G0_CPU1_G2_TX_DP<14>")
	)
	(segment
		(start 345.91117 -235.900722)
		(end 345.906598 -235.898182)
		(width 0.1143)
		(layer "In13.Cu")
		(net "GMI_CPU0_G0_CPU1_G2_TX_DP<14>")
	)
	(segment
		(start 345.871292 -228.790754)
		(end 345.871546 -228.790246)
		(width 0.1143)
		(layer "In13.Cu")
		(net "GMI_CPU0_G0_CPU1_G2_TX_DP<14>")
	)
	(segment
		(start 345.936316 -228.752908)
		(end 345.943174 -228.748844)
		(width 0.1143)
		(layer "In13.Cu")
		(net "GMI_CPU0_G0_CPU1_G2_TX_DP<14>")
	)
	(segment
		(start 345.905074 -224.557336)
		(end 345.904058 -224.556828)
		(width 0.1143)
		(layer "In13.Cu")
		(net "GMI_CPU0_G0_CPU1_G2_TX_DP<14>")
	)
	(segment
		(start 345.904058 -239.136682)
		(end 345.903296 -239.136174)
		(width 0.1143)
		(layer "In13.Cu")
		(net "GMI_CPU0_G0_CPU1_G2_TX_DP<14>")
	)
	(segment
		(start 346.231972 -221.17939)
		(end 346.231972 -221.034356)
		(width 0.14224)
		(layer "In13.Cu")
		(net "GMI_CPU0_G0_CPU1_G2_TX_DP<14>")
	)
	(segment
		(start 125.59157 -226.177348)
		(end 125.554232 -226.198938)
		(width 0.1143)
		(layer "In13.Cu")
		(net "GMI_CPU0_G0_CPU1_G2_TX_DP<14>")
	)
	(segment
		(start 345.863926 -235.275882)
		(end 345.870784 -235.270802)
		(width 0.1143)
		(layer "In13.Cu")
		(net "GMI_CPU0_G0_CPU1_G2_TX_DP<14>")
	)
	(segment
		(start 345.935554 -228.753416)
		(end 345.936316 -228.752908)
		(width 0.1143)
		(layer "In13.Cu")
		(net "GMI_CPU0_G0_CPU1_G2_TX_DP<14>")
	)
	(segment
		(start 345.905074 -238.491014)
		(end 345.906852 -238.489998)
		(width 0.1143)
		(layer "In13.Cu")
		(net "GMI_CPU0_G0_CPU1_G2_TX_DP<14>")
	)
	(segment
		(start 345.872308 -223.929956)
		(end 345.903296 -223.912176)
		(width 0.1143)
		(layer "In13.Cu")
		(net "GMI_CPU0_G0_CPU1_G2_TX_DP<14>")
	)
	(segment
		(start 345.872308 -233.649774)
		(end 345.903296 -233.631994)
		(width 0.1143)
		(layer "In13.Cu")
		(net "GMI_CPU0_G0_CPU1_G2_TX_DP<14>")
	)
	(segment
		(start 345.908376 -227.149152)
		(end 345.909392 -227.148644)
		(width 0.1143)
		(layer "In13.Cu")
		(net "GMI_CPU0_G0_CPU1_G2_TX_DP<14>")
	)
	(segment
		(start 345.908376 -238.488982)
		(end 345.909392 -238.488474)
		(width 0.1143)
		(layer "In13.Cu")
		(net "GMI_CPU0_G0_CPU1_G2_TX_DP<14>")
	)
	(segment
		(start 345.943174 -229.43947)
		(end 345.905582 -229.417372)
		(width 0.1143)
		(layer "In13.Cu")
		(net "GMI_CPU0_G0_CPU1_G2_TX_DP<14>")
	)
	(segment
		(start 345.905074 -226.177348)
		(end 345.904058 -226.17684)
		(width 0.1143)
		(layer "In13.Cu")
		(net "GMI_CPU0_G0_CPU1_G2_TX_DP<14>")
	)
	(segment
		(start 345.904058 -236.87151)
		(end 345.905074 -236.871002)
		(width 0.1143)
		(layer "In13.Cu")
		(net "GMI_CPU0_G0_CPU1_G2_TX_DP<14>")
	)
	(segment
		(start 345.904058 -233.631486)
		(end 345.905074 -233.630978)
		(width 0.1143)
		(layer "In13.Cu")
		(net "GMI_CPU0_G0_CPU1_G2_TX_DP<14>")
	)
	(segment
		(start 345.908376 -225.52914)
		(end 345.909392 -225.528632)
		(width 0.1143)
		(layer "In13.Cu")
		(net "GMI_CPU0_G0_CPU1_G2_TX_DP<14>")
	)
	(segment
		(start 345.906852 -226.178364)
		(end 345.905074 -226.177348)
		(width 0.1143)
		(layer "In13.Cu")
		(net "GMI_CPU0_G0_CPU1_G2_TX_DP<14>")
	)
	(segment
		(start 345.872308 -235.87837)
		(end 345.863926 -235.872274)
		(width 0.1143)
		(layer "In13.Cu")
		(net "GMI_CPU0_G0_CPU1_G2_TX_DP<14>")
	)
	(segment
		(start 345.943174 -235.919518)
		(end 345.91117 -235.900722)
		(width 0.1143)
		(layer "In13.Cu")
		(net "GMI_CPU0_G0_CPU1_G2_TX_DP<14>")
	)
	(segment
		(start 346.231972 -221.207838)
		(end 346.231972 -221.17939)
		(width 0.1143)
		(layer "In13.Cu")
		(net "GMI_CPU0_G0_CPU1_G2_TX_DP<14>")
	)
	(segment
		(start 125.591824 -229.417118)
		(end 125.551946 -229.439978)
		(width 0.1143)
		(layer "In13.Cu")
		(net "GMI_CPU0_G0_CPU1_G2_TX_DP<14>")
	)
	(segment
		(start 345.935554 -225.513392)
		(end 345.936316 -225.512884)
		(width 0.1143)
		(layer "In13.Cu")
		(net "GMI_CPU0_G0_CPU1_G2_TX_DP<14>")
	)
	(segment
		(start 345.872308 -236.889798)
		(end 345.903296 -236.872018)
		(width 0.1143)
		(layer "In13.Cu")
		(net "GMI_CPU0_G0_CPU1_G2_TX_DP<14>")
	)
	(segment
		(start 345.90482 -229.416864)
		(end 345.871038 -229.397052)
		(width 0.1143)
		(layer "In13.Cu")
		(net "GMI_CPU0_G0_CPU1_G2_TX_DP<14>")
	)
	(segment
		(start 345.907868 -226.178872)
		(end 345.906852 -226.178364)
		(width 0.1143)
		(layer "In13.Cu")
		(net "GMI_CPU0_G0_CPU1_G2_TX_DP<14>")
	)
	(segment
		(start 345.936316 -234.295442)
		(end 345.935554 -234.294934)
		(width 0.1143)
		(layer "In13.Cu")
		(net "GMI_CPU0_G0_CPU1_G2_TX_DP<14>")
	)
	(segment
		(start 345.909392 -228.768656)
		(end 345.910154 -228.768148)
		(width 0.1143)
		(layer "In13.Cu")
		(net "GMI_CPU0_G0_CPU1_G2_TX_DP<14>")
	)
	(segment
		(start 125.59157 -235.897166)
		(end 125.554232 -235.918756)
		(width 0.1143)
		(layer "In13.Cu")
		(net "GMI_CPU0_G0_CPU1_G2_TX_DP<14>")
	)
	(segment
		(start 345.903296 -225.532188)
		(end 345.904058 -225.53168)
		(width 0.1143)
		(layer "In13.Cu")
		(net "GMI_CPU0_G0_CPU1_G2_TX_DP<14>")
	)
	(segment
		(start 136.593326 -210.497674)
		(end 126.350014 -218.896692)
		(width 0.14224)
		(layer "In13.Cu")
		(net "GMI_CPU0_G0_CPU1_G2_TX_DP<14>")
	)
	(segment
		(start 125.554232 -227.130102)
		(end 125.59157 -227.151692)
		(width 0.1143)
		(layer "In13.Cu")
		(net "GMI_CPU0_G0_CPU1_G2_TX_DP<14>")
	)
	(segment
		(start 345.904058 -232.656634)
		(end 345.903296 -232.656126)
		(width 0.1143)
		(layer "In13.Cu")
		(net "GMI_CPU0_G0_CPU1_G2_TX_DP<14>")
	)
	(segment
		(start 345.900248 -228.77399)
		(end 345.903296 -228.772212)
		(width 0.1143)
		(layer "In13.Cu")
		(net "GMI_CPU0_G0_CPU1_G2_TX_DP<14>")
	)
	(segment
		(start 345.905074 -237.517178)
		(end 345.904058 -237.51667)
		(width 0.1143)
		(layer "In13.Cu")
		(net "GMI_CPU0_G0_CPU1_G2_TX_DP<14>")
	)
	(segment
		(start 345.91117 -237.520734)
		(end 345.906598 -237.518194)
		(width 0.1143)
		(layer "In13.Cu")
		(net "GMI_CPU0_G0_CPU1_G2_TX_DP<14>")
	)
	(segment
		(start 125.554232 -235.229908)
		(end 125.59157 -235.251498)
		(width 0.1143)
		(layer "In13.Cu")
		(net "GMI_CPU0_G0_CPU1_G2_TX_DP<14>")
	)
	(segment
		(start 345.86164 -225.557588)
		(end 345.872308 -225.549968)
		(width 0.1143)
		(layer "In13.Cu")
		(net "GMI_CPU0_G0_CPU1_G2_TX_DP<14>")
	)
	(segment
		(start 345.936316 -236.852714)
		(end 345.943174 -236.84865)
		(width 0.1143)
		(layer "In13.Cu")
		(net "GMI_CPU0_G0_CPU1_G2_TX_DP<14>")
	)
	(segment
		(start 345.864688 -236.895132)
		(end 345.872308 -236.889798)
		(width 0.1143)
		(layer "In13.Cu")
		(net "GMI_CPU0_G0_CPU1_G2_TX_DP<14>")
	)
	(segment
		(start 125.59157 -237.517178)
		(end 125.554232 -237.538768)
		(width 0.1143)
		(layer "In13.Cu")
		(net "GMI_CPU0_G0_CPU1_G2_TX_DP<14>")
	)
	(segment
		(start 136.593326 -210.49742)
		(end 136.593326 -210.497674)
		(width 0.14224)
		(layer "In13.Cu")
		(net "GMI_CPU0_G0_CPU1_G2_TX_DP<14>")
	)
	(segment
		(start 161.468816 -191.068706)
		(end 161.155634 -191.653922)
		(width 0.14224)
		(layer "In13.Cu")
		(net "GMI_CPU0_G0_CPU1_G2_TX_DP<14>")
	)
	(segment
		(start 345.899994 -228.77399)
		(end 345.900248 -228.77399)
		(width 0.1143)
		(layer "In13.Cu")
		(net "GMI_CPU0_G0_CPU1_G2_TX_DP<14>")
	)
	(segment
		(start 345.905074 -225.531172)
		(end 345.906852 -225.530156)
		(width 0.1143)
		(layer "In13.Cu")
		(net "GMI_CPU0_G0_CPU1_G2_TX_DP<14>")
	)
	(segment
		(start 346.186252 -221.791022)
		(end 346.186252 -221.253558)
		(width 0.1143)
		(layer "In13.Cu")
		(net "GMI_CPU0_G0_CPU1_G2_TX_DP<14>")
	)
	(segment
		(start 251.312934 -191.746886)
		(end 239.845088 -199.777096)
		(width 0.14224)
		(layer "In13.Cu")
		(net "GMI_CPU0_G0_CPU1_G2_TX_DP<14>")
	)
	(segment
		(start 345.905074 -236.871002)
		(end 345.906852 -236.869986)
		(width 0.1143)
		(layer "In13.Cu")
		(net "GMI_CPU0_G0_CPU1_G2_TX_DP<14>")
	)
	(segment
		(start 345.906852 -223.910144)
		(end 345.908376 -223.909128)
		(width 0.1143)
		(layer "In13.Cu")
		(net "GMI_CPU0_G0_CPU1_G2_TX_DP<14>")
	)
	(segment
		(start 345.904058 -235.896658)
		(end 345.903296 -235.89615)
		(width 0.1143)
		(layer "In13.Cu")
		(net "GMI_CPU0_G0_CPU1_G2_TX_DP<14>")
	)
	(segment
		(start 345.904058 -234.276646)
		(end 345.903296 -234.276138)
		(width 0.1143)
		(layer "In13.Cu")
		(net "GMI_CPU0_G0_CPU1_G2_TX_DP<14>")
	)
	(segment
		(start 345.903296 -232.656126)
		(end 345.872308 -232.638346)
		(width 0.1143)
		(layer "In13.Cu")
		(net "GMI_CPU0_G0_CPU1_G2_TX_DP<14>")
	)
	(segment
		(start 161.155634 -191.653922)
		(end 153.969974 -197.544944)
		(width 0.14224)
		(layer "In13.Cu")
		(net "GMI_CPU0_G0_CPU1_G2_TX_DP<14>")
	)
	(segment
		(start 345.870784 -235.270802)
		(end 345.904058 -235.251498)
		(width 0.1143)
		(layer "In13.Cu")
		(net "GMI_CPU0_G0_CPU1_G2_TX_DP<14>")
	)
	(segment
		(start 345.935808 -226.195128)
		(end 345.910662 -226.180396)
		(width 0.1143)
		(layer "In13.Cu")
		(net "GMI_CPU0_G0_CPU1_G2_TX_DP<14>")
	)
	(segment
		(start 125.554232 -223.890078)
		(end 125.59157 -223.911668)
		(width 0.1143)
		(layer "In13.Cu")
		(net "GMI_CPU0_G0_CPU1_G2_TX_DP<14>")
	)
	(segment
		(start 125.263402 -221.575884)
		(end 125.309122 -221.621604)
		(width 0.1143)
		(layer "In13.Cu")
		(net "GMI_CPU0_G0_CPU1_G2_TX_DP<14>")
	)
	(segment
		(start 345.904058 -227.796852)
		(end 345.903296 -227.796344)
		(width 0.1143)
		(layer "In13.Cu")
		(net "GMI_CPU0_G0_CPU1_G2_TX_DP<14>")
	)
	(segment
		(start 345.904058 -223.911668)
		(end 345.905074 -223.91116)
		(width 0.1143)
		(layer "In13.Cu")
		(net "GMI_CPU0_G0_CPU1_G2_TX_DP<14>")
	)
	(segment
		(start 345.936316 -225.512884)
		(end 345.943174 -225.50882)
		(width 0.1143)
		(layer "In13.Cu")
		(net "GMI_CPU0_G0_CPU1_G2_TX_DP<14>")
	)
	(segment
		(start 346.231972 -221.034356)
		(end 346.236544 -220.97746)
		(width 0.14224)
		(layer "In13.Cu")
		(net "GMI_CPU0_G0_CPU1_G2_TX_DP<14>")
	)
	(segment
		(start 345.85275 -227.18395)
		(end 345.872308 -227.16998)
		(width 0.1143)
		(layer "In13.Cu")
		(net "GMI_CPU0_G0_CPU1_G2_TX_DP<14>")
	)
	(segment
		(start 125.58522 -222.2881)
		(end 125.624336 -222.31096)
		(width 0.1143)
		(layer "In13.Cu")
		(net "GMI_CPU0_G0_CPU1_G2_TX_DP<14>")
	)
	(segment
		(start 125.59157 -238.491522)
		(end 125.623574 -238.510318)
		(width 0.1143)
		(layer "In13.Cu")
		(net "GMI_CPU0_G0_CPU1_G2_TX_DP<14>")
	)
	(segment
		(start 125.554232 -231.989884)
		(end 125.59157 -232.011474)
		(width 0.1143)
		(layer "In13.Cu")
		(net "GMI_CPU0_G0_CPU1_G2_TX_DP<14>")
	)
	(segment
		(start 345.94038 -231.990646)
		(end 345.943174 -231.988614)
		(width 0.1143)
		(layer "In13.Cu")
		(net "GMI_CPU0_G0_CPU1_G2_TX_DP<14>")
	)
	(segment
		(start 239.844834 -199.777096)
		(end 239.84204 -199.77735)
		(width 0.14224)
		(layer "In13.Cu")
		(net "GMI_CPU0_G0_CPU1_G2_TX_DP<14>")
	)
	(segment
		(start 125.59157 -234.277154)
		(end 125.554232 -234.298744)
		(width 0.1143)
		(layer "In13.Cu")
		(net "GMI_CPU0_G0_CPU1_G2_TX_DP<14>")
	)
	(segment
		(start 125.554232 -225.51009)
		(end 125.59157 -225.53168)
		(width 0.1143)
		(layer "In13.Cu")
		(net "GMI_CPU0_G0_CPU1_G2_TX_DP<14>")
	)
	(segment
		(start 345.904058 -228.771704)
		(end 345.905074 -228.771196)
		(width 0.1143)
		(layer "In13.Cu")
		(net "GMI_CPU0_G0_CPU1_G2_TX_DP<14>")
	)
	(segment
		(start 125.59157 -227.79736)
		(end 125.554232 -227.81895)
		(width 0.1143)
		(layer "In13.Cu")
		(net "GMI_CPU0_G0_CPU1_G2_TX_DP<14>")
	)
	(segment
		(start 345.935554 -232.674922)
		(end 345.904058 -232.656634)
		(width 0.1143)
		(layer "In13.Cu")
		(net "GMI_CPU0_G0_CPU1_G2_TX_DP<14>")
	)
	(segment
		(start 345.903296 -237.516162)
		(end 345.872308 -237.498382)
		(width 0.1143)
		(layer "In13.Cu")
		(net "GMI_CPU0_G0_CPU1_G2_TX_DP<14>")
	)
	(segment
		(start 345.905074 -227.79736)
		(end 345.904058 -227.796852)
		(width 0.1143)
		(layer "In13.Cu")
		(net "GMI_CPU0_G0_CPU1_G2_TX_DP<14>")
	)
	(segment
		(start 125.62332 -226.158552)
		(end 125.59157 -226.177348)
		(width 0.1143)
		(layer "In13.Cu")
		(net "GMI_CPU0_G0_CPU1_G2_TX_DP<14>")
	)
	(segment
		(start 345.903296 -233.631994)
		(end 345.904058 -233.631486)
		(width 0.1143)
		(layer "In13.Cu")
		(net "GMI_CPU0_G0_CPU1_G2_TX_DP<14>")
	)
	(segment
		(start 125.623574 -239.118394)
		(end 125.59157 -239.13719)
		(width 0.1143)
		(layer "In13.Cu")
		(net "GMI_CPU0_G0_CPU1_G2_TX_DP<14>")
	)
	(segment
		(start 345.852496 -232.043986)
		(end 345.872308 -232.029762)
		(width 0.1143)
		(layer "In13.Cu")
		(net "GMI_CPU0_G0_CPU1_G2_TX_DP<14>")
	)
	(segment
		(start 346.237052 -220.639386)
		(end 345.343226 -219.135452)
		(width 0.14224)
		(layer "In13.Cu")
		(net "GMI_CPU0_G0_CPU1_G2_TX_DP<14>")
	)
	(segment
		(start 345.872308 -232.638346)
		(end 345.852496 -232.624122)
		(width 0.1143)
		(layer "In13.Cu")
		(net "GMI_CPU0_G0_CPU1_G2_TX_DP<14>")
	)
	(segment
		(start 125.59157 -233.631486)
		(end 125.623574 -233.650282)
		(width 0.1143)
		(layer "In13.Cu")
		(net "GMI_CPU0_G0_CPU1_G2_TX_DP<14>")
	)
	(segment
		(start 345.935554 -236.853222)
		(end 345.936316 -236.852714)
		(width 0.1143)
		(layer "In13.Cu")
		(net "GMI_CPU0_G0_CPU1_G2_TX_DP<14>")
	)
	(segment
		(start 125.62332 -232.638346)
		(end 125.59157 -232.657142)
		(width 0.1143)
		(layer "In13.Cu")
		(net "GMI_CPU0_G0_CPU1_G2_TX_DP<14>")
	)
	(segment
		(start 125.59157 -228.771704)
		(end 125.623574 -228.7905)
		(width 0.1143)
		(layer "In13.Cu")
		(net "GMI_CPU0_G0_CPU1_G2_TX_DP<14>")
	)
	(segment
		(start 346.561156 -239.624108)
		(end 346.263214 -239.624108)
		(width 0.1143)
		(layer "In13.Cu")
		(net "GMI_CPU0_G0_CPU1_G2_TX_DP<14>")
	)
	(segment
		(start 345.909392 -236.868462)
		(end 345.910154 -236.867954)
		(width 0.1143)
		(layer "In13.Cu")
		(net "GMI_CPU0_G0_CPU1_G2_TX_DP<14>")
	)
	(segment
		(start 345.872308 -226.158552)
		(end 345.86164 -226.150932)
		(width 0.1143)
		(layer "In13.Cu")
		(net "GMI_CPU0_G0_CPU1_G2_TX_DP<14>")
	)
	(segment
		(start 345.898724 -239.133634)
		(end 345.897962 -239.133126)
		(width 0.1143)
		(layer "In13.Cu")
		(net "GMI_CPU0_G0_CPU1_G2_TX_DP<14>")
	)
	(segment
		(start 125.309122 -221.621604)
		(end 125.309122 -221.805754)
		(width 0.1143)
		(layer "In13.Cu")
		(net "GMI_CPU0_G0_CPU1_G2_TX_DP<14>")
	)
	(segment
		(start 345.904058 -235.251498)
		(end 345.943174 -235.228638)
		(width 0.1143)
		(layer "In13.Cu")
		(net "GMI_CPU0_G0_CPU1_G2_TX_DP<14>")
	)
	(segment
		(start 125.26391 -220.813884)
		(end 125.26391 -221.157038)
		(width 0.14224)
		(layer "In13.Cu")
		(net "GMI_CPU0_G0_CPU1_G2_TX_DP<14>")
	)
	(segment
		(start 125.62332 -237.498382)
		(end 125.59157 -237.517178)
		(width 0.1143)
		(layer "In13.Cu")
		(net "GMI_CPU0_G0_CPU1_G2_TX_DP<14>")
	)
	(segment
		(start 345.903296 -223.912176)
		(end 345.904058 -223.911668)
		(width 0.1143)
		(layer "In13.Cu")
		(net "GMI_CPU0_G0_CPU1_G2_TX_DP<14>")
	)
	(segment
		(start 125.542802 -222.259398)
		(end 125.58522 -222.2881)
		(width 0.1143)
		(layer "In13.Cu")
		(net "GMI_CPU0_G0_CPU1_G2_TX_DP<14>")
	)
	(segment
		(start 345.872308 -238.50981)
		(end 345.903296 -238.49203)
		(width 0.1143)
		(layer "In13.Cu")
		(net "GMI_CPU0_G0_CPU1_G2_TX_DP<14>")
	)
	(segment
		(start 125.62332 -231.018588)
		(end 125.591824 -231.03713)
		(width 0.1143)
		(layer "In13.Cu")
		(net "GMI_CPU0_G0_CPU1_G2_TX_DP<14>")
	)
	(segment
		(start 345.903296 -230.392224)
		(end 345.904058 -230.391716)
		(width 0.1143)
		(layer "In13.Cu")
		(net "GMI_CPU0_G0_CPU1_G2_TX_DP<14>")
	)
	(segment
		(start 345.910154 -225.528124)
		(end 345.935554 -225.513392)
		(width 0.1143)
		(layer "In13.Cu")
		(net "GMI_CPU0_G0_CPU1_G2_TX_DP<14>")
	)
	(segment
		(start 125.59157 -236.87151)
		(end 125.623574 -236.890306)
		(width 0.1143)
		(layer "In13.Cu")
		(net "GMI_CPU0_G0_CPU1_G2_TX_DP<14>")
	)
	(segment
		(start 345.872308 -227.778564)
		(end 345.85275 -227.764594)
		(width 0.1143)
		(layer "In13.Cu")
		(net "GMI_CPU0_G0_CPU1_G2_TX_DP<14>")
	)
	(segment
		(start 345.908376 -228.769164)
		(end 345.909392 -228.768656)
		(width 0.1143)
		(layer "In13.Cu")
		(net "GMI_CPU0_G0_CPU1_G2_TX_DP<14>")
	)
	(segment
		(start 345.906852 -238.489998)
		(end 345.908376 -238.488982)
		(width 0.1143)
		(layer "In13.Cu")
		(net "GMI_CPU0_G0_CPU1_G2_TX_DP<14>")
	)
	(segment
		(start 345.903296 -235.89615)
		(end 345.872308 -235.87837)
		(width 0.1143)
		(layer "In13.Cu")
		(net "GMI_CPU0_G0_CPU1_G2_TX_DP<14>")
	)
	(segment
		(start 345.906598 -222.93834)
		(end 345.905074 -222.937324)
		(width 0.1143)
		(layer "In13.Cu")
		(net "GMI_CPU0_G0_CPU1_G2_TX_DP<14>")
	)
	(segment
		(start 346.236544 -220.639894)
		(end 346.237052 -220.639386)
		(width 0.14224)
		(layer "In13.Cu")
		(net "GMI_CPU0_G0_CPU1_G2_TX_DP<14>")
	)
	(segment
		(start 345.905074 -223.91116)
		(end 345.906852 -223.910144)
		(width 0.1143)
		(layer "In13.Cu")
		(net "GMI_CPU0_G0_CPU1_G2_TX_DP<14>")
	)
	(segment
		(start 346.1766 -239.518444)
		(end 346.164662 -239.455452)
		(width 0.1143)
		(layer "In13.Cu")
		(net "GMI_CPU0_G0_CPU1_G2_TX_DP<14>")
	)
	(segment
		(start 345.936316 -223.892872)
		(end 345.943174 -223.888808)
		(width 0.1143)
		(layer "In13.Cu")
		(net "GMI_CPU0_G0_CPU1_G2_TX_DP<14>")
	)
	(segment
		(start 125.315726 -239.541558)
		(end 125.315472 -239.541558)
		(width 0.1143)
		(layer "In13.Cu")
		(net "GMI_CPU0_G0_CPU1_G2_TX_DP<14>")
	)
	(segment
		(start 345.904058 -226.17684)
		(end 345.903296 -226.176332)
		(width 0.1143)
		(layer "In13.Cu")
		(net "GMI_CPU0_G0_CPU1_G2_TX_DP<14>")
	)
	(segment
		(start 125.59157 -232.657142)
		(end 125.554232 -232.678732)
		(width 0.1143)
		(layer "In13.Cu")
		(net "GMI_CPU0_G0_CPU1_G2_TX_DP<14>")
	)
	(segment
		(start 345.908376 -236.86897)
		(end 345.909392 -236.868462)
		(width 0.1143)
		(layer "In13.Cu")
		(net "GMI_CPU0_G0_CPU1_G2_TX_DP<14>")
	)
	(segment
		(start 345.905074 -222.937324)
		(end 345.904058 -222.936816)
		(width 0.1143)
		(layer "In13.Cu")
		(net "GMI_CPU0_G0_CPU1_G2_TX_DP<14>")
	)
	(segment
		(start 345.904058 -238.491522)
		(end 345.905074 -238.491014)
		(width 0.1143)
		(layer "In13.Cu")
		(net "GMI_CPU0_G0_CPU1_G2_TX_DP<14>")
	)
	(segment
		(start 345.906852 -225.530156)
		(end 345.908376 -225.52914)
		(width 0.1143)
		(layer "In13.Cu")
		(net "GMI_CPU0_G0_CPU1_G2_TX_DP<14>")
	)
	(segment
		(start 125.62332 -227.778564)
		(end 125.59157 -227.79736)
		(width 0.1143)
		(layer "In13.Cu")
		(net "GMI_CPU0_G0_CPU1_G2_TX_DP<14>")
	)
	(segment
		(start 125.263402 -221.547436)
		(end 125.263402 -221.575884)
		(width 0.1143)
		(layer "In13.Cu")
		(net "GMI_CPU0_G0_CPU1_G2_TX_DP<14>")
	)
	(segment
		(start 345.910154 -228.768148)
		(end 345.935554 -228.753416)
		(width 0.1143)
		(layer "In13.Cu")
		(net "GMI_CPU0_G0_CPU1_G2_TX_DP<14>")
	)
	(segment
		(start 345.897962 -239.133126)
		(end 345.872308 -239.118394)
		(width 0.1143)
		(layer "In13.Cu")
		(net "GMI_CPU0_G0_CPU1_G2_TX_DP<14>")
	)
	(segment
		(start 345.909392 -225.528632)
		(end 345.910154 -225.528124)
		(width 0.1143)
		(layer "In13.Cu")
		(net "GMI_CPU0_G0_CPU1_G2_TX_DP<14>")
	)
	(segment
		(start 345.905074 -228.771196)
		(end 345.906852 -228.77018)
		(width 0.1143)
		(layer "In13.Cu")
		(net "GMI_CPU0_G0_CPU1_G2_TX_DP<14>")
	)
	(segment
		(start 345.903296 -222.936308)
		(end 345.899486 -222.934022)
		(width 0.1143)
		(layer "In13.Cu")
		(net "GMI_CPU0_G0_CPU1_G2_TX_DP<14>")
	)
	(segment
		(start 345.910154 -238.487966)
		(end 345.935554 -238.473234)
		(width 0.1143)
		(layer "In13.Cu")
		(net "GMI_CPU0_G0_CPU1_G2_TX_DP<14>")
	)
	(segment
		(start 345.905074 -233.630978)
		(end 345.943174 -233.608626)
		(width 0.1143)
		(layer "In13.Cu")
		(net "GMI_CPU0_G0_CPU1_G2_TX_DP<14>")
	)
	(segment
		(start 345.872308 -230.410004)
		(end 345.900502 -230.393748)
		(width 0.1143)
		(layer "In13.Cu")
		(net "GMI_CPU0_G0_CPU1_G2_TX_DP<14>")
	)
	(segment
		(start 345.903296 -234.276138)
		(end 345.872308 -234.258358)
		(width 0.1143)
		(layer "In13.Cu")
		(net "GMI_CPU0_G0_CPU1_G2_TX_DP<14>")
	)
	(segment
		(start 345.935554 -227.133404)
		(end 345.936316 -227.132896)
		(width 0.1143)
		(layer "In13.Cu")
		(net "GMI_CPU0_G0_CPU1_G2_TX_DP<14>")
	)
	(segment
		(start 262.742426 -189.73165)
		(end 251.312934 -191.746886)
		(width 0.14224)
		(layer "In13.Cu")
		(net "GMI_CPU0_G0_CPU1_G2_TX_DP<14>")
	)
	(segment
		(start 210.873594 -190.643002)
		(end 207.281272 -190.009018)
		(width 0.14224)
		(layer "In13.Cu")
		(net "GMI_CPU0_G0_CPU1_G2_TX_DP<14>")
	)
	(segment
		(start 345.903296 -227.1522)
		(end 345.904058 -227.151692)
		(width 0.1143)
		(layer "In13.Cu")
		(net "GMI_CPU0_G0_CPU1_G2_TX_DP<14>")
	)
	(segment
		(start 233.086148 -199.843136)
		(end 210.873594 -190.643002)
		(width 0.14224)
		(layer "In13.Cu")
		(net "GMI_CPU0_G0_CPU1_G2_TX_DP<14>")
	)
	(segment
		(start 345.935554 -223.89338)
		(end 345.936316 -223.892872)
		(width 0.1143)
		(layer "In13.Cu")
		(net "GMI_CPU0_G0_CPU1_G2_TX_DP<14>")
	)
	(segment
		(start 153.970228 -197.544944)
		(end 149.344634 -201.33691)
		(width 0.14224)
		(layer "In13.Cu")
		(net "GMI_CPU0_G0_CPU1_G2_TX_DP<14>")
	)
	(segment
		(start 125.232668 -239.624362)
		(end 124.934726 -239.624362)
		(width 0.1143)
		(layer "In13.Cu")
		(net "GMI_CPU0_G0_CPU1_G2_TX_DP<14>")
	)
	(segment
		(start 345.906852 -227.150168)
		(end 345.908376 -227.149152)
		(width 0.1143)
		(layer "In13.Cu")
		(net "GMI_CPU0_G0_CPU1_G2_TX_DP<14>")
	)
	(segment
		(start 345.908376 -223.909128)
		(end 345.909392 -223.90862)
		(width 0.1143)
		(layer "In13.Cu")
		(net "GMI_CPU0_G0_CPU1_G2_TX_DP<14>")
	)
	(segment
		(start 153.969974 -197.544944)
		(end 153.970228 -197.544944)
		(width 0.14224)
		(layer "In13.Cu")
		(net "GMI_CPU0_G0_CPU1_G2_TX_DP<14>")
	)
	(segment
		(start 125.59157 -222.937324)
		(end 125.554232 -222.958914)
		(width 0.1143)
		(layer "In13.Cu")
		(net "GMI_CPU0_G0_CPU1_G2_TX_DP<14>")
	)
	(segment
		(start 345.936316 -238.472726)
		(end 345.943174 -238.468662)
		(width 0.1143)
		(layer "In13.Cu")
		(net "GMI_CPU0_G0_CPU1_G2_TX_DP<14>")
	)
	(segment
		(start 345.863926 -238.515906)
		(end 345.872308 -238.50981)
		(width 0.1143)
		(layer "In13.Cu")
		(net "GMI_CPU0_G0_CPU1_G2_TX_DP<14>")
	)
	(segment
		(start 345.903296 -226.176332)
		(end 345.872308 -226.158552)
		(width 0.1143)
		(layer "In13.Cu")
		(net "GMI_CPU0_G0_CPU1_G2_TX_DP<14>")
	)
	(segment
		(start 345.905582 -229.417372)
		(end 345.90482 -229.416864)
		(width 0.1143)
		(layer "In13.Cu")
		(net "GMI_CPU0_G0_CPU1_G2_TX_DP<14>")
	)
	(segment
		(start 125.554232 -233.609896)
		(end 125.59157 -233.631486)
		(width 0.1143)
		(layer "In13.Cu")
		(net "GMI_CPU0_G0_CPU1_G2_TX_DP<14>")
	)
	(segment
		(start 345.904058 -222.936816)
		(end 345.903296 -222.936308)
		(width 0.1143)
		(layer "In13.Cu")
		(net "GMI_CPU0_G0_CPU1_G2_TX_DP<14>")
	)
	(segment
		(start 345.937332 -226.196144)
		(end 345.935808 -226.195128)
		(width 0.1143)
		(layer "In13.Cu")
		(net "GMI_CPU0_G0_CPU1_G2_TX_DP<14>")
	)
	(segment
		(start 207.281272 -190.009018)
		(end 162.529266 -190.198756)
		(width 0.14224)
		(layer "In13.Cu")
		(net "GMI_CPU0_G0_CPU1_G2_TX_DP<14>")
	)
	(segment
		(start 345.909392 -223.90862)
		(end 345.910154 -223.908112)
		(width 0.1143)
		(layer "In13.Cu")
		(net "GMI_CPU0_G0_CPU1_G2_TX_DP<14>")
	)
	(segment
		(start 345.343226 -219.135452)
		(end 317.269622 -196.116956)
		(width 0.14224)
		(layer "In13.Cu")
		(net "GMI_CPU0_G0_CPU1_G2_TX_DP<14>")
	)
	(segment
		(start 345.943174 -231.059482)
		(end 345.898978 -231.033828)
		(width 0.1143)
		(layer "In13.Cu")
		(net "GMI_CPU0_G0_CPU1_G2_TX_DP<14>")
	)
	(segment
		(start 125.59157 -225.53168)
		(end 125.623574 -225.550476)
		(width 0.1143)
		(layer "In13.Cu")
		(net "GMI_CPU0_G0_CPU1_G2_TX_DP<14>")
	)
	(segment
		(start 125.263402 -221.157546)
		(end 125.263402 -221.547436)
		(width 0.14224)
		(layer "In13.Cu")
		(net "GMI_CPU0_G0_CPU1_G2_TX_DP<14>")
	)
	(arc
		(start 125.623574 -232.03027)
		(mid 125.779401 -232.334411)
		(end 125.62332 -232.638346)
		(width 0.1143)
		(layer "In13.Cu")
		(net "GMI_CPU0_G0_CPU1_G2_TX_DP<14>")
	)
	(arc
		(start 345.942412 -222.256096)
		(mid 346.121605 -222.053586)
		(end 346.186252 -221.791022)
		(width 0.1143)
		(layer "In13.Cu")
		(net "GMI_CPU0_G0_CPU1_G2_TX_DP<14>")
	)
	(arc
		(start 345.852496 -232.624122)
		(mid 345.703782 -232.334054)
		(end 345.852496 -232.043986)
		(width 0.1143)
		(layer "In13.Cu")
		(net "GMI_CPU0_G0_CPU1_G2_TX_DP<14>")
	)
	(arc
		(start 345.90736 -230.389684)
		(mid 346.111659 -230.184216)
		(end 346.186506 -229.90429)
		(width 0.1143)
		(layer "In13.Cu")
		(net "GMI_CPU0_G0_CPU1_G2_TX_DP<14>")
	)
	(arc
		(start 125.77953 -230.71455)
		(mid 125.738132 -230.885424)
		(end 125.62332 -231.018588)
		(width 0.1143)
		(layer "In13.Cu")
		(net "GMI_CPU0_G0_CPU1_G2_TX_DP<14>")
	)
	(arc
		(start 345.898978 -231.033828)
		(mid 345.764828 -230.898535)
		(end 345.716352 -230.714296)
		(width 0.1143)
		(layer "In13.Cu")
		(net "GMI_CPU0_G0_CPU1_G2_TX_DP<14>")
	)
	(arc
		(start 345.943174 -235.228638)
		(mid 346.186501 -234.764072)
		(end 345.943174 -234.299506)
		(width 0.1143)
		(layer "In13.Cu")
		(net "GMI_CPU0_G0_CPU1_G2_TX_DP<14>")
	)
	(arc
		(start 345.943174 -228.748844)
		(mid 346.186501 -228.284278)
		(end 345.943174 -227.819712)
		(width 0.1143)
		(layer "In13.Cu")
		(net "GMI_CPU0_G0_CPU1_G2_TX_DP<14>")
	)
	(arc
		(start 125.554232 -235.918756)
		(mid 125.309411 -236.384338)
		(end 125.554232 -236.84992)
		(width 0.1143)
		(layer "In13.Cu")
		(net "GMI_CPU0_G0_CPU1_G2_TX_DP<14>")
	)
	(arc
		(start 346.18041 -239.541304)
		(mid 346.178622 -239.529855)
		(end 346.1766 -239.518444)
		(width 0.1143)
		(layer "In13.Cu")
		(net "GMI_CPU0_G0_CPU1_G2_TX_DP<14>")
	)
	(arc
		(start 345.716352 -230.714296)
		(mid 345.757945 -230.543508)
		(end 345.872308 -230.410004)
		(width 0.1143)
		(layer "In13.Cu")
		(net "GMI_CPU0_G0_CPU1_G2_TX_DP<14>")
	)
	(arc
		(start 345.943174 -236.84865)
		(mid 346.186501 -236.384084)
		(end 345.943174 -235.919518)
		(width 0.1143)
		(layer "In13.Cu")
		(net "GMI_CPU0_G0_CPU1_G2_TX_DP<14>")
	)
	(arc
		(start 345.943174 -238.468662)
		(mid 346.186501 -238.004096)
		(end 345.943174 -237.53953)
		(width 0.1143)
		(layer "In13.Cu")
		(net "GMI_CPU0_G0_CPU1_G2_TX_DP<14>")
	)
	(arc
		(start 125.623574 -238.510318)
		(mid 125.779401 -238.814356)
		(end 125.623574 -239.118394)
		(width 0.1143)
		(layer "In13.Cu")
		(net "GMI_CPU0_G0_CPU1_G2_TX_DP<14>")
	)
	(arc
		(start 125.554232 -227.81895)
		(mid 125.309411 -228.284532)
		(end 125.554232 -228.750114)
		(width 0.1143)
		(layer "In13.Cu")
		(net "GMI_CPU0_G0_CPU1_G2_TX_DP<14>")
	)
	(arc
		(start 345.871038 -229.397052)
		(mid 345.757317 -229.264254)
		(end 345.716352 -229.094284)
		(width 0.1143)
		(layer "In13.Cu")
		(net "GMI_CPU0_G0_CPU1_G2_TX_DP<14>")
	)
	(arc
		(start 345.863926 -235.872274)
		(mid 345.711045 -235.574078)
		(end 345.863926 -235.275882)
		(width 0.1143)
		(layer "In13.Cu")
		(net "GMI_CPU0_G0_CPU1_G2_TX_DP<14>")
	)
	(arc
		(start 125.621542 -230.408988)
		(mid 125.737723 -230.542547)
		(end 125.77953 -230.71455)
		(width 0.1143)
		(layer "In13.Cu")
		(net "GMI_CPU0_G0_CPU1_G2_TX_DP<14>")
	)
	(arc
		(start 345.943174 -223.888808)
		(mid 346.186501 -223.424242)
		(end 345.943174 -222.959676)
		(width 0.1143)
		(layer "In13.Cu")
		(net "GMI_CPU0_G0_CPU1_G2_TX_DP<14>")
	)
	(arc
		(start 345.864688 -237.493048)
		(mid 345.711505 -237.19409)
		(end 345.864688 -236.895132)
		(width 0.1143)
		(layer "In13.Cu")
		(net "GMI_CPU0_G0_CPU1_G2_TX_DP<14>")
	)
	(arc
		(start 125.77953 -229.094538)
		(mid 125.738132 -229.265412)
		(end 125.62332 -229.398576)
		(width 0.1143)
		(layer "In13.Cu")
		(net "GMI_CPU0_G0_CPU1_G2_TX_DP<14>")
	)
	(arc
		(start 345.863926 -239.112298)
		(mid 345.711045 -238.814102)
		(end 345.863926 -238.515906)
		(width 0.1143)
		(layer "In13.Cu")
		(net "GMI_CPU0_G0_CPU1_G2_TX_DP<14>")
	)
	(arc
		(start 125.554232 -239.15878)
		(mid 125.395095 -239.325331)
		(end 125.315726 -239.541558)
		(width 0.1143)
		(layer "In13.Cu")
		(net "GMI_CPU0_G0_CPU1_G2_TX_DP<14>")
	)
	(arc
		(start 125.623574 -227.170488)
		(mid 125.779401 -227.474629)
		(end 125.62332 -227.778564)
		(width 0.1143)
		(layer "In13.Cu")
		(net "GMI_CPU0_G0_CPU1_G2_TX_DP<14>")
	)
	(arc
		(start 345.872308 -224.53854)
		(mid 345.720618 -224.234248)
		(end 345.872308 -223.929956)
		(width 0.1143)
		(layer "In13.Cu")
		(net "GMI_CPU0_G0_CPU1_G2_TX_DP<14>")
	)
	(arc
		(start 125.623574 -225.550476)
		(mid 125.779401 -225.854617)
		(end 125.62332 -226.158552)
		(width 0.1143)
		(layer "In13.Cu")
		(net "GMI_CPU0_G0_CPU1_G2_TX_DP<14>")
	)
	(arc
		(start 125.309122 -221.805754)
		(mid 125.371727 -222.060517)
		(end 125.542802 -222.259398)
		(width 0.1143)
		(layer "In13.Cu")
		(net "GMI_CPU0_G0_CPU1_G2_TX_DP<14>")
	)
	(arc
		(start 125.551946 -231.05999)
		(mid 125.373764 -231.262393)
		(end 125.30963 -231.524302)
		(width 0.1143)
		(layer "In13.Cu")
		(net "GMI_CPU0_G0_CPU1_G2_TX_DP<14>")
	)
	(arc
		(start 125.554232 -224.578926)
		(mid 125.309411 -225.044508)
		(end 125.554232 -225.51009)
		(width 0.1143)
		(layer "In13.Cu")
		(net "GMI_CPU0_G0_CPU1_G2_TX_DP<14>")
	)
	(arc
		(start 345.86164 -226.150932)
		(mid 345.709573 -225.85426)
		(end 345.86164 -225.557588)
		(width 0.1143)
		(layer "In13.Cu")
		(net "GMI_CPU0_G0_CPU1_G2_TX_DP<14>")
	)
	(arc
		(start 346.186506 -229.904036)
		(mid 346.121991 -229.641817)
		(end 345.943174 -229.43947)
		(width 0.1143)
		(layer "In13.Cu")
		(net "GMI_CPU0_G0_CPU1_G2_TX_DP<14>")
	)
	(arc
		(start 125.624336 -222.31096)
		(mid 125.738339 -222.444083)
		(end 125.779276 -222.61449)
		(width 0.1143)
		(layer "In13.Cu")
		(net "GMI_CPU0_G0_CPU1_G2_TX_DP<14>")
	)
	(arc
		(start 345.943174 -233.608626)
		(mid 346.186501 -233.14406)
		(end 345.943174 -232.679494)
		(width 0.1143)
		(layer "In13.Cu")
		(net "GMI_CPU0_G0_CPU1_G2_TX_DP<14>")
	)
	(arc
		(start 345.896184 -222.932244)
		(mid 345.708458 -222.626324)
		(end 345.863926 -222.302832)
		(width 0.1143)
		(layer "In13.Cu")
		(net "GMI_CPU0_G0_CPU1_G2_TX_DP<14>")
	)
	(arc
		(start 345.943174 -225.50882)
		(mid 346.186501 -225.044254)
		(end 345.943174 -224.579688)
		(width 0.1143)
		(layer "In13.Cu")
		(net "GMI_CPU0_G0_CPU1_G2_TX_DP<14>")
	)
	(arc
		(start 125.623574 -223.930464)
		(mid 125.779401 -224.234605)
		(end 125.62332 -224.53854)
		(width 0.1143)
		(layer "In13.Cu")
		(net "GMI_CPU0_G0_CPU1_G2_TX_DP<14>")
	)
	(arc
		(start 345.85275 -227.764594)
		(mid 345.703936 -227.474272)
		(end 345.85275 -227.18395)
		(width 0.1143)
		(layer "In13.Cu")
		(net "GMI_CPU0_G0_CPU1_G2_TX_DP<14>")
	)
	(arc
		(start 345.716606 -229.093776)
		(mid 345.757533 -228.92369)
		(end 345.871292 -228.790754)
		(width 0.1143)
		(layer "In13.Cu")
		(net "GMI_CPU0_G0_CPU1_G2_TX_DP<14>")
	)
	(arc
		(start 125.554232 -226.198938)
		(mid 125.309411 -226.66452)
		(end 125.554232 -227.130102)
		(width 0.1143)
		(layer "In13.Cu")
		(net "GMI_CPU0_G0_CPU1_G2_TX_DP<14>")
	)
	(arc
		(start 125.554232 -232.678732)
		(mid 125.309411 -233.144314)
		(end 125.554232 -233.609896)
		(width 0.1143)
		(layer "In13.Cu")
		(net "GMI_CPU0_G0_CPU1_G2_TX_DP<14>")
	)
	(arc
		(start 125.554232 -222.958914)
		(mid 125.309411 -223.424496)
		(end 125.554232 -223.890078)
		(width 0.1143)
		(layer "In13.Cu")
		(net "GMI_CPU0_G0_CPU1_G2_TX_DP<14>")
	)
	(arc
		(start 125.623574 -236.890306)
		(mid 125.779401 -237.194447)
		(end 125.62332 -237.498382)
		(width 0.1143)
		(layer "In13.Cu")
		(net "GMI_CPU0_G0_CPU1_G2_TX_DP<14>")
	)
	(arc
		(start 125.779276 -222.61449)
		(mid 125.738017 -222.785347)
		(end 125.62332 -222.918528)
		(width 0.1143)
		(layer "In13.Cu")
		(net "GMI_CPU0_G0_CPU1_G2_TX_DP<14>")
	)
	(arc
		(start 345.943174 -227.128832)
		(mid 346.186501 -226.664266)
		(end 345.943174 -226.1997)
		(width 0.1143)
		(layer "In13.Cu")
		(net "GMI_CPU0_G0_CPU1_G2_TX_DP<14>")
	)
	(arc
		(start 125.623574 -235.270294)
		(mid 125.779401 -235.574435)
		(end 125.62332 -235.87837)
		(width 0.1143)
		(layer "In13.Cu")
		(net "GMI_CPU0_G0_CPU1_G2_TX_DP<14>")
	)
	(arc
		(start 345.943174 -231.988614)
		(mid 346.186501 -231.524048)
		(end 345.943174 -231.059482)
		(width 0.1143)
		(layer "In13.Cu")
		(net "GMI_CPU0_G0_CPU1_G2_TX_DP<14>")
	)
	(arc
		(start 345.872308 -234.258358)
		(mid 345.720719 -233.954066)
		(end 345.872308 -233.649774)
		(width 0.1143)
		(layer "In13.Cu")
		(net "GMI_CPU0_G0_CPU1_G2_TX_DP<14>")
	)
	(arc
		(start 125.30963 -229.90429)
		(mid 125.374448 -230.167279)
		(end 125.554232 -230.369872)
		(width 0.1143)
		(layer "In13.Cu")
		(net "GMI_CPU0_G0_CPU1_G2_TX_DP<14>")
	)
	(arc
		(start 125.623574 -233.650282)
		(mid 125.779401 -233.954423)
		(end 125.62332 -234.258358)
		(width 0.1143)
		(layer "In13.Cu")
		(net "GMI_CPU0_G0_CPU1_G2_TX_DP<14>")
	)
	(arc
		(start 125.623574 -228.7905)
		(mid 125.73825 -228.923691)
		(end 125.77953 -229.094538)
		(width 0.1143)
		(layer "In13.Cu")
		(net "GMI_CPU0_G0_CPU1_G2_TX_DP<14>")
	)
	(arc
		(start 125.554232 -234.298744)
		(mid 125.309411 -234.764326)
		(end 125.554232 -235.229908)
		(width 0.1143)
		(layer "In13.Cu")
		(net "GMI_CPU0_G0_CPU1_G2_TX_DP<14>")
	)
	(arc
		(start 125.30963 -231.524302)
		(mid 125.374448 -231.787291)
		(end 125.554232 -231.989884)
		(width 0.1143)
		(layer "In13.Cu")
		(net "GMI_CPU0_G0_CPU1_G2_TX_DP<14>")
	)
	(arc
		(start 125.554232 -237.538768)
		(mid 125.309411 -238.00435)
		(end 125.554232 -238.469932)
		(width 0.1143)
		(layer "In13.Cu")
		(net "GMI_CPU0_G0_CPU1_G2_TX_DP<14>")
	)
	(arc
		(start 125.551946 -229.439978)
		(mid 125.373764 -229.642381)
		(end 125.30963 -229.90429)
		(width 0.1143)
		(layer "In13.Cu")
		(net "GMI_CPU0_G0_CPU1_G2_TX_DP<14>")
	)
	(arc
		(start 346.164662 -239.455452)
		(mid 346.105738 -239.309143)
		(end 345.995752 -239.196118)
		(width 0.1143)
		(layer "In13.Cu")
		(net "GMI_CPU0_G0_CPU1_G2_TX_DP<14>")
	)
	(segment
		(start 347.028008 -243.13007)
		(end 346.561156 -242.864132)
		(width 0.12954)
		(layer "F.Cu")
		(net "GMI_CPU0_G0_CPU1_G2_TX_DP<13>")
	)
	(segment
		(start 124.467874 -243.130324)
		(end 124.934726 -242.864386)
		(width 0.12954)
		(layer "F.Cu")
		(net "GMI_CPU0_G0_CPU1_G2_TX_DP<13>")
	)
	(segment
		(start 346.836746 -235.255816)
		(end 346.838016 -235.255054)
		(width 0.1143)
		(layer "In13.Cu")
		(net "GMI_CPU0_G0_CPU1_G2_TX_DP<13>")
	)
	(segment
		(start 124.68352 -234.258612)
		(end 124.673614 -234.2642)
		(width 0.1143)
		(layer "In13.Cu")
		(net "GMI_CPU0_G0_CPU1_G2_TX_DP<13>")
	)
	(segment
		(start 124.651262 -232.011474)
		(end 124.652024 -232.011982)
		(width 0.1143)
		(layer "In13.Cu")
		(net "GMI_CPU0_G0_CPU1_G2_TX_DP<13>")
	)
	(segment
		(start 346.812616 -233.649774)
		(end 346.882466 -233.609134)
		(width 0.1143)
		(layer "In13.Cu")
		(net "GMI_CPU0_G0_CPU1_G2_TX_DP<13>")
	)
	(segment
		(start 124.631196 -227.809044)
		(end 124.630434 -227.809552)
		(width 0.1143)
		(layer "In13.Cu")
		(net "GMI_CPU0_G0_CPU1_G2_TX_DP<13>")
	)
	(segment
		(start 346.812362 -241.750088)
		(end 346.883228 -241.70894)
		(width 0.1143)
		(layer "In13.Cu")
		(net "GMI_CPU0_G0_CPU1_G2_TX_DP<13>")
	)
	(segment
		(start 346.812362 -223.929956)
		(end 346.838016 -223.915224)
		(width 0.1143)
		(layer "In13.Cu")
		(net "GMI_CPU0_G0_CPU1_G2_TX_DP<13>")
	)
	(segment
		(start 346.839794 -223.914208)
		(end 346.840556 -223.9137)
		(width 0.1143)
		(layer "In13.Cu")
		(net "GMI_CPU0_G0_CPU1_G2_TX_DP<13>")
	)
	(segment
		(start 347.171772 -221.227142)
		(end 347.171772 -221.198694)
		(width 0.1143)
		(layer "In13.Cu")
		(net "GMI_CPU0_G0_CPU1_G2_TX_DP<13>")
	)
	(segment
		(start 346.882466 -236.849158)
		(end 346.903294 -236.834426)
		(width 0.1143)
		(layer "In13.Cu")
		(net "GMI_CPU0_G0_CPU1_G2_TX_DP<13>")
	)
	(segment
		(start 346.844112 -226.17684)
		(end 346.812362 -226.158552)
		(width 0.1143)
		(layer "In13.Cu")
		(net "GMI_CPU0_G0_CPU1_G2_TX_DP<13>")
	)
	(segment
		(start 124.653548 -223.912938)
		(end 124.65431 -223.913446)
		(width 0.1143)
		(layer "In13.Cu")
		(net "GMI_CPU0_G0_CPU1_G2_TX_DP<13>")
	)
	(segment
		(start 125.232668 -242.864386)
		(end 124.934726 -242.864386)
		(width 0.1143)
		(layer "In13.Cu")
		(net "GMI_CPU0_G0_CPU1_G2_TX_DP<13>")
	)
	(segment
		(start 148.580602 -200.5711)
		(end 146.36623 -201.242168)
		(width 0.14224)
		(layer "In13.Cu")
		(net "GMI_CPU0_G0_CPU1_G2_TX_DP<13>")
	)
	(segment
		(start 124.613416 -236.849412)
		(end 124.683266 -236.890052)
		(width 0.1143)
		(layer "In13.Cu")
		(net "GMI_CPU0_G0_CPU1_G2_TX_DP<13>")
	)
	(segment
		(start 346.81922 -230.406194)
		(end 346.822014 -230.40467)
		(width 0.1143)
		(layer "In13.Cu")
		(net "GMI_CPU0_G0_CPU1_G2_TX_DP<13>")
	)
	(segment
		(start 124.65177 -235.251752)
		(end 124.652532 -235.25226)
		(width 0.1143)
		(layer "In13.Cu")
		(net "GMI_CPU0_G0_CPU1_G2_TX_DP<13>")
	)
	(segment
		(start 346.812362 -238.50981)
		(end 346.812616 -238.50981)
		(width 0.1143)
		(layer "In13.Cu")
		(net "GMI_CPU0_G0_CPU1_G2_TX_DP<13>")
	)
	(segment
		(start 347.126052 -221.272862)
		(end 347.171772 -221.227142)
		(width 0.1143)
		(layer "In13.Cu")
		(net "GMI_CPU0_G0_CPU1_G2_TX_DP<13>")
	)
	(segment
		(start 346.841572 -235.253022)
		(end 346.842334 -235.252514)
		(width 0.1143)
		(layer "In13.Cu")
		(net "GMI_CPU0_G0_CPU1_G2_TX_DP<13>")
	)
	(segment
		(start 309.09768 -189.169548)
		(end 303.734724 -189.169548)
		(width 0.14224)
		(layer "In13.Cu")
		(net "GMI_CPU0_G0_CPU1_G2_TX_DP<13>")
	)
	(segment
		(start 124.592588 -236.83468)
		(end 124.613416 -236.849412)
		(width 0.1143)
		(layer "In13.Cu")
		(net "GMI_CPU0_G0_CPU1_G2_TX_DP<13>")
	)
	(segment
		(start 124.68352 -222.918782)
		(end 124.673614 -222.92437)
		(width 0.1143)
		(layer "In13.Cu")
		(net "GMI_CPU0_G0_CPU1_G2_TX_DP<13>")
	)
	(segment
		(start 124.673868 -230.404924)
		(end 124.676662 -230.406448)
		(width 0.1143)
		(layer "In13.Cu")
		(net "GMI_CPU0_G0_CPU1_G2_TX_DP<13>")
	)
	(segment
		(start 207.361536 -189.068202)
		(end 162.17773 -189.259718)
		(width 0.14224)
		(layer "In13.Cu")
		(net "GMI_CPU0_G0_CPU1_G2_TX_DP<13>")
	)
	(segment
		(start 124.685298 -231.017318)
		(end 124.65177 -231.036876)
		(width 0.1143)
		(layer "In13.Cu")
		(net "GMI_CPU0_G0_CPU1_G2_TX_DP<13>")
	)
	(segment
		(start 124.615448 -240.090706)
		(end 124.65177 -240.111788)
		(width 0.1143)
		(layer "In13.Cu")
		(net "GMI_CPU0_G0_CPU1_G2_TX_DP<13>")
	)
	(segment
		(start 346.883482 -230.368856)
		(end 346.893896 -230.361236)
		(width 0.1143)
		(layer "In13.Cu")
		(net "GMI_CPU0_G0_CPU1_G2_TX_DP<13>")
	)
	(segment
		(start 346.812362 -232.029762)
		(end 346.843858 -232.011728)
		(width 0.1143)
		(layer "In13.Cu")
		(net "GMI_CPU0_G0_CPU1_G2_TX_DP<13>")
	)
	(segment
		(start 346.844112 -239.136682)
		(end 346.812362 -239.118394)
		(width 0.1143)
		(layer "In13.Cu")
		(net "GMI_CPU0_G0_CPU1_G2_TX_DP<13>")
	)
	(segment
		(start 125.6538 -218.224862)
		(end 124.323602 -220.541342)
		(width 0.14224)
		(layer "In13.Cu")
		(net "GMI_CPU0_G0_CPU1_G2_TX_DP<13>")
	)
	(segment
		(start 160.633156 -190.526924)
		(end 160.47847 -190.815722)
		(width 0.14224)
		(layer "In13.Cu")
		(net "GMI_CPU0_G0_CPU1_G2_TX_DP<13>")
	)
	(segment
		(start 346.882466 -235.91901)
		(end 346.812362 -235.87837)
		(width 0.1143)
		(layer "In13.Cu")
		(net "GMI_CPU0_G0_CPU1_G2_TX_DP<13>")
	)
	(segment
		(start 124.65431 -223.913446)
		(end 124.655326 -223.913954)
		(width 0.1143)
		(layer "In13.Cu")
		(net "GMI_CPU0_G0_CPU1_G2_TX_DP<13>")
	)
	(segment
		(start 124.592588 -233.594656)
		(end 124.613416 -233.609388)
		(width 0.1143)
		(layer "In13.Cu")
		(net "GMI_CPU0_G0_CPU1_G2_TX_DP<13>")
	)
	(segment
		(start 345.964256 -218.349576)
		(end 318.311276 -195.67652)
		(width 0.14224)
		(layer "In13.Cu")
		(net "GMI_CPU0_G0_CPU1_G2_TX_DP<13>")
	)
	(segment
		(start 346.841572 -223.913192)
		(end 346.842334 -223.912684)
		(width 0.1143)
		(layer "In13.Cu")
		(net "GMI_CPU0_G0_CPU1_G2_TX_DP<13>")
	)
	(segment
		(start 346.812362 -236.889798)
		(end 346.812616 -236.889798)
		(width 0.1143)
		(layer "In13.Cu")
		(net "GMI_CPU0_G0_CPU1_G2_TX_DP<13>")
	)
	(segment
		(start 124.659136 -235.25607)
		(end 124.68352 -235.27004)
		(width 0.1143)
		(layer "In13.Cu")
		(net "GMI_CPU0_G0_CPU1_G2_TX_DP<13>")
	)
	(segment
		(start 124.612654 -240.779554)
		(end 124.584968 -240.79962)
		(width 0.1143)
		(layer "In13.Cu")
		(net "GMI_CPU0_G0_CPU1_G2_TX_DP<13>")
	)
	(segment
		(start 346.840556 -223.9137)
		(end 346.841572 -223.913192)
		(width 0.1143)
		(layer "In13.Cu")
		(net "GMI_CPU0_G0_CPU1_G2_TX_DP<13>")
	)
	(segment
		(start 236.278928 -199.451214)
		(end 234.011978 -199.051418)
		(width 0.14224)
		(layer "In13.Cu")
		(net "GMI_CPU0_G0_CPU1_G2_TX_DP<13>")
	)
	(segment
		(start 346.812362 -240.129822)
		(end 346.844112 -240.111534)
		(width 0.1143)
		(layer "In13.Cu")
		(net "GMI_CPU0_G0_CPU1_G2_TX_DP<13>")
	)
	(segment
		(start 346.882466 -233.609134)
		(end 346.903294 -233.594402)
		(width 0.1143)
		(layer "In13.Cu")
		(net "GMI_CPU0_G0_CPU1_G2_TX_DP<13>")
	)
	(segment
		(start 124.673614 -222.92437)
		(end 124.672852 -222.924878)
		(width 0.1143)
		(layer "In13.Cu")
		(net "GMI_CPU0_G0_CPU1_G2_TX_DP<13>")
	)
	(segment
		(start 124.65177 -227.797106)
		(end 124.631196 -227.809044)
		(width 0.1143)
		(layer "In13.Cu")
		(net "GMI_CPU0_G0_CPU1_G2_TX_DP<13>")
	)
	(segment
		(start 346.82303 -222.924624)
		(end 346.822268 -222.924116)
		(width 0.1143)
		(layer "In13.Cu")
		(net "GMI_CPU0_G0_CPU1_G2_TX_DP<13>")
	)
	(segment
		(start 124.676662 -230.406448)
		(end 124.680218 -230.40848)
		(width 0.1143)
		(layer "In13.Cu")
		(net "GMI_CPU0_G0_CPU1_G2_TX_DP<13>")
	)
	(segment
		(start 124.68352 -235.878624)
		(end 124.613416 -235.919264)
		(width 0.1143)
		(layer "In13.Cu")
		(net "GMI_CPU0_G0_CPU1_G2_TX_DP<13>")
	)
	(segment
		(start 346.822268 -234.263946)
		(end 346.812362 -234.258358)
		(width 0.1143)
		(layer "In13.Cu")
		(net "GMI_CPU0_G0_CPU1_G2_TX_DP<13>")
	)
	(segment
		(start 346.827856 -230.40086)
		(end 346.883482 -230.368856)
		(width 0.1143)
		(layer "In13.Cu")
		(net "GMI_CPU0_G0_CPU1_G2_TX_DP<13>")
	)
	(segment
		(start 125.302518 -242.794536)
		(end 125.232668 -242.864386)
		(width 0.1143)
		(layer "In13.Cu")
		(net "GMI_CPU0_G0_CPU1_G2_TX_DP<13>")
	)
	(segment
		(start 124.670058 -230.402638)
		(end 124.671582 -230.4034)
		(width 0.1143)
		(layer "In13.Cu")
		(net "GMI_CPU0_G0_CPU1_G2_TX_DP<13>")
	)
	(segment
		(start 346.844112 -231.036622)
		(end 346.810584 -231.017064)
		(width 0.1143)
		(layer "In13.Cu")
		(net "GMI_CPU0_G0_CPU1_G2_TX_DP<13>")
	)
	(segment
		(start 239.47628 -198.887334)
		(end 239.476026 -198.887334)
		(width 0.14224)
		(layer "In13.Cu")
		(net "GMI_CPU0_G0_CPU1_G2_TX_DP<13>")
	)
	(segment
		(start 346.883736 -238.468408)
		(end 346.910152 -238.449612)
		(width 0.1143)
		(layer "In13.Cu")
		(net "GMI_CPU0_G0_CPU1_G2_TX_DP<13>")
	)
	(segment
		(start 124.680218 -230.40848)
		(end 124.68352 -230.410258)
		(width 0.1143)
		(layer "In13.Cu")
		(net "GMI_CPU0_G0_CPU1_G2_TX_DP<13>")
	)
	(segment
		(start 347.122496 -229.945184)
		(end 347.126306 -229.904036)
		(width 0.1143)
		(layer "In13.Cu")
		(net "GMI_CPU0_G0_CPU1_G2_TX_DP<13>")
	)
	(segment
		(start 124.612146 -237.540038)
		(end 124.58573 -237.559088)
		(width 0.1143)
		(layer "In13.Cu")
		(net "GMI_CPU0_G0_CPU1_G2_TX_DP<13>")
	)
	(segment
		(start 124.613416 -232.67924)
		(end 124.592588 -232.693972)
		(width 0.1143)
		(layer "In13.Cu")
		(net "GMI_CPU0_G0_CPU1_G2_TX_DP<13>")
	)
	(segment
		(start 124.645928 -232.008426)
		(end 124.651262 -232.011474)
		(width 0.1143)
		(layer "In13.Cu")
		(net "GMI_CPU0_G0_CPU1_G2_TX_DP<13>")
	)
	(segment
		(start 346.903294 -235.933742)
		(end 346.882466 -235.91901)
		(width 0.1143)
		(layer "In13.Cu")
		(net "GMI_CPU0_G0_CPU1_G2_TX_DP<13>")
	)
	(segment
		(start 125.082808 -242.518946)
		(end 125.121924 -242.541806)
		(width 0.1143)
		(layer "In13.Cu")
		(net "GMI_CPU0_G0_CPU1_G2_TX_DP<13>")
	)
	(segment
		(start 262.665464 -188.790326)
		(end 250.94438 -190.857124)
		(width 0.14224)
		(layer "In13.Cu")
		(net "GMI_CPU0_G0_CPU1_G2_TX_DP<13>")
	)
	(segment
		(start 124.672852 -234.264708)
		(end 124.65177 -234.2769)
		(width 0.1143)
		(layer "In13.Cu")
		(net "GMI_CPU0_G0_CPU1_G2_TX_DP<13>")
	)
	(segment
		(start 346.812362 -233.649774)
		(end 346.812616 -233.649774)
		(width 0.1143)
		(layer "In13.Cu")
		(net "GMI_CPU0_G0_CPU1_G2_TX_DP<13>")
	)
	(segment
		(start 347.17228 -221.198186)
		(end 347.17228 -220.382592)
		(width 0.14224)
		(layer "In13.Cu")
		(net "GMI_CPU0_G0_CPU1_G2_TX_DP<13>")
	)
	(segment
		(start 346.82303 -234.264454)
		(end 346.822268 -234.263946)
		(width 0.1143)
		(layer "In13.Cu")
		(net "GMI_CPU0_G0_CPU1_G2_TX_DP<13>")
	)
	(segment
		(start 124.652532 -235.25226)
		(end 124.653548 -235.252768)
		(width 0.1143)
		(layer "In13.Cu")
		(net "GMI_CPU0_G0_CPU1_G2_TX_DP<13>")
	)
	(segment
		(start 124.673614 -234.2642)
		(end 124.672852 -234.264708)
		(width 0.1143)
		(layer "In13.Cu")
		(net "GMI_CPU0_G0_CPU1_G2_TX_DP<13>")
	)
	(segment
		(start 346.838016 -235.255054)
		(end 346.838778 -235.254546)
		(width 0.1143)
		(layer "In13.Cu")
		(net "GMI_CPU0_G0_CPU1_G2_TX_DP<13>")
	)
	(segment
		(start 346.883736 -225.508566)
		(end 346.910152 -225.48977)
		(width 0.1143)
		(layer "In13.Cu")
		(net "GMI_CPU0_G0_CPU1_G2_TX_DP<13>")
	)
	(segment
		(start 318.311276 -195.663312)
		(end 309.09768 -189.169548)
		(width 0.14224)
		(layer "In13.Cu")
		(net "GMI_CPU0_G0_CPU1_G2_TX_DP<13>")
	)
	(segment
		(start 149.731984 -199.627236)
		(end 148.580602 -200.5711)
		(width 0.14224)
		(layer "In13.Cu")
		(net "GMI_CPU0_G0_CPU1_G2_TX_DP<13>")
	)
	(segment
		(start 124.65177 -239.136936)
		(end 124.615448 -239.158018)
		(width 0.1143)
		(layer "In13.Cu")
		(net "GMI_CPU0_G0_CPU1_G2_TX_DP<13>")
	)
	(segment
		(start 124.657866 -235.255308)
		(end 124.659136 -235.25607)
		(width 0.1143)
		(layer "In13.Cu")
		(net "GMI_CPU0_G0_CPU1_G2_TX_DP<13>")
	)
	(segment
		(start 124.612146 -224.580196)
		(end 124.58573 -224.599246)
		(width 0.1143)
		(layer "In13.Cu")
		(net "GMI_CPU0_G0_CPU1_G2_TX_DP<13>")
	)
	(segment
		(start 346.844112 -235.251498)
		(end 346.844366 -235.251498)
		(width 0.1143)
		(layer "In13.Cu")
		(net "GMI_CPU0_G0_CPU1_G2_TX_DP<13>")
	)
	(segment
		(start 125.121924 -242.541806)
		(end 125.152404 -242.559586)
		(width 0.1143)
		(layer "In13.Cu")
		(net "GMI_CPU0_G0_CPU1_G2_TX_DP<13>")
	)
	(segment
		(start 124.68352 -226.158806)
		(end 124.65177 -226.177094)
		(width 0.1143)
		(layer "In13.Cu")
		(net "GMI_CPU0_G0_CPU1_G2_TX_DP<13>")
	)
	(segment
		(start 124.604272 -230.364284)
		(end 124.667264 -230.400606)
		(width 0.1143)
		(layer "In13.Cu")
		(net "GMI_CPU0_G0_CPU1_G2_TX_DP<13>")
	)
	(segment
		(start 150.882858 -198.683118)
		(end 150.882858 -198.683372)
		(width 0.14224)
		(layer "In13.Cu")
		(net "GMI_CPU0_G0_CPU1_G2_TX_DP<13>")
	)
	(segment
		(start 124.612146 -238.468662)
		(end 124.683266 -238.510064)
		(width 0.1143)
		(layer "In13.Cu")
		(net "GMI_CPU0_G0_CPU1_G2_TX_DP<13>")
	)
	(segment
		(start 124.32411 -221.227396)
		(end 124.36983 -221.273116)
		(width 0.1143)
		(layer "In13.Cu")
		(net "GMI_CPU0_G0_CPU1_G2_TX_DP<13>")
	)
	(segment
		(start 124.660406 -223.916748)
		(end 124.68352 -223.93021)
		(width 0.1143)
		(layer "In13.Cu")
		(net "GMI_CPU0_G0_CPU1_G2_TX_DP<13>")
	)
	(segment
		(start 346.844366 -234.2769)
		(end 346.844112 -234.276646)
		(width 0.1143)
		(layer "In13.Cu")
		(net "GMI_CPU0_G0_CPU1_G2_TX_DP<13>")
	)
	(segment
		(start 124.58573 -225.490024)
		(end 124.612146 -225.50882)
		(width 0.1143)
		(layer "In13.Cu")
		(net "GMI_CPU0_G0_CPU1_G2_TX_DP<13>")
	)
	(segment
		(start 346.263214 -242.864132)
		(end 346.193364 -242.794282)
		(width 0.1143)
		(layer "In13.Cu")
		(net "GMI_CPU0_G0_CPU1_G2_TX_DP<13>")
	)
	(segment
		(start 149.73173 -199.627236)
		(end 149.731984 -199.627236)
		(width 0.14224)
		(layer "In13.Cu")
		(net "GMI_CPU0_G0_CPU1_G2_TX_DP<13>")
	)
	(segment
		(start 124.613416 -235.919264)
		(end 124.592588 -235.933996)
		(width 0.1143)
		(layer "In13.Cu")
		(net "GMI_CPU0_G0_CPU1_G2_TX_DP<13>")
	)
	(segment
		(start 346.839794 -235.254038)
		(end 346.840556 -235.25353)
		(width 0.1143)
		(layer "In13.Cu")
		(net "GMI_CPU0_G0_CPU1_G2_TX_DP<13>")
	)
	(segment
		(start 124.612146 -225.50882)
		(end 124.683266 -225.550222)
		(width 0.1143)
		(layer "In13.Cu")
		(net "GMI_CPU0_G0_CPU1_G2_TX_DP<13>")
	)
	(segment
		(start 346.843858 -232.011728)
		(end 346.84462 -232.01122)
		(width 0.1143)
		(layer "In13.Cu")
		(net "GMI_CPU0_G0_CPU1_G2_TX_DP<13>")
	)
	(segment
		(start 124.65431 -235.253276)
		(end 124.655326 -235.253784)
		(width 0.1143)
		(layer "In13.Cu")
		(net "GMI_CPU0_G0_CPU1_G2_TX_DP<13>")
	)
	(segment
		(start 346.910152 -237.558834)
		(end 346.883736 -237.539784)
		(width 0.1143)
		(layer "In13.Cu")
		(net "GMI_CPU0_G0_CPU1_G2_TX_DP<13>")
	)
	(segment
		(start 346.812362 -235.269786)
		(end 346.836746 -235.255816)
		(width 0.1143)
		(layer "In13.Cu")
		(net "GMI_CPU0_G0_CPU1_G2_TX_DP<13>")
	)
	(segment
		(start 346.842334 -223.912684)
		(end 346.84335 -223.912176)
		(width 0.1143)
		(layer "In13.Cu")
		(net "GMI_CPU0_G0_CPU1_G2_TX_DP<13>")
	)
	(segment
		(start 124.68352 -224.538794)
		(end 124.612146 -224.580196)
		(width 0.1143)
		(layer "In13.Cu")
		(net "GMI_CPU0_G0_CPU1_G2_TX_DP<13>")
	)
	(segment
		(start 346.838778 -235.254546)
		(end 346.839794 -235.254038)
		(width 0.1143)
		(layer "In13.Cu")
		(net "GMI_CPU0_G0_CPU1_G2_TX_DP<13>")
	)
	(segment
		(start 346.883736 -224.579942)
		(end 346.812362 -224.53854)
		(width 0.1143)
		(layer "In13.Cu")
		(net "GMI_CPU0_G0_CPU1_G2_TX_DP<13>")
	)
	(segment
		(start 346.865448 -227.809298)
		(end 346.864686 -227.80879)
		(width 0.1143)
		(layer "In13.Cu")
		(net "GMI_CPU0_G0_CPU1_G2_TX_DP<13>")
	)
	(segment
		(start 346.561156 -242.864132)
		(end 346.263214 -242.864132)
		(width 0.1143)
		(layer "In13.Cu")
		(net "GMI_CPU0_G0_CPU1_G2_TX_DP<13>")
	)
	(segment
		(start 346.84335 -223.912176)
		(end 346.844112 -223.911668)
		(width 0.1143)
		(layer "In13.Cu")
		(net "GMI_CPU0_G0_CPU1_G2_TX_DP<13>")
	)
	(segment
		(start 346.813378 -222.309436)
		(end 346.882974 -222.268796)
		(width 0.1143)
		(layer "In13.Cu")
		(net "GMI_CPU0_G0_CPU1_G2_TX_DP<13>")
	)
	(segment
		(start 124.671582 -230.4034)
		(end 124.673868 -230.404924)
		(width 0.1143)
		(layer "In13.Cu")
		(net "GMI_CPU0_G0_CPU1_G2_TX_DP<13>")
	)
	(segment
		(start 346.84462 -232.01122)
		(end 346.849954 -232.008172)
		(width 0.1143)
		(layer "In13.Cu")
		(net "GMI_CPU0_G0_CPU1_G2_TX_DP<13>")
	)
	(segment
		(start 346.825824 -230.402384)
		(end 346.827094 -230.401622)
		(width 0.1143)
		(layer "In13.Cu")
		(net "GMI_CPU0_G0_CPU1_G2_TX_DP<13>")
	)
	(segment
		(start 346.844366 -222.93707)
		(end 346.844112 -222.936816)
		(width 0.1143)
		(layer "In13.Cu")
		(net "GMI_CPU0_G0_CPU1_G2_TX_DP<13>")
	)
	(segment
		(start 250.94438 -190.857124)
		(end 239.47628 -198.887334)
		(width 0.14224)
		(layer "In13.Cu")
		(net "GMI_CPU0_G0_CPU1_G2_TX_DP<13>")
	)
	(segment
		(start 124.657104 -223.91497)
		(end 124.657866 -223.915478)
		(width 0.1143)
		(layer "In13.Cu")
		(net "GMI_CPU0_G0_CPU1_G2_TX_DP<13>")
	)
	(segment
		(start 346.84335 -235.252006)
		(end 346.844112 -235.251498)
		(width 0.1143)
		(layer "In13.Cu")
		(net "GMI_CPU0_G0_CPU1_G2_TX_DP<13>")
	)
	(segment
		(start 124.32411 -221.198948)
		(end 124.32411 -221.227396)
		(width 0.1143)
		(layer "In13.Cu")
		(net "GMI_CPU0_G0_CPU1_G2_TX_DP<13>")
	)
	(segment
		(start 124.58573 -238.449866)
		(end 124.612146 -238.468662)
		(width 0.1143)
		(layer "In13.Cu")
		(net "GMI_CPU0_G0_CPU1_G2_TX_DP<13>")
	)
	(segment
		(start 124.653548 -235.252768)
		(end 124.65431 -235.253276)
		(width 0.1143)
		(layer "In13.Cu")
		(net "GMI_CPU0_G0_CPU1_G2_TX_DP<13>")
	)
	(segment
		(start 124.672852 -222.924878)
		(end 124.65177 -222.93707)
		(width 0.1143)
		(layer "In13.Cu")
		(net "GMI_CPU0_G0_CPU1_G2_TX_DP<13>")
	)
	(segment
		(start 346.883736 -237.539784)
		(end 346.812362 -237.498382)
		(width 0.1143)
		(layer "In13.Cu")
		(net "GMI_CPU0_G0_CPU1_G2_TX_DP<13>")
	)
	(segment
		(start 124.66701 -230.400606)
		(end 124.668026 -230.401114)
		(width 0.1143)
		(layer "In13.Cu")
		(net "GMI_CPU0_G0_CPU1_G2_TX_DP<13>")
	)
	(segment
		(start 124.656088 -223.914462)
		(end 124.657104 -223.91497)
		(width 0.1143)
		(layer "In13.Cu")
		(net "GMI_CPU0_G0_CPU1_G2_TX_DP<13>")
	)
	(segment
		(start 346.910914 -240.799366)
		(end 346.883228 -240.7793)
		(width 0.1143)
		(layer "In13.Cu")
		(net "GMI_CPU0_G0_CPU1_G2_TX_DP<13>")
	)
	(segment
		(start 124.68352 -239.118648)
		(end 124.65177 -239.136936)
		(width 0.1143)
		(layer "In13.Cu")
		(net "GMI_CPU0_G0_CPU1_G2_TX_DP<13>")
	)
	(segment
		(start 346.812616 -236.889798)
		(end 346.882466 -236.849158)
		(width 0.1143)
		(layer "In13.Cu")
		(net "GMI_CPU0_G0_CPU1_G2_TX_DP<13>")
	)
	(segment
		(start 146.36623 -201.242168)
		(end 125.6538 -218.224862)
		(width 0.14224)
		(layer "In13.Cu")
		(net "GMI_CPU0_G0_CPU1_G2_TX_DP<13>")
	)
	(segment
		(start 124.323602 -221.19844)
		(end 124.32411 -221.198948)
		(width 0.14224)
		(layer "In13.Cu")
		(net "GMI_CPU0_G0_CPU1_G2_TX_DP<13>")
	)
	(segment
		(start 160.47847 -190.815722)
		(end 150.882858 -198.683118)
		(width 0.14224)
		(layer "In13.Cu")
		(net "GMI_CPU0_G0_CPU1_G2_TX_DP<13>")
	)
	(segment
		(start 318.311276 -195.67652)
		(end 318.311276 -195.663312)
		(width 0.14224)
		(layer "In13.Cu")
		(net "GMI_CPU0_G0_CPU1_G2_TX_DP<13>")
	)
	(segment
		(start 124.651516 -223.911922)
		(end 124.65177 -223.911922)
		(width 0.1143)
		(layer "In13.Cu")
		(net "GMI_CPU0_G0_CPU1_G2_TX_DP<13>")
	)
	(segment
		(start 124.667264 -230.400606)
		(end 124.66701 -230.400606)
		(width 0.1143)
		(layer "In13.Cu")
		(net "GMI_CPU0_G0_CPU1_G2_TX_DP<13>")
	)
	(segment
		(start 150.882858 -198.683372)
		(end 149.73173 -199.627236)
		(width 0.14224)
		(layer "In13.Cu")
		(net "GMI_CPU0_G0_CPU1_G2_TX_DP<13>")
	)
	(segment
		(start 346.8243 -230.403146)
		(end 346.825824 -230.402384)
		(width 0.1143)
		(layer "In13.Cu")
		(net "GMI_CPU0_G0_CPU1_G2_TX_DP<13>")
	)
	(segment
		(start 346.840556 -235.25353)
		(end 346.841572 -235.253022)
		(width 0.1143)
		(layer "In13.Cu")
		(net "GMI_CPU0_G0_CPU1_G2_TX_DP<13>")
	)
	(segment
		(start 124.65177 -222.93707)
		(end 124.651516 -222.937324)
		(width 0.1143)
		(layer "In13.Cu")
		(net "GMI_CPU0_G0_CPU1_G2_TX_DP<13>")
	)
	(segment
		(start 124.630434 -228.759512)
		(end 124.68352 -228.790246)
		(width 0.1143)
		(layer "In13.Cu")
		(net "GMI_CPU0_G0_CPU1_G2_TX_DP<13>")
	)
	(segment
		(start 124.323602 -220.541342)
		(end 124.323602 -221.19844)
		(width 0.14224)
		(layer "In13.Cu")
		(net "GMI_CPU0_G0_CPU1_G2_TX_DP<13>")
	)
	(segment
		(start 124.613416 -233.609388)
		(end 124.683266 -233.650028)
		(width 0.1143)
		(layer "In13.Cu")
		(net "GMI_CPU0_G0_CPU1_G2_TX_DP<13>")
	)
	(segment
		(start 124.685298 -229.397306)
		(end 124.682504 -229.399338)
		(width 0.1143)
		(layer "In13.Cu")
		(net "GMI_CPU0_G0_CPU1_G2_TX_DP<13>")
	)
	(segment
		(start 346.844112 -227.151692)
		(end 346.880434 -227.13061)
		(width 0.1143)
		(layer "In13.Cu")
		(net "GMI_CPU0_G0_CPU1_G2_TX_DP<13>")
	)
	(segment
		(start 346.880434 -226.197922)
		(end 346.844112 -226.17684)
		(width 0.1143)
		(layer "In13.Cu")
		(net "GMI_CPU0_G0_CPU1_G2_TX_DP<13>")
	)
	(segment
		(start 347.126052 -221.80423)
		(end 347.126052 -221.272862)
		(width 0.1143)
		(layer "In13.Cu")
		(net "GMI_CPU0_G0_CPU1_G2_TX_DP<13>")
	)
	(segment
		(start 346.844112 -223.911668)
		(end 346.844366 -223.911668)
		(width 0.1143)
		(layer "In13.Cu")
		(net "GMI_CPU0_G0_CPU1_G2_TX_DP<13>")
	)
	(segment
		(start 124.682504 -229.399338)
		(end 124.610622 -229.441248)
		(width 0.1143)
		(layer "In13.Cu")
		(net "GMI_CPU0_G0_CPU1_G2_TX_DP<13>")
	)
	(segment
		(start 346.822268 -222.924116)
		(end 346.812362 -222.918528)
		(width 0.1143)
		(layer "In13.Cu")
		(net "GMI_CPU0_G0_CPU1_G2_TX_DP<13>")
	)
	(segment
		(start 124.655326 -235.253784)
		(end 124.656088 -235.254292)
		(width 0.1143)
		(layer "In13.Cu")
		(net "GMI_CPU0_G0_CPU1_G2_TX_DP<13>")
	)
	(segment
		(start 124.652024 -232.011982)
		(end 124.68352 -232.030016)
		(width 0.1143)
		(layer "In13.Cu")
		(net "GMI_CPU0_G0_CPU1_G2_TX_DP<13>")
	)
	(segment
		(start 124.542042 -230.306118)
		(end 124.604272 -230.364284)
		(width 0.1143)
		(layer "In13.Cu")
		(net "GMI_CPU0_G0_CPU1_G2_TX_DP<13>")
	)
	(segment
		(start 124.668788 -230.401876)
		(end 124.670058 -230.402638)
		(width 0.1143)
		(layer "In13.Cu")
		(net "GMI_CPU0_G0_CPU1_G2_TX_DP<13>")
	)
	(segment
		(start 124.65177 -227.151946)
		(end 124.68352 -227.170234)
		(width 0.1143)
		(layer "In13.Cu")
		(net "GMI_CPU0_G0_CPU1_G2_TX_DP<13>")
	)
	(segment
		(start 162.17773 -189.259718)
		(end 160.633156 -190.526924)
		(width 0.14224)
		(layer "In13.Cu")
		(net "GMI_CPU0_G0_CPU1_G2_TX_DP<13>")
	)
	(segment
		(start 124.683266 -225.550222)
		(end 124.68352 -225.550222)
		(width 0.1143)
		(layer "In13.Cu")
		(net "GMI_CPU0_G0_CPU1_G2_TX_DP<13>")
	)
	(segment
		(start 346.842334 -235.252514)
		(end 346.84335 -235.252006)
		(width 0.1143)
		(layer "In13.Cu")
		(net "GMI_CPU0_G0_CPU1_G2_TX_DP<13>")
	)
	(segment
		(start 347.171772 -221.198694)
		(end 347.17228 -221.198186)
		(width 0.14224)
		(layer "In13.Cu")
		(net "GMI_CPU0_G0_CPU1_G2_TX_DP<13>")
	)
	(segment
		(start 346.844112 -227.796852)
		(end 346.812362 -227.778564)
		(width 0.1143)
		(layer "In13.Cu")
		(net "GMI_CPU0_G0_CPU1_G2_TX_DP<13>")
	)
	(segment
		(start 124.655326 -223.913954)
		(end 124.656088 -223.914462)
		(width 0.1143)
		(layer "In13.Cu")
		(net "GMI_CPU0_G0_CPU1_G2_TX_DP<13>")
	)
	(segment
		(start 346.812616 -238.50981)
		(end 346.883736 -238.468408)
		(width 0.1143)
		(layer "In13.Cu")
		(net "GMI_CPU0_G0_CPU1_G2_TX_DP<13>")
	)
	(segment
		(start 124.668026 -230.401114)
		(end 124.668026 -230.401368)
		(width 0.1143)
		(layer "In13.Cu")
		(net "GMI_CPU0_G0_CPU1_G2_TX_DP<13>")
	)
	(segment
		(start 124.612654 -241.709194)
		(end 124.68352 -241.750342)
		(width 0.1143)
		(layer "In13.Cu")
		(net "GMI_CPU0_G0_CPU1_G2_TX_DP<13>")
	)
	(segment
		(start 124.68352 -240.73866)
		(end 124.612654 -240.779554)
		(width 0.1143)
		(layer "In13.Cu")
		(net "GMI_CPU0_G0_CPU1_G2_TX_DP<13>")
	)
	(segment
		(start 124.668026 -230.401368)
		(end 124.668788 -230.401876)
		(width 0.1143)
		(layer "In13.Cu")
		(net "GMI_CPU0_G0_CPU1_G2_TX_DP<13>")
	)
	(segment
		(start 346.812616 -225.549968)
		(end 346.883736 -225.508566)
		(width 0.1143)
		(layer "In13.Cu")
		(net "GMI_CPU0_G0_CPU1_G2_TX_DP<13>")
	)
	(segment
		(start 124.683266 -236.890052)
		(end 124.68352 -236.890052)
		(width 0.1143)
		(layer "In13.Cu")
		(net "GMI_CPU0_G0_CPU1_G2_TX_DP<13>")
	)
	(segment
		(start 124.65177 -234.2769)
		(end 124.651516 -234.277154)
		(width 0.1143)
		(layer "In13.Cu")
		(net "GMI_CPU0_G0_CPU1_G2_TX_DP<13>")
	)
	(segment
		(start 124.65177 -223.911922)
		(end 124.652532 -223.91243)
		(width 0.1143)
		(layer "In13.Cu")
		(net "GMI_CPU0_G0_CPU1_G2_TX_DP<13>")
	)
	(segment
		(start 346.880434 -239.157764)
		(end 346.844112 -239.136682)
		(width 0.1143)
		(layer "In13.Cu")
		(net "GMI_CPU0_G0_CPU1_G2_TX_DP<13>")
	)
	(segment
		(start 124.36983 -221.273116)
		(end 124.36983 -221.804484)
		(width 0.1143)
		(layer "In13.Cu")
		(net "GMI_CPU0_G0_CPU1_G2_TX_DP<13>")
	)
	(segment
		(start 124.65177 -231.036876)
		(end 124.645928 -231.040178)
		(width 0.1143)
		(layer "In13.Cu")
		(net "GMI_CPU0_G0_CPU1_G2_TX_DP<13>")
	)
	(segment
		(start 124.68352 -232.6386)
		(end 124.613416 -232.67924)
		(width 0.1143)
		(layer "In13.Cu")
		(net "GMI_CPU0_G0_CPU1_G2_TX_DP<13>")
	)
	(segment
		(start 346.343478 -242.559332)
		(end 346.413074 -242.518692)
		(width 0.1143)
		(layer "In13.Cu")
		(net "GMI_CPU0_G0_CPU1_G2_TX_DP<13>")
	)
	(segment
		(start 346.882466 -232.678986)
		(end 346.812362 -232.638346)
		(width 0.1143)
		(layer "In13.Cu")
		(net "GMI_CPU0_G0_CPU1_G2_TX_DP<13>")
	)
	(segment
		(start 346.844112 -240.111534)
		(end 346.880434 -240.090452)
		(width 0.1143)
		(layer "In13.Cu")
		(net "GMI_CPU0_G0_CPU1_G2_TX_DP<13>")
	)
	(segment
		(start 124.68352 -227.778818)
		(end 124.65177 -227.797106)
		(width 0.1143)
		(layer "In13.Cu")
		(net "GMI_CPU0_G0_CPU1_G2_TX_DP<13>")
	)
	(segment
		(start 346.812362 -228.789992)
		(end 346.865448 -228.759258)
		(width 0.1143)
		(layer "In13.Cu")
		(net "GMI_CPU0_G0_CPU1_G2_TX_DP<13>")
	)
	(segment
		(start 346.88526 -229.440994)
		(end 346.810584 -229.397052)
		(width 0.1143)
		(layer "In13.Cu")
		(net "GMI_CPU0_G0_CPU1_G2_TX_DP<13>")
	)
	(segment
		(start 346.903294 -232.693718)
		(end 346.882466 -232.678986)
		(width 0.1143)
		(layer "In13.Cu")
		(net "GMI_CPU0_G0_CPU1_G2_TX_DP<13>")
	)
	(segment
		(start 303.734724 -189.169548)
		(end 262.665464 -188.790326)
		(width 0.14224)
		(layer "In13.Cu")
		(net "GMI_CPU0_G0_CPU1_G2_TX_DP<13>")
	)
	(segment
		(start 346.838016 -223.915224)
		(end 346.838778 -223.914716)
		(width 0.1143)
		(layer "In13.Cu")
		(net "GMI_CPU0_G0_CPU1_G2_TX_DP<13>")
	)
	(segment
		(start 124.683266 -233.650028)
		(end 124.68352 -233.650028)
		(width 0.1143)
		(layer "In13.Cu")
		(net "GMI_CPU0_G0_CPU1_G2_TX_DP<13>")
	)
	(segment
		(start 346.815664 -230.408226)
		(end 346.81922 -230.406194)
		(width 0.1143)
		(layer "In13.Cu")
		(net "GMI_CPU0_G0_CPU1_G2_TX_DP<13>")
	)
	(segment
		(start 234.011978 -199.051418)
		(end 211.800186 -189.850776)
		(width 0.14224)
		(layer "In13.Cu")
		(net "GMI_CPU0_G0_CPU1_G2_TX_DP<13>")
	)
	(segment
		(start 346.844112 -222.936816)
		(end 346.82303 -222.924624)
		(width 0.1143)
		(layer "In13.Cu")
		(net "GMI_CPU0_G0_CPU1_G2_TX_DP<13>")
	)
	(segment
		(start 346.812362 -225.549968)
		(end 346.812616 -225.549968)
		(width 0.1143)
		(layer "In13.Cu")
		(net "GMI_CPU0_G0_CPU1_G2_TX_DP<13>")
	)
	(segment
		(start 124.65177 -240.111788)
		(end 124.68352 -240.130076)
		(width 0.1143)
		(layer "In13.Cu")
		(net "GMI_CPU0_G0_CPU1_G2_TX_DP<13>")
	)
	(segment
		(start 346.844112 -234.276646)
		(end 346.82303 -234.264454)
		(width 0.1143)
		(layer "In13.Cu")
		(net "GMI_CPU0_G0_CPU1_G2_TX_DP<13>")
	)
	(segment
		(start 346.827094 -230.401622)
		(end 346.827856 -230.401114)
		(width 0.1143)
		(layer "In13.Cu")
		(net "GMI_CPU0_G0_CPU1_G2_TX_DP<13>")
	)
	(segment
		(start 346.812362 -227.16998)
		(end 346.844112 -227.151692)
		(width 0.1143)
		(layer "In13.Cu")
		(net "GMI_CPU0_G0_CPU1_G2_TX_DP<13>")
	)
	(segment
		(start 124.68352 -237.498636)
		(end 124.612146 -237.540038)
		(width 0.1143)
		(layer "In13.Cu")
		(net "GMI_CPU0_G0_CPU1_G2_TX_DP<13>")
	)
	(segment
		(start 346.910152 -224.598992)
		(end 346.883736 -224.579942)
		(width 0.1143)
		(layer "In13.Cu")
		(net "GMI_CPU0_G0_CPU1_G2_TX_DP<13>")
	)
	(segment
		(start 346.812362 -230.410004)
		(end 346.815664 -230.408226)
		(width 0.1143)
		(layer "In13.Cu")
		(net "GMI_CPU0_G0_CPU1_G2_TX_DP<13>")
	)
	(segment
		(start 239.476026 -198.887334)
		(end 236.278928 -199.451214)
		(width 0.14224)
		(layer "In13.Cu")
		(net "GMI_CPU0_G0_CPU1_G2_TX_DP<13>")
	)
	(segment
		(start 124.65177 -226.177094)
		(end 124.615448 -226.198176)
		(width 0.1143)
		(layer "In13.Cu")
		(net "GMI_CPU0_G0_CPU1_G2_TX_DP<13>")
	)
	(segment
		(start 124.369576 -229.905052)
		(end 124.377704 -229.979728)
		(width 0.1143)
		(layer "In13.Cu")
		(net "GMI_CPU0_G0_CPU1_G2_TX_DP<13>")
	)
	(segment
		(start 346.883228 -241.70894)
		(end 346.910914 -241.688874)
		(width 0.1143)
		(layer "In13.Cu")
		(net "GMI_CPU0_G0_CPU1_G2_TX_DP<13>")
	)
	(segment
		(start 124.657866 -223.915478)
		(end 124.660406 -223.916748)
		(width 0.1143)
		(layer "In13.Cu")
		(net "GMI_CPU0_G0_CPU1_G2_TX_DP<13>")
	)
	(segment
		(start 124.615448 -227.130864)
		(end 124.65177 -227.151946)
		(width 0.1143)
		(layer "In13.Cu")
		(net "GMI_CPU0_G0_CPU1_G2_TX_DP<13>")
	)
	(segment
		(start 347.17228 -220.382592)
		(end 345.964256 -218.349576)
		(width 0.14224)
		(layer "In13.Cu")
		(net "GMI_CPU0_G0_CPU1_G2_TX_DP<13>")
	)
	(segment
		(start 124.612908 -222.26905)
		(end 124.682504 -222.30969)
		(width 0.1143)
		(layer "In13.Cu")
		(net "GMI_CPU0_G0_CPU1_G2_TX_DP<13>")
	)
	(segment
		(start 346.822014 -230.40467)
		(end 346.8243 -230.403146)
		(width 0.1143)
		(layer "In13.Cu")
		(net "GMI_CPU0_G0_CPU1_G2_TX_DP<13>")
	)
	(segment
		(start 346.849954 -231.039924)
		(end 346.844112 -231.036622)
		(width 0.1143)
		(layer "In13.Cu")
		(net "GMI_CPU0_G0_CPU1_G2_TX_DP<13>")
	)
	(segment
		(start 346.838778 -223.914716)
		(end 346.839794 -223.914208)
		(width 0.1143)
		(layer "In13.Cu")
		(net "GMI_CPU0_G0_CPU1_G2_TX_DP<13>")
	)
	(segment
		(start 124.683266 -238.510064)
		(end 124.68352 -238.510064)
		(width 0.1143)
		(layer "In13.Cu")
		(net "GMI_CPU0_G0_CPU1_G2_TX_DP<13>")
	)
	(segment
		(start 124.651516 -235.251752)
		(end 124.65177 -235.251752)
		(width 0.1143)
		(layer "In13.Cu")
		(net "GMI_CPU0_G0_CPU1_G2_TX_DP<13>")
	)
	(segment
		(start 124.584968 -241.689128)
		(end 124.612654 -241.709194)
		(width 0.1143)
		(layer "In13.Cu")
		(net "GMI_CPU0_G0_CPU1_G2_TX_DP<13>")
	)
	(segment
		(start 124.657104 -235.2548)
		(end 124.657866 -235.255308)
		(width 0.1143)
		(layer "In13.Cu")
		(net "GMI_CPU0_G0_CPU1_G2_TX_DP<13>")
	)
	(segment
		(start 346.893896 -230.361236)
		(end 346.924884 -230.334058)
		(width 0.1143)
		(layer "In13.Cu")
		(net "GMI_CPU0_G0_CPU1_G2_TX_DP<13>")
	)
	(segment
		(start 124.652532 -223.91243)
		(end 124.653548 -223.912938)
		(width 0.1143)
		(layer "In13.Cu")
		(net "GMI_CPU0_G0_CPU1_G2_TX_DP<13>")
	)
	(segment
		(start 346.883228 -240.7793)
		(end 346.812362 -240.738406)
		(width 0.1143)
		(layer "In13.Cu")
		(net "GMI_CPU0_G0_CPU1_G2_TX_DP<13>")
	)
	(segment
		(start 346.827856 -230.401114)
		(end 346.827856 -230.40086)
		(width 0.1143)
		(layer "In13.Cu")
		(net "GMI_CPU0_G0_CPU1_G2_TX_DP<13>")
	)
	(segment
		(start 346.864686 -227.80879)
		(end 346.844112 -227.796852)
		(width 0.1143)
		(layer "In13.Cu")
		(net "GMI_CPU0_G0_CPU1_G2_TX_DP<13>")
	)
	(segment
		(start 124.656088 -235.254292)
		(end 124.657104 -235.2548)
		(width 0.1143)
		(layer "In13.Cu")
		(net "GMI_CPU0_G0_CPU1_G2_TX_DP<13>")
	)
	(segment
		(start 211.800186 -189.850776)
		(end 207.361536 -189.068202)
		(width 0.14224)
		(layer "In13.Cu")
		(net "GMI_CPU0_G0_CPU1_G2_TX_DP<13>")
	)
	(arc
		(start 124.36983 -221.804484)
		(mid 124.434204 -222.066688)
		(end 124.612908 -222.26905)
		(width 0.1143)
		(layer "In13.Cu")
		(net "GMI_CPU0_G0_CPU1_G2_TX_DP<13>")
	)
	(arc
		(start 124.592588 -235.933996)
		(mid 124.361319 -236.384338)
		(end 124.592588 -236.83468)
		(width 0.1143)
		(layer "In13.Cu")
		(net "GMI_CPU0_G0_CPU1_G2_TX_DP<13>")
	)
	(arc
		(start 124.601224 -239.167924)
		(mid 124.373841 -239.624362)
		(end 124.601224 -240.0808)
		(width 0.1143)
		(layer "In13.Cu")
		(net "GMI_CPU0_G0_CPU1_G2_TX_DP<13>")
	)
	(arc
		(start 346.812362 -235.87837)
		(mid 346.656434 -235.574078)
		(end 346.812362 -235.269786)
		(width 0.1143)
		(layer "In13.Cu")
		(net "GMI_CPU0_G0_CPU1_G2_TX_DP<13>")
	)
	(arc
		(start 346.903294 -236.834426)
		(mid 347.134563 -236.384084)
		(end 346.903294 -235.933742)
		(width 0.1143)
		(layer "In13.Cu")
		(net "GMI_CPU0_G0_CPU1_G2_TX_DP<13>")
	)
	(arc
		(start 346.810584 -229.397052)
		(mid 346.697177 -229.264163)
		(end 346.656406 -229.094284)
		(width 0.1143)
		(layer "In13.Cu")
		(net "GMI_CPU0_G0_CPU1_G2_TX_DP<13>")
	)
	(arc
		(start 124.615448 -239.158018)
		(mid 124.608299 -239.162918)
		(end 124.601224 -239.167924)
		(width 0.1143)
		(layer "In13.Cu")
		(net "GMI_CPU0_G0_CPU1_G2_TX_DP<13>")
	)
	(arc
		(start 124.601224 -240.0808)
		(mid 124.608298 -240.085807)
		(end 124.615448 -240.090706)
		(width 0.1143)
		(layer "In13.Cu")
		(net "GMI_CPU0_G0_CPU1_G2_TX_DP<13>")
	)
	(arc
		(start 346.844366 -235.251498)
		(mid 347.124793 -234.764262)
		(end 346.844366 -234.2769)
		(width 0.1143)
		(layer "In13.Cu")
		(net "GMI_CPU0_G0_CPU1_G2_TX_DP<13>")
	)
	(arc
		(start 346.812362 -224.53854)
		(mid 346.656434 -224.234248)
		(end 346.812362 -223.929956)
		(width 0.1143)
		(layer "In13.Cu")
		(net "GMI_CPU0_G0_CPU1_G2_TX_DP<13>")
	)
	(arc
		(start 347.126306 -229.904036)
		(mid 347.0625 -229.642983)
		(end 346.88526 -229.440994)
		(width 0.1143)
		(layer "In13.Cu")
		(net "GMI_CPU0_G0_CPU1_G2_TX_DP<13>")
	)
	(arc
		(start 124.610622 -229.441248)
		(mid 124.43325 -229.643598)
		(end 124.369576 -229.905052)
		(width 0.1143)
		(layer "In13.Cu")
		(net "GMI_CPU0_G0_CPU1_G2_TX_DP<13>")
	)
	(arc
		(start 124.682504 -222.30969)
		(mid 124.797931 -222.443066)
		(end 124.839476 -222.61449)
		(width 0.1143)
		(layer "In13.Cu")
		(net "GMI_CPU0_G0_CPU1_G2_TX_DP<13>")
	)
	(arc
		(start 124.68352 -235.27004)
		(mid 124.839448 -235.574332)
		(end 124.68352 -235.878624)
		(width 0.1143)
		(layer "In13.Cu")
		(net "GMI_CPU0_G0_CPU1_G2_TX_DP<13>")
	)
	(arc
		(start 346.910914 -241.688874)
		(mid 347.138914 -241.24412)
		(end 346.910914 -240.799366)
		(width 0.1143)
		(layer "In13.Cu")
		(net "GMI_CPU0_G0_CPU1_G2_TX_DP<13>")
	)
	(arc
		(start 346.810584 -231.017064)
		(mid 346.697177 -230.884175)
		(end 346.656406 -230.714296)
		(width 0.1143)
		(layer "In13.Cu")
		(net "GMI_CPU0_G0_CPU1_G2_TX_DP<13>")
	)
	(arc
		(start 346.849954 -232.008172)
		(mid 347.128757 -231.524048)
		(end 346.849954 -231.039924)
		(width 0.1143)
		(layer "In13.Cu")
		(net "GMI_CPU0_G0_CPU1_G2_TX_DP<13>")
	)
	(arc
		(start 125.152404 -242.559586)
		(mid 125.250169 -242.662562)
		(end 125.302518 -242.794536)
		(width 0.1143)
		(layer "In13.Cu")
		(net "GMI_CPU0_G0_CPU1_G2_TX_DP<13>")
	)
	(arc
		(start 124.68352 -230.410258)
		(mid 124.798196 -230.543592)
		(end 124.839476 -230.71455)
		(width 0.1143)
		(layer "In13.Cu")
		(net "GMI_CPU0_G0_CPU1_G2_TX_DP<13>")
	)
	(arc
		(start 124.68352 -225.550222)
		(mid 124.839448 -225.854514)
		(end 124.68352 -226.158806)
		(width 0.1143)
		(layer "In13.Cu")
		(net "GMI_CPU0_G0_CPU1_G2_TX_DP<13>")
	)
	(arc
		(start 124.615448 -226.198176)
		(mid 124.60727 -226.203819)
		(end 124.599192 -226.209606)
		(width 0.1143)
		(layer "In13.Cu")
		(net "GMI_CPU0_G0_CPU1_G2_TX_DP<13>")
	)
	(arc
		(start 124.584968 -240.79962)
		(mid 124.356968 -241.244374)
		(end 124.584968 -241.689128)
		(width 0.1143)
		(layer "In13.Cu")
		(net "GMI_CPU0_G0_CPU1_G2_TX_DP<13>")
	)
	(arc
		(start 124.839476 -229.094538)
		(mid 124.798714 -229.264422)
		(end 124.685298 -229.397306)
		(width 0.1143)
		(layer "In13.Cu")
		(net "GMI_CPU0_G0_CPU1_G2_TX_DP<13>")
	)
	(arc
		(start 124.651516 -222.937324)
		(mid 124.370869 -223.424686)
		(end 124.651516 -223.911922)
		(width 0.1143)
		(layer "In13.Cu")
		(net "GMI_CPU0_G0_CPU1_G2_TX_DP<13>")
	)
	(arc
		(start 346.910152 -225.48977)
		(mid 347.138142 -225.044434)
		(end 346.910152 -224.598992)
		(width 0.1143)
		(layer "In13.Cu")
		(net "GMI_CPU0_G0_CPU1_G2_TX_DP<13>")
	)
	(arc
		(start 346.910152 -238.449612)
		(mid 347.138142 -238.004276)
		(end 346.910152 -237.558834)
		(width 0.1143)
		(layer "In13.Cu")
		(net "GMI_CPU0_G0_CPU1_G2_TX_DP<13>")
	)
	(arc
		(start 124.68352 -238.510064)
		(mid 124.839448 -238.814356)
		(end 124.68352 -239.118648)
		(width 0.1143)
		(layer "In13.Cu")
		(net "GMI_CPU0_G0_CPU1_G2_TX_DP<13>")
	)
	(arc
		(start 346.844366 -223.911668)
		(mid 347.124793 -223.424432)
		(end 346.844366 -222.93707)
		(width 0.1143)
		(layer "In13.Cu")
		(net "GMI_CPU0_G0_CPU1_G2_TX_DP<13>")
	)
	(arc
		(start 346.812362 -222.918528)
		(mid 346.697686 -222.785194)
		(end 346.656406 -222.614236)
		(width 0.1143)
		(layer "In13.Cu")
		(net "GMI_CPU0_G0_CPU1_G2_TX_DP<13>")
	)
	(arc
		(start 124.68352 -236.890052)
		(mid 124.839448 -237.194344)
		(end 124.68352 -237.498636)
		(width 0.1143)
		(layer "In13.Cu")
		(net "GMI_CPU0_G0_CPU1_G2_TX_DP<13>")
	)
	(arc
		(start 124.68352 -223.93021)
		(mid 124.839448 -224.234502)
		(end 124.68352 -224.538794)
		(width 0.1143)
		(layer "In13.Cu")
		(net "GMI_CPU0_G0_CPU1_G2_TX_DP<13>")
	)
	(arc
		(start 346.812362 -240.738406)
		(mid 346.656434 -240.434114)
		(end 346.812362 -240.129822)
		(width 0.1143)
		(layer "In13.Cu")
		(net "GMI_CPU0_G0_CPU1_G2_TX_DP<13>")
	)
	(arc
		(start 124.377704 -229.979728)
		(mid 124.430297 -230.157819)
		(end 124.542042 -230.306118)
		(width 0.1143)
		(layer "In13.Cu")
		(net "GMI_CPU0_G0_CPU1_G2_TX_DP<13>")
	)
	(arc
		(start 124.68352 -241.750342)
		(mid 124.73243 -241.792313)
		(end 124.773436 -241.842036)
		(width 0.1143)
		(layer "In13.Cu")
		(net "GMI_CPU0_G0_CPU1_G2_TX_DP<13>")
	)
	(arc
		(start 346.882974 -222.268796)
		(mid 347.061617 -222.066401)
		(end 347.126052 -221.80423)
		(width 0.1143)
		(layer "In13.Cu")
		(net "GMI_CPU0_G0_CPU1_G2_TX_DP<13>")
	)
	(arc
		(start 346.812362 -226.158552)
		(mid 346.656434 -225.85426)
		(end 346.812362 -225.549968)
		(width 0.1143)
		(layer "In13.Cu")
		(net "GMI_CPU0_G0_CPU1_G2_TX_DP<13>")
	)
	(arc
		(start 346.656406 -222.614236)
		(mid 346.697955 -222.442814)
		(end 346.813378 -222.309436)
		(width 0.1143)
		(layer "In13.Cu")
		(net "GMI_CPU0_G0_CPU1_G2_TX_DP<13>")
	)
	(arc
		(start 124.773436 -241.842036)
		(mid 124.82252 -241.943205)
		(end 124.839476 -242.05438)
		(width 0.1143)
		(layer "In13.Cu")
		(net "GMI_CPU0_G0_CPU1_G2_TX_DP<13>")
	)
	(arc
		(start 346.89669 -227.11918)
		(mid 347.119574 -226.664266)
		(end 346.89669 -226.209352)
		(width 0.1143)
		(layer "In13.Cu")
		(net "GMI_CPU0_G0_CPU1_G2_TX_DP<13>")
	)
	(arc
		(start 124.68352 -227.170234)
		(mid 124.839448 -227.474526)
		(end 124.68352 -227.778818)
		(width 0.1143)
		(layer "In13.Cu")
		(net "GMI_CPU0_G0_CPU1_G2_TX_DP<13>")
	)
	(arc
		(start 124.68352 -228.790246)
		(mid 124.798196 -228.92358)
		(end 124.839476 -229.094538)
		(width 0.1143)
		(layer "In13.Cu")
		(net "GMI_CPU0_G0_CPU1_G2_TX_DP<13>")
	)
	(arc
		(start 346.865448 -228.759258)
		(mid 347.138999 -228.284278)
		(end 346.865448 -227.809298)
		(width 0.1143)
		(layer "In13.Cu")
		(net "GMI_CPU0_G0_CPU1_G2_TX_DP<13>")
	)
	(arc
		(start 346.812362 -234.258358)
		(mid 346.656434 -233.954066)
		(end 346.812362 -233.649774)
		(width 0.1143)
		(layer "In13.Cu")
		(net "GMI_CPU0_G0_CPU1_G2_TX_DP<13>")
	)
	(arc
		(start 124.839476 -242.05438)
		(mid 124.903991 -242.316599)
		(end 125.082808 -242.518946)
		(width 0.1143)
		(layer "In13.Cu")
		(net "GMI_CPU0_G0_CPU1_G2_TX_DP<13>")
	)
	(arc
		(start 124.58573 -237.559088)
		(mid 124.357534 -238.00453)
		(end 124.58573 -238.449866)
		(width 0.1143)
		(layer "In13.Cu")
		(net "GMI_CPU0_G0_CPU1_G2_TX_DP<13>")
	)
	(arc
		(start 346.812362 -227.778564)
		(mid 346.656434 -227.474272)
		(end 346.812362 -227.16998)
		(width 0.1143)
		(layer "In13.Cu")
		(net "GMI_CPU0_G0_CPU1_G2_TX_DP<13>")
	)
	(arc
		(start 346.656406 -242.054126)
		(mid 346.673277 -241.942925)
		(end 346.722446 -241.841782)
		(width 0.1143)
		(layer "In13.Cu")
		(net "GMI_CPU0_G0_CPU1_G2_TX_DP<13>")
	)
	(arc
		(start 124.630434 -227.809552)
		(mid 124.356883 -228.284532)
		(end 124.630434 -228.759512)
		(width 0.1143)
		(layer "In13.Cu")
		(net "GMI_CPU0_G0_CPU1_G2_TX_DP<13>")
	)
	(arc
		(start 124.651516 -234.277154)
		(mid 124.370869 -234.764516)
		(end 124.651516 -235.251752)
		(width 0.1143)
		(layer "In13.Cu")
		(net "GMI_CPU0_G0_CPU1_G2_TX_DP<13>")
	)
	(arc
		(start 346.812362 -232.638346)
		(mid 346.656434 -232.334054)
		(end 346.812362 -232.029762)
		(width 0.1143)
		(layer "In13.Cu")
		(net "GMI_CPU0_G0_CPU1_G2_TX_DP<13>")
	)
	(arc
		(start 124.68352 -240.130076)
		(mid 124.839448 -240.434368)
		(end 124.68352 -240.73866)
		(width 0.1143)
		(layer "In13.Cu")
		(net "GMI_CPU0_G0_CPU1_G2_TX_DP<13>")
	)
	(arc
		(start 124.68352 -232.030016)
		(mid 124.839448 -232.334308)
		(end 124.68352 -232.6386)
		(width 0.1143)
		(layer "In13.Cu")
		(net "GMI_CPU0_G0_CPU1_G2_TX_DP<13>")
	)
	(arc
		(start 124.839476 -222.61449)
		(mid 124.798221 -222.785461)
		(end 124.68352 -222.918782)
		(width 0.1143)
		(layer "In13.Cu")
		(net "GMI_CPU0_G0_CPU1_G2_TX_DP<13>")
	)
	(arc
		(start 346.413074 -242.518692)
		(mid 346.591887 -242.316342)
		(end 346.656406 -242.054126)
		(width 0.1143)
		(layer "In13.Cu")
		(net "GMI_CPU0_G0_CPU1_G2_TX_DP<13>")
	)
	(arc
		(start 124.58573 -224.599246)
		(mid 124.357534 -225.044688)
		(end 124.58573 -225.490024)
		(width 0.1143)
		(layer "In13.Cu")
		(net "GMI_CPU0_G0_CPU1_G2_TX_DP<13>")
	)
	(arc
		(start 124.592588 -232.693972)
		(mid 124.361319 -233.144314)
		(end 124.592588 -233.594656)
		(width 0.1143)
		(layer "In13.Cu")
		(net "GMI_CPU0_G0_CPU1_G2_TX_DP<13>")
	)
	(arc
		(start 346.880434 -227.13061)
		(mid 346.888612 -227.124967)
		(end 346.89669 -227.11918)
		(width 0.1143)
		(layer "In13.Cu")
		(net "GMI_CPU0_G0_CPU1_G2_TX_DP<13>")
	)
	(arc
		(start 346.656406 -230.714296)
		(mid 346.697661 -230.543325)
		(end 346.812362 -230.410004)
		(width 0.1143)
		(layer "In13.Cu")
		(net "GMI_CPU0_G0_CPU1_G2_TX_DP<13>")
	)
	(arc
		(start 124.68352 -233.650028)
		(mid 124.839448 -233.95432)
		(end 124.68352 -234.258612)
		(width 0.1143)
		(layer "In13.Cu")
		(net "GMI_CPU0_G0_CPU1_G2_TX_DP<13>")
	)
	(arc
		(start 124.839476 -230.71455)
		(mid 124.798714 -230.884434)
		(end 124.685298 -231.017318)
		(width 0.1143)
		(layer "In13.Cu")
		(net "GMI_CPU0_G0_CPU1_G2_TX_DP<13>")
	)
	(arc
		(start 346.894658 -240.080546)
		(mid 347.122041 -239.624108)
		(end 346.894658 -239.16767)
		(width 0.1143)
		(layer "In13.Cu")
		(net "GMI_CPU0_G0_CPU1_G2_TX_DP<13>")
	)
	(arc
		(start 346.193364 -242.794282)
		(mid 346.245781 -242.662351)
		(end 346.343478 -242.559332)
		(width 0.1143)
		(layer "In13.Cu")
		(net "GMI_CPU0_G0_CPU1_G2_TX_DP<13>")
	)
	(arc
		(start 346.894658 -239.16767)
		(mid 346.887585 -239.162661)
		(end 346.880434 -239.157764)
		(width 0.1143)
		(layer "In13.Cu")
		(net "GMI_CPU0_G0_CPU1_G2_TX_DP<13>")
	)
	(arc
		(start 346.656406 -229.094284)
		(mid 346.697661 -228.923313)
		(end 346.812362 -228.789992)
		(width 0.1143)
		(layer "In13.Cu")
		(net "GMI_CPU0_G0_CPU1_G2_TX_DP<13>")
	)
	(arc
		(start 346.924884 -230.334058)
		(mid 347.061102 -230.158626)
		(end 347.122496 -229.945184)
		(width 0.1143)
		(layer "In13.Cu")
		(net "GMI_CPU0_G0_CPU1_G2_TX_DP<13>")
	)
	(arc
		(start 124.645928 -231.040178)
		(mid 124.367125 -231.524302)
		(end 124.645928 -232.008426)
		(width 0.1143)
		(layer "In13.Cu")
		(net "GMI_CPU0_G0_CPU1_G2_TX_DP<13>")
	)
	(arc
		(start 346.722446 -241.841782)
		(mid 346.763435 -241.792041)
		(end 346.812362 -241.750088)
		(width 0.1143)
		(layer "In13.Cu")
		(net "GMI_CPU0_G0_CPU1_G2_TX_DP<13>")
	)
	(arc
		(start 346.812362 -239.118394)
		(mid 346.656434 -238.814102)
		(end 346.812362 -238.50981)
		(width 0.1143)
		(layer "In13.Cu")
		(net "GMI_CPU0_G0_CPU1_G2_TX_DP<13>")
	)
	(arc
		(start 346.903294 -233.594402)
		(mid 347.134563 -233.14406)
		(end 346.903294 -232.693718)
		(width 0.1143)
		(layer "In13.Cu")
		(net "GMI_CPU0_G0_CPU1_G2_TX_DP<13>")
	)
	(arc
		(start 124.599192 -226.209606)
		(mid 124.376308 -226.66452)
		(end 124.599192 -227.119434)
		(width 0.1143)
		(layer "In13.Cu")
		(net "GMI_CPU0_G0_CPU1_G2_TX_DP<13>")
	)
	(arc
		(start 346.812362 -237.498382)
		(mid 346.656434 -237.19409)
		(end 346.812362 -236.889798)
		(width 0.1143)
		(layer "In13.Cu")
		(net "GMI_CPU0_G0_CPU1_G2_TX_DP<13>")
	)
	(arc
		(start 346.880434 -240.090452)
		(mid 346.887584 -240.085554)
		(end 346.894658 -240.080546)
		(width 0.1143)
		(layer "In13.Cu")
		(net "GMI_CPU0_G0_CPU1_G2_TX_DP<13>")
	)
	(arc
		(start 346.89669 -226.209352)
		(mid 346.888612 -226.203566)
		(end 346.880434 -226.197922)
		(width 0.1143)
		(layer "In13.Cu")
		(net "GMI_CPU0_G0_CPU1_G2_TX_DP<13>")
	)
	(arc
		(start 124.599192 -227.119434)
		(mid 124.60727 -227.12522)
		(end 124.615448 -227.130864)
		(width 0.1143)
		(layer "In13.Cu")
		(net "GMI_CPU0_G0_CPU1_G2_TX_DP<13>")
	)
	(segment
		(start 349.847916 -241.510058)
		(end 349.381064 -241.24412)
		(width 0.12954)
		(layer "F.Cu")
		(net "GMI_CPU0_G0_CPU1_G2_TX_DP<12>")
	)
	(segment
		(start 121.647966 -241.510312)
		(end 122.114818 -241.244374)
		(width 0.12954)
		(layer "F.Cu")
		(net "GMI_CPU0_G0_CPU1_G2_TX_DP<12>")
	)
	(segment
		(start 347.753432 -235.269278)
		(end 347.823028 -235.228638)
		(width 0.1143)
		(layer "In13.Cu")
		(net "GMI_CPU0_G0_CPU1_G2_TX_DP<12>")
	)
	(segment
		(start 123.672854 -225.509074)
		(end 123.71197 -225.531934)
		(width 0.1143)
		(layer "In13.Cu")
		(net "GMI_CPU0_G0_CPU1_G2_TX_DP<12>")
	)
	(segment
		(start 347.823028 -237.53953)
		(end 347.753432 -237.49889)
		(width 0.1143)
		(layer "In13.Cu")
		(net "GMI_CPU0_G0_CPU1_G2_TX_DP<12>")
	)
	(segment
		(start 123.243848 -239.945672)
		(end 123.242578 -239.946434)
		(width 0.1143)
		(layer "In13.Cu")
		(net "GMI_CPU0_G0_CPU1_G2_TX_DP<12>")
	)
	(segment
		(start 161.846514 -188.302138)
		(end 159.67202 -190.08471)
		(width 0.14224)
		(layer "In13.Cu")
		(net "GMI_CPU0_G0_CPU1_G2_TX_DP<12>")
	)
	(segment
		(start 347.753432 -233.649266)
		(end 347.823028 -233.608626)
		(width 0.1143)
		(layer "In13.Cu")
		(net "GMI_CPU0_G0_CPU1_G2_TX_DP<12>")
	)
	(segment
		(start 347.823028 -235.919518)
		(end 347.753432 -235.878878)
		(width 0.1143)
		(layer "In13.Cu")
		(net "GMI_CPU0_G0_CPU1_G2_TX_DP<12>")
	)
	(segment
		(start 347.823028 -239.159542)
		(end 347.753432 -239.118902)
		(width 0.1143)
		(layer "In13.Cu")
		(net "GMI_CPU0_G0_CPU1_G2_TX_DP<12>")
	)
	(segment
		(start 239.107726 -197.99808)
		(end 239.107218 -197.99808)
		(width 0.14224)
		(layer "In13.Cu")
		(net "GMI_CPU0_G0_CPU1_G2_TX_DP<12>")
	)
	(segment
		(start 123.74245 -237.499144)
		(end 123.71197 -237.516924)
		(width 0.1143)
		(layer "In13.Cu")
		(net "GMI_CPU0_G0_CPU1_G2_TX_DP<12>")
	)
	(segment
		(start 123.74245 -232.639108)
		(end 123.71197 -232.656888)
		(width 0.1143)
		(layer "In13.Cu")
		(net "GMI_CPU0_G0_CPU1_G2_TX_DP<12>")
	)
	(segment
		(start 123.74245 -234.25912)
		(end 123.71197 -234.2769)
		(width 0.1143)
		(layer "In13.Cu")
		(net "GMI_CPU0_G0_CPU1_G2_TX_DP<12>")
	)
	(segment
		(start 123.74245 -222.91929)
		(end 123.71197 -222.93707)
		(width 0.1143)
		(layer "In13.Cu")
		(net "GMI_CPU0_G0_CPU1_G2_TX_DP<12>")
	)
	(segment
		(start 123.71197 -223.911922)
		(end 123.74245 -223.929702)
		(width 0.1143)
		(layer "In13.Cu")
		(net "GMI_CPU0_G0_CPU1_G2_TX_DP<12>")
	)
	(segment
		(start 123.384056 -220.944948)
		(end 123.384056 -220.973396)
		(width 0.1143)
		(layer "In13.Cu")
		(net "GMI_CPU0_G0_CPU1_G2_TX_DP<12>")
	)
	(segment
		(start 346.631768 -217.643456)
		(end 318.94907 -194.944746)
		(width 0.14224)
		(layer "In13.Cu")
		(net "GMI_CPU0_G0_CPU1_G2_TX_DP<12>")
	)
	(segment
		(start 347.823028 -234.299506)
		(end 347.753432 -234.258866)
		(width 0.1143)
		(layer "In13.Cu")
		(net "GMI_CPU0_G0_CPU1_G2_TX_DP<12>")
	)
	(segment
		(start 122.803666 -240.73866)
		(end 122.772678 -240.75644)
		(width 0.1143)
		(layer "In13.Cu")
		(net "GMI_CPU0_G0_CPU1_G2_TX_DP<12>")
	)
	(segment
		(start 303.706784 -188.201808)
		(end 262.7376 -187.823348)
		(width 0.14224)
		(layer "In13.Cu")
		(net "GMI_CPU0_G0_CPU1_G2_TX_DP<12>")
	)
	(segment
		(start 348.111826 -220.944694)
		(end 348.111826 -220.13672)
		(width 0.14224)
		(layer "In13.Cu")
		(net "GMI_CPU0_G0_CPU1_G2_TX_DP<12>")
	)
	(segment
		(start 123.384056 -220.29166)
		(end 123.384056 -220.944948)
		(width 0.14224)
		(layer "In13.Cu")
		(net "GMI_CPU0_G0_CPU1_G2_TX_DP<12>")
	)
	(segment
		(start 147.870418 -199.76211)
		(end 145.74266 -200.406254)
		(width 0.14224)
		(layer "In13.Cu")
		(net "GMI_CPU0_G0_CPU1_G2_TX_DP<12>")
	)
	(segment
		(start 123.71197 -236.871764)
		(end 123.74245 -236.889544)
		(width 0.1143)
		(layer "In13.Cu")
		(net "GMI_CPU0_G0_CPU1_G2_TX_DP<12>")
	)
	(segment
		(start 123.242578 -239.946434)
		(end 123.241816 -239.946942)
		(width 0.1143)
		(layer "In13.Cu")
		(net "GMI_CPU0_G0_CPU1_G2_TX_DP<12>")
	)
	(segment
		(start 159.582104 -190.158624)
		(end 159.58185 -190.159132)
		(width 0.14224)
		(layer "In13.Cu")
		(net "GMI_CPU0_G0_CPU1_G2_TX_DP<12>")
	)
	(segment
		(start 349.083122 -241.24412)
		(end 349.000318 -241.161316)
		(width 0.1143)
		(layer "In13.Cu")
		(net "GMI_CPU0_G0_CPU1_G2_TX_DP<12>")
	)
	(segment
		(start 123.429776 -221.019116)
		(end 123.429776 -221.804484)
		(width 0.1143)
		(layer "In13.Cu")
		(net "GMI_CPU0_G0_CPU1_G2_TX_DP<12>")
	)
	(segment
		(start 348.254066 -239.946688)
		(end 348.253304 -239.94618)
		(width 0.1143)
		(layer "In13.Cu")
		(net "GMI_CPU0_G0_CPU1_G2_TX_DP<12>")
	)
	(segment
		(start 318.819784 -194.815714)
		(end 309.435754 -188.201808)
		(width 0.14224)
		(layer "In13.Cu")
		(net "GMI_CPU0_G0_CPU1_G2_TX_DP<12>")
	)
	(segment
		(start 318.94907 -194.944746)
		(end 318.819784 -194.815714)
		(width 0.14224)
		(layer "In13.Cu")
		(net "GMI_CPU0_G0_CPU1_G2_TX_DP<12>")
	)
	(segment
		(start 348.723204 -240.756186)
		(end 348.692216 -240.738406)
		(width 0.1143)
		(layer "In13.Cu")
		(net "GMI_CPU0_G0_CPU1_G2_TX_DP<12>")
	)
	(segment
		(start 348.726506 -240.758218)
		(end 348.724982 -240.757202)
		(width 0.1143)
		(layer "In13.Cu")
		(net "GMI_CPU0_G0_CPU1_G2_TX_DP<12>")
	)
	(segment
		(start 309.435754 -188.201808)
		(end 303.706784 -188.201808)
		(width 0.14224)
		(layer "In13.Cu")
		(net "GMI_CPU0_G0_CPU1_G2_TX_DP<12>")
	)
	(segment
		(start 207.332072 -188.108844)
		(end 161.846514 -188.302138)
		(width 0.14224)
		(layer "In13.Cu")
		(net "GMI_CPU0_G0_CPU1_G2_TX_DP<12>")
	)
	(segment
		(start 347.753432 -225.54946)
		(end 347.823028 -225.50882)
		(width 0.1143)
		(layer "In13.Cu")
		(net "GMI_CPU0_G0_CPU1_G2_TX_DP<12>")
	)
	(segment
		(start 347.753432 -230.409496)
		(end 347.820488 -230.37038)
		(width 0.1143)
		(layer "In13.Cu")
		(net "GMI_CPU0_G0_CPU1_G2_TX_DP<12>")
	)
	(segment
		(start 123.71197 -232.656888)
		(end 123.672854 -232.679748)
		(width 0.1143)
		(layer "In13.Cu")
		(net "GMI_CPU0_G0_CPU1_G2_TX_DP<12>")
	)
	(segment
		(start 235.326428 -198.329042)
		(end 213.113874 -189.128146)
		(width 0.14224)
		(layer "In13.Cu")
		(net "GMI_CPU0_G0_CPU1_G2_TX_DP<12>")
	)
	(segment
		(start 347.753432 -227.169472)
		(end 347.823028 -227.128832)
		(width 0.1143)
		(layer "In13.Cu")
		(net "GMI_CPU0_G0_CPU1_G2_TX_DP<12>")
	)
	(segment
		(start 159.67202 -190.08471)
		(end 159.672274 -190.08471)
		(width 0.14224)
		(layer "In13.Cu")
		(net "GMI_CPU0_G0_CPU1_G2_TX_DP<12>")
	)
	(segment
		(start 347.823028 -227.819712)
		(end 347.753432 -227.779072)
		(width 0.1143)
		(layer "In13.Cu")
		(net "GMI_CPU0_G0_CPU1_G2_TX_DP<12>")
	)
	(segment
		(start 347.753432 -238.509302)
		(end 347.823028 -238.468662)
		(width 0.1143)
		(layer "In13.Cu")
		(net "GMI_CPU0_G0_CPU1_G2_TX_DP<12>")
	)
	(segment
		(start 347.753432 -223.929448)
		(end 347.823028 -223.888808)
		(width 0.1143)
		(layer "In13.Cu")
		(net "GMI_CPU0_G0_CPU1_G2_TX_DP<12>")
	)
	(segment
		(start 348.253304 -239.94618)
		(end 348.252034 -239.945418)
		(width 0.1143)
		(layer "In13.Cu")
		(net "GMI_CPU0_G0_CPU1_G2_TX_DP<12>")
	)
	(segment
		(start 123.71197 -228.771958)
		(end 123.74245 -228.789738)
		(width 0.1143)
		(layer "In13.Cu")
		(net "GMI_CPU0_G0_CPU1_G2_TX_DP<12>")
	)
	(segment
		(start 347.823028 -231.059482)
		(end 347.783912 -231.036622)
		(width 0.1143)
		(layer "In13.Cu")
		(net "GMI_CPU0_G0_CPU1_G2_TX_DP<12>")
	)
	(segment
		(start 348.111826 -220.973142)
		(end 348.111826 -220.944694)
		(width 0.1143)
		(layer "In13.Cu")
		(net "GMI_CPU0_G0_CPU1_G2_TX_DP<12>")
	)
	(segment
		(start 348.763082 -240.779554)
		(end 348.726506 -240.758218)
		(width 0.1143)
		(layer "In13.Cu")
		(net "GMI_CPU0_G0_CPU1_G2_TX_DP<12>")
	)
	(segment
		(start 123.384056 -220.973396)
		(end 123.429776 -221.019116)
		(width 0.1143)
		(layer "In13.Cu")
		(net "GMI_CPU0_G0_CPU1_G2_TX_DP<12>")
	)
	(segment
		(start 122.495564 -241.16157)
		(end 122.41276 -241.244374)
		(width 0.1143)
		(layer "In13.Cu")
		(net "GMI_CPU0_G0_CPU1_G2_TX_DP<12>")
	)
	(segment
		(start 123.71197 -233.63174)
		(end 123.74245 -233.64952)
		(width 0.1143)
		(layer "In13.Cu")
		(net "GMI_CPU0_G0_CPU1_G2_TX_DP<12>")
	)
	(segment
		(start 123.71197 -231.036876)
		(end 123.672854 -231.059736)
		(width 0.1143)
		(layer "In13.Cu")
		(net "GMI_CPU0_G0_CPU1_G2_TX_DP<12>")
	)
	(segment
		(start 159.58185 -190.159132)
		(end 150.22068 -197.834758)
		(width 0.14224)
		(layer "In13.Cu")
		(net "GMI_CPU0_G0_CPU1_G2_TX_DP<12>")
	)
	(segment
		(start 122.769376 -240.758472)
		(end 122.7328 -240.779808)
		(width 0.1143)
		(layer "In13.Cu")
		(net "GMI_CPU0_G0_CPU1_G2_TX_DP<12>")
	)
	(segment
		(start 123.71197 -232.011728)
		(end 123.74245 -232.029508)
		(width 0.1143)
		(layer "In13.Cu")
		(net "GMI_CPU0_G0_CPU1_G2_TX_DP<12>")
	)
	(segment
		(start 239.107218 -197.99808)
		(end 236.278928 -198.496936)
		(width 0.14224)
		(layer "In13.Cu")
		(net "GMI_CPU0_G0_CPU1_G2_TX_DP<12>")
	)
	(segment
		(start 349.381064 -241.24412)
		(end 349.083122 -241.24412)
		(width 0.1143)
		(layer "In13.Cu")
		(net "GMI_CPU0_G0_CPU1_G2_TX_DP<12>")
	)
	(segment
		(start 122.7709 -240.757456)
		(end 122.769376 -240.758472)
		(width 0.1143)
		(layer "In13.Cu")
		(net "GMI_CPU0_G0_CPU1_G2_TX_DP<12>")
	)
	(segment
		(start 122.41276 -241.244374)
		(end 122.114818 -241.244374)
		(width 0.1143)
		(layer "In13.Cu")
		(net "GMI_CPU0_G0_CPU1_G2_TX_DP<12>")
	)
	(segment
		(start 348.25559 -239.94745)
		(end 348.254066 -239.946688)
		(width 0.1143)
		(layer "In13.Cu")
		(net "GMI_CPU0_G0_CPU1_G2_TX_DP<12>")
	)
	(segment
		(start 348.066106 -221.018862)
		(end 348.111826 -220.973142)
		(width 0.1143)
		(layer "In13.Cu")
		(net "GMI_CPU0_G0_CPU1_G2_TX_DP<12>")
	)
	(segment
		(start 123.71197 -235.251752)
		(end 123.74245 -235.269532)
		(width 0.1143)
		(layer "In13.Cu")
		(net "GMI_CPU0_G0_CPU1_G2_TX_DP<12>")
	)
	(segment
		(start 123.71197 -239.136936)
		(end 123.672854 -239.159796)
		(width 0.1143)
		(layer "In13.Cu")
		(net "GMI_CPU0_G0_CPU1_G2_TX_DP<12>")
	)
	(segment
		(start 236.278928 -198.496936)
		(end 235.326428 -198.329042)
		(width 0.14224)
		(layer "In13.Cu")
		(net "GMI_CPU0_G0_CPU1_G2_TX_DP<12>")
	)
	(segment
		(start 123.672854 -228.749098)
		(end 123.71197 -228.771958)
		(width 0.1143)
		(layer "In13.Cu")
		(net "GMI_CPU0_G0_CPU1_G2_TX_DP<12>")
	)
	(segment
		(start 145.74266 -200.406254)
		(end 125.084586 -217.345006)
		(width 0.14224)
		(layer "In13.Cu")
		(net "GMI_CPU0_G0_CPU1_G2_TX_DP<12>")
	)
	(segment
		(start 347.823028 -222.959676)
		(end 347.753432 -222.919036)
		(width 0.1143)
		(layer "In13.Cu")
		(net "GMI_CPU0_G0_CPU1_G2_TX_DP<12>")
	)
	(segment
		(start 159.672274 -190.08471)
		(end 159.582104 -190.158624)
		(width 0.14224)
		(layer "In13.Cu")
		(net "GMI_CPU0_G0_CPU1_G2_TX_DP<12>")
	)
	(segment
		(start 123.71197 -227.151946)
		(end 123.74245 -227.169726)
		(width 0.1143)
		(layer "In13.Cu")
		(net "GMI_CPU0_G0_CPU1_G2_TX_DP<12>")
	)
	(segment
		(start 123.672854 -238.468916)
		(end 123.71197 -238.491776)
		(width 0.1143)
		(layer "In13.Cu")
		(net "GMI_CPU0_G0_CPU1_G2_TX_DP<12>")
	)
	(segment
		(start 347.753432 -228.789484)
		(end 347.823028 -228.748844)
		(width 0.1143)
		(layer "In13.Cu")
		(net "GMI_CPU0_G0_CPU1_G2_TX_DP<12>")
	)
	(segment
		(start 123.71197 -238.491776)
		(end 123.74245 -238.509556)
		(width 0.1143)
		(layer "In13.Cu")
		(net "GMI_CPU0_G0_CPU1_G2_TX_DP<12>")
	)
	(segment
		(start 123.71197 -226.177094)
		(end 123.672854 -226.199954)
		(width 0.1143)
		(layer "In13.Cu")
		(net "GMI_CPU0_G0_CPU1_G2_TX_DP<12>")
	)
	(segment
		(start 123.74245 -226.159314)
		(end 123.71197 -226.177094)
		(width 0.1143)
		(layer "In13.Cu")
		(net "GMI_CPU0_G0_CPU1_G2_TX_DP<12>")
	)
	(segment
		(start 347.783912 -231.036622)
		(end 347.7514 -231.017826)
		(width 0.1143)
		(layer "In13.Cu")
		(net "GMI_CPU0_G0_CPU1_G2_TX_DP<12>")
	)
	(segment
		(start 123.71197 -237.516924)
		(end 123.672854 -237.539784)
		(width 0.1143)
		(layer "In13.Cu")
		(net "GMI_CPU0_G0_CPU1_G2_TX_DP<12>")
	)
	(segment
		(start 123.74245 -227.779326)
		(end 123.71197 -227.797106)
		(width 0.1143)
		(layer "In13.Cu")
		(net "GMI_CPU0_G0_CPU1_G2_TX_DP<12>")
	)
	(segment
		(start 123.675394 -230.370634)
		(end 123.74245 -230.40975)
		(width 0.1143)
		(layer "In13.Cu")
		(net "GMI_CPU0_G0_CPU1_G2_TX_DP<12>")
	)
	(segment
		(start 123.71197 -234.2769)
		(end 123.672854 -234.29976)
		(width 0.1143)
		(layer "In13.Cu")
		(net "GMI_CPU0_G0_CPU1_G2_TX_DP<12>")
	)
	(segment
		(start 123.672854 -236.848904)
		(end 123.71197 -236.871764)
		(width 0.1143)
		(layer "In13.Cu")
		(net "GMI_CPU0_G0_CPU1_G2_TX_DP<12>")
	)
	(segment
		(start 123.672854 -235.228892)
		(end 123.71197 -235.251752)
		(width 0.1143)
		(layer "In13.Cu")
		(net "GMI_CPU0_G0_CPU1_G2_TX_DP<12>")
	)
	(segment
		(start 348.723966 -240.756694)
		(end 348.723204 -240.756186)
		(width 0.1143)
		(layer "In13.Cu")
		(net "GMI_CPU0_G0_CPU1_G2_TX_DP<12>")
	)
	(segment
		(start 122.772678 -240.75644)
		(end 122.771916 -240.756948)
		(width 0.1143)
		(layer "In13.Cu")
		(net "GMI_CPU0_G0_CPU1_G2_TX_DP<12>")
	)
	(segment
		(start 123.74245 -235.879132)
		(end 123.71197 -235.896912)
		(width 0.1143)
		(layer "In13.Cu")
		(net "GMI_CPU0_G0_CPU1_G2_TX_DP<12>")
	)
	(segment
		(start 348.111826 -220.13672)
		(end 346.631768 -217.643456)
		(width 0.14224)
		(layer "In13.Cu")
		(net "GMI_CPU0_G0_CPU1_G2_TX_DP<12>")
	)
	(segment
		(start 348.066106 -221.80423)
		(end 348.066106 -221.018862)
		(width 0.1143)
		(layer "In13.Cu")
		(net "GMI_CPU0_G0_CPU1_G2_TX_DP<12>")
	)
	(segment
		(start 348.724982 -240.757202)
		(end 348.723966 -240.756694)
		(width 0.1143)
		(layer "In13.Cu")
		(net "GMI_CPU0_G0_CPU1_G2_TX_DP<12>")
	)
	(segment
		(start 122.771916 -240.756948)
		(end 122.7709 -240.757456)
		(width 0.1143)
		(layer "In13.Cu")
		(net "GMI_CPU0_G0_CPU1_G2_TX_DP<12>")
	)
	(segment
		(start 150.22068 -197.834758)
		(end 150.220934 -197.834758)
		(width 0.14224)
		(layer "In13.Cu")
		(net "GMI_CPU0_G0_CPU1_G2_TX_DP<12>")
	)
	(segment
		(start 123.71197 -225.531934)
		(end 123.74245 -225.549714)
		(width 0.1143)
		(layer "In13.Cu")
		(net "GMI_CPU0_G0_CPU1_G2_TX_DP<12>")
	)
	(segment
		(start 347.823028 -229.43947)
		(end 347.783912 -229.41661)
		(width 0.1143)
		(layer "In13.Cu")
		(net "GMI_CPU0_G0_CPU1_G2_TX_DP<12>")
	)
	(segment
		(start 347.753432 -222.309436)
		(end 347.823028 -222.268796)
		(width 0.1143)
		(layer "In13.Cu")
		(net "GMI_CPU0_G0_CPU1_G2_TX_DP<12>")
	)
	(segment
		(start 123.71197 -222.93707)
		(end 123.672854 -222.95993)
		(width 0.1143)
		(layer "In13.Cu")
		(net "GMI_CPU0_G0_CPU1_G2_TX_DP<12>")
	)
	(segment
		(start 347.753432 -236.88929)
		(end 347.823028 -236.84865)
		(width 0.1143)
		(layer "In13.Cu")
		(net "GMI_CPU0_G0_CPU1_G2_TX_DP<12>")
	)
	(segment
		(start 123.672854 -233.60888)
		(end 123.71197 -233.63174)
		(width 0.1143)
		(layer "In13.Cu")
		(net "GMI_CPU0_G0_CPU1_G2_TX_DP<12>")
	)
	(segment
		(start 123.71197 -229.416864)
		(end 123.672854 -229.439724)
		(width 0.1143)
		(layer "In13.Cu")
		(net "GMI_CPU0_G0_CPU1_G2_TX_DP<12>")
	)
	(segment
		(start 123.744482 -231.01808)
		(end 123.71197 -231.036876)
		(width 0.1143)
		(layer "In13.Cu")
		(net "GMI_CPU0_G0_CPU1_G2_TX_DP<12>")
	)
	(segment
		(start 123.71197 -224.557082)
		(end 123.672854 -224.579942)
		(width 0.1143)
		(layer "In13.Cu")
		(net "GMI_CPU0_G0_CPU1_G2_TX_DP<12>")
	)
	(segment
		(start 123.672854 -222.26905)
		(end 123.74245 -222.30969)
		(width 0.1143)
		(layer "In13.Cu")
		(net "GMI_CPU0_G0_CPU1_G2_TX_DP<12>")
	)
	(segment
		(start 123.273566 -239.928654)
		(end 123.243848 -239.945672)
		(width 0.1143)
		(layer "In13.Cu")
		(net "GMI_CPU0_G0_CPU1_G2_TX_DP<12>")
	)
	(segment
		(start 123.672854 -223.889062)
		(end 123.71197 -223.911922)
		(width 0.1143)
		(layer "In13.Cu")
		(net "GMI_CPU0_G0_CPU1_G2_TX_DP<12>")
	)
	(segment
		(start 213.113874 -189.128146)
		(end 207.332072 -188.108844)
		(width 0.14224)
		(layer "In13.Cu")
		(net "GMI_CPU0_G0_CPU1_G2_TX_DP<12>")
	)
	(segment
		(start 123.241816 -239.946942)
		(end 123.240292 -239.947704)
		(width 0.1143)
		(layer "In13.Cu")
		(net "GMI_CPU0_G0_CPU1_G2_TX_DP<12>")
	)
	(segment
		(start 123.71197 -227.797106)
		(end 123.672854 -227.819966)
		(width 0.1143)
		(layer "In13.Cu")
		(net "GMI_CPU0_G0_CPU1_G2_TX_DP<12>")
	)
	(segment
		(start 123.672854 -227.129086)
		(end 123.71197 -227.151946)
		(width 0.1143)
		(layer "In13.Cu")
		(net "GMI_CPU0_G0_CPU1_G2_TX_DP<12>")
	)
	(segment
		(start 347.823028 -226.1997)
		(end 347.753432 -226.15906)
		(width 0.1143)
		(layer "In13.Cu")
		(net "GMI_CPU0_G0_CPU1_G2_TX_DP<12>")
	)
	(segment
		(start 123.240292 -239.947704)
		(end 123.205494 -239.968024)
		(width 0.1143)
		(layer "In13.Cu")
		(net "GMI_CPU0_G0_CPU1_G2_TX_DP<12>")
	)
	(segment
		(start 123.74245 -239.119156)
		(end 123.71197 -239.136936)
		(width 0.1143)
		(layer "In13.Cu")
		(net "GMI_CPU0_G0_CPU1_G2_TX_DP<12>")
	)
	(segment
		(start 347.783912 -229.41661)
		(end 347.7514 -229.397814)
		(width 0.1143)
		(layer "In13.Cu")
		(net "GMI_CPU0_G0_CPU1_G2_TX_DP<12>")
	)
	(segment
		(start 250.57608 -189.96787)
		(end 239.107726 -197.99808)
		(width 0.14224)
		(layer "In13.Cu")
		(net "GMI_CPU0_G0_CPU1_G2_TX_DP<12>")
	)
	(segment
		(start 123.672854 -231.988868)
		(end 123.71197 -232.011728)
		(width 0.1143)
		(layer "In13.Cu")
		(net "GMI_CPU0_G0_CPU1_G2_TX_DP<12>")
	)
	(segment
		(start 123.744482 -229.398068)
		(end 123.71197 -229.416864)
		(width 0.1143)
		(layer "In13.Cu")
		(net "GMI_CPU0_G0_CPU1_G2_TX_DP<12>")
	)
	(segment
		(start 150.220934 -197.834758)
		(end 147.870418 -199.76211)
		(width 0.14224)
		(layer "In13.Cu")
		(net "GMI_CPU0_G0_CPU1_G2_TX_DP<12>")
	)
	(segment
		(start 347.753432 -232.029254)
		(end 347.823028 -231.988614)
		(width 0.1143)
		(layer "In13.Cu")
		(net "GMI_CPU0_G0_CPU1_G2_TX_DP<12>")
	)
	(segment
		(start 262.7376 -187.823348)
		(end 250.57608 -189.96787)
		(width 0.14224)
		(layer "In13.Cu")
		(net "GMI_CPU0_G0_CPU1_G2_TX_DP<12>")
	)
	(segment
		(start 123.74245 -224.539302)
		(end 123.71197 -224.557082)
		(width 0.1143)
		(layer "In13.Cu")
		(net "GMI_CPU0_G0_CPU1_G2_TX_DP<12>")
	)
	(segment
		(start 347.823028 -224.579688)
		(end 347.753432 -224.539048)
		(width 0.1143)
		(layer "In13.Cu")
		(net "GMI_CPU0_G0_CPU1_G2_TX_DP<12>")
	)
	(segment
		(start 123.71197 -235.896912)
		(end 123.672854 -235.919772)
		(width 0.1143)
		(layer "In13.Cu")
		(net "GMI_CPU0_G0_CPU1_G2_TX_DP<12>")
	)
	(segment
		(start 125.084586 -217.345006)
		(end 123.384056 -220.29166)
		(width 0.14224)
		(layer "In13.Cu")
		(net "GMI_CPU0_G0_CPU1_G2_TX_DP<12>")
	)
	(segment
		(start 348.290388 -239.96777)
		(end 348.25559 -239.94745)
		(width 0.1143)
		(layer "In13.Cu")
		(net "GMI_CPU0_G0_CPU1_G2_TX_DP<12>")
	)
	(segment
		(start 347.823028 -232.679494)
		(end 347.753432 -232.638854)
		(width 0.1143)
		(layer "In13.Cu")
		(net "GMI_CPU0_G0_CPU1_G2_TX_DP<12>")
	)
	(segment
		(start 348.252034 -239.945418)
		(end 348.222316 -239.9284)
		(width 0.1143)
		(layer "In13.Cu")
		(net "GMI_CPU0_G0_CPU1_G2_TX_DP<12>")
	)
	(arc
		(start 347.823028 -235.228638)
		(mid 348.066355 -234.764072)
		(end 347.823028 -234.299506)
		(width 0.1143)
		(layer "In13.Cu")
		(net "GMI_CPU0_G0_CPU1_G2_TX_DP<12>")
	)
	(arc
		(start 348.06636 -229.904036)
		(mid 348.001845 -229.641817)
		(end 347.823028 -229.43947)
		(width 0.1143)
		(layer "In13.Cu")
		(net "GMI_CPU0_G0_CPU1_G2_TX_DP<12>")
	)
	(arc
		(start 348.534482 -240.407444)
		(mid 348.462938 -240.182126)
		(end 348.321884 -239.992408)
		(width 0.1143)
		(layer "In13.Cu")
		(net "GMI_CPU0_G0_CPU1_G2_TX_DP<12>")
	)
	(arc
		(start 122.7328 -240.779808)
		(mid 122.580813 -240.936316)
		(end 122.499374 -241.13871)
		(width 0.1143)
		(layer "In13.Cu")
		(net "GMI_CPU0_G0_CPU1_G2_TX_DP<12>")
	)
	(arc
		(start 123.74245 -222.30969)
		(mid 123.899427 -222.61449)
		(end 123.74245 -222.91929)
		(width 0.1143)
		(layer "In13.Cu")
		(net "GMI_CPU0_G0_CPU1_G2_TX_DP<12>")
	)
	(arc
		(start 123.672854 -224.579942)
		(mid 123.429527 -225.044508)
		(end 123.672854 -225.509074)
		(width 0.1143)
		(layer "In13.Cu")
		(net "GMI_CPU0_G0_CPU1_G2_TX_DP<12>")
	)
	(arc
		(start 347.753432 -222.919036)
		(mid 347.596455 -222.614236)
		(end 347.753432 -222.309436)
		(width 0.1143)
		(layer "In13.Cu")
		(net "GMI_CPU0_G0_CPU1_G2_TX_DP<12>")
	)
	(arc
		(start 347.59646 -229.094284)
		(mid 347.638009 -228.922862)
		(end 347.753432 -228.789484)
		(width 0.1143)
		(layer "In13.Cu")
		(net "GMI_CPU0_G0_CPU1_G2_TX_DP<12>")
	)
	(arc
		(start 123.672854 -234.29976)
		(mid 123.429527 -234.764326)
		(end 123.672854 -235.228892)
		(width 0.1143)
		(layer "In13.Cu")
		(net "GMI_CPU0_G0_CPU1_G2_TX_DP<12>")
	)
	(arc
		(start 347.753432 -234.258866)
		(mid 347.596455 -233.954066)
		(end 347.753432 -233.649266)
		(width 0.1143)
		(layer "In13.Cu")
		(net "GMI_CPU0_G0_CPU1_G2_TX_DP<12>")
	)
	(arc
		(start 347.753432 -224.539048)
		(mid 347.596455 -224.234248)
		(end 347.753432 -223.929448)
		(width 0.1143)
		(layer "In13.Cu")
		(net "GMI_CPU0_G0_CPU1_G2_TX_DP<12>")
	)
	(arc
		(start 349.000318 -241.161316)
		(mid 348.99853 -241.149867)
		(end 348.996508 -241.138456)
		(width 0.1143)
		(layer "In13.Cu")
		(net "GMI_CPU0_G0_CPU1_G2_TX_DP<12>")
	)
	(arc
		(start 123.899422 -230.71455)
		(mid 123.858456 -230.884956)
		(end 123.744482 -231.01808)
		(width 0.1143)
		(layer "In13.Cu")
		(net "GMI_CPU0_G0_CPU1_G2_TX_DP<12>")
	)
	(arc
		(start 123.74245 -235.269532)
		(mid 123.899427 -235.574332)
		(end 123.74245 -235.879132)
		(width 0.1143)
		(layer "In13.Cu")
		(net "GMI_CPU0_G0_CPU1_G2_TX_DP<12>")
	)
	(arc
		(start 123.429522 -229.90429)
		(mid 123.494758 -230.167881)
		(end 123.675394 -230.370634)
		(width 0.1143)
		(layer "In13.Cu")
		(net "GMI_CPU0_G0_CPU1_G2_TX_DP<12>")
	)
	(arc
		(start 122.959622 -240.434368)
		(mid 122.915551 -240.603904)
		(end 122.803666 -240.73866)
		(width 0.1143)
		(layer "In13.Cu")
		(net "GMI_CPU0_G0_CPU1_G2_TX_DP<12>")
	)
	(arc
		(start 348.53626 -240.434114)
		(mid 348.535855 -240.420746)
		(end 348.534482 -240.407444)
		(width 0.1143)
		(layer "In13.Cu")
		(net "GMI_CPU0_G0_CPU1_G2_TX_DP<12>")
	)
	(arc
		(start 347.7514 -229.397814)
		(mid 347.637471 -229.264667)
		(end 347.59646 -229.094284)
		(width 0.1143)
		(layer "In13.Cu")
		(net "GMI_CPU0_G0_CPU1_G2_TX_DP<12>")
	)
	(arc
		(start 122.499374 -241.13871)
		(mid 122.497351 -241.15012)
		(end 122.495564 -241.16157)
		(width 0.1143)
		(layer "In13.Cu")
		(net "GMI_CPU0_G0_CPU1_G2_TX_DP<12>")
	)
	(arc
		(start 123.672854 -227.819966)
		(mid 123.429527 -228.284532)
		(end 123.672854 -228.749098)
		(width 0.1143)
		(layer "In13.Cu")
		(net "GMI_CPU0_G0_CPU1_G2_TX_DP<12>")
	)
	(arc
		(start 123.74245 -223.929702)
		(mid 123.899427 -224.234502)
		(end 123.74245 -224.539302)
		(width 0.1143)
		(layer "In13.Cu")
		(net "GMI_CPU0_G0_CPU1_G2_TX_DP<12>")
	)
	(arc
		(start 347.753432 -237.49889)
		(mid 347.596455 -237.19409)
		(end 347.753432 -236.88929)
		(width 0.1143)
		(layer "In13.Cu")
		(net "GMI_CPU0_G0_CPU1_G2_TX_DP<12>")
	)
	(arc
		(start 347.820488 -230.37038)
		(mid 348.00114 -230.167635)
		(end 348.06636 -229.904036)
		(width 0.1143)
		(layer "In13.Cu")
		(net "GMI_CPU0_G0_CPU1_G2_TX_DP<12>")
	)
	(arc
		(start 347.823028 -236.84865)
		(mid 348.066355 -236.384084)
		(end 347.823028 -235.919518)
		(width 0.1143)
		(layer "In13.Cu")
		(net "GMI_CPU0_G0_CPU1_G2_TX_DP<12>")
	)
	(arc
		(start 347.823028 -222.268796)
		(mid 348.001671 -222.066401)
		(end 348.066106 -221.80423)
		(width 0.1143)
		(layer "In13.Cu")
		(net "GMI_CPU0_G0_CPU1_G2_TX_DP<12>")
	)
	(arc
		(start 123.74245 -227.169726)
		(mid 123.899427 -227.474526)
		(end 123.74245 -227.779326)
		(width 0.1143)
		(layer "In13.Cu")
		(net "GMI_CPU0_G0_CPU1_G2_TX_DP<12>")
	)
	(arc
		(start 123.74245 -236.889544)
		(mid 123.899427 -237.194344)
		(end 123.74245 -237.499144)
		(width 0.1143)
		(layer "In13.Cu")
		(net "GMI_CPU0_G0_CPU1_G2_TX_DP<12>")
	)
	(arc
		(start 347.7514 -231.017826)
		(mid 347.637471 -230.884679)
		(end 347.59646 -230.714296)
		(width 0.1143)
		(layer "In13.Cu")
		(net "GMI_CPU0_G0_CPU1_G2_TX_DP<12>")
	)
	(arc
		(start 123.672854 -237.539784)
		(mid 123.429527 -238.00435)
		(end 123.672854 -238.468916)
		(width 0.1143)
		(layer "In13.Cu")
		(net "GMI_CPU0_G0_CPU1_G2_TX_DP<12>")
	)
	(arc
		(start 347.59646 -230.714296)
		(mid 347.638009 -230.542874)
		(end 347.753432 -230.409496)
		(width 0.1143)
		(layer "In13.Cu")
		(net "GMI_CPU0_G0_CPU1_G2_TX_DP<12>")
	)
	(arc
		(start 123.672854 -235.919772)
		(mid 123.429527 -236.384338)
		(end 123.672854 -236.848904)
		(width 0.1143)
		(layer "In13.Cu")
		(net "GMI_CPU0_G0_CPU1_G2_TX_DP<12>")
	)
	(arc
		(start 348.06636 -239.624108)
		(mid 348.001845 -239.361889)
		(end 347.823028 -239.159542)
		(width 0.1143)
		(layer "In13.Cu")
		(net "GMI_CPU0_G0_CPU1_G2_TX_DP<12>")
	)
	(arc
		(start 347.823028 -233.608626)
		(mid 348.066355 -233.14406)
		(end 347.823028 -232.679494)
		(width 0.1143)
		(layer "In13.Cu")
		(net "GMI_CPU0_G0_CPU1_G2_TX_DP<12>")
	)
	(arc
		(start 347.823028 -223.888808)
		(mid 348.066355 -223.424242)
		(end 347.823028 -222.959676)
		(width 0.1143)
		(layer "In13.Cu")
		(net "GMI_CPU0_G0_CPU1_G2_TX_DP<12>")
	)
	(arc
		(start 122.9614 -240.407698)
		(mid 122.960043 -240.421002)
		(end 122.959622 -240.434368)
		(width 0.1143)
		(layer "In13.Cu")
		(net "GMI_CPU0_G0_CPU1_G2_TX_DP<12>")
	)
	(arc
		(start 123.205494 -239.968024)
		(mid 123.189525 -239.980061)
		(end 123.173998 -239.992662)
		(width 0.1143)
		(layer "In13.Cu")
		(net "GMI_CPU0_G0_CPU1_G2_TX_DP<12>")
	)
	(arc
		(start 123.429776 -221.804484)
		(mid 123.49415 -222.066688)
		(end 123.672854 -222.26905)
		(width 0.1143)
		(layer "In13.Cu")
		(net "GMI_CPU0_G0_CPU1_G2_TX_DP<12>")
	)
	(arc
		(start 123.74245 -228.789738)
		(mid 123.857877 -228.923114)
		(end 123.899422 -229.094538)
		(width 0.1143)
		(layer "In13.Cu")
		(net "GMI_CPU0_G0_CPU1_G2_TX_DP<12>")
	)
	(arc
		(start 348.996508 -241.138456)
		(mid 348.915075 -240.936058)
		(end 348.763082 -240.779554)
		(width 0.1143)
		(layer "In13.Cu")
		(net "GMI_CPU0_G0_CPU1_G2_TX_DP<12>")
	)
	(arc
		(start 347.753432 -235.878878)
		(mid 347.596455 -235.574078)
		(end 347.753432 -235.269278)
		(width 0.1143)
		(layer "In13.Cu")
		(net "GMI_CPU0_G0_CPU1_G2_TX_DP<12>")
	)
	(arc
		(start 348.321884 -239.992408)
		(mid 348.306352 -239.979813)
		(end 348.290388 -239.96777)
		(width 0.1143)
		(layer "In13.Cu")
		(net "GMI_CPU0_G0_CPU1_G2_TX_DP<12>")
	)
	(arc
		(start 347.823028 -225.50882)
		(mid 348.066355 -225.044254)
		(end 347.823028 -224.579688)
		(width 0.1143)
		(layer "In13.Cu")
		(net "GMI_CPU0_G0_CPU1_G2_TX_DP<12>")
	)
	(arc
		(start 123.173998 -239.992662)
		(mid 123.032911 -240.182364)
		(end 122.9614 -240.407698)
		(width 0.1143)
		(layer "In13.Cu")
		(net "GMI_CPU0_G0_CPU1_G2_TX_DP<12>")
	)
	(arc
		(start 123.672854 -222.95993)
		(mid 123.429527 -223.424496)
		(end 123.672854 -223.889062)
		(width 0.1143)
		(layer "In13.Cu")
		(net "GMI_CPU0_G0_CPU1_G2_TX_DP<12>")
	)
	(arc
		(start 347.823028 -238.468662)
		(mid 348.066355 -238.004096)
		(end 347.823028 -237.53953)
		(width 0.1143)
		(layer "In13.Cu")
		(net "GMI_CPU0_G0_CPU1_G2_TX_DP<12>")
	)
	(arc
		(start 123.74245 -225.549714)
		(mid 123.899427 -225.854514)
		(end 123.74245 -226.159314)
		(width 0.1143)
		(layer "In13.Cu")
		(net "GMI_CPU0_G0_CPU1_G2_TX_DP<12>")
	)
	(arc
		(start 123.74245 -232.029508)
		(mid 123.899427 -232.334308)
		(end 123.74245 -232.639108)
		(width 0.1143)
		(layer "In13.Cu")
		(net "GMI_CPU0_G0_CPU1_G2_TX_DP<12>")
	)
	(arc
		(start 347.753432 -226.15906)
		(mid 347.596455 -225.85426)
		(end 347.753432 -225.54946)
		(width 0.1143)
		(layer "In13.Cu")
		(net "GMI_CPU0_G0_CPU1_G2_TX_DP<12>")
	)
	(arc
		(start 123.672854 -229.439724)
		(mid 123.494041 -229.642074)
		(end 123.429522 -229.90429)
		(width 0.1143)
		(layer "In13.Cu")
		(net "GMI_CPU0_G0_CPU1_G2_TX_DP<12>")
	)
	(arc
		(start 123.74245 -233.64952)
		(mid 123.899427 -233.95432)
		(end 123.74245 -234.25912)
		(width 0.1143)
		(layer "In13.Cu")
		(net "GMI_CPU0_G0_CPU1_G2_TX_DP<12>")
	)
	(arc
		(start 123.672854 -239.159796)
		(mid 123.494041 -239.362146)
		(end 123.429522 -239.624362)
		(width 0.1143)
		(layer "In13.Cu")
		(net "GMI_CPU0_G0_CPU1_G2_TX_DP<12>")
	)
	(arc
		(start 347.823028 -231.988614)
		(mid 348.066355 -231.524048)
		(end 347.823028 -231.059482)
		(width 0.1143)
		(layer "In13.Cu")
		(net "GMI_CPU0_G0_CPU1_G2_TX_DP<12>")
	)
	(arc
		(start 348.222316 -239.9284)
		(mid 348.10764 -239.795066)
		(end 348.06636 -239.624108)
		(width 0.1143)
		(layer "In13.Cu")
		(net "GMI_CPU0_G0_CPU1_G2_TX_DP<12>")
	)
	(arc
		(start 123.429522 -239.624362)
		(mid 123.388267 -239.795333)
		(end 123.273566 -239.928654)
		(width 0.1143)
		(layer "In13.Cu")
		(net "GMI_CPU0_G0_CPU1_G2_TX_DP<12>")
	)
	(arc
		(start 347.823028 -227.128832)
		(mid 348.066355 -226.664266)
		(end 347.823028 -226.1997)
		(width 0.1143)
		(layer "In13.Cu")
		(net "GMI_CPU0_G0_CPU1_G2_TX_DP<12>")
	)
	(arc
		(start 348.692216 -240.738406)
		(mid 348.580419 -240.603605)
		(end 348.53626 -240.434114)
		(width 0.1143)
		(layer "In13.Cu")
		(net "GMI_CPU0_G0_CPU1_G2_TX_DP<12>")
	)
	(arc
		(start 123.74245 -230.40975)
		(mid 123.857877 -230.543126)
		(end 123.899422 -230.71455)
		(width 0.1143)
		(layer "In13.Cu")
		(net "GMI_CPU0_G0_CPU1_G2_TX_DP<12>")
	)
	(arc
		(start 123.672854 -231.059736)
		(mid 123.429527 -231.524302)
		(end 123.672854 -231.988868)
		(width 0.1143)
		(layer "In13.Cu")
		(net "GMI_CPU0_G0_CPU1_G2_TX_DP<12>")
	)
	(arc
		(start 123.899422 -229.094538)
		(mid 123.858456 -229.264944)
		(end 123.744482 -229.398068)
		(width 0.1143)
		(layer "In13.Cu")
		(net "GMI_CPU0_G0_CPU1_G2_TX_DP<12>")
	)
	(arc
		(start 347.753432 -227.779072)
		(mid 347.596455 -227.474272)
		(end 347.753432 -227.169472)
		(width 0.1143)
		(layer "In13.Cu")
		(net "GMI_CPU0_G0_CPU1_G2_TX_DP<12>")
	)
	(arc
		(start 123.74245 -238.509556)
		(mid 123.899427 -238.814356)
		(end 123.74245 -239.119156)
		(width 0.1143)
		(layer "In13.Cu")
		(net "GMI_CPU0_G0_CPU1_G2_TX_DP<12>")
	)
	(arc
		(start 347.823028 -228.748844)
		(mid 348.066355 -228.284278)
		(end 347.823028 -227.819712)
		(width 0.1143)
		(layer "In13.Cu")
		(net "GMI_CPU0_G0_CPU1_G2_TX_DP<12>")
	)
	(arc
		(start 347.753432 -239.118902)
		(mid 347.596455 -238.814102)
		(end 347.753432 -238.509302)
		(width 0.1143)
		(layer "In13.Cu")
		(net "GMI_CPU0_G0_CPU1_G2_TX_DP<12>")
	)
	(arc
		(start 347.753432 -232.638854)
		(mid 347.596455 -232.334054)
		(end 347.753432 -232.029254)
		(width 0.1143)
		(layer "In13.Cu")
		(net "GMI_CPU0_G0_CPU1_G2_TX_DP<12>")
	)
	(arc
		(start 123.672854 -226.199954)
		(mid 123.429527 -226.66452)
		(end 123.672854 -227.129086)
		(width 0.1143)
		(layer "In13.Cu")
		(net "GMI_CPU0_G0_CPU1_G2_TX_DP<12>")
	)
	(arc
		(start 123.672854 -232.679748)
		(mid 123.429527 -233.144314)
		(end 123.672854 -233.60888)
		(width 0.1143)
		(layer "In13.Cu")
		(net "GMI_CPU0_G0_CPU1_G2_TX_DP<12>")
	)
	(segment
		(start 121.647966 -239.8903)
		(end 122.114818 -239.624362)
		(width 0.12954)
		(layer "F.Cu")
		(net "GMI_CPU0_G0_CPU1_G2_TX_DP<11>")
	)
	(segment
		(start 349.847916 -239.890046)
		(end 349.381064 -239.624108)
		(width 0.12954)
		(layer "F.Cu")
		(net "GMI_CPU0_G0_CPU1_G2_TX_DP<11>")
	)
	(segment
		(start 122.69978 -232.705148)
		(end 122.701304 -232.703878)
		(width 0.1143)
		(layer "In13.Cu")
		(net "GMI_CPU0_G0_CPU1_G2_TX_DP<11>")
	)
	(segment
		(start 122.804682 -228.791008)
		(end 122.804428 -228.7905)
		(width 0.1143)
		(layer "In13.Cu")
		(net "GMI_CPU0_G0_CPU1_G2_TX_DP<11>")
	)
	(segment
		(start 122.7328 -229.439724)
		(end 122.804936 -229.397306)
		(width 0.1143)
		(layer "In13.Cu")
		(net "GMI_CPU0_G0_CPU1_G2_TX_DP<11>")
	)
	(segment
		(start 122.771916 -233.63174)
		(end 122.767852 -233.6292)
		(width 0.1143)
		(layer "In13.Cu")
		(net "GMI_CPU0_G0_CPU1_G2_TX_DP<11>")
	)
	(segment
		(start 348.723204 -225.532188)
		(end 348.692216 -225.549968)
		(width 0.1143)
		(layer "In13.Cu")
		(net "GMI_CPU0_G0_CPU1_G2_TX_DP<11>")
	)
	(segment
		(start 348.690946 -229.397052)
		(end 348.724728 -229.416864)
		(width 0.1143)
		(layer "In13.Cu")
		(net "GMI_CPU0_G0_CPU1_G2_TX_DP<11>")
	)
	(segment
		(start 348.782386 -222.257874)
		(end 348.69247 -222.309944)
		(width 0.1143)
		(layer "In13.Cu")
		(net "GMI_CPU0_G0_CPU1_G2_TX_DP<11>")
	)
	(segment
		(start 348.683834 -234.252262)
		(end 348.692216 -234.258358)
		(width 0.1143)
		(layer "In13.Cu")
		(net "GMI_CPU0_G0_CPU1_G2_TX_DP<11>")
	)
	(segment
		(start 348.755462 -225.513392)
		(end 348.724982 -225.531172)
		(width 0.1143)
		(layer "In13.Cu")
		(net "GMI_CPU0_G0_CPU1_G2_TX_DP<11>")
	)
	(segment
		(start 348.727776 -226.178872)
		(end 348.73057 -226.180396)
		(width 0.1143)
		(layer "In13.Cu")
		(net "GMI_CPU0_G0_CPU1_G2_TX_DP<11>")
	)
	(segment
		(start 122.765312 -226.18065)
		(end 122.768106 -226.179126)
		(width 0.1143)
		(layer "In13.Cu")
		(net "GMI_CPU0_G0_CPU1_G2_TX_DP<11>")
	)
	(segment
		(start 122.695716 -234.328462)
		(end 122.727466 -234.302808)
		(width 0.1143)
		(layer "In13.Cu")
		(net "GMI_CPU0_G0_CPU1_G2_TX_DP<11>")
	)
	(segment
		(start 163.189666 -185.809382)
		(end 167.271446 -184.349898)
		(width 0.14224)
		(layer "In13.Cu")
		(net "GMI_CPU0_G0_CPU1_G2_TX_DP<11>")
	)
	(segment
		(start 348.77883 -232.690924)
		(end 348.779084 -232.691178)
		(width 0.1143)
		(layer "In13.Cu")
		(net "GMI_CPU0_G0_CPU1_G2_TX_DP<11>")
	)
	(segment
		(start 122.763026 -226.18192)
		(end 122.765312 -226.18065)
		(width 0.1143)
		(layer "In13.Cu")
		(net "GMI_CPU0_G0_CPU1_G2_TX_DP<11>")
	)
	(segment
		(start 122.803666 -223.93021)
		(end 122.772678 -223.91243)
		(width 0.1143)
		(layer "In13.Cu")
		(net "GMI_CPU0_G0_CPU1_G2_TX_DP<11>")
	)
	(segment
		(start 348.732602 -232.661714)
		(end 348.763082 -232.679494)
		(width 0.1143)
		(layer "In13.Cu")
		(net "GMI_CPU0_G0_CPU1_G2_TX_DP<11>")
	)
	(segment
		(start 348.729554 -227.800154)
		(end 348.763082 -227.819712)
		(width 0.1143)
		(layer "In13.Cu")
		(net "GMI_CPU0_G0_CPU1_G2_TX_DP<11>")
	)
	(segment
		(start 122.803666 -235.27004)
		(end 122.772678 -235.25226)
		(width 0.1143)
		(layer "In13.Cu")
		(net "GMI_CPU0_G0_CPU1_G2_TX_DP<11>")
	)
	(segment
		(start 349.071692 -219.91066)
		(end 349.071692 -221.093538)
		(width 0.14224)
		(layer "In13.Cu")
		(net "GMI_CPU0_G0_CPU1_G2_TX_DP<11>")
	)
	(segment
		(start 348.756224 -227.132896)
		(end 348.755462 -227.133404)
		(width 0.1143)
		(layer "In13.Cu")
		(net "GMI_CPU0_G0_CPU1_G2_TX_DP<11>")
	)
	(segment
		(start 348.690692 -235.8771)
		(end 348.72422 -235.896658)
		(width 0.1143)
		(layer "In13.Cu")
		(net "GMI_CPU0_G0_CPU1_G2_TX_DP<11>")
	)
	(segment
		(start 348.723966 -225.53168)
		(end 348.723204 -225.532188)
		(width 0.1143)
		(layer "In13.Cu")
		(net "GMI_CPU0_G0_CPU1_G2_TX_DP<11>")
	)
	(segment
		(start 348.692216 -227.778564)
		(end 348.723204 -227.796344)
		(width 0.1143)
		(layer "In13.Cu")
		(net "GMI_CPU0_G0_CPU1_G2_TX_DP<11>")
	)
	(segment
		(start 122.73534 -222.270828)
		(end 122.734324 -222.27032)
		(width 0.1143)
		(layer "In13.Cu")
		(net "GMI_CPU0_G0_CPU1_G2_TX_DP<11>")
	)
	(segment
		(start 348.724982 -232.657142)
		(end 348.726506 -232.658158)
		(width 0.1143)
		(layer "In13.Cu")
		(net "GMI_CPU0_G0_CPU1_G2_TX_DP<11>")
	)
	(segment
		(start 348.783402 -233.59364)
		(end 348.77883 -233.597196)
		(width 0.1143)
		(layer "In13.Cu")
		(net "GMI_CPU0_G0_CPU1_G2_TX_DP<11>")
	)
	(segment
		(start 349.006414 -229.904036)
		(end 349.006414 -229.90429)
		(width 0.1143)
		(layer "In13.Cu")
		(net "GMI_CPU0_G0_CPU1_G2_TX_DP<11>")
	)
	(segment
		(start 122.772678 -233.632248)
		(end 122.771916 -233.63174)
		(width 0.1143)
		(layer "In13.Cu")
		(net "GMI_CPU0_G0_CPU1_G2_TX_DP<11>")
	)
	(segment
		(start 122.7709 -232.01122)
		(end 122.74042 -231.99344)
		(width 0.1143)
		(layer "In13.Cu")
		(net "GMI_CPU0_G0_CPU1_G2_TX_DP<11>")
	)
	(segment
		(start 348.732602 -234.281726)
		(end 348.759526 -234.297474)
		(width 0.1143)
		(layer "In13.Cu")
		(net "GMI_CPU0_G0_CPU1_G2_TX_DP<11>")
	)
	(segment
		(start 122.716798 -232.691178)
		(end 122.717052 -232.691178)
		(width 0.1143)
		(layer "In13.Cu")
		(net "GMI_CPU0_G0_CPU1_G2_TX_DP<11>")
	)
	(segment
		(start 348.681548 -226.150932)
		(end 348.692216 -226.158552)
		(width 0.1143)
		(layer "In13.Cu")
		(net "GMI_CPU0_G0_CPU1_G2_TX_DP<11>")
	)
	(segment
		(start 122.489468 -229.904544)
		(end 122.489468 -229.90429)
		(width 0.1143)
		(layer "In13.Cu")
		(net "GMI_CPU0_G0_CPU1_G2_TX_DP<11>")
	)
	(segment
		(start 348.756224 -233.61269)
		(end 348.755462 -233.613198)
		(width 0.1143)
		(layer "In13.Cu")
		(net "GMI_CPU0_G0_CPU1_G2_TX_DP<11>")
	)
	(segment
		(start 122.74042 -228.75367)
		(end 122.739658 -228.753162)
		(width 0.1143)
		(layer "In13.Cu")
		(net "GMI_CPU0_G0_CPU1_G2_TX_DP<11>")
	)
	(segment
		(start 122.489468 -221.401894)
		(end 122.46991 -221.382336)
		(width 0.1143)
		(layer "In13.Cu")
		(net "GMI_CPU0_G0_CPU1_G2_TX_DP<11>")
	)
	(segment
		(start 302.886872 -185.132726)
		(end 302.886872 -185.13298)
		(width 0.14224)
		(layer "In13.Cu")
		(net "GMI_CPU0_G0_CPU1_G2_TX_DP<11>")
	)
	(segment
		(start 348.723966 -227.151692)
		(end 348.723204 -227.1522)
		(width 0.1143)
		(layer "In13.Cu")
		(net "GMI_CPU0_G0_CPU1_G2_TX_DP<11>")
	)
	(segment
		(start 122.734324 -222.27032)
		(end 122.733308 -222.269558)
		(width 0.1143)
		(layer "In13.Cu")
		(net "GMI_CPU0_G0_CPU1_G2_TX_DP<11>")
	)
	(segment
		(start 122.771916 -223.911922)
		(end 122.7709 -223.911414)
		(width 0.1143)
		(layer "In13.Cu")
		(net "GMI_CPU0_G0_CPU1_G2_TX_DP<11>")
	)
	(segment
		(start 122.775472 -230.394002)
		(end 122.773948 -230.39324)
		(width 0.1143)
		(layer "In13.Cu")
		(net "GMI_CPU0_G0_CPU1_G2_TX_DP<11>")
	)
	(segment
		(start 348.692216 -234.258358)
		(end 348.723204 -234.276138)
		(width 0.1143)
		(layer "In13.Cu")
		(net "GMI_CPU0_G0_CPU1_G2_TX_DP<11>")
	)
	(segment
		(start 122.803412 -222.310198)
		(end 122.73534 -222.270828)
		(width 0.1143)
		(layer "In13.Cu")
		(net "GMI_CPU0_G0_CPU1_G2_TX_DP<11>")
	)
	(segment
		(start 122.497088 -239.541812)
		(end 122.501406 -239.518444)
		(width 0.1143)
		(layer "In13.Cu")
		(net "GMI_CPU0_G0_CPU1_G2_TX_DP<11>")
	)
	(segment
		(start 122.771916 -225.531934)
		(end 122.7709 -225.531426)
		(width 0.1143)
		(layer "In13.Cu")
		(net "GMI_CPU0_G0_CPU1_G2_TX_DP<11>")
	)
	(segment
		(start 349.083122 -239.624108)
		(end 349.381064 -239.624108)
		(width 0.1143)
		(layer "In13.Cu")
		(net "GMI_CPU0_G0_CPU1_G2_TX_DP<11>")
	)
	(segment
		(start 122.701304 -232.703878)
		(end 122.705368 -232.700322)
		(width 0.1143)
		(layer "In13.Cu")
		(net "GMI_CPU0_G0_CPU1_G2_TX_DP<11>")
	)
	(segment
		(start 122.772678 -225.532442)
		(end 122.771916 -225.531934)
		(width 0.1143)
		(layer "In13.Cu")
		(net "GMI_CPU0_G0_CPU1_G2_TX_DP<11>")
	)
	(segment
		(start 348.692216 -232.029762)
		(end 348.68485 -232.035096)
		(width 0.1143)
		(layer "In13.Cu")
		(net "GMI_CPU0_G0_CPU1_G2_TX_DP<11>")
	)
	(segment
		(start 306.42687 -185.13298)
		(end 307.390292 -185.531252)
		(width 0.14224)
		(layer "In13.Cu")
		(net "GMI_CPU0_G0_CPU1_G2_TX_DP<11>")
	)
	(segment
		(start 122.7328 -222.95993)
		(end 122.736864 -222.957136)
		(width 0.1143)
		(layer "In13.Cu")
		(net "GMI_CPU0_G0_CPU1_G2_TX_DP<11>")
	)
	(segment
		(start 348.723966 -223.911668)
		(end 348.723204 -223.912176)
		(width 0.1143)
		(layer "In13.Cu")
		(net "GMI_CPU0_G0_CPU1_G2_TX_DP<11>")
	)
	(segment
		(start 348.731078 -234.28071)
		(end 348.732602 -234.281726)
		(width 0.1143)
		(layer "In13.Cu")
		(net "GMI_CPU0_G0_CPU1_G2_TX_DP<11>")
	)
	(segment
		(start 122.771916 -226.177094)
		(end 122.772678 -226.176586)
		(width 0.1143)
		(layer "In13.Cu")
		(net "GMI_CPU0_G0_CPU1_G2_TX_DP<11>")
	)
	(segment
		(start 122.771662 -238.491776)
		(end 122.73534 -238.470694)
		(width 0.1143)
		(layer "In13.Cu")
		(net "GMI_CPU0_G0_CPU1_G2_TX_DP<11>")
	)
	(segment
		(start 122.767852 -233.6292)
		(end 122.727974 -233.60634)
		(width 0.1143)
		(layer "In13.Cu")
		(net "GMI_CPU0_G0_CPU1_G2_TX_DP<11>")
	)
	(segment
		(start 122.727974 -233.60634)
		(end 122.69216 -233.577638)
		(width 0.1143)
		(layer "In13.Cu")
		(net "GMI_CPU0_G0_CPU1_G2_TX_DP<11>")
	)
	(segment
		(start 122.811032 -232.03535)
		(end 122.803666 -232.030016)
		(width 0.1143)
		(layer "In13.Cu")
		(net "GMI_CPU0_G0_CPU1_G2_TX_DP<11>")
	)
	(segment
		(start 122.764804 -234.280964)
		(end 122.769376 -234.278424)
		(width 0.1143)
		(layer "In13.Cu")
		(net "GMI_CPU0_G0_CPU1_G2_TX_DP<11>")
	)
	(segment
		(start 122.772678 -234.276392)
		(end 122.803666 -234.258612)
		(width 0.1143)
		(layer "In13.Cu")
		(net "GMI_CPU0_G0_CPU1_G2_TX_DP<11>")
	)
	(segment
		(start 122.803666 -232.6386)
		(end 122.811032 -232.633266)
		(width 0.1143)
		(layer "In13.Cu")
		(net "GMI_CPU0_G0_CPU1_G2_TX_DP<11>")
	)
	(segment
		(start 348.759018 -222.956882)
		(end 348.763082 -222.959676)
		(width 0.1143)
		(layer "In13.Cu")
		(net "GMI_CPU0_G0_CPU1_G2_TX_DP<11>")
	)
	(segment
		(start 349.006414 -221.579948)
		(end 349.006414 -221.868746)
		(width 0.1143)
		(layer "In13.Cu")
		(net "GMI_CPU0_G0_CPU1_G2_TX_DP<11>")
	)
	(segment
		(start 348.760542 -236.850428)
		(end 348.72422 -236.87151)
		(width 0.1143)
		(layer "In13.Cu")
		(net "GMI_CPU0_G0_CPU1_G2_TX_DP<11>")
	)
	(segment
		(start 122.76328 -234.28198)
		(end 122.764804 -234.280964)
		(width 0.1143)
		(layer "In13.Cu")
		(net "GMI_CPU0_G0_CPU1_G2_TX_DP<11>")
	)
	(segment
		(start 348.760542 -238.47044)
		(end 348.72422 -238.491522)
		(width 0.1143)
		(layer "In13.Cu")
		(net "GMI_CPU0_G0_CPU1_G2_TX_DP<11>")
	)
	(segment
		(start 122.771916 -232.011728)
		(end 122.7709 -232.01122)
		(width 0.1143)
		(layer "In13.Cu")
		(net "GMI_CPU0_G0_CPU1_G2_TX_DP<11>")
	)
	(segment
		(start 348.724982 -227.79736)
		(end 348.729554 -227.800154)
		(width 0.1143)
		(layer "In13.Cu")
		(net "GMI_CPU0_G0_CPU1_G2_TX_DP<11>")
	)
	(segment
		(start 122.7709 -234.277408)
		(end 122.771916 -234.2769)
		(width 0.1143)
		(layer "In13.Cu")
		(net "GMI_CPU0_G0_CPU1_G2_TX_DP<11>")
	)
	(segment
		(start 348.723966 -230.391716)
		(end 348.723204 -230.392224)
		(width 0.1143)
		(layer "In13.Cu")
		(net "GMI_CPU0_G0_CPU1_G2_TX_DP<11>")
	)
	(segment
		(start 348.755462 -223.89338)
		(end 348.724982 -223.91116)
		(width 0.1143)
		(layer "In13.Cu")
		(net "GMI_CPU0_G0_CPU1_G2_TX_DP<11>")
	)
	(segment
		(start 348.726506 -234.27817)
		(end 348.731078 -234.28071)
		(width 0.1143)
		(layer "In13.Cu")
		(net "GMI_CPU0_G0_CPU1_G2_TX_DP<11>")
	)
	(segment
		(start 122.772678 -235.25226)
		(end 122.771916 -235.251752)
		(width 0.1143)
		(layer "In13.Cu")
		(net "GMI_CPU0_G0_CPU1_G2_TX_DP<11>")
	)
	(segment
		(start 348.720156 -228.77399)
		(end 348.719902 -228.77399)
		(width 0.1143)
		(layer "In13.Cu")
		(net "GMI_CPU0_G0_CPU1_G2_TX_DP<11>")
	)
	(segment
		(start 348.723204 -223.912176)
		(end 348.692216 -223.929956)
		(width 0.1143)
		(layer "In13.Cu")
		(net "GMI_CPU0_G0_CPU1_G2_TX_DP<11>")
	)
	(segment
		(start 122.768106 -226.179126)
		(end 122.769122 -226.178618)
		(width 0.1143)
		(layer "In13.Cu")
		(net "GMI_CPU0_G0_CPU1_G2_TX_DP<11>")
	)
	(segment
		(start 348.723204 -227.796344)
		(end 348.723966 -227.796852)
		(width 0.1143)
		(layer "In13.Cu")
		(net "GMI_CPU0_G0_CPU1_G2_TX_DP<11>")
	)
	(segment
		(start 348.692216 -226.158552)
		(end 348.723204 -226.176332)
		(width 0.1143)
		(layer "In13.Cu")
		(net "GMI_CPU0_G0_CPU1_G2_TX_DP<11>")
	)
	(segment
		(start 348.718886 -231.033828)
		(end 348.763082 -231.059482)
		(width 0.1143)
		(layer "In13.Cu")
		(net "GMI_CPU0_G0_CPU1_G2_TX_DP<11>")
	)
	(segment
		(start 122.803666 -233.650028)
		(end 122.772678 -233.632248)
		(width 0.1143)
		(layer "In13.Cu")
		(net "GMI_CPU0_G0_CPU1_G2_TX_DP<11>")
	)
	(segment
		(start 122.812048 -235.276136)
		(end 122.803666 -235.27004)
		(width 0.1143)
		(layer "In13.Cu")
		(net "GMI_CPU0_G0_CPU1_G2_TX_DP<11>")
	)
	(segment
		(start 314.258452 -189.817756)
		(end 347.28277 -216.89695)
		(width 0.14224)
		(layer "In13.Cu")
		(net "GMI_CPU0_G0_CPU1_G2_TX_DP<11>")
	)
	(segment
		(start 122.771916 -227.151946)
		(end 122.7709 -227.151438)
		(width 0.1143)
		(layer "In13.Cu")
		(net "GMI_CPU0_G0_CPU1_G2_TX_DP<11>")
	)
	(segment
		(start 122.803666 -234.258612)
		(end 122.812048 -234.252516)
		(width 0.1143)
		(layer "In13.Cu")
		(net "GMI_CPU0_G0_CPU1_G2_TX_DP<11>")
	)
	(segment
		(start 348.756224 -231.992678)
		(end 348.755462 -231.993186)
		(width 0.1143)
		(layer "In13.Cu")
		(net "GMI_CPU0_G0_CPU1_G2_TX_DP<11>")
	)
	(segment
		(start 348.691454 -228.790246)
		(end 348.6912 -228.790754)
		(width 0.1143)
		(layer "In13.Cu")
		(net "GMI_CPU0_G0_CPU1_G2_TX_DP<11>")
	)
	(segment
		(start 348.692216 -235.269786)
		(end 348.683834 -235.275882)
		(width 0.1143)
		(layer "In13.Cu")
		(net "GMI_CPU0_G0_CPU1_G2_TX_DP<11>")
	)
	(segment
		(start 122.814334 -225.557842)
		(end 122.803666 -225.550222)
		(width 0.1143)
		(layer "In13.Cu")
		(net "GMI_CPU0_G0_CPU1_G2_TX_DP<11>")
	)
	(segment
		(start 348.756224 -228.752908)
		(end 348.755462 -228.753416)
		(width 0.1143)
		(layer "In13.Cu")
		(net "GMI_CPU0_G0_CPU1_G2_TX_DP<11>")
	)
	(segment
		(start 348.779084 -232.691178)
		(end 348.801436 -232.709212)
		(width 0.1143)
		(layer "In13.Cu")
		(net "GMI_CPU0_G0_CPU1_G2_TX_DP<11>")
	)
	(segment
		(start 348.723204 -226.176332)
		(end 348.723966 -226.17684)
		(width 0.1143)
		(layer "In13.Cu")
		(net "GMI_CPU0_G0_CPU1_G2_TX_DP<11>")
	)
	(segment
		(start 122.823224 -227.184204)
		(end 122.803666 -227.170234)
		(width 0.1143)
		(layer "In13.Cu")
		(net "GMI_CPU0_G0_CPU1_G2_TX_DP<11>")
	)
	(segment
		(start 122.7328 -227.819966)
		(end 122.766328 -227.800408)
		(width 0.1143)
		(layer "In13.Cu")
		(net "GMI_CPU0_G0_CPU1_G2_TX_DP<11>")
	)
	(segment
		(start 348.784164 -233.593132)
		(end 348.783402 -233.59364)
		(width 0.1143)
		(layer "In13.Cu")
		(net "GMI_CPU0_G0_CPU1_G2_TX_DP<11>")
	)
	(segment
		(start 122.771662 -237.516924)
		(end 122.803412 -237.498636)
		(width 0.1143)
		(layer "In13.Cu")
		(net "GMI_CPU0_G0_CPU1_G2_TX_DP<11>")
	)
	(segment
		(start 348.756224 -225.512884)
		(end 348.755462 -225.513392)
		(width 0.1143)
		(layer "In13.Cu")
		(net "GMI_CPU0_G0_CPU1_G2_TX_DP<11>")
	)
	(segment
		(start 122.772678 -227.152454)
		(end 122.771916 -227.151946)
		(width 0.1143)
		(layer "In13.Cu")
		(net "GMI_CPU0_G0_CPU1_G2_TX_DP<11>")
	)
	(segment
		(start 122.769376 -234.278424)
		(end 122.7709 -234.277408)
		(width 0.1143)
		(layer "In13.Cu")
		(net "GMI_CPU0_G0_CPU1_G2_TX_DP<11>")
	)
	(segment
		(start 122.715274 -232.692448)
		(end 122.716798 -232.691178)
		(width 0.1143)
		(layer "In13.Cu")
		(net "GMI_CPU0_G0_CPU1_G2_TX_DP<11>")
	)
	(segment
		(start 122.772678 -228.772466)
		(end 122.771916 -228.771958)
		(width 0.1143)
		(layer "In13.Cu")
		(net "GMI_CPU0_G0_CPU1_G2_TX_DP<11>")
	)
	(segment
		(start 122.74042 -227.133658)
		(end 122.739658 -227.13315)
		(width 0.1143)
		(layer "In13.Cu")
		(net "GMI_CPU0_G0_CPU1_G2_TX_DP<11>")
	)
	(segment
		(start 348.767908 -235.226098)
		(end 348.725744 -235.250482)
		(width 0.1143)
		(layer "In13.Cu")
		(net "GMI_CPU0_G0_CPU1_G2_TX_DP<11>")
	)
	(segment
		(start 349.00616 -221.401894)
		(end 349.00616 -221.579694)
		(width 0.1143)
		(layer "In13.Cu")
		(net "GMI_CPU0_G0_CPU1_G2_TX_DP<11>")
	)
	(segment
		(start 122.772678 -224.556574)
		(end 122.803666 -224.538794)
		(width 0.1143)
		(layer "In13.Cu")
		(net "GMI_CPU0_G0_CPU1_G2_TX_DP<11>")
	)
	(segment
		(start 122.772678 -227.796598)
		(end 122.803666 -227.778818)
		(width 0.1143)
		(layer "In13.Cu")
		(net "GMI_CPU0_G0_CPU1_G2_TX_DP<11>")
	)
	(segment
		(start 122.771916 -235.251752)
		(end 122.7709 -235.251244)
		(width 0.1143)
		(layer "In13.Cu")
		(net "GMI_CPU0_G0_CPU1_G2_TX_DP<11>")
	)
	(segment
		(start 348.801944 -233.578654)
		(end 348.784164 -233.593132)
		(width 0.1143)
		(layer "In13.Cu")
		(net "GMI_CPU0_G0_CPU1_G2_TX_DP<11>")
	)
	(segment
		(start 348.723966 -226.17684)
		(end 348.724982 -226.177348)
		(width 0.1143)
		(layer "In13.Cu")
		(net "GMI_CPU0_G0_CPU1_G2_TX_DP<11>")
	)
	(segment
		(start 348.723966 -232.011474)
		(end 348.723204 -232.011982)
		(width 0.1143)
		(layer "In13.Cu")
		(net "GMI_CPU0_G0_CPU1_G2_TX_DP<11>")
	)
	(segment
		(start 122.771916 -232.656888)
		(end 122.772678 -232.65638)
		(width 0.1143)
		(layer "In13.Cu")
		(net "GMI_CPU0_G0_CPU1_G2_TX_DP<11>")
	)
	(segment
		(start 348.724982 -226.177348)
		(end 348.72676 -226.178364)
		(width 0.1143)
		(layer "In13.Cu")
		(net "GMI_CPU0_G0_CPU1_G2_TX_DP<11>")
	)
	(segment
		(start 122.764804 -232.660952)
		(end 122.769376 -232.658412)
		(width 0.1143)
		(layer "In13.Cu")
		(net "GMI_CPU0_G0_CPU1_G2_TX_DP<11>")
	)
	(segment
		(start 348.724982 -232.010966)
		(end 348.723966 -232.011474)
		(width 0.1143)
		(layer "In13.Cu")
		(net "GMI_CPU0_G0_CPU1_G2_TX_DP<11>")
	)
	(segment
		(start 349.010732 -239.611408)
		(end 349.083122 -239.624108)
		(width 0.1143)
		(layer "In13.Cu")
		(net "GMI_CPU0_G0_CPU1_G2_TX_DP<11>")
	)
	(segment
		(start 348.724728 -229.416864)
		(end 348.72549 -229.417372)
		(width 0.1143)
		(layer "In13.Cu")
		(net "GMI_CPU0_G0_CPU1_G2_TX_DP<11>")
	)
	(segment
		(start 348.72422 -235.896658)
		(end 348.760542 -235.91774)
		(width 0.1143)
		(layer "In13.Cu")
		(net "GMI_CPU0_G0_CPU1_G2_TX_DP<11>")
	)
	(segment
		(start 348.723966 -228.771704)
		(end 348.723204 -228.772212)
		(width 0.1143)
		(layer "In13.Cu")
		(net "GMI_CPU0_G0_CPU1_G2_TX_DP<11>")
	)
	(segment
		(start 348.69247 -222.918528)
		(end 348.759018 -222.956882)
		(width 0.1143)
		(layer "In13.Cu")
		(net "GMI_CPU0_G0_CPU1_G2_TX_DP<11>")
	)
	(segment
		(start 348.72676 -226.178364)
		(end 348.727776 -226.178872)
		(width 0.1143)
		(layer "In13.Cu")
		(net "GMI_CPU0_G0_CPU1_G2_TX_DP<11>")
	)
	(segment
		(start 348.536514 -229.093776)
		(end 348.53626 -229.093522)
		(width 0.1143)
		(layer "In13.Cu")
		(net "GMI_CPU0_G0_CPU1_G2_TX_DP<11>")
	)
	(segment
		(start 348.723966 -234.276646)
		(end 348.724982 -234.277154)
		(width 0.1143)
		(layer "In13.Cu")
		(net "GMI_CPU0_G0_CPU1_G2_TX_DP<11>")
	)
	(segment
		(start 122.803666 -232.030016)
		(end 122.772678 -232.012236)
		(width 0.1143)
		(layer "In13.Cu")
		(net "GMI_CPU0_G0_CPU1_G2_TX_DP<11>")
	)
	(segment
		(start 145.224754 -199.550528)
		(end 147.138136 -198.9709)
		(width 0.14224)
		(layer "In13.Cu")
		(net "GMI_CPU0_G0_CPU1_G2_TX_DP<11>")
	)
	(segment
		(start 348.692216 -227.16998)
		(end 348.672658 -227.18395)
		(width 0.1143)
		(layer "In13.Cu")
		(net "GMI_CPU0_G0_CPU1_G2_TX_DP<11>")
	)
	(segment
		(start 122.73534 -235.917994)
		(end 122.771662 -235.896912)
		(width 0.1143)
		(layer "In13.Cu")
		(net "GMI_CPU0_G0_CPU1_G2_TX_DP<11>")
	)
	(segment
		(start 122.7074 -232.698798)
		(end 122.708162 -232.698036)
		(width 0.1143)
		(layer "In13.Cu")
		(net "GMI_CPU0_G0_CPU1_G2_TX_DP<11>")
	)
	(segment
		(start 147.138136 -198.9709)
		(end 163.189666 -185.809382)
		(width 0.14224)
		(layer "In13.Cu")
		(net "GMI_CPU0_G0_CPU1_G2_TX_DP<11>")
	)
	(segment
		(start 122.769376 -232.658412)
		(end 122.7709 -232.657396)
		(width 0.1143)
		(layer "In13.Cu")
		(net "GMI_CPU0_G0_CPU1_G2_TX_DP<11>")
	)
	(segment
		(start 348.763082 -228.748844)
		(end 348.756224 -228.752908)
		(width 0.1143)
		(layer "In13.Cu")
		(net "GMI_CPU0_G0_CPU1_G2_TX_DP<11>")
	)
	(segment
		(start 122.7709 -232.657396)
		(end 122.771916 -232.656888)
		(width 0.1143)
		(layer "In13.Cu")
		(net "GMI_CPU0_G0_CPU1_G2_TX_DP<11>")
	)
	(segment
		(start 348.724982 -227.151184)
		(end 348.723966 -227.151692)
		(width 0.1143)
		(layer "In13.Cu")
		(net "GMI_CPU0_G0_CPU1_G2_TX_DP<11>")
	)
	(segment
		(start 348.723204 -235.252006)
		(end 348.692216 -235.269786)
		(width 0.1143)
		(layer "In13.Cu")
		(net "GMI_CPU0_G0_CPU1_G2_TX_DP<11>")
	)
	(segment
		(start 122.771916 -234.2769)
		(end 122.772678 -234.276392)
		(width 0.1143)
		(layer "In13.Cu")
		(net "GMI_CPU0_G0_CPU1_G2_TX_DP<11>")
	)
	(segment
		(start 348.73057 -226.180396)
		(end 348.732856 -226.181666)
		(width 0.1143)
		(layer "In13.Cu")
		(net "GMI_CPU0_G0_CPU1_G2_TX_DP<11>")
	)
	(segment
		(start 122.775726 -228.774244)
		(end 122.772678 -228.772466)
		(width 0.1143)
		(layer "In13.Cu")
		(net "GMI_CPU0_G0_CPU1_G2_TX_DP<11>")
	)
	(segment
		(start 348.732856 -226.181666)
		(end 348.73438 -226.182682)
		(width 0.1143)
		(layer "In13.Cu")
		(net "GMI_CPU0_G0_CPU1_G2_TX_DP<11>")
	)
	(segment
		(start 122.708162 -232.698036)
		(end 122.710956 -232.69575)
		(width 0.1143)
		(layer "In13.Cu")
		(net "GMI_CPU0_G0_CPU1_G2_TX_DP<11>")
	)
	(segment
		(start 122.739658 -225.513138)
		(end 122.7328 -225.509074)
		(width 0.1143)
		(layer "In13.Cu")
		(net "GMI_CPU0_G0_CPU1_G2_TX_DP<11>")
	)
	(segment
		(start 122.812048 -233.656124)
		(end 122.803666 -233.650028)
		(width 0.1143)
		(layer "In13.Cu")
		(net "GMI_CPU0_G0_CPU1_G2_TX_DP<11>")
	)
	(segment
		(start 348.723966 -224.556828)
		(end 348.724982 -224.557336)
		(width 0.1143)
		(layer "In13.Cu")
		(net "GMI_CPU0_G0_CPU1_G2_TX_DP<11>")
	)
	(segment
		(start 122.7709 -228.77145)
		(end 122.74042 -228.75367)
		(width 0.1143)
		(layer "In13.Cu")
		(net "GMI_CPU0_G0_CPU1_G2_TX_DP<11>")
	)
	(segment
		(start 122.7328 -226.199954)
		(end 122.761502 -226.182936)
		(width 0.1143)
		(layer "In13.Cu")
		(net "GMI_CPU0_G0_CPU1_G2_TX_DP<11>")
	)
	(segment
		(start 122.74042 -225.513646)
		(end 122.739658 -225.513138)
		(width 0.1143)
		(layer "In13.Cu")
		(net "GMI_CPU0_G0_CPU1_G2_TX_DP<11>")
	)
	(segment
		(start 302.886872 -185.13298)
		(end 306.42687 -185.13298)
		(width 0.14224)
		(layer "In13.Cu")
		(net "GMI_CPU0_G0_CPU1_G2_TX_DP<11>")
	)
	(segment
		(start 348.723204 -234.276138)
		(end 348.723966 -234.276646)
		(width 0.1143)
		(layer "In13.Cu")
		(net "GMI_CPU0_G0_CPU1_G2_TX_DP<11>")
	)
	(segment
		(start 348.723966 -233.631486)
		(end 348.723204 -233.631994)
		(width 0.1143)
		(layer "In13.Cu")
		(net "GMI_CPU0_G0_CPU1_G2_TX_DP<11>")
	)
	(segment
		(start 348.755462 -227.133404)
		(end 348.724982 -227.151184)
		(width 0.1143)
		(layer "In13.Cu")
		(net "GMI_CPU0_G0_CPU1_G2_TX_DP<11>")
	)
	(segment
		(start 348.723966 -235.251498)
		(end 348.723204 -235.252006)
		(width 0.1143)
		(layer "In13.Cu")
		(net "GMI_CPU0_G0_CPU1_G2_TX_DP<11>")
	)
	(segment
		(start 348.692216 -224.53854)
		(end 348.723204 -224.55632)
		(width 0.1143)
		(layer "In13.Cu")
		(net "GMI_CPU0_G0_CPU1_G2_TX_DP<11>")
	)
	(segment
		(start 122.803412 -236.890052)
		(end 122.771662 -236.871764)
		(width 0.1143)
		(layer "In13.Cu")
		(net "GMI_CPU0_G0_CPU1_G2_TX_DP<11>")
	)
	(segment
		(start 122.714258 -232.69321)
		(end 122.715274 -232.692448)
		(width 0.1143)
		(layer "In13.Cu")
		(net "GMI_CPU0_G0_CPU1_G2_TX_DP<11>")
	)
	(segment
		(start 167.271446 -184.349898)
		(end 168.366948 -184.349898)
		(width 0.14224)
		(layer "In13.Cu")
		(net "GMI_CPU0_G0_CPU1_G2_TX_DP<11>")
	)
	(segment
		(start 348.72041 -230.393748)
		(end 348.692216 -230.410004)
		(width 0.1143)
		(layer "In13.Cu")
		(net "GMI_CPU0_G0_CPU1_G2_TX_DP<11>")
	)
	(segment
		(start 122.7328 -224.579942)
		(end 122.7709 -224.55759)
		(width 0.1143)
		(layer "In13.Cu")
		(net "GMI_CPU0_G0_CPU1_G2_TX_DP<11>")
	)
	(segment
		(start 348.53626 -229.093522)
		(end 348.53626 -229.094284)
		(width 0.1143)
		(layer "In13.Cu")
		(net "GMI_CPU0_G0_CPU1_G2_TX_DP<11>")
	)
	(segment
		(start 348.723204 -224.55632)
		(end 348.723966 -224.556828)
		(width 0.1143)
		(layer "In13.Cu")
		(net "GMI_CPU0_G0_CPU1_G2_TX_DP<11>")
	)
	(segment
		(start 348.756224 -223.892872)
		(end 348.755462 -223.89338)
		(width 0.1143)
		(layer "In13.Cu")
		(net "GMI_CPU0_G0_CPU1_G2_TX_DP<11>")
	)
	(segment
		(start 122.712734 -232.694226)
		(end 122.714258 -232.69321)
		(width 0.1143)
		(layer "In13.Cu")
		(net "GMI_CPU0_G0_CPU1_G2_TX_DP<11>")
	)
	(segment
		(start 348.719902 -228.77399)
		(end 348.691454 -228.790246)
		(width 0.1143)
		(layer "In13.Cu")
		(net "GMI_CPU0_G0_CPU1_G2_TX_DP<11>")
	)
	(segment
		(start 348.692216 -233.649774)
		(end 348.683834 -233.65587)
		(width 0.1143)
		(layer "In13.Cu")
		(net "GMI_CPU0_G0_CPU1_G2_TX_DP<11>")
	)
	(segment
		(start 122.771916 -227.797106)
		(end 122.772678 -227.796598)
		(width 0.1143)
		(layer "In13.Cu")
		(net "GMI_CPU0_G0_CPU1_G2_TX_DP<11>")
	)
	(segment
		(start 122.771916 -228.771958)
		(end 122.7709 -228.77145)
		(width 0.1143)
		(layer "In13.Cu")
		(net "GMI_CPU0_G0_CPU1_G2_TX_DP<11>")
	)
	(segment
		(start 349.071692 -221.093538)
		(end 349.071692 -221.100142)
		(width 0.1143)
		(layer "In13.Cu")
		(net "GMI_CPU0_G0_CPU1_G2_TX_DP<11>")
	)
	(segment
		(start 122.7328 -231.059736)
		(end 122.776996 -231.034082)
		(width 0.1143)
		(layer "In13.Cu")
		(net "GMI_CPU0_G0_CPU1_G2_TX_DP<11>")
	)
	(segment
		(start 122.7328 -232.679748)
		(end 122.736356 -232.677716)
		(width 0.1143)
		(layer "In13.Cu")
		(net "GMI_CPU0_G0_CPU1_G2_TX_DP<11>")
	)
	(segment
		(start 122.74042 -231.99344)
		(end 122.739658 -231.992932)
		(width 0.1143)
		(layer "In13.Cu")
		(net "GMI_CPU0_G0_CPU1_G2_TX_DP<11>")
	)
	(segment
		(start 122.739658 -228.753162)
		(end 122.7328 -228.749098)
		(width 0.1143)
		(layer "In13.Cu")
		(net "GMI_CPU0_G0_CPU1_G2_TX_DP<11>")
	)
	(segment
		(start 122.772678 -232.012236)
		(end 122.771916 -232.011728)
		(width 0.1143)
		(layer "In13.Cu")
		(net "GMI_CPU0_G0_CPU1_G2_TX_DP<11>")
	)
	(segment
		(start 168.366948 -184.349898)
		(end 302.606456 -185.131202)
		(width 0.14224)
		(layer "In13.Cu")
		(net "GMI_CPU0_G0_CPU1_G2_TX_DP<11>")
	)
	(segment
		(start 122.773948 -230.39324)
		(end 122.772678 -230.392478)
		(width 0.1143)
		(layer "In13.Cu")
		(net "GMI_CPU0_G0_CPU1_G2_TX_DP<11>")
	)
	(segment
		(start 349.025972 -221.382082)
		(end 349.00616 -221.401894)
		(width 0.1143)
		(layer "In13.Cu")
		(net "GMI_CPU0_G0_CPU1_G2_TX_DP<11>")
	)
	(segment
		(start 122.7709 -226.177602)
		(end 122.771916 -226.177094)
		(width 0.1143)
		(layer "In13.Cu")
		(net "GMI_CPU0_G0_CPU1_G2_TX_DP<11>")
	)
	(segment
		(start 348.755462 -233.613198)
		(end 348.724982 -233.630978)
		(width 0.1143)
		(layer "In13.Cu")
		(net "GMI_CPU0_G0_CPU1_G2_TX_DP<11>")
	)
	(segment
		(start 122.739658 -231.992932)
		(end 122.7328 -231.988868)
		(width 0.1143)
		(layer "In13.Cu")
		(net "GMI_CPU0_G0_CPU1_G2_TX_DP<11>")
	)
	(segment
		(start 348.727268 -230.389684)
		(end 348.723966 -230.391716)
		(width 0.1143)
		(layer "In13.Cu")
		(net "GMI_CPU0_G0_CPU1_G2_TX_DP<11>")
	)
	(segment
		(start 122.7709 -227.151438)
		(end 122.74042 -227.133658)
		(width 0.1143)
		(layer "In13.Cu")
		(net "GMI_CPU0_G0_CPU1_G2_TX_DP<11>")
	)
	(segment
		(start 122.771662 -222.93707)
		(end 122.803412 -222.918782)
		(width 0.1143)
		(layer "In13.Cu")
		(net "GMI_CPU0_G0_CPU1_G2_TX_DP<11>")
	)
	(segment
		(start 348.72422 -237.51667)
		(end 348.760542 -237.537752)
		(width 0.1143)
		(layer "In13.Cu")
		(net "GMI_CPU0_G0_CPU1_G2_TX_DP<11>")
	)
	(segment
		(start 122.766328 -227.800408)
		(end 122.7709 -227.797614)
		(width 0.1143)
		(layer "In13.Cu")
		(net "GMI_CPU0_G0_CPU1_G2_TX_DP<11>")
	)
	(segment
		(start 122.772678 -226.176586)
		(end 122.803666 -226.158806)
		(width 0.1143)
		(layer "In13.Cu")
		(net "GMI_CPU0_G0_CPU1_G2_TX_DP<11>")
	)
	(segment
		(start 122.7709 -235.251244)
		(end 122.767344 -235.249212)
		(width 0.1143)
		(layer "In13.Cu")
		(net "GMI_CPU0_G0_CPU1_G2_TX_DP<11>")
	)
	(segment
		(start 122.771916 -230.39197)
		(end 122.768614 -230.389938)
		(width 0.1143)
		(layer "In13.Cu")
		(net "GMI_CPU0_G0_CPU1_G2_TX_DP<11>")
	)
	(segment
		(start 122.74042 -223.893634)
		(end 122.739658 -223.893126)
		(width 0.1143)
		(layer "In13.Cu")
		(net "GMI_CPU0_G0_CPU1_G2_TX_DP<11>")
	)
	(segment
		(start 348.672658 -227.764594)
		(end 348.692216 -227.778564)
		(width 0.1143)
		(layer "In13.Cu")
		(net "GMI_CPU0_G0_CPU1_G2_TX_DP<11>")
	)
	(segment
		(start 122.803666 -230.410258)
		(end 122.775472 -230.394002)
		(width 0.1143)
		(layer "In13.Cu")
		(net "GMI_CPU0_G0_CPU1_G2_TX_DP<11>")
	)
	(segment
		(start 122.959622 -229.094538)
		(end 122.959622 -229.093776)
		(width 0.1143)
		(layer "In13.Cu")
		(net "GMI_CPU0_G0_CPU1_G2_TX_DP<11>")
	)
	(segment
		(start 348.723966 -227.796852)
		(end 348.724982 -227.79736)
		(width 0.1143)
		(layer "In13.Cu")
		(net "GMI_CPU0_G0_CPU1_G2_TX_DP<11>")
	)
	(segment
		(start 348.724982 -233.630978)
		(end 348.723966 -233.631486)
		(width 0.1143)
		(layer "In13.Cu")
		(net "GMI_CPU0_G0_CPU1_G2_TX_DP<11>")
	)
	(segment
		(start 122.771916 -224.557082)
		(end 122.772678 -224.556574)
		(width 0.1143)
		(layer "In13.Cu")
		(net "GMI_CPU0_G0_CPU1_G2_TX_DP<11>")
	)
	(segment
		(start 122.739658 -227.13315)
		(end 122.7328 -227.129086)
		(width 0.1143)
		(layer "In13.Cu")
		(net "GMI_CPU0_G0_CPU1_G2_TX_DP<11>")
	)
	(segment
		(start 122.46991 -221.146116)
		(end 122.42419 -221.100396)
		(width 0.1143)
		(layer "In13.Cu")
		(net "GMI_CPU0_G0_CPU1_G2_TX_DP<11>")
	)
	(segment
		(start 122.803666 -226.158806)
		(end 122.814334 -226.151186)
		(width 0.1143)
		(layer "In13.Cu")
		(net "GMI_CPU0_G0_CPU1_G2_TX_DP<11>")
	)
	(segment
		(start 122.761502 -226.182936)
		(end 122.763026 -226.18192)
		(width 0.1143)
		(layer "In13.Cu")
		(net "GMI_CPU0_G0_CPU1_G2_TX_DP<11>")
	)
	(segment
		(start 122.803666 -227.778818)
		(end 122.823224 -227.764848)
		(width 0.1143)
		(layer "In13.Cu")
		(net "GMI_CPU0_G0_CPU1_G2_TX_DP<11>")
	)
	(segment
		(start 122.771662 -239.136936)
		(end 122.803412 -239.118648)
		(width 0.1143)
		(layer "In13.Cu")
		(net "GMI_CPU0_G0_CPU1_G2_TX_DP<11>")
	)
	(segment
		(start 122.42419 -221.071948)
		(end 122.42419 -220.070934)
		(width 0.14224)
		(layer "In13.Cu")
		(net "GMI_CPU0_G0_CPU1_G2_TX_DP<11>")
	)
	(segment
		(start 122.7709 -227.797614)
		(end 122.771916 -227.797106)
		(width 0.1143)
		(layer "In13.Cu")
		(net "GMI_CPU0_G0_CPU1_G2_TX_DP<11>")
	)
	(segment
		(start 122.736356 -232.677716)
		(end 122.76328 -232.661968)
		(width 0.1143)
		(layer "In13.Cu")
		(net "GMI_CPU0_G0_CPU1_G2_TX_DP<11>")
	)
	(segment
		(start 348.77883 -234.310936)
		(end 348.798642 -234.326684)
		(width 0.1143)
		(layer "In13.Cu")
		(net "GMI_CPU0_G0_CPU1_G2_TX_DP<11>")
	)
	(segment
		(start 349.025972 -221.145862)
		(end 349.025972 -221.382082)
		(width 0.1143)
		(layer "In13.Cu")
		(net "GMI_CPU0_G0_CPU1_G2_TX_DP<11>")
	)
	(segment
		(start 348.724982 -234.277154)
		(end 348.726506 -234.27817)
		(width 0.1143)
		(layer "In13.Cu")
		(net "GMI_CPU0_G0_CPU1_G2_TX_DP<11>")
	)
	(segment
		(start 348.801436 -232.709212)
		(end 348.802198 -232.70972)
		(width 0.1143)
		(layer "In13.Cu")
		(net "GMI_CPU0_G0_CPU1_G2_TX_DP<11>")
	)
	(segment
		(start 307.390292 -185.531252)
		(end 314.258452 -189.817756)
		(width 0.14224)
		(layer "In13.Cu")
		(net "GMI_CPU0_G0_CPU1_G2_TX_DP<11>")
	)
	(segment
		(start 122.73534 -237.538006)
		(end 122.771662 -237.516924)
		(width 0.1143)
		(layer "In13.Cu")
		(net "GMI_CPU0_G0_CPU1_G2_TX_DP<11>")
	)
	(segment
		(start 348.724982 -225.531172)
		(end 348.723966 -225.53168)
		(width 0.1143)
		(layer "In13.Cu")
		(net "GMI_CPU0_G0_CPU1_G2_TX_DP<11>")
	)
	(segment
		(start 124.441458 -216.59215)
		(end 145.224754 -199.550528)
		(width 0.14224)
		(layer "In13.Cu")
		(net "GMI_CPU0_G0_CPU1_G2_TX_DP<11>")
	)
	(segment
		(start 122.705368 -232.700322)
		(end 122.70613 -232.699814)
		(width 0.1143)
		(layer "In13.Cu")
		(net "GMI_CPU0_G0_CPU1_G2_TX_DP<11>")
	)
	(segment
		(start 348.72422 -238.491522)
		(end 348.69247 -238.50981)
		(width 0.1143)
		(layer "In13.Cu")
		(net "GMI_CPU0_G0_CPU1_G2_TX_DP<11>")
	)
	(segment
		(start 348.723204 -232.656126)
		(end 348.723966 -232.656634)
		(width 0.1143)
		(layer "In13.Cu")
		(net "GMI_CPU0_G0_CPU1_G2_TX_DP<11>")
	)
	(segment
		(start 348.72549 -229.417372)
		(end 348.763082 -229.43947)
		(width 0.1143)
		(layer "In13.Cu")
		(net "GMI_CPU0_G0_CPU1_G2_TX_DP<11>")
	)
	(segment
		(start 122.80519 -235.877354)
		(end 122.812048 -235.872528)
		(width 0.1143)
		(layer "In13.Cu")
		(net "GMI_CPU0_G0_CPU1_G2_TX_DP<11>")
	)
	(segment
		(start 122.771662 -235.896912)
		(end 122.80519 -235.877354)
		(width 0.1143)
		(layer "In13.Cu")
		(net "GMI_CPU0_G0_CPU1_G2_TX_DP<11>")
	)
	(segment
		(start 122.771408 -239.136936)
		(end 122.771662 -239.136936)
		(width 0.1143)
		(layer "In13.Cu")
		(net "GMI_CPU0_G0_CPU1_G2_TX_DP<11>")
	)
	(segment
		(start 122.727466 -234.302808)
		(end 122.76328 -234.28198)
		(width 0.1143)
		(layer "In13.Cu")
		(net "GMI_CPU0_G0_CPU1_G2_TX_DP<11>")
	)
	(segment
		(start 122.70613 -232.699814)
		(end 122.7074 -232.698798)
		(width 0.1143)
		(layer "In13.Cu")
		(net "GMI_CPU0_G0_CPU1_G2_TX_DP<11>")
	)
	(segment
		(start 348.69247 -239.118394)
		(end 348.72422 -239.136682)
		(width 0.1143)
		(layer "In13.Cu")
		(net "GMI_CPU0_G0_CPU1_G2_TX_DP<11>")
	)
	(segment
		(start 348.723966 -232.656634)
		(end 348.724982 -232.657142)
		(width 0.1143)
		(layer "In13.Cu")
		(net "GMI_CPU0_G0_CPU1_G2_TX_DP<11>")
	)
	(segment
		(start 122.772678 -223.91243)
		(end 122.771916 -223.911922)
		(width 0.1143)
		(layer "In13.Cu")
		(net "GMI_CPU0_G0_CPU1_G2_TX_DP<11>")
	)
	(segment
		(start 122.41276 -239.624362)
		(end 122.48515 -239.611662)
		(width 0.1143)
		(layer "In13.Cu")
		(net "GMI_CPU0_G0_CPU1_G2_TX_DP<11>")
	)
	(segment
		(start 122.728482 -235.226606)
		(end 122.69597 -235.200698)
		(width 0.1143)
		(layer "In13.Cu")
		(net "GMI_CPU0_G0_CPU1_G2_TX_DP<11>")
	)
	(segment
		(start 122.803412 -238.510064)
		(end 122.771662 -238.491776)
		(width 0.1143)
		(layer "In13.Cu")
		(net "GMI_CPU0_G0_CPU1_G2_TX_DP<11>")
	)
	(segment
		(start 348.73438 -226.182682)
		(end 348.763082 -226.1997)
		(width 0.1143)
		(layer "In13.Cu")
		(net "GMI_CPU0_G0_CPU1_G2_TX_DP<11>")
	)
	(segment
		(start 348.721934 -230.392986)
		(end 348.72041 -230.393748)
		(width 0.1143)
		(layer "In13.Cu")
		(net "GMI_CPU0_G0_CPU1_G2_TX_DP<11>")
	)
	(segment
		(start 122.804428 -228.7905)
		(end 122.77598 -228.774244)
		(width 0.1143)
		(layer "In13.Cu")
		(net "GMI_CPU0_G0_CPU1_G2_TX_DP<11>")
	)
	(segment
		(start 122.736864 -222.957136)
		(end 122.771662 -222.93707)
		(width 0.1143)
		(layer "In13.Cu")
		(net "GMI_CPU0_G0_CPU1_G2_TX_DP<11>")
	)
	(segment
		(start 348.723204 -228.772212)
		(end 348.720156 -228.77399)
		(width 0.1143)
		(layer "In13.Cu")
		(net "GMI_CPU0_G0_CPU1_G2_TX_DP<11>")
	)
	(segment
		(start 122.769122 -226.178618)
		(end 122.7709 -226.177602)
		(width 0.1143)
		(layer "In13.Cu")
		(net "GMI_CPU0_G0_CPU1_G2_TX_DP<11>")
	)
	(segment
		(start 348.723204 -232.011982)
		(end 348.692216 -232.029762)
		(width 0.1143)
		(layer "In13.Cu")
		(net "GMI_CPU0_G0_CPU1_G2_TX_DP<11>")
	)
	(segment
		(start 348.755462 -228.753416)
		(end 348.724982 -228.771196)
		(width 0.1143)
		(layer "In13.Cu")
		(net "GMI_CPU0_G0_CPU1_G2_TX_DP<11>")
	)
	(segment
		(start 348.723204 -230.392224)
		(end 348.721934 -230.392986)
		(width 0.1143)
		(layer "In13.Cu")
		(net "GMI_CPU0_G0_CPU1_G2_TX_DP<11>")
	)
	(segment
		(start 122.772678 -230.392478)
		(end 122.771916 -230.39197)
		(width 0.1143)
		(layer "In13.Cu")
		(net "GMI_CPU0_G0_CPU1_G2_TX_DP<11>")
	)
	(segment
		(start 348.994476 -239.51819)
		(end 348.998794 -239.541558)
		(width 0.1143)
		(layer "In13.Cu")
		(net "GMI_CPU0_G0_CPU1_G2_TX_DP<11>")
	)
	(segment
		(start 348.724982 -235.25099)
		(end 348.723966 -235.251498)
		(width 0.1143)
		(layer "In13.Cu")
		(net "GMI_CPU0_G0_CPU1_G2_TX_DP<11>")
	)
	(segment
		(start 122.76328 -232.661968)
		(end 122.764804 -232.660952)
		(width 0.1143)
		(layer "In13.Cu")
		(net "GMI_CPU0_G0_CPU1_G2_TX_DP<11>")
	)
	(segment
		(start 348.68485 -232.633012)
		(end 348.692216 -232.638346)
		(width 0.1143)
		(layer "In13.Cu")
		(net "GMI_CPU0_G0_CPU1_G2_TX_DP<11>")
	)
	(segment
		(start 348.763082 -227.128832)
		(end 348.756224 -227.132896)
		(width 0.1143)
		(layer "In13.Cu")
		(net "GMI_CPU0_G0_CPU1_G2_TX_DP<11>")
	)
	(segment
		(start 348.692216 -225.549968)
		(end 348.681548 -225.557588)
		(width 0.1143)
		(layer "In13.Cu")
		(net "GMI_CPU0_G0_CPU1_G2_TX_DP<11>")
	)
	(segment
		(start 122.739658 -223.893126)
		(end 122.7328 -223.889062)
		(width 0.1143)
		(layer "In13.Cu")
		(net "GMI_CPU0_G0_CPU1_G2_TX_DP<11>")
	)
	(segment
		(start 122.42419 -221.100396)
		(end 122.42419 -221.071948)
		(width 0.1143)
		(layer "In13.Cu")
		(net "GMI_CPU0_G0_CPU1_G2_TX_DP<11>")
	)
	(segment
		(start 348.725744 -235.250482)
		(end 348.724982 -235.25099)
		(width 0.1143)
		(layer "In13.Cu")
		(net "GMI_CPU0_G0_CPU1_G2_TX_DP<11>")
	)
	(segment
		(start 122.7709 -224.55759)
		(end 122.771916 -224.557082)
		(width 0.1143)
		(layer "In13.Cu")
		(net "GMI_CPU0_G0_CPU1_G2_TX_DP<11>")
	)
	(segment
		(start 348.731078 -232.660698)
		(end 348.732602 -232.661714)
		(width 0.1143)
		(layer "In13.Cu")
		(net "GMI_CPU0_G0_CPU1_G2_TX_DP<11>")
	)
	(segment
		(start 348.726506 -232.658158)
		(end 348.731078 -232.660698)
		(width 0.1143)
		(layer "In13.Cu")
		(net "GMI_CPU0_G0_CPU1_G2_TX_DP<11>")
	)
	(segment
		(start 348.759526 -234.297474)
		(end 348.763082 -234.299506)
		(width 0.1143)
		(layer "In13.Cu")
		(net "GMI_CPU0_G0_CPU1_G2_TX_DP<11>")
	)
	(segment
		(start 348.763082 -231.988614)
		(end 348.756224 -231.992678)
		(width 0.1143)
		(layer "In13.Cu")
		(net "GMI_CPU0_G0_CPU1_G2_TX_DP<11>")
	)
	(segment
		(start 122.691906 -232.711498)
		(end 122.698764 -232.70591)
		(width 0.1143)
		(layer "In13.Cu")
		(net "GMI_CPU0_G0_CPU1_G2_TX_DP<11>")
	)
	(segment
		(start 122.771662 -236.871764)
		(end 122.73534 -236.850682)
		(width 0.1143)
		(layer "In13.Cu")
		(net "GMI_CPU0_G0_CPU1_G2_TX_DP<11>")
	)
	(segment
		(start 122.767344 -235.248958)
		(end 122.728482 -235.226606)
		(width 0.1143)
		(layer "In13.Cu")
		(net "GMI_CPU0_G0_CPU1_G2_TX_DP<11>")
	)
	(segment
		(start 347.28277 -216.89695)
		(end 349.071692 -219.91066)
		(width 0.14224)
		(layer "In13.Cu")
		(net "GMI_CPU0_G0_CPU1_G2_TX_DP<11>")
	)
	(segment
		(start 122.489468 -221.804484)
		(end 122.489468 -221.401894)
		(width 0.1143)
		(layer "In13.Cu")
		(net "GMI_CPU0_G0_CPU1_G2_TX_DP<11>")
	)
	(segment
		(start 349.00616 -221.579694)
		(end 349.006414 -221.579948)
		(width 0.1143)
		(layer "In13.Cu")
		(net "GMI_CPU0_G0_CPU1_G2_TX_DP<11>")
	)
	(segment
		(start 348.72422 -239.136682)
		(end 348.724474 -239.136682)
		(width 0.1143)
		(layer "In13.Cu")
		(net "GMI_CPU0_G0_CPU1_G2_TX_DP<11>")
	)
	(segment
		(start 348.683834 -235.872274)
		(end 348.690692 -235.8771)
		(width 0.1143)
		(layer "In13.Cu")
		(net "GMI_CPU0_G0_CPU1_G2_TX_DP<11>")
	)
	(segment
		(start 348.763082 -233.608626)
		(end 348.756224 -233.61269)
		(width 0.1143)
		(layer "In13.Cu")
		(net "GMI_CPU0_G0_CPU1_G2_TX_DP<11>")
	)
	(segment
		(start 348.724982 -224.557336)
		(end 348.763082 -224.579688)
		(width 0.1143)
		(layer "In13.Cu")
		(net "GMI_CPU0_G0_CPU1_G2_TX_DP<11>")
	)
	(segment
		(start 348.798388 -235.201714)
		(end 348.767908 -235.226098)
		(width 0.1143)
		(layer "In13.Cu")
		(net "GMI_CPU0_G0_CPU1_G2_TX_DP<11>")
	)
	(segment
		(start 348.763082 -225.50882)
		(end 348.756224 -225.512884)
		(width 0.1143)
		(layer "In13.Cu")
		(net "GMI_CPU0_G0_CPU1_G2_TX_DP<11>")
	)
	(segment
		(start 349.071692 -221.100142)
		(end 349.025972 -221.145862)
		(width 0.1143)
		(layer "In13.Cu")
		(net "GMI_CPU0_G0_CPU1_G2_TX_DP<11>")
	)
	(segment
		(start 122.42419 -220.070934)
		(end 124.441458 -216.59215)
		(width 0.14224)
		(layer "In13.Cu")
		(net "GMI_CPU0_G0_CPU1_G2_TX_DP<11>")
	)
	(segment
		(start 348.755462 -231.993186)
		(end 348.724982 -232.010966)
		(width 0.1143)
		(layer "In13.Cu")
		(net "GMI_CPU0_G0_CPU1_G2_TX_DP<11>")
	)
	(segment
		(start 348.724982 -223.91116)
		(end 348.723966 -223.911668)
		(width 0.1143)
		(layer "In13.Cu")
		(net "GMI_CPU0_G0_CPU1_G2_TX_DP<11>")
	)
	(segment
		(start 122.803666 -225.550222)
		(end 122.772678 -225.532442)
		(width 0.1143)
		(layer "In13.Cu")
		(net "GMI_CPU0_G0_CPU1_G2_TX_DP<11>")
	)
	(segment
		(start 122.959622 -229.093776)
		(end 122.959368 -229.09403)
		(width 0.1143)
		(layer "In13.Cu")
		(net "GMI_CPU0_G0_CPU1_G2_TX_DP<11>")
	)
	(segment
		(start 348.72422 -236.87151)
		(end 348.69247 -236.889798)
		(width 0.1143)
		(layer "In13.Cu")
		(net "GMI_CPU0_G0_CPU1_G2_TX_DP<11>")
	)
	(segment
		(start 122.114818 -239.624362)
		(end 122.41276 -239.624362)
		(width 0.1143)
		(layer "In13.Cu")
		(net "GMI_CPU0_G0_CPU1_G2_TX_DP<11>")
	)
	(segment
		(start 122.710956 -232.69575)
		(end 122.712734 -232.694226)
		(width 0.1143)
		(layer "In13.Cu")
		(net "GMI_CPU0_G0_CPU1_G2_TX_DP<11>")
	)
	(segment
		(start 302.606456 -185.131202)
		(end 302.638714 -185.131202)
		(width 0.14224)
		(layer "In13.Cu")
		(net "GMI_CPU0_G0_CPU1_G2_TX_DP<11>")
	)
	(segment
		(start 122.7709 -225.531426)
		(end 122.74042 -225.513646)
		(width 0.1143)
		(layer "In13.Cu")
		(net "GMI_CPU0_G0_CPU1_G2_TX_DP<11>")
	)
	(segment
		(start 122.77598 -228.774244)
		(end 122.775726 -228.774244)
		(width 0.1143)
		(layer "In13.Cu")
		(net "GMI_CPU0_G0_CPU1_G2_TX_DP<11>")
	)
	(segment
		(start 348.724982 -228.771196)
		(end 348.723966 -228.771704)
		(width 0.1143)
		(layer "In13.Cu")
		(net "GMI_CPU0_G0_CPU1_G2_TX_DP<11>")
	)
	(segment
		(start 122.803666 -227.170234)
		(end 122.772678 -227.152454)
		(width 0.1143)
		(layer "In13.Cu")
		(net "GMI_CPU0_G0_CPU1_G2_TX_DP<11>")
	)
	(segment
		(start 348.723204 -233.631994)
		(end 348.692216 -233.649774)
		(width 0.1143)
		(layer "In13.Cu")
		(net "GMI_CPU0_G0_CPU1_G2_TX_DP<11>")
	)
	(segment
		(start 348.763082 -223.888808)
		(end 348.756224 -223.892872)
		(width 0.1143)
		(layer "In13.Cu")
		(net "GMI_CPU0_G0_CPU1_G2_TX_DP<11>")
	)
	(segment
		(start 122.7709 -223.911414)
		(end 122.74042 -223.893634)
		(width 0.1143)
		(layer "In13.Cu")
		(net "GMI_CPU0_G0_CPU1_G2_TX_DP<11>")
	)
	(segment
		(start 122.46991 -221.382336)
		(end 122.46991 -221.146116)
		(width 0.1143)
		(layer "In13.Cu")
		(net "GMI_CPU0_G0_CPU1_G2_TX_DP<11>")
	)
	(segment
		(start 122.772678 -232.65638)
		(end 122.803666 -232.6386)
		(width 0.1143)
		(layer "In13.Cu")
		(net "GMI_CPU0_G0_CPU1_G2_TX_DP<11>")
	)
	(segment
		(start 122.767344 -235.249212)
		(end 122.767344 -235.248958)
		(width 0.1143)
		(layer "In13.Cu")
		(net "GMI_CPU0_G0_CPU1_G2_TX_DP<11>")
	)
	(segment
		(start 348.69247 -237.498382)
		(end 348.72422 -237.51667)
		(width 0.1143)
		(layer "In13.Cu")
		(net "GMI_CPU0_G0_CPU1_G2_TX_DP<11>")
	)
	(segment
		(start 122.698764 -232.70591)
		(end 122.69978 -232.705148)
		(width 0.1143)
		(layer "In13.Cu")
		(net "GMI_CPU0_G0_CPU1_G2_TX_DP<11>")
	)
	(segment
		(start 348.723204 -227.1522)
		(end 348.692216 -227.16998)
		(width 0.1143)
		(layer "In13.Cu")
		(net "GMI_CPU0_G0_CPU1_G2_TX_DP<11>")
	)
	(segment
		(start 302.638714 -185.131202)
		(end 302.886872 -185.132726)
		(width 0.14224)
		(layer "In13.Cu")
		(net "GMI_CPU0_G0_CPU1_G2_TX_DP<11>")
	)
	(segment
		(start 348.692216 -232.638346)
		(end 348.723204 -232.656126)
		(width 0.1143)
		(layer "In13.Cu")
		(net "GMI_CPU0_G0_CPU1_G2_TX_DP<11>")
	)
	(arc
		(start 122.804936 -229.397306)
		(mid 122.918657 -229.264508)
		(end 122.959622 -229.094538)
		(width 0.1143)
		(layer "In13.Cu")
		(net "GMI_CPU0_G0_CPU1_G2_TX_DP<11>")
	)
	(arc
		(start 122.69597 -235.200698)
		(mid 122.486494 -234.764679)
		(end 122.695716 -234.328462)
		(width 0.1143)
		(layer "In13.Cu")
		(net "GMI_CPU0_G0_CPU1_G2_TX_DP<11>")
	)
	(arc
		(start 348.802198 -232.70972)
		(mid 349.010857 -233.144239)
		(end 348.801944 -233.578654)
		(width 0.1143)
		(layer "In13.Cu")
		(net "GMI_CPU0_G0_CPU1_G2_TX_DP<11>")
	)
	(arc
		(start 122.489468 -229.90429)
		(mid 122.553983 -229.642071)
		(end 122.7328 -229.439724)
		(width 0.1143)
		(layer "In13.Cu")
		(net "GMI_CPU0_G0_CPU1_G2_TX_DP<11>")
	)
	(arc
		(start 348.772226 -238.462312)
		(mid 348.76641 -238.466413)
		(end 348.760542 -238.47044)
		(width 0.1143)
		(layer "In13.Cu")
		(net "GMI_CPU0_G0_CPU1_G2_TX_DP<11>")
	)
	(arc
		(start 122.959622 -230.71455)
		(mid 122.918029 -230.543762)
		(end 122.803666 -230.410258)
		(width 0.1143)
		(layer "In13.Cu")
		(net "GMI_CPU0_G0_CPU1_G2_TX_DP<11>")
	)
	(arc
		(start 348.760542 -237.537752)
		(mid 348.76641 -237.541779)
		(end 348.772226 -237.54588)
		(width 0.1143)
		(layer "In13.Cu")
		(net "GMI_CPU0_G0_CPU1_G2_TX_DP<11>")
	)
	(arc
		(start 349.006414 -221.868746)
		(mid 348.946416 -222.093266)
		(end 348.782386 -222.257874)
		(width 0.1143)
		(layer "In13.Cu")
		(net "GMI_CPU0_G0_CPU1_G2_TX_DP<11>")
	)
	(arc
		(start 122.768614 -230.389938)
		(mid 122.564315 -230.18447)
		(end 122.489468 -229.904544)
		(width 0.1143)
		(layer "In13.Cu")
		(net "GMI_CPU0_G0_CPU1_G2_TX_DP<11>")
	)
	(arc
		(start 122.7328 -227.129086)
		(mid 122.489473 -226.66452)
		(end 122.7328 -226.199954)
		(width 0.1143)
		(layer "In13.Cu")
		(net "GMI_CPU0_G0_CPU1_G2_TX_DP<11>")
	)
	(arc
		(start 348.681548 -225.557588)
		(mid 348.529481 -225.85426)
		(end 348.681548 -226.150932)
		(width 0.1143)
		(layer "In13.Cu")
		(net "GMI_CPU0_G0_CPU1_G2_TX_DP<11>")
	)
	(arc
		(start 122.812048 -235.872528)
		(mid 122.964929 -235.574332)
		(end 122.812048 -235.276136)
		(width 0.1143)
		(layer "In13.Cu")
		(net "GMI_CPU0_G0_CPU1_G2_TX_DP<11>")
	)
	(arc
		(start 348.760542 -235.91774)
		(mid 348.766665 -235.921892)
		(end 348.772734 -235.926122)
		(width 0.1143)
		(layer "In13.Cu")
		(net "GMI_CPU0_G0_CPU1_G2_TX_DP<11>")
	)
	(arc
		(start 122.723148 -236.8423)
		(mid 122.491164 -236.384338)
		(end 122.723148 -235.926376)
		(width 0.1143)
		(layer "In13.Cu")
		(net "GMI_CPU0_G0_CPU1_G2_TX_DP<11>")
	)
	(arc
		(start 348.763082 -234.299506)
		(mid 348.771005 -234.305154)
		(end 348.77883 -234.310936)
		(width 0.1143)
		(layer "In13.Cu")
		(net "GMI_CPU0_G0_CPU1_G2_TX_DP<11>")
	)
	(arc
		(start 348.683834 -233.65587)
		(mid 348.530953 -233.954066)
		(end 348.683834 -234.252262)
		(width 0.1143)
		(layer "In13.Cu")
		(net "GMI_CPU0_G0_CPU1_G2_TX_DP<11>")
	)
	(arc
		(start 122.7328 -223.889062)
		(mid 122.489473 -223.424496)
		(end 122.7328 -222.95993)
		(width 0.1143)
		(layer "In13.Cu")
		(net "GMI_CPU0_G0_CPU1_G2_TX_DP<11>")
	)
	(arc
		(start 122.959368 -229.09403)
		(mid 122.918441 -228.923944)
		(end 122.804682 -228.791008)
		(width 0.1143)
		(layer "In13.Cu")
		(net "GMI_CPU0_G0_CPU1_G2_TX_DP<11>")
	)
	(arc
		(start 122.7328 -225.509074)
		(mid 122.489473 -225.044508)
		(end 122.7328 -224.579942)
		(width 0.1143)
		(layer "In13.Cu")
		(net "GMI_CPU0_G0_CPU1_G2_TX_DP<11>")
	)
	(arc
		(start 122.717052 -232.691178)
		(mid 122.724876 -232.685395)
		(end 122.7328 -232.679748)
		(width 0.1143)
		(layer "In13.Cu")
		(net "GMI_CPU0_G0_CPU1_G2_TX_DP<11>")
	)
	(arc
		(start 348.772734 -235.926122)
		(mid 349.004718 -236.384084)
		(end 348.772734 -236.842046)
		(width 0.1143)
		(layer "In13.Cu")
		(net "GMI_CPU0_G0_CPU1_G2_TX_DP<11>")
	)
	(arc
		(start 348.69247 -238.50981)
		(mid 348.536542 -238.814102)
		(end 348.69247 -239.118394)
		(width 0.1143)
		(layer "In13.Cu")
		(net "GMI_CPU0_G0_CPU1_G2_TX_DP<11>")
	)
	(arc
		(start 348.692216 -230.410004)
		(mid 348.577812 -230.543487)
		(end 348.53626 -230.714296)
		(width 0.1143)
		(layer "In13.Cu")
		(net "GMI_CPU0_G0_CPU1_G2_TX_DP<11>")
	)
	(arc
		(start 348.798642 -234.326684)
		(mid 349.008728 -234.764251)
		(end 348.798388 -235.201714)
		(width 0.1143)
		(layer "In13.Cu")
		(net "GMI_CPU0_G0_CPU1_G2_TX_DP<11>")
	)
	(arc
		(start 122.733308 -222.269558)
		(mid 122.554115 -222.067048)
		(end 122.489468 -221.804484)
		(width 0.1143)
		(layer "In13.Cu")
		(net "GMI_CPU0_G0_CPU1_G2_TX_DP<11>")
	)
	(arc
		(start 348.53626 -230.714296)
		(mid 348.584794 -230.898501)
		(end 348.718886 -231.033828)
		(width 0.1143)
		(layer "In13.Cu")
		(net "GMI_CPU0_G0_CPU1_G2_TX_DP<11>")
	)
	(arc
		(start 348.69247 -236.889798)
		(mid 348.536542 -237.19409)
		(end 348.69247 -237.498382)
		(width 0.1143)
		(layer "In13.Cu")
		(net "GMI_CPU0_G0_CPU1_G2_TX_DP<11>")
	)
	(arc
		(start 348.772734 -236.842046)
		(mid 348.766666 -236.846278)
		(end 348.760542 -236.850428)
		(width 0.1143)
		(layer "In13.Cu")
		(net "GMI_CPU0_G0_CPU1_G2_TX_DP<11>")
	)
	(arc
		(start 348.763082 -229.43947)
		(mid 348.941895 -229.64182)
		(end 349.006414 -229.904036)
		(width 0.1143)
		(layer "In13.Cu")
		(net "GMI_CPU0_G0_CPU1_G2_TX_DP<11>")
	)
	(arc
		(start 122.7328 -228.749098)
		(mid 122.489473 -228.284532)
		(end 122.7328 -227.819966)
		(width 0.1143)
		(layer "In13.Cu")
		(net "GMI_CPU0_G0_CPU1_G2_TX_DP<11>")
	)
	(arc
		(start 348.724474 -239.136682)
		(mid 348.900981 -239.298065)
		(end 348.994476 -239.51819)
		(width 0.1143)
		(layer "In13.Cu")
		(net "GMI_CPU0_G0_CPU1_G2_TX_DP<11>")
	)
	(arc
		(start 122.501406 -239.518444)
		(mid 122.594922 -239.298334)
		(end 122.771408 -239.136936)
		(width 0.1143)
		(layer "In13.Cu")
		(net "GMI_CPU0_G0_CPU1_G2_TX_DP<11>")
	)
	(arc
		(start 348.53626 -229.094284)
		(mid 348.577226 -229.264253)
		(end 348.690946 -229.397052)
		(width 0.1143)
		(layer "In13.Cu")
		(net "GMI_CPU0_G0_CPU1_G2_TX_DP<11>")
	)
	(arc
		(start 348.763082 -222.959676)
		(mid 349.006409 -223.424242)
		(end 348.763082 -223.888808)
		(width 0.1143)
		(layer "In13.Cu")
		(net "GMI_CPU0_G0_CPU1_G2_TX_DP<11>")
	)
	(arc
		(start 349.006414 -229.90429)
		(mid 348.931598 -230.184234)
		(end 348.727268 -230.389684)
		(width 0.1143)
		(layer "In13.Cu")
		(net "GMI_CPU0_G0_CPU1_G2_TX_DP<11>")
	)
	(arc
		(start 348.6912 -228.790754)
		(mid 348.577346 -228.923641)
		(end 348.536514 -229.093776)
		(width 0.1143)
		(layer "In13.Cu")
		(net "GMI_CPU0_G0_CPU1_G2_TX_DP<11>")
	)
	(arc
		(start 348.998794 -239.541558)
		(mid 349.005129 -239.57642)
		(end 349.010732 -239.611408)
		(width 0.1143)
		(layer "In13.Cu")
		(net "GMI_CPU0_G0_CPU1_G2_TX_DP<11>")
	)
	(arc
		(start 122.803412 -237.498636)
		(mid 122.95934 -237.194344)
		(end 122.803412 -236.890052)
		(width 0.1143)
		(layer "In13.Cu")
		(net "GMI_CPU0_G0_CPU1_G2_TX_DP<11>")
	)
	(arc
		(start 122.803412 -239.118648)
		(mid 122.95934 -238.814356)
		(end 122.803412 -238.510064)
		(width 0.1143)
		(layer "In13.Cu")
		(net "GMI_CPU0_G0_CPU1_G2_TX_DP<11>")
	)
	(arc
		(start 122.811032 -232.633266)
		(mid 122.964215 -232.334308)
		(end 122.811032 -232.03535)
		(width 0.1143)
		(layer "In13.Cu")
		(net "GMI_CPU0_G0_CPU1_G2_TX_DP<11>")
	)
	(arc
		(start 348.763082 -231.059482)
		(mid 349.006409 -231.524048)
		(end 348.763082 -231.988614)
		(width 0.1143)
		(layer "In13.Cu")
		(net "GMI_CPU0_G0_CPU1_G2_TX_DP<11>")
	)
	(arc
		(start 122.723656 -238.462566)
		(mid 122.490739 -238.00435)
		(end 122.723656 -237.546134)
		(width 0.1143)
		(layer "In13.Cu")
		(net "GMI_CPU0_G0_CPU1_G2_TX_DP<11>")
	)
	(arc
		(start 122.814334 -226.151186)
		(mid 122.966401 -225.854514)
		(end 122.814334 -225.557842)
		(width 0.1143)
		(layer "In13.Cu")
		(net "GMI_CPU0_G0_CPU1_G2_TX_DP<11>")
	)
	(arc
		(start 122.7328 -231.988868)
		(mid 122.489473 -231.524302)
		(end 122.7328 -231.059736)
		(width 0.1143)
		(layer "In13.Cu")
		(net "GMI_CPU0_G0_CPU1_G2_TX_DP<11>")
	)
	(arc
		(start 122.812048 -234.252516)
		(mid 122.964929 -233.95432)
		(end 122.812048 -233.656124)
		(width 0.1143)
		(layer "In13.Cu")
		(net "GMI_CPU0_G0_CPU1_G2_TX_DP<11>")
	)
	(arc
		(start 122.803412 -222.918782)
		(mid 122.95934 -222.61449)
		(end 122.803412 -222.310198)
		(width 0.1143)
		(layer "In13.Cu")
		(net "GMI_CPU0_G0_CPU1_G2_TX_DP<11>")
	)
	(arc
		(start 348.763082 -227.819712)
		(mid 349.006409 -228.284278)
		(end 348.763082 -228.748844)
		(width 0.1143)
		(layer "In13.Cu")
		(net "GMI_CPU0_G0_CPU1_G2_TX_DP<11>")
	)
	(arc
		(start 122.723656 -237.546134)
		(mid 122.729472 -237.542033)
		(end 122.73534 -237.538006)
		(width 0.1143)
		(layer "In13.Cu")
		(net "GMI_CPU0_G0_CPU1_G2_TX_DP<11>")
	)
	(arc
		(start 348.68485 -232.035096)
		(mid 348.531667 -232.334054)
		(end 348.68485 -232.633012)
		(width 0.1143)
		(layer "In13.Cu")
		(net "GMI_CPU0_G0_CPU1_G2_TX_DP<11>")
	)
	(arc
		(start 348.763082 -232.679494)
		(mid 348.771005 -232.685142)
		(end 348.77883 -232.690924)
		(width 0.1143)
		(layer "In13.Cu")
		(net "GMI_CPU0_G0_CPU1_G2_TX_DP<11>")
	)
	(arc
		(start 122.823224 -227.764848)
		(mid 122.972038 -227.474526)
		(end 122.823224 -227.184204)
		(width 0.1143)
		(layer "In13.Cu")
		(net "GMI_CPU0_G0_CPU1_G2_TX_DP<11>")
	)
	(arc
		(start 122.69216 -233.577638)
		(mid 122.484111 -233.144667)
		(end 122.691906 -232.711498)
		(width 0.1143)
		(layer "In13.Cu")
		(net "GMI_CPU0_G0_CPU1_G2_TX_DP<11>")
	)
	(arc
		(start 348.772226 -237.54588)
		(mid 349.005143 -238.004096)
		(end 348.772226 -238.462312)
		(width 0.1143)
		(layer "In13.Cu")
		(net "GMI_CPU0_G0_CPU1_G2_TX_DP<11>")
	)
	(arc
		(start 122.723148 -235.926376)
		(mid 122.729216 -235.922144)
		(end 122.73534 -235.917994)
		(width 0.1143)
		(layer "In13.Cu")
		(net "GMI_CPU0_G0_CPU1_G2_TX_DP<11>")
	)
	(arc
		(start 122.73534 -236.850682)
		(mid 122.729217 -236.84653)
		(end 122.723148 -236.8423)
		(width 0.1143)
		(layer "In13.Cu")
		(net "GMI_CPU0_G0_CPU1_G2_TX_DP<11>")
	)
	(arc
		(start 348.763082 -224.579688)
		(mid 349.006409 -225.044254)
		(end 348.763082 -225.50882)
		(width 0.1143)
		(layer "In13.Cu")
		(net "GMI_CPU0_G0_CPU1_G2_TX_DP<11>")
	)
	(arc
		(start 348.683834 -235.275882)
		(mid 348.530953 -235.574078)
		(end 348.683834 -235.872274)
		(width 0.1143)
		(layer "In13.Cu")
		(net "GMI_CPU0_G0_CPU1_G2_TX_DP<11>")
	)
	(arc
		(start 122.48515 -239.611662)
		(mid 122.490751 -239.576674)
		(end 122.497088 -239.541812)
		(width 0.1143)
		(layer "In13.Cu")
		(net "GMI_CPU0_G0_CPU1_G2_TX_DP<11>")
	)
	(arc
		(start 348.77883 -233.597196)
		(mid 348.771006 -233.602979)
		(end 348.763082 -233.608626)
		(width 0.1143)
		(layer "In13.Cu")
		(net "GMI_CPU0_G0_CPU1_G2_TX_DP<11>")
	)
	(arc
		(start 122.803666 -224.538794)
		(mid 122.955356 -224.234502)
		(end 122.803666 -223.93021)
		(width 0.1143)
		(layer "In13.Cu")
		(net "GMI_CPU0_G0_CPU1_G2_TX_DP<11>")
	)
	(arc
		(start 348.672658 -227.18395)
		(mid 348.523844 -227.474272)
		(end 348.672658 -227.764594)
		(width 0.1143)
		(layer "In13.Cu")
		(net "GMI_CPU0_G0_CPU1_G2_TX_DP<11>")
	)
	(arc
		(start 122.73534 -238.470694)
		(mid 122.729472 -238.466667)
		(end 122.723656 -238.462566)
		(width 0.1143)
		(layer "In13.Cu")
		(net "GMI_CPU0_G0_CPU1_G2_TX_DP<11>")
	)
	(arc
		(start 348.692216 -223.929956)
		(mid 348.540526 -224.234248)
		(end 348.692216 -224.53854)
		(width 0.1143)
		(layer "In13.Cu")
		(net "GMI_CPU0_G0_CPU1_G2_TX_DP<11>")
	)
	(arc
		(start 122.776996 -231.034082)
		(mid 122.911146 -230.898789)
		(end 122.959622 -230.71455)
		(width 0.1143)
		(layer "In13.Cu")
		(net "GMI_CPU0_G0_CPU1_G2_TX_DP<11>")
	)
	(arc
		(start 348.69247 -222.309944)
		(mid 348.536542 -222.614236)
		(end 348.69247 -222.918528)
		(width 0.1143)
		(layer "In13.Cu")
		(net "GMI_CPU0_G0_CPU1_G2_TX_DP<11>")
	)
	(arc
		(start 348.763082 -226.1997)
		(mid 349.006409 -226.664266)
		(end 348.763082 -227.128832)
		(width 0.1143)
		(layer "In13.Cu")
		(net "GMI_CPU0_G0_CPU1_G2_TX_DP<11>")
	)
	(segment
		(start 121.647966 -243.130324)
		(end 122.114818 -242.864386)
		(width 0.12954)
		(layer "F.Cu")
		(net "GMI_CPU0_G0_CPU1_G2_TX_DP<10>")
	)
	(segment
		(start 349.847916 -243.13007)
		(end 349.381064 -242.864132)
		(width 0.12954)
		(layer "F.Cu")
		(net "GMI_CPU0_G0_CPU1_G2_TX_DP<10>")
	)
	(segment
		(start 349.659702 -235.254038)
		(end 349.660464 -235.25353)
		(width 0.1143)
		(layer "In13.Cu")
		(net "GMI_CPU0_G0_CPU1_G2_TX_DP<10>")
	)
	(segment
		(start 122.48261 -242.794536)
		(end 122.41276 -242.864386)
		(width 0.1143)
		(layer "In13.Cu")
		(net "GMI_CPU0_G0_CPU1_G2_TX_DP<10>")
	)
	(segment
		(start 121.848118 -230.401114)
		(end 121.848118 -230.401368)
		(width 0.1143)
		(layer "In13.Cu")
		(net "GMI_CPU0_G0_CPU1_G2_TX_DP<10>")
	)
	(segment
		(start 349.163386 -242.559332)
		(end 349.232982 -242.518692)
		(width 0.1143)
		(layer "In13.Cu")
		(net "GMI_CPU0_G0_CPU1_G2_TX_DP<10>")
	)
	(segment
		(start 121.793508 -232.67924)
		(end 121.77268 -232.693972)
		(width 0.1143)
		(layer "In13.Cu")
		(net "GMI_CPU0_G0_CPU1_G2_TX_DP<10>")
	)
	(segment
		(start 121.851674 -230.4034)
		(end 121.85396 -230.404924)
		(width 0.1143)
		(layer "In13.Cu")
		(net "GMI_CPU0_G0_CPU1_G2_TX_DP<10>")
	)
	(segment
		(start 121.863612 -235.878624)
		(end 121.793508 -235.919264)
		(width 0.1143)
		(layer "In13.Cu")
		(net "GMI_CPU0_G0_CPU1_G2_TX_DP<10>")
	)
	(segment
		(start 121.837958 -235.255308)
		(end 121.839228 -235.25607)
		(width 0.1143)
		(layer "In13.Cu")
		(net "GMI_CPU0_G0_CPU1_G2_TX_DP<10>")
	)
	(segment
		(start 349.641922 -230.40467)
		(end 349.644208 -230.403146)
		(width 0.1143)
		(layer "In13.Cu")
		(net "GMI_CPU0_G0_CPU1_G2_TX_DP<10>")
	)
	(segment
		(start 349.647764 -230.401114)
		(end 349.647764 -230.40086)
		(width 0.1143)
		(layer "In13.Cu")
		(net "GMI_CPU0_G0_CPU1_G2_TX_DP<10>")
	)
	(segment
		(start 349.642176 -234.263946)
		(end 349.63227 -234.258358)
		(width 0.1143)
		(layer "In13.Cu")
		(net "GMI_CPU0_G0_CPU1_G2_TX_DP<10>")
	)
	(segment
		(start 350.016572 -219.656406)
		(end 347.952314 -216.179654)
		(width 0.14224)
		(layer "In13.Cu")
		(net "GMI_CPU0_G0_CPU1_G2_TX_DP<10>")
	)
	(segment
		(start 121.810526 -228.759512)
		(end 121.863612 -228.790246)
		(width 0.1143)
		(layer "In13.Cu")
		(net "GMI_CPU0_G0_CPU1_G2_TX_DP<10>")
	)
	(segment
		(start 121.863612 -224.538794)
		(end 121.792238 -224.580196)
		(width 0.1143)
		(layer "In13.Cu")
		(net "GMI_CPU0_G0_CPU1_G2_TX_DP<10>")
	)
	(segment
		(start 349.63227 -232.029762)
		(end 349.663766 -232.011728)
		(width 0.1143)
		(layer "In13.Cu")
		(net "GMI_CPU0_G0_CPU1_G2_TX_DP<10>")
	)
	(segment
		(start 121.76506 -241.689128)
		(end 121.792746 -241.709194)
		(width 0.1143)
		(layer "In13.Cu")
		(net "GMI_CPU0_G0_CPU1_G2_TX_DP<10>")
	)
	(segment
		(start 122.2629 -242.518946)
		(end 122.302016 -242.541806)
		(width 0.1143)
		(layer "In13.Cu")
		(net "GMI_CPU0_G0_CPU1_G2_TX_DP<10>")
	)
	(segment
		(start 349.703644 -224.579942)
		(end 349.63227 -224.53854)
		(width 0.1143)
		(layer "In13.Cu")
		(net "GMI_CPU0_G0_CPU1_G2_TX_DP<10>")
	)
	(segment
		(start 307.211984 -184.421018)
		(end 306.713636 -184.192926)
		(width 0.14224)
		(layer "In13.Cu")
		(net "GMI_CPU0_G0_CPU1_G2_TX_DP<10>")
	)
	(segment
		(start 121.793 -222.26905)
		(end 121.862596 -222.30969)
		(width 0.1143)
		(layer "In13.Cu")
		(net "GMI_CPU0_G0_CPU1_G2_TX_DP<10>")
	)
	(segment
		(start 121.853706 -222.92437)
		(end 121.852944 -222.924878)
		(width 0.1143)
		(layer "In13.Cu")
		(net "GMI_CPU0_G0_CPU1_G2_TX_DP<10>")
	)
	(segment
		(start 349.702374 -236.849158)
		(end 349.723202 -236.834426)
		(width 0.1143)
		(layer "In13.Cu")
		(net "GMI_CPU0_G0_CPU1_G2_TX_DP<10>")
	)
	(segment
		(start 144.98955 -198.47814)
		(end 123.755912 -215.88857)
		(width 0.14224)
		(layer "In13.Cu")
		(net "GMI_CPU0_G0_CPU1_G2_TX_DP<10>")
	)
	(segment
		(start 121.792238 -225.50882)
		(end 121.863358 -225.550222)
		(width 0.1143)
		(layer "In13.Cu")
		(net "GMI_CPU0_G0_CPU1_G2_TX_DP<10>")
	)
	(segment
		(start 121.765822 -225.490024)
		(end 121.792238 -225.50882)
		(width 0.1143)
		(layer "In13.Cu")
		(net "GMI_CPU0_G0_CPU1_G2_TX_DP<10>")
	)
	(segment
		(start 121.832624 -223.91243)
		(end 121.83364 -223.912938)
		(width 0.1143)
		(layer "In13.Cu")
		(net "GMI_CPU0_G0_CPU1_G2_TX_DP<10>")
	)
	(segment
		(start 349.970852 -221.303088)
		(end 349.970852 -221.145862)
		(width 0.1143)
		(layer "In13.Cu")
		(net "GMI_CPU0_G0_CPU1_G2_TX_DP<10>")
	)
	(segment
		(start 121.784618 -230.364538)
		(end 121.847356 -230.400606)
		(width 0.1143)
		(layer "In13.Cu")
		(net "GMI_CPU0_G0_CPU1_G2_TX_DP<10>")
	)
	(segment
		(start 349.664528 -232.01122)
		(end 349.669862 -232.008172)
		(width 0.1143)
		(layer "In13.Cu")
		(net "GMI_CPU0_G0_CPU1_G2_TX_DP<10>")
	)
	(segment
		(start 121.847356 -230.400606)
		(end 121.847102 -230.400606)
		(width 0.1143)
		(layer "In13.Cu")
		(net "GMI_CPU0_G0_CPU1_G2_TX_DP<10>")
	)
	(segment
		(start 349.73006 -224.598992)
		(end 349.703644 -224.579942)
		(width 0.1143)
		(layer "In13.Cu")
		(net "GMI_CPU0_G0_CPU1_G2_TX_DP<10>")
	)
	(segment
		(start 349.94596 -221.80423)
		(end 349.94596 -221.32798)
		(width 0.1143)
		(layer "In13.Cu")
		(net "GMI_CPU0_G0_CPU1_G2_TX_DP<10>")
	)
	(segment
		(start 121.792238 -237.540038)
		(end 121.765822 -237.559088)
		(width 0.1143)
		(layer "In13.Cu")
		(net "GMI_CPU0_G0_CPU1_G2_TX_DP<10>")
	)
	(segment
		(start 349.66402 -223.911668)
		(end 349.664274 -223.911668)
		(width 0.1143)
		(layer "In13.Cu")
		(net "GMI_CPU0_G0_CPU1_G2_TX_DP<10>")
	)
	(segment
		(start 349.642938 -222.924624)
		(end 349.642176 -222.924116)
		(width 0.1143)
		(layer "In13.Cu")
		(net "GMI_CPU0_G0_CPU1_G2_TX_DP<10>")
	)
	(segment
		(start 121.831862 -240.111788)
		(end 121.863612 -240.130076)
		(width 0.1143)
		(layer "In13.Cu")
		(net "GMI_CPU0_G0_CPU1_G2_TX_DP<10>")
	)
	(segment
		(start 121.852944 -222.924878)
		(end 121.831862 -222.93707)
		(width 0.1143)
		(layer "In13.Cu")
		(net "GMI_CPU0_G0_CPU1_G2_TX_DP<10>")
	)
	(segment
		(start 121.86031 -230.40848)
		(end 121.863612 -230.410258)
		(width 0.1143)
		(layer "In13.Cu")
		(net "GMI_CPU0_G0_CPU1_G2_TX_DP<10>")
	)
	(segment
		(start 349.703136 -240.7793)
		(end 349.63227 -240.738406)
		(width 0.1143)
		(layer "In13.Cu")
		(net "GMI_CPU0_G0_CPU1_G2_TX_DP<10>")
	)
	(segment
		(start 121.52503 -221.146116)
		(end 121.52503 -221.303342)
		(width 0.1143)
		(layer "In13.Cu")
		(net "GMI_CPU0_G0_CPU1_G2_TX_DP<10>")
	)
	(segment
		(start 349.632524 -233.649774)
		(end 349.702374 -233.609134)
		(width 0.1143)
		(layer "In13.Cu")
		(net "GMI_CPU0_G0_CPU1_G2_TX_DP<10>")
	)
	(segment
		(start 349.633286 -222.309436)
		(end 349.702882 -222.268796)
		(width 0.1143)
		(layer "In13.Cu")
		(net "GMI_CPU0_G0_CPU1_G2_TX_DP<10>")
	)
	(segment
		(start 121.85396 -230.404924)
		(end 121.856754 -230.406448)
		(width 0.1143)
		(layer "In13.Cu")
		(net "GMI_CPU0_G0_CPU1_G2_TX_DP<10>")
	)
	(segment
		(start 349.941134 -229.960678)
		(end 349.946214 -229.904036)
		(width 0.1143)
		(layer "In13.Cu")
		(net "GMI_CPU0_G0_CPU1_G2_TX_DP<10>")
	)
	(segment
		(start 349.684594 -227.80879)
		(end 349.66402 -227.796852)
		(width 0.1143)
		(layer "In13.Cu")
		(net "GMI_CPU0_G0_CPU1_G2_TX_DP<10>")
	)
	(segment
		(start 349.705168 -229.440994)
		(end 349.630492 -229.397052)
		(width 0.1143)
		(layer "In13.Cu")
		(net "GMI_CPU0_G0_CPU1_G2_TX_DP<10>")
	)
	(segment
		(start 121.863612 -226.158806)
		(end 121.831862 -226.177094)
		(width 0.1143)
		(layer "In13.Cu")
		(net "GMI_CPU0_G0_CPU1_G2_TX_DP<10>")
	)
	(segment
		(start 121.847102 -230.400606)
		(end 121.848118 -230.401114)
		(width 0.1143)
		(layer "In13.Cu")
		(net "GMI_CPU0_G0_CPU1_G2_TX_DP<10>")
	)
	(segment
		(start 349.94596 -221.32798)
		(end 349.970852 -221.303088)
		(width 0.1143)
		(layer "In13.Cu")
		(net "GMI_CPU0_G0_CPU1_G2_TX_DP<10>")
	)
	(segment
		(start 121.83364 -223.912938)
		(end 121.834402 -223.913446)
		(width 0.1143)
		(layer "In13.Cu")
		(net "GMI_CPU0_G0_CPU1_G2_TX_DP<10>")
	)
	(segment
		(start 349.723202 -235.933742)
		(end 349.702374 -235.91901)
		(width 0.1143)
		(layer "In13.Cu")
		(net "GMI_CPU0_G0_CPU1_G2_TX_DP<10>")
	)
	(segment
		(start 308.55031 -185.03392)
		(end 307.654452 -184.623456)
		(width 0.14224)
		(layer "In13.Cu")
		(net "GMI_CPU0_G0_CPU1_G2_TX_DP<10>")
	)
	(segment
		(start 349.63227 -236.889798)
		(end 349.632524 -236.889798)
		(width 0.1143)
		(layer "In13.Cu")
		(net "GMI_CPU0_G0_CPU1_G2_TX_DP<10>")
	)
	(segment
		(start 121.831862 -234.2769)
		(end 121.831608 -234.277154)
		(width 0.1143)
		(layer "In13.Cu")
		(net "GMI_CPU0_G0_CPU1_G2_TX_DP<10>")
	)
	(segment
		(start 349.703644 -237.539784)
		(end 349.63227 -237.498382)
		(width 0.1143)
		(layer "In13.Cu")
		(net "GMI_CPU0_G0_CPU1_G2_TX_DP<10>")
	)
	(segment
		(start 349.63227 -225.549968)
		(end 349.632524 -225.549968)
		(width 0.1143)
		(layer "In13.Cu")
		(net "GMI_CPU0_G0_CPU1_G2_TX_DP<10>")
	)
	(segment
		(start 121.79554 -240.090706)
		(end 121.831862 -240.111788)
		(width 0.1143)
		(layer "In13.Cu")
		(net "GMI_CPU0_G0_CPU1_G2_TX_DP<10>")
	)
	(segment
		(start 121.853706 -234.2642)
		(end 121.852944 -234.264708)
		(width 0.1143)
		(layer "In13.Cu")
		(net "GMI_CPU0_G0_CPU1_G2_TX_DP<10>")
	)
	(segment
		(start 121.831608 -235.251752)
		(end 121.831862 -235.251752)
		(width 0.1143)
		(layer "In13.Cu")
		(net "GMI_CPU0_G0_CPU1_G2_TX_DP<10>")
	)
	(segment
		(start 349.647002 -230.401622)
		(end 349.647764 -230.401114)
		(width 0.1143)
		(layer "In13.Cu")
		(net "GMI_CPU0_G0_CPU1_G2_TX_DP<10>")
	)
	(segment
		(start 121.77268 -236.83468)
		(end 121.793508 -236.849412)
		(width 0.1143)
		(layer "In13.Cu")
		(net "GMI_CPU0_G0_CPU1_G2_TX_DP<10>")
	)
	(segment
		(start 121.84888 -230.401876)
		(end 121.85015 -230.402638)
		(width 0.1143)
		(layer "In13.Cu")
		(net "GMI_CPU0_G0_CPU1_G2_TX_DP<10>")
	)
	(segment
		(start 349.63227 -235.269786)
		(end 349.656654 -235.255816)
		(width 0.1143)
		(layer "In13.Cu")
		(net "GMI_CPU0_G0_CPU1_G2_TX_DP<10>")
	)
	(segment
		(start 349.635572 -230.408226)
		(end 349.639128 -230.406194)
		(width 0.1143)
		(layer "In13.Cu")
		(net "GMI_CPU0_G0_CPU1_G2_TX_DP<10>")
	)
	(segment
		(start 121.863358 -236.890052)
		(end 121.863612 -236.890052)
		(width 0.1143)
		(layer "In13.Cu")
		(net "GMI_CPU0_G0_CPU1_G2_TX_DP<10>")
	)
	(segment
		(start 121.863358 -225.550222)
		(end 121.863612 -225.550222)
		(width 0.1143)
		(layer "In13.Cu")
		(net "GMI_CPU0_G0_CPU1_G2_TX_DP<10>")
	)
	(segment
		(start 349.66402 -227.796852)
		(end 349.63227 -227.778564)
		(width 0.1143)
		(layer "In13.Cu")
		(net "GMI_CPU0_G0_CPU1_G2_TX_DP<10>")
	)
	(segment
		(start 121.848118 -230.401368)
		(end 121.84888 -230.401876)
		(width 0.1143)
		(layer "In13.Cu")
		(net "GMI_CPU0_G0_CPU1_G2_TX_DP<10>")
	)
	(segment
		(start 349.66402 -239.136682)
		(end 349.63227 -239.118394)
		(width 0.1143)
		(layer "In13.Cu")
		(net "GMI_CPU0_G0_CPU1_G2_TX_DP<10>")
	)
	(segment
		(start 121.85015 -230.402638)
		(end 121.851674 -230.4034)
		(width 0.1143)
		(layer "In13.Cu")
		(net "GMI_CPU0_G0_CPU1_G2_TX_DP<10>")
	)
	(segment
		(start 121.792746 -240.779554)
		(end 121.76506 -240.79962)
		(width 0.1143)
		(layer "In13.Cu")
		(net "GMI_CPU0_G0_CPU1_G2_TX_DP<10>")
	)
	(segment
		(start 146.658076 -197.972426)
		(end 144.98955 -198.47814)
		(width 0.14224)
		(layer "In13.Cu")
		(net "GMI_CPU0_G0_CPU1_G2_TX_DP<10>")
	)
	(segment
		(start 121.792746 -241.709194)
		(end 121.863612 -241.750342)
		(width 0.1143)
		(layer "In13.Cu")
		(net "GMI_CPU0_G0_CPU1_G2_TX_DP<10>")
	)
	(segment
		(start 121.834402 -235.253276)
		(end 121.835418 -235.253784)
		(width 0.1143)
		(layer "In13.Cu")
		(net "GMI_CPU0_G0_CPU1_G2_TX_DP<10>")
	)
	(segment
		(start 307.654452 -184.623456)
		(end 307.654452 -184.62371)
		(width 0.14224)
		(layer "In13.Cu")
		(net "GMI_CPU0_G0_CPU1_G2_TX_DP<10>")
	)
	(segment
		(start 121.863612 -222.918782)
		(end 121.853706 -222.92437)
		(width 0.1143)
		(layer "In13.Cu")
		(net "GMI_CPU0_G0_CPU1_G2_TX_DP<10>")
	)
	(segment
		(start 121.863612 -237.498636)
		(end 121.792238 -237.540038)
		(width 0.1143)
		(layer "In13.Cu")
		(net "GMI_CPU0_G0_CPU1_G2_TX_DP<10>")
	)
	(segment
		(start 121.792238 -238.468662)
		(end 121.863358 -238.510064)
		(width 0.1143)
		(layer "In13.Cu")
		(net "GMI_CPU0_G0_CPU1_G2_TX_DP<10>")
	)
	(segment
		(start 121.83618 -235.254292)
		(end 121.837196 -235.2548)
		(width 0.1143)
		(layer "In13.Cu")
		(net "GMI_CPU0_G0_CPU1_G2_TX_DP<10>")
	)
	(segment
		(start 349.723202 -232.693718)
		(end 349.702374 -232.678986)
		(width 0.1143)
		(layer "In13.Cu")
		(net "GMI_CPU0_G0_CPU1_G2_TX_DP<10>")
	)
	(segment
		(start 306.713636 -184.192926)
		(end 302.88992 -184.192926)
		(width 0.14224)
		(layer "In13.Cu")
		(net "GMI_CPU0_G0_CPU1_G2_TX_DP<10>")
	)
	(segment
		(start 349.083122 -242.864132)
		(end 349.013272 -242.794282)
		(width 0.1143)
		(layer "In13.Cu")
		(net "GMI_CPU0_G0_CPU1_G2_TX_DP<10>")
	)
	(segment
		(start 349.664274 -234.2769)
		(end 349.66402 -234.276646)
		(width 0.1143)
		(layer "In13.Cu")
		(net "GMI_CPU0_G0_CPU1_G2_TX_DP<10>")
	)
	(segment
		(start 121.86539 -231.017318)
		(end 121.831862 -231.036876)
		(width 0.1143)
		(layer "In13.Cu")
		(net "GMI_CPU0_G0_CPU1_G2_TX_DP<10>")
	)
	(segment
		(start 349.700342 -239.157764)
		(end 349.66402 -239.136682)
		(width 0.1143)
		(layer "In13.Cu")
		(net "GMI_CPU0_G0_CPU1_G2_TX_DP<10>")
	)
	(segment
		(start 349.685356 -227.809298)
		(end 349.684594 -227.80879)
		(width 0.1143)
		(layer "In13.Cu")
		(net "GMI_CPU0_G0_CPU1_G2_TX_DP<10>")
	)
	(segment
		(start 349.70339 -230.368856)
		(end 349.713804 -230.361236)
		(width 0.1143)
		(layer "In13.Cu")
		(net "GMI_CPU0_G0_CPU1_G2_TX_DP<10>")
	)
	(segment
		(start 349.970852 -221.145862)
		(end 350.016572 -221.100142)
		(width 0.1143)
		(layer "In13.Cu")
		(net "GMI_CPU0_G0_CPU1_G2_TX_DP<10>")
	)
	(segment
		(start 121.549668 -229.905052)
		(end 121.55678 -229.970076)
		(width 0.1143)
		(layer "In13.Cu")
		(net "GMI_CPU0_G0_CPU1_G2_TX_DP<10>")
	)
	(segment
		(start 349.700342 -226.197922)
		(end 349.66402 -226.17684)
		(width 0.1143)
		(layer "In13.Cu")
		(net "GMI_CPU0_G0_CPU1_G2_TX_DP<10>")
	)
	(segment
		(start 121.831862 -227.151946)
		(end 121.863612 -227.170234)
		(width 0.1143)
		(layer "In13.Cu")
		(net "GMI_CPU0_G0_CPU1_G2_TX_DP<10>")
	)
	(segment
		(start 349.632524 -236.889798)
		(end 349.702374 -236.849158)
		(width 0.1143)
		(layer "In13.Cu")
		(net "GMI_CPU0_G0_CPU1_G2_TX_DP<10>")
	)
	(segment
		(start 349.663766 -232.011728)
		(end 349.664528 -232.01122)
		(width 0.1143)
		(layer "In13.Cu")
		(net "GMI_CPU0_G0_CPU1_G2_TX_DP<10>")
	)
	(segment
		(start 121.863612 -240.73866)
		(end 121.792746 -240.779554)
		(width 0.1143)
		(layer "In13.Cu")
		(net "GMI_CPU0_G0_CPU1_G2_TX_DP<10>")
	)
	(segment
		(start 349.66402 -222.936816)
		(end 349.642938 -222.924624)
		(width 0.1143)
		(layer "In13.Cu")
		(net "GMI_CPU0_G0_CPU1_G2_TX_DP<10>")
	)
	(segment
		(start 349.663258 -223.912176)
		(end 349.66402 -223.911668)
		(width 0.1143)
		(layer "In13.Cu")
		(net "GMI_CPU0_G0_CPU1_G2_TX_DP<10>")
	)
	(segment
		(start 121.77268 -233.594656)
		(end 121.793508 -233.609388)
		(width 0.1143)
		(layer "In13.Cu")
		(net "GMI_CPU0_G0_CPU1_G2_TX_DP<10>")
	)
	(segment
		(start 349.702374 -233.609134)
		(end 349.723202 -233.594402)
		(width 0.1143)
		(layer "In13.Cu")
		(net "GMI_CPU0_G0_CPU1_G2_TX_DP<10>")
	)
	(segment
		(start 349.66402 -234.276646)
		(end 349.642938 -234.264454)
		(width 0.1143)
		(layer "In13.Cu")
		(net "GMI_CPU0_G0_CPU1_G2_TX_DP<10>")
	)
	(segment
		(start 349.642176 -222.924116)
		(end 349.63227 -222.918528)
		(width 0.1143)
		(layer "In13.Cu")
		(net "GMI_CPU0_G0_CPU1_G2_TX_DP<10>")
	)
	(segment
		(start 307.654452 -184.62371)
		(end 307.211984 -184.420764)
		(width 0.14224)
		(layer "In13.Cu")
		(net "GMI_CPU0_G0_CPU1_G2_TX_DP<10>")
	)
	(segment
		(start 349.63227 -233.649774)
		(end 349.632524 -233.649774)
		(width 0.1143)
		(layer "In13.Cu")
		(net "GMI_CPU0_G0_CPU1_G2_TX_DP<10>")
	)
	(segment
		(start 121.793508 -235.919264)
		(end 121.77268 -235.933996)
		(width 0.1143)
		(layer "In13.Cu")
		(net "GMI_CPU0_G0_CPU1_G2_TX_DP<10>")
	)
	(segment
		(start 162.450272 -185.0263)
		(end 146.658076 -197.972426)
		(width 0.14224)
		(layer "In13.Cu")
		(net "GMI_CPU0_G0_CPU1_G2_TX_DP<10>")
	)
	(segment
		(start 121.831862 -239.136936)
		(end 121.79554 -239.158018)
		(width 0.1143)
		(layer "In13.Cu")
		(net "GMI_CPU0_G0_CPU1_G2_TX_DP<10>")
	)
	(segment
		(start 349.63227 -240.129822)
		(end 349.66402 -240.111534)
		(width 0.1143)
		(layer "In13.Cu")
		(net "GMI_CPU0_G0_CPU1_G2_TX_DP<10>")
	)
	(segment
		(start 350.016572 -221.093538)
		(end 350.016572 -219.656406)
		(width 0.14224)
		(layer "In13.Cu")
		(net "GMI_CPU0_G0_CPU1_G2_TX_DP<10>")
	)
	(segment
		(start 121.863612 -234.258612)
		(end 121.853706 -234.2642)
		(width 0.1143)
		(layer "In13.Cu")
		(net "GMI_CPU0_G0_CPU1_G2_TX_DP<10>")
	)
	(segment
		(start 349.663258 -235.252006)
		(end 349.66402 -235.251498)
		(width 0.1143)
		(layer "In13.Cu")
		(net "GMI_CPU0_G0_CPU1_G2_TX_DP<10>")
	)
	(segment
		(start 123.755912 -215.88857)
		(end 121.47931 -219.801948)
		(width 0.14224)
		(layer "In13.Cu")
		(net "GMI_CPU0_G0_CPU1_G2_TX_DP<10>")
	)
	(segment
		(start 349.66402 -227.151692)
		(end 349.700342 -227.13061)
		(width 0.1143)
		(layer "In13.Cu")
		(net "GMI_CPU0_G0_CPU1_G2_TX_DP<10>")
	)
	(segment
		(start 121.831862 -227.797106)
		(end 121.811288 -227.809044)
		(width 0.1143)
		(layer "In13.Cu")
		(net "GMI_CPU0_G0_CPU1_G2_TX_DP<10>")
	)
	(segment
		(start 121.47931 -221.100396)
		(end 121.52503 -221.146116)
		(width 0.1143)
		(layer "In13.Cu")
		(net "GMI_CPU0_G0_CPU1_G2_TX_DP<10>")
	)
	(segment
		(start 122.302016 -242.541806)
		(end 122.332496 -242.559586)
		(width 0.1143)
		(layer "In13.Cu")
		(net "GMI_CPU0_G0_CPU1_G2_TX_DP<10>")
	)
	(segment
		(start 349.642938 -234.264454)
		(end 349.642176 -234.263946)
		(width 0.1143)
		(layer "In13.Cu")
		(net "GMI_CPU0_G0_CPU1_G2_TX_DP<10>")
	)
	(segment
		(start 121.831862 -222.93707)
		(end 121.831608 -222.937324)
		(width 0.1143)
		(layer "In13.Cu")
		(net "GMI_CPU0_G0_CPU1_G2_TX_DP<10>")
	)
	(segment
		(start 349.645732 -230.402384)
		(end 349.647002 -230.401622)
		(width 0.1143)
		(layer "In13.Cu")
		(net "GMI_CPU0_G0_CPU1_G2_TX_DP<10>")
	)
	(segment
		(start 121.832116 -232.011982)
		(end 121.863612 -232.030016)
		(width 0.1143)
		(layer "In13.Cu")
		(net "GMI_CPU0_G0_CPU1_G2_TX_DP<10>")
	)
	(segment
		(start 349.66402 -226.17684)
		(end 349.63227 -226.158552)
		(width 0.1143)
		(layer "In13.Cu")
		(net "GMI_CPU0_G0_CPU1_G2_TX_DP<10>")
	)
	(segment
		(start 349.664274 -222.93707)
		(end 349.66402 -222.936816)
		(width 0.1143)
		(layer "In13.Cu")
		(net "GMI_CPU0_G0_CPU1_G2_TX_DP<10>")
	)
	(segment
		(start 121.792238 -224.580196)
		(end 121.765822 -224.599246)
		(width 0.1143)
		(layer "In13.Cu")
		(net "GMI_CPU0_G0_CPU1_G2_TX_DP<10>")
	)
	(segment
		(start 121.863358 -238.510064)
		(end 121.863612 -238.510064)
		(width 0.1143)
		(layer "In13.Cu")
		(net "GMI_CPU0_G0_CPU1_G2_TX_DP<10>")
	)
	(segment
		(start 121.856754 -230.406448)
		(end 121.86031 -230.40848)
		(width 0.1143)
		(layer "In13.Cu")
		(net "GMI_CPU0_G0_CPU1_G2_TX_DP<10>")
	)
	(segment
		(start 302.88992 -184.192926)
		(end 166.994332 -183.401462)
		(width 0.14224)
		(layer "In13.Cu")
		(net "GMI_CPU0_G0_CPU1_G2_TX_DP<10>")
	)
	(segment
		(start 121.863612 -227.778818)
		(end 121.831862 -227.797106)
		(width 0.1143)
		(layer "In13.Cu")
		(net "GMI_CPU0_G0_CPU1_G2_TX_DP<10>")
	)
	(segment
		(start 121.549922 -221.328234)
		(end 121.549922 -221.804484)
		(width 0.1143)
		(layer "In13.Cu")
		(net "GMI_CPU0_G0_CPU1_G2_TX_DP<10>")
	)
	(segment
		(start 349.639128 -230.406194)
		(end 349.641922 -230.40467)
		(width 0.1143)
		(layer "In13.Cu")
		(net "GMI_CPU0_G0_CPU1_G2_TX_DP<10>")
	)
	(segment
		(start 121.837958 -223.915478)
		(end 121.839228 -223.91624)
		(width 0.1143)
		(layer "In13.Cu")
		(net "GMI_CPU0_G0_CPU1_G2_TX_DP<10>")
	)
	(segment
		(start 349.63227 -227.16998)
		(end 349.66402 -227.151692)
		(width 0.1143)
		(layer "In13.Cu")
		(net "GMI_CPU0_G0_CPU1_G2_TX_DP<10>")
	)
	(segment
		(start 349.669862 -231.039924)
		(end 349.66402 -231.036622)
		(width 0.1143)
		(layer "In13.Cu")
		(net "GMI_CPU0_G0_CPU1_G2_TX_DP<10>")
	)
	(segment
		(start 121.839228 -223.91624)
		(end 121.863612 -223.93021)
		(width 0.1143)
		(layer "In13.Cu")
		(net "GMI_CPU0_G0_CPU1_G2_TX_DP<10>")
	)
	(segment
		(start 121.837196 -235.2548)
		(end 121.837958 -235.255308)
		(width 0.1143)
		(layer "In13.Cu")
		(net "GMI_CPU0_G0_CPU1_G2_TX_DP<10>")
	)
	(segment
		(start 121.862596 -229.399338)
		(end 121.790714 -229.441248)
		(width 0.1143)
		(layer "In13.Cu")
		(net "GMI_CPU0_G0_CPU1_G2_TX_DP<10>")
	)
	(segment
		(start 121.837196 -223.91497)
		(end 121.837958 -223.915478)
		(width 0.1143)
		(layer "In13.Cu")
		(net "GMI_CPU0_G0_CPU1_G2_TX_DP<10>")
	)
	(segment
		(start 349.662242 -235.252514)
		(end 349.663258 -235.252006)
		(width 0.1143)
		(layer "In13.Cu")
		(net "GMI_CPU0_G0_CPU1_G2_TX_DP<10>")
	)
	(segment
		(start 349.381064 -242.864132)
		(end 349.083122 -242.864132)
		(width 0.1143)
		(layer "In13.Cu")
		(net "GMI_CPU0_G0_CPU1_G2_TX_DP<10>")
	)
	(segment
		(start 121.831862 -231.036876)
		(end 121.82602 -231.040178)
		(width 0.1143)
		(layer "In13.Cu")
		(net "GMI_CPU0_G0_CPU1_G2_TX_DP<10>")
	)
	(segment
		(start 349.66402 -231.036622)
		(end 349.630492 -231.017064)
		(width 0.1143)
		(layer "In13.Cu")
		(net "GMI_CPU0_G0_CPU1_G2_TX_DP<10>")
	)
	(segment
		(start 121.863612 -232.6386)
		(end 121.793508 -232.67924)
		(width 0.1143)
		(layer "In13.Cu")
		(net "GMI_CPU0_G0_CPU1_G2_TX_DP<10>")
	)
	(segment
		(start 350.016572 -221.100142)
		(end 350.016572 -221.093538)
		(width 0.1143)
		(layer "In13.Cu")
		(net "GMI_CPU0_G0_CPU1_G2_TX_DP<10>")
	)
	(segment
		(start 349.703644 -238.468408)
		(end 349.73006 -238.449612)
		(width 0.1143)
		(layer "In13.Cu")
		(net "GMI_CPU0_G0_CPU1_G2_TX_DP<10>")
	)
	(segment
		(start 349.66148 -223.913192)
		(end 349.662242 -223.912684)
		(width 0.1143)
		(layer "In13.Cu")
		(net "GMI_CPU0_G0_CPU1_G2_TX_DP<10>")
	)
	(segment
		(start 121.82602 -232.008426)
		(end 121.831354 -232.011474)
		(width 0.1143)
		(layer "In13.Cu")
		(net "GMI_CPU0_G0_CPU1_G2_TX_DP<10>")
	)
	(segment
		(start 121.86539 -229.397306)
		(end 121.862596 -229.399338)
		(width 0.1143)
		(layer "In13.Cu")
		(net "GMI_CPU0_G0_CPU1_G2_TX_DP<10>")
	)
	(segment
		(start 349.662242 -223.912684)
		(end 349.663258 -223.912176)
		(width 0.1143)
		(layer "In13.Cu")
		(net "GMI_CPU0_G0_CPU1_G2_TX_DP<10>")
	)
	(segment
		(start 349.66148 -235.253022)
		(end 349.662242 -235.252514)
		(width 0.1143)
		(layer "In13.Cu")
		(net "GMI_CPU0_G0_CPU1_G2_TX_DP<10>")
	)
	(segment
		(start 121.831608 -223.911922)
		(end 121.831862 -223.911922)
		(width 0.1143)
		(layer "In13.Cu")
		(net "GMI_CPU0_G0_CPU1_G2_TX_DP<10>")
	)
	(segment
		(start 349.658686 -235.254546)
		(end 349.659702 -235.254038)
		(width 0.1143)
		(layer "In13.Cu")
		(net "GMI_CPU0_G0_CPU1_G2_TX_DP<10>")
	)
	(segment
		(start 121.832624 -235.25226)
		(end 121.83364 -235.252768)
		(width 0.1143)
		(layer "In13.Cu")
		(net "GMI_CPU0_G0_CPU1_G2_TX_DP<10>")
	)
	(segment
		(start 349.647764 -230.40086)
		(end 349.70339 -230.368856)
		(width 0.1143)
		(layer "In13.Cu")
		(net "GMI_CPU0_G0_CPU1_G2_TX_DP<10>")
	)
	(segment
		(start 307.211984 -184.420764)
		(end 307.211984 -184.421018)
		(width 0.14224)
		(layer "In13.Cu")
		(net "GMI_CPU0_G0_CPU1_G2_TX_DP<10>")
	)
	(segment
		(start 349.63227 -230.410004)
		(end 349.635572 -230.408226)
		(width 0.1143)
		(layer "In13.Cu")
		(net "GMI_CPU0_G0_CPU1_G2_TX_DP<10>")
	)
	(segment
		(start 121.79554 -227.130864)
		(end 121.831862 -227.151946)
		(width 0.1143)
		(layer "In13.Cu")
		(net "GMI_CPU0_G0_CPU1_G2_TX_DP<10>")
	)
	(segment
		(start 349.703136 -241.70894)
		(end 349.730822 -241.688874)
		(width 0.1143)
		(layer "In13.Cu")
		(net "GMI_CPU0_G0_CPU1_G2_TX_DP<10>")
	)
	(segment
		(start 349.644208 -230.403146)
		(end 349.645732 -230.402384)
		(width 0.1143)
		(layer "In13.Cu")
		(net "GMI_CPU0_G0_CPU1_G2_TX_DP<10>")
	)
	(segment
		(start 121.839228 -235.25607)
		(end 121.863612 -235.27004)
		(width 0.1143)
		(layer "In13.Cu")
		(net "GMI_CPU0_G0_CPU1_G2_TX_DP<10>")
	)
	(segment
		(start 349.730822 -240.799366)
		(end 349.703136 -240.7793)
		(width 0.1143)
		(layer "In13.Cu")
		(net "GMI_CPU0_G0_CPU1_G2_TX_DP<10>")
	)
	(segment
		(start 349.63227 -223.929956)
		(end 349.66148 -223.913192)
		(width 0.1143)
		(layer "In13.Cu")
		(net "GMI_CPU0_G0_CPU1_G2_TX_DP<10>")
	)
	(segment
		(start 349.656654 -235.255816)
		(end 349.657924 -235.255054)
		(width 0.1143)
		(layer "In13.Cu")
		(net "GMI_CPU0_G0_CPU1_G2_TX_DP<10>")
	)
	(segment
		(start 349.632524 -238.50981)
		(end 349.703644 -238.468408)
		(width 0.1143)
		(layer "In13.Cu")
		(net "GMI_CPU0_G0_CPU1_G2_TX_DP<10>")
	)
	(segment
		(start 121.793508 -233.609388)
		(end 121.863358 -233.650028)
		(width 0.1143)
		(layer "In13.Cu")
		(net "GMI_CPU0_G0_CPU1_G2_TX_DP<10>")
	)
	(segment
		(start 349.703644 -225.508566)
		(end 349.73006 -225.48977)
		(width 0.1143)
		(layer "In13.Cu")
		(net "GMI_CPU0_G0_CPU1_G2_TX_DP<10>")
	)
	(segment
		(start 349.63227 -238.50981)
		(end 349.632524 -238.50981)
		(width 0.1143)
		(layer "In13.Cu")
		(net "GMI_CPU0_G0_CPU1_G2_TX_DP<10>")
	)
	(segment
		(start 121.83364 -235.252768)
		(end 121.834402 -235.253276)
		(width 0.1143)
		(layer "In13.Cu")
		(net "GMI_CPU0_G0_CPU1_G2_TX_DP<10>")
	)
	(segment
		(start 121.852944 -234.264708)
		(end 121.831862 -234.2769)
		(width 0.1143)
		(layer "In13.Cu")
		(net "GMI_CPU0_G0_CPU1_G2_TX_DP<10>")
	)
	(segment
		(start 349.66402 -235.251498)
		(end 349.664274 -235.251498)
		(width 0.1143)
		(layer "In13.Cu")
		(net "GMI_CPU0_G0_CPU1_G2_TX_DP<10>")
	)
	(segment
		(start 121.863358 -233.650028)
		(end 121.863612 -233.650028)
		(width 0.1143)
		(layer "In13.Cu")
		(net "GMI_CPU0_G0_CPU1_G2_TX_DP<10>")
	)
	(segment
		(start 349.73006 -237.558834)
		(end 349.703644 -237.539784)
		(width 0.1143)
		(layer "In13.Cu")
		(net "GMI_CPU0_G0_CPU1_G2_TX_DP<10>")
	)
	(segment
		(start 121.831862 -223.911922)
		(end 121.832624 -223.91243)
		(width 0.1143)
		(layer "In13.Cu")
		(net "GMI_CPU0_G0_CPU1_G2_TX_DP<10>")
	)
	(segment
		(start 121.83618 -223.914462)
		(end 121.837196 -223.91497)
		(width 0.1143)
		(layer "In13.Cu")
		(net "GMI_CPU0_G0_CPU1_G2_TX_DP<10>")
	)
	(segment
		(start 121.835418 -223.913954)
		(end 121.83618 -223.914462)
		(width 0.1143)
		(layer "In13.Cu")
		(net "GMI_CPU0_G0_CPU1_G2_TX_DP<10>")
	)
	(segment
		(start 349.657924 -235.255054)
		(end 349.658686 -235.254546)
		(width 0.1143)
		(layer "In13.Cu")
		(net "GMI_CPU0_G0_CPU1_G2_TX_DP<10>")
	)
	(segment
		(start 349.713804 -230.361236)
		(end 349.75673 -230.323644)
		(width 0.1143)
		(layer "In13.Cu")
		(net "GMI_CPU0_G0_CPU1_G2_TX_DP<10>")
	)
	(segment
		(start 121.765822 -238.449866)
		(end 121.792238 -238.468662)
		(width 0.1143)
		(layer "In13.Cu")
		(net "GMI_CPU0_G0_CPU1_G2_TX_DP<10>")
	)
	(segment
		(start 121.52503 -221.303342)
		(end 121.549922 -221.328234)
		(width 0.1143)
		(layer "In13.Cu")
		(net "GMI_CPU0_G0_CPU1_G2_TX_DP<10>")
	)
	(segment
		(start 349.63227 -241.750088)
		(end 349.703136 -241.70894)
		(width 0.1143)
		(layer "In13.Cu")
		(net "GMI_CPU0_G0_CPU1_G2_TX_DP<10>")
	)
	(segment
		(start 121.793508 -236.849412)
		(end 121.863358 -236.890052)
		(width 0.1143)
		(layer "In13.Cu")
		(net "GMI_CPU0_G0_CPU1_G2_TX_DP<10>")
	)
	(segment
		(start 121.835418 -235.253784)
		(end 121.83618 -235.254292)
		(width 0.1143)
		(layer "In13.Cu")
		(net "GMI_CPU0_G0_CPU1_G2_TX_DP<10>")
	)
	(segment
		(start 122.41276 -242.864386)
		(end 122.114818 -242.864386)
		(width 0.1143)
		(layer "In13.Cu")
		(net "GMI_CPU0_G0_CPU1_G2_TX_DP<10>")
	)
	(segment
		(start 349.702374 -235.91901)
		(end 349.63227 -235.87837)
		(width 0.1143)
		(layer "In13.Cu")
		(net "GMI_CPU0_G0_CPU1_G2_TX_DP<10>")
	)
	(segment
		(start 121.831354 -232.011474)
		(end 121.832116 -232.011982)
		(width 0.1143)
		(layer "In13.Cu")
		(net "GMI_CPU0_G0_CPU1_G2_TX_DP<10>")
	)
	(segment
		(start 349.632524 -225.549968)
		(end 349.703644 -225.508566)
		(width 0.1143)
		(layer "In13.Cu")
		(net "GMI_CPU0_G0_CPU1_G2_TX_DP<10>")
	)
	(segment
		(start 121.47931 -219.801948)
		(end 121.47931 -221.071948)
		(width 0.14224)
		(layer "In13.Cu")
		(net "GMI_CPU0_G0_CPU1_G2_TX_DP<10>")
	)
	(segment
		(start 349.63227 -228.789992)
		(end 349.685356 -228.759258)
		(width 0.1143)
		(layer "In13.Cu")
		(net "GMI_CPU0_G0_CPU1_G2_TX_DP<10>")
	)
	(segment
		(start 349.660464 -235.25353)
		(end 349.66148 -235.253022)
		(width 0.1143)
		(layer "In13.Cu")
		(net "GMI_CPU0_G0_CPU1_G2_TX_DP<10>")
	)
	(segment
		(start 121.834402 -223.913446)
		(end 121.835418 -223.913954)
		(width 0.1143)
		(layer "In13.Cu")
		(net "GMI_CPU0_G0_CPU1_G2_TX_DP<10>")
	)
	(segment
		(start 121.863612 -239.118648)
		(end 121.831862 -239.136936)
		(width 0.1143)
		(layer "In13.Cu")
		(net "GMI_CPU0_G0_CPU1_G2_TX_DP<10>")
	)
	(segment
		(start 349.702374 -232.678986)
		(end 349.63227 -232.638346)
		(width 0.1143)
		(layer "In13.Cu")
		(net "GMI_CPU0_G0_CPU1_G2_TX_DP<10>")
	)
	(segment
		(start 313.12739 -187.624974)
		(end 308.55031 -185.03392)
		(width 0.14224)
		(layer "In13.Cu")
		(net "GMI_CPU0_G0_CPU1_G2_TX_DP<10>")
	)
	(segment
		(start 349.66402 -240.111534)
		(end 349.700342 -240.090452)
		(width 0.1143)
		(layer "In13.Cu")
		(net "GMI_CPU0_G0_CPU1_G2_TX_DP<10>")
	)
	(segment
		(start 121.811288 -227.809044)
		(end 121.810526 -227.809552)
		(width 0.1143)
		(layer "In13.Cu")
		(net "GMI_CPU0_G0_CPU1_G2_TX_DP<10>")
	)
	(segment
		(start 121.729246 -230.312976)
		(end 121.784618 -230.364538)
		(width 0.1143)
		(layer "In13.Cu")
		(net "GMI_CPU0_G0_CPU1_G2_TX_DP<10>")
	)
	(segment
		(start 121.831862 -226.177094)
		(end 121.79554 -226.198176)
		(width 0.1143)
		(layer "In13.Cu")
		(net "GMI_CPU0_G0_CPU1_G2_TX_DP<10>")
	)
	(segment
		(start 121.831862 -235.251752)
		(end 121.832624 -235.25226)
		(width 0.1143)
		(layer "In13.Cu")
		(net "GMI_CPU0_G0_CPU1_G2_TX_DP<10>")
	)
	(segment
		(start 121.47931 -221.071948)
		(end 121.47931 -221.100396)
		(width 0.1143)
		(layer "In13.Cu")
		(net "GMI_CPU0_G0_CPU1_G2_TX_DP<10>")
	)
	(segment
		(start 166.994332 -183.401462)
		(end 162.450272 -185.0263)
		(width 0.14224)
		(layer "In13.Cu")
		(net "GMI_CPU0_G0_CPU1_G2_TX_DP<10>")
	)
	(segment
		(start 347.952314 -216.179654)
		(end 313.12739 -187.624974)
		(width 0.14224)
		(layer "In13.Cu")
		(net "GMI_CPU0_G0_CPU1_G2_TX_DP<10>")
	)
	(arc
		(start 121.779284 -227.119434)
		(mid 121.787362 -227.12522)
		(end 121.79554 -227.130864)
		(width 0.1143)
		(layer "In13.Cu")
		(net "GMI_CPU0_G0_CPU1_G2_TX_DP<10>")
	)
	(arc
		(start 349.664274 -235.251498)
		(mid 349.944701 -234.764262)
		(end 349.664274 -234.2769)
		(width 0.1143)
		(layer "In13.Cu")
		(net "GMI_CPU0_G0_CPU1_G2_TX_DP<10>")
	)
	(arc
		(start 121.863612 -228.790246)
		(mid 121.978288 -228.92358)
		(end 122.019568 -229.094538)
		(width 0.1143)
		(layer "In13.Cu")
		(net "GMI_CPU0_G0_CPU1_G2_TX_DP<10>")
	)
	(arc
		(start 349.702882 -222.268796)
		(mid 349.881525 -222.066401)
		(end 349.94596 -221.80423)
		(width 0.1143)
		(layer "In13.Cu")
		(net "GMI_CPU0_G0_CPU1_G2_TX_DP<10>")
	)
	(arc
		(start 122.019568 -222.61449)
		(mid 121.978313 -222.785461)
		(end 121.863612 -222.918782)
		(width 0.1143)
		(layer "In13.Cu")
		(net "GMI_CPU0_G0_CPU1_G2_TX_DP<10>")
	)
	(arc
		(start 349.723202 -233.594402)
		(mid 349.954471 -233.14406)
		(end 349.723202 -232.693718)
		(width 0.1143)
		(layer "In13.Cu")
		(net "GMI_CPU0_G0_CPU1_G2_TX_DP<10>")
	)
	(arc
		(start 349.630492 -231.017064)
		(mid 349.517085 -230.884175)
		(end 349.476314 -230.714296)
		(width 0.1143)
		(layer "In13.Cu")
		(net "GMI_CPU0_G0_CPU1_G2_TX_DP<10>")
	)
	(arc
		(start 349.946214 -229.904036)
		(mid 349.882408 -229.642983)
		(end 349.705168 -229.440994)
		(width 0.1143)
		(layer "In13.Cu")
		(net "GMI_CPU0_G0_CPU1_G2_TX_DP<10>")
	)
	(arc
		(start 349.630492 -229.397052)
		(mid 349.517085 -229.264163)
		(end 349.476314 -229.094284)
		(width 0.1143)
		(layer "In13.Cu")
		(net "GMI_CPU0_G0_CPU1_G2_TX_DP<10>")
	)
	(arc
		(start 349.476314 -229.094284)
		(mid 349.517569 -228.923313)
		(end 349.63227 -228.789992)
		(width 0.1143)
		(layer "In13.Cu")
		(net "GMI_CPU0_G0_CPU1_G2_TX_DP<10>")
	)
	(arc
		(start 349.63227 -222.918528)
		(mid 349.517594 -222.785194)
		(end 349.476314 -222.614236)
		(width 0.1143)
		(layer "In13.Cu")
		(net "GMI_CPU0_G0_CPU1_G2_TX_DP<10>")
	)
	(arc
		(start 349.63227 -224.53854)
		(mid 349.476342 -224.234248)
		(end 349.63227 -223.929956)
		(width 0.1143)
		(layer "In13.Cu")
		(net "GMI_CPU0_G0_CPU1_G2_TX_DP<10>")
	)
	(arc
		(start 121.831608 -222.937324)
		(mid 121.550961 -223.424686)
		(end 121.831608 -223.911922)
		(width 0.1143)
		(layer "In13.Cu")
		(net "GMI_CPU0_G0_CPU1_G2_TX_DP<10>")
	)
	(arc
		(start 121.863612 -223.93021)
		(mid 122.01954 -224.234502)
		(end 121.863612 -224.538794)
		(width 0.1143)
		(layer "In13.Cu")
		(net "GMI_CPU0_G0_CPU1_G2_TX_DP<10>")
	)
	(arc
		(start 121.863612 -236.890052)
		(mid 122.01954 -237.194344)
		(end 121.863612 -237.498636)
		(width 0.1143)
		(layer "In13.Cu")
		(net "GMI_CPU0_G0_CPU1_G2_TX_DP<10>")
	)
	(arc
		(start 349.73006 -225.48977)
		(mid 349.95805 -225.044434)
		(end 349.73006 -224.598992)
		(width 0.1143)
		(layer "In13.Cu")
		(net "GMI_CPU0_G0_CPU1_G2_TX_DP<10>")
	)
	(arc
		(start 349.664274 -223.911668)
		(mid 349.944701 -223.424432)
		(end 349.664274 -222.93707)
		(width 0.1143)
		(layer "In13.Cu")
		(net "GMI_CPU0_G0_CPU1_G2_TX_DP<10>")
	)
	(arc
		(start 349.476314 -222.614236)
		(mid 349.517863 -222.442814)
		(end 349.633286 -222.309436)
		(width 0.1143)
		(layer "In13.Cu")
		(net "GMI_CPU0_G0_CPU1_G2_TX_DP<10>")
	)
	(arc
		(start 121.863612 -241.750342)
		(mid 121.912522 -241.792313)
		(end 121.953528 -241.842036)
		(width 0.1143)
		(layer "In13.Cu")
		(net "GMI_CPU0_G0_CPU1_G2_TX_DP<10>")
	)
	(arc
		(start 121.77268 -232.693972)
		(mid 121.541411 -233.144314)
		(end 121.77268 -233.594656)
		(width 0.1143)
		(layer "In13.Cu")
		(net "GMI_CPU0_G0_CPU1_G2_TX_DP<10>")
	)
	(arc
		(start 122.019568 -229.094538)
		(mid 121.978806 -229.264422)
		(end 121.86539 -229.397306)
		(width 0.1143)
		(layer "In13.Cu")
		(net "GMI_CPU0_G0_CPU1_G2_TX_DP<10>")
	)
	(arc
		(start 121.77268 -235.933996)
		(mid 121.541411 -236.384338)
		(end 121.77268 -236.83468)
		(width 0.1143)
		(layer "In13.Cu")
		(net "GMI_CPU0_G0_CPU1_G2_TX_DP<10>")
	)
	(arc
		(start 121.831608 -234.277154)
		(mid 121.550961 -234.764516)
		(end 121.831608 -235.251752)
		(width 0.1143)
		(layer "In13.Cu")
		(net "GMI_CPU0_G0_CPU1_G2_TX_DP<10>")
	)
	(arc
		(start 121.781316 -240.0808)
		(mid 121.78839 -240.085807)
		(end 121.79554 -240.090706)
		(width 0.1143)
		(layer "In13.Cu")
		(net "GMI_CPU0_G0_CPU1_G2_TX_DP<10>")
	)
	(arc
		(start 349.716598 -226.209352)
		(mid 349.70852 -226.203566)
		(end 349.700342 -226.197922)
		(width 0.1143)
		(layer "In13.Cu")
		(net "GMI_CPU0_G0_CPU1_G2_TX_DP<10>")
	)
	(arc
		(start 349.685356 -228.759258)
		(mid 349.958907 -228.284278)
		(end 349.685356 -227.809298)
		(width 0.1143)
		(layer "In13.Cu")
		(net "GMI_CPU0_G0_CPU1_G2_TX_DP<10>")
	)
	(arc
		(start 121.79554 -226.198176)
		(mid 121.787362 -226.203819)
		(end 121.779284 -226.209606)
		(width 0.1143)
		(layer "In13.Cu")
		(net "GMI_CPU0_G0_CPU1_G2_TX_DP<10>")
	)
	(arc
		(start 349.73006 -238.449612)
		(mid 349.95805 -238.004276)
		(end 349.73006 -237.558834)
		(width 0.1143)
		(layer "In13.Cu")
		(net "GMI_CPU0_G0_CPU1_G2_TX_DP<10>")
	)
	(arc
		(start 121.810526 -227.809552)
		(mid 121.536975 -228.284532)
		(end 121.810526 -228.759512)
		(width 0.1143)
		(layer "In13.Cu")
		(net "GMI_CPU0_G0_CPU1_G2_TX_DP<10>")
	)
	(arc
		(start 349.476314 -242.054126)
		(mid 349.493185 -241.942925)
		(end 349.542354 -241.841782)
		(width 0.1143)
		(layer "In13.Cu")
		(net "GMI_CPU0_G0_CPU1_G2_TX_DP<10>")
	)
	(arc
		(start 349.700342 -240.090452)
		(mid 349.707492 -240.085554)
		(end 349.714566 -240.080546)
		(width 0.1143)
		(layer "In13.Cu")
		(net "GMI_CPU0_G0_CPU1_G2_TX_DP<10>")
	)
	(arc
		(start 349.716598 -227.11918)
		(mid 349.939482 -226.664266)
		(end 349.716598 -226.209352)
		(width 0.1143)
		(layer "In13.Cu")
		(net "GMI_CPU0_G0_CPU1_G2_TX_DP<10>")
	)
	(arc
		(start 349.63227 -237.498382)
		(mid 349.476342 -237.19409)
		(end 349.63227 -236.889798)
		(width 0.1143)
		(layer "In13.Cu")
		(net "GMI_CPU0_G0_CPU1_G2_TX_DP<10>")
	)
	(arc
		(start 122.332496 -242.559586)
		(mid 122.430261 -242.662562)
		(end 122.48261 -242.794536)
		(width 0.1143)
		(layer "In13.Cu")
		(net "GMI_CPU0_G0_CPU1_G2_TX_DP<10>")
	)
	(arc
		(start 121.781316 -239.167924)
		(mid 121.553933 -239.624362)
		(end 121.781316 -240.0808)
		(width 0.1143)
		(layer "In13.Cu")
		(net "GMI_CPU0_G0_CPU1_G2_TX_DP<10>")
	)
	(arc
		(start 349.63227 -240.738406)
		(mid 349.476342 -240.434114)
		(end 349.63227 -240.129822)
		(width 0.1143)
		(layer "In13.Cu")
		(net "GMI_CPU0_G0_CPU1_G2_TX_DP<10>")
	)
	(arc
		(start 121.55678 -229.970076)
		(mid 121.611909 -230.157171)
		(end 121.729246 -230.312976)
		(width 0.1143)
		(layer "In13.Cu")
		(net "GMI_CPU0_G0_CPU1_G2_TX_DP<10>")
	)
	(arc
		(start 121.549922 -221.804484)
		(mid 121.614296 -222.066688)
		(end 121.793 -222.26905)
		(width 0.1143)
		(layer "In13.Cu")
		(net "GMI_CPU0_G0_CPU1_G2_TX_DP<10>")
	)
	(arc
		(start 349.63227 -226.158552)
		(mid 349.476342 -225.85426)
		(end 349.63227 -225.549968)
		(width 0.1143)
		(layer "In13.Cu")
		(net "GMI_CPU0_G0_CPU1_G2_TX_DP<10>")
	)
	(arc
		(start 349.714566 -239.16767)
		(mid 349.707493 -239.162661)
		(end 349.700342 -239.157764)
		(width 0.1143)
		(layer "In13.Cu")
		(net "GMI_CPU0_G0_CPU1_G2_TX_DP<10>")
	)
	(arc
		(start 121.863612 -240.130076)
		(mid 122.01954 -240.434368)
		(end 121.863612 -240.73866)
		(width 0.1143)
		(layer "In13.Cu")
		(net "GMI_CPU0_G0_CPU1_G2_TX_DP<10>")
	)
	(arc
		(start 122.019568 -230.71455)
		(mid 121.978806 -230.884434)
		(end 121.86539 -231.017318)
		(width 0.1143)
		(layer "In13.Cu")
		(net "GMI_CPU0_G0_CPU1_G2_TX_DP<10>")
	)
	(arc
		(start 349.714566 -240.080546)
		(mid 349.941949 -239.624108)
		(end 349.714566 -239.16767)
		(width 0.1143)
		(layer "In13.Cu")
		(net "GMI_CPU0_G0_CPU1_G2_TX_DP<10>")
	)
	(arc
		(start 349.723202 -236.834426)
		(mid 349.954471 -236.384084)
		(end 349.723202 -235.933742)
		(width 0.1143)
		(layer "In13.Cu")
		(net "GMI_CPU0_G0_CPU1_G2_TX_DP<10>")
	)
	(arc
		(start 121.863612 -235.27004)
		(mid 122.01954 -235.574332)
		(end 121.863612 -235.878624)
		(width 0.1143)
		(layer "In13.Cu")
		(net "GMI_CPU0_G0_CPU1_G2_TX_DP<10>")
	)
	(arc
		(start 121.765822 -237.559088)
		(mid 121.537626 -238.00453)
		(end 121.765822 -238.449866)
		(width 0.1143)
		(layer "In13.Cu")
		(net "GMI_CPU0_G0_CPU1_G2_TX_DP<10>")
	)
	(arc
		(start 349.63227 -227.778564)
		(mid 349.476342 -227.474272)
		(end 349.63227 -227.16998)
		(width 0.1143)
		(layer "In13.Cu")
		(net "GMI_CPU0_G0_CPU1_G2_TX_DP<10>")
	)
	(arc
		(start 121.953528 -241.842036)
		(mid 122.002612 -241.943205)
		(end 122.019568 -242.05438)
		(width 0.1143)
		(layer "In13.Cu")
		(net "GMI_CPU0_G0_CPU1_G2_TX_DP<10>")
	)
	(arc
		(start 349.63227 -235.87837)
		(mid 349.476342 -235.574078)
		(end 349.63227 -235.269786)
		(width 0.1143)
		(layer "In13.Cu")
		(net "GMI_CPU0_G0_CPU1_G2_TX_DP<10>")
	)
	(arc
		(start 121.863612 -233.650028)
		(mid 122.01954 -233.95432)
		(end 121.863612 -234.258612)
		(width 0.1143)
		(layer "In13.Cu")
		(net "GMI_CPU0_G0_CPU1_G2_TX_DP<10>")
	)
	(arc
		(start 349.232982 -242.518692)
		(mid 349.411795 -242.316342)
		(end 349.476314 -242.054126)
		(width 0.1143)
		(layer "In13.Cu")
		(net "GMI_CPU0_G0_CPU1_G2_TX_DP<10>")
	)
	(arc
		(start 349.63227 -232.638346)
		(mid 349.476342 -232.334054)
		(end 349.63227 -232.029762)
		(width 0.1143)
		(layer "In13.Cu")
		(net "GMI_CPU0_G0_CPU1_G2_TX_DP<10>")
	)
	(arc
		(start 122.019568 -242.05438)
		(mid 122.084083 -242.316599)
		(end 122.2629 -242.518946)
		(width 0.1143)
		(layer "In13.Cu")
		(net "GMI_CPU0_G0_CPU1_G2_TX_DP<10>")
	)
	(arc
		(start 121.863612 -230.410258)
		(mid 121.978288 -230.543592)
		(end 122.019568 -230.71455)
		(width 0.1143)
		(layer "In13.Cu")
		(net "GMI_CPU0_G0_CPU1_G2_TX_DP<10>")
	)
	(arc
		(start 121.863612 -225.550222)
		(mid 122.01954 -225.854514)
		(end 121.863612 -226.158806)
		(width 0.1143)
		(layer "In13.Cu")
		(net "GMI_CPU0_G0_CPU1_G2_TX_DP<10>")
	)
	(arc
		(start 349.730822 -241.688874)
		(mid 349.958822 -241.24412)
		(end 349.730822 -240.799366)
		(width 0.1143)
		(layer "In13.Cu")
		(net "GMI_CPU0_G0_CPU1_G2_TX_DP<10>")
	)
	(arc
		(start 349.75673 -230.323644)
		(mid 349.883803 -230.159884)
		(end 349.941134 -229.960678)
		(width 0.1143)
		(layer "In13.Cu")
		(net "GMI_CPU0_G0_CPU1_G2_TX_DP<10>")
	)
	(arc
		(start 121.76506 -240.79962)
		(mid 121.53706 -241.244374)
		(end 121.76506 -241.689128)
		(width 0.1143)
		(layer "In13.Cu")
		(net "GMI_CPU0_G0_CPU1_G2_TX_DP<10>")
	)
	(arc
		(start 121.862596 -222.30969)
		(mid 121.978023 -222.443066)
		(end 122.019568 -222.61449)
		(width 0.1143)
		(layer "In13.Cu")
		(net "GMI_CPU0_G0_CPU1_G2_TX_DP<10>")
	)
	(arc
		(start 349.700342 -227.13061)
		(mid 349.70852 -227.124967)
		(end 349.716598 -227.11918)
		(width 0.1143)
		(layer "In13.Cu")
		(net "GMI_CPU0_G0_CPU1_G2_TX_DP<10>")
	)
	(arc
		(start 349.542354 -241.841782)
		(mid 349.583343 -241.792041)
		(end 349.63227 -241.750088)
		(width 0.1143)
		(layer "In13.Cu")
		(net "GMI_CPU0_G0_CPU1_G2_TX_DP<10>")
	)
	(arc
		(start 349.013272 -242.794282)
		(mid 349.065689 -242.662351)
		(end 349.163386 -242.559332)
		(width 0.1143)
		(layer "In13.Cu")
		(net "GMI_CPU0_G0_CPU1_G2_TX_DP<10>")
	)
	(arc
		(start 121.779284 -226.209606)
		(mid 121.5564 -226.66452)
		(end 121.779284 -227.119434)
		(width 0.1143)
		(layer "In13.Cu")
		(net "GMI_CPU0_G0_CPU1_G2_TX_DP<10>")
	)
	(arc
		(start 121.79554 -239.158018)
		(mid 121.788391 -239.162918)
		(end 121.781316 -239.167924)
		(width 0.1143)
		(layer "In13.Cu")
		(net "GMI_CPU0_G0_CPU1_G2_TX_DP<10>")
	)
	(arc
		(start 349.476314 -230.714296)
		(mid 349.517569 -230.543325)
		(end 349.63227 -230.410004)
		(width 0.1143)
		(layer "In13.Cu")
		(net "GMI_CPU0_G0_CPU1_G2_TX_DP<10>")
	)
	(arc
		(start 121.863612 -227.170234)
		(mid 122.01954 -227.474526)
		(end 121.863612 -227.778818)
		(width 0.1143)
		(layer "In13.Cu")
		(net "GMI_CPU0_G0_CPU1_G2_TX_DP<10>")
	)
	(arc
		(start 349.63227 -239.118394)
		(mid 349.476342 -238.814102)
		(end 349.63227 -238.50981)
		(width 0.1143)
		(layer "In13.Cu")
		(net "GMI_CPU0_G0_CPU1_G2_TX_DP<10>")
	)
	(arc
		(start 121.863612 -238.510064)
		(mid 122.01954 -238.814356)
		(end 121.863612 -239.118648)
		(width 0.1143)
		(layer "In13.Cu")
		(net "GMI_CPU0_G0_CPU1_G2_TX_DP<10>")
	)
	(arc
		(start 121.82602 -231.040178)
		(mid 121.547217 -231.524302)
		(end 121.82602 -232.008426)
		(width 0.1143)
		(layer "In13.Cu")
		(net "GMI_CPU0_G0_CPU1_G2_TX_DP<10>")
	)
	(arc
		(start 121.863612 -232.030016)
		(mid 122.01954 -232.334308)
		(end 121.863612 -232.6386)
		(width 0.1143)
		(layer "In13.Cu")
		(net "GMI_CPU0_G0_CPU1_G2_TX_DP<10>")
	)
	(arc
		(start 349.63227 -234.258358)
		(mid 349.476342 -233.954066)
		(end 349.63227 -233.649774)
		(width 0.1143)
		(layer "In13.Cu")
		(net "GMI_CPU0_G0_CPU1_G2_TX_DP<10>")
	)
	(arc
		(start 121.790714 -229.441248)
		(mid 121.613342 -229.643598)
		(end 121.549668 -229.905052)
		(width 0.1143)
		(layer "In13.Cu")
		(net "GMI_CPU0_G0_CPU1_G2_TX_DP<10>")
	)
	(arc
		(start 121.765822 -224.599246)
		(mid 121.537626 -225.044688)
		(end 121.765822 -225.490024)
		(width 0.1143)
		(layer "In13.Cu")
		(net "GMI_CPU0_G0_CPU1_G2_TX_DP<10>")
	)
	(arc
		(start 349.669862 -232.008172)
		(mid 349.948665 -231.524048)
		(end 349.669862 -231.039924)
		(width 0.1143)
		(layer "In13.Cu")
		(net "GMI_CPU0_G0_CPU1_G2_TX_DP<10>")
	)
	(segment
		(start 113.657888 -242.320318)
		(end 114.12474 -242.05438)
		(width 0.12954)
		(layer "F.Cu")
		(net "GMI_CPU0_G0_CPU1_G2_TX_DP<0>")
	)
	(segment
		(start 357.837994 -242.320064)
		(end 357.371142 -242.054126)
		(width 0.12954)
		(layer "F.Cu")
		(net "GMI_CPU0_G0_CPU1_G2_TX_DP<0>")
	)
	(segment
		(start 311.920382 -175.927512)
		(end 308.723538 -174.784512)
		(width 0.14224)
		(layer "In13.Cu")
		(net "GMI_CPU0_G0_CPU1_G2_TX_DP<0>")
	)
	(segment
		(start 112.0775 -237.374684)
		(end 112.0775 -237.555532)
		(width 0.1143)
		(layer "In13.Cu")
		(net "GMI_CPU0_G0_CPU1_G2_TX_DP<0>")
	)
	(segment
		(start 355.997764 -210.38312)
		(end 318.563752 -179.688236)
		(width 0.14224)
		(layer "In13.Cu")
		(net "GMI_CPU0_G0_CPU1_G2_TX_DP<0>")
	)
	(segment
		(start 113.371884 -240.111788)
		(end 113.402364 -240.129568)
		(width 0.1143)
		(layer "In13.Cu")
		(net "GMI_CPU0_G0_CPU1_G2_TX_DP<0>")
	)
	(segment
		(start 113.809526 -240.902998)
		(end 113.810288 -240.903506)
		(width 0.1143)
		(layer "In13.Cu")
		(net "GMI_CPU0_G0_CPU1_G2_TX_DP<0>")
	)
	(segment
		(start 113.843054 -240.922302)
		(end 113.851944 -240.927636)
		(width 0.1143)
		(layer "In13.Cu")
		(net "GMI_CPU0_G0_CPU1_G2_TX_DP<0>")
	)
	(segment
		(start 113.842546 -240.922302)
		(end 113.843054 -240.922302)
		(width 0.1143)
		(layer "In13.Cu")
		(net "GMI_CPU0_G0_CPU1_G2_TX_DP<0>")
	)
	(segment
		(start 115.409726 -210.375246)
		(end 112.03051 -216.123266)
		(width 0.14224)
		(layer "In13.Cu")
		(net "GMI_CPU0_G0_CPU1_G2_TX_DP<0>")
	)
	(segment
		(start 114.311938 -241.7318)
		(end 114.343434 -241.750342)
		(width 0.1143)
		(layer "In13.Cu")
		(net "GMI_CPU0_G0_CPU1_G2_TX_DP<0>")
	)
	(segment
		(start 318.563752 -179.688236)
		(end 311.920382 -175.927512)
		(width 0.14224)
		(layer "In13.Cu")
		(net "GMI_CPU0_G0_CPU1_G2_TX_DP<0>")
	)
	(segment
		(start 135.687054 -193.748152)
		(end 115.409726 -210.375246)
		(width 0.14224)
		(layer "In13.Cu")
		(net "GMI_CPU0_G0_CPU1_G2_TX_DP<0>")
	)
	(segment
		(start 357.0732 -242.054126)
		(end 357.003096 -241.984022)
		(width 0.1143)
		(layer "In13.Cu")
		(net "GMI_CPU0_G0_CPU1_G2_TX_DP<0>")
	)
	(segment
		(start 357.655114 -240.921032)
		(end 357.657654 -240.919508)
		(width 0.1143)
		(layer "In13.Cu")
		(net "GMI_CPU0_G0_CPU1_G2_TX_DP<0>")
	)
	(segment
		(start 302.9204 -174.784512)
		(end 164.760148 -173.975776)
		(width 0.14224)
		(layer "In13.Cu")
		(net "GMI_CPU0_G0_CPU1_G2_TX_DP<0>")
	)
	(segment
		(start 114.422682 -242.05438)
		(end 114.12474 -242.05438)
		(width 0.1143)
		(layer "In13.Cu")
		(net "GMI_CPU0_G0_CPU1_G2_TX_DP<0>")
	)
	(segment
		(start 357.685594 -240.903252)
		(end 357.686356 -240.902744)
		(width 0.1143)
		(layer "In13.Cu")
		(net "GMI_CPU0_G0_CPU1_G2_TX_DP<0>")
	)
	(segment
		(start 357.657654 -240.919508)
		(end 357.658416 -240.919)
		(width 0.1143)
		(layer "In13.Cu")
		(net "GMI_CPU0_G0_CPU1_G2_TX_DP<0>")
	)
	(segment
		(start 358.123998 -240.111534)
		(end 358.16032 -240.090452)
		(width 0.1143)
		(layer "In13.Cu")
		(net "GMI_CPU0_G0_CPU1_G2_TX_DP<0>")
	)
	(segment
		(start 357.658416 -240.919)
		(end 357.685594 -240.903252)
		(width 0.1143)
		(layer "In13.Cu")
		(net "GMI_CPU0_G0_CPU1_G2_TX_DP<0>")
	)
	(segment
		(start 358.709722 -239.212628)
		(end 358.747822 -239.174528)
		(width 0.1143)
		(layer "In13.Cu")
		(net "GMI_CPU0_G0_CPU1_G2_TX_DP<0>")
	)
	(segment
		(start 357.457756 -241.25682)
		(end 357.457756 -241.250978)
		(width 0.1143)
		(layer "In13.Cu")
		(net "GMI_CPU0_G0_CPU1_G2_TX_DP<0>")
	)
	(segment
		(start 155.964382 -177.121312)
		(end 135.687562 -193.747898)
		(width 0.14224)
		(layer "In13.Cu")
		(net "GMI_CPU0_G0_CPU1_G2_TX_DP<0>")
	)
	(segment
		(start 308.723538 -174.784512)
		(end 302.9204 -174.784512)
		(width 0.14224)
		(layer "In13.Cu")
		(net "GMI_CPU0_G0_CPU1_G2_TX_DP<0>")
	)
	(segment
		(start 357.686356 -240.902744)
		(end 357.693214 -240.89868)
		(width 0.1143)
		(layer "In13.Cu")
		(net "GMI_CPU0_G0_CPU1_G2_TX_DP<0>")
	)
	(segment
		(start 135.687562 -193.747898)
		(end 135.687054 -193.748152)
		(width 0.14224)
		(layer "In13.Cu")
		(net "GMI_CPU0_G0_CPU1_G2_TX_DP<0>")
	)
	(segment
		(start 357.643938 -240.927382)
		(end 357.652828 -240.922048)
		(width 0.1143)
		(layer "In13.Cu")
		(net "GMI_CPU0_G0_CPU1_G2_TX_DP<0>")
	)
	(segment
		(start 357.653336 -240.922048)
		(end 357.654098 -240.92154)
		(width 0.1143)
		(layer "In13.Cu")
		(net "GMI_CPU0_G0_CPU1_G2_TX_DP<0>")
	)
	(segment
		(start 359.465372 -237.32744)
		(end 359.465372 -216.223342)
		(width 0.14224)
		(layer "In13.Cu")
		(net "GMI_CPU0_G0_CPU1_G2_TX_DP<0>")
	)
	(segment
		(start 112.03051 -216.123266)
		(end 112.03051 -237.327694)
		(width 0.14224)
		(layer "In13.Cu")
		(net "GMI_CPU0_G0_CPU1_G2_TX_DP<0>")
	)
	(segment
		(start 357.654098 -240.92154)
		(end 357.655114 -240.921032)
		(width 0.1143)
		(layer "In13.Cu")
		(net "GMI_CPU0_G0_CPU1_G2_TX_DP<0>")
	)
	(segment
		(start 164.760148 -173.975776)
		(end 155.964382 -177.121312)
		(width 0.14224)
		(layer "In13.Cu")
		(net "GMI_CPU0_G0_CPU1_G2_TX_DP<0>")
	)
	(segment
		(start 357.371142 -242.054126)
		(end 357.0732 -242.054126)
		(width 0.1143)
		(layer "In13.Cu")
		(net "GMI_CPU0_G0_CPU1_G2_TX_DP<0>")
	)
	(segment
		(start 114.038126 -241.251232)
		(end 114.038126 -241.257074)
		(width 0.1143)
		(layer "In13.Cu")
		(net "GMI_CPU0_G0_CPU1_G2_TX_DP<0>")
	)
	(segment
		(start 357.152448 -241.750088)
		(end 357.183944 -241.731546)
		(width 0.1143)
		(layer "In13.Cu")
		(net "GMI_CPU0_G0_CPU1_G2_TX_DP<0>")
	)
	(segment
		(start 358.562148 -239.319816)
		(end 358.593898 -239.301528)
		(width 0.1143)
		(layer "In13.Cu")
		(net "GMI_CPU0_G0_CPU1_G2_TX_DP<0>")
	)
	(segment
		(start 359.418382 -237.555278)
		(end 359.418382 -237.37443)
		(width 0.1143)
		(layer "In13.Cu")
		(net "GMI_CPU0_G0_CPU1_G2_TX_DP<0>")
	)
	(segment
		(start 356.851204 -211.82076)
		(end 355.997764 -210.38312)
		(width 0.14224)
		(layer "In13.Cu")
		(net "GMI_CPU0_G0_CPU1_G2_TX_DP<0>")
	)
	(segment
		(start 359.418382 -237.37443)
		(end 359.465372 -237.32744)
		(width 0.1143)
		(layer "In13.Cu")
		(net "GMI_CPU0_G0_CPU1_G2_TX_DP<0>")
	)
	(segment
		(start 356.851458 -211.820506)
		(end 356.851204 -211.82076)
		(width 0.14224)
		(layer "In13.Cu")
		(net "GMI_CPU0_G0_CPU1_G2_TX_DP<0>")
	)
	(segment
		(start 112.901984 -239.301782)
		(end 112.933734 -239.32007)
		(width 0.1143)
		(layer "In13.Cu")
		(net "GMI_CPU0_G0_CPU1_G2_TX_DP<0>")
	)
	(segment
		(start 113.802668 -240.898934)
		(end 113.809526 -240.902998)
		(width 0.1143)
		(layer "In13.Cu")
		(net "GMI_CPU0_G0_CPU1_G2_TX_DP<0>")
	)
	(segment
		(start 113.841784 -240.921794)
		(end 113.842546 -240.922302)
		(width 0.1143)
		(layer "In13.Cu")
		(net "GMI_CPU0_G0_CPU1_G2_TX_DP<0>")
	)
	(segment
		(start 114.492786 -241.984276)
		(end 114.422682 -242.05438)
		(width 0.1143)
		(layer "In13.Cu")
		(net "GMI_CPU0_G0_CPU1_G2_TX_DP<0>")
	)
	(segment
		(start 112.74806 -239.174782)
		(end 112.78616 -239.212882)
		(width 0.1143)
		(layer "In13.Cu")
		(net "GMI_CPU0_G0_CPU1_G2_TX_DP<0>")
	)
	(segment
		(start 113.810288 -240.903506)
		(end 113.840768 -240.921286)
		(width 0.1143)
		(layer "In13.Cu")
		(net "GMI_CPU0_G0_CPU1_G2_TX_DP<0>")
	)
	(segment
		(start 113.335562 -240.090706)
		(end 113.371884 -240.111788)
		(width 0.1143)
		(layer "In13.Cu")
		(net "GMI_CPU0_G0_CPU1_G2_TX_DP<0>")
	)
	(segment
		(start 112.03051 -237.327694)
		(end 112.0775 -237.374684)
		(width 0.1143)
		(layer "In13.Cu")
		(net "GMI_CPU0_G0_CPU1_G2_TX_DP<0>")
	)
	(segment
		(start 113.840768 -240.921286)
		(end 113.841784 -240.921794)
		(width 0.1143)
		(layer "In13.Cu")
		(net "GMI_CPU0_G0_CPU1_G2_TX_DP<0>")
	)
	(segment
		(start 358.093518 -240.129314)
		(end 358.123998 -240.111534)
		(width 0.1143)
		(layer "In13.Cu")
		(net "GMI_CPU0_G0_CPU1_G2_TX_DP<0>")
	)
	(segment
		(start 359.465372 -216.223342)
		(end 356.851458 -211.820506)
		(width 0.14224)
		(layer "In13.Cu")
		(net "GMI_CPU0_G0_CPU1_G2_TX_DP<0>")
	)
	(segment
		(start 357.652828 -240.922048)
		(end 357.653336 -240.922048)
		(width 0.1143)
		(layer "In13.Cu")
		(net "GMI_CPU0_G0_CPU1_G2_TX_DP<0>")
	)
	(arc
		(start 113.559336 -240.434368)
		(mid 113.623851 -240.696587)
		(end 113.802668 -240.898934)
		(width 0.1143)
		(layer "In13.Cu")
		(net "GMI_CPU0_G0_CPU1_G2_TX_DP<0>")
	)
	(arc
		(start 113.08969 -239.624362)
		(mid 113.154926 -239.887953)
		(end 113.335562 -240.090706)
		(width 0.1143)
		(layer "In13.Cu")
		(net "GMI_CPU0_G0_CPU1_G2_TX_DP<0>")
	)
	(arc
		(start 113.402364 -240.129568)
		(mid 113.517791 -240.262944)
		(end 113.559336 -240.434368)
		(width 0.1143)
		(layer "In13.Cu")
		(net "GMI_CPU0_G0_CPU1_G2_TX_DP<0>")
	)
	(arc
		(start 358.406192 -239.624108)
		(mid 358.447447 -239.453137)
		(end 358.562148 -239.319816)
		(width 0.1143)
		(layer "In13.Cu")
		(net "GMI_CPU0_G0_CPU1_G2_TX_DP<0>")
	)
	(arc
		(start 358.593898 -239.301528)
		(mid 358.654708 -239.260853)
		(end 358.709722 -239.212628)
		(width 0.1143)
		(layer "In13.Cu")
		(net "GMI_CPU0_G0_CPU1_G2_TX_DP<0>")
	)
	(arc
		(start 357.936546 -240.434114)
		(mid 357.978095 -240.262692)
		(end 358.093518 -240.129314)
		(width 0.1143)
		(layer "In13.Cu")
		(net "GMI_CPU0_G0_CPU1_G2_TX_DP<0>")
	)
	(arc
		(start 114.343434 -241.750342)
		(mid 114.440575 -241.852968)
		(end 114.492786 -241.984276)
		(width 0.1143)
		(layer "In13.Cu")
		(net "GMI_CPU0_G0_CPU1_G2_TX_DP<0>")
	)
	(arc
		(start 357.183944 -241.731546)
		(mid 357.384415 -241.530842)
		(end 357.457756 -241.25682)
		(width 0.1143)
		(layer "In13.Cu")
		(net "GMI_CPU0_G0_CPU1_G2_TX_DP<0>")
	)
	(arc
		(start 112.0775 -237.555532)
		(mid 112.251771 -238.431833)
		(end 112.74806 -239.174782)
		(width 0.1143)
		(layer "In13.Cu")
		(net "GMI_CPU0_G0_CPU1_G2_TX_DP<0>")
	)
	(arc
		(start 112.933734 -239.32007)
		(mid 113.04841 -239.453404)
		(end 113.08969 -239.624362)
		(width 0.1143)
		(layer "In13.Cu")
		(net "GMI_CPU0_G0_CPU1_G2_TX_DP<0>")
	)
	(arc
		(start 358.747822 -239.174528)
		(mid 359.244117 -238.431581)
		(end 359.418382 -237.555278)
		(width 0.1143)
		(layer "In13.Cu")
		(net "GMI_CPU0_G0_CPU1_G2_TX_DP<0>")
	)
	(arc
		(start 357.693214 -240.89868)
		(mid 357.872027 -240.69633)
		(end 357.936546 -240.434114)
		(width 0.1143)
		(layer "In13.Cu")
		(net "GMI_CPU0_G0_CPU1_G2_TX_DP<0>")
	)
	(arc
		(start 113.851944 -240.927636)
		(mid 113.988145 -241.064618)
		(end 114.038126 -241.251232)
		(width 0.1143)
		(layer "In13.Cu")
		(net "GMI_CPU0_G0_CPU1_G2_TX_DP<0>")
	)
	(arc
		(start 358.16032 -240.090452)
		(mid 358.340972 -239.887707)
		(end 358.406192 -239.624108)
		(width 0.1143)
		(layer "In13.Cu")
		(net "GMI_CPU0_G0_CPU1_G2_TX_DP<0>")
	)
	(arc
		(start 114.038126 -241.257074)
		(mid 114.11149 -241.531083)
		(end 114.311938 -241.7318)
		(width 0.1143)
		(layer "In13.Cu")
		(net "GMI_CPU0_G0_CPU1_G2_TX_DP<0>")
	)
	(arc
		(start 112.78616 -239.212882)
		(mid 112.841185 -239.261092)
		(end 112.901984 -239.301782)
		(width 0.1143)
		(layer "In13.Cu")
		(net "GMI_CPU0_G0_CPU1_G2_TX_DP<0>")
	)
	(arc
		(start 357.003096 -241.984022)
		(mid 357.055321 -241.852724)
		(end 357.152448 -241.750088)
		(width 0.1143)
		(layer "In13.Cu")
		(net "GMI_CPU0_G0_CPU1_G2_TX_DP<0>")
	)
	(arc
		(start 357.457756 -241.250978)
		(mid 357.507669 -241.064326)
		(end 357.643938 -240.927382)
		(width 0.1143)
		(layer "In13.Cu")
		(net "GMI_CPU0_G0_CPU1_G2_TX_DP<0>")
	)
	(segment
		(start 119.767858 -241.510312)
		(end 120.23471 -241.244374)
		(width 0.12954)
		(layer "F.Cu")
		(net "GMI_CPU0_G0_CPU1_G2_TX_DN<9>")
	)
	(segment
		(start 351.728024 -241.510058)
		(end 351.261172 -241.24412)
		(width 0.12954)
		(layer "F.Cu")
		(net "GMI_CPU0_G0_CPU1_G2_TX_DN<9>")
	)
	(segment
		(start 144.995138 -197.603364)
		(end 123.266708 -215.41994)
		(width 0.14224)
		(layer "In13.Cu")
		(net "GMI_CPU0_G0_CPU1_G2_TX_DN<9>")
	)
	(segment
		(start 120.987566 -235.086906)
		(end 121.026682 -235.109766)
		(width 0.1143)
		(layer "In13.Cu")
		(net "GMI_CPU0_G0_CPU1_G2_TX_DN<9>")
	)
	(segment
		(start 120.957086 -235.069126)
		(end 120.987566 -235.086906)
		(width 0.1143)
		(layer "In13.Cu")
		(net "GMI_CPU0_G0_CPU1_G2_TX_DN<9>")
	)
	(segment
		(start 150.791926 -193.736214)
		(end 150.598886 -193.717164)
		(width 0.14224)
		(layer "In13.Cu")
		(net "GMI_CPU0_G0_CPU1_G2_TX_DN<9>")
	)
	(segment
		(start 120.957086 -230.20909)
		(end 121.024142 -230.248206)
		(width 0.1143)
		(layer "In13.Cu")
		(net "GMI_CPU0_G0_CPU1_G2_TX_DN<9>")
	)
	(segment
		(start 120.987566 -231.846882)
		(end 121.026682 -231.869742)
		(width 0.1143)
		(layer "In13.Cu")
		(net "GMI_CPU0_G0_CPU1_G2_TX_DN<9>")
	)
	(segment
		(start 350.725232 -221.145862)
		(end 350.679512 -221.100142)
		(width 0.1143)
		(layer "In13.Cu")
		(net "GMI_CPU0_G0_CPU1_G2_TX_DN<9>")
	)
	(segment
		(start 151.471122 -193.0019)
		(end 151.141176 -193.27241)
		(width 0.14224)
		(layer "In13.Cu")
		(net "GMI_CPU0_G0_CPU1_G2_TX_DN<9>")
	)
	(segment
		(start 350.538796 -227.979478)
		(end 350.4692 -227.938838)
		(width 0.1143)
		(layer "In13.Cu")
		(net "GMI_CPU0_G0_CPU1_G2_TX_DN<9>")
	)
	(segment
		(start 351.559114 -241.24412)
		(end 351.628964 -241.17427)
		(width 0.1143)
		(layer "In13.Cu")
		(net "GMI_CPU0_G0_CPU1_G2_TX_DN<9>")
	)
	(segment
		(start 350.4692 -235.109512)
		(end 350.538796 -235.068872)
		(width 0.1143)
		(layer "In13.Cu")
		(net "GMI_CPU0_G0_CPU1_G2_TX_DN<9>")
	)
	(segment
		(start 120.81637 -221.071948)
		(end 120.81637 -221.100396)
		(width 0.1143)
		(layer "In13.Cu")
		(net "GMI_CPU0_G0_CPU1_G2_TX_DN<9>")
	)
	(segment
		(start 350.4692 -228.629718)
		(end 350.538796 -228.589078)
		(width 0.1143)
		(layer "In13.Cu")
		(net "GMI_CPU0_G0_CPU1_G2_TX_DN<9>")
	)
	(segment
		(start 119.866918 -241.174524)
		(end 119.936768 -241.244374)
		(width 0.1143)
		(layer "In13.Cu")
		(net "GMI_CPU0_G0_CPU1_G2_TX_DN<9>")
	)
	(segment
		(start 157.246828 -188.265562)
		(end 157.227778 -188.458602)
		(width 0.14224)
		(layer "In13.Cu")
		(net "GMI_CPU0_G0_CPU1_G2_TX_DN<9>")
	)
	(segment
		(start 302.891952 -183.534812)
		(end 166.677848 -182.741316)
		(width 0.14224)
		(layer "In13.Cu")
		(net "GMI_CPU0_G0_CPU1_G2_TX_DN<9>")
	)
	(segment
		(start 152.885648 -191.841882)
		(end 152.866598 -192.034922)
		(width 0.14224)
		(layer "In13.Cu")
		(net "GMI_CPU0_G0_CPU1_G2_TX_DN<9>")
	)
	(segment
		(start 161.891218 -184.45734)
		(end 157.246828 -188.265562)
		(width 0.14224)
		(layer "In13.Cu")
		(net "GMI_CPU0_G0_CPU1_G2_TX_DN<9>")
	)
	(segment
		(start 350.538796 -232.83926)
		(end 350.4692 -232.79862)
		(width 0.1143)
		(layer "In13.Cu")
		(net "GMI_CPU0_G0_CPU1_G2_TX_DN<9>")
	)
	(segment
		(start 121.026682 -226.31908)
		(end 120.987566 -226.34194)
		(width 0.1143)
		(layer "In13.Cu")
		(net "GMI_CPU0_G0_CPU1_G2_TX_DN<9>")
	)
	(segment
		(start 350.4692 -236.729524)
		(end 350.538796 -236.688884)
		(width 0.1143)
		(layer "In13.Cu")
		(net "GMI_CPU0_G0_CPU1_G2_TX_DN<9>")
	)
	(segment
		(start 154.61107 -190.604394)
		(end 154.28087 -190.875158)
		(width 0.14224)
		(layer "In13.Cu")
		(net "GMI_CPU0_G0_CPU1_G2_TX_DN<9>")
	)
	(segment
		(start 120.987566 -225.367088)
		(end 121.026682 -225.389948)
		(width 0.1143)
		(layer "In13.Cu")
		(net "GMI_CPU0_G0_CPU1_G2_TX_DN<9>")
	)
	(segment
		(start 350.725232 -221.303088)
		(end 350.725232 -221.145862)
		(width 0.1143)
		(layer "In13.Cu")
		(net "GMI_CPU0_G0_CPU1_G2_TX_DN<9>")
	)
	(segment
		(start 350.47174 -230.247952)
		(end 350.538796 -230.208836)
		(width 0.1143)
		(layer "In13.Cu")
		(net "GMI_CPU0_G0_CPU1_G2_TX_DN<9>")
	)
	(segment
		(start 350.9772 -240.111026)
		(end 350.975676 -240.11001)
		(width 0.1143)
		(layer "In13.Cu")
		(net "GMI_CPU0_G0_CPU1_G2_TX_DN<9>")
	)
	(segment
		(start 120.987566 -233.466894)
		(end 121.026682 -233.489754)
		(width 0.1143)
		(layer "In13.Cu")
		(net "GMI_CPU0_G0_CPU1_G2_TX_DN<9>")
	)
	(segment
		(start 348.33433 -215.54821)
		(end 313.82716 -187.253372)
		(width 0.14224)
		(layer "In13.Cu")
		(net "GMI_CPU0_G0_CPU1_G2_TX_DN<9>")
	)
	(segment
		(start 120.957086 -236.689138)
		(end 120.987566 -236.706918)
		(width 0.1143)
		(layer "In13.Cu")
		(net "GMI_CPU0_G0_CPU1_G2_TX_DN<9>")
	)
	(segment
		(start 350.538796 -239.319308)
		(end 350.4692 -239.278668)
		(width 0.1143)
		(layer "In13.Cu")
		(net "GMI_CPU0_G0_CPU1_G2_TX_DN<9>")
	)
	(segment
		(start 350.508316 -229.58171)
		(end 350.4692 -229.55885)
		(width 0.1143)
		(layer "In13.Cu")
		(net "GMI_CPU0_G0_CPU1_G2_TX_DN<9>")
	)
	(segment
		(start 350.540828 -231.220518)
		(end 350.508316 -231.201722)
		(width 0.1143)
		(layer "In13.Cu")
		(net "GMI_CPU0_G0_CPU1_G2_TX_DN<9>")
	)
	(segment
		(start 155.483306 -189.88913)
		(end 155.153106 -190.159894)
		(width 0.14224)
		(layer "In13.Cu")
		(net "GMI_CPU0_G0_CPU1_G2_TX_DN<9>")
	)
	(segment
		(start 120.957086 -233.449114)
		(end 120.987566 -233.466894)
		(width 0.1143)
		(layer "In13.Cu")
		(net "GMI_CPU0_G0_CPU1_G2_TX_DN<9>")
	)
	(segment
		(start 120.987566 -222.127064)
		(end 121.026682 -222.149924)
		(width 0.1143)
		(layer "In13.Cu")
		(net "GMI_CPU0_G0_CPU1_G2_TX_DN<9>")
	)
	(segment
		(start 154.960066 -190.140844)
		(end 154.63012 -190.411354)
		(width 0.14224)
		(layer "In13.Cu")
		(net "GMI_CPU0_G0_CPU1_G2_TX_DN<9>")
	)
	(segment
		(start 351.004632 -240.126774)
		(end 350.978724 -240.111534)
		(width 0.1143)
		(layer "In13.Cu")
		(net "GMI_CPU0_G0_CPU1_G2_TX_DN<9>")
	)
	(segment
		(start 166.677848 -182.741316)
		(end 161.891218 -184.45734)
		(width 0.14224)
		(layer "In13.Cu")
		(net "GMI_CPU0_G0_CPU1_G2_TX_DN<9>")
	)
	(segment
		(start 153.757884 -191.126618)
		(end 153.738834 -191.319658)
		(width 0.14224)
		(layer "In13.Cu")
		(net "GMI_CPU0_G0_CPU1_G2_TX_DN<9>")
	)
	(segment
		(start 350.540828 -229.600506)
		(end 350.508316 -229.58171)
		(width 0.1143)
		(layer "In13.Cu")
		(net "GMI_CPU0_G0_CPU1_G2_TX_DN<9>")
	)
	(segment
		(start 351.005394 -240.127282)
		(end 351.004632 -240.126774)
		(width 0.1143)
		(layer "In13.Cu")
		(net "GMI_CPU0_G0_CPU1_G2_TX_DN<9>")
	)
	(segment
		(start 350.538796 -223.119442)
		(end 350.4692 -223.078802)
		(width 0.1143)
		(layer "In13.Cu")
		(net "GMI_CPU0_G0_CPU1_G2_TX_DN<9>")
	)
	(segment
		(start 120.987566 -224.721928)
		(end 120.957086 -224.739708)
		(width 0.1143)
		(layer "In13.Cu")
		(net "GMI_CPU0_G0_CPU1_G2_TX_DN<9>")
	)
	(segment
		(start 350.4692 -231.869488)
		(end 350.538796 -231.828848)
		(width 0.1143)
		(layer "In13.Cu")
		(net "GMI_CPU0_G0_CPU1_G2_TX_DN<9>")
	)
	(segment
		(start 121.026682 -227.939092)
		(end 120.987566 -227.961952)
		(width 0.1143)
		(layer "In13.Cu")
		(net "GMI_CPU0_G0_CPU1_G2_TX_DN<9>")
	)
	(segment
		(start 120.517666 -240.111788)
		(end 120.517158 -240.111788)
		(width 0.1143)
		(layer "In13.Cu")
		(net "GMI_CPU0_G0_CPU1_G2_TX_DN<9>")
	)
	(segment
		(start 120.047766 -240.921794)
		(end 120.047004 -240.922302)
		(width 0.1143)
		(layer "In13.Cu")
		(net "GMI_CPU0_G0_CPU1_G2_TX_DN<9>")
	)
	(segment
		(start 157.227778 -188.458602)
		(end 156.897578 -188.729366)
		(width 0.14224)
		(layer "In13.Cu")
		(net "GMI_CPU0_G0_CPU1_G2_TX_DN<9>")
	)
	(segment
		(start 350.538796 -234.459272)
		(end 350.4692 -234.418632)
		(width 0.1143)
		(layer "In13.Cu")
		(net "GMI_CPU0_G0_CPU1_G2_TX_DN<9>")
	)
	(segment
		(start 121.026682 -239.278922)
		(end 120.987566 -239.301782)
		(width 0.1143)
		(layer "In13.Cu")
		(net "GMI_CPU0_G0_CPU1_G2_TX_DN<9>")
	)
	(segment
		(start 313.82716 -187.253372)
		(end 308.012084 -183.961532)
		(width 0.14224)
		(layer "In13.Cu")
		(net "GMI_CPU0_G0_CPU1_G2_TX_DN<9>")
	)
	(segment
		(start 151.122126 -193.46545)
		(end 150.791926 -193.736214)
		(width 0.14224)
		(layer "In13.Cu")
		(net "GMI_CPU0_G0_CPU1_G2_TX_DN<9>")
	)
	(segment
		(start 350.508316 -231.201722)
		(end 350.4692 -231.178862)
		(width 0.1143)
		(layer "In13.Cu")
		(net "GMI_CPU0_G0_CPU1_G2_TX_DN<9>")
	)
	(segment
		(start 150.598886 -193.717164)
		(end 146.364452 -197.188836)
		(width 0.14224)
		(layer "In13.Cu")
		(net "GMI_CPU0_G0_CPU1_G2_TX_DN<9>")
	)
	(segment
		(start 152.536398 -192.305686)
		(end 152.343358 -192.286636)
		(width 0.14224)
		(layer "In13.Cu")
		(net "GMI_CPU0_G0_CPU1_G2_TX_DN<9>")
	)
	(segment
		(start 153.215594 -191.571372)
		(end 152.885648 -191.841882)
		(width 0.14224)
		(layer "In13.Cu")
		(net "GMI_CPU0_G0_CPU1_G2_TX_DN<9>")
	)
	(segment
		(start 308.012084 -183.961532)
		(end 306.818538 -183.534812)
		(width 0.14224)
		(layer "In13.Cu")
		(net "GMI_CPU0_G0_CPU1_G2_TX_DN<9>")
	)
	(segment
		(start 120.77065 -221.303342)
		(end 120.800114 -221.332806)
		(width 0.1143)
		(layer "In13.Cu")
		(net "GMI_CPU0_G0_CPU1_G2_TX_DN<9>")
	)
	(segment
		(start 156.355542 -189.173866)
		(end 156.025342 -189.44463)
		(width 0.14224)
		(layer "In13.Cu")
		(net "GMI_CPU0_G0_CPU1_G2_TX_DN<9>")
	)
	(segment
		(start 121.026682 -223.079056)
		(end 120.987566 -223.101916)
		(width 0.1143)
		(layer "In13.Cu")
		(net "GMI_CPU0_G0_CPU1_G2_TX_DN<9>")
	)
	(segment
		(start 120.957086 -226.96932)
		(end 120.987566 -226.9871)
		(width 0.1143)
		(layer "In13.Cu")
		(net "GMI_CPU0_G0_CPU1_G2_TX_DN<9>")
	)
	(segment
		(start 121.026682 -232.798874)
		(end 120.987566 -232.821734)
		(width 0.1143)
		(layer "In13.Cu")
		(net "GMI_CPU0_G0_CPU1_G2_TX_DN<9>")
	)
	(segment
		(start 350.4692 -223.769682)
		(end 350.538796 -223.729042)
		(width 0.1143)
		(layer "In13.Cu")
		(net "GMI_CPU0_G0_CPU1_G2_TX_DN<9>")
	)
	(segment
		(start 121.026682 -231.179116)
		(end 120.987566 -231.201976)
		(width 0.1143)
		(layer "In13.Cu")
		(net "GMI_CPU0_G0_CPU1_G2_TX_DN<9>")
	)
	(segment
		(start 120.957086 -223.729296)
		(end 120.987566 -223.747076)
		(width 0.1143)
		(layer "In13.Cu")
		(net "GMI_CPU0_G0_CPU1_G2_TX_DN<9>")
	)
	(segment
		(start 152.343358 -192.286636)
		(end 152.013412 -192.557146)
		(width 0.14224)
		(layer "In13.Cu")
		(net "GMI_CPU0_G0_CPU1_G2_TX_DN<9>")
	)
	(segment
		(start 120.987566 -223.101916)
		(end 120.957086 -223.119696)
		(width 0.1143)
		(layer "In13.Cu")
		(net "GMI_CPU0_G0_CPU1_G2_TX_DN<9>")
	)
	(segment
		(start 350.4692 -233.4895)
		(end 350.538796 -233.44886)
		(width 0.1143)
		(layer "In13.Cu")
		(net "GMI_CPU0_G0_CPU1_G2_TX_DN<9>")
	)
	(segment
		(start 120.987566 -237.68177)
		(end 120.957086 -237.69955)
		(width 0.1143)
		(layer "In13.Cu")
		(net "GMI_CPU0_G0_CPU1_G2_TX_DN<9>")
	)
	(segment
		(start 350.679512 -221.093538)
		(end 350.679512 -219.498164)
		(width 0.14224)
		(layer "In13.Cu")
		(net "GMI_CPU0_G0_CPU1_G2_TX_DN<9>")
	)
	(segment
		(start 350.538796 -236.079284)
		(end 350.4692 -236.038644)
		(width 0.1143)
		(layer "In13.Cu")
		(net "GMI_CPU0_G0_CPU1_G2_TX_DN<9>")
	)
	(segment
		(start 156.374592 -188.980826)
		(end 156.355542 -189.173866)
		(width 0.14224)
		(layer "In13.Cu")
		(net "GMI_CPU0_G0_CPU1_G2_TX_DN<9>")
	)
	(segment
		(start 121.026682 -237.65891)
		(end 120.987566 -237.68177)
		(width 0.1143)
		(layer "In13.Cu")
		(net "GMI_CPU0_G0_CPU1_G2_TX_DN<9>")
	)
	(segment
		(start 152.013412 -192.557146)
		(end 151.994362 -192.750186)
		(width 0.14224)
		(layer "In13.Cu")
		(net "GMI_CPU0_G0_CPU1_G2_TX_DN<9>")
	)
	(segment
		(start 151.141176 -193.27241)
		(end 151.122126 -193.46545)
		(width 0.14224)
		(layer "In13.Cu")
		(net "GMI_CPU0_G0_CPU1_G2_TX_DN<9>")
	)
	(segment
		(start 120.084088 -240.900712)
		(end 120.047766 -240.921794)
		(width 0.1143)
		(layer "In13.Cu")
		(net "GMI_CPU0_G0_CPU1_G2_TX_DN<9>")
	)
	(segment
		(start 120.987566 -236.061758)
		(end 120.957086 -236.079538)
		(width 0.1143)
		(layer "In13.Cu")
		(net "GMI_CPU0_G0_CPU1_G2_TX_DN<9>")
	)
	(segment
		(start 120.957086 -225.349308)
		(end 120.987566 -225.367088)
		(width 0.1143)
		(layer "In13.Cu")
		(net "GMI_CPU0_G0_CPU1_G2_TX_DN<9>")
	)
	(segment
		(start 350.4692 -222.14967)
		(end 350.538796 -222.10903)
		(width 0.1143)
		(layer "In13.Cu")
		(net "GMI_CPU0_G0_CPU1_G2_TX_DN<9>")
	)
	(segment
		(start 156.704538 -188.710316)
		(end 156.374592 -188.980826)
		(width 0.14224)
		(layer "In13.Cu")
		(net "GMI_CPU0_G0_CPU1_G2_TX_DN<9>")
	)
	(segment
		(start 120.77065 -221.146116)
		(end 120.77065 -221.303342)
		(width 0.1143)
		(layer "In13.Cu")
		(net "GMI_CPU0_G0_CPU1_G2_TX_DN<9>")
	)
	(segment
		(start 120.957086 -228.589332)
		(end 120.987566 -228.607112)
		(width 0.1143)
		(layer "In13.Cu")
		(net "GMI_CPU0_G0_CPU1_G2_TX_DN<9>")
	)
	(segment
		(start 123.266708 -215.41994)
		(end 120.81637 -219.620338)
		(width 0.14224)
		(layer "In13.Cu")
		(net "GMI_CPU0_G0_CPU1_G2_TX_DN<9>")
	)
	(segment
		(start 350.695768 -221.332552)
		(end 350.725232 -221.303088)
		(width 0.1143)
		(layer "In13.Cu")
		(net "GMI_CPU0_G0_CPU1_G2_TX_DN<9>")
	)
	(segment
		(start 120.987566 -223.747076)
		(end 121.026682 -223.769936)
		(width 0.1143)
		(layer "In13.Cu")
		(net "GMI_CPU0_G0_CPU1_G2_TX_DN<9>")
	)
	(segment
		(start 120.49125 -240.127028)
		(end 120.490488 -240.127536)
		(width 0.1143)
		(layer "In13.Cu")
		(net "GMI_CPU0_G0_CPU1_G2_TX_DN<9>")
	)
	(segment
		(start 120.957086 -231.829102)
		(end 120.987566 -231.846882)
		(width 0.1143)
		(layer "In13.Cu")
		(net "GMI_CPU0_G0_CPU1_G2_TX_DN<9>")
	)
	(segment
		(start 152.866598 -192.034922)
		(end 152.536398 -192.305686)
		(width 0.14224)
		(layer "In13.Cu")
		(net "GMI_CPU0_G0_CPU1_G2_TX_DN<9>")
	)
	(segment
		(start 156.025342 -189.44463)
		(end 155.832302 -189.42558)
		(width 0.14224)
		(layer "In13.Cu")
		(net "GMI_CPU0_G0_CPU1_G2_TX_DN<9>")
	)
	(segment
		(start 120.987566 -234.441746)
		(end 120.957086 -234.459526)
		(width 0.1143)
		(layer "In13.Cu")
		(net "GMI_CPU0_G0_CPU1_G2_TX_DN<9>")
	)
	(segment
		(start 146.364452 -197.188836)
		(end 144.995138 -197.603364)
		(width 0.14224)
		(layer "In13.Cu")
		(net "GMI_CPU0_G0_CPU1_G2_TX_DN<9>")
	)
	(segment
		(start 121.026682 -234.418886)
		(end 120.987566 -234.441746)
		(width 0.1143)
		(layer "In13.Cu")
		(net "GMI_CPU0_G0_CPU1_G2_TX_DN<9>")
	)
	(segment
		(start 155.502356 -189.69609)
		(end 155.483306 -189.88913)
		(width 0.14224)
		(layer "In13.Cu")
		(net "GMI_CPU0_G0_CPU1_G2_TX_DN<9>")
	)
	(segment
		(start 350.679512 -221.100142)
		(end 350.679512 -221.093538)
		(width 0.1143)
		(layer "In13.Cu")
		(net "GMI_CPU0_G0_CPU1_G2_TX_DN<9>")
	)
	(segment
		(start 154.28087 -190.875158)
		(end 154.08783 -190.856108)
		(width 0.14224)
		(layer "In13.Cu")
		(net "GMI_CPU0_G0_CPU1_G2_TX_DN<9>")
	)
	(segment
		(start 120.957086 -222.109284)
		(end 120.987566 -222.127064)
		(width 0.1143)
		(layer "In13.Cu")
		(net "GMI_CPU0_G0_CPU1_G2_TX_DN<9>")
	)
	(segment
		(start 120.81637 -221.100396)
		(end 120.77065 -221.146116)
		(width 0.1143)
		(layer "In13.Cu")
		(net "GMI_CPU0_G0_CPU1_G2_TX_DN<9>")
	)
	(segment
		(start 351.261172 -241.24412)
		(end 351.559114 -241.24412)
		(width 0.1143)
		(layer "In13.Cu")
		(net "GMI_CPU0_G0_CPU1_G2_TX_DN<9>")
	)
	(segment
		(start 120.987566 -229.581964)
		(end 120.955054 -229.60076)
		(width 0.1143)
		(layer "In13.Cu")
		(net "GMI_CPU0_G0_CPU1_G2_TX_DN<9>")
	)
	(segment
		(start 351.479866 -240.939828)
		(end 351.448878 -240.922048)
		(width 0.1143)
		(layer "In13.Cu")
		(net "GMI_CPU0_G0_CPU1_G2_TX_DN<9>")
	)
	(segment
		(start 120.987566 -227.961952)
		(end 120.957086 -227.979732)
		(width 0.1143)
		(layer "In13.Cu")
		(net "GMI_CPU0_G0_CPU1_G2_TX_DN<9>")
	)
	(segment
		(start 153.738834 -191.319658)
		(end 153.408634 -191.590422)
		(width 0.14224)
		(layer "In13.Cu")
		(net "GMI_CPU0_G0_CPU1_G2_TX_DN<9>")
	)
	(segment
		(start 120.987566 -226.34194)
		(end 120.957086 -226.35972)
		(width 0.1143)
		(layer "In13.Cu")
		(net "GMI_CPU0_G0_CPU1_G2_TX_DN<9>")
	)
	(segment
		(start 350.538796 -226.359466)
		(end 350.4692 -226.318826)
		(width 0.1143)
		(layer "In13.Cu")
		(net "GMI_CPU0_G0_CPU1_G2_TX_DN<9>")
	)
	(segment
		(start 350.978216 -240.111534)
		(end 350.9772 -240.111026)
		(width 0.1143)
		(layer "In13.Cu")
		(net "GMI_CPU0_G0_CPU1_G2_TX_DN<9>")
	)
	(segment
		(start 156.897578 -188.729366)
		(end 156.704538 -188.710316)
		(width 0.14224)
		(layer "In13.Cu")
		(net "GMI_CPU0_G0_CPU1_G2_TX_DN<9>")
	)
	(segment
		(start 120.957086 -238.30915)
		(end 120.987566 -238.32693)
		(width 0.1143)
		(layer "In13.Cu")
		(net "GMI_CPU0_G0_CPU1_G2_TX_DN<9>")
	)
	(segment
		(start 350.4692 -227.009706)
		(end 350.538796 -226.969066)
		(width 0.1143)
		(layer "In13.Cu")
		(net "GMI_CPU0_G0_CPU1_G2_TX_DN<9>")
	)
	(segment
		(start 120.045734 -240.923064)
		(end 120.016016 -240.940082)
		(width 0.1143)
		(layer "In13.Cu")
		(net "GMI_CPU0_G0_CPU1_G2_TX_DN<9>")
	)
	(segment
		(start 151.664162 -193.02095)
		(end 151.471122 -193.0019)
		(width 0.14224)
		(layer "In13.Cu")
		(net "GMI_CPU0_G0_CPU1_G2_TX_DN<9>")
	)
	(segment
		(start 350.978724 -240.111534)
		(end 350.978216 -240.111534)
		(width 0.1143)
		(layer "In13.Cu")
		(net "GMI_CPU0_G0_CPU1_G2_TX_DN<9>")
	)
	(segment
		(start 120.047004 -240.922302)
		(end 120.045734 -240.923064)
		(width 0.1143)
		(layer "In13.Cu")
		(net "GMI_CPU0_G0_CPU1_G2_TX_DN<9>")
	)
	(segment
		(start 121.026682 -236.038898)
		(end 120.987566 -236.061758)
		(width 0.1143)
		(layer "In13.Cu")
		(net "GMI_CPU0_G0_CPU1_G2_TX_DN<9>")
	)
	(segment
		(start 351.448116 -240.92154)
		(end 351.411794 -240.900458)
		(width 0.1143)
		(layer "In13.Cu")
		(net "GMI_CPU0_G0_CPU1_G2_TX_DN<9>")
	)
	(segment
		(start 120.81637 -219.620338)
		(end 120.81637 -221.071948)
		(width 0.14224)
		(layer "In13.Cu")
		(net "GMI_CPU0_G0_CPU1_G2_TX_DN<9>")
	)
	(segment
		(start 120.987566 -232.821734)
		(end 120.957086 -232.839514)
		(width 0.1143)
		(layer "In13.Cu")
		(net "GMI_CPU0_G0_CPU1_G2_TX_DN<9>")
	)
	(segment
		(start 121.026682 -224.699068)
		(end 120.987566 -224.721928)
		(width 0.1143)
		(layer "In13.Cu")
		(net "GMI_CPU0_G0_CPU1_G2_TX_DN<9>")
	)
	(segment
		(start 120.800114 -221.332806)
		(end 120.800114 -221.804484)
		(width 0.1143)
		(layer "In13.Cu")
		(net "GMI_CPU0_G0_CPU1_G2_TX_DN<9>")
	)
	(segment
		(start 351.448878 -240.922048)
		(end 351.448116 -240.92154)
		(width 0.1143)
		(layer "In13.Cu")
		(net "GMI_CPU0_G0_CPU1_G2_TX_DN<9>")
	)
	(segment
		(start 120.987566 -226.9871)
		(end 121.026682 -227.00996)
		(width 0.1143)
		(layer "In13.Cu")
		(net "GMI_CPU0_G0_CPU1_G2_TX_DN<9>")
	)
	(segment
		(start 120.556782 -240.088928)
		(end 120.517666 -240.111788)
		(width 0.1143)
		(layer "In13.Cu")
		(net "GMI_CPU0_G0_CPU1_G2_TX_DN<9>")
	)
	(segment
		(start 121.026682 -229.559104)
		(end 120.987566 -229.581964)
		(width 0.1143)
		(layer "In13.Cu")
		(net "GMI_CPU0_G0_CPU1_G2_TX_DN<9>")
	)
	(segment
		(start 120.987566 -238.32693)
		(end 121.026682 -238.34979)
		(width 0.1143)
		(layer "In13.Cu")
		(net "GMI_CPU0_G0_CPU1_G2_TX_DN<9>")
	)
	(segment
		(start 350.975676 -240.11001)
		(end 350.9391 -240.088674)
		(width 0.1143)
		(layer "In13.Cu")
		(net "GMI_CPU0_G0_CPU1_G2_TX_DN<9>")
	)
	(segment
		(start 350.695768 -221.80423)
		(end 350.695768 -221.332552)
		(width 0.1143)
		(layer "In13.Cu")
		(net "GMI_CPU0_G0_CPU1_G2_TX_DN<9>")
	)
	(segment
		(start 155.832302 -189.42558)
		(end 155.502356 -189.69609)
		(width 0.14224)
		(layer "In13.Cu")
		(net "GMI_CPU0_G0_CPU1_G2_TX_DN<9>")
	)
	(segment
		(start 119.936768 -241.244374)
		(end 120.23471 -241.244374)
		(width 0.1143)
		(layer "In13.Cu")
		(net "GMI_CPU0_G0_CPU1_G2_TX_DN<9>")
	)
	(segment
		(start 151.994362 -192.750186)
		(end 151.664162 -193.02095)
		(width 0.14224)
		(layer "In13.Cu")
		(net "GMI_CPU0_G0_CPU1_G2_TX_DN<9>")
	)
	(segment
		(start 350.538796 -237.699296)
		(end 350.4692 -237.658656)
		(width 0.1143)
		(layer "In13.Cu")
		(net "GMI_CPU0_G0_CPU1_G2_TX_DN<9>")
	)
	(segment
		(start 350.538796 -224.739454)
		(end 350.4692 -224.698814)
		(width 0.1143)
		(layer "In13.Cu")
		(net "GMI_CPU0_G0_CPU1_G2_TX_DN<9>")
	)
	(segment
		(start 306.818538 -183.534812)
		(end 302.891952 -183.534812)
		(width 0.14224)
		(layer "In13.Cu")
		(net "GMI_CPU0_G0_CPU1_G2_TX_DN<9>")
	)
	(segment
		(start 350.4692 -238.349536)
		(end 350.538796 -238.308896)
		(width 0.1143)
		(layer "In13.Cu")
		(net "GMI_CPU0_G0_CPU1_G2_TX_DN<9>")
	)
	(segment
		(start 153.408634 -191.590422)
		(end 153.215594 -191.571372)
		(width 0.14224)
		(layer "In13.Cu")
		(net "GMI_CPU0_G0_CPU1_G2_TX_DN<9>")
	)
	(segment
		(start 350.4692 -225.389694)
		(end 350.538796 -225.349054)
		(width 0.1143)
		(layer "In13.Cu")
		(net "GMI_CPU0_G0_CPU1_G2_TX_DN<9>")
	)
	(segment
		(start 120.987566 -239.301782)
		(end 120.957086 -239.319562)
		(width 0.1143)
		(layer "In13.Cu")
		(net "GMI_CPU0_G0_CPU1_G2_TX_DN<9>")
	)
	(segment
		(start 120.987566 -231.201976)
		(end 120.955054 -231.220772)
		(width 0.1143)
		(layer "In13.Cu")
		(net "GMI_CPU0_G0_CPU1_G2_TX_DN<9>")
	)
	(segment
		(start 120.987566 -228.607112)
		(end 121.026682 -228.629972)
		(width 0.1143)
		(layer "In13.Cu")
		(net "GMI_CPU0_G0_CPU1_G2_TX_DN<9>")
	)
	(segment
		(start 155.153106 -190.159894)
		(end 154.960066 -190.140844)
		(width 0.14224)
		(layer "In13.Cu")
		(net "GMI_CPU0_G0_CPU1_G2_TX_DN<9>")
	)
	(segment
		(start 120.987566 -236.706918)
		(end 121.026682 -236.729778)
		(width 0.1143)
		(layer "In13.Cu")
		(net "GMI_CPU0_G0_CPU1_G2_TX_DN<9>")
	)
	(segment
		(start 154.63012 -190.411354)
		(end 154.61107 -190.604394)
		(width 0.14224)
		(layer "In13.Cu")
		(net "GMI_CPU0_G0_CPU1_G2_TX_DN<9>")
	)
	(segment
		(start 154.08783 -190.856108)
		(end 153.757884 -191.126618)
		(width 0.14224)
		(layer "In13.Cu")
		(net "GMI_CPU0_G0_CPU1_G2_TX_DN<9>")
	)
	(segment
		(start 120.517158 -240.111788)
		(end 120.49125 -240.127028)
		(width 0.1143)
		(layer "In13.Cu")
		(net "GMI_CPU0_G0_CPU1_G2_TX_DN<9>")
	)
	(segment
		(start 350.679512 -219.498164)
		(end 348.33433 -215.54821)
		(width 0.14224)
		(layer "In13.Cu")
		(net "GMI_CPU0_G0_CPU1_G2_TX_DN<9>")
	)
	(arc
		(start 121.026682 -235.109766)
		(mid 121.270009 -235.574332)
		(end 121.026682 -236.038898)
		(width 0.1143)
		(layer "In13.Cu")
		(net "GMI_CPU0_G0_CPU1_G2_TX_DN<9>")
	)
	(arc
		(start 350.4692 -231.178862)
		(mid 350.290387 -230.976512)
		(end 350.225868 -230.714296)
		(width 0.1143)
		(layer "In13.Cu")
		(net "GMI_CPU0_G0_CPU1_G2_TX_DN<9>")
	)
	(arc
		(start 120.957086 -226.35972)
		(mid 120.800109 -226.66452)
		(end 120.957086 -226.96932)
		(width 0.1143)
		(layer "In13.Cu")
		(net "GMI_CPU0_G0_CPU1_G2_TX_DN<9>")
	)
	(arc
		(start 120.800114 -231.524302)
		(mid 120.841663 -231.695724)
		(end 120.957086 -231.829102)
		(width 0.1143)
		(layer "In13.Cu")
		(net "GMI_CPU0_G0_CPU1_G2_TX_DN<9>")
	)
	(arc
		(start 121.026682 -225.389948)
		(mid 121.270009 -225.854514)
		(end 121.026682 -226.31908)
		(width 0.1143)
		(layer "In13.Cu")
		(net "GMI_CPU0_G0_CPU1_G2_TX_DN<9>")
	)
	(arc
		(start 350.4692 -224.698814)
		(mid 350.225873 -224.234248)
		(end 350.4692 -223.769682)
		(width 0.1143)
		(layer "In13.Cu")
		(net "GMI_CPU0_G0_CPU1_G2_TX_DN<9>")
	)
	(arc
		(start 350.538796 -223.729042)
		(mid 350.695773 -223.424242)
		(end 350.538796 -223.119442)
		(width 0.1143)
		(layer "In13.Cu")
		(net "GMI_CPU0_G0_CPU1_G2_TX_DN<9>")
	)
	(arc
		(start 120.957086 -236.079538)
		(mid 120.800109 -236.384338)
		(end 120.957086 -236.689138)
		(width 0.1143)
		(layer "In13.Cu")
		(net "GMI_CPU0_G0_CPU1_G2_TX_DN<9>")
	)
	(arc
		(start 350.9391 -240.088674)
		(mid 350.760287 -239.886324)
		(end 350.695768 -239.624108)
		(width 0.1143)
		(layer "In13.Cu")
		(net "GMI_CPU0_G0_CPU1_G2_TX_DN<9>")
	)
	(arc
		(start 350.538796 -236.688884)
		(mid 350.695773 -236.384084)
		(end 350.538796 -236.079284)
		(width 0.1143)
		(layer "In13.Cu")
		(net "GMI_CPU0_G0_CPU1_G2_TX_DN<9>")
	)
	(arc
		(start 120.800114 -229.90429)
		(mid 120.841663 -230.075712)
		(end 120.957086 -230.20909)
		(width 0.1143)
		(layer "In13.Cu")
		(net "GMI_CPU0_G0_CPU1_G2_TX_DN<9>")
	)
	(arc
		(start 120.100344 -240.889282)
		(mid 120.092266 -240.895068)
		(end 120.084088 -240.900712)
		(width 0.1143)
		(layer "In13.Cu")
		(net "GMI_CPU0_G0_CPU1_G2_TX_DN<9>")
	)
	(arc
		(start 350.695768 -239.624108)
		(mid 350.654219 -239.452686)
		(end 350.538796 -239.319308)
		(width 0.1143)
		(layer "In13.Cu")
		(net "GMI_CPU0_G0_CPU1_G2_TX_DN<9>")
	)
	(arc
		(start 350.538796 -228.589078)
		(mid 350.695773 -228.284278)
		(end 350.538796 -227.979478)
		(width 0.1143)
		(layer "In13.Cu")
		(net "GMI_CPU0_G0_CPU1_G2_TX_DN<9>")
	)
	(arc
		(start 350.538796 -226.969066)
		(mid 350.695773 -226.664266)
		(end 350.538796 -226.359466)
		(width 0.1143)
		(layer "In13.Cu")
		(net "GMI_CPU0_G0_CPU1_G2_TX_DN<9>")
	)
	(arc
		(start 120.481344 -240.134648)
		(mid 120.381054 -240.272079)
		(end 120.32996 -240.434368)
		(width 0.1143)
		(layer "In13.Cu")
		(net "GMI_CPU0_G0_CPU1_G2_TX_DN<9>")
	)
	(arc
		(start 350.4692 -234.418632)
		(mid 350.225873 -233.954066)
		(end 350.4692 -233.4895)
		(width 0.1143)
		(layer "In13.Cu")
		(net "GMI_CPU0_G0_CPU1_G2_TX_DN<9>")
	)
	(arc
		(start 120.957086 -232.839514)
		(mid 120.800109 -233.144314)
		(end 120.957086 -233.449114)
		(width 0.1143)
		(layer "In13.Cu")
		(net "GMI_CPU0_G0_CPU1_G2_TX_DN<9>")
	)
	(arc
		(start 350.538796 -231.828848)
		(mid 350.654223 -231.695472)
		(end 350.695768 -231.524048)
		(width 0.1143)
		(layer "In13.Cu")
		(net "GMI_CPU0_G0_CPU1_G2_TX_DN<9>")
	)
	(arc
		(start 350.538796 -235.068872)
		(mid 350.695773 -234.764072)
		(end 350.538796 -234.459272)
		(width 0.1143)
		(layer "In13.Cu")
		(net "GMI_CPU0_G0_CPU1_G2_TX_DN<9>")
	)
	(arc
		(start 350.225868 -230.714296)
		(mid 350.291104 -230.450705)
		(end 350.47174 -230.247952)
		(width 0.1143)
		(layer "In13.Cu")
		(net "GMI_CPU0_G0_CPU1_G2_TX_DN<9>")
	)
	(arc
		(start 121.026682 -238.34979)
		(mid 121.270009 -238.814356)
		(end 121.026682 -239.278922)
		(width 0.1143)
		(layer "In13.Cu")
		(net "GMI_CPU0_G0_CPU1_G2_TX_DN<9>")
	)
	(arc
		(start 350.538796 -225.349054)
		(mid 350.695773 -225.044254)
		(end 350.538796 -224.739454)
		(width 0.1143)
		(layer "In13.Cu")
		(net "GMI_CPU0_G0_CPU1_G2_TX_DN<9>")
	)
	(arc
		(start 120.32996 -240.440972)
		(mid 120.265088 -240.690714)
		(end 120.100344 -240.889282)
		(width 0.1143)
		(layer "In13.Cu")
		(net "GMI_CPU0_G0_CPU1_G2_TX_DN<9>")
	)
	(arc
		(start 120.957086 -234.459526)
		(mid 120.800109 -234.764326)
		(end 120.957086 -235.069126)
		(width 0.1143)
		(layer "In13.Cu")
		(net "GMI_CPU0_G0_CPU1_G2_TX_DN<9>")
	)
	(arc
		(start 350.4692 -239.278668)
		(mid 350.225873 -238.814102)
		(end 350.4692 -238.349536)
		(width 0.1143)
		(layer "In13.Cu")
		(net "GMI_CPU0_G0_CPU1_G2_TX_DN<9>")
	)
	(arc
		(start 350.4692 -223.078802)
		(mid 350.225873 -222.614236)
		(end 350.4692 -222.14967)
		(width 0.1143)
		(layer "In13.Cu")
		(net "GMI_CPU0_G0_CPU1_G2_TX_DN<9>")
	)
	(arc
		(start 121.026682 -236.729778)
		(mid 121.270009 -237.194344)
		(end 121.026682 -237.65891)
		(width 0.1143)
		(layer "In13.Cu")
		(net "GMI_CPU0_G0_CPU1_G2_TX_DN<9>")
	)
	(arc
		(start 121.270014 -230.71455)
		(mid 121.205499 -230.976769)
		(end 121.026682 -231.179116)
		(width 0.1143)
		(layer "In13.Cu")
		(net "GMI_CPU0_G0_CPU1_G2_TX_DN<9>")
	)
	(arc
		(start 120.957086 -237.69955)
		(mid 120.800109 -238.00435)
		(end 120.957086 -238.30915)
		(width 0.1143)
		(layer "In13.Cu")
		(net "GMI_CPU0_G0_CPU1_G2_TX_DN<9>")
	)
	(arc
		(start 351.165922 -240.434114)
		(mid 351.114877 -240.2718)
		(end 351.014538 -240.134394)
		(width 0.1143)
		(layer "In13.Cu")
		(net "GMI_CPU0_G0_CPU1_G2_TX_DN<9>")
	)
	(arc
		(start 351.165922 -240.440718)
		(mid 351.165912 -240.437416)
		(end 351.165922 -240.434114)
		(width 0.1143)
		(layer "In13.Cu")
		(net "GMI_CPU0_G0_CPU1_G2_TX_DN<9>")
	)
	(arc
		(start 120.957086 -223.119696)
		(mid 120.800109 -223.424496)
		(end 120.957086 -223.729296)
		(width 0.1143)
		(layer "In13.Cu")
		(net "GMI_CPU0_G0_CPU1_G2_TX_DN<9>")
	)
	(arc
		(start 351.395538 -240.889028)
		(mid 351.230871 -240.690421)
		(end 351.165922 -240.440718)
		(width 0.1143)
		(layer "In13.Cu")
		(net "GMI_CPU0_G0_CPU1_G2_TX_DN<9>")
	)
	(arc
		(start 351.628964 -241.17427)
		(mid 351.576915 -241.042751)
		(end 351.479866 -240.939828)
		(width 0.1143)
		(layer "In13.Cu")
		(net "GMI_CPU0_G0_CPU1_G2_TX_DN<9>")
	)
	(arc
		(start 120.955054 -229.60076)
		(mid 120.841125 -229.733907)
		(end 120.800114 -229.90429)
		(width 0.1143)
		(layer "In13.Cu")
		(net "GMI_CPU0_G0_CPU1_G2_TX_DN<9>")
	)
	(arc
		(start 350.538796 -233.44886)
		(mid 350.695773 -233.14406)
		(end 350.538796 -232.83926)
		(width 0.1143)
		(layer "In13.Cu")
		(net "GMI_CPU0_G0_CPU1_G2_TX_DN<9>")
	)
	(arc
		(start 350.695768 -229.904036)
		(mid 350.654802 -229.73363)
		(end 350.540828 -229.600506)
		(width 0.1143)
		(layer "In13.Cu")
		(net "GMI_CPU0_G0_CPU1_G2_TX_DN<9>")
	)
	(arc
		(start 121.026682 -233.489754)
		(mid 121.270009 -233.95432)
		(end 121.026682 -234.418886)
		(width 0.1143)
		(layer "In13.Cu")
		(net "GMI_CPU0_G0_CPU1_G2_TX_DN<9>")
	)
	(arc
		(start 121.026682 -222.149924)
		(mid 121.270009 -222.61449)
		(end 121.026682 -223.079056)
		(width 0.1143)
		(layer "In13.Cu")
		(net "GMI_CPU0_G0_CPU1_G2_TX_DN<9>")
	)
	(arc
		(start 350.4692 -226.318826)
		(mid 350.225873 -225.85426)
		(end 350.4692 -225.389694)
		(width 0.1143)
		(layer "In13.Cu")
		(net "GMI_CPU0_G0_CPU1_G2_TX_DN<9>")
	)
	(arc
		(start 121.026682 -227.00996)
		(mid 121.270009 -227.474526)
		(end 121.026682 -227.939092)
		(width 0.1143)
		(layer "In13.Cu")
		(net "GMI_CPU0_G0_CPU1_G2_TX_DN<9>")
	)
	(arc
		(start 350.538796 -230.208836)
		(mid 350.654223 -230.07546)
		(end 350.695768 -229.904036)
		(width 0.1143)
		(layer "In13.Cu")
		(net "GMI_CPU0_G0_CPU1_G2_TX_DN<9>")
	)
	(arc
		(start 121.024142 -230.248206)
		(mid 121.204794 -230.450951)
		(end 121.270014 -230.71455)
		(width 0.1143)
		(layer "In13.Cu")
		(net "GMI_CPU0_G0_CPU1_G2_TX_DN<9>")
	)
	(arc
		(start 350.695768 -231.524048)
		(mid 350.654802 -231.353642)
		(end 350.540828 -231.220518)
		(width 0.1143)
		(layer "In13.Cu")
		(net "GMI_CPU0_G0_CPU1_G2_TX_DN<9>")
	)
	(arc
		(start 350.4692 -229.55885)
		(mid 350.225873 -229.094284)
		(end 350.4692 -228.629718)
		(width 0.1143)
		(layer "In13.Cu")
		(net "GMI_CPU0_G0_CPU1_G2_TX_DN<9>")
	)
	(arc
		(start 121.026682 -231.869742)
		(mid 121.270009 -232.334308)
		(end 121.026682 -232.798874)
		(width 0.1143)
		(layer "In13.Cu")
		(net "GMI_CPU0_G0_CPU1_G2_TX_DN<9>")
	)
	(arc
		(start 120.957086 -239.319562)
		(mid 120.841659 -239.452938)
		(end 120.800114 -239.624362)
		(width 0.1143)
		(layer "In13.Cu")
		(net "GMI_CPU0_G0_CPU1_G2_TX_DN<9>")
	)
	(arc
		(start 120.490488 -240.127536)
		(mid 120.485888 -240.131057)
		(end 120.481344 -240.134648)
		(width 0.1143)
		(layer "In13.Cu")
		(net "GMI_CPU0_G0_CPU1_G2_TX_DN<9>")
	)
	(arc
		(start 120.800114 -239.624362)
		(mid 120.735599 -239.886581)
		(end 120.556782 -240.088928)
		(width 0.1143)
		(layer "In13.Cu")
		(net "GMI_CPU0_G0_CPU1_G2_TX_DN<9>")
	)
	(arc
		(start 120.955054 -231.220772)
		(mid 120.841125 -231.353919)
		(end 120.800114 -231.524302)
		(width 0.1143)
		(layer "In13.Cu")
		(net "GMI_CPU0_G0_CPU1_G2_TX_DN<9>")
	)
	(arc
		(start 350.538796 -238.308896)
		(mid 350.695773 -238.004096)
		(end 350.538796 -237.699296)
		(width 0.1143)
		(layer "In13.Cu")
		(net "GMI_CPU0_G0_CPU1_G2_TX_DN<9>")
	)
	(arc
		(start 350.4692 -237.658656)
		(mid 350.225873 -237.19409)
		(end 350.4692 -236.729524)
		(width 0.1143)
		(layer "In13.Cu")
		(net "GMI_CPU0_G0_CPU1_G2_TX_DN<9>")
	)
	(arc
		(start 351.014538 -240.134394)
		(mid 351.009994 -240.130803)
		(end 351.005394 -240.127282)
		(width 0.1143)
		(layer "In13.Cu")
		(net "GMI_CPU0_G0_CPU1_G2_TX_DN<9>")
	)
	(arc
		(start 120.32996 -240.434368)
		(mid 120.32997 -240.43767)
		(end 120.32996 -240.440972)
		(width 0.1143)
		(layer "In13.Cu")
		(net "GMI_CPU0_G0_CPU1_G2_TX_DN<9>")
	)
	(arc
		(start 350.4692 -232.79862)
		(mid 350.225873 -232.334054)
		(end 350.4692 -231.869488)
		(width 0.1143)
		(layer "In13.Cu")
		(net "GMI_CPU0_G0_CPU1_G2_TX_DN<9>")
	)
	(arc
		(start 350.4692 -227.938838)
		(mid 350.225873 -227.474272)
		(end 350.4692 -227.009706)
		(width 0.1143)
		(layer "In13.Cu")
		(net "GMI_CPU0_G0_CPU1_G2_TX_DN<9>")
	)
	(arc
		(start 121.026682 -223.769936)
		(mid 121.270009 -224.234502)
		(end 121.026682 -224.699068)
		(width 0.1143)
		(layer "In13.Cu")
		(net "GMI_CPU0_G0_CPU1_G2_TX_DN<9>")
	)
	(arc
		(start 120.957086 -224.739708)
		(mid 120.800109 -225.044508)
		(end 120.957086 -225.349308)
		(width 0.1143)
		(layer "In13.Cu")
		(net "GMI_CPU0_G0_CPU1_G2_TX_DN<9>")
	)
	(arc
		(start 120.957086 -227.979732)
		(mid 120.800109 -228.284532)
		(end 120.957086 -228.589332)
		(width 0.1143)
		(layer "In13.Cu")
		(net "GMI_CPU0_G0_CPU1_G2_TX_DN<9>")
	)
	(arc
		(start 121.026682 -228.629972)
		(mid 121.270009 -229.094538)
		(end 121.026682 -229.559104)
		(width 0.1143)
		(layer "In13.Cu")
		(net "GMI_CPU0_G0_CPU1_G2_TX_DN<9>")
	)
	(arc
		(start 351.411794 -240.900458)
		(mid 351.403616 -240.894815)
		(end 351.395538 -240.889028)
		(width 0.1143)
		(layer "In13.Cu")
		(net "GMI_CPU0_G0_CPU1_G2_TX_DN<9>")
	)
	(arc
		(start 350.538796 -222.10903)
		(mid 350.654223 -221.975654)
		(end 350.695768 -221.80423)
		(width 0.1143)
		(layer "In13.Cu")
		(net "GMI_CPU0_G0_CPU1_G2_TX_DN<9>")
	)
	(arc
		(start 120.800114 -221.804484)
		(mid 120.841663 -221.975906)
		(end 120.957086 -222.109284)
		(width 0.1143)
		(layer "In13.Cu")
		(net "GMI_CPU0_G0_CPU1_G2_TX_DN<9>")
	)
	(arc
		(start 120.016016 -240.940082)
		(mid 119.918881 -241.042951)
		(end 119.866918 -241.174524)
		(width 0.1143)
		(layer "In13.Cu")
		(net "GMI_CPU0_G0_CPU1_G2_TX_DN<9>")
	)
	(arc
		(start 350.4692 -236.038644)
		(mid 350.225873 -235.574078)
		(end 350.4692 -235.109512)
		(width 0.1143)
		(layer "In13.Cu")
		(net "GMI_CPU0_G0_CPU1_G2_TX_DN<9>")
	)
	(segment
		(start 351.728024 -239.890046)
		(end 351.261172 -239.624108)
		(width 0.12954)
		(layer "F.Cu")
		(net "GMI_CPU0_G0_CPU1_G2_TX_DN<8>")
	)
	(segment
		(start 119.767858 -239.8903)
		(end 120.23471 -239.624362)
		(width 0.12954)
		(layer "F.Cu")
		(net "GMI_CPU0_G0_CPU1_G2_TX_DN<8>")
	)
	(segment
		(start 351.4471 -239.30102)
		(end 351.445068 -239.29975)
		(width 0.1143)
		(layer "In13.Cu")
		(net "GMI_CPU0_G0_CPU1_G2_TX_DN<8>")
	)
	(segment
		(start 120.043448 -234.444286)
		(end 120.042432 -234.444794)
		(width 0.1143)
		(layer "In13.Cu")
		(net "GMI_CPU0_G0_CPU1_G2_TX_DN<8>")
	)
	(segment
		(start 351.448878 -231.84612)
		(end 351.450148 -231.845358)
		(width 0.1143)
		(layer "In13.Cu")
		(net "GMI_CPU0_G0_CPU1_G2_TX_DN<8>")
	)
	(segment
		(start 120.047766 -235.086906)
		(end 120.050306 -235.088684)
		(width 0.1143)
		(layer "In13.Cu")
		(net "GMI_CPU0_G0_CPU1_G2_TX_DN<8>")
	)
	(segment
		(start 120.016016 -236.68863)
		(end 120.047004 -236.70641)
		(width 0.1143)
		(layer "In13.Cu")
		(net "GMI_CPU0_G0_CPU1_G2_TX_DN<8>")
	)
	(segment
		(start 119.936768 -239.624362)
		(end 120.23471 -239.624362)
		(width 0.1143)
		(layer "In13.Cu")
		(net "GMI_CPU0_G0_CPU1_G2_TX_DN<8>")
	)
	(segment
		(start 351.455228 -223.105726)
		(end 351.454212 -223.105218)
		(width 0.1143)
		(layer "In13.Cu")
		(net "GMI_CPU0_G0_CPU1_G2_TX_DN<8>")
	)
	(segment
		(start 351.451672 -223.74479)
		(end 351.452434 -223.744282)
		(width 0.1143)
		(layer "In13.Cu")
		(net "GMI_CPU0_G0_CPU1_G2_TX_DN<8>")
	)
	(segment
		(start 120.0404 -226.346004)
		(end 120.016016 -226.360228)
		(width 0.1143)
		(layer "In13.Cu")
		(net "GMI_CPU0_G0_CPU1_G2_TX_DN<8>")
	)
	(segment
		(start 351.409 -228.629464)
		(end 351.445322 -228.608636)
		(width 0.1143)
		(layer "In13.Cu")
		(net "GMI_CPU0_G0_CPU1_G2_TX_DN<8>")
	)
	(segment
		(start 120.05056 -225.368866)
		(end 120.086628 -225.389694)
		(width 0.1143)
		(layer "In13.Cu")
		(net "GMI_CPU0_G0_CPU1_G2_TX_DN<8>")
	)
	(segment
		(start 120.047004 -231.846374)
		(end 120.047766 -231.846882)
		(width 0.1143)
		(layer "In13.Cu")
		(net "GMI_CPU0_G0_CPU1_G2_TX_DN<8>")
	)
	(segment
		(start 351.635822 -221.337378)
		(end 351.670112 -221.303088)
		(width 0.1143)
		(layer "In13.Cu")
		(net "GMI_CPU0_G0_CPU1_G2_TX_DN<8>")
	)
	(segment
		(start 120.015 -229.601014)
		(end 120.014238 -229.601522)
		(width 0.1143)
		(layer "In13.Cu")
		(net "GMI_CPU0_G0_CPU1_G2_TX_DN<8>")
	)
	(segment
		(start 120.016016 -235.068618)
		(end 120.047004 -235.086398)
		(width 0.1143)
		(layer "In13.Cu")
		(net "GMI_CPU0_G0_CPU1_G2_TX_DN<8>")
	)
	(segment
		(start 351.452434 -228.604318)
		(end 351.45345 -228.60381)
		(width 0.1143)
		(layer "In13.Cu")
		(net "GMI_CPU0_G0_CPU1_G2_TX_DN<8>")
	)
	(segment
		(start 351.408492 -234.418632)
		(end 351.392236 -234.406694)
		(width 0.1143)
		(layer "In13.Cu")
		(net "GMI_CPU0_G0_CPU1_G2_TX_DN<8>")
	)
	(segment
		(start 351.455228 -237.68558)
		(end 351.454212 -237.685072)
		(width 0.1143)
		(layer "In13.Cu")
		(net "GMI_CPU0_G0_CPU1_G2_TX_DN<8>")
	)
	(segment
		(start 150.404576 -192.484756)
		(end 150.385526 -192.677796)
		(width 0.14224)
		(layer "In13.Cu")
		(net "GMI_CPU0_G0_CPU1_G2_TX_DN<8>")
	)
	(segment
		(start 351.448878 -234.442)
		(end 351.448116 -234.441492)
		(width 0.1143)
		(layer "In13.Cu")
		(net "GMI_CPU0_G0_CPU1_G2_TX_DN<8>")
	)
	(segment
		(start 120.041162 -226.345496)
		(end 120.0404 -226.346004)
		(width 0.1143)
		(layer "In13.Cu")
		(net "GMI_CPU0_G0_CPU1_G2_TX_DN<8>")
	)
	(segment
		(start 153.002234 -190.532258)
		(end 152.672034 -190.803022)
		(width 0.14224)
		(layer "In13.Cu")
		(net "GMI_CPU0_G0_CPU1_G2_TX_DN<8>")
	)
	(segment
		(start 351.451672 -238.324644)
		(end 351.452434 -238.324136)
		(width 0.1143)
		(layer "In13.Cu")
		(net "GMI_CPU0_G0_CPU1_G2_TX_DN<8>")
	)
	(segment
		(start 120.044464 -230.225092)
		(end 120.047766 -230.22687)
		(width 0.1143)
		(layer "In13.Cu")
		(net "GMI_CPU0_G0_CPU1_G2_TX_DN<8>")
	)
	(segment
		(start 351.4471 -230.227124)
		(end 351.448116 -230.226616)
		(width 0.1143)
		(layer "In13.Cu")
		(net "GMI_CPU0_G0_CPU1_G2_TX_DN<8>")
	)
	(segment
		(start 351.414588 -230.246174)
		(end 351.416112 -230.245158)
		(width 0.1143)
		(layer "In13.Cu")
		(net "GMI_CPU0_G0_CPU1_G2_TX_DN<8>")
	)
	(segment
		(start 120.04167 -223.105472)
		(end 120.040654 -223.10598)
		(width 0.1143)
		(layer "In13.Cu")
		(net "GMI_CPU0_G0_CPU1_G2_TX_DN<8>")
	)
	(segment
		(start 119.866918 -239.554512)
		(end 119.936768 -239.624362)
		(width 0.1143)
		(layer "In13.Cu")
		(net "GMI_CPU0_G0_CPU1_G2_TX_DN<8>")
	)
	(segment
		(start 351.448878 -225.366326)
		(end 351.450148 -225.365564)
		(width 0.1143)
		(layer "In13.Cu")
		(net "GMI_CPU0_G0_CPU1_G2_TX_DN<8>")
	)
	(segment
		(start 351.629218 -239.55375)
		(end 351.617534 -239.491012)
		(width 0.1143)
		(layer "In13.Cu")
		(net "GMI_CPU0_G0_CPU1_G2_TX_DN<8>")
	)
	(segment
		(start 120.048782 -239.301274)
		(end 119.96674 -239.354614)
		(width 0.1143)
		(layer "In13.Cu")
		(net "GMI_CPU0_G0_CPU1_G2_TX_DN<8>")
	)
	(segment
		(start 152.672034 -190.803022)
		(end 152.478994 -190.783972)
		(width 0.14224)
		(layer "In13.Cu")
		(net "GMI_CPU0_G0_CPU1_G2_TX_DN<8>")
	)
	(segment
		(start 351.451672 -232.823512)
		(end 351.450148 -232.82275)
		(width 0.1143)
		(layer "In13.Cu")
		(net "GMI_CPU0_G0_CPU1_G2_TX_DN<8>")
	)
	(segment
		(start 307.036978 -182.593488)
		(end 302.895 -182.593488)
		(width 0.14224)
		(layer "In13.Cu")
		(net "GMI_CPU0_G0_CPU1_G2_TX_DN<8>")
	)
	(segment
		(start 351.451672 -226.984814)
		(end 351.452434 -226.984306)
		(width 0.1143)
		(layer "In13.Cu")
		(net "GMI_CPU0_G0_CPU1_G2_TX_DN<8>")
	)
	(segment
		(start 351.45345 -232.824528)
		(end 351.452434 -232.82402)
		(width 0.1143)
		(layer "In13.Cu")
		(net "GMI_CPU0_G0_CPU1_G2_TX_DN<8>")
	)
	(segment
		(start 351.45345 -225.363786)
		(end 351.479866 -225.348546)
		(width 0.1143)
		(layer "In13.Cu")
		(net "GMI_CPU0_G0_CPU1_G2_TX_DN<8>")
	)
	(segment
		(start 351.456244 -234.446064)
		(end 351.454212 -234.445048)
		(width 0.1143)
		(layer "In13.Cu")
		(net "GMI_CPU0_G0_CPU1_G2_TX_DN<8>")
	)
	(segment
		(start 120.043702 -227.964238)
		(end 120.042686 -227.964746)
		(width 0.1143)
		(layer "In13.Cu")
		(net "GMI_CPU0_G0_CPU1_G2_TX_DN<8>")
	)
	(segment
		(start 351.448116 -230.226616)
		(end 351.451418 -230.224838)
		(width 0.1143)
		(layer "In13.Cu")
		(net "GMI_CPU0_G0_CPU1_G2_TX_DN<8>")
	)
	(segment
		(start 119.82577 -221.303342)
		(end 119.86006 -221.337632)
		(width 0.1143)
		(layer "In13.Cu")
		(net "GMI_CPU0_G0_CPU1_G2_TX_DN<8>")
	)
	(segment
		(start 120.043448 -236.064298)
		(end 120.042432 -236.064806)
		(width 0.1143)
		(layer "In13.Cu")
		(net "GMI_CPU0_G0_CPU1_G2_TX_DN<8>")
	)
	(segment
		(start 351.448116 -236.061504)
		(end 351.408492 -236.038644)
		(width 0.1143)
		(layer "In13.Cu")
		(net "GMI_CPU0_G0_CPU1_G2_TX_DN<8>")
	)
	(segment
		(start 351.452434 -233.4641)
		(end 351.45345 -233.463592)
		(width 0.1143)
		(layer "In13.Cu")
		(net "GMI_CPU0_G0_CPU1_G2_TX_DN<8>")
	)
	(segment
		(start 351.670112 -221.145862)
		(end 351.624392 -221.100142)
		(width 0.1143)
		(layer "In13.Cu")
		(net "GMI_CPU0_G0_CPU1_G2_TX_DN<8>")
	)
	(segment
		(start 351.448116 -236.706664)
		(end 351.448878 -236.706156)
		(width 0.1143)
		(layer "In13.Cu")
		(net "GMI_CPU0_G0_CPU1_G2_TX_DN<8>")
	)
	(segment
		(start 351.451672 -231.844596)
		(end 351.452434 -231.844088)
		(width 0.1143)
		(layer "In13.Cu")
		(net "GMI_CPU0_G0_CPU1_G2_TX_DN<8>")
	)
	(segment
		(start 351.481644 -229.601268)
		(end 351.480882 -229.60076)
		(width 0.1143)
		(layer "In13.Cu")
		(net "GMI_CPU0_G0_CPU1_G2_TX_DN<8>")
	)
	(segment
		(start 120.052592 -239.298988)
		(end 120.050814 -239.300004)
		(width 0.1143)
		(layer "In13.Cu")
		(net "GMI_CPU0_G0_CPU1_G2_TX_DN<8>")
	)
	(segment
		(start 351.392236 -235.12145)
		(end 351.408492 -235.109512)
		(width 0.1143)
		(layer "In13.Cu")
		(net "GMI_CPU0_G0_CPU1_G2_TX_DN<8>")
	)
	(segment
		(start 119.87149 -219.380816)
		(end 119.87149 -221.071948)
		(width 0.14224)
		(layer "In13.Cu")
		(net "GMI_CPU0_G0_CPU1_G2_TX_DN<8>")
	)
	(segment
		(start 351.451672 -234.443524)
		(end 351.450148 -234.442762)
		(width 0.1143)
		(layer "In13.Cu")
		(net "GMI_CPU0_G0_CPU1_G2_TX_DN<8>")
	)
	(segment
		(start 351.628964 -239.554258)
		(end 351.629218 -239.554258)
		(width 0.1143)
		(layer "In13.Cu")
		(net "GMI_CPU0_G0_CPU1_G2_TX_DN<8>")
	)
	(segment
		(start 351.47885 -233.44886)
		(end 351.48139 -233.446828)
		(width 0.1143)
		(layer "In13.Cu")
		(net "GMI_CPU0_G0_CPU1_G2_TX_DN<8>")
	)
	(segment
		(start 351.45218 -227.963984)
		(end 351.451418 -227.963476)
		(width 0.1143)
		(layer "In13.Cu")
		(net "GMI_CPU0_G0_CPU1_G2_TX_DN<8>")
	)
	(segment
		(start 155.768802 -188.085984)
		(end 155.749752 -188.279024)
		(width 0.14224)
		(layer "In13.Cu")
		(net "GMI_CPU0_G0_CPU1_G2_TX_DN<8>")
	)
	(segment
		(start 161.119312 -183.698388)
		(end 155.768802 -188.085984)
		(width 0.14224)
		(layer "In13.Cu")
		(net "GMI_CPU0_G0_CPU1_G2_TX_DN<8>")
	)
	(segment
		(start 351.448878 -223.10217)
		(end 351.445068 -223.09963)
		(width 0.1143)
		(layer "In13.Cu")
		(net "GMI_CPU0_G0_CPU1_G2_TX_DN<8>")
	)
	(segment
		(start 351.448116 -226.986846)
		(end 351.448878 -226.986338)
		(width 0.1143)
		(layer "In13.Cu")
		(net "GMI_CPU0_G0_CPU1_G2_TX_DN<8>")
	)
	(segment
		(start 120.047004 -234.442254)
		(end 120.045734 -234.443016)
		(width 0.1143)
		(layer "In13.Cu")
		(net "GMI_CPU0_G0_CPU1_G2_TX_DN<8>")
	)
	(segment
		(start 120.04548 -226.34321)
		(end 120.044464 -226.343718)
		(width 0.1143)
		(layer "In13.Cu")
		(net "GMI_CPU0_G0_CPU1_G2_TX_DN<8>")
	)
	(segment
		(start 119.87149 -221.071948)
		(end 119.87149 -221.100396)
		(width 0.1143)
		(layer "In13.Cu")
		(net "GMI_CPU0_G0_CPU1_G2_TX_DN<8>")
	)
	(segment
		(start 154.877516 -188.994288)
		(end 154.547316 -189.265052)
		(width 0.14224)
		(layer "In13.Cu")
		(net "GMI_CPU0_G0_CPU1_G2_TX_DN<8>")
	)
	(segment
		(start 120.041924 -227.965254)
		(end 120.016016 -227.98024)
		(width 0.1143)
		(layer "In13.Cu")
		(net "GMI_CPU0_G0_CPU1_G2_TX_DN<8>")
	)
	(segment
		(start 351.450148 -231.845358)
		(end 351.451672 -231.844596)
		(width 0.1143)
		(layer "In13.Cu")
		(net "GMI_CPU0_G0_CPU1_G2_TX_DN<8>")
	)
	(segment
		(start 120.043702 -226.344226)
		(end 120.041162 -226.345496)
		(width 0.1143)
		(layer "In13.Cu")
		(net "GMI_CPU0_G0_CPU1_G2_TX_DN<8>")
	)
	(segment
		(start 351.409254 -227.939092)
		(end 351.381822 -227.919534)
		(width 0.1143)
		(layer "In13.Cu")
		(net "GMI_CPU0_G0_CPU1_G2_TX_DN<8>")
	)
	(segment
		(start 351.635822 -221.791022)
		(end 351.635822 -221.337378)
		(width 0.1143)
		(layer "In13.Cu")
		(net "GMI_CPU0_G0_CPU1_G2_TX_DN<8>")
	)
	(segment
		(start 351.445576 -235.08843)
		(end 351.448116 -235.086652)
		(width 0.1143)
		(layer "In13.Cu")
		(net "GMI_CPU0_G0_CPU1_G2_TX_DN<8>")
	)
	(segment
		(start 351.411794 -223.767904)
		(end 351.448116 -223.746822)
		(width 0.1143)
		(layer "In13.Cu")
		(net "GMI_CPU0_G0_CPU1_G2_TX_DN<8>")
	)
	(segment
		(start 351.481644 -231.22128)
		(end 351.448116 -231.201722)
		(width 0.1143)
		(layer "In13.Cu")
		(net "GMI_CPU0_G0_CPU1_G2_TX_DN<8>")
	)
	(segment
		(start 120.047766 -233.466894)
		(end 120.050306 -233.468672)
		(width 0.1143)
		(layer "In13.Cu")
		(net "GMI_CPU0_G0_CPU1_G2_TX_DN<8>")
	)
	(segment
		(start 351.165922 -229.094284)
		(end 351.165922 -229.093776)
		(width 0.1143)
		(layer "In13.Cu")
		(net "GMI_CPU0_G0_CPU1_G2_TX_DN<8>")
	)
	(segment
		(start 351.559114 -239.624108)
		(end 351.628964 -239.554258)
		(width 0.1143)
		(layer "In13.Cu")
		(net "GMI_CPU0_G0_CPU1_G2_TX_DN<8>")
	)
	(segment
		(start 351.445322 -226.988624)
		(end 351.448116 -226.986846)
		(width 0.1143)
		(layer "In13.Cu")
		(net "GMI_CPU0_G0_CPU1_G2_TX_DN<8>")
	)
	(segment
		(start 351.45345 -231.84358)
		(end 351.479866 -231.82834)
		(width 0.1143)
		(layer "In13.Cu")
		(net "GMI_CPU0_G0_CPU1_G2_TX_DN<8>")
	)
	(segment
		(start 308.31536 -183.050434)
		(end 307.036978 -182.593488)
		(width 0.14224)
		(layer "In13.Cu")
		(net "GMI_CPU0_G0_CPU1_G2_TX_DN<8>")
	)
	(segment
		(start 351.408746 -231.869488)
		(end 351.445322 -231.848406)
		(width 0.1143)
		(layer "In13.Cu")
		(net "GMI_CPU0_G0_CPU1_G2_TX_DN<8>")
	)
	(segment
		(start 351.445576 -236.708442)
		(end 351.448116 -236.706664)
		(width 0.1143)
		(layer "In13.Cu")
		(net "GMI_CPU0_G0_CPU1_G2_TX_DN<8>")
	)
	(segment
		(start 120.047004 -233.466386)
		(end 120.047766 -233.466894)
		(width 0.1143)
		(layer "In13.Cu")
		(net "GMI_CPU0_G0_CPU1_G2_TX_DN<8>")
	)
	(segment
		(start 351.454212 -223.105218)
		(end 351.45345 -223.10471)
		(width 0.1143)
		(layer "In13.Cu")
		(net "GMI_CPU0_G0_CPU1_G2_TX_DN<8>")
	)
	(segment
		(start 351.453196 -227.964492)
		(end 351.45218 -227.963984)
		(width 0.1143)
		(layer "In13.Cu")
		(net "GMI_CPU0_G0_CPU1_G2_TX_DN<8>")
	)
	(segment
		(start 153.89352 -189.6237)
		(end 153.87447 -189.81674)
		(width 0.14224)
		(layer "In13.Cu")
		(net "GMI_CPU0_G0_CPU1_G2_TX_DN<8>")
	)
	(segment
		(start 351.261172 -239.624108)
		(end 351.559114 -239.624108)
		(width 0.1143)
		(layer "In13.Cu")
		(net "GMI_CPU0_G0_CPU1_G2_TX_DN<8>")
	)
	(segment
		(start 150.734522 -192.214246)
		(end 150.404576 -192.484756)
		(width 0.14224)
		(layer "In13.Cu")
		(net "GMI_CPU0_G0_CPU1_G2_TX_DN<8>")
	)
	(segment
		(start 351.45345 -234.44454)
		(end 351.452434 -234.444032)
		(width 0.1143)
		(layer "In13.Cu")
		(net "GMI_CPU0_G0_CPU1_G2_TX_DN<8>")
	)
	(segment
		(start 120.046242 -227.962714)
		(end 120.04548 -227.963222)
		(width 0.1143)
		(layer "In13.Cu")
		(net "GMI_CPU0_G0_CPU1_G2_TX_DN<8>")
	)
	(segment
		(start 120.04421 -234.443778)
		(end 120.043448 -234.444286)
		(width 0.1143)
		(layer "In13.Cu")
		(net "GMI_CPU0_G0_CPU1_G2_TX_DN<8>")
	)
	(segment
		(start 351.448116 -224.721674)
		(end 351.411794 -224.700592)
		(width 0.1143)
		(layer "In13.Cu")
		(net "GMI_CPU0_G0_CPU1_G2_TX_DN<8>")
	)
	(segment
		(start 351.45472 -226.345242)
		(end 351.45218 -226.343972)
		(width 0.1143)
		(layer "In13.Cu")
		(net "GMI_CPU0_G0_CPU1_G2_TX_DN<8>")
	)
	(segment
		(start 149.51329 -193.392806)
		(end 149.18309 -193.66357)
		(width 0.14224)
		(layer "In13.Cu")
		(net "GMI_CPU0_G0_CPU1_G2_TX_DN<8>")
	)
	(segment
		(start 351.451672 -236.063536)
		(end 351.450148 -236.062774)
		(width 0.1143)
		(layer "In13.Cu")
		(net "GMI_CPU0_G0_CPU1_G2_TX_DN<8>")
	)
	(segment
		(start 351.48012 -234.460034)
		(end 351.456244 -234.446064)
		(width 0.1143)
		(layer "In13.Cu")
		(net "GMI_CPU0_G0_CPU1_G2_TX_DN<8>")
	)
	(segment
		(start 120.103646 -236.02696)
		(end 120.08739 -236.038898)
		(width 0.1143)
		(layer "In13.Cu")
		(net "GMI_CPU0_G0_CPU1_G2_TX_DN<8>")
	)
	(segment
		(start 119.87149 -221.100396)
		(end 119.82577 -221.146116)
		(width 0.1143)
		(layer "In13.Cu")
		(net "GMI_CPU0_G0_CPU1_G2_TX_DN<8>")
	)
	(segment
		(start 120.086628 -227.009706)
		(end 120.11406 -227.029264)
		(width 0.1143)
		(layer "In13.Cu")
		(net "GMI_CPU0_G0_CPU1_G2_TX_DN<8>")
	)
	(segment
		(start 351.478342 -233.449114)
		(end 351.47885 -233.44886)
		(width 0.1143)
		(layer "In13.Cu")
		(net "GMI_CPU0_G0_CPU1_G2_TX_DN<8>")
	)
	(segment
		(start 120.045734 -232.823004)
		(end 120.04421 -232.823766)
		(width 0.1143)
		(layer "In13.Cu")
		(net "GMI_CPU0_G0_CPU1_G2_TX_DN<8>")
	)
	(segment
		(start 120.050814 -223.099884)
		(end 120.047004 -223.102424)
		(width 0.1143)
		(layer "In13.Cu")
		(net "GMI_CPU0_G0_CPU1_G2_TX_DN<8>")
	)
	(segment
		(start 351.452434 -231.844088)
		(end 351.45345 -231.84358)
		(width 0.1143)
		(layer "In13.Cu")
		(net "GMI_CPU0_G0_CPU1_G2_TX_DN<8>")
	)
	(segment
		(start 120.08866 -229.55758)
		(end 120.047766 -229.581456)
		(width 0.1143)
		(layer "In13.Cu")
		(net "GMI_CPU0_G0_CPU1_G2_TX_DN<8>")
	)
	(segment
		(start 351.445322 -231.848406)
		(end 351.448116 -231.846628)
		(width 0.1143)
		(layer "In13.Cu")
		(net "GMI_CPU0_G0_CPU1_G2_TX_DN<8>")
	)
	(segment
		(start 120.047766 -238.32693)
		(end 120.08739 -238.34979)
		(width 0.1143)
		(layer "In13.Cu")
		(net "GMI_CPU0_G0_CPU1_G2_TX_DN<8>")
	)
	(segment
		(start 351.381822 -227.02901)
		(end 351.409254 -227.009452)
		(width 0.1143)
		(layer "In13.Cu")
		(net "GMI_CPU0_G0_CPU1_G2_TX_DN<8>")
	)
	(segment
		(start 351.445068 -239.29975)
		(end 351.44329 -239.298734)
		(width 0.1143)
		(layer "In13.Cu")
		(net "GMI_CPU0_G0_CPU1_G2_TX_DN<8>")
	)
	(segment
		(start 120.016016 -228.588824)
		(end 120.047004 -228.606604)
		(width 0.1143)
		(layer "In13.Cu")
		(net "GMI_CPU0_G0_CPU1_G2_TX_DN<8>")
	)
	(segment
		(start 120.086882 -228.629718)
		(end 120.095518 -228.635814)
		(width 0.1143)
		(layer "In13.Cu")
		(net "GMI_CPU0_G0_CPU1_G2_TX_DN<8>")
	)
	(segment
		(start 120.10263 -232.787952)
		(end 120.087136 -232.798874)
		(width 0.1143)
		(layer "In13.Cu")
		(net "GMI_CPU0_G0_CPU1_G2_TX_DN<8>")
	)
	(segment
		(start 120.04421 -223.103948)
		(end 120.043448 -223.104456)
		(width 0.1143)
		(layer "In13.Cu")
		(net "GMI_CPU0_G0_CPU1_G2_TX_DN<8>")
	)
	(segment
		(start 120.05056 -228.60889)
		(end 120.086882 -228.629718)
		(width 0.1143)
		(layer "In13.Cu")
		(net "GMI_CPU0_G0_CPU1_G2_TX_DN<8>")
	)
	(segment
		(start 120.045734 -223.103186)
		(end 120.04421 -223.103948)
		(width 0.1143)
		(layer "In13.Cu")
		(net "GMI_CPU0_G0_CPU1_G2_TX_DN<8>")
	)
	(segment
		(start 351.477834 -235.06938)
		(end 351.478596 -235.068872)
		(width 0.1143)
		(layer "In13.Cu")
		(net "GMI_CPU0_G0_CPU1_G2_TX_DN<8>")
	)
	(segment
		(start 351.44456 -230.228648)
		(end 351.445576 -230.22814)
		(width 0.1143)
		(layer "In13.Cu")
		(net "GMI_CPU0_G0_CPU1_G2_TX_DN<8>")
	)
	(segment
		(start 351.409254 -226.31908)
		(end 351.390712 -226.305872)
		(width 0.1143)
		(layer "In13.Cu")
		(net "GMI_CPU0_G0_CPU1_G2_TX_DN<8>")
	)
	(segment
		(start 119.86006 -221.337632)
		(end 119.86006 -221.791276)
		(width 0.1143)
		(layer "In13.Cu")
		(net "GMI_CPU0_G0_CPU1_G2_TX_DN<8>")
	)
	(segment
		(start 351.452434 -238.324136)
		(end 351.45345 -238.323628)
		(width 0.1143)
		(layer "In13.Cu")
		(net "GMI_CPU0_G0_CPU1_G2_TX_DN<8>")
	)
	(segment
		(start 351.410016 -236.728508)
		(end 351.445576 -236.708442)
		(width 0.1143)
		(layer "In13.Cu")
		(net "GMI_CPU0_G0_CPU1_G2_TX_DN<8>")
	)
	(segment
		(start 351.448878 -237.682024)
		(end 351.448116 -237.681516)
		(width 0.1143)
		(layer "In13.Cu")
		(net "GMI_CPU0_G0_CPU1_G2_TX_DN<8>")
	)
	(segment
		(start 351.448116 -233.46664)
		(end 351.448878 -233.466132)
		(width 0.1143)
		(layer "In13.Cu")
		(net "GMI_CPU0_G0_CPU1_G2_TX_DN<8>")
	)
	(segment
		(start 351.45345 -226.983798)
		(end 351.479866 -226.968558)
		(width 0.1143)
		(layer "In13.Cu")
		(net "GMI_CPU0_G0_CPU1_G2_TX_DN<8>")
	)
	(segment
		(start 351.392236 -233.501438)
		(end 351.408492 -233.4895)
		(width 0.1143)
		(layer "In13.Cu")
		(net "GMI_CPU0_G0_CPU1_G2_TX_DN<8>")
	)
	(segment
		(start 351.450148 -236.705394)
		(end 351.451672 -236.704632)
		(width 0.1143)
		(layer "In13.Cu")
		(net "GMI_CPU0_G0_CPU1_G2_TX_DN<8>")
	)
	(segment
		(start 351.448878 -233.466132)
		(end 351.450148 -233.46537)
		(width 0.1143)
		(layer "In13.Cu")
		(net "GMI_CPU0_G0_CPU1_G2_TX_DN<8>")
	)
	(segment
		(start 120.084088 -224.700846)
		(end 120.047766 -224.721928)
		(width 0.1143)
		(layer "In13.Cu")
		(net "GMI_CPU0_G0_CPU1_G2_TX_DN<8>")
	)
	(segment
		(start 120.047766 -237.68177)
		(end 120.047004 -237.682278)
		(width 0.1143)
		(layer "In13.Cu")
		(net "GMI_CPU0_G0_CPU1_G2_TX_DN<8>")
	)
	(segment
		(start 120.047766 -231.846882)
		(end 120.05056 -231.84866)
		(width 0.1143)
		(layer "In13.Cu")
		(net "GMI_CPU0_G0_CPU1_G2_TX_DN<8>")
	)
	(segment
		(start 120.047766 -232.821734)
		(end 120.047004 -232.822242)
		(width 0.1143)
		(layer "In13.Cu")
		(net "GMI_CPU0_G0_CPU1_G2_TX_DN<8>")
	)
	(segment
		(start 120.044464 -226.343718)
		(end 120.043702 -226.344226)
		(width 0.1143)
		(layer "In13.Cu")
		(net "GMI_CPU0_G0_CPU1_G2_TX_DN<8>")
	)
	(segment
		(start 120.10517 -226.306126)
		(end 120.086628 -226.319334)
		(width 0.1143)
		(layer "In13.Cu")
		(net "GMI_CPU0_G0_CPU1_G2_TX_DN<8>")
	)
	(segment
		(start 120.016016 -233.448606)
		(end 120.047004 -233.466386)
		(width 0.1143)
		(layer "In13.Cu")
		(net "GMI_CPU0_G0_CPU1_G2_TX_DN<8>")
	)
	(segment
		(start 119.878348 -239.491266)
		(end 119.866664 -239.554004)
		(width 0.1143)
		(layer "In13.Cu")
		(net "GMI_CPU0_G0_CPU1_G2_TX_DN<8>")
	)
	(segment
		(start 351.448878 -236.062012)
		(end 351.448116 -236.061504)
		(width 0.1143)
		(layer "In13.Cu")
		(net "GMI_CPU0_G0_CPU1_G2_TX_DN<8>")
	)
	(segment
		(start 120.050306 -235.088684)
		(end 120.08739 -235.109766)
		(width 0.1143)
		(layer "In13.Cu")
		(net "GMI_CPU0_G0_CPU1_G2_TX_DN<8>")
	)
	(segment
		(start 120.039638 -232.826306)
		(end 120.015762 -232.840276)
		(width 0.1143)
		(layer "In13.Cu")
		(net "GMI_CPU0_G0_CPU1_G2_TX_DN<8>")
	)
	(segment
		(start 120.10136 -237.64875)
		(end 120.085866 -237.659926)
		(width 0.1143)
		(layer "In13.Cu")
		(net "GMI_CPU0_G0_CPU1_G2_TX_DN<8>")
	)
	(segment
		(start 152.149048 -191.054482)
		(end 152.129998 -191.247522)
		(width 0.14224)
		(layer "In13.Cu")
		(net "GMI_CPU0_G0_CPU1_G2_TX_DN<8>")
	)
	(segment
		(start 120.042432 -234.444794)
		(end 120.04167 -234.445302)
		(width 0.1143)
		(layer "In13.Cu")
		(net "GMI_CPU0_G0_CPU1_G2_TX_DN<8>")
	)
	(segment
		(start 351.455482 -226.34575)
		(end 351.45472 -226.345242)
		(width 0.1143)
		(layer "In13.Cu")
		(net "GMI_CPU0_G0_CPU1_G2_TX_DN<8>")
	)
	(segment
		(start 351.450148 -228.605588)
		(end 351.451672 -228.604826)
		(width 0.1143)
		(layer "In13.Cu")
		(net "GMI_CPU0_G0_CPU1_G2_TX_DN<8>")
	)
	(segment
		(start 120.045734 -234.443016)
		(end 120.04421 -234.443778)
		(width 0.1143)
		(layer "In13.Cu")
		(net "GMI_CPU0_G0_CPU1_G2_TX_DN<8>")
	)
	(segment
		(start 351.450148 -235.085382)
		(end 351.451672 -235.08462)
		(width 0.1143)
		(layer "In13.Cu")
		(net "GMI_CPU0_G0_CPU1_G2_TX_DN<8>")
	)
	(segment
		(start 120.017032 -222.09633)
		(end 120.095772 -222.143066)
		(width 0.1143)
		(layer "In13.Cu")
		(net "GMI_CPU0_G0_CPU1_G2_TX_DN<8>")
	)
	(segment
		(start 120.047004 -236.70641)
		(end 120.047766 -236.706918)
		(width 0.1143)
		(layer "In13.Cu")
		(net "GMI_CPU0_G0_CPU1_G2_TX_DN<8>")
	)
	(segment
		(start 351.448878 -228.60635)
		(end 351.450148 -228.605588)
		(width 0.1143)
		(layer "In13.Cu")
		(net "GMI_CPU0_G0_CPU1_G2_TX_DN<8>")
	)
	(segment
		(start 120.047766 -229.581456)
		(end 120.047766 -229.581964)
		(width 0.1143)
		(layer "In13.Cu")
		(net "GMI_CPU0_G0_CPU1_G2_TX_DN<8>")
	)
	(segment
		(start 119.866664 -239.554512)
		(end 119.866918 -239.554512)
		(width 0.1143)
		(layer "In13.Cu")
		(net "GMI_CPU0_G0_CPU1_G2_TX_DN<8>")
	)
	(segment
		(start 302.895 -182.593488)
		(end 166.433246 -181.798214)
		(width 0.14224)
		(layer "In13.Cu")
		(net "GMI_CPU0_G0_CPU1_G2_TX_DN<8>")
	)
	(segment
		(start 120.043448 -223.104456)
		(end 120.042432 -223.104964)
		(width 0.1143)
		(layer "In13.Cu")
		(net "GMI_CPU0_G0_CPU1_G2_TX_DN<8>")
	)
	(segment
		(start 120.047004 -235.086398)
		(end 120.047766 -235.086906)
		(width 0.1143)
		(layer "In13.Cu")
		(net "GMI_CPU0_G0_CPU1_G2_TX_DN<8>")
	)
	(segment
		(start 120.047766 -225.367088)
		(end 120.05056 -225.368866)
		(width 0.1143)
		(layer "In13.Cu")
		(net "GMI_CPU0_G0_CPU1_G2_TX_DN<8>")
	)
	(segment
		(start 351.445576 -233.468418)
		(end 351.448116 -233.46664)
		(width 0.1143)
		(layer "In13.Cu")
		(net "GMI_CPU0_G0_CPU1_G2_TX_DN<8>")
	)
	(segment
		(start 351.450148 -226.985576)
		(end 351.451672 -226.984814)
		(width 0.1143)
		(layer "In13.Cu")
		(net "GMI_CPU0_G0_CPU1_G2_TX_DN<8>")
	)
	(segment
		(start 349.006414 -214.853774)
		(end 314.465462 -186.532012)
		(width 0.14224)
		(layer "In13.Cu")
		(net "GMI_CPU0_G0_CPU1_G2_TX_DN<8>")
	)
	(segment
		(start 351.529142 -239.35436)
		(end 351.4471 -239.30102)
		(width 0.1143)
		(layer "In13.Cu")
		(net "GMI_CPU0_G0_CPU1_G2_TX_DN<8>")
	)
	(segment
		(start 351.479866 -236.079792)
		(end 351.455228 -236.065568)
		(width 0.1143)
		(layer "In13.Cu")
		(net "GMI_CPU0_G0_CPU1_G2_TX_DN<8>")
	)
	(segment
		(start 351.454212 -237.685072)
		(end 351.45345 -237.684564)
		(width 0.1143)
		(layer "In13.Cu")
		(net "GMI_CPU0_G0_CPU1_G2_TX_DN<8>")
	)
	(segment
		(start 153.35123 -190.068454)
		(end 153.021284 -190.338964)
		(width 0.14224)
		(layer "In13.Cu")
		(net "GMI_CPU0_G0_CPU1_G2_TX_DN<8>")
	)
	(segment
		(start 351.451672 -225.364802)
		(end 351.452434 -225.364294)
		(width 0.1143)
		(layer "In13.Cu")
		(net "GMI_CPU0_G0_CPU1_G2_TX_DN<8>")
	)
	(segment
		(start 120.050306 -236.708696)
		(end 120.085866 -236.728762)
		(width 0.1143)
		(layer "In13.Cu")
		(net "GMI_CPU0_G0_CPU1_G2_TX_DN<8>")
	)
	(segment
		(start 119.866664 -239.554004)
		(end 119.866664 -239.554512)
		(width 0.1143)
		(layer "In13.Cu")
		(net "GMI_CPU0_G0_CPU1_G2_TX_DN<8>")
	)
	(segment
		(start 351.448116 -232.82148)
		(end 351.408746 -232.79862)
		(width 0.1143)
		(layer "In13.Cu")
		(net "GMI_CPU0_G0_CPU1_G2_TX_DN<8>")
	)
	(segment
		(start 120.047004 -226.986592)
		(end 120.047766 -226.9871)
		(width 0.1143)
		(layer "In13.Cu")
		(net "GMI_CPU0_G0_CPU1_G2_TX_DN<8>")
	)
	(segment
		(start 351.47885 -232.839514)
		(end 351.456244 -232.826052)
		(width 0.1143)
		(layer "In13.Cu")
		(net "GMI_CPU0_G0_CPU1_G2_TX_DN<8>")
	)
	(segment
		(start 120.11406 -227.919788)
		(end 120.086628 -227.939346)
		(width 0.1143)
		(layer "In13.Cu")
		(net "GMI_CPU0_G0_CPU1_G2_TX_DN<8>")
	)
	(segment
		(start 351.448878 -238.326168)
		(end 351.450148 -238.325406)
		(width 0.1143)
		(layer "In13.Cu")
		(net "GMI_CPU0_G0_CPU1_G2_TX_DN<8>")
	)
	(segment
		(start 154.547316 -189.265052)
		(end 154.354276 -189.246002)
		(width 0.14224)
		(layer "In13.Cu")
		(net "GMI_CPU0_G0_CPU1_G2_TX_DN<8>")
	)
	(segment
		(start 120.047004 -223.746568)
		(end 120.047766 -223.747076)
		(width 0.1143)
		(layer "In13.Cu")
		(net "GMI_CPU0_G0_CPU1_G2_TX_DN<8>")
	)
	(segment
		(start 153.87447 -189.81674)
		(end 153.54427 -190.087504)
		(width 0.14224)
		(layer "In13.Cu")
		(net "GMI_CPU0_G0_CPU1_G2_TX_DN<8>")
	)
	(segment
		(start 120.05056 -231.200198)
		(end 120.047766 -231.201722)
		(width 0.1143)
		(layer "In13.Cu")
		(net "GMI_CPU0_G0_CPU1_G2_TX_DN<8>")
	)
	(segment
		(start 120.040654 -237.685834)
		(end 120.016016 -237.700058)
		(width 0.1143)
		(layer "In13.Cu")
		(net "GMI_CPU0_G0_CPU1_G2_TX_DN<8>")
	)
	(segment
		(start 120.04167 -234.445302)
		(end 120.039638 -234.446318)
		(width 0.1143)
		(layer "In13.Cu")
		(net "GMI_CPU0_G0_CPU1_G2_TX_DN<8>")
	)
	(segment
		(start 351.45345 -223.10471)
		(end 351.452434 -223.104202)
		(width 0.1143)
		(layer "In13.Cu")
		(net "GMI_CPU0_G0_CPU1_G2_TX_DN<8>")
	)
	(segment
		(start 120.047766 -228.607112)
		(end 120.05056 -228.60889)
		(width 0.1143)
		(layer "In13.Cu")
		(net "GMI_CPU0_G0_CPU1_G2_TX_DN<8>")
	)
	(segment
		(start 351.448116 -225.366834)
		(end 351.448878 -225.366326)
		(width 0.1143)
		(layer "In13.Cu")
		(net "GMI_CPU0_G0_CPU1_G2_TX_DN<8>")
	)
	(segment
		(start 120.103646 -234.406948)
		(end 120.08739 -234.418886)
		(width 0.1143)
		(layer "In13.Cu")
		(net "GMI_CPU0_G0_CPU1_G2_TX_DN<8>")
	)
	(segment
		(start 120.047766 -231.201976)
		(end 120.014238 -231.221534)
		(width 0.1143)
		(layer "In13.Cu")
		(net "GMI_CPU0_G0_CPU1_G2_TX_DN<8>")
	)
	(segment
		(start 351.408492 -239.278668)
		(end 351.392236 -239.26673)
		(width 0.1143)
		(layer "In13.Cu")
		(net "GMI_CPU0_G0_CPU1_G2_TX_DN<8>")
	)
	(segment
		(start 351.483168 -232.842562)
		(end 351.481644 -232.841546)
		(width 0.1143)
		(layer "In13.Cu")
		(net "GMI_CPU0_G0_CPU1_G2_TX_DN<8>")
	)
	(segment
		(start 120.016016 -231.828594)
		(end 120.047004 -231.846374)
		(width 0.1143)
		(layer "In13.Cu")
		(net "GMI_CPU0_G0_CPU1_G2_TX_DN<8>")
	)
	(segment
		(start 120.05056 -231.84866)
		(end 120.087136 -231.869742)
		(width 0.1143)
		(layer "In13.Cu")
		(net "GMI_CPU0_G0_CPU1_G2_TX_DN<8>")
	)
	(segment
		(start 120.042432 -223.104964)
		(end 120.04167 -223.105472)
		(width 0.1143)
		(layer "In13.Cu")
		(net "GMI_CPU0_G0_CPU1_G2_TX_DN<8>")
	)
	(segment
		(start 351.450402 -226.342956)
		(end 351.44964 -226.342448)
		(width 0.1143)
		(layer "In13.Cu")
		(net "GMI_CPU0_G0_CPU1_G2_TX_DN<8>")
	)
	(segment
		(start 351.624392 -221.100142)
		(end 351.624392 -221.093538)
		(width 0.1143)
		(layer "In13.Cu")
		(net "GMI_CPU0_G0_CPU1_G2_TX_DN<8>")
	)
	(segment
		(start 351.450148 -236.062774)
		(end 351.448878 -236.062012)
		(width 0.1143)
		(layer "In13.Cu")
		(net "GMI_CPU0_G0_CPU1_G2_TX_DN<8>")
	)
	(segment
		(start 351.452434 -236.064044)
		(end 351.451672 -236.063536)
		(width 0.1143)
		(layer "In13.Cu")
		(net "GMI_CPU0_G0_CPU1_G2_TX_DN<8>")
	)
	(segment
		(start 120.047766 -230.22687)
		(end 120.048782 -230.227378)
		(width 0.1143)
		(layer "In13.Cu")
		(net "GMI_CPU0_G0_CPU1_G2_TX_DN<8>")
	)
	(segment
		(start 120.050306 -230.228394)
		(end 120.051322 -230.228902)
		(width 0.1143)
		(layer "In13.Cu")
		(net "GMI_CPU0_G0_CPU1_G2_TX_DN<8>")
	)
	(segment
		(start 120.016016 -223.728788)
		(end 120.047004 -223.746568)
		(width 0.1143)
		(layer "In13.Cu")
		(net "GMI_CPU0_G0_CPU1_G2_TX_DN<8>")
	)
	(segment
		(start 351.408492 -235.109512)
		(end 351.445576 -235.08843)
		(width 0.1143)
		(layer "In13.Cu")
		(net "GMI_CPU0_G0_CPU1_G2_TX_DN<8>")
	)
	(segment
		(start 351.624392 -221.093538)
		(end 351.624392 -219.263468)
		(width 0.14224)
		(layer "In13.Cu")
		(net "GMI_CPU0_G0_CPU1_G2_TX_DN<8>")
	)
	(segment
		(start 120.0531 -239.298734)
		(end 120.052592 -239.298988)
		(width 0.1143)
		(layer "In13.Cu")
		(net "GMI_CPU0_G0_CPU1_G2_TX_DN<8>")
	)
	(segment
		(start 147.47113 -194.889374)
		(end 145.90903 -196.170296)
		(width 0.14224)
		(layer "In13.Cu")
		(net "GMI_CPU0_G0_CPU1_G2_TX_DN<8>")
	)
	(segment
		(start 351.452434 -234.444032)
		(end 351.451672 -234.443524)
		(width 0.1143)
		(layer "In13.Cu")
		(net "GMI_CPU0_G0_CPU1_G2_TX_DN<8>")
	)
	(segment
		(start 351.445576 -230.22814)
		(end 351.4471 -230.227124)
		(width 0.1143)
		(layer "In13.Cu")
		(net "GMI_CPU0_G0_CPU1_G2_TX_DN<8>")
	)
	(segment
		(start 351.450148 -234.442762)
		(end 351.448878 -234.442)
		(width 0.1143)
		(layer "In13.Cu")
		(net "GMI_CPU0_G0_CPU1_G2_TX_DN<8>")
	)
	(segment
		(start 119.994934 -235.051854)
		(end 120.016016 -235.068618)
		(width 0.1143)
		(layer "In13.Cu")
		(net "GMI_CPU0_G0_CPU1_G2_TX_DN<8>")
	)
	(segment
		(start 351.394522 -236.739684)
		(end 351.410016 -236.728508)
		(width 0.1143)
		(layer "In13.Cu")
		(net "GMI_CPU0_G0_CPU1_G2_TX_DN<8>")
	)
	(segment
		(start 120.08739 -233.489754)
		(end 120.103646 -233.501692)
		(width 0.1143)
		(layer "In13.Cu")
		(net "GMI_CPU0_G0_CPU1_G2_TX_DN<8>")
	)
	(segment
		(start 351.45345 -235.083604)
		(end 351.477834 -235.06938)
		(width 0.1143)
		(layer "In13.Cu")
		(net "GMI_CPU0_G0_CPU1_G2_TX_DN<8>")
	)
	(segment
		(start 145.90903 -196.170296)
		(end 144.86001 -196.487796)
		(width 0.14224)
		(layer "In13.Cu")
		(net "GMI_CPU0_G0_CPU1_G2_TX_DN<8>")
	)
	(segment
		(start 351.408492 -238.349536)
		(end 351.448116 -238.326676)
		(width 0.1143)
		(layer "In13.Cu")
		(net "GMI_CPU0_G0_CPU1_G2_TX_DN<8>")
	)
	(segment
		(start 351.451672 -228.604826)
		(end 351.452434 -228.604318)
		(width 0.1143)
		(layer "In13.Cu")
		(net "GMI_CPU0_G0_CPU1_G2_TX_DN<8>")
	)
	(segment
		(start 351.448116 -228.606858)
		(end 351.448878 -228.60635)
		(width 0.1143)
		(layer "In13.Cu")
		(net "GMI_CPU0_G0_CPU1_G2_TX_DN<8>")
	)
	(segment
		(start 120.08739 -236.038898)
		(end 120.047766 -236.061758)
		(width 0.1143)
		(layer "In13.Cu")
		(net "GMI_CPU0_G0_CPU1_G2_TX_DN<8>")
	)
	(segment
		(start 351.453958 -227.965)
		(end 351.453196 -227.964492)
		(width 0.1143)
		(layer "In13.Cu")
		(net "GMI_CPU0_G0_CPU1_G2_TX_DN<8>")
	)
	(segment
		(start 351.50171 -234.477306)
		(end 351.48012 -234.460034)
		(width 0.1143)
		(layer "In13.Cu")
		(net "GMI_CPU0_G0_CPU1_G2_TX_DN<8>")
	)
	(segment
		(start 351.48139 -233.446828)
		(end 351.482914 -233.445812)
		(width 0.1143)
		(layer "In13.Cu")
		(net "GMI_CPU0_G0_CPU1_G2_TX_DN<8>")
	)
	(segment
		(start 351.448116 -234.441492)
		(end 351.408492 -234.418632)
		(width 0.1143)
		(layer "In13.Cu")
		(net "GMI_CPU0_G0_CPU1_G2_TX_DN<8>")
	)
	(segment
		(start 153.54427 -190.087504)
		(end 153.35123 -190.068454)
		(width 0.14224)
		(layer "In13.Cu")
		(net "GMI_CPU0_G0_CPU1_G2_TX_DN<8>")
	)
	(segment
		(start 120.087136 -232.798874)
		(end 120.047766 -232.821734)
		(width 0.1143)
		(layer "In13.Cu")
		(net "GMI_CPU0_G0_CPU1_G2_TX_DN<8>")
	)
	(segment
		(start 120.015762 -234.460288)
		(end 119.99468 -234.477052)
		(width 0.1143)
		(layer "In13.Cu")
		(net "GMI_CPU0_G0_CPU1_G2_TX_DN<8>")
	)
	(segment
		(start 120.047004 -237.682278)
		(end 120.045734 -237.68304)
		(width 0.1143)
		(layer "In13.Cu")
		(net "GMI_CPU0_G0_CPU1_G2_TX_DN<8>")
	)
	(segment
		(start 351.448116 -223.746822)
		(end 351.448878 -223.746314)
		(width 0.1143)
		(layer "In13.Cu")
		(net "GMI_CPU0_G0_CPU1_G2_TX_DN<8>")
	)
	(segment
		(start 351.409254 -225.38944)
		(end 351.445322 -225.368612)
		(width 0.1143)
		(layer "In13.Cu")
		(net "GMI_CPU0_G0_CPU1_G2_TX_DN<8>")
	)
	(segment
		(start 150.055326 -192.94856)
		(end 149.862286 -192.929256)
		(width 0.14224)
		(layer "In13.Cu")
		(net "GMI_CPU0_G0_CPU1_G2_TX_DN<8>")
	)
	(segment
		(start 351.450148 -238.325406)
		(end 351.451672 -238.324644)
		(width 0.1143)
		(layer "In13.Cu")
		(net "GMI_CPU0_G0_CPU1_G2_TX_DN<8>")
	)
	(segment
		(start 120.050306 -233.468672)
		(end 120.08739 -233.489754)
		(width 0.1143)
		(layer "In13.Cu")
		(net "GMI_CPU0_G0_CPU1_G2_TX_DN<8>")
	)
	(segment
		(start 351.448116 -231.846628)
		(end 351.448878 -231.84612)
		(width 0.1143)
		(layer "In13.Cu")
		(net "GMI_CPU0_G0_CPU1_G2_TX_DN<8>")
	)
	(segment
		(start 351.45345 -238.323628)
		(end 351.479866 -238.308388)
		(width 0.1143)
		(layer "In13.Cu")
		(net "GMI_CPU0_G0_CPU1_G2_TX_DN<8>")
	)
	(segment
		(start 151.799798 -191.518286)
		(end 151.606758 -191.498982)
		(width 0.14224)
		(layer "In13.Cu")
		(net "GMI_CPU0_G0_CPU1_G2_TX_DN<8>")
	)
	(segment
		(start 151.606758 -191.498982)
		(end 151.276812 -191.769492)
		(width 0.14224)
		(layer "In13.Cu")
		(net "GMI_CPU0_G0_CPU1_G2_TX_DN<8>")
	)
	(segment
		(start 351.408492 -236.038644)
		(end 351.392236 -236.026706)
		(width 0.1143)
		(layer "In13.Cu")
		(net "GMI_CPU0_G0_CPU1_G2_TX_DN<8>")
	)
	(segment
		(start 147.471384 -194.889374)
		(end 147.47113 -194.889374)
		(width 0.14224)
		(layer "In13.Cu")
		(net "GMI_CPU0_G0_CPU1_G2_TX_DN<8>")
	)
	(segment
		(start 150.385526 -192.677796)
		(end 150.055326 -192.94856)
		(width 0.14224)
		(layer "In13.Cu")
		(net "GMI_CPU0_G0_CPU1_G2_TX_DN<8>")
	)
	(segment
		(start 151.257762 -191.962532)
		(end 150.927562 -192.233296)
		(width 0.14224)
		(layer "In13.Cu")
		(net "GMI_CPU0_G0_CPU1_G2_TX_DN<8>")
	)
	(segment
		(start 148.99005 -193.644266)
		(end 147.471384 -194.889374)
		(width 0.14224)
		(layer "In13.Cu")
		(net "GMI_CPU0_G0_CPU1_G2_TX_DN<8>")
	)
	(segment
		(start 120.04167 -236.065314)
		(end 120.040654 -236.065822)
		(width 0.1143)
		(layer "In13.Cu")
		(net "GMI_CPU0_G0_CPU1_G2_TX_DN<8>")
	)
	(segment
		(start 351.629218 -239.554258)
		(end 351.629218 -239.55375)
		(width 0.1143)
		(layer "In13.Cu")
		(net "GMI_CPU0_G0_CPU1_G2_TX_DN<8>")
	)
	(segment
		(start 120.047766 -224.721928)
		(end 120.016016 -224.740216)
		(width 0.1143)
		(layer "In13.Cu")
		(net "GMI_CPU0_G0_CPU1_G2_TX_DN<8>")
	)
	(segment
		(start 120.085866 -236.728762)
		(end 120.10136 -236.739938)
		(width 0.1143)
		(layer "In13.Cu")
		(net "GMI_CPU0_G0_CPU1_G2_TX_DN<8>")
	)
	(segment
		(start 120.046242 -226.342702)
		(end 120.04548 -226.34321)
		(width 0.1143)
		(layer "In13.Cu")
		(net "GMI_CPU0_G0_CPU1_G2_TX_DN<8>")
	)
	(segment
		(start 120.087136 -231.869742)
		(end 120.10263 -231.880664)
		(width 0.1143)
		(layer "In13.Cu")
		(net "GMI_CPU0_G0_CPU1_G2_TX_DN<8>")
	)
	(segment
		(start 351.408746 -232.79862)
		(end 351.393252 -232.787698)
		(width 0.1143)
		(layer "In13.Cu")
		(net "GMI_CPU0_G0_CPU1_G2_TX_DN<8>")
	)
	(segment
		(start 120.044464 -227.96373)
		(end 120.043702 -227.964238)
		(width 0.1143)
		(layer "In13.Cu")
		(net "GMI_CPU0_G0_CPU1_G2_TX_DN<8>")
	)
	(segment
		(start 351.442782 -239.29848)
		(end 351.408492 -239.278668)
		(width 0.1143)
		(layer "In13.Cu")
		(net "GMI_CPU0_G0_CPU1_G2_TX_DN<8>")
	)
	(segment
		(start 120.086628 -226.319334)
		(end 120.046242 -226.342702)
		(width 0.1143)
		(layer "In13.Cu")
		(net "GMI_CPU0_G0_CPU1_G2_TX_DN<8>")
	)
	(segment
		(start 120.047766 -229.581964)
		(end 120.047004 -229.582472)
		(width 0.1143)
		(layer "In13.Cu")
		(net "GMI_CPU0_G0_CPU1_G2_TX_DN<8>")
	)
	(segment
		(start 120.047766 -236.061758)
		(end 120.047004 -236.062266)
		(width 0.1143)
		(layer "In13.Cu")
		(net "GMI_CPU0_G0_CPU1_G2_TX_DN<8>")
	)
	(segment
		(start 351.448878 -236.706156)
		(end 351.450148 -236.705394)
		(width 0.1143)
		(layer "In13.Cu")
		(net "GMI_CPU0_G0_CPU1_G2_TX_DN<8>")
	)
	(segment
		(start 351.454212 -232.825036)
		(end 351.45345 -232.824528)
		(width 0.1143)
		(layer "In13.Cu")
		(net "GMI_CPU0_G0_CPU1_G2_TX_DN<8>")
	)
	(segment
		(start 120.048782 -230.227378)
		(end 120.050306 -230.228394)
		(width 0.1143)
		(layer "In13.Cu")
		(net "GMI_CPU0_G0_CPU1_G2_TX_DN<8>")
	)
	(segment
		(start 152.478994 -190.783972)
		(end 152.149048 -191.054482)
		(width 0.14224)
		(layer "In13.Cu")
		(net "GMI_CPU0_G0_CPU1_G2_TX_DN<8>")
	)
	(segment
		(start 351.479866 -223.11995)
		(end 351.455228 -223.105726)
		(width 0.1143)
		(layer "In13.Cu")
		(net "GMI_CPU0_G0_CPU1_G2_TX_DN<8>")
	)
	(segment
		(start 351.452434 -226.984306)
		(end 351.45345 -226.983798)
		(width 0.1143)
		(layer "In13.Cu")
		(net "GMI_CPU0_G0_CPU1_G2_TX_DN<8>")
	)
	(segment
		(start 120.057926 -223.09582)
		(end 120.050814 -223.099884)
		(width 0.1143)
		(layer "In13.Cu")
		(net "GMI_CPU0_G0_CPU1_G2_TX_DN<8>")
	)
	(segment
		(start 351.44329 -239.298734)
		(end 351.442782 -239.29848)
		(width 0.1143)
		(layer "In13.Cu")
		(net "GMI_CPU0_G0_CPU1_G2_TX_DN<8>")
	)
	(segment
		(start 120.042432 -236.064806)
		(end 120.04167 -236.065314)
		(width 0.1143)
		(layer "In13.Cu")
		(net "GMI_CPU0_G0_CPU1_G2_TX_DN<8>")
	)
	(segment
		(start 314.465462 -186.532012)
		(end 308.31536 -183.050434)
		(width 0.14224)
		(layer "In13.Cu")
		(net "GMI_CPU0_G0_CPU1_G2_TX_DN<8>")
	)
	(segment
		(start 120.32996 -229.09403)
		(end 120.32996 -229.094538)
		(width 0.1143)
		(layer "In13.Cu")
		(net "GMI_CPU0_G0_CPU1_G2_TX_DN<8>")
	)
	(segment
		(start 351.445068 -223.09963)
		(end 351.437956 -223.095566)
		(width 0.1143)
		(layer "In13.Cu")
		(net "GMI_CPU0_G0_CPU1_G2_TX_DN<8>")
	)
	(segment
		(start 351.45218 -226.343972)
		(end 351.451418 -226.343464)
		(width 0.1143)
		(layer "In13.Cu")
		(net "GMI_CPU0_G0_CPU1_G2_TX_DN<8>")
	)
	(segment
		(start 351.448878 -232.821988)
		(end 351.448116 -232.82148)
		(width 0.1143)
		(layer "In13.Cu")
		(net "GMI_CPU0_G0_CPU1_G2_TX_DN<8>")
	)
	(segment
		(start 120.047004 -229.582472)
		(end 120.015 -229.601014)
		(width 0.1143)
		(layer "In13.Cu")
		(net "GMI_CPU0_G0_CPU1_G2_TX_DN<8>")
	)
	(segment
		(start 120.04167 -232.82529)
		(end 120.039638 -232.826306)
		(width 0.1143)
		(layer "In13.Cu")
		(net "GMI_CPU0_G0_CPU1_G2_TX_DN<8>")
	)
	(segment
		(start 150.927562 -192.233296)
		(end 150.734522 -192.214246)
		(width 0.14224)
		(layer "In13.Cu")
		(net "GMI_CPU0_G0_CPU1_G2_TX_DN<8>")
	)
	(segment
		(start 351.481898 -235.066586)
		(end 351.501456 -235.051092)
		(width 0.1143)
		(layer "In13.Cu")
		(net "GMI_CPU0_G0_CPU1_G2_TX_DN<8>")
	)
	(segment
		(start 351.448878 -229.582218)
		(end 351.448116 -229.58171)
		(width 0.1143)
		(layer "In13.Cu")
		(net "GMI_CPU0_G0_CPU1_G2_TX_DN<8>")
	)
	(segment
		(start 351.450148 -223.745552)
		(end 351.451672 -223.74479)
		(width 0.1143)
		(layer "In13.Cu")
		(net "GMI_CPU0_G0_CPU1_G2_TX_DN<8>")
	)
	(segment
		(start 351.448116 -229.58171)
		(end 351.448116 -229.581202)
		(width 0.1143)
		(layer "In13.Cu")
		(net "GMI_CPU0_G0_CPU1_G2_TX_DN<8>")
	)
	(segment
		(start 351.670112 -221.303088)
		(end 351.670112 -221.145862)
		(width 0.1143)
		(layer "In13.Cu")
		(net "GMI_CPU0_G0_CPU1_G2_TX_DN<8>")
	)
	(segment
		(start 351.400364 -228.63556)
		(end 351.409 -228.629464)
		(width 0.1143)
		(layer "In13.Cu")
		(net "GMI_CPU0_G0_CPU1_G2_TX_DN<8>")
	)
	(segment
		(start 351.445322 -225.368612)
		(end 351.448116 -225.366834)
		(width 0.1143)
		(layer "In13.Cu")
		(net "GMI_CPU0_G0_CPU1_G2_TX_DN<8>")
	)
	(segment
		(start 153.021284 -190.338964)
		(end 153.021284 -190.339218)
		(width 0.14224)
		(layer "In13.Cu")
		(net "GMI_CPU0_G0_CPU1_G2_TX_DN<8>")
	)
	(segment
		(start 351.448878 -235.086144)
		(end 351.450148 -235.085382)
		(width 0.1143)
		(layer "In13.Cu")
		(net "GMI_CPU0_G0_CPU1_G2_TX_DN<8>")
	)
	(segment
		(start 351.452434 -225.364294)
		(end 351.45345 -225.363786)
		(width 0.1143)
		(layer "In13.Cu")
		(net "GMI_CPU0_G0_CPU1_G2_TX_DN<8>")
	)
	(segment
		(start 120.042432 -237.684818)
		(end 120.04167 -237.685326)
		(width 0.1143)
		(layer "In13.Cu")
		(net "GMI_CPU0_G0_CPU1_G2_TX_DN<8>")
	)
	(segment
		(start 351.392236 -238.361474)
		(end 351.408492 -238.349536)
		(width 0.1143)
		(layer "In13.Cu")
		(net "GMI_CPU0_G0_CPU1_G2_TX_DN<8>")
	)
	(segment
		(start 351.455228 -236.065568)
		(end 351.454212 -236.06506)
		(width 0.1143)
		(layer "In13.Cu")
		(net "GMI_CPU0_G0_CPU1_G2_TX_DN<8>")
	)
	(segment
		(start 149.862286 -192.929256)
		(end 149.53234 -193.199766)
		(width 0.14224)
		(layer "In13.Cu")
		(net "GMI_CPU0_G0_CPU1_G2_TX_DN<8>")
	)
	(segment
		(start 351.450148 -232.82275)
		(end 351.448878 -232.821988)
		(width 0.1143)
		(layer "In13.Cu")
		(net "GMI_CPU0_G0_CPU1_G2_TX_DN<8>")
	)
	(segment
		(start 351.45345 -237.684564)
		(end 351.452434 -237.684056)
		(width 0.1143)
		(layer "In13.Cu")
		(net "GMI_CPU0_G0_CPU1_G2_TX_DN<8>")
	)
	(segment
		(start 351.393252 -231.88041)
		(end 351.408746 -231.869488)
		(width 0.1143)
		(layer "In13.Cu")
		(net "GMI_CPU0_G0_CPU1_G2_TX_DN<8>")
	)
	(segment
		(start 351.479866 -227.979986)
		(end 351.453958 -227.965)
		(width 0.1143)
		(layer "In13.Cu")
		(net "GMI_CPU0_G0_CPU1_G2_TX_DN<8>")
	)
	(segment
		(start 155.226512 -188.530738)
		(end 154.896566 -188.801248)
		(width 0.14224)
		(layer "In13.Cu")
		(net "GMI_CPU0_G0_CPU1_G2_TX_DN<8>")
	)
	(segment
		(start 120.015762 -232.840276)
		(end 119.99468 -232.85704)
		(width 0.1143)
		(layer "In13.Cu")
		(net "GMI_CPU0_G0_CPU1_G2_TX_DN<8>")
	)
	(segment
		(start 351.448116 -237.681516)
		(end 351.410016 -237.659672)
		(width 0.1143)
		(layer "In13.Cu")
		(net "GMI_CPU0_G0_CPU1_G2_TX_DN<8>")
	)
	(segment
		(start 120.045734 -236.063028)
		(end 120.04421 -236.06379)
		(width 0.1143)
		(layer "In13.Cu")
		(net "GMI_CPU0_G0_CPU1_G2_TX_DN<8>")
	)
	(segment
		(start 120.042432 -232.824782)
		(end 120.04167 -232.82529)
		(width 0.1143)
		(layer "In13.Cu")
		(net "GMI_CPU0_G0_CPU1_G2_TX_DN<8>")
	)
	(segment
		(start 122.566176 -214.768176)
		(end 119.87149 -219.380816)
		(width 0.14224)
		(layer "In13.Cu")
		(net "GMI_CPU0_G0_CPU1_G2_TX_DN<8>")
	)
	(segment
		(start 120.042686 -227.964746)
		(end 120.041924 -227.965254)
		(width 0.1143)
		(layer "In13.Cu")
		(net "GMI_CPU0_G0_CPU1_G2_TX_DN<8>")
	)
	(segment
		(start 120.04421 -236.06379)
		(end 120.043448 -236.064298)
		(width 0.1143)
		(layer "In13.Cu")
		(net "GMI_CPU0_G0_CPU1_G2_TX_DN<8>")
	)
	(segment
		(start 351.450402 -227.962968)
		(end 351.44964 -227.96246)
		(width 0.1143)
		(layer "In13.Cu")
		(net "GMI_CPU0_G0_CPU1_G2_TX_DN<8>")
	)
	(segment
		(start 120.04421 -232.823766)
		(end 120.043448 -232.824274)
		(width 0.1143)
		(layer "In13.Cu")
		(net "GMI_CPU0_G0_CPU1_G2_TX_DN<8>")
	)
	(segment
		(start 120.05056 -226.988878)
		(end 120.086628 -227.009706)
		(width 0.1143)
		(layer "In13.Cu")
		(net "GMI_CPU0_G0_CPU1_G2_TX_DN<8>")
	)
	(segment
		(start 351.448116 -231.201722)
		(end 351.448116 -231.201468)
		(width 0.1143)
		(layer "In13.Cu")
		(net "GMI_CPU0_G0_CPU1_G2_TX_DN<8>")
	)
	(segment
		(start 120.086628 -225.389694)
		(end 120.10517 -225.402902)
		(width 0.1143)
		(layer "In13.Cu")
		(net "GMI_CPU0_G0_CPU1_G2_TX_DN<8>")
	)
	(segment
		(start 351.451672 -233.464608)
		(end 351.452434 -233.4641)
		(width 0.1143)
		(layer "In13.Cu")
		(net "GMI_CPU0_G0_CPU1_G2_TX_DN<8>")
	)
	(segment
		(start 120.016016 -238.308642)
		(end 120.047004 -238.326422)
		(width 0.1143)
		(layer "In13.Cu")
		(net "GMI_CPU0_G0_CPU1_G2_TX_DN<8>")
	)
	(segment
		(start 120.016016 -226.968812)
		(end 120.047004 -226.986592)
		(width 0.1143)
		(layer "In13.Cu")
		(net "GMI_CPU0_G0_CPU1_G2_TX_DN<8>")
	)
	(segment
		(start 351.45345 -236.703616)
		(end 351.479866 -236.688376)
		(width 0.1143)
		(layer "In13.Cu")
		(net "GMI_CPU0_G0_CPU1_G2_TX_DN<8>")
	)
	(segment
		(start 120.043448 -232.824274)
		(end 120.042432 -232.824782)
		(width 0.1143)
		(layer "In13.Cu")
		(net "GMI_CPU0_G0_CPU1_G2_TX_DN<8>")
	)
	(segment
		(start 155.749752 -188.279024)
		(end 155.419552 -188.549788)
		(width 0.14224)
		(layer "In13.Cu")
		(net "GMI_CPU0_G0_CPU1_G2_TX_DN<8>")
	)
	(segment
		(start 149.53234 -193.199766)
		(end 149.51329 -193.392806)
		(width 0.14224)
		(layer "In13.Cu")
		(net "GMI_CPU0_G0_CPU1_G2_TX_DN<8>")
	)
	(segment
		(start 166.433246 -181.798214)
		(end 161.119312 -183.698388)
		(width 0.14224)
		(layer "In13.Cu")
		(net "GMI_CPU0_G0_CPU1_G2_TX_DN<8>")
	)
	(segment
		(start 351.45345 -236.064552)
		(end 351.452434 -236.064044)
		(width 0.1143)
		(layer "In13.Cu")
		(net "GMI_CPU0_G0_CPU1_G2_TX_DN<8>")
	)
	(segment
		(start 120.047766 -234.441746)
		(end 120.047004 -234.442254)
		(width 0.1143)
		(layer "In13.Cu")
		(net "GMI_CPU0_G0_CPU1_G2_TX_DN<8>")
	)
	(segment
		(start 120.08739 -238.34979)
		(end 120.103646 -238.361728)
		(width 0.1143)
		(layer "In13.Cu")
		(net "GMI_CPU0_G0_CPU1_G2_TX_DN<8>")
	)
	(segment
		(start 351.480882 -229.60076)
		(end 351.448878 -229.582218)
		(width 0.1143)
		(layer "In13.Cu")
		(net "GMI_CPU0_G0_CPU1_G2_TX_DN<8>")
	)
	(segment
		(start 120.07977 -230.245412)
		(end 120.081294 -230.246428)
		(width 0.1143)
		(layer "In13.Cu")
		(net "GMI_CPU0_G0_CPU1_G2_TX_DN<8>")
	)
	(segment
		(start 152.129998 -191.247522)
		(end 151.799798 -191.518286)
		(width 0.14224)
		(layer "In13.Cu")
		(net "GMI_CPU0_G0_CPU1_G2_TX_DN<8>")
	)
	(segment
		(start 120.047004 -228.606604)
		(end 120.047766 -228.607112)
		(width 0.1143)
		(layer "In13.Cu")
		(net "GMI_CPU0_G0_CPU1_G2_TX_DN<8>")
	)
	(segment
		(start 154.354276 -189.246002)
		(end 153.89352 -189.6237)
		(width 0.14224)
		(layer "In13.Cu")
		(net "GMI_CPU0_G0_CPU1_G2_TX_DN<8>")
	)
	(segment
		(start 351.40011 -222.142812)
		(end 351.47885 -222.096076)
		(width 0.1143)
		(layer "In13.Cu")
		(net "GMI_CPU0_G0_CPU1_G2_TX_DN<8>")
	)
	(segment
		(start 351.390712 -225.402648)
		(end 351.409254 -225.38944)
		(width 0.1143)
		(layer "In13.Cu")
		(net "GMI_CPU0_G0_CPU1_G2_TX_DN<8>")
	)
	(segment
		(start 351.450148 -233.46537)
		(end 351.451672 -233.464608)
		(width 0.1143)
		(layer "In13.Cu")
		(net "GMI_CPU0_G0_CPU1_G2_TX_DN<8>")
	)
	(segment
		(start 351.448116 -231.201468)
		(end 351.445322 -231.199944)
		(width 0.1143)
		(layer "In13.Cu")
		(net "GMI_CPU0_G0_CPU1_G2_TX_DN<8>")
	)
	(segment
		(start 351.454212 -234.445048)
		(end 351.45345 -234.44454)
		(width 0.1143)
		(layer "In13.Cu")
		(net "GMI_CPU0_G0_CPU1_G2_TX_DN<8>")
	)
	(segment
		(start 351.450148 -225.365564)
		(end 351.451672 -225.364802)
		(width 0.1143)
		(layer "In13.Cu")
		(net "GMI_CPU0_G0_CPU1_G2_TX_DN<8>")
	)
	(segment
		(start 351.451672 -235.08462)
		(end 351.452434 -235.084112)
		(width 0.1143)
		(layer "In13.Cu")
		(net "GMI_CPU0_G0_CPU1_G2_TX_DN<8>")
	)
	(segment
		(start 351.451672 -237.683548)
		(end 351.450148 -237.682786)
		(width 0.1143)
		(layer "In13.Cu")
		(net "GMI_CPU0_G0_CPU1_G2_TX_DN<8>")
	)
	(segment
		(start 120.04548 -227.963222)
		(end 120.044464 -227.96373)
		(width 0.1143)
		(layer "In13.Cu")
		(net "GMI_CPU0_G0_CPU1_G2_TX_DN<8>")
	)
	(segment
		(start 351.452434 -237.684056)
		(end 351.451672 -237.683548)
		(width 0.1143)
		(layer "In13.Cu")
		(net "GMI_CPU0_G0_CPU1_G2_TX_DN<8>")
	)
	(segment
		(start 351.479866 -237.699804)
		(end 351.455228 -237.68558)
		(width 0.1143)
		(layer "In13.Cu")
		(net "GMI_CPU0_G0_CPU1_G2_TX_DN<8>")
	)
	(segment
		(start 120.047004 -232.822242)
		(end 120.045734 -232.823004)
		(width 0.1143)
		(layer "In13.Cu")
		(net "GMI_CPU0_G0_CPU1_G2_TX_DN<8>")
	)
	(segment
		(start 351.410016 -237.659672)
		(end 351.394522 -237.648496)
		(width 0.1143)
		(layer "In13.Cu")
		(net "GMI_CPU0_G0_CPU1_G2_TX_DN<8>")
	)
	(segment
		(start 120.04167 -237.685326)
		(end 120.040654 -237.685834)
		(width 0.1143)
		(layer "In13.Cu")
		(net "GMI_CPU0_G0_CPU1_G2_TX_DN<8>")
	)
	(segment
		(start 144.86001 -196.487796)
		(end 122.566176 -214.768176)
		(width 0.14224)
		(layer "In13.Cu")
		(net "GMI_CPU0_G0_CPU1_G2_TX_DN<8>")
	)
	(segment
		(start 351.451418 -226.343464)
		(end 351.450402 -226.342956)
		(width 0.1143)
		(layer "In13.Cu")
		(net "GMI_CPU0_G0_CPU1_G2_TX_DN<8>")
	)
	(segment
		(start 153.021284 -190.339218)
		(end 153.002234 -190.532258)
		(width 0.14224)
		(layer "In13.Cu")
		(net "GMI_CPU0_G0_CPU1_G2_TX_DN<8>")
	)
	(segment
		(start 351.481644 -232.841546)
		(end 351.479104 -232.839514)
		(width 0.1143)
		(layer "In13.Cu")
		(net "GMI_CPU0_G0_CPU1_G2_TX_DN<8>")
	)
	(segment
		(start 120.08739 -235.109766)
		(end 120.103646 -235.121704)
		(width 0.1143)
		(layer "In13.Cu")
		(net "GMI_CPU0_G0_CPU1_G2_TX_DN<8>")
	)
	(segment
		(start 120.043448 -237.68431)
		(end 120.042432 -237.684818)
		(width 0.1143)
		(layer "In13.Cu")
		(net "GMI_CPU0_G0_CPU1_G2_TX_DN<8>")
	)
	(segment
		(start 120.103646 -239.266984)
		(end 120.08739 -239.278922)
		(width 0.1143)
		(layer "In13.Cu")
		(net "GMI_CPU0_G0_CPU1_G2_TX_DN<8>")
	)
	(segment
		(start 351.452434 -235.084112)
		(end 351.45345 -235.083604)
		(width 0.1143)
		(layer "In13.Cu")
		(net "GMI_CPU0_G0_CPU1_G2_TX_DN<8>")
	)
	(segment
		(start 154.896566 -188.801248)
		(end 154.877516 -188.994288)
		(width 0.14224)
		(layer "In13.Cu")
		(net "GMI_CPU0_G0_CPU1_G2_TX_DN<8>")
	)
	(segment
		(start 120.047766 -226.9871)
		(end 120.05056 -226.988878)
		(width 0.1143)
		(layer "In13.Cu")
		(net "GMI_CPU0_G0_CPU1_G2_TX_DN<8>")
	)
	(segment
		(start 120.047766 -223.747076)
		(end 120.084088 -223.768158)
		(width 0.1143)
		(layer "In13.Cu")
		(net "GMI_CPU0_G0_CPU1_G2_TX_DN<8>")
	)
	(segment
		(start 351.45345 -228.60381)
		(end 351.479866 -228.58857)
		(width 0.1143)
		(layer "In13.Cu")
		(net "GMI_CPU0_G0_CPU1_G2_TX_DN<8>")
	)
	(segment
		(start 120.045734 -237.68304)
		(end 120.04421 -237.683802)
		(width 0.1143)
		(layer "In13.Cu")
		(net "GMI_CPU0_G0_CPU1_G2_TX_DN<8>")
	)
	(segment
		(start 351.452434 -232.82402)
		(end 351.451672 -232.823512)
		(width 0.1143)
		(layer "In13.Cu")
		(net "GMI_CPU0_G0_CPU1_G2_TX_DN<8>")
	)
	(segment
		(start 351.452434 -236.704124)
		(end 351.45345 -236.703616)
		(width 0.1143)
		(layer "In13.Cu")
		(net "GMI_CPU0_G0_CPU1_G2_TX_DN<8>")
	)
	(segment
		(start 351.44964 -227.96246)
		(end 351.409254 -227.939092)
		(width 0.1143)
		(layer "In13.Cu")
		(net "GMI_CPU0_G0_CPU1_G2_TX_DN<8>")
	)
	(segment
		(start 149.18309 -193.66357)
		(end 148.99005 -193.644266)
		(width 0.14224)
		(layer "In13.Cu")
		(net "GMI_CPU0_G0_CPU1_G2_TX_DN<8>")
	)
	(segment
		(start 351.448878 -223.746314)
		(end 351.450148 -223.745552)
		(width 0.1143)
		(layer "In13.Cu")
		(net "GMI_CPU0_G0_CPU1_G2_TX_DN<8>")
	)
	(segment
		(start 120.047004 -236.062266)
		(end 120.045734 -236.063028)
		(width 0.1143)
		(layer "In13.Cu")
		(net "GMI_CPU0_G0_CPU1_G2_TX_DN<8>")
	)
	(segment
		(start 120.04421 -237.683802)
		(end 120.043448 -237.68431)
		(width 0.1143)
		(layer "In13.Cu")
		(net "GMI_CPU0_G0_CPU1_G2_TX_DN<8>")
	)
	(segment
		(start 120.047004 -225.36658)
		(end 120.047766 -225.367088)
		(width 0.1143)
		(layer "In13.Cu")
		(net "GMI_CPU0_G0_CPU1_G2_TX_DN<8>")
	)
	(segment
		(start 351.445322 -228.608636)
		(end 351.448116 -228.606858)
		(width 0.1143)
		(layer "In13.Cu")
		(net "GMI_CPU0_G0_CPU1_G2_TX_DN<8>")
	)
	(segment
		(start 351.451418 -227.963476)
		(end 351.450402 -227.962968)
		(width 0.1143)
		(layer "In13.Cu")
		(net "GMI_CPU0_G0_CPU1_G2_TX_DN<8>")
	)
	(segment
		(start 351.45345 -223.743774)
		(end 351.479866 -223.728534)
		(width 0.1143)
		(layer "In13.Cu")
		(net "GMI_CPU0_G0_CPU1_G2_TX_DN<8>")
	)
	(segment
		(start 351.448116 -238.326676)
		(end 351.448878 -238.326168)
		(width 0.1143)
		(layer "In13.Cu")
		(net "GMI_CPU0_G0_CPU1_G2_TX_DN<8>")
	)
	(segment
		(start 351.451672 -236.704632)
		(end 351.452434 -236.704124)
		(width 0.1143)
		(layer "In13.Cu")
		(net "GMI_CPU0_G0_CPU1_G2_TX_DN<8>")
	)
	(segment
		(start 120.040654 -223.10598)
		(end 120.016016 -223.120204)
		(width 0.1143)
		(layer "In13.Cu")
		(net "GMI_CPU0_G0_CPU1_G2_TX_DN<8>")
	)
	(segment
		(start 120.086628 -227.939346)
		(end 120.046242 -227.962714)
		(width 0.1143)
		(layer "In13.Cu")
		(net "GMI_CPU0_G0_CPU1_G2_TX_DN<8>")
	)
	(segment
		(start 351.450148 -223.102932)
		(end 351.448878 -223.10217)
		(width 0.1143)
		(layer "In13.Cu")
		(net "GMI_CPU0_G0_CPU1_G2_TX_DN<8>")
	)
	(segment
		(start 351.451672 -223.103694)
		(end 351.450148 -223.102932)
		(width 0.1143)
		(layer "In13.Cu")
		(net "GMI_CPU0_G0_CPU1_G2_TX_DN<8>")
	)
	(segment
		(start 351.44964 -226.342448)
		(end 351.409254 -226.31908)
		(width 0.1143)
		(layer "In13.Cu")
		(net "GMI_CPU0_G0_CPU1_G2_TX_DN<8>")
	)
	(segment
		(start 119.82577 -221.146116)
		(end 119.82577 -221.303342)
		(width 0.1143)
		(layer "In13.Cu")
		(net "GMI_CPU0_G0_CPU1_G2_TX_DN<8>")
	)
	(segment
		(start 351.409254 -227.009452)
		(end 351.445322 -226.988624)
		(width 0.1143)
		(layer "In13.Cu")
		(net "GMI_CPU0_G0_CPU1_G2_TX_DN<8>")
	)
	(segment
		(start 120.039638 -234.446318)
		(end 120.015762 -234.460288)
		(width 0.1143)
		(layer "In13.Cu")
		(net "GMI_CPU0_G0_CPU1_G2_TX_DN<8>")
	)
	(segment
		(start 351.448878 -226.986338)
		(end 351.450148 -226.985576)
		(width 0.1143)
		(layer "In13.Cu")
		(net "GMI_CPU0_G0_CPU1_G2_TX_DN<8>")
	)
	(segment
		(start 351.452434 -223.744282)
		(end 351.45345 -223.743774)
		(width 0.1143)
		(layer "In13.Cu")
		(net "GMI_CPU0_G0_CPU1_G2_TX_DN<8>")
	)
	(segment
		(start 351.624392 -219.263468)
		(end 349.006414 -214.853774)
		(width 0.14224)
		(layer "In13.Cu")
		(net "GMI_CPU0_G0_CPU1_G2_TX_DN<8>")
	)
	(segment
		(start 120.051322 -230.228902)
		(end 120.07977 -230.245412)
		(width 0.1143)
		(layer "In13.Cu")
		(net "GMI_CPU0_G0_CPU1_G2_TX_DN<8>")
	)
	(segment
		(start 351.479866 -224.739962)
		(end 351.448116 -224.721674)
		(width 0.1143)
		(layer "In13.Cu")
		(net "GMI_CPU0_G0_CPU1_G2_TX_DN<8>")
	)
	(segment
		(start 351.479104 -232.839514)
		(end 351.47885 -232.839514)
		(width 0.1143)
		(layer "In13.Cu")
		(net "GMI_CPU0_G0_CPU1_G2_TX_DN<8>")
	)
	(segment
		(start 120.050814 -239.300004)
		(end 120.048782 -239.301274)
		(width 0.1143)
		(layer "In13.Cu")
		(net "GMI_CPU0_G0_CPU1_G2_TX_DN<8>")
	)
	(segment
		(start 351.448116 -229.581202)
		(end 351.407222 -229.557326)
		(width 0.1143)
		(layer "In13.Cu")
		(net "GMI_CPU0_G0_CPU1_G2_TX_DN<8>")
	)
	(segment
		(start 351.452434 -223.104202)
		(end 351.451672 -223.103694)
		(width 0.1143)
		(layer "In13.Cu")
		(net "GMI_CPU0_G0_CPU1_G2_TX_DN<8>")
	)
	(segment
		(start 351.479866 -226.359974)
		(end 351.455482 -226.34575)
		(width 0.1143)
		(layer "In13.Cu")
		(net "GMI_CPU0_G0_CPU1_G2_TX_DN<8>")
	)
	(segment
		(start 351.456244 -232.826052)
		(end 351.454212 -232.825036)
		(width 0.1143)
		(layer "In13.Cu")
		(net "GMI_CPU0_G0_CPU1_G2_TX_DN<8>")
	)
	(segment
		(start 351.45345 -233.463592)
		(end 351.478342 -233.449114)
		(width 0.1143)
		(layer "In13.Cu")
		(net "GMI_CPU0_G0_CPU1_G2_TX_DN<8>")
	)
	(segment
		(start 120.047766 -236.706918)
		(end 120.050306 -236.708696)
		(width 0.1143)
		(layer "In13.Cu")
		(net "GMI_CPU0_G0_CPU1_G2_TX_DN<8>")
	)
	(segment
		(start 351.448116 -235.086652)
		(end 351.448878 -235.086144)
		(width 0.1143)
		(layer "In13.Cu")
		(net "GMI_CPU0_G0_CPU1_G2_TX_DN<8>")
	)
	(segment
		(start 120.047004 -223.102424)
		(end 120.045734 -223.103186)
		(width 0.1143)
		(layer "In13.Cu")
		(net "GMI_CPU0_G0_CPU1_G2_TX_DN<8>")
	)
	(segment
		(start 119.994934 -233.431842)
		(end 120.016016 -233.448606)
		(width 0.1143)
		(layer "In13.Cu")
		(net "GMI_CPU0_G0_CPU1_G2_TX_DN<8>")
	)
	(segment
		(start 120.016016 -225.3488)
		(end 120.047004 -225.36658)
		(width 0.1143)
		(layer "In13.Cu")
		(net "GMI_CPU0_G0_CPU1_G2_TX_DN<8>")
	)
	(segment
		(start 120.040654 -236.065822)
		(end 120.016016 -236.080046)
		(width 0.1143)
		(layer "In13.Cu")
		(net "GMI_CPU0_G0_CPU1_G2_TX_DN<8>")
	)
	(segment
		(start 120.08739 -239.278922)
		(end 120.0531 -239.298734)
		(width 0.1143)
		(layer "In13.Cu")
		(net "GMI_CPU0_G0_CPU1_G2_TX_DN<8>")
	)
	(segment
		(start 120.085866 -237.659926)
		(end 120.047766 -237.68177)
		(width 0.1143)
		(layer "In13.Cu")
		(net "GMI_CPU0_G0_CPU1_G2_TX_DN<8>")
	)
	(segment
		(start 351.416112 -230.245158)
		(end 351.44456 -230.228648)
		(width 0.1143)
		(layer "In13.Cu")
		(net "GMI_CPU0_G0_CPU1_G2_TX_DN<8>")
	)
	(segment
		(start 151.276812 -191.769492)
		(end 151.257762 -191.962532)
		(width 0.14224)
		(layer "In13.Cu")
		(net "GMI_CPU0_G0_CPU1_G2_TX_DN<8>")
	)
	(segment
		(start 351.408492 -233.4895)
		(end 351.445576 -233.468418)
		(width 0.1143)
		(layer "In13.Cu")
		(net "GMI_CPU0_G0_CPU1_G2_TX_DN<8>")
	)
	(segment
		(start 155.419552 -188.549788)
		(end 155.226512 -188.530738)
		(width 0.14224)
		(layer "In13.Cu")
		(net "GMI_CPU0_G0_CPU1_G2_TX_DN<8>")
	)
	(segment
		(start 351.450148 -237.682786)
		(end 351.448878 -237.682024)
		(width 0.1143)
		(layer "In13.Cu")
		(net "GMI_CPU0_G0_CPU1_G2_TX_DN<8>")
	)
	(segment
		(start 120.047766 -231.201722)
		(end 120.047766 -231.201976)
		(width 0.1143)
		(layer "In13.Cu")
		(net "GMI_CPU0_G0_CPU1_G2_TX_DN<8>")
	)
	(segment
		(start 120.047004 -238.326422)
		(end 120.047766 -238.32693)
		(width 0.1143)
		(layer "In13.Cu")
		(net "GMI_CPU0_G0_CPU1_G2_TX_DN<8>")
	)
	(segment
		(start 351.454212 -236.06506)
		(end 351.45345 -236.064552)
		(width 0.1143)
		(layer "In13.Cu")
		(net "GMI_CPU0_G0_CPU1_G2_TX_DN<8>")
	)
	(segment
		(start 120.08739 -234.418886)
		(end 120.047766 -234.441746)
		(width 0.1143)
		(layer "In13.Cu")
		(net "GMI_CPU0_G0_CPU1_G2_TX_DN<8>")
	)
	(arc
		(start 351.47885 -222.096076)
		(mid 351.594276 -221.962558)
		(end 351.635822 -221.791022)
		(width 0.1143)
		(layer "In13.Cu")
		(net "GMI_CPU0_G0_CPU1_G2_TX_DN<8>")
	)
	(arc
		(start 120.10136 -236.739938)
		(mid 120.334872 -237.194344)
		(end 120.10136 -237.64875)
		(width 0.1143)
		(layer "In13.Cu")
		(net "GMI_CPU0_G0_CPU1_G2_TX_DN<8>")
	)
	(arc
		(start 119.99468 -232.85704)
		(mid 119.856723 -233.144493)
		(end 119.994934 -233.431842)
		(width 0.1143)
		(layer "In13.Cu")
		(net "GMI_CPU0_G0_CPU1_G2_TX_DN<8>")
	)
	(arc
		(start 120.095772 -222.143066)
		(mid 120.338117 -222.62982)
		(end 120.057926 -223.09582)
		(width 0.1143)
		(layer "In13.Cu")
		(net "GMI_CPU0_G0_CPU1_G2_TX_DN<8>")
	)
	(arc
		(start 120.32996 -229.094538)
		(mid 120.266014 -229.355607)
		(end 120.08866 -229.55758)
		(width 0.1143)
		(layer "In13.Cu")
		(net "GMI_CPU0_G0_CPU1_G2_TX_DN<8>")
	)
	(arc
		(start 120.10263 -231.880664)
		(mid 120.334888 -232.334308)
		(end 120.10263 -232.787952)
		(width 0.1143)
		(layer "In13.Cu")
		(net "GMI_CPU0_G0_CPU1_G2_TX_DN<8>")
	)
	(arc
		(start 351.617534 -239.491012)
		(mid 351.586543 -239.41415)
		(end 351.529142 -239.35436)
		(width 0.1143)
		(layer "In13.Cu")
		(net "GMI_CPU0_G0_CPU1_G2_TX_DN<8>")
	)
	(arc
		(start 120.084088 -223.768158)
		(mid 120.091237 -223.773058)
		(end 120.098312 -223.778064)
		(width 0.1143)
		(layer "In13.Cu")
		(net "GMI_CPU0_G0_CPU1_G2_TX_DN<8>")
	)
	(arc
		(start 351.479866 -228.58857)
		(mid 351.635794 -228.284278)
		(end 351.479866 -227.979986)
		(width 0.1143)
		(layer "In13.Cu")
		(net "GMI_CPU0_G0_CPU1_G2_TX_DN<8>")
	)
	(arc
		(start 351.411794 -224.700592)
		(mid 351.404644 -224.695694)
		(end 351.39757 -224.690686)
		(width 0.1143)
		(layer "In13.Cu")
		(net "GMI_CPU0_G0_CPU1_G2_TX_DN<8>")
	)
	(arc
		(start 351.482914 -233.445812)
		(mid 351.627982 -233.144239)
		(end 351.483168 -232.842562)
		(width 0.1143)
		(layer "In13.Cu")
		(net "GMI_CPU0_G0_CPU1_G2_TX_DN<8>")
	)
	(arc
		(start 351.400364 -230.255826)
		(mid 351.40744 -230.250947)
		(end 351.414588 -230.246174)
		(width 0.1143)
		(layer "In13.Cu")
		(net "GMI_CPU0_G0_CPU1_G2_TX_DN<8>")
	)
	(arc
		(start 120.098312 -224.69094)
		(mid 120.091238 -224.695947)
		(end 120.084088 -224.700846)
		(width 0.1143)
		(layer "In13.Cu")
		(net "GMI_CPU0_G0_CPU1_G2_TX_DN<8>")
	)
	(arc
		(start 351.479866 -225.348546)
		(mid 351.635794 -225.044254)
		(end 351.479866 -224.739962)
		(width 0.1143)
		(layer "In13.Cu")
		(net "GMI_CPU0_G0_CPU1_G2_TX_DN<8>")
	)
	(arc
		(start 120.095518 -230.25608)
		(mid 120.267536 -230.456882)
		(end 120.32996 -230.713788)
		(width 0.1143)
		(layer "In13.Cu")
		(net "GMI_CPU0_G0_CPU1_G2_TX_DN<8>")
	)
	(arc
		(start 351.39757 -224.690686)
		(mid 351.170086 -224.234248)
		(end 351.39757 -223.77781)
		(width 0.1143)
		(layer "In13.Cu")
		(net "GMI_CPU0_G0_CPU1_G2_TX_DN<8>")
	)
	(arc
		(start 120.016016 -223.120204)
		(mid 119.860088 -223.424496)
		(end 120.016016 -223.728788)
		(width 0.1143)
		(layer "In13.Cu")
		(net "GMI_CPU0_G0_CPU1_G2_TX_DN<8>")
	)
	(arc
		(start 351.479866 -226.968558)
		(mid 351.635794 -226.664266)
		(end 351.479866 -226.359974)
		(width 0.1143)
		(layer "In13.Cu")
		(net "GMI_CPU0_G0_CPU1_G2_TX_DN<8>")
	)
	(arc
		(start 120.095518 -228.635814)
		(mid 120.267963 -228.83666)
		(end 120.32996 -229.09403)
		(width 0.1143)
		(layer "In13.Cu")
		(net "GMI_CPU0_G0_CPU1_G2_TX_DN<8>")
	)
	(arc
		(start 351.407222 -229.557326)
		(mid 351.229857 -229.355359)
		(end 351.165922 -229.094284)
		(width 0.1143)
		(layer "In13.Cu")
		(net "GMI_CPU0_G0_CPU1_G2_TX_DN<8>")
	)
	(arc
		(start 120.103646 -233.501692)
		(mid 120.335396 -233.95432)
		(end 120.103646 -234.406948)
		(width 0.1143)
		(layer "In13.Cu")
		(net "GMI_CPU0_G0_CPU1_G2_TX_DN<8>")
	)
	(arc
		(start 119.96674 -239.354614)
		(mid 119.909304 -239.414381)
		(end 119.878348 -239.491266)
		(width 0.1143)
		(layer "In13.Cu")
		(net "GMI_CPU0_G0_CPU1_G2_TX_DN<8>")
	)
	(arc
		(start 351.479866 -231.82834)
		(mid 351.636003 -231.525215)
		(end 351.481644 -231.22128)
		(width 0.1143)
		(layer "In13.Cu")
		(net "GMI_CPU0_G0_CPU1_G2_TX_DN<8>")
	)
	(arc
		(start 351.437956 -223.095566)
		(mid 351.15776 -222.629566)
		(end 351.40011 -222.142812)
		(width 0.1143)
		(layer "In13.Cu")
		(net "GMI_CPU0_G0_CPU1_G2_TX_DN<8>")
	)
	(arc
		(start 120.103646 -235.121704)
		(mid 120.335396 -235.574332)
		(end 120.103646 -236.02696)
		(width 0.1143)
		(layer "In13.Cu")
		(net "GMI_CPU0_G0_CPU1_G2_TX_DN<8>")
	)
	(arc
		(start 120.014238 -231.221534)
		(mid 119.860072 -231.525469)
		(end 120.016016 -231.828594)
		(width 0.1143)
		(layer "In13.Cu")
		(net "GMI_CPU0_G0_CPU1_G2_TX_DN<8>")
	)
	(arc
		(start 351.393252 -232.787698)
		(mid 351.160994 -232.334054)
		(end 351.393252 -231.88041)
		(width 0.1143)
		(layer "In13.Cu")
		(net "GMI_CPU0_G0_CPU1_G2_TX_DN<8>")
	)
	(arc
		(start 120.016016 -227.98024)
		(mid 119.860088 -228.284532)
		(end 120.016016 -228.588824)
		(width 0.1143)
		(layer "In13.Cu")
		(net "GMI_CPU0_G0_CPU1_G2_TX_DN<8>")
	)
	(arc
		(start 351.39757 -223.77781)
		(mid 351.404643 -223.772801)
		(end 351.411794 -223.767904)
		(width 0.1143)
		(layer "In13.Cu")
		(net "GMI_CPU0_G0_CPU1_G2_TX_DN<8>")
	)
	(arc
		(start 120.081294 -230.246428)
		(mid 120.088443 -230.251199)
		(end 120.095518 -230.25608)
		(width 0.1143)
		(layer "In13.Cu")
		(net "GMI_CPU0_G0_CPU1_G2_TX_DN<8>")
	)
	(arc
		(start 351.381822 -227.919534)
		(mid 351.15341 -227.474272)
		(end 351.381822 -227.02901)
		(width 0.1143)
		(layer "In13.Cu")
		(net "GMI_CPU0_G0_CPU1_G2_TX_DN<8>")
	)
	(arc
		(start 120.016016 -236.080046)
		(mid 119.860088 -236.384338)
		(end 120.016016 -236.68863)
		(width 0.1143)
		(layer "In13.Cu")
		(net "GMI_CPU0_G0_CPU1_G2_TX_DN<8>")
	)
	(arc
		(start 120.10517 -225.402902)
		(mid 120.336835 -225.854514)
		(end 120.10517 -226.306126)
		(width 0.1143)
		(layer "In13.Cu")
		(net "GMI_CPU0_G0_CPU1_G2_TX_DN<8>")
	)
	(arc
		(start 120.32996 -230.713788)
		(mid 120.255721 -230.994585)
		(end 120.05056 -231.200198)
		(width 0.1143)
		(layer "In13.Cu")
		(net "GMI_CPU0_G0_CPU1_G2_TX_DN<8>")
	)
	(arc
		(start 351.392236 -236.026706)
		(mid 351.160486 -235.574078)
		(end 351.392236 -235.12145)
		(width 0.1143)
		(layer "In13.Cu")
		(net "GMI_CPU0_G0_CPU1_G2_TX_DN<8>")
	)
	(arc
		(start 119.99468 -234.477052)
		(mid 119.856723 -234.764505)
		(end 119.994934 -235.051854)
		(width 0.1143)
		(layer "In13.Cu")
		(net "GMI_CPU0_G0_CPU1_G2_TX_DN<8>")
	)
	(arc
		(start 351.479866 -236.688376)
		(mid 351.635794 -236.384084)
		(end 351.479866 -236.079792)
		(width 0.1143)
		(layer "In13.Cu")
		(net "GMI_CPU0_G0_CPU1_G2_TX_DN<8>")
	)
	(arc
		(start 119.859806 -229.90429)
		(mid 119.909333 -230.089322)
		(end 120.044464 -230.225092)
		(width 0.1143)
		(layer "In13.Cu")
		(net "GMI_CPU0_G0_CPU1_G2_TX_DN<8>")
	)
	(arc
		(start 120.016016 -237.700058)
		(mid 119.860088 -238.00435)
		(end 120.016016 -238.308642)
		(width 0.1143)
		(layer "In13.Cu")
		(net "GMI_CPU0_G0_CPU1_G2_TX_DN<8>")
	)
	(arc
		(start 351.479866 -223.728534)
		(mid 351.635794 -223.424242)
		(end 351.479866 -223.11995)
		(width 0.1143)
		(layer "In13.Cu")
		(net "GMI_CPU0_G0_CPU1_G2_TX_DN<8>")
	)
	(arc
		(start 120.11406 -227.029264)
		(mid 120.342472 -227.474526)
		(end 120.11406 -227.919788)
		(width 0.1143)
		(layer "In13.Cu")
		(net "GMI_CPU0_G0_CPU1_G2_TX_DN<8>")
	)
	(arc
		(start 351.394522 -237.648496)
		(mid 351.16101 -237.19409)
		(end 351.394522 -236.739684)
		(width 0.1143)
		(layer "In13.Cu")
		(net "GMI_CPU0_G0_CPU1_G2_TX_DN<8>")
	)
	(arc
		(start 120.103646 -238.361728)
		(mid 120.335396 -238.814356)
		(end 120.103646 -239.266984)
		(width 0.1143)
		(layer "In13.Cu")
		(net "GMI_CPU0_G0_CPU1_G2_TX_DN<8>")
	)
	(arc
		(start 120.014238 -229.601522)
		(mid 119.900666 -229.734368)
		(end 119.859806 -229.90429)
		(width 0.1143)
		(layer "In13.Cu")
		(net "GMI_CPU0_G0_CPU1_G2_TX_DN<8>")
	)
	(arc
		(start 351.479866 -238.308388)
		(mid 351.635794 -238.004096)
		(end 351.479866 -237.699804)
		(width 0.1143)
		(layer "In13.Cu")
		(net "GMI_CPU0_G0_CPU1_G2_TX_DN<8>")
	)
	(arc
		(start 351.392236 -239.26673)
		(mid 351.160486 -238.814102)
		(end 351.392236 -238.361474)
		(width 0.1143)
		(layer "In13.Cu")
		(net "GMI_CPU0_G0_CPU1_G2_TX_DN<8>")
	)
	(arc
		(start 351.478596 -235.068872)
		(mid 351.48025 -235.067734)
		(end 351.481898 -235.066586)
		(width 0.1143)
		(layer "In13.Cu")
		(net "GMI_CPU0_G0_CPU1_G2_TX_DN<8>")
	)
	(arc
		(start 351.392236 -234.406694)
		(mid 351.160486 -233.954066)
		(end 351.392236 -233.501438)
		(width 0.1143)
		(layer "In13.Cu")
		(net "GMI_CPU0_G0_CPU1_G2_TX_DN<8>")
	)
	(arc
		(start 351.451418 -230.224838)
		(mid 351.586585 -230.089088)
		(end 351.636076 -229.904036)
		(width 0.1143)
		(layer "In13.Cu")
		(net "GMI_CPU0_G0_CPU1_G2_TX_DN<8>")
	)
	(arc
		(start 351.165922 -230.713534)
		(mid 351.228451 -230.456682)
		(end 351.400364 -230.255826)
		(width 0.1143)
		(layer "In13.Cu")
		(net "GMI_CPU0_G0_CPU1_G2_TX_DN<8>")
	)
	(arc
		(start 120.016016 -226.360228)
		(mid 119.860088 -226.66452)
		(end 120.016016 -226.968812)
		(width 0.1143)
		(layer "In13.Cu")
		(net "GMI_CPU0_G0_CPU1_G2_TX_DN<8>")
	)
	(arc
		(start 120.098312 -223.778064)
		(mid 120.325796 -224.234502)
		(end 120.098312 -224.69094)
		(width 0.1143)
		(layer "In13.Cu")
		(net "GMI_CPU0_G0_CPU1_G2_TX_DN<8>")
	)
	(arc
		(start 351.501456 -235.051092)
		(mid 351.6395 -234.764251)
		(end 351.50171 -234.477306)
		(width 0.1143)
		(layer "In13.Cu")
		(net "GMI_CPU0_G0_CPU1_G2_TX_DN<8>")
	)
	(arc
		(start 351.165922 -229.093776)
		(mid 351.227872 -228.836382)
		(end 351.400364 -228.63556)
		(width 0.1143)
		(layer "In13.Cu")
		(net "GMI_CPU0_G0_CPU1_G2_TX_DN<8>")
	)
	(arc
		(start 351.390712 -226.305872)
		(mid 351.159047 -225.85426)
		(end 351.390712 -225.402648)
		(width 0.1143)
		(layer "In13.Cu")
		(net "GMI_CPU0_G0_CPU1_G2_TX_DN<8>")
	)
	(arc
		(start 119.86006 -221.791276)
		(mid 119.901605 -221.962812)
		(end 120.017032 -222.09633)
		(width 0.1143)
		(layer "In13.Cu")
		(net "GMI_CPU0_G0_CPU1_G2_TX_DN<8>")
	)
	(arc
		(start 120.016016 -224.740216)
		(mid 119.860088 -225.044508)
		(end 120.016016 -225.3488)
		(width 0.1143)
		(layer "In13.Cu")
		(net "GMI_CPU0_G0_CPU1_G2_TX_DN<8>")
	)
	(arc
		(start 351.636076 -229.904036)
		(mid 351.595176 -229.734135)
		(end 351.481644 -229.601268)
		(width 0.1143)
		(layer "In13.Cu")
		(net "GMI_CPU0_G0_CPU1_G2_TX_DN<8>")
	)
	(arc
		(start 351.445322 -231.199944)
		(mid 351.240105 -230.994363)
		(end 351.165922 -230.713534)
		(width 0.1143)
		(layer "In13.Cu")
		(net "GMI_CPU0_G0_CPU1_G2_TX_DN<8>")
	)
	(segment
		(start 119.767858 -243.130324)
		(end 120.23471 -242.864386)
		(width 0.12954)
		(layer "F.Cu")
		(net "GMI_CPU0_G0_CPU1_G2_TX_DN<7>")
	)
	(segment
		(start 351.728024 -243.13007)
		(end 351.261172 -242.864132)
		(width 0.12954)
		(layer "F.Cu")
		(net "GMI_CPU0_G0_CPU1_G2_TX_DN<7>")
	)
	(segment
		(start 352.36531 -230.240078)
		(end 352.360738 -230.242618)
		(width 0.1143)
		(layer "In13.Cu")
		(net "GMI_CPU0_G0_CPU1_G2_TX_DN<7>")
	)
	(segment
		(start 151.387302 -190.28791)
		(end 151.717248 -190.0174)
		(width 0.14224)
		(layer "In13.Cu")
		(net "GMI_CPU0_G0_CPU1_G2_TX_DN<7>")
	)
	(segment
		(start 155.318968 -187.063888)
		(end 155.318968 -187.063634)
		(width 0.14224)
		(layer "In13.Cu")
		(net "GMI_CPU0_G0_CPU1_G2_TX_DN<7>")
	)
	(segment
		(start 352.438462 -238.294926)
		(end 352.41992 -238.308388)
		(width 0.1143)
		(layer "In13.Cu")
		(net "GMI_CPU0_G0_CPU1_G2_TX_DN<7>")
	)
	(segment
		(start 118.92661 -219.131134)
		(end 121.87682 -214.089742)
		(width 0.14224)
		(layer "In13.Cu")
		(net "GMI_CPU0_G0_CPU1_G2_TX_DN<7>")
	)
	(segment
		(start 119.075962 -237.700058)
		(end 119.107712 -237.68177)
		(width 0.1143)
		(layer "In13.Cu")
		(net "GMI_CPU0_G0_CPU1_G2_TX_DN<7>")
	)
	(segment
		(start 119.107712 -237.68177)
		(end 119.146828 -237.65891)
		(width 0.1143)
		(layer "In13.Cu")
		(net "GMI_CPU0_G0_CPU1_G2_TX_DN<7>")
	)
	(segment
		(start 352.38817 -226.341686)
		(end 352.41992 -226.359974)
		(width 0.1143)
		(layer "In13.Cu")
		(net "GMI_CPU0_G0_CPU1_G2_TX_DN<7>")
	)
	(segment
		(start 352.41992 -236.688376)
		(end 352.349054 -236.729524)
		(width 0.1143)
		(layer "In13.Cu")
		(net "GMI_CPU0_G0_CPU1_G2_TX_DN<7>")
	)
	(segment
		(start 154.652726 -187.777628)
		(end 154.977084 -187.51169)
		(width 0.14224)
		(layer "In13.Cu")
		(net "GMI_CPU0_G0_CPU1_G2_TX_DN<7>")
	)
	(segment
		(start 119.107204 -234.442)
		(end 119.12854 -234.429554)
		(width 0.1143)
		(layer "In13.Cu")
		(net "GMI_CPU0_G0_CPU1_G2_TX_DN<7>")
	)
	(segment
		(start 119.130572 -230.240332)
		(end 119.128286 -230.238808)
		(width 0.1143)
		(layer "In13.Cu")
		(net "GMI_CPU0_G0_CPU1_G2_TX_DN<7>")
	)
	(segment
		(start 119.074184 -229.601522)
		(end 119.146828 -229.559104)
		(width 0.1143)
		(layer "In13.Cu")
		(net "GMI_CPU0_G0_CPU1_G2_TX_DN<7>")
	)
	(segment
		(start 352.349054 -239.278668)
		(end 352.38817 -239.301528)
		(width 0.1143)
		(layer "In13.Cu")
		(net "GMI_CPU0_G0_CPU1_G2_TX_DN<7>")
	)
	(segment
		(start 119.075962 -240.940082)
		(end 119.146828 -240.898934)
		(width 0.1143)
		(layer "In13.Cu")
		(net "GMI_CPU0_G0_CPU1_G2_TX_DN<7>")
	)
	(segment
		(start 119.107712 -222.127064)
		(end 119.077232 -222.109284)
		(width 0.1143)
		(layer "In13.Cu")
		(net "GMI_CPU0_G0_CPU1_G2_TX_DN<7>")
	)
	(segment
		(start 352.38817 -241.5667)
		(end 352.349054 -241.58956)
		(width 0.1143)
		(layer "In13.Cu")
		(net "GMI_CPU0_G0_CPU1_G2_TX_DN<7>")
	)
	(segment
		(start 302.898048 -181.659276)
		(end 307.21808 -181.659276)
		(width 0.14224)
		(layer "In13.Cu")
		(net "GMI_CPU0_G0_CPU1_G2_TX_DN<7>")
	)
	(segment
		(start 152.240488 -189.765686)
		(end 152.259538 -189.572646)
		(width 0.14224)
		(layer "In13.Cu")
		(net "GMI_CPU0_G0_CPU1_G2_TX_DN<7>")
	)
	(segment
		(start 118.92661 -221.071948)
		(end 118.92661 -219.131134)
		(width 0.14224)
		(layer "In13.Cu")
		(net "GMI_CPU0_G0_CPU1_G2_TX_DN<7>")
	)
	(segment
		(start 119.107712 -226.9871)
		(end 119.075962 -226.968812)
		(width 0.1143)
		(layer "In13.Cu")
		(net "GMI_CPU0_G0_CPU1_G2_TX_DN<7>")
	)
	(segment
		(start 119.107712 -239.946942)
		(end 119.075962 -239.928654)
		(width 0.1143)
		(layer "In13.Cu")
		(net "GMI_CPU0_G0_CPU1_G2_TX_DN<7>")
	)
	(segment
		(start 352.396044 -235.08208)
		(end 352.383598 -235.089192)
		(width 0.1143)
		(layer "In13.Cu")
		(net "GMI_CPU0_G0_CPU1_G2_TX_DN<7>")
	)
	(segment
		(start 349.628206 -214.074756)
		(end 352.569272 -219.028518)
		(width 0.14224)
		(layer "In13.Cu")
		(net "GMI_CPU0_G0_CPU1_G2_TX_DN<7>")
	)
	(segment
		(start 121.87682 -214.089742)
		(end 144.357852 -195.656708)
		(width 0.14224)
		(layer "In13.Cu")
		(net "GMI_CPU0_G0_CPU1_G2_TX_DN<7>")
	)
	(segment
		(start 119.116348 -223.752156)
		(end 119.114824 -223.75114)
		(width 0.1143)
		(layer "In13.Cu")
		(net "GMI_CPU0_G0_CPU1_G2_TX_DN<7>")
	)
	(segment
		(start 119.075962 -236.68863)
		(end 119.063008 -236.679486)
		(width 0.1143)
		(layer "In13.Cu")
		(net "GMI_CPU0_G0_CPU1_G2_TX_DN<7>")
	)
	(segment
		(start 352.349054 -232.79862)
		(end 352.38817 -232.82148)
		(width 0.1143)
		(layer "In13.Cu")
		(net "GMI_CPU0_G0_CPU1_G2_TX_DN<7>")
	)
	(segment
		(start 118.926356 -229.951534)
		(end 118.92026 -229.895654)
		(width 0.1143)
		(layer "In13.Cu")
		(net "GMI_CPU0_G0_CPU1_G2_TX_DN<7>")
	)
	(segment
		(start 352.569272 -219.028518)
		(end 352.569272 -221.093538)
		(width 0.14224)
		(layer "In13.Cu")
		(net "GMI_CPU0_G0_CPU1_G2_TX_DN<7>")
	)
	(segment
		(start 352.349054 -231.178862)
		(end 352.354642 -231.181656)
		(width 0.1143)
		(layer "In13.Cu")
		(net "GMI_CPU0_G0_CPU1_G2_TX_DN<7>")
	)
	(segment
		(start 307.21808 -181.659276)
		(end 308.75859 -182.210456)
		(width 0.14224)
		(layer "In13.Cu")
		(net "GMI_CPU0_G0_CPU1_G2_TX_DN<7>")
	)
	(segment
		(start 151.368252 -190.48095)
		(end 151.387302 -190.28791)
		(width 0.14224)
		(layer "In13.Cu")
		(net "GMI_CPU0_G0_CPU1_G2_TX_DN<7>")
	)
	(segment
		(start 119.146828 -233.489754)
		(end 119.075962 -233.448606)
		(width 0.1143)
		(layer "In13.Cu")
		(net "GMI_CPU0_G0_CPU1_G2_TX_DN<7>")
	)
	(segment
		(start 152.654762 -189.248542)
		(end 152.837134 -189.266576)
		(width 0.14224)
		(layer "In13.Cu")
		(net "GMI_CPU0_G0_CPU1_G2_TX_DN<7>")
	)
	(segment
		(start 145.12163 -195.42506)
		(end 149.10054 -192.162938)
		(width 0.14224)
		(layer "In13.Cu")
		(net "GMI_CPU0_G0_CPU1_G2_TX_DN<7>")
	)
	(segment
		(start 352.367088 -223.08947)
		(end 352.367342 -223.08947)
		(width 0.1143)
		(layer "In13.Cu")
		(net "GMI_CPU0_G0_CPU1_G2_TX_DN<7>")
	)
	(segment
		(start 119.135144 -230.242872)
		(end 119.130572 -230.240332)
		(width 0.1143)
		(layer "In13.Cu")
		(net "GMI_CPU0_G0_CPU1_G2_TX_DN<7>")
	)
	(segment
		(start 352.410014 -228.594412)
		(end 352.409506 -228.594412)
		(width 0.1143)
		(layer "In13.Cu")
		(net "GMI_CPU0_G0_CPU1_G2_TX_DN<7>")
	)
	(segment
		(start 352.385376 -229.579932)
		(end 352.421444 -229.601014)
		(width 0.1143)
		(layer "In13.Cu")
		(net "GMI_CPU0_G0_CPU1_G2_TX_DN<7>")
	)
	(segment
		(start 155.843732 -186.633358)
		(end 160.294828 -182.983632)
		(width 0.14224)
		(layer "In13.Cu")
		(net "GMI_CPU0_G0_CPU1_G2_TX_DN<7>")
	)
	(segment
		(start 119.086122 -227.974398)
		(end 119.086376 -227.974398)
		(width 0.1143)
		(layer "In13.Cu")
		(net "GMI_CPU0_G0_CPU1_G2_TX_DN<7>")
	)
	(segment
		(start 149.62378 -191.911478)
		(end 149.64283 -191.718438)
		(width 0.14224)
		(layer "In13.Cu")
		(net "GMI_CPU0_G0_CPU1_G2_TX_DN<7>")
	)
	(segment
		(start 119.107204 -223.10217)
		(end 119.12854 -223.089724)
		(width 0.1143)
		(layer "In13.Cu")
		(net "GMI_CPU0_G0_CPU1_G2_TX_DN<7>")
	)
	(segment
		(start 151.038052 -190.751714)
		(end 151.368252 -190.48095)
		(width 0.14224)
		(layer "In13.Cu")
		(net "GMI_CPU0_G0_CPU1_G2_TX_DN<7>")
	)
	(segment
		(start 352.41992 -240.939828)
		(end 352.439732 -240.954052)
		(width 0.1143)
		(layer "In13.Cu")
		(net "GMI_CPU0_G0_CPU1_G2_TX_DN<7>")
	)
	(segment
		(start 352.569272 -221.100142)
		(end 352.614992 -221.145862)
		(width 0.1143)
		(layer "In13.Cu")
		(net "GMI_CPU0_G0_CPU1_G2_TX_DN<7>")
	)
	(segment
		(start 352.349054 -236.038644)
		(end 352.38817 -236.061504)
		(width 0.1143)
		(layer "In13.Cu")
		(net "GMI_CPU0_G0_CPU1_G2_TX_DN<7>")
	)
	(segment
		(start 352.439732 -241.534188)
		(end 352.41992 -241.548412)
		(width 0.1143)
		(layer "In13.Cu")
		(net "GMI_CPU0_G0_CPU1_G2_TX_DN<7>")
	)
	(segment
		(start 154.470354 -187.759594)
		(end 154.652726 -187.777628)
		(width 0.14224)
		(layer "In13.Cu")
		(net "GMI_CPU0_G0_CPU1_G2_TX_DN<7>")
	)
	(segment
		(start 352.41992 -239.9284)
		(end 352.38817 -239.946688)
		(width 0.1143)
		(layer "In13.Cu")
		(net "GMI_CPU0_G0_CPU1_G2_TX_DN<7>")
	)
	(segment
		(start 153.179526 -188.818266)
		(end 153.621994 -188.455554)
		(width 0.14224)
		(layer "In13.Cu")
		(net "GMI_CPU0_G0_CPU1_G2_TX_DN<7>")
	)
	(segment
		(start 151.910288 -190.03645)
		(end 152.240488 -189.765686)
		(width 0.14224)
		(layer "In13.Cu")
		(net "GMI_CPU0_G0_CPU1_G2_TX_DN<7>")
	)
	(segment
		(start 352.389694 -231.845866)
		(end 352.388932 -231.846374)
		(width 0.1143)
		(layer "In13.Cu")
		(net "GMI_CPU0_G0_CPU1_G2_TX_DN<7>")
	)
	(segment
		(start 119.126254 -230.237792)
		(end 119.125492 -230.237284)
		(width 0.1143)
		(layer "In13.Cu")
		(net "GMI_CPU0_G0_CPU1_G2_TX_DN<7>")
	)
	(segment
		(start 150.515066 -191.003174)
		(end 150.845012 -190.732664)
		(width 0.14224)
		(layer "In13.Cu")
		(net "GMI_CPU0_G0_CPU1_G2_TX_DN<7>")
	)
	(segment
		(start 119.114824 -223.75114)
		(end 119.099838 -223.742504)
		(width 0.1143)
		(layer "In13.Cu")
		(net "GMI_CPU0_G0_CPU1_G2_TX_DN<7>")
	)
	(segment
		(start 119.128794 -234.429554)
		(end 119.146828 -234.418886)
		(width 0.1143)
		(layer "In13.Cu")
		(net "GMI_CPU0_G0_CPU1_G2_TX_DN<7>")
	)
	(segment
		(start 352.349054 -223.078802)
		(end 352.367088 -223.08947)
		(width 0.1143)
		(layer "In13.Cu")
		(net "GMI_CPU0_G0_CPU1_G2_TX_DN<7>")
	)
	(segment
		(start 150.496016 -191.196214)
		(end 150.515066 -191.003174)
		(width 0.14224)
		(layer "In13.Cu")
		(net "GMI_CPU0_G0_CPU1_G2_TX_DN<7>")
	)
	(segment
		(start 119.114062 -235.090462)
		(end 119.113046 -235.089954)
		(width 0.1143)
		(layer "In13.Cu")
		(net "GMI_CPU0_G0_CPU1_G2_TX_DN<7>")
	)
	(segment
		(start 119.087138 -227.97389)
		(end 119.146828 -227.939092)
		(width 0.1143)
		(layer "In13.Cu")
		(net "GMI_CPU0_G0_CPU1_G2_TX_DN<7>")
	)
	(segment
		(start 352.38817 -236.061504)
		(end 352.41992 -236.079792)
		(width 0.1143)
		(layer "In13.Cu")
		(net "GMI_CPU0_G0_CPU1_G2_TX_DN<7>")
	)
	(segment
		(start 119.577612 -242.37696)
		(end 119.547132 -242.35918)
		(width 0.1143)
		(layer "In13.Cu")
		(net "GMI_CPU0_G0_CPU1_G2_TX_DN<7>")
	)
	(segment
		(start 119.063008 -236.08919)
		(end 119.075962 -236.080046)
		(width 0.1143)
		(layer "In13.Cu")
		(net "GMI_CPU0_G0_CPU1_G2_TX_DN<7>")
	)
	(segment
		(start 119.146066 -231.869234)
		(end 119.10695 -231.846628)
		(width 0.1143)
		(layer "In13.Cu")
		(net "GMI_CPU0_G0_CPU1_G2_TX_DN<7>")
	)
	(segment
		(start 352.614992 -221.145862)
		(end 352.614992 -221.303088)
		(width 0.1143)
		(layer "In13.Cu")
		(net "GMI_CPU0_G0_CPU1_G2_TX_DN<7>")
	)
	(segment
		(start 119.12854 -223.089724)
		(end 119.128794 -223.089724)
		(width 0.1143)
		(layer "In13.Cu")
		(net "GMI_CPU0_G0_CPU1_G2_TX_DN<7>")
	)
	(segment
		(start 352.371406 -230.236522)
		(end 352.37039 -230.23703)
		(width 0.1143)
		(layer "In13.Cu")
		(net "GMI_CPU0_G0_CPU1_G2_TX_DN<7>")
	)
	(segment
		(start 352.41865 -222.10903)
		(end 352.349054 -222.14967)
		(width 0.1143)
		(layer "In13.Cu")
		(net "GMI_CPU0_G0_CPU1_G2_TX_DN<7>")
	)
	(segment
		(start 154.146504 -188.025278)
		(end 154.470354 -187.759594)
		(width 0.14224)
		(layer "In13.Cu")
		(net "GMI_CPU0_G0_CPU1_G2_TX_DN<7>")
	)
	(segment
		(start 351.641918 -242.781328)
		(end 351.559114 -242.864132)
		(width 0.1143)
		(layer "In13.Cu")
		(net "GMI_CPU0_G0_CPU1_G2_TX_DN<7>")
	)
	(segment
		(start 352.409506 -228.594412)
		(end 352.349816 -228.62921)
		(width 0.1143)
		(layer "In13.Cu")
		(net "GMI_CPU0_G0_CPU1_G2_TX_DN<7>")
	)
	(segment
		(start 119.075962 -224.740216)
		(end 119.107712 -224.721928)
		(width 0.1143)
		(layer "In13.Cu")
		(net "GMI_CPU0_G0_CPU1_G2_TX_DN<7>")
	)
	(segment
		(start 149.10054 -192.162938)
		(end 149.29358 -192.182242)
		(width 0.14224)
		(layer "In13.Cu")
		(net "GMI_CPU0_G0_CPU1_G2_TX_DN<7>")
	)
	(segment
		(start 352.438462 -225.335084)
		(end 352.41992 -225.348546)
		(width 0.1143)
		(layer "In13.Cu")
		(net "GMI_CPU0_G0_CPU1_G2_TX_DN<7>")
	)
	(segment
		(start 352.41992 -232.839768)
		(end 352.432874 -232.848912)
		(width 0.1143)
		(layer "In13.Cu")
		(net "GMI_CPU0_G0_CPU1_G2_TX_DN<7>")
	)
	(segment
		(start 352.372168 -230.236014)
		(end 352.371406 -230.236522)
		(width 0.1143)
		(layer "In13.Cu")
		(net "GMI_CPU0_G0_CPU1_G2_TX_DN<7>")
	)
	(segment
		(start 119.122952 -230.23576)
		(end 119.078248 -230.209852)
		(width 0.1143)
		(layer "In13.Cu")
		(net "GMI_CPU0_G0_CPU1_G2_TX_DN<7>")
	)
	(segment
		(start 352.383598 -235.089192)
		(end 352.382836 -235.0897)
		(width 0.1143)
		(layer "In13.Cu")
		(net "GMI_CPU0_G0_CPU1_G2_TX_DN<7>")
	)
	(segment
		(start 119.05742 -224.753678)
		(end 119.075962 -224.740216)
		(width 0.1143)
		(layer "In13.Cu")
		(net "GMI_CPU0_G0_CPU1_G2_TX_DN<7>")
	)
	(segment
		(start 119.107712 -232.821734)
		(end 119.146828 -232.798874)
		(width 0.1143)
		(layer "In13.Cu")
		(net "GMI_CPU0_G0_CPU1_G2_TX_DN<7>")
	)
	(segment
		(start 352.349054 -226.318826)
		(end 352.38817 -226.341686)
		(width 0.1143)
		(layer "In13.Cu")
		(net "GMI_CPU0_G0_CPU1_G2_TX_DN<7>")
	)
	(segment
		(start 144.357852 -195.656708)
		(end 145.12163 -195.42506)
		(width 0.14224)
		(layer "In13.Cu")
		(net "GMI_CPU0_G0_CPU1_G2_TX_DN<7>")
	)
	(segment
		(start 119.146066 -235.109258)
		(end 119.114062 -235.090462)
		(width 0.1143)
		(layer "In13.Cu")
		(net "GMI_CPU0_G0_CPU1_G2_TX_DN<7>")
	)
	(segment
		(start 119.146828 -238.34979)
		(end 119.075962 -238.308642)
		(width 0.1143)
		(layer "In13.Cu")
		(net "GMI_CPU0_G0_CPU1_G2_TX_DN<7>")
	)
	(segment
		(start 118.88089 -221.146116)
		(end 118.92661 -221.100396)
		(width 0.1143)
		(layer "In13.Cu")
		(net "GMI_CPU0_G0_CPU1_G2_TX_DN<7>")
	)
	(segment
		(start 119.107712 -239.301782)
		(end 119.146828 -239.278922)
		(width 0.1143)
		(layer "In13.Cu")
		(net "GMI_CPU0_G0_CPU1_G2_TX_DN<7>")
	)
	(segment
		(start 120.23471 -242.864386)
		(end 119.936768 -242.864386)
		(width 0.1143)
		(layer "In13.Cu")
		(net "GMI_CPU0_G0_CPU1_G2_TX_DN<7>")
	)
	(segment
		(start 352.41992 -224.739962)
		(end 352.438462 -224.753424)
		(width 0.1143)
		(layer "In13.Cu")
		(net "GMI_CPU0_G0_CPU1_G2_TX_DN<7>")
	)
	(segment
		(start 352.349054 -234.418632)
		(end 352.367088 -234.4293)
		(width 0.1143)
		(layer "In13.Cu")
		(net "GMI_CPU0_G0_CPU1_G2_TX_DN<7>")
	)
	(segment
		(start 119.078248 -230.209852)
		(end 119.036846 -230.171752)
		(width 0.1143)
		(layer "In13.Cu")
		(net "GMI_CPU0_G0_CPU1_G2_TX_DN<7>")
	)
	(segment
		(start 352.354642 -231.181656)
		(end 352.395028 -231.205278)
		(width 0.1143)
		(layer "In13.Cu")
		(net "GMI_CPU0_G0_CPU1_G2_TX_DN<7>")
	)
	(segment
		(start 352.38182 -235.090208)
		(end 352.349816 -235.109004)
		(width 0.1143)
		(layer "In13.Cu")
		(net "GMI_CPU0_G0_CPU1_G2_TX_DN<7>")
	)
	(segment
		(start 352.41992 -238.308388)
		(end 352.349054 -238.349536)
		(width 0.1143)
		(layer "In13.Cu")
		(net "GMI_CPU0_G0_CPU1_G2_TX_DN<7>")
	)
	(segment
		(start 352.367342 -234.4293)
		(end 352.388678 -234.441746)
		(width 0.1143)
		(layer "In13.Cu")
		(net "GMI_CPU0_G0_CPU1_G2_TX_DN<7>")
	)
	(segment
		(start 352.41992 -241.548412)
		(end 352.38817 -241.5667)
		(width 0.1143)
		(layer "In13.Cu")
		(net "GMI_CPU0_G0_CPU1_G2_TX_DN<7>")
	)
	(segment
		(start 153.804112 -188.473588)
		(end 154.12847 -188.20765)
		(width 0.14224)
		(layer "In13.Cu")
		(net "GMI_CPU0_G0_CPU1_G2_TX_DN<7>")
	)
	(segment
		(start 352.38817 -239.301528)
		(end 352.41992 -239.319816)
		(width 0.1143)
		(layer "In13.Cu")
		(net "GMI_CPU0_G0_CPU1_G2_TX_DN<7>")
	)
	(segment
		(start 119.616728 -242.39982)
		(end 119.577612 -242.37696)
		(width 0.1143)
		(layer "In13.Cu")
		(net "GMI_CPU0_G0_CPU1_G2_TX_DN<7>")
	)
	(segment
		(start 352.41992 -236.079792)
		(end 352.432874 -236.088936)
		(width 0.1143)
		(layer "In13.Cu")
		(net "GMI_CPU0_G0_CPU1_G2_TX_DN<7>")
	)
	(segment
		(start 154.977084 -187.51169)
		(end 154.995118 -187.329318)
		(width 0.14224)
		(layer "In13.Cu")
		(net "GMI_CPU0_G0_CPU1_G2_TX_DN<7>")
	)
	(segment
		(start 352.37039 -230.23703)
		(end 352.369628 -230.237538)
		(width 0.1143)
		(layer "In13.Cu")
		(net "GMI_CPU0_G0_CPU1_G2_TX_DN<7>")
	)
	(segment
		(start 119.075962 -239.32007)
		(end 119.107712 -239.301782)
		(width 0.1143)
		(layer "In13.Cu")
		(net "GMI_CPU0_G0_CPU1_G2_TX_DN<7>")
	)
	(segment
		(start 118.92661 -221.100396)
		(end 118.92661 -221.071948)
		(width 0.1143)
		(layer "In13.Cu")
		(net "GMI_CPU0_G0_CPU1_G2_TX_DN<7>")
	)
	(segment
		(start 352.349054 -237.658656)
		(end 352.38817 -237.681516)
		(width 0.1143)
		(layer "In13.Cu")
		(net "GMI_CPU0_G0_CPU1_G2_TX_DN<7>")
	)
	(segment
		(start 119.144288 -230.248206)
		(end 119.135144 -230.242872)
		(width 0.1143)
		(layer "In13.Cu")
		(net "GMI_CPU0_G0_CPU1_G2_TX_DN<7>")
	)
	(segment
		(start 352.349054 -224.698814)
		(end 352.38817 -224.721674)
		(width 0.1143)
		(layer "In13.Cu")
		(net "GMI_CPU0_G0_CPU1_G2_TX_DN<7>")
	)
	(segment
		(start 150.845012 -190.732664)
		(end 151.038052 -190.751714)
		(width 0.14224)
		(layer "In13.Cu")
		(net "GMI_CPU0_G0_CPU1_G2_TX_DN<7>")
	)
	(segment
		(start 155.50134 -187.081668)
		(end 155.825698 -186.81573)
		(width 0.14224)
		(layer "In13.Cu")
		(net "GMI_CPU0_G0_CPU1_G2_TX_DN<7>")
	)
	(segment
		(start 352.41992 -225.348546)
		(end 352.349054 -225.389694)
		(width 0.1143)
		(layer "In13.Cu")
		(net "GMI_CPU0_G0_CPU1_G2_TX_DN<7>")
	)
	(segment
		(start 119.10695 -231.846628)
		(end 119.106188 -231.84612)
		(width 0.1143)
		(layer "In13.Cu")
		(net "GMI_CPU0_G0_CPU1_G2_TX_DN<7>")
	)
	(segment
		(start 153.161492 -189.000638)
		(end 153.179526 -188.818266)
		(width 0.14224)
		(layer "In13.Cu")
		(net "GMI_CPU0_G0_CPU1_G2_TX_DN<7>")
	)
	(segment
		(start 352.38817 -239.946688)
		(end 352.349054 -239.969548)
		(width 0.1143)
		(layer "In13.Cu")
		(net "GMI_CPU0_G0_CPU1_G2_TX_DN<7>")
	)
	(segment
		(start 119.146828 -222.149924)
		(end 119.107712 -222.127064)
		(width 0.1143)
		(layer "In13.Cu")
		(net "GMI_CPU0_G0_CPU1_G2_TX_DN<7>")
	)
	(segment
		(start 119.106188 -231.84612)
		(end 119.1006 -231.843072)
		(width 0.1143)
		(layer "In13.Cu")
		(net "GMI_CPU0_G0_CPU1_G2_TX_DN<7>")
	)
	(segment
		(start 352.38817 -232.82148)
		(end 352.41992 -232.839768)
		(width 0.1143)
		(layer "In13.Cu")
		(net "GMI_CPU0_G0_CPU1_G2_TX_DN<7>")
	)
	(segment
		(start 149.29358 -192.182242)
		(end 149.62378 -191.911478)
		(width 0.14224)
		(layer "In13.Cu")
		(net "GMI_CPU0_G0_CPU1_G2_TX_DN<7>")
	)
	(segment
		(start 119.146066 -228.629464)
		(end 119.086376 -228.594666)
		(width 0.1143)
		(layer "In13.Cu")
		(net "GMI_CPU0_G0_CPU1_G2_TX_DN<7>")
	)
	(segment
		(start 149.64283 -191.718438)
		(end 149.972776 -191.447928)
		(width 0.14224)
		(layer "In13.Cu")
		(net "GMI_CPU0_G0_CPU1_G2_TX_DN<7>")
	)
	(segment
		(start 119.100854 -231.205532)
		(end 119.14124 -231.18191)
		(width 0.1143)
		(layer "In13.Cu")
		(net "GMI_CPU0_G0_CPU1_G2_TX_DN<7>")
	)
	(segment
		(start 352.575622 -221.342458)
		(end 352.575622 -221.80423)
		(width 0.1143)
		(layer "In13.Cu")
		(net "GMI_CPU0_G0_CPU1_G2_TX_DN<7>")
	)
	(segment
		(start 352.38817 -224.721674)
		(end 352.41992 -224.739962)
		(width 0.1143)
		(layer "In13.Cu")
		(net "GMI_CPU0_G0_CPU1_G2_TX_DN<7>")
	)
	(segment
		(start 315.24702 -185.883296)
		(end 349.628206 -214.074756)
		(width 0.14224)
		(layer "In13.Cu")
		(net "GMI_CPU0_G0_CPU1_G2_TX_DN<7>")
	)
	(segment
		(start 118.92026 -221.342712)
		(end 118.88089 -221.303342)
		(width 0.1143)
		(layer "In13.Cu")
		(net "GMI_CPU0_G0_CPU1_G2_TX_DN<7>")
	)
	(segment
		(start 352.395282 -231.842818)
		(end 352.389694 -231.845866)
		(width 0.1143)
		(layer "In13.Cu")
		(net "GMI_CPU0_G0_CPU1_G2_TX_DN<7>")
	)
	(segment
		(start 352.396044 -223.74225)
		(end 352.349816 -223.769174)
		(width 0.1143)
		(layer "In13.Cu")
		(net "GMI_CPU0_G0_CPU1_G2_TX_DN<7>")
	)
	(segment
		(start 154.995118 -187.329572)
		(end 155.318968 -187.063888)
		(width 0.14224)
		(layer "In13.Cu")
		(net "GMI_CPU0_G0_CPU1_G2_TX_DN<7>")
	)
	(segment
		(start 152.259538 -189.572646)
		(end 152.654762 -189.248542)
		(width 0.14224)
		(layer "In13.Cu")
		(net "GMI_CPU0_G0_CPU1_G2_TX_DN<7>")
	)
	(segment
		(start 352.349054 -240.89868)
		(end 352.41992 -240.939828)
		(width 0.1143)
		(layer "In13.Cu")
		(net "GMI_CPU0_G0_CPU1_G2_TX_DN<7>")
	)
	(segment
		(start 119.112284 -235.089446)
		(end 119.099838 -235.082334)
		(width 0.1143)
		(layer "In13.Cu")
		(net "GMI_CPU0_G0_CPU1_G2_TX_DN<7>")
	)
	(segment
		(start 352.41611 -230.210106)
		(end 352.415094 -230.211122)
		(width 0.1143)
		(layer "In13.Cu")
		(net "GMI_CPU0_G0_CPU1_G2_TX_DN<7>")
	)
	(segment
		(start 119.12854 -234.429554)
		(end 119.128794 -234.429554)
		(width 0.1143)
		(layer "In13.Cu")
		(net "GMI_CPU0_G0_CPU1_G2_TX_DN<7>")
	)
	(segment
		(start 154.12847 -188.20765)
		(end 154.146504 -188.025278)
		(width 0.14224)
		(layer "In13.Cu")
		(net "GMI_CPU0_G0_CPU1_G2_TX_DN<7>")
	)
	(segment
		(start 119.146828 -227.00996)
		(end 119.107712 -226.9871)
		(width 0.1143)
		(layer "In13.Cu")
		(net "GMI_CPU0_G0_CPU1_G2_TX_DN<7>")
	)
	(segment
		(start 119.146828 -239.969802)
		(end 119.107712 -239.946942)
		(width 0.1143)
		(layer "In13.Cu")
		(net "GMI_CPU0_G0_CPU1_G2_TX_DN<7>")
	)
	(segment
		(start 119.063008 -232.849166)
		(end 119.075962 -232.840022)
		(width 0.1143)
		(layer "In13.Cu")
		(net "GMI_CPU0_G0_CPU1_G2_TX_DN<7>")
	)
	(segment
		(start 119.146066 -223.769428)
		(end 119.116348 -223.752156)
		(width 0.1143)
		(layer "In13.Cu")
		(net "GMI_CPU0_G0_CPU1_G2_TX_DN<7>")
	)
	(segment
		(start 352.367088 -234.4293)
		(end 352.367342 -234.4293)
		(width 0.1143)
		(layer "In13.Cu")
		(net "GMI_CPU0_G0_CPU1_G2_TX_DN<7>")
	)
	(segment
		(start 352.41992 -233.448352)
		(end 352.349054 -233.4895)
		(width 0.1143)
		(layer "In13.Cu")
		(net "GMI_CPU0_G0_CPU1_G2_TX_DN<7>")
	)
	(segment
		(start 118.88089 -221.303342)
		(end 118.88089 -221.146116)
		(width 0.1143)
		(layer "In13.Cu")
		(net "GMI_CPU0_G0_CPU1_G2_TX_DN<7>")
	)
	(segment
		(start 352.432874 -236.679232)
		(end 352.41992 -236.688376)
		(width 0.1143)
		(layer "In13.Cu")
		(net "GMI_CPU0_G0_CPU1_G2_TX_DN<7>")
	)
	(segment
		(start 119.086376 -228.594666)
		(end 119.085868 -228.594666)
		(width 0.1143)
		(layer "In13.Cu")
		(net "GMI_CPU0_G0_CPU1_G2_TX_DN<7>")
	)
	(segment
		(start 119.075962 -241.548666)
		(end 119.05615 -241.534442)
		(width 0.1143)
		(layer "In13.Cu")
		(net "GMI_CPU0_G0_CPU1_G2_TX_DN<7>")
	)
	(segment
		(start 154.995118 -187.329318)
		(end 154.995118 -187.329572)
		(width 0.14224)
		(layer "In13.Cu")
		(net "GMI_CPU0_G0_CPU1_G2_TX_DN<7>")
	)
	(segment
		(start 352.614992 -221.303088)
		(end 352.575622 -221.342458)
		(width 0.1143)
		(layer "In13.Cu")
		(net "GMI_CPU0_G0_CPU1_G2_TX_DN<7>")
	)
	(segment
		(start 352.417126 -230.210106)
		(end 352.41611 -230.210106)
		(width 0.1143)
		(layer "In13.Cu")
		(net "GMI_CPU0_G0_CPU1_G2_TX_DN<7>")
	)
	(segment
		(start 119.075962 -233.448606)
		(end 119.063008 -233.439462)
		(width 0.1143)
		(layer "In13.Cu")
		(net "GMI_CPU0_G0_CPU1_G2_TX_DN<7>")
	)
	(segment
		(start 152.837134 -189.266576)
		(end 153.161492 -189.000638)
		(width 0.14224)
		(layer "In13.Cu")
		(net "GMI_CPU0_G0_CPU1_G2_TX_DN<7>")
	)
	(segment
		(start 119.128286 -230.238808)
		(end 119.126254 -230.237792)
		(width 0.1143)
		(layer "In13.Cu")
		(net "GMI_CPU0_G0_CPU1_G2_TX_DN<7>")
	)
	(segment
		(start 352.369628 -230.237538)
		(end 352.367596 -230.238554)
		(width 0.1143)
		(layer "In13.Cu")
		(net "GMI_CPU0_G0_CPU1_G2_TX_DN<7>")
	)
	(segment
		(start 119.075962 -225.3488)
		(end 119.05742 -225.335338)
		(width 0.1143)
		(layer "In13.Cu")
		(net "GMI_CPU0_G0_CPU1_G2_TX_DN<7>")
	)
	(segment
		(start 119.113046 -235.089954)
		(end 119.112284 -235.089446)
		(width 0.1143)
		(layer "In13.Cu")
		(net "GMI_CPU0_G0_CPU1_G2_TX_DN<7>")
	)
	(segment
		(start 352.569272 -221.093538)
		(end 352.569272 -221.100142)
		(width 0.1143)
		(layer "In13.Cu")
		(net "GMI_CPU0_G0_CPU1_G2_TX_DN<7>")
	)
	(segment
		(start 352.408744 -227.973636)
		(end 352.409506 -227.974144)
		(width 0.1143)
		(layer "In13.Cu")
		(net "GMI_CPU0_G0_CPU1_G2_TX_DN<7>")
	)
	(segment
		(start 352.38817 -226.986846)
		(end 352.349054 -227.009706)
		(width 0.1143)
		(layer "In13.Cu")
		(net "GMI_CPU0_G0_CPU1_G2_TX_DN<7>")
	)
	(segment
		(start 352.360738 -230.242618)
		(end 352.351594 -230.247952)
		(width 0.1143)
		(layer "In13.Cu")
		(net "GMI_CPU0_G0_CPU1_G2_TX_DN<7>")
	)
	(segment
		(start 352.367596 -230.238554)
		(end 352.36531 -230.240078)
		(width 0.1143)
		(layer "In13.Cu")
		(net "GMI_CPU0_G0_CPU1_G2_TX_DN<7>")
	)
	(segment
		(start 119.075962 -236.080046)
		(end 119.107712 -236.061758)
		(width 0.1143)
		(layer "In13.Cu")
		(net "GMI_CPU0_G0_CPU1_G2_TX_DN<7>")
	)
	(segment
		(start 352.415094 -230.211122)
		(end 352.372168 -230.236014)
		(width 0.1143)
		(layer "In13.Cu")
		(net "GMI_CPU0_G0_CPU1_G2_TX_DN<7>")
	)
	(segment
		(start 352.388932 -231.846374)
		(end 352.349816 -231.86898)
		(width 0.1143)
		(layer "In13.Cu")
		(net "GMI_CPU0_G0_CPU1_G2_TX_DN<7>")
	)
	(segment
		(start 119.146828 -241.589814)
		(end 119.107712 -241.566954)
		(width 0.1143)
		(layer "In13.Cu")
		(net "GMI_CPU0_G0_CPU1_G2_TX_DN<7>")
	)
	(segment
		(start 119.107712 -224.721928)
		(end 119.146828 -224.699068)
		(width 0.1143)
		(layer "In13.Cu")
		(net "GMI_CPU0_G0_CPU1_G2_TX_DN<7>")
	)
	(segment
		(start 155.318968 -187.063634)
		(end 155.50134 -187.081668)
		(width 0.14224)
		(layer "In13.Cu")
		(net "GMI_CPU0_G0_CPU1_G2_TX_DN<7>")
	)
	(segment
		(start 119.107712 -236.061758)
		(end 119.146828 -236.038898)
		(width 0.1143)
		(layer "In13.Cu")
		(net "GMI_CPU0_G0_CPU1_G2_TX_DN<7>")
	)
	(segment
		(start 352.449384 -230.181912)
		(end 352.417126 -230.210106)
		(width 0.1143)
		(layer "In13.Cu")
		(net "GMI_CPU0_G0_CPU1_G2_TX_DN<7>")
	)
	(segment
		(start 119.125492 -230.237284)
		(end 119.124476 -230.236776)
		(width 0.1143)
		(layer "In13.Cu")
		(net "GMI_CPU0_G0_CPU1_G2_TX_DN<7>")
	)
	(segment
		(start 352.41992 -237.699804)
		(end 352.438462 -237.713266)
		(width 0.1143)
		(layer "In13.Cu")
		(net "GMI_CPU0_G0_CPU1_G2_TX_DN<7>")
	)
	(segment
		(start 352.349054 -229.55885)
		(end 352.385376 -229.579932)
		(width 0.1143)
		(layer "In13.Cu")
		(net "GMI_CPU0_G0_CPU1_G2_TX_DN<7>")
	)
	(segment
		(start 119.14124 -231.18191)
		(end 119.146828 -231.179116)
		(width 0.1143)
		(layer "In13.Cu")
		(net "GMI_CPU0_G0_CPU1_G2_TX_DN<7>")
	)
	(segment
		(start 119.05742 -237.71352)
		(end 119.075962 -237.700058)
		(width 0.1143)
		(layer "In13.Cu")
		(net "GMI_CPU0_G0_CPU1_G2_TX_DN<7>")
	)
	(segment
		(start 119.124476 -230.236776)
		(end 119.122952 -230.23576)
		(width 0.1143)
		(layer "In13.Cu")
		(net "GMI_CPU0_G0_CPU1_G2_TX_DN<7>")
	)
	(segment
		(start 352.575622 -229.896416)
		(end 352.571558 -229.941374)
		(width 0.1143)
		(layer "In13.Cu")
		(net "GMI_CPU0_G0_CPU1_G2_TX_DN<7>")
	)
	(segment
		(start 118.92026 -221.804484)
		(end 118.92026 -221.342712)
		(width 0.1143)
		(layer "In13.Cu")
		(net "GMI_CPU0_G0_CPU1_G2_TX_DN<7>")
	)
	(segment
		(start 149.972776 -191.447928)
		(end 150.165816 -191.466978)
		(width 0.14224)
		(layer "In13.Cu")
		(net "GMI_CPU0_G0_CPU1_G2_TX_DN<7>")
	)
	(segment
		(start 308.75859 -182.210456)
		(end 315.24702 -185.883296)
		(width 0.14224)
		(layer "In13.Cu")
		(net "GMI_CPU0_G0_CPU1_G2_TX_DN<7>")
	)
	(segment
		(start 352.367342 -223.08947)
		(end 352.388678 -223.101916)
		(width 0.1143)
		(layer "In13.Cu")
		(net "GMI_CPU0_G0_CPU1_G2_TX_DN<7>")
	)
	(segment
		(start 352.432874 -233.439208)
		(end 352.41992 -233.448352)
		(width 0.1143)
		(layer "In13.Cu")
		(net "GMI_CPU0_G0_CPU1_G2_TX_DN<7>")
	)
	(segment
		(start 153.621994 -188.455554)
		(end 153.804112 -188.473588)
		(width 0.14224)
		(layer "In13.Cu")
		(net "GMI_CPU0_G0_CPU1_G2_TX_DN<7>")
	)
	(segment
		(start 155.825698 -186.81573)
		(end 155.843732 -186.633358)
		(width 0.14224)
		(layer "In13.Cu")
		(net "GMI_CPU0_G0_CPU1_G2_TX_DN<7>")
	)
	(segment
		(start 119.086376 -227.974398)
		(end 119.087138 -227.97389)
		(width 0.1143)
		(layer "In13.Cu")
		(net "GMI_CPU0_G0_CPU1_G2_TX_DN<7>")
	)
	(segment
		(start 119.075962 -238.308642)
		(end 119.05742 -238.29518)
		(width 0.1143)
		(layer "In13.Cu")
		(net "GMI_CPU0_G0_CPU1_G2_TX_DN<7>")
	)
	(segment
		(start 351.559114 -242.864132)
		(end 351.261172 -242.864132)
		(width 0.1143)
		(layer "In13.Cu")
		(net "GMI_CPU0_G0_CPU1_G2_TX_DN<7>")
	)
	(segment
		(start 352.382836 -235.0897)
		(end 352.38182 -235.090208)
		(width 0.1143)
		(layer "In13.Cu")
		(net "GMI_CPU0_G0_CPU1_G2_TX_DN<7>")
	)
	(segment
		(start 119.146828 -225.389948)
		(end 119.075962 -225.3488)
		(width 0.1143)
		(layer "In13.Cu")
		(net "GMI_CPU0_G0_CPU1_G2_TX_DN<7>")
	)
	(segment
		(start 119.05615 -240.954306)
		(end 119.075962 -240.940082)
		(width 0.1143)
		(layer "In13.Cu")
		(net "GMI_CPU0_G0_CPU1_G2_TX_DN<7>")
	)
	(segment
		(start 352.409506 -227.974144)
		(end 352.40976 -227.974144)
		(width 0.1143)
		(layer "In13.Cu")
		(net "GMI_CPU0_G0_CPU1_G2_TX_DN<7>")
	)
	(segment
		(start 166.226998 -180.862478)
		(end 302.898048 -181.659276)
		(width 0.14224)
		(layer "In13.Cu")
		(net "GMI_CPU0_G0_CPU1_G2_TX_DN<7>")
	)
	(segment
		(start 119.075962 -232.840022)
		(end 119.107712 -232.821734)
		(width 0.1143)
		(layer "In13.Cu")
		(net "GMI_CPU0_G0_CPU1_G2_TX_DN<7>")
	)
	(segment
		(start 119.075962 -226.360228)
		(end 119.107712 -226.34194)
		(width 0.1143)
		(layer "In13.Cu")
		(net "GMI_CPU0_G0_CPU1_G2_TX_DN<7>")
	)
	(segment
		(start 351.94875 -242.358926)
		(end 351.879154 -242.399566)
		(width 0.1143)
		(layer "In13.Cu")
		(net "GMI_CPU0_G0_CPU1_G2_TX_DN<7>")
	)
	(segment
		(start 160.294828 -182.983632)
		(end 166.226998 -180.862478)
		(width 0.14224)
		(layer "In13.Cu")
		(net "GMI_CPU0_G0_CPU1_G2_TX_DN<7>")
	)
	(segment
		(start 352.41992 -226.968558)
		(end 352.38817 -226.986846)
		(width 0.1143)
		(layer "In13.Cu")
		(net "GMI_CPU0_G0_CPU1_G2_TX_DN<7>")
	)
	(segment
		(start 119.128794 -223.089724)
		(end 119.146828 -223.079056)
		(width 0.1143)
		(layer "In13.Cu")
		(net "GMI_CPU0_G0_CPU1_G2_TX_DN<7>")
	)
	(segment
		(start 352.349054 -227.938838)
		(end 352.408744 -227.973636)
		(width 0.1143)
		(layer "In13.Cu")
		(net "GMI_CPU0_G0_CPU1_G2_TX_DN<7>")
	)
	(segment
		(start 151.717248 -190.0174)
		(end 151.910288 -190.03645)
		(width 0.14224)
		(layer "In13.Cu")
		(net "GMI_CPU0_G0_CPU1_G2_TX_DN<7>")
	)
	(segment
		(start 119.146828 -236.729778)
		(end 119.075962 -236.68863)
		(width 0.1143)
		(layer "In13.Cu")
		(net "GMI_CPU0_G0_CPU1_G2_TX_DN<7>")
	)
	(segment
		(start 150.165816 -191.466978)
		(end 150.496016 -191.196214)
		(width 0.14224)
		(layer "In13.Cu")
		(net "GMI_CPU0_G0_CPU1_G2_TX_DN<7>")
	)
	(segment
		(start 119.107712 -241.566954)
		(end 119.075962 -241.548666)
		(width 0.1143)
		(layer "In13.Cu")
		(net "GMI_CPU0_G0_CPU1_G2_TX_DN<7>")
	)
	(segment
		(start 119.107712 -226.34194)
		(end 119.146828 -226.31908)
		(width 0.1143)
		(layer "In13.Cu")
		(net "GMI_CPU0_G0_CPU1_G2_TX_DN<7>")
	)
	(segment
		(start 352.38817 -237.681516)
		(end 352.41992 -237.699804)
		(width 0.1143)
		(layer "In13.Cu")
		(net "GMI_CPU0_G0_CPU1_G2_TX_DN<7>")
	)
	(segment
		(start 119.936768 -242.864386)
		(end 119.853964 -242.781582)
		(width 0.1143)
		(layer "In13.Cu")
		(net "GMI_CPU0_G0_CPU1_G2_TX_DN<7>")
	)
	(arc
		(start 352.571558 -229.941374)
		(mid 352.533614 -230.073409)
		(end 352.449384 -230.181912)
		(width 0.1143)
		(layer "In13.Cu")
		(net "GMI_CPU0_G0_CPU1_G2_TX_DN<7>")
	)
	(arc
		(start 119.099838 -235.082334)
		(mid 118.921621 -234.760057)
		(end 119.107204 -234.442)
		(width 0.1143)
		(layer "In13.Cu")
		(net "GMI_CPU0_G0_CPU1_G2_TX_DN<7>")
	)
	(arc
		(start 352.349054 -223.769682)
		(mid 352.105727 -224.234248)
		(end 352.349054 -224.698814)
		(width 0.1143)
		(layer "In13.Cu")
		(net "GMI_CPU0_G0_CPU1_G2_TX_DN<7>")
	)
	(arc
		(start 352.351594 -230.247952)
		(mid 352.170942 -230.450697)
		(end 352.105722 -230.714296)
		(width 0.1143)
		(layer "In13.Cu")
		(net "GMI_CPU0_G0_CPU1_G2_TX_DN<7>")
	)
	(arc
		(start 119.075962 -239.928654)
		(mid 118.924373 -239.624362)
		(end 119.075962 -239.32007)
		(width 0.1143)
		(layer "In13.Cu")
		(net "GMI_CPU0_G0_CPU1_G2_TX_DN<7>")
	)
	(arc
		(start 352.20529 -241.733578)
		(mid 352.131176 -241.886292)
		(end 352.105722 -242.054126)
		(width 0.1143)
		(layer "In13.Cu")
		(net "GMI_CPU0_G0_CPU1_G2_TX_DN<7>")
	)
	(arc
		(start 352.349054 -241.58956)
		(mid 352.270631 -241.655041)
		(end 352.20529 -241.733578)
		(width 0.1143)
		(layer "In13.Cu")
		(net "GMI_CPU0_G0_CPU1_G2_TX_DN<7>")
	)
	(arc
		(start 119.146828 -229.559104)
		(mid 119.390155 -229.094538)
		(end 119.146828 -228.629972)
		(width 0.1143)
		(layer "In13.Cu")
		(net "GMI_CPU0_G0_CPU1_G2_TX_DN<7>")
	)
	(arc
		(start 352.349054 -227.009706)
		(mid 352.105727 -227.474272)
		(end 352.349054 -227.938838)
		(width 0.1143)
		(layer "In13.Cu")
		(net "GMI_CPU0_G0_CPU1_G2_TX_DN<7>")
	)
	(arc
		(start 119.05615 -241.534442)
		(mid 118.907436 -241.244374)
		(end 119.05615 -240.954306)
		(width 0.1143)
		(layer "In13.Cu")
		(net "GMI_CPU0_G0_CPU1_G2_TX_DN<7>")
	)
	(arc
		(start 119.146828 -231.869742)
		(mid 119.146447 -231.869488)
		(end 119.146066 -231.869234)
		(width 0.1143)
		(layer "In13.Cu")
		(net "GMI_CPU0_G0_CPU1_G2_TX_DN<7>")
	)
	(arc
		(start 119.146828 -239.278922)
		(mid 119.390155 -238.814356)
		(end 119.146828 -238.34979)
		(width 0.1143)
		(layer "In13.Cu")
		(net "GMI_CPU0_G0_CPU1_G2_TX_DN<7>")
	)
	(arc
		(start 119.063008 -233.439462)
		(mid 118.911756 -233.144314)
		(end 119.063008 -232.849166)
		(width 0.1143)
		(layer "In13.Cu")
		(net "GMI_CPU0_G0_CPU1_G2_TX_DN<7>")
	)
	(arc
		(start 352.349816 -231.86898)
		(mid 352.349435 -231.869234)
		(end 352.349054 -231.869488)
		(width 0.1143)
		(layer "In13.Cu")
		(net "GMI_CPU0_G0_CPU1_G2_TX_DN<7>")
	)
	(arc
		(start 119.146828 -236.038898)
		(mid 119.390155 -235.574332)
		(end 119.146828 -235.109766)
		(width 0.1143)
		(layer "In13.Cu")
		(net "GMI_CPU0_G0_CPU1_G2_TX_DN<7>")
	)
	(arc
		(start 119.39016 -230.71455)
		(mid 119.324924 -230.450959)
		(end 119.144288 -230.248206)
		(width 0.1143)
		(layer "In13.Cu")
		(net "GMI_CPU0_G0_CPU1_G2_TX_DN<7>")
	)
	(arc
		(start 352.349054 -239.969548)
		(mid 352.105727 -240.434114)
		(end 352.349054 -240.89868)
		(width 0.1143)
		(layer "In13.Cu")
		(net "GMI_CPU0_G0_CPU1_G2_TX_DN<7>")
	)
	(arc
		(start 119.036846 -230.171752)
		(mid 118.961625 -230.071662)
		(end 118.926356 -229.951534)
		(width 0.1143)
		(layer "In13.Cu")
		(net "GMI_CPU0_G0_CPU1_G2_TX_DN<7>")
	)
	(arc
		(start 119.05742 -238.29518)
		(mid 118.908405 -238.00435)
		(end 119.05742 -237.71352)
		(width 0.1143)
		(layer "In13.Cu")
		(net "GMI_CPU0_G0_CPU1_G2_TX_DN<7>")
	)
	(arc
		(start 352.575622 -221.80423)
		(mid 352.534073 -221.975652)
		(end 352.41865 -222.10903)
		(width 0.1143)
		(layer "In13.Cu")
		(net "GMI_CPU0_G0_CPU1_G2_TX_DN<7>")
	)
	(arc
		(start 352.349054 -238.349536)
		(mid 352.105727 -238.814102)
		(end 352.349054 -239.278668)
		(width 0.1143)
		(layer "In13.Cu")
		(net "GMI_CPU0_G0_CPU1_G2_TX_DN<7>")
	)
	(arc
		(start 352.432874 -236.088936)
		(mid 352.584126 -236.384084)
		(end 352.432874 -236.679232)
		(width 0.1143)
		(layer "In13.Cu")
		(net "GMI_CPU0_G0_CPU1_G2_TX_DN<7>")
	)
	(arc
		(start 119.39016 -242.05438)
		(mid 119.36474 -241.886535)
		(end 119.290592 -241.733832)
		(width 0.1143)
		(layer "In13.Cu")
		(net "GMI_CPU0_G0_CPU1_G2_TX_DN<7>")
	)
	(arc
		(start 119.099838 -223.742504)
		(mid 118.921621 -223.420227)
		(end 119.107204 -223.10217)
		(width 0.1143)
		(layer "In13.Cu")
		(net "GMI_CPU0_G0_CPU1_G2_TX_DN<7>")
	)
	(arc
		(start 119.146828 -223.769936)
		(mid 119.146447 -223.769682)
		(end 119.146066 -223.769428)
		(width 0.1143)
		(layer "In13.Cu")
		(net "GMI_CPU0_G0_CPU1_G2_TX_DN<7>")
	)
	(arc
		(start 119.146828 -232.798874)
		(mid 119.390155 -232.334308)
		(end 119.146828 -231.869742)
		(width 0.1143)
		(layer "In13.Cu")
		(net "GMI_CPU0_G0_CPU1_G2_TX_DN<7>")
	)
	(arc
		(start 352.438462 -237.713266)
		(mid 352.587477 -238.004096)
		(end 352.438462 -238.294926)
		(width 0.1143)
		(layer "In13.Cu")
		(net "GMI_CPU0_G0_CPU1_G2_TX_DN<7>")
	)
	(arc
		(start 119.063008 -236.679486)
		(mid 118.911756 -236.384338)
		(end 119.063008 -236.08919)
		(width 0.1143)
		(layer "In13.Cu")
		(net "GMI_CPU0_G0_CPU1_G2_TX_DN<7>")
	)
	(arc
		(start 352.349054 -236.729524)
		(mid 352.105727 -237.19409)
		(end 352.349054 -237.658656)
		(width 0.1143)
		(layer "In13.Cu")
		(net "GMI_CPU0_G0_CPU1_G2_TX_DN<7>")
	)
	(arc
		(start 119.146828 -235.109766)
		(mid 119.146447 -235.109512)
		(end 119.146066 -235.109258)
		(width 0.1143)
		(layer "In13.Cu")
		(net "GMI_CPU0_G0_CPU1_G2_TX_DN<7>")
	)
	(arc
		(start 352.41992 -226.359974)
		(mid 352.569017 -226.664266)
		(end 352.41992 -226.968558)
		(width 0.1143)
		(layer "In13.Cu")
		(net "GMI_CPU0_G0_CPU1_G2_TX_DN<7>")
	)
	(arc
		(start 352.349816 -228.62921)
		(mid 352.349435 -228.629464)
		(end 352.349054 -228.629718)
		(width 0.1143)
		(layer "In13.Cu")
		(net "GMI_CPU0_G0_CPU1_G2_TX_DN<7>")
	)
	(arc
		(start 352.349054 -233.4895)
		(mid 352.105727 -233.954066)
		(end 352.349054 -234.418632)
		(width 0.1143)
		(layer "In13.Cu")
		(net "GMI_CPU0_G0_CPU1_G2_TX_DN<7>")
	)
	(arc
		(start 352.105722 -230.714296)
		(mid 352.170237 -230.976515)
		(end 352.349054 -231.178862)
		(width 0.1143)
		(layer "In13.Cu")
		(net "GMI_CPU0_G0_CPU1_G2_TX_DN<7>")
	)
	(arc
		(start 352.388678 -234.441746)
		(mid 352.574198 -234.759803)
		(end 352.396044 -235.08208)
		(width 0.1143)
		(layer "In13.Cu")
		(net "GMI_CPU0_G0_CPU1_G2_TX_DN<7>")
	)
	(arc
		(start 119.290592 -241.733832)
		(mid 119.22524 -241.655305)
		(end 119.146828 -241.589814)
		(width 0.1143)
		(layer "In13.Cu")
		(net "GMI_CPU0_G0_CPU1_G2_TX_DN<7>")
	)
	(arc
		(start 352.349054 -225.389694)
		(mid 352.105727 -225.85426)
		(end 352.349054 -226.318826)
		(width 0.1143)
		(layer "In13.Cu")
		(net "GMI_CPU0_G0_CPU1_G2_TX_DN<7>")
	)
	(arc
		(start 352.349816 -223.769174)
		(mid 352.349435 -223.769428)
		(end 352.349054 -223.769682)
		(width 0.1143)
		(layer "In13.Cu")
		(net "GMI_CPU0_G0_CPU1_G2_TX_DN<7>")
	)
	(arc
		(start 352.349054 -231.869488)
		(mid 352.105727 -232.334054)
		(end 352.349054 -232.79862)
		(width 0.1143)
		(layer "In13.Cu")
		(net "GMI_CPU0_G0_CPU1_G2_TX_DN<7>")
	)
	(arc
		(start 352.438462 -224.753424)
		(mid 352.587477 -225.044254)
		(end 352.438462 -225.335084)
		(width 0.1143)
		(layer "In13.Cu")
		(net "GMI_CPU0_G0_CPU1_G2_TX_DN<7>")
	)
	(arc
		(start 119.146828 -234.418886)
		(mid 119.390155 -233.95432)
		(end 119.146828 -233.489754)
		(width 0.1143)
		(layer "In13.Cu")
		(net "GMI_CPU0_G0_CPU1_G2_TX_DN<7>")
	)
	(arc
		(start 119.850154 -242.758722)
		(mid 119.768721 -242.556324)
		(end 119.616728 -242.39982)
		(width 0.1143)
		(layer "In13.Cu")
		(net "GMI_CPU0_G0_CPU1_G2_TX_DN<7>")
	)
	(arc
		(start 119.547132 -242.35918)
		(mid 119.431705 -242.225804)
		(end 119.39016 -242.05438)
		(width 0.1143)
		(layer "In13.Cu")
		(net "GMI_CPU0_G0_CPU1_G2_TX_DN<7>")
	)
	(arc
		(start 119.146828 -231.179116)
		(mid 119.325641 -230.976766)
		(end 119.39016 -230.71455)
		(width 0.1143)
		(layer "In13.Cu")
		(net "GMI_CPU0_G0_CPU1_G2_TX_DN<7>")
	)
	(arc
		(start 119.853964 -242.781582)
		(mid 119.852176 -242.770133)
		(end 119.850154 -242.758722)
		(width 0.1143)
		(layer "In13.Cu")
		(net "GMI_CPU0_G0_CPU1_G2_TX_DN<7>")
	)
	(arc
		(start 119.146828 -228.629972)
		(mid 119.146447 -228.629718)
		(end 119.146066 -228.629464)
		(width 0.1143)
		(layer "In13.Cu")
		(net "GMI_CPU0_G0_CPU1_G2_TX_DN<7>")
	)
	(arc
		(start 119.075962 -226.968812)
		(mid 118.926865 -226.66452)
		(end 119.075962 -226.360228)
		(width 0.1143)
		(layer "In13.Cu")
		(net "GMI_CPU0_G0_CPU1_G2_TX_DN<7>")
	)
	(arc
		(start 352.395028 -231.205278)
		(mid 352.578005 -231.523938)
		(end 352.395282 -231.842818)
		(width 0.1143)
		(layer "In13.Cu")
		(net "GMI_CPU0_G0_CPU1_G2_TX_DN<7>")
	)
	(arc
		(start 352.421444 -229.601014)
		(mid 352.533164 -229.730629)
		(end 352.575622 -229.896416)
		(width 0.1143)
		(layer "In13.Cu")
		(net "GMI_CPU0_G0_CPU1_G2_TX_DN<7>")
	)
	(arc
		(start 352.349816 -235.109004)
		(mid 352.349435 -235.109258)
		(end 352.349054 -235.109512)
		(width 0.1143)
		(layer "In13.Cu")
		(net "GMI_CPU0_G0_CPU1_G2_TX_DN<7>")
	)
	(arc
		(start 351.879154 -242.399566)
		(mid 351.727167 -242.556074)
		(end 351.645728 -242.758468)
		(width 0.1143)
		(layer "In13.Cu")
		(net "GMI_CPU0_G0_CPU1_G2_TX_DN<7>")
	)
	(arc
		(start 352.439732 -240.954052)
		(mid 352.588446 -241.24412)
		(end 352.439732 -241.534188)
		(width 0.1143)
		(layer "In13.Cu")
		(net "GMI_CPU0_G0_CPU1_G2_TX_DN<7>")
	)
	(arc
		(start 119.05742 -225.335338)
		(mid 118.908405 -225.044508)
		(end 119.05742 -224.753678)
		(width 0.1143)
		(layer "In13.Cu")
		(net "GMI_CPU0_G0_CPU1_G2_TX_DN<7>")
	)
	(arc
		(start 118.92026 -229.895654)
		(mid 118.962799 -229.730566)
		(end 119.074184 -229.601522)
		(width 0.1143)
		(layer "In13.Cu")
		(net "GMI_CPU0_G0_CPU1_G2_TX_DN<7>")
	)
	(arc
		(start 119.1006 -231.843072)
		(mid 118.917749 -231.524192)
		(end 119.100854 -231.205532)
		(width 0.1143)
		(layer "In13.Cu")
		(net "GMI_CPU0_G0_CPU1_G2_TX_DN<7>")
	)
	(arc
		(start 119.146828 -223.079056)
		(mid 119.390155 -222.61449)
		(end 119.146828 -222.149924)
		(width 0.1143)
		(layer "In13.Cu")
		(net "GMI_CPU0_G0_CPU1_G2_TX_DN<7>")
	)
	(arc
		(start 351.645728 -242.758468)
		(mid 351.643705 -242.769878)
		(end 351.641918 -242.781328)
		(width 0.1143)
		(layer "In13.Cu")
		(net "GMI_CPU0_G0_CPU1_G2_TX_DN<7>")
	)
	(arc
		(start 352.40976 -227.974144)
		(mid 352.588302 -228.284168)
		(end 352.410014 -228.594412)
		(width 0.1143)
		(layer "In13.Cu")
		(net "GMI_CPU0_G0_CPU1_G2_TX_DN<7>")
	)
	(arc
		(start 119.085868 -228.594666)
		(mid 118.907452 -228.284422)
		(end 119.086122 -227.974398)
		(width 0.1143)
		(layer "In13.Cu")
		(net "GMI_CPU0_G0_CPU1_G2_TX_DN<7>")
	)
	(arc
		(start 352.41992 -239.319816)
		(mid 352.571509 -239.624108)
		(end 352.41992 -239.9284)
		(width 0.1143)
		(layer "In13.Cu")
		(net "GMI_CPU0_G0_CPU1_G2_TX_DN<7>")
	)
	(arc
		(start 119.146828 -237.65891)
		(mid 119.390155 -237.194344)
		(end 119.146828 -236.729778)
		(width 0.1143)
		(layer "In13.Cu")
		(net "GMI_CPU0_G0_CPU1_G2_TX_DN<7>")
	)
	(arc
		(start 352.432874 -232.848912)
		(mid 352.584126 -233.14406)
		(end 352.432874 -233.439208)
		(width 0.1143)
		(layer "In13.Cu")
		(net "GMI_CPU0_G0_CPU1_G2_TX_DN<7>")
	)
	(arc
		(start 119.146828 -224.699068)
		(mid 119.390155 -224.234502)
		(end 119.146828 -223.769936)
		(width 0.1143)
		(layer "In13.Cu")
		(net "GMI_CPU0_G0_CPU1_G2_TX_DN<7>")
	)
	(arc
		(start 119.146828 -227.939092)
		(mid 119.390155 -227.474526)
		(end 119.146828 -227.00996)
		(width 0.1143)
		(layer "In13.Cu")
		(net "GMI_CPU0_G0_CPU1_G2_TX_DN<7>")
	)
	(arc
		(start 352.349054 -235.109512)
		(mid 352.105727 -235.574078)
		(end 352.349054 -236.038644)
		(width 0.1143)
		(layer "In13.Cu")
		(net "GMI_CPU0_G0_CPU1_G2_TX_DN<7>")
	)
	(arc
		(start 352.388678 -223.101916)
		(mid 352.574198 -223.419973)
		(end 352.396044 -223.74225)
		(width 0.1143)
		(layer "In13.Cu")
		(net "GMI_CPU0_G0_CPU1_G2_TX_DN<7>")
	)
	(arc
		(start 352.349054 -222.14967)
		(mid 352.105727 -222.614236)
		(end 352.349054 -223.078802)
		(width 0.1143)
		(layer "In13.Cu")
		(net "GMI_CPU0_G0_CPU1_G2_TX_DN<7>")
	)
	(arc
		(start 352.105722 -242.054126)
		(mid 352.064173 -242.225548)
		(end 351.94875 -242.358926)
		(width 0.1143)
		(layer "In13.Cu")
		(net "GMI_CPU0_G0_CPU1_G2_TX_DN<7>")
	)
	(arc
		(start 352.349054 -228.629718)
		(mid 352.105727 -229.094284)
		(end 352.349054 -229.55885)
		(width 0.1143)
		(layer "In13.Cu")
		(net "GMI_CPU0_G0_CPU1_G2_TX_DN<7>")
	)
	(arc
		(start 119.077232 -222.109284)
		(mid 118.961805 -221.975908)
		(end 118.92026 -221.804484)
		(width 0.1143)
		(layer "In13.Cu")
		(net "GMI_CPU0_G0_CPU1_G2_TX_DN<7>")
	)
	(arc
		(start 119.146828 -240.898934)
		(mid 119.390155 -240.434368)
		(end 119.146828 -239.969802)
		(width 0.1143)
		(layer "In13.Cu")
		(net "GMI_CPU0_G0_CPU1_G2_TX_DN<7>")
	)
	(arc
		(start 119.146828 -226.31908)
		(mid 119.390155 -225.854514)
		(end 119.146828 -225.389948)
		(width 0.1143)
		(layer "In13.Cu")
		(net "GMI_CPU0_G0_CPU1_G2_TX_DN<7>")
	)
	(segment
		(start 354.547932 -241.510058)
		(end 354.08108 -241.24412)
		(width 0.12954)
		(layer "F.Cu")
		(net "GMI_CPU0_G0_CPU1_G2_TX_DN<6>")
	)
	(segment
		(start 116.94795 -241.510312)
		(end 117.414802 -241.244374)
		(width 0.12954)
		(layer "F.Cu")
		(net "GMI_CPU0_G0_CPU1_G2_TX_DN<6>")
	)
	(segment
		(start 302.907192 -178.831748)
		(end 165.65626 -178.030886)
		(width 0.14224)
		(layer "In13.Cu")
		(net "GMI_CPU0_G0_CPU1_G2_TX_DN<6>")
	)
	(segment
		(start 355.21011 -234.442762)
		(end 355.20884 -234.442)
		(width 0.1143)
		(layer "In13.Cu")
		(net "GMI_CPU0_G0_CPU1_G2_TX_DN<6>")
	)
	(segment
		(start 116.30914 -229.569518)
		(end 116.254276 -229.601522)
		(width 0.1143)
		(layer "In13.Cu")
		(net "GMI_CPU0_G0_CPU1_G2_TX_DN<6>")
	)
	(segment
		(start 149.104858 -187.98032)
		(end 149.085808 -188.17336)
		(width 0.14224)
		(layer "In13.Cu")
		(net "GMI_CPU0_G0_CPU1_G2_TX_DN<6>")
	)
	(segment
		(start 310.023256 -179.624482)
		(end 307.805836 -178.831748)
		(width 0.14224)
		(layer "In13.Cu")
		(net "GMI_CPU0_G0_CPU1_G2_TX_DN<6>")
	)
	(segment
		(start 116.287804 -223.101916)
		(end 116.256054 -223.120204)
		(width 0.1143)
		(layer "In13.Cu")
		(net "GMI_CPU0_G0_CPU1_G2_TX_DN<6>")
	)
	(segment
		(start 355.171756 -223.767904)
		(end 355.208078 -223.746822)
		(width 0.1143)
		(layer "In13.Cu")
		(net "GMI_CPU0_G0_CPU1_G2_TX_DN<6>")
	)
	(segment
		(start 116.285772 -234.443016)
		(end 116.256054 -234.460034)
		(width 0.1143)
		(layer "In13.Cu")
		(net "GMI_CPU0_G0_CPU1_G2_TX_DN<6>")
	)
	(segment
		(start 149.085808 -188.17336)
		(end 148.755608 -188.444124)
		(width 0.14224)
		(layer "In13.Cu")
		(net "GMI_CPU0_G0_CPU1_G2_TX_DN<6>")
	)
	(segment
		(start 146.4691 -190.318644)
		(end 146.1389 -190.589408)
		(width 0.14224)
		(layer "In13.Cu")
		(net "GMI_CPU0_G0_CPU1_G2_TX_DN<6>")
	)
	(segment
		(start 355.208078 -237.681516)
		(end 355.171756 -237.660434)
		(width 0.1143)
		(layer "In13.Cu")
		(net "GMI_CPU0_G0_CPU1_G2_TX_DN<6>")
	)
	(segment
		(start 355.159564 -239.976152)
		(end 355.169216 -239.969294)
		(width 0.1143)
		(layer "In13.Cu")
		(net "GMI_CPU0_G0_CPU1_G2_TX_DN<6>")
	)
	(segment
		(start 149.434804 -187.70981)
		(end 149.435058 -187.710318)
		(width 0.14224)
		(layer "In13.Cu")
		(net "GMI_CPU0_G0_CPU1_G2_TX_DN<6>")
	)
	(segment
		(start 355.210618 -230.225092)
		(end 355.21138 -230.224584)
		(width 0.1143)
		(layer "In13.Cu")
		(net "GMI_CPU0_G0_CPU1_G2_TX_DN<6>")
	)
	(segment
		(start 116.324126 -232.800652)
		(end 116.287804 -232.821734)
		(width 0.1143)
		(layer "In13.Cu")
		(net "GMI_CPU0_G0_CPU1_G2_TX_DN<6>")
	)
	(segment
		(start 355.20884 -230.226108)
		(end 355.210618 -230.225092)
		(width 0.1143)
		(layer "In13.Cu")
		(net "GMI_CPU0_G0_CPU1_G2_TX_DN<6>")
	)
	(segment
		(start 355.208078 -224.721674)
		(end 355.171756 -224.700592)
		(width 0.1143)
		(layer "In13.Cu")
		(net "GMI_CPU0_G0_CPU1_G2_TX_DN<6>")
	)
	(segment
		(start 116.324126 -226.320858)
		(end 116.287804 -226.34194)
		(width 0.1143)
		(layer "In13.Cu")
		(net "GMI_CPU0_G0_CPU1_G2_TX_DN<6>")
	)
	(segment
		(start 355.188266 -228.618288)
		(end 355.189282 -228.61778)
		(width 0.1143)
		(layer "In13.Cu")
		(net "GMI_CPU0_G0_CPU1_G2_TX_DN<6>")
	)
	(segment
		(start 355.449632 -221.303088)
		(end 355.449632 -221.145862)
		(width 0.1143)
		(layer "In13.Cu")
		(net "GMI_CPU0_G0_CPU1_G2_TX_DN<6>")
	)
	(segment
		(start 116.09197 -221.071948)
		(end 116.09197 -221.100396)
		(width 0.1143)
		(layer "In13.Cu")
		(net "GMI_CPU0_G0_CPU1_G2_TX_DN<6>")
	)
	(segment
		(start 116.04625 -221.146116)
		(end 116.04625 -221.303342)
		(width 0.1143)
		(layer "In13.Cu")
		(net "GMI_CPU0_G0_CPU1_G2_TX_DN<6>")
	)
	(segment
		(start 116.287042 -235.086398)
		(end 116.287804 -235.086906)
		(width 0.1143)
		(layer "In13.Cu")
		(net "GMI_CPU0_G0_CPU1_G2_TX_DN<6>")
	)
	(segment
		(start 355.20884 -237.682024)
		(end 355.208078 -237.681516)
		(width 0.1143)
		(layer "In13.Cu")
		(net "GMI_CPU0_G0_CPU1_G2_TX_DN<6>")
	)
	(segment
		(start 151.179276 -186.279282)
		(end 151.17953 -186.280044)
		(width 0.14224)
		(layer "In13.Cu")
		(net "GMI_CPU0_G0_CPU1_G2_TX_DN<6>")
	)
	(segment
		(start 150.849838 -186.550554)
		(end 150.84933 -186.549792)
		(width 0.14224)
		(layer "In13.Cu")
		(net "GMI_CPU0_G0_CPU1_G2_TX_DN<6>")
	)
	(segment
		(start 355.213666 -230.223314)
		(end 355.214936 -230.222552)
		(width 0.1143)
		(layer "In13.Cu")
		(net "GMI_CPU0_G0_CPU1_G2_TX_DN<6>")
	)
	(segment
		(start 355.21011 -239.302798)
		(end 355.20884 -239.302036)
		(width 0.1143)
		(layer "In13.Cu")
		(net "GMI_CPU0_G0_CPU1_G2_TX_DN<6>")
	)
	(segment
		(start 116.289328 -234.44073)
		(end 116.287042 -234.442254)
		(width 0.1143)
		(layer "In13.Cu")
		(net "GMI_CPU0_G0_CPU1_G2_TX_DN<6>")
	)
	(segment
		(start 355.169216 -227.009452)
		(end 355.205284 -226.988624)
		(width 0.1143)
		(layer "In13.Cu")
		(net "GMI_CPU0_G0_CPU1_G2_TX_DN<6>")
	)
	(segment
		(start 116.287804 -225.367088)
		(end 116.324126 -225.38817)
		(width 0.1143)
		(layer "In13.Cu")
		(net "GMI_CPU0_G0_CPU1_G2_TX_DN<6>")
	)
	(segment
		(start 148.232622 -188.69533)
		(end 148.213572 -188.88837)
		(width 0.14224)
		(layer "In13.Cu")
		(net "GMI_CPU0_G0_CPU1_G2_TX_DN<6>")
	)
	(segment
		(start 116.256054 -233.448606)
		(end 116.287042 -233.466386)
		(width 0.1143)
		(layer "In13.Cu")
		(net "GMI_CPU0_G0_CPU1_G2_TX_DN<6>")
	)
	(segment
		(start 355.209856 -224.72269)
		(end 355.208078 -224.721674)
		(width 0.1143)
		(layer "In13.Cu")
		(net "GMI_CPU0_G0_CPU1_G2_TX_DN<6>")
	)
	(segment
		(start 152.051512 -185.564018)
		(end 152.051766 -185.56478)
		(width 0.14224)
		(layer "In13.Cu")
		(net "GMI_CPU0_G0_CPU1_G2_TX_DN<6>")
	)
	(segment
		(start 116.09197 -218.226386)
		(end 116.09197 -221.071948)
		(width 0.14224)
		(layer "In13.Cu")
		(net "GMI_CPU0_G0_CPU1_G2_TX_DN<6>")
	)
	(segment
		(start 355.21011 -232.82275)
		(end 355.20884 -232.821988)
		(width 0.1143)
		(layer "In13.Cu")
		(net "GMI_CPU0_G0_CPU1_G2_TX_DN<6>")
	)
	(segment
		(start 117.11686 -241.244374)
		(end 117.414802 -241.244374)
		(width 0.1143)
		(layer "In13.Cu")
		(net "GMI_CPU0_G0_CPU1_G2_TX_DN<6>")
	)
	(segment
		(start 355.239828 -227.979986)
		(end 355.21011 -227.962968)
		(width 0.1143)
		(layer "In13.Cu")
		(net "GMI_CPU0_G0_CPU1_G2_TX_DN<6>")
	)
	(segment
		(start 355.171756 -225.387916)
		(end 355.208078 -225.366834)
		(width 0.1143)
		(layer "In13.Cu")
		(net "GMI_CPU0_G0_CPU1_G2_TX_DN<6>")
	)
	(segment
		(start 355.21011 -235.085382)
		(end 355.239828 -235.068364)
		(width 0.1143)
		(layer "In13.Cu")
		(net "GMI_CPU0_G0_CPU1_G2_TX_DN<6>")
	)
	(segment
		(start 355.208078 -230.226616)
		(end 355.20884 -230.226108)
		(width 0.1143)
		(layer "In13.Cu")
		(net "GMI_CPU0_G0_CPU1_G2_TX_DN<6>")
	)
	(segment
		(start 355.208078 -223.746822)
		(end 355.20884 -223.746314)
		(width 0.1143)
		(layer "In13.Cu")
		(net "GMI_CPU0_G0_CPU1_G2_TX_DN<6>")
	)
	(segment
		(start 148.23313 -188.696092)
		(end 148.232622 -188.69533)
		(width 0.14224)
		(layer "In13.Cu")
		(net "GMI_CPU0_G0_CPU1_G2_TX_DN<6>")
	)
	(segment
		(start 355.239828 -234.45978)
		(end 355.21011 -234.442762)
		(width 0.1143)
		(layer "In13.Cu")
		(net "GMI_CPU0_G0_CPU1_G2_TX_DN<6>")
	)
	(segment
		(start 116.290598 -233.468672)
		(end 116.326666 -233.4895)
		(width 0.1143)
		(layer "In13.Cu")
		(net "GMI_CPU0_G0_CPU1_G2_TX_DN<6>")
	)
	(segment
		(start 355.208078 -238.326676)
		(end 355.20884 -238.326168)
		(width 0.1143)
		(layer "In13.Cu")
		(net "GMI_CPU0_G0_CPU1_G2_TX_DN<6>")
	)
	(segment
		(start 146.818096 -189.855094)
		(end 146.818604 -189.855856)
		(width 0.14224)
		(layer "In13.Cu")
		(net "GMI_CPU0_G0_CPU1_G2_TX_DN<6>")
	)
	(segment
		(start 355.169216 -238.349282)
		(end 355.205284 -238.328454)
		(width 0.1143)
		(layer "In13.Cu")
		(net "GMI_CPU0_G0_CPU1_G2_TX_DN<6>")
	)
	(segment
		(start 145.946876 -190.570358)
		(end 119.768874 -212.033866)
		(width 0.14224)
		(layer "In13.Cu")
		(net "GMI_CPU0_G0_CPU1_G2_TX_DN<6>")
	)
	(segment
		(start 116.326666 -227.939346)
		(end 116.289328 -227.960936)
		(width 0.1143)
		(layer "In13.Cu")
		(net "GMI_CPU0_G0_CPU1_G2_TX_DN<6>")
	)
	(segment
		(start 116.287804 -226.34194)
		(end 116.287042 -226.342448)
		(width 0.1143)
		(layer "In13.Cu")
		(net "GMI_CPU0_G0_CPU1_G2_TX_DN<6>")
	)
	(segment
		(start 116.307362 -228.618542)
		(end 116.30914 -228.619558)
		(width 0.1143)
		(layer "In13.Cu")
		(net "GMI_CPU0_G0_CPU1_G2_TX_DN<6>")
	)
	(segment
		(start 355.395784 -221.80423)
		(end 355.395784 -221.356936)
		(width 0.1143)
		(layer "In13.Cu")
		(net "GMI_CPU0_G0_CPU1_G2_TX_DN<6>")
	)
	(segment
		(start 147.360386 -189.41034)
		(end 147.341336 -189.60338)
		(width 0.14224)
		(layer "In13.Cu")
		(net "GMI_CPU0_G0_CPU1_G2_TX_DN<6>")
	)
	(segment
		(start 355.20884 -226.986338)
		(end 355.21011 -226.985576)
		(width 0.1143)
		(layer "In13.Cu")
		(net "GMI_CPU0_G0_CPU1_G2_TX_DN<6>")
	)
	(segment
		(start 355.189282 -228.61778)
		(end 355.208078 -228.606858)
		(width 0.1143)
		(layer "In13.Cu")
		(net "GMI_CPU0_G0_CPU1_G2_TX_DN<6>")
	)
	(segment
		(start 355.21011 -228.605588)
		(end 355.239828 -228.58857)
		(width 0.1143)
		(layer "In13.Cu")
		(net "GMI_CPU0_G0_CPU1_G2_TX_DN<6>")
	)
	(segment
		(start 116.287804 -231.846882)
		(end 116.324126 -231.867964)
		(width 0.1143)
		(layer "In13.Cu")
		(net "GMI_CPU0_G0_CPU1_G2_TX_DN<6>")
	)
	(segment
		(start 355.171756 -235.107734)
		(end 355.208078 -235.086652)
		(width 0.1143)
		(layer "In13.Cu")
		(net "GMI_CPU0_G0_CPU1_G2_TX_DN<6>")
	)
	(segment
		(start 116.287042 -233.466386)
		(end 116.287804 -233.466894)
		(width 0.1143)
		(layer "In13.Cu")
		(net "GMI_CPU0_G0_CPU1_G2_TX_DN<6>")
	)
	(segment
		(start 116.287042 -239.946434)
		(end 116.287804 -239.946942)
		(width 0.1143)
		(layer "In13.Cu")
		(net "GMI_CPU0_G0_CPU1_G2_TX_DN<6>")
	)
	(segment
		(start 354.699062 -240.779554)
		(end 354.738178 -240.756694)
		(width 0.1143)
		(layer "In13.Cu")
		(net "GMI_CPU0_G0_CPU1_G2_TX_DN<6>")
	)
	(segment
		(start 116.287042 -234.442254)
		(end 116.285772 -234.443016)
		(width 0.1143)
		(layer "In13.Cu")
		(net "GMI_CPU0_G0_CPU1_G2_TX_DN<6>")
	)
	(segment
		(start 116.285772 -232.823004)
		(end 116.256054 -232.840022)
		(width 0.1143)
		(layer "In13.Cu")
		(net "GMI_CPU0_G0_CPU1_G2_TX_DN<6>")
	)
	(segment
		(start 116.256054 -225.3488)
		(end 116.287042 -225.36658)
		(width 0.1143)
		(layer "In13.Cu")
		(net "GMI_CPU0_G0_CPU1_G2_TX_DN<6>")
	)
	(segment
		(start 157.824932 -180.830728)
		(end 152.593802 -185.119518)
		(width 0.14224)
		(layer "In13.Cu")
		(net "GMI_CPU0_G0_CPU1_G2_TX_DN<6>")
	)
	(segment
		(start 116.256054 -236.68863)
		(end 116.287042 -236.70641)
		(width 0.1143)
		(layer "In13.Cu")
		(net "GMI_CPU0_G0_CPU1_G2_TX_DN<6>")
	)
	(segment
		(start 116.287804 -239.946942)
		(end 116.290598 -239.94872)
		(width 0.1143)
		(layer "In13.Cu")
		(net "GMI_CPU0_G0_CPU1_G2_TX_DN<6>")
	)
	(segment
		(start 147.690332 -189.13983)
		(end 147.69084 -189.140592)
		(width 0.14224)
		(layer "In13.Cu")
		(net "GMI_CPU0_G0_CPU1_G2_TX_DN<6>")
	)
	(segment
		(start 147.011136 -189.874144)
		(end 146.818096 -189.855094)
		(width 0.14224)
		(layer "In13.Cu")
		(net "GMI_CPU0_G0_CPU1_G2_TX_DN<6>")
	)
	(segment
		(start 116.287042 -236.70641)
		(end 116.287804 -236.706918)
		(width 0.1143)
		(layer "In13.Cu")
		(net "GMI_CPU0_G0_CPU1_G2_TX_DN<6>")
	)
	(segment
		(start 355.208078 -233.46664)
		(end 355.20884 -233.466132)
		(width 0.1143)
		(layer "In13.Cu")
		(net "GMI_CPU0_G0_CPU1_G2_TX_DN<6>")
	)
	(segment
		(start 116.354606 -227.91928)
		(end 116.326666 -227.939346)
		(width 0.1143)
		(layer "In13.Cu")
		(net "GMI_CPU0_G0_CPU1_G2_TX_DN<6>")
	)
	(segment
		(start 116.256054 -222.108776)
		(end 116.287804 -222.127064)
		(width 0.1143)
		(layer "In13.Cu")
		(net "GMI_CPU0_G0_CPU1_G2_TX_DN<6>")
	)
	(segment
		(start 355.169216 -239.969294)
		(end 355.205284 -239.948466)
		(width 0.1143)
		(layer "In13.Cu")
		(net "GMI_CPU0_G0_CPU1_G2_TX_DN<6>")
	)
	(segment
		(start 355.21011 -223.745552)
		(end 355.239828 -223.728534)
		(width 0.1143)
		(layer "In13.Cu")
		(net "GMI_CPU0_G0_CPU1_G2_TX_DN<6>")
	)
	(segment
		(start 116.290598 -238.328708)
		(end 116.326666 -238.349536)
		(width 0.1143)
		(layer "In13.Cu")
		(net "GMI_CPU0_G0_CPU1_G2_TX_DN<6>")
	)
	(segment
		(start 355.20884 -236.062012)
		(end 355.208078 -236.061504)
		(width 0.1143)
		(layer "In13.Cu")
		(net "GMI_CPU0_G0_CPU1_G2_TX_DN<6>")
	)
	(segment
		(start 116.286026 -224.722944)
		(end 116.285264 -224.723452)
		(width 0.1143)
		(layer "In13.Cu")
		(net "GMI_CPU0_G0_CPU1_G2_TX_DN<6>")
	)
	(segment
		(start 355.21011 -227.962968)
		(end 355.20884 -227.962206)
		(width 0.1143)
		(layer "In13.Cu")
		(net "GMI_CPU0_G0_CPU1_G2_TX_DN<6>")
	)
	(segment
		(start 355.208078 -226.986846)
		(end 355.20884 -226.986338)
		(width 0.1143)
		(layer "In13.Cu")
		(net "GMI_CPU0_G0_CPU1_G2_TX_DN<6>")
	)
	(segment
		(start 355.205284 -238.328454)
		(end 355.208078 -238.326676)
		(width 0.1143)
		(layer "In13.Cu")
		(net "GMI_CPU0_G0_CPU1_G2_TX_DN<6>")
	)
	(segment
		(start 355.239828 -223.11995)
		(end 355.208078 -223.101662)
		(width 0.1143)
		(layer "In13.Cu")
		(net "GMI_CPU0_G0_CPU1_G2_TX_DN<6>")
	)
	(segment
		(start 116.285772 -237.68304)
		(end 116.256054 -237.700058)
		(width 0.1143)
		(layer "In13.Cu")
		(net "GMI_CPU0_G0_CPU1_G2_TX_DN<6>")
	)
	(segment
		(start 116.287804 -236.706918)
		(end 116.324126 -236.728)
		(width 0.1143)
		(layer "In13.Cu")
		(net "GMI_CPU0_G0_CPU1_G2_TX_DN<6>")
	)
	(segment
		(start 116.04625 -221.303342)
		(end 116.100098 -221.35719)
		(width 0.1143)
		(layer "In13.Cu")
		(net "GMI_CPU0_G0_CPU1_G2_TX_DN<6>")
	)
	(segment
		(start 116.289328 -227.960936)
		(end 116.287042 -227.96246)
		(width 0.1143)
		(layer "In13.Cu")
		(net "GMI_CPU0_G0_CPU1_G2_TX_DN<6>")
	)
	(segment
		(start 116.287042 -237.682278)
		(end 116.285772 -237.68304)
		(width 0.1143)
		(layer "In13.Cu")
		(net "GMI_CPU0_G0_CPU1_G2_TX_DN<6>")
	)
	(segment
		(start 355.208078 -236.061504)
		(end 355.171756 -236.040422)
		(width 0.1143)
		(layer "In13.Cu")
		(net "GMI_CPU0_G0_CPU1_G2_TX_DN<6>")
	)
	(segment
		(start 116.09197 -221.100396)
		(end 116.04625 -221.146116)
		(width 0.1143)
		(layer "In13.Cu")
		(net "GMI_CPU0_G0_CPU1_G2_TX_DN<6>")
	)
	(segment
		(start 355.212904 -230.223822)
		(end 355.213666 -230.223314)
		(width 0.1143)
		(layer "In13.Cu")
		(net "GMI_CPU0_G0_CPU1_G2_TX_DN<6>")
	)
	(segment
		(start 355.169216 -234.418886)
		(end 355.141276 -234.39882)
		(width 0.1143)
		(layer "In13.Cu")
		(net "GMI_CPU0_G0_CPU1_G2_TX_DN<6>")
	)
	(segment
		(start 152.574752 -185.312304)
		(end 152.244552 -185.583322)
		(width 0.14224)
		(layer "In13.Cu")
		(net "GMI_CPU0_G0_CPU1_G2_TX_DN<6>")
	)
	(segment
		(start 355.208078 -226.341686)
		(end 355.171756 -226.320604)
		(width 0.1143)
		(layer "In13.Cu")
		(net "GMI_CPU0_G0_CPU1_G2_TX_DN<6>")
	)
	(segment
		(start 355.20884 -239.302036)
		(end 355.206554 -239.300512)
		(width 0.1143)
		(layer "In13.Cu")
		(net "GMI_CPU0_G0_CPU1_G2_TX_DN<6>")
	)
	(segment
		(start 351.769172 -212.20049)
		(end 316.53861 -183.312816)
		(width 0.14224)
		(layer "In13.Cu")
		(net "GMI_CPU0_G0_CPU1_G2_TX_DN<6>")
	)
	(segment
		(start 355.21011 -231.845358)
		(end 355.239828 -231.82834)
		(width 0.1143)
		(layer "In13.Cu")
		(net "GMI_CPU0_G0_CPU1_G2_TX_DN<6>")
	)
	(segment
		(start 116.287042 -230.226362)
		(end 116.287804 -230.22687)
		(width 0.1143)
		(layer "In13.Cu")
		(net "GMI_CPU0_G0_CPU1_G2_TX_DN<6>")
	)
	(segment
		(start 116.287042 -232.822242)
		(end 116.285772 -232.823004)
		(width 0.1143)
		(layer "In13.Cu")
		(net "GMI_CPU0_G0_CPU1_G2_TX_DN<6>")
	)
	(segment
		(start 116.725954 -240.73866)
		(end 116.757704 -240.756948)
		(width 0.1143)
		(layer "In13.Cu")
		(net "GMI_CPU0_G0_CPU1_G2_TX_DN<6>")
	)
	(segment
		(start 149.105366 -187.980828)
		(end 149.104858 -187.98032)
		(width 0.14224)
		(layer "In13.Cu")
		(net "GMI_CPU0_G0_CPU1_G2_TX_DN<6>")
	)
	(segment
		(start 148.213572 -188.88837)
		(end 147.883372 -189.159134)
		(width 0.14224)
		(layer "In13.Cu")
		(net "GMI_CPU0_G0_CPU1_G2_TX_DN<6>")
	)
	(segment
		(start 355.20884 -223.746314)
		(end 355.21011 -223.745552)
		(width 0.1143)
		(layer "In13.Cu")
		(net "GMI_CPU0_G0_CPU1_G2_TX_DN<6>")
	)
	(segment
		(start 355.20884 -239.94618)
		(end 355.21011 -239.945418)
		(width 0.1143)
		(layer "In13.Cu")
		(net "GMI_CPU0_G0_CPU1_G2_TX_DN<6>")
	)
	(segment
		(start 355.239828 -224.739962)
		(end 355.210618 -224.723198)
		(width 0.1143)
		(layer "In13.Cu")
		(net "GMI_CPU0_G0_CPU1_G2_TX_DN<6>")
	)
	(segment
		(start 150.83028 -186.742832)
		(end 150.50008 -187.01385)
		(width 0.14224)
		(layer "In13.Cu")
		(net "GMI_CPU0_G0_CPU1_G2_TX_DN<6>")
	)
	(segment
		(start 355.171756 -231.86771)
		(end 355.208078 -231.846628)
		(width 0.1143)
		(layer "In13.Cu")
		(net "GMI_CPU0_G0_CPU1_G2_TX_DN<6>")
	)
	(segment
		(start 355.171756 -222.147892)
		(end 355.208078 -222.12681)
		(width 0.1143)
		(layer "In13.Cu")
		(net "GMI_CPU0_G0_CPU1_G2_TX_DN<6>")
	)
	(segment
		(start 152.051766 -185.56478)
		(end 151.722074 -185.83529)
		(width 0.14224)
		(layer "In13.Cu")
		(net "GMI_CPU0_G0_CPU1_G2_TX_DN<6>")
	)
	(segment
		(start 355.169216 -239.278922)
		(end 355.141276 -239.258856)
		(width 0.1143)
		(layer "In13.Cu")
		(net "GMI_CPU0_G0_CPU1_G2_TX_DN<6>")
	)
	(segment
		(start 116.287042 -239.30229)
		(end 116.285772 -239.303052)
		(width 0.1143)
		(layer "In13.Cu")
		(net "GMI_CPU0_G0_CPU1_G2_TX_DN<6>")
	)
	(segment
		(start 116.285772 -226.34321)
		(end 116.256054 -226.360228)
		(width 0.1143)
		(layer "In13.Cu")
		(net "GMI_CPU0_G0_CPU1_G2_TX_DN<6>")
	)
	(segment
		(start 355.20884 -227.962206)
		(end 355.206554 -227.960682)
		(width 0.1143)
		(layer "In13.Cu")
		(net "GMI_CPU0_G0_CPU1_G2_TX_DN<6>")
	)
	(segment
		(start 116.757704 -240.756948)
		(end 116.79682 -240.779808)
		(width 0.1143)
		(layer "In13.Cu")
		(net "GMI_CPU0_G0_CPU1_G2_TX_DN<6>")
	)
	(segment
		(start 116.285772 -227.963222)
		(end 116.256054 -227.98024)
		(width 0.1143)
		(layer "In13.Cu")
		(net "GMI_CPU0_G0_CPU1_G2_TX_DN<6>")
	)
	(segment
		(start 146.48815 -190.125604)
		(end 146.4691 -190.318644)
		(width 0.14224)
		(layer "In13.Cu")
		(net "GMI_CPU0_G0_CPU1_G2_TX_DN<6>")
	)
	(segment
		(start 147.341336 -189.60338)
		(end 147.011136 -189.874144)
		(width 0.14224)
		(layer "In13.Cu")
		(net "GMI_CPU0_G0_CPU1_G2_TX_DN<6>")
	)
	(segment
		(start 116.287804 -228.607112)
		(end 116.3066 -228.618034)
		(width 0.1143)
		(layer "In13.Cu")
		(net "GMI_CPU0_G0_CPU1_G2_TX_DN<6>")
	)
	(segment
		(start 116.290598 -239.94872)
		(end 116.326666 -239.969548)
		(width 0.1143)
		(layer "In13.Cu")
		(net "GMI_CPU0_G0_CPU1_G2_TX_DN<6>")
	)
	(segment
		(start 147.361148 -189.411102)
		(end 147.360386 -189.41034)
		(width 0.14224)
		(layer "In13.Cu")
		(net "GMI_CPU0_G0_CPU1_G2_TX_DN<6>")
	)
	(segment
		(start 355.239828 -237.699804)
		(end 355.21011 -237.682786)
		(width 0.1143)
		(layer "In13.Cu")
		(net "GMI_CPU0_G0_CPU1_G2_TX_DN<6>")
	)
	(segment
		(start 354.379022 -241.24412)
		(end 354.461826 -241.161316)
		(width 0.1143)
		(layer "In13.Cu")
		(net "GMI_CPU0_G0_CPU1_G2_TX_DN<6>")
	)
	(segment
		(start 307.805836 -178.831748)
		(end 302.907192 -178.831748)
		(width 0.14224)
		(layer "In13.Cu")
		(net "GMI_CPU0_G0_CPU1_G2_TX_DN<6>")
	)
	(segment
		(start 355.403912 -221.100142)
		(end 355.403912 -221.093538)
		(width 0.1143)
		(layer "In13.Cu")
		(net "GMI_CPU0_G0_CPU1_G2_TX_DN<6>")
	)
	(segment
		(start 116.287804 -226.9871)
		(end 116.290598 -226.988878)
		(width 0.1143)
		(layer "In13.Cu")
		(net "GMI_CPU0_G0_CPU1_G2_TX_DN<6>")
	)
	(segment
		(start 116.287804 -222.127064)
		(end 116.324126 -222.148146)
		(width 0.1143)
		(layer "In13.Cu")
		(net "GMI_CPU0_G0_CPU1_G2_TX_DN<6>")
	)
	(segment
		(start 150.30704 -186.994546)
		(end 150.307294 -186.995308)
		(width 0.14224)
		(layer "In13.Cu")
		(net "GMI_CPU0_G0_CPU1_G2_TX_DN<6>")
	)
	(segment
		(start 355.21138 -230.224584)
		(end 355.212904 -230.223822)
		(width 0.1143)
		(layer "In13.Cu")
		(net "GMI_CPU0_G0_CPU1_G2_TX_DN<6>")
	)
	(segment
		(start 355.208078 -235.086652)
		(end 355.20884 -235.086144)
		(width 0.1143)
		(layer "In13.Cu")
		(net "GMI_CPU0_G0_CPU1_G2_TX_DN<6>")
	)
	(segment
		(start 116.287804 -231.201976)
		(end 116.254276 -231.221534)
		(width 0.1143)
		(layer "In13.Cu")
		(net "GMI_CPU0_G0_CPU1_G2_TX_DN<6>")
	)
	(segment
		(start 151.702516 -186.027568)
		(end 151.372316 -186.298586)
		(width 0.14224)
		(layer "In13.Cu")
		(net "GMI_CPU0_G0_CPU1_G2_TX_DN<6>")
	)
	(segment
		(start 116.324126 -224.700846)
		(end 116.287804 -224.721928)
		(width 0.1143)
		(layer "In13.Cu")
		(net "GMI_CPU0_G0_CPU1_G2_TX_DN<6>")
	)
	(segment
		(start 355.239828 -239.319816)
		(end 355.21011 -239.302798)
		(width 0.1143)
		(layer "In13.Cu")
		(net "GMI_CPU0_G0_CPU1_G2_TX_DN<6>")
	)
	(segment
		(start 355.241606 -229.601268)
		(end 355.186742 -229.569264)
		(width 0.1143)
		(layer "In13.Cu")
		(net "GMI_CPU0_G0_CPU1_G2_TX_DN<6>")
	)
	(segment
		(start 355.217476 -230.221282)
		(end 355.239828 -230.208328)
		(width 0.1143)
		(layer "In13.Cu")
		(net "GMI_CPU0_G0_CPU1_G2_TX_DN<6>")
	)
	(segment
		(start 355.208078 -232.82148)
		(end 355.171756 -232.800398)
		(width 0.1143)
		(layer "In13.Cu")
		(net "GMI_CPU0_G0_CPU1_G2_TX_DN<6>")
	)
	(segment
		(start 149.958044 -187.458096)
		(end 149.627844 -187.729114)
		(width 0.14224)
		(layer "In13.Cu")
		(net "GMI_CPU0_G0_CPU1_G2_TX_DN<6>")
	)
	(segment
		(start 116.326666 -238.349536)
		(end 116.354606 -238.369602)
		(width 0.1143)
		(layer "In13.Cu")
		(net "GMI_CPU0_G0_CPU1_G2_TX_DN<6>")
	)
	(segment
		(start 151.722074 -185.83529)
		(end 151.721566 -185.834528)
		(width 0.14224)
		(layer "In13.Cu")
		(net "GMI_CPU0_G0_CPU1_G2_TX_DN<6>")
	)
	(segment
		(start 355.210618 -224.723198)
		(end 355.209856 -224.72269)
		(width 0.1143)
		(layer "In13.Cu")
		(net "GMI_CPU0_G0_CPU1_G2_TX_DN<6>")
	)
	(segment
		(start 116.285264 -224.723452)
		(end 116.256054 -224.740216)
		(width 0.1143)
		(layer "In13.Cu")
		(net "GMI_CPU0_G0_CPU1_G2_TX_DN<6>")
	)
	(segment
		(start 152.244552 -185.583322)
		(end 152.051512 -185.564018)
		(width 0.14224)
		(layer "In13.Cu")
		(net "GMI_CPU0_G0_CPU1_G2_TX_DN<6>")
	)
	(segment
		(start 116.326666 -239.279176)
		(end 116.289328 -239.300766)
		(width 0.1143)
		(layer "In13.Cu")
		(net "GMI_CPU0_G0_CPU1_G2_TX_DN<6>")
	)
	(segment
		(start 116.256054 -231.828594)
		(end 116.287042 -231.846374)
		(width 0.1143)
		(layer "In13.Cu")
		(net "GMI_CPU0_G0_CPU1_G2_TX_DN<6>")
	)
	(segment
		(start 355.208078 -236.706664)
		(end 355.20884 -236.706156)
		(width 0.1143)
		(layer "In13.Cu")
		(net "GMI_CPU0_G0_CPU1_G2_TX_DN<6>")
	)
	(segment
		(start 116.28755 -230.227124)
		(end 116.288312 -230.227632)
		(width 0.1143)
		(layer "In13.Cu")
		(net "GMI_CPU0_G0_CPU1_G2_TX_DN<6>")
	)
	(segment
		(start 355.205284 -239.948466)
		(end 355.208078 -239.946688)
		(width 0.1143)
		(layer "In13.Cu")
		(net "GMI_CPU0_G0_CPU1_G2_TX_DN<6>")
	)
	(segment
		(start 116.287042 -238.326422)
		(end 116.287804 -238.32693)
		(width 0.1143)
		(layer "In13.Cu")
		(net "GMI_CPU0_G0_CPU1_G2_TX_DN<6>")
	)
	(segment
		(start 355.20884 -231.84612)
		(end 355.21011 -231.845358)
		(width 0.1143)
		(layer "In13.Cu")
		(net "GMI_CPU0_G0_CPU1_G2_TX_DN<6>")
	)
	(segment
		(start 116.287042 -236.062266)
		(end 116.285772 -236.063028)
		(width 0.1143)
		(layer "In13.Cu")
		(net "GMI_CPU0_G0_CPU1_G2_TX_DN<6>")
	)
	(segment
		(start 116.256054 -235.068618)
		(end 116.287042 -235.086398)
		(width 0.1143)
		(layer "In13.Cu")
		(net "GMI_CPU0_G0_CPU1_G2_TX_DN<6>")
	)
	(segment
		(start 116.324126 -223.080834)
		(end 116.287804 -223.101916)
		(width 0.1143)
		(layer "In13.Cu")
		(net "GMI_CPU0_G0_CPU1_G2_TX_DN<6>")
	)
	(segment
		(start 119.768874 -212.033866)
		(end 116.09197 -218.226386)
		(width 0.14224)
		(layer "In13.Cu")
		(net "GMI_CPU0_G0_CPU1_G2_TX_DN<6>")
	)
	(segment
		(start 355.141276 -227.029518)
		(end 355.169216 -227.009452)
		(width 0.1143)
		(layer "In13.Cu")
		(net "GMI_CPU0_G0_CPU1_G2_TX_DN<6>")
	)
	(segment
		(start 151.372316 -186.298586)
		(end 151.179276 -186.279282)
		(width 0.14224)
		(layer "In13.Cu")
		(net "GMI_CPU0_G0_CPU1_G2_TX_DN<6>")
	)
	(segment
		(start 355.141276 -238.369348)
		(end 355.169216 -238.349282)
		(width 0.1143)
		(layer "In13.Cu")
		(net "GMI_CPU0_G0_CPU1_G2_TX_DN<6>")
	)
	(segment
		(start 116.324126 -231.180894)
		(end 116.287804 -231.201976)
		(width 0.1143)
		(layer "In13.Cu")
		(net "GMI_CPU0_G0_CPU1_G2_TX_DN<6>")
	)
	(segment
		(start 355.186742 -228.619304)
		(end 355.188266 -228.618288)
		(width 0.1143)
		(layer "In13.Cu")
		(net "GMI_CPU0_G0_CPU1_G2_TX_DN<6>")
	)
	(segment
		(start 116.256054 -228.588824)
		(end 116.287042 -228.606604)
		(width 0.1143)
		(layer "In13.Cu")
		(net "GMI_CPU0_G0_CPU1_G2_TX_DN<6>")
	)
	(segment
		(start 355.205284 -233.468418)
		(end 355.208078 -233.46664)
		(width 0.1143)
		(layer "In13.Cu")
		(net "GMI_CPU0_G0_CPU1_G2_TX_DN<6>")
	)
	(segment
		(start 147.883372 -189.159134)
		(end 147.690332 -189.13983)
		(width 0.14224)
		(layer "In13.Cu")
		(net "GMI_CPU0_G0_CPU1_G2_TX_DN<6>")
	)
	(segment
		(start 116.354606 -234.399074)
		(end 116.326666 -234.41914)
		(width 0.1143)
		(layer "In13.Cu")
		(net "GMI_CPU0_G0_CPU1_G2_TX_DN<6>")
	)
	(segment
		(start 355.206554 -234.440476)
		(end 355.169216 -234.418886)
		(width 0.1143)
		(layer "In13.Cu")
		(net "GMI_CPU0_G0_CPU1_G2_TX_DN<6>")
	)
	(segment
		(start 355.20884 -228.60635)
		(end 355.21011 -228.605588)
		(width 0.1143)
		(layer "In13.Cu")
		(net "GMI_CPU0_G0_CPU1_G2_TX_DN<6>")
	)
	(segment
		(start 150.50008 -187.01385)
		(end 150.30704 -186.994546)
		(width 0.14224)
		(layer "In13.Cu")
		(net "GMI_CPU0_G0_CPU1_G2_TX_DN<6>")
	)
	(segment
		(start 355.208078 -225.366834)
		(end 355.20884 -225.366326)
		(width 0.1143)
		(layer "In13.Cu")
		(net "GMI_CPU0_G0_CPU1_G2_TX_DN<6>")
	)
	(segment
		(start 116.287804 -237.68177)
		(end 116.287042 -237.682278)
		(width 0.1143)
		(layer "In13.Cu")
		(net "GMI_CPU0_G0_CPU1_G2_TX_DN<6>")
	)
	(segment
		(start 355.403912 -221.093538)
		(end 355.403912 -218.32189)
		(width 0.14224)
		(layer "In13.Cu")
		(net "GMI_CPU0_G0_CPU1_G2_TX_DN<6>")
	)
	(segment
		(start 355.239828 -236.079792)
		(end 355.21011 -236.062774)
		(width 0.1143)
		(layer "In13.Cu")
		(net "GMI_CPU0_G0_CPU1_G2_TX_DN<6>")
	)
	(segment
		(start 355.20884 -234.442)
		(end 355.206554 -234.440476)
		(width 0.1143)
		(layer "In13.Cu")
		(net "GMI_CPU0_G0_CPU1_G2_TX_DN<6>")
	)
	(segment
		(start 116.287042 -231.846374)
		(end 116.287804 -231.846882)
		(width 0.1143)
		(layer "In13.Cu")
		(net "GMI_CPU0_G0_CPU1_G2_TX_DN<6>")
	)
	(segment
		(start 355.20884 -238.326168)
		(end 355.21011 -238.325406)
		(width 0.1143)
		(layer "In13.Cu")
		(net "GMI_CPU0_G0_CPU1_G2_TX_DN<6>")
	)
	(segment
		(start 355.208078 -223.101662)
		(end 355.171756 -223.08058)
		(width 0.1143)
		(layer "In13.Cu")
		(net "GMI_CPU0_G0_CPU1_G2_TX_DN<6>")
	)
	(segment
		(start 151.17953 -186.280044)
		(end 150.849838 -186.550554)
		(width 0.14224)
		(layer "In13.Cu")
		(net "GMI_CPU0_G0_CPU1_G2_TX_DN<6>")
	)
	(segment
		(start 149.435058 -187.710318)
		(end 149.105366 -187.980828)
		(width 0.14224)
		(layer "In13.Cu")
		(net "GMI_CPU0_G0_CPU1_G2_TX_DN<6>")
	)
	(segment
		(start 116.285772 -239.303052)
		(end 116.256054 -239.32007)
		(width 0.1143)
		(layer "In13.Cu")
		(net "GMI_CPU0_G0_CPU1_G2_TX_DN<6>")
	)
	(segment
		(start 116.324126 -236.040676)
		(end 116.287804 -236.061758)
		(width 0.1143)
		(layer "In13.Cu")
		(net "GMI_CPU0_G0_CPU1_G2_TX_DN<6>")
	)
	(segment
		(start 355.20884 -236.706156)
		(end 355.21011 -236.705394)
		(width 0.1143)
		(layer "In13.Cu")
		(net "GMI_CPU0_G0_CPU1_G2_TX_DN<6>")
	)
	(segment
		(start 355.208078 -222.12681)
		(end 355.239828 -222.108522)
		(width 0.1143)
		(layer "In13.Cu")
		(net "GMI_CPU0_G0_CPU1_G2_TX_DN<6>")
	)
	(segment
		(start 355.20884 -233.466132)
		(end 355.21011 -233.46537)
		(width 0.1143)
		(layer "In13.Cu")
		(net "GMI_CPU0_G0_CPU1_G2_TX_DN<6>")
	)
	(segment
		(start 355.403912 -218.32189)
		(end 351.769172 -212.20049)
		(width 0.14224)
		(layer "In13.Cu")
		(net "GMI_CPU0_G0_CPU1_G2_TX_DN<6>")
	)
	(segment
		(start 355.239828 -232.839768)
		(end 355.21011 -232.82275)
		(width 0.1143)
		(layer "In13.Cu")
		(net "GMI_CPU0_G0_CPU1_G2_TX_DN<6>")
	)
	(segment
		(start 116.287042 -223.746568)
		(end 116.287804 -223.747076)
		(width 0.1143)
		(layer "In13.Cu")
		(net "GMI_CPU0_G0_CPU1_G2_TX_DN<6>")
	)
	(segment
		(start 355.21011 -237.682786)
		(end 355.20884 -237.682024)
		(width 0.1143)
		(layer "In13.Cu")
		(net "GMI_CPU0_G0_CPU1_G2_TX_DN<6>")
	)
	(segment
		(start 149.977094 -187.265056)
		(end 149.958044 -187.458096)
		(width 0.14224)
		(layer "In13.Cu")
		(net "GMI_CPU0_G0_CPU1_G2_TX_DN<6>")
	)
	(segment
		(start 355.21011 -236.705394)
		(end 355.239828 -236.688376)
		(width 0.1143)
		(layer "In13.Cu")
		(net "GMI_CPU0_G0_CPU1_G2_TX_DN<6>")
	)
	(segment
		(start 116.354606 -239.25911)
		(end 116.326666 -239.279176)
		(width 0.1143)
		(layer "In13.Cu")
		(net "GMI_CPU0_G0_CPU1_G2_TX_DN<6>")
	)
	(segment
		(start 355.141276 -233.509312)
		(end 355.169216 -233.489246)
		(width 0.1143)
		(layer "In13.Cu")
		(net "GMI_CPU0_G0_CPU1_G2_TX_DN<6>")
	)
	(segment
		(start 116.251736 -225.345752)
		(end 116.256054 -225.3488)
		(width 0.1143)
		(layer "In13.Cu")
		(net "GMI_CPU0_G0_CPU1_G2_TX_DN<6>")
	)
	(segment
		(start 116.287804 -238.32693)
		(end 116.290598 -238.328708)
		(width 0.1143)
		(layer "In13.Cu")
		(net "GMI_CPU0_G0_CPU1_G2_TX_DN<6>")
	)
	(segment
		(start 116.326666 -234.41914)
		(end 116.289328 -234.44073)
		(width 0.1143)
		(layer "In13.Cu")
		(net "GMI_CPU0_G0_CPU1_G2_TX_DN<6>")
	)
	(segment
		(start 355.208078 -228.606858)
		(end 355.20884 -228.60635)
		(width 0.1143)
		(layer "In13.Cu")
		(net "GMI_CPU0_G0_CPU1_G2_TX_DN<6>")
	)
	(segment
		(start 116.287804 -223.747076)
		(end 116.324126 -223.768158)
		(width 0.1143)
		(layer "In13.Cu")
		(net "GMI_CPU0_G0_CPU1_G2_TX_DN<6>")
	)
	(segment
		(start 116.287804 -230.22687)
		(end 116.28755 -230.227124)
		(width 0.1143)
		(layer "In13.Cu")
		(net "GMI_CPU0_G0_CPU1_G2_TX_DN<6>")
	)
	(segment
		(start 116.287804 -232.821734)
		(end 116.287042 -232.822242)
		(width 0.1143)
		(layer "In13.Cu")
		(net "GMI_CPU0_G0_CPU1_G2_TX_DN<6>")
	)
	(segment
		(start 116.326666 -227.009706)
		(end 116.354606 -227.029772)
		(width 0.1143)
		(layer "In13.Cu")
		(net "GMI_CPU0_G0_CPU1_G2_TX_DN<6>")
	)
	(segment
		(start 355.206554 -227.960682)
		(end 355.169216 -227.939092)
		(width 0.1143)
		(layer "In13.Cu")
		(net "GMI_CPU0_G0_CPU1_G2_TX_DN<6>")
	)
	(segment
		(start 146.1389 -190.589408)
		(end 145.946876 -190.570358)
		(width 0.14224)
		(layer "In13.Cu")
		(net "GMI_CPU0_G0_CPU1_G2_TX_DN<6>")
	)
	(segment
		(start 146.488658 -190.126366)
		(end 146.48815 -190.125604)
		(width 0.14224)
		(layer "In13.Cu")
		(net "GMI_CPU0_G0_CPU1_G2_TX_DN<6>")
	)
	(segment
		(start 316.53861 -183.312816)
		(end 310.023256 -179.624482)
		(width 0.14224)
		(layer "In13.Cu")
		(net "GMI_CPU0_G0_CPU1_G2_TX_DN<6>")
	)
	(segment
		(start 355.169216 -227.939092)
		(end 355.141276 -227.919026)
		(width 0.1143)
		(layer "In13.Cu")
		(net "GMI_CPU0_G0_CPU1_G2_TX_DN<6>")
	)
	(segment
		(start 150.84933 -186.549792)
		(end 150.83028 -186.742832)
		(width 0.14224)
		(layer "In13.Cu")
		(net "GMI_CPU0_G0_CPU1_G2_TX_DN<6>")
	)
	(segment
		(start 355.21011 -239.945418)
		(end 355.239828 -239.9284)
		(width 0.1143)
		(layer "In13.Cu")
		(net "GMI_CPU0_G0_CPU1_G2_TX_DN<6>")
	)
	(segment
		(start 148.562568 -188.42482)
		(end 148.563076 -188.425582)
		(width 0.14224)
		(layer "In13.Cu")
		(net "GMI_CPU0_G0_CPU1_G2_TX_DN<6>")
	)
	(segment
		(start 116.256054 -230.208582)
		(end 116.287042 -230.226362)
		(width 0.1143)
		(layer "In13.Cu")
		(net "GMI_CPU0_G0_CPU1_G2_TX_DN<6>")
	)
	(segment
		(start 116.287804 -235.086906)
		(end 116.324126 -235.107988)
		(width 0.1143)
		(layer "In13.Cu")
		(net "GMI_CPU0_G0_CPU1_G2_TX_DN<6>")
	)
	(segment
		(start 355.205284 -226.988624)
		(end 355.208078 -226.986846)
		(width 0.1143)
		(layer "In13.Cu")
		(net "GMI_CPU0_G0_CPU1_G2_TX_DN<6>")
	)
	(segment
		(start 355.169216 -233.489246)
		(end 355.205284 -233.468418)
		(width 0.1143)
		(layer "In13.Cu")
		(net "GMI_CPU0_G0_CPU1_G2_TX_DN<6>")
	)
	(segment
		(start 116.287042 -226.342448)
		(end 116.285772 -226.34321)
		(width 0.1143)
		(layer "In13.Cu")
		(net "GMI_CPU0_G0_CPU1_G2_TX_DN<6>")
	)
	(segment
		(start 116.287804 -224.721928)
		(end 116.286026 -224.722944)
		(width 0.1143)
		(layer "In13.Cu")
		(net "GMI_CPU0_G0_CPU1_G2_TX_DN<6>")
	)
	(segment
		(start 355.395784 -221.356936)
		(end 355.449632 -221.303088)
		(width 0.1143)
		(layer "In13.Cu")
		(net "GMI_CPU0_G0_CPU1_G2_TX_DN<6>")
	)
	(segment
		(start 149.977602 -187.265818)
		(end 149.977094 -187.265056)
		(width 0.14224)
		(layer "In13.Cu")
		(net "GMI_CPU0_G0_CPU1_G2_TX_DN<6>")
	)
	(segment
		(start 116.569998 -240.432336)
		(end 116.569998 -240.435384)
		(width 0.1143)
		(layer "In13.Cu")
		(net "GMI_CPU0_G0_CPU1_G2_TX_DN<6>")
	)
	(segment
		(start 355.241606 -231.22128)
		(end 355.208078 -231.201722)
		(width 0.1143)
		(layer "In13.Cu")
		(net "GMI_CPU0_G0_CPU1_G2_TX_DN<6>")
	)
	(segment
		(start 116.285772 -236.063028)
		(end 116.256054 -236.080046)
		(width 0.1143)
		(layer "In13.Cu")
		(net "GMI_CPU0_G0_CPU1_G2_TX_DN<6>")
	)
	(segment
		(start 116.287042 -225.36658)
		(end 116.287804 -225.367088)
		(width 0.1143)
		(layer "In13.Cu")
		(net "GMI_CPU0_G0_CPU1_G2_TX_DN<6>")
	)
	(segment
		(start 355.20884 -232.821988)
		(end 355.208078 -232.82148)
		(width 0.1143)
		(layer "In13.Cu")
		(net "GMI_CPU0_G0_CPU1_G2_TX_DN<6>")
	)
	(segment
		(start 147.69084 -189.140592)
		(end 147.361148 -189.411102)
		(width 0.14224)
		(layer "In13.Cu")
		(net "GMI_CPU0_G0_CPU1_G2_TX_DN<6>")
	)
	(segment
		(start 355.214936 -230.222552)
		(end 355.217476 -230.221282)
		(width 0.1143)
		(layer "In13.Cu")
		(net "GMI_CPU0_G0_CPU1_G2_TX_DN<6>")
	)
	(segment
		(start 355.239828 -225.348546)
		(end 355.244146 -225.345498)
		(width 0.1143)
		(layer "In13.Cu")
		(net "GMI_CPU0_G0_CPU1_G2_TX_DN<6>")
	)
	(segment
		(start 355.21011 -236.062774)
		(end 355.20884 -236.062012)
		(width 0.1143)
		(layer "In13.Cu")
		(net "GMI_CPU0_G0_CPU1_G2_TX_DN<6>")
	)
	(segment
		(start 116.324126 -237.660688)
		(end 116.287804 -237.68177)
		(width 0.1143)
		(layer "In13.Cu")
		(net "GMI_CPU0_G0_CPU1_G2_TX_DN<6>")
	)
	(segment
		(start 116.287042 -226.986592)
		(end 116.287804 -226.9871)
		(width 0.1143)
		(layer "In13.Cu")
		(net "GMI_CPU0_G0_CPU1_G2_TX_DN<6>")
	)
	(segment
		(start 116.287804 -236.061758)
		(end 116.287042 -236.062266)
		(width 0.1143)
		(layer "In13.Cu")
		(net "GMI_CPU0_G0_CPU1_G2_TX_DN<6>")
	)
	(segment
		(start 116.3066 -228.618034)
		(end 116.307362 -228.618542)
		(width 0.1143)
		(layer "In13.Cu")
		(net "GMI_CPU0_G0_CPU1_G2_TX_DN<6>")
	)
	(segment
		(start 148.563076 -188.425582)
		(end 148.23313 -188.696092)
		(width 0.14224)
		(layer "In13.Cu")
		(net "GMI_CPU0_G0_CPU1_G2_TX_DN<6>")
	)
	(segment
		(start 355.21011 -226.342956)
		(end 355.20884 -226.342194)
		(width 0.1143)
		(layer "In13.Cu")
		(net "GMI_CPU0_G0_CPU1_G2_TX_DN<6>")
	)
	(segment
		(start 116.289328 -239.300766)
		(end 116.287042 -239.30229)
		(width 0.1143)
		(layer "In13.Cu")
		(net "GMI_CPU0_G0_CPU1_G2_TX_DN<6>")
	)
	(segment
		(start 116.256054 -223.728788)
		(end 116.287042 -223.746568)
		(width 0.1143)
		(layer "In13.Cu")
		(net "GMI_CPU0_G0_CPU1_G2_TX_DN<6>")
	)
	(segment
		(start 116.290598 -226.988878)
		(end 116.326666 -227.009706)
		(width 0.1143)
		(layer "In13.Cu")
		(net "GMI_CPU0_G0_CPU1_G2_TX_DN<6>")
	)
	(segment
		(start 355.208078 -231.201722)
		(end 355.171756 -231.18064)
		(width 0.1143)
		(layer "In13.Cu")
		(net "GMI_CPU0_G0_CPU1_G2_TX_DN<6>")
	)
	(segment
		(start 355.21011 -238.325406)
		(end 355.239828 -238.308388)
		(width 0.1143)
		(layer "In13.Cu")
		(net "GMI_CPU0_G0_CPU1_G2_TX_DN<6>")
	)
	(segment
		(start 355.208078 -239.946688)
		(end 355.20884 -239.94618)
		(width 0.1143)
		(layer "In13.Cu")
		(net "GMI_CPU0_G0_CPU1_G2_TX_DN<6>")
	)
	(segment
		(start 116.287042 -228.606604)
		(end 116.287804 -228.607112)
		(width 0.1143)
		(layer "In13.Cu")
		(net "GMI_CPU0_G0_CPU1_G2_TX_DN<6>")
	)
	(segment
		(start 355.171756 -236.727746)
		(end 355.208078 -236.706664)
		(width 0.1143)
		(layer "In13.Cu")
		(net "GMI_CPU0_G0_CPU1_G2_TX_DN<6>")
	)
	(segment
		(start 355.20757 -230.227378)
		(end 355.208332 -230.22687)
		(width 0.1143)
		(layer "In13.Cu")
		(net "GMI_CPU0_G0_CPU1_G2_TX_DN<6>")
	)
	(segment
		(start 148.755608 -188.444124)
		(end 148.562568 -188.42482)
		(width 0.14224)
		(layer "In13.Cu")
		(net "GMI_CPU0_G0_CPU1_G2_TX_DN<6>")
	)
	(segment
		(start 355.20884 -226.342194)
		(end 355.208078 -226.341686)
		(width 0.1143)
		(layer "In13.Cu")
		(net "GMI_CPU0_G0_CPU1_G2_TX_DN<6>")
	)
	(segment
		(start 355.20884 -225.366326)
		(end 355.239828 -225.348546)
		(width 0.1143)
		(layer "In13.Cu")
		(net "GMI_CPU0_G0_CPU1_G2_TX_DN<6>")
	)
	(segment
		(start 116.100098 -221.35719)
		(end 116.100098 -221.804484)
		(width 0.1143)
		(layer "In13.Cu")
		(net "GMI_CPU0_G0_CPU1_G2_TX_DN<6>")
	)
	(segment
		(start 116.287804 -233.466894)
		(end 116.290598 -233.468672)
		(width 0.1143)
		(layer "In13.Cu")
		(net "GMI_CPU0_G0_CPU1_G2_TX_DN<6>")
	)
	(segment
		(start 355.208078 -231.846628)
		(end 355.20884 -231.84612)
		(width 0.1143)
		(layer "In13.Cu")
		(net "GMI_CPU0_G0_CPU1_G2_TX_DN<6>")
	)
	(segment
		(start 117.034056 -241.16157)
		(end 117.11686 -241.244374)
		(width 0.1143)
		(layer "In13.Cu")
		(net "GMI_CPU0_G0_CPU1_G2_TX_DN<6>")
	)
	(segment
		(start 116.256054 -239.928654)
		(end 116.287042 -239.946434)
		(width 0.1143)
		(layer "In13.Cu")
		(net "GMI_CPU0_G0_CPU1_G2_TX_DN<6>")
	)
	(segment
		(start 116.326666 -233.4895)
		(end 116.354606 -233.509566)
		(width 0.1143)
		(layer "In13.Cu")
		(net "GMI_CPU0_G0_CPU1_G2_TX_DN<6>")
	)
	(segment
		(start 355.449632 -221.145862)
		(end 355.403912 -221.100142)
		(width 0.1143)
		(layer "In13.Cu")
		(net "GMI_CPU0_G0_CPU1_G2_TX_DN<6>")
	)
	(segment
		(start 116.326666 -239.969548)
		(end 116.336318 -239.976406)
		(width 0.1143)
		(layer "In13.Cu")
		(net "GMI_CPU0_G0_CPU1_G2_TX_DN<6>")
	)
	(segment
		(start 355.206554 -239.300512)
		(end 355.169216 -239.278922)
		(width 0.1143)
		(layer "In13.Cu")
		(net "GMI_CPU0_G0_CPU1_G2_TX_DN<6>")
	)
	(segment
		(start 152.593802 -185.119518)
		(end 152.574752 -185.312304)
		(width 0.14224)
		(layer "In13.Cu")
		(net "GMI_CPU0_G0_CPU1_G2_TX_DN<6>")
	)
	(segment
		(start 355.20884 -235.086144)
		(end 355.21011 -235.085382)
		(width 0.1143)
		(layer "In13.Cu")
		(net "GMI_CPU0_G0_CPU1_G2_TX_DN<6>")
	)
	(segment
		(start 149.627844 -187.729114)
		(end 149.434804 -187.70981)
		(width 0.14224)
		(layer "In13.Cu")
		(net "GMI_CPU0_G0_CPU1_G2_TX_DN<6>")
	)
	(segment
		(start 151.721566 -185.834528)
		(end 151.702516 -186.027568)
		(width 0.14224)
		(layer "In13.Cu")
		(net "GMI_CPU0_G0_CPU1_G2_TX_DN<6>")
	)
	(segment
		(start 355.239828 -226.359974)
		(end 355.21011 -226.342956)
		(width 0.1143)
		(layer "In13.Cu")
		(net "GMI_CPU0_G0_CPU1_G2_TX_DN<6>")
	)
	(segment
		(start 354.925884 -240.43513)
		(end 354.925884 -240.432082)
		(width 0.1143)
		(layer "In13.Cu")
		(net "GMI_CPU0_G0_CPU1_G2_TX_DN<6>")
	)
	(segment
		(start 354.08108 -241.24412)
		(end 354.379022 -241.24412)
		(width 0.1143)
		(layer "In13.Cu")
		(net "GMI_CPU0_G0_CPU1_G2_TX_DN<6>")
	)
	(segment
		(start 150.307294 -186.995308)
		(end 149.977602 -187.265818)
		(width 0.14224)
		(layer "In13.Cu")
		(net "GMI_CPU0_G0_CPU1_G2_TX_DN<6>")
	)
	(segment
		(start 355.244146 -224.74301)
		(end 355.239828 -224.739962)
		(width 0.1143)
		(layer "In13.Cu")
		(net "GMI_CPU0_G0_CPU1_G2_TX_DN<6>")
	)
	(segment
		(start 116.256054 -224.740216)
		(end 116.251736 -224.743264)
		(width 0.1143)
		(layer "In13.Cu")
		(net "GMI_CPU0_G0_CPU1_G2_TX_DN<6>")
	)
	(segment
		(start 146.818604 -189.855856)
		(end 146.488658 -190.126366)
		(width 0.14224)
		(layer "In13.Cu")
		(net "GMI_CPU0_G0_CPU1_G2_TX_DN<6>")
	)
	(segment
		(start 116.287042 -227.96246)
		(end 116.285772 -227.963222)
		(width 0.1143)
		(layer "In13.Cu")
		(net "GMI_CPU0_G0_CPU1_G2_TX_DN<6>")
	)
	(segment
		(start 354.738178 -240.756694)
		(end 354.769928 -240.738406)
		(width 0.1143)
		(layer "In13.Cu")
		(net "GMI_CPU0_G0_CPU1_G2_TX_DN<6>")
	)
	(segment
		(start 116.256054 -238.308642)
		(end 116.287042 -238.326422)
		(width 0.1143)
		(layer "In13.Cu")
		(net "GMI_CPU0_G0_CPU1_G2_TX_DN<6>")
	)
	(segment
		(start 355.208332 -230.22687)
		(end 355.208078 -230.226616)
		(width 0.1143)
		(layer "In13.Cu")
		(net "GMI_CPU0_G0_CPU1_G2_TX_DN<6>")
	)
	(segment
		(start 355.21011 -226.985576)
		(end 355.239828 -226.968558)
		(width 0.1143)
		(layer "In13.Cu")
		(net "GMI_CPU0_G0_CPU1_G2_TX_DN<6>")
	)
	(segment
		(start 116.256054 -226.968812)
		(end 116.287042 -226.986592)
		(width 0.1143)
		(layer "In13.Cu")
		(net "GMI_CPU0_G0_CPU1_G2_TX_DN<6>")
	)
	(segment
		(start 165.65626 -178.030886)
		(end 157.824932 -180.830728)
		(width 0.14224)
		(layer "In13.Cu")
		(net "GMI_CPU0_G0_CPU1_G2_TX_DN<6>")
	)
	(segment
		(start 355.21011 -233.46537)
		(end 355.239828 -233.448352)
		(width 0.1143)
		(layer "In13.Cu")
		(net "GMI_CPU0_G0_CPU1_G2_TX_DN<6>")
	)
	(arc
		(start 116.256054 -234.460034)
		(mid 116.100126 -234.764326)
		(end 116.256054 -235.068618)
		(width 0.1143)
		(layer "In13.Cu")
		(net "GMI_CPU0_G0_CPU1_G2_TX_DN<6>")
	)
	(arc
		(start 355.171756 -236.040422)
		(mid 355.164606 -236.035524)
		(end 355.157532 -236.030516)
		(width 0.1143)
		(layer "In13.Cu")
		(net "GMI_CPU0_G0_CPU1_G2_TX_DN<6>")
	)
	(arc
		(start 116.354606 -227.029772)
		(mid 116.582606 -227.474526)
		(end 116.354606 -227.91928)
		(width 0.1143)
		(layer "In13.Cu")
		(net "GMI_CPU0_G0_CPU1_G2_TX_DN<6>")
	)
	(arc
		(start 355.157532 -237.650528)
		(mid 354.930048 -237.19409)
		(end 355.157532 -236.737652)
		(width 0.1143)
		(layer "In13.Cu")
		(net "GMI_CPU0_G0_CPU1_G2_TX_DN<6>")
	)
	(arc
		(start 355.239828 -239.9284)
		(mid 355.395756 -239.624108)
		(end 355.239828 -239.319816)
		(width 0.1143)
		(layer "In13.Cu")
		(net "GMI_CPU0_G0_CPU1_G2_TX_DN<6>")
	)
	(arc
		(start 355.239828 -233.448352)
		(mid 355.395756 -233.14406)
		(end 355.239828 -232.839768)
		(width 0.1143)
		(layer "In13.Cu")
		(net "GMI_CPU0_G0_CPU1_G2_TX_DN<6>")
	)
	(arc
		(start 116.288312 -230.227632)
		(mid 116.494534 -230.433276)
		(end 116.569998 -230.71455)
		(width 0.1143)
		(layer "In13.Cu")
		(net "GMI_CPU0_G0_CPU1_G2_TX_DN<6>")
	)
	(arc
		(start 116.33835 -223.070928)
		(mid 116.331276 -223.075935)
		(end 116.324126 -223.080834)
		(width 0.1143)
		(layer "In13.Cu")
		(net "GMI_CPU0_G0_CPU1_G2_TX_DN<6>")
	)
	(arc
		(start 116.33835 -235.117894)
		(mid 116.565834 -235.574332)
		(end 116.33835 -236.03077)
		(width 0.1143)
		(layer "In13.Cu")
		(net "GMI_CPU0_G0_CPU1_G2_TX_DN<6>")
	)
	(arc
		(start 355.395784 -231.524048)
		(mid 355.355022 -231.354164)
		(end 355.241606 -231.22128)
		(width 0.1143)
		(layer "In13.Cu")
		(net "GMI_CPU0_G0_CPU1_G2_TX_DN<6>")
	)
	(arc
		(start 355.239828 -231.82834)
		(mid 355.354504 -231.695006)
		(end 355.395784 -231.524048)
		(width 0.1143)
		(layer "In13.Cu")
		(net "GMI_CPU0_G0_CPU1_G2_TX_DN<6>")
	)
	(arc
		(start 116.100098 -229.90429)
		(mid 116.141353 -230.075261)
		(end 116.256054 -230.208582)
		(width 0.1143)
		(layer "In13.Cu")
		(net "GMI_CPU0_G0_CPU1_G2_TX_DN<6>")
	)
	(arc
		(start 354.925884 -240.436146)
		(mid 354.925884 -240.435638)
		(end 354.925884 -240.43513)
		(width 0.1143)
		(layer "In13.Cu")
		(net "GMI_CPU0_G0_CPU1_G2_TX_DN<6>")
	)
	(arc
		(start 116.100098 -221.804484)
		(mid 116.141353 -221.975455)
		(end 116.256054 -222.108776)
		(width 0.1143)
		(layer "In13.Cu")
		(net "GMI_CPU0_G0_CPU1_G2_TX_DN<6>")
	)
	(arc
		(start 116.336318 -239.976406)
		(mid 116.508183 -240.17617)
		(end 116.569998 -240.432336)
		(width 0.1143)
		(layer "In13.Cu")
		(net "GMI_CPU0_G0_CPU1_G2_TX_DN<6>")
	)
	(arc
		(start 354.925884 -240.432082)
		(mid 354.987709 -240.175921)
		(end 355.159564 -239.976152)
		(width 0.1143)
		(layer "In13.Cu")
		(net "GMI_CPU0_G0_CPU1_G2_TX_DN<6>")
	)
	(arc
		(start 355.157532 -224.690686)
		(mid 354.930149 -224.234248)
		(end 355.157532 -223.77781)
		(width 0.1143)
		(layer "In13.Cu")
		(net "GMI_CPU0_G0_CPU1_G2_TX_DN<6>")
	)
	(arc
		(start 355.239828 -228.58857)
		(mid 355.395756 -228.284278)
		(end 355.239828 -227.979986)
		(width 0.1143)
		(layer "In13.Cu")
		(net "GMI_CPU0_G0_CPU1_G2_TX_DN<6>")
	)
	(arc
		(start 116.33835 -224.69094)
		(mid 116.331276 -224.695947)
		(end 116.324126 -224.700846)
		(width 0.1143)
		(layer "In13.Cu")
		(net "GMI_CPU0_G0_CPU1_G2_TX_DN<6>")
	)
	(arc
		(start 355.156516 -225.398584)
		(mid 355.164092 -225.393188)
		(end 355.171756 -225.387916)
		(width 0.1143)
		(layer "In13.Cu")
		(net "GMI_CPU0_G0_CPU1_G2_TX_DN<6>")
	)
	(arc
		(start 116.33835 -222.158052)
		(mid 116.565733 -222.61449)
		(end 116.33835 -223.070928)
		(width 0.1143)
		(layer "In13.Cu")
		(net "GMI_CPU0_G0_CPU1_G2_TX_DN<6>")
	)
	(arc
		(start 116.324126 -231.867964)
		(mid 116.331275 -231.872864)
		(end 116.33835 -231.87787)
		(width 0.1143)
		(layer "In13.Cu")
		(net "GMI_CPU0_G0_CPU1_G2_TX_DN<6>")
	)
	(arc
		(start 355.157532 -231.877616)
		(mid 355.164605 -231.872607)
		(end 355.171756 -231.86771)
		(width 0.1143)
		(layer "In13.Cu")
		(net "GMI_CPU0_G0_CPU1_G2_TX_DN<6>")
	)
	(arc
		(start 116.254276 -229.601522)
		(mid 116.140869 -229.734411)
		(end 116.100098 -229.90429)
		(width 0.1143)
		(layer "In13.Cu")
		(net "GMI_CPU0_G0_CPU1_G2_TX_DN<6>")
	)
	(arc
		(start 355.157532 -236.737652)
		(mid 355.164605 -236.732643)
		(end 355.171756 -236.727746)
		(width 0.1143)
		(layer "In13.Cu")
		(net "GMI_CPU0_G0_CPU1_G2_TX_DN<6>")
	)
	(arc
		(start 116.33835 -236.737906)
		(mid 116.565834 -237.194344)
		(end 116.33835 -237.650782)
		(width 0.1143)
		(layer "In13.Cu")
		(net "GMI_CPU0_G0_CPU1_G2_TX_DN<6>")
	)
	(arc
		(start 116.354606 -238.369602)
		(mid 116.582606 -238.814356)
		(end 116.354606 -239.25911)
		(width 0.1143)
		(layer "In13.Cu")
		(net "GMI_CPU0_G0_CPU1_G2_TX_DN<6>")
	)
	(arc
		(start 117.030246 -241.13871)
		(mid 117.032269 -241.15012)
		(end 117.034056 -241.16157)
		(width 0.1143)
		(layer "In13.Cu")
		(net "GMI_CPU0_G0_CPU1_G2_TX_DN<6>")
	)
	(arc
		(start 354.465636 -241.138456)
		(mid 354.547069 -240.936058)
		(end 354.699062 -240.779554)
		(width 0.1143)
		(layer "In13.Cu")
		(net "GMI_CPU0_G0_CPU1_G2_TX_DN<6>")
	)
	(arc
		(start 355.239828 -236.688376)
		(mid 355.395756 -236.384084)
		(end 355.239828 -236.079792)
		(width 0.1143)
		(layer "In13.Cu")
		(net "GMI_CPU0_G0_CPU1_G2_TX_DN<6>")
	)
	(arc
		(start 355.157532 -235.11764)
		(mid 355.164605 -235.112631)
		(end 355.171756 -235.107734)
		(width 0.1143)
		(layer "In13.Cu")
		(net "GMI_CPU0_G0_CPU1_G2_TX_DN<6>")
	)
	(arc
		(start 116.256054 -236.080046)
		(mid 116.100126 -236.384338)
		(end 116.256054 -236.68863)
		(width 0.1143)
		(layer "In13.Cu")
		(net "GMI_CPU0_G0_CPU1_G2_TX_DN<6>")
	)
	(arc
		(start 355.157532 -223.070674)
		(mid 354.930149 -222.614236)
		(end 355.157532 -222.157798)
		(width 0.1143)
		(layer "In13.Cu")
		(net "GMI_CPU0_G0_CPU1_G2_TX_DN<6>")
	)
	(arc
		(start 116.569998 -230.71455)
		(mid 116.504762 -230.978141)
		(end 116.324126 -231.180894)
		(width 0.1143)
		(layer "In13.Cu")
		(net "GMI_CPU0_G0_CPU1_G2_TX_DN<6>")
	)
	(arc
		(start 116.79682 -240.779808)
		(mid 116.948807 -240.936316)
		(end 117.030246 -241.13871)
		(width 0.1143)
		(layer "In13.Cu")
		(net "GMI_CPU0_G0_CPU1_G2_TX_DN<6>")
	)
	(arc
		(start 355.171756 -232.800398)
		(mid 355.164606 -232.7955)
		(end 355.157532 -232.790492)
		(width 0.1143)
		(layer "In13.Cu")
		(net "GMI_CPU0_G0_CPU1_G2_TX_DN<6>")
	)
	(arc
		(start 355.157532 -223.77781)
		(mid 355.164605 -223.772801)
		(end 355.171756 -223.767904)
		(width 0.1143)
		(layer "In13.Cu")
		(net "GMI_CPU0_G0_CPU1_G2_TX_DN<6>")
	)
	(arc
		(start 355.171756 -237.660434)
		(mid 355.164606 -237.655536)
		(end 355.157532 -237.650528)
		(width 0.1143)
		(layer "In13.Cu")
		(net "GMI_CPU0_G0_CPU1_G2_TX_DN<6>")
	)
	(arc
		(start 116.569998 -240.4364)
		(mid 116.614031 -240.605047)
		(end 116.725954 -240.73866)
		(width 0.1143)
		(layer "In13.Cu")
		(net "GMI_CPU0_G0_CPU1_G2_TX_DN<6>")
	)
	(arc
		(start 116.33835 -236.03077)
		(mid 116.331276 -236.035777)
		(end 116.324126 -236.040676)
		(width 0.1143)
		(layer "In13.Cu")
		(net "GMI_CPU0_G0_CPU1_G2_TX_DN<6>")
	)
	(arc
		(start 355.239828 -230.208328)
		(mid 355.354504 -230.074994)
		(end 355.395784 -229.904036)
		(width 0.1143)
		(layer "In13.Cu")
		(net "GMI_CPU0_G0_CPU1_G2_TX_DN<6>")
	)
	(arc
		(start 116.324126 -222.148146)
		(mid 116.331275 -222.153046)
		(end 116.33835 -222.158052)
		(width 0.1143)
		(layer "In13.Cu")
		(net "GMI_CPU0_G0_CPU1_G2_TX_DN<6>")
	)
	(arc
		(start 355.156516 -226.309936)
		(mid 354.931345 -225.85426)
		(end 355.156516 -225.398584)
		(width 0.1143)
		(layer "In13.Cu")
		(net "GMI_CPU0_G0_CPU1_G2_TX_DN<6>")
	)
	(arc
		(start 116.569998 -240.435384)
		(mid 116.569998 -240.435892)
		(end 116.569998 -240.4364)
		(width 0.1143)
		(layer "In13.Cu")
		(net "GMI_CPU0_G0_CPU1_G2_TX_DN<6>")
	)
	(arc
		(start 116.33835 -237.650782)
		(mid 116.331276 -237.655789)
		(end 116.324126 -237.660688)
		(width 0.1143)
		(layer "In13.Cu")
		(net "GMI_CPU0_G0_CPU1_G2_TX_DN<6>")
	)
	(arc
		(start 116.251736 -224.743264)
		(mid 116.097331 -225.044508)
		(end 116.251736 -225.345752)
		(width 0.1143)
		(layer "In13.Cu")
		(net "GMI_CPU0_G0_CPU1_G2_TX_DN<6>")
	)
	(arc
		(start 116.339366 -225.398838)
		(mid 116.564537 -225.854514)
		(end 116.339366 -226.31019)
		(width 0.1143)
		(layer "In13.Cu")
		(net "GMI_CPU0_G0_CPU1_G2_TX_DN<6>")
	)
	(arc
		(start 116.256054 -226.360228)
		(mid 116.100126 -226.66452)
		(end 116.256054 -226.968812)
		(width 0.1143)
		(layer "In13.Cu")
		(net "GMI_CPU0_G0_CPU1_G2_TX_DN<6>")
	)
	(arc
		(start 116.33835 -232.790746)
		(mid 116.331276 -232.795753)
		(end 116.324126 -232.800652)
		(width 0.1143)
		(layer "In13.Cu")
		(net "GMI_CPU0_G0_CPU1_G2_TX_DN<6>")
	)
	(arc
		(start 116.100098 -231.524302)
		(mid 116.141353 -231.695273)
		(end 116.256054 -231.828594)
		(width 0.1143)
		(layer "In13.Cu")
		(net "GMI_CPU0_G0_CPU1_G2_TX_DN<6>")
	)
	(arc
		(start 116.324126 -235.107988)
		(mid 116.331275 -235.112888)
		(end 116.33835 -235.117894)
		(width 0.1143)
		(layer "In13.Cu")
		(net "GMI_CPU0_G0_CPU1_G2_TX_DN<6>")
	)
	(arc
		(start 355.239828 -222.108522)
		(mid 355.354504 -221.975188)
		(end 355.395784 -221.80423)
		(width 0.1143)
		(layer "In13.Cu")
		(net "GMI_CPU0_G0_CPU1_G2_TX_DN<6>")
	)
	(arc
		(start 116.339366 -226.31019)
		(mid 116.33179 -226.315586)
		(end 116.324126 -226.320858)
		(width 0.1143)
		(layer "In13.Cu")
		(net "GMI_CPU0_G0_CPU1_G2_TX_DN<6>")
	)
	(arc
		(start 116.324126 -225.38817)
		(mid 116.33179 -225.393441)
		(end 116.339366 -225.398838)
		(width 0.1143)
		(layer "In13.Cu")
		(net "GMI_CPU0_G0_CPU1_G2_TX_DN<6>")
	)
	(arc
		(start 116.33835 -231.87787)
		(mid 116.565834 -232.334308)
		(end 116.33835 -232.790746)
		(width 0.1143)
		(layer "In13.Cu")
		(net "GMI_CPU0_G0_CPU1_G2_TX_DN<6>")
	)
	(arc
		(start 355.239828 -235.068364)
		(mid 355.395756 -234.764072)
		(end 355.239828 -234.45978)
		(width 0.1143)
		(layer "In13.Cu")
		(net "GMI_CPU0_G0_CPU1_G2_TX_DN<6>")
	)
	(arc
		(start 116.324126 -236.728)
		(mid 116.331275 -236.7329)
		(end 116.33835 -236.737906)
		(width 0.1143)
		(layer "In13.Cu")
		(net "GMI_CPU0_G0_CPU1_G2_TX_DN<6>")
	)
	(arc
		(start 355.171756 -223.08058)
		(mid 355.164606 -223.075682)
		(end 355.157532 -223.070674)
		(width 0.1143)
		(layer "In13.Cu")
		(net "GMI_CPU0_G0_CPU1_G2_TX_DN<6>")
	)
	(arc
		(start 355.244146 -225.345498)
		(mid 355.398551 -225.044254)
		(end 355.244146 -224.74301)
		(width 0.1143)
		(layer "In13.Cu")
		(net "GMI_CPU0_G0_CPU1_G2_TX_DN<6>")
	)
	(arc
		(start 355.171756 -224.700592)
		(mid 355.164606 -224.695694)
		(end 355.157532 -224.690686)
		(width 0.1143)
		(layer "In13.Cu")
		(net "GMI_CPU0_G0_CPU1_G2_TX_DN<6>")
	)
	(arc
		(start 355.157532 -232.790492)
		(mid 354.930048 -232.334054)
		(end 355.157532 -231.877616)
		(width 0.1143)
		(layer "In13.Cu")
		(net "GMI_CPU0_G0_CPU1_G2_TX_DN<6>")
	)
	(arc
		(start 116.256054 -239.32007)
		(mid 116.100126 -239.624362)
		(end 116.256054 -239.928654)
		(width 0.1143)
		(layer "In13.Cu")
		(net "GMI_CPU0_G0_CPU1_G2_TX_DN<6>")
	)
	(arc
		(start 116.256054 -232.840022)
		(mid 116.100126 -233.144314)
		(end 116.256054 -233.448606)
		(width 0.1143)
		(layer "In13.Cu")
		(net "GMI_CPU0_G0_CPU1_G2_TX_DN<6>")
	)
	(arc
		(start 354.769928 -240.738406)
		(mid 354.881837 -240.604785)
		(end 354.925884 -240.436146)
		(width 0.1143)
		(layer "In13.Cu")
		(net "GMI_CPU0_G0_CPU1_G2_TX_DN<6>")
	)
	(arc
		(start 355.171756 -231.18064)
		(mid 354.991104 -230.977895)
		(end 354.925884 -230.714296)
		(width 0.1143)
		(layer "In13.Cu")
		(net "GMI_CPU0_G0_CPU1_G2_TX_DN<6>")
	)
	(arc
		(start 116.256054 -223.120204)
		(mid 116.100126 -223.424496)
		(end 116.256054 -223.728788)
		(width 0.1143)
		(layer "In13.Cu")
		(net "GMI_CPU0_G0_CPU1_G2_TX_DN<6>")
	)
	(arc
		(start 355.141276 -239.258856)
		(mid 354.913276 -238.814102)
		(end 355.141276 -238.369348)
		(width 0.1143)
		(layer "In13.Cu")
		(net "GMI_CPU0_G0_CPU1_G2_TX_DN<6>")
	)
	(arc
		(start 355.239828 -226.968558)
		(mid 355.395756 -226.664266)
		(end 355.239828 -226.359974)
		(width 0.1143)
		(layer "In13.Cu")
		(net "GMI_CPU0_G0_CPU1_G2_TX_DN<6>")
	)
	(arc
		(start 116.324126 -223.768158)
		(mid 116.331275 -223.773058)
		(end 116.33835 -223.778064)
		(width 0.1143)
		(layer "In13.Cu")
		(net "GMI_CPU0_G0_CPU1_G2_TX_DN<6>")
	)
	(arc
		(start 355.186742 -229.569264)
		(mid 354.913191 -229.094284)
		(end 355.186742 -228.619304)
		(width 0.1143)
		(layer "In13.Cu")
		(net "GMI_CPU0_G0_CPU1_G2_TX_DN<6>")
	)
	(arc
		(start 355.141276 -234.39882)
		(mid 354.913276 -233.954066)
		(end 355.141276 -233.509312)
		(width 0.1143)
		(layer "In13.Cu")
		(net "GMI_CPU0_G0_CPU1_G2_TX_DN<6>")
	)
	(arc
		(start 355.395784 -229.904036)
		(mid 355.355022 -229.734152)
		(end 355.241606 -229.601268)
		(width 0.1143)
		(layer "In13.Cu")
		(net "GMI_CPU0_G0_CPU1_G2_TX_DN<6>")
	)
	(arc
		(start 355.239828 -238.308388)
		(mid 355.395756 -238.004096)
		(end 355.239828 -237.699804)
		(width 0.1143)
		(layer "In13.Cu")
		(net "GMI_CPU0_G0_CPU1_G2_TX_DN<6>")
	)
	(arc
		(start 116.30914 -228.619558)
		(mid 116.582691 -229.094538)
		(end 116.30914 -229.569518)
		(width 0.1143)
		(layer "In13.Cu")
		(net "GMI_CPU0_G0_CPU1_G2_TX_DN<6>")
	)
	(arc
		(start 116.256054 -227.98024)
		(mid 116.100126 -228.284532)
		(end 116.256054 -228.588824)
		(width 0.1143)
		(layer "In13.Cu")
		(net "GMI_CPU0_G0_CPU1_G2_TX_DN<6>")
	)
	(arc
		(start 355.157532 -222.157798)
		(mid 355.164605 -222.152789)
		(end 355.171756 -222.147892)
		(width 0.1143)
		(layer "In13.Cu")
		(net "GMI_CPU0_G0_CPU1_G2_TX_DN<6>")
	)
	(arc
		(start 355.157532 -236.030516)
		(mid 354.930048 -235.574078)
		(end 355.157532 -235.11764)
		(width 0.1143)
		(layer "In13.Cu")
		(net "GMI_CPU0_G0_CPU1_G2_TX_DN<6>")
	)
	(arc
		(start 116.33835 -223.778064)
		(mid 116.565733 -224.234502)
		(end 116.33835 -224.69094)
		(width 0.1143)
		(layer "In13.Cu")
		(net "GMI_CPU0_G0_CPU1_G2_TX_DN<6>")
	)
	(arc
		(start 355.239828 -223.728534)
		(mid 355.395756 -223.424242)
		(end 355.239828 -223.11995)
		(width 0.1143)
		(layer "In13.Cu")
		(net "GMI_CPU0_G0_CPU1_G2_TX_DN<6>")
	)
	(arc
		(start 355.171756 -226.320604)
		(mid 355.164092 -226.315333)
		(end 355.156516 -226.309936)
		(width 0.1143)
		(layer "In13.Cu")
		(net "GMI_CPU0_G0_CPU1_G2_TX_DN<6>")
	)
	(arc
		(start 354.461826 -241.161316)
		(mid 354.463614 -241.149867)
		(end 354.465636 -241.138456)
		(width 0.1143)
		(layer "In13.Cu")
		(net "GMI_CPU0_G0_CPU1_G2_TX_DN<6>")
	)
	(arc
		(start 355.141276 -227.919026)
		(mid 354.913276 -227.474272)
		(end 355.141276 -227.029518)
		(width 0.1143)
		(layer "In13.Cu")
		(net "GMI_CPU0_G0_CPU1_G2_TX_DN<6>")
	)
	(arc
		(start 354.925884 -230.714296)
		(mid 355.001386 -230.433044)
		(end 355.20757 -230.227378)
		(width 0.1143)
		(layer "In13.Cu")
		(net "GMI_CPU0_G0_CPU1_G2_TX_DN<6>")
	)
	(arc
		(start 116.254276 -231.221534)
		(mid 116.140869 -231.354423)
		(end 116.100098 -231.524302)
		(width 0.1143)
		(layer "In13.Cu")
		(net "GMI_CPU0_G0_CPU1_G2_TX_DN<6>")
	)
	(arc
		(start 116.256054 -237.700058)
		(mid 116.100126 -238.00435)
		(end 116.256054 -238.308642)
		(width 0.1143)
		(layer "In13.Cu")
		(net "GMI_CPU0_G0_CPU1_G2_TX_DN<6>")
	)
	(arc
		(start 116.354606 -233.509566)
		(mid 116.582606 -233.95432)
		(end 116.354606 -234.399074)
		(width 0.1143)
		(layer "In13.Cu")
		(net "GMI_CPU0_G0_CPU1_G2_TX_DN<6>")
	)
	(segment
		(start 116.94795 -239.8903)
		(end 117.414802 -239.624362)
		(width 0.12954)
		(layer "F.Cu")
		(net "GMI_CPU0_G0_CPU1_G2_TX_DN<5>")
	)
	(segment
		(start 354.547932 -239.890046)
		(end 354.08108 -239.624108)
		(width 0.12954)
		(layer "F.Cu")
		(net "GMI_CPU0_G0_CPU1_G2_TX_DN<5>")
	)
	(segment
		(start 118.206774 -231.869742)
		(end 118.167658 -231.846882)
		(width 0.1143)
		(layer "In13.Cu")
		(net "GMI_CPU0_G0_CPU1_G2_TX_DN<5>")
	)
	(segment
		(start 353.795584 -238.489998)
		(end 353.797108 -238.491014)
		(width 0.1143)
		(layer "In13.Cu")
		(net "GMI_CPU0_G0_CPU1_G2_TX_DN<5>")
	)
	(segment
		(start 151.369522 -188.911738)
		(end 151.699468 -188.641228)
		(width 0.14224)
		(layer "In13.Cu")
		(net "GMI_CPU0_G0_CPU1_G2_TX_DN<5>")
	)
	(segment
		(start 148.210524 -191.502284)
		(end 148.403564 -191.521334)
		(width 0.14224)
		(layer "In13.Cu")
		(net "GMI_CPU0_G0_CPU1_G2_TX_DN<5>")
	)
	(segment
		(start 166.09441 -179.913534)
		(end 302.901096 -180.711348)
		(width 0.14224)
		(layer "In13.Cu")
		(net "GMI_CPU0_G0_CPU1_G2_TX_DN<5>")
	)
	(segment
		(start 353.797108 -238.491014)
		(end 353.798124 -238.491522)
		(width 0.1143)
		(layer "In13.Cu")
		(net "GMI_CPU0_G0_CPU1_G2_TX_DN<5>")
	)
	(segment
		(start 152.222708 -188.389514)
		(end 152.241758 -188.196474)
		(width 0.14224)
		(layer "In13.Cu")
		(net "GMI_CPU0_G0_CPU1_G2_TX_DN<5>")
	)
	(segment
		(start 118.137178 -237.69955)
		(end 118.167658 -237.68177)
		(width 0.1143)
		(layer "In13.Cu")
		(net "GMI_CPU0_G0_CPU1_G2_TX_DN<5>")
	)
	(segment
		(start 151.699468 -188.641228)
		(end 151.892508 -188.660278)
		(width 0.14224)
		(layer "In13.Cu")
		(net "GMI_CPU0_G0_CPU1_G2_TX_DN<5>")
	)
	(segment
		(start 354.448872 -239.554258)
		(end 354.379022 -239.624108)
		(width 0.1143)
		(layer "In13.Cu")
		(net "GMI_CPU0_G0_CPU1_G2_TX_DN<5>")
	)
	(segment
		(start 118.206774 -223.769936)
		(end 118.167658 -223.747076)
		(width 0.1143)
		(layer "In13.Cu")
		(net "GMI_CPU0_G0_CPU1_G2_TX_DN<5>")
	)
	(segment
		(start 118.135146 -229.60076)
		(end 118.167658 -229.581964)
		(width 0.1143)
		(layer "In13.Cu")
		(net "GMI_CPU0_G0_CPU1_G2_TX_DN<5>")
	)
	(segment
		(start 118.167658 -231.846882)
		(end 118.137178 -231.829102)
		(width 0.1143)
		(layer "In13.Cu")
		(net "GMI_CPU0_G0_CPU1_G2_TX_DN<5>")
	)
	(segment
		(start 118.167658 -223.747076)
		(end 118.137178 -223.729296)
		(width 0.1143)
		(layer "In13.Cu")
		(net "GMI_CPU0_G0_CPU1_G2_TX_DN<5>")
	)
	(segment
		(start 118.167658 -235.086906)
		(end 118.137178 -235.069126)
		(width 0.1143)
		(layer "In13.Cu")
		(net "GMI_CPU0_G0_CPU1_G2_TX_DN<5>")
	)
	(segment
		(start 118.167658 -232.821734)
		(end 118.206774 -232.798874)
		(width 0.1143)
		(layer "In13.Cu")
		(net "GMI_CPU0_G0_CPU1_G2_TX_DN<5>")
	)
	(segment
		(start 117.414802 -239.624362)
		(end 117.11686 -239.624362)
		(width 0.1143)
		(layer "In13.Cu")
		(net "GMI_CPU0_G0_CPU1_G2_TX_DN<5>")
	)
	(segment
		(start 117.98173 -221.071948)
		(end 117.98173 -218.864434)
		(width 0.14224)
		(layer "In13.Cu")
		(net "GMI_CPU0_G0_CPU1_G2_TX_DN<5>")
	)
	(segment
		(start 151.020272 -189.375542)
		(end 151.350472 -189.104778)
		(width 0.14224)
		(layer "In13.Cu")
		(net "GMI_CPU0_G0_CPU1_G2_TX_DN<5>")
	)
	(segment
		(start 353.358704 -236.688884)
		(end 353.289108 -236.729524)
		(width 0.1143)
		(layer "In13.Cu")
		(net "GMI_CPU0_G0_CPU1_G2_TX_DN<5>")
	)
	(segment
		(start 118.167658 -234.441746)
		(end 118.206774 -234.418886)
		(width 0.1143)
		(layer "In13.Cu")
		(net "GMI_CPU0_G0_CPU1_G2_TX_DN<5>")
	)
	(segment
		(start 152.764744 -187.945014)
		(end 153.094944 -187.67425)
		(width 0.14224)
		(layer "In13.Cu")
		(net "GMI_CPU0_G0_CPU1_G2_TX_DN<5>")
	)
	(segment
		(start 117.98173 -218.864434)
		(end 121.124726 -213.500208)
		(width 0.14224)
		(layer "In13.Cu")
		(net "GMI_CPU0_G0_CPU1_G2_TX_DN<5>")
	)
	(segment
		(start 118.167658 -223.101916)
		(end 118.206774 -223.079056)
		(width 0.1143)
		(layer "In13.Cu")
		(net "GMI_CPU0_G0_CPU1_G2_TX_DN<5>")
	)
	(segment
		(start 150.148036 -190.090806)
		(end 150.478236 -189.820042)
		(width 0.14224)
		(layer "In13.Cu")
		(net "GMI_CPU0_G0_CPU1_G2_TX_DN<5>")
	)
	(segment
		(start 118.206774 -227.00996)
		(end 118.167658 -226.9871)
		(width 0.1143)
		(layer "In13.Cu")
		(net "GMI_CPU0_G0_CPU1_G2_TX_DN<5>")
	)
	(segment
		(start 353.289108 -234.418632)
		(end 353.358704 -234.459272)
		(width 0.1143)
		(layer "In13.Cu")
		(net "GMI_CPU0_G0_CPU1_G2_TX_DN<5>")
	)
	(segment
		(start 353.289108 -227.938838)
		(end 353.358704 -227.979478)
		(width 0.1143)
		(layer "In13.Cu")
		(net "GMI_CPU0_G0_CPU1_G2_TX_DN<5>")
	)
	(segment
		(start 150.497286 -189.627002)
		(end 150.827232 -189.356492)
		(width 0.14224)
		(layer "In13.Cu")
		(net "GMI_CPU0_G0_CPU1_G2_TX_DN<5>")
	)
	(segment
		(start 117.93601 -221.303342)
		(end 117.93601 -221.146116)
		(width 0.1143)
		(layer "In13.Cu")
		(net "GMI_CPU0_G0_CPU1_G2_TX_DN<5>")
	)
	(segment
		(start 353.798886 -238.49203)
		(end 353.829874 -238.50981)
		(width 0.1143)
		(layer "In13.Cu")
		(net "GMI_CPU0_G0_CPU1_G2_TX_DN<5>")
	)
	(segment
		(start 118.167658 -228.607112)
		(end 118.137178 -228.589332)
		(width 0.1143)
		(layer "In13.Cu")
		(net "GMI_CPU0_G0_CPU1_G2_TX_DN<5>")
	)
	(segment
		(start 353.559872 -221.145862)
		(end 353.559872 -221.303088)
		(width 0.1143)
		(layer "In13.Cu")
		(net "GMI_CPU0_G0_CPU1_G2_TX_DN<5>")
	)
	(segment
		(start 149.2758 -190.80607)
		(end 149.606 -190.535306)
		(width 0.14224)
		(layer "In13.Cu")
		(net "GMI_CPU0_G0_CPU1_G2_TX_DN<5>")
	)
	(segment
		(start 118.206774 -228.629972)
		(end 118.167658 -228.607112)
		(width 0.1143)
		(layer "In13.Cu")
		(net "GMI_CPU0_G0_CPU1_G2_TX_DN<5>")
	)
	(segment
		(start 353.289108 -226.318826)
		(end 353.358704 -226.359466)
		(width 0.1143)
		(layer "In13.Cu")
		(net "GMI_CPU0_G0_CPU1_G2_TX_DN<5>")
	)
	(segment
		(start 152.241758 -188.196474)
		(end 152.571704 -187.925964)
		(width 0.14224)
		(layer "In13.Cu")
		(net "GMI_CPU0_G0_CPU1_G2_TX_DN<5>")
	)
	(segment
		(start 152.571704 -187.925964)
		(end 152.764744 -187.945014)
		(width 0.14224)
		(layer "In13.Cu")
		(net "GMI_CPU0_G0_CPU1_G2_TX_DN<5>")
	)
	(segment
		(start 153.77287 -187.118498)
		(end 154.10307 -186.847734)
		(width 0.14224)
		(layer "In13.Cu")
		(net "GMI_CPU0_G0_CPU1_G2_TX_DN<5>")
	)
	(segment
		(start 118.137178 -223.119696)
		(end 118.167658 -223.101916)
		(width 0.1143)
		(layer "In13.Cu")
		(net "GMI_CPU0_G0_CPU1_G2_TX_DN<5>")
	)
	(segment
		(start 302.901096 -180.711348)
		(end 307.388006 -180.711348)
		(width 0.14224)
		(layer "In13.Cu")
		(net "GMI_CPU0_G0_CPU1_G2_TX_DN<5>")
	)
	(segment
		(start 151.892508 -188.660278)
		(end 152.222708 -188.389514)
		(width 0.14224)
		(layer "In13.Cu")
		(net "GMI_CPU0_G0_CPU1_G2_TX_DN<5>")
	)
	(segment
		(start 118.167658 -226.34194)
		(end 118.206774 -226.31908)
		(width 0.1143)
		(layer "In13.Cu")
		(net "GMI_CPU0_G0_CPU1_G2_TX_DN<5>")
	)
	(segment
		(start 148.403564 -191.521334)
		(end 148.733764 -191.25057)
		(width 0.14224)
		(layer "In13.Cu")
		(net "GMI_CPU0_G0_CPU1_G2_TX_DN<5>")
	)
	(segment
		(start 117.197124 -239.319562)
		(end 117.227604 -239.301782)
		(width 0.1143)
		(layer "In13.Cu")
		(net "GMI_CPU0_G0_CPU1_G2_TX_DN<5>")
	)
	(segment
		(start 148.733764 -191.25057)
		(end 148.752814 -191.05753)
		(width 0.14224)
		(layer "In13.Cu")
		(net "GMI_CPU0_G0_CPU1_G2_TX_DN<5>")
	)
	(segment
		(start 353.328224 -229.58171)
		(end 353.360736 -229.600506)
		(width 0.1143)
		(layer "In13.Cu")
		(net "GMI_CPU0_G0_CPU1_G2_TX_DN<5>")
	)
	(segment
		(start 121.124726 -213.500208)
		(end 144.000982 -194.743324)
		(width 0.14224)
		(layer "In13.Cu")
		(net "GMI_CPU0_G0_CPU1_G2_TX_DN<5>")
	)
	(segment
		(start 353.759008 -238.468662)
		(end 353.795584 -238.489998)
		(width 0.1143)
		(layer "In13.Cu")
		(net "GMI_CPU0_G0_CPU1_G2_TX_DN<5>")
	)
	(segment
		(start 353.358704 -222.10903)
		(end 353.289108 -222.14967)
		(width 0.1143)
		(layer "In13.Cu")
		(net "GMI_CPU0_G0_CPU1_G2_TX_DN<5>")
	)
	(segment
		(start 144.000982 -194.743324)
		(end 144.408144 -194.620134)
		(width 0.14224)
		(layer "In13.Cu")
		(net "GMI_CPU0_G0_CPU1_G2_TX_DN<5>")
	)
	(segment
		(start 118.206774 -236.729778)
		(end 118.167658 -236.706918)
		(width 0.1143)
		(layer "In13.Cu")
		(net "GMI_CPU0_G0_CPU1_G2_TX_DN<5>")
	)
	(segment
		(start 118.167658 -231.201976)
		(end 118.206774 -231.179116)
		(width 0.1143)
		(layer "In13.Cu")
		(net "GMI_CPU0_G0_CPU1_G2_TX_DN<5>")
	)
	(segment
		(start 118.167658 -236.061758)
		(end 118.206774 -236.038898)
		(width 0.1143)
		(layer "In13.Cu")
		(net "GMI_CPU0_G0_CPU1_G2_TX_DN<5>")
	)
	(segment
		(start 118.167658 -226.9871)
		(end 118.137178 -226.96932)
		(width 0.1143)
		(layer "In13.Cu")
		(net "GMI_CPU0_G0_CPU1_G2_TX_DN<5>")
	)
	(segment
		(start 353.514152 -221.093538)
		(end 353.514152 -221.100142)
		(width 0.1143)
		(layer "In13.Cu")
		(net "GMI_CPU0_G0_CPU1_G2_TX_DN<5>")
	)
	(segment
		(start 150.478236 -189.820042)
		(end 150.497286 -189.627002)
		(width 0.14224)
		(layer "In13.Cu")
		(net "GMI_CPU0_G0_CPU1_G2_TX_DN<5>")
	)
	(segment
		(start 149.606 -190.535306)
		(end 149.62505 -190.342266)
		(width 0.14224)
		(layer "In13.Cu")
		(net "GMI_CPU0_G0_CPU1_G2_TX_DN<5>")
	)
	(segment
		(start 117.227604 -239.301782)
		(end 117.26672 -239.278922)
		(width 0.1143)
		(layer "In13.Cu")
		(net "GMI_CPU0_G0_CPU1_G2_TX_DN<5>")
	)
	(segment
		(start 117.980206 -221.804484)
		(end 117.980206 -221.347538)
		(width 0.1143)
		(layer "In13.Cu")
		(net "GMI_CPU0_G0_CPU1_G2_TX_DN<5>")
	)
	(segment
		(start 353.289108 -223.078802)
		(end 353.358704 -223.119442)
		(width 0.1143)
		(layer "In13.Cu")
		(net "GMI_CPU0_G0_CPU1_G2_TX_DN<5>")
	)
	(segment
		(start 353.358704 -231.828848)
		(end 353.289108 -231.869488)
		(width 0.1143)
		(layer "In13.Cu")
		(net "GMI_CPU0_G0_CPU1_G2_TX_DN<5>")
	)
	(segment
		(start 118.206774 -235.109766)
		(end 118.167658 -235.086906)
		(width 0.1143)
		(layer "In13.Cu")
		(net "GMI_CPU0_G0_CPU1_G2_TX_DN<5>")
	)
	(segment
		(start 118.204234 -230.248206)
		(end 118.137178 -230.20909)
		(width 0.1143)
		(layer "In13.Cu")
		(net "GMI_CPU0_G0_CPU1_G2_TX_DN<5>")
	)
	(segment
		(start 118.137178 -224.739708)
		(end 118.167658 -224.721928)
		(width 0.1143)
		(layer "In13.Cu")
		(net "GMI_CPU0_G0_CPU1_G2_TX_DN<5>")
	)
	(segment
		(start 353.358704 -228.589078)
		(end 353.289108 -228.629718)
		(width 0.1143)
		(layer "In13.Cu")
		(net "GMI_CPU0_G0_CPU1_G2_TX_DN<5>")
	)
	(segment
		(start 307.388006 -180.711348)
		(end 309.41137 -181.434486)
		(width 0.14224)
		(layer "In13.Cu")
		(net "GMI_CPU0_G0_CPU1_G2_TX_DN<5>")
	)
	(segment
		(start 350.332802 -213.434676)
		(end 353.514152 -218.79306)
		(width 0.14224)
		(layer "In13.Cu")
		(net "GMI_CPU0_G0_CPU1_G2_TX_DN<5>")
	)
	(segment
		(start 146.331178 -193.043302)
		(end 148.210524 -191.502284)
		(width 0.14224)
		(layer "In13.Cu")
		(net "GMI_CPU0_G0_CPU1_G2_TX_DN<5>")
	)
	(segment
		(start 146.330924 -193.043302)
		(end 146.331178 -193.043302)
		(width 0.14224)
		(layer "In13.Cu")
		(net "GMI_CPU0_G0_CPU1_G2_TX_DN<5>")
	)
	(segment
		(start 153.094944 -187.67425)
		(end 153.113994 -187.48121)
		(width 0.14224)
		(layer "In13.Cu")
		(net "GMI_CPU0_G0_CPU1_G2_TX_DN<5>")
	)
	(segment
		(start 153.113994 -187.48121)
		(end 153.57983 -187.099448)
		(width 0.14224)
		(layer "In13.Cu")
		(net "GMI_CPU0_G0_CPU1_G2_TX_DN<5>")
	)
	(segment
		(start 353.358704 -225.349054)
		(end 353.289108 -225.389694)
		(width 0.1143)
		(layer "In13.Cu")
		(net "GMI_CPU0_G0_CPU1_G2_TX_DN<5>")
	)
	(segment
		(start 117.666008 -238.510064)
		(end 117.695726 -238.493046)
		(width 0.1143)
		(layer "In13.Cu")
		(net "GMI_CPU0_G0_CPU1_G2_TX_DN<5>")
	)
	(segment
		(start 151.350472 -189.104778)
		(end 151.369522 -188.911738)
		(width 0.14224)
		(layer "In13.Cu")
		(net "GMI_CPU0_G0_CPU1_G2_TX_DN<5>")
	)
	(segment
		(start 315.531246 -184.898792)
		(end 350.332802 -213.434676)
		(width 0.14224)
		(layer "In13.Cu")
		(net "GMI_CPU0_G0_CPU1_G2_TX_DN<5>")
	)
	(segment
		(start 117.695726 -238.493046)
		(end 117.696996 -238.492284)
		(width 0.1143)
		(layer "In13.Cu")
		(net "GMI_CPU0_G0_CPU1_G2_TX_DN<5>")
	)
	(segment
		(start 144.408144 -194.620134)
		(end 146.330924 -193.043302)
		(width 0.14224)
		(layer "In13.Cu")
		(net "GMI_CPU0_G0_CPU1_G2_TX_DN<5>")
	)
	(segment
		(start 117.93601 -221.146116)
		(end 117.98173 -221.100396)
		(width 0.1143)
		(layer "In13.Cu")
		(net "GMI_CPU0_G0_CPU1_G2_TX_DN<5>")
	)
	(segment
		(start 353.289108 -231.178862)
		(end 353.328224 -231.201722)
		(width 0.1143)
		(layer "In13.Cu")
		(net "GMI_CPU0_G0_CPU1_G2_TX_DN<5>")
	)
	(segment
		(start 149.954996 -190.071756)
		(end 150.148036 -190.090806)
		(width 0.14224)
		(layer "In13.Cu")
		(net "GMI_CPU0_G0_CPU1_G2_TX_DN<5>")
	)
	(segment
		(start 353.289108 -236.038644)
		(end 353.358704 -236.079284)
		(width 0.1143)
		(layer "In13.Cu")
		(net "GMI_CPU0_G0_CPU1_G2_TX_DN<5>")
	)
	(segment
		(start 154.975306 -186.13247)
		(end 154.994356 -185.93943)
		(width 0.14224)
		(layer "In13.Cu")
		(net "GMI_CPU0_G0_CPU1_G2_TX_DN<5>")
	)
	(segment
		(start 118.206774 -222.149924)
		(end 118.167658 -222.127064)
		(width 0.1143)
		(layer "In13.Cu")
		(net "GMI_CPU0_G0_CPU1_G2_TX_DN<5>")
	)
	(segment
		(start 354.379022 -239.624108)
		(end 354.08108 -239.624108)
		(width 0.1143)
		(layer "In13.Cu")
		(net "GMI_CPU0_G0_CPU1_G2_TX_DN<5>")
	)
	(segment
		(start 118.167658 -237.68177)
		(end 118.206774 -237.65891)
		(width 0.1143)
		(layer "In13.Cu")
		(net "GMI_CPU0_G0_CPU1_G2_TX_DN<5>")
	)
	(segment
		(start 118.137178 -236.079538)
		(end 118.167658 -236.061758)
		(width 0.1143)
		(layer "In13.Cu")
		(net "GMI_CPU0_G0_CPU1_G2_TX_DN<5>")
	)
	(segment
		(start 118.167658 -236.706918)
		(end 118.137178 -236.689138)
		(width 0.1143)
		(layer "In13.Cu")
		(net "GMI_CPU0_G0_CPU1_G2_TX_DN<5>")
	)
	(segment
		(start 117.980206 -221.347538)
		(end 117.93601 -221.303342)
		(width 0.1143)
		(layer "In13.Cu")
		(net "GMI_CPU0_G0_CPU1_G2_TX_DN<5>")
	)
	(segment
		(start 353.289108 -237.658656)
		(end 353.358704 -237.699296)
		(width 0.1143)
		(layer "In13.Cu")
		(net "GMI_CPU0_G0_CPU1_G2_TX_DN<5>")
	)
	(segment
		(start 118.167658 -224.721928)
		(end 118.206774 -224.699068)
		(width 0.1143)
		(layer "In13.Cu")
		(net "GMI_CPU0_G0_CPU1_G2_TX_DN<5>")
	)
	(segment
		(start 353.358704 -233.44886)
		(end 353.289108 -233.4895)
		(width 0.1143)
		(layer "In13.Cu")
		(net "GMI_CPU0_G0_CPU1_G2_TX_DN<5>")
	)
	(segment
		(start 154.645106 -186.403234)
		(end 154.975306 -186.13247)
		(width 0.14224)
		(layer "In13.Cu")
		(net "GMI_CPU0_G0_CPU1_G2_TX_DN<5>")
	)
	(segment
		(start 118.167658 -225.367088)
		(end 118.137178 -225.349308)
		(width 0.1143)
		(layer "In13.Cu")
		(net "GMI_CPU0_G0_CPU1_G2_TX_DN<5>")
	)
	(segment
		(start 149.08276 -190.78702)
		(end 149.2758 -190.80607)
		(width 0.14224)
		(layer "In13.Cu")
		(net "GMI_CPU0_G0_CPU1_G2_TX_DN<5>")
	)
	(segment
		(start 353.514152 -218.79306)
		(end 353.514152 -221.093538)
		(width 0.14224)
		(layer "In13.Cu")
		(net "GMI_CPU0_G0_CPU1_G2_TX_DN<5>")
	)
	(segment
		(start 118.135146 -231.220772)
		(end 118.167658 -231.201976)
		(width 0.1143)
		(layer "In13.Cu")
		(net "GMI_CPU0_G0_CPU1_G2_TX_DN<5>")
	)
	(segment
		(start 353.798124 -238.491522)
		(end 353.798886 -238.49203)
		(width 0.1143)
		(layer "In13.Cu")
		(net "GMI_CPU0_G0_CPU1_G2_TX_DN<5>")
	)
	(segment
		(start 150.827232 -189.356492)
		(end 151.020272 -189.375542)
		(width 0.14224)
		(layer "In13.Cu")
		(net "GMI_CPU0_G0_CPU1_G2_TX_DN<5>")
	)
	(segment
		(start 353.514152 -221.100142)
		(end 353.559872 -221.145862)
		(width 0.1143)
		(layer "In13.Cu")
		(net "GMI_CPU0_G0_CPU1_G2_TX_DN<5>")
	)
	(segment
		(start 118.137178 -232.839514)
		(end 118.167658 -232.821734)
		(width 0.1143)
		(layer "In13.Cu")
		(net "GMI_CPU0_G0_CPU1_G2_TX_DN<5>")
	)
	(segment
		(start 118.167658 -222.127064)
		(end 118.137178 -222.109284)
		(width 0.1143)
		(layer "In13.Cu")
		(net "GMI_CPU0_G0_CPU1_G2_TX_DN<5>")
	)
	(segment
		(start 118.167658 -229.581964)
		(end 118.206774 -229.559104)
		(width 0.1143)
		(layer "In13.Cu")
		(net "GMI_CPU0_G0_CPU1_G2_TX_DN<5>")
	)
	(segment
		(start 118.137178 -234.459526)
		(end 118.167658 -234.441746)
		(width 0.1143)
		(layer "In13.Cu")
		(net "GMI_CPU0_G0_CPU1_G2_TX_DN<5>")
	)
	(segment
		(start 353.559872 -221.303088)
		(end 353.515676 -221.347284)
		(width 0.1143)
		(layer "In13.Cu")
		(net "GMI_CPU0_G0_CPU1_G2_TX_DN<5>")
	)
	(segment
		(start 353.289108 -224.698814)
		(end 353.358704 -224.739454)
		(width 0.1143)
		(layer "In13.Cu")
		(net "GMI_CPU0_G0_CPU1_G2_TX_DN<5>")
	)
	(segment
		(start 154.12212 -186.654694)
		(end 154.452066 -186.384184)
		(width 0.14224)
		(layer "In13.Cu")
		(net "GMI_CPU0_G0_CPU1_G2_TX_DN<5>")
	)
	(segment
		(start 148.752814 -191.05753)
		(end 149.08276 -190.78702)
		(width 0.14224)
		(layer "In13.Cu")
		(net "GMI_CPU0_G0_CPU1_G2_TX_DN<5>")
	)
	(segment
		(start 118.137178 -227.979732)
		(end 118.167658 -227.961952)
		(width 0.1143)
		(layer "In13.Cu")
		(net "GMI_CPU0_G0_CPU1_G2_TX_DN<5>")
	)
	(segment
		(start 118.167658 -233.466894)
		(end 118.137178 -233.449114)
		(width 0.1143)
		(layer "In13.Cu")
		(net "GMI_CPU0_G0_CPU1_G2_TX_DN<5>")
	)
	(segment
		(start 154.994356 -185.93943)
		(end 159.441896 -182.292244)
		(width 0.14224)
		(layer "In13.Cu")
		(net "GMI_CPU0_G0_CPU1_G2_TX_DN<5>")
	)
	(segment
		(start 353.289108 -232.79862)
		(end 353.358704 -232.83926)
		(width 0.1143)
		(layer "In13.Cu")
		(net "GMI_CPU0_G0_CPU1_G2_TX_DN<5>")
	)
	(segment
		(start 117.697758 -238.491776)
		(end 117.736874 -238.468916)
		(width 0.1143)
		(layer "In13.Cu")
		(net "GMI_CPU0_G0_CPU1_G2_TX_DN<5>")
	)
	(segment
		(start 153.57983 -187.099448)
		(end 153.77287 -187.118498)
		(width 0.14224)
		(layer "In13.Cu")
		(net "GMI_CPU0_G0_CPU1_G2_TX_DN<5>")
	)
	(segment
		(start 353.358704 -223.729042)
		(end 353.289108 -223.769682)
		(width 0.1143)
		(layer "In13.Cu")
		(net "GMI_CPU0_G0_CPU1_G2_TX_DN<5>")
	)
	(segment
		(start 353.358704 -235.068872)
		(end 353.289108 -235.109512)
		(width 0.1143)
		(layer "In13.Cu")
		(net "GMI_CPU0_G0_CPU1_G2_TX_DN<5>")
	)
	(segment
		(start 154.452066 -186.384184)
		(end 154.645106 -186.403234)
		(width 0.14224)
		(layer "In13.Cu")
		(net "GMI_CPU0_G0_CPU1_G2_TX_DN<5>")
	)
	(segment
		(start 117.11686 -239.624362)
		(end 117.04701 -239.554512)
		(width 0.1143)
		(layer "In13.Cu")
		(net "GMI_CPU0_G0_CPU1_G2_TX_DN<5>")
	)
	(segment
		(start 154.10307 -186.847734)
		(end 154.12212 -186.654694)
		(width 0.14224)
		(layer "In13.Cu")
		(net "GMI_CPU0_G0_CPU1_G2_TX_DN<5>")
	)
	(segment
		(start 309.41137 -181.434486)
		(end 315.531246 -184.898792)
		(width 0.14224)
		(layer "In13.Cu")
		(net "GMI_CPU0_G0_CPU1_G2_TX_DN<5>")
	)
	(segment
		(start 353.358704 -230.208836)
		(end 353.291648 -230.247952)
		(width 0.1143)
		(layer "In13.Cu")
		(net "GMI_CPU0_G0_CPU1_G2_TX_DN<5>")
	)
	(segment
		(start 353.358704 -226.969066)
		(end 353.289108 -227.009706)
		(width 0.1143)
		(layer "In13.Cu")
		(net "GMI_CPU0_G0_CPU1_G2_TX_DN<5>")
	)
	(segment
		(start 118.137178 -226.35972)
		(end 118.167658 -226.34194)
		(width 0.1143)
		(layer "In13.Cu")
		(net "GMI_CPU0_G0_CPU1_G2_TX_DN<5>")
	)
	(segment
		(start 353.289108 -229.55885)
		(end 353.328224 -229.58171)
		(width 0.1143)
		(layer "In13.Cu")
		(net "GMI_CPU0_G0_CPU1_G2_TX_DN<5>")
	)
	(segment
		(start 117.696996 -238.492284)
		(end 117.697758 -238.491776)
		(width 0.1143)
		(layer "In13.Cu")
		(net "GMI_CPU0_G0_CPU1_G2_TX_DN<5>")
	)
	(segment
		(start 118.167658 -227.961952)
		(end 118.206774 -227.939092)
		(width 0.1143)
		(layer "In13.Cu")
		(net "GMI_CPU0_G0_CPU1_G2_TX_DN<5>")
	)
	(segment
		(start 159.441896 -182.292244)
		(end 166.09441 -179.913534)
		(width 0.14224)
		(layer "In13.Cu")
		(net "GMI_CPU0_G0_CPU1_G2_TX_DN<5>")
	)
	(segment
		(start 353.515676 -221.347284)
		(end 353.515676 -221.80423)
		(width 0.1143)
		(layer "In13.Cu")
		(net "GMI_CPU0_G0_CPU1_G2_TX_DN<5>")
	)
	(segment
		(start 354.229162 -239.278668)
		(end 354.298758 -239.319308)
		(width 0.1143)
		(layer "In13.Cu")
		(net "GMI_CPU0_G0_CPU1_G2_TX_DN<5>")
	)
	(segment
		(start 149.62505 -190.342266)
		(end 149.954996 -190.071756)
		(width 0.14224)
		(layer "In13.Cu")
		(net "GMI_CPU0_G0_CPU1_G2_TX_DN<5>")
	)
	(segment
		(start 117.98173 -221.100396)
		(end 117.98173 -221.071948)
		(width 0.1143)
		(layer "In13.Cu")
		(net "GMI_CPU0_G0_CPU1_G2_TX_DN<5>")
	)
	(segment
		(start 353.328224 -231.201722)
		(end 353.360736 -231.220518)
		(width 0.1143)
		(layer "In13.Cu")
		(net "GMI_CPU0_G0_CPU1_G2_TX_DN<5>")
	)
	(segment
		(start 118.206774 -225.389948)
		(end 118.167658 -225.367088)
		(width 0.1143)
		(layer "In13.Cu")
		(net "GMI_CPU0_G0_CPU1_G2_TX_DN<5>")
	)
	(segment
		(start 118.206774 -233.489754)
		(end 118.167658 -233.466894)
		(width 0.1143)
		(layer "In13.Cu")
		(net "GMI_CPU0_G0_CPU1_G2_TX_DN<5>")
	)
	(arc
		(start 353.289108 -233.4895)
		(mid 353.045781 -233.954066)
		(end 353.289108 -234.418632)
		(width 0.1143)
		(layer "In13.Cu")
		(net "GMI_CPU0_G0_CPU1_G2_TX_DN<5>")
	)
	(arc
		(start 118.137178 -226.96932)
		(mid 117.980201 -226.66452)
		(end 118.137178 -226.35972)
		(width 0.1143)
		(layer "In13.Cu")
		(net "GMI_CPU0_G0_CPU1_G2_TX_DN<5>")
	)
	(arc
		(start 118.206774 -237.65891)
		(mid 118.450101 -237.194344)
		(end 118.206774 -236.729778)
		(width 0.1143)
		(layer "In13.Cu")
		(net "GMI_CPU0_G0_CPU1_G2_TX_DN<5>")
	)
	(arc
		(start 353.358704 -236.079284)
		(mid 353.515681 -236.384084)
		(end 353.358704 -236.688884)
		(width 0.1143)
		(layer "In13.Cu")
		(net "GMI_CPU0_G0_CPU1_G2_TX_DN<5>")
	)
	(arc
		(start 353.515676 -229.904036)
		(mid 353.474127 -230.075458)
		(end 353.358704 -230.208836)
		(width 0.1143)
		(layer "In13.Cu")
		(net "GMI_CPU0_G0_CPU1_G2_TX_DN<5>")
	)
	(arc
		(start 354.298758 -239.319308)
		(mid 354.396523 -239.422284)
		(end 354.448872 -239.554258)
		(width 0.1143)
		(layer "In13.Cu")
		(net "GMI_CPU0_G0_CPU1_G2_TX_DN<5>")
	)
	(arc
		(start 353.289108 -228.629718)
		(mid 353.045781 -229.094284)
		(end 353.289108 -229.55885)
		(width 0.1143)
		(layer "In13.Cu")
		(net "GMI_CPU0_G0_CPU1_G2_TX_DN<5>")
	)
	(arc
		(start 118.137178 -225.349308)
		(mid 117.980201 -225.044508)
		(end 118.137178 -224.739708)
		(width 0.1143)
		(layer "In13.Cu")
		(net "GMI_CPU0_G0_CPU1_G2_TX_DN<5>")
	)
	(arc
		(start 118.137178 -228.589332)
		(mid 117.980201 -228.284532)
		(end 118.137178 -227.979732)
		(width 0.1143)
		(layer "In13.Cu")
		(net "GMI_CPU0_G0_CPU1_G2_TX_DN<5>")
	)
	(arc
		(start 353.289108 -225.389694)
		(mid 353.045781 -225.85426)
		(end 353.289108 -226.318826)
		(width 0.1143)
		(layer "In13.Cu")
		(net "GMI_CPU0_G0_CPU1_G2_TX_DN<5>")
	)
	(arc
		(start 353.360736 -229.600506)
		(mid 353.474665 -229.733653)
		(end 353.515676 -229.904036)
		(width 0.1143)
		(layer "In13.Cu")
		(net "GMI_CPU0_G0_CPU1_G2_TX_DN<5>")
	)
	(arc
		(start 353.045776 -230.714296)
		(mid 353.110291 -230.976515)
		(end 353.289108 -231.178862)
		(width 0.1143)
		(layer "In13.Cu")
		(net "GMI_CPU0_G0_CPU1_G2_TX_DN<5>")
	)
	(arc
		(start 118.206774 -224.699068)
		(mid 118.450101 -224.234502)
		(end 118.206774 -223.769936)
		(width 0.1143)
		(layer "In13.Cu")
		(net "GMI_CPU0_G0_CPU1_G2_TX_DN<5>")
	)
	(arc
		(start 353.358704 -232.83926)
		(mid 353.515681 -233.14406)
		(end 353.358704 -233.44886)
		(width 0.1143)
		(layer "In13.Cu")
		(net "GMI_CPU0_G0_CPU1_G2_TX_DN<5>")
	)
	(arc
		(start 117.980206 -231.524302)
		(mid 118.021172 -231.353896)
		(end 118.135146 -231.220772)
		(width 0.1143)
		(layer "In13.Cu")
		(net "GMI_CPU0_G0_CPU1_G2_TX_DN<5>")
	)
	(arc
		(start 353.358704 -226.359466)
		(mid 353.515681 -226.664266)
		(end 353.358704 -226.969066)
		(width 0.1143)
		(layer "In13.Cu")
		(net "GMI_CPU0_G0_CPU1_G2_TX_DN<5>")
	)
	(arc
		(start 117.510052 -238.814356)
		(mid 117.551307 -238.643385)
		(end 117.666008 -238.510064)
		(width 0.1143)
		(layer "In13.Cu")
		(net "GMI_CPU0_G0_CPU1_G2_TX_DN<5>")
	)
	(arc
		(start 118.206774 -226.31908)
		(mid 118.450101 -225.854514)
		(end 118.206774 -225.389948)
		(width 0.1143)
		(layer "In13.Cu")
		(net "GMI_CPU0_G0_CPU1_G2_TX_DN<5>")
	)
	(arc
		(start 353.358704 -224.739454)
		(mid 353.515681 -225.044254)
		(end 353.358704 -225.349054)
		(width 0.1143)
		(layer "In13.Cu")
		(net "GMI_CPU0_G0_CPU1_G2_TX_DN<5>")
	)
	(arc
		(start 353.358704 -237.699296)
		(mid 353.474131 -237.832672)
		(end 353.515676 -238.004096)
		(width 0.1143)
		(layer "In13.Cu")
		(net "GMI_CPU0_G0_CPU1_G2_TX_DN<5>")
	)
	(arc
		(start 118.137178 -222.109284)
		(mid 118.021751 -221.975908)
		(end 117.980206 -221.804484)
		(width 0.1143)
		(layer "In13.Cu")
		(net "GMI_CPU0_G0_CPU1_G2_TX_DN<5>")
	)
	(arc
		(start 353.289108 -231.869488)
		(mid 353.045781 -232.334054)
		(end 353.289108 -232.79862)
		(width 0.1143)
		(layer "In13.Cu")
		(net "GMI_CPU0_G0_CPU1_G2_TX_DN<5>")
	)
	(arc
		(start 118.206774 -234.418886)
		(mid 118.450101 -233.95432)
		(end 118.206774 -233.489754)
		(width 0.1143)
		(layer "In13.Cu")
		(net "GMI_CPU0_G0_CPU1_G2_TX_DN<5>")
	)
	(arc
		(start 353.360736 -231.220518)
		(mid 353.474665 -231.353665)
		(end 353.515676 -231.524048)
		(width 0.1143)
		(layer "In13.Cu")
		(net "GMI_CPU0_G0_CPU1_G2_TX_DN<5>")
	)
	(arc
		(start 353.358704 -234.459272)
		(mid 353.515681 -234.764072)
		(end 353.358704 -235.068872)
		(width 0.1143)
		(layer "In13.Cu")
		(net "GMI_CPU0_G0_CPU1_G2_TX_DN<5>")
	)
	(arc
		(start 353.829874 -238.50981)
		(mid 353.94455 -238.643144)
		(end 353.98583 -238.814102)
		(width 0.1143)
		(layer "In13.Cu")
		(net "GMI_CPU0_G0_CPU1_G2_TX_DN<5>")
	)
	(arc
		(start 118.137178 -233.449114)
		(mid 117.980201 -233.144314)
		(end 118.137178 -232.839514)
		(width 0.1143)
		(layer "In13.Cu")
		(net "GMI_CPU0_G0_CPU1_G2_TX_DN<5>")
	)
	(arc
		(start 353.289108 -227.009706)
		(mid 353.045781 -227.474272)
		(end 353.289108 -227.938838)
		(width 0.1143)
		(layer "In13.Cu")
		(net "GMI_CPU0_G0_CPU1_G2_TX_DN<5>")
	)
	(arc
		(start 118.450106 -230.71455)
		(mid 118.38487 -230.450959)
		(end 118.204234 -230.248206)
		(width 0.1143)
		(layer "In13.Cu")
		(net "GMI_CPU0_G0_CPU1_G2_TX_DN<5>")
	)
	(arc
		(start 117.26672 -239.278922)
		(mid 117.445533 -239.076572)
		(end 117.510052 -238.814356)
		(width 0.1143)
		(layer "In13.Cu")
		(net "GMI_CPU0_G0_CPU1_G2_TX_DN<5>")
	)
	(arc
		(start 118.206774 -223.079056)
		(mid 118.450101 -222.61449)
		(end 118.206774 -222.149924)
		(width 0.1143)
		(layer "In13.Cu")
		(net "GMI_CPU0_G0_CPU1_G2_TX_DN<5>")
	)
	(arc
		(start 118.137178 -235.069126)
		(mid 117.980201 -234.764326)
		(end 118.137178 -234.459526)
		(width 0.1143)
		(layer "In13.Cu")
		(net "GMI_CPU0_G0_CPU1_G2_TX_DN<5>")
	)
	(arc
		(start 117.980206 -229.90429)
		(mid 118.021172 -229.733884)
		(end 118.135146 -229.60076)
		(width 0.1143)
		(layer "In13.Cu")
		(net "GMI_CPU0_G0_CPU1_G2_TX_DN<5>")
	)
	(arc
		(start 117.04701 -239.554512)
		(mid 117.099427 -239.422581)
		(end 117.197124 -239.319562)
		(width 0.1143)
		(layer "In13.Cu")
		(net "GMI_CPU0_G0_CPU1_G2_TX_DN<5>")
	)
	(arc
		(start 353.289108 -236.729524)
		(mid 353.045781 -237.19409)
		(end 353.289108 -237.658656)
		(width 0.1143)
		(layer "In13.Cu")
		(net "GMI_CPU0_G0_CPU1_G2_TX_DN<5>")
	)
	(arc
		(start 117.980206 -238.00435)
		(mid 118.021755 -237.832928)
		(end 118.137178 -237.69955)
		(width 0.1143)
		(layer "In13.Cu")
		(net "GMI_CPU0_G0_CPU1_G2_TX_DN<5>")
	)
	(arc
		(start 118.206774 -229.559104)
		(mid 118.450101 -229.094538)
		(end 118.206774 -228.629972)
		(width 0.1143)
		(layer "In13.Cu")
		(net "GMI_CPU0_G0_CPU1_G2_TX_DN<5>")
	)
	(arc
		(start 353.289108 -223.769682)
		(mid 353.045781 -224.234248)
		(end 353.289108 -224.698814)
		(width 0.1143)
		(layer "In13.Cu")
		(net "GMI_CPU0_G0_CPU1_G2_TX_DN<5>")
	)
	(arc
		(start 118.137178 -230.20909)
		(mid 118.021751 -230.075714)
		(end 117.980206 -229.90429)
		(width 0.1143)
		(layer "In13.Cu")
		(net "GMI_CPU0_G0_CPU1_G2_TX_DN<5>")
	)
	(arc
		(start 118.206774 -227.939092)
		(mid 118.450101 -227.474526)
		(end 118.206774 -227.00996)
		(width 0.1143)
		(layer "In13.Cu")
		(net "GMI_CPU0_G0_CPU1_G2_TX_DN<5>")
	)
	(arc
		(start 353.358704 -223.119442)
		(mid 353.515681 -223.424242)
		(end 353.358704 -223.729042)
		(width 0.1143)
		(layer "In13.Cu")
		(net "GMI_CPU0_G0_CPU1_G2_TX_DN<5>")
	)
	(arc
		(start 353.515676 -231.524048)
		(mid 353.474127 -231.69547)
		(end 353.358704 -231.828848)
		(width 0.1143)
		(layer "In13.Cu")
		(net "GMI_CPU0_G0_CPU1_G2_TX_DN<5>")
	)
	(arc
		(start 353.289108 -222.14967)
		(mid 353.045781 -222.614236)
		(end 353.289108 -223.078802)
		(width 0.1143)
		(layer "In13.Cu")
		(net "GMI_CPU0_G0_CPU1_G2_TX_DN<5>")
	)
	(arc
		(start 118.206774 -236.038898)
		(mid 118.450101 -235.574332)
		(end 118.206774 -235.109766)
		(width 0.1143)
		(layer "In13.Cu")
		(net "GMI_CPU0_G0_CPU1_G2_TX_DN<5>")
	)
	(arc
		(start 353.515676 -221.80423)
		(mid 353.474127 -221.975652)
		(end 353.358704 -222.10903)
		(width 0.1143)
		(layer "In13.Cu")
		(net "GMI_CPU0_G0_CPU1_G2_TX_DN<5>")
	)
	(arc
		(start 117.736874 -238.468916)
		(mid 117.915687 -238.266566)
		(end 117.980206 -238.00435)
		(width 0.1143)
		(layer "In13.Cu")
		(net "GMI_CPU0_G0_CPU1_G2_TX_DN<5>")
	)
	(arc
		(start 353.98583 -238.814102)
		(mid 354.050345 -239.076321)
		(end 354.229162 -239.278668)
		(width 0.1143)
		(layer "In13.Cu")
		(net "GMI_CPU0_G0_CPU1_G2_TX_DN<5>")
	)
	(arc
		(start 353.515676 -238.004096)
		(mid 353.580191 -238.266315)
		(end 353.759008 -238.468662)
		(width 0.1143)
		(layer "In13.Cu")
		(net "GMI_CPU0_G0_CPU1_G2_TX_DN<5>")
	)
	(arc
		(start 353.289108 -235.109512)
		(mid 353.045781 -235.574078)
		(end 353.289108 -236.038644)
		(width 0.1143)
		(layer "In13.Cu")
		(net "GMI_CPU0_G0_CPU1_G2_TX_DN<5>")
	)
	(arc
		(start 118.137178 -223.729296)
		(mid 117.980201 -223.424496)
		(end 118.137178 -223.119696)
		(width 0.1143)
		(layer "In13.Cu")
		(net "GMI_CPU0_G0_CPU1_G2_TX_DN<5>")
	)
	(arc
		(start 118.206774 -232.798874)
		(mid 118.450101 -232.334308)
		(end 118.206774 -231.869742)
		(width 0.1143)
		(layer "In13.Cu")
		(net "GMI_CPU0_G0_CPU1_G2_TX_DN<5>")
	)
	(arc
		(start 353.358704 -227.979478)
		(mid 353.515681 -228.284278)
		(end 353.358704 -228.589078)
		(width 0.1143)
		(layer "In13.Cu")
		(net "GMI_CPU0_G0_CPU1_G2_TX_DN<5>")
	)
	(arc
		(start 118.137178 -236.689138)
		(mid 117.980201 -236.384338)
		(end 118.137178 -236.079538)
		(width 0.1143)
		(layer "In13.Cu")
		(net "GMI_CPU0_G0_CPU1_G2_TX_DN<5>")
	)
	(arc
		(start 353.291648 -230.247952)
		(mid 353.110996 -230.450697)
		(end 353.045776 -230.714296)
		(width 0.1143)
		(layer "In13.Cu")
		(net "GMI_CPU0_G0_CPU1_G2_TX_DN<5>")
	)
	(arc
		(start 118.206774 -231.179116)
		(mid 118.385587 -230.976766)
		(end 118.450106 -230.71455)
		(width 0.1143)
		(layer "In13.Cu")
		(net "GMI_CPU0_G0_CPU1_G2_TX_DN<5>")
	)
	(arc
		(start 118.137178 -231.829102)
		(mid 118.021751 -231.695726)
		(end 117.980206 -231.524302)
		(width 0.1143)
		(layer "In13.Cu")
		(net "GMI_CPU0_G0_CPU1_G2_TX_DN<5>")
	)
	(segment
		(start 354.547932 -238.270034)
		(end 354.08108 -238.004096)
		(width 0.12954)
		(layer "F.Cu")
		(net "GMI_CPU0_G0_CPU1_G2_TX_DN<4>")
	)
	(segment
		(start 116.94795 -238.270288)
		(end 117.414802 -238.00435)
		(width 0.12954)
		(layer "F.Cu")
		(net "GMI_CPU0_G0_CPU1_G2_TX_DN<4>")
	)
	(segment
		(start 354.298758 -226.359466)
		(end 354.229162 -226.318826)
		(width 0.1143)
		(layer "In13.Cu")
		(net "GMI_CPU0_G0_CPU1_G2_TX_DN<4>")
	)
	(segment
		(start 116.99113 -221.303342)
		(end 117.040152 -221.352364)
		(width 0.1143)
		(layer "In13.Cu")
		(net "GMI_CPU0_G0_CPU1_G2_TX_DN<4>")
	)
	(segment
		(start 354.08108 -238.004096)
		(end 354.379022 -238.004096)
		(width 0.1143)
		(layer "In13.Cu")
		(net "GMI_CPU0_G0_CPU1_G2_TX_DN<4>")
	)
	(segment
		(start 154.889454 -184.634632)
		(end 154.87142 -184.817004)
		(width 0.14224)
		(layer "In13.Cu")
		(net "GMI_CPU0_G0_CPU1_G2_TX_DN<4>")
	)
	(segment
		(start 117.227604 -231.846882)
		(end 117.26672 -231.869742)
		(width 0.1143)
		(layer "In13.Cu")
		(net "GMI_CPU0_G0_CPU1_G2_TX_DN<4>")
	)
	(segment
		(start 117.227604 -231.201976)
		(end 117.195092 -231.220772)
		(width 0.1143)
		(layer "In13.Cu")
		(net "GMI_CPU0_G0_CPU1_G2_TX_DN<4>")
	)
	(segment
		(start 116.99113 -221.146116)
		(end 116.99113 -221.303342)
		(width 0.1143)
		(layer "In13.Cu")
		(net "GMI_CPU0_G0_CPU1_G2_TX_DN<4>")
	)
	(segment
		(start 153.698448 -185.778648)
		(end 153.51633 -185.76036)
		(width 0.14224)
		(layer "In13.Cu")
		(net "GMI_CPU0_G0_CPU1_G2_TX_DN<4>")
	)
	(segment
		(start 354.231702 -230.247952)
		(end 354.298758 -230.208836)
		(width 0.1143)
		(layer "In13.Cu")
		(net "GMI_CPU0_G0_CPU1_G2_TX_DN<4>")
	)
	(segment
		(start 117.26672 -237.65891)
		(end 117.227604 -237.68177)
		(width 0.1143)
		(layer "In13.Cu")
		(net "GMI_CPU0_G0_CPU1_G2_TX_DN<4>")
	)
	(segment
		(start 152.256998 -186.793378)
		(end 152.256744 -186.793124)
		(width 0.14224)
		(layer "In13.Cu")
		(net "GMI_CPU0_G0_CPU1_G2_TX_DN<4>")
	)
	(segment
		(start 151.914352 -187.241434)
		(end 151.732234 -187.2234)
		(width 0.14224)
		(layer "In13.Cu")
		(net "GMI_CPU0_G0_CPU1_G2_TX_DN<4>")
	)
	(segment
		(start 151.329898 -187.553092)
		(end 151.311864 -187.735464)
		(width 0.14224)
		(layer "In13.Cu")
		(net "GMI_CPU0_G0_CPU1_G2_TX_DN<4>")
	)
	(segment
		(start 148.116036 -190.188088)
		(end 146.269202 -191.702182)
		(width 0.14224)
		(layer "In13.Cu")
		(net "GMI_CPU0_G0_CPU1_G2_TX_DN<4>")
	)
	(segment
		(start 117.26672 -227.939092)
		(end 117.227604 -227.961952)
		(width 0.1143)
		(layer "In13.Cu")
		(net "GMI_CPU0_G0_CPU1_G2_TX_DN<4>")
	)
	(segment
		(start 117.197124 -230.20909)
		(end 117.26418 -230.248206)
		(width 0.1143)
		(layer "In13.Cu")
		(net "GMI_CPU0_G0_CPU1_G2_TX_DN<4>")
	)
	(segment
		(start 117.197124 -222.109284)
		(end 117.227604 -222.127064)
		(width 0.1143)
		(layer "In13.Cu")
		(net "GMI_CPU0_G0_CPU1_G2_TX_DN<4>")
	)
	(segment
		(start 117.26672 -234.418886)
		(end 117.227604 -234.441746)
		(width 0.1143)
		(layer "In13.Cu")
		(net "GMI_CPU0_G0_CPU1_G2_TX_DN<4>")
	)
	(segment
		(start 165.865048 -178.97475)
		(end 158.644082 -181.556914)
		(width 0.14224)
		(layer "In13.Cu")
		(net "GMI_CPU0_G0_CPU1_G2_TX_DN<4>")
	)
	(segment
		(start 354.504752 -221.303088)
		(end 354.504752 -221.145862)
		(width 0.1143)
		(layer "In13.Cu")
		(net "GMI_CPU0_G0_CPU1_G2_TX_DN<4>")
	)
	(segment
		(start 354.298758 -234.459272)
		(end 354.229162 -234.418632)
		(width 0.1143)
		(layer "In13.Cu")
		(net "GMI_CPU0_G0_CPU1_G2_TX_DN<4>")
	)
	(segment
		(start 117.227604 -229.581964)
		(end 117.195092 -229.60076)
		(width 0.1143)
		(layer "In13.Cu")
		(net "GMI_CPU0_G0_CPU1_G2_TX_DN<4>")
	)
	(segment
		(start 117.197124 -236.689138)
		(end 117.227604 -236.706918)
		(width 0.1143)
		(layer "In13.Cu")
		(net "GMI_CPU0_G0_CPU1_G2_TX_DN<4>")
	)
	(segment
		(start 117.03685 -221.071948)
		(end 117.03685 -221.100396)
		(width 0.1143)
		(layer "In13.Cu")
		(net "GMI_CPU0_G0_CPU1_G2_TX_DN<4>")
	)
	(segment
		(start 117.227604 -235.086906)
		(end 117.26672 -235.109766)
		(width 0.1143)
		(layer "In13.Cu")
		(net "GMI_CPU0_G0_CPU1_G2_TX_DN<4>")
	)
	(segment
		(start 151.732234 -187.2234)
		(end 151.329898 -187.553092)
		(width 0.14224)
		(layer "In13.Cu")
		(net "GMI_CPU0_G0_CPU1_G2_TX_DN<4>")
	)
	(segment
		(start 150.987506 -188.001402)
		(end 150.805388 -187.983368)
		(width 0.14224)
		(layer "In13.Cu")
		(net "GMI_CPU0_G0_CPU1_G2_TX_DN<4>")
	)
	(segment
		(start 117.227604 -234.441746)
		(end 117.197124 -234.459526)
		(width 0.1143)
		(layer "In13.Cu")
		(net "GMI_CPU0_G0_CPU1_G2_TX_DN<4>")
	)
	(segment
		(start 117.03685 -218.58224)
		(end 117.03685 -221.071948)
		(width 0.14224)
		(layer "In13.Cu")
		(net "GMI_CPU0_G0_CPU1_G2_TX_DN<4>")
	)
	(segment
		(start 148.639276 -189.936628)
		(end 148.309076 -190.207392)
		(width 0.14224)
		(layer "In13.Cu")
		(net "GMI_CPU0_G0_CPU1_G2_TX_DN<4>")
	)
	(segment
		(start 354.379022 -238.004096)
		(end 354.448872 -237.934246)
		(width 0.1143)
		(layer "In13.Cu")
		(net "GMI_CPU0_G0_CPU1_G2_TX_DN<4>")
	)
	(segment
		(start 354.229162 -223.769682)
		(end 354.298758 -223.729042)
		(width 0.1143)
		(layer "In13.Cu")
		(net "GMI_CPU0_G0_CPU1_G2_TX_DN<4>")
	)
	(segment
		(start 146.268948 -191.702436)
		(end 144.378426 -193.252344)
		(width 0.14224)
		(layer "In13.Cu")
		(net "GMI_CPU0_G0_CPU1_G2_TX_DN<4>")
	)
	(segment
		(start 117.197124 -228.589332)
		(end 117.227604 -228.607112)
		(width 0.1143)
		(layer "In13.Cu")
		(net "GMI_CPU0_G0_CPU1_G2_TX_DN<4>")
	)
	(segment
		(start 153.19248 -186.026552)
		(end 153.192226 -186.026044)
		(width 0.14224)
		(layer "In13.Cu")
		(net "GMI_CPU0_G0_CPU1_G2_TX_DN<4>")
	)
	(segment
		(start 117.227604 -224.721928)
		(end 117.197124 -224.739708)
		(width 0.1143)
		(layer "In13.Cu")
		(net "GMI_CPU0_G0_CPU1_G2_TX_DN<4>")
	)
	(segment
		(start 149.511512 -189.221364)
		(end 149.181312 -189.492128)
		(width 0.14224)
		(layer "In13.Cu")
		(net "GMI_CPU0_G0_CPU1_G2_TX_DN<4>")
	)
	(segment
		(start 154.022806 -185.51271)
		(end 153.698448 -185.778648)
		(width 0.14224)
		(layer "In13.Cu")
		(net "GMI_CPU0_G0_CPU1_G2_TX_DN<4>")
	)
	(segment
		(start 117.26672 -224.699068)
		(end 117.227604 -224.721928)
		(width 0.1143)
		(layer "In13.Cu")
		(net "GMI_CPU0_G0_CPU1_G2_TX_DN<4>")
	)
	(segment
		(start 354.229162 -222.14967)
		(end 354.298758 -222.10903)
		(width 0.1143)
		(layer "In13.Cu")
		(net "GMI_CPU0_G0_CPU1_G2_TX_DN<4>")
	)
	(segment
		(start 117.197124 -235.069126)
		(end 117.227604 -235.086906)
		(width 0.1143)
		(layer "In13.Cu")
		(net "GMI_CPU0_G0_CPU1_G2_TX_DN<4>")
	)
	(segment
		(start 354.229162 -236.729524)
		(end 354.298758 -236.688884)
		(width 0.1143)
		(layer "In13.Cu")
		(net "GMI_CPU0_G0_CPU1_G2_TX_DN<4>")
	)
	(segment
		(start 117.227604 -225.367088)
		(end 117.26672 -225.389948)
		(width 0.1143)
		(layer "In13.Cu")
		(net "GMI_CPU0_G0_CPU1_G2_TX_DN<4>")
	)
	(segment
		(start 117.227604 -223.101916)
		(end 117.197124 -223.119696)
		(width 0.1143)
		(layer "In13.Cu")
		(net "GMI_CPU0_G0_CPU1_G2_TX_DN<4>")
	)
	(segment
		(start 117.03685 -221.100396)
		(end 116.99113 -221.146116)
		(width 0.1143)
		(layer "In13.Cu")
		(net "GMI_CPU0_G0_CPU1_G2_TX_DN<4>")
	)
	(segment
		(start 144.378426 -193.252344)
		(end 144.149318 -193.32194)
		(width 0.14224)
		(layer "In13.Cu")
		(net "GMI_CPU0_G0_CPU1_G2_TX_DN<4>")
	)
	(segment
		(start 154.547062 -185.082942)
		(end 154.364944 -185.064654)
		(width 0.14224)
		(layer "In13.Cu")
		(net "GMI_CPU0_G0_CPU1_G2_TX_DN<4>")
	)
	(segment
		(start 149.530562 -189.028578)
		(end 149.530562 -189.028324)
		(width 0.14224)
		(layer "In13.Cu")
		(net "GMI_CPU0_G0_CPU1_G2_TX_DN<4>")
	)
	(segment
		(start 354.229162 -225.389694)
		(end 354.298758 -225.349054)
		(width 0.1143)
		(layer "In13.Cu")
		(net "GMI_CPU0_G0_CPU1_G2_TX_DN<4>")
	)
	(segment
		(start 152.849834 -186.474354)
		(end 152.667462 -186.45632)
		(width 0.14224)
		(layer "In13.Cu")
		(net "GMI_CPU0_G0_CPU1_G2_TX_DN<4>")
	)
	(segment
		(start 354.45573 -221.35211)
		(end 354.504752 -221.303088)
		(width 0.1143)
		(layer "In13.Cu")
		(net "GMI_CPU0_G0_CPU1_G2_TX_DN<4>")
	)
	(segment
		(start 154.87142 -184.817004)
		(end 154.547062 -185.082942)
		(width 0.14224)
		(layer "In13.Cu")
		(net "GMI_CPU0_G0_CPU1_G2_TX_DN<4>")
	)
	(segment
		(start 354.459032 -218.557348)
		(end 351.05086 -212.817456)
		(width 0.14224)
		(layer "In13.Cu")
		(net "GMI_CPU0_G0_CPU1_G2_TX_DN<4>")
	)
	(segment
		(start 302.904144 -179.774088)
		(end 165.865048 -178.97475)
		(width 0.14224)
		(layer "In13.Cu")
		(net "GMI_CPU0_G0_CPU1_G2_TX_DN<4>")
	)
	(segment
		(start 150.402798 -188.313314)
		(end 150.383748 -188.506354)
		(width 0.14224)
		(layer "In13.Cu")
		(net "GMI_CPU0_G0_CPU1_G2_TX_DN<4>")
	)
	(segment
		(start 117.26672 -229.559104)
		(end 117.227604 -229.581964)
		(width 0.1143)
		(layer "In13.Cu")
		(net "GMI_CPU0_G0_CPU1_G2_TX_DN<4>")
	)
	(segment
		(start 154.364944 -185.064654)
		(end 154.365198 -185.064908)
		(width 0.14224)
		(layer "In13.Cu")
		(net "GMI_CPU0_G0_CPU1_G2_TX_DN<4>")
	)
	(segment
		(start 354.504752 -221.145862)
		(end 354.459032 -221.100142)
		(width 0.1143)
		(layer "In13.Cu")
		(net "GMI_CPU0_G0_CPU1_G2_TX_DN<4>")
	)
	(segment
		(start 117.26672 -226.31908)
		(end 117.227604 -226.34194)
		(width 0.1143)
		(layer "In13.Cu")
		(net "GMI_CPU0_G0_CPU1_G2_TX_DN<4>")
	)
	(segment
		(start 149.530562 -189.028324)
		(end 149.511512 -189.221364)
		(width 0.14224)
		(layer "In13.Cu")
		(net "GMI_CPU0_G0_CPU1_G2_TX_DN<4>")
	)
	(segment
		(start 117.197124 -226.96932)
		(end 117.227604 -226.9871)
		(width 0.1143)
		(layer "In13.Cu")
		(net "GMI_CPU0_G0_CPU1_G2_TX_DN<4>")
	)
	(segment
		(start 117.227604 -222.127064)
		(end 117.26672 -222.149924)
		(width 0.1143)
		(layer "In13.Cu")
		(net "GMI_CPU0_G0_CPU1_G2_TX_DN<4>")
	)
	(segment
		(start 354.298758 -237.699296)
		(end 354.229162 -237.658656)
		(width 0.1143)
		(layer "In13.Cu")
		(net "GMI_CPU0_G0_CPU1_G2_TX_DN<4>")
	)
	(segment
		(start 117.227604 -237.68177)
		(end 117.197124 -237.69955)
		(width 0.1143)
		(layer "In13.Cu")
		(net "GMI_CPU0_G0_CPU1_G2_TX_DN<4>")
	)
	(segment
		(start 154.04084 -185.330338)
		(end 154.022806 -185.51271)
		(width 0.14224)
		(layer "In13.Cu")
		(net "GMI_CPU0_G0_CPU1_G2_TX_DN<4>")
	)
	(segment
		(start 150.053548 -188.777118)
		(end 149.860508 -188.757814)
		(width 0.14224)
		(layer "In13.Cu")
		(net "GMI_CPU0_G0_CPU1_G2_TX_DN<4>")
	)
	(segment
		(start 148.658326 -189.743588)
		(end 148.639276 -189.936628)
		(width 0.14224)
		(layer "In13.Cu")
		(net "GMI_CPU0_G0_CPU1_G2_TX_DN<4>")
	)
	(segment
		(start 307.568854 -179.774088)
		(end 302.904144 -179.774088)
		(width 0.14224)
		(layer "In13.Cu")
		(net "GMI_CPU0_G0_CPU1_G2_TX_DN<4>")
	)
	(segment
		(start 117.227604 -236.061758)
		(end 117.197124 -236.079538)
		(width 0.1143)
		(layer "In13.Cu")
		(net "GMI_CPU0_G0_CPU1_G2_TX_DN<4>")
	)
	(segment
		(start 354.298758 -227.979478)
		(end 354.229162 -227.938838)
		(width 0.1143)
		(layer "In13.Cu")
		(net "GMI_CPU0_G0_CPU1_G2_TX_DN<4>")
	)
	(segment
		(start 354.298758 -224.739454)
		(end 354.229162 -224.698814)
		(width 0.1143)
		(layer "In13.Cu")
		(net "GMI_CPU0_G0_CPU1_G2_TX_DN<4>")
	)
	(segment
		(start 354.229162 -228.629718)
		(end 354.298758 -228.589078)
		(width 0.1143)
		(layer "In13.Cu")
		(net "GMI_CPU0_G0_CPU1_G2_TX_DN<4>")
	)
	(segment
		(start 148.988272 -189.473078)
		(end 148.658326 -189.743588)
		(width 0.14224)
		(layer "In13.Cu")
		(net "GMI_CPU0_G0_CPU1_G2_TX_DN<4>")
	)
	(segment
		(start 154.041094 -185.330846)
		(end 154.04084 -185.330338)
		(width 0.14224)
		(layer "In13.Cu")
		(net "GMI_CPU0_G0_CPU1_G2_TX_DN<4>")
	)
	(segment
		(start 152.256744 -186.793124)
		(end 152.23871 -186.975496)
		(width 0.14224)
		(layer "In13.Cu")
		(net "GMI_CPU0_G0_CPU1_G2_TX_DN<4>")
	)
	(segment
		(start 354.298758 -232.83926)
		(end 354.229162 -232.79862)
		(width 0.1143)
		(layer "In13.Cu")
		(net "GMI_CPU0_G0_CPU1_G2_TX_DN<4>")
	)
	(segment
		(start 152.23871 -186.975496)
		(end 151.914352 -187.241434)
		(width 0.14224)
		(layer "In13.Cu")
		(net "GMI_CPU0_G0_CPU1_G2_TX_DN<4>")
	)
	(segment
		(start 117.04701 -237.9345)
		(end 117.11686 -238.00435)
		(width 0.1143)
		(layer "In13.Cu")
		(net "GMI_CPU0_G0_CPU1_G2_TX_DN<4>")
	)
	(segment
		(start 149.181312 -189.492128)
		(end 148.988272 -189.473078)
		(width 0.14224)
		(layer "In13.Cu")
		(net "GMI_CPU0_G0_CPU1_G2_TX_DN<4>")
	)
	(segment
		(start 149.860508 -188.758068)
		(end 149.530562 -189.028578)
		(width 0.14224)
		(layer "In13.Cu")
		(net "GMI_CPU0_G0_CPU1_G2_TX_DN<4>")
	)
	(segment
		(start 117.197124 -223.729296)
		(end 117.227604 -223.747076)
		(width 0.1143)
		(layer "In13.Cu")
		(net "GMI_CPU0_G0_CPU1_G2_TX_DN<4>")
	)
	(segment
		(start 354.298758 -223.119442)
		(end 354.229162 -223.078802)
		(width 0.1143)
		(layer "In13.Cu")
		(net "GMI_CPU0_G0_CPU1_G2_TX_DN<4>")
	)
	(segment
		(start 354.30079 -231.220518)
		(end 354.268278 -231.201722)
		(width 0.1143)
		(layer "In13.Cu")
		(net "GMI_CPU0_G0_CPU1_G2_TX_DN<4>")
	)
	(segment
		(start 150.805388 -187.983368)
		(end 150.402798 -188.313314)
		(width 0.14224)
		(layer "In13.Cu")
		(net "GMI_CPU0_G0_CPU1_G2_TX_DN<4>")
	)
	(segment
		(start 153.51633 -185.76036)
		(end 153.516584 -185.760614)
		(width 0.14224)
		(layer "In13.Cu")
		(net "GMI_CPU0_G0_CPU1_G2_TX_DN<4>")
	)
	(segment
		(start 120.45569 -212.749638)
		(end 117.03685 -218.58224)
		(width 0.14224)
		(layer "In13.Cu")
		(net "GMI_CPU0_G0_CPU1_G2_TX_DN<4>")
	)
	(segment
		(start 117.227604 -232.821734)
		(end 117.197124 -232.839514)
		(width 0.1143)
		(layer "In13.Cu")
		(net "GMI_CPU0_G0_CPU1_G2_TX_DN<4>")
	)
	(segment
		(start 117.11686 -238.00435)
		(end 117.414802 -238.00435)
		(width 0.1143)
		(layer "In13.Cu")
		(net "GMI_CPU0_G0_CPU1_G2_TX_DN<4>")
	)
	(segment
		(start 153.192226 -186.026044)
		(end 153.174192 -186.208416)
		(width 0.14224)
		(layer "In13.Cu")
		(net "GMI_CPU0_G0_CPU1_G2_TX_DN<4>")
	)
	(segment
		(start 117.227604 -236.706918)
		(end 117.26672 -236.729778)
		(width 0.1143)
		(layer "In13.Cu")
		(net "GMI_CPU0_G0_CPU1_G2_TX_DN<4>")
	)
	(segment
		(start 153.174192 -186.208416)
		(end 152.849834 -186.474354)
		(width 0.14224)
		(layer "In13.Cu")
		(net "GMI_CPU0_G0_CPU1_G2_TX_DN<4>")
	)
	(segment
		(start 316.022736 -184.09539)
		(end 309.794656 -180.56987)
		(width 0.14224)
		(layer "In13.Cu")
		(net "GMI_CPU0_G0_CPU1_G2_TX_DN<4>")
	)
	(segment
		(start 117.26672 -231.179116)
		(end 117.227604 -231.201976)
		(width 0.1143)
		(layer "In13.Cu")
		(net "GMI_CPU0_G0_CPU1_G2_TX_DN<4>")
	)
	(segment
		(start 354.229162 -231.869488)
		(end 354.298758 -231.828848)
		(width 0.1143)
		(layer "In13.Cu")
		(net "GMI_CPU0_G0_CPU1_G2_TX_DN<4>")
	)
	(segment
		(start 117.227604 -223.747076)
		(end 117.26672 -223.769936)
		(width 0.1143)
		(layer "In13.Cu")
		(net "GMI_CPU0_G0_CPU1_G2_TX_DN<4>")
	)
	(segment
		(start 117.040152 -221.352364)
		(end 117.040152 -221.804484)
		(width 0.1143)
		(layer "In13.Cu")
		(net "GMI_CPU0_G0_CPU1_G2_TX_DN<4>")
	)
	(segment
		(start 117.26672 -232.798874)
		(end 117.227604 -232.821734)
		(width 0.1143)
		(layer "In13.Cu")
		(net "GMI_CPU0_G0_CPU1_G2_TX_DN<4>")
	)
	(segment
		(start 117.26672 -236.038898)
		(end 117.227604 -236.061758)
		(width 0.1143)
		(layer "In13.Cu")
		(net "GMI_CPU0_G0_CPU1_G2_TX_DN<4>")
	)
	(segment
		(start 151.311864 -187.735464)
		(end 150.987506 -188.001402)
		(width 0.14224)
		(layer "In13.Cu")
		(net "GMI_CPU0_G0_CPU1_G2_TX_DN<4>")
	)
	(segment
		(start 354.229162 -227.009706)
		(end 354.298758 -226.969066)
		(width 0.1143)
		(layer "In13.Cu")
		(net "GMI_CPU0_G0_CPU1_G2_TX_DN<4>")
	)
	(segment
		(start 150.383748 -188.506354)
		(end 150.053548 -188.777118)
		(width 0.14224)
		(layer "In13.Cu")
		(net "GMI_CPU0_G0_CPU1_G2_TX_DN<4>")
	)
	(segment
		(start 152.667462 -186.45632)
		(end 152.667716 -186.456574)
		(width 0.14224)
		(layer "In13.Cu")
		(net "GMI_CPU0_G0_CPU1_G2_TX_DN<4>")
	)
	(segment
		(start 117.227604 -226.9871)
		(end 117.26672 -227.00996)
		(width 0.1143)
		(layer "In13.Cu")
		(net "GMI_CPU0_G0_CPU1_G2_TX_DN<4>")
	)
	(segment
		(start 309.794656 -180.56987)
		(end 307.568854 -179.774088)
		(width 0.14224)
		(layer "In13.Cu")
		(net "GMI_CPU0_G0_CPU1_G2_TX_DN<4>")
	)
	(segment
		(start 154.365198 -185.064908)
		(end 154.041094 -185.330846)
		(width 0.14224)
		(layer "In13.Cu")
		(net "GMI_CPU0_G0_CPU1_G2_TX_DN<4>")
	)
	(segment
		(start 153.516584 -185.760614)
		(end 153.19248 -186.026552)
		(width 0.14224)
		(layer "In13.Cu")
		(net "GMI_CPU0_G0_CPU1_G2_TX_DN<4>")
	)
	(segment
		(start 354.30079 -229.600506)
		(end 354.268278 -229.58171)
		(width 0.1143)
		(layer "In13.Cu")
		(net "GMI_CPU0_G0_CPU1_G2_TX_DN<4>")
	)
	(segment
		(start 152.667716 -186.456574)
		(end 152.256998 -186.793378)
		(width 0.14224)
		(layer "In13.Cu")
		(net "GMI_CPU0_G0_CPU1_G2_TX_DN<4>")
	)
	(segment
		(start 354.268278 -229.58171)
		(end 354.229162 -229.55885)
		(width 0.1143)
		(layer "In13.Cu")
		(net "GMI_CPU0_G0_CPU1_G2_TX_DN<4>")
	)
	(segment
		(start 354.229162 -235.109512)
		(end 354.298758 -235.068872)
		(width 0.1143)
		(layer "In13.Cu")
		(net "GMI_CPU0_G0_CPU1_G2_TX_DN<4>")
	)
	(segment
		(start 354.45573 -221.80423)
		(end 354.45573 -221.35211)
		(width 0.1143)
		(layer "In13.Cu")
		(net "GMI_CPU0_G0_CPU1_G2_TX_DN<4>")
	)
	(segment
		(start 117.197124 -233.449114)
		(end 117.227604 -233.466894)
		(width 0.1143)
		(layer "In13.Cu")
		(net "GMI_CPU0_G0_CPU1_G2_TX_DN<4>")
	)
	(segment
		(start 148.309076 -190.207392)
		(end 148.116036 -190.188088)
		(width 0.14224)
		(layer "In13.Cu")
		(net "GMI_CPU0_G0_CPU1_G2_TX_DN<4>")
	)
	(segment
		(start 117.227604 -233.466894)
		(end 117.26672 -233.489754)
		(width 0.1143)
		(layer "In13.Cu")
		(net "GMI_CPU0_G0_CPU1_G2_TX_DN<4>")
	)
	(segment
		(start 149.860508 -188.757814)
		(end 149.860508 -188.758068)
		(width 0.14224)
		(layer "In13.Cu")
		(net "GMI_CPU0_G0_CPU1_G2_TX_DN<4>")
	)
	(segment
		(start 158.644082 -181.556914)
		(end 154.889454 -184.634632)
		(width 0.14224)
		(layer "In13.Cu")
		(net "GMI_CPU0_G0_CPU1_G2_TX_DN<4>")
	)
	(segment
		(start 354.298758 -236.079284)
		(end 354.229162 -236.038644)
		(width 0.1143)
		(layer "In13.Cu")
		(net "GMI_CPU0_G0_CPU1_G2_TX_DN<4>")
	)
	(segment
		(start 354.459032 -221.093538)
		(end 354.459032 -218.557348)
		(width 0.14224)
		(layer "In13.Cu")
		(net "GMI_CPU0_G0_CPU1_G2_TX_DN<4>")
	)
	(segment
		(start 146.269202 -191.702182)
		(end 146.268948 -191.702436)
		(width 0.14224)
		(layer "In13.Cu")
		(net "GMI_CPU0_G0_CPU1_G2_TX_DN<4>")
	)
	(segment
		(start 117.26672 -223.079056)
		(end 117.227604 -223.101916)
		(width 0.1143)
		(layer "In13.Cu")
		(net "GMI_CPU0_G0_CPU1_G2_TX_DN<4>")
	)
	(segment
		(start 117.197124 -231.829102)
		(end 117.227604 -231.846882)
		(width 0.1143)
		(layer "In13.Cu")
		(net "GMI_CPU0_G0_CPU1_G2_TX_DN<4>")
	)
	(segment
		(start 354.459032 -221.100142)
		(end 354.459032 -221.093538)
		(width 0.1143)
		(layer "In13.Cu")
		(net "GMI_CPU0_G0_CPU1_G2_TX_DN<4>")
	)
	(segment
		(start 354.268278 -231.201722)
		(end 354.229162 -231.178862)
		(width 0.1143)
		(layer "In13.Cu")
		(net "GMI_CPU0_G0_CPU1_G2_TX_DN<4>")
	)
	(segment
		(start 117.227604 -228.607112)
		(end 117.26672 -228.629972)
		(width 0.1143)
		(layer "In13.Cu")
		(net "GMI_CPU0_G0_CPU1_G2_TX_DN<4>")
	)
	(segment
		(start 351.05086 -212.817456)
		(end 316.022736 -184.09539)
		(width 0.14224)
		(layer "In13.Cu")
		(net "GMI_CPU0_G0_CPU1_G2_TX_DN<4>")
	)
	(segment
		(start 117.197124 -225.349308)
		(end 117.227604 -225.367088)
		(width 0.1143)
		(layer "In13.Cu")
		(net "GMI_CPU0_G0_CPU1_G2_TX_DN<4>")
	)
	(segment
		(start 117.227604 -227.961952)
		(end 117.197124 -227.979732)
		(width 0.1143)
		(layer "In13.Cu")
		(net "GMI_CPU0_G0_CPU1_G2_TX_DN<4>")
	)
	(segment
		(start 354.229162 -233.4895)
		(end 354.298758 -233.44886)
		(width 0.1143)
		(layer "In13.Cu")
		(net "GMI_CPU0_G0_CPU1_G2_TX_DN<4>")
	)
	(segment
		(start 144.149318 -193.32194)
		(end 120.45569 -212.749638)
		(width 0.14224)
		(layer "In13.Cu")
		(net "GMI_CPU0_G0_CPU1_G2_TX_DN<4>")
	)
	(segment
		(start 117.227604 -226.34194)
		(end 117.197124 -226.35972)
		(width 0.1143)
		(layer "In13.Cu")
		(net "GMI_CPU0_G0_CPU1_G2_TX_DN<4>")
	)
	(arc
		(start 354.45573 -231.524048)
		(mid 354.414764 -231.353642)
		(end 354.30079 -231.220518)
		(width 0.1143)
		(layer "In13.Cu")
		(net "GMI_CPU0_G0_CPU1_G2_TX_DN<4>")
	)
	(arc
		(start 117.26672 -225.389948)
		(mid 117.510047 -225.854514)
		(end 117.26672 -226.31908)
		(width 0.1143)
		(layer "In13.Cu")
		(net "GMI_CPU0_G0_CPU1_G2_TX_DN<4>")
	)
	(arc
		(start 354.45573 -229.904036)
		(mid 354.414764 -229.73363)
		(end 354.30079 -229.600506)
		(width 0.1143)
		(layer "In13.Cu")
		(net "GMI_CPU0_G0_CPU1_G2_TX_DN<4>")
	)
	(arc
		(start 117.040152 -229.90429)
		(mid 117.081701 -230.075712)
		(end 117.197124 -230.20909)
		(width 0.1143)
		(layer "In13.Cu")
		(net "GMI_CPU0_G0_CPU1_G2_TX_DN<4>")
	)
	(arc
		(start 117.26672 -236.729778)
		(mid 117.510047 -237.194344)
		(end 117.26672 -237.65891)
		(width 0.1143)
		(layer "In13.Cu")
		(net "GMI_CPU0_G0_CPU1_G2_TX_DN<4>")
	)
	(arc
		(start 117.197124 -224.739708)
		(mid 117.040147 -225.044508)
		(end 117.197124 -225.349308)
		(width 0.1143)
		(layer "In13.Cu")
		(net "GMI_CPU0_G0_CPU1_G2_TX_DN<4>")
	)
	(arc
		(start 117.197124 -237.69955)
		(mid 117.099359 -237.802526)
		(end 117.04701 -237.9345)
		(width 0.1143)
		(layer "In13.Cu")
		(net "GMI_CPU0_G0_CPU1_G2_TX_DN<4>")
	)
	(arc
		(start 354.298758 -233.44886)
		(mid 354.455735 -233.14406)
		(end 354.298758 -232.83926)
		(width 0.1143)
		(layer "In13.Cu")
		(net "GMI_CPU0_G0_CPU1_G2_TX_DN<4>")
	)
	(arc
		(start 354.298758 -223.729042)
		(mid 354.455735 -223.424242)
		(end 354.298758 -223.119442)
		(width 0.1143)
		(layer "In13.Cu")
		(net "GMI_CPU0_G0_CPU1_G2_TX_DN<4>")
	)
	(arc
		(start 354.229162 -232.79862)
		(mid 353.985835 -232.334054)
		(end 354.229162 -231.869488)
		(width 0.1143)
		(layer "In13.Cu")
		(net "GMI_CPU0_G0_CPU1_G2_TX_DN<4>")
	)
	(arc
		(start 354.229162 -234.418632)
		(mid 353.985835 -233.954066)
		(end 354.229162 -233.4895)
		(width 0.1143)
		(layer "In13.Cu")
		(net "GMI_CPU0_G0_CPU1_G2_TX_DN<4>")
	)
	(arc
		(start 117.26672 -227.00996)
		(mid 117.510047 -227.474526)
		(end 117.26672 -227.939092)
		(width 0.1143)
		(layer "In13.Cu")
		(net "GMI_CPU0_G0_CPU1_G2_TX_DN<4>")
	)
	(arc
		(start 354.229162 -237.658656)
		(mid 353.985835 -237.19409)
		(end 354.229162 -236.729524)
		(width 0.1143)
		(layer "In13.Cu")
		(net "GMI_CPU0_G0_CPU1_G2_TX_DN<4>")
	)
	(arc
		(start 354.448872 -237.934246)
		(mid 354.396455 -237.802315)
		(end 354.298758 -237.699296)
		(width 0.1143)
		(layer "In13.Cu")
		(net "GMI_CPU0_G0_CPU1_G2_TX_DN<4>")
	)
	(arc
		(start 117.26672 -222.149924)
		(mid 117.510047 -222.61449)
		(end 117.26672 -223.079056)
		(width 0.1143)
		(layer "In13.Cu")
		(net "GMI_CPU0_G0_CPU1_G2_TX_DN<4>")
	)
	(arc
		(start 117.26672 -233.489754)
		(mid 117.510047 -233.95432)
		(end 117.26672 -234.418886)
		(width 0.1143)
		(layer "In13.Cu")
		(net "GMI_CPU0_G0_CPU1_G2_TX_DN<4>")
	)
	(arc
		(start 117.26672 -223.769936)
		(mid 117.510047 -224.234502)
		(end 117.26672 -224.699068)
		(width 0.1143)
		(layer "In13.Cu")
		(net "GMI_CPU0_G0_CPU1_G2_TX_DN<4>")
	)
	(arc
		(start 354.298758 -222.10903)
		(mid 354.414185 -221.975654)
		(end 354.45573 -221.80423)
		(width 0.1143)
		(layer "In13.Cu")
		(net "GMI_CPU0_G0_CPU1_G2_TX_DN<4>")
	)
	(arc
		(start 117.040152 -231.524302)
		(mid 117.081701 -231.695724)
		(end 117.197124 -231.829102)
		(width 0.1143)
		(layer "In13.Cu")
		(net "GMI_CPU0_G0_CPU1_G2_TX_DN<4>")
	)
	(arc
		(start 117.197124 -223.119696)
		(mid 117.040147 -223.424496)
		(end 117.197124 -223.729296)
		(width 0.1143)
		(layer "In13.Cu")
		(net "GMI_CPU0_G0_CPU1_G2_TX_DN<4>")
	)
	(arc
		(start 354.298758 -228.589078)
		(mid 354.455735 -228.284278)
		(end 354.298758 -227.979478)
		(width 0.1143)
		(layer "In13.Cu")
		(net "GMI_CPU0_G0_CPU1_G2_TX_DN<4>")
	)
	(arc
		(start 117.197124 -226.35972)
		(mid 117.040147 -226.66452)
		(end 117.197124 -226.96932)
		(width 0.1143)
		(layer "In13.Cu")
		(net "GMI_CPU0_G0_CPU1_G2_TX_DN<4>")
	)
	(arc
		(start 354.298758 -236.688884)
		(mid 354.455735 -236.384084)
		(end 354.298758 -236.079284)
		(width 0.1143)
		(layer "In13.Cu")
		(net "GMI_CPU0_G0_CPU1_G2_TX_DN<4>")
	)
	(arc
		(start 354.298758 -231.828848)
		(mid 354.414185 -231.695472)
		(end 354.45573 -231.524048)
		(width 0.1143)
		(layer "In13.Cu")
		(net "GMI_CPU0_G0_CPU1_G2_TX_DN<4>")
	)
	(arc
		(start 354.298758 -235.068872)
		(mid 354.455735 -234.764072)
		(end 354.298758 -234.459272)
		(width 0.1143)
		(layer "In13.Cu")
		(net "GMI_CPU0_G0_CPU1_G2_TX_DN<4>")
	)
	(arc
		(start 117.26672 -235.109766)
		(mid 117.510047 -235.574332)
		(end 117.26672 -236.038898)
		(width 0.1143)
		(layer "In13.Cu")
		(net "GMI_CPU0_G0_CPU1_G2_TX_DN<4>")
	)
	(arc
		(start 117.197124 -234.459526)
		(mid 117.040147 -234.764326)
		(end 117.197124 -235.069126)
		(width 0.1143)
		(layer "In13.Cu")
		(net "GMI_CPU0_G0_CPU1_G2_TX_DN<4>")
	)
	(arc
		(start 353.98583 -230.714296)
		(mid 354.051066 -230.450705)
		(end 354.231702 -230.247952)
		(width 0.1143)
		(layer "In13.Cu")
		(net "GMI_CPU0_G0_CPU1_G2_TX_DN<4>")
	)
	(arc
		(start 117.197124 -232.839514)
		(mid 117.040147 -233.144314)
		(end 117.197124 -233.449114)
		(width 0.1143)
		(layer "In13.Cu")
		(net "GMI_CPU0_G0_CPU1_G2_TX_DN<4>")
	)
	(arc
		(start 117.510052 -230.71455)
		(mid 117.445537 -230.976769)
		(end 117.26672 -231.179116)
		(width 0.1143)
		(layer "In13.Cu")
		(net "GMI_CPU0_G0_CPU1_G2_TX_DN<4>")
	)
	(arc
		(start 354.298758 -226.969066)
		(mid 354.455735 -226.664266)
		(end 354.298758 -226.359466)
		(width 0.1143)
		(layer "In13.Cu")
		(net "GMI_CPU0_G0_CPU1_G2_TX_DN<4>")
	)
	(arc
		(start 354.229162 -229.55885)
		(mid 353.985835 -229.094284)
		(end 354.229162 -228.629718)
		(width 0.1143)
		(layer "In13.Cu")
		(net "GMI_CPU0_G0_CPU1_G2_TX_DN<4>")
	)
	(arc
		(start 354.229162 -236.038644)
		(mid 353.985835 -235.574078)
		(end 354.229162 -235.109512)
		(width 0.1143)
		(layer "In13.Cu")
		(net "GMI_CPU0_G0_CPU1_G2_TX_DN<4>")
	)
	(arc
		(start 117.195092 -231.220772)
		(mid 117.081163 -231.353919)
		(end 117.040152 -231.524302)
		(width 0.1143)
		(layer "In13.Cu")
		(net "GMI_CPU0_G0_CPU1_G2_TX_DN<4>")
	)
	(arc
		(start 354.298758 -230.208836)
		(mid 354.414185 -230.07546)
		(end 354.45573 -229.904036)
		(width 0.1143)
		(layer "In13.Cu")
		(net "GMI_CPU0_G0_CPU1_G2_TX_DN<4>")
	)
	(arc
		(start 354.229162 -226.318826)
		(mid 353.985835 -225.85426)
		(end 354.229162 -225.389694)
		(width 0.1143)
		(layer "In13.Cu")
		(net "GMI_CPU0_G0_CPU1_G2_TX_DN<4>")
	)
	(arc
		(start 117.26672 -228.629972)
		(mid 117.510047 -229.094538)
		(end 117.26672 -229.559104)
		(width 0.1143)
		(layer "In13.Cu")
		(net "GMI_CPU0_G0_CPU1_G2_TX_DN<4>")
	)
	(arc
		(start 117.26418 -230.248206)
		(mid 117.444832 -230.450951)
		(end 117.510052 -230.71455)
		(width 0.1143)
		(layer "In13.Cu")
		(net "GMI_CPU0_G0_CPU1_G2_TX_DN<4>")
	)
	(arc
		(start 354.229162 -227.938838)
		(mid 353.985835 -227.474272)
		(end 354.229162 -227.009706)
		(width 0.1143)
		(layer "In13.Cu")
		(net "GMI_CPU0_G0_CPU1_G2_TX_DN<4>")
	)
	(arc
		(start 117.040152 -221.804484)
		(mid 117.081701 -221.975906)
		(end 117.197124 -222.109284)
		(width 0.1143)
		(layer "In13.Cu")
		(net "GMI_CPU0_G0_CPU1_G2_TX_DN<4>")
	)
	(arc
		(start 117.197124 -227.979732)
		(mid 117.040147 -228.284532)
		(end 117.197124 -228.589332)
		(width 0.1143)
		(layer "In13.Cu")
		(net "GMI_CPU0_G0_CPU1_G2_TX_DN<4>")
	)
	(arc
		(start 117.197124 -236.079538)
		(mid 117.040147 -236.384338)
		(end 117.197124 -236.689138)
		(width 0.1143)
		(layer "In13.Cu")
		(net "GMI_CPU0_G0_CPU1_G2_TX_DN<4>")
	)
	(arc
		(start 354.229162 -224.698814)
		(mid 353.985835 -224.234248)
		(end 354.229162 -223.769682)
		(width 0.1143)
		(layer "In13.Cu")
		(net "GMI_CPU0_G0_CPU1_G2_TX_DN<4>")
	)
	(arc
		(start 354.229162 -223.078802)
		(mid 353.985835 -222.614236)
		(end 354.229162 -222.14967)
		(width 0.1143)
		(layer "In13.Cu")
		(net "GMI_CPU0_G0_CPU1_G2_TX_DN<4>")
	)
	(arc
		(start 117.195092 -229.60076)
		(mid 117.081163 -229.733907)
		(end 117.040152 -229.90429)
		(width 0.1143)
		(layer "In13.Cu")
		(net "GMI_CPU0_G0_CPU1_G2_TX_DN<4>")
	)
	(arc
		(start 354.298758 -225.349054)
		(mid 354.455735 -225.044254)
		(end 354.298758 -224.739454)
		(width 0.1143)
		(layer "In13.Cu")
		(net "GMI_CPU0_G0_CPU1_G2_TX_DN<4>")
	)
	(arc
		(start 117.26672 -231.869742)
		(mid 117.510047 -232.334308)
		(end 117.26672 -232.798874)
		(width 0.1143)
		(layer "In13.Cu")
		(net "GMI_CPU0_G0_CPU1_G2_TX_DN<4>")
	)
	(arc
		(start 354.229162 -231.178862)
		(mid 354.050349 -230.976512)
		(end 353.98583 -230.714296)
		(width 0.1143)
		(layer "In13.Cu")
		(net "GMI_CPU0_G0_CPU1_G2_TX_DN<4>")
	)
	(segment
		(start 354.547932 -243.13007)
		(end 354.08108 -242.864132)
		(width 0.12954)
		(layer "F.Cu")
		(net "GMI_CPU0_G0_CPU1_G2_TX_DN<3>")
	)
	(segment
		(start 116.94795 -243.130324)
		(end 117.414802 -242.864386)
		(width 0.12954)
		(layer "F.Cu")
		(net "GMI_CPU0_G0_CPU1_G2_TX_DN<3>")
	)
	(segment
		(start 356.148132 -226.986846)
		(end 356.148894 -226.986338)
		(width 0.1143)
		(layer "In13.Cu")
		(net "GMI_CPU0_G0_CPU1_G2_TX_DN<3>")
	)
	(segment
		(start 115.348766 -224.72142)
		(end 115.34775 -224.721928)
		(width 0.1143)
		(layer "In13.Cu")
		(net "GMI_CPU0_G0_CPU1_G2_TX_DN<3>")
	)
	(segment
		(start 115.386866 -227.939092)
		(end 115.348766 -227.961444)
		(width 0.1143)
		(layer "In13.Cu")
		(net "GMI_CPU0_G0_CPU1_G2_TX_DN<3>")
	)
	(segment
		(start 115.348766 -239.94745)
		(end 115.35029 -239.948466)
		(width 0.1143)
		(layer "In13.Cu")
		(net "GMI_CPU0_G0_CPU1_G2_TX_DN<3>")
	)
	(segment
		(start 356.147116 -232.820972)
		(end 356.145592 -232.819956)
		(width 0.1143)
		(layer "In13.Cu")
		(net "GMI_CPU0_G0_CPU1_G2_TX_DN<3>")
	)
	(segment
		(start 115.34775 -232.821734)
		(end 115.346988 -232.822242)
		(width 0.1143)
		(layer "In13.Cu")
		(net "GMI_CPU0_G0_CPU1_G2_TX_DN<3>")
	)
	(segment
		(start 356.178866 -223.728788)
		(end 356.179628 -223.72828)
		(width 0.1143)
		(layer "In13.Cu")
		(net "GMI_CPU0_G0_CPU1_G2_TX_DN<3>")
	)
	(segment
		(start 356.150164 -237.682786)
		(end 356.148894 -237.682024)
		(width 0.1143)
		(layer "In13.Cu")
		(net "GMI_CPU0_G0_CPU1_G2_TX_DN<3>")
	)
	(segment
		(start 354.073714 -214.240618)
		(end 354.118926 -214.063072)
		(width 0.14224)
		(layer "In13.Cu")
		(net "GMI_CPU0_G0_CPU1_G2_TX_DN<3>")
	)
	(segment
		(start 355.754686 -217.071448)
		(end 355.799898 -216.893902)
		(width 0.14224)
		(layer "In13.Cu")
		(net "GMI_CPU0_G0_CPU1_G2_TX_DN<3>")
	)
	(segment
		(start 115.348766 -236.06125)
		(end 115.34775 -236.061758)
		(width 0.1143)
		(layer "In13.Cu")
		(net "GMI_CPU0_G0_CPU1_G2_TX_DN<3>")
	)
	(segment
		(start 115.345718 -227.963222)
		(end 115.316 -227.98024)
		(width 0.1143)
		(layer "In13.Cu")
		(net "GMI_CPU0_G0_CPU1_G2_TX_DN<3>")
	)
	(segment
		(start 117.034056 -242.781582)
		(end 117.11686 -242.864386)
		(width 0.1143)
		(layer "In13.Cu")
		(net "GMI_CPU0_G0_CPU1_G2_TX_DN<3>")
	)
	(segment
		(start 356.147116 -237.681008)
		(end 356.145592 -237.679992)
		(width 0.1143)
		(layer "In13.Cu")
		(net "GMI_CPU0_G0_CPU1_G2_TX_DN<3>")
	)
	(segment
		(start 115.348766 -226.341432)
		(end 115.34775 -226.34194)
		(width 0.1143)
		(layer "In13.Cu")
		(net "GMI_CPU0_G0_CPU1_G2_TX_DN<3>")
	)
	(segment
		(start 116.015262 -216.497662)
		(end 115.837716 -216.54389)
		(width 0.14224)
		(layer "In13.Cu")
		(net "GMI_CPU0_G0_CPU1_G2_TX_DN<3>")
	)
	(segment
		(start 355.968554 -217.432128)
		(end 355.754686 -217.071448)
		(width 0.14224)
		(layer "In13.Cu")
		(net "GMI_CPU0_G0_CPU1_G2_TX_DN<3>")
	)
	(segment
		(start 356.179882 -224.739962)
		(end 356.148132 -224.721674)
		(width 0.1143)
		(layer "In13.Cu")
		(net "GMI_CPU0_G0_CPU1_G2_TX_DN<3>")
	)
	(segment
		(start 115.78717 -240.739168)
		(end 115.856766 -240.779808)
		(width 0.1143)
		(layer "In13.Cu")
		(net "GMI_CPU0_G0_CPU1_G2_TX_DN<3>")
	)
	(segment
		(start 115.386866 -237.65891)
		(end 115.348766 -237.681262)
		(width 0.1143)
		(layer "In13.Cu")
		(net "GMI_CPU0_G0_CPU1_G2_TX_DN<3>")
	)
	(segment
		(start 356.11689 -231.864916)
		(end 356.127812 -231.858566)
		(width 0.1143)
		(layer "In13.Cu")
		(net "GMI_CPU0_G0_CPU1_G2_TX_DN<3>")
	)
	(segment
		(start 355.239574 -215.950292)
		(end 355.025706 -215.59012)
		(width 0.14224)
		(layer "In13.Cu")
		(net "GMI_CPU0_G0_CPU1_G2_TX_DN<3>")
	)
	(segment
		(start 356.109016 -227.009706)
		(end 356.147116 -226.987354)
		(width 0.1143)
		(layer "In13.Cu")
		(net "GMI_CPU0_G0_CPU1_G2_TX_DN<3>")
	)
	(segment
		(start 115.353846 -235.090462)
		(end 115.35537 -235.091478)
		(width 0.1143)
		(layer "In13.Cu")
		(net "GMI_CPU0_G0_CPU1_G2_TX_DN<3>")
	)
	(segment
		(start 356.179882 -223.11995)
		(end 356.148132 -223.101662)
		(width 0.1143)
		(layer "In13.Cu")
		(net "GMI_CPU0_G0_CPU1_G2_TX_DN<3>")
	)
	(segment
		(start 115.34775 -227.961952)
		(end 115.346988 -227.96246)
		(width 0.1143)
		(layer "In13.Cu")
		(net "GMI_CPU0_G0_CPU1_G2_TX_DN<3>")
	)
	(segment
		(start 355.20884 -241.566192)
		(end 355.239828 -241.548412)
		(width 0.1143)
		(layer "In13.Cu")
		(net "GMI_CPU0_G0_CPU1_G2_TX_DN<3>")
	)
	(segment
		(start 356.11943 -223.763586)
		(end 356.178866 -223.728788)
		(width 0.1143)
		(layer "In13.Cu")
		(net "GMI_CPU0_G0_CPU1_G2_TX_DN<3>")
	)
	(segment
		(start 115.345718 -226.34321)
		(end 115.316 -226.360228)
		(width 0.1143)
		(layer "In13.Cu")
		(net "GMI_CPU0_G0_CPU1_G2_TX_DN<3>")
	)
	(segment
		(start 356.109016 -228.629718)
		(end 356.11689 -228.625146)
		(width 0.1143)
		(layer "In13.Cu")
		(net "GMI_CPU0_G0_CPU1_G2_TX_DN<3>")
	)
	(segment
		(start 115.346988 -237.682278)
		(end 115.345718 -237.68304)
		(width 0.1143)
		(layer "In13.Cu")
		(net "GMI_CPU0_G0_CPU1_G2_TX_DN<3>")
	)
	(segment
		(start 115.346988 -239.946434)
		(end 115.34775 -239.946942)
		(width 0.1143)
		(layer "In13.Cu")
		(net "GMI_CPU0_G0_CPU1_G2_TX_DN<3>")
	)
	(segment
		(start 356.150164 -239.302798)
		(end 356.148894 -239.302036)
		(width 0.1143)
		(layer "In13.Cu")
		(net "GMI_CPU0_G0_CPU1_G2_TX_DN<3>")
	)
	(segment
		(start 115.345718 -237.68304)
		(end 115.316 -237.700058)
		(width 0.1143)
		(layer "In13.Cu")
		(net "GMI_CPU0_G0_CPU1_G2_TX_DN<3>")
	)
	(segment
		(start 356.153212 -238.323628)
		(end 356.153974 -238.32312)
		(width 0.1143)
		(layer "In13.Cu")
		(net "GMI_CPU0_G0_CPU1_G2_TX_DN<3>")
	)
	(segment
		(start 115.352068 -223.749616)
		(end 115.353846 -223.750632)
		(width 0.1143)
		(layer "In13.Cu")
		(net "GMI_CPU0_G0_CPU1_G2_TX_DN<3>")
	)
	(segment
		(start 115.35537 -228.611684)
		(end 115.386866 -228.629972)
		(width 0.1143)
		(layer "In13.Cu")
		(net "GMI_CPU0_G0_CPU1_G2_TX_DN<3>")
	)
	(segment
		(start 115.351306 -239.948974)
		(end 115.352068 -239.949482)
		(width 0.1143)
		(layer "In13.Cu")
		(net "GMI_CPU0_G0_CPU1_G2_TX_DN<3>")
	)
	(segment
		(start 356.147116 -226.341178)
		(end 356.145592 -226.340162)
		(width 0.1143)
		(layer "In13.Cu")
		(net "GMI_CPU0_G0_CPU1_G2_TX_DN<3>")
	)
	(segment
		(start 356.179628 -223.72828)
		(end 356.179882 -223.728534)
		(width 0.1143)
		(layer "In13.Cu")
		(net "GMI_CPU0_G0_CPU1_G2_TX_DN<3>")
	)
	(segment
		(start 116.57584 -242.060476)
		(end 116.57584 -242.062)
		(width 0.1143)
		(layer "In13.Cu")
		(net "GMI_CPU0_G0_CPU1_G2_TX_DN<3>")
	)
	(segment
		(start 115.34775 -235.086906)
		(end 115.348766 -235.087414)
		(width 0.1143)
		(layer "In13.Cu")
		(net "GMI_CPU0_G0_CPU1_G2_TX_DN<3>")
	)
	(segment
		(start 115.351306 -236.70895)
		(end 115.352068 -236.709458)
		(width 0.1143)
		(layer "In13.Cu")
		(net "GMI_CPU0_G0_CPU1_G2_TX_DN<3>")
	)
	(segment
		(start 356.148132 -224.721674)
		(end 356.147116 -224.721166)
		(width 0.1143)
		(layer "In13.Cu")
		(net "GMI_CPU0_G0_CPU1_G2_TX_DN<3>")
	)
	(segment
		(start 356.335838 -221.361762)
		(end 356.394512 -221.303088)
		(width 0.1143)
		(layer "In13.Cu")
		(net "GMI_CPU0_G0_CPU1_G2_TX_DN<3>")
	)
	(segment
		(start 356.109016 -231.869488)
		(end 356.11689 -231.864916)
		(width 0.1143)
		(layer "In13.Cu")
		(net "GMI_CPU0_G0_CPU1_G2_TX_DN<3>")
	)
	(segment
		(start 115.34775 -233.466894)
		(end 115.348766 -233.467402)
		(width 0.1143)
		(layer "In13.Cu")
		(net "GMI_CPU0_G0_CPU1_G2_TX_DN<3>")
	)
	(segment
		(start 115.316 -223.728788)
		(end 115.346988 -223.746568)
		(width 0.1143)
		(layer "In13.Cu")
		(net "GMI_CPU0_G0_CPU1_G2_TX_DN<3>")
	)
	(segment
		(start 356.394512 -221.303088)
		(end 356.394512 -221.145862)
		(width 0.1143)
		(layer "In13.Cu")
		(net "GMI_CPU0_G0_CPU1_G2_TX_DN<3>")
	)
	(segment
		(start 115.386866 -239.278922)
		(end 115.348766 -239.301274)
		(width 0.1143)
		(layer "In13.Cu")
		(net "GMI_CPU0_G0_CPU1_G2_TX_DN<3>")
	)
	(segment
		(start 354.287582 -214.601044)
		(end 354.073714 -214.240618)
		(width 0.14224)
		(layer "In13.Cu")
		(net "GMI_CPU0_G0_CPU1_G2_TX_DN<3>")
	)
	(segment
		(start 356.146354 -217.47734)
		(end 355.968554 -217.432128)
		(width 0.14224)
		(layer "In13.Cu")
		(net "GMI_CPU0_G0_CPU1_G2_TX_DN<3>")
	)
	(segment
		(start 115.348766 -238.327438)
		(end 115.35029 -238.328454)
		(width 0.1143)
		(layer "In13.Cu")
		(net "GMI_CPU0_G0_CPU1_G2_TX_DN<3>")
	)
	(segment
		(start 115.316 -226.968812)
		(end 115.345718 -226.98583)
		(width 0.1143)
		(layer "In13.Cu")
		(net "GMI_CPU0_G0_CPU1_G2_TX_DN<3>")
	)
	(segment
		(start 115.34775 -224.721928)
		(end 115.316 -224.740216)
		(width 0.1143)
		(layer "In13.Cu")
		(net "GMI_CPU0_G0_CPU1_G2_TX_DN<3>")
	)
	(segment
		(start 356.11689 -228.625146)
		(end 356.127812 -228.618796)
		(width 0.1143)
		(layer "In13.Cu")
		(net "GMI_CPU0_G0_CPU1_G2_TX_DN<3>")
	)
	(segment
		(start 118.660164 -211.731606)
		(end 116.736368 -215.012016)
		(width 0.14224)
		(layer "In13.Cu")
		(net "GMI_CPU0_G0_CPU1_G2_TX_DN<3>")
	)
	(segment
		(start 356.132892 -233.47553)
		(end 356.17912 -233.448606)
		(width 0.1143)
		(layer "In13.Cu")
		(net "GMI_CPU0_G0_CPU1_G2_TX_DN<3>")
	)
	(segment
		(start 310.47563 -178.764946)
		(end 308.042564 -177.894996)
		(width 0.14224)
		(layer "In13.Cu")
		(net "GMI_CPU0_G0_CPU1_G2_TX_DN<3>")
	)
	(segment
		(start 115.346988 -239.30229)
		(end 115.345718 -239.303052)
		(width 0.1143)
		(layer "In13.Cu")
		(net "GMI_CPU0_G0_CPU1_G2_TX_DN<3>")
	)
	(segment
		(start 354.67925 -215.006682)
		(end 354.465382 -214.64651)
		(width 0.14224)
		(layer "In13.Cu")
		(net "GMI_CPU0_G0_CPU1_G2_TX_DN<3>")
	)
	(segment
		(start 115.346988 -236.062266)
		(end 115.345718 -236.063028)
		(width 0.1143)
		(layer "In13.Cu")
		(net "GMI_CPU0_G0_CPU1_G2_TX_DN<3>")
	)
	(segment
		(start 356.148132 -222.12681)
		(end 356.179882 -222.108522)
		(width 0.1143)
		(layer "In13.Cu")
		(net "GMI_CPU0_G0_CPU1_G2_TX_DN<3>")
	)
	(segment
		(start 355.025706 -215.59012)
		(end 354.847906 -215.544654)
		(width 0.14224)
		(layer "In13.Cu")
		(net "GMI_CPU0_G0_CPU1_G2_TX_DN<3>")
	)
	(segment
		(start 354.847906 -215.544654)
		(end 354.634038 -215.184228)
		(width 0.14224)
		(layer "In13.Cu")
		(net "GMI_CPU0_G0_CPU1_G2_TX_DN<3>")
	)
	(segment
		(start 115.345718 -234.443016)
		(end 115.316 -234.460034)
		(width 0.1143)
		(layer "In13.Cu")
		(net "GMI_CPU0_G0_CPU1_G2_TX_DN<3>")
	)
	(segment
		(start 353.306634 -212.694266)
		(end 353.128834 -212.6488)
		(width 0.14224)
		(layer "In13.Cu")
		(net "GMI_CPU0_G0_CPU1_G2_TX_DN<3>")
	)
	(segment
		(start 115.837716 -216.544144)
		(end 115.14709 -217.721688)
		(width 0.14224)
		(layer "In13.Cu")
		(net "GMI_CPU0_G0_CPU1_G2_TX_DN<3>")
	)
	(segment
		(start 356.145592 -232.819956)
		(end 356.109016 -232.79862)
		(width 0.1143)
		(layer "In13.Cu")
		(net "GMI_CPU0_G0_CPU1_G2_TX_DN<3>")
	)
	(segment
		(start 356.145592 -236.05998)
		(end 356.109016 -236.038644)
		(width 0.1143)
		(layer "In13.Cu")
		(net "GMI_CPU0_G0_CPU1_G2_TX_DN<3>")
	)
	(segment
		(start 356.148132 -239.301528)
		(end 356.147116 -239.30102)
		(width 0.1143)
		(layer "In13.Cu")
		(net "GMI_CPU0_G0_CPU1_G2_TX_DN<3>")
	)
	(segment
		(start 352.70059 -211.673186)
		(end 317.22949 -182.588154)
		(width 0.14224)
		(layer "In13.Cu")
		(net "GMI_CPU0_G0_CPU1_G2_TX_DN<3>")
	)
	(segment
		(start 115.345718 -226.98583)
		(end 115.346988 -226.986592)
		(width 0.1143)
		(layer "In13.Cu")
		(net "GMI_CPU0_G0_CPU1_G2_TX_DN<3>")
	)
	(segment
		(start 355.639116 -240.779554)
		(end 355.708712 -240.738914)
		(width 0.1143)
		(layer "In13.Cu")
		(net "GMI_CPU0_G0_CPU1_G2_TX_DN<3>")
	)
	(segment
		(start 115.346988 -233.466386)
		(end 115.34775 -233.466894)
		(width 0.1143)
		(layer "In13.Cu")
		(net "GMI_CPU0_G0_CPU1_G2_TX_DN<3>")
	)
	(segment
		(start 115.34775 -238.32693)
		(end 115.348766 -238.327438)
		(width 0.1143)
		(layer "In13.Cu")
		(net "GMI_CPU0_G0_CPU1_G2_TX_DN<3>")
	)
	(segment
		(start 116.287042 -241.566446)
		(end 116.287804 -241.566954)
		(width 0.1143)
		(layer "In13.Cu")
		(net "GMI_CPU0_G0_CPU1_G2_TX_DN<3>")
	)
	(segment
		(start 356.145592 -226.340162)
		(end 356.109016 -226.318826)
		(width 0.1143)
		(layer "In13.Cu")
		(net "GMI_CPU0_G0_CPU1_G2_TX_DN<3>")
	)
	(segment
		(start 115.345718 -232.823004)
		(end 115.316 -232.840022)
		(width 0.1143)
		(layer "In13.Cu")
		(net "GMI_CPU0_G0_CPU1_G2_TX_DN<3>")
	)
	(segment
		(start 356.148894 -236.062012)
		(end 356.148132 -236.061504)
		(width 0.1143)
		(layer "In13.Cu")
		(net "GMI_CPU0_G0_CPU1_G2_TX_DN<3>")
	)
	(segment
		(start 115.10137 -221.146116)
		(end 115.10137 -221.303342)
		(width 0.1143)
		(layer "In13.Cu")
		(net "GMI_CPU0_G0_CPU1_G2_TX_DN<3>")
	)
	(segment
		(start 356.127812 -228.618796)
		(end 356.179628 -228.588316)
		(width 0.1143)
		(layer "In13.Cu")
		(net "GMI_CPU0_G0_CPU1_G2_TX_DN<3>")
	)
	(segment
		(start 356.147116 -227.96119)
		(end 356.145592 -227.960174)
		(width 0.1143)
		(layer "In13.Cu")
		(net "GMI_CPU0_G0_CPU1_G2_TX_DN<3>")
	)
	(segment
		(start 115.348766 -234.441238)
		(end 115.34775 -234.441746)
		(width 0.1143)
		(layer "In13.Cu")
		(net "GMI_CPU0_G0_CPU1_G2_TX_DN<3>")
	)
	(segment
		(start 115.345718 -239.303052)
		(end 115.316 -239.32007)
		(width 0.1143)
		(layer "In13.Cu")
		(net "GMI_CPU0_G0_CPU1_G2_TX_DN<3>")
	)
	(segment
		(start 115.353846 -236.710474)
		(end 115.35537 -236.71149)
		(width 0.1143)
		(layer "In13.Cu")
		(net "GMI_CPU0_G0_CPU1_G2_TX_DN<3>")
	)
	(segment
		(start 117.11686 -242.864386)
		(end 117.414802 -242.864386)
		(width 0.1143)
		(layer "In13.Cu")
		(net "GMI_CPU0_G0_CPU1_G2_TX_DN<3>")
	)
	(segment
		(start 115.35537 -236.71149)
		(end 115.386866 -236.729778)
		(width 0.1143)
		(layer "In13.Cu")
		(net "GMI_CPU0_G0_CPU1_G2_TX_DN<3>")
	)
	(segment
		(start 115.35537 -231.851454)
		(end 115.386866 -231.869742)
		(width 0.1143)
		(layer "In13.Cu")
		(net "GMI_CPU0_G0_CPU1_G2_TX_DN<3>")
	)
	(segment
		(start 115.351306 -231.848914)
		(end 115.352068 -231.849422)
		(width 0.1143)
		(layer "In13.Cu")
		(net "GMI_CPU0_G0_CPU1_G2_TX_DN<3>")
	)
	(segment
		(start 115.35029 -233.468418)
		(end 115.351306 -233.468926)
		(width 0.1143)
		(layer "In13.Cu")
		(net "GMI_CPU0_G0_CPU1_G2_TX_DN<3>")
	)
	(segment
		(start 115.346988 -238.326422)
		(end 115.34775 -238.32693)
		(width 0.1143)
		(layer "In13.Cu")
		(net "GMI_CPU0_G0_CPU1_G2_TX_DN<3>")
	)
	(segment
		(start 356.179628 -225.348546)
		(end 356.179882 -225.348546)
		(width 0.1143)
		(layer "In13.Cu")
		(net "GMI_CPU0_G0_CPU1_G2_TX_DN<3>")
	)
	(segment
		(start 115.348766 -237.681262)
		(end 115.34775 -237.68177)
		(width 0.1143)
		(layer "In13.Cu")
		(net "GMI_CPU0_G0_CPU1_G2_TX_DN<3>")
	)
	(segment
		(start 356.145592 -239.300004)
		(end 356.109016 -239.278668)
		(width 0.1143)
		(layer "In13.Cu")
		(net "GMI_CPU0_G0_CPU1_G2_TX_DN<3>")
	)
	(segment
		(start 115.348766 -227.961444)
		(end 115.34775 -227.961952)
		(width 0.1143)
		(layer "In13.Cu")
		(net "GMI_CPU0_G0_CPU1_G2_TX_DN<3>")
	)
	(segment
		(start 356.148132 -237.681516)
		(end 356.147116 -237.681008)
		(width 0.1143)
		(layer "In13.Cu")
		(net "GMI_CPU0_G0_CPU1_G2_TX_DN<3>")
	)
	(segment
		(start 356.179882 -227.979986)
		(end 356.150164 -227.962968)
		(width 0.1143)
		(layer "In13.Cu")
		(net "GMI_CPU0_G0_CPU1_G2_TX_DN<3>")
	)
	(segment
		(start 356.148132 -236.061504)
		(end 356.147116 -236.060996)
		(width 0.1143)
		(layer "In13.Cu")
		(net "GMI_CPU0_G0_CPU1_G2_TX_DN<3>")
	)
	(segment
		(start 115.35537 -223.751648)
		(end 115.386866 -223.769936)
		(width 0.1143)
		(layer "In13.Cu")
		(net "GMI_CPU0_G0_CPU1_G2_TX_DN<3>")
	)
	(segment
		(start 115.35029 -235.08843)
		(end 115.351306 -235.088938)
		(width 0.1143)
		(layer "In13.Cu")
		(net "GMI_CPU0_G0_CPU1_G2_TX_DN<3>")
	)
	(segment
		(start 115.352068 -225.369628)
		(end 115.353846 -225.370644)
		(width 0.1143)
		(layer "In13.Cu")
		(net "GMI_CPU0_G0_CPU1_G2_TX_DN<3>")
	)
	(segment
		(start 115.34775 -234.441746)
		(end 115.346988 -234.442254)
		(width 0.1143)
		(layer "In13.Cu")
		(net "GMI_CPU0_G0_CPU1_G2_TX_DN<3>")
	)
	(segment
		(start 116.254276 -241.547396)
		(end 116.256054 -241.548666)
		(width 0.1143)
		(layer "In13.Cu")
		(net "GMI_CPU0_G0_CPU1_G2_TX_DN<3>")
	)
	(segment
		(start 356.156006 -225.362262)
		(end 356.179628 -225.348546)
		(width 0.1143)
		(layer "In13.Cu")
		(net "GMI_CPU0_G0_CPU1_G2_TX_DN<3>")
	)
	(segment
		(start 353.128834 -212.6488)
		(end 352.914966 -212.28812)
		(width 0.14224)
		(layer "In13.Cu")
		(net "GMI_CPU0_G0_CPU1_G2_TX_DN<3>")
	)
	(segment
		(start 115.348766 -228.60762)
		(end 115.35029 -228.608636)
		(width 0.1143)
		(layer "In13.Cu")
		(net "GMI_CPU0_G0_CPU1_G2_TX_DN<3>")
	)
	(segment
		(start 115.35029 -236.708442)
		(end 115.351306 -236.70895)
		(width 0.1143)
		(layer "In13.Cu")
		(net "GMI_CPU0_G0_CPU1_G2_TX_DN<3>")
	)
	(segment
		(start 115.14709 -217.721688)
		(end 115.14709 -221.071948)
		(width 0.14224)
		(layer "In13.Cu")
		(net "GMI_CPU0_G0_CPU1_G2_TX_DN<3>")
	)
	(segment
		(start 115.34775 -228.607112)
		(end 115.348766 -228.60762)
		(width 0.1143)
		(layer "In13.Cu")
		(net "GMI_CPU0_G0_CPU1_G2_TX_DN<3>")
	)
	(segment
		(start 352.960178 -212.110828)
		(end 352.70059 -211.673186)
		(width 0.14224)
		(layer "In13.Cu")
		(net "GMI_CPU0_G0_CPU1_G2_TX_DN<3>")
	)
	(segment
		(start 115.316 -225.3488)
		(end 115.346988 -225.36658)
		(width 0.1143)
		(layer "In13.Cu")
		(net "GMI_CPU0_G0_CPU1_G2_TX_DN<3>")
	)
	(segment
		(start 115.351306 -233.468926)
		(end 115.352068 -233.469434)
		(width 0.1143)
		(layer "In13.Cu")
		(net "GMI_CPU0_G0_CPU1_G2_TX_DN<3>")
	)
	(segment
		(start 115.34775 -236.706918)
		(end 115.348766 -236.707426)
		(width 0.1143)
		(layer "In13.Cu")
		(net "GMI_CPU0_G0_CPU1_G2_TX_DN<3>")
	)
	(segment
		(start 356.130352 -239.957102)
		(end 356.179628 -239.928146)
		(width 0.1143)
		(layer "In13.Cu")
		(net "GMI_CPU0_G0_CPU1_G2_TX_DN<3>")
	)
	(segment
		(start 115.34775 -229.581964)
		(end 115.314222 -229.601522)
		(width 0.1143)
		(layer "In13.Cu")
		(net "GMI_CPU0_G0_CPU1_G2_TX_DN<3>")
	)
	(segment
		(start 356.154736 -238.322866)
		(end 356.155752 -238.322358)
		(width 0.1143)
		(layer "In13.Cu")
		(net "GMI_CPU0_G0_CPU1_G2_TX_DN<3>")
	)
	(segment
		(start 115.34775 -225.367088)
		(end 115.348766 -225.367596)
		(width 0.1143)
		(layer "In13.Cu")
		(net "GMI_CPU0_G0_CPU1_G2_TX_DN<3>")
	)
	(segment
		(start 356.179882 -239.319816)
		(end 356.150164 -239.302798)
		(width 0.1143)
		(layer "In13.Cu")
		(net "GMI_CPU0_G0_CPU1_G2_TX_DN<3>")
	)
	(segment
		(start 115.34775 -237.68177)
		(end 115.346988 -237.682278)
		(width 0.1143)
		(layer "In13.Cu")
		(net "GMI_CPU0_G0_CPU1_G2_TX_DN<3>")
	)
	(segment
		(start 356.179882 -226.359974)
		(end 356.150164 -226.342956)
		(width 0.1143)
		(layer "In13.Cu")
		(net "GMI_CPU0_G0_CPU1_G2_TX_DN<3>")
	)
	(segment
		(start 115.386866 -224.699068)
		(end 115.35029 -224.720404)
		(width 0.1143)
		(layer "In13.Cu")
		(net "GMI_CPU0_G0_CPU1_G2_TX_DN<3>")
	)
	(segment
		(start 356.148132 -227.961698)
		(end 356.147116 -227.96119)
		(width 0.1143)
		(layer "In13.Cu")
		(net "GMI_CPU0_G0_CPU1_G2_TX_DN<3>")
	)
	(segment
		(start 356.150164 -226.985576)
		(end 356.179882 -226.968558)
		(width 0.1143)
		(layer "In13.Cu")
		(net "GMI_CPU0_G0_CPU1_G2_TX_DN<3>")
	)
	(segment
		(start 356.147116 -239.30102)
		(end 356.145592 -239.300004)
		(width 0.1143)
		(layer "In13.Cu")
		(net "GMI_CPU0_G0_CPU1_G2_TX_DN<3>")
	)
	(segment
		(start 356.147116 -234.440984)
		(end 356.145592 -234.439968)
		(width 0.1143)
		(layer "In13.Cu")
		(net "GMI_CPU0_G0_CPU1_G2_TX_DN<3>")
	)
	(segment
		(start 356.117652 -236.724444)
		(end 356.179882 -236.688376)
		(width 0.1143)
		(layer "In13.Cu")
		(net "GMI_CPU0_G0_CPU1_G2_TX_DN<3>")
	)
	(segment
		(start 115.316 -235.068618)
		(end 115.346988 -235.086398)
		(width 0.1143)
		(layer "In13.Cu")
		(net "GMI_CPU0_G0_CPU1_G2_TX_DN<3>")
	)
	(segment
		(start 353.727512 -213.657434)
		(end 353.51339 -213.296754)
		(width 0.14224)
		(layer "In13.Cu")
		(net "GMI_CPU0_G0_CPU1_G2_TX_DN<3>")
	)
	(segment
		(start 115.346988 -223.746568)
		(end 115.34775 -223.747076)
		(width 0.1143)
		(layer "In13.Cu")
		(net "GMI_CPU0_G0_CPU1_G2_TX_DN<3>")
	)
	(segment
		(start 356.148132 -234.441492)
		(end 356.147116 -234.440984)
		(width 0.1143)
		(layer "In13.Cu")
		(net "GMI_CPU0_G0_CPU1_G2_TX_DN<3>")
	)
	(segment
		(start 356.18166 -229.601268)
		(end 356.109016 -229.55885)
		(width 0.1143)
		(layer "In13.Cu")
		(net "GMI_CPU0_G0_CPU1_G2_TX_DN<3>")
	)
	(segment
		(start 356.145592 -237.679992)
		(end 356.109016 -237.658656)
		(width 0.1143)
		(layer "In13.Cu")
		(net "GMI_CPU0_G0_CPU1_G2_TX_DN<3>")
	)
	(segment
		(start 115.351306 -235.088938)
		(end 115.352068 -235.089446)
		(width 0.1143)
		(layer "In13.Cu")
		(net "GMI_CPU0_G0_CPU1_G2_TX_DN<3>")
	)
	(segment
		(start 356.109016 -236.729524)
		(end 356.115366 -236.725714)
		(width 0.1143)
		(layer "In13.Cu")
		(net "GMI_CPU0_G0_CPU1_G2_TX_DN<3>")
	)
	(segment
		(start 355.208078 -241.5667)
		(end 355.20884 -241.566192)
		(width 0.1143)
		(layer "In13.Cu")
		(net "GMI_CPU0_G0_CPU1_G2_TX_DN<3>")
	)
	(segment
		(start 355.799898 -216.893902)
		(end 355.58603 -216.53373)
		(width 0.14224)
		(layer "In13.Cu")
		(net "GMI_CPU0_G0_CPU1_G2_TX_DN<3>")
	)
	(segment
		(start 165.477952 -177.092864)
		(end 157.369002 -179.99202)
		(width 0.14224)
		(layer "In13.Cu")
		(net "GMI_CPU0_G0_CPU1_G2_TX_DN<3>")
	)
	(segment
		(start 115.353846 -233.47045)
		(end 115.35537 -233.471466)
		(width 0.1143)
		(layer "In13.Cu")
		(net "GMI_CPU0_G0_CPU1_G2_TX_DN<3>")
	)
	(segment
		(start 115.34775 -230.22687)
		(end 115.384326 -230.248206)
		(width 0.1143)
		(layer "In13.Cu")
		(net "GMI_CPU0_G0_CPU1_G2_TX_DN<3>")
	)
	(segment
		(start 115.160044 -221.362016)
		(end 115.160044 -221.804484)
		(width 0.1143)
		(layer "In13.Cu")
		(net "GMI_CPU0_G0_CPU1_G2_TX_DN<3>")
	)
	(segment
		(start 115.316 -238.308642)
		(end 115.346988 -238.326422)
		(width 0.1143)
		(layer "In13.Cu")
		(net "GMI_CPU0_G0_CPU1_G2_TX_DN<3>")
	)
	(segment
		(start 354.118926 -214.063072)
		(end 353.905058 -213.7029)
		(width 0.14224)
		(layer "In13.Cu")
		(net "GMI_CPU0_G0_CPU1_G2_TX_DN<3>")
	)
	(segment
		(start 353.905058 -213.7029)
		(end 353.727512 -213.657434)
		(width 0.14224)
		(layer "In13.Cu")
		(net "GMI_CPU0_G0_CPU1_G2_TX_DN<3>")
	)
	(segment
		(start 115.35537 -233.471466)
		(end 115.386866 -233.489754)
		(width 0.1143)
		(layer "In13.Cu")
		(net "GMI_CPU0_G0_CPU1_G2_TX_DN<3>")
	)
	(segment
		(start 115.14709 -221.071948)
		(end 115.14709 -221.100396)
		(width 0.1143)
		(layer "In13.Cu")
		(net "GMI_CPU0_G0_CPU1_G2_TX_DN<3>")
	)
	(segment
		(start 115.348766 -235.087414)
		(end 115.35029 -235.08843)
		(width 0.1143)
		(layer "In13.Cu")
		(net "GMI_CPU0_G0_CPU1_G2_TX_DN<3>")
	)
	(segment
		(start 115.35537 -238.331502)
		(end 115.386866 -238.34979)
		(width 0.1143)
		(layer "In13.Cu")
		(net "GMI_CPU0_G0_CPU1_G2_TX_DN<3>")
	)
	(segment
		(start 356.148894 -227.962206)
		(end 356.148132 -227.961698)
		(width 0.1143)
		(layer "In13.Cu")
		(net "GMI_CPU0_G0_CPU1_G2_TX_DN<3>")
	)
	(segment
		(start 115.346988 -235.086398)
		(end 115.34775 -235.086906)
		(width 0.1143)
		(layer "In13.Cu")
		(net "GMI_CPU0_G0_CPU1_G2_TX_DN<3>")
	)
	(segment
		(start 115.34775 -223.747076)
		(end 115.348766 -223.747584)
		(width 0.1143)
		(layer "In13.Cu")
		(net "GMI_CPU0_G0_CPU1_G2_TX_DN<3>")
	)
	(segment
		(start 115.346988 -232.822242)
		(end 115.345718 -232.823004)
		(width 0.1143)
		(layer "In13.Cu")
		(net "GMI_CPU0_G0_CPU1_G2_TX_DN<3>")
	)
	(segment
		(start 116.736368 -215.012016)
		(end 116.782596 -215.189308)
		(width 0.14224)
		(layer "In13.Cu")
		(net "GMI_CPU0_G0_CPU1_G2_TX_DN<3>")
	)
	(segment
		(start 356.145592 -234.439968)
		(end 356.109016 -234.418632)
		(width 0.1143)
		(layer "In13.Cu")
		(net "GMI_CPU0_G0_CPU1_G2_TX_DN<3>")
	)
	(segment
		(start 115.346988 -226.342448)
		(end 115.345718 -226.34321)
		(width 0.1143)
		(layer "In13.Cu")
		(net "GMI_CPU0_G0_CPU1_G2_TX_DN<3>")
	)
	(segment
		(start 115.316 -231.828594)
		(end 115.346988 -231.846374)
		(width 0.1143)
		(layer "In13.Cu")
		(net "GMI_CPU0_G0_CPU1_G2_TX_DN<3>")
	)
	(segment
		(start 356.145592 -223.100138)
		(end 356.109016 -223.078802)
		(width 0.1143)
		(layer "In13.Cu")
		(net "GMI_CPU0_G0_CPU1_G2_TX_DN<3>")
	)
	(segment
		(start 356.179882 -236.079792)
		(end 356.150164 -236.062774)
		(width 0.1143)
		(layer "In13.Cu")
		(net "GMI_CPU0_G0_CPU1_G2_TX_DN<3>")
	)
	(segment
		(start 308.042564 -177.894996)
		(end 302.91024 -177.894996)
		(width 0.14224)
		(layer "In13.Cu")
		(net "GMI_CPU0_G0_CPU1_G2_TX_DN<3>")
	)
	(segment
		(start 115.351306 -223.749108)
		(end 115.352068 -223.749616)
		(width 0.1143)
		(layer "In13.Cu")
		(net "GMI_CPU0_G0_CPU1_G2_TX_DN<3>")
	)
	(segment
		(start 356.109016 -238.349536)
		(end 356.114604 -238.346234)
		(width 0.1143)
		(layer "In13.Cu")
		(net "GMI_CPU0_G0_CPU1_G2_TX_DN<3>")
	)
	(segment
		(start 356.394512 -221.145862)
		(end 356.348792 -221.100142)
		(width 0.1143)
		(layer "In13.Cu")
		(net "GMI_CPU0_G0_CPU1_G2_TX_DN<3>")
	)
	(segment
		(start 115.353846 -223.750632)
		(end 115.35537 -223.751648)
		(width 0.1143)
		(layer "In13.Cu")
		(net "GMI_CPU0_G0_CPU1_G2_TX_DN<3>")
	)
	(segment
		(start 115.837716 -216.54389)
		(end 115.837716 -216.544144)
		(width 0.14224)
		(layer "In13.Cu")
		(net "GMI_CPU0_G0_CPU1_G2_TX_DN<3>")
	)
	(segment
		(start 356.148894 -234.442)
		(end 356.148132 -234.441492)
		(width 0.1143)
		(layer "In13.Cu")
		(net "GMI_CPU0_G0_CPU1_G2_TX_DN<3>")
	)
	(segment
		(start 115.353846 -231.850438)
		(end 115.35537 -231.851454)
		(width 0.1143)
		(layer "In13.Cu")
		(net "GMI_CPU0_G0_CPU1_G2_TX_DN<3>")
	)
	(segment
		(start 115.386866 -231.179116)
		(end 115.34775 -231.201976)
		(width 0.1143)
		(layer "In13.Cu")
		(net "GMI_CPU0_G0_CPU1_G2_TX_DN<3>")
	)
	(segment
		(start 356.348792 -221.100142)
		(end 356.348792 -221.093538)
		(width 0.1143)
		(layer "In13.Cu")
		(net "GMI_CPU0_G0_CPU1_G2_TX_DN<3>")
	)
	(segment
		(start 115.35537 -235.091478)
		(end 115.386866 -235.109766)
		(width 0.1143)
		(layer "In13.Cu")
		(net "GMI_CPU0_G0_CPU1_G2_TX_DN<3>")
	)
	(segment
		(start 356.148894 -239.302036)
		(end 356.148132 -239.301528)
		(width 0.1143)
		(layer "In13.Cu")
		(net "GMI_CPU0_G0_CPU1_G2_TX_DN<3>")
	)
	(segment
		(start 356.116382 -239.96523)
		(end 356.130352 -239.957102)
		(width 0.1143)
		(layer "In13.Cu")
		(net "GMI_CPU0_G0_CPU1_G2_TX_DN<3>")
	)
	(segment
		(start 356.150164 -226.342956)
		(end 356.148894 -226.342194)
		(width 0.1143)
		(layer "In13.Cu")
		(net "GMI_CPU0_G0_CPU1_G2_TX_DN<3>")
	)
	(segment
		(start 116.181124 -215.958674)
		(end 116.227352 -216.135966)
		(width 0.14224)
		(layer "In13.Cu")
		(net "GMI_CPU0_G0_CPU1_G2_TX_DN<3>")
	)
	(segment
		(start 115.345718 -236.063028)
		(end 115.316 -236.080046)
		(width 0.1143)
		(layer "In13.Cu")
		(net "GMI_CPU0_G0_CPU1_G2_TX_DN<3>")
	)
	(segment
		(start 115.34775 -239.301782)
		(end 115.346988 -239.30229)
		(width 0.1143)
		(layer "In13.Cu")
		(net "GMI_CPU0_G0_CPU1_G2_TX_DN<3>")
	)
	(segment
		(start 356.116382 -233.485182)
		(end 356.132892 -233.47553)
		(width 0.1143)
		(layer "In13.Cu")
		(net "GMI_CPU0_G0_CPU1_G2_TX_DN<3>")
	)
	(segment
		(start 115.348766 -233.467402)
		(end 115.35029 -233.468418)
		(width 0.1143)
		(layer "In13.Cu")
		(net "GMI_CPU0_G0_CPU1_G2_TX_DN<3>")
	)
	(segment
		(start 356.155752 -238.322358)
		(end 356.179882 -238.308388)
		(width 0.1143)
		(layer "In13.Cu")
		(net "GMI_CPU0_G0_CPU1_G2_TX_DN<3>")
	)
	(segment
		(start 356.147116 -226.987354)
		(end 356.148132 -226.986846)
		(width 0.1143)
		(layer "In13.Cu")
		(net "GMI_CPU0_G0_CPU1_G2_TX_DN<3>")
	)
	(segment
		(start 356.127812 -231.858566)
		(end 356.179628 -231.828086)
		(width 0.1143)
		(layer "In13.Cu")
		(net "GMI_CPU0_G0_CPU1_G2_TX_DN<3>")
	)
	(segment
		(start 115.35029 -224.720404)
		(end 115.348766 -224.72142)
		(width 0.1143)
		(layer "In13.Cu")
		(net "GMI_CPU0_G0_CPU1_G2_TX_DN<3>")
	)
	(segment
		(start 355.239828 -241.548412)
		(end 355.241606 -241.547142)
		(width 0.1143)
		(layer "In13.Cu")
		(net "GMI_CPU0_G0_CPU1_G2_TX_DN<3>")
	)
	(segment
		(start 356.348792 -221.093538)
		(end 356.348792 -217.818208)
		(width 0.14224)
		(layer "In13.Cu")
		(net "GMI_CPU0_G0_CPU1_G2_TX_DN<3>")
	)
	(segment
		(start 116.227352 -216.135966)
		(end 116.015262 -216.497662)
		(width 0.14224)
		(layer "In13.Cu")
		(net "GMI_CPU0_G0_CPU1_G2_TX_DN<3>")
	)
	(segment
		(start 356.115366 -236.725714)
		(end 356.117652 -236.724444)
		(width 0.1143)
		(layer "In13.Cu")
		(net "GMI_CPU0_G0_CPU1_G2_TX_DN<3>")
	)
	(segment
		(start 115.316 -239.928654)
		(end 115.346988 -239.946434)
		(width 0.1143)
		(layer "In13.Cu")
		(net "GMI_CPU0_G0_CPU1_G2_TX_DN<3>")
	)
	(segment
		(start 115.316 -228.588824)
		(end 115.346988 -228.606604)
		(width 0.1143)
		(layer "In13.Cu")
		(net "GMI_CPU0_G0_CPU1_G2_TX_DN<3>")
	)
	(segment
		(start 115.352068 -235.089446)
		(end 115.353846 -235.090462)
		(width 0.1143)
		(layer "In13.Cu")
		(net "GMI_CPU0_G0_CPU1_G2_TX_DN<3>")
	)
	(segment
		(start 115.316 -233.448606)
		(end 115.346988 -233.466386)
		(width 0.1143)
		(layer "In13.Cu")
		(net "GMI_CPU0_G0_CPU1_G2_TX_DN<3>")
	)
	(segment
		(start 356.111556 -230.247952)
		(end 356.148132 -230.226616)
		(width 0.1143)
		(layer "In13.Cu")
		(net "GMI_CPU0_G0_CPU1_G2_TX_DN<3>")
	)
	(segment
		(start 356.179628 -239.928146)
		(end 356.179882 -239.9284)
		(width 0.1143)
		(layer "In13.Cu")
		(net "GMI_CPU0_G0_CPU1_G2_TX_DN<3>")
	)
	(segment
		(start 356.179882 -237.699804)
		(end 356.150164 -237.682786)
		(width 0.1143)
		(layer "In13.Cu")
		(net "GMI_CPU0_G0_CPU1_G2_TX_DN<3>")
	)
	(segment
		(start 115.34775 -239.946942)
		(end 115.348766 -239.94745)
		(width 0.1143)
		(layer "In13.Cu")
		(net "GMI_CPU0_G0_CPU1_G2_TX_DN<3>")
	)
	(segment
		(start 115.316 -230.208582)
		(end 115.34775 -230.22687)
		(width 0.1143)
		(layer "In13.Cu")
		(net "GMI_CPU0_G0_CPU1_G2_TX_DN<3>")
	)
	(segment
		(start 356.145592 -227.960174)
		(end 356.109016 -227.938838)
		(width 0.1143)
		(layer "In13.Cu")
		(net "GMI_CPU0_G0_CPU1_G2_TX_DN<3>")
	)
	(segment
		(start 115.346988 -225.36658)
		(end 115.34775 -225.367088)
		(width 0.1143)
		(layer "In13.Cu")
		(net "GMI_CPU0_G0_CPU1_G2_TX_DN<3>")
	)
	(segment
		(start 115.351306 -228.609144)
		(end 115.352068 -228.609652)
		(width 0.1143)
		(layer "In13.Cu")
		(net "GMI_CPU0_G0_CPU1_G2_TX_DN<3>")
	)
	(segment
		(start 115.35029 -223.7486)
		(end 115.351306 -223.749108)
		(width 0.1143)
		(layer "In13.Cu")
		(net "GMI_CPU0_G0_CPU1_G2_TX_DN<3>")
	)
	(segment
		(start 115.35029 -231.848406)
		(end 115.351306 -231.848914)
		(width 0.1143)
		(layer "In13.Cu")
		(net "GMI_CPU0_G0_CPU1_G2_TX_DN<3>")
	)
	(segment
		(start 356.109016 -235.109512)
		(end 356.179882 -235.068364)
		(width 0.1143)
		(layer "In13.Cu")
		(net "GMI_CPU0_G0_CPU1_G2_TX_DN<3>")
	)
	(segment
		(start 356.179628 -231.828086)
		(end 356.179882 -231.82834)
		(width 0.1143)
		(layer "In13.Cu")
		(net "GMI_CPU0_G0_CPU1_G2_TX_DN<3>")
	)
	(segment
		(start 116.757196 -242.376706)
		(end 116.796058 -242.399312)
		(width 0.1143)
		(layer "In13.Cu")
		(net "GMI_CPU0_G0_CPU1_G2_TX_DN<3>")
	)
	(segment
		(start 115.10137 -221.303342)
		(end 115.160044 -221.362016)
		(width 0.1143)
		(layer "In13.Cu")
		(net "GMI_CPU0_G0_CPU1_G2_TX_DN<3>")
	)
	(segment
		(start 115.348766 -226.987608)
		(end 115.386866 -227.00996)
		(width 0.1143)
		(layer "In13.Cu")
		(net "GMI_CPU0_G0_CPU1_G2_TX_DN<3>")
	)
	(segment
		(start 356.148132 -223.101662)
		(end 356.147116 -223.101154)
		(width 0.1143)
		(layer "In13.Cu")
		(net "GMI_CPU0_G0_CPU1_G2_TX_DN<3>")
	)
	(segment
		(start 115.346988 -231.846374)
		(end 115.34775 -231.846882)
		(width 0.1143)
		(layer "In13.Cu")
		(net "GMI_CPU0_G0_CPU1_G2_TX_DN<3>")
	)
	(segment
		(start 115.346988 -227.96246)
		(end 115.345718 -227.963222)
		(width 0.1143)
		(layer "In13.Cu")
		(net "GMI_CPU0_G0_CPU1_G2_TX_DN<3>")
	)
	(segment
		(start 115.352068 -228.609652)
		(end 115.353846 -228.610668)
		(width 0.1143)
		(layer "In13.Cu")
		(net "GMI_CPU0_G0_CPU1_G2_TX_DN<3>")
	)
	(segment
		(start 356.18166 -231.22128)
		(end 356.109016 -231.178862)
		(width 0.1143)
		(layer "In13.Cu")
		(net "GMI_CPU0_G0_CPU1_G2_TX_DN<3>")
	)
	(segment
		(start 116.256054 -241.548666)
		(end 116.287042 -241.566446)
		(width 0.1143)
		(layer "In13.Cu")
		(net "GMI_CPU0_G0_CPU1_G2_TX_DN<3>")
	)
	(segment
		(start 356.153974 -238.32312)
		(end 356.153974 -238.323374)
		(width 0.1143)
		(layer "In13.Cu")
		(net "GMI_CPU0_G0_CPU1_G2_TX_DN<3>")
	)
	(segment
		(start 356.109016 -233.4895)
		(end 356.116382 -233.485182)
		(width 0.1143)
		(layer "In13.Cu")
		(net "GMI_CPU0_G0_CPU1_G2_TX_DN<3>")
	)
	(segment
		(start 115.348766 -239.301274)
		(end 115.34775 -239.301782)
		(width 0.1143)
		(layer "In13.Cu")
		(net "GMI_CPU0_G0_CPU1_G2_TX_DN<3>")
	)
	(segment
		(start 115.316 -236.68863)
		(end 115.346988 -236.70641)
		(width 0.1143)
		(layer "In13.Cu")
		(net "GMI_CPU0_G0_CPU1_G2_TX_DN<3>")
	)
	(segment
		(start 115.34775 -226.9871)
		(end 115.348766 -226.987608)
		(width 0.1143)
		(layer "In13.Cu")
		(net "GMI_CPU0_G0_CPU1_G2_TX_DN<3>")
	)
	(segment
		(start 356.348792 -217.818208)
		(end 356.146354 -217.47734)
		(width 0.14224)
		(layer "In13.Cu")
		(net "GMI_CPU0_G0_CPU1_G2_TX_DN<3>")
	)
	(segment
		(start 352.914966 -212.28812)
		(end 352.960178 -212.110828)
		(width 0.14224)
		(layer "In13.Cu")
		(net "GMI_CPU0_G0_CPU1_G2_TX_DN<3>")
	)
	(segment
		(start 302.91024 -177.894996)
		(end 165.477952 -177.092864)
		(width 0.14224)
		(layer "In13.Cu")
		(net "GMI_CPU0_G0_CPU1_G2_TX_DN<3>")
	)
	(segment
		(start 115.35029 -228.608636)
		(end 115.351306 -228.609144)
		(width 0.1143)
		(layer "In13.Cu")
		(net "GMI_CPU0_G0_CPU1_G2_TX_DN<3>")
	)
	(segment
		(start 115.35537 -239.951514)
		(end 115.386866 -239.969802)
		(width 0.1143)
		(layer "In13.Cu")
		(net "GMI_CPU0_G0_CPU1_G2_TX_DN<3>")
	)
	(segment
		(start 115.351306 -225.36912)
		(end 115.352068 -225.369628)
		(width 0.1143)
		(layer "In13.Cu")
		(net "GMI_CPU0_G0_CPU1_G2_TX_DN<3>")
	)
	(segment
		(start 115.346988 -226.986592)
		(end 115.34775 -226.9871)
		(width 0.1143)
		(layer "In13.Cu")
		(net "GMI_CPU0_G0_CPU1_G2_TX_DN<3>")
	)
	(segment
		(start 115.346988 -234.442254)
		(end 115.345718 -234.443016)
		(width 0.1143)
		(layer "In13.Cu")
		(net "GMI_CPU0_G0_CPU1_G2_TX_DN<3>")
	)
	(segment
		(start 356.148132 -232.82148)
		(end 356.147116 -232.820972)
		(width 0.1143)
		(layer "In13.Cu")
		(net "GMI_CPU0_G0_CPU1_G2_TX_DN<3>")
	)
	(segment
		(start 116.100098 -241.244374)
		(end 116.100098 -241.246406)
		(width 0.1143)
		(layer "In13.Cu")
		(net "GMI_CPU0_G0_CPU1_G2_TX_DN<3>")
	)
	(segment
		(start 355.58603 -216.53373)
		(end 355.40823 -216.488264)
		(width 0.14224)
		(layer "In13.Cu")
		(net "GMI_CPU0_G0_CPU1_G2_TX_DN<3>")
	)
	(segment
		(start 356.109016 -222.14967)
		(end 356.148132 -222.12681)
		(width 0.1143)
		(layer "In13.Cu")
		(net "GMI_CPU0_G0_CPU1_G2_TX_DN<3>")
	)
	(segment
		(start 356.148894 -237.682024)
		(end 356.148132 -237.681516)
		(width 0.1143)
		(layer "In13.Cu")
		(net "GMI_CPU0_G0_CPU1_G2_TX_DN<3>")
	)
	(segment
		(start 354.920042 -242.061746)
		(end 354.920042 -242.060222)
		(width 0.1143)
		(layer "In13.Cu")
		(net "GMI_CPU0_G0_CPU1_G2_TX_DN<3>")
	)
	(segment
		(start 115.35029 -223.100392)
		(end 115.348766 -223.101408)
		(width 0.1143)
		(layer "In13.Cu")
		(net "GMI_CPU0_G0_CPU1_G2_TX_DN<3>")
	)
	(segment
		(start 356.147116 -224.721166)
		(end 356.145592 -224.72015)
		(width 0.1143)
		(layer "In13.Cu")
		(net "GMI_CPU0_G0_CPU1_G2_TX_DN<3>")
	)
	(segment
		(start 356.148894 -226.986338)
		(end 356.150164 -226.985576)
		(width 0.1143)
		(layer "In13.Cu")
		(net "GMI_CPU0_G0_CPU1_G2_TX_DN<3>")
	)
	(segment
		(start 115.353846 -238.330486)
		(end 115.35537 -238.331502)
		(width 0.1143)
		(layer "In13.Cu")
		(net "GMI_CPU0_G0_CPU1_G2_TX_DN<3>")
	)
	(segment
		(start 115.351306 -238.328962)
		(end 115.352068 -238.32947)
		(width 0.1143)
		(layer "In13.Cu")
		(net "GMI_CPU0_G0_CPU1_G2_TX_DN<3>")
	)
	(segment
		(start 115.35029 -225.368612)
		(end 115.351306 -225.36912)
		(width 0.1143)
		(layer "In13.Cu")
		(net "GMI_CPU0_G0_CPU1_G2_TX_DN<3>")
	)
	(segment
		(start 115.352068 -239.949482)
		(end 115.353846 -239.950498)
		(width 0.1143)
		(layer "In13.Cu")
		(net "GMI_CPU0_G0_CPU1_G2_TX_DN<3>")
	)
	(segment
		(start 356.148132 -230.226616)
		(end 356.179882 -230.208328)
		(width 0.1143)
		(layer "In13.Cu")
		(net "GMI_CPU0_G0_CPU1_G2_TX_DN<3>")
	)
	(segment
		(start 356.179628 -228.588316)
		(end 356.179882 -228.58857)
		(width 0.1143)
		(layer "In13.Cu")
		(net "GMI_CPU0_G0_CPU1_G2_TX_DN<3>")
	)
	(segment
		(start 356.335838 -221.80423)
		(end 356.335838 -221.361762)
		(width 0.1143)
		(layer "In13.Cu")
		(net "GMI_CPU0_G0_CPU1_G2_TX_DN<3>")
	)
	(segment
		(start 115.386866 -223.079056)
		(end 115.35029 -223.100392)
		(width 0.1143)
		(layer "In13.Cu")
		(net "GMI_CPU0_G0_CPU1_G2_TX_DN<3>")
	)
	(segment
		(start 356.115874 -238.345472)
		(end 356.153212 -238.323628)
		(width 0.1143)
		(layer "In13.Cu")
		(net "GMI_CPU0_G0_CPU1_G2_TX_DN<3>")
	)
	(segment
		(start 353.558856 -213.119208)
		(end 353.306634 -212.694266)
		(width 0.14224)
		(layer "In13.Cu")
		(net "GMI_CPU0_G0_CPU1_G2_TX_DN<3>")
	)
	(segment
		(start 115.34775 -236.061758)
		(end 115.346988 -236.062266)
		(width 0.1143)
		(layer "In13.Cu")
		(net "GMI_CPU0_G0_CPU1_G2_TX_DN<3>")
	)
	(segment
		(start 115.348766 -225.367596)
		(end 115.35029 -225.368612)
		(width 0.1143)
		(layer "In13.Cu")
		(net "GMI_CPU0_G0_CPU1_G2_TX_DN<3>")
	)
	(segment
		(start 115.348766 -232.821226)
		(end 115.34775 -232.821734)
		(width 0.1143)
		(layer "In13.Cu")
		(net "GMI_CPU0_G0_CPU1_G2_TX_DN<3>")
	)
	(segment
		(start 115.348766 -231.84739)
		(end 115.35029 -231.848406)
		(width 0.1143)
		(layer "In13.Cu")
		(net "GMI_CPU0_G0_CPU1_G2_TX_DN<3>")
	)
	(segment
		(start 115.346988 -228.606604)
		(end 115.34775 -228.607112)
		(width 0.1143)
		(layer "In13.Cu")
		(net "GMI_CPU0_G0_CPU1_G2_TX_DN<3>")
	)
	(segment
		(start 116.782596 -215.189308)
		(end 116.570506 -215.551004)
		(width 0.14224)
		(layer "In13.Cu")
		(net "GMI_CPU0_G0_CPU1_G2_TX_DN<3>")
	)
	(segment
		(start 354.634038 -215.184228)
		(end 354.67925 -215.006682)
		(width 0.14224)
		(layer "In13.Cu")
		(net "GMI_CPU0_G0_CPU1_G2_TX_DN<3>")
	)
	(segment
		(start 356.150164 -227.962968)
		(end 356.148894 -227.962206)
		(width 0.1143)
		(layer "In13.Cu")
		(net "GMI_CPU0_G0_CPU1_G2_TX_DN<3>")
	)
	(segment
		(start 115.14709 -221.100396)
		(end 115.10137 -221.146116)
		(width 0.1143)
		(layer "In13.Cu")
		(net "GMI_CPU0_G0_CPU1_G2_TX_DN<3>")
	)
	(segment
		(start 115.34775 -223.101916)
		(end 115.316 -223.120204)
		(width 0.1143)
		(layer "In13.Cu")
		(net "GMI_CPU0_G0_CPU1_G2_TX_DN<3>")
	)
	(segment
		(start 356.148132 -226.341686)
		(end 356.147116 -226.341178)
		(width 0.1143)
		(layer "In13.Cu")
		(net "GMI_CPU0_G0_CPU1_G2_TX_DN<3>")
	)
	(segment
		(start 356.179882 -234.45978)
		(end 356.150164 -234.442762)
		(width 0.1143)
		(layer "In13.Cu")
		(net "GMI_CPU0_G0_CPU1_G2_TX_DN<3>")
	)
	(segment
		(start 115.34775 -231.201976)
		(end 115.314222 -231.221534)
		(width 0.1143)
		(layer "In13.Cu")
		(net "GMI_CPU0_G0_CPU1_G2_TX_DN<3>")
	)
	(segment
		(start 115.35029 -239.948466)
		(end 115.351306 -239.948974)
		(width 0.1143)
		(layer "In13.Cu")
		(net "GMI_CPU0_G0_CPU1_G2_TX_DN<3>")
	)
	(segment
		(start 355.20503 -241.568478)
		(end 355.208078 -241.5667)
		(width 0.1143)
		(layer "In13.Cu")
		(net "GMI_CPU0_G0_CPU1_G2_TX_DN<3>")
	)
	(segment
		(start 115.352068 -231.849422)
		(end 115.353846 -231.850438)
		(width 0.1143)
		(layer "In13.Cu")
		(net "GMI_CPU0_G0_CPU1_G2_TX_DN<3>")
	)
	(segment
		(start 115.386866 -232.798874)
		(end 115.348766 -232.821226)
		(width 0.1143)
		(layer "In13.Cu")
		(net "GMI_CPU0_G0_CPU1_G2_TX_DN<3>")
	)
	(segment
		(start 115.348766 -223.101408)
		(end 115.34775 -223.101916)
		(width 0.1143)
		(layer "In13.Cu")
		(net "GMI_CPU0_G0_CPU1_G2_TX_DN<3>")
	)
	(segment
		(start 353.51339 -213.296754)
		(end 353.558856 -213.119208)
		(width 0.14224)
		(layer "In13.Cu")
		(net "GMI_CPU0_G0_CPU1_G2_TX_DN<3>")
	)
	(segment
		(start 157.369002 -179.99202)
		(end 118.660164 -211.731606)
		(width 0.14224)
		(layer "In13.Cu")
		(net "GMI_CPU0_G0_CPU1_G2_TX_DN<3>")
	)
	(segment
		(start 356.153974 -238.323374)
		(end 356.154736 -238.322866)
		(width 0.1143)
		(layer "In13.Cu")
		(net "GMI_CPU0_G0_CPU1_G2_TX_DN<3>")
	)
	(segment
		(start 356.11943 -225.383598)
		(end 356.156006 -225.362262)
		(width 0.1143)
		(layer "In13.Cu")
		(net "GMI_CPU0_G0_CPU1_G2_TX_DN<3>")
	)
	(segment
		(start 115.386866 -229.559104)
		(end 115.34775 -229.581964)
		(width 0.1143)
		(layer "In13.Cu")
		(net "GMI_CPU0_G0_CPU1_G2_TX_DN<3>")
	)
	(segment
		(start 115.348766 -223.747584)
		(end 115.35029 -223.7486)
		(width 0.1143)
		(layer "In13.Cu")
		(net "GMI_CPU0_G0_CPU1_G2_TX_DN<3>")
	)
	(segment
		(start 356.109016 -223.769682)
		(end 356.117652 -223.764602)
		(width 0.1143)
		(layer "In13.Cu")
		(net "GMI_CPU0_G0_CPU1_G2_TX_DN<3>")
	)
	(segment
		(start 115.353846 -239.950498)
		(end 115.35537 -239.951514)
		(width 0.1143)
		(layer "In13.Cu")
		(net "GMI_CPU0_G0_CPU1_G2_TX_DN<3>")
	)
	(segment
		(start 356.114604 -238.346234)
		(end 356.115874 -238.345472)
		(width 0.1143)
		(layer "In13.Cu")
		(net "GMI_CPU0_G0_CPU1_G2_TX_DN<3>")
	)
	(segment
		(start 116.287804 -241.566954)
		(end 116.290852 -241.568732)
		(width 0.1143)
		(layer "In13.Cu")
		(net "GMI_CPU0_G0_CPU1_G2_TX_DN<3>")
	)
	(segment
		(start 356.17912 -233.448606)
		(end 356.179882 -233.448098)
		(width 0.1143)
		(layer "In13.Cu")
		(net "GMI_CPU0_G0_CPU1_G2_TX_DN<3>")
	)
	(segment
		(start 356.179882 -232.839768)
		(end 356.150164 -232.82275)
		(width 0.1143)
		(layer "In13.Cu")
		(net "GMI_CPU0_G0_CPU1_G2_TX_DN<3>")
	)
	(segment
		(start 356.145592 -224.72015)
		(end 356.109016 -224.698814)
		(width 0.1143)
		(layer "In13.Cu")
		(net "GMI_CPU0_G0_CPU1_G2_TX_DN<3>")
	)
	(segment
		(start 317.22949 -182.588154)
		(end 310.47563 -178.764946)
		(width 0.14224)
		(layer "In13.Cu")
		(net "GMI_CPU0_G0_CPU1_G2_TX_DN<3>")
	)
	(segment
		(start 115.34775 -231.846882)
		(end 115.348766 -231.84739)
		(width 0.1143)
		(layer "In13.Cu")
		(net "GMI_CPU0_G0_CPU1_G2_TX_DN<3>")
	)
	(segment
		(start 354.08108 -242.864132)
		(end 354.379022 -242.864132)
		(width 0.1143)
		(layer "In13.Cu")
		(net "GMI_CPU0_G0_CPU1_G2_TX_DN<3>")
	)
	(segment
		(start 354.465382 -214.64651)
		(end 354.287582 -214.601044)
		(width 0.14224)
		(layer "In13.Cu")
		(net "GMI_CPU0_G0_CPU1_G2_TX_DN<3>")
	)
	(segment
		(start 355.194362 -216.127838)
		(end 355.239574 -215.950292)
		(width 0.14224)
		(layer "In13.Cu")
		(net "GMI_CPU0_G0_CPU1_G2_TX_DN<3>")
	)
	(segment
		(start 355.40823 -216.488264)
		(end 355.194362 -216.127838)
		(width 0.14224)
		(layer "In13.Cu")
		(net "GMI_CPU0_G0_CPU1_G2_TX_DN<3>")
	)
	(segment
		(start 115.353846 -225.370644)
		(end 115.35537 -225.37166)
		(width 0.1143)
		(layer "In13.Cu")
		(net "GMI_CPU0_G0_CPU1_G2_TX_DN<3>")
	)
	(segment
		(start 115.352068 -236.709458)
		(end 115.353846 -236.710474)
		(width 0.1143)
		(layer "In13.Cu")
		(net "GMI_CPU0_G0_CPU1_G2_TX_DN<3>")
	)
	(segment
		(start 115.352068 -233.469434)
		(end 115.353846 -233.47045)
		(width 0.1143)
		(layer "In13.Cu")
		(net "GMI_CPU0_G0_CPU1_G2_TX_DN<3>")
	)
	(segment
		(start 115.353846 -228.610668)
		(end 115.35537 -228.611684)
		(width 0.1143)
		(layer "In13.Cu")
		(net "GMI_CPU0_G0_CPU1_G2_TX_DN<3>")
	)
	(segment
		(start 115.34775 -226.34194)
		(end 115.346988 -226.342448)
		(width 0.1143)
		(layer "In13.Cu")
		(net "GMI_CPU0_G0_CPU1_G2_TX_DN<3>")
	)
	(segment
		(start 115.35029 -238.328454)
		(end 115.351306 -238.328962)
		(width 0.1143)
		(layer "In13.Cu")
		(net "GMI_CPU0_G0_CPU1_G2_TX_DN<3>")
	)
	(segment
		(start 355.395784 -241.246152)
		(end 355.395784 -241.24412)
		(width 0.1143)
		(layer "In13.Cu")
		(net "GMI_CPU0_G0_CPU1_G2_TX_DN<3>")
	)
	(segment
		(start 356.150164 -234.442762)
		(end 356.148894 -234.442)
		(width 0.1143)
		(layer "In13.Cu")
		(net "GMI_CPU0_G0_CPU1_G2_TX_DN<3>")
	)
	(segment
		(start 356.150164 -236.062774)
		(end 356.148894 -236.062012)
		(width 0.1143)
		(layer "In13.Cu")
		(net "GMI_CPU0_G0_CPU1_G2_TX_DN<3>")
	)
	(segment
		(start 354.699824 -242.399058)
		(end 354.738686 -242.376452)
		(width 0.1143)
		(layer "In13.Cu")
		(net "GMI_CPU0_G0_CPU1_G2_TX_DN<3>")
	)
	(segment
		(start 356.148894 -226.342194)
		(end 356.148132 -226.341686)
		(width 0.1143)
		(layer "In13.Cu")
		(net "GMI_CPU0_G0_CPU1_G2_TX_DN<3>")
	)
	(segment
		(start 115.386866 -234.418886)
		(end 115.348766 -234.441238)
		(width 0.1143)
		(layer "In13.Cu")
		(net "GMI_CPU0_G0_CPU1_G2_TX_DN<3>")
	)
	(segment
		(start 115.352068 -238.32947)
		(end 115.353846 -238.330486)
		(width 0.1143)
		(layer "In13.Cu")
		(net "GMI_CPU0_G0_CPU1_G2_TX_DN<3>")
	)
	(segment
		(start 115.35537 -225.37166)
		(end 115.386866 -225.389948)
		(width 0.1143)
		(layer "In13.Cu")
		(net "GMI_CPU0_G0_CPU1_G2_TX_DN<3>")
	)
	(segment
		(start 116.570506 -215.551004)
		(end 116.39296 -215.597232)
		(width 0.14224)
		(layer "In13.Cu")
		(net "GMI_CPU0_G0_CPU1_G2_TX_DN<3>")
	)
	(segment
		(start 356.147116 -236.060996)
		(end 356.145592 -236.05998)
		(width 0.1143)
		(layer "In13.Cu")
		(net "GMI_CPU0_G0_CPU1_G2_TX_DN<3>")
	)
	(segment
		(start 115.386866 -226.31908)
		(end 115.348766 -226.341432)
		(width 0.1143)
		(layer "In13.Cu")
		(net "GMI_CPU0_G0_CPU1_G2_TX_DN<3>")
	)
	(segment
		(start 115.386866 -236.038898)
		(end 115.348766 -236.06125)
		(width 0.1143)
		(layer "In13.Cu")
		(net "GMI_CPU0_G0_CPU1_G2_TX_DN<3>")
	)
	(segment
		(start 115.348766 -236.707426)
		(end 115.35029 -236.708442)
		(width 0.1143)
		(layer "In13.Cu")
		(net "GMI_CPU0_G0_CPU1_G2_TX_DN<3>")
	)
	(segment
		(start 356.179882 -233.448098)
		(end 356.179882 -233.448352)
		(width 0.1143)
		(layer "In13.Cu")
		(net "GMI_CPU0_G0_CPU1_G2_TX_DN<3>")
	)
	(segment
		(start 354.379022 -242.864132)
		(end 354.461826 -242.781328)
		(width 0.1143)
		(layer "In13.Cu")
		(net "GMI_CPU0_G0_CPU1_G2_TX_DN<3>")
	)
	(segment
		(start 115.316 -222.108776)
		(end 115.34775 -222.127064)
		(width 0.1143)
		(layer "In13.Cu")
		(net "GMI_CPU0_G0_CPU1_G2_TX_DN<3>")
	)
	(segment
		(start 356.109016 -225.389694)
		(end 356.11943 -225.383598)
		(width 0.1143)
		(layer "In13.Cu")
		(net "GMI_CPU0_G0_CPU1_G2_TX_DN<3>")
	)
	(segment
		(start 356.117652 -223.764602)
		(end 356.11943 -223.763586)
		(width 0.1143)
		(layer "In13.Cu")
		(net "GMI_CPU0_G0_CPU1_G2_TX_DN<3>")
	)
	(segment
		(start 115.346988 -236.70641)
		(end 115.34775 -236.706918)
		(width 0.1143)
		(layer "In13.Cu")
		(net "GMI_CPU0_G0_CPU1_G2_TX_DN<3>")
	)
	(segment
		(start 115.34775 -222.127064)
		(end 115.386866 -222.149924)
		(width 0.1143)
		(layer "In13.Cu")
		(net "GMI_CPU0_G0_CPU1_G2_TX_DN<3>")
	)
	(segment
		(start 116.39296 -215.597232)
		(end 116.181124 -215.958674)
		(width 0.14224)
		(layer "In13.Cu")
		(net "GMI_CPU0_G0_CPU1_G2_TX_DN<3>")
	)
	(segment
		(start 356.148894 -232.821988)
		(end 356.148132 -232.82148)
		(width 0.1143)
		(layer "In13.Cu")
		(net "GMI_CPU0_G0_CPU1_G2_TX_DN<3>")
	)
	(segment
		(start 356.147116 -223.101154)
		(end 356.145592 -223.100138)
		(width 0.1143)
		(layer "In13.Cu")
		(net "GMI_CPU0_G0_CPU1_G2_TX_DN<3>")
	)
	(segment
		(start 356.109016 -239.969548)
		(end 356.116382 -239.96523)
		(width 0.1143)
		(layer "In13.Cu")
		(net "GMI_CPU0_G0_CPU1_G2_TX_DN<3>")
	)
	(segment
		(start 356.150164 -232.82275)
		(end 356.148894 -232.821988)
		(width 0.1143)
		(layer "In13.Cu")
		(net "GMI_CPU0_G0_CPU1_G2_TX_DN<3>")
	)
	(arc
		(start 115.386866 -223.769936)
		(mid 115.630193 -224.234502)
		(end 115.386866 -224.699068)
		(width 0.1143)
		(layer "In13.Cu")
		(net "GMI_CPU0_G0_CPU1_G2_TX_DN<3>")
	)
	(arc
		(start 115.316 -223.120204)
		(mid 115.160072 -223.424496)
		(end 115.316 -223.728788)
		(width 0.1143)
		(layer "In13.Cu")
		(net "GMI_CPU0_G0_CPU1_G2_TX_DN<3>")
	)
	(arc
		(start 356.179882 -239.9284)
		(mid 356.33581 -239.624108)
		(end 356.179882 -239.319816)
		(width 0.1143)
		(layer "In13.Cu")
		(net "GMI_CPU0_G0_CPU1_G2_TX_DN<3>")
	)
	(arc
		(start 115.386866 -236.729778)
		(mid 115.630193 -237.194344)
		(end 115.386866 -237.65891)
		(width 0.1143)
		(layer "In13.Cu")
		(net "GMI_CPU0_G0_CPU1_G2_TX_DN<3>")
	)
	(arc
		(start 116.79682 -242.39982)
		(mid 116.948807 -242.556328)
		(end 117.030246 -242.758722)
		(width 0.1143)
		(layer "In13.Cu")
		(net "GMI_CPU0_G0_CPU1_G2_TX_DN<3>")
	)
	(arc
		(start 356.109016 -232.79862)
		(mid 355.865689 -232.334054)
		(end 356.109016 -231.869488)
		(width 0.1143)
		(layer "In13.Cu")
		(net "GMI_CPU0_G0_CPU1_G2_TX_DN<3>")
	)
	(arc
		(start 115.386866 -227.00996)
		(mid 115.630193 -227.474526)
		(end 115.386866 -227.939092)
		(width 0.1143)
		(layer "In13.Cu")
		(net "GMI_CPU0_G0_CPU1_G2_TX_DN<3>")
	)
	(arc
		(start 356.109016 -234.418632)
		(mid 355.865689 -233.954066)
		(end 356.109016 -233.4895)
		(width 0.1143)
		(layer "In13.Cu")
		(net "GMI_CPU0_G0_CPU1_G2_TX_DN<3>")
	)
	(arc
		(start 356.179882 -238.308388)
		(mid 356.33581 -238.004096)
		(end 356.179882 -237.699804)
		(width 0.1143)
		(layer "In13.Cu")
		(net "GMI_CPU0_G0_CPU1_G2_TX_DN<3>")
	)
	(arc
		(start 356.179882 -230.208328)
		(mid 356.294558 -230.074994)
		(end 356.335838 -229.904036)
		(width 0.1143)
		(layer "In13.Cu")
		(net "GMI_CPU0_G0_CPU1_G2_TX_DN<3>")
	)
	(arc
		(start 355.241606 -241.547142)
		(mid 355.355011 -241.415247)
		(end 355.395784 -241.246152)
		(width 0.1143)
		(layer "In13.Cu")
		(net "GMI_CPU0_G0_CPU1_G2_TX_DN<3>")
	)
	(arc
		(start 115.316 -227.98024)
		(mid 115.160072 -228.284532)
		(end 115.316 -228.588824)
		(width 0.1143)
		(layer "In13.Cu")
		(net "GMI_CPU0_G0_CPU1_G2_TX_DN<3>")
	)
	(arc
		(start 356.109016 -226.318826)
		(mid 355.865689 -225.85426)
		(end 356.109016 -225.389694)
		(width 0.1143)
		(layer "In13.Cu")
		(net "GMI_CPU0_G0_CPU1_G2_TX_DN<3>")
	)
	(arc
		(start 356.179882 -228.58857)
		(mid 356.33581 -228.284278)
		(end 356.179882 -227.979986)
		(width 0.1143)
		(layer "In13.Cu")
		(net "GMI_CPU0_G0_CPU1_G2_TX_DN<3>")
	)
	(arc
		(start 115.630198 -240.434368)
		(mid 115.671747 -240.60579)
		(end 115.78717 -240.739168)
		(width 0.1143)
		(layer "In13.Cu")
		(net "GMI_CPU0_G0_CPU1_G2_TX_DN<3>")
	)
	(arc
		(start 115.386866 -228.629972)
		(mid 115.630193 -229.094538)
		(end 115.386866 -229.559104)
		(width 0.1143)
		(layer "In13.Cu")
		(net "GMI_CPU0_G0_CPU1_G2_TX_DN<3>")
	)
	(arc
		(start 356.179882 -222.108522)
		(mid 356.294558 -221.975188)
		(end 356.335838 -221.80423)
		(width 0.1143)
		(layer "In13.Cu")
		(net "GMI_CPU0_G0_CPU1_G2_TX_DN<3>")
	)
	(arc
		(start 356.179882 -236.688376)
		(mid 356.33581 -236.384084)
		(end 356.179882 -236.079792)
		(width 0.1143)
		(layer "In13.Cu")
		(net "GMI_CPU0_G0_CPU1_G2_TX_DN<3>")
	)
	(arc
		(start 115.386866 -225.389948)
		(mid 115.630193 -225.854514)
		(end 115.386866 -226.31908)
		(width 0.1143)
		(layer "In13.Cu")
		(net "GMI_CPU0_G0_CPU1_G2_TX_DN<3>")
	)
	(arc
		(start 115.316 -226.360228)
		(mid 115.160072 -226.66452)
		(end 115.316 -226.968812)
		(width 0.1143)
		(layer "In13.Cu")
		(net "GMI_CPU0_G0_CPU1_G2_TX_DN<3>")
	)
	(arc
		(start 115.386866 -231.869742)
		(mid 115.630193 -232.334308)
		(end 115.386866 -232.798874)
		(width 0.1143)
		(layer "In13.Cu")
		(net "GMI_CPU0_G0_CPU1_G2_TX_DN<3>")
	)
	(arc
		(start 115.160044 -231.524302)
		(mid 115.201299 -231.695273)
		(end 115.316 -231.828594)
		(width 0.1143)
		(layer "In13.Cu")
		(net "GMI_CPU0_G0_CPU1_G2_TX_DN<3>")
	)
	(arc
		(start 115.316 -239.32007)
		(mid 115.160072 -239.624362)
		(end 115.316 -239.928654)
		(width 0.1143)
		(layer "In13.Cu")
		(net "GMI_CPU0_G0_CPU1_G2_TX_DN<3>")
	)
	(arc
		(start 115.386866 -235.109766)
		(mid 115.630193 -235.574332)
		(end 115.386866 -236.038898)
		(width 0.1143)
		(layer "In13.Cu")
		(net "GMI_CPU0_G0_CPU1_G2_TX_DN<3>")
	)
	(arc
		(start 356.109016 -239.278668)
		(mid 355.865689 -238.814102)
		(end 356.109016 -238.349536)
		(width 0.1143)
		(layer "In13.Cu")
		(net "GMI_CPU0_G0_CPU1_G2_TX_DN<3>")
	)
	(arc
		(start 355.708712 -240.738914)
		(mid 355.824139 -240.605538)
		(end 355.865684 -240.434114)
		(width 0.1143)
		(layer "In13.Cu")
		(net "GMI_CPU0_G0_CPU1_G2_TX_DN<3>")
	)
	(arc
		(start 115.314222 -229.601522)
		(mid 115.200815 -229.734411)
		(end 115.160044 -229.90429)
		(width 0.1143)
		(layer "In13.Cu")
		(net "GMI_CPU0_G0_CPU1_G2_TX_DN<3>")
	)
	(arc
		(start 354.920042 -242.060222)
		(mid 354.996241 -241.775911)
		(end 355.20503 -241.568478)
		(width 0.1143)
		(layer "In13.Cu")
		(net "GMI_CPU0_G0_CPU1_G2_TX_DN<3>")
	)
	(arc
		(start 115.316 -232.840022)
		(mid 115.160072 -233.144314)
		(end 115.316 -233.448606)
		(width 0.1143)
		(layer "In13.Cu")
		(net "GMI_CPU0_G0_CPU1_G2_TX_DN<3>")
	)
	(arc
		(start 354.738686 -242.376452)
		(mid 354.871466 -242.243347)
		(end 354.920042 -242.061746)
		(width 0.1143)
		(layer "In13.Cu")
		(net "GMI_CPU0_G0_CPU1_G2_TX_DN<3>")
	)
	(arc
		(start 115.316 -224.740216)
		(mid 115.160072 -225.044508)
		(end 115.316 -225.3488)
		(width 0.1143)
		(layer "In13.Cu")
		(net "GMI_CPU0_G0_CPU1_G2_TX_DN<3>")
	)
	(arc
		(start 356.179882 -223.728534)
		(mid 356.33581 -223.424242)
		(end 356.179882 -223.11995)
		(width 0.1143)
		(layer "In13.Cu")
		(net "GMI_CPU0_G0_CPU1_G2_TX_DN<3>")
	)
	(arc
		(start 356.179882 -225.348546)
		(mid 356.33581 -225.044254)
		(end 356.179882 -224.739962)
		(width 0.1143)
		(layer "In13.Cu")
		(net "GMI_CPU0_G0_CPU1_G2_TX_DN<3>")
	)
	(arc
		(start 356.179882 -235.068364)
		(mid 356.33581 -234.764072)
		(end 356.179882 -234.45978)
		(width 0.1143)
		(layer "In13.Cu")
		(net "GMI_CPU0_G0_CPU1_G2_TX_DN<3>")
	)
	(arc
		(start 356.179882 -233.448352)
		(mid 356.33581 -233.14406)
		(end 356.179882 -232.839768)
		(width 0.1143)
		(layer "In13.Cu")
		(net "GMI_CPU0_G0_CPU1_G2_TX_DN<3>")
	)
	(arc
		(start 356.335838 -231.524048)
		(mid 356.295076 -231.354164)
		(end 356.18166 -231.22128)
		(width 0.1143)
		(layer "In13.Cu")
		(net "GMI_CPU0_G0_CPU1_G2_TX_DN<3>")
	)
	(arc
		(start 116.100098 -241.246406)
		(mid 116.140889 -241.415491)
		(end 116.254276 -241.547396)
		(width 0.1143)
		(layer "In13.Cu")
		(net "GMI_CPU0_G0_CPU1_G2_TX_DN<3>")
	)
	(arc
		(start 354.699062 -242.399566)
		(mid 354.699443 -242.399312)
		(end 354.699824 -242.399058)
		(width 0.1143)
		(layer "In13.Cu")
		(net "GMI_CPU0_G0_CPU1_G2_TX_DN<3>")
	)
	(arc
		(start 115.386866 -222.149924)
		(mid 115.630193 -222.61449)
		(end 115.386866 -223.079056)
		(width 0.1143)
		(layer "In13.Cu")
		(net "GMI_CPU0_G0_CPU1_G2_TX_DN<3>")
	)
	(arc
		(start 115.386866 -233.489754)
		(mid 115.630193 -233.95432)
		(end 115.386866 -234.418886)
		(width 0.1143)
		(layer "In13.Cu")
		(net "GMI_CPU0_G0_CPU1_G2_TX_DN<3>")
	)
	(arc
		(start 116.290852 -241.568732)
		(mid 116.499541 -241.776223)
		(end 116.57584 -242.060476)
		(width 0.1143)
		(layer "In13.Cu")
		(net "GMI_CPU0_G0_CPU1_G2_TX_DN<3>")
	)
	(arc
		(start 356.179882 -231.82834)
		(mid 356.294558 -231.695006)
		(end 356.335838 -231.524048)
		(width 0.1143)
		(layer "In13.Cu")
		(net "GMI_CPU0_G0_CPU1_G2_TX_DN<3>")
	)
	(arc
		(start 115.316 -236.080046)
		(mid 115.160072 -236.384338)
		(end 115.316 -236.68863)
		(width 0.1143)
		(layer "In13.Cu")
		(net "GMI_CPU0_G0_CPU1_G2_TX_DN<3>")
	)
	(arc
		(start 354.465636 -242.758468)
		(mid 354.547069 -242.55607)
		(end 354.699062 -242.399566)
		(width 0.1143)
		(layer "In13.Cu")
		(net "GMI_CPU0_G0_CPU1_G2_TX_DN<3>")
	)
	(arc
		(start 356.179882 -226.968558)
		(mid 356.33581 -226.664266)
		(end 356.179882 -226.359974)
		(width 0.1143)
		(layer "In13.Cu")
		(net "GMI_CPU0_G0_CPU1_G2_TX_DN<3>")
	)
	(arc
		(start 356.109016 -224.698814)
		(mid 355.865689 -224.234248)
		(end 356.109016 -223.769682)
		(width 0.1143)
		(layer "In13.Cu")
		(net "GMI_CPU0_G0_CPU1_G2_TX_DN<3>")
	)
	(arc
		(start 356.109016 -236.038644)
		(mid 355.865689 -235.574078)
		(end 356.109016 -235.109512)
		(width 0.1143)
		(layer "In13.Cu")
		(net "GMI_CPU0_G0_CPU1_G2_TX_DN<3>")
	)
	(arc
		(start 117.030246 -242.758722)
		(mid 117.032269 -242.770132)
		(end 117.034056 -242.781582)
		(width 0.1143)
		(layer "In13.Cu")
		(net "GMI_CPU0_G0_CPU1_G2_TX_DN<3>")
	)
	(arc
		(start 354.461826 -242.781328)
		(mid 354.463614 -242.769879)
		(end 354.465636 -242.758468)
		(width 0.1143)
		(layer "In13.Cu")
		(net "GMI_CPU0_G0_CPU1_G2_TX_DN<3>")
	)
	(arc
		(start 356.109016 -227.938838)
		(mid 355.865689 -227.474272)
		(end 356.109016 -227.009706)
		(width 0.1143)
		(layer "In13.Cu")
		(net "GMI_CPU0_G0_CPU1_G2_TX_DN<3>")
	)
	(arc
		(start 115.316 -234.460034)
		(mid 115.160072 -234.764326)
		(end 115.316 -235.068618)
		(width 0.1143)
		(layer "In13.Cu")
		(net "GMI_CPU0_G0_CPU1_G2_TX_DN<3>")
	)
	(arc
		(start 355.865684 -230.714296)
		(mid 355.93092 -230.450705)
		(end 356.111556 -230.247952)
		(width 0.1143)
		(layer "In13.Cu")
		(net "GMI_CPU0_G0_CPU1_G2_TX_DN<3>")
	)
	(arc
		(start 115.316 -237.700058)
		(mid 115.160072 -238.00435)
		(end 115.316 -238.308642)
		(width 0.1143)
		(layer "In13.Cu")
		(net "GMI_CPU0_G0_CPU1_G2_TX_DN<3>")
	)
	(arc
		(start 355.865684 -240.434114)
		(mid 355.930199 -240.171895)
		(end 356.109016 -239.969548)
		(width 0.1143)
		(layer "In13.Cu")
		(net "GMI_CPU0_G0_CPU1_G2_TX_DN<3>")
	)
	(arc
		(start 115.160044 -221.804484)
		(mid 115.201299 -221.975455)
		(end 115.316 -222.108776)
		(width 0.1143)
		(layer "In13.Cu")
		(net "GMI_CPU0_G0_CPU1_G2_TX_DN<3>")
	)
	(arc
		(start 115.314222 -231.221534)
		(mid 115.200815 -231.354423)
		(end 115.160044 -231.524302)
		(width 0.1143)
		(layer "In13.Cu")
		(net "GMI_CPU0_G0_CPU1_G2_TX_DN<3>")
	)
	(arc
		(start 115.384326 -230.248206)
		(mid 115.564978 -230.450951)
		(end 115.630198 -230.71455)
		(width 0.1143)
		(layer "In13.Cu")
		(net "GMI_CPU0_G0_CPU1_G2_TX_DN<3>")
	)
	(arc
		(start 356.335838 -229.904036)
		(mid 356.295076 -229.734152)
		(end 356.18166 -229.601268)
		(width 0.1143)
		(layer "In13.Cu")
		(net "GMI_CPU0_G0_CPU1_G2_TX_DN<3>")
	)
	(arc
		(start 115.160044 -229.90429)
		(mid 115.201299 -230.075261)
		(end 115.316 -230.208582)
		(width 0.1143)
		(layer "In13.Cu")
		(net "GMI_CPU0_G0_CPU1_G2_TX_DN<3>")
	)
	(arc
		(start 115.630198 -230.71455)
		(mid 115.565683 -230.976769)
		(end 115.386866 -231.179116)
		(width 0.1143)
		(layer "In13.Cu")
		(net "GMI_CPU0_G0_CPU1_G2_TX_DN<3>")
	)
	(arc
		(start 116.57584 -242.062)
		(mid 116.624498 -242.243553)
		(end 116.757196 -242.376706)
		(width 0.1143)
		(layer "In13.Cu")
		(net "GMI_CPU0_G0_CPU1_G2_TX_DN<3>")
	)
	(arc
		(start 356.109016 -229.55885)
		(mid 355.865689 -229.094284)
		(end 356.109016 -228.629718)
		(width 0.1143)
		(layer "In13.Cu")
		(net "GMI_CPU0_G0_CPU1_G2_TX_DN<3>")
	)
	(arc
		(start 356.109016 -231.178862)
		(mid 355.930203 -230.976512)
		(end 355.865684 -230.714296)
		(width 0.1143)
		(layer "In13.Cu")
		(net "GMI_CPU0_G0_CPU1_G2_TX_DN<3>")
	)
	(arc
		(start 115.386866 -239.969802)
		(mid 115.565679 -240.172152)
		(end 115.630198 -240.434368)
		(width 0.1143)
		(layer "In13.Cu")
		(net "GMI_CPU0_G0_CPU1_G2_TX_DN<3>")
	)
	(arc
		(start 356.109016 -237.658656)
		(mid 355.865689 -237.19409)
		(end 356.109016 -236.729524)
		(width 0.1143)
		(layer "In13.Cu")
		(net "GMI_CPU0_G0_CPU1_G2_TX_DN<3>")
	)
	(arc
		(start 115.386866 -238.34979)
		(mid 115.630193 -238.814356)
		(end 115.386866 -239.278922)
		(width 0.1143)
		(layer "In13.Cu")
		(net "GMI_CPU0_G0_CPU1_G2_TX_DN<3>")
	)
	(arc
		(start 355.395784 -241.24412)
		(mid 355.460299 -240.981901)
		(end 355.639116 -240.779554)
		(width 0.1143)
		(layer "In13.Cu")
		(net "GMI_CPU0_G0_CPU1_G2_TX_DN<3>")
	)
	(arc
		(start 115.856766 -240.779808)
		(mid 116.035579 -240.982158)
		(end 116.100098 -241.244374)
		(width 0.1143)
		(layer "In13.Cu")
		(net "GMI_CPU0_G0_CPU1_G2_TX_DN<3>")
	)
	(arc
		(start 356.109016 -223.078802)
		(mid 355.865689 -222.614236)
		(end 356.109016 -222.14967)
		(width 0.1143)
		(layer "In13.Cu")
		(net "GMI_CPU0_G0_CPU1_G2_TX_DN<3>")
	)
	(arc
		(start 116.796058 -242.399312)
		(mid 116.796439 -242.399566)
		(end 116.79682 -242.39982)
		(width 0.1143)
		(layer "In13.Cu")
		(net "GMI_CPU0_G0_CPU1_G2_TX_DN<3>")
	)
	(segment
		(start 356.89794 -239.08004)
		(end 356.431088 -238.814102)
		(width 0.12954)
		(layer "F.Cu")
		(net "GMI_CPU0_G0_CPU1_G2_TX_DN<2>")
	)
	(segment
		(start 114.597942 -239.080294)
		(end 115.064794 -238.814356)
		(width 0.12954)
		(layer "F.Cu")
		(net "GMI_CPU0_G0_CPU1_G2_TX_DN<2>")
	)
	(segment
		(start 357.088948 -222.126302)
		(end 357.090218 -222.12554)
		(width 0.1143)
		(layer "In13.Cu")
		(net "GMI_CPU0_G0_CPU1_G2_TX_DN<2>")
	)
	(segment
		(start 357.082852 -226.989894)
		(end 357.083614 -226.989386)
		(width 0.1143)
		(layer "In13.Cu")
		(net "GMI_CPU0_G0_CPU1_G2_TX_DN<2>")
	)
	(segment
		(start 354.492306 -212.601302)
		(end 353.720654 -211.301076)
		(width 0.14224)
		(layer "In13.Cu")
		(net "GMI_CPU0_G0_CPU1_G2_TX_DN<2>")
	)
	(segment
		(start 165.30574 -176.15154)
		(end 156.917136 -179.151026)
		(width 0.14224)
		(layer "In13.Cu")
		(net "GMI_CPU0_G0_CPU1_G2_TX_DN<2>")
	)
	(segment
		(start 308.394862 -176.955196)
		(end 302.913288 -176.955196)
		(width 0.14224)
		(layer "In13.Cu")
		(net "GMI_CPU0_G0_CPU1_G2_TX_DN<2>")
	)
	(segment
		(start 114.428524 -224.709736)
		(end 114.407188 -224.722182)
		(width 0.1143)
		(layer "In13.Cu")
		(net "GMI_CPU0_G0_CPU1_G2_TX_DN<2>")
	)
	(segment
		(start 357.275892 -221.366588)
		(end 357.339392 -221.303088)
		(width 0.1143)
		(layer "In13.Cu")
		(net "GMI_CPU0_G0_CPU1_G2_TX_DN<2>")
	)
	(segment
		(start 114.399822 -226.982528)
		(end 114.412268 -226.98964)
		(width 0.1143)
		(layer "In13.Cu")
		(net "GMI_CPU0_G0_CPU1_G2_TX_DN<2>")
	)
	(segment
		(start 357.083614 -235.089192)
		(end 357.09606 -235.08208)
		(width 0.1143)
		(layer "In13.Cu")
		(net "GMI_CPU0_G0_CPU1_G2_TX_DN<2>")
	)
	(segment
		(start 357.067358 -232.809288)
		(end 357.067104 -232.809288)
		(width 0.1143)
		(layer "In13.Cu")
		(net "GMI_CPU0_G0_CPU1_G2_TX_DN<2>")
	)
	(segment
		(start 357.049832 -227.009198)
		(end 357.082852 -226.989894)
		(width 0.1143)
		(layer "In13.Cu")
		(net "GMI_CPU0_G0_CPU1_G2_TX_DN<2>")
	)
	(segment
		(start 357.293672 -221.100142)
		(end 357.293672 -221.093538)
		(width 0.1143)
		(layer "In13.Cu")
		(net "GMI_CPU0_G0_CPU1_G2_TX_DN<2>")
	)
	(segment
		(start 357.067104 -232.809288)
		(end 357.04907 -232.79862)
		(width 0.1143)
		(layer "In13.Cu")
		(net "GMI_CPU0_G0_CPU1_G2_TX_DN<2>")
	)
	(segment
		(start 357.088694 -227.961952)
		(end 357.067358 -227.949506)
		(width 0.1143)
		(layer "In13.Cu")
		(net "GMI_CPU0_G0_CPU1_G2_TX_DN<2>")
	)
	(segment
		(start 114.21999 -221.366842)
		(end 114.21999 -221.804484)
		(width 0.1143)
		(layer "In13.Cu")
		(net "GMI_CPU0_G0_CPU1_G2_TX_DN<2>")
	)
	(segment
		(start 114.428778 -223.089724)
		(end 114.428524 -223.089724)
		(width 0.1143)
		(layer "In13.Cu")
		(net "GMI_CPU0_G0_CPU1_G2_TX_DN<2>")
	)
	(segment
		(start 353.720654 -211.301076)
		(end 317.647828 -181.723284)
		(width 0.14224)
		(layer "In13.Cu")
		(net "GMI_CPU0_G0_CPU1_G2_TX_DN<2>")
	)
	(segment
		(start 114.15649 -221.146116)
		(end 114.15649 -221.303342)
		(width 0.1143)
		(layer "In13.Cu")
		(net "GMI_CPU0_G0_CPU1_G2_TX_DN<2>")
	)
	(segment
		(start 114.20221 -221.100396)
		(end 114.15649 -221.146116)
		(width 0.1143)
		(layer "In13.Cu")
		(net "GMI_CPU0_G0_CPU1_G2_TX_DN<2>")
	)
	(segment
		(start 357.081836 -231.850184)
		(end 357.082852 -231.849676)
		(width 0.1143)
		(layer "In13.Cu")
		(net "GMI_CPU0_G0_CPU1_G2_TX_DN<2>")
	)
	(segment
		(start 357.092504 -222.12427)
		(end 357.09352 -222.123762)
		(width 0.1143)
		(layer "In13.Cu")
		(net "GMI_CPU0_G0_CPU1_G2_TX_DN<2>")
	)
	(segment
		(start 114.428524 -234.429554)
		(end 114.407188 -234.442)
		(width 0.1143)
		(layer "In13.Cu")
		(net "GMI_CPU0_G0_CPU1_G2_TX_DN<2>")
	)
	(segment
		(start 357.067104 -223.08947)
		(end 357.065834 -223.088708)
		(width 0.1143)
		(layer "In13.Cu")
		(net "GMI_CPU0_G0_CPU1_G2_TX_DN<2>")
	)
	(segment
		(start 356.72903 -238.814102)
		(end 356.811834 -238.731298)
		(width 0.1143)
		(layer "In13.Cu")
		(net "GMI_CPU0_G0_CPU1_G2_TX_DN<2>")
	)
	(segment
		(start 114.412268 -231.849422)
		(end 114.41303 -231.84993)
		(width 0.1143)
		(layer "In13.Cu")
		(net "GMI_CPU0_G0_CPU1_G2_TX_DN<2>")
	)
	(segment
		(start 114.446812 -227.939092)
		(end 114.428778 -227.94976)
		(width 0.1143)
		(layer "In13.Cu")
		(net "GMI_CPU0_G0_CPU1_G2_TX_DN<2>")
	)
	(segment
		(start 310.648096 -177.760884)
		(end 308.394862 -176.955196)
		(width 0.14224)
		(layer "In13.Cu")
		(net "GMI_CPU0_G0_CPU1_G2_TX_DN<2>")
	)
	(segment
		(start 114.399822 -223.742504)
		(end 114.412268 -223.749616)
		(width 0.1143)
		(layer "In13.Cu")
		(net "GMI_CPU0_G0_CPU1_G2_TX_DN<2>")
	)
	(segment
		(start 357.049832 -238.349028)
		(end 357.088694 -238.326676)
		(width 0.1143)
		(layer "In13.Cu")
		(net "GMI_CPU0_G0_CPU1_G2_TX_DN<2>")
	)
	(segment
		(start 114.879882 -216.322656)
		(end 114.702336 -216.36863)
		(width 0.14224)
		(layer "In13.Cu")
		(net "GMI_CPU0_G0_CPU1_G2_TX_DN<2>")
	)
	(segment
		(start 357.081836 -235.090208)
		(end 357.082852 -235.0897)
		(width 0.1143)
		(layer "In13.Cu")
		(net "GMI_CPU0_G0_CPU1_G2_TX_DN<2>")
	)
	(segment
		(start 357.081836 -228.610414)
		(end 357.082852 -228.609906)
		(width 0.1143)
		(layer "In13.Cu")
		(net "GMI_CPU0_G0_CPU1_G2_TX_DN<2>")
	)
	(segment
		(start 114.430048 -223.088962)
		(end 114.428778 -223.089724)
		(width 0.1143)
		(layer "In13.Cu")
		(net "GMI_CPU0_G0_CPU1_G2_TX_DN<2>")
	)
	(segment
		(start 114.414046 -233.47045)
		(end 114.44605 -233.489246)
		(width 0.1143)
		(layer "In13.Cu")
		(net "GMI_CPU0_G0_CPU1_G2_TX_DN<2>")
	)
	(segment
		(start 114.399822 -233.462322)
		(end 114.412268 -233.469434)
		(width 0.1143)
		(layer "In13.Cu")
		(net "GMI_CPU0_G0_CPU1_G2_TX_DN<2>")
	)
	(segment
		(start 114.405664 -222.125794)
		(end 114.406934 -222.126556)
		(width 0.1143)
		(layer "In13.Cu")
		(net "GMI_CPU0_G0_CPU1_G2_TX_DN<2>")
	)
	(segment
		(start 357.091742 -222.124778)
		(end 357.092504 -222.12427)
		(width 0.1143)
		(layer "In13.Cu")
		(net "GMI_CPU0_G0_CPU1_G2_TX_DN<2>")
	)
	(segment
		(start 357.067358 -223.08947)
		(end 357.067104 -223.08947)
		(width 0.1143)
		(layer "In13.Cu")
		(net "GMI_CPU0_G0_CPU1_G2_TX_DN<2>")
	)
	(segment
		(start 114.375946 -236.68863)
		(end 114.404648 -236.704886)
		(width 0.1143)
		(layer "In13.Cu")
		(net "GMI_CPU0_G0_CPU1_G2_TX_DN<2>")
	)
	(segment
		(start 114.399822 -231.84231)
		(end 114.412268 -231.849422)
		(width 0.1143)
		(layer "In13.Cu")
		(net "GMI_CPU0_G0_CPU1_G2_TX_DN<2>")
	)
	(segment
		(start 357.04907 -225.389694)
		(end 357.08717 -225.367342)
		(width 0.1143)
		(layer "In13.Cu")
		(net "GMI_CPU0_G0_CPU1_G2_TX_DN<2>")
	)
	(segment
		(start 357.083614 -233.46918)
		(end 357.09606 -233.462068)
		(width 0.1143)
		(layer "In13.Cu")
		(net "GMI_CPU0_G0_CPU1_G2_TX_DN<2>")
	)
	(segment
		(start 356.34168 -215.970358)
		(end 356.127812 -215.609678)
		(width 0.14224)
		(layer "In13.Cu")
		(net "GMI_CPU0_G0_CPU1_G2_TX_DN<2>")
	)
	(segment
		(start 114.407188 -238.32693)
		(end 114.44605 -238.349282)
		(width 0.1143)
		(layer "In13.Cu")
		(net "GMI_CPU0_G0_CPU1_G2_TX_DN<2>")
	)
	(segment
		(start 114.410744 -236.708442)
		(end 114.446812 -236.729778)
		(width 0.1143)
		(layer "In13.Cu")
		(net "GMI_CPU0_G0_CPU1_G2_TX_DN<2>")
	)
	(segment
		(start 356.688136 -216.553288)
		(end 356.733348 -216.375742)
		(width 0.14224)
		(layer "In13.Cu")
		(net "GMI_CPU0_G0_CPU1_G2_TX_DN<2>")
	)
	(segment
		(start 355.052376 -213.544912)
		(end 354.838508 -213.18474)
		(width 0.14224)
		(layer "In13.Cu")
		(net "GMI_CPU0_G0_CPU1_G2_TX_DN<2>")
	)
	(segment
		(start 357.079804 -216.95918)
		(end 356.902004 -216.913968)
		(width 0.14224)
		(layer "In13.Cu")
		(net "GMI_CPU0_G0_CPU1_G2_TX_DN<2>")
	)
	(segment
		(start 114.446812 -224.699068)
		(end 114.428778 -224.709736)
		(width 0.1143)
		(layer "In13.Cu")
		(net "GMI_CPU0_G0_CPU1_G2_TX_DN<2>")
	)
	(segment
		(start 356.733348 -216.375742)
		(end 356.51948 -216.01557)
		(width 0.14224)
		(layer "In13.Cu")
		(net "GMI_CPU0_G0_CPU1_G2_TX_DN<2>")
	)
	(segment
		(start 355.959156 -215.07196)
		(end 355.781356 -215.026494)
		(width 0.14224)
		(layer "In13.Cu")
		(net "GMI_CPU0_G0_CPU1_G2_TX_DN<2>")
	)
	(segment
		(start 356.431088 -238.814102)
		(end 356.72903 -238.814102)
		(width 0.1143)
		(layer "In13.Cu")
		(net "GMI_CPU0_G0_CPU1_G2_TX_DN<2>")
	)
	(segment
		(start 357.088694 -229.581456)
		(end 357.04907 -229.55885)
		(width 0.1143)
		(layer "In13.Cu")
		(net "GMI_CPU0_G0_CPU1_G2_TX_DN<2>")
	)
	(segment
		(start 357.067104 -234.4293)
		(end 357.04907 -234.418632)
		(width 0.1143)
		(layer "In13.Cu")
		(net "GMI_CPU0_G0_CPU1_G2_TX_DN<2>")
	)
	(segment
		(start 317.647828 -181.723284)
		(end 310.648096 -177.760884)
		(width 0.14224)
		(layer "In13.Cu")
		(net "GMI_CPU0_G0_CPU1_G2_TX_DN<2>")
	)
	(segment
		(start 115.091972 -215.96096)
		(end 114.879882 -216.322656)
		(width 0.14224)
		(layer "In13.Cu")
		(net "GMI_CPU0_G0_CPU1_G2_TX_DN<2>")
	)
	(segment
		(start 357.049832 -231.86898)
		(end 357.081836 -231.850184)
		(width 0.1143)
		(layer "In13.Cu")
		(net "GMI_CPU0_G0_CPU1_G2_TX_DN<2>")
	)
	(segment
		(start 355.007164 -213.722458)
		(end 355.052376 -213.544912)
		(width 0.14224)
		(layer "In13.Cu")
		(net "GMI_CPU0_G0_CPU1_G2_TX_DN<2>")
	)
	(segment
		(start 354.838508 -213.18474)
		(end 354.660962 -213.139274)
		(width 0.14224)
		(layer "In13.Cu")
		(net "GMI_CPU0_G0_CPU1_G2_TX_DN<2>")
	)
	(segment
		(start 356.51948 -216.01557)
		(end 356.34168 -215.970358)
		(width 0.14224)
		(layer "In13.Cu")
		(net "GMI_CPU0_G0_CPU1_G2_TX_DN<2>")
	)
	(segment
		(start 114.443764 -231.18064)
		(end 114.407188 -231.201976)
		(width 0.1143)
		(layer "In13.Cu")
		(net "GMI_CPU0_G0_CPU1_G2_TX_DN<2>")
	)
	(segment
		(start 114.408712 -222.127572)
		(end 114.42827 -222.139002)
		(width 0.1143)
		(layer "In13.Cu")
		(net "GMI_CPU0_G0_CPU1_G2_TX_DN<2>")
	)
	(segment
		(start 357.067104 -226.329494)
		(end 357.04907 -226.318826)
		(width 0.1143)
		(layer "In13.Cu")
		(net "GMI_CPU0_G0_CPU1_G2_TX_DN<2>")
	)
	(segment
		(start 115.813332 -214.475822)
		(end 115.601242 -214.837264)
		(width 0.14224)
		(layer "In13.Cu")
		(net "GMI_CPU0_G0_CPU1_G2_TX_DN<2>")
	)
	(segment
		(start 357.083614 -226.989386)
		(end 357.09606 -226.982274)
		(width 0.1143)
		(layer "In13.Cu")
		(net "GMI_CPU0_G0_CPU1_G2_TX_DN<2>")
	)
	(segment
		(start 114.412268 -226.98964)
		(end 114.41303 -226.990148)
		(width 0.1143)
		(layer "In13.Cu")
		(net "GMI_CPU0_G0_CPU1_G2_TX_DN<2>")
	)
	(segment
		(start 114.766852 -238.814356)
		(end 115.064794 -238.814356)
		(width 0.1143)
		(layer "In13.Cu")
		(net "GMI_CPU0_G0_CPU1_G2_TX_DN<2>")
	)
	(segment
		(start 114.412268 -233.469434)
		(end 114.41303 -233.469942)
		(width 0.1143)
		(layer "In13.Cu")
		(net "GMI_CPU0_G0_CPU1_G2_TX_DN<2>")
	)
	(segment
		(start 357.293672 -217.319352)
		(end 357.079804 -216.95918)
		(width 0.14224)
		(layer "In13.Cu")
		(net "GMI_CPU0_G0_CPU1_G2_TX_DN<2>")
	)
	(segment
		(start 114.702336 -216.36863)
		(end 114.20221 -217.221054)
		(width 0.14224)
		(layer "In13.Cu")
		(net "GMI_CPU0_G0_CPU1_G2_TX_DN<2>")
	)
	(segment
		(start 115.601242 -214.837264)
		(end 115.64747 -215.014556)
		(width 0.14224)
		(layer "In13.Cu")
		(net "GMI_CPU0_G0_CPU1_G2_TX_DN<2>")
	)
	(segment
		(start 115.045744 -215.783668)
		(end 115.091972 -215.96096)
		(width 0.14224)
		(layer "In13.Cu")
		(net "GMI_CPU0_G0_CPU1_G2_TX_DN<2>")
	)
	(segment
		(start 114.446812 -226.31908)
		(end 114.428778 -226.329748)
		(width 0.1143)
		(layer "In13.Cu")
		(net "GMI_CPU0_G0_CPU1_G2_TX_DN<2>")
	)
	(segment
		(start 114.406934 -222.126556)
		(end 114.407696 -222.127064)
		(width 0.1143)
		(layer "In13.Cu")
		(net "GMI_CPU0_G0_CPU1_G2_TX_DN<2>")
	)
	(segment
		(start 114.428524 -226.329748)
		(end 114.407188 -226.342194)
		(width 0.1143)
		(layer "In13.Cu")
		(net "GMI_CPU0_G0_CPU1_G2_TX_DN<2>")
	)
	(segment
		(start 114.412268 -235.089446)
		(end 114.41303 -235.089954)
		(width 0.1143)
		(layer "In13.Cu")
		(net "GMI_CPU0_G0_CPU1_G2_TX_DN<2>")
	)
	(segment
		(start 114.407696 -222.127064)
		(end 114.408712 -222.127572)
		(width 0.1143)
		(layer "In13.Cu")
		(net "GMI_CPU0_G0_CPU1_G2_TX_DN<2>")
	)
	(segment
		(start 357.139748 -236.094016)
		(end 357.119936 -236.079792)
		(width 0.1143)
		(layer "In13.Cu")
		(net "GMI_CPU0_G0_CPU1_G2_TX_DN<2>")
	)
	(segment
		(start 357.117396 -229.59822)
		(end 357.088694 -229.581456)
		(width 0.1143)
		(layer "In13.Cu")
		(net "GMI_CPU0_G0_CPU1_G2_TX_DN<2>")
	)
	(segment
		(start 357.067612 -222.138748)
		(end 357.08717 -222.127318)
		(width 0.1143)
		(layer "In13.Cu")
		(net "GMI_CPU0_G0_CPU1_G2_TX_DN<2>")
	)
	(segment
		(start 357.088186 -222.12681)
		(end 357.088948 -222.126302)
		(width 0.1143)
		(layer "In13.Cu")
		(net "GMI_CPU0_G0_CPU1_G2_TX_DN<2>")
	)
	(segment
		(start 357.082852 -233.469688)
		(end 357.083614 -233.46918)
		(width 0.1143)
		(layer "In13.Cu")
		(net "GMI_CPU0_G0_CPU1_G2_TX_DN<2>")
	)
	(segment
		(start 357.083614 -228.609398)
		(end 357.09606 -228.602286)
		(width 0.1143)
		(layer "In13.Cu")
		(net "GMI_CPU0_G0_CPU1_G2_TX_DN<2>")
	)
	(segment
		(start 357.091234 -236.704632)
		(end 357.119936 -236.688376)
		(width 0.1143)
		(layer "In13.Cu")
		(net "GMI_CPU0_G0_CPU1_G2_TX_DN<2>")
	)
	(segment
		(start 357.052118 -231.180386)
		(end 357.04907 -231.178862)
		(width 0.1143)
		(layer "In13.Cu")
		(net "GMI_CPU0_G0_CPU1_G2_TX_DN<2>")
	)
	(segment
		(start 114.414046 -235.090462)
		(end 114.44605 -235.109258)
		(width 0.1143)
		(layer "In13.Cu")
		(net "GMI_CPU0_G0_CPU1_G2_TX_DN<2>")
	)
	(segment
		(start 357.339392 -221.145862)
		(end 357.293672 -221.100142)
		(width 0.1143)
		(layer "In13.Cu")
		(net "GMI_CPU0_G0_CPU1_G2_TX_DN<2>")
	)
	(segment
		(start 357.081836 -233.470196)
		(end 357.082852 -233.469688)
		(width 0.1143)
		(layer "In13.Cu")
		(net "GMI_CPU0_G0_CPU1_G2_TX_DN<2>")
	)
	(segment
		(start 156.917136 -179.151026)
		(end 117.64772 -211.349844)
		(width 0.14224)
		(layer "In13.Cu")
		(net "GMI_CPU0_G0_CPU1_G2_TX_DN<2>")
	)
	(segment
		(start 356.127812 -215.609678)
		(end 356.173024 -215.432132)
		(width 0.14224)
		(layer "In13.Cu")
		(net "GMI_CPU0_G0_CPU1_G2_TX_DN<2>")
	)
	(segment
		(start 114.20221 -221.071948)
		(end 114.20221 -221.100396)
		(width 0.1143)
		(layer "In13.Cu")
		(net "GMI_CPU0_G0_CPU1_G2_TX_DN<2>")
	)
	(segment
		(start 357.119936 -236.079792)
		(end 357.088186 -236.061504)
		(width 0.1143)
		(layer "In13.Cu")
		(net "GMI_CPU0_G0_CPU1_G2_TX_DN<2>")
	)
	(segment
		(start 114.387122 -230.214932)
		(end 114.444272 -230.248206)
		(width 0.1143)
		(layer "In13.Cu")
		(net "GMI_CPU0_G0_CPU1_G2_TX_DN<2>")
	)
	(segment
		(start 357.088694 -231.201722)
		(end 357.052118 -231.180386)
		(width 0.1143)
		(layer "In13.Cu")
		(net "GMI_CPU0_G0_CPU1_G2_TX_DN<2>")
	)
	(segment
		(start 357.088694 -224.721928)
		(end 357.067358 -224.709482)
		(width 0.1143)
		(layer "In13.Cu")
		(net "GMI_CPU0_G0_CPU1_G2_TX_DN<2>")
	)
	(segment
		(start 114.408712 -225.367596)
		(end 114.446812 -225.389948)
		(width 0.1143)
		(layer "In13.Cu")
		(net "GMI_CPU0_G0_CPU1_G2_TX_DN<2>")
	)
	(segment
		(start 114.428778 -227.94976)
		(end 114.428524 -227.94976)
		(width 0.1143)
		(layer "In13.Cu")
		(net "GMI_CPU0_G0_CPU1_G2_TX_DN<2>")
	)
	(segment
		(start 357.088186 -225.366834)
		(end 357.088948 -225.36658)
		(width 0.1143)
		(layer "In13.Cu")
		(net "GMI_CPU0_G0_CPU1_G2_TX_DN<2>")
	)
	(segment
		(start 356.173024 -215.432132)
		(end 355.959156 -215.07196)
		(width 0.14224)
		(layer "In13.Cu")
		(net "GMI_CPU0_G0_CPU1_G2_TX_DN<2>")
	)
	(segment
		(start 114.40414 -222.125032)
		(end 114.405664 -222.125794)
		(width 0.1143)
		(layer "In13.Cu")
		(net "GMI_CPU0_G0_CPU1_G2_TX_DN<2>")
	)
	(segment
		(start 357.09352 -222.123762)
		(end 357.119936 -222.108522)
		(width 0.1143)
		(layer "In13.Cu")
		(net "GMI_CPU0_G0_CPU1_G2_TX_DN<2>")
	)
	(segment
		(start 357.067358 -226.329494)
		(end 357.067104 -226.329494)
		(width 0.1143)
		(layer "In13.Cu")
		(net "GMI_CPU0_G0_CPU1_G2_TX_DN<2>")
	)
	(segment
		(start 114.15649 -221.303342)
		(end 114.21999 -221.366842)
		(width 0.1143)
		(layer "In13.Cu")
		(net "GMI_CPU0_G0_CPU1_G2_TX_DN<2>")
	)
	(segment
		(start 114.414046 -228.610668)
		(end 114.44605 -228.629464)
		(width 0.1143)
		(layer "In13.Cu")
		(net "GMI_CPU0_G0_CPU1_G2_TX_DN<2>")
	)
	(segment
		(start 355.781356 -215.026494)
		(end 355.567488 -214.666068)
		(width 0.14224)
		(layer "In13.Cu")
		(net "GMI_CPU0_G0_CPU1_G2_TX_DN<2>")
	)
	(segment
		(start 114.446812 -234.418886)
		(end 114.428778 -234.429554)
		(width 0.1143)
		(layer "In13.Cu")
		(net "GMI_CPU0_G0_CPU1_G2_TX_DN<2>")
	)
	(segment
		(start 357.049832 -235.109004)
		(end 357.081836 -235.090208)
		(width 0.1143)
		(layer "In13.Cu")
		(net "GMI_CPU0_G0_CPU1_G2_TX_DN<2>")
	)
	(segment
		(start 114.446812 -232.798874)
		(end 114.428778 -232.809542)
		(width 0.1143)
		(layer "In13.Cu")
		(net "GMI_CPU0_G0_CPU1_G2_TX_DN<2>")
	)
	(segment
		(start 114.414046 -226.990656)
		(end 114.44605 -227.009452)
		(width 0.1143)
		(layer "In13.Cu")
		(net "GMI_CPU0_G0_CPU1_G2_TX_DN<2>")
	)
	(segment
		(start 114.399822 -235.082334)
		(end 114.412268 -235.089446)
		(width 0.1143)
		(layer "In13.Cu")
		(net "GMI_CPU0_G0_CPU1_G2_TX_DN<2>")
	)
	(segment
		(start 357.067104 -224.709482)
		(end 357.04907 -224.698814)
		(width 0.1143)
		(layer "In13.Cu")
		(net "GMI_CPU0_G0_CPU1_G2_TX_DN<2>")
	)
	(segment
		(start 357.049832 -228.62921)
		(end 357.081836 -228.610414)
		(width 0.1143)
		(layer "In13.Cu")
		(net "GMI_CPU0_G0_CPU1_G2_TX_DN<2>")
	)
	(segment
		(start 355.6127 -214.488522)
		(end 355.398832 -214.12835)
		(width 0.14224)
		(layer "In13.Cu")
		(net "GMI_CPU0_G0_CPU1_G2_TX_DN<2>")
	)
	(segment
		(start 355.567488 -214.666068)
		(end 355.6127 -214.488522)
		(width 0.14224)
		(layer "In13.Cu")
		(net "GMI_CPU0_G0_CPU1_G2_TX_DN<2>")
	)
	(segment
		(start 114.446812 -237.65891)
		(end 114.407188 -237.682024)
		(width 0.1143)
		(layer "In13.Cu")
		(net "GMI_CPU0_G0_CPU1_G2_TX_DN<2>")
	)
	(segment
		(start 114.407696 -225.367088)
		(end 114.408712 -225.367596)
		(width 0.1143)
		(layer "In13.Cu")
		(net "GMI_CPU0_G0_CPU1_G2_TX_DN<2>")
	)
	(segment
		(start 357.088694 -234.441746)
		(end 357.067358 -234.4293)
		(width 0.1143)
		(layer "In13.Cu")
		(net "GMI_CPU0_G0_CPU1_G2_TX_DN<2>")
	)
	(segment
		(start 357.082852 -235.0897)
		(end 357.083614 -235.089192)
		(width 0.1143)
		(layer "In13.Cu")
		(net "GMI_CPU0_G0_CPU1_G2_TX_DN<2>")
	)
	(segment
		(start 114.407696 -236.061758)
		(end 114.375946 -236.080046)
		(width 0.1143)
		(layer "In13.Cu")
		(net "GMI_CPU0_G0_CPU1_G2_TX_DN<2>")
	)
	(segment
		(start 355.398832 -214.12835)
		(end 355.221032 -214.082884)
		(width 0.14224)
		(layer "In13.Cu")
		(net "GMI_CPU0_G0_CPU1_G2_TX_DN<2>")
	)
	(segment
		(start 114.684048 -238.731552)
		(end 114.766852 -238.814356)
		(width 0.1143)
		(layer "In13.Cu")
		(net "GMI_CPU0_G0_CPU1_G2_TX_DN<2>")
	)
	(segment
		(start 115.64747 -215.014556)
		(end 115.43538 -215.376252)
		(width 0.14224)
		(layer "In13.Cu")
		(net "GMI_CPU0_G0_CPU1_G2_TX_DN<2>")
	)
	(segment
		(start 114.375946 -236.080046)
		(end 114.356134 -236.09427)
		(width 0.1143)
		(layer "In13.Cu")
		(net "GMI_CPU0_G0_CPU1_G2_TX_DN<2>")
	)
	(segment
		(start 114.41303 -228.61016)
		(end 114.414046 -228.610668)
		(width 0.1143)
		(layer "In13.Cu")
		(net "GMI_CPU0_G0_CPU1_G2_TX_DN<2>")
	)
	(segment
		(start 357.088694 -223.101916)
		(end 357.067358 -223.08947)
		(width 0.1143)
		(layer "In13.Cu")
		(net "GMI_CPU0_G0_CPU1_G2_TX_DN<2>")
	)
	(segment
		(start 357.088948 -225.36658)
		(end 357.09733 -225.361754)
		(width 0.1143)
		(layer "In13.Cu")
		(net "GMI_CPU0_G0_CPU1_G2_TX_DN<2>")
	)
	(segment
		(start 354.660962 -213.139274)
		(end 354.44684 -212.778594)
		(width 0.14224)
		(layer "In13.Cu")
		(net "GMI_CPU0_G0_CPU1_G2_TX_DN<2>")
	)
	(segment
		(start 114.683794 -238.731552)
		(end 114.684048 -238.731552)
		(width 0.1143)
		(layer "In13.Cu")
		(net "GMI_CPU0_G0_CPU1_G2_TX_DN<2>")
	)
	(segment
		(start 114.20221 -217.221054)
		(end 114.20221 -221.071948)
		(width 0.14224)
		(layer "In13.Cu")
		(net "GMI_CPU0_G0_CPU1_G2_TX_DN<2>")
	)
	(segment
		(start 114.428778 -234.429554)
		(end 114.428524 -234.429554)
		(width 0.1143)
		(layer "In13.Cu")
		(net "GMI_CPU0_G0_CPU1_G2_TX_DN<2>")
	)
	(segment
		(start 114.428778 -224.709736)
		(end 114.428524 -224.709736)
		(width 0.1143)
		(layer "In13.Cu")
		(net "GMI_CPU0_G0_CPU1_G2_TX_DN<2>")
	)
	(segment
		(start 115.990878 -214.429848)
		(end 115.813332 -214.475822)
		(width 0.14224)
		(layer "In13.Cu")
		(net "GMI_CPU0_G0_CPU1_G2_TX_DN<2>")
	)
	(segment
		(start 114.41303 -235.089954)
		(end 114.414046 -235.090462)
		(width 0.1143)
		(layer "In13.Cu")
		(net "GMI_CPU0_G0_CPU1_G2_TX_DN<2>")
	)
	(segment
		(start 114.41303 -233.469942)
		(end 114.414046 -233.47045)
		(width 0.1143)
		(layer "In13.Cu")
		(net "GMI_CPU0_G0_CPU1_G2_TX_DN<2>")
	)
	(segment
		(start 114.356134 -236.674406)
		(end 114.375946 -236.68863)
		(width 0.1143)
		(layer "In13.Cu")
		(net "GMI_CPU0_G0_CPU1_G2_TX_DN<2>")
	)
	(segment
		(start 302.913288 -176.955196)
		(end 165.30574 -176.15154)
		(width 0.14224)
		(layer "In13.Cu")
		(net "GMI_CPU0_G0_CPU1_G2_TX_DN<2>")
	)
	(segment
		(start 114.414046 -231.850438)
		(end 114.44605 -231.869234)
		(width 0.1143)
		(layer "In13.Cu")
		(net "GMI_CPU0_G0_CPU1_G2_TX_DN<2>")
	)
	(segment
		(start 357.082852 -228.609906)
		(end 357.083614 -228.609398)
		(width 0.1143)
		(layer "In13.Cu")
		(net "GMI_CPU0_G0_CPU1_G2_TX_DN<2>")
	)
	(segment
		(start 357.05161 -230.247952)
		(end 357.10876 -230.214678)
		(width 0.1143)
		(layer "In13.Cu")
		(net "GMI_CPU0_G0_CPU1_G2_TX_DN<2>")
	)
	(segment
		(start 356.811834 -238.731298)
		(end 356.812088 -238.731298)
		(width 0.1143)
		(layer "In13.Cu")
		(net "GMI_CPU0_G0_CPU1_G2_TX_DN<2>")
	)
	(segment
		(start 357.088694 -226.34194)
		(end 357.067358 -226.329494)
		(width 0.1143)
		(layer "In13.Cu")
		(net "GMI_CPU0_G0_CPU1_G2_TX_DN<2>")
	)
	(segment
		(start 114.407696 -236.706918)
		(end 114.410744 -236.708442)
		(width 0.1143)
		(layer "In13.Cu")
		(net "GMI_CPU0_G0_CPU1_G2_TX_DN<2>")
	)
	(segment
		(start 117.64772 -211.349844)
		(end 116.15674 -213.89086)
		(width 0.14224)
		(layer "In13.Cu")
		(net "GMI_CPU0_G0_CPU1_G2_TX_DN<2>")
	)
	(segment
		(start 114.41303 -231.84993)
		(end 114.414046 -231.850438)
		(width 0.1143)
		(layer "In13.Cu")
		(net "GMI_CPU0_G0_CPU1_G2_TX_DN<2>")
	)
	(segment
		(start 114.428524 -232.809542)
		(end 114.407188 -232.821988)
		(width 0.1143)
		(layer "In13.Cu")
		(net "GMI_CPU0_G0_CPU1_G2_TX_DN<2>")
	)
	(segment
		(start 114.446812 -229.559104)
		(end 114.407188 -229.58171)
		(width 0.1143)
		(layer "In13.Cu")
		(net "GMI_CPU0_G0_CPU1_G2_TX_DN<2>")
	)
	(segment
		(start 114.375946 -222.108776)
		(end 114.40414 -222.125032)
		(width 0.1143)
		(layer "In13.Cu")
		(net "GMI_CPU0_G0_CPU1_G2_TX_DN<2>")
	)
	(segment
		(start 114.407188 -229.58171)
		(end 114.378486 -229.598474)
		(width 0.1143)
		(layer "In13.Cu")
		(net "GMI_CPU0_G0_CPU1_G2_TX_DN<2>")
	)
	(segment
		(start 357.090218 -222.12554)
		(end 357.091742 -222.124778)
		(width 0.1143)
		(layer "In13.Cu")
		(net "GMI_CPU0_G0_CPU1_G2_TX_DN<2>")
	)
	(segment
		(start 357.067104 -227.949506)
		(end 357.04907 -227.938838)
		(width 0.1143)
		(layer "In13.Cu")
		(net "GMI_CPU0_G0_CPU1_G2_TX_DN<2>")
	)
	(segment
		(start 114.428778 -226.329748)
		(end 114.428524 -226.329748)
		(width 0.1143)
		(layer "In13.Cu")
		(net "GMI_CPU0_G0_CPU1_G2_TX_DN<2>")
	)
	(segment
		(start 357.339392 -221.303088)
		(end 357.339392 -221.145862)
		(width 0.1143)
		(layer "In13.Cu")
		(net "GMI_CPU0_G0_CPU1_G2_TX_DN<2>")
	)
	(segment
		(start 357.293672 -221.093538)
		(end 357.293672 -217.319352)
		(width 0.14224)
		(layer "In13.Cu")
		(net "GMI_CPU0_G0_CPU1_G2_TX_DN<2>")
	)
	(segment
		(start 357.067358 -224.709482)
		(end 357.067104 -224.709482)
		(width 0.1143)
		(layer "In13.Cu")
		(net "GMI_CPU0_G0_CPU1_G2_TX_DN<2>")
	)
	(segment
		(start 357.085138 -236.708188)
		(end 357.088186 -236.706664)
		(width 0.1143)
		(layer "In13.Cu")
		(net "GMI_CPU0_G0_CPU1_G2_TX_DN<2>")
	)
	(segment
		(start 114.412268 -223.749616)
		(end 114.41303 -223.750124)
		(width 0.1143)
		(layer "In13.Cu")
		(net "GMI_CPU0_G0_CPU1_G2_TX_DN<2>")
	)
	(segment
		(start 357.088186 -236.706664)
		(end 357.091234 -236.704632)
		(width 0.1143)
		(layer "In13.Cu")
		(net "GMI_CPU0_G0_CPU1_G2_TX_DN<2>")
	)
	(segment
		(start 116.202968 -214.068152)
		(end 115.990878 -214.429848)
		(width 0.14224)
		(layer "In13.Cu")
		(net "GMI_CPU0_G0_CPU1_G2_TX_DN<2>")
	)
	(segment
		(start 114.399822 -228.60254)
		(end 114.412268 -228.609652)
		(width 0.1143)
		(layer "In13.Cu")
		(net "GMI_CPU0_G0_CPU1_G2_TX_DN<2>")
	)
	(segment
		(start 114.41303 -223.750124)
		(end 114.44605 -223.769428)
		(width 0.1143)
		(layer "In13.Cu")
		(net "GMI_CPU0_G0_CPU1_G2_TX_DN<2>")
	)
	(segment
		(start 114.428778 -232.809542)
		(end 114.428524 -232.809542)
		(width 0.1143)
		(layer "In13.Cu")
		(net "GMI_CPU0_G0_CPU1_G2_TX_DN<2>")
	)
	(segment
		(start 357.275892 -221.80423)
		(end 357.275892 -221.366588)
		(width 0.1143)
		(layer "In13.Cu")
		(net "GMI_CPU0_G0_CPU1_G2_TX_DN<2>")
	)
	(segment
		(start 357.067358 -234.4293)
		(end 357.067104 -234.4293)
		(width 0.1143)
		(layer "In13.Cu")
		(net "GMI_CPU0_G0_CPU1_G2_TX_DN<2>")
	)
	(segment
		(start 114.412268 -228.609652)
		(end 114.41303 -228.61016)
		(width 0.1143)
		(layer "In13.Cu")
		(net "GMI_CPU0_G0_CPU1_G2_TX_DN<2>")
	)
	(segment
		(start 357.082852 -231.849676)
		(end 357.083614 -231.849168)
		(width 0.1143)
		(layer "In13.Cu")
		(net "GMI_CPU0_G0_CPU1_G2_TX_DN<2>")
	)
	(segment
		(start 114.406934 -225.366834)
		(end 114.407696 -225.367088)
		(width 0.1143)
		(layer "In13.Cu")
		(net "GMI_CPU0_G0_CPU1_G2_TX_DN<2>")
	)
	(segment
		(start 114.428524 -227.94976)
		(end 114.407188 -227.962206)
		(width 0.1143)
		(layer "In13.Cu")
		(net "GMI_CPU0_G0_CPU1_G2_TX_DN<2>")
	)
	(segment
		(start 357.067358 -227.949506)
		(end 357.067104 -227.949506)
		(width 0.1143)
		(layer "In13.Cu")
		(net "GMI_CPU0_G0_CPU1_G2_TX_DN<2>")
	)
	(segment
		(start 357.088186 -236.061504)
		(end 357.04907 -236.038644)
		(width 0.1143)
		(layer "In13.Cu")
		(net "GMI_CPU0_G0_CPU1_G2_TX_DN<2>")
	)
	(segment
		(start 357.083614 -231.849168)
		(end 357.09606 -231.842056)
		(width 0.1143)
		(layer "In13.Cu")
		(net "GMI_CPU0_G0_CPU1_G2_TX_DN<2>")
	)
	(segment
		(start 357.049832 -233.488992)
		(end 357.081836 -233.470196)
		(width 0.1143)
		(layer "In13.Cu")
		(net "GMI_CPU0_G0_CPU1_G2_TX_DN<2>")
	)
	(segment
		(start 114.428524 -223.089724)
		(end 114.407188 -223.10217)
		(width 0.1143)
		(layer "In13.Cu")
		(net "GMI_CPU0_G0_CPU1_G2_TX_DN<2>")
	)
	(segment
		(start 115.43538 -215.376252)
		(end 115.257834 -215.422226)
		(width 0.14224)
		(layer "In13.Cu")
		(net "GMI_CPU0_G0_CPU1_G2_TX_DN<2>")
	)
	(segment
		(start 357.049832 -223.769174)
		(end 357.09606 -223.74225)
		(width 0.1143)
		(layer "In13.Cu")
		(net "GMI_CPU0_G0_CPU1_G2_TX_DN<2>")
	)
	(segment
		(start 357.119936 -236.688376)
		(end 357.139748 -236.674152)
		(width 0.1143)
		(layer "In13.Cu")
		(net "GMI_CPU0_G0_CPU1_G2_TX_DN<2>")
	)
	(segment
		(start 114.446812 -231.179116)
		(end 114.443764 -231.18064)
		(width 0.1143)
		(layer "In13.Cu")
		(net "GMI_CPU0_G0_CPU1_G2_TX_DN<2>")
	)
	(segment
		(start 115.257834 -215.422226)
		(end 115.045744 -215.783668)
		(width 0.14224)
		(layer "In13.Cu")
		(net "GMI_CPU0_G0_CPU1_G2_TX_DN<2>")
	)
	(segment
		(start 114.398552 -225.362008)
		(end 114.406934 -225.366834)
		(width 0.1143)
		(layer "In13.Cu")
		(net "GMI_CPU0_G0_CPU1_G2_TX_DN<2>")
	)
	(segment
		(start 114.41303 -226.990148)
		(end 114.414046 -226.990656)
		(width 0.1143)
		(layer "In13.Cu")
		(net "GMI_CPU0_G0_CPU1_G2_TX_DN<2>")
	)
	(segment
		(start 357.088694 -232.821734)
		(end 357.067358 -232.809288)
		(width 0.1143)
		(layer "In13.Cu")
		(net "GMI_CPU0_G0_CPU1_G2_TX_DN<2>")
	)
	(segment
		(start 356.902004 -216.913968)
		(end 356.688136 -216.553288)
		(width 0.14224)
		(layer "In13.Cu")
		(net "GMI_CPU0_G0_CPU1_G2_TX_DN<2>")
	)
	(segment
		(start 116.15674 -213.89086)
		(end 116.202968 -214.068152)
		(width 0.14224)
		(layer "In13.Cu")
		(net "GMI_CPU0_G0_CPU1_G2_TX_DN<2>")
	)
	(segment
		(start 355.221032 -214.082884)
		(end 355.007164 -213.722458)
		(width 0.14224)
		(layer "In13.Cu")
		(net "GMI_CPU0_G0_CPU1_G2_TX_DN<2>")
	)
	(segment
		(start 114.404648 -236.704886)
		(end 114.407696 -236.706918)
		(width 0.1143)
		(layer "In13.Cu")
		(net "GMI_CPU0_G0_CPU1_G2_TX_DN<2>")
	)
	(segment
		(start 354.44684 -212.778594)
		(end 354.492306 -212.601302)
		(width 0.14224)
		(layer "In13.Cu")
		(net "GMI_CPU0_G0_CPU1_G2_TX_DN<2>")
	)
	(segment
		(start 357.088694 -237.68177)
		(end 357.04907 -237.658656)
		(width 0.1143)
		(layer "In13.Cu")
		(net "GMI_CPU0_G0_CPU1_G2_TX_DN<2>")
	)
	(segment
		(start 114.446812 -236.038898)
		(end 114.407696 -236.061758)
		(width 0.1143)
		(layer "In13.Cu")
		(net "GMI_CPU0_G0_CPU1_G2_TX_DN<2>")
	)
	(segment
		(start 357.08717 -222.127318)
		(end 357.088186 -222.12681)
		(width 0.1143)
		(layer "In13.Cu")
		(net "GMI_CPU0_G0_CPU1_G2_TX_DN<2>")
	)
	(segment
		(start 357.04907 -236.729524)
		(end 357.085138 -236.708188)
		(width 0.1143)
		(layer "In13.Cu")
		(net "GMI_CPU0_G0_CPU1_G2_TX_DN<2>")
	)
	(segment
		(start 357.08717 -225.367342)
		(end 357.088186 -225.366834)
		(width 0.1143)
		(layer "In13.Cu")
		(net "GMI_CPU0_G0_CPU1_G2_TX_DN<2>")
	)
	(arc
		(start 114.446812 -227.00996)
		(mid 114.690139 -227.474526)
		(end 114.446812 -227.939092)
		(width 0.1143)
		(layer "In13.Cu")
		(net "GMI_CPU0_G0_CPU1_G2_TX_DN<2>")
	)
	(arc
		(start 357.04907 -227.938838)
		(mid 356.805743 -227.474272)
		(end 357.04907 -227.009706)
		(width 0.1143)
		(layer "In13.Cu")
		(net "GMI_CPU0_G0_CPU1_G2_TX_DN<2>")
	)
	(arc
		(start 114.44605 -238.349282)
		(mid 114.604613 -238.515734)
		(end 114.683794 -238.731552)
		(width 0.1143)
		(layer "In13.Cu")
		(net "GMI_CPU0_G0_CPU1_G2_TX_DN<2>")
	)
	(arc
		(start 357.04907 -233.4895)
		(mid 357.049451 -233.489246)
		(end 357.049832 -233.488992)
		(width 0.1143)
		(layer "In13.Cu")
		(net "GMI_CPU0_G0_CPU1_G2_TX_DN<2>")
	)
	(arc
		(start 114.690144 -230.71455)
		(mid 114.625629 -230.976769)
		(end 114.446812 -231.179116)
		(width 0.1143)
		(layer "In13.Cu")
		(net "GMI_CPU0_G0_CPU1_G2_TX_DN<2>")
	)
	(arc
		(start 357.04907 -224.698814)
		(mid 356.805743 -224.234248)
		(end 357.04907 -223.769682)
		(width 0.1143)
		(layer "In13.Cu")
		(net "GMI_CPU0_G0_CPU1_G2_TX_DN<2>")
	)
	(arc
		(start 357.09606 -235.08208)
		(mid 357.274277 -234.759803)
		(end 357.088694 -234.441746)
		(width 0.1143)
		(layer "In13.Cu")
		(net "GMI_CPU0_G0_CPU1_G2_TX_DN<2>")
	)
	(arc
		(start 114.378486 -229.598474)
		(mid 114.376577 -229.599865)
		(end 114.374676 -229.601268)
		(width 0.1143)
		(layer "In13.Cu")
		(net "GMI_CPU0_G0_CPU1_G2_TX_DN<2>")
	)
	(arc
		(start 114.446812 -225.389948)
		(mid 114.690139 -225.854514)
		(end 114.446812 -226.31908)
		(width 0.1143)
		(layer "In13.Cu")
		(net "GMI_CPU0_G0_CPU1_G2_TX_DN<2>")
	)
	(arc
		(start 357.09733 -225.361754)
		(mid 357.274283 -225.039434)
		(end 357.088694 -224.721928)
		(width 0.1143)
		(layer "In13.Cu")
		(net "GMI_CPU0_G0_CPU1_G2_TX_DN<2>")
	)
	(arc
		(start 357.04907 -236.038644)
		(mid 356.805743 -235.574078)
		(end 357.04907 -235.109512)
		(width 0.1143)
		(layer "In13.Cu")
		(net "GMI_CPU0_G0_CPU1_G2_TX_DN<2>")
	)
	(arc
		(start 114.44605 -227.009452)
		(mid 114.446431 -227.009706)
		(end 114.446812 -227.00996)
		(width 0.1143)
		(layer "In13.Cu")
		(net "GMI_CPU0_G0_CPU1_G2_TX_DN<2>")
	)
	(arc
		(start 357.139748 -236.674152)
		(mid 357.288462 -236.384084)
		(end 357.139748 -236.094016)
		(width 0.1143)
		(layer "In13.Cu")
		(net "GMI_CPU0_G0_CPU1_G2_TX_DN<2>")
	)
	(arc
		(start 114.407188 -237.682024)
		(mid 114.22155 -238.00454)
		(end 114.407188 -238.32693)
		(width 0.1143)
		(layer "In13.Cu")
		(net "GMI_CPU0_G0_CPU1_G2_TX_DN<2>")
	)
	(arc
		(start 114.374676 -229.601268)
		(mid 114.263238 -229.729669)
		(end 114.220244 -229.89413)
		(width 0.1143)
		(layer "In13.Cu")
		(net "GMI_CPU0_G0_CPU1_G2_TX_DN<2>")
	)
	(arc
		(start 357.09606 -226.982274)
		(mid 357.274277 -226.659997)
		(end 357.088694 -226.34194)
		(width 0.1143)
		(layer "In13.Cu")
		(net "GMI_CPU0_G0_CPU1_G2_TX_DN<2>")
	)
	(arc
		(start 114.446812 -231.869742)
		(mid 114.690139 -232.334308)
		(end 114.446812 -232.798874)
		(width 0.1143)
		(layer "In13.Cu")
		(net "GMI_CPU0_G0_CPU1_G2_TX_DN<2>")
	)
	(arc
		(start 357.09606 -233.462068)
		(mid 357.274277 -233.139791)
		(end 357.088694 -232.821734)
		(width 0.1143)
		(layer "In13.Cu")
		(net "GMI_CPU0_G0_CPU1_G2_TX_DN<2>")
	)
	(arc
		(start 357.04907 -237.658656)
		(mid 356.805743 -237.19409)
		(end 357.04907 -236.729524)
		(width 0.1143)
		(layer "In13.Cu")
		(net "GMI_CPU0_G0_CPU1_G2_TX_DN<2>")
	)
	(arc
		(start 357.275638 -229.893876)
		(mid 357.23254 -229.729469)
		(end 357.121206 -229.601014)
		(width 0.1143)
		(layer "In13.Cu")
		(net "GMI_CPU0_G0_CPU1_G2_TX_DN<2>")
	)
	(arc
		(start 357.09606 -228.602286)
		(mid 357.274277 -228.280009)
		(end 357.088694 -227.961952)
		(width 0.1143)
		(layer "In13.Cu")
		(net "GMI_CPU0_G0_CPU1_G2_TX_DN<2>")
	)
	(arc
		(start 114.407188 -234.442)
		(mid 114.221668 -234.760057)
		(end 114.399822 -235.082334)
		(width 0.1143)
		(layer "In13.Cu")
		(net "GMI_CPU0_G0_CPU1_G2_TX_DN<2>")
	)
	(arc
		(start 114.44605 -235.109258)
		(mid 114.446431 -235.109512)
		(end 114.446812 -235.109766)
		(width 0.1143)
		(layer "In13.Cu")
		(net "GMI_CPU0_G0_CPU1_G2_TX_DN<2>")
	)
	(arc
		(start 357.09606 -231.842056)
		(mid 357.274277 -231.519779)
		(end 357.088694 -231.201722)
		(width 0.1143)
		(layer "In13.Cu")
		(net "GMI_CPU0_G0_CPU1_G2_TX_DN<2>")
	)
	(arc
		(start 114.446812 -223.769936)
		(mid 114.690139 -224.234502)
		(end 114.446812 -224.699068)
		(width 0.1143)
		(layer "In13.Cu")
		(net "GMI_CPU0_G0_CPU1_G2_TX_DN<2>")
	)
	(arc
		(start 114.407188 -226.342194)
		(mid 114.221668 -226.660251)
		(end 114.399822 -226.982528)
		(width 0.1143)
		(layer "In13.Cu")
		(net "GMI_CPU0_G0_CPU1_G2_TX_DN<2>")
	)
	(arc
		(start 114.407188 -232.821988)
		(mid 114.221668 -233.140045)
		(end 114.399822 -233.462322)
		(width 0.1143)
		(layer "In13.Cu")
		(net "GMI_CPU0_G0_CPU1_G2_TX_DN<2>")
	)
	(arc
		(start 357.04907 -223.769682)
		(mid 357.049451 -223.769428)
		(end 357.049832 -223.769174)
		(width 0.1143)
		(layer "In13.Cu")
		(net "GMI_CPU0_G0_CPU1_G2_TX_DN<2>")
	)
	(arc
		(start 114.407188 -223.10217)
		(mid 114.221668 -223.420227)
		(end 114.399822 -223.742504)
		(width 0.1143)
		(layer "In13.Cu")
		(net "GMI_CPU0_G0_CPU1_G2_TX_DN<2>")
	)
	(arc
		(start 356.805738 -230.714296)
		(mid 356.870974 -230.450705)
		(end 357.05161 -230.247952)
		(width 0.1143)
		(layer "In13.Cu")
		(net "GMI_CPU0_G0_CPU1_G2_TX_DN<2>")
	)
	(arc
		(start 114.44605 -228.629464)
		(mid 114.446431 -228.629718)
		(end 114.446812 -228.629972)
		(width 0.1143)
		(layer "In13.Cu")
		(net "GMI_CPU0_G0_CPU1_G2_TX_DN<2>")
	)
	(arc
		(start 114.446812 -235.109766)
		(mid 114.690139 -235.574332)
		(end 114.446812 -236.038898)
		(width 0.1143)
		(layer "In13.Cu")
		(net "GMI_CPU0_G0_CPU1_G2_TX_DN<2>")
	)
	(arc
		(start 114.407188 -227.962206)
		(mid 114.221668 -228.280263)
		(end 114.399822 -228.60254)
		(width 0.1143)
		(layer "In13.Cu")
		(net "GMI_CPU0_G0_CPU1_G2_TX_DN<2>")
	)
	(arc
		(start 114.407188 -224.722182)
		(mid 114.221458 -225.039686)
		(end 114.398552 -225.362008)
		(width 0.1143)
		(layer "In13.Cu")
		(net "GMI_CPU0_G0_CPU1_G2_TX_DN<2>")
	)
	(arc
		(start 357.04907 -234.418632)
		(mid 356.805743 -233.954066)
		(end 357.04907 -233.4895)
		(width 0.1143)
		(layer "In13.Cu")
		(net "GMI_CPU0_G0_CPU1_G2_TX_DN<2>")
	)
	(arc
		(start 114.356134 -236.09427)
		(mid 114.20742 -236.384338)
		(end 114.356134 -236.674406)
		(width 0.1143)
		(layer "In13.Cu")
		(net "GMI_CPU0_G0_CPU1_G2_TX_DN<2>")
	)
	(arc
		(start 357.119936 -222.108522)
		(mid 357.234612 -221.975188)
		(end 357.275892 -221.80423)
		(width 0.1143)
		(layer "In13.Cu")
		(net "GMI_CPU0_G0_CPU1_G2_TX_DN<2>")
	)
	(arc
		(start 357.04907 -232.79862)
		(mid 356.805743 -232.334054)
		(end 357.04907 -231.869488)
		(width 0.1143)
		(layer "In13.Cu")
		(net "GMI_CPU0_G0_CPU1_G2_TX_DN<2>")
	)
	(arc
		(start 357.04907 -226.318826)
		(mid 356.805743 -225.85426)
		(end 357.04907 -225.389694)
		(width 0.1143)
		(layer "In13.Cu")
		(net "GMI_CPU0_G0_CPU1_G2_TX_DN<2>")
	)
	(arc
		(start 114.444272 -230.248206)
		(mid 114.624924 -230.450951)
		(end 114.690144 -230.71455)
		(width 0.1143)
		(layer "In13.Cu")
		(net "GMI_CPU0_G0_CPU1_G2_TX_DN<2>")
	)
	(arc
		(start 114.407188 -231.201976)
		(mid 114.221668 -231.520033)
		(end 114.399822 -231.84231)
		(width 0.1143)
		(layer "In13.Cu")
		(net "GMI_CPU0_G0_CPU1_G2_TX_DN<2>")
	)
	(arc
		(start 357.04907 -229.55885)
		(mid 356.805743 -229.094284)
		(end 357.04907 -228.629718)
		(width 0.1143)
		(layer "In13.Cu")
		(net "GMI_CPU0_G0_CPU1_G2_TX_DN<2>")
	)
	(arc
		(start 357.04907 -228.629718)
		(mid 357.049451 -228.629464)
		(end 357.049832 -228.62921)
		(width 0.1143)
		(layer "In13.Cu")
		(net "GMI_CPU0_G0_CPU1_G2_TX_DN<2>")
	)
	(arc
		(start 357.10876 -230.214678)
		(mid 357.222905 -230.070239)
		(end 357.275638 -229.893876)
		(width 0.1143)
		(layer "In13.Cu")
		(net "GMI_CPU0_G0_CPU1_G2_TX_DN<2>")
	)
	(arc
		(start 357.09606 -223.74225)
		(mid 357.274277 -223.419973)
		(end 357.088694 -223.101916)
		(width 0.1143)
		(layer "In13.Cu")
		(net "GMI_CPU0_G0_CPU1_G2_TX_DN<2>")
	)
	(arc
		(start 357.04907 -227.009706)
		(mid 357.049451 -227.009452)
		(end 357.049832 -227.009198)
		(width 0.1143)
		(layer "In13.Cu")
		(net "GMI_CPU0_G0_CPU1_G2_TX_DN<2>")
	)
	(arc
		(start 357.04907 -231.869488)
		(mid 357.049451 -231.869234)
		(end 357.049832 -231.86898)
		(width 0.1143)
		(layer "In13.Cu")
		(net "GMI_CPU0_G0_CPU1_G2_TX_DN<2>")
	)
	(arc
		(start 356.812088 -238.731298)
		(mid 356.89128 -238.515487)
		(end 357.049832 -238.349028)
		(width 0.1143)
		(layer "In13.Cu")
		(net "GMI_CPU0_G0_CPU1_G2_TX_DN<2>")
	)
	(arc
		(start 114.44605 -233.489246)
		(mid 114.446431 -233.4895)
		(end 114.446812 -233.489754)
		(width 0.1143)
		(layer "In13.Cu")
		(net "GMI_CPU0_G0_CPU1_G2_TX_DN<2>")
	)
	(arc
		(start 114.446812 -233.489754)
		(mid 114.690139 -233.95432)
		(end 114.446812 -234.418886)
		(width 0.1143)
		(layer "In13.Cu")
		(net "GMI_CPU0_G0_CPU1_G2_TX_DN<2>")
	)
	(arc
		(start 357.04907 -235.109512)
		(mid 357.049451 -235.109258)
		(end 357.049832 -235.109004)
		(width 0.1143)
		(layer "In13.Cu")
		(net "GMI_CPU0_G0_CPU1_G2_TX_DN<2>")
	)
	(arc
		(start 357.065834 -223.088708)
		(mid 356.795234 -222.613212)
		(end 357.067612 -222.138748)
		(width 0.1143)
		(layer "In13.Cu")
		(net "GMI_CPU0_G0_CPU1_G2_TX_DN<2>")
	)
	(arc
		(start 357.04907 -231.178862)
		(mid 356.870257 -230.976512)
		(end 356.805738 -230.714296)
		(width 0.1143)
		(layer "In13.Cu")
		(net "GMI_CPU0_G0_CPU1_G2_TX_DN<2>")
	)
	(arc
		(start 114.446812 -228.629972)
		(mid 114.690139 -229.094538)
		(end 114.446812 -229.559104)
		(width 0.1143)
		(layer "In13.Cu")
		(net "GMI_CPU0_G0_CPU1_G2_TX_DN<2>")
	)
	(arc
		(start 114.44605 -231.869234)
		(mid 114.446431 -231.869488)
		(end 114.446812 -231.869742)
		(width 0.1143)
		(layer "In13.Cu")
		(net "GMI_CPU0_G0_CPU1_G2_TX_DN<2>")
	)
	(arc
		(start 114.446812 -236.729778)
		(mid 114.690139 -237.194344)
		(end 114.446812 -237.65891)
		(width 0.1143)
		(layer "In13.Cu")
		(net "GMI_CPU0_G0_CPU1_G2_TX_DN<2>")
	)
	(arc
		(start 357.121206 -229.601014)
		(mid 357.119306 -229.599611)
		(end 357.117396 -229.59822)
		(width 0.1143)
		(layer "In13.Cu")
		(net "GMI_CPU0_G0_CPU1_G2_TX_DN<2>")
	)
	(arc
		(start 114.42827 -222.139002)
		(mid 114.700621 -222.613466)
		(end 114.430048 -223.088962)
		(width 0.1143)
		(layer "In13.Cu")
		(net "GMI_CPU0_G0_CPU1_G2_TX_DN<2>")
	)
	(arc
		(start 357.088694 -238.326676)
		(mid 357.274112 -238.004286)
		(end 357.088694 -237.68177)
		(width 0.1143)
		(layer "In13.Cu")
		(net "GMI_CPU0_G0_CPU1_G2_TX_DN<2>")
	)
	(arc
		(start 114.44605 -223.769428)
		(mid 114.446431 -223.769682)
		(end 114.446812 -223.769936)
		(width 0.1143)
		(layer "In13.Cu")
		(net "GMI_CPU0_G0_CPU1_G2_TX_DN<2>")
	)
	(arc
		(start 114.220244 -229.89413)
		(mid 114.273068 -230.070446)
		(end 114.387122 -230.214932)
		(width 0.1143)
		(layer "In13.Cu")
		(net "GMI_CPU0_G0_CPU1_G2_TX_DN<2>")
	)
	(arc
		(start 114.21999 -221.804484)
		(mid 114.261245 -221.975455)
		(end 114.375946 -222.108776)
		(width 0.1143)
		(layer "In13.Cu")
		(net "GMI_CPU0_G0_CPU1_G2_TX_DN<2>")
	)
	(segment
		(start 114.597942 -240.700306)
		(end 115.064794 -240.434368)
		(width 0.12954)
		(layer "F.Cu")
		(net "GMI_CPU0_G0_CPU1_G2_TX_DN<1>")
	)
	(segment
		(start 356.89794 -240.700052)
		(end 356.431088 -240.434114)
		(width 0.12954)
		(layer "F.Cu")
		(net "GMI_CPU0_G0_CPU1_G2_TX_DN<1>")
	)
	(segment
		(start 113.437162 -233.449114)
		(end 113.467642 -233.466894)
		(width 0.1143)
		(layer "In13.Cu")
		(net "GMI_CPU0_G0_CPU1_G2_TX_DN<1>")
	)
	(segment
		(start 113.467642 -233.466894)
		(end 113.506758 -233.489754)
		(width 0.1143)
		(layer "In13.Cu")
		(net "GMI_CPU0_G0_CPU1_G2_TX_DN<1>")
	)
	(segment
		(start 357.989124 -238.349536)
		(end 358.05872 -238.308896)
		(width 0.1143)
		(layer "In13.Cu")
		(net "GMI_CPU0_G0_CPU1_G2_TX_DN<1>")
	)
	(segment
		(start 358.238552 -221.093538)
		(end 358.238552 -216.822274)
		(width 0.14224)
		(layer "In13.Cu")
		(net "GMI_CPU0_G0_CPU1_G2_TX_DN<1>")
	)
	(segment
		(start 355.797358 -212.711284)
		(end 355.619812 -212.665818)
		(width 0.14224)
		(layer "In13.Cu")
		(net "GMI_CPU0_G0_CPU1_G2_TX_DN<1>")
	)
	(segment
		(start 113.813336 -215.75395)
		(end 113.85931 -215.931242)
		(width 0.14224)
		(layer "In13.Cu")
		(net "GMI_CPU0_G0_CPU1_G2_TX_DN<1>")
	)
	(segment
		(start 356.526338 -214.192612)
		(end 356.57155 -214.015066)
		(width 0.14224)
		(layer "In13.Cu")
		(net "GMI_CPU0_G0_CPU1_G2_TX_DN<1>")
	)
	(segment
		(start 355.40569 -212.305138)
		(end 355.451156 -212.127846)
		(width 0.14224)
		(layer "In13.Cu")
		(net "GMI_CPU0_G0_CPU1_G2_TX_DN<1>")
	)
	(segment
		(start 357.30053 -215.496902)
		(end 357.086662 -215.136222)
		(width 0.14224)
		(layer "In13.Cu")
		(net "GMI_CPU0_G0_CPU1_G2_TX_DN<1>")
	)
	(segment
		(start 113.44656 -231.834436)
		(end 113.505234 -231.868726)
		(width 0.1143)
		(layer "In13.Cu")
		(net "GMI_CPU0_G0_CPU1_G2_TX_DN<1>")
	)
	(segment
		(start 356.57155 -214.015066)
		(end 356.357682 -213.654894)
		(width 0.14224)
		(layer "In13.Cu")
		(net "GMI_CPU0_G0_CPU1_G2_TX_DN<1>")
	)
	(segment
		(start 113.467642 -235.086906)
		(end 113.506758 -235.109766)
		(width 0.1143)
		(layer "In13.Cu")
		(net "GMI_CPU0_G0_CPU1_G2_TX_DN<1>")
	)
	(segment
		(start 113.25733 -221.071948)
		(end 113.25733 -221.100396)
		(width 0.1143)
		(layer "In13.Cu")
		(net "GMI_CPU0_G0_CPU1_G2_TX_DN<1>")
	)
	(segment
		(start 358.05872 -224.739454)
		(end 357.989124 -224.698814)
		(width 0.1143)
		(layer "In13.Cu")
		(net "GMI_CPU0_G0_CPU1_G2_TX_DN<1>")
	)
	(segment
		(start 358.238552 -221.100142)
		(end 358.238552 -221.093538)
		(width 0.1143)
		(layer "In13.Cu")
		(net "GMI_CPU0_G0_CPU1_G2_TX_DN<1>")
	)
	(segment
		(start 357.086662 -215.136222)
		(end 357.131874 -214.958676)
		(width 0.14224)
		(layer "In13.Cu")
		(net "GMI_CPU0_G0_CPU1_G2_TX_DN<1>")
	)
	(segment
		(start 356.179882 -213.609428)
		(end 355.966014 -213.249002)
		(width 0.14224)
		(layer "In13.Cu")
		(net "GMI_CPU0_G0_CPU1_G2_TX_DN<1>")
	)
	(segment
		(start 358.05872 -236.079284)
		(end 357.989124 -236.038644)
		(width 0.1143)
		(layer "In13.Cu")
		(net "GMI_CPU0_G0_CPU1_G2_TX_DN<1>")
	)
	(segment
		(start 113.506758 -237.65891)
		(end 113.467642 -237.68177)
		(width 0.1143)
		(layer "In13.Cu")
		(net "GMI_CPU0_G0_CPU1_G2_TX_DN<1>")
	)
	(segment
		(start 114.684048 -240.351564)
		(end 114.766852 -240.434368)
		(width 0.1143)
		(layer "In13.Cu")
		(net "GMI_CPU0_G0_CPU1_G2_TX_DN<1>")
	)
	(segment
		(start 355.966014 -213.249002)
		(end 356.011226 -213.071456)
		(width 0.14224)
		(layer "In13.Cu")
		(net "GMI_CPU0_G0_CPU1_G2_TX_DN<1>")
	)
	(segment
		(start 114.766852 -240.434368)
		(end 115.064794 -240.434368)
		(width 0.1143)
		(layer "In13.Cu")
		(net "GMI_CPU0_G0_CPU1_G2_TX_DN<1>")
	)
	(segment
		(start 113.446052 -231.834436)
		(end 113.44656 -231.834436)
		(width 0.1143)
		(layer "In13.Cu")
		(net "GMI_CPU0_G0_CPU1_G2_TX_DN<1>")
	)
	(segment
		(start 358.051608 -229.595172)
		(end 357.9876 -229.558088)
		(width 0.1143)
		(layer "In13.Cu")
		(net "GMI_CPU0_G0_CPU1_G2_TX_DN<1>")
	)
	(segment
		(start 114.38509 -239.933734)
		(end 114.446812 -239.969802)
		(width 0.1143)
		(layer "In13.Cu")
		(net "GMI_CPU0_G0_CPU1_G2_TX_DN<1>")
	)
	(segment
		(start 355.451156 -212.127846)
		(end 354.73513 -210.921346)
		(width 0.14224)
		(layer "In13.Cu")
		(net "GMI_CPU0_G0_CPU1_G2_TX_DN<1>")
	)
	(segment
		(start 113.467642 -226.9871)
		(end 113.506758 -227.00996)
		(width 0.1143)
		(layer "In13.Cu")
		(net "GMI_CPU0_G0_CPU1_G2_TX_DN<1>")
	)
	(segment
		(start 114.202972 -215.346534)
		(end 114.025426 -215.392762)
		(width 0.14224)
		(layer "In13.Cu")
		(net "GMI_CPU0_G0_CPU1_G2_TX_DN<1>")
	)
	(segment
		(start 314.628784 -178.89347)
		(end 311.250584 -176.981104)
		(width 0.14224)
		(layer "In13.Cu")
		(net "GMI_CPU0_G0_CPU1_G2_TX_DN<1>")
	)
	(segment
		(start 358.026462 -222.129604)
		(end 358.02951 -222.12808)
		(width 0.1143)
		(layer "In13.Cu")
		(net "GMI_CPU0_G0_CPU1_G2_TX_DN<1>")
	)
	(segment
		(start 357.558848 -239.136174)
		(end 357.560118 -239.135412)
		(width 0.1143)
		(layer "In13.Cu")
		(net "GMI_CPU0_G0_CPU1_G2_TX_DN<1>")
	)
	(segment
		(start 113.437162 -238.30915)
		(end 113.467642 -238.32693)
		(width 0.1143)
		(layer "In13.Cu")
		(net "GMI_CPU0_G0_CPU1_G2_TX_DN<1>")
	)
	(segment
		(start 358.215946 -221.80423)
		(end 358.215946 -221.371414)
		(width 0.1143)
		(layer "In13.Cu")
		(net "GMI_CPU0_G0_CPU1_G2_TX_DN<1>")
	)
	(segment
		(start 113.4999 -231.182926)
		(end 113.447322 -231.21366)
		(width 0.1143)
		(layer "In13.Cu")
		(net "GMI_CPU0_G0_CPU1_G2_TX_DN<1>")
	)
	(segment
		(start 358.05872 -226.359466)
		(end 357.989124 -226.318826)
		(width 0.1143)
		(layer "In13.Cu")
		(net "GMI_CPU0_G0_CPU1_G2_TX_DN<1>")
	)
	(segment
		(start 357.989124 -233.4895)
		(end 358.05872 -233.44886)
		(width 0.1143)
		(layer "In13.Cu")
		(net "GMI_CPU0_G0_CPU1_G2_TX_DN<1>")
	)
	(segment
		(start 113.508282 -229.558342)
		(end 113.444274 -229.595426)
		(width 0.1143)
		(layer "In13.Cu")
		(net "GMI_CPU0_G0_CPU1_G2_TX_DN<1>")
	)
	(segment
		(start 113.447322 -231.21366)
		(end 113.44656 -231.214168)
		(width 0.1143)
		(layer "In13.Cu")
		(net "GMI_CPU0_G0_CPU1_G2_TX_DN<1>")
	)
	(segment
		(start 113.467642 -227.961952)
		(end 113.437162 -227.979732)
		(width 0.1143)
		(layer "In13.Cu")
		(net "GMI_CPU0_G0_CPU1_G2_TX_DN<1>")
	)
	(segment
		(start 357.692198 -215.902286)
		(end 357.47833 -215.542114)
		(width 0.14224)
		(layer "In13.Cu")
		(net "GMI_CPU0_G0_CPU1_G2_TX_DN<1>")
	)
	(segment
		(start 113.505234 -223.080072)
		(end 113.437162 -223.119696)
		(width 0.1143)
		(layer "In13.Cu")
		(net "GMI_CPU0_G0_CPU1_G2_TX_DN<1>")
	)
	(segment
		(start 156.513276 -178.269138)
		(end 116.614956 -210.984338)
		(width 0.14224)
		(layer "In13.Cu")
		(net "GMI_CPU0_G0_CPU1_G2_TX_DN<1>")
	)
	(segment
		(start 355.619812 -212.665818)
		(end 355.40569 -212.305138)
		(width 0.14224)
		(layer "In13.Cu")
		(net "GMI_CPU0_G0_CPU1_G2_TX_DN<1>")
	)
	(segment
		(start 113.46942 -216.338912)
		(end 113.469674 -216.338912)
		(width 0.14224)
		(layer "In13.Cu")
		(net "GMI_CPU0_G0_CPU1_G2_TX_DN<1>")
	)
	(segment
		(start 113.506758 -234.418886)
		(end 113.467642 -234.441746)
		(width 0.1143)
		(layer "In13.Cu")
		(net "GMI_CPU0_G0_CPU1_G2_TX_DN<1>")
	)
	(segment
		(start 357.564182 -239.133126)
		(end 357.589836 -239.118394)
		(width 0.1143)
		(layer "In13.Cu")
		(net "GMI_CPU0_G0_CPU1_G2_TX_DN<1>")
	)
	(segment
		(start 356.011226 -213.071456)
		(end 355.797358 -212.711284)
		(width 0.14224)
		(layer "In13.Cu")
		(net "GMI_CPU0_G0_CPU1_G2_TX_DN<1>")
	)
	(segment
		(start 113.25733 -216.700354)
		(end 113.25733 -221.071948)
		(width 0.14224)
		(layer "In13.Cu")
		(net "GMI_CPU0_G0_CPU1_G2_TX_DN<1>")
	)
	(segment
		(start 113.437162 -236.689138)
		(end 113.467642 -236.706918)
		(width 0.1143)
		(layer "In13.Cu")
		(net "GMI_CPU0_G0_CPU1_G2_TX_DN<1>")
	)
	(segment
		(start 116.614956 -210.984338)
		(end 114.92484 -213.86165)
		(width 0.14224)
		(layer "In13.Cu")
		(net "GMI_CPU0_G0_CPU1_G2_TX_DN<1>")
	)
	(segment
		(start 357.989124 -236.729524)
		(end 358.05872 -236.688884)
		(width 0.1143)
		(layer "In13.Cu")
		(net "GMI_CPU0_G0_CPU1_G2_TX_DN<1>")
	)
	(segment
		(start 356.431088 -240.434114)
		(end 356.72903 -240.434114)
		(width 0.1143)
		(layer "In13.Cu")
		(net "GMI_CPU0_G0_CPU1_G2_TX_DN<1>")
	)
	(segment
		(start 113.506758 -226.31908)
		(end 113.467642 -226.34194)
		(width 0.1143)
		(layer "In13.Cu")
		(net "GMI_CPU0_G0_CPU1_G2_TX_DN<1>")
	)
	(segment
		(start 357.989124 -223.769682)
		(end 358.05872 -223.729042)
		(width 0.1143)
		(layer "In13.Cu")
		(net "GMI_CPU0_G0_CPU1_G2_TX_DN<1>")
	)
	(segment
		(start 358.05872 -227.979478)
		(end 357.989124 -227.938838)
		(width 0.1143)
		(layer "In13.Cu")
		(net "GMI_CPU0_G0_CPU1_G2_TX_DN<1>")
	)
	(segment
		(start 356.357682 -213.654894)
		(end 356.179882 -213.609428)
		(width 0.14224)
		(layer "In13.Cu")
		(net "GMI_CPU0_G0_CPU1_G2_TX_DN<1>")
	)
	(segment
		(start 308.57063 -176.022762)
		(end 302.916336 -176.022762)
		(width 0.14224)
		(layer "In13.Cu")
		(net "GMI_CPU0_G0_CPU1_G2_TX_DN<1>")
	)
	(segment
		(start 358.215946 -221.371414)
		(end 358.284272 -221.303088)
		(width 0.1143)
		(layer "In13.Cu")
		(net "GMI_CPU0_G0_CPU1_G2_TX_DN<1>")
	)
	(segment
		(start 356.740206 -214.553038)
		(end 356.526338 -214.192612)
		(width 0.14224)
		(layer "In13.Cu")
		(net "GMI_CPU0_G0_CPU1_G2_TX_DN<1>")
	)
	(segment
		(start 113.21161 -221.303342)
		(end 113.279936 -221.371668)
		(width 0.1143)
		(layer "In13.Cu")
		(net "GMI_CPU0_G0_CPU1_G2_TX_DN<1>")
	)
	(segment
		(start 113.467642 -236.061758)
		(end 113.437162 -236.079538)
		(width 0.1143)
		(layer "In13.Cu")
		(net "GMI_CPU0_G0_CPU1_G2_TX_DN<1>")
	)
	(segment
		(start 113.85931 -215.931242)
		(end 113.646966 -216.292684)
		(width 0.14224)
		(layer "In13.Cu")
		(net "GMI_CPU0_G0_CPU1_G2_TX_DN<1>")
	)
	(segment
		(start 113.467642 -237.68177)
		(end 113.437162 -237.69955)
		(width 0.1143)
		(layer "In13.Cu")
		(net "GMI_CPU0_G0_CPU1_G2_TX_DN<1>")
	)
	(segment
		(start 113.25733 -221.100396)
		(end 113.21161 -221.146116)
		(width 0.1143)
		(layer "In13.Cu")
		(net "GMI_CPU0_G0_CPU1_G2_TX_DN<1>")
	)
	(segment
		(start 311.250584 -176.981104)
		(end 308.57063 -176.022762)
		(width 0.14224)
		(layer "In13.Cu")
		(net "GMI_CPU0_G0_CPU1_G2_TX_DN<1>")
	)
	(segment
		(start 357.558086 -239.136682)
		(end 357.558848 -239.136174)
		(width 0.1143)
		(layer "In13.Cu")
		(net "GMI_CPU0_G0_CPU1_G2_TX_DN<1>")
	)
	(segment
		(start 113.467642 -225.367088)
		(end 113.506758 -225.389948)
		(width 0.1143)
		(layer "In13.Cu")
		(net "GMI_CPU0_G0_CPU1_G2_TX_DN<1>")
	)
	(segment
		(start 357.989124 -235.109512)
		(end 358.05872 -235.068872)
		(width 0.1143)
		(layer "In13.Cu")
		(net "GMI_CPU0_G0_CPU1_G2_TX_DN<1>")
	)
	(segment
		(start 114.369088 -214.8078)
		(end 114.415316 -214.985092)
		(width 0.14224)
		(layer "In13.Cu")
		(net "GMI_CPU0_G0_CPU1_G2_TX_DN<1>")
	)
	(segment
		(start 358.05872 -234.459272)
		(end 357.989124 -234.418632)
		(width 0.1143)
		(layer "In13.Cu")
		(net "GMI_CPU0_G0_CPU1_G2_TX_DN<1>")
	)
	(segment
		(start 356.918006 -214.598504)
		(end 356.740206 -214.553038)
		(width 0.14224)
		(layer "In13.Cu")
		(net "GMI_CPU0_G0_CPU1_G2_TX_DN<1>")
	)
	(segment
		(start 357.989124 -225.389694)
		(end 358.05872 -225.349054)
		(width 0.1143)
		(layer "In13.Cu")
		(net "GMI_CPU0_G0_CPU1_G2_TX_DN<1>")
	)
	(segment
		(start 113.467642 -234.441746)
		(end 113.437162 -234.459526)
		(width 0.1143)
		(layer "In13.Cu")
		(net "GMI_CPU0_G0_CPU1_G2_TX_DN<1>")
	)
	(segment
		(start 302.916336 -176.022762)
		(end 165.0492 -175.21682)
		(width 0.14224)
		(layer "In13.Cu")
		(net "GMI_CPU0_G0_CPU1_G2_TX_DN<1>")
	)
	(segment
		(start 113.467642 -223.747076)
		(end 113.506758 -223.769936)
		(width 0.1143)
		(layer "In13.Cu")
		(net "GMI_CPU0_G0_CPU1_G2_TX_DN<1>")
	)
	(segment
		(start 113.506758 -231.179116)
		(end 113.4999 -231.182926)
		(width 0.1143)
		(layer "In13.Cu")
		(net "GMI_CPU0_G0_CPU1_G2_TX_DN<1>")
	)
	(segment
		(start 113.44656 -231.214168)
		(end 113.446306 -231.214168)
		(width 0.1143)
		(layer "In13.Cu")
		(net "GMI_CPU0_G0_CPU1_G2_TX_DN<1>")
	)
	(segment
		(start 113.469674 -216.338912)
		(end 113.25733 -216.700354)
		(width 0.14224)
		(layer "In13.Cu")
		(net "GMI_CPU0_G0_CPU1_G2_TX_DN<1>")
	)
	(segment
		(start 114.025426 -215.392762)
		(end 113.813336 -215.75395)
		(width 0.14224)
		(layer "In13.Cu")
		(net "GMI_CPU0_G0_CPU1_G2_TX_DN<1>")
	)
	(segment
		(start 113.467642 -238.32693)
		(end 113.506758 -238.34979)
		(width 0.1143)
		(layer "In13.Cu")
		(net "GMI_CPU0_G0_CPU1_G2_TX_DN<1>")
	)
	(segment
		(start 358.049576 -231.213914)
		(end 358.049322 -231.213914)
		(width 0.1143)
		(layer "In13.Cu")
		(net "GMI_CPU0_G0_CPU1_G2_TX_DN<1>")
	)
	(segment
		(start 113.437162 -223.729296)
		(end 113.467642 -223.747076)
		(width 0.1143)
		(layer "In13.Cu")
		(net "GMI_CPU0_G0_CPU1_G2_TX_DN<1>")
	)
	(segment
		(start 113.506758 -227.939092)
		(end 113.467642 -227.961952)
		(width 0.1143)
		(layer "In13.Cu")
		(net "GMI_CPU0_G0_CPU1_G2_TX_DN<1>")
	)
	(segment
		(start 113.437162 -225.349308)
		(end 113.467642 -225.367088)
		(width 0.1143)
		(layer "In13.Cu")
		(net "GMI_CPU0_G0_CPU1_G2_TX_DN<1>")
	)
	(segment
		(start 358.238552 -216.822274)
		(end 358.038654 -216.485724)
		(width 0.14224)
		(layer "In13.Cu")
		(net "GMI_CPU0_G0_CPU1_G2_TX_DN<1>")
	)
	(segment
		(start 114.581178 -214.446612)
		(end 114.369088 -214.8078)
		(width 0.14224)
		(layer "In13.Cu")
		(net "GMI_CPU0_G0_CPU1_G2_TX_DN<1>")
	)
	(segment
		(start 113.467642 -228.607112)
		(end 113.506758 -228.629972)
		(width 0.1143)
		(layer "In13.Cu")
		(net "GMI_CPU0_G0_CPU1_G2_TX_DN<1>")
	)
	(segment
		(start 113.467642 -224.721928)
		(end 113.437162 -224.739708)
		(width 0.1143)
		(layer "In13.Cu")
		(net "GMI_CPU0_G0_CPU1_G2_TX_DN<1>")
	)
	(segment
		(start 358.038654 -216.485724)
		(end 357.860854 -216.440512)
		(width 0.14224)
		(layer "In13.Cu")
		(net "GMI_CPU0_G0_CPU1_G2_TX_DN<1>")
	)
	(segment
		(start 357.991664 -230.247952)
		(end 358.05872 -230.208836)
		(width 0.1143)
		(layer "In13.Cu")
		(net "GMI_CPU0_G0_CPU1_G2_TX_DN<1>")
	)
	(segment
		(start 357.562404 -239.134142)
		(end 357.56342 -239.133634)
		(width 0.1143)
		(layer "In13.Cu")
		(net "GMI_CPU0_G0_CPU1_G2_TX_DN<1>")
	)
	(segment
		(start 114.92484 -213.86165)
		(end 114.971068 -214.038942)
		(width 0.14224)
		(layer "In13.Cu")
		(net "GMI_CPU0_G0_CPU1_G2_TX_DN<1>")
	)
	(segment
		(start 357.990648 -231.868472)
		(end 358.049322 -231.834182)
		(width 0.1143)
		(layer "In13.Cu")
		(net "GMI_CPU0_G0_CPU1_G2_TX_DN<1>")
	)
	(segment
		(start 357.47833 -215.542114)
		(end 357.30053 -215.496902)
		(width 0.14224)
		(layer "In13.Cu")
		(net "GMI_CPU0_G0_CPU1_G2_TX_DN<1>")
	)
	(segment
		(start 358.05872 -223.119442)
		(end 357.990648 -223.079818)
		(width 0.1143)
		(layer "In13.Cu")
		(net "GMI_CPU0_G0_CPU1_G2_TX_DN<1>")
	)
	(segment
		(start 358.05872 -232.83926)
		(end 357.989124 -232.79862)
		(width 0.1143)
		(layer "In13.Cu")
		(net "GMI_CPU0_G0_CPU1_G2_TX_DN<1>")
	)
	(segment
		(start 113.21161 -221.146116)
		(end 113.21161 -221.303342)
		(width 0.1143)
		(layer "In13.Cu")
		(net "GMI_CPU0_G0_CPU1_G2_TX_DN<1>")
	)
	(segment
		(start 357.860854 -216.440512)
		(end 357.646986 -216.079832)
		(width 0.14224)
		(layer "In13.Cu")
		(net "GMI_CPU0_G0_CPU1_G2_TX_DN<1>")
	)
	(segment
		(start 113.467642 -236.706918)
		(end 113.506758 -236.729778)
		(width 0.1143)
		(layer "In13.Cu")
		(net "GMI_CPU0_G0_CPU1_G2_TX_DN<1>")
	)
	(segment
		(start 357.519986 -239.15878)
		(end 357.558086 -239.136682)
		(width 0.1143)
		(layer "In13.Cu")
		(net "GMI_CPU0_G0_CPU1_G2_TX_DN<1>")
	)
	(segment
		(start 113.437162 -226.96932)
		(end 113.467642 -226.9871)
		(width 0.1143)
		(layer "In13.Cu")
		(net "GMI_CPU0_G0_CPU1_G2_TX_DN<1>")
	)
	(segment
		(start 358.04856 -231.213406)
		(end 357.995982 -231.182672)
		(width 0.1143)
		(layer "In13.Cu")
		(net "GMI_CPU0_G0_CPU1_G2_TX_DN<1>")
	)
	(segment
		(start 114.415316 -214.985092)
		(end 114.202972 -215.346534)
		(width 0.14224)
		(layer "In13.Cu")
		(net "GMI_CPU0_G0_CPU1_G2_TX_DN<1>")
	)
	(segment
		(start 114.758724 -214.400384)
		(end 114.581178 -214.446612)
		(width 0.14224)
		(layer "In13.Cu")
		(net "GMI_CPU0_G0_CPU1_G2_TX_DN<1>")
	)
	(segment
		(start 113.937034 -239.136428)
		(end 113.937796 -239.136936)
		(width 0.1143)
		(layer "In13.Cu")
		(net "GMI_CPU0_G0_CPU1_G2_TX_DN<1>")
	)
	(segment
		(start 356.72903 -240.434114)
		(end 356.811834 -240.35131)
		(width 0.1143)
		(layer "In13.Cu")
		(net "GMI_CPU0_G0_CPU1_G2_TX_DN<1>")
	)
	(segment
		(start 113.437162 -230.20909)
		(end 113.504218 -230.248206)
		(width 0.1143)
		(layer "In13.Cu")
		(net "GMI_CPU0_G0_CPU1_G2_TX_DN<1>")
	)
	(segment
		(start 357.56342 -239.133634)
		(end 357.564182 -239.133126)
		(width 0.1143)
		(layer "In13.Cu")
		(net "GMI_CPU0_G0_CPU1_G2_TX_DN<1>")
	)
	(segment
		(start 113.937796 -239.136936)
		(end 113.975896 -239.159034)
		(width 0.1143)
		(layer "In13.Cu")
		(net "GMI_CPU0_G0_CPU1_G2_TX_DN<1>")
	)
	(segment
		(start 358.05872 -237.699296)
		(end 357.989124 -237.658656)
		(width 0.1143)
		(layer "In13.Cu")
		(net "GMI_CPU0_G0_CPU1_G2_TX_DN<1>")
	)
	(segment
		(start 113.506758 -236.038898)
		(end 113.467642 -236.061758)
		(width 0.1143)
		(layer "In13.Cu")
		(net "GMI_CPU0_G0_CPU1_G2_TX_DN<1>")
	)
	(segment
		(start 113.467642 -226.34194)
		(end 113.437162 -226.35972)
		(width 0.1143)
		(layer "In13.Cu")
		(net "GMI_CPU0_G0_CPU1_G2_TX_DN<1>")
	)
	(segment
		(start 114.971068 -214.038942)
		(end 114.758724 -214.400384)
		(width 0.14224)
		(layer "In13.Cu")
		(net "GMI_CPU0_G0_CPU1_G2_TX_DN<1>")
	)
	(segment
		(start 113.467642 -232.821734)
		(end 113.437162 -232.839514)
		(width 0.1143)
		(layer "In13.Cu")
		(net "GMI_CPU0_G0_CPU1_G2_TX_DN<1>")
	)
	(segment
		(start 357.131874 -214.958676)
		(end 356.918006 -214.598504)
		(width 0.14224)
		(layer "In13.Cu")
		(net "GMI_CPU0_G0_CPU1_G2_TX_DN<1>")
	)
	(segment
		(start 113.466372 -222.128334)
		(end 113.46942 -222.129858)
		(width 0.1143)
		(layer "In13.Cu")
		(net "GMI_CPU0_G0_CPU1_G2_TX_DN<1>")
	)
	(segment
		(start 357.989124 -227.009706)
		(end 358.05872 -226.969066)
		(width 0.1143)
		(layer "In13.Cu")
		(net "GMI_CPU0_G0_CPU1_G2_TX_DN<1>")
	)
	(segment
		(start 113.279936 -221.371668)
		(end 113.279936 -221.804484)
		(width 0.1143)
		(layer "In13.Cu")
		(net "GMI_CPU0_G0_CPU1_G2_TX_DN<1>")
	)
	(segment
		(start 113.506758 -224.699068)
		(end 113.467642 -224.721928)
		(width 0.1143)
		(layer "In13.Cu")
		(net "GMI_CPU0_G0_CPU1_G2_TX_DN<1>")
	)
	(segment
		(start 357.04907 -239.969548)
		(end 357.110792 -239.93348)
		(width 0.1143)
		(layer "In13.Cu")
		(net "GMI_CPU0_G0_CPU1_G2_TX_DN<1>")
	)
	(segment
		(start 358.284272 -221.303088)
		(end 358.284272 -221.145862)
		(width 0.1143)
		(layer "In13.Cu")
		(net "GMI_CPU0_G0_CPU1_G2_TX_DN<1>")
	)
	(segment
		(start 113.906046 -239.118648)
		(end 113.937034 -239.136428)
		(width 0.1143)
		(layer "In13.Cu")
		(net "GMI_CPU0_G0_CPU1_G2_TX_DN<1>")
	)
	(segment
		(start 113.506758 -232.798874)
		(end 113.467642 -232.821734)
		(width 0.1143)
		(layer "In13.Cu")
		(net "GMI_CPU0_G0_CPU1_G2_TX_DN<1>")
	)
	(segment
		(start 357.561642 -239.13465)
		(end 357.562404 -239.134142)
		(width 0.1143)
		(layer "In13.Cu")
		(net "GMI_CPU0_G0_CPU1_G2_TX_DN<1>")
	)
	(segment
		(start 113.437162 -228.589332)
		(end 113.467642 -228.607112)
		(width 0.1143)
		(layer "In13.Cu")
		(net "GMI_CPU0_G0_CPU1_G2_TX_DN<1>")
	)
	(segment
		(start 113.437162 -235.069126)
		(end 113.467642 -235.086906)
		(width 0.1143)
		(layer "In13.Cu")
		(net "GMI_CPU0_G0_CPU1_G2_TX_DN<1>")
	)
	(segment
		(start 113.646966 -216.292684)
		(end 113.46942 -216.338912)
		(width 0.14224)
		(layer "In13.Cu")
		(net "GMI_CPU0_G0_CPU1_G2_TX_DN<1>")
	)
	(segment
		(start 357.989124 -228.629718)
		(end 358.05872 -228.589078)
		(width 0.1143)
		(layer "In13.Cu")
		(net "GMI_CPU0_G0_CPU1_G2_TX_DN<1>")
	)
	(segment
		(start 358.284272 -221.145862)
		(end 358.238552 -221.100142)
		(width 0.1143)
		(layer "In13.Cu")
		(net "GMI_CPU0_G0_CPU1_G2_TX_DN<1>")
	)
	(segment
		(start 318.00673 -180.805582)
		(end 314.628784 -178.89347)
		(width 0.14224)
		(layer "In13.Cu")
		(net "GMI_CPU0_G0_CPU1_G2_TX_DN<1>")
	)
	(segment
		(start 358.049322 -231.834182)
		(end 358.04983 -231.834182)
		(width 0.1143)
		(layer "In13.Cu")
		(net "GMI_CPU0_G0_CPU1_G2_TX_DN<1>")
	)
	(segment
		(start 357.646986 -216.079832)
		(end 357.692198 -215.902286)
		(width 0.14224)
		(layer "In13.Cu")
		(net "GMI_CPU0_G0_CPU1_G2_TX_DN<1>")
	)
	(segment
		(start 357.995982 -231.182672)
		(end 357.989124 -231.178862)
		(width 0.1143)
		(layer "In13.Cu")
		(net "GMI_CPU0_G0_CPU1_G2_TX_DN<1>")
	)
	(segment
		(start 165.0492 -175.21682)
		(end 156.513276 -178.269138)
		(width 0.14224)
		(layer "In13.Cu")
		(net "GMI_CPU0_G0_CPU1_G2_TX_DN<1>")
	)
	(segment
		(start 354.73513 -210.921346)
		(end 318.00673 -180.805582)
		(width 0.14224)
		(layer "In13.Cu")
		(net "GMI_CPU0_G0_CPU1_G2_TX_DN<1>")
	)
	(segment
		(start 358.049322 -231.213914)
		(end 358.04856 -231.213406)
		(width 0.1143)
		(layer "In13.Cu")
		(net "GMI_CPU0_G0_CPU1_G2_TX_DN<1>")
	)
	(segment
		(start 357.560118 -239.135412)
		(end 357.561642 -239.13465)
		(width 0.1143)
		(layer "In13.Cu")
		(net "GMI_CPU0_G0_CPU1_G2_TX_DN<1>")
	)
	(arc
		(start 357.989124 -237.658656)
		(mid 357.745797 -237.19409)
		(end 357.989124 -236.729524)
		(width 0.1143)
		(layer "In13.Cu")
		(net "GMI_CPU0_G0_CPU1_G2_TX_DN<1>")
	)
	(arc
		(start 358.05872 -233.44886)
		(mid 358.215697 -233.14406)
		(end 358.05872 -232.83926)
		(width 0.1143)
		(layer "In13.Cu")
		(net "GMI_CPU0_G0_CPU1_G2_TX_DN<1>")
	)
	(arc
		(start 113.446306 -231.214168)
		(mid 113.267764 -231.524192)
		(end 113.446052 -231.834436)
		(width 0.1143)
		(layer "In13.Cu")
		(net "GMI_CPU0_G0_CPU1_G2_TX_DN<1>")
	)
	(arc
		(start 356.815644 -240.32845)
		(mid 356.897077 -240.126052)
		(end 357.04907 -239.969548)
		(width 0.1143)
		(layer "In13.Cu")
		(net "GMI_CPU0_G0_CPU1_G2_TX_DN<1>")
	)
	(arc
		(start 113.975896 -239.159034)
		(mid 114.150832 -239.352708)
		(end 114.220244 -239.604296)
		(width 0.1143)
		(layer "In13.Cu")
		(net "GMI_CPU0_G0_CPU1_G2_TX_DN<1>")
	)
	(arc
		(start 113.506758 -223.769936)
		(mid 113.750085 -224.234502)
		(end 113.506758 -224.699068)
		(width 0.1143)
		(layer "In13.Cu")
		(net "GMI_CPU0_G0_CPU1_G2_TX_DN<1>")
	)
	(arc
		(start 358.05872 -225.349054)
		(mid 358.215697 -225.044254)
		(end 358.05872 -224.739454)
		(width 0.1143)
		(layer "In13.Cu")
		(net "GMI_CPU0_G0_CPU1_G2_TX_DN<1>")
	)
	(arc
		(start 358.05872 -230.208836)
		(mid 358.171849 -230.07985)
		(end 358.215438 -229.913942)
		(width 0.1143)
		(layer "In13.Cu")
		(net "GMI_CPU0_G0_CPU1_G2_TX_DN<1>")
	)
	(arc
		(start 357.9876 -229.558088)
		(mid 357.809951 -229.355796)
		(end 357.746046 -229.094284)
		(width 0.1143)
		(layer "In13.Cu")
		(net "GMI_CPU0_G0_CPU1_G2_TX_DN<1>")
	)
	(arc
		(start 113.437162 -234.459526)
		(mid 113.280185 -234.764326)
		(end 113.437162 -235.069126)
		(width 0.1143)
		(layer "In13.Cu")
		(net "GMI_CPU0_G0_CPU1_G2_TX_DN<1>")
	)
	(arc
		(start 357.273606 -239.63376)
		(mid 357.275077 -239.618932)
		(end 357.275638 -239.604042)
		(width 0.1143)
		(layer "In13.Cu")
		(net "GMI_CPU0_G0_CPU1_G2_TX_DN<1>")
	)
	(arc
		(start 113.75009 -230.71455)
		(mid 113.685575 -230.976769)
		(end 113.506758 -231.179116)
		(width 0.1143)
		(layer "In13.Cu")
		(net "GMI_CPU0_G0_CPU1_G2_TX_DN<1>")
	)
	(arc
		(start 113.437162 -227.979732)
		(mid 113.280185 -228.284532)
		(end 113.437162 -228.589332)
		(width 0.1143)
		(layer "In13.Cu")
		(net "GMI_CPU0_G0_CPU1_G2_TX_DN<1>")
	)
	(arc
		(start 358.05872 -228.589078)
		(mid 358.215697 -228.284278)
		(end 358.05872 -227.979478)
		(width 0.1143)
		(layer "In13.Cu")
		(net "GMI_CPU0_G0_CPU1_G2_TX_DN<1>")
	)
	(arc
		(start 358.05872 -235.068872)
		(mid 358.215697 -234.764072)
		(end 358.05872 -234.459272)
		(width 0.1143)
		(layer "In13.Cu")
		(net "GMI_CPU0_G0_CPU1_G2_TX_DN<1>")
	)
	(arc
		(start 113.506758 -231.869742)
		(mid 113.750085 -232.334308)
		(end 113.506758 -232.798874)
		(width 0.1143)
		(layer "In13.Cu")
		(net "GMI_CPU0_G0_CPU1_G2_TX_DN<1>")
	)
	(arc
		(start 357.989124 -234.418632)
		(mid 357.745797 -233.954066)
		(end 357.989124 -233.4895)
		(width 0.1143)
		(layer "In13.Cu")
		(net "GMI_CPU0_G0_CPU1_G2_TX_DN<1>")
	)
	(arc
		(start 114.680238 -240.328704)
		(mid 114.682261 -240.340114)
		(end 114.684048 -240.351564)
		(width 0.1143)
		(layer "In13.Cu")
		(net "GMI_CPU0_G0_CPU1_G2_TX_DN<1>")
	)
	(arc
		(start 357.990648 -223.079818)
		(mid 357.810856 -222.87723)
		(end 357.746046 -222.614236)
		(width 0.1143)
		(layer "In13.Cu")
		(net "GMI_CPU0_G0_CPU1_G2_TX_DN<1>")
	)
	(arc
		(start 357.989124 -236.038644)
		(mid 357.745797 -235.574078)
		(end 357.989124 -235.109512)
		(width 0.1143)
		(layer "In13.Cu")
		(net "GMI_CPU0_G0_CPU1_G2_TX_DN<1>")
	)
	(arc
		(start 357.745792 -238.814102)
		(mid 357.810307 -238.551883)
		(end 357.989124 -238.349536)
		(width 0.1143)
		(layer "In13.Cu")
		(net "GMI_CPU0_G0_CPU1_G2_TX_DN<1>")
	)
	(arc
		(start 113.749836 -229.094538)
		(mid 113.685872 -229.356019)
		(end 113.508282 -229.558342)
		(width 0.1143)
		(layer "In13.Cu")
		(net "GMI_CPU0_G0_CPU1_G2_TX_DN<1>")
	)
	(arc
		(start 113.279936 -221.804484)
		(mid 113.329883 -221.991313)
		(end 113.466372 -222.128334)
		(width 0.1143)
		(layer "In13.Cu")
		(net "GMI_CPU0_G0_CPU1_G2_TX_DN<1>")
	)
	(arc
		(start 358.02951 -222.12808)
		(mid 358.16604 -221.991082)
		(end 358.215946 -221.80423)
		(width 0.1143)
		(layer "In13.Cu")
		(net "GMI_CPU0_G0_CPU1_G2_TX_DN<1>")
	)
	(arc
		(start 113.506758 -235.109766)
		(mid 113.750085 -235.574332)
		(end 113.506758 -236.038898)
		(width 0.1143)
		(layer "In13.Cu")
		(net "GMI_CPU0_G0_CPU1_G2_TX_DN<1>")
	)
	(arc
		(start 113.505234 -231.868726)
		(mid 113.505996 -231.869233)
		(end 113.506758 -231.869742)
		(width 0.1143)
		(layer "In13.Cu")
		(net "GMI_CPU0_G0_CPU1_G2_TX_DN<1>")
	)
	(arc
		(start 113.504218 -230.248206)
		(mid 113.68487 -230.450951)
		(end 113.75009 -230.71455)
		(width 0.1143)
		(layer "In13.Cu")
		(net "GMI_CPU0_G0_CPU1_G2_TX_DN<1>")
	)
	(arc
		(start 113.75009 -238.814356)
		(mid 113.791345 -238.985327)
		(end 113.906046 -239.118648)
		(width 0.1143)
		(layer "In13.Cu")
		(net "GMI_CPU0_G0_CPU1_G2_TX_DN<1>")
	)
	(arc
		(start 358.04983 -231.834182)
		(mid 358.228246 -231.523938)
		(end 358.049576 -231.213914)
		(width 0.1143)
		(layer "In13.Cu")
		(net "GMI_CPU0_G0_CPU1_G2_TX_DN<1>")
	)
	(arc
		(start 357.589836 -239.118394)
		(mid 357.704512 -238.98506)
		(end 357.745792 -238.814102)
		(width 0.1143)
		(layer "In13.Cu")
		(net "GMI_CPU0_G0_CPU1_G2_TX_DN<1>")
	)
	(arc
		(start 114.222276 -239.634014)
		(mid 114.276959 -239.798391)
		(end 114.38509 -239.933734)
		(width 0.1143)
		(layer "In13.Cu")
		(net "GMI_CPU0_G0_CPU1_G2_TX_DN<1>")
	)
	(arc
		(start 114.446812 -239.969802)
		(mid 114.598799 -240.12631)
		(end 114.680238 -240.328704)
		(width 0.1143)
		(layer "In13.Cu")
		(net "GMI_CPU0_G0_CPU1_G2_TX_DN<1>")
	)
	(arc
		(start 357.746046 -222.614236)
		(mid 357.821144 -222.334247)
		(end 358.026462 -222.129604)
		(width 0.1143)
		(layer "In13.Cu")
		(net "GMI_CPU0_G0_CPU1_G2_TX_DN<1>")
	)
	(arc
		(start 357.275638 -239.604042)
		(mid 357.345031 -239.352443)
		(end 357.519986 -239.15878)
		(width 0.1143)
		(layer "In13.Cu")
		(net "GMI_CPU0_G0_CPU1_G2_TX_DN<1>")
	)
	(arc
		(start 358.05872 -236.688884)
		(mid 358.215697 -236.384084)
		(end 358.05872 -236.079284)
		(width 0.1143)
		(layer "In13.Cu")
		(net "GMI_CPU0_G0_CPU1_G2_TX_DN<1>")
	)
	(arc
		(start 357.110792 -239.93348)
		(mid 357.218928 -239.798139)
		(end 357.273606 -239.63376)
		(width 0.1143)
		(layer "In13.Cu")
		(net "GMI_CPU0_G0_CPU1_G2_TX_DN<1>")
	)
	(arc
		(start 357.745792 -230.714296)
		(mid 357.811028 -230.450705)
		(end 357.991664 -230.247952)
		(width 0.1143)
		(layer "In13.Cu")
		(net "GMI_CPU0_G0_CPU1_G2_TX_DN<1>")
	)
	(arc
		(start 113.506758 -233.489754)
		(mid 113.750085 -233.95432)
		(end 113.506758 -234.418886)
		(width 0.1143)
		(layer "In13.Cu")
		(net "GMI_CPU0_G0_CPU1_G2_TX_DN<1>")
	)
	(arc
		(start 357.989124 -231.869488)
		(mid 357.989886 -231.868979)
		(end 357.990648 -231.868472)
		(width 0.1143)
		(layer "In13.Cu")
		(net "GMI_CPU0_G0_CPU1_G2_TX_DN<1>")
	)
	(arc
		(start 113.46942 -222.129858)
		(mid 113.674742 -222.334499)
		(end 113.749836 -222.61449)
		(width 0.1143)
		(layer "In13.Cu")
		(net "GMI_CPU0_G0_CPU1_G2_TX_DN<1>")
	)
	(arc
		(start 113.437162 -236.079538)
		(mid 113.280185 -236.384338)
		(end 113.437162 -236.689138)
		(width 0.1143)
		(layer "In13.Cu")
		(net "GMI_CPU0_G0_CPU1_G2_TX_DN<1>")
	)
	(arc
		(start 114.220244 -239.604296)
		(mid 114.220817 -239.619185)
		(end 114.222276 -239.634014)
		(width 0.1143)
		(layer "In13.Cu")
		(net "GMI_CPU0_G0_CPU1_G2_TX_DN<1>")
	)
	(arc
		(start 356.811834 -240.35131)
		(mid 356.813622 -240.339861)
		(end 356.815644 -240.32845)
		(width 0.1143)
		(layer "In13.Cu")
		(net "GMI_CPU0_G0_CPU1_G2_TX_DN<1>")
	)
	(arc
		(start 113.506758 -227.00996)
		(mid 113.750085 -227.474526)
		(end 113.506758 -227.939092)
		(width 0.1143)
		(layer "In13.Cu")
		(net "GMI_CPU0_G0_CPU1_G2_TX_DN<1>")
	)
	(arc
		(start 113.280444 -229.914196)
		(mid 113.324146 -230.080044)
		(end 113.437162 -230.20909)
		(width 0.1143)
		(layer "In13.Cu")
		(net "GMI_CPU0_G0_CPU1_G2_TX_DN<1>")
	)
	(arc
		(start 358.05872 -223.729042)
		(mid 358.215697 -223.424242)
		(end 358.05872 -223.119442)
		(width 0.1143)
		(layer "In13.Cu")
		(net "GMI_CPU0_G0_CPU1_G2_TX_DN<1>")
	)
	(arc
		(start 357.989124 -224.698814)
		(mid 357.745797 -224.234248)
		(end 357.989124 -223.769682)
		(width 0.1143)
		(layer "In13.Cu")
		(net "GMI_CPU0_G0_CPU1_G2_TX_DN<1>")
	)
	(arc
		(start 358.215438 -229.913942)
		(mid 358.163636 -229.739088)
		(end 358.051608 -229.595172)
		(width 0.1143)
		(layer "In13.Cu")
		(net "GMI_CPU0_G0_CPU1_G2_TX_DN<1>")
	)
	(arc
		(start 113.437162 -226.35972)
		(mid 113.280185 -226.66452)
		(end 113.437162 -226.96932)
		(width 0.1143)
		(layer "In13.Cu")
		(net "GMI_CPU0_G0_CPU1_G2_TX_DN<1>")
	)
	(arc
		(start 357.989124 -226.318826)
		(mid 357.745797 -225.85426)
		(end 357.989124 -225.389694)
		(width 0.1143)
		(layer "In13.Cu")
		(net "GMI_CPU0_G0_CPU1_G2_TX_DN<1>")
	)
	(arc
		(start 357.746046 -229.094284)
		(mid 357.810439 -228.832106)
		(end 357.989124 -228.629718)
		(width 0.1143)
		(layer "In13.Cu")
		(net "GMI_CPU0_G0_CPU1_G2_TX_DN<1>")
	)
	(arc
		(start 113.506758 -236.729778)
		(mid 113.750085 -237.194344)
		(end 113.506758 -237.65891)
		(width 0.1143)
		(layer "In13.Cu")
		(net "GMI_CPU0_G0_CPU1_G2_TX_DN<1>")
	)
	(arc
		(start 113.437162 -237.69955)
		(mid 113.280185 -238.00435)
		(end 113.437162 -238.30915)
		(width 0.1143)
		(layer "In13.Cu")
		(net "GMI_CPU0_G0_CPU1_G2_TX_DN<1>")
	)
	(arc
		(start 358.05872 -238.308896)
		(mid 358.215697 -238.004096)
		(end 358.05872 -237.699296)
		(width 0.1143)
		(layer "In13.Cu")
		(net "GMI_CPU0_G0_CPU1_G2_TX_DN<1>")
	)
	(arc
		(start 113.506758 -238.34979)
		(mid 113.685571 -238.55214)
		(end 113.75009 -238.814356)
		(width 0.1143)
		(layer "In13.Cu")
		(net "GMI_CPU0_G0_CPU1_G2_TX_DN<1>")
	)
	(arc
		(start 357.989124 -231.178862)
		(mid 357.810311 -230.976512)
		(end 357.745792 -230.714296)
		(width 0.1143)
		(layer "In13.Cu")
		(net "GMI_CPU0_G0_CPU1_G2_TX_DN<1>")
	)
	(arc
		(start 113.749836 -222.61449)
		(mid 113.685018 -222.877479)
		(end 113.505234 -223.080072)
		(width 0.1143)
		(layer "In13.Cu")
		(net "GMI_CPU0_G0_CPU1_G2_TX_DN<1>")
	)
	(arc
		(start 357.989124 -227.938838)
		(mid 357.745797 -227.474272)
		(end 357.989124 -227.009706)
		(width 0.1143)
		(layer "In13.Cu")
		(net "GMI_CPU0_G0_CPU1_G2_TX_DN<1>")
	)
	(arc
		(start 113.506758 -225.389948)
		(mid 113.750085 -225.854514)
		(end 113.506758 -226.31908)
		(width 0.1143)
		(layer "In13.Cu")
		(net "GMI_CPU0_G0_CPU1_G2_TX_DN<1>")
	)
	(arc
		(start 113.506758 -228.629972)
		(mid 113.685478 -228.832341)
		(end 113.749836 -229.094538)
		(width 0.1143)
		(layer "In13.Cu")
		(net "GMI_CPU0_G0_CPU1_G2_TX_DN<1>")
	)
	(arc
		(start 113.437162 -223.119696)
		(mid 113.280185 -223.424496)
		(end 113.437162 -223.729296)
		(width 0.1143)
		(layer "In13.Cu")
		(net "GMI_CPU0_G0_CPU1_G2_TX_DN<1>")
	)
	(arc
		(start 113.437162 -224.739708)
		(mid 113.280185 -225.044508)
		(end 113.437162 -225.349308)
		(width 0.1143)
		(layer "In13.Cu")
		(net "GMI_CPU0_G0_CPU1_G2_TX_DN<1>")
	)
	(arc
		(start 358.05872 -226.969066)
		(mid 358.215697 -226.664266)
		(end 358.05872 -226.359466)
		(width 0.1143)
		(layer "In13.Cu")
		(net "GMI_CPU0_G0_CPU1_G2_TX_DN<1>")
	)
	(arc
		(start 357.989124 -232.79862)
		(mid 357.745797 -232.334054)
		(end 357.989124 -231.869488)
		(width 0.1143)
		(layer "In13.Cu")
		(net "GMI_CPU0_G0_CPU1_G2_TX_DN<1>")
	)
	(arc
		(start 113.437162 -232.839514)
		(mid 113.280185 -233.144314)
		(end 113.437162 -233.449114)
		(width 0.1143)
		(layer "In13.Cu")
		(net "GMI_CPU0_G0_CPU1_G2_TX_DN<1>")
	)
	(arc
		(start 113.444274 -229.595426)
		(mid 113.332181 -229.739309)
		(end 113.280444 -229.914196)
		(width 0.1143)
		(layer "In13.Cu")
		(net "GMI_CPU0_G0_CPU1_G2_TX_DN<1>")
	)
	(segment
		(start 125.407928 -241.510312)
		(end 125.87478 -241.244374)
		(width 0.12954)
		(layer "F.Cu")
		(net "GMI_CPU0_G0_CPU1_G2_TX_DN<15>")
	)
	(segment
		(start 346.087954 -241.510058)
		(end 345.621102 -241.24412)
		(width 0.12954)
		(layer "F.Cu")
		(net "GMI_CPU0_G0_CPU1_G2_TX_DN<15>")
	)
	(segment
		(start 126.627636 -237.68177)
		(end 126.597156 -237.69955)
		(width 0.1143)
		(layer "In13.Cu")
		(net "GMI_CPU0_G0_CPU1_G2_TX_DN<15>")
	)
	(segment
		(start 160.7439 -193.746628)
		(end 160.72485 -193.939668)
		(width 0.14224)
		(layer "In13.Cu")
		(net "GMI_CPU0_G0_CPU1_G2_TX_DN<15>")
	)
	(segment
		(start 157.254956 -196.607684)
		(end 157.235906 -196.800724)
		(width 0.14224)
		(layer "In13.Cu")
		(net "GMI_CPU0_G0_CPU1_G2_TX_DN<15>")
	)
	(segment
		(start 156.38272 -197.322948)
		(end 156.36367 -197.515988)
		(width 0.14224)
		(layer "In13.Cu")
		(net "GMI_CPU0_G0_CPU1_G2_TX_DN<15>")
	)
	(segment
		(start 344.82913 -227.009706)
		(end 344.898726 -226.969066)
		(width 0.1143)
		(layer "In13.Cu")
		(net "GMI_CPU0_G0_CPU1_G2_TX_DN<15>")
	)
	(segment
		(start 345.365324 -240.127282)
		(end 345.364562 -240.126774)
		(width 0.1143)
		(layer "In13.Cu")
		(net "GMI_CPU0_G0_CPU1_G2_TX_DN<15>")
	)
	(segment
		(start 344.82913 -222.14967)
		(end 344.898726 -222.10903)
		(width 0.1143)
		(layer "In13.Cu")
		(net "GMI_CPU0_G0_CPU1_G2_TX_DN<15>")
	)
	(segment
		(start 126.597156 -228.589332)
		(end 126.627636 -228.607112)
		(width 0.1143)
		(layer "In13.Cu")
		(net "GMI_CPU0_G0_CPU1_G2_TX_DN<15>")
	)
	(segment
		(start 262.841486 -190.954914)
		(end 251.791724 -192.903094)
		(width 0.14224)
		(layer "In13.Cu")
		(net "GMI_CPU0_G0_CPU1_G2_TX_DN<15>")
	)
	(segment
		(start 126.597156 -222.109284)
		(end 126.627636 -222.127064)
		(width 0.1143)
		(layer "In13.Cu")
		(net "GMI_CPU0_G0_CPU1_G2_TX_DN<15>")
	)
	(segment
		(start 126.627636 -222.127064)
		(end 126.666752 -222.149924)
		(width 0.1143)
		(layer "In13.Cu")
		(net "GMI_CPU0_G0_CPU1_G2_TX_DN<15>")
	)
	(segment
		(start 158.108142 -196.08546)
		(end 157.777942 -196.356224)
		(width 0.14224)
		(layer "In13.Cu")
		(net "GMI_CPU0_G0_CPU1_G2_TX_DN<15>")
	)
	(segment
		(start 344.82913 -228.629718)
		(end 344.898726 -228.589078)
		(width 0.1143)
		(layer "In13.Cu")
		(net "GMI_CPU0_G0_CPU1_G2_TX_DN<15>")
	)
	(segment
		(start 126.666752 -226.31908)
		(end 126.627636 -226.34194)
		(width 0.1143)
		(layer "In13.Cu")
		(net "GMI_CPU0_G0_CPU1_G2_TX_DN<15>")
	)
	(segment
		(start 236.278928 -201.64679)
		(end 231.94772 -200.883012)
		(width 0.14224)
		(layer "In13.Cu")
		(net "GMI_CPU0_G0_CPU1_G2_TX_DN<15>")
	)
	(segment
		(start 344.900758 -229.600506)
		(end 344.868246 -229.58171)
		(width 0.1143)
		(layer "In13.Cu")
		(net "GMI_CPU0_G0_CPU1_G2_TX_DN<15>")
	)
	(segment
		(start 126.666752 -229.559104)
		(end 126.627636 -229.581964)
		(width 0.1143)
		(layer "In13.Cu")
		(net "GMI_CPU0_G0_CPU1_G2_TX_DN<15>")
	)
	(segment
		(start 126.597156 -225.349308)
		(end 126.627636 -225.367088)
		(width 0.1143)
		(layer "In13.Cu")
		(net "GMI_CPU0_G0_CPU1_G2_TX_DN<15>")
	)
	(segment
		(start 207.164178 -191.22898)
		(end 162.964114 -191.415924)
		(width 0.14224)
		(layer "In13.Cu")
		(net "GMI_CPU0_G0_CPU1_G2_TX_DN<15>")
	)
	(segment
		(start 162.14471 -192.59804)
		(end 161.61639 -193.031364)
		(width 0.14224)
		(layer "In13.Cu")
		(net "GMI_CPU0_G0_CPU1_G2_TX_DN<15>")
	)
	(segment
		(start 155.161234 -198.502016)
		(end 154.968194 -198.482966)
		(width 0.14224)
		(layer "In13.Cu")
		(net "GMI_CPU0_G0_CPU1_G2_TX_DN<15>")
	)
	(segment
		(start 125.685804 -240.923064)
		(end 125.656086 -240.940082)
		(width 0.1143)
		(layer "In13.Cu")
		(net "GMI_CPU0_G0_CPU1_G2_TX_DN<15>")
	)
	(segment
		(start 308.267862 -191.33185)
		(end 303.7332 -191.33185)
		(width 0.14224)
		(layer "In13.Cu")
		(net "GMI_CPU0_G0_CPU1_G2_TX_DN<15>")
	)
	(segment
		(start 161.073846 -193.476118)
		(end 160.7439 -193.746628)
		(width 0.14224)
		(layer "In13.Cu")
		(net "GMI_CPU0_G0_CPU1_G2_TX_DN<15>")
	)
	(segment
		(start 345.919044 -241.24412)
		(end 345.988894 -241.17427)
		(width 0.1143)
		(layer "In13.Cu")
		(net "GMI_CPU0_G0_CPU1_G2_TX_DN<15>")
	)
	(segment
		(start 158.650178 -195.64096)
		(end 158.457138 -195.62191)
		(width 0.14224)
		(layer "In13.Cu")
		(net "GMI_CPU0_G0_CPU1_G2_TX_DN<15>")
	)
	(segment
		(start 157.777942 -196.356224)
		(end 157.584902 -196.337174)
		(width 0.14224)
		(layer "In13.Cu")
		(net "GMI_CPU0_G0_CPU1_G2_TX_DN<15>")
	)
	(segment
		(start 148.74494 -202.83424)
		(end 147.420584 -203.23556)
		(width 0.14224)
		(layer "In13.Cu")
		(net "GMI_CPU0_G0_CPU1_G2_TX_DN<15>")
	)
	(segment
		(start 126.627636 -235.086906)
		(end 126.666752 -235.109766)
		(width 0.1143)
		(layer "In13.Cu")
		(net "GMI_CPU0_G0_CPU1_G2_TX_DN<15>")
	)
	(segment
		(start 345.009978 -221.127828)
		(end 345.010486 -221.12732)
		(width 0.14224)
		(layer "In13.Cu")
		(net "GMI_CPU0_G0_CPU1_G2_TX_DN<15>")
	)
	(segment
		(start 126.666752 -232.798874)
		(end 126.627636 -232.821734)
		(width 0.1143)
		(layer "In13.Cu")
		(net "GMI_CPU0_G0_CPU1_G2_TX_DN<15>")
	)
	(segment
		(start 160.72485 -193.939668)
		(end 160.39465 -194.210432)
		(width 0.14224)
		(layer "In13.Cu")
		(net "GMI_CPU0_G0_CPU1_G2_TX_DN<15>")
	)
	(segment
		(start 161.61639 -193.031364)
		(end 161.59734 -193.224404)
		(width 0.14224)
		(layer "In13.Cu")
		(net "GMI_CPU0_G0_CPU1_G2_TX_DN<15>")
	)
	(segment
		(start 126.485396 -221.127574)
		(end 126.485904 -221.128082)
		(width 0.14224)
		(layer "In13.Cu")
		(net "GMI_CPU0_G0_CPU1_G2_TX_DN<15>")
	)
	(segment
		(start 344.898726 -223.119442)
		(end 344.82913 -223.078802)
		(width 0.1143)
		(layer "In13.Cu")
		(net "GMI_CPU0_G0_CPU1_G2_TX_DN<15>")
	)
	(segment
		(start 126.627636 -239.301782)
		(end 126.597156 -239.319562)
		(width 0.1143)
		(layer "In13.Cu")
		(net "GMI_CPU0_G0_CPU1_G2_TX_DN<15>")
	)
	(segment
		(start 345.808808 -240.922048)
		(end 345.808046 -240.92154)
		(width 0.1143)
		(layer "In13.Cu")
		(net "GMI_CPU0_G0_CPU1_G2_TX_DN<15>")
	)
	(segment
		(start 231.94772 -200.883012)
		(end 209.73542 -191.682624)
		(width 0.14224)
		(layer "In13.Cu")
		(net "GMI_CPU0_G0_CPU1_G2_TX_DN<15>")
	)
	(segment
		(start 158.127192 -195.89242)
		(end 158.108142 -196.08546)
		(width 0.14224)
		(layer "In13.Cu")
		(net "GMI_CPU0_G0_CPU1_G2_TX_DN<15>")
	)
	(segment
		(start 344.900758 -231.220518)
		(end 344.868246 -231.201722)
		(width 0.1143)
		(layer "In13.Cu")
		(net "GMI_CPU0_G0_CPU1_G2_TX_DN<15>")
	)
	(segment
		(start 316.413896 -197.02018)
		(end 308.267862 -191.33185)
		(width 0.14224)
		(layer "In13.Cu")
		(net "GMI_CPU0_G0_CPU1_G2_TX_DN<15>")
	)
	(segment
		(start 126.196852 -240.088928)
		(end 126.1618 -240.109502)
		(width 0.1143)
		(layer "In13.Cu")
		(net "GMI_CPU0_G0_CPU1_G2_TX_DN<15>")
	)
	(segment
		(start 126.597156 -226.96932)
		(end 126.627636 -226.9871)
		(width 0.1143)
		(layer "In13.Cu")
		(net "GMI_CPU0_G0_CPU1_G2_TX_DN<15>")
	)
	(segment
		(start 154.967686 -198.482966)
		(end 150.197312 -202.394312)
		(width 0.14224)
		(layer "In13.Cu")
		(net "GMI_CPU0_G0_CPU1_G2_TX_DN<15>")
	)
	(segment
		(start 126.627636 -238.32693)
		(end 126.666752 -238.34979)
		(width 0.1143)
		(layer "In13.Cu")
		(net "GMI_CPU0_G0_CPU1_G2_TX_DN<15>")
	)
	(segment
		(start 126.1618 -240.109502)
		(end 126.157736 -240.111788)
		(width 0.1143)
		(layer "In13.Cu")
		(net "GMI_CPU0_G0_CPU1_G2_TX_DN<15>")
	)
	(segment
		(start 158.658814 -195.633848)
		(end 158.650178 -195.64096)
		(width 0.14224)
		(layer "In13.Cu")
		(net "GMI_CPU0_G0_CPU1_G2_TX_DN<15>")
	)
	(segment
		(start 126.627636 -229.581964)
		(end 126.595124 -229.60076)
		(width 0.1143)
		(layer "In13.Cu")
		(net "GMI_CPU0_G0_CPU1_G2_TX_DN<15>")
	)
	(segment
		(start 159.329374 -194.906646)
		(end 158.999428 -195.177156)
		(width 0.14224)
		(layer "In13.Cu")
		(net "GMI_CPU0_G0_CPU1_G2_TX_DN<15>")
	)
	(segment
		(start 345.338654 -240.111534)
		(end 345.338146 -240.111534)
		(width 0.1143)
		(layer "In13.Cu")
		(net "GMI_CPU0_G0_CPU1_G2_TX_DN<15>")
	)
	(segment
		(start 126.666752 -223.079056)
		(end 126.627636 -223.101916)
		(width 0.1143)
		(layer "In13.Cu")
		(net "GMI_CPU0_G0_CPU1_G2_TX_DN<15>")
	)
	(segment
		(start 126.627636 -224.721928)
		(end 126.597156 -224.739708)
		(width 0.1143)
		(layer "In13.Cu")
		(net "GMI_CPU0_G0_CPU1_G2_TX_DN<15>")
	)
	(segment
		(start 345.330018 -240.106708)
		(end 345.29903 -240.088674)
		(width 0.1143)
		(layer "In13.Cu")
		(net "GMI_CPU0_G0_CPU1_G2_TX_DN<15>")
	)
	(segment
		(start 126.666752 -239.278922)
		(end 126.627636 -239.301782)
		(width 0.1143)
		(layer "In13.Cu")
		(net "GMI_CPU0_G0_CPU1_G2_TX_DN<15>")
	)
	(segment
		(start 147.420584 -203.23556)
		(end 127.32512 -219.712286)
		(width 0.14224)
		(layer "In13.Cu")
		(net "GMI_CPU0_G0_CPU1_G2_TX_DN<15>")
	)
	(segment
		(start 126.597156 -230.20909)
		(end 126.664212 -230.248206)
		(width 0.1143)
		(layer "In13.Cu")
		(net "GMI_CPU0_G0_CPU1_G2_TX_DN<15>")
	)
	(segment
		(start 344.82913 -231.869488)
		(end 344.898726 -231.828848)
		(width 0.1143)
		(layer "In13.Cu")
		(net "GMI_CPU0_G0_CPU1_G2_TX_DN<15>")
	)
	(segment
		(start 126.597156 -223.729296)
		(end 126.627636 -223.747076)
		(width 0.1143)
		(layer "In13.Cu")
		(net "GMI_CPU0_G0_CPU1_G2_TX_DN<15>")
	)
	(segment
		(start 126.485904 -221.263464)
		(end 126.485904 -221.291912)
		(width 0.1143)
		(layer "In13.Cu")
		(net "GMI_CPU0_G0_CPU1_G2_TX_DN<15>")
	)
	(segment
		(start 126.666752 -227.939092)
		(end 126.627636 -227.961952)
		(width 0.1143)
		(layer "In13.Cu")
		(net "GMI_CPU0_G0_CPU1_G2_TX_DN<15>")
	)
	(segment
		(start 126.666752 -234.418886)
		(end 126.627636 -234.441746)
		(width 0.1143)
		(layer "In13.Cu")
		(net "GMI_CPU0_G0_CPU1_G2_TX_DN<15>")
	)
	(segment
		(start 126.597156 -231.829102)
		(end 126.627636 -231.846882)
		(width 0.1143)
		(layer "In13.Cu")
		(net "GMI_CPU0_G0_CPU1_G2_TX_DN<15>")
	)
	(segment
		(start 126.627636 -223.101916)
		(end 126.597156 -223.119696)
		(width 0.1143)
		(layer "In13.Cu")
		(net "GMI_CPU0_G0_CPU1_G2_TX_DN<15>")
	)
	(segment
		(start 126.666752 -237.65891)
		(end 126.627636 -237.68177)
		(width 0.1143)
		(layer "In13.Cu")
		(net "GMI_CPU0_G0_CPU1_G2_TX_DN<15>")
	)
	(segment
		(start 345.010232 -220.962728)
		(end 344.4367 -219.997274)
		(width 0.14224)
		(layer "In13.Cu")
		(net "GMI_CPU0_G0_CPU1_G2_TX_DN<15>")
	)
	(segment
		(start 160.39465 -194.210432)
		(end 160.20161 -194.191382)
		(width 0.14224)
		(layer "In13.Cu")
		(net "GMI_CPU0_G0_CPU1_G2_TX_DN<15>")
	)
	(segment
		(start 126.666752 -231.179116)
		(end 126.627636 -231.201976)
		(width 0.1143)
		(layer "In13.Cu")
		(net "GMI_CPU0_G0_CPU1_G2_TX_DN<15>")
	)
	(segment
		(start 157.235906 -196.800724)
		(end 156.905706 -197.071488)
		(width 0.14224)
		(layer "In13.Cu")
		(net "GMI_CPU0_G0_CPU1_G2_TX_DN<15>")
	)
	(segment
		(start 344.898726 -232.83926)
		(end 344.82913 -232.79862)
		(width 0.1143)
		(layer "In13.Cu")
		(net "GMI_CPU0_G0_CPU1_G2_TX_DN<15>")
	)
	(segment
		(start 148.745956 -202.833986)
		(end 148.745194 -202.83424)
		(width 0.14224)
		(layer "In13.Cu")
		(net "GMI_CPU0_G0_CPU1_G2_TX_DN<15>")
	)
	(segment
		(start 344.83167 -230.247952)
		(end 344.898726 -230.208836)
		(width 0.1143)
		(layer "In13.Cu")
		(net "GMI_CPU0_G0_CPU1_G2_TX_DN<15>")
	)
	(segment
		(start 159.522414 -194.925696)
		(end 159.329374 -194.906646)
		(width 0.14224)
		(layer "In13.Cu")
		(net "GMI_CPU0_G0_CPU1_G2_TX_DN<15>")
	)
	(segment
		(start 126.485904 -221.128082)
		(end 126.485904 -221.263464)
		(width 0.14224)
		(layer "In13.Cu")
		(net "GMI_CPU0_G0_CPU1_G2_TX_DN<15>")
	)
	(segment
		(start 344.82913 -225.389694)
		(end 344.898726 -225.349054)
		(width 0.1143)
		(layer "In13.Cu")
		(net "GMI_CPU0_G0_CPU1_G2_TX_DN<15>")
	)
	(segment
		(start 345.808046 -240.92154)
		(end 345.771724 -240.900458)
		(width 0.1143)
		(layer "In13.Cu")
		(net "GMI_CPU0_G0_CPU1_G2_TX_DN<15>")
	)
	(segment
		(start 344.898726 -236.079284)
		(end 344.82913 -236.038644)
		(width 0.1143)
		(layer "In13.Cu")
		(net "GMI_CPU0_G0_CPU1_G2_TX_DN<15>")
	)
	(segment
		(start 155.84043 -197.767702)
		(end 155.510484 -198.038212)
		(width 0.14224)
		(layer "In13.Cu")
		(net "GMI_CPU0_G0_CPU1_G2_TX_DN<15>")
	)
	(segment
		(start 345.621102 -241.24412)
		(end 345.919044 -241.24412)
		(width 0.1143)
		(layer "In13.Cu")
		(net "GMI_CPU0_G0_CPU1_G2_TX_DN<15>")
	)
	(segment
		(start 345.009978 -221.291658)
		(end 345.009978 -221.26321)
		(width 0.1143)
		(layer "In13.Cu")
		(net "GMI_CPU0_G0_CPU1_G2_TX_DN<15>")
	)
	(segment
		(start 344.82913 -223.769682)
		(end 344.898726 -223.729042)
		(width 0.1143)
		(layer "In13.Cu")
		(net "GMI_CPU0_G0_CPU1_G2_TX_DN<15>")
	)
	(segment
		(start 209.73542 -191.682624)
		(end 207.164178 -191.22898)
		(width 0.14224)
		(layer "In13.Cu")
		(net "GMI_CPU0_G0_CPU1_G2_TX_DN<15>")
	)
	(segment
		(start 240.324132 -200.933304)
		(end 236.278928 -201.64679)
		(width 0.14224)
		(layer "In13.Cu")
		(net "GMI_CPU0_G0_CPU1_G2_TX_DN<15>")
	)
	(segment
		(start 162.964114 -191.415924)
		(end 162.632898 -191.688212)
		(width 0.14224)
		(layer "In13.Cu")
		(net "GMI_CPU0_G0_CPU1_G2_TX_DN<15>")
	)
	(segment
		(start 126.627636 -236.706918)
		(end 126.666752 -236.729778)
		(width 0.1143)
		(layer "In13.Cu")
		(net "GMI_CPU0_G0_CPU1_G2_TX_DN<15>")
	)
	(segment
		(start 126.627636 -226.34194)
		(end 126.597156 -226.35972)
		(width 0.1143)
		(layer "In13.Cu")
		(net "GMI_CPU0_G0_CPU1_G2_TX_DN<15>")
	)
	(segment
		(start 126.485904 -221.291912)
		(end 126.440184 -221.337632)
		(width 0.1143)
		(layer "In13.Cu")
		(net "GMI_CPU0_G0_CPU1_G2_TX_DN<15>")
	)
	(segment
		(start 148.74494 -202.834494)
		(end 148.74494 -202.83424)
		(width 0.14224)
		(layer "In13.Cu")
		(net "GMI_CPU0_G0_CPU1_G2_TX_DN<15>")
	)
	(segment
		(start 345.010232 -221.093538)
		(end 345.010232 -220.962728)
		(width 0.14224)
		(layer "In13.Cu")
		(net "GMI_CPU0_G0_CPU1_G2_TX_DN<15>")
	)
	(segment
		(start 126.440184 -221.337632)
		(end 126.440184 -221.804484)
		(width 0.1143)
		(layer "In13.Cu")
		(net "GMI_CPU0_G0_CPU1_G2_TX_DN<15>")
	)
	(segment
		(start 126.627636 -223.747076)
		(end 126.666752 -223.769936)
		(width 0.1143)
		(layer "In13.Cu")
		(net "GMI_CPU0_G0_CPU1_G2_TX_DN<15>")
	)
	(segment
		(start 157.584902 -196.337174)
		(end 157.254956 -196.607684)
		(width 0.14224)
		(layer "In13.Cu")
		(net "GMI_CPU0_G0_CPU1_G2_TX_DN<15>")
	)
	(segment
		(start 125.506988 -241.174524)
		(end 125.576838 -241.244374)
		(width 0.1143)
		(layer "In13.Cu")
		(net "GMI_CPU0_G0_CPU1_G2_TX_DN<15>")
	)
	(segment
		(start 251.791724 -192.903094)
		(end 240.324132 -200.933304)
		(width 0.14224)
		(layer "In13.Cu")
		(net "GMI_CPU0_G0_CPU1_G2_TX_DN<15>")
	)
	(segment
		(start 345.009978 -221.26321)
		(end 345.009978 -221.127828)
		(width 0.14224)
		(layer "In13.Cu")
		(net "GMI_CPU0_G0_CPU1_G2_TX_DN<15>")
	)
	(segment
		(start 345.839796 -240.939828)
		(end 345.808808 -240.922048)
		(width 0.1143)
		(layer "In13.Cu")
		(net "GMI_CPU0_G0_CPU1_G2_TX_DN<15>")
	)
	(segment
		(start 126.627636 -226.9871)
		(end 126.666752 -227.00996)
		(width 0.1143)
		(layer "In13.Cu")
		(net "GMI_CPU0_G0_CPU1_G2_TX_DN<15>")
	)
	(segment
		(start 344.898726 -237.699296)
		(end 344.82913 -237.658656)
		(width 0.1143)
		(layer "In13.Cu")
		(net "GMI_CPU0_G0_CPU1_G2_TX_DN<15>")
	)
	(segment
		(start 154.968194 -198.482966)
		(end 154.967686 -198.482966)
		(width 0.14224)
		(layer "In13.Cu")
		(net "GMI_CPU0_G0_CPU1_G2_TX_DN<15>")
	)
	(segment
		(start 345.364562 -240.126774)
		(end 345.338654 -240.111534)
		(width 0.1143)
		(layer "In13.Cu")
		(net "GMI_CPU0_G0_CPU1_G2_TX_DN<15>")
	)
	(segment
		(start 126.666752 -236.038898)
		(end 126.627636 -236.061758)
		(width 0.1143)
		(layer "In13.Cu")
		(net "GMI_CPU0_G0_CPU1_G2_TX_DN<15>")
	)
	(segment
		(start 126.627636 -232.821734)
		(end 126.597156 -232.839514)
		(width 0.1143)
		(layer "In13.Cu")
		(net "GMI_CPU0_G0_CPU1_G2_TX_DN<15>")
	)
	(segment
		(start 126.627636 -233.466894)
		(end 126.666752 -233.489754)
		(width 0.1143)
		(layer "In13.Cu")
		(net "GMI_CPU0_G0_CPU1_G2_TX_DN<15>")
	)
	(segment
		(start 126.627636 -225.367088)
		(end 126.666752 -225.389948)
		(width 0.1143)
		(layer "In13.Cu")
		(net "GMI_CPU0_G0_CPU1_G2_TX_DN<15>")
	)
	(segment
		(start 344.868246 -229.58171)
		(end 344.82913 -229.55885)
		(width 0.1143)
		(layer "In13.Cu")
		(net "GMI_CPU0_G0_CPU1_G2_TX_DN<15>")
	)
	(segment
		(start 345.338146 -240.111534)
		(end 345.334082 -240.109248)
		(width 0.1143)
		(layer "In13.Cu")
		(net "GMI_CPU0_G0_CPU1_G2_TX_DN<15>")
	)
	(segment
		(start 126.627636 -236.061758)
		(end 126.597156 -236.079538)
		(width 0.1143)
		(layer "In13.Cu")
		(net "GMI_CPU0_G0_CPU1_G2_TX_DN<15>")
	)
	(segment
		(start 345.010486 -221.12732)
		(end 345.010486 -221.093792)
		(width 0.14224)
		(layer "In13.Cu")
		(net "GMI_CPU0_G0_CPU1_G2_TX_DN<15>")
	)
	(segment
		(start 125.724158 -240.900712)
		(end 125.687836 -240.921794)
		(width 0.1143)
		(layer "In13.Cu")
		(net "GMI_CPU0_G0_CPU1_G2_TX_DN<15>")
	)
	(segment
		(start 159.852614 -194.654932)
		(end 159.522414 -194.925696)
		(width 0.14224)
		(layer "In13.Cu")
		(net "GMI_CPU0_G0_CPU1_G2_TX_DN<15>")
	)
	(segment
		(start 126.13132 -240.127028)
		(end 126.130558 -240.127536)
		(width 0.1143)
		(layer "In13.Cu")
		(net "GMI_CPU0_G0_CPU1_G2_TX_DN<15>")
	)
	(segment
		(start 126.627636 -231.846882)
		(end 126.666752 -231.869742)
		(width 0.1143)
		(layer "In13.Cu")
		(net "GMI_CPU0_G0_CPU1_G2_TX_DN<15>")
	)
	(segment
		(start 156.712666 -197.052438)
		(end 156.38272 -197.322948)
		(width 0.14224)
		(layer "In13.Cu")
		(net "GMI_CPU0_G0_CPU1_G2_TX_DN<15>")
	)
	(segment
		(start 155.510484 -198.038212)
		(end 155.491434 -198.231252)
		(width 0.14224)
		(layer "In13.Cu")
		(net "GMI_CPU0_G0_CPU1_G2_TX_DN<15>")
	)
	(segment
		(start 344.898726 -227.979478)
		(end 344.82913 -227.938838)
		(width 0.1143)
		(layer "In13.Cu")
		(net "GMI_CPU0_G0_CPU1_G2_TX_DN<15>")
	)
	(segment
		(start 156.03347 -197.786752)
		(end 155.84043 -197.767702)
		(width 0.14224)
		(layer "In13.Cu")
		(net "GMI_CPU0_G0_CPU1_G2_TX_DN<15>")
	)
	(segment
		(start 158.457138 -195.62191)
		(end 158.127192 -195.89242)
		(width 0.14224)
		(layer "In13.Cu")
		(net "GMI_CPU0_G0_CPU1_G2_TX_DN<15>")
	)
	(segment
		(start 126.157736 -240.111788)
		(end 126.157228 -240.111788)
		(width 0.1143)
		(layer "In13.Cu")
		(net "GMI_CPU0_G0_CPU1_G2_TX_DN<15>")
	)
	(segment
		(start 160.20161 -194.191382)
		(end 159.871664 -194.461892)
		(width 0.14224)
		(layer "In13.Cu")
		(net "GMI_CPU0_G0_CPU1_G2_TX_DN<15>")
	)
	(segment
		(start 345.055698 -221.80423)
		(end 345.055698 -221.337378)
		(width 0.1143)
		(layer "In13.Cu")
		(net "GMI_CPU0_G0_CPU1_G2_TX_DN<15>")
	)
	(segment
		(start 126.485396 -221.12605)
		(end 126.485396 -221.127574)
		(width 0.14224)
		(layer "In13.Cu")
		(net "GMI_CPU0_G0_CPU1_G2_TX_DN<15>")
	)
	(segment
		(start 126.157228 -240.111788)
		(end 126.13132 -240.127028)
		(width 0.1143)
		(layer "In13.Cu")
		(net "GMI_CPU0_G0_CPU1_G2_TX_DN<15>")
	)
	(segment
		(start 150.197312 -202.394312)
		(end 148.745956 -202.833986)
		(width 0.14224)
		(layer "In13.Cu")
		(net "GMI_CPU0_G0_CPU1_G2_TX_DN<15>")
	)
	(segment
		(start 126.627636 -234.441746)
		(end 126.597156 -234.459526)
		(width 0.1143)
		(layer "In13.Cu")
		(net "GMI_CPU0_G0_CPU1_G2_TX_DN<15>")
	)
	(segment
		(start 126.597156 -236.689138)
		(end 126.627636 -236.706918)
		(width 0.1143)
		(layer "In13.Cu")
		(net "GMI_CPU0_G0_CPU1_G2_TX_DN<15>")
	)
	(segment
		(start 162.632898 -191.688212)
		(end 162.14471 -192.59804)
		(width 0.14224)
		(layer "In13.Cu")
		(net "GMI_CPU0_G0_CPU1_G2_TX_DN<15>")
	)
	(segment
		(start 148.745194 -202.83424)
		(end 148.74494 -202.834494)
		(width 0.14224)
		(layer "In13.Cu")
		(net "GMI_CPU0_G0_CPU1_G2_TX_DN<15>")
	)
	(segment
		(start 159.871664 -194.461892)
		(end 159.852614 -194.654932)
		(width 0.14224)
		(layer "In13.Cu")
		(net "GMI_CPU0_G0_CPU1_G2_TX_DN<15>")
	)
	(segment
		(start 126.666752 -224.699068)
		(end 126.627636 -224.721928)
		(width 0.1143)
		(layer "In13.Cu")
		(net "GMI_CPU0_G0_CPU1_G2_TX_DN<15>")
	)
	(segment
		(start 344.82913 -238.349536)
		(end 344.898726 -238.308896)
		(width 0.1143)
		(layer "In13.Cu")
		(net "GMI_CPU0_G0_CPU1_G2_TX_DN<15>")
	)
	(segment
		(start 155.491434 -198.231252)
		(end 155.161234 -198.502016)
		(width 0.14224)
		(layer "In13.Cu")
		(net "GMI_CPU0_G0_CPU1_G2_TX_DN<15>")
	)
	(segment
		(start 344.82913 -233.4895)
		(end 344.898726 -233.44886)
		(width 0.1143)
		(layer "In13.Cu")
		(net "GMI_CPU0_G0_CPU1_G2_TX_DN<15>")
	)
	(segment
		(start 161.59734 -193.224404)
		(end 161.266886 -193.495168)
		(width 0.14224)
		(layer "In13.Cu")
		(net "GMI_CPU0_G0_CPU1_G2_TX_DN<15>")
	)
	(segment
		(start 125.687836 -240.921794)
		(end 125.687074 -240.922302)
		(width 0.1143)
		(layer "In13.Cu")
		(net "GMI_CPU0_G0_CPU1_G2_TX_DN<15>")
	)
	(segment
		(start 345.010486 -221.093792)
		(end 345.010232 -221.093538)
		(width 0.14224)
		(layer "In13.Cu")
		(net "GMI_CPU0_G0_CPU1_G2_TX_DN<15>")
	)
	(segment
		(start 125.687074 -240.922302)
		(end 125.685804 -240.923064)
		(width 0.1143)
		(layer "In13.Cu")
		(net "GMI_CPU0_G0_CPU1_G2_TX_DN<15>")
	)
	(segment
		(start 345.055698 -221.337378)
		(end 345.009978 -221.291658)
		(width 0.1143)
		(layer "In13.Cu")
		(net "GMI_CPU0_G0_CPU1_G2_TX_DN<15>")
	)
	(segment
		(start 344.898726 -239.319308)
		(end 344.82913 -239.278668)
		(width 0.1143)
		(layer "In13.Cu")
		(net "GMI_CPU0_G0_CPU1_G2_TX_DN<15>")
	)
	(segment
		(start 344.868246 -231.201722)
		(end 344.82913 -231.178862)
		(width 0.1143)
		(layer "In13.Cu")
		(net "GMI_CPU0_G0_CPU1_G2_TX_DN<15>")
	)
	(segment
		(start 126.627636 -228.607112)
		(end 126.666752 -228.629972)
		(width 0.1143)
		(layer "In13.Cu")
		(net "GMI_CPU0_G0_CPU1_G2_TX_DN<15>")
	)
	(segment
		(start 158.980378 -195.370196)
		(end 158.658814 -195.633848)
		(width 0.14224)
		(layer "In13.Cu")
		(net "GMI_CPU0_G0_CPU1_G2_TX_DN<15>")
	)
	(segment
		(start 126.597156 -238.30915)
		(end 126.627636 -238.32693)
		(width 0.1143)
		(layer "In13.Cu")
		(net "GMI_CPU0_G0_CPU1_G2_TX_DN<15>")
	)
	(segment
		(start 345.334082 -240.109248)
		(end 345.332304 -240.108232)
		(width 0.1143)
		(layer "In13.Cu")
		(net "GMI_CPU0_G0_CPU1_G2_TX_DN<15>")
	)
	(segment
		(start 126.597156 -235.069126)
		(end 126.627636 -235.086906)
		(width 0.1143)
		(layer "In13.Cu")
		(net "GMI_CPU0_G0_CPU1_G2_TX_DN<15>")
	)
	(segment
		(start 126.627636 -227.961952)
		(end 126.597156 -227.979732)
		(width 0.1143)
		(layer "In13.Cu")
		(net "GMI_CPU0_G0_CPU1_G2_TX_DN<15>")
	)
	(segment
		(start 126.627636 -231.201976)
		(end 126.595124 -231.220772)
		(width 0.1143)
		(layer "In13.Cu")
		(net "GMI_CPU0_G0_CPU1_G2_TX_DN<15>")
	)
	(segment
		(start 344.898726 -226.359466)
		(end 344.82913 -226.318826)
		(width 0.1143)
		(layer "In13.Cu")
		(net "GMI_CPU0_G0_CPU1_G2_TX_DN<15>")
	)
	(segment
		(start 344.82913 -235.109512)
		(end 344.898726 -235.068872)
		(width 0.1143)
		(layer "In13.Cu")
		(net "GMI_CPU0_G0_CPU1_G2_TX_DN<15>")
	)
	(segment
		(start 126.597156 -233.449114)
		(end 126.627636 -233.466894)
		(width 0.1143)
		(layer "In13.Cu")
		(net "GMI_CPU0_G0_CPU1_G2_TX_DN<15>")
	)
	(segment
		(start 303.7332 -191.33185)
		(end 262.841486 -190.954914)
		(width 0.14224)
		(layer "In13.Cu")
		(net "GMI_CPU0_G0_CPU1_G2_TX_DN<15>")
	)
	(segment
		(start 344.898726 -224.739454)
		(end 344.82913 -224.698814)
		(width 0.1143)
		(layer "In13.Cu")
		(net "GMI_CPU0_G0_CPU1_G2_TX_DN<15>")
	)
	(segment
		(start 345.332304 -240.108232)
		(end 345.330018 -240.106708)
		(width 0.1143)
		(layer "In13.Cu")
		(net "GMI_CPU0_G0_CPU1_G2_TX_DN<15>")
	)
	(segment
		(start 344.898726 -234.459272)
		(end 344.82913 -234.418632)
		(width 0.1143)
		(layer "In13.Cu")
		(net "GMI_CPU0_G0_CPU1_G2_TX_DN<15>")
	)
	(segment
		(start 344.82913 -236.729524)
		(end 344.898726 -236.688884)
		(width 0.1143)
		(layer "In13.Cu")
		(net "GMI_CPU0_G0_CPU1_G2_TX_DN<15>")
	)
	(segment
		(start 158.999428 -195.177156)
		(end 158.980378 -195.370196)
		(width 0.14224)
		(layer "In13.Cu")
		(net "GMI_CPU0_G0_CPU1_G2_TX_DN<15>")
	)
	(segment
		(start 125.576838 -241.244374)
		(end 125.87478 -241.244374)
		(width 0.1143)
		(layer "In13.Cu")
		(net "GMI_CPU0_G0_CPU1_G2_TX_DN<15>")
	)
	(segment
		(start 344.4367 -219.997274)
		(end 316.413896 -197.02018)
		(width 0.14224)
		(layer "In13.Cu")
		(net "GMI_CPU0_G0_CPU1_G2_TX_DN<15>")
	)
	(segment
		(start 156.905706 -197.071488)
		(end 156.712666 -197.052438)
		(width 0.14224)
		(layer "In13.Cu")
		(net "GMI_CPU0_G0_CPU1_G2_TX_DN<15>")
	)
	(segment
		(start 161.266886 -193.495168)
		(end 161.073846 -193.476118)
		(width 0.14224)
		(layer "In13.Cu")
		(net "GMI_CPU0_G0_CPU1_G2_TX_DN<15>")
	)
	(segment
		(start 127.32512 -219.712286)
		(end 126.485396 -221.12605)
		(width 0.14224)
		(layer "In13.Cu")
		(net "GMI_CPU0_G0_CPU1_G2_TX_DN<15>")
	)
	(segment
		(start 156.36367 -197.515988)
		(end 156.03347 -197.786752)
		(width 0.14224)
		(layer "In13.Cu")
		(net "GMI_CPU0_G0_CPU1_G2_TX_DN<15>")
	)
	(arc
		(start 345.374468 -240.134394)
		(mid 345.369924 -240.130803)
		(end 345.365324 -240.127282)
		(width 0.1143)
		(layer "In13.Cu")
		(net "GMI_CPU0_G0_CPU1_G2_TX_DN<15>")
	)
	(arc
		(start 126.597156 -234.459526)
		(mid 126.440179 -234.764326)
		(end 126.597156 -235.069126)
		(width 0.1143)
		(layer "In13.Cu")
		(net "GMI_CPU0_G0_CPU1_G2_TX_DN<15>")
	)
	(arc
		(start 344.82913 -229.55885)
		(mid 344.585803 -229.094284)
		(end 344.82913 -228.629718)
		(width 0.1143)
		(layer "In13.Cu")
		(net "GMI_CPU0_G0_CPU1_G2_TX_DN<15>")
	)
	(arc
		(start 126.121414 -240.134648)
		(mid 126.021124 -240.272079)
		(end 125.97003 -240.434368)
		(width 0.1143)
		(layer "In13.Cu")
		(net "GMI_CPU0_G0_CPU1_G2_TX_DN<15>")
	)
	(arc
		(start 345.055698 -229.904036)
		(mid 345.014732 -229.73363)
		(end 344.900758 -229.600506)
		(width 0.1143)
		(layer "In13.Cu")
		(net "GMI_CPU0_G0_CPU1_G2_TX_DN<15>")
	)
	(arc
		(start 126.597156 -226.35972)
		(mid 126.440179 -226.66452)
		(end 126.597156 -226.96932)
		(width 0.1143)
		(layer "In13.Cu")
		(net "GMI_CPU0_G0_CPU1_G2_TX_DN<15>")
	)
	(arc
		(start 126.440184 -231.524302)
		(mid 126.481733 -231.695724)
		(end 126.597156 -231.829102)
		(width 0.1143)
		(layer "In13.Cu")
		(net "GMI_CPU0_G0_CPU1_G2_TX_DN<15>")
	)
	(arc
		(start 126.666752 -225.389948)
		(mid 126.910079 -225.854514)
		(end 126.666752 -226.31908)
		(width 0.1143)
		(layer "In13.Cu")
		(net "GMI_CPU0_G0_CPU1_G2_TX_DN<15>")
	)
	(arc
		(start 344.82913 -234.418632)
		(mid 344.585803 -233.954066)
		(end 344.82913 -233.4895)
		(width 0.1143)
		(layer "In13.Cu")
		(net "GMI_CPU0_G0_CPU1_G2_TX_DN<15>")
	)
	(arc
		(start 126.597156 -224.739708)
		(mid 126.440179 -225.044508)
		(end 126.597156 -225.349308)
		(width 0.1143)
		(layer "In13.Cu")
		(net "GMI_CPU0_G0_CPU1_G2_TX_DN<15>")
	)
	(arc
		(start 126.666752 -222.149924)
		(mid 126.910079 -222.61449)
		(end 126.666752 -223.079056)
		(width 0.1143)
		(layer "In13.Cu")
		(net "GMI_CPU0_G0_CPU1_G2_TX_DN<15>")
	)
	(arc
		(start 344.82913 -239.278668)
		(mid 344.585803 -238.814102)
		(end 344.82913 -238.349536)
		(width 0.1143)
		(layer "In13.Cu")
		(net "GMI_CPU0_G0_CPU1_G2_TX_DN<15>")
	)
	(arc
		(start 345.755468 -240.889028)
		(mid 345.590801 -240.690421)
		(end 345.525852 -240.440718)
		(width 0.1143)
		(layer "In13.Cu")
		(net "GMI_CPU0_G0_CPU1_G2_TX_DN<15>")
	)
	(arc
		(start 344.898726 -236.688884)
		(mid 345.055703 -236.384084)
		(end 344.898726 -236.079284)
		(width 0.1143)
		(layer "In13.Cu")
		(net "GMI_CPU0_G0_CPU1_G2_TX_DN<15>")
	)
	(arc
		(start 344.898726 -223.729042)
		(mid 345.055703 -223.424242)
		(end 344.898726 -223.119442)
		(width 0.1143)
		(layer "In13.Cu")
		(net "GMI_CPU0_G0_CPU1_G2_TX_DN<15>")
	)
	(arc
		(start 126.666752 -227.00996)
		(mid 126.910079 -227.474526)
		(end 126.666752 -227.939092)
		(width 0.1143)
		(layer "In13.Cu")
		(net "GMI_CPU0_G0_CPU1_G2_TX_DN<15>")
	)
	(arc
		(start 126.597156 -239.319562)
		(mid 126.481729 -239.452938)
		(end 126.440184 -239.624362)
		(width 0.1143)
		(layer "In13.Cu")
		(net "GMI_CPU0_G0_CPU1_G2_TX_DN<15>")
	)
	(arc
		(start 126.597156 -227.979732)
		(mid 126.440179 -228.284532)
		(end 126.597156 -228.589332)
		(width 0.1143)
		(layer "In13.Cu")
		(net "GMI_CPU0_G0_CPU1_G2_TX_DN<15>")
	)
	(arc
		(start 344.898726 -230.208836)
		(mid 345.014153 -230.07546)
		(end 345.055698 -229.904036)
		(width 0.1143)
		(layer "In13.Cu")
		(net "GMI_CPU0_G0_CPU1_G2_TX_DN<15>")
	)
	(arc
		(start 344.82913 -237.658656)
		(mid 344.585803 -237.19409)
		(end 344.82913 -236.729524)
		(width 0.1143)
		(layer "In13.Cu")
		(net "GMI_CPU0_G0_CPU1_G2_TX_DN<15>")
	)
	(arc
		(start 125.97003 -240.434368)
		(mid 125.97004 -240.43767)
		(end 125.97003 -240.440972)
		(width 0.1143)
		(layer "In13.Cu")
		(net "GMI_CPU0_G0_CPU1_G2_TX_DN<15>")
	)
	(arc
		(start 345.055698 -231.524048)
		(mid 345.014732 -231.353642)
		(end 344.900758 -231.220518)
		(width 0.1143)
		(layer "In13.Cu")
		(net "GMI_CPU0_G0_CPU1_G2_TX_DN<15>")
	)
	(arc
		(start 126.666752 -223.769936)
		(mid 126.910079 -224.234502)
		(end 126.666752 -224.699068)
		(width 0.1143)
		(layer "In13.Cu")
		(net "GMI_CPU0_G0_CPU1_G2_TX_DN<15>")
	)
	(arc
		(start 345.988894 -241.17427)
		(mid 345.936845 -241.042751)
		(end 345.839796 -240.939828)
		(width 0.1143)
		(layer "In13.Cu")
		(net "GMI_CPU0_G0_CPU1_G2_TX_DN<15>")
	)
	(arc
		(start 126.666752 -235.109766)
		(mid 126.910079 -235.574332)
		(end 126.666752 -236.038898)
		(width 0.1143)
		(layer "In13.Cu")
		(net "GMI_CPU0_G0_CPU1_G2_TX_DN<15>")
	)
	(arc
		(start 344.898726 -225.349054)
		(mid 345.055703 -225.044254)
		(end 344.898726 -224.739454)
		(width 0.1143)
		(layer "In13.Cu")
		(net "GMI_CPU0_G0_CPU1_G2_TX_DN<15>")
	)
	(arc
		(start 126.595124 -229.60076)
		(mid 126.481195 -229.733907)
		(end 126.440184 -229.90429)
		(width 0.1143)
		(layer "In13.Cu")
		(net "GMI_CPU0_G0_CPU1_G2_TX_DN<15>")
	)
	(arc
		(start 345.29903 -240.088674)
		(mid 345.120217 -239.886324)
		(end 345.055698 -239.624108)
		(width 0.1143)
		(layer "In13.Cu")
		(net "GMI_CPU0_G0_CPU1_G2_TX_DN<15>")
	)
	(arc
		(start 126.666752 -231.869742)
		(mid 126.910079 -232.334308)
		(end 126.666752 -232.798874)
		(width 0.1143)
		(layer "In13.Cu")
		(net "GMI_CPU0_G0_CPU1_G2_TX_DN<15>")
	)
	(arc
		(start 126.597156 -223.119696)
		(mid 126.440179 -223.424496)
		(end 126.597156 -223.729296)
		(width 0.1143)
		(layer "In13.Cu")
		(net "GMI_CPU0_G0_CPU1_G2_TX_DN<15>")
	)
	(arc
		(start 126.666752 -228.629972)
		(mid 126.910079 -229.094538)
		(end 126.666752 -229.559104)
		(width 0.1143)
		(layer "In13.Cu")
		(net "GMI_CPU0_G0_CPU1_G2_TX_DN<15>")
	)
	(arc
		(start 126.597156 -237.69955)
		(mid 126.440179 -238.00435)
		(end 126.597156 -238.30915)
		(width 0.1143)
		(layer "In13.Cu")
		(net "GMI_CPU0_G0_CPU1_G2_TX_DN<15>")
	)
	(arc
		(start 126.664212 -230.248206)
		(mid 126.844864 -230.450951)
		(end 126.910084 -230.71455)
		(width 0.1143)
		(layer "In13.Cu")
		(net "GMI_CPU0_G0_CPU1_G2_TX_DN<15>")
	)
	(arc
		(start 126.666752 -238.34979)
		(mid 126.910079 -238.814356)
		(end 126.666752 -239.278922)
		(width 0.1143)
		(layer "In13.Cu")
		(net "GMI_CPU0_G0_CPU1_G2_TX_DN<15>")
	)
	(arc
		(start 344.898726 -228.589078)
		(mid 345.055703 -228.284278)
		(end 344.898726 -227.979478)
		(width 0.1143)
		(layer "In13.Cu")
		(net "GMI_CPU0_G0_CPU1_G2_TX_DN<15>")
	)
	(arc
		(start 126.666752 -233.489754)
		(mid 126.910079 -233.95432)
		(end 126.666752 -234.418886)
		(width 0.1143)
		(layer "In13.Cu")
		(net "GMI_CPU0_G0_CPU1_G2_TX_DN<15>")
	)
	(arc
		(start 344.898726 -231.828848)
		(mid 345.014153 -231.695472)
		(end 345.055698 -231.524048)
		(width 0.1143)
		(layer "In13.Cu")
		(net "GMI_CPU0_G0_CPU1_G2_TX_DN<15>")
	)
	(arc
		(start 345.525852 -240.434114)
		(mid 345.474807 -240.2718)
		(end 345.374468 -240.134394)
		(width 0.1143)
		(layer "In13.Cu")
		(net "GMI_CPU0_G0_CPU1_G2_TX_DN<15>")
	)
	(arc
		(start 345.771724 -240.900458)
		(mid 345.763546 -240.894815)
		(end 345.755468 -240.889028)
		(width 0.1143)
		(layer "In13.Cu")
		(net "GMI_CPU0_G0_CPU1_G2_TX_DN<15>")
	)
	(arc
		(start 344.82913 -232.79862)
		(mid 344.585803 -232.334054)
		(end 344.82913 -231.869488)
		(width 0.1143)
		(layer "In13.Cu")
		(net "GMI_CPU0_G0_CPU1_G2_TX_DN<15>")
	)
	(arc
		(start 126.440184 -239.624362)
		(mid 126.375669 -239.886581)
		(end 126.196852 -240.088928)
		(width 0.1143)
		(layer "In13.Cu")
		(net "GMI_CPU0_G0_CPU1_G2_TX_DN<15>")
	)
	(arc
		(start 344.82913 -223.078802)
		(mid 344.585803 -222.614236)
		(end 344.82913 -222.14967)
		(width 0.1143)
		(layer "In13.Cu")
		(net "GMI_CPU0_G0_CPU1_G2_TX_DN<15>")
	)
	(arc
		(start 344.898726 -238.308896)
		(mid 345.055703 -238.004096)
		(end 344.898726 -237.699296)
		(width 0.1143)
		(layer "In13.Cu")
		(net "GMI_CPU0_G0_CPU1_G2_TX_DN<15>")
	)
	(arc
		(start 345.055698 -239.624108)
		(mid 345.014149 -239.452686)
		(end 344.898726 -239.319308)
		(width 0.1143)
		(layer "In13.Cu")
		(net "GMI_CPU0_G0_CPU1_G2_TX_DN<15>")
	)
	(arc
		(start 125.740414 -240.889282)
		(mid 125.732336 -240.895068)
		(end 125.724158 -240.900712)
		(width 0.1143)
		(layer "In13.Cu")
		(net "GMI_CPU0_G0_CPU1_G2_TX_DN<15>")
	)
	(arc
		(start 125.656086 -240.940082)
		(mid 125.558951 -241.042951)
		(end 125.506988 -241.174524)
		(width 0.1143)
		(layer "In13.Cu")
		(net "GMI_CPU0_G0_CPU1_G2_TX_DN<15>")
	)
	(arc
		(start 344.82913 -227.938838)
		(mid 344.585803 -227.474272)
		(end 344.82913 -227.009706)
		(width 0.1143)
		(layer "In13.Cu")
		(net "GMI_CPU0_G0_CPU1_G2_TX_DN<15>")
	)
	(arc
		(start 126.666752 -236.729778)
		(mid 126.910079 -237.194344)
		(end 126.666752 -237.65891)
		(width 0.1143)
		(layer "In13.Cu")
		(net "GMI_CPU0_G0_CPU1_G2_TX_DN<15>")
	)
	(arc
		(start 344.898726 -226.969066)
		(mid 345.055703 -226.664266)
		(end 344.898726 -226.359466)
		(width 0.1143)
		(layer "In13.Cu")
		(net "GMI_CPU0_G0_CPU1_G2_TX_DN<15>")
	)
	(arc
		(start 344.82913 -224.698814)
		(mid 344.585803 -224.234248)
		(end 344.82913 -223.769682)
		(width 0.1143)
		(layer "In13.Cu")
		(net "GMI_CPU0_G0_CPU1_G2_TX_DN<15>")
	)
	(arc
		(start 126.440184 -229.90429)
		(mid 126.481733 -230.075712)
		(end 126.597156 -230.20909)
		(width 0.1143)
		(layer "In13.Cu")
		(net "GMI_CPU0_G0_CPU1_G2_TX_DN<15>")
	)
	(arc
		(start 344.585798 -230.714296)
		(mid 344.651034 -230.450705)
		(end 344.83167 -230.247952)
		(width 0.1143)
		(layer "In13.Cu")
		(net "GMI_CPU0_G0_CPU1_G2_TX_DN<15>")
	)
	(arc
		(start 344.82913 -231.178862)
		(mid 344.650317 -230.976512)
		(end 344.585798 -230.714296)
		(width 0.1143)
		(layer "In13.Cu")
		(net "GMI_CPU0_G0_CPU1_G2_TX_DN<15>")
	)
	(arc
		(start 126.130558 -240.127536)
		(mid 126.125958 -240.131057)
		(end 126.121414 -240.134648)
		(width 0.1143)
		(layer "In13.Cu")
		(net "GMI_CPU0_G0_CPU1_G2_TX_DN<15>")
	)
	(arc
		(start 344.82913 -226.318826)
		(mid 344.585803 -225.85426)
		(end 344.82913 -225.389694)
		(width 0.1143)
		(layer "In13.Cu")
		(net "GMI_CPU0_G0_CPU1_G2_TX_DN<15>")
	)
	(arc
		(start 344.82913 -236.038644)
		(mid 344.585803 -235.574078)
		(end 344.82913 -235.109512)
		(width 0.1143)
		(layer "In13.Cu")
		(net "GMI_CPU0_G0_CPU1_G2_TX_DN<15>")
	)
	(arc
		(start 125.97003 -240.440972)
		(mid 125.905158 -240.690714)
		(end 125.740414 -240.889282)
		(width 0.1143)
		(layer "In13.Cu")
		(net "GMI_CPU0_G0_CPU1_G2_TX_DN<15>")
	)
	(arc
		(start 345.525852 -240.440718)
		(mid 345.525842 -240.437416)
		(end 345.525852 -240.434114)
		(width 0.1143)
		(layer "In13.Cu")
		(net "GMI_CPU0_G0_CPU1_G2_TX_DN<15>")
	)
	(arc
		(start 126.910084 -230.71455)
		(mid 126.845569 -230.976769)
		(end 126.666752 -231.179116)
		(width 0.1143)
		(layer "In13.Cu")
		(net "GMI_CPU0_G0_CPU1_G2_TX_DN<15>")
	)
	(arc
		(start 126.595124 -231.220772)
		(mid 126.481195 -231.353919)
		(end 126.440184 -231.524302)
		(width 0.1143)
		(layer "In13.Cu")
		(net "GMI_CPU0_G0_CPU1_G2_TX_DN<15>")
	)
	(arc
		(start 344.898726 -222.10903)
		(mid 345.014153 -221.975654)
		(end 345.055698 -221.80423)
		(width 0.1143)
		(layer "In13.Cu")
		(net "GMI_CPU0_G0_CPU1_G2_TX_DN<15>")
	)
	(arc
		(start 344.898726 -233.44886)
		(mid 345.055703 -233.14406)
		(end 344.898726 -232.83926)
		(width 0.1143)
		(layer "In13.Cu")
		(net "GMI_CPU0_G0_CPU1_G2_TX_DN<15>")
	)
	(arc
		(start 126.597156 -232.839514)
		(mid 126.440179 -233.144314)
		(end 126.597156 -233.449114)
		(width 0.1143)
		(layer "In13.Cu")
		(net "GMI_CPU0_G0_CPU1_G2_TX_DN<15>")
	)
	(arc
		(start 344.898726 -235.068872)
		(mid 345.055703 -234.764072)
		(end 344.898726 -234.459272)
		(width 0.1143)
		(layer "In13.Cu")
		(net "GMI_CPU0_G0_CPU1_G2_TX_DN<15>")
	)
	(arc
		(start 126.597156 -236.079538)
		(mid 126.440179 -236.384338)
		(end 126.597156 -236.689138)
		(width 0.1143)
		(layer "In13.Cu")
		(net "GMI_CPU0_G0_CPU1_G2_TX_DN<15>")
	)
	(arc
		(start 126.440184 -221.804484)
		(mid 126.481733 -221.975906)
		(end 126.597156 -222.109284)
		(width 0.1143)
		(layer "In13.Cu")
		(net "GMI_CPU0_G0_CPU1_G2_TX_DN<15>")
	)
	(segment
		(start 125.407928 -239.8903)
		(end 125.87478 -239.624362)
		(width 0.12954)
		(layer "F.Cu")
		(net "GMI_CPU0_G0_CPU1_G2_TX_DN<14>")
	)
	(segment
		(start 346.087954 -239.890046)
		(end 345.621102 -239.624108)
		(width 0.12954)
		(layer "F.Cu")
		(net "GMI_CPU0_G0_CPU1_G2_TX_DN<14>")
	)
	(segment
		(start 125.687582 -239.301782)
		(end 125.657102 -239.319562)
		(width 0.1143)
		(layer "In13.Cu")
		(net "GMI_CPU0_G0_CPU1_G2_TX_DN<14>")
	)
	(segment
		(start 345.810078 -238.325406)
		(end 345.812618 -238.324136)
		(width 0.1143)
		(layer "In13.Cu")
		(net "GMI_CPU0_G0_CPU1_G2_TX_DN<14>")
	)
	(segment
		(start 345.815158 -237.68558)
		(end 345.814142 -237.685072)
		(width 0.1143)
		(layer "In13.Cu")
		(net "GMI_CPU0_G0_CPU1_G2_TX_DN<14>")
	)
	(segment
		(start 345.80957 -226.342448)
		(end 345.769184 -226.31908)
		(width 0.1143)
		(layer "In13.Cu")
		(net "GMI_CPU0_G0_CPU1_G2_TX_DN<14>")
	)
	(segment
		(start 345.808808 -228.60635)
		(end 345.810078 -228.605588)
		(width 0.1143)
		(layer "In13.Cu")
		(net "GMI_CPU0_G0_CPU1_G2_TX_DN<14>")
	)
	(segment
		(start 149.48027 -201.590656)
		(end 146.974814 -202.350116)
		(width 0.14224)
		(layer "In13.Cu")
		(net "GMI_CPU0_G0_CPU1_G2_TX_DN<14>")
	)
	(segment
		(start 159.052768 -193.742818)
		(end 159.033718 -193.935604)
		(width 0.14224)
		(layer "In13.Cu")
		(net "GMI_CPU0_G0_CPU1_G2_TX_DN<14>")
	)
	(segment
		(start 156.435806 -195.888102)
		(end 156.416756 -196.081142)
		(width 0.14224)
		(layer "In13.Cu")
		(net "GMI_CPU0_G0_CPU1_G2_TX_DN<14>")
	)
	(segment
		(start 125.687582 -226.34194)
		(end 125.657102 -226.35972)
		(width 0.1143)
		(layer "In13.Cu")
		(net "GMI_CPU0_G0_CPU1_G2_TX_DN<14>")
	)
	(segment
		(start 345.81338 -238.323628)
		(end 345.814904 -238.322866)
		(width 0.1143)
		(layer "In13.Cu")
		(net "GMI_CPU0_G0_CPU1_G2_TX_DN<14>")
	)
	(segment
		(start 345.808808 -238.326168)
		(end 345.810078 -238.325406)
		(width 0.1143)
		(layer "In13.Cu")
		(net "GMI_CPU0_G0_CPU1_G2_TX_DN<14>")
	)
	(segment
		(start 345.750642 -225.402648)
		(end 345.769184 -225.38944)
		(width 0.1143)
		(layer "In13.Cu")
		(net "GMI_CPU0_G0_CPU1_G2_TX_DN<14>")
	)
	(segment
		(start 345.126056 -219.322142)
		(end 317.09868 -196.341746)
		(width 0.14224)
		(layer "In13.Cu")
		(net "GMI_CPU0_G0_CPU1_G2_TX_DN<14>")
	)
	(segment
		(start 345.989148 -239.554258)
		(end 345.989148 -239.55375)
		(width 0.1143)
		(layer "In13.Cu")
		(net "GMI_CPU0_G0_CPU1_G2_TX_DN<14>")
	)
	(segment
		(start 125.726698 -236.038898)
		(end 125.687582 -236.061758)
		(width 0.1143)
		(layer "In13.Cu")
		(net "GMI_CPU0_G0_CPU1_G2_TX_DN<14>")
	)
	(segment
		(start 125.726698 -223.079056)
		(end 125.687582 -223.101916)
		(width 0.1143)
		(layer "In13.Cu")
		(net "GMI_CPU0_G0_CPU1_G2_TX_DN<14>")
	)
	(segment
		(start 156.435806 -195.888356)
		(end 156.435806 -195.888102)
		(width 0.14224)
		(layer "In13.Cu")
		(net "GMI_CPU0_G0_CPU1_G2_TX_DN<14>")
	)
	(segment
		(start 125.687582 -223.101916)
		(end 125.657102 -223.119696)
		(width 0.1143)
		(layer "In13.Cu")
		(net "GMI_CPU0_G0_CPU1_G2_TX_DN<14>")
	)
	(segment
		(start 345.811602 -236.063536)
		(end 345.810078 -236.062774)
		(width 0.1143)
		(layer "In13.Cu")
		(net "GMI_CPU0_G0_CPU1_G2_TX_DN<14>")
	)
	(segment
		(start 345.808808 -225.366326)
		(end 345.810078 -225.365564)
		(width 0.1143)
		(layer "In13.Cu")
		(net "GMI_CPU0_G0_CPU1_G2_TX_DN<14>")
	)
	(segment
		(start 207.257142 -190.291212)
		(end 162.630612 -190.480442)
		(width 0.14224)
		(layer "In13.Cu")
		(net "GMI_CPU0_G0_CPU1_G2_TX_DN<14>")
	)
	(segment
		(start 345.808046 -236.061504)
		(end 345.768422 -236.038644)
		(width 0.1143)
		(layer "In13.Cu")
		(net "GMI_CPU0_G0_CPU1_G2_TX_DN<14>")
	)
	(segment
		(start 345.808046 -226.986846)
		(end 345.808808 -226.986338)
		(width 0.1143)
		(layer "In13.Cu")
		(net "GMI_CPU0_G0_CPU1_G2_TX_DN<14>")
	)
	(segment
		(start 345.814904 -225.363024)
		(end 345.839796 -225.348546)
		(width 0.1143)
		(layer "In13.Cu")
		(net "GMI_CPU0_G0_CPU1_G2_TX_DN<14>")
	)
	(segment
		(start 345.814904 -226.983036)
		(end 345.839796 -226.968558)
		(width 0.1143)
		(layer "In13.Cu")
		(net "GMI_CPU0_G0_CPU1_G2_TX_DN<14>")
	)
	(segment
		(start 317.09868 -196.341746)
		(end 308.646068 -190.391796)
		(width 0.14224)
		(layer "In13.Cu")
		(net "GMI_CPU0_G0_CPU1_G2_TX_DN<14>")
	)
	(segment
		(start 155.02128 -197.047866)
		(end 154.691334 -197.318376)
		(width 0.14224)
		(layer "In13.Cu")
		(net "GMI_CPU0_G0_CPU1_G2_TX_DN<14>")
	)
	(segment
		(start 345.810078 -223.745552)
		(end 345.812618 -223.744282)
		(width 0.1143)
		(layer "In13.Cu")
		(net "GMI_CPU0_G0_CPU1_G2_TX_DN<14>")
	)
	(segment
		(start 345.80322 -239.298734)
		(end 345.802712 -239.29848)
		(width 0.1143)
		(layer "In13.Cu")
		(net "GMI_CPU0_G0_CPU1_G2_TX_DN<14>")
	)
	(segment
		(start 345.955112 -220.716856)
		(end 345.126056 -219.322142)
		(width 0.14224)
		(layer "In13.Cu")
		(net "GMI_CPU0_G0_CPU1_G2_TX_DN<14>")
	)
	(segment
		(start 154.342084 -197.78218)
		(end 154.149044 -197.76313)
		(width 0.14224)
		(layer "In13.Cu")
		(net "GMI_CPU0_G0_CPU1_G2_TX_DN<14>")
	)
	(segment
		(start 345.954604 -220.97746)
		(end 345.954604 -220.717364)
		(width 0.14224)
		(layer "In13.Cu")
		(net "GMI_CPU0_G0_CPU1_G2_TX_DN<14>")
	)
	(segment
		(start 125.545342 -221.547436)
		(end 125.545342 -221.575884)
		(width 0.1143)
		(layer "In13.Cu")
		(net "GMI_CPU0_G0_CPU1_G2_TX_DN<14>")
	)
	(segment
		(start 126.56947 -219.08135)
		(end 125.54585 -220.88856)
		(width 0.14224)
		(layer "In13.Cu")
		(net "GMI_CPU0_G0_CPU1_G2_TX_DN<14>")
	)
	(segment
		(start 345.810078 -236.705394)
		(end 345.812618 -236.704124)
		(width 0.1143)
		(layer "In13.Cu")
		(net "GMI_CPU0_G0_CPU1_G2_TX_DN<14>")
	)
	(segment
		(start 125.687582 -234.441746)
		(end 125.657102 -234.459526)
		(width 0.1143)
		(layer "In13.Cu")
		(net "GMI_CPU0_G0_CPU1_G2_TX_DN<14>")
	)
	(segment
		(start 345.954604 -220.717364)
		(end 345.955112 -220.716856)
		(width 0.14224)
		(layer "In13.Cu")
		(net "GMI_CPU0_G0_CPU1_G2_TX_DN<14>")
	)
	(segment
		(start 161.377884 -191.836294)
		(end 160.79724 -192.312544)
		(width 0.14224)
		(layer "In13.Cu")
		(net "GMI_CPU0_G0_CPU1_G2_TX_DN<14>")
	)
	(segment
		(start 125.726698 -227.939092)
		(end 125.687582 -227.961952)
		(width 0.1143)
		(layer "In13.Cu")
		(net "GMI_CPU0_G0_CPU1_G2_TX_DN<14>")
	)
	(segment
		(start 345.995752 -221.791022)
		(end 345.995752 -221.253558)
		(width 0.1143)
		(layer "In13.Cu")
		(net "GMI_CPU0_G0_CPU1_G2_TX_DN<14>")
	)
	(segment
		(start 125.652784 -222.103442)
		(end 125.687328 -222.127064)
		(width 0.1143)
		(layer "In13.Cu")
		(net "GMI_CPU0_G0_CPU1_G2_TX_DN<14>")
	)
	(segment
		(start 345.741244 -231.8893)
		(end 345.76893 -231.869234)
		(width 0.1143)
		(layer "In13.Cu")
		(net "GMI_CPU0_G0_CPU1_G2_TX_DN<14>")
	)
	(segment
		(start 125.657102 -226.96932)
		(end 125.687582 -226.9871)
		(width 0.1143)
		(layer "In13.Cu")
		(net "GMI_CPU0_G0_CPU1_G2_TX_DN<14>")
	)
	(segment
		(start 155.89377 -196.332856)
		(end 155.56357 -196.603366)
		(width 0.14224)
		(layer "In13.Cu")
		(net "GMI_CPU0_G0_CPU1_G2_TX_DN<14>")
	)
	(segment
		(start 125.54585 -220.88856)
		(end 125.54585 -221.157038)
		(width 0.14224)
		(layer "In13.Cu")
		(net "GMI_CPU0_G0_CPU1_G2_TX_DN<14>")
	)
	(segment
		(start 125.687582 -228.607112)
		(end 125.726698 -228.629972)
		(width 0.1143)
		(layer "In13.Cu")
		(net "GMI_CPU0_G0_CPU1_G2_TX_DN<14>")
	)
	(segment
		(start 156.086556 -196.351906)
		(end 155.89377 -196.332856)
		(width 0.14224)
		(layer "In13.Cu")
		(net "GMI_CPU0_G0_CPU1_G2_TX_DN<14>")
	)
	(segment
		(start 159.575754 -193.491612)
		(end 159.382714 -193.472308)
		(width 0.14224)
		(layer "In13.Cu")
		(net "GMI_CPU0_G0_CPU1_G2_TX_DN<14>")
	)
	(segment
		(start 345.808046 -229.58171)
		(end 345.808046 -229.581202)
		(width 0.1143)
		(layer "In13.Cu")
		(net "GMI_CPU0_G0_CPU1_G2_TX_DN<14>")
	)
	(segment
		(start 345.989148 -239.55375)
		(end 345.977464 -239.491012)
		(width 0.1143)
		(layer "In13.Cu")
		(net "GMI_CPU0_G0_CPU1_G2_TX_DN<14>")
	)
	(segment
		(start 345.81338 -236.064552)
		(end 345.812364 -236.064044)
		(width 0.1143)
		(layer "In13.Cu")
		(net "GMI_CPU0_G0_CPU1_G2_TX_DN<14>")
	)
	(segment
		(start 125.687582 -229.581964)
		(end 125.65507 -229.60076)
		(width 0.1143)
		(layer "In13.Cu")
		(net "GMI_CPU0_G0_CPU1_G2_TX_DN<14>")
	)
	(segment
		(start 345.81211 -226.343972)
		(end 345.811348 -226.343464)
		(width 0.1143)
		(layer "In13.Cu")
		(net "GMI_CPU0_G0_CPU1_G2_TX_DN<14>")
	)
	(segment
		(start 158.703518 -194.206622)
		(end 158.658814 -194.20205)
		(width 0.14224)
		(layer "In13.Cu")
		(net "GMI_CPU0_G0_CPU1_G2_TX_DN<14>")
	)
	(segment
		(start 345.812618 -223.744282)
		(end 345.81338 -223.743774)
		(width 0.1143)
		(layer "In13.Cu")
		(net "GMI_CPU0_G0_CPU1_G2_TX_DN<14>")
	)
	(segment
		(start 125.687582 -225.367088)
		(end 125.726698 -225.389948)
		(width 0.1143)
		(layer "In13.Cu")
		(net "GMI_CPU0_G0_CPU1_G2_TX_DN<14>")
	)
	(segment
		(start 154.149044 -197.76313)
		(end 149.48027 -201.590656)
		(width 0.14224)
		(layer "In13.Cu")
		(net "GMI_CPU0_G0_CPU1_G2_TX_DN<14>")
	)
	(segment
		(start 345.808046 -224.721674)
		(end 345.771724 -224.700592)
		(width 0.1143)
		(layer "In13.Cu")
		(net "GMI_CPU0_G0_CPU1_G2_TX_DN<14>")
	)
	(segment
		(start 345.815412 -226.34575)
		(end 345.81465 -226.345242)
		(width 0.1143)
		(layer "In13.Cu")
		(net "GMI_CPU0_G0_CPU1_G2_TX_DN<14>")
	)
	(segment
		(start 125.687582 -231.846882)
		(end 125.726698 -231.869742)
		(width 0.1143)
		(layer "In13.Cu")
		(net "GMI_CPU0_G0_CPU1_G2_TX_DN<14>")
	)
	(segment
		(start 125.726698 -226.31908)
		(end 125.687582 -226.34194)
		(width 0.1143)
		(layer "In13.Cu")
		(net "GMI_CPU0_G0_CPU1_G2_TX_DN<14>")
	)
	(segment
		(start 345.802712 -239.29848)
		(end 345.768422 -239.278668)
		(width 0.1143)
		(layer "In13.Cu")
		(net "GMI_CPU0_G0_CPU1_G2_TX_DN<14>")
	)
	(segment
		(start 125.657102 -230.20909)
		(end 125.724158 -230.248206)
		(width 0.1143)
		(layer "In13.Cu")
		(net "GMI_CPU0_G0_CPU1_G2_TX_DN<14>")
	)
	(segment
		(start 345.80703 -239.30102)
		(end 345.804998 -239.29975)
		(width 0.1143)
		(layer "In13.Cu")
		(net "GMI_CPU0_G0_CPU1_G2_TX_DN<14>")
	)
	(segment
		(start 345.839796 -234.45978)
		(end 345.808808 -234.442)
		(width 0.1143)
		(layer "In13.Cu")
		(net "GMI_CPU0_G0_CPU1_G2_TX_DN<14>")
	)
	(segment
		(start 125.657102 -235.069126)
		(end 125.687582 -235.086906)
		(width 0.1143)
		(layer "In13.Cu")
		(net "GMI_CPU0_G0_CPU1_G2_TX_DN<14>")
	)
	(segment
		(start 345.814904 -223.743012)
		(end 345.839796 -223.728534)
		(width 0.1143)
		(layer "In13.Cu")
		(net "GMI_CPU0_G0_CPU1_G2_TX_DN<14>")
	)
	(segment
		(start 345.80957 -227.96246)
		(end 345.769184 -227.939092)
		(width 0.1143)
		(layer "In13.Cu")
		(net "GMI_CPU0_G0_CPU1_G2_TX_DN<14>")
	)
	(segment
		(start 157.288992 -195.366132)
		(end 156.958792 -195.636896)
		(width 0.14224)
		(layer "In13.Cu")
		(net "GMI_CPU0_G0_CPU1_G2_TX_DN<14>")
	)
	(segment
		(start 155.21432 -197.06717)
		(end 155.02128 -197.047866)
		(width 0.14224)
		(layer "In13.Cu")
		(net "GMI_CPU0_G0_CPU1_G2_TX_DN<14>")
	)
	(segment
		(start 161.691066 -191.251078)
		(end 161.377884 -191.836294)
		(width 0.14224)
		(layer "In13.Cu")
		(net "GMI_CPU0_G0_CPU1_G2_TX_DN<14>")
	)
	(segment
		(start 125.726698 -231.179116)
		(end 125.687582 -231.201976)
		(width 0.1143)
		(layer "In13.Cu")
		(net "GMI_CPU0_G0_CPU1_G2_TX_DN<14>")
	)
	(segment
		(start 345.776042 -230.245158)
		(end 345.80449 -230.228648)
		(width 0.1143)
		(layer "In13.Cu")
		(net "GMI_CPU0_G0_CPU1_G2_TX_DN<14>")
	)
	(segment
		(start 345.812364 -237.684056)
		(end 345.811602 -237.683548)
		(width 0.1143)
		(layer "In13.Cu")
		(net "GMI_CPU0_G0_CPU1_G2_TX_DN<14>")
	)
	(segment
		(start 125.726698 -234.418886)
		(end 125.687582 -234.441746)
		(width 0.1143)
		(layer "In13.Cu")
		(net "GMI_CPU0_G0_CPU1_G2_TX_DN<14>")
	)
	(segment
		(start 125.545342 -221.575884)
		(end 125.499622 -221.621604)
		(width 0.1143)
		(layer "In13.Cu")
		(net "GMI_CPU0_G0_CPU1_G2_TX_DN<14>")
	)
	(segment
		(start 345.76893 -228.629464)
		(end 345.805252 -228.608636)
		(width 0.1143)
		(layer "In13.Cu")
		(net "GMI_CPU0_G0_CPU1_G2_TX_DN<14>")
	)
	(segment
		(start 345.811602 -237.683548)
		(end 345.810078 -237.682786)
		(width 0.1143)
		(layer "In13.Cu")
		(net "GMI_CPU0_G0_CPU1_G2_TX_DN<14>")
	)
	(segment
		(start 125.657102 -225.349308)
		(end 125.687582 -225.367088)
		(width 0.1143)
		(layer "In13.Cu")
		(net "GMI_CPU0_G0_CPU1_G2_TX_DN<14>")
	)
	(segment
		(start 345.769946 -237.659672)
		(end 345.754452 -237.648496)
		(width 0.1143)
		(layer "In13.Cu")
		(net "GMI_CPU0_G0_CPU1_G2_TX_DN<14>")
	)
	(segment
		(start 159.033718 -193.935604)
		(end 158.703518 -194.206622)
		(width 0.14224)
		(layer "In13.Cu")
		(net "GMI_CPU0_G0_CPU1_G2_TX_DN<14>")
	)
	(segment
		(start 345.950032 -221.207838)
		(end 345.950032 -221.17939)
		(width 0.1143)
		(layer "In13.Cu")
		(net "GMI_CPU0_G0_CPU1_G2_TX_DN<14>")
	)
	(segment
		(start 125.687582 -226.9871)
		(end 125.726698 -227.00996)
		(width 0.1143)
		(layer "In13.Cu")
		(net "GMI_CPU0_G0_CPU1_G2_TX_DN<14>")
	)
	(segment
		(start 345.950032 -221.17939)
		(end 345.950032 -221.022926)
		(width 0.14224)
		(layer "In13.Cu")
		(net "GMI_CPU0_G0_CPU1_G2_TX_DN<14>")
	)
	(segment
		(start 345.808046 -223.746822)
		(end 345.808808 -223.746314)
		(width 0.1143)
		(layer "In13.Cu")
		(net "GMI_CPU0_G0_CPU1_G2_TX_DN<14>")
	)
	(segment
		(start 125.499622 -221.621604)
		(end 125.499622 -221.804484)
		(width 0.1143)
		(layer "In13.Cu")
		(net "GMI_CPU0_G0_CPU1_G2_TX_DN<14>")
	)
	(segment
		(start 345.805506 -236.708442)
		(end 345.808046 -236.706664)
		(width 0.1143)
		(layer "In13.Cu")
		(net "GMI_CPU0_G0_CPU1_G2_TX_DN<14>")
	)
	(segment
		(start 345.808808 -229.582218)
		(end 345.808046 -229.58171)
		(width 0.1143)
		(layer "In13.Cu")
		(net "GMI_CPU0_G0_CPU1_G2_TX_DN<14>")
	)
	(segment
		(start 345.808046 -234.441492)
		(end 345.771724 -234.42041)
		(width 0.1143)
		(layer "In13.Cu")
		(net "GMI_CPU0_G0_CPU1_G2_TX_DN<14>")
	)
	(segment
		(start 345.812618 -226.984306)
		(end 345.81338 -226.983798)
		(width 0.1143)
		(layer "In13.Cu")
		(net "GMI_CPU0_G0_CPU1_G2_TX_DN<14>")
	)
	(segment
		(start 345.839796 -237.699804)
		(end 345.815158 -237.68558)
		(width 0.1143)
		(layer "In13.Cu")
		(net "GMI_CPU0_G0_CPU1_G2_TX_DN<14>")
	)
	(segment
		(start 262.765794 -190.013844)
		(end 251.423424 -192.01384)
		(width 0.14224)
		(layer "In13.Cu")
		(net "GMI_CPU0_G0_CPU1_G2_TX_DN<14>")
	)
	(segment
		(start 345.814904 -238.322866)
		(end 345.839796 -238.308388)
		(width 0.1143)
		(layer "In13.Cu")
		(net "GMI_CPU0_G0_CPU1_G2_TX_DN<14>")
	)
	(segment
		(start 345.814142 -223.105218)
		(end 345.81338 -223.10471)
		(width 0.1143)
		(layer "In13.Cu")
		(net "GMI_CPU0_G0_CPU1_G2_TX_DN<14>")
	)
	(segment
		(start 345.805252 -228.608636)
		(end 345.808046 -228.606858)
		(width 0.1143)
		(layer "In13.Cu")
		(net "GMI_CPU0_G0_CPU1_G2_TX_DN<14>")
	)
	(segment
		(start 345.810332 -227.962968)
		(end 345.80957 -227.96246)
		(width 0.1143)
		(layer "In13.Cu")
		(net "GMI_CPU0_G0_CPU1_G2_TX_DN<14>")
	)
	(segment
		(start 345.808808 -234.442)
		(end 345.808046 -234.441492)
		(width 0.1143)
		(layer "In13.Cu")
		(net "GMI_CPU0_G0_CPU1_G2_TX_DN<14>")
	)
	(segment
		(start 156.766006 -195.617846)
		(end 156.435806 -195.888356)
		(width 0.14224)
		(layer "In13.Cu")
		(net "GMI_CPU0_G0_CPU1_G2_TX_DN<14>")
	)
	(segment
		(start 210.794092 -190.91529)
		(end 207.257142 -190.291212)
		(width 0.14224)
		(layer "In13.Cu")
		(net "GMI_CPU0_G0_CPU1_G2_TX_DN<14>")
	)
	(segment
		(start 156.765752 -195.617592)
		(end 156.766006 -195.617846)
		(width 0.14224)
		(layer "In13.Cu")
		(net "GMI_CPU0_G0_CPU1_G2_TX_DN<14>")
	)
	(segment
		(start 345.769184 -227.939092)
		(end 345.741752 -227.919534)
		(width 0.1143)
		(layer "In13.Cu")
		(net "GMI_CPU0_G0_CPU1_G2_TX_DN<14>")
	)
	(segment
		(start 345.815158 -236.065568)
		(end 345.814142 -236.06506)
		(width 0.1143)
		(layer "In13.Cu")
		(net "GMI_CPU0_G0_CPU1_G2_TX_DN<14>")
	)
	(segment
		(start 345.839796 -223.11995)
		(end 345.815158 -223.105726)
		(width 0.1143)
		(layer "In13.Cu")
		(net "GMI_CPU0_G0_CPU1_G2_TX_DN<14>")
	)
	(segment
		(start 345.81338 -225.363786)
		(end 345.814904 -225.363024)
		(width 0.1143)
		(layer "In13.Cu")
		(net "GMI_CPU0_G0_CPU1_G2_TX_DN<14>")
	)
	(segment
		(start 345.81338 -223.10471)
		(end 345.812364 -223.104202)
		(width 0.1143)
		(layer "In13.Cu")
		(net "GMI_CPU0_G0_CPU1_G2_TX_DN<14>")
	)
	(segment
		(start 345.814142 -237.685072)
		(end 345.81338 -237.684564)
		(width 0.1143)
		(layer "In13.Cu")
		(net "GMI_CPU0_G0_CPU1_G2_TX_DN<14>")
	)
	(segment
		(start 345.814904 -228.603048)
		(end 345.839796 -228.58857)
		(width 0.1143)
		(layer "In13.Cu")
		(net "GMI_CPU0_G0_CPU1_G2_TX_DN<14>")
	)
	(segment
		(start 125.54585 -221.157038)
		(end 125.545342 -221.157546)
		(width 0.14224)
		(layer "In13.Cu")
		(net "GMI_CPU0_G0_CPU1_G2_TX_DN<14>")
	)
	(segment
		(start 345.812618 -228.604318)
		(end 345.81338 -228.60381)
		(width 0.1143)
		(layer "In13.Cu")
		(net "GMI_CPU0_G0_CPU1_G2_TX_DN<14>")
	)
	(segment
		(start 345.81338 -223.743774)
		(end 345.814904 -223.743012)
		(width 0.1143)
		(layer "In13.Cu")
		(net "GMI_CPU0_G0_CPU1_G2_TX_DN<14>")
	)
	(segment
		(start 125.657102 -233.449114)
		(end 125.687582 -233.466894)
		(width 0.1143)
		(layer "In13.Cu")
		(net "GMI_CPU0_G0_CPU1_G2_TX_DN<14>")
	)
	(segment
		(start 345.808046 -236.706664)
		(end 345.808808 -236.706156)
		(width 0.1143)
		(layer "In13.Cu")
		(net "GMI_CPU0_G0_CPU1_G2_TX_DN<14>")
	)
	(segment
		(start 345.768422 -236.038644)
		(end 345.752166 -236.026706)
		(width 0.1143)
		(layer "In13.Cu")
		(net "GMI_CPU0_G0_CPU1_G2_TX_DN<14>")
	)
	(segment
		(start 125.726698 -232.798874)
		(end 125.687582 -232.821734)
		(width 0.1143)
		(layer "In13.Cu")
		(net "GMI_CPU0_G0_CPU1_G2_TX_DN<14>")
	)
	(segment
		(start 157.638242 -194.902582)
		(end 157.308296 -195.173092)
		(width 0.14224)
		(layer "In13.Cu")
		(net "GMI_CPU0_G0_CPU1_G2_TX_DN<14>")
	)
	(segment
		(start 345.771724 -233.487722)
		(end 345.808046 -233.46664)
		(width 0.1143)
		(layer "In13.Cu")
		(net "GMI_CPU0_G0_CPU1_G2_TX_DN<14>")
	)
	(segment
		(start 345.769184 -225.38944)
		(end 345.805252 -225.368612)
		(width 0.1143)
		(layer "In13.Cu")
		(net "GMI_CPU0_G0_CPU1_G2_TX_DN<14>")
	)
	(segment
		(start 125.687582 -238.32693)
		(end 125.726698 -238.34979)
		(width 0.1143)
		(layer "In13.Cu")
		(net "GMI_CPU0_G0_CPU1_G2_TX_DN<14>")
	)
	(segment
		(start 345.810078 -236.062774)
		(end 345.808808 -236.062012)
		(width 0.1143)
		(layer "In13.Cu")
		(net "GMI_CPU0_G0_CPU1_G2_TX_DN<14>")
	)
	(segment
		(start 345.812618 -236.704124)
		(end 345.81338 -236.703616)
		(width 0.1143)
		(layer "In13.Cu")
		(net "GMI_CPU0_G0_CPU1_G2_TX_DN<14>")
	)
	(segment
		(start 345.741752 -227.02901)
		(end 345.769184 -227.009452)
		(width 0.1143)
		(layer "In13.Cu")
		(net "GMI_CPU0_G0_CPU1_G2_TX_DN<14>")
	)
	(segment
		(start 125.657102 -231.829102)
		(end 125.687582 -231.846882)
		(width 0.1143)
		(layer "In13.Cu")
		(net "GMI_CPU0_G0_CPU1_G2_TX_DN<14>")
	)
	(segment
		(start 154.691334 -197.318376)
		(end 154.672284 -197.511416)
		(width 0.14224)
		(layer "In13.Cu")
		(net "GMI_CPU0_G0_CPU1_G2_TX_DN<14>")
	)
	(segment
		(start 125.687582 -224.721928)
		(end 125.657102 -224.739708)
		(width 0.1143)
		(layer "In13.Cu")
		(net "GMI_CPU0_G0_CPU1_G2_TX_DN<14>")
	)
	(segment
		(start 345.768422 -239.278668)
		(end 345.752166 -239.26673)
		(width 0.1143)
		(layer "In13.Cu")
		(net "GMI_CPU0_G0_CPU1_G2_TX_DN<14>")
	)
	(segment
		(start 157.831282 -194.921886)
		(end 157.638242 -194.902582)
		(width 0.14224)
		(layer "In13.Cu")
		(net "GMI_CPU0_G0_CPU1_G2_TX_DN<14>")
	)
	(segment
		(start 345.805252 -225.368612)
		(end 345.808046 -225.366834)
		(width 0.1143)
		(layer "In13.Cu")
		(net "GMI_CPU0_G0_CPU1_G2_TX_DN<14>")
	)
	(segment
		(start 125.545342 -221.157546)
		(end 125.545342 -221.547436)
		(width 0.14224)
		(layer "In13.Cu")
		(net "GMI_CPU0_G0_CPU1_G2_TX_DN<14>")
	)
	(segment
		(start 345.80703 -230.227124)
		(end 345.808046 -230.226616)
		(width 0.1143)
		(layer "In13.Cu")
		(net "GMI_CPU0_G0_CPU1_G2_TX_DN<14>")
	)
	(segment
		(start 125.657102 -228.589332)
		(end 125.687582 -228.607112)
		(width 0.1143)
		(layer "In13.Cu")
		(net "GMI_CPU0_G0_CPU1_G2_TX_DN<14>")
	)
	(segment
		(start 160.25495 -192.757044)
		(end 159.925004 -193.027554)
		(width 0.14224)
		(layer "In13.Cu")
		(net "GMI_CPU0_G0_CPU1_G2_TX_DN<14>")
	)
	(segment
		(start 345.810078 -228.605588)
		(end 345.812618 -228.604318)
		(width 0.1143)
		(layer "In13.Cu")
		(net "GMI_CPU0_G0_CPU1_G2_TX_DN<14>")
	)
	(segment
		(start 125.687582 -237.68177)
		(end 125.657102 -237.69955)
		(width 0.1143)
		(layer "In13.Cu")
		(net "GMI_CPU0_G0_CPU1_G2_TX_DN<14>")
	)
	(segment
		(start 345.769946 -236.728508)
		(end 345.805506 -236.708442)
		(width 0.1143)
		(layer "In13.Cu")
		(net "GMI_CPU0_G0_CPU1_G2_TX_DN<14>")
	)
	(segment
		(start 125.687582 -236.706918)
		(end 125.726698 -236.729778)
		(width 0.1143)
		(layer "In13.Cu")
		(net "GMI_CPU0_G0_CPU1_G2_TX_DN<14>")
	)
	(segment
		(start 345.769184 -232.798874)
		(end 345.741244 -232.778808)
		(width 0.1143)
		(layer "In13.Cu")
		(net "GMI_CPU0_G0_CPU1_G2_TX_DN<14>")
	)
	(segment
		(start 345.7702 -235.108496)
		(end 345.808046 -235.086652)
		(width 0.1143)
		(layer "In13.Cu")
		(net "GMI_CPU0_G0_CPU1_G2_TX_DN<14>")
	)
	(segment
		(start 125.726698 -224.699068)
		(end 125.687582 -224.721928)
		(width 0.1143)
		(layer "In13.Cu")
		(net "GMI_CPU0_G0_CPU1_G2_TX_DN<14>")
	)
	(segment
		(start 159.905954 -193.220594)
		(end 159.575754 -193.491612)
		(width 0.14224)
		(layer "In13.Cu")
		(net "GMI_CPU0_G0_CPU1_G2_TX_DN<14>")
	)
	(segment
		(start 345.810078 -237.682786)
		(end 345.808808 -237.682024)
		(width 0.1143)
		(layer "In13.Cu")
		(net "GMI_CPU0_G0_CPU1_G2_TX_DN<14>")
	)
	(segment
		(start 345.80449 -230.228648)
		(end 345.805506 -230.22814)
		(width 0.1143)
		(layer "In13.Cu")
		(net "GMI_CPU0_G0_CPU1_G2_TX_DN<14>")
	)
	(segment
		(start 345.839796 -226.359974)
		(end 345.815412 -226.34575)
		(width 0.1143)
		(layer "In13.Cu")
		(net "GMI_CPU0_G0_CPU1_G2_TX_DN<14>")
	)
	(segment
		(start 345.804998 -239.29975)
		(end 345.80322 -239.298734)
		(width 0.1143)
		(layer "In13.Cu")
		(net "GMI_CPU0_G0_CPU1_G2_TX_DN<14>")
	)
	(segment
		(start 125.726698 -239.278922)
		(end 125.687582 -239.301782)
		(width 0.1143)
		(layer "In13.Cu")
		(net "GMI_CPU0_G0_CPU1_G2_TX_DN<14>")
	)
	(segment
		(start 345.808046 -225.366834)
		(end 345.808808 -225.366326)
		(width 0.1143)
		(layer "In13.Cu")
		(net "GMI_CPU0_G0_CPU1_G2_TX_DN<14>")
	)
	(segment
		(start 345.839796 -236.079792)
		(end 345.815158 -236.065568)
		(width 0.1143)
		(layer "In13.Cu")
		(net "GMI_CPU0_G0_CPU1_G2_TX_DN<14>")
	)
	(segment
		(start 155.56357 -196.603366)
		(end 155.54452 -196.796406)
		(width 0.14224)
		(layer "In13.Cu")
		(net "GMI_CPU0_G0_CPU1_G2_TX_DN<14>")
	)
	(segment
		(start 345.805252 -226.988624)
		(end 345.808046 -226.986846)
		(width 0.1143)
		(layer "In13.Cu")
		(net "GMI_CPU0_G0_CPU1_G2_TX_DN<14>")
	)
	(segment
		(start 125.687582 -233.466894)
		(end 125.726698 -233.489754)
		(width 0.1143)
		(layer "In13.Cu")
		(net "GMI_CPU0_G0_CPU1_G2_TX_DN<14>")
	)
	(segment
		(start 158.180532 -194.457828)
		(end 158.161482 -194.650868)
		(width 0.14224)
		(layer "In13.Cu")
		(net "GMI_CPU0_G0_CPU1_G2_TX_DN<14>")
	)
	(segment
		(start 345.808046 -231.201722)
		(end 345.808046 -231.201468)
		(width 0.1143)
		(layer "In13.Cu")
		(net "GMI_CPU0_G0_CPU1_G2_TX_DN<14>")
	)
	(segment
		(start 345.752166 -235.12145)
		(end 345.7702 -235.108496)
		(width 0.1143)
		(layer "In13.Cu")
		(net "GMI_CPU0_G0_CPU1_G2_TX_DN<14>")
	)
	(segment
		(start 345.812618 -238.324136)
		(end 345.81338 -238.323628)
		(width 0.1143)
		(layer "In13.Cu")
		(net "GMI_CPU0_G0_CPU1_G2_TX_DN<14>")
	)
	(segment
		(start 125.657102 -236.689138)
		(end 125.687582 -236.706918)
		(width 0.1143)
		(layer "In13.Cu")
		(net "GMI_CPU0_G0_CPU1_G2_TX_DN<14>")
	)
	(segment
		(start 159.382714 -193.472308)
		(end 159.052768 -193.742818)
		(width 0.14224)
		(layer "In13.Cu")
		(net "GMI_CPU0_G0_CPU1_G2_TX_DN<14>")
	)
	(segment
		(start 125.687582 -236.061758)
		(end 125.657102 -236.079538)
		(width 0.1143)
		(layer "In13.Cu")
		(net "GMI_CPU0_G0_CPU1_G2_TX_DN<14>")
	)
	(segment
		(start 345.808046 -230.226616)
		(end 345.811348 -230.224838)
		(width 0.1143)
		(layer "In13.Cu")
		(net "GMI_CPU0_G0_CPU1_G2_TX_DN<14>")
	)
	(segment
		(start 345.808808 -223.746314)
		(end 345.810078 -223.745552)
		(width 0.1143)
		(layer "In13.Cu")
		(net "GMI_CPU0_G0_CPU1_G2_TX_DN<14>")
	)
	(segment
		(start 345.995752 -221.253558)
		(end 345.950032 -221.207838)
		(width 0.1143)
		(layer "In13.Cu")
		(net "GMI_CPU0_G0_CPU1_G2_TX_DN<14>")
	)
	(segment
		(start 146.974814 -202.350116)
		(end 126.56947 -219.08135)
		(width 0.14224)
		(layer "In13.Cu")
		(net "GMI_CPU0_G0_CPU1_G2_TX_DN<14>")
	)
	(segment
		(start 345.813888 -227.965)
		(end 345.813126 -227.964492)
		(width 0.1143)
		(layer "In13.Cu")
		(net "GMI_CPU0_G0_CPU1_G2_TX_DN<14>")
	)
	(segment
		(start 233.006646 -200.115678)
		(end 210.794092 -190.91529)
		(width 0.14224)
		(layer "In13.Cu")
		(net "GMI_CPU0_G0_CPU1_G2_TX_DN<14>")
	)
	(segment
		(start 345.988894 -239.554258)
		(end 345.989148 -239.554258)
		(width 0.1143)
		(layer "In13.Cu")
		(net "GMI_CPU0_G0_CPU1_G2_TX_DN<14>")
	)
	(segment
		(start 345.81211 -227.963984)
		(end 345.811348 -227.963476)
		(width 0.1143)
		(layer "In13.Cu")
		(net "GMI_CPU0_G0_CPU1_G2_TX_DN<14>")
	)
	(segment
		(start 251.423424 -192.01384)
		(end 239.955578 -200.04405)
		(width 0.14224)
		(layer "In13.Cu")
		(net "GMI_CPU0_G0_CPU1_G2_TX_DN<14>")
	)
	(segment
		(start 345.808046 -228.606858)
		(end 345.808808 -228.60635)
		(width 0.1143)
		(layer "In13.Cu")
		(net "GMI_CPU0_G0_CPU1_G2_TX_DN<14>")
	)
	(segment
		(start 345.81465 -226.345242)
		(end 345.81211 -226.343972)
		(width 0.1143)
		(layer "In13.Cu")
		(net "GMI_CPU0_G0_CPU1_G2_TX_DN<14>")
	)
	(segment
		(start 345.621102 -239.624108)
		(end 345.919044 -239.624108)
		(width 0.1143)
		(layer "In13.Cu")
		(net "GMI_CPU0_G0_CPU1_G2_TX_DN<14>")
	)
	(segment
		(start 345.769184 -227.009452)
		(end 345.805252 -226.988624)
		(width 0.1143)
		(layer "In13.Cu")
		(net "GMI_CPU0_G0_CPU1_G2_TX_DN<14>")
	)
	(segment
		(start 154.672284 -197.511416)
		(end 154.342084 -197.78218)
		(width 0.14224)
		(layer "In13.Cu")
		(net "GMI_CPU0_G0_CPU1_G2_TX_DN<14>")
	)
	(segment
		(start 345.808046 -237.681516)
		(end 345.769946 -237.659672)
		(width 0.1143)
		(layer "In13.Cu")
		(net "GMI_CPU0_G0_CPU1_G2_TX_DN<14>")
	)
	(segment
		(start 239.955578 -200.04405)
		(end 236.278928 -200.692512)
		(width 0.14224)
		(layer "In13.Cu")
		(net "GMI_CPU0_G0_CPU1_G2_TX_DN<14>")
	)
	(segment
		(start 125.687582 -235.086906)
		(end 125.726698 -235.109766)
		(width 0.1143)
		(layer "In13.Cu")
		(net "GMI_CPU0_G0_CPU1_G2_TX_DN<14>")
	)
	(segment
		(start 345.814904 -236.702854)
		(end 345.839796 -236.688376)
		(width 0.1143)
		(layer "In13.Cu")
		(net "GMI_CPU0_G0_CPU1_G2_TX_DN<14>")
	)
	(segment
		(start 345.812364 -236.064044)
		(end 345.811602 -236.063536)
		(width 0.1143)
		(layer "In13.Cu")
		(net "GMI_CPU0_G0_CPU1_G2_TX_DN<14>")
	)
	(segment
		(start 156.416756 -196.081142)
		(end 156.086556 -196.351906)
		(width 0.14224)
		(layer "In13.Cu")
		(net "GMI_CPU0_G0_CPU1_G2_TX_DN<14>")
	)
	(segment
		(start 345.808808 -232.821988)
		(end 345.808046 -232.82148)
		(width 0.1143)
		(layer "In13.Cu")
		(net "GMI_CPU0_G0_CPU1_G2_TX_DN<14>")
	)
	(segment
		(start 125.687328 -222.127064)
		(end 125.727714 -222.150686)
		(width 0.1143)
		(layer "In13.Cu")
		(net "GMI_CPU0_G0_CPU1_G2_TX_DN<14>")
	)
	(segment
		(start 158.658814 -194.20205)
		(end 158.510478 -194.187318)
		(width 0.14224)
		(layer "In13.Cu")
		(net "GMI_CPU0_G0_CPU1_G2_TX_DN<14>")
	)
	(segment
		(start 125.687582 -232.821734)
		(end 125.657102 -232.839514)
		(width 0.1143)
		(layer "In13.Cu")
		(net "GMI_CPU0_G0_CPU1_G2_TX_DN<14>")
	)
	(segment
		(start 345.841574 -231.22128)
		(end 345.808046 -231.201722)
		(width 0.1143)
		(layer "In13.Cu")
		(net "GMI_CPU0_G0_CPU1_G2_TX_DN<14>")
	)
	(segment
		(start 345.805252 -232.819702)
		(end 345.769184 -232.798874)
		(width 0.1143)
		(layer "In13.Cu")
		(net "GMI_CPU0_G0_CPU1_G2_TX_DN<14>")
	)
	(segment
		(start 159.925004 -193.027554)
		(end 159.905954 -193.220594)
		(width 0.14224)
		(layer "In13.Cu")
		(net "GMI_CPU0_G0_CPU1_G2_TX_DN<14>")
	)
	(segment
		(start 160.79724 -192.312544)
		(end 160.77819 -192.505584)
		(width 0.14224)
		(layer "In13.Cu")
		(net "GMI_CPU0_G0_CPU1_G2_TX_DN<14>")
	)
	(segment
		(start 160.77819 -192.505584)
		(end 160.44799 -192.776348)
		(width 0.14224)
		(layer "In13.Cu")
		(net "GMI_CPU0_G0_CPU1_G2_TX_DN<14>")
	)
	(segment
		(start 345.760294 -228.63556)
		(end 345.76893 -228.629464)
		(width 0.1143)
		(layer "In13.Cu")
		(net "GMI_CPU0_G0_CPU1_G2_TX_DN<14>")
	)
	(segment
		(start 345.812364 -223.104202)
		(end 345.811602 -223.103694)
		(width 0.1143)
		(layer "In13.Cu")
		(net "GMI_CPU0_G0_CPU1_G2_TX_DN<14>")
	)
	(segment
		(start 157.308042 -195.173092)
		(end 157.288992 -195.366132)
		(width 0.14224)
		(layer "In13.Cu")
		(net "GMI_CPU0_G0_CPU1_G2_TX_DN<14>")
	)
	(segment
		(start 125.726698 -229.559104)
		(end 125.687582 -229.581964)
		(width 0.1143)
		(layer "In13.Cu")
		(net "GMI_CPU0_G0_CPU1_G2_TX_DN<14>")
	)
	(segment
		(start 125.506988 -239.554512)
		(end 125.576838 -239.624362)
		(width 0.1143)
		(layer "In13.Cu")
		(net "GMI_CPU0_G0_CPU1_G2_TX_DN<14>")
	)
	(segment
		(start 345.812618 -225.364294)
		(end 345.81338 -225.363786)
		(width 0.1143)
		(layer "In13.Cu")
		(net "GMI_CPU0_G0_CPU1_G2_TX_DN<14>")
	)
	(segment
		(start 345.808808 -236.062012)
		(end 345.808046 -236.061504)
		(width 0.1143)
		(layer "In13.Cu")
		(net "GMI_CPU0_G0_CPU1_G2_TX_DN<14>")
	)
	(segment
		(start 345.808046 -233.46664)
		(end 345.839796 -233.448352)
		(width 0.1143)
		(layer "In13.Cu")
		(net "GMI_CPU0_G0_CPU1_G2_TX_DN<14>")
	)
	(segment
		(start 345.813126 -227.964492)
		(end 345.81211 -227.963984)
		(width 0.1143)
		(layer "In13.Cu")
		(net "GMI_CPU0_G0_CPU1_G2_TX_DN<14>")
	)
	(segment
		(start 345.754452 -236.739684)
		(end 345.769946 -236.728508)
		(width 0.1143)
		(layer "In13.Cu")
		(net "GMI_CPU0_G0_CPU1_G2_TX_DN<14>")
	)
	(segment
		(start 345.815158 -223.105726)
		(end 345.814142 -223.105218)
		(width 0.1143)
		(layer "In13.Cu")
		(net "GMI_CPU0_G0_CPU1_G2_TX_DN<14>")
	)
	(segment
		(start 345.811602 -223.103694)
		(end 345.810078 -223.102932)
		(width 0.1143)
		(layer "In13.Cu")
		(net "GMI_CPU0_G0_CPU1_G2_TX_DN<14>")
	)
	(segment
		(start 345.841574 -229.601268)
		(end 345.840812 -229.60076)
		(width 0.1143)
		(layer "In13.Cu")
		(net "GMI_CPU0_G0_CPU1_G2_TX_DN<14>")
	)
	(segment
		(start 125.726698 -237.65891)
		(end 125.687582 -237.68177)
		(width 0.1143)
		(layer "In13.Cu")
		(net "GMI_CPU0_G0_CPU1_G2_TX_DN<14>")
	)
	(segment
		(start 345.808808 -223.10217)
		(end 345.804998 -223.09963)
		(width 0.1143)
		(layer "In13.Cu")
		(net "GMI_CPU0_G0_CPU1_G2_TX_DN<14>")
	)
	(segment
		(start 345.811348 -226.343464)
		(end 345.810332 -226.342956)
		(width 0.1143)
		(layer "In13.Cu")
		(net "GMI_CPU0_G0_CPU1_G2_TX_DN<14>")
	)
	(segment
		(start 156.958792 -195.636896)
		(end 156.765752 -195.617592)
		(width 0.14224)
		(layer "In13.Cu")
		(net "GMI_CPU0_G0_CPU1_G2_TX_DN<14>")
	)
	(segment
		(start 303.7332 -190.391796)
		(end 262.765794 -190.013844)
		(width 0.14224)
		(layer "In13.Cu")
		(net "GMI_CPU0_G0_CPU1_G2_TX_DN<14>")
	)
	(segment
		(start 345.808046 -235.086652)
		(end 345.839796 -235.068364)
		(width 0.1143)
		(layer "In13.Cu")
		(net "GMI_CPU0_G0_CPU1_G2_TX_DN<14>")
	)
	(segment
		(start 345.804998 -223.09963)
		(end 345.797886 -223.095566)
		(width 0.1143)
		(layer "In13.Cu")
		(net "GMI_CPU0_G0_CPU1_G2_TX_DN<14>")
	)
	(segment
		(start 125.687582 -223.747076)
		(end 125.726698 -223.769936)
		(width 0.1143)
		(layer "In13.Cu")
		(net "GMI_CPU0_G0_CPU1_G2_TX_DN<14>")
	)
	(segment
		(start 155.54452 -196.796406)
		(end 155.21432 -197.06717)
		(width 0.14224)
		(layer "In13.Cu")
		(net "GMI_CPU0_G0_CPU1_G2_TX_DN<14>")
	)
	(segment
		(start 345.808808 -237.682024)
		(end 345.808046 -237.681516)
		(width 0.1143)
		(layer "In13.Cu")
		(net "GMI_CPU0_G0_CPU1_G2_TX_DN<14>")
	)
	(segment
		(start 345.76004 -222.142812)
		(end 345.83878 -222.096076)
		(width 0.1143)
		(layer "In13.Cu")
		(net "GMI_CPU0_G0_CPU1_G2_TX_DN<14>")
	)
	(segment
		(start 345.805506 -230.22814)
		(end 345.80703 -230.227124)
		(width 0.1143)
		(layer "In13.Cu")
		(net "GMI_CPU0_G0_CPU1_G2_TX_DN<14>")
	)
	(segment
		(start 308.646068 -190.391796)
		(end 303.7332 -190.391796)
		(width 0.14224)
		(layer "In13.Cu")
		(net "GMI_CPU0_G0_CPU1_G2_TX_DN<14>")
	)
	(segment
		(start 345.814142 -236.06506)
		(end 345.81338 -236.064552)
		(width 0.1143)
		(layer "In13.Cu")
		(net "GMI_CPU0_G0_CPU1_G2_TX_DN<14>")
	)
	(segment
		(start 345.774518 -230.246174)
		(end 345.776042 -230.245158)
		(width 0.1143)
		(layer "In13.Cu")
		(net "GMI_CPU0_G0_CPU1_G2_TX_DN<14>")
	)
	(segment
		(start 345.81338 -226.983798)
		(end 345.814904 -226.983036)
		(width 0.1143)
		(layer "In13.Cu")
		(net "GMI_CPU0_G0_CPU1_G2_TX_DN<14>")
	)
	(segment
		(start 345.811348 -227.963476)
		(end 345.810332 -227.962968)
		(width 0.1143)
		(layer "In13.Cu")
		(net "GMI_CPU0_G0_CPU1_G2_TX_DN<14>")
	)
	(segment
		(start 345.808808 -226.986338)
		(end 345.810078 -226.985576)
		(width 0.1143)
		(layer "In13.Cu")
		(net "GMI_CPU0_G0_CPU1_G2_TX_DN<14>")
	)
	(segment
		(start 158.161482 -194.650868)
		(end 157.831282 -194.921886)
		(width 0.14224)
		(layer "In13.Cu")
		(net "GMI_CPU0_G0_CPU1_G2_TX_DN<14>")
	)
	(segment
		(start 345.525852 -229.094284)
		(end 345.525852 -229.093776)
		(width 0.1143)
		(layer "In13.Cu")
		(net "GMI_CPU0_G0_CPU1_G2_TX_DN<14>")
	)
	(segment
		(start 345.950032 -221.022926)
		(end 345.954604 -220.97746)
		(width 0.14224)
		(layer "In13.Cu")
		(net "GMI_CPU0_G0_CPU1_G2_TX_DN<14>")
	)
	(segment
		(start 345.839796 -224.739962)
		(end 345.808046 -224.721674)
		(width 0.1143)
		(layer "In13.Cu")
		(net "GMI_CPU0_G0_CPU1_G2_TX_DN<14>")
	)
	(segment
		(start 345.76893 -231.869234)
		(end 345.839796 -231.82834)
		(width 0.1143)
		(layer "In13.Cu")
		(net "GMI_CPU0_G0_CPU1_G2_TX_DN<14>")
	)
	(segment
		(start 158.510478 -194.187318)
		(end 158.180532 -194.457828)
		(width 0.14224)
		(layer "In13.Cu")
		(net "GMI_CPU0_G0_CPU1_G2_TX_DN<14>")
	)
	(segment
		(start 345.768422 -238.349536)
		(end 345.808046 -238.326676)
		(width 0.1143)
		(layer "In13.Cu")
		(net "GMI_CPU0_G0_CPU1_G2_TX_DN<14>")
	)
	(segment
		(start 125.657102 -238.30915)
		(end 125.687582 -238.32693)
		(width 0.1143)
		(layer "In13.Cu")
		(net "GMI_CPU0_G0_CPU1_G2_TX_DN<14>")
	)
	(segment
		(start 345.808046 -232.82148)
		(end 345.805252 -232.819702)
		(width 0.1143)
		(layer "In13.Cu")
		(net "GMI_CPU0_G0_CPU1_G2_TX_DN<14>")
	)
	(segment
		(start 125.657102 -223.729296)
		(end 125.687582 -223.747076)
		(width 0.1143)
		(layer "In13.Cu")
		(net "GMI_CPU0_G0_CPU1_G2_TX_DN<14>")
	)
	(segment
		(start 345.771724 -223.767904)
		(end 345.808046 -223.746822)
		(width 0.1143)
		(layer "In13.Cu")
		(net "GMI_CPU0_G0_CPU1_G2_TX_DN<14>")
	)
	(segment
		(start 345.889072 -239.35436)
		(end 345.80703 -239.30102)
		(width 0.1143)
		(layer "In13.Cu")
		(net "GMI_CPU0_G0_CPU1_G2_TX_DN<14>")
	)
	(segment
		(start 345.810078 -225.365564)
		(end 345.812618 -225.364294)
		(width 0.1143)
		(layer "In13.Cu")
		(net "GMI_CPU0_G0_CPU1_G2_TX_DN<14>")
	)
	(segment
		(start 345.81338 -236.703616)
		(end 345.814904 -236.702854)
		(width 0.1143)
		(layer "In13.Cu")
		(net "GMI_CPU0_G0_CPU1_G2_TX_DN<14>")
	)
	(segment
		(start 345.808046 -231.201468)
		(end 345.805252 -231.199944)
		(width 0.1143)
		(layer "In13.Cu")
		(net "GMI_CPU0_G0_CPU1_G2_TX_DN<14>")
	)
	(segment
		(start 345.808046 -229.581202)
		(end 345.767152 -229.557326)
		(width 0.1143)
		(layer "In13.Cu")
		(net "GMI_CPU0_G0_CPU1_G2_TX_DN<14>")
	)
	(segment
		(start 160.44799 -192.776348)
		(end 160.25495 -192.757044)
		(width 0.14224)
		(layer "In13.Cu")
		(net "GMI_CPU0_G0_CPU1_G2_TX_DN<14>")
	)
	(segment
		(start 345.840812 -229.60076)
		(end 345.808808 -229.582218)
		(width 0.1143)
		(layer "In13.Cu")
		(net "GMI_CPU0_G0_CPU1_G2_TX_DN<14>")
	)
	(segment
		(start 345.839796 -227.979986)
		(end 345.813888 -227.965)
		(width 0.1143)
		(layer "In13.Cu")
		(net "GMI_CPU0_G0_CPU1_G2_TX_DN<14>")
	)
	(segment
		(start 345.81338 -237.684564)
		(end 345.812364 -237.684056)
		(width 0.1143)
		(layer "In13.Cu")
		(net "GMI_CPU0_G0_CPU1_G2_TX_DN<14>")
	)
	(segment
		(start 162.630612 -190.480442)
		(end 161.691066 -191.251078)
		(width 0.14224)
		(layer "In13.Cu")
		(net "GMI_CPU0_G0_CPU1_G2_TX_DN<14>")
	)
	(segment
		(start 345.769184 -226.31908)
		(end 345.750642 -226.305872)
		(width 0.1143)
		(layer "In13.Cu")
		(net "GMI_CPU0_G0_CPU1_G2_TX_DN<14>")
	)
	(segment
		(start 345.919044 -239.624108)
		(end 345.988894 -239.554258)
		(width 0.1143)
		(layer "In13.Cu")
		(net "GMI_CPU0_G0_CPU1_G2_TX_DN<14>")
	)
	(segment
		(start 345.810078 -226.985576)
		(end 345.812618 -226.984306)
		(width 0.1143)
		(layer "In13.Cu")
		(net "GMI_CPU0_G0_CPU1_G2_TX_DN<14>")
	)
	(segment
		(start 345.81338 -228.60381)
		(end 345.814904 -228.603048)
		(width 0.1143)
		(layer "In13.Cu")
		(net "GMI_CPU0_G0_CPU1_G2_TX_DN<14>")
	)
	(segment
		(start 345.808046 -238.326676)
		(end 345.808808 -238.326168)
		(width 0.1143)
		(layer "In13.Cu")
		(net "GMI_CPU0_G0_CPU1_G2_TX_DN<14>")
	)
	(segment
		(start 345.810332 -226.342956)
		(end 345.80957 -226.342448)
		(width 0.1143)
		(layer "In13.Cu")
		(net "GMI_CPU0_G0_CPU1_G2_TX_DN<14>")
	)
	(segment
		(start 157.308296 -195.173092)
		(end 157.308042 -195.173092)
		(width 0.14224)
		(layer "In13.Cu")
		(net "GMI_CPU0_G0_CPU1_G2_TX_DN<14>")
	)
	(segment
		(start 125.576838 -239.624362)
		(end 125.87478 -239.624362)
		(width 0.1143)
		(layer "In13.Cu")
		(net "GMI_CPU0_G0_CPU1_G2_TX_DN<14>")
	)
	(segment
		(start 345.808808 -236.706156)
		(end 345.810078 -236.705394)
		(width 0.1143)
		(layer "In13.Cu")
		(net "GMI_CPU0_G0_CPU1_G2_TX_DN<14>")
	)
	(segment
		(start 125.687582 -231.201976)
		(end 125.65507 -231.220772)
		(width 0.1143)
		(layer "In13.Cu")
		(net "GMI_CPU0_G0_CPU1_G2_TX_DN<14>")
	)
	(segment
		(start 345.752166 -238.361474)
		(end 345.768422 -238.349536)
		(width 0.1143)
		(layer "In13.Cu")
		(net "GMI_CPU0_G0_CPU1_G2_TX_DN<14>")
	)
	(segment
		(start 236.278928 -200.692512)
		(end 233.006646 -200.115678)
		(width 0.14224)
		(layer "In13.Cu")
		(net "GMI_CPU0_G0_CPU1_G2_TX_DN<14>")
	)
	(segment
		(start 345.810078 -223.102932)
		(end 345.808808 -223.10217)
		(width 0.1143)
		(layer "In13.Cu")
		(net "GMI_CPU0_G0_CPU1_G2_TX_DN<14>")
	)
	(segment
		(start 125.687582 -227.961952)
		(end 125.657102 -227.979732)
		(width 0.1143)
		(layer "In13.Cu")
		(net "GMI_CPU0_G0_CPU1_G2_TX_DN<14>")
	)
	(segment
		(start 345.839796 -232.839768)
		(end 345.808808 -232.821988)
		(width 0.1143)
		(layer "In13.Cu")
		(net "GMI_CPU0_G0_CPU1_G2_TX_DN<14>")
	)
	(arc
		(start 125.657102 -234.459526)
		(mid 125.500125 -234.764326)
		(end 125.657102 -235.069126)
		(width 0.1143)
		(layer "In13.Cu")
		(net "GMI_CPU0_G0_CPU1_G2_TX_DN<14>")
	)
	(arc
		(start 125.657102 -227.979732)
		(mid 125.500125 -228.284532)
		(end 125.657102 -228.589332)
		(width 0.1143)
		(layer "In13.Cu")
		(net "GMI_CPU0_G0_CPU1_G2_TX_DN<14>")
	)
	(arc
		(start 345.839796 -223.728534)
		(mid 345.995724 -223.424242)
		(end 345.839796 -223.11995)
		(width 0.1143)
		(layer "In13.Cu")
		(net "GMI_CPU0_G0_CPU1_G2_TX_DN<14>")
	)
	(arc
		(start 345.83878 -222.096076)
		(mid 345.954206 -221.962558)
		(end 345.995752 -221.791022)
		(width 0.1143)
		(layer "In13.Cu")
		(net "GMI_CPU0_G0_CPU1_G2_TX_DN<14>")
	)
	(arc
		(start 125.726698 -236.729778)
		(mid 125.970025 -237.194344)
		(end 125.726698 -237.65891)
		(width 0.1143)
		(layer "In13.Cu")
		(net "GMI_CPU0_G0_CPU1_G2_TX_DN<14>")
	)
	(arc
		(start 345.760294 -230.255826)
		(mid 345.76737 -230.250947)
		(end 345.774518 -230.246174)
		(width 0.1143)
		(layer "In13.Cu")
		(net "GMI_CPU0_G0_CPU1_G2_TX_DN<14>")
	)
	(arc
		(start 345.741244 -232.778808)
		(mid 345.513244 -232.334054)
		(end 345.741244 -231.8893)
		(width 0.1143)
		(layer "In13.Cu")
		(net "GMI_CPU0_G0_CPU1_G2_TX_DN<14>")
	)
	(arc
		(start 345.805252 -231.199944)
		(mid 345.600035 -230.994363)
		(end 345.525852 -230.713534)
		(width 0.1143)
		(layer "In13.Cu")
		(net "GMI_CPU0_G0_CPU1_G2_TX_DN<14>")
	)
	(arc
		(start 125.726698 -233.489754)
		(mid 125.970025 -233.95432)
		(end 125.726698 -234.418886)
		(width 0.1143)
		(layer "In13.Cu")
		(net "GMI_CPU0_G0_CPU1_G2_TX_DN<14>")
	)
	(arc
		(start 125.726698 -227.00996)
		(mid 125.970025 -227.474526)
		(end 125.726698 -227.939092)
		(width 0.1143)
		(layer "In13.Cu")
		(net "GMI_CPU0_G0_CPU1_G2_TX_DN<14>")
	)
	(arc
		(start 125.657102 -239.319562)
		(mid 125.559337 -239.422538)
		(end 125.506988 -239.554512)
		(width 0.1143)
		(layer "In13.Cu")
		(net "GMI_CPU0_G0_CPU1_G2_TX_DN<14>")
	)
	(arc
		(start 345.839796 -236.688376)
		(mid 345.995724 -236.384084)
		(end 345.839796 -236.079792)
		(width 0.1143)
		(layer "In13.Cu")
		(net "GMI_CPU0_G0_CPU1_G2_TX_DN<14>")
	)
	(arc
		(start 125.657102 -236.079538)
		(mid 125.500125 -236.384338)
		(end 125.657102 -236.689138)
		(width 0.1143)
		(layer "In13.Cu")
		(net "GMI_CPU0_G0_CPU1_G2_TX_DN<14>")
	)
	(arc
		(start 125.65507 -229.60076)
		(mid 125.541141 -229.733907)
		(end 125.50013 -229.90429)
		(width 0.1143)
		(layer "In13.Cu")
		(net "GMI_CPU0_G0_CPU1_G2_TX_DN<14>")
	)
	(arc
		(start 345.767152 -229.557326)
		(mid 345.589787 -229.355359)
		(end 345.525852 -229.094284)
		(width 0.1143)
		(layer "In13.Cu")
		(net "GMI_CPU0_G0_CPU1_G2_TX_DN<14>")
	)
	(arc
		(start 125.726698 -225.389948)
		(mid 125.970025 -225.854514)
		(end 125.726698 -226.31908)
		(width 0.1143)
		(layer "In13.Cu")
		(net "GMI_CPU0_G0_CPU1_G2_TX_DN<14>")
	)
	(arc
		(start 345.797886 -223.095566)
		(mid 345.51769 -222.629566)
		(end 345.76004 -222.142812)
		(width 0.1143)
		(layer "In13.Cu")
		(net "GMI_CPU0_G0_CPU1_G2_TX_DN<14>")
	)
	(arc
		(start 345.7575 -224.690686)
		(mid 345.530016 -224.234248)
		(end 345.7575 -223.77781)
		(width 0.1143)
		(layer "In13.Cu")
		(net "GMI_CPU0_G0_CPU1_G2_TX_DN<14>")
	)
	(arc
		(start 345.7575 -233.497628)
		(mid 345.764574 -233.492621)
		(end 345.771724 -233.487722)
		(width 0.1143)
		(layer "In13.Cu")
		(net "GMI_CPU0_G0_CPU1_G2_TX_DN<14>")
	)
	(arc
		(start 125.726698 -228.629972)
		(mid 125.970025 -229.094538)
		(end 125.726698 -229.559104)
		(width 0.1143)
		(layer "In13.Cu")
		(net "GMI_CPU0_G0_CPU1_G2_TX_DN<14>")
	)
	(arc
		(start 345.525852 -230.713534)
		(mid 345.588381 -230.456682)
		(end 345.760294 -230.255826)
		(width 0.1143)
		(layer "In13.Cu")
		(net "GMI_CPU0_G0_CPU1_G2_TX_DN<14>")
	)
	(arc
		(start 125.726698 -223.769936)
		(mid 125.970025 -224.234502)
		(end 125.726698 -224.699068)
		(width 0.1143)
		(layer "In13.Cu")
		(net "GMI_CPU0_G0_CPU1_G2_TX_DN<14>")
	)
	(arc
		(start 125.97003 -230.71455)
		(mid 125.905515 -230.976769)
		(end 125.726698 -231.179116)
		(width 0.1143)
		(layer "In13.Cu")
		(net "GMI_CPU0_G0_CPU1_G2_TX_DN<14>")
	)
	(arc
		(start 345.839796 -235.068364)
		(mid 345.995724 -234.764072)
		(end 345.839796 -234.45978)
		(width 0.1143)
		(layer "In13.Cu")
		(net "GMI_CPU0_G0_CPU1_G2_TX_DN<14>")
	)
	(arc
		(start 345.7575 -234.410504)
		(mid 345.530117 -233.954066)
		(end 345.7575 -233.497628)
		(width 0.1143)
		(layer "In13.Cu")
		(net "GMI_CPU0_G0_CPU1_G2_TX_DN<14>")
	)
	(arc
		(start 345.839796 -225.348546)
		(mid 345.995724 -225.044254)
		(end 345.839796 -224.739962)
		(width 0.1143)
		(layer "In13.Cu")
		(net "GMI_CPU0_G0_CPU1_G2_TX_DN<14>")
	)
	(arc
		(start 345.839796 -228.58857)
		(mid 345.995724 -228.284278)
		(end 345.839796 -227.979986)
		(width 0.1143)
		(layer "In13.Cu")
		(net "GMI_CPU0_G0_CPU1_G2_TX_DN<14>")
	)
	(arc
		(start 125.726698 -235.109766)
		(mid 125.970025 -235.574332)
		(end 125.726698 -236.038898)
		(width 0.1143)
		(layer "In13.Cu")
		(net "GMI_CPU0_G0_CPU1_G2_TX_DN<14>")
	)
	(arc
		(start 345.752166 -236.026706)
		(mid 345.520416 -235.574078)
		(end 345.752166 -235.12145)
		(width 0.1143)
		(layer "In13.Cu")
		(net "GMI_CPU0_G0_CPU1_G2_TX_DN<14>")
	)
	(arc
		(start 345.741752 -227.919534)
		(mid 345.51334 -227.474272)
		(end 345.741752 -227.02901)
		(width 0.1143)
		(layer "In13.Cu")
		(net "GMI_CPU0_G0_CPU1_G2_TX_DN<14>")
	)
	(arc
		(start 125.97003 -222.61449)
		(mid 125.905515 -222.876709)
		(end 125.726698 -223.079056)
		(width 0.1143)
		(layer "In13.Cu")
		(net "GMI_CPU0_G0_CPU1_G2_TX_DN<14>")
	)
	(arc
		(start 345.996006 -229.904036)
		(mid 345.955106 -229.734135)
		(end 345.841574 -229.601268)
		(width 0.1143)
		(layer "In13.Cu")
		(net "GMI_CPU0_G0_CPU1_G2_TX_DN<14>")
	)
	(arc
		(start 125.726698 -231.869742)
		(mid 125.970025 -232.334308)
		(end 125.726698 -232.798874)
		(width 0.1143)
		(layer "In13.Cu")
		(net "GMI_CPU0_G0_CPU1_G2_TX_DN<14>")
	)
	(arc
		(start 345.771724 -224.700592)
		(mid 345.764574 -224.695694)
		(end 345.7575 -224.690686)
		(width 0.1143)
		(layer "In13.Cu")
		(net "GMI_CPU0_G0_CPU1_G2_TX_DN<14>")
	)
	(arc
		(start 345.839796 -238.308388)
		(mid 345.995724 -238.004096)
		(end 345.839796 -237.699804)
		(width 0.1143)
		(layer "In13.Cu")
		(net "GMI_CPU0_G0_CPU1_G2_TX_DN<14>")
	)
	(arc
		(start 125.65507 -231.220772)
		(mid 125.541141 -231.353919)
		(end 125.50013 -231.524302)
		(width 0.1143)
		(layer "In13.Cu")
		(net "GMI_CPU0_G0_CPU1_G2_TX_DN<14>")
	)
	(arc
		(start 345.525852 -229.093776)
		(mid 345.587802 -228.836382)
		(end 345.760294 -228.63556)
		(width 0.1143)
		(layer "In13.Cu")
		(net "GMI_CPU0_G0_CPU1_G2_TX_DN<14>")
	)
	(arc
		(start 345.839796 -233.448352)
		(mid 345.995724 -233.14406)
		(end 345.839796 -232.839768)
		(width 0.1143)
		(layer "In13.Cu")
		(net "GMI_CPU0_G0_CPU1_G2_TX_DN<14>")
	)
	(arc
		(start 345.750642 -226.305872)
		(mid 345.518977 -225.85426)
		(end 345.750642 -225.402648)
		(width 0.1143)
		(layer "In13.Cu")
		(net "GMI_CPU0_G0_CPU1_G2_TX_DN<14>")
	)
	(arc
		(start 345.771724 -234.42041)
		(mid 345.764575 -234.41551)
		(end 345.7575 -234.410504)
		(width 0.1143)
		(layer "In13.Cu")
		(net "GMI_CPU0_G0_CPU1_G2_TX_DN<14>")
	)
	(arc
		(start 125.657102 -232.839514)
		(mid 125.500125 -233.144314)
		(end 125.657102 -233.449114)
		(width 0.1143)
		(layer "In13.Cu")
		(net "GMI_CPU0_G0_CPU1_G2_TX_DN<14>")
	)
	(arc
		(start 125.50013 -229.90429)
		(mid 125.541679 -230.075712)
		(end 125.657102 -230.20909)
		(width 0.1143)
		(layer "In13.Cu")
		(net "GMI_CPU0_G0_CPU1_G2_TX_DN<14>")
	)
	(arc
		(start 125.657102 -223.119696)
		(mid 125.500125 -223.424496)
		(end 125.657102 -223.729296)
		(width 0.1143)
		(layer "In13.Cu")
		(net "GMI_CPU0_G0_CPU1_G2_TX_DN<14>")
	)
	(arc
		(start 345.839796 -226.968558)
		(mid 345.995724 -226.664266)
		(end 345.839796 -226.359974)
		(width 0.1143)
		(layer "In13.Cu")
		(net "GMI_CPU0_G0_CPU1_G2_TX_DN<14>")
	)
	(arc
		(start 345.752166 -239.26673)
		(mid 345.520416 -238.814102)
		(end 345.752166 -238.361474)
		(width 0.1143)
		(layer "In13.Cu")
		(net "GMI_CPU0_G0_CPU1_G2_TX_DN<14>")
	)
	(arc
		(start 345.754452 -237.648496)
		(mid 345.52094 -237.19409)
		(end 345.754452 -236.739684)
		(width 0.1143)
		(layer "In13.Cu")
		(net "GMI_CPU0_G0_CPU1_G2_TX_DN<14>")
	)
	(arc
		(start 125.657102 -237.69955)
		(mid 125.500125 -238.00435)
		(end 125.657102 -238.30915)
		(width 0.1143)
		(layer "In13.Cu")
		(net "GMI_CPU0_G0_CPU1_G2_TX_DN<14>")
	)
	(arc
		(start 345.811348 -230.224838)
		(mid 345.946515 -230.089088)
		(end 345.996006 -229.904036)
		(width 0.1143)
		(layer "In13.Cu")
		(net "GMI_CPU0_G0_CPU1_G2_TX_DN<14>")
	)
	(arc
		(start 345.977464 -239.491012)
		(mid 345.946473 -239.41415)
		(end 345.889072 -239.35436)
		(width 0.1143)
		(layer "In13.Cu")
		(net "GMI_CPU0_G0_CPU1_G2_TX_DN<14>")
	)
	(arc
		(start 125.727714 -222.150686)
		(mid 125.905779 -222.352863)
		(end 125.97003 -222.61449)
		(width 0.1143)
		(layer "In13.Cu")
		(net "GMI_CPU0_G0_CPU1_G2_TX_DN<14>")
	)
	(arc
		(start 125.657102 -226.35972)
		(mid 125.500125 -226.66452)
		(end 125.657102 -226.96932)
		(width 0.1143)
		(layer "In13.Cu")
		(net "GMI_CPU0_G0_CPU1_G2_TX_DN<14>")
	)
	(arc
		(start 125.499622 -221.804484)
		(mid 125.540673 -221.972169)
		(end 125.652784 -222.103442)
		(width 0.1143)
		(layer "In13.Cu")
		(net "GMI_CPU0_G0_CPU1_G2_TX_DN<14>")
	)
	(arc
		(start 345.839796 -231.82834)
		(mid 345.995933 -231.525215)
		(end 345.841574 -231.22128)
		(width 0.1143)
		(layer "In13.Cu")
		(net "GMI_CPU0_G0_CPU1_G2_TX_DN<14>")
	)
	(arc
		(start 125.724158 -230.248206)
		(mid 125.90481 -230.450951)
		(end 125.97003 -230.71455)
		(width 0.1143)
		(layer "In13.Cu")
		(net "GMI_CPU0_G0_CPU1_G2_TX_DN<14>")
	)
	(arc
		(start 345.7575 -223.77781)
		(mid 345.764573 -223.772801)
		(end 345.771724 -223.767904)
		(width 0.1143)
		(layer "In13.Cu")
		(net "GMI_CPU0_G0_CPU1_G2_TX_DN<14>")
	)
	(arc
		(start 125.726698 -238.34979)
		(mid 125.970025 -238.814356)
		(end 125.726698 -239.278922)
		(width 0.1143)
		(layer "In13.Cu")
		(net "GMI_CPU0_G0_CPU1_G2_TX_DN<14>")
	)
	(arc
		(start 125.657102 -224.739708)
		(mid 125.500125 -225.044508)
		(end 125.657102 -225.349308)
		(width 0.1143)
		(layer "In13.Cu")
		(net "GMI_CPU0_G0_CPU1_G2_TX_DN<14>")
	)
	(arc
		(start 125.50013 -231.524302)
		(mid 125.541679 -231.695724)
		(end 125.657102 -231.829102)
		(width 0.1143)
		(layer "In13.Cu")
		(net "GMI_CPU0_G0_CPU1_G2_TX_DN<14>")
	)
	(segment
		(start 346.087954 -243.13007)
		(end 345.621102 -242.864132)
		(width 0.12954)
		(layer "F.Cu")
		(net "GMI_CPU0_G0_CPU1_G2_TX_DN<13>")
	)
	(segment
		(start 125.407928 -243.130324)
		(end 125.87478 -242.864386)
		(width 0.12954)
		(layer "F.Cu")
		(net "GMI_CPU0_G0_CPU1_G2_TX_DN<13>")
	)
	(segment
		(start 346.7481 -239.946688)
		(end 346.77985 -239.9284)
		(width 0.1143)
		(layer "In13.Cu")
		(net "GMI_CPU0_G0_CPU1_G2_TX_DN<13>")
	)
	(segment
		(start 124.739908 -235.082334)
		(end 124.752354 -235.089446)
		(width 0.1143)
		(layer "In13.Cu")
		(net "GMI_CPU0_G0_CPU1_G2_TX_DN<13>")
	)
	(segment
		(start 124.716032 -232.840022)
		(end 124.703078 -232.849166)
		(width 0.1143)
		(layer "In13.Cu")
		(net "GMI_CPU0_G0_CPU1_G2_TX_DN<13>")
	)
	(segment
		(start 318.029336 -195.809616)
		(end 309.008272 -189.451488)
		(width 0.14224)
		(layer "In13.Cu")
		(net "GMI_CPU0_G0_CPU1_G2_TX_DN<13>")
	)
	(segment
		(start 124.786898 -234.418886)
		(end 124.768864 -234.429554)
		(width 0.1143)
		(layer "In13.Cu")
		(net "GMI_CPU0_G0_CPU1_G2_TX_DN<13>")
	)
	(segment
		(start 157.724856 -193.438272)
		(end 157.395164 -193.708274)
		(width 0.14224)
		(layer "In13.Cu")
		(net "GMI_CPU0_G0_CPU1_G2_TX_DN<13>")
	)
	(segment
		(start 162.279076 -189.541404)
		(end 160.855406 -190.70955)
		(width 0.14224)
		(layer "In13.Cu")
		(net "GMI_CPU0_G0_CPU1_G2_TX_DN<13>")
	)
	(segment
		(start 124.56033 -229.895654)
		(end 124.567188 -229.959154)
		(width 0.1143)
		(layer "In13.Cu")
		(net "GMI_CPU0_G0_CPU1_G2_TX_DN<13>")
	)
	(segment
		(start 346.708984 -238.349536)
		(end 346.77985 -238.308388)
		(width 0.1143)
		(layer "In13.Cu")
		(net "GMI_CPU0_G0_CPU1_G2_TX_DN<13>")
	)
	(segment
		(start 157.395164 -193.708782)
		(end 157.376114 -193.901822)
		(width 0.14224)
		(layer "In13.Cu")
		(net "GMI_CPU0_G0_CPU1_G2_TX_DN<13>")
	)
	(segment
		(start 346.239084 -242.399566)
		(end 346.30868 -242.358926)
		(width 0.1143)
		(layer "In13.Cu")
		(net "GMI_CPU0_G0_CPU1_G2_TX_DN<13>")
	)
	(segment
		(start 156.852874 -194.153536)
		(end 156.522928 -194.424046)
		(width 0.14224)
		(layer "In13.Cu")
		(net "GMI_CPU0_G0_CPU1_G2_TX_DN<13>")
	)
	(segment
		(start 124.786898 -231.179116)
		(end 124.78131 -231.18191)
		(width 0.1143)
		(layer "In13.Cu")
		(net "GMI_CPU0_G0_CPU1_G2_TX_DN<13>")
	)
	(segment
		(start 346.769436 -228.594412)
		(end 346.769944 -228.594412)
		(width 0.1143)
		(layer "In13.Cu")
		(net "GMI_CPU0_G0_CPU1_G2_TX_DN<13>")
	)
	(segment
		(start 124.76861 -234.429554)
		(end 124.747274 -234.442)
		(width 0.1143)
		(layer "In13.Cu")
		(net "GMI_CPU0_G0_CPU1_G2_TX_DN<13>")
	)
	(segment
		(start 159.469582 -192.007744)
		(end 159.139636 -192.278254)
		(width 0.14224)
		(layer "In13.Cu")
		(net "GMI_CPU0_G0_CPU1_G2_TX_DN<13>")
	)
	(segment
		(start 124.754894 -223.75114)
		(end 124.756418 -223.752156)
		(width 0.1143)
		(layer "In13.Cu")
		(net "GMI_CPU0_G0_CPU1_G2_TX_DN<13>")
	)
	(segment
		(start 346.77985 -226.359974)
		(end 346.7481 -226.341686)
		(width 0.1143)
		(layer "In13.Cu")
		(net "GMI_CPU0_G0_CPU1_G2_TX_DN<13>")
	)
	(segment
		(start 346.792804 -236.088936)
		(end 346.77985 -236.079792)
		(width 0.1143)
		(layer "In13.Cu")
		(net "GMI_CPU0_G0_CPU1_G2_TX_DN<13>")
	)
	(segment
		(start 124.718318 -230.209852)
		(end 124.763022 -230.23576)
		(width 0.1143)
		(layer "In13.Cu")
		(net "GMI_CPU0_G0_CPU1_G2_TX_DN<13>")
	)
	(segment
		(start 125.217682 -242.37696)
		(end 125.256798 -242.39982)
		(width 0.1143)
		(layer "In13.Cu")
		(net "GMI_CPU0_G0_CPU1_G2_TX_DN<13>")
	)
	(segment
		(start 157.91815 -193.457322)
		(end 157.72511 -193.438272)
		(width 0.14224)
		(layer "In13.Cu")
		(net "GMI_CPU0_G0_CPU1_G2_TX_DN<13>")
	)
	(segment
		(start 346.89034 -221.198186)
		(end 346.89034 -220.460062)
		(width 0.14224)
		(layer "In13.Cu")
		(net "GMI_CPU0_G0_CPU1_G2_TX_DN<13>")
	)
	(segment
		(start 124.756418 -223.752156)
		(end 124.786136 -223.769428)
		(width 0.1143)
		(layer "In13.Cu")
		(net "GMI_CPU0_G0_CPU1_G2_TX_DN<13>")
	)
	(segment
		(start 124.786898 -240.898934)
		(end 124.716032 -240.940082)
		(width 0.1143)
		(layer "In13.Cu")
		(net "GMI_CPU0_G0_CPU1_G2_TX_DN<13>")
	)
	(segment
		(start 124.747782 -222.127064)
		(end 124.786898 -222.149924)
		(width 0.1143)
		(layer "In13.Cu")
		(net "GMI_CPU0_G0_CPU1_G2_TX_DN<13>")
	)
	(segment
		(start 346.77985 -233.448352)
		(end 346.792804 -233.439208)
		(width 0.1143)
		(layer "In13.Cu")
		(net "GMI_CPU0_G0_CPU1_G2_TX_DN<13>")
	)
	(segment
		(start 346.709746 -223.769174)
		(end 346.755974 -223.74225)
		(width 0.1143)
		(layer "In13.Cu")
		(net "GMI_CPU0_G0_CPU1_G2_TX_DN<13>")
	)
	(segment
		(start 346.727018 -223.08947)
		(end 346.708984 -223.078802)
		(width 0.1143)
		(layer "In13.Cu")
		(net "GMI_CPU0_G0_CPU1_G2_TX_DN<13>")
	)
	(segment
		(start 124.747782 -239.946942)
		(end 124.786898 -239.969802)
		(width 0.1143)
		(layer "In13.Cu")
		(net "GMI_CPU0_G0_CPU1_G2_TX_DN<13>")
	)
	(segment
		(start 124.726446 -227.974398)
		(end 124.726192 -227.974398)
		(width 0.1143)
		(layer "In13.Cu")
		(net "GMI_CPU0_G0_CPU1_G2_TX_DN<13>")
	)
	(segment
		(start 124.703078 -233.439462)
		(end 124.716032 -233.448606)
		(width 0.1143)
		(layer "In13.Cu")
		(net "GMI_CPU0_G0_CPU1_G2_TX_DN<13>")
	)
	(segment
		(start 346.77985 -240.939828)
		(end 346.708984 -240.89868)
		(width 0.1143)
		(layer "In13.Cu")
		(net "GMI_CPU0_G0_CPU1_G2_TX_DN<13>")
	)
	(segment
		(start 346.89034 -220.460062)
		(end 345.747086 -218.536266)
		(width 0.14224)
		(layer "In13.Cu")
		(net "GMI_CPU0_G0_CPU1_G2_TX_DN<13>")
	)
	(segment
		(start 124.716032 -236.68863)
		(end 124.786898 -236.729778)
		(width 0.1143)
		(layer "In13.Cu")
		(net "GMI_CPU0_G0_CPU1_G2_TX_DN<13>")
	)
	(segment
		(start 124.716032 -241.548666)
		(end 124.747782 -241.566954)
		(width 0.1143)
		(layer "In13.Cu")
		(net "GMI_CPU0_G0_CPU1_G2_TX_DN<13>")
	)
	(segment
		(start 124.78131 -231.18191)
		(end 124.740924 -231.205532)
		(width 0.1143)
		(layer "In13.Cu")
		(net "GMI_CPU0_G0_CPU1_G2_TX_DN<13>")
	)
	(segment
		(start 124.770642 -230.240332)
		(end 124.775214 -230.242872)
		(width 0.1143)
		(layer "In13.Cu")
		(net "GMI_CPU0_G0_CPU1_G2_TX_DN<13>")
	)
	(segment
		(start 124.747782 -226.34194)
		(end 124.716032 -226.360228)
		(width 0.1143)
		(layer "In13.Cu")
		(net "GMI_CPU0_G0_CPU1_G2_TX_DN<13>")
	)
	(segment
		(start 303.7332 -189.451488)
		(end 262.688832 -189.07252)
		(width 0.14224)
		(layer "In13.Cu")
		(net "GMI_CPU0_G0_CPU1_G2_TX_DN<13>")
	)
	(segment
		(start 345.919044 -242.864132)
		(end 346.001848 -242.781328)
		(width 0.1143)
		(layer "In13.Cu")
		(net "GMI_CPU0_G0_CPU1_G2_TX_DN<13>")
	)
	(segment
		(start 124.786898 -237.65891)
		(end 124.747782 -237.68177)
		(width 0.1143)
		(layer "In13.Cu")
		(net "GMI_CPU0_G0_CPU1_G2_TX_DN<13>")
	)
	(segment
		(start 157.395164 -193.708274)
		(end 157.395164 -193.708782)
		(width 0.14224)
		(layer "In13.Cu")
		(net "GMI_CPU0_G0_CPU1_G2_TX_DN<13>")
	)
	(segment
		(start 160.855406 -190.70955)
		(end 160.700466 -190.998348)
		(width 0.14224)
		(layer "In13.Cu")
		(net "GMI_CPU0_G0_CPU1_G2_TX_DN<13>")
	)
	(segment
		(start 346.727526 -230.238554)
		(end 346.729558 -230.237538)
		(width 0.1143)
		(layer "In13.Cu")
		(net "GMI_CPU0_G0_CPU1_G2_TX_DN<13>")
	)
	(segment
		(start 124.727208 -227.97389)
		(end 124.726446 -227.974398)
		(width 0.1143)
		(layer "In13.Cu")
		(net "GMI_CPU0_G0_CPU1_G2_TX_DN<13>")
	)
	(segment
		(start 124.76861 -223.089724)
		(end 124.747274 -223.10217)
		(width 0.1143)
		(layer "In13.Cu")
		(net "GMI_CPU0_G0_CPU1_G2_TX_DN<13>")
	)
	(segment
		(start 124.716032 -239.928654)
		(end 124.747782 -239.946942)
		(width 0.1143)
		(layer "In13.Cu")
		(net "GMI_CPU0_G0_CPU1_G2_TX_DN<13>")
	)
	(segment
		(start 124.766324 -230.237792)
		(end 124.768356 -230.238808)
		(width 0.1143)
		(layer "In13.Cu")
		(net "GMI_CPU0_G0_CPU1_G2_TX_DN<13>")
	)
	(segment
		(start 124.726446 -228.594666)
		(end 124.786136 -228.629464)
		(width 0.1143)
		(layer "In13.Cu")
		(net "GMI_CPU0_G0_CPU1_G2_TX_DN<13>")
	)
	(segment
		(start 346.727272 -234.4293)
		(end 346.727018 -234.4293)
		(width 0.1143)
		(layer "In13.Cu")
		(net "GMI_CPU0_G0_CPU1_G2_TX_DN<13>")
	)
	(segment
		(start 124.703078 -236.679486)
		(end 124.716032 -236.68863)
		(width 0.1143)
		(layer "In13.Cu")
		(net "GMI_CPU0_G0_CPU1_G2_TX_DN<13>")
	)
	(segment
		(start 124.69622 -241.534442)
		(end 124.716032 -241.548666)
		(width 0.1143)
		(layer "In13.Cu")
		(net "GMI_CPU0_G0_CPU1_G2_TX_DN<13>")
	)
	(segment
		(start 156.173678 -194.88785)
		(end 155.980638 -194.8688)
		(width 0.14224)
		(layer "In13.Cu")
		(net "GMI_CPU0_G0_CPU1_G2_TX_DN<13>")
	)
	(segment
		(start 158.790386 -192.742058)
		(end 158.597346 -192.723008)
		(width 0.14224)
		(layer "In13.Cu")
		(net "GMI_CPU0_G0_CPU1_G2_TX_DN<13>")
	)
	(segment
		(start 124.763022 -230.23576)
		(end 124.764546 -230.236776)
		(width 0.1143)
		(layer "In13.Cu")
		(net "GMI_CPU0_G0_CPU1_G2_TX_DN<13>")
	)
	(segment
		(start 155.650692 -195.13931)
		(end 155.631642 -195.33235)
		(width 0.14224)
		(layer "In13.Cu")
		(net "GMI_CPU0_G0_CPU1_G2_TX_DN<13>")
	)
	(segment
		(start 154.429206 -196.318378)
		(end 154.236166 -196.299074)
		(width 0.14224)
		(layer "In13.Cu")
		(net "GMI_CPU0_G0_CPU1_G2_TX_DN<13>")
	)
	(segment
		(start 346.935552 -221.80423)
		(end 346.935552 -221.272862)
		(width 0.1143)
		(layer "In13.Cu")
		(net "GMI_CPU0_G0_CPU1_G2_TX_DN<13>")
	)
	(segment
		(start 124.716032 -224.740216)
		(end 124.69749 -224.753678)
		(width 0.1143)
		(layer "In13.Cu")
		(net "GMI_CPU0_G0_CPU1_G2_TX_DN<13>")
	)
	(segment
		(start 125.187202 -242.35918)
		(end 125.217682 -242.37696)
		(width 0.1143)
		(layer "In13.Cu")
		(net "GMI_CPU0_G0_CPU1_G2_TX_DN<13>")
	)
	(segment
		(start 346.748608 -234.441746)
		(end 346.727272 -234.4293)
		(width 0.1143)
		(layer "In13.Cu")
		(net "GMI_CPU0_G0_CPU1_G2_TX_DN<13>")
	)
	(segment
		(start 233.932476 -199.32396)
		(end 211.720684 -190.123318)
		(width 0.14224)
		(layer "In13.Cu")
		(net "GMI_CPU0_G0_CPU1_G2_TX_DN<13>")
	)
	(segment
		(start 124.56033 -221.273116)
		(end 124.56033 -221.804484)
		(width 0.1143)
		(layer "In13.Cu")
		(net "GMI_CPU0_G0_CPU1_G2_TX_DN<13>")
	)
	(segment
		(start 157.376114 -193.901822)
		(end 157.045914 -194.172586)
		(width 0.14224)
		(layer "In13.Cu")
		(net "GMI_CPU0_G0_CPU1_G2_TX_DN<13>")
	)
	(segment
		(start 346.77985 -236.688376)
		(end 346.792804 -236.679232)
		(width 0.1143)
		(layer "In13.Cu")
		(net "GMI_CPU0_G0_CPU1_G2_TX_DN<13>")
	)
	(segment
		(start 124.671582 -230.166418)
		(end 124.718318 -230.209852)
		(width 0.1143)
		(layer "In13.Cu")
		(net "GMI_CPU0_G0_CPU1_G2_TX_DN<13>")
	)
	(segment
		(start 346.708984 -241.58956)
		(end 346.7481 -241.5667)
		(width 0.1143)
		(layer "In13.Cu")
		(net "GMI_CPU0_G0_CPU1_G2_TX_DN<13>")
	)
	(segment
		(start 309.008272 -189.451488)
		(end 303.7332 -189.451488)
		(width 0.14224)
		(layer "In13.Cu")
		(net "GMI_CPU0_G0_CPU1_G2_TX_DN<13>")
	)
	(segment
		(start 346.775024 -230.211122)
		(end 346.77604 -230.210106)
		(width 0.1143)
		(layer "In13.Cu")
		(net "GMI_CPU0_G0_CPU1_G2_TX_DN<13>")
	)
	(segment
		(start 155.108402 -195.584064)
		(end 154.778456 -195.854574)
		(width 0.14224)
		(layer "In13.Cu")
		(net "GMI_CPU0_G0_CPU1_G2_TX_DN<13>")
	)
	(segment
		(start 124.69749 -225.335338)
		(end 124.716032 -225.3488)
		(width 0.1143)
		(layer "In13.Cu")
		(net "GMI_CPU0_G0_CPU1_G2_TX_DN<13>")
	)
	(segment
		(start 346.77985 -238.308388)
		(end 346.798392 -238.294926)
		(width 0.1143)
		(layer "In13.Cu")
		(net "GMI_CPU0_G0_CPU1_G2_TX_DN<13>")
	)
	(segment
		(start 154.778456 -195.854574)
		(end 154.759406 -196.047614)
		(width 0.14224)
		(layer "In13.Cu")
		(net "GMI_CPU0_G0_CPU1_G2_TX_DN<13>")
	)
	(segment
		(start 153.55697 -197.033388)
		(end 153.36393 -197.014338)
		(width 0.14224)
		(layer "In13.Cu")
		(net "GMI_CPU0_G0_CPU1_G2_TX_DN<13>")
	)
	(segment
		(start 346.769436 -227.974144)
		(end 346.768674 -227.973636)
		(width 0.1143)
		(layer "In13.Cu")
		(net "GMI_CPU0_G0_CPU1_G2_TX_DN<13>")
	)
	(segment
		(start 154.759406 -196.047614)
		(end 154.429206 -196.318378)
		(width 0.14224)
		(layer "In13.Cu")
		(net "GMI_CPU0_G0_CPU1_G2_TX_DN<13>")
	)
	(segment
		(start 346.742766 -235.0897)
		(end 346.743528 -235.089192)
		(width 0.1143)
		(layer "In13.Cu")
		(net "GMI_CPU0_G0_CPU1_G2_TX_DN<13>")
	)
	(segment
		(start 345.747086 -218.536266)
		(end 331.939646 -207.215232)
		(width 0.14224)
		(layer "In13.Cu")
		(net "GMI_CPU0_G0_CPU1_G2_TX_DN<13>")
	)
	(segment
		(start 346.889832 -221.227142)
		(end 346.889832 -221.198694)
		(width 0.1143)
		(layer "In13.Cu")
		(net "GMI_CPU0_G0_CPU1_G2_TX_DN<13>")
	)
	(segment
		(start 346.798392 -224.753424)
		(end 346.77985 -224.739962)
		(width 0.1143)
		(layer "In13.Cu")
		(net "GMI_CPU0_G0_CPU1_G2_TX_DN<13>")
	)
	(segment
		(start 318.029336 -195.810124)
		(end 318.029336 -195.809616)
		(width 0.14224)
		(layer "In13.Cu")
		(net "GMI_CPU0_G0_CPU1_G2_TX_DN<13>")
	)
	(segment
		(start 125.576838 -242.864386)
		(end 125.87478 -242.864386)
		(width 0.1143)
		(layer "In13.Cu")
		(net "GMI_CPU0_G0_CPU1_G2_TX_DN<13>")
	)
	(segment
		(start 346.889832 -221.198694)
		(end 346.89034 -221.198186)
		(width 0.14224)
		(layer "In13.Cu")
		(net "GMI_CPU0_G0_CPU1_G2_TX_DN<13>")
	)
	(segment
		(start 346.7481 -226.986846)
		(end 346.77985 -226.968558)
		(width 0.1143)
		(layer "In13.Cu")
		(net "GMI_CPU0_G0_CPU1_G2_TX_DN<13>")
	)
	(segment
		(start 156.522928 -194.424046)
		(end 156.503878 -194.617086)
		(width 0.14224)
		(layer "In13.Cu")
		(net "GMI_CPU0_G0_CPU1_G2_TX_DN<13>")
	)
	(segment
		(start 346.727018 -234.4293)
		(end 346.708984 -234.418632)
		(width 0.1143)
		(layer "In13.Cu")
		(net "GMI_CPU0_G0_CPU1_G2_TX_DN<13>")
	)
	(segment
		(start 124.717302 -222.109284)
		(end 124.747782 -222.127064)
		(width 0.1143)
		(layer "In13.Cu")
		(net "GMI_CPU0_G0_CPU1_G2_TX_DN<13>")
	)
	(segment
		(start 124.74067 -231.843072)
		(end 124.746258 -231.84612)
		(width 0.1143)
		(layer "In13.Cu")
		(net "GMI_CPU0_G0_CPU1_G2_TX_DN<13>")
	)
	(segment
		(start 251.05487 -191.124078)
		(end 239.58677 -199.154288)
		(width 0.14224)
		(layer "In13.Cu")
		(net "GMI_CPU0_G0_CPU1_G2_TX_DN<13>")
	)
	(segment
		(start 154.236166 -196.299074)
		(end 153.90622 -196.569584)
		(width 0.14224)
		(layer "In13.Cu")
		(net "GMI_CPU0_G0_CPU1_G2_TX_DN<13>")
	)
	(segment
		(start 331.939646 -207.215486)
		(end 318.029336 -195.810124)
		(width 0.14224)
		(layer "In13.Cu")
		(net "GMI_CPU0_G0_CPU1_G2_TX_DN<13>")
	)
	(segment
		(start 346.77985 -232.839768)
		(end 346.7481 -232.82148)
		(width 0.1143)
		(layer "In13.Cu")
		(net "GMI_CPU0_G0_CPU1_G2_TX_DN<13>")
	)
	(segment
		(start 125.494034 -242.781582)
		(end 125.576838 -242.864386)
		(width 0.1143)
		(layer "In13.Cu")
		(net "GMI_CPU0_G0_CPU1_G2_TX_DN<13>")
	)
	(segment
		(start 124.765562 -230.237284)
		(end 124.766324 -230.237792)
		(width 0.1143)
		(layer "In13.Cu")
		(net "GMI_CPU0_G0_CPU1_G2_TX_DN<13>")
	)
	(segment
		(start 124.754132 -235.090462)
		(end 124.786136 -235.109258)
		(width 0.1143)
		(layer "In13.Cu")
		(net "GMI_CPU0_G0_CPU1_G2_TX_DN<13>")
	)
	(segment
		(start 346.77985 -225.348546)
		(end 346.798392 -225.335084)
		(width 0.1143)
		(layer "In13.Cu")
		(net "GMI_CPU0_G0_CPU1_G2_TX_DN<13>")
	)
	(segment
		(start 158.2674 -192.993518)
		(end 158.24835 -193.186558)
		(width 0.14224)
		(layer "In13.Cu")
		(net "GMI_CPU0_G0_CPU1_G2_TX_DN<13>")
	)
	(segment
		(start 346.748862 -231.846374)
		(end 346.749624 -231.845866)
		(width 0.1143)
		(layer "In13.Cu")
		(net "GMI_CPU0_G0_CPU1_G2_TX_DN<13>")
	)
	(segment
		(start 346.727272 -223.08947)
		(end 346.727018 -223.08947)
		(width 0.1143)
		(layer "In13.Cu")
		(net "GMI_CPU0_G0_CPU1_G2_TX_DN<13>")
	)
	(segment
		(start 124.775214 -230.242872)
		(end 124.784358 -230.248206)
		(width 0.1143)
		(layer "In13.Cu")
		(net "GMI_CPU0_G0_CPU1_G2_TX_DN<13>")
	)
	(segment
		(start 124.716032 -226.968812)
		(end 124.747782 -226.9871)
		(width 0.1143)
		(layer "In13.Cu")
		(net "GMI_CPU0_G0_CPU1_G2_TX_DN<13>")
	)
	(segment
		(start 346.708984 -239.969548)
		(end 346.7481 -239.946688)
		(width 0.1143)
		(layer "In13.Cu")
		(net "GMI_CPU0_G0_CPU1_G2_TX_DN<13>")
	)
	(segment
		(start 124.716032 -240.940082)
		(end 124.69622 -240.954306)
		(width 0.1143)
		(layer "In13.Cu")
		(net "GMI_CPU0_G0_CPU1_G2_TX_DN<13>")
	)
	(segment
		(start 124.747782 -236.061758)
		(end 124.716032 -236.080046)
		(width 0.1143)
		(layer "In13.Cu")
		(net "GMI_CPU0_G0_CPU1_G2_TX_DN<13>")
	)
	(segment
		(start 346.935552 -221.272862)
		(end 346.889832 -221.227142)
		(width 0.1143)
		(layer "In13.Cu")
		(net "GMI_CPU0_G0_CPU1_G2_TX_DN<13>")
	)
	(segment
		(start 239.58677 -199.154288)
		(end 236.278928 -199.737726)
		(width 0.14224)
		(layer "In13.Cu")
		(net "GMI_CPU0_G0_CPU1_G2_TX_DN<13>")
	)
	(segment
		(start 346.729558 -230.237538)
		(end 346.73032 -230.23703)
		(width 0.1143)
		(layer "In13.Cu")
		(net "GMI_CPU0_G0_CPU1_G2_TX_DN<13>")
	)
	(segment
		(start 346.749624 -231.845866)
		(end 346.755212 -231.842818)
		(width 0.1143)
		(layer "In13.Cu")
		(net "GMI_CPU0_G0_CPU1_G2_TX_DN<13>")
	)
	(segment
		(start 155.980638 -194.8688)
		(end 155.650692 -195.13931)
		(width 0.14224)
		(layer "In13.Cu")
		(net "GMI_CPU0_G0_CPU1_G2_TX_DN<13>")
	)
	(segment
		(start 346.77985 -237.699804)
		(end 346.7481 -237.681516)
		(width 0.1143)
		(layer "In13.Cu")
		(net "GMI_CPU0_G0_CPU1_G2_TX_DN<13>")
	)
	(segment
		(start 346.708984 -222.14967)
		(end 346.77858 -222.10903)
		(width 0.1143)
		(layer "In13.Cu")
		(net "GMI_CPU0_G0_CPU1_G2_TX_DN<13>")
	)
	(segment
		(start 346.732098 -230.236014)
		(end 346.775024 -230.211122)
		(width 0.1143)
		(layer "In13.Cu")
		(net "GMI_CPU0_G0_CPU1_G2_TX_DN<13>")
	)
	(segment
		(start 262.688832 -189.07252)
		(end 251.05487 -191.124078)
		(width 0.14224)
		(layer "In13.Cu")
		(net "GMI_CPU0_G0_CPU1_G2_TX_DN<13>")
	)
	(segment
		(start 346.708984 -225.389694)
		(end 346.77985 -225.348546)
		(width 0.1143)
		(layer "In13.Cu")
		(net "GMI_CPU0_G0_CPU1_G2_TX_DN<13>")
	)
	(segment
		(start 346.714572 -231.181656)
		(end 346.708984 -231.178862)
		(width 0.1143)
		(layer "In13.Cu")
		(net "GMI_CPU0_G0_CPU1_G2_TX_DN<13>")
	)
	(segment
		(start 346.745306 -229.579932)
		(end 346.708984 -229.55885)
		(width 0.1143)
		(layer "In13.Cu")
		(net "GMI_CPU0_G0_CPU1_G2_TX_DN<13>")
	)
	(segment
		(start 125.872748 -218.410282)
		(end 124.605542 -220.61678)
		(width 0.14224)
		(layer "In13.Cu")
		(net "GMI_CPU0_G0_CPU1_G2_TX_DN<13>")
	)
	(segment
		(start 346.77985 -224.739962)
		(end 346.7481 -224.721674)
		(width 0.1143)
		(layer "In13.Cu")
		(net "GMI_CPU0_G0_CPU1_G2_TX_DN<13>")
	)
	(segment
		(start 124.716032 -225.3488)
		(end 124.786898 -225.389948)
		(width 0.1143)
		(layer "In13.Cu")
		(net "GMI_CPU0_G0_CPU1_G2_TX_DN<13>")
	)
	(segment
		(start 160.700466 -190.998348)
		(end 160.011872 -191.56299)
		(width 0.14224)
		(layer "In13.Cu")
		(net "GMI_CPU0_G0_CPU1_G2_TX_DN<13>")
	)
	(segment
		(start 124.786898 -224.699068)
		(end 124.747782 -224.721928)
		(width 0.1143)
		(layer "In13.Cu")
		(net "GMI_CPU0_G0_CPU1_G2_TX_DN<13>")
	)
	(segment
		(start 159.662622 -192.026794)
		(end 159.469582 -192.007744)
		(width 0.14224)
		(layer "In13.Cu")
		(net "GMI_CPU0_G0_CPU1_G2_TX_DN<13>")
	)
	(segment
		(start 124.786898 -223.079056)
		(end 124.768864 -223.089724)
		(width 0.1143)
		(layer "In13.Cu")
		(net "GMI_CPU0_G0_CPU1_G2_TX_DN<13>")
	)
	(segment
		(start 124.786898 -236.038898)
		(end 124.747782 -236.061758)
		(width 0.1143)
		(layer "In13.Cu")
		(net "GMI_CPU0_G0_CPU1_G2_TX_DN<13>")
	)
	(segment
		(start 157.72511 -193.438272)
		(end 157.724856 -193.438272)
		(width 0.14224)
		(layer "In13.Cu")
		(net "GMI_CPU0_G0_CPU1_G2_TX_DN<13>")
	)
	(segment
		(start 157.045914 -194.172586)
		(end 156.852874 -194.153536)
		(width 0.14224)
		(layer "In13.Cu")
		(net "GMI_CPU0_G0_CPU1_G2_TX_DN<13>")
	)
	(segment
		(start 124.605542 -221.19844)
		(end 124.60605 -221.198948)
		(width 0.14224)
		(layer "In13.Cu")
		(net "GMI_CPU0_G0_CPU1_G2_TX_DN<13>")
	)
	(segment
		(start 124.716032 -238.308642)
		(end 124.786898 -238.34979)
		(width 0.1143)
		(layer "In13.Cu")
		(net "GMI_CPU0_G0_CPU1_G2_TX_DN<13>")
	)
	(segment
		(start 156.503878 -194.617086)
		(end 156.173678 -194.88785)
		(width 0.14224)
		(layer "In13.Cu")
		(net "GMI_CPU0_G0_CPU1_G2_TX_DN<13>")
	)
	(segment
		(start 153.36393 -197.014338)
		(end 148.715984 -200.824846)
		(width 0.14224)
		(layer "In13.Cu")
		(net "GMI_CPU0_G0_CPU1_G2_TX_DN<13>")
	)
	(segment
		(start 346.709746 -235.109004)
		(end 346.74175 -235.090208)
		(width 0.1143)
		(layer "In13.Cu")
		(net "GMI_CPU0_G0_CPU1_G2_TX_DN<13>")
	)
	(segment
		(start 124.725938 -228.594666)
		(end 124.726446 -228.594666)
		(width 0.1143)
		(layer "In13.Cu")
		(net "GMI_CPU0_G0_CPU1_G2_TX_DN<13>")
	)
	(segment
		(start 124.60605 -221.198948)
		(end 124.60605 -221.227396)
		(width 0.1143)
		(layer "In13.Cu")
		(net "GMI_CPU0_G0_CPU1_G2_TX_DN<13>")
	)
	(segment
		(start 346.743528 -235.089192)
		(end 346.755974 -235.08208)
		(width 0.1143)
		(layer "In13.Cu")
		(net "GMI_CPU0_G0_CPU1_G2_TX_DN<13>")
	)
	(segment
		(start 124.747782 -241.566954)
		(end 124.786898 -241.589814)
		(width 0.1143)
		(layer "In13.Cu")
		(net "GMI_CPU0_G0_CPU1_G2_TX_DN<13>")
	)
	(segment
		(start 124.605542 -220.61678)
		(end 124.605542 -221.19844)
		(width 0.14224)
		(layer "In13.Cu")
		(net "GMI_CPU0_G0_CPU1_G2_TX_DN<13>")
	)
	(segment
		(start 153.88717 -196.762624)
		(end 153.55697 -197.033388)
		(width 0.14224)
		(layer "In13.Cu")
		(net "GMI_CPU0_G0_CPU1_G2_TX_DN<13>")
	)
	(segment
		(start 346.708984 -227.009706)
		(end 346.7481 -226.986846)
		(width 0.1143)
		(layer "In13.Cu")
		(net "GMI_CPU0_G0_CPU1_G2_TX_DN<13>")
	)
	(segment
		(start 124.60605 -221.227396)
		(end 124.56033 -221.273116)
		(width 0.1143)
		(layer "In13.Cu")
		(net "GMI_CPU0_G0_CPU1_G2_TX_DN<13>")
	)
	(segment
		(start 346.77985 -239.319816)
		(end 346.7481 -239.301528)
		(width 0.1143)
		(layer "In13.Cu")
		(net "GMI_CPU0_G0_CPU1_G2_TX_DN<13>")
	)
	(segment
		(start 160.011872 -191.56299)
		(end 159.992822 -191.75603)
		(width 0.14224)
		(layer "In13.Cu")
		(net "GMI_CPU0_G0_CPU1_G2_TX_DN<13>")
	)
	(segment
		(start 124.768864 -234.429554)
		(end 124.76861 -234.429554)
		(width 0.1143)
		(layer "In13.Cu")
		(net "GMI_CPU0_G0_CPU1_G2_TX_DN<13>")
	)
	(segment
		(start 346.72524 -230.240078)
		(end 346.727526 -230.238554)
		(width 0.1143)
		(layer "In13.Cu")
		(net "GMI_CPU0_G0_CPU1_G2_TX_DN<13>")
	)
	(segment
		(start 346.709746 -231.86898)
		(end 346.748862 -231.846374)
		(width 0.1143)
		(layer "In13.Cu")
		(net "GMI_CPU0_G0_CPU1_G2_TX_DN<13>")
	)
	(segment
		(start 124.786898 -239.278922)
		(end 124.747782 -239.301782)
		(width 0.1143)
		(layer "In13.Cu")
		(net "GMI_CPU0_G0_CPU1_G2_TX_DN<13>")
	)
	(segment
		(start 124.786898 -232.798874)
		(end 124.747782 -232.821734)
		(width 0.1143)
		(layer "In13.Cu")
		(net "GMI_CPU0_G0_CPU1_G2_TX_DN<13>")
	)
	(segment
		(start 124.752354 -235.089446)
		(end 124.753116 -235.089954)
		(width 0.1143)
		(layer "In13.Cu")
		(net "GMI_CPU0_G0_CPU1_G2_TX_DN<13>")
	)
	(segment
		(start 236.278928 -199.737726)
		(end 233.932476 -199.32396)
		(width 0.14224)
		(layer "In13.Cu")
		(net "GMI_CPU0_G0_CPU1_G2_TX_DN<13>")
	)
	(segment
		(start 124.747782 -232.821734)
		(end 124.716032 -232.840022)
		(width 0.1143)
		(layer "In13.Cu")
		(net "GMI_CPU0_G0_CPU1_G2_TX_DN<13>")
	)
	(segment
		(start 346.7481 -224.721674)
		(end 346.708984 -224.698814)
		(width 0.1143)
		(layer "In13.Cu")
		(net "GMI_CPU0_G0_CPU1_G2_TX_DN<13>")
	)
	(segment
		(start 346.76969 -227.974144)
		(end 346.769436 -227.974144)
		(width 0.1143)
		(layer "In13.Cu")
		(net "GMI_CPU0_G0_CPU1_G2_TX_DN<13>")
	)
	(segment
		(start 124.768356 -230.238808)
		(end 124.770642 -230.240332)
		(width 0.1143)
		(layer "In13.Cu")
		(net "GMI_CPU0_G0_CPU1_G2_TX_DN<13>")
	)
	(segment
		(start 155.631642 -195.33235)
		(end 155.301442 -195.603114)
		(width 0.14224)
		(layer "In13.Cu")
		(net "GMI_CPU0_G0_CPU1_G2_TX_DN<13>")
	)
	(segment
		(start 346.77985 -236.079792)
		(end 346.7481 -236.061504)
		(width 0.1143)
		(layer "In13.Cu")
		(net "GMI_CPU0_G0_CPU1_G2_TX_DN<13>")
	)
	(segment
		(start 153.90622 -196.569584)
		(end 153.88717 -196.762624)
		(width 0.14224)
		(layer "In13.Cu")
		(net "GMI_CPU0_G0_CPU1_G2_TX_DN<13>")
	)
	(segment
		(start 124.747782 -224.721928)
		(end 124.716032 -224.740216)
		(width 0.1143)
		(layer "In13.Cu")
		(net "GMI_CPU0_G0_CPU1_G2_TX_DN<13>")
	)
	(segment
		(start 346.711524 -230.247952)
		(end 346.720668 -230.242618)
		(width 0.1143)
		(layer "In13.Cu")
		(net "GMI_CPU0_G0_CPU1_G2_TX_DN<13>")
	)
	(segment
		(start 346.731336 -230.236522)
		(end 346.732098 -230.236014)
		(width 0.1143)
		(layer "In13.Cu")
		(net "GMI_CPU0_G0_CPU1_G2_TX_DN<13>")
	)
	(segment
		(start 124.753116 -235.089954)
		(end 124.754132 -235.090462)
		(width 0.1143)
		(layer "In13.Cu")
		(net "GMI_CPU0_G0_CPU1_G2_TX_DN<13>")
	)
	(segment
		(start 346.7481 -237.681516)
		(end 346.708984 -237.658656)
		(width 0.1143)
		(layer "In13.Cu")
		(net "GMI_CPU0_G0_CPU1_G2_TX_DN<13>")
	)
	(segment
		(start 124.716032 -233.448606)
		(end 124.786898 -233.489754)
		(width 0.1143)
		(layer "In13.Cu")
		(net "GMI_CPU0_G0_CPU1_G2_TX_DN<13>")
	)
	(segment
		(start 158.24835 -193.186558)
		(end 157.91815 -193.457322)
		(width 0.14224)
		(layer "In13.Cu")
		(net "GMI_CPU0_G0_CPU1_G2_TX_DN<13>")
	)
	(segment
		(start 159.139636 -192.278254)
		(end 159.120586 -192.471294)
		(width 0.14224)
		(layer "In13.Cu")
		(net "GMI_CPU0_G0_CPU1_G2_TX_DN<13>")
	)
	(segment
		(start 124.69749 -238.29518)
		(end 124.716032 -238.308642)
		(width 0.1143)
		(layer "In13.Cu")
		(net "GMI_CPU0_G0_CPU1_G2_TX_DN<13>")
	)
	(segment
		(start 159.992822 -191.75603)
		(end 159.662622 -192.026794)
		(width 0.14224)
		(layer "In13.Cu")
		(net "GMI_CPU0_G0_CPU1_G2_TX_DN<13>")
	)
	(segment
		(start 148.715984 -200.824846)
		(end 146.501866 -201.495914)
		(width 0.14224)
		(layer "In13.Cu")
		(net "GMI_CPU0_G0_CPU1_G2_TX_DN<13>")
	)
	(segment
		(start 207.337406 -189.350396)
		(end 162.279076 -189.541404)
		(width 0.14224)
		(layer "In13.Cu")
		(net "GMI_CPU0_G0_CPU1_G2_TX_DN<13>")
	)
	(segment
		(start 346.7481 -232.82148)
		(end 346.708984 -232.79862)
		(width 0.1143)
		(layer "In13.Cu")
		(net "GMI_CPU0_G0_CPU1_G2_TX_DN<13>")
	)
	(segment
		(start 346.798392 -237.713266)
		(end 346.77985 -237.699804)
		(width 0.1143)
		(layer "In13.Cu")
		(net "GMI_CPU0_G0_CPU1_G2_TX_DN<13>")
	)
	(segment
		(start 346.781374 -229.601014)
		(end 346.745306 -229.579932)
		(width 0.1143)
		(layer "In13.Cu")
		(net "GMI_CPU0_G0_CPU1_G2_TX_DN<13>")
	)
	(segment
		(start 124.786898 -226.31908)
		(end 124.747782 -226.34194)
		(width 0.1143)
		(layer "In13.Cu")
		(net "GMI_CPU0_G0_CPU1_G2_TX_DN<13>")
	)
	(segment
		(start 124.747782 -237.68177)
		(end 124.716032 -237.700058)
		(width 0.1143)
		(layer "In13.Cu")
		(net "GMI_CPU0_G0_CPU1_G2_TX_DN<13>")
	)
	(segment
		(start 345.621102 -242.864132)
		(end 345.919044 -242.864132)
		(width 0.1143)
		(layer "In13.Cu")
		(net "GMI_CPU0_G0_CPU1_G2_TX_DN<13>")
	)
	(segment
		(start 124.786898 -227.939092)
		(end 124.727208 -227.97389)
		(width 0.1143)
		(layer "In13.Cu")
		(net "GMI_CPU0_G0_CPU1_G2_TX_DN<13>")
	)
	(segment
		(start 124.716032 -237.700058)
		(end 124.69749 -237.71352)
		(width 0.1143)
		(layer "In13.Cu")
		(net "GMI_CPU0_G0_CPU1_G2_TX_DN<13>")
	)
	(segment
		(start 124.747782 -226.9871)
		(end 124.786898 -227.00996)
		(width 0.1143)
		(layer "In13.Cu")
		(net "GMI_CPU0_G0_CPU1_G2_TX_DN<13>")
	)
	(segment
		(start 346.708984 -233.4895)
		(end 346.77985 -233.448352)
		(width 0.1143)
		(layer "In13.Cu")
		(net "GMI_CPU0_G0_CPU1_G2_TX_DN<13>")
	)
	(segment
		(start 211.720684 -190.123318)
		(end 207.337406 -189.350396)
		(width 0.14224)
		(layer "In13.Cu")
		(net "GMI_CPU0_G0_CPU1_G2_TX_DN<13>")
	)
	(segment
		(start 158.597346 -192.723008)
		(end 158.2674 -192.993518)
		(width 0.14224)
		(layer "In13.Cu")
		(net "GMI_CPU0_G0_CPU1_G2_TX_DN<13>")
	)
	(segment
		(start 346.720668 -230.242618)
		(end 346.72524 -230.240078)
		(width 0.1143)
		(layer "In13.Cu")
		(net "GMI_CPU0_G0_CPU1_G2_TX_DN<13>")
	)
	(segment
		(start 124.764546 -230.236776)
		(end 124.765562 -230.237284)
		(width 0.1143)
		(layer "In13.Cu")
		(net "GMI_CPU0_G0_CPU1_G2_TX_DN<13>")
	)
	(segment
		(start 346.799662 -240.954052)
		(end 346.77985 -240.939828)
		(width 0.1143)
		(layer "In13.Cu")
		(net "GMI_CPU0_G0_CPU1_G2_TX_DN<13>")
	)
	(segment
		(start 331.939646 -207.215232)
		(end 331.939646 -207.215486)
		(width 0.14224)
		(layer "In13.Cu")
		(net "GMI_CPU0_G0_CPU1_G2_TX_DN<13>")
	)
	(segment
		(start 159.120586 -192.471294)
		(end 158.790386 -192.742058)
		(width 0.14224)
		(layer "In13.Cu")
		(net "GMI_CPU0_G0_CPU1_G2_TX_DN<13>")
	)
	(segment
		(start 346.792804 -232.848912)
		(end 346.77985 -232.839768)
		(width 0.1143)
		(layer "In13.Cu")
		(net "GMI_CPU0_G0_CPU1_G2_TX_DN<13>")
	)
	(segment
		(start 346.777056 -230.210106)
		(end 346.799154 -230.190802)
		(width 0.1143)
		(layer "In13.Cu")
		(net "GMI_CPU0_G0_CPU1_G2_TX_DN<13>")
	)
	(segment
		(start 346.7481 -239.301528)
		(end 346.708984 -239.278668)
		(width 0.1143)
		(layer "In13.Cu")
		(net "GMI_CPU0_G0_CPU1_G2_TX_DN<13>")
	)
	(segment
		(start 346.7481 -241.5667)
		(end 346.77985 -241.548412)
		(width 0.1143)
		(layer "In13.Cu")
		(net "GMI_CPU0_G0_CPU1_G2_TX_DN<13>")
	)
	(segment
		(start 155.301442 -195.603114)
		(end 155.108402 -195.584064)
		(width 0.14224)
		(layer "In13.Cu")
		(net "GMI_CPU0_G0_CPU1_G2_TX_DN<13>")
	)
	(segment
		(start 346.74175 -235.090208)
		(end 346.742766 -235.0897)
		(width 0.1143)
		(layer "In13.Cu")
		(net "GMI_CPU0_G0_CPU1_G2_TX_DN<13>")
	)
	(segment
		(start 124.768864 -223.089724)
		(end 124.76861 -223.089724)
		(width 0.1143)
		(layer "In13.Cu")
		(net "GMI_CPU0_G0_CPU1_G2_TX_DN<13>")
	)
	(segment
		(start 146.501866 -201.495914)
		(end 125.872748 -218.410282)
		(width 0.14224)
		(layer "In13.Cu")
		(net "GMI_CPU0_G0_CPU1_G2_TX_DN<13>")
	)
	(segment
		(start 346.7481 -236.061504)
		(end 346.708984 -236.038644)
		(width 0.1143)
		(layer "In13.Cu")
		(net "GMI_CPU0_G0_CPU1_G2_TX_DN<13>")
	)
	(segment
		(start 346.708984 -236.729524)
		(end 346.77985 -236.688376)
		(width 0.1143)
		(layer "In13.Cu")
		(net "GMI_CPU0_G0_CPU1_G2_TX_DN<13>")
	)
	(segment
		(start 124.74702 -231.846628)
		(end 124.786136 -231.869234)
		(width 0.1143)
		(layer "In13.Cu")
		(net "GMI_CPU0_G0_CPU1_G2_TX_DN<13>")
	)
	(segment
		(start 346.7481 -226.341686)
		(end 346.708984 -226.318826)
		(width 0.1143)
		(layer "In13.Cu")
		(net "GMI_CPU0_G0_CPU1_G2_TX_DN<13>")
	)
	(segment
		(start 346.754958 -231.205278)
		(end 346.714572 -231.181656)
		(width 0.1143)
		(layer "In13.Cu")
		(net "GMI_CPU0_G0_CPU1_G2_TX_DN<13>")
	)
	(segment
		(start 124.716032 -236.080046)
		(end 124.703078 -236.08919)
		(width 0.1143)
		(layer "In13.Cu")
		(net "GMI_CPU0_G0_CPU1_G2_TX_DN<13>")
	)
	(segment
		(start 346.748608 -223.101916)
		(end 346.727272 -223.08947)
		(width 0.1143)
		(layer "In13.Cu")
		(net "GMI_CPU0_G0_CPU1_G2_TX_DN<13>")
	)
	(segment
		(start 346.73032 -230.23703)
		(end 346.731336 -230.236522)
		(width 0.1143)
		(layer "In13.Cu")
		(net "GMI_CPU0_G0_CPU1_G2_TX_DN<13>")
	)
	(segment
		(start 124.739908 -223.742504)
		(end 124.754894 -223.75114)
		(width 0.1143)
		(layer "In13.Cu")
		(net "GMI_CPU0_G0_CPU1_G2_TX_DN<13>")
	)
	(segment
		(start 124.746258 -231.84612)
		(end 124.74702 -231.846628)
		(width 0.1143)
		(layer "In13.Cu")
		(net "GMI_CPU0_G0_CPU1_G2_TX_DN<13>")
	)
	(segment
		(start 346.77604 -230.210106)
		(end 346.777056 -230.210106)
		(width 0.1143)
		(layer "In13.Cu")
		(net "GMI_CPU0_G0_CPU1_G2_TX_DN<13>")
	)
	(segment
		(start 124.747782 -239.301782)
		(end 124.716032 -239.32007)
		(width 0.1143)
		(layer "In13.Cu")
		(net "GMI_CPU0_G0_CPU1_G2_TX_DN<13>")
	)
	(segment
		(start 346.77985 -241.548412)
		(end 346.799662 -241.534188)
		(width 0.1143)
		(layer "In13.Cu")
		(net "GMI_CPU0_G0_CPU1_G2_TX_DN<13>")
	)
	(segment
		(start 346.932758 -229.927912)
		(end 346.935552 -229.896162)
		(width 0.1143)
		(layer "In13.Cu")
		(net "GMI_CPU0_G0_CPU1_G2_TX_DN<13>")
	)
	(segment
		(start 124.786898 -229.559104)
		(end 124.714254 -229.601522)
		(width 0.1143)
		(layer "In13.Cu")
		(net "GMI_CPU0_G0_CPU1_G2_TX_DN<13>")
	)
	(segment
		(start 346.768674 -227.973636)
		(end 346.708984 -227.938838)
		(width 0.1143)
		(layer "In13.Cu")
		(net "GMI_CPU0_G0_CPU1_G2_TX_DN<13>")
	)
	(segment
		(start 346.709746 -228.62921)
		(end 346.769436 -228.594412)
		(width 0.1143)
		(layer "In13.Cu")
		(net "GMI_CPU0_G0_CPU1_G2_TX_DN<13>")
	)
	(arc
		(start 346.708984 -224.698814)
		(mid 346.465657 -224.234248)
		(end 346.708984 -223.769682)
		(width 0.1143)
		(layer "In13.Cu")
		(net "GMI_CPU0_G0_CPU1_G2_TX_DN<13>")
	)
	(arc
		(start 346.798392 -225.335084)
		(mid 346.947407 -225.044254)
		(end 346.798392 -224.753424)
		(width 0.1143)
		(layer "In13.Cu")
		(net "GMI_CPU0_G0_CPU1_G2_TX_DN<13>")
	)
	(arc
		(start 346.708984 -228.629718)
		(mid 346.709365 -228.629464)
		(end 346.709746 -228.62921)
		(width 0.1143)
		(layer "In13.Cu")
		(net "GMI_CPU0_G0_CPU1_G2_TX_DN<13>")
	)
	(arc
		(start 346.77985 -239.9284)
		(mid 346.931439 -239.624108)
		(end 346.77985 -239.319816)
		(width 0.1143)
		(layer "In13.Cu")
		(net "GMI_CPU0_G0_CPU1_G2_TX_DN<13>")
	)
	(arc
		(start 124.69749 -237.71352)
		(mid 124.548475 -238.00435)
		(end 124.69749 -238.29518)
		(width 0.1143)
		(layer "In13.Cu")
		(net "GMI_CPU0_G0_CPU1_G2_TX_DN<13>")
	)
	(arc
		(start 124.69749 -224.753678)
		(mid 124.548475 -225.044508)
		(end 124.69749 -225.335338)
		(width 0.1143)
		(layer "In13.Cu")
		(net "GMI_CPU0_G0_CPU1_G2_TX_DN<13>")
	)
	(arc
		(start 124.747274 -223.10217)
		(mid 124.561754 -223.420227)
		(end 124.739908 -223.742504)
		(width 0.1143)
		(layer "In13.Cu")
		(net "GMI_CPU0_G0_CPU1_G2_TX_DN<13>")
	)
	(arc
		(start 124.786898 -241.589814)
		(mid 124.865321 -241.655295)
		(end 124.930662 -241.733832)
		(width 0.1143)
		(layer "In13.Cu")
		(net "GMI_CPU0_G0_CPU1_G2_TX_DN<13>")
	)
	(arc
		(start 124.69622 -240.954306)
		(mid 124.547506 -241.244374)
		(end 124.69622 -241.534442)
		(width 0.1143)
		(layer "In13.Cu")
		(net "GMI_CPU0_G0_CPU1_G2_TX_DN<13>")
	)
	(arc
		(start 125.03023 -230.71455)
		(mid 124.965715 -230.976769)
		(end 124.786898 -231.179116)
		(width 0.1143)
		(layer "In13.Cu")
		(net "GMI_CPU0_G0_CPU1_G2_TX_DN<13>")
	)
	(arc
		(start 346.708984 -223.769682)
		(mid 346.709365 -223.769428)
		(end 346.709746 -223.769174)
		(width 0.1143)
		(layer "In13.Cu")
		(net "GMI_CPU0_G0_CPU1_G2_TX_DN<13>")
	)
	(arc
		(start 346.755974 -235.08208)
		(mid 346.934191 -234.759803)
		(end 346.748608 -234.441746)
		(width 0.1143)
		(layer "In13.Cu")
		(net "GMI_CPU0_G0_CPU1_G2_TX_DN<13>")
	)
	(arc
		(start 346.708984 -229.55885)
		(mid 346.465657 -229.094284)
		(end 346.708984 -228.629718)
		(width 0.1143)
		(layer "In13.Cu")
		(net "GMI_CPU0_G0_CPU1_G2_TX_DN<13>")
	)
	(arc
		(start 346.755212 -231.842818)
		(mid 346.938063 -231.523938)
		(end 346.754958 -231.205278)
		(width 0.1143)
		(layer "In13.Cu")
		(net "GMI_CPU0_G0_CPU1_G2_TX_DN<13>")
	)
	(arc
		(start 346.798392 -238.294926)
		(mid 346.947407 -238.004096)
		(end 346.798392 -237.713266)
		(width 0.1143)
		(layer "In13.Cu")
		(net "GMI_CPU0_G0_CPU1_G2_TX_DN<13>")
	)
	(arc
		(start 124.716032 -226.360228)
		(mid 124.566935 -226.66452)
		(end 124.716032 -226.968812)
		(width 0.1143)
		(layer "In13.Cu")
		(net "GMI_CPU0_G0_CPU1_G2_TX_DN<13>")
	)
	(arc
		(start 125.256798 -242.39982)
		(mid 125.408785 -242.556328)
		(end 125.490224 -242.758722)
		(width 0.1143)
		(layer "In13.Cu")
		(net "GMI_CPU0_G0_CPU1_G2_TX_DN<13>")
	)
	(arc
		(start 346.708984 -227.938838)
		(mid 346.465657 -227.474272)
		(end 346.708984 -227.009706)
		(width 0.1143)
		(layer "In13.Cu")
		(net "GMI_CPU0_G0_CPU1_G2_TX_DN<13>")
	)
	(arc
		(start 346.77985 -226.968558)
		(mid 346.928947 -226.664266)
		(end 346.77985 -226.359974)
		(width 0.1143)
		(layer "In13.Cu")
		(net "GMI_CPU0_G0_CPU1_G2_TX_DN<13>")
	)
	(arc
		(start 346.799662 -241.534188)
		(mid 346.948376 -241.24412)
		(end 346.799662 -240.954052)
		(width 0.1143)
		(layer "In13.Cu")
		(net "GMI_CPU0_G0_CPU1_G2_TX_DN<13>")
	)
	(arc
		(start 124.784358 -230.248206)
		(mid 124.96501 -230.450951)
		(end 125.03023 -230.71455)
		(width 0.1143)
		(layer "In13.Cu")
		(net "GMI_CPU0_G0_CPU1_G2_TX_DN<13>")
	)
	(arc
		(start 346.708984 -232.79862)
		(mid 346.465657 -232.334054)
		(end 346.708984 -231.869488)
		(width 0.1143)
		(layer "In13.Cu")
		(net "GMI_CPU0_G0_CPU1_G2_TX_DN<13>")
	)
	(arc
		(start 124.703078 -232.849166)
		(mid 124.551826 -233.144314)
		(end 124.703078 -233.439462)
		(width 0.1143)
		(layer "In13.Cu")
		(net "GMI_CPU0_G0_CPU1_G2_TX_DN<13>")
	)
	(arc
		(start 124.786898 -228.629972)
		(mid 125.030225 -229.094538)
		(end 124.786898 -229.559104)
		(width 0.1143)
		(layer "In13.Cu")
		(net "GMI_CPU0_G0_CPU1_G2_TX_DN<13>")
	)
	(arc
		(start 124.930662 -241.733832)
		(mid 125.004776 -241.886546)
		(end 125.03023 -242.05438)
		(width 0.1143)
		(layer "In13.Cu")
		(net "GMI_CPU0_G0_CPU1_G2_TX_DN<13>")
	)
	(arc
		(start 346.792804 -233.439208)
		(mid 346.944056 -233.14406)
		(end 346.792804 -232.848912)
		(width 0.1143)
		(layer "In13.Cu")
		(net "GMI_CPU0_G0_CPU1_G2_TX_DN<13>")
	)
	(arc
		(start 124.726192 -227.974398)
		(mid 124.54765 -228.284422)
		(end 124.725938 -228.594666)
		(width 0.1143)
		(layer "In13.Cu")
		(net "GMI_CPU0_G0_CPU1_G2_TX_DN<13>")
	)
	(arc
		(start 346.001848 -242.781328)
		(mid 346.003636 -242.769879)
		(end 346.005658 -242.758468)
		(width 0.1143)
		(layer "In13.Cu")
		(net "GMI_CPU0_G0_CPU1_G2_TX_DN<13>")
	)
	(arc
		(start 346.708984 -236.038644)
		(mid 346.465657 -235.574078)
		(end 346.708984 -235.109512)
		(width 0.1143)
		(layer "In13.Cu")
		(net "GMI_CPU0_G0_CPU1_G2_TX_DN<13>")
	)
	(arc
		(start 124.786898 -225.389948)
		(mid 125.030225 -225.854514)
		(end 124.786898 -226.31908)
		(width 0.1143)
		(layer "In13.Cu")
		(net "GMI_CPU0_G0_CPU1_G2_TX_DN<13>")
	)
	(arc
		(start 346.465652 -242.054126)
		(mid 346.491072 -241.886281)
		(end 346.56522 -241.733578)
		(width 0.1143)
		(layer "In13.Cu")
		(net "GMI_CPU0_G0_CPU1_G2_TX_DN<13>")
	)
	(arc
		(start 346.708984 -231.869488)
		(mid 346.709365 -231.869234)
		(end 346.709746 -231.86898)
		(width 0.1143)
		(layer "In13.Cu")
		(net "GMI_CPU0_G0_CPU1_G2_TX_DN<13>")
	)
	(arc
		(start 124.786898 -238.34979)
		(mid 125.030225 -238.814356)
		(end 124.786898 -239.278922)
		(width 0.1143)
		(layer "In13.Cu")
		(net "GMI_CPU0_G0_CPU1_G2_TX_DN<13>")
	)
	(arc
		(start 124.740924 -231.205532)
		(mid 124.557947 -231.524192)
		(end 124.74067 -231.843072)
		(width 0.1143)
		(layer "In13.Cu")
		(net "GMI_CPU0_G0_CPU1_G2_TX_DN<13>")
	)
	(arc
		(start 124.56033 -221.804484)
		(mid 124.601879 -221.975906)
		(end 124.717302 -222.109284)
		(width 0.1143)
		(layer "In13.Cu")
		(net "GMI_CPU0_G0_CPU1_G2_TX_DN<13>")
	)
	(arc
		(start 346.708984 -226.318826)
		(mid 346.465657 -225.85426)
		(end 346.708984 -225.389694)
		(width 0.1143)
		(layer "In13.Cu")
		(net "GMI_CPU0_G0_CPU1_G2_TX_DN<13>")
	)
	(arc
		(start 124.786898 -231.869742)
		(mid 125.030225 -232.334308)
		(end 124.786898 -232.798874)
		(width 0.1143)
		(layer "In13.Cu")
		(net "GMI_CPU0_G0_CPU1_G2_TX_DN<13>")
	)
	(arc
		(start 346.005658 -242.758468)
		(mid 346.087091 -242.55607)
		(end 346.239084 -242.399566)
		(width 0.1143)
		(layer "In13.Cu")
		(net "GMI_CPU0_G0_CPU1_G2_TX_DN<13>")
	)
	(arc
		(start 124.714254 -229.601522)
		(mid 124.602918 -229.730592)
		(end 124.56033 -229.895654)
		(width 0.1143)
		(layer "In13.Cu")
		(net "GMI_CPU0_G0_CPU1_G2_TX_DN<13>")
	)
	(arc
		(start 124.786136 -228.629464)
		(mid 124.786517 -228.629718)
		(end 124.786898 -228.629972)
		(width 0.1143)
		(layer "In13.Cu")
		(net "GMI_CPU0_G0_CPU1_G2_TX_DN<13>")
	)
	(arc
		(start 124.786898 -235.109766)
		(mid 125.030225 -235.574332)
		(end 124.786898 -236.038898)
		(width 0.1143)
		(layer "In13.Cu")
		(net "GMI_CPU0_G0_CPU1_G2_TX_DN<13>")
	)
	(arc
		(start 125.490224 -242.758722)
		(mid 125.492247 -242.770132)
		(end 125.494034 -242.781582)
		(width 0.1143)
		(layer "In13.Cu")
		(net "GMI_CPU0_G0_CPU1_G2_TX_DN<13>")
	)
	(arc
		(start 346.792804 -236.679232)
		(mid 346.944056 -236.384084)
		(end 346.792804 -236.088936)
		(width 0.1143)
		(layer "In13.Cu")
		(net "GMI_CPU0_G0_CPU1_G2_TX_DN<13>")
	)
	(arc
		(start 346.799154 -230.190802)
		(mid 346.891218 -230.072198)
		(end 346.932758 -229.927912)
		(width 0.1143)
		(layer "In13.Cu")
		(net "GMI_CPU0_G0_CPU1_G2_TX_DN<13>")
	)
	(arc
		(start 124.747274 -234.442)
		(mid 124.561754 -234.760057)
		(end 124.739908 -235.082334)
		(width 0.1143)
		(layer "In13.Cu")
		(net "GMI_CPU0_G0_CPU1_G2_TX_DN<13>")
	)
	(arc
		(start 124.786898 -239.969802)
		(mid 125.030225 -240.434368)
		(end 124.786898 -240.898934)
		(width 0.1143)
		(layer "In13.Cu")
		(net "GMI_CPU0_G0_CPU1_G2_TX_DN<13>")
	)
	(arc
		(start 346.708984 -239.278668)
		(mid 346.465657 -238.814102)
		(end 346.708984 -238.349536)
		(width 0.1143)
		(layer "In13.Cu")
		(net "GMI_CPU0_G0_CPU1_G2_TX_DN<13>")
	)
	(arc
		(start 124.786136 -231.869234)
		(mid 124.786517 -231.869488)
		(end 124.786898 -231.869742)
		(width 0.1143)
		(layer "In13.Cu")
		(net "GMI_CPU0_G0_CPU1_G2_TX_DN<13>")
	)
	(arc
		(start 346.708984 -234.418632)
		(mid 346.465657 -233.954066)
		(end 346.708984 -233.4895)
		(width 0.1143)
		(layer "In13.Cu")
		(net "GMI_CPU0_G0_CPU1_G2_TX_DN<13>")
	)
	(arc
		(start 346.708984 -235.109512)
		(mid 346.709365 -235.109258)
		(end 346.709746 -235.109004)
		(width 0.1143)
		(layer "In13.Cu")
		(net "GMI_CPU0_G0_CPU1_G2_TX_DN<13>")
	)
	(arc
		(start 124.786898 -227.00996)
		(mid 125.030225 -227.474526)
		(end 124.786898 -227.939092)
		(width 0.1143)
		(layer "In13.Cu")
		(net "GMI_CPU0_G0_CPU1_G2_TX_DN<13>")
	)
	(arc
		(start 346.708984 -231.178862)
		(mid 346.530171 -230.976512)
		(end 346.465652 -230.714296)
		(width 0.1143)
		(layer "In13.Cu")
		(net "GMI_CPU0_G0_CPU1_G2_TX_DN<13>")
	)
	(arc
		(start 124.567188 -229.959154)
		(mid 124.600583 -230.07226)
		(end 124.671582 -230.166418)
		(width 0.1143)
		(layer "In13.Cu")
		(net "GMI_CPU0_G0_CPU1_G2_TX_DN<13>")
	)
	(arc
		(start 346.77858 -222.10903)
		(mid 346.894007 -221.975654)
		(end 346.935552 -221.80423)
		(width 0.1143)
		(layer "In13.Cu")
		(net "GMI_CPU0_G0_CPU1_G2_TX_DN<13>")
	)
	(arc
		(start 346.708984 -223.078802)
		(mid 346.465657 -222.614236)
		(end 346.708984 -222.14967)
		(width 0.1143)
		(layer "In13.Cu")
		(net "GMI_CPU0_G0_CPU1_G2_TX_DN<13>")
	)
	(arc
		(start 124.786136 -235.109258)
		(mid 124.786517 -235.109512)
		(end 124.786898 -235.109766)
		(width 0.1143)
		(layer "In13.Cu")
		(net "GMI_CPU0_G0_CPU1_G2_TX_DN<13>")
	)
	(arc
		(start 124.786136 -223.769428)
		(mid 124.786517 -223.769682)
		(end 124.786898 -223.769936)
		(width 0.1143)
		(layer "In13.Cu")
		(net "GMI_CPU0_G0_CPU1_G2_TX_DN<13>")
	)
	(arc
		(start 124.786898 -223.769936)
		(mid 125.030225 -224.234502)
		(end 124.786898 -224.699068)
		(width 0.1143)
		(layer "In13.Cu")
		(net "GMI_CPU0_G0_CPU1_G2_TX_DN<13>")
	)
	(arc
		(start 346.708984 -240.89868)
		(mid 346.465657 -240.434114)
		(end 346.708984 -239.969548)
		(width 0.1143)
		(layer "In13.Cu")
		(net "GMI_CPU0_G0_CPU1_G2_TX_DN<13>")
	)
	(arc
		(start 346.769944 -228.594412)
		(mid 346.94836 -228.284168)
		(end 346.76969 -227.974144)
		(width 0.1143)
		(layer "In13.Cu")
		(net "GMI_CPU0_G0_CPU1_G2_TX_DN<13>")
	)
	(arc
		(start 124.716032 -239.32007)
		(mid 124.564443 -239.624362)
		(end 124.716032 -239.928654)
		(width 0.1143)
		(layer "In13.Cu")
		(net "GMI_CPU0_G0_CPU1_G2_TX_DN<13>")
	)
	(arc
		(start 124.786898 -236.729778)
		(mid 125.030225 -237.194344)
		(end 124.786898 -237.65891)
		(width 0.1143)
		(layer "In13.Cu")
		(net "GMI_CPU0_G0_CPU1_G2_TX_DN<13>")
	)
	(arc
		(start 125.03023 -242.05438)
		(mid 125.071779 -242.225802)
		(end 125.187202 -242.35918)
		(width 0.1143)
		(layer "In13.Cu")
		(net "GMI_CPU0_G0_CPU1_G2_TX_DN<13>")
	)
	(arc
		(start 124.786898 -233.489754)
		(mid 125.030225 -233.95432)
		(end 124.786898 -234.418886)
		(width 0.1143)
		(layer "In13.Cu")
		(net "GMI_CPU0_G0_CPU1_G2_TX_DN<13>")
	)
	(arc
		(start 346.708984 -237.658656)
		(mid 346.465657 -237.19409)
		(end 346.708984 -236.729524)
		(width 0.1143)
		(layer "In13.Cu")
		(net "GMI_CPU0_G0_CPU1_G2_TX_DN<13>")
	)
	(arc
		(start 346.56522 -241.733578)
		(mid 346.630572 -241.655051)
		(end 346.708984 -241.58956)
		(width 0.1143)
		(layer "In13.Cu")
		(net "GMI_CPU0_G0_CPU1_G2_TX_DN<13>")
	)
	(arc
		(start 124.786898 -222.149924)
		(mid 125.030225 -222.61449)
		(end 124.786898 -223.079056)
		(width 0.1143)
		(layer "In13.Cu")
		(net "GMI_CPU0_G0_CPU1_G2_TX_DN<13>")
	)
	(arc
		(start 346.30868 -242.358926)
		(mid 346.424107 -242.22555)
		(end 346.465652 -242.054126)
		(width 0.1143)
		(layer "In13.Cu")
		(net "GMI_CPU0_G0_CPU1_G2_TX_DN<13>")
	)
	(arc
		(start 346.935552 -229.896162)
		(mid 346.893113 -229.730476)
		(end 346.781374 -229.601014)
		(width 0.1143)
		(layer "In13.Cu")
		(net "GMI_CPU0_G0_CPU1_G2_TX_DN<13>")
	)
	(arc
		(start 346.465652 -230.714296)
		(mid 346.530888 -230.450705)
		(end 346.711524 -230.247952)
		(width 0.1143)
		(layer "In13.Cu")
		(net "GMI_CPU0_G0_CPU1_G2_TX_DN<13>")
	)
	(arc
		(start 346.755974 -223.74225)
		(mid 346.934191 -223.419973)
		(end 346.748608 -223.101916)
		(width 0.1143)
		(layer "In13.Cu")
		(net "GMI_CPU0_G0_CPU1_G2_TX_DN<13>")
	)
	(arc
		(start 124.703078 -236.08919)
		(mid 124.551826 -236.384338)
		(end 124.703078 -236.679486)
		(width 0.1143)
		(layer "In13.Cu")
		(net "GMI_CPU0_G0_CPU1_G2_TX_DN<13>")
	)
	(segment
		(start 348.907862 -241.510058)
		(end 348.44101 -241.24412)
		(width 0.12954)
		(layer "F.Cu")
		(net "GMI_CPU0_G0_CPU1_G2_TX_DN<12>")
	)
	(segment
		(start 122.587766 -241.510312)
		(end 123.054618 -241.244374)
		(width 0.12954)
		(layer "F.Cu")
		(net "GMI_CPU0_G0_CPU1_G2_TX_DN<12>")
	)
	(segment
		(start 123.777248 -225.349308)
		(end 123.807728 -225.367088)
		(width 0.1143)
		(layer "In13.Cu")
		(net "GMI_CPU0_G0_CPU1_G2_TX_DN<12>")
	)
	(segment
		(start 213.034372 -189.400688)
		(end 207.307942 -188.391038)
		(width 0.14224)
		(layer "In13.Cu")
		(net "GMI_CPU0_G0_CPU1_G2_TX_DN<12>")
	)
	(segment
		(start 122.867928 -240.921794)
		(end 122.867166 -240.922302)
		(width 0.1143)
		(layer "In13.Cu")
		(net "GMI_CPU0_G0_CPU1_G2_TX_DN<12>")
	)
	(segment
		(start 347.720666 -229.600506)
		(end 347.688154 -229.58171)
		(width 0.1143)
		(layer "In13.Cu")
		(net "GMI_CPU0_G0_CPU1_G2_TX_DN<12>")
	)
	(segment
		(start 158.658814 -191.458088)
		(end 158.629604 -191.481964)
		(width 0.14224)
		(layer "In13.Cu")
		(net "GMI_CPU0_G0_CPU1_G2_TX_DN<12>")
	)
	(segment
		(start 123.777248 -228.589332)
		(end 123.807728 -228.607112)
		(width 0.1143)
		(layer "In13.Cu")
		(net "GMI_CPU0_G0_CPU1_G2_TX_DN<12>")
	)
	(segment
		(start 236.278928 -198.783448)
		(end 235.24718 -198.601584)
		(width 0.14224)
		(layer "In13.Cu")
		(net "GMI_CPU0_G0_CPU1_G2_TX_DN<12>")
	)
	(segment
		(start 262.760968 -188.105542)
		(end 250.68657 -190.234824)
		(width 0.14224)
		(layer "In13.Cu")
		(net "GMI_CPU0_G0_CPU1_G2_TX_DN<12>")
	)
	(segment
		(start 123.341892 -240.109502)
		(end 123.337828 -240.111788)
		(width 0.1143)
		(layer "In13.Cu")
		(net "GMI_CPU0_G0_CPU1_G2_TX_DN<12>")
	)
	(segment
		(start 123.777248 -230.20909)
		(end 123.844304 -230.248206)
		(width 0.1143)
		(layer "In13.Cu")
		(net "GMI_CPU0_G0_CPU1_G2_TX_DN<12>")
	)
	(segment
		(start 123.807728 -235.086906)
		(end 123.846844 -235.109766)
		(width 0.1143)
		(layer "In13.Cu")
		(net "GMI_CPU0_G0_CPU1_G2_TX_DN<12>")
	)
	(segment
		(start 123.807728 -239.301782)
		(end 123.777248 -239.319562)
		(width 0.1143)
		(layer "In13.Cu")
		(net "GMI_CPU0_G0_CPU1_G2_TX_DN<12>")
	)
	(segment
		(start 123.807728 -237.68177)
		(end 123.777248 -237.69955)
		(width 0.1143)
		(layer "In13.Cu")
		(net "GMI_CPU0_G0_CPU1_G2_TX_DN<12>")
	)
	(segment
		(start 123.846844 -227.939092)
		(end 123.807728 -227.961952)
		(width 0.1143)
		(layer "In13.Cu")
		(net "GMI_CPU0_G0_CPU1_G2_TX_DN<12>")
	)
	(segment
		(start 348.152212 -240.108232)
		(end 348.149926 -240.106708)
		(width 0.1143)
		(layer "In13.Cu")
		(net "GMI_CPU0_G0_CPU1_G2_TX_DN<12>")
	)
	(segment
		(start 156.885132 -192.912492)
		(end 156.692092 -192.893188)
		(width 0.14224)
		(layer "In13.Cu")
		(net "GMI_CPU0_G0_CPU1_G2_TX_DN<12>")
	)
	(segment
		(start 155.366974 -193.9798)
		(end 155.037028 -194.25031)
		(width 0.14224)
		(layer "In13.Cu")
		(net "GMI_CPU0_G0_CPU1_G2_TX_DN<12>")
	)
	(segment
		(start 157.215332 -192.641728)
		(end 156.885132 -192.912492)
		(width 0.14224)
		(layer "In13.Cu")
		(net "GMI_CPU0_G0_CPU1_G2_TX_DN<12>")
	)
	(segment
		(start 123.777248 -233.449114)
		(end 123.807728 -233.466894)
		(width 0.1143)
		(layer "In13.Cu")
		(net "GMI_CPU0_G0_CPU1_G2_TX_DN<12>")
	)
	(segment
		(start 239.218216 -198.265034)
		(end 236.278928 -198.783448)
		(width 0.14224)
		(layer "In13.Cu")
		(net "GMI_CPU0_G0_CPU1_G2_TX_DN<12>")
	)
	(segment
		(start 153.273252 -195.873878)
		(end 152.943052 -196.144896)
		(width 0.14224)
		(layer "In13.Cu")
		(net "GMI_CPU0_G0_CPU1_G2_TX_DN<12>")
	)
	(segment
		(start 148.0058 -200.015856)
		(end 145.878042 -200.66)
		(width 0.14224)
		(layer "In13.Cu")
		(net "GMI_CPU0_G0_CPU1_G2_TX_DN<12>")
	)
	(segment
		(start 123.846844 -223.079056)
		(end 123.807728 -223.101916)
		(width 0.1143)
		(layer "In13.Cu")
		(net "GMI_CPU0_G0_CPU1_G2_TX_DN<12>")
	)
	(segment
		(start 347.688154 -229.58171)
		(end 347.649038 -229.55885)
		(width 0.1143)
		(layer "In13.Cu")
		(net "GMI_CPU0_G0_CPU1_G2_TX_DN<12>")
	)
	(segment
		(start 347.829886 -220.973142)
		(end 347.829886 -220.944694)
		(width 0.1143)
		(layer "In13.Cu")
		(net "GMI_CPU0_G0_CPU1_G2_TX_DN<12>")
	)
	(segment
		(start 123.620276 -221.019116)
		(end 123.620276 -221.804484)
		(width 0.1143)
		(layer "In13.Cu")
		(net "GMI_CPU0_G0_CPU1_G2_TX_DN<12>")
	)
	(segment
		(start 348.18447 -240.126774)
		(end 348.158562 -240.111534)
		(width 0.1143)
		(layer "In13.Cu")
		(net "GMI_CPU0_G0_CPU1_G2_TX_DN<12>")
	)
	(segment
		(start 123.807728 -225.367088)
		(end 123.846844 -225.389948)
		(width 0.1143)
		(layer "In13.Cu")
		(net "GMI_CPU0_G0_CPU1_G2_TX_DN<12>")
	)
	(segment
		(start 123.311412 -240.127028)
		(end 123.31065 -240.127536)
		(width 0.1143)
		(layer "In13.Cu")
		(net "GMI_CPU0_G0_CPU1_G2_TX_DN<12>")
	)
	(segment
		(start 123.846844 -236.038898)
		(end 123.807728 -236.061758)
		(width 0.1143)
		(layer "In13.Cu")
		(net "GMI_CPU0_G0_CPU1_G2_TX_DN<12>")
	)
	(segment
		(start 347.718634 -236.079284)
		(end 347.649038 -236.038644)
		(width 0.1143)
		(layer "In13.Cu")
		(net "GMI_CPU0_G0_CPU1_G2_TX_DN<12>")
	)
	(segment
		(start 158.436564 -191.462914)
		(end 158.106618 -191.733424)
		(width 0.14224)
		(layer "In13.Cu")
		(net "GMI_CPU0_G0_CPU1_G2_TX_DN<12>")
	)
	(segment
		(start 158.629604 -191.481964)
		(end 158.436564 -191.462914)
		(width 0.14224)
		(layer "In13.Cu")
		(net "GMI_CPU0_G0_CPU1_G2_TX_DN<12>")
	)
	(segment
		(start 123.846844 -239.278922)
		(end 123.807728 -239.301782)
		(width 0.1143)
		(layer "In13.Cu")
		(net "GMI_CPU0_G0_CPU1_G2_TX_DN<12>")
	)
	(segment
		(start 348.185232 -240.127282)
		(end 348.18447 -240.126774)
		(width 0.1143)
		(layer "In13.Cu")
		(net "GMI_CPU0_G0_CPU1_G2_TX_DN<12>")
	)
	(segment
		(start 123.846844 -234.418886)
		(end 123.807728 -234.441746)
		(width 0.1143)
		(layer "In13.Cu")
		(net "GMI_CPU0_G0_CPU1_G2_TX_DN<12>")
	)
	(segment
		(start 158.978854 -191.01816)
		(end 158.959804 -191.2112)
		(width 0.14224)
		(layer "In13.Cu")
		(net "GMI_CPU0_G0_CPU1_G2_TX_DN<12>")
	)
	(segment
		(start 348.15399 -240.109248)
		(end 348.152212 -240.108232)
		(width 0.1143)
		(layer "In13.Cu")
		(net "GMI_CPU0_G0_CPU1_G2_TX_DN<12>")
	)
	(segment
		(start 123.777248 -231.829102)
		(end 123.807728 -231.846882)
		(width 0.1143)
		(layer "In13.Cu")
		(net "GMI_CPU0_G0_CPU1_G2_TX_DN<12>")
	)
	(segment
		(start 347.649038 -235.109512)
		(end 347.718634 -235.068872)
		(width 0.1143)
		(layer "In13.Cu")
		(net "GMI_CPU0_G0_CPU1_G2_TX_DN<12>")
	)
	(segment
		(start 122.865896 -240.923064)
		(end 122.836178 -240.940082)
		(width 0.1143)
		(layer "In13.Cu")
		(net "GMI_CPU0_G0_CPU1_G2_TX_DN<12>")
	)
	(segment
		(start 346.414598 -217.830146)
		(end 318.759586 -195.154042)
		(width 0.14224)
		(layer "In13.Cu")
		(net "GMI_CPU0_G0_CPU1_G2_TX_DN<12>")
	)
	(segment
		(start 159.83204 -190.495936)
		(end 159.50184 -190.7667)
		(width 0.14224)
		(layer "In13.Cu")
		(net "GMI_CPU0_G0_CPU1_G2_TX_DN<12>")
	)
	(segment
		(start 123.846844 -224.699068)
		(end 123.807728 -224.721928)
		(width 0.1143)
		(layer "In13.Cu")
		(net "GMI_CPU0_G0_CPU1_G2_TX_DN<12>")
	)
	(segment
		(start 161.94786 -188.583824)
		(end 159.851344 -190.302896)
		(width 0.14224)
		(layer "In13.Cu")
		(net "GMI_CPU0_G0_CPU1_G2_TX_DN<12>")
	)
	(segment
		(start 154.494738 -194.695064)
		(end 154.164792 -194.965574)
		(width 0.14224)
		(layer "In13.Cu")
		(net "GMI_CPU0_G0_CPU1_G2_TX_DN<12>")
	)
	(segment
		(start 348.158562 -240.111534)
		(end 348.158054 -240.111534)
		(width 0.1143)
		(layer "In13.Cu")
		(net "GMI_CPU0_G0_CPU1_G2_TX_DN<12>")
	)
	(segment
		(start 318.637666 -195.032376)
		(end 309.346346 -188.483748)
		(width 0.14224)
		(layer "In13.Cu")
		(net "GMI_CPU0_G0_CPU1_G2_TX_DN<12>")
	)
	(segment
		(start 347.718634 -232.83926)
		(end 347.649038 -232.79862)
		(width 0.1143)
		(layer "In13.Cu")
		(net "GMI_CPU0_G0_CPU1_G2_TX_DN<12>")
	)
	(segment
		(start 123.846844 -232.798874)
		(end 123.807728 -232.821734)
		(width 0.1143)
		(layer "In13.Cu")
		(net "GMI_CPU0_G0_CPU1_G2_TX_DN<12>")
	)
	(segment
		(start 347.718634 -224.739454)
		(end 347.649038 -224.698814)
		(width 0.1143)
		(layer "In13.Cu")
		(net "GMI_CPU0_G0_CPU1_G2_TX_DN<12>")
	)
	(segment
		(start 156.692092 -192.893188)
		(end 156.692092 -192.893442)
		(width 0.14224)
		(layer "In13.Cu")
		(net "GMI_CPU0_G0_CPU1_G2_TX_DN<12>")
	)
	(segment
		(start 123.807728 -231.846882)
		(end 123.846844 -231.869742)
		(width 0.1143)
		(layer "In13.Cu")
		(net "GMI_CPU0_G0_CPU1_G2_TX_DN<12>")
	)
	(segment
		(start 123.807728 -236.061758)
		(end 123.777248 -236.079538)
		(width 0.1143)
		(layer "In13.Cu")
		(net "GMI_CPU0_G0_CPU1_G2_TX_DN<12>")
	)
	(segment
		(start 347.649038 -228.629718)
		(end 347.718634 -228.589078)
		(width 0.1143)
		(layer "In13.Cu")
		(net "GMI_CPU0_G0_CPU1_G2_TX_DN<12>")
	)
	(segment
		(start 250.68657 -190.234824)
		(end 239.218216 -198.265034)
		(width 0.14224)
		(layer "In13.Cu")
		(net "GMI_CPU0_G0_CPU1_G2_TX_DN<12>")
	)
	(segment
		(start 152.943052 -196.144896)
		(end 152.750012 -196.125846)
		(width 0.14224)
		(layer "In13.Cu")
		(net "GMI_CPU0_G0_CPU1_G2_TX_DN<12>")
	)
	(segment
		(start 347.718634 -223.119442)
		(end 347.649038 -223.078802)
		(width 0.1143)
		(layer "In13.Cu")
		(net "GMI_CPU0_G0_CPU1_G2_TX_DN<12>")
	)
	(segment
		(start 348.628716 -240.922048)
		(end 348.627954 -240.92154)
		(width 0.1143)
		(layer "In13.Cu")
		(net "GMI_CPU0_G0_CPU1_G2_TX_DN<12>")
	)
	(segment
		(start 123.846844 -226.31908)
		(end 123.807728 -226.34194)
		(width 0.1143)
		(layer "In13.Cu")
		(net "GMI_CPU0_G0_CPU1_G2_TX_DN<12>")
	)
	(segment
		(start 155.890214 -193.728086)
		(end 155.560014 -193.99885)
		(width 0.14224)
		(layer "In13.Cu")
		(net "GMI_CPU0_G0_CPU1_G2_TX_DN<12>")
	)
	(segment
		(start 154.164792 -194.965574)
		(end 154.145742 -195.158614)
		(width 0.14224)
		(layer "In13.Cu")
		(net "GMI_CPU0_G0_CPU1_G2_TX_DN<12>")
	)
	(segment
		(start 123.807728 -227.961952)
		(end 123.777248 -227.979732)
		(width 0.1143)
		(layer "In13.Cu")
		(net "GMI_CPU0_G0_CPU1_G2_TX_DN<12>")
	)
	(segment
		(start 347.649038 -238.349536)
		(end 347.718634 -238.308896)
		(width 0.1143)
		(layer "In13.Cu")
		(net "GMI_CPU0_G0_CPU1_G2_TX_DN<12>")
	)
	(segment
		(start 155.037028 -194.25031)
		(end 155.017978 -194.44335)
		(width 0.14224)
		(layer "In13.Cu")
		(net "GMI_CPU0_G0_CPU1_G2_TX_DN<12>")
	)
	(segment
		(start 347.649038 -227.009706)
		(end 347.718634 -226.969066)
		(width 0.1143)
		(layer "In13.Cu")
		(net "GMI_CPU0_G0_CPU1_G2_TX_DN<12>")
	)
	(segment
		(start 152.750012 -196.125846)
		(end 148.0058 -200.015856)
		(width 0.14224)
		(layer "In13.Cu")
		(net "GMI_CPU0_G0_CPU1_G2_TX_DN<12>")
	)
	(segment
		(start 155.017978 -194.44335)
		(end 154.687778 -194.714114)
		(width 0.14224)
		(layer "In13.Cu")
		(net "GMI_CPU0_G0_CPU1_G2_TX_DN<12>")
	)
	(segment
		(start 154.687778 -194.714114)
		(end 154.494738 -194.695064)
		(width 0.14224)
		(layer "In13.Cu")
		(net "GMI_CPU0_G0_CPU1_G2_TX_DN<12>")
	)
	(segment
		(start 347.649038 -223.769682)
		(end 347.718634 -223.729042)
		(width 0.1143)
		(layer "In13.Cu")
		(net "GMI_CPU0_G0_CPU1_G2_TX_DN<12>")
	)
	(segment
		(start 348.149926 -240.106708)
		(end 348.118938 -240.088674)
		(width 0.1143)
		(layer "In13.Cu")
		(net "GMI_CPU0_G0_CPU1_G2_TX_DN<12>")
	)
	(segment
		(start 123.807728 -224.721928)
		(end 123.777248 -224.739708)
		(width 0.1143)
		(layer "In13.Cu")
		(net "GMI_CPU0_G0_CPU1_G2_TX_DN<12>")
	)
	(segment
		(start 123.807728 -234.441746)
		(end 123.777248 -234.459526)
		(width 0.1143)
		(layer "In13.Cu")
		(net "GMI_CPU0_G0_CPU1_G2_TX_DN<12>")
	)
	(segment
		(start 122.68708 -241.174524)
		(end 122.75693 -241.244374)
		(width 0.1143)
		(layer "In13.Cu")
		(net "GMI_CPU0_G0_CPU1_G2_TX_DN<12>")
	)
	(segment
		(start 123.337828 -240.111788)
		(end 123.33732 -240.111788)
		(width 0.1143)
		(layer "In13.Cu")
		(net "GMI_CPU0_G0_CPU1_G2_TX_DN<12>")
	)
	(segment
		(start 347.829886 -220.944694)
		(end 347.829886 -220.21419)
		(width 0.14224)
		(layer "In13.Cu")
		(net "GMI_CPU0_G0_CPU1_G2_TX_DN<12>")
	)
	(segment
		(start 347.649038 -231.869488)
		(end 347.718634 -231.828848)
		(width 0.1143)
		(layer "In13.Cu")
		(net "GMI_CPU0_G0_CPU1_G2_TX_DN<12>")
	)
	(segment
		(start 123.807728 -226.34194)
		(end 123.777248 -226.35972)
		(width 0.1143)
		(layer "In13.Cu")
		(net "GMI_CPU0_G0_CPU1_G2_TX_DN<12>")
	)
	(segment
		(start 123.376944 -240.088928)
		(end 123.341892 -240.109502)
		(width 0.1143)
		(layer "In13.Cu")
		(net "GMI_CPU0_G0_CPU1_G2_TX_DN<12>")
	)
	(segment
		(start 158.087568 -191.926464)
		(end 157.757368 -192.197228)
		(width 0.14224)
		(layer "In13.Cu")
		(net "GMI_CPU0_G0_CPU1_G2_TX_DN<12>")
	)
	(segment
		(start 347.718634 -227.979478)
		(end 347.649038 -227.938838)
		(width 0.1143)
		(layer "In13.Cu")
		(net "GMI_CPU0_G0_CPU1_G2_TX_DN<12>")
	)
	(segment
		(start 123.807728 -226.9871)
		(end 123.846844 -227.00996)
		(width 0.1143)
		(layer "In13.Cu")
		(net "GMI_CPU0_G0_CPU1_G2_TX_DN<12>")
	)
	(segment
		(start 123.846844 -237.65891)
		(end 123.807728 -237.68177)
		(width 0.1143)
		(layer "In13.Cu")
		(net "GMI_CPU0_G0_CPU1_G2_TX_DN<12>")
	)
	(segment
		(start 157.757368 -192.197228)
		(end 157.564328 -192.178178)
		(width 0.14224)
		(layer "In13.Cu")
		(net "GMI_CPU0_G0_CPU1_G2_TX_DN<12>")
	)
	(segment
		(start 347.718634 -226.359466)
		(end 347.649038 -226.318826)
		(width 0.1143)
		(layer "In13.Cu")
		(net "GMI_CPU0_G0_CPU1_G2_TX_DN<12>")
	)
	(segment
		(start 123.807728 -228.607112)
		(end 123.846844 -228.629972)
		(width 0.1143)
		(layer "In13.Cu")
		(net "GMI_CPU0_G0_CPU1_G2_TX_DN<12>")
	)
	(segment
		(start 347.720666 -231.220518)
		(end 347.688154 -231.201722)
		(width 0.1143)
		(layer "In13.Cu")
		(net "GMI_CPU0_G0_CPU1_G2_TX_DN<12>")
	)
	(segment
		(start 348.158054 -240.111534)
		(end 348.15399 -240.109248)
		(width 0.1143)
		(layer "In13.Cu")
		(net "GMI_CPU0_G0_CPU1_G2_TX_DN<12>")
	)
	(segment
		(start 159.851344 -190.302896)
		(end 159.83204 -190.495936)
		(width 0.14224)
		(layer "In13.Cu")
		(net "GMI_CPU0_G0_CPU1_G2_TX_DN<12>")
	)
	(segment
		(start 123.807728 -222.127064)
		(end 123.846844 -222.149924)
		(width 0.1143)
		(layer "In13.Cu")
		(net "GMI_CPU0_G0_CPU1_G2_TX_DN<12>")
	)
	(segment
		(start 318.759586 -195.154042)
		(end 318.637666 -195.032376)
		(width 0.14224)
		(layer "In13.Cu")
		(net "GMI_CPU0_G0_CPU1_G2_TX_DN<12>")
	)
	(segment
		(start 123.807728 -229.581964)
		(end 123.775216 -229.60076)
		(width 0.1143)
		(layer "In13.Cu")
		(net "GMI_CPU0_G0_CPU1_G2_TX_DN<12>")
	)
	(segment
		(start 123.807728 -223.101916)
		(end 123.777248 -223.119696)
		(width 0.1143)
		(layer "In13.Cu")
		(net "GMI_CPU0_G0_CPU1_G2_TX_DN<12>")
	)
	(segment
		(start 348.627954 -240.92154)
		(end 348.591632 -240.900458)
		(width 0.1143)
		(layer "In13.Cu")
		(net "GMI_CPU0_G0_CPU1_G2_TX_DN<12>")
	)
	(segment
		(start 123.665996 -220.944948)
		(end 123.665996 -220.973396)
		(width 0.1143)
		(layer "In13.Cu")
		(net "GMI_CPU0_G0_CPU1_G2_TX_DN<12>")
	)
	(segment
		(start 348.44101 -241.24412)
		(end 348.738952 -241.24412)
		(width 0.1143)
		(layer "In13.Cu")
		(net "GMI_CPU0_G0_CPU1_G2_TX_DN<12>")
	)
	(segment
		(start 159.3088 -190.74765)
		(end 158.978854 -191.01816)
		(width 0.14224)
		(layer "In13.Cu")
		(net "GMI_CPU0_G0_CPU1_G2_TX_DN<12>")
	)
	(segment
		(start 123.846844 -229.559104)
		(end 123.807728 -229.581964)
		(width 0.1143)
		(layer "In13.Cu")
		(net "GMI_CPU0_G0_CPU1_G2_TX_DN<12>")
	)
	(segment
		(start 347.829886 -220.21419)
		(end 346.414598 -217.830146)
		(width 0.14224)
		(layer "In13.Cu")
		(net "GMI_CPU0_G0_CPU1_G2_TX_DN<12>")
	)
	(segment
		(start 155.560014 -193.99885)
		(end 155.366974 -193.9798)
		(width 0.14224)
		(layer "In13.Cu")
		(net "GMI_CPU0_G0_CPU1_G2_TX_DN<12>")
	)
	(segment
		(start 235.24718 -198.601584)
		(end 213.034372 -189.400688)
		(width 0.14224)
		(layer "In13.Cu")
		(net "GMI_CPU0_G0_CPU1_G2_TX_DN<12>")
	)
	(segment
		(start 347.688154 -231.201722)
		(end 347.649038 -231.178862)
		(width 0.1143)
		(layer "In13.Cu")
		(net "GMI_CPU0_G0_CPU1_G2_TX_DN<12>")
	)
	(segment
		(start 153.815542 -195.429378)
		(end 153.622502 -195.410328)
		(width 0.14224)
		(layer "In13.Cu")
		(net "GMI_CPU0_G0_CPU1_G2_TX_DN<12>")
	)
	(segment
		(start 123.777248 -238.30915)
		(end 123.807728 -238.32693)
		(width 0.1143)
		(layer "In13.Cu")
		(net "GMI_CPU0_G0_CPU1_G2_TX_DN<12>")
	)
	(segment
		(start 123.777248 -222.109284)
		(end 123.807728 -222.127064)
		(width 0.1143)
		(layer "In13.Cu")
		(net "GMI_CPU0_G0_CPU1_G2_TX_DN<12>")
	)
	(segment
		(start 122.75693 -241.244374)
		(end 123.054618 -241.244374)
		(width 0.1143)
		(layer "In13.Cu")
		(net "GMI_CPU0_G0_CPU1_G2_TX_DN<12>")
	)
	(segment
		(start 153.292556 -195.680838)
		(end 153.273252 -195.873878)
		(width 0.14224)
		(layer "In13.Cu")
		(net "GMI_CPU0_G0_CPU1_G2_TX_DN<12>")
	)
	(segment
		(start 347.649038 -236.729524)
		(end 347.718634 -236.688884)
		(width 0.1143)
		(layer "In13.Cu")
		(net "GMI_CPU0_G0_CPU1_G2_TX_DN<12>")
	)
	(segment
		(start 153.622502 -195.410328)
		(end 153.292556 -195.680838)
		(width 0.14224)
		(layer "In13.Cu")
		(net "GMI_CPU0_G0_CPU1_G2_TX_DN<12>")
	)
	(segment
		(start 123.777248 -235.069126)
		(end 123.807728 -235.086906)
		(width 0.1143)
		(layer "In13.Cu")
		(net "GMI_CPU0_G0_CPU1_G2_TX_DN<12>")
	)
	(segment
		(start 347.649038 -233.4895)
		(end 347.718634 -233.44886)
		(width 0.1143)
		(layer "In13.Cu")
		(net "GMI_CPU0_G0_CPU1_G2_TX_DN<12>")
	)
	(segment
		(start 347.718634 -234.459272)
		(end 347.649038 -234.418632)
		(width 0.1143)
		(layer "In13.Cu")
		(net "GMI_CPU0_G0_CPU1_G2_TX_DN<12>")
	)
	(segment
		(start 123.807728 -233.466894)
		(end 123.846844 -233.489754)
		(width 0.1143)
		(layer "In13.Cu")
		(net "GMI_CPU0_G0_CPU1_G2_TX_DN<12>")
	)
	(segment
		(start 348.659704 -240.939828)
		(end 348.629986 -240.92281)
		(width 0.1143)
		(layer "In13.Cu")
		(net "GMI_CPU0_G0_CPU1_G2_TX_DN<12>")
	)
	(segment
		(start 158.959804 -191.2112)
		(end 158.658814 -191.458088)
		(width 0.14224)
		(layer "In13.Cu")
		(net "GMI_CPU0_G0_CPU1_G2_TX_DN<12>")
	)
	(segment
		(start 347.718634 -239.319308)
		(end 347.649038 -239.278668)
		(width 0.1143)
		(layer "In13.Cu")
		(net "GMI_CPU0_G0_CPU1_G2_TX_DN<12>")
	)
	(segment
		(start 145.878042 -200.66)
		(end 125.30328 -217.53068)
		(width 0.14224)
		(layer "In13.Cu")
		(net "GMI_CPU0_G0_CPU1_G2_TX_DN<12>")
	)
	(segment
		(start 207.307942 -188.391038)
		(end 161.94786 -188.583824)
		(width 0.14224)
		(layer "In13.Cu")
		(net "GMI_CPU0_G0_CPU1_G2_TX_DN<12>")
	)
	(segment
		(start 158.106618 -191.733424)
		(end 158.087568 -191.926464)
		(width 0.14224)
		(layer "In13.Cu")
		(net "GMI_CPU0_G0_CPU1_G2_TX_DN<12>")
	)
	(segment
		(start 123.665996 -220.973396)
		(end 123.620276 -221.019116)
		(width 0.1143)
		(layer "In13.Cu")
		(net "GMI_CPU0_G0_CPU1_G2_TX_DN<12>")
	)
	(segment
		(start 309.346346 -188.483748)
		(end 303.70526 -188.483748)
		(width 0.14224)
		(layer "In13.Cu")
		(net "GMI_CPU0_G0_CPU1_G2_TX_DN<12>")
	)
	(segment
		(start 157.564328 -192.178178)
		(end 157.234382 -192.448688)
		(width 0.14224)
		(layer "In13.Cu")
		(net "GMI_CPU0_G0_CPU1_G2_TX_DN<12>")
	)
	(segment
		(start 154.145742 -195.158614)
		(end 153.815542 -195.429378)
		(width 0.14224)
		(layer "In13.Cu")
		(net "GMI_CPU0_G0_CPU1_G2_TX_DN<12>")
	)
	(segment
		(start 123.33732 -240.111788)
		(end 123.311412 -240.127028)
		(width 0.1143)
		(layer "In13.Cu")
		(net "GMI_CPU0_G0_CPU1_G2_TX_DN<12>")
	)
	(segment
		(start 123.807728 -223.747076)
		(end 123.846844 -223.769936)
		(width 0.1143)
		(layer "In13.Cu")
		(net "GMI_CPU0_G0_CPU1_G2_TX_DN<12>")
	)
	(segment
		(start 347.649038 -225.389694)
		(end 347.718634 -225.349054)
		(width 0.1143)
		(layer "In13.Cu")
		(net "GMI_CPU0_G0_CPU1_G2_TX_DN<12>")
	)
	(segment
		(start 123.807728 -236.706918)
		(end 123.846844 -236.729778)
		(width 0.1143)
		(layer "In13.Cu")
		(net "GMI_CPU0_G0_CPU1_G2_TX_DN<12>")
	)
	(segment
		(start 348.738952 -241.24412)
		(end 348.808802 -241.17427)
		(width 0.1143)
		(layer "In13.Cu")
		(net "GMI_CPU0_G0_CPU1_G2_TX_DN<12>")
	)
	(segment
		(start 123.846844 -231.179116)
		(end 123.807728 -231.201976)
		(width 0.1143)
		(layer "In13.Cu")
		(net "GMI_CPU0_G0_CPU1_G2_TX_DN<12>")
	)
	(segment
		(start 348.629986 -240.92281)
		(end 348.628716 -240.922048)
		(width 0.1143)
		(layer "In13.Cu")
		(net "GMI_CPU0_G0_CPU1_G2_TX_DN<12>")
	)
	(segment
		(start 347.875606 -221.80423)
		(end 347.875606 -221.018862)
		(width 0.1143)
		(layer "In13.Cu")
		(net "GMI_CPU0_G0_CPU1_G2_TX_DN<12>")
	)
	(segment
		(start 155.909264 -193.535046)
		(end 155.890214 -193.728086)
		(width 0.14224)
		(layer "In13.Cu")
		(net "GMI_CPU0_G0_CPU1_G2_TX_DN<12>")
	)
	(segment
		(start 155.909264 -193.5353)
		(end 155.909264 -193.535046)
		(width 0.14224)
		(layer "In13.Cu")
		(net "GMI_CPU0_G0_CPU1_G2_TX_DN<12>")
	)
	(segment
		(start 125.30328 -217.53068)
		(end 123.665996 -220.367352)
		(width 0.14224)
		(layer "In13.Cu")
		(net "GMI_CPU0_G0_CPU1_G2_TX_DN<12>")
	)
	(segment
		(start 123.807728 -231.201976)
		(end 123.775216 -231.220772)
		(width 0.1143)
		(layer "In13.Cu")
		(net "GMI_CPU0_G0_CPU1_G2_TX_DN<12>")
	)
	(segment
		(start 303.70526 -188.483748)
		(end 262.760968 -188.105542)
		(width 0.14224)
		(layer "In13.Cu")
		(net "GMI_CPU0_G0_CPU1_G2_TX_DN<12>")
	)
	(segment
		(start 347.875606 -221.018862)
		(end 347.829886 -220.973142)
		(width 0.1143)
		(layer "In13.Cu")
		(net "GMI_CPU0_G0_CPU1_G2_TX_DN<12>")
	)
	(segment
		(start 123.665996 -220.367352)
		(end 123.665996 -220.944948)
		(width 0.14224)
		(layer "In13.Cu")
		(net "GMI_CPU0_G0_CPU1_G2_TX_DN<12>")
	)
	(segment
		(start 123.777248 -226.96932)
		(end 123.807728 -226.9871)
		(width 0.1143)
		(layer "In13.Cu")
		(net "GMI_CPU0_G0_CPU1_G2_TX_DN<12>")
	)
	(segment
		(start 123.807728 -232.821734)
		(end 123.777248 -232.839514)
		(width 0.1143)
		(layer "In13.Cu")
		(net "GMI_CPU0_G0_CPU1_G2_TX_DN<12>")
	)
	(segment
		(start 123.777248 -236.689138)
		(end 123.807728 -236.706918)
		(width 0.1143)
		(layer "In13.Cu")
		(net "GMI_CPU0_G0_CPU1_G2_TX_DN<12>")
	)
	(segment
		(start 122.867166 -240.922302)
		(end 122.865896 -240.923064)
		(width 0.1143)
		(layer "In13.Cu")
		(net "GMI_CPU0_G0_CPU1_G2_TX_DN<12>")
	)
	(segment
		(start 123.807728 -238.32693)
		(end 123.846844 -238.34979)
		(width 0.1143)
		(layer "In13.Cu")
		(net "GMI_CPU0_G0_CPU1_G2_TX_DN<12>")
	)
	(segment
		(start 347.649038 -222.14967)
		(end 347.718634 -222.10903)
		(width 0.1143)
		(layer "In13.Cu")
		(net "GMI_CPU0_G0_CPU1_G2_TX_DN<12>")
	)
	(segment
		(start 157.234382 -192.448688)
		(end 157.215332 -192.641728)
		(width 0.14224)
		(layer "In13.Cu")
		(net "GMI_CPU0_G0_CPU1_G2_TX_DN<12>")
	)
	(segment
		(start 122.90425 -240.900712)
		(end 122.867928 -240.921794)
		(width 0.1143)
		(layer "In13.Cu")
		(net "GMI_CPU0_G0_CPU1_G2_TX_DN<12>")
	)
	(segment
		(start 347.651578 -230.247952)
		(end 347.718634 -230.208836)
		(width 0.1143)
		(layer "In13.Cu")
		(net "GMI_CPU0_G0_CPU1_G2_TX_DN<12>")
	)
	(segment
		(start 156.692092 -192.893442)
		(end 155.909264 -193.5353)
		(width 0.14224)
		(layer "In13.Cu")
		(net "GMI_CPU0_G0_CPU1_G2_TX_DN<12>")
	)
	(segment
		(start 347.718634 -237.699296)
		(end 347.649038 -237.658656)
		(width 0.1143)
		(layer "In13.Cu")
		(net "GMI_CPU0_G0_CPU1_G2_TX_DN<12>")
	)
	(segment
		(start 123.777248 -223.729296)
		(end 123.807728 -223.747076)
		(width 0.1143)
		(layer "In13.Cu")
		(net "GMI_CPU0_G0_CPU1_G2_TX_DN<12>")
	)
	(segment
		(start 159.50184 -190.7667)
		(end 159.3088 -190.74765)
		(width 0.14224)
		(layer "In13.Cu")
		(net "GMI_CPU0_G0_CPU1_G2_TX_DN<12>")
	)
	(arc
		(start 347.718634 -233.44886)
		(mid 347.875611 -233.14406)
		(end 347.718634 -232.83926)
		(width 0.1143)
		(layer "In13.Cu")
		(net "GMI_CPU0_G0_CPU1_G2_TX_DN<12>")
	)
	(arc
		(start 123.777248 -234.459526)
		(mid 123.620271 -234.764326)
		(end 123.777248 -235.069126)
		(width 0.1143)
		(layer "In13.Cu")
		(net "GMI_CPU0_G0_CPU1_G2_TX_DN<12>")
	)
	(arc
		(start 122.920506 -240.889282)
		(mid 122.912428 -240.895068)
		(end 122.90425 -240.900712)
		(width 0.1143)
		(layer "In13.Cu")
		(net "GMI_CPU0_G0_CPU1_G2_TX_DN<12>")
	)
	(arc
		(start 347.718634 -225.349054)
		(mid 347.875611 -225.044254)
		(end 347.718634 -224.739454)
		(width 0.1143)
		(layer "In13.Cu")
		(net "GMI_CPU0_G0_CPU1_G2_TX_DN<12>")
	)
	(arc
		(start 123.846844 -233.489754)
		(mid 124.090171 -233.95432)
		(end 123.846844 -234.418886)
		(width 0.1143)
		(layer "In13.Cu")
		(net "GMI_CPU0_G0_CPU1_G2_TX_DN<12>")
	)
	(arc
		(start 123.846844 -223.769936)
		(mid 124.090171 -224.234502)
		(end 123.846844 -224.699068)
		(width 0.1143)
		(layer "In13.Cu")
		(net "GMI_CPU0_G0_CPU1_G2_TX_DN<12>")
	)
	(arc
		(start 347.405706 -230.714296)
		(mid 347.470942 -230.450705)
		(end 347.651578 -230.247952)
		(width 0.1143)
		(layer "In13.Cu")
		(net "GMI_CPU0_G0_CPU1_G2_TX_DN<12>")
	)
	(arc
		(start 347.718634 -228.589078)
		(mid 347.875611 -228.284278)
		(end 347.718634 -227.979478)
		(width 0.1143)
		(layer "In13.Cu")
		(net "GMI_CPU0_G0_CPU1_G2_TX_DN<12>")
	)
	(arc
		(start 123.777248 -232.839514)
		(mid 123.620271 -233.144314)
		(end 123.777248 -233.449114)
		(width 0.1143)
		(layer "In13.Cu")
		(net "GMI_CPU0_G0_CPU1_G2_TX_DN<12>")
	)
	(arc
		(start 123.844304 -230.248206)
		(mid 124.024956 -230.450951)
		(end 124.090176 -230.71455)
		(width 0.1143)
		(layer "In13.Cu")
		(net "GMI_CPU0_G0_CPU1_G2_TX_DN<12>")
	)
	(arc
		(start 347.718634 -222.10903)
		(mid 347.834061 -221.975654)
		(end 347.875606 -221.80423)
		(width 0.1143)
		(layer "In13.Cu")
		(net "GMI_CPU0_G0_CPU1_G2_TX_DN<12>")
	)
	(arc
		(start 123.150122 -240.434368)
		(mid 123.150132 -240.43767)
		(end 123.150122 -240.440972)
		(width 0.1143)
		(layer "In13.Cu")
		(net "GMI_CPU0_G0_CPU1_G2_TX_DN<12>")
	)
	(arc
		(start 123.777248 -236.079538)
		(mid 123.620271 -236.384338)
		(end 123.777248 -236.689138)
		(width 0.1143)
		(layer "In13.Cu")
		(net "GMI_CPU0_G0_CPU1_G2_TX_DN<12>")
	)
	(arc
		(start 123.620276 -229.90429)
		(mid 123.661825 -230.075712)
		(end 123.777248 -230.20909)
		(width 0.1143)
		(layer "In13.Cu")
		(net "GMI_CPU0_G0_CPU1_G2_TX_DN<12>")
	)
	(arc
		(start 123.620276 -221.804484)
		(mid 123.661825 -221.975906)
		(end 123.777248 -222.109284)
		(width 0.1143)
		(layer "In13.Cu")
		(net "GMI_CPU0_G0_CPU1_G2_TX_DN<12>")
	)
	(arc
		(start 347.875606 -231.524048)
		(mid 347.83464 -231.353642)
		(end 347.720666 -231.220518)
		(width 0.1143)
		(layer "In13.Cu")
		(net "GMI_CPU0_G0_CPU1_G2_TX_DN<12>")
	)
	(arc
		(start 123.620276 -231.524302)
		(mid 123.661825 -231.695724)
		(end 123.777248 -231.829102)
		(width 0.1143)
		(layer "In13.Cu")
		(net "GMI_CPU0_G0_CPU1_G2_TX_DN<12>")
	)
	(arc
		(start 347.875606 -229.904036)
		(mid 347.83464 -229.73363)
		(end 347.720666 -229.600506)
		(width 0.1143)
		(layer "In13.Cu")
		(net "GMI_CPU0_G0_CPU1_G2_TX_DN<12>")
	)
	(arc
		(start 348.118938 -240.088674)
		(mid 347.940125 -239.886324)
		(end 347.875606 -239.624108)
		(width 0.1143)
		(layer "In13.Cu")
		(net "GMI_CPU0_G0_CPU1_G2_TX_DN<12>")
	)
	(arc
		(start 347.718634 -226.969066)
		(mid 347.875611 -226.664266)
		(end 347.718634 -226.359466)
		(width 0.1143)
		(layer "In13.Cu")
		(net "GMI_CPU0_G0_CPU1_G2_TX_DN<12>")
	)
	(arc
		(start 123.777248 -224.739708)
		(mid 123.620271 -225.044508)
		(end 123.777248 -225.349308)
		(width 0.1143)
		(layer "In13.Cu")
		(net "GMI_CPU0_G0_CPU1_G2_TX_DN<12>")
	)
	(arc
		(start 347.718634 -231.828848)
		(mid 347.834061 -231.695472)
		(end 347.875606 -231.524048)
		(width 0.1143)
		(layer "In13.Cu")
		(net "GMI_CPU0_G0_CPU1_G2_TX_DN<12>")
	)
	(arc
		(start 123.301506 -240.134648)
		(mid 123.201216 -240.272079)
		(end 123.150122 -240.434368)
		(width 0.1143)
		(layer "In13.Cu")
		(net "GMI_CPU0_G0_CPU1_G2_TX_DN<12>")
	)
	(arc
		(start 123.846844 -235.109766)
		(mid 124.090171 -235.574332)
		(end 123.846844 -236.038898)
		(width 0.1143)
		(layer "In13.Cu")
		(net "GMI_CPU0_G0_CPU1_G2_TX_DN<12>")
	)
	(arc
		(start 347.649038 -232.79862)
		(mid 347.405711 -232.334054)
		(end 347.649038 -231.869488)
		(width 0.1143)
		(layer "In13.Cu")
		(net "GMI_CPU0_G0_CPU1_G2_TX_DN<12>")
	)
	(arc
		(start 347.718634 -238.308896)
		(mid 347.875611 -238.004096)
		(end 347.718634 -237.699296)
		(width 0.1143)
		(layer "In13.Cu")
		(net "GMI_CPU0_G0_CPU1_G2_TX_DN<12>")
	)
	(arc
		(start 348.194376 -240.134394)
		(mid 348.189832 -240.130803)
		(end 348.185232 -240.127282)
		(width 0.1143)
		(layer "In13.Cu")
		(net "GMI_CPU0_G0_CPU1_G2_TX_DN<12>")
	)
	(arc
		(start 123.777248 -227.979732)
		(mid 123.620271 -228.284532)
		(end 123.777248 -228.589332)
		(width 0.1143)
		(layer "In13.Cu")
		(net "GMI_CPU0_G0_CPU1_G2_TX_DN<12>")
	)
	(arc
		(start 123.846844 -222.149924)
		(mid 124.090171 -222.61449)
		(end 123.846844 -223.079056)
		(width 0.1143)
		(layer "In13.Cu")
		(net "GMI_CPU0_G0_CPU1_G2_TX_DN<12>")
	)
	(arc
		(start 123.846844 -228.629972)
		(mid 124.090171 -229.094538)
		(end 123.846844 -229.559104)
		(width 0.1143)
		(layer "In13.Cu")
		(net "GMI_CPU0_G0_CPU1_G2_TX_DN<12>")
	)
	(arc
		(start 123.620276 -239.624362)
		(mid 123.555761 -239.886581)
		(end 123.376944 -240.088928)
		(width 0.1143)
		(layer "In13.Cu")
		(net "GMI_CPU0_G0_CPU1_G2_TX_DN<12>")
	)
	(arc
		(start 348.808802 -241.17427)
		(mid 348.756753 -241.042751)
		(end 348.659704 -240.939828)
		(width 0.1143)
		(layer "In13.Cu")
		(net "GMI_CPU0_G0_CPU1_G2_TX_DN<12>")
	)
	(arc
		(start 124.090176 -230.71455)
		(mid 124.025661 -230.976769)
		(end 123.846844 -231.179116)
		(width 0.1143)
		(layer "In13.Cu")
		(net "GMI_CPU0_G0_CPU1_G2_TX_DN<12>")
	)
	(arc
		(start 347.649038 -236.038644)
		(mid 347.405711 -235.574078)
		(end 347.649038 -235.109512)
		(width 0.1143)
		(layer "In13.Cu")
		(net "GMI_CPU0_G0_CPU1_G2_TX_DN<12>")
	)
	(arc
		(start 347.649038 -237.658656)
		(mid 347.405711 -237.19409)
		(end 347.649038 -236.729524)
		(width 0.1143)
		(layer "In13.Cu")
		(net "GMI_CPU0_G0_CPU1_G2_TX_DN<12>")
	)
	(arc
		(start 123.777248 -239.319562)
		(mid 123.661821 -239.452938)
		(end 123.620276 -239.624362)
		(width 0.1143)
		(layer "In13.Cu")
		(net "GMI_CPU0_G0_CPU1_G2_TX_DN<12>")
	)
	(arc
		(start 123.846844 -225.389948)
		(mid 124.090171 -225.854514)
		(end 123.846844 -226.31908)
		(width 0.1143)
		(layer "In13.Cu")
		(net "GMI_CPU0_G0_CPU1_G2_TX_DN<12>")
	)
	(arc
		(start 123.775216 -229.60076)
		(mid 123.661287 -229.733907)
		(end 123.620276 -229.90429)
		(width 0.1143)
		(layer "In13.Cu")
		(net "GMI_CPU0_G0_CPU1_G2_TX_DN<12>")
	)
	(arc
		(start 122.836178 -240.940082)
		(mid 122.739043 -241.042951)
		(end 122.68708 -241.174524)
		(width 0.1143)
		(layer "In13.Cu")
		(net "GMI_CPU0_G0_CPU1_G2_TX_DN<12>")
	)
	(arc
		(start 348.591632 -240.900458)
		(mid 348.583454 -240.894815)
		(end 348.575376 -240.889028)
		(width 0.1143)
		(layer "In13.Cu")
		(net "GMI_CPU0_G0_CPU1_G2_TX_DN<12>")
	)
	(arc
		(start 347.875606 -239.624108)
		(mid 347.834057 -239.452686)
		(end 347.718634 -239.319308)
		(width 0.1143)
		(layer "In13.Cu")
		(net "GMI_CPU0_G0_CPU1_G2_TX_DN<12>")
	)
	(arc
		(start 123.846844 -231.869742)
		(mid 124.090171 -232.334308)
		(end 123.846844 -232.798874)
		(width 0.1143)
		(layer "In13.Cu")
		(net "GMI_CPU0_G0_CPU1_G2_TX_DN<12>")
	)
	(arc
		(start 123.777248 -226.35972)
		(mid 123.620271 -226.66452)
		(end 123.777248 -226.96932)
		(width 0.1143)
		(layer "In13.Cu")
		(net "GMI_CPU0_G0_CPU1_G2_TX_DN<12>")
	)
	(arc
		(start 123.846844 -238.34979)
		(mid 124.090171 -238.814356)
		(end 123.846844 -239.278922)
		(width 0.1143)
		(layer "In13.Cu")
		(net "GMI_CPU0_G0_CPU1_G2_TX_DN<12>")
	)
	(arc
		(start 348.34576 -240.440718)
		(mid 348.34575 -240.437416)
		(end 348.34576 -240.434114)
		(width 0.1143)
		(layer "In13.Cu")
		(net "GMI_CPU0_G0_CPU1_G2_TX_DN<12>")
	)
	(arc
		(start 123.775216 -231.220772)
		(mid 123.661287 -231.353919)
		(end 123.620276 -231.524302)
		(width 0.1143)
		(layer "In13.Cu")
		(net "GMI_CPU0_G0_CPU1_G2_TX_DN<12>")
	)
	(arc
		(start 347.718634 -236.688884)
		(mid 347.875611 -236.384084)
		(end 347.718634 -236.079284)
		(width 0.1143)
		(layer "In13.Cu")
		(net "GMI_CPU0_G0_CPU1_G2_TX_DN<12>")
	)
	(arc
		(start 123.150122 -240.440972)
		(mid 123.08525 -240.690714)
		(end 122.920506 -240.889282)
		(width 0.1143)
		(layer "In13.Cu")
		(net "GMI_CPU0_G0_CPU1_G2_TX_DN<12>")
	)
	(arc
		(start 347.718634 -230.208836)
		(mid 347.834061 -230.07546)
		(end 347.875606 -229.904036)
		(width 0.1143)
		(layer "In13.Cu")
		(net "GMI_CPU0_G0_CPU1_G2_TX_DN<12>")
	)
	(arc
		(start 347.649038 -227.938838)
		(mid 347.405711 -227.474272)
		(end 347.649038 -227.009706)
		(width 0.1143)
		(layer "In13.Cu")
		(net "GMI_CPU0_G0_CPU1_G2_TX_DN<12>")
	)
	(arc
		(start 347.649038 -239.278668)
		(mid 347.405711 -238.814102)
		(end 347.649038 -238.349536)
		(width 0.1143)
		(layer "In13.Cu")
		(net "GMI_CPU0_G0_CPU1_G2_TX_DN<12>")
	)
	(arc
		(start 123.846844 -227.00996)
		(mid 124.090171 -227.474526)
		(end 123.846844 -227.939092)
		(width 0.1143)
		(layer "In13.Cu")
		(net "GMI_CPU0_G0_CPU1_G2_TX_DN<12>")
	)
	(arc
		(start 123.31065 -240.127536)
		(mid 123.30605 -240.131057)
		(end 123.301506 -240.134648)
		(width 0.1143)
		(layer "In13.Cu")
		(net "GMI_CPU0_G0_CPU1_G2_TX_DN<12>")
	)
	(arc
		(start 348.34576 -240.434114)
		(mid 348.294715 -240.2718)
		(end 348.194376 -240.134394)
		(width 0.1143)
		(layer "In13.Cu")
		(net "GMI_CPU0_G0_CPU1_G2_TX_DN<12>")
	)
	(arc
		(start 123.846844 -236.729778)
		(mid 124.090171 -237.194344)
		(end 123.846844 -237.65891)
		(width 0.1143)
		(layer "In13.Cu")
		(net "GMI_CPU0_G0_CPU1_G2_TX_DN<12>")
	)
	(arc
		(start 347.718634 -235.068872)
		(mid 347.875611 -234.764072)
		(end 347.718634 -234.459272)
		(width 0.1143)
		(layer "In13.Cu")
		(net "GMI_CPU0_G0_CPU1_G2_TX_DN<12>")
	)
	(arc
		(start 123.777248 -223.119696)
		(mid 123.620271 -223.424496)
		(end 123.777248 -223.729296)
		(width 0.1143)
		(layer "In13.Cu")
		(net "GMI_CPU0_G0_CPU1_G2_TX_DN<12>")
	)
	(arc
		(start 347.649038 -231.178862)
		(mid 347.470225 -230.976512)
		(end 347.405706 -230.714296)
		(width 0.1143)
		(layer "In13.Cu")
		(net "GMI_CPU0_G0_CPU1_G2_TX_DN<12>")
	)
	(arc
		(start 347.649038 -224.698814)
		(mid 347.405711 -224.234248)
		(end 347.649038 -223.769682)
		(width 0.1143)
		(layer "In13.Cu")
		(net "GMI_CPU0_G0_CPU1_G2_TX_DN<12>")
	)
	(arc
		(start 347.649038 -229.55885)
		(mid 347.405711 -229.094284)
		(end 347.649038 -228.629718)
		(width 0.1143)
		(layer "In13.Cu")
		(net "GMI_CPU0_G0_CPU1_G2_TX_DN<12>")
	)
	(arc
		(start 347.649038 -226.318826)
		(mid 347.405711 -225.85426)
		(end 347.649038 -225.389694)
		(width 0.1143)
		(layer "In13.Cu")
		(net "GMI_CPU0_G0_CPU1_G2_TX_DN<12>")
	)
	(arc
		(start 347.649038 -223.078802)
		(mid 347.405711 -222.614236)
		(end 347.649038 -222.14967)
		(width 0.1143)
		(layer "In13.Cu")
		(net "GMI_CPU0_G0_CPU1_G2_TX_DN<12>")
	)
	(arc
		(start 347.718634 -223.729042)
		(mid 347.875611 -223.424242)
		(end 347.718634 -223.119442)
		(width 0.1143)
		(layer "In13.Cu")
		(net "GMI_CPU0_G0_CPU1_G2_TX_DN<12>")
	)
	(arc
		(start 348.575376 -240.889028)
		(mid 348.410709 -240.690421)
		(end 348.34576 -240.440718)
		(width 0.1143)
		(layer "In13.Cu")
		(net "GMI_CPU0_G0_CPU1_G2_TX_DN<12>")
	)
	(arc
		(start 123.777248 -237.69955)
		(mid 123.620271 -238.00435)
		(end 123.777248 -238.30915)
		(width 0.1143)
		(layer "In13.Cu")
		(net "GMI_CPU0_G0_CPU1_G2_TX_DN<12>")
	)
	(arc
		(start 347.649038 -234.418632)
		(mid 347.405711 -233.954066)
		(end 347.649038 -233.4895)
		(width 0.1143)
		(layer "In13.Cu")
		(net "GMI_CPU0_G0_CPU1_G2_TX_DN<12>")
	)
	(segment
		(start 348.907862 -239.890046)
		(end 348.44101 -239.624108)
		(width 0.12954)
		(layer "F.Cu")
		(net "GMI_CPU0_G0_CPU1_G2_TX_DN<11>")
	)
	(segment
		(start 122.587766 -239.8903)
		(end 123.054618 -239.624362)
		(width 0.12954)
		(layer "F.Cu")
		(net "GMI_CPU0_G0_CPU1_G2_TX_DN<11>")
	)
	(segment
		(start 122.867928 -234.441746)
		(end 122.907552 -234.418886)
		(width 0.1143)
		(layer "In13.Cu")
		(net "GMI_CPU0_G0_CPU1_G2_TX_DN<11>")
	)
	(segment
		(start 348.589092 -225.38944)
		(end 348.57055 -225.402648)
		(width 0.1143)
		(layer "In13.Cu")
		(net "GMI_CPU0_G0_CPU1_G2_TX_DN<11>")
	)
	(segment
		(start 122.836178 -227.98024)
		(end 122.862086 -227.965254)
		(width 0.1143)
		(layer "In13.Cu")
		(net "GMI_CPU0_G0_CPU1_G2_TX_DN<11>")
	)
	(segment
		(start 122.867166 -234.442254)
		(end 122.867928 -234.441746)
		(width 0.1143)
		(layer "In13.Cu")
		(net "GMI_CPU0_G0_CPU1_G2_TX_DN<11>")
	)
	(segment
		(start 153.815542 -193.861182)
		(end 154.008582 -193.880232)
		(width 0.14224)
		(layer "In13.Cu")
		(net "GMI_CPU0_G0_CPU1_G2_TX_DN<11>")
	)
	(segment
		(start 122.70613 -220.14688)
		(end 124.659898 -216.777824)
		(width 0.14224)
		(layer "In13.Cu")
		(net "GMI_CPU0_G0_CPU1_G2_TX_DN<11>")
	)
	(segment
		(start 348.81566 -221.658688)
		(end 348.815914 -221.658942)
		(width 0.1143)
		(layer "In13.Cu")
		(net "GMI_CPU0_G0_CPU1_G2_TX_DN<11>")
	)
	(segment
		(start 122.862594 -234.444794)
		(end 122.86361 -234.444286)
		(width 0.1143)
		(layer "In13.Cu")
		(net "GMI_CPU0_G0_CPU1_G2_TX_DN<11>")
	)
	(segment
		(start 348.628716 -229.582218)
		(end 348.66072 -229.60076)
		(width 0.1143)
		(layer "In13.Cu")
		(net "GMI_CPU0_G0_CPU1_G2_TX_DN<11>")
	)
	(segment
		(start 348.659704 -235.068364)
		(end 348.632526 -235.084112)
		(width 0.1143)
		(layer "In13.Cu")
		(net "GMI_CPU0_G0_CPU1_G2_TX_DN<11>")
	)
	(segment
		(start 302.604932 -185.413142)
		(end 302.604932 -185.41492)
		(width 0.14224)
		(layer "In13.Cu")
		(net "GMI_CPU0_G0_CPU1_G2_TX_DN<11>")
	)
	(segment
		(start 122.867928 -225.367088)
		(end 122.867166 -225.36658)
		(width 0.1143)
		(layer "In13.Cu")
		(net "GMI_CPU0_G0_CPU1_G2_TX_DN<11>")
	)
	(segment
		(start 348.58706 -229.557326)
		(end 348.627954 -229.581202)
		(width 0.1143)
		(layer "In13.Cu")
		(net "GMI_CPU0_G0_CPU1_G2_TX_DN<11>")
	)
	(segment
		(start 157.569662 -190.782448)
		(end 157.88386 -190.524892)
		(width 0.14224)
		(layer "In13.Cu")
		(net "GMI_CPU0_G0_CPU1_G2_TX_DN<11>")
	)
	(segment
		(start 348.63405 -234.445048)
		(end 348.636082 -234.446064)
		(width 0.1143)
		(layer "In13.Cu")
		(net "GMI_CPU0_G0_CPU1_G2_TX_DN<11>")
	)
	(segment
		(start 122.863356 -231.844342)
		(end 122.836178 -231.828594)
		(width 0.1143)
		(layer "In13.Cu")
		(net "GMI_CPU0_G0_CPU1_G2_TX_DN<11>")
	)
	(segment
		(start 122.863356 -225.364548)
		(end 122.836178 -225.3488)
		(width 0.1143)
		(layer "In13.Cu")
		(net "GMI_CPU0_G0_CPU1_G2_TX_DN<11>")
	)
	(segment
		(start 348.63151 -232.823512)
		(end 348.632272 -232.82402)
		(width 0.1143)
		(layer "In13.Cu")
		(net "GMI_CPU0_G0_CPU1_G2_TX_DN<11>")
	)
	(segment
		(start 154.880818 -193.164968)
		(end 155.211018 -192.894204)
		(width 0.14224)
		(layer "In13.Cu")
		(net "GMI_CPU0_G0_CPU1_G2_TX_DN<11>")
	)
	(segment
		(start 151.070818 -196.111622)
		(end 151.249634 -196.129402)
		(width 0.14224)
		(layer "In13.Cu")
		(net "GMI_CPU0_G0_CPU1_G2_TX_DN<11>")
	)
	(segment
		(start 348.629986 -223.745552)
		(end 348.628716 -223.746314)
		(width 0.1143)
		(layer "In13.Cu")
		(net "GMI_CPU0_G0_CPU1_G2_TX_DN<11>")
	)
	(segment
		(start 122.868944 -230.227378)
		(end 122.867928 -230.22687)
		(width 0.1143)
		(layer "In13.Cu")
		(net "GMI_CPU0_G0_CPU1_G2_TX_DN<11>")
	)
	(segment
		(start 122.867674 -236.706918)
		(end 122.835924 -236.68863)
		(width 0.1143)
		(layer "In13.Cu")
		(net "GMI_CPU0_G0_CPU1_G2_TX_DN<11>")
	)
	(segment
		(start 122.867166 -223.746568)
		(end 122.865896 -223.745806)
		(width 0.1143)
		(layer "In13.Cu")
		(net "GMI_CPU0_G0_CPU1_G2_TX_DN<11>")
	)
	(segment
		(start 122.867166 -232.822242)
		(end 122.867928 -232.821734)
		(width 0.1143)
		(layer "In13.Cu")
		(net "GMI_CPU0_G0_CPU1_G2_TX_DN<11>")
	)
	(segment
		(start 155.211018 -192.894204)
		(end 155.230068 -192.701164)
		(width 0.14224)
		(layer "In13.Cu")
		(net "GMI_CPU0_G0_CPU1_G2_TX_DN<11>")
	)
	(segment
		(start 348.629478 -227.96246)
		(end 348.63024 -227.962968)
		(width 0.1143)
		(layer "In13.Cu")
		(net "GMI_CPU0_G0_CPU1_G2_TX_DN<11>")
	)
	(segment
		(start 122.867166 -233.466386)
		(end 122.865896 -233.465624)
		(width 0.1143)
		(layer "In13.Cu")
		(net "GMI_CPU0_G0_CPU1_G2_TX_DN<11>")
	)
	(segment
		(start 155.230068 -192.701164)
		(end 156.233876 -191.878204)
		(width 0.14224)
		(layer "In13.Cu")
		(net "GMI_CPU0_G0_CPU1_G2_TX_DN<11>")
	)
	(segment
		(start 122.867674 -223.101916)
		(end 122.90679 -223.079056)
		(width 0.1143)
		(layer "In13.Cu")
		(net "GMI_CPU0_G0_CPU1_G2_TX_DN<11>")
	)
	(segment
		(start 348.632272 -234.444032)
		(end 348.633288 -234.44454)
		(width 0.1143)
		(layer "In13.Cu")
		(net "GMI_CPU0_G0_CPU1_G2_TX_DN<11>")
	)
	(segment
		(start 122.836178 -235.068618)
		(end 122.81535 -235.051854)
		(width 0.1143)
		(layer "In13.Cu")
		(net "GMI_CPU0_G0_CPU1_G2_TX_DN<11>")
	)
	(segment
		(start 158.377128 -190.284608)
		(end 158.394908 -190.106046)
		(width 0.14224)
		(layer "In13.Cu")
		(net "GMI_CPU0_G0_CPU1_G2_TX_DN<11>")
	)
	(segment
		(start 122.90679 -236.729778)
		(end 122.867674 -236.706918)
		(width 0.1143)
		(layer "In13.Cu")
		(net "GMI_CPU0_G0_CPU1_G2_TX_DN<11>")
	)
	(segment
		(start 122.811286 -232.860088)
		(end 122.818398 -232.8545)
		(width 0.1143)
		(layer "In13.Cu")
		(net "GMI_CPU0_G0_CPU1_G2_TX_DN<11>")
	)
	(segment
		(start 348.572074 -236.026706)
		(end 348.589092 -236.038898)
		(width 0.1143)
		(layer "In13.Cu")
		(net "GMI_CPU0_G0_CPU1_G2_TX_DN<11>")
	)
	(segment
		(start 348.789752 -221.093538)
		(end 348.789752 -221.100142)
		(width 0.1143)
		(layer "In13.Cu")
		(net "GMI_CPU0_G0_CPU1_G2_TX_DN<11>")
	)
	(segment
		(start 348.66072 -229.60076)
		(end 348.661482 -229.601268)
		(width 0.1143)
		(layer "In13.Cu")
		(net "GMI_CPU0_G0_CPU1_G2_TX_DN<11>")
	)
	(segment
		(start 122.934222 -227.029264)
		(end 122.90679 -227.009706)
		(width 0.1143)
		(layer "In13.Cu")
		(net "GMI_CPU0_G0_CPU1_G2_TX_DN<11>")
	)
	(segment
		(start 348.572074 -234.406694)
		(end 348.58833 -234.418632)
		(width 0.1143)
		(layer "In13.Cu")
		(net "GMI_CPU0_G0_CPU1_G2_TX_DN<11>")
	)
	(segment
		(start 348.629986 -231.845358)
		(end 348.628716 -231.84612)
		(width 0.1143)
		(layer "In13.Cu")
		(net "GMI_CPU0_G0_CPU1_G2_TX_DN<11>")
	)
	(segment
		(start 122.864626 -226.343718)
		(end 122.865642 -226.34321)
		(width 0.1143)
		(layer "In13.Cu")
		(net "GMI_CPU0_G0_CPU1_G2_TX_DN<11>")
	)
	(segment
		(start 122.907552 -233.489754)
		(end 122.870468 -233.468672)
		(width 0.1143)
		(layer "In13.Cu")
		(net "GMI_CPU0_G0_CPU1_G2_TX_DN<11>")
	)
	(segment
		(start 348.659704 -223.728534)
		(end 348.632526 -223.744282)
		(width 0.1143)
		(layer "In13.Cu")
		(net "GMI_CPU0_G0_CPU1_G2_TX_DN<11>")
	)
	(segment
		(start 348.682818 -233.42981)
		(end 348.664276 -233.444796)
		(width 0.1143)
		(layer "In13.Cu")
		(net "GMI_CPU0_G0_CPU1_G2_TX_DN<11>")
	)
	(segment
		(start 122.870722 -225.368866)
		(end 122.867928 -225.367088)
		(width 0.1143)
		(layer "In13.Cu")
		(net "GMI_CPU0_G0_CPU1_G2_TX_DN<11>")
	)
	(segment
		(start 122.836178 -233.448606)
		(end 122.81154 -233.428794)
		(width 0.1143)
		(layer "In13.Cu")
		(net "GMI_CPU0_G0_CPU1_G2_TX_DN<11>")
	)
	(segment
		(start 122.865896 -226.98583)
		(end 122.863356 -226.98456)
		(width 0.1143)
		(layer "In13.Cu")
		(net "GMI_CPU0_G0_CPU1_G2_TX_DN<11>")
	)
	(segment
		(start 122.86361 -234.444286)
		(end 122.864372 -234.443778)
		(width 0.1143)
		(layer "In13.Cu")
		(net "GMI_CPU0_G0_CPU1_G2_TX_DN<11>")
	)
	(segment
		(start 348.589092 -226.31908)
		(end 348.629478 -226.342448)
		(width 0.1143)
		(layer "In13.Cu")
		(net "GMI_CPU0_G0_CPU1_G2_TX_DN<11>")
	)
	(segment
		(start 348.632526 -231.844088)
		(end 348.629986 -231.845358)
		(width 0.1143)
		(layer "In13.Cu")
		(net "GMI_CPU0_G0_CPU1_G2_TX_DN<11>")
	)
	(segment
		(start 122.83186 -232.843324)
		(end 122.83313 -232.842308)
		(width 0.1143)
		(layer "In13.Cu")
		(net "GMI_CPU0_G0_CPU1_G2_TX_DN<11>")
	)
	(segment
		(start 122.8344 -231.221534)
		(end 122.867928 -231.201976)
		(width 0.1143)
		(layer "In13.Cu")
		(net "GMI_CPU0_G0_CPU1_G2_TX_DN<11>")
	)
	(segment
		(start 348.629986 -226.985576)
		(end 348.628716 -226.986338)
		(width 0.1143)
		(layer "In13.Cu")
		(net "GMI_CPU0_G0_CPU1_G2_TX_DN<11>")
	)
	(segment
		(start 162.487864 -186.92368)
		(end 162.812222 -186.657742)
		(width 0.14224)
		(layer "In13.Cu")
		(net "GMI_CPU0_G0_CPU1_G2_TX_DN<11>")
	)
	(segment
		(start 122.836178 -223.120204)
		(end 122.867674 -223.101916)
		(width 0.1143)
		(layer "In13.Cu")
		(net "GMI_CPU0_G0_CPU1_G2_TX_DN<11>")
	)
	(segment
		(start 122.865896 -235.085636)
		(end 122.863356 -235.084366)
		(width 0.1143)
		(layer "In13.Cu")
		(net "GMI_CPU0_G0_CPU1_G2_TX_DN<11>")
	)
	(segment
		(start 348.627954 -229.58171)
		(end 348.628716 -229.582218)
		(width 0.1143)
		(layer "In13.Cu")
		(net "GMI_CPU0_G0_CPU1_G2_TX_DN<11>")
	)
	(segment
		(start 151.249634 -196.129402)
		(end 151.564086 -195.871592)
		(width 0.14224)
		(layer "In13.Cu")
		(net "GMI_CPU0_G0_CPU1_G2_TX_DN<11>")
	)
	(segment
		(start 122.90679 -222.149924)
		(end 122.903996 -222.147892)
		(width 0.1143)
		(layer "In13.Cu")
		(net "GMI_CPU0_G0_CPU1_G2_TX_DN<11>")
	)
	(segment
		(start 122.835924 -237.700058)
		(end 122.867674 -237.68177)
		(width 0.1143)
		(layer "In13.Cu")
		(net "GMI_CPU0_G0_CPU1_G2_TX_DN<11>")
	)
	(segment
		(start 122.863356 -233.464354)
		(end 122.836178 -233.448606)
		(width 0.1143)
		(layer "In13.Cu")
		(net "GMI_CPU0_G0_CPU1_G2_TX_DN<11>")
	)
	(segment
		(start 122.903996 -222.147892)
		(end 122.867674 -222.127064)
		(width 0.1143)
		(layer "In13.Cu")
		(net "GMI_CPU0_G0_CPU1_G2_TX_DN<11>")
	)
	(segment
		(start 348.591632 -224.700592)
		(end 348.627954 -224.721674)
		(width 0.1143)
		(layer "In13.Cu")
		(net "GMI_CPU0_G0_CPU1_G2_TX_DN<11>")
	)
	(segment
		(start 122.679968 -221.3229)
		(end 122.66041 -221.303342)
		(width 0.1143)
		(layer "In13.Cu")
		(net "GMI_CPU0_G0_CPU1_G2_TX_DN<11>")
	)
	(segment
		(start 122.867166 -226.986592)
		(end 122.865896 -226.98583)
		(width 0.1143)
		(layer "In13.Cu")
		(net "GMI_CPU0_G0_CPU1_G2_TX_DN<11>")
	)
	(segment
		(start 348.627954 -231.201722)
		(end 348.661482 -231.22128)
		(width 0.1143)
		(layer "In13.Cu")
		(net "GMI_CPU0_G0_CPU1_G2_TX_DN<11>")
	)
	(segment
		(start 348.629986 -228.605588)
		(end 348.628716 -228.60635)
		(width 0.1143)
		(layer "In13.Cu")
		(net "GMI_CPU0_G0_CPU1_G2_TX_DN<11>")
	)
	(segment
		(start 153.485596 -194.131692)
		(end 153.815542 -193.861182)
		(width 0.14224)
		(layer "In13.Cu")
		(net "GMI_CPU0_G0_CPU1_G2_TX_DN<11>")
	)
	(segment
		(start 122.862594 -232.824782)
		(end 122.86361 -232.824274)
		(width 0.1143)
		(layer "In13.Cu")
		(net "GMI_CPU0_G0_CPU1_G2_TX_DN<11>")
	)
	(segment
		(start 145.36039 -199.804274)
		(end 147.273772 -199.224646)
		(width 0.14224)
		(layer "In13.Cu")
		(net "GMI_CPU0_G0_CPU1_G2_TX_DN<11>")
	)
	(segment
		(start 149.193758 -197.6501)
		(end 149.194012 -197.6501)
		(width 0.14224)
		(layer "In13.Cu")
		(net "GMI_CPU0_G0_CPU1_G2_TX_DN<11>")
	)
	(segment
		(start 348.659958 -236.688376)
		(end 348.628208 -236.706664)
		(width 0.1143)
		(layer "In13.Cu")
		(net "GMI_CPU0_G0_CPU1_G2_TX_DN<11>")
	)
	(segment
		(start 348.658942 -233.448606)
		(end 348.632526 -233.4641)
		(width 0.1143)
		(layer "In13.Cu")
		(net "GMI_CPU0_G0_CPU1_G2_TX_DN<11>")
	)
	(segment
		(start 348.627954 -231.846628)
		(end 348.62516 -231.848406)
		(width 0.1143)
		(layer "In13.Cu")
		(net "GMI_CPU0_G0_CPU1_G2_TX_DN<11>")
	)
	(segment
		(start 157.237684 -191.219074)
		(end 157.552136 -190.961264)
		(width 0.14224)
		(layer "In13.Cu")
		(net "GMI_CPU0_G0_CPU1_G2_TX_DN<11>")
	)
	(segment
		(start 348.589092 -227.009452)
		(end 348.56166 -227.02901)
		(width 0.1143)
		(layer "In13.Cu")
		(net "GMI_CPU0_G0_CPU1_G2_TX_DN<11>")
	)
	(segment
		(start 122.861832 -234.445302)
		(end 122.862594 -234.444794)
		(width 0.1143)
		(layer "In13.Cu")
		(net "GMI_CPU0_G0_CPU1_G2_TX_DN<11>")
	)
	(segment
		(start 348.632526 -223.744282)
		(end 348.629986 -223.745552)
		(width 0.1143)
		(layer "In13.Cu")
		(net "GMI_CPU0_G0_CPU1_G2_TX_DN<11>")
	)
	(segment
		(start 348.62516 -225.368612)
		(end 348.589092 -225.38944)
		(width 0.1143)
		(layer "In13.Cu")
		(net "GMI_CPU0_G0_CPU1_G2_TX_DN<11>")
	)
	(segment
		(start 348.835472 -221.303088)
		(end 348.81566 -221.3229)
		(width 0.1143)
		(layer "In13.Cu")
		(net "GMI_CPU0_G0_CPU1_G2_TX_DN<11>")
	)
	(segment
		(start 348.628716 -232.821988)
		(end 348.629986 -232.82275)
		(width 0.1143)
		(layer "In13.Cu")
		(net "GMI_CPU0_G0_CPU1_G2_TX_DN<11>")
	)
	(segment
		(start 348.81566 -221.3229)
		(end 348.81566 -221.658688)
		(width 0.1143)
		(layer "In13.Cu")
		(net "GMI_CPU0_G0_CPU1_G2_TX_DN<11>")
	)
	(segment
		(start 348.629986 -234.442762)
		(end 348.63151 -234.443524)
		(width 0.1143)
		(layer "In13.Cu")
		(net "GMI_CPU0_G0_CPU1_G2_TX_DN<11>")
	)
	(segment
		(start 122.907552 -235.109766)
		(end 122.870468 -235.088684)
		(width 0.1143)
		(layer "In13.Cu")
		(net "GMI_CPU0_G0_CPU1_G2_TX_DN<11>")
	)
	(segment
		(start 122.867928 -231.846882)
		(end 122.867166 -231.846374)
		(width 0.1143)
		(layer "In13.Cu")
		(net "GMI_CPU0_G0_CPU1_G2_TX_DN<11>")
	)
	(segment
		(start 348.631256 -227.963476)
		(end 348.632018 -227.963984)
		(width 0.1143)
		(layer "In13.Cu")
		(net "GMI_CPU0_G0_CPU1_G2_TX_DN<11>")
	)
	(segment
		(start 122.870722 -228.60889)
		(end 122.867928 -228.607112)
		(width 0.1143)
		(layer "In13.Cu")
		(net "GMI_CPU0_G0_CPU1_G2_TX_DN<11>")
	)
	(segment
		(start 348.636082 -234.446064)
		(end 348.659958 -234.460034)
		(width 0.1143)
		(layer "In13.Cu")
		(net "GMI_CPU0_G0_CPU1_G2_TX_DN<11>")
	)
	(segment
		(start 302.604932 -185.41492)
		(end 306.370736 -185.41492)
		(width 0.14224)
		(layer "In13.Cu")
		(net "GMI_CPU0_G0_CPU1_G2_TX_DN<11>")
	)
	(segment
		(start 122.867166 -225.36658)
		(end 122.865896 -225.365818)
		(width 0.1143)
		(layer "In13.Cu")
		(net "GMI_CPU0_G0_CPU1_G2_TX_DN<11>")
	)
	(segment
		(start 122.870722 -231.84866)
		(end 122.867928 -231.846882)
		(width 0.1143)
		(layer "In13.Cu")
		(net "GMI_CPU0_G0_CPU1_G2_TX_DN<11>")
	)
	(segment
		(start 348.629986 -235.085382)
		(end 348.628716 -235.086144)
		(width 0.1143)
		(layer "In13.Cu")
		(net "GMI_CPU0_G0_CPU1_G2_TX_DN<11>")
	)
	(segment
		(start 122.870468 -233.468672)
		(end 122.867928 -233.466894)
		(width 0.1143)
		(layer "In13.Cu")
		(net "GMI_CPU0_G0_CPU1_G2_TX_DN<11>")
	)
	(segment
		(start 348.633034 -227.964492)
		(end 348.633796 -227.965)
		(width 0.1143)
		(layer "In13.Cu")
		(net "GMI_CPU0_G0_CPU1_G2_TX_DN<11>")
	)
	(segment
		(start 348.633796 -227.965)
		(end 348.659704 -227.979986)
		(width 0.1143)
		(layer "In13.Cu")
		(net "GMI_CPU0_G0_CPU1_G2_TX_DN<11>")
	)
	(segment
		(start 122.922792 -231.880664)
		(end 122.907298 -231.869742)
		(width 0.1143)
		(layer "In13.Cu")
		(net "GMI_CPU0_G0_CPU1_G2_TX_DN<11>")
	)
	(segment
		(start 149.194012 -197.6501)
		(end 151.070818 -196.111622)
		(width 0.14224)
		(layer "In13.Cu")
		(net "GMI_CPU0_G0_CPU1_G2_TX_DN<11>")
	)
	(segment
		(start 348.627954 -234.441492)
		(end 348.628716 -234.442)
		(width 0.1143)
		(layer "In13.Cu")
		(net "GMI_CPU0_G0_CPU1_G2_TX_DN<11>")
	)
	(segment
		(start 122.864372 -234.443778)
		(end 122.865896 -234.443016)
		(width 0.1143)
		(layer "In13.Cu")
		(net "GMI_CPU0_G0_CPU1_G2_TX_DN<11>")
	)
	(segment
		(start 348.629986 -232.82275)
		(end 348.63151 -232.823512)
		(width 0.1143)
		(layer "In13.Cu")
		(net "GMI_CPU0_G0_CPU1_G2_TX_DN<11>")
	)
	(segment
		(start 348.63151 -234.443524)
		(end 348.632272 -234.444032)
		(width 0.1143)
		(layer "In13.Cu")
		(net "GMI_CPU0_G0_CPU1_G2_TX_DN<11>")
	)
	(segment
		(start 168.365932 -184.631838)
		(end 302.604932 -185.413142)
		(width 0.14224)
		(layer "In13.Cu")
		(net "GMI_CPU0_G0_CPU1_G2_TX_DN<11>")
	)
	(segment
		(start 122.867928 -233.466894)
		(end 122.867166 -233.466386)
		(width 0.1143)
		(layer "In13.Cu")
		(net "GMI_CPU0_G0_CPU1_G2_TX_DN<11>")
	)
	(segment
		(start 157.88386 -190.524892)
		(end 158.062676 -190.542672)
		(width 0.14224)
		(layer "In13.Cu")
		(net "GMI_CPU0_G0_CPU1_G2_TX_DN<11>")
	)
	(segment
		(start 122.864372 -232.823766)
		(end 122.865896 -232.823004)
		(width 0.1143)
		(layer "In13.Cu")
		(net "GMI_CPU0_G0_CPU1_G2_TX_DN<11>")
	)
	(segment
		(start 122.70613 -221.100396)
		(end 122.70613 -221.071948)
		(width 0.1143)
		(layer "In13.Cu")
		(net "GMI_CPU0_G0_CPU1_G2_TX_DN<11>")
	)
	(segment
		(start 122.867674 -237.68177)
		(end 122.90679 -237.65891)
		(width 0.1143)
		(layer "In13.Cu")
		(net "GMI_CPU0_G0_CPU1_G2_TX_DN<11>")
	)
	(segment
		(start 122.867928 -229.581964)
		(end 122.867928 -229.581456)
		(width 0.1143)
		(layer "In13.Cu")
		(net "GMI_CPU0_G0_CPU1_G2_TX_DN<11>")
	)
	(segment
		(start 122.907298 -231.869742)
		(end 122.870722 -231.84866)
		(width 0.1143)
		(layer "In13.Cu")
		(net "GMI_CPU0_G0_CPU1_G2_TX_DN<11>")
	)
	(segment
		(start 122.867674 -236.061758)
		(end 122.90679 -236.039152)
		(width 0.1143)
		(layer "In13.Cu")
		(net "GMI_CPU0_G0_CPU1_G2_TX_DN<11>")
	)
	(segment
		(start 162.29838 -186.905138)
		(end 162.487864 -186.92368)
		(width 0.14224)
		(layer "In13.Cu")
		(net "GMI_CPU0_G0_CPU1_G2_TX_DN<11>")
	)
	(segment
		(start 348.59595 -230.245158)
		(end 348.594426 -230.246174)
		(width 0.1143)
		(layer "In13.Cu")
		(net "GMI_CPU0_G0_CPU1_G2_TX_DN<11>")
	)
	(segment
		(start 122.815096 -234.477052)
		(end 122.835924 -234.460288)
		(width 0.1143)
		(layer "In13.Cu")
		(net "GMI_CPU0_G0_CPU1_G2_TX_DN<11>")
	)
	(segment
		(start 122.819922 -232.85323)
		(end 122.822462 -232.851198)
		(width 0.1143)
		(layer "In13.Cu")
		(net "GMI_CPU0_G0_CPU1_G2_TX_DN<11>")
	)
	(segment
		(start 348.789752 -219.98813)
		(end 348.789752 -221.093538)
		(width 0.14224)
		(layer "In13.Cu")
		(net "GMI_CPU0_G0_CPU1_G2_TX_DN<11>")
	)
	(segment
		(start 122.83313 -232.842308)
		(end 122.834146 -232.841546)
		(width 0.1143)
		(layer "In13.Cu")
		(net "GMI_CPU0_G0_CPU1_G2_TX_DN<11>")
	)
	(segment
		(start 348.634558 -226.345242)
		(end 348.63532 -226.34575)
		(width 0.1143)
		(layer "In13.Cu")
		(net "GMI_CPU0_G0_CPU1_G2_TX_DN<11>")
	)
	(segment
		(start 348.63532 -226.34575)
		(end 348.659704 -226.359974)
		(width 0.1143)
		(layer "In13.Cu")
		(net "GMI_CPU0_G0_CPU1_G2_TX_DN<11>")
	)
	(segment
		(start 348.628208 -236.061504)
		(end 348.659958 -236.079792)
		(width 0.1143)
		(layer "In13.Cu")
		(net "GMI_CPU0_G0_CPU1_G2_TX_DN<11>")
	)
	(segment
		(start 152.07107 -195.29171)
		(end 152.26411 -195.31076)
		(width 0.14224)
		(layer "In13.Cu")
		(net "GMI_CPU0_G0_CPU1_G2_TX_DN<11>")
	)
	(segment
		(start 122.865642 -226.34321)
		(end 122.866404 -226.342702)
		(width 0.1143)
		(layer "In13.Cu")
		(net "GMI_CPU0_G0_CPU1_G2_TX_DN<11>")
	)
	(segment
		(start 348.34576 -229.093776)
		(end 348.34576 -229.094284)
		(width 0.1143)
		(layer "In13.Cu")
		(net "GMI_CPU0_G0_CPU1_G2_TX_DN<11>")
	)
	(segment
		(start 122.865896 -228.605842)
		(end 122.863356 -228.604572)
		(width 0.1143)
		(layer "In13.Cu")
		(net "GMI_CPU0_G0_CPU1_G2_TX_DN<11>")
	)
	(segment
		(start 348.659704 -225.348546)
		(end 348.632526 -225.364294)
		(width 0.1143)
		(layer "In13.Cu")
		(net "GMI_CPU0_G0_CPU1_G2_TX_DN<11>")
	)
	(segment
		(start 122.923808 -233.501692)
		(end 122.907552 -233.489754)
		(width 0.1143)
		(layer "In13.Cu")
		(net "GMI_CPU0_G0_CPU1_G2_TX_DN<11>")
	)
	(segment
		(start 347.0656 -217.08364)
		(end 348.789752 -219.98813)
		(width 0.14224)
		(layer "In13.Cu")
		(net "GMI_CPU0_G0_CPU1_G2_TX_DN<11>")
	)
	(segment
		(start 147.273772 -199.224646)
		(end 149.193758 -197.6501)
		(width 0.14224)
		(layer "In13.Cu")
		(net "GMI_CPU0_G0_CPU1_G2_TX_DN<11>")
	)
	(segment
		(start 122.867928 -228.607112)
		(end 122.867166 -228.606604)
		(width 0.1143)
		(layer "In13.Cu")
		(net "GMI_CPU0_G0_CPU1_G2_TX_DN<11>")
	)
	(segment
		(start 348.628208 -237.681516)
		(end 348.659958 -237.699804)
		(width 0.1143)
		(layer "In13.Cu")
		(net "GMI_CPU0_G0_CPU1_G2_TX_DN<11>")
	)
	(segment
		(start 348.628716 -225.366326)
		(end 348.627954 -225.366834)
		(width 0.1143)
		(layer "In13.Cu")
		(net "GMI_CPU0_G0_CPU1_G2_TX_DN<11>")
	)
	(segment
		(start 122.90679 -236.039152)
		(end 122.923808 -236.02696)
		(width 0.1143)
		(layer "In13.Cu")
		(net "GMI_CPU0_G0_CPU1_G2_TX_DN<11>")
	)
	(segment
		(start 348.62516 -228.608636)
		(end 348.588838 -228.629464)
		(width 0.1143)
		(layer "In13.Cu")
		(net "GMI_CPU0_G0_CPU1_G2_TX_DN<11>")
	)
	(segment
		(start 154.338782 -193.609468)
		(end 154.357832 -193.416428)
		(width 0.14224)
		(layer "In13.Cu")
		(net "GMI_CPU0_G0_CPU1_G2_TX_DN<11>")
	)
	(segment
		(start 348.631256 -226.343464)
		(end 348.632018 -226.343972)
		(width 0.1143)
		(layer "In13.Cu")
		(net "GMI_CPU0_G0_CPU1_G2_TX_DN<11>")
	)
	(segment
		(start 348.624398 -230.228648)
		(end 348.59595 -230.245158)
		(width 0.1143)
		(layer "In13.Cu")
		(net "GMI_CPU0_G0_CPU1_G2_TX_DN<11>")
	)
	(segment
		(start 122.90679 -227.009706)
		(end 122.870722 -226.988878)
		(width 0.1143)
		(layer "In13.Cu")
		(net "GMI_CPU0_G0_CPU1_G2_TX_DN<11>")
	)
	(segment
		(start 348.627954 -229.581202)
		(end 348.627954 -229.58171)
		(width 0.1143)
		(layer "In13.Cu")
		(net "GMI_CPU0_G0_CPU1_G2_TX_DN<11>")
	)
	(segment
		(start 122.91568 -228.635814)
		(end 122.907044 -228.629718)
		(width 0.1143)
		(layer "In13.Cu")
		(net "GMI_CPU0_G0_CPU1_G2_TX_DN<11>")
	)
	(segment
		(start 153.466546 -194.324732)
		(end 153.485596 -194.131692)
		(width 0.14224)
		(layer "In13.Cu")
		(net "GMI_CPU0_G0_CPU1_G2_TX_DN<11>")
	)
	(segment
		(start 122.865896 -234.443016)
		(end 122.867166 -234.442254)
		(width 0.1143)
		(layer "In13.Cu")
		(net "GMI_CPU0_G0_CPU1_G2_TX_DN<11>")
	)
	(segment
		(start 348.659958 -234.460034)
		(end 348.679262 -234.475528)
		(width 0.1143)
		(layer "In13.Cu")
		(net "GMI_CPU0_G0_CPU1_G2_TX_DN<11>")
	)
	(segment
		(start 348.589092 -227.939092)
		(end 348.629478 -227.96246)
		(width 0.1143)
		(layer "In13.Cu")
		(net "GMI_CPU0_G0_CPU1_G2_TX_DN<11>")
	)
	(segment
		(start 348.632526 -228.604318)
		(end 348.629986 -228.605588)
		(width 0.1143)
		(layer "In13.Cu")
		(net "GMI_CPU0_G0_CPU1_G2_TX_DN<11>")
	)
	(segment
		(start 122.756676 -239.624362)
		(end 122.68835 -239.556036)
		(width 0.1143)
		(layer "In13.Cu")
		(net "GMI_CPU0_G0_CPU1_G2_TX_DN<11>")
	)
	(segment
		(start 122.836178 -224.740216)
		(end 122.867928 -224.721928)
		(width 0.1143)
		(layer "In13.Cu")
		(net "GMI_CPU0_G0_CPU1_G2_TX_DN<11>")
	)
	(segment
		(start 348.835472 -221.145862)
		(end 348.835472 -221.303088)
		(width 0.1143)
		(layer "In13.Cu")
		(net "GMI_CPU0_G0_CPU1_G2_TX_DN<11>")
	)
	(segment
		(start 348.58833 -235.109512)
		(end 348.572074 -235.12145)
		(width 0.1143)
		(layer "In13.Cu")
		(net "GMI_CPU0_G0_CPU1_G2_TX_DN<11>")
	)
	(segment
		(start 348.628716 -231.84612)
		(end 348.627954 -231.846628)
		(width 0.1143)
		(layer "In13.Cu")
		(net "GMI_CPU0_G0_CPU1_G2_TX_DN<11>")
	)
	(segment
		(start 122.825256 -232.848912)
		(end 122.827034 -232.847388)
		(width 0.1143)
		(layer "In13.Cu")
		(net "GMI_CPU0_G0_CPU1_G2_TX_DN<11>")
	)
	(segment
		(start 122.867674 -238.32693)
		(end 122.835924 -238.308642)
		(width 0.1143)
		(layer "In13.Cu")
		(net "GMI_CPU0_G0_CPU1_G2_TX_DN<11>")
	)
	(segment
		(start 348.589854 -239.279176)
		(end 348.635828 -239.305846)
		(width 0.1143)
		(layer "In13.Cu")
		(net "GMI_CPU0_G0_CPU1_G2_TX_DN<11>")
	)
	(segment
		(start 122.834908 -232.841038)
		(end 122.835924 -232.840276)
		(width 0.1143)
		(layer "In13.Cu")
		(net "GMI_CPU0_G0_CPU1_G2_TX_DN<11>")
	)
	(segment
		(start 348.628716 -234.442)
		(end 348.629986 -234.442762)
		(width 0.1143)
		(layer "In13.Cu")
		(net "GMI_CPU0_G0_CPU1_G2_TX_DN<11>")
	)
	(segment
		(start 122.68835 -239.556036)
		(end 122.688858 -239.553496)
		(width 0.1143)
		(layer "In13.Cu")
		(net "GMI_CPU0_G0_CPU1_G2_TX_DN<11>")
	)
	(segment
		(start 122.8598 -232.826306)
		(end 122.861832 -232.82529)
		(width 0.1143)
		(layer "In13.Cu")
		(net "GMI_CPU0_G0_CPU1_G2_TX_DN<11>")
	)
	(segment
		(start 163.330636 -186.058556)
		(end 167.320468 -184.631838)
		(width 0.14224)
		(layer "In13.Cu")
		(net "GMI_CPU0_G0_CPU1_G2_TX_DN<11>")
	)
	(segment
		(start 122.863356 -228.604572)
		(end 122.836178 -228.588824)
		(width 0.1143)
		(layer "In13.Cu")
		(net "GMI_CPU0_G0_CPU1_G2_TX_DN<11>")
	)
	(segment
		(start 123.054618 -239.624362)
		(end 122.756676 -239.624362)
		(width 0.1143)
		(layer "In13.Cu")
		(net "GMI_CPU0_G0_CPU1_G2_TX_DN<11>")
	)
	(segment
		(start 348.632018 -227.963984)
		(end 348.633034 -227.964492)
		(width 0.1143)
		(layer "In13.Cu")
		(net "GMI_CPU0_G0_CPU1_G2_TX_DN<11>")
	)
	(segment
		(start 122.864626 -227.96373)
		(end 122.865642 -227.963222)
		(width 0.1143)
		(layer "In13.Cu")
		(net "GMI_CPU0_G0_CPU1_G2_TX_DN<11>")
	)
	(segment
		(start 348.58833 -234.418632)
		(end 348.627954 -234.441492)
		(width 0.1143)
		(layer "In13.Cu")
		(net "GMI_CPU0_G0_CPU1_G2_TX_DN<11>")
	)
	(segment
		(start 122.867928 -226.9871)
		(end 122.867166 -226.986592)
		(width 0.1143)
		(layer "In13.Cu")
		(net "GMI_CPU0_G0_CPU1_G2_TX_DN<11>")
	)
	(segment
		(start 348.628208 -238.326676)
		(end 348.591886 -238.347504)
		(width 0.1143)
		(layer "In13.Cu")
		(net "GMI_CPU0_G0_CPU1_G2_TX_DN<11>")
	)
	(segment
		(start 122.830336 -232.844848)
		(end 122.83186 -232.843324)
		(width 0.1143)
		(layer "In13.Cu")
		(net "GMI_CPU0_G0_CPU1_G2_TX_DN<11>")
	)
	(segment
		(start 348.627954 -230.226616)
		(end 348.626938 -230.227124)
		(width 0.1143)
		(layer "In13.Cu")
		(net "GMI_CPU0_G0_CPU1_G2_TX_DN<11>")
	)
	(segment
		(start 152.943306 -194.576446)
		(end 153.136346 -194.595496)
		(width 0.14224)
		(layer "In13.Cu")
		(net "GMI_CPU0_G0_CPU1_G2_TX_DN<11>")
	)
	(segment
		(start 348.659958 -232.840022)
		(end 348.682056 -232.858056)
		(width 0.1143)
		(layer "In13.Cu")
		(net "GMI_CPU0_G0_CPU1_G2_TX_DN<11>")
	)
	(segment
		(start 348.628716 -235.086144)
		(end 348.627954 -235.086652)
		(width 0.1143)
		(layer "In13.Cu")
		(net "GMI_CPU0_G0_CPU1_G2_TX_DN<11>")
	)
	(segment
		(start 348.57309 -232.787698)
		(end 348.588584 -232.79862)
		(width 0.1143)
		(layer "In13.Cu")
		(net "GMI_CPU0_G0_CPU1_G2_TX_DN<11>")
	)
	(segment
		(start 122.867928 -235.086906)
		(end 122.867166 -235.086398)
		(width 0.1143)
		(layer "In13.Cu")
		(net "GMI_CPU0_G0_CPU1_G2_TX_DN<11>")
	)
	(segment
		(start 122.679968 -221.804484)
		(end 122.679968 -221.3229)
		(width 0.1143)
		(layer "In13.Cu")
		(net "GMI_CPU0_G0_CPU1_G2_TX_DN<11>")
	)
	(segment
		(start 122.867928 -231.201722)
		(end 122.870722 -231.200198)
		(width 0.1143)
		(layer "In13.Cu")
		(net "GMI_CPU0_G0_CPU1_G2_TX_DN<11>")
	)
	(segment
		(start 348.56166 -227.919534)
		(end 348.589092 -227.939092)
		(width 0.1143)
		(layer "In13.Cu")
		(net "GMI_CPU0_G0_CPU1_G2_TX_DN<11>")
	)
	(segment
		(start 348.627954 -226.986846)
		(end 348.62516 -226.988624)
		(width 0.1143)
		(layer "In13.Cu")
		(net "GMI_CPU0_G0_CPU1_G2_TX_DN<11>")
	)
	(segment
		(start 152.61336 -194.846956)
		(end 152.943306 -194.576446)
		(width 0.14224)
		(layer "In13.Cu")
		(net "GMI_CPU0_G0_CPU1_G2_TX_DN<11>")
	)
	(segment
		(start 122.865896 -225.365818)
		(end 122.863356 -225.364548)
		(width 0.1143)
		(layer "In13.Cu")
		(net "GMI_CPU0_G0_CPU1_G2_TX_DN<11>")
	)
	(segment
		(start 348.588584 -232.79862)
		(end 348.627954 -232.82148)
		(width 0.1143)
		(layer "In13.Cu")
		(net "GMI_CPU0_G0_CPU1_G2_TX_DN<11>")
	)
	(segment
		(start 122.835924 -234.460288)
		(end 122.8598 -234.446318)
		(width 0.1143)
		(layer "In13.Cu")
		(net "GMI_CPU0_G0_CPU1_G2_TX_DN<11>")
	)
	(segment
		(start 122.834146 -232.841546)
		(end 122.834908 -232.841038)
		(width 0.1143)
		(layer "In13.Cu")
		(net "GMI_CPU0_G0_CPU1_G2_TX_DN<11>")
	)
	(segment
		(start 122.863356 -235.084366)
		(end 122.836178 -235.068618)
		(width 0.1143)
		(layer "In13.Cu")
		(net "GMI_CPU0_G0_CPU1_G2_TX_DN<11>")
	)
	(segment
		(start 122.867166 -235.086398)
		(end 122.865896 -235.085636)
		(width 0.1143)
		(layer "In13.Cu")
		(net "GMI_CPU0_G0_CPU1_G2_TX_DN<11>")
	)
	(segment
		(start 122.925332 -225.402902)
		(end 122.90679 -225.389694)
		(width 0.1143)
		(layer "In13.Cu")
		(net "GMI_CPU0_G0_CPU1_G2_TX_DN<11>")
	)
	(segment
		(start 122.870722 -226.988878)
		(end 122.867928 -226.9871)
		(width 0.1143)
		(layer "In13.Cu")
		(net "GMI_CPU0_G0_CPU1_G2_TX_DN<11>")
	)
	(segment
		(start 348.789752 -221.100142)
		(end 348.835472 -221.145862)
		(width 0.1143)
		(layer "In13.Cu")
		(net "GMI_CPU0_G0_CPU1_G2_TX_DN<11>")
	)
	(segment
		(start 348.625414 -233.468418)
		(end 348.58833 -233.4895)
		(width 0.1143)
		(layer "In13.Cu")
		(net "GMI_CPU0_G0_CPU1_G2_TX_DN<11>")
	)
	(segment
		(start 348.686628 -222.093028)
		(end 348.589092 -222.14967)
		(width 0.1143)
		(layer "In13.Cu")
		(net "GMI_CPU0_G0_CPU1_G2_TX_DN<11>")
	)
	(segment
		(start 348.627954 -223.746822)
		(end 348.591632 -223.767904)
		(width 0.1143)
		(layer "In13.Cu")
		(net "GMI_CPU0_G0_CPU1_G2_TX_DN<11>")
	)
	(segment
		(start 122.907298 -232.798874)
		(end 122.922792 -232.787952)
		(width 0.1143)
		(layer "In13.Cu")
		(net "GMI_CPU0_G0_CPU1_G2_TX_DN<11>")
	)
	(segment
		(start 122.835924 -232.840276)
		(end 122.8598 -232.826306)
		(width 0.1143)
		(layer "In13.Cu")
		(net "GMI_CPU0_G0_CPU1_G2_TX_DN<11>")
	)
	(segment
		(start 158.394908 -190.106046)
		(end 158.394908 -190.105792)
		(width 0.14224)
		(layer "In13.Cu")
		(net "GMI_CPU0_G0_CPU1_G2_TX_DN<11>")
	)
	(segment
		(start 122.90679 -238.34979)
		(end 122.903996 -238.347758)
		(width 0.1143)
		(layer "In13.Cu")
		(net "GMI_CPU0_G0_CPU1_G2_TX_DN<11>")
	)
	(segment
		(start 122.871484 -230.228902)
		(end 122.870468 -230.228394)
		(width 0.1143)
		(layer "In13.Cu")
		(net "GMI_CPU0_G0_CPU1_G2_TX_DN<11>")
	)
	(segment
		(start 348.807024 -239.553242)
		(end 348.807532 -239.555782)
		(width 0.1143)
		(layer "In13.Cu")
		(net "GMI_CPU0_G0_CPU1_G2_TX_DN<11>")
	)
	(segment
		(start 122.835924 -236.080046)
		(end 122.867674 -236.061758)
		(width 0.1143)
		(layer "In13.Cu")
		(net "GMI_CPU0_G0_CPU1_G2_TX_DN<11>")
	)
	(segment
		(start 167.320468 -184.631838)
		(end 168.365932 -184.631838)
		(width 0.14224)
		(layer "In13.Cu")
		(net "GMI_CPU0_G0_CPU1_G2_TX_DN<11>")
	)
	(segment
		(start 154.357832 -193.416428)
		(end 154.687778 -193.145918)
		(width 0.14224)
		(layer "In13.Cu")
		(net "GMI_CPU0_G0_CPU1_G2_TX_DN<11>")
	)
	(segment
		(start 153.136346 -194.595496)
		(end 153.466546 -194.324732)
		(width 0.14224)
		(layer "In13.Cu")
		(net "GMI_CPU0_G0_CPU1_G2_TX_DN<11>")
	)
	(segment
		(start 156.412438 -191.89573)
		(end 156.727144 -191.63792)
		(width 0.14224)
		(layer "In13.Cu")
		(net "GMI_CPU0_G0_CPU1_G2_TX_DN<11>")
	)
	(segment
		(start 348.627954 -232.82148)
		(end 348.628716 -232.821988)
		(width 0.1143)
		(layer "In13.Cu")
		(net "GMI_CPU0_G0_CPU1_G2_TX_DN<11>")
	)
	(segment
		(start 307.261006 -185.782966)
		(end 314.093606 -190.047626)
		(width 0.14224)
		(layer "In13.Cu")
		(net "GMI_CPU0_G0_CPU1_G2_TX_DN<11>")
	)
	(segment
		(start 122.836178 -226.360228)
		(end 122.860562 -226.346004)
		(width 0.1143)
		(layer "In13.Cu")
		(net "GMI_CPU0_G0_CPU1_G2_TX_DN<11>")
	)
	(segment
		(start 348.633288 -232.824528)
		(end 348.63405 -232.825036)
		(width 0.1143)
		(layer "In13.Cu")
		(net "GMI_CPU0_G0_CPU1_G2_TX_DN<11>")
	)
	(segment
		(start 348.628716 -233.466132)
		(end 348.627954 -233.46664)
		(width 0.1143)
		(layer "In13.Cu")
		(net "GMI_CPU0_G0_CPU1_G2_TX_DN<11>")
	)
	(segment
		(start 348.726506 -239.636808)
		(end 348.45371 -239.636808)
		(width 0.1143)
		(layer "In13.Cu")
		(net "GMI_CPU0_G0_CPU1_G2_TX_DN<11>")
	)
	(segment
		(start 348.589092 -236.038898)
		(end 348.628208 -236.061504)
		(width 0.1143)
		(layer "In13.Cu")
		(net "GMI_CPU0_G0_CPU1_G2_TX_DN<11>")
	)
	(segment
		(start 348.633288 -234.44454)
		(end 348.63405 -234.445048)
		(width 0.1143)
		(layer "In13.Cu")
		(net "GMI_CPU0_G0_CPU1_G2_TX_DN<11>")
	)
	(segment
		(start 348.659958 -238.308388)
		(end 348.628208 -238.326676)
		(width 0.1143)
		(layer "In13.Cu")
		(net "GMI_CPU0_G0_CPU1_G2_TX_DN<11>")
	)
	(segment
		(start 122.86361 -232.824274)
		(end 122.864372 -232.823766)
		(width 0.1143)
		(layer "In13.Cu")
		(net "GMI_CPU0_G0_CPU1_G2_TX_DN<11>")
	)
	(segment
		(start 122.822462 -232.851198)
		(end 122.82424 -232.849674)
		(width 0.1143)
		(layer "In13.Cu")
		(net "GMI_CPU0_G0_CPU1_G2_TX_DN<11>")
	)
	(segment
		(start 348.628716 -223.746314)
		(end 348.627954 -223.746822)
		(width 0.1143)
		(layer "In13.Cu")
		(net "GMI_CPU0_G0_CPU1_G2_TX_DN<11>")
	)
	(segment
		(start 122.66041 -221.146116)
		(end 122.70613 -221.100396)
		(width 0.1143)
		(layer "In13.Cu")
		(net "GMI_CPU0_G0_CPU1_G2_TX_DN<11>")
	)
	(segment
		(start 122.8598 -234.446318)
		(end 122.861832 -234.445302)
		(width 0.1143)
		(layer "In13.Cu")
		(net "GMI_CPU0_G0_CPU1_G2_TX_DN<11>")
	)
	(segment
		(start 348.63405 -232.825036)
		(end 348.636082 -232.826052)
		(width 0.1143)
		(layer "In13.Cu")
		(net "GMI_CPU0_G0_CPU1_G2_TX_DN<11>")
	)
	(segment
		(start 348.632018 -226.343972)
		(end 348.634558 -226.345242)
		(width 0.1143)
		(layer "In13.Cu")
		(net "GMI_CPU0_G0_CPU1_G2_TX_DN<11>")
	)
	(segment
		(start 122.860054 -239.3061)
		(end 122.906028 -239.27943)
		(width 0.1143)
		(layer "In13.Cu")
		(net "GMI_CPU0_G0_CPU1_G2_TX_DN<11>")
	)
	(segment
		(start 122.8344 -229.601522)
		(end 122.835162 -229.601014)
		(width 0.1143)
		(layer "In13.Cu")
		(net "GMI_CPU0_G0_CPU1_G2_TX_DN<11>")
	)
	(segment
		(start 348.659704 -228.58857)
		(end 348.632526 -228.604318)
		(width 0.1143)
		(layer "In13.Cu")
		(net "GMI_CPU0_G0_CPU1_G2_TX_DN<11>")
	)
	(segment
		(start 156.233876 -191.878204)
		(end 156.412438 -191.89573)
		(width 0.14224)
		(layer "In13.Cu")
		(net "GMI_CPU0_G0_CPU1_G2_TX_DN<11>")
	)
	(segment
		(start 348.589092 -237.658656)
		(end 348.628208 -237.681516)
		(width 0.1143)
		(layer "In13.Cu")
		(net "GMI_CPU0_G0_CPU1_G2_TX_DN<11>")
	)
	(segment
		(start 122.870468 -230.228394)
		(end 122.868944 -230.227378)
		(width 0.1143)
		(layer "In13.Cu")
		(net "GMI_CPU0_G0_CPU1_G2_TX_DN<11>")
	)
	(segment
		(start 152.59431 -195.039996)
		(end 152.61336 -194.846956)
		(width 0.14224)
		(layer "In13.Cu")
		(net "GMI_CPU0_G0_CPU1_G2_TX_DN<11>")
	)
	(segment
		(start 122.90679 -225.389694)
		(end 122.870722 -225.368866)
		(width 0.1143)
		(layer "In13.Cu")
		(net "GMI_CPU0_G0_CPU1_G2_TX_DN<11>")
	)
	(segment
		(start 348.632526 -233.4641)
		(end 348.629986 -233.46537)
		(width 0.1143)
		(layer "In13.Cu")
		(net "GMI_CPU0_G0_CPU1_G2_TX_DN<11>")
	)
	(segment
		(start 348.57055 -226.305872)
		(end 348.589092 -226.31908)
		(width 0.1143)
		(layer "In13.Cu")
		(net "GMI_CPU0_G0_CPU1_G2_TX_DN<11>")
	)
	(segment
		(start 348.627954 -235.086652)
		(end 348.625414 -235.08843)
		(width 0.1143)
		(layer "In13.Cu")
		(net "GMI_CPU0_G0_CPU1_G2_TX_DN<11>")
	)
	(segment
		(start 123.150122 -229.094538)
		(end 123.150122 -229.09403)
		(width 0.1143)
		(layer "In13.Cu")
		(net "GMI_CPU0_G0_CPU1_G2_TX_DN<11>")
	)
	(segment
		(start 122.867674 -222.127064)
		(end 122.835924 -222.108776)
		(width 0.1143)
		(layer "In13.Cu")
		(net "GMI_CPU0_G0_CPU1_G2_TX_DN<11>")
	)
	(segment
		(start 122.865896 -223.745806)
		(end 122.863356 -223.744536)
		(width 0.1143)
		(layer "In13.Cu")
		(net "GMI_CPU0_G0_CPU1_G2_TX_DN<11>")
	)
	(segment
		(start 122.90425 -223.768158)
		(end 122.867928 -223.747076)
		(width 0.1143)
		(layer "In13.Cu")
		(net "GMI_CPU0_G0_CPU1_G2_TX_DN<11>")
	)
	(segment
		(start 348.807532 -239.555782)
		(end 348.726506 -239.636808)
		(width 0.1143)
		(layer "In13.Cu")
		(net "GMI_CPU0_G0_CPU1_G2_TX_DN<11>")
	)
	(segment
		(start 122.901456 -230.246428)
		(end 122.899932 -230.245412)
		(width 0.1143)
		(layer "In13.Cu")
		(net "GMI_CPU0_G0_CPU1_G2_TX_DN<11>")
	)
	(segment
		(start 122.907044 -228.629718)
		(end 122.870722 -228.60889)
		(width 0.1143)
		(layer "In13.Cu")
		(net "GMI_CPU0_G0_CPU1_G2_TX_DN<11>")
	)
	(segment
		(start 348.679008 -235.05287)
		(end 348.659704 -235.068364)
		(width 0.1143)
		(layer "In13.Cu")
		(net "GMI_CPU0_G0_CPU1_G2_TX_DN<11>")
	)
	(segment
		(start 154.008582 -193.880232)
		(end 154.338782 -193.609468)
		(width 0.14224)
		(layer "In13.Cu")
		(net "GMI_CPU0_G0_CPU1_G2_TX_DN<11>")
	)
	(segment
		(start 348.815914 -221.658942)
		(end 348.815914 -221.868746)
		(width 0.1143)
		(layer "In13.Cu")
		(net "GMI_CPU0_G0_CPU1_G2_TX_DN<11>")
	)
	(segment
		(start 348.632526 -226.984306)
		(end 348.629986 -226.985576)
		(width 0.1143)
		(layer "In13.Cu")
		(net "GMI_CPU0_G0_CPU1_G2_TX_DN<11>")
	)
	(segment
		(start 122.70613 -221.071948)
		(end 122.70613 -220.14688)
		(width 0.14224)
		(layer "In13.Cu")
		(net "GMI_CPU0_G0_CPU1_G2_TX_DN<11>")
	)
	(segment
		(start 348.63024 -227.962968)
		(end 348.631256 -227.963476)
		(width 0.1143)
		(layer "In13.Cu")
		(net "GMI_CPU0_G0_CPU1_G2_TX_DN<11>")
	)
	(segment
		(start 122.863864 -226.344226)
		(end 122.864626 -226.343718)
		(width 0.1143)
		(layer "In13.Cu")
		(net "GMI_CPU0_G0_CPU1_G2_TX_DN<11>")
	)
	(segment
		(start 122.862086 -227.965254)
		(end 122.862848 -227.964746)
		(width 0.1143)
		(layer "In13.Cu")
		(net "GMI_CPU0_G0_CPU1_G2_TX_DN<11>")
	)
	(segment
		(start 348.628208 -236.706664)
		(end 348.589092 -236.729524)
		(width 0.1143)
		(layer "In13.Cu")
		(net "GMI_CPU0_G0_CPU1_G2_TX_DN<11>")
	)
	(segment
		(start 122.870468 -235.088684)
		(end 122.867928 -235.086906)
		(width 0.1143)
		(layer "In13.Cu")
		(net "GMI_CPU0_G0_CPU1_G2_TX_DN<11>")
	)
	(segment
		(start 122.82424 -232.849674)
		(end 122.825256 -232.848912)
		(width 0.1143)
		(layer "In13.Cu")
		(net "GMI_CPU0_G0_CPU1_G2_TX_DN<11>")
	)
	(segment
		(start 348.632526 -225.364294)
		(end 348.629986 -225.365564)
		(width 0.1143)
		(layer "In13.Cu")
		(net "GMI_CPU0_G0_CPU1_G2_TX_DN<11>")
	)
	(segment
		(start 122.865642 -227.963222)
		(end 122.866404 -227.962714)
		(width 0.1143)
		(layer "In13.Cu")
		(net "GMI_CPU0_G0_CPU1_G2_TX_DN<11>")
	)
	(segment
		(start 348.625414 -230.22814)
		(end 348.624398 -230.228648)
		(width 0.1143)
		(layer "In13.Cu")
		(net "GMI_CPU0_G0_CPU1_G2_TX_DN<11>")
	)
	(segment
		(start 122.867928 -224.721928)
		(end 122.90425 -224.700846)
		(width 0.1143)
		(layer "In13.Cu")
		(net "GMI_CPU0_G0_CPU1_G2_TX_DN<11>")
	)
	(segment
		(start 154.687778 -193.145918)
		(end 154.880818 -193.164968)
		(width 0.14224)
		(layer "In13.Cu")
		(net "GMI_CPU0_G0_CPU1_G2_TX_DN<11>")
	)
	(segment
		(start 348.628716 -226.986338)
		(end 348.627954 -226.986846)
		(width 0.1143)
		(layer "In13.Cu")
		(net "GMI_CPU0_G0_CPU1_G2_TX_DN<11>")
	)
	(segment
		(start 306.370736 -185.41492)
		(end 307.261006 -185.782966)
		(width 0.14224)
		(layer "In13.Cu")
		(net "GMI_CPU0_G0_CPU1_G2_TX_DN<11>")
	)
	(segment
		(start 122.818398 -232.8545)
		(end 122.819922 -232.85323)
		(width 0.1143)
		(layer "In13.Cu")
		(net "GMI_CPU0_G0_CPU1_G2_TX_DN<11>")
	)
	(segment
		(start 348.591886 -238.347504)
		(end 348.589092 -238.349536)
		(width 0.1143)
		(layer "In13.Cu")
		(net "GMI_CPU0_G0_CPU1_G2_TX_DN<11>")
	)
	(segment
		(start 122.82932 -232.84561)
		(end 122.830336 -232.844848)
		(width 0.1143)
		(layer "In13.Cu")
		(net "GMI_CPU0_G0_CPU1_G2_TX_DN<11>")
	)
	(segment
		(start 348.625414 -235.08843)
		(end 348.58833 -235.109512)
		(width 0.1143)
		(layer "In13.Cu")
		(net "GMI_CPU0_G0_CPU1_G2_TX_DN<11>")
	)
	(segment
		(start 348.659704 -231.82834)
		(end 348.632526 -231.844088)
		(width 0.1143)
		(layer "In13.Cu")
		(net "GMI_CPU0_G0_CPU1_G2_TX_DN<11>")
	)
	(segment
		(start 122.867166 -228.606604)
		(end 122.865896 -228.605842)
		(width 0.1143)
		(layer "In13.Cu")
		(net "GMI_CPU0_G0_CPU1_G2_TX_DN<11>")
	)
	(segment
		(start 122.827034 -232.847388)
		(end 122.82932 -232.84561)
		(width 0.1143)
		(layer "In13.Cu")
		(net "GMI_CPU0_G0_CPU1_G2_TX_DN<11>")
	)
	(segment
		(start 348.63024 -226.342956)
		(end 348.631256 -226.343464)
		(width 0.1143)
		(layer "In13.Cu")
		(net "GMI_CPU0_G0_CPU1_G2_TX_DN<11>")
	)
	(segment
		(start 122.861324 -226.345496)
		(end 122.863864 -226.344226)
		(width 0.1143)
		(layer "In13.Cu")
		(net "GMI_CPU0_G0_CPU1_G2_TX_DN<11>")
	)
	(segment
		(start 314.093606 -190.047626)
		(end 347.0656 -217.08364)
		(width 0.14224)
		(layer "In13.Cu")
		(net "GMI_CPU0_G0_CPU1_G2_TX_DN<11>")
	)
	(segment
		(start 122.865896 -232.823004)
		(end 122.867166 -232.822242)
		(width 0.1143)
		(layer "In13.Cu")
		(net "GMI_CPU0_G0_CPU1_G2_TX_DN<11>")
	)
	(segment
		(start 122.865896 -233.465624)
		(end 122.863356 -233.464354)
		(width 0.1143)
		(layer "In13.Cu")
		(net "GMI_CPU0_G0_CPU1_G2_TX_DN<11>")
	)
	(segment
		(start 348.629986 -225.365564)
		(end 348.628716 -225.366326)
		(width 0.1143)
		(layer "In13.Cu")
		(net "GMI_CPU0_G0_CPU1_G2_TX_DN<11>")
	)
	(segment
		(start 348.62516 -231.848406)
		(end 348.588584 -231.869488)
		(width 0.1143)
		(layer "In13.Cu")
		(net "GMI_CPU0_G0_CPU1_G2_TX_DN<11>")
	)
	(segment
		(start 122.923808 -235.121704)
		(end 122.907552 -235.109766)
		(width 0.1143)
		(layer "In13.Cu")
		(net "GMI_CPU0_G0_CPU1_G2_TX_DN<11>")
	)
	(segment
		(start 158.062676 -190.542672)
		(end 158.377128 -190.284608)
		(width 0.14224)
		(layer "In13.Cu")
		(net "GMI_CPU0_G0_CPU1_G2_TX_DN<11>")
	)
	(segment
		(start 151.564086 -195.871592)
		(end 151.581866 -195.692776)
		(width 0.14224)
		(layer "In13.Cu")
		(net "GMI_CPU0_G0_CPU1_G2_TX_DN<11>")
	)
	(segment
		(start 348.627954 -231.201468)
		(end 348.627954 -231.201722)
		(width 0.1143)
		(layer "In13.Cu")
		(net "GMI_CPU0_G0_CPU1_G2_TX_DN<11>")
	)
	(segment
		(start 122.867928 -232.821734)
		(end 122.907298 -232.798874)
		(width 0.1143)
		(layer "In13.Cu")
		(net "GMI_CPU0_G0_CPU1_G2_TX_DN<11>")
	)
	(segment
		(start 122.861832 -232.82529)
		(end 122.862594 -232.824782)
		(width 0.1143)
		(layer "In13.Cu")
		(net "GMI_CPU0_G0_CPU1_G2_TX_DN<11>")
	)
	(segment
		(start 348.627954 -224.721674)
		(end 348.659704 -224.739962)
		(width 0.1143)
		(layer "In13.Cu")
		(net "GMI_CPU0_G0_CPU1_G2_TX_DN<11>")
	)
	(segment
		(start 348.627954 -233.46664)
		(end 348.625414 -233.468418)
		(width 0.1143)
		(layer "In13.Cu")
		(net "GMI_CPU0_G0_CPU1_G2_TX_DN<11>")
	)
	(segment
		(start 122.867928 -223.747076)
		(end 122.867166 -223.746568)
		(width 0.1143)
		(layer "In13.Cu")
		(net "GMI_CPU0_G0_CPU1_G2_TX_DN<11>")
	)
	(segment
		(start 348.62516 -231.199944)
		(end 348.627954 -231.201468)
		(width 0.1143)
		(layer "In13.Cu")
		(net "GMI_CPU0_G0_CPU1_G2_TX_DN<11>")
	)
	(segment
		(start 122.66041 -221.303342)
		(end 122.66041 -221.146116)
		(width 0.1143)
		(layer "In13.Cu")
		(net "GMI_CPU0_G0_CPU1_G2_TX_DN<11>")
	)
	(segment
		(start 156.74467 -191.459104)
		(end 157.058868 -191.201548)
		(width 0.14224)
		(layer "In13.Cu")
		(net "GMI_CPU0_G0_CPU1_G2_TX_DN<11>")
	)
	(segment
		(start 122.907552 -234.418886)
		(end 122.923808 -234.406948)
		(width 0.1143)
		(layer "In13.Cu")
		(net "GMI_CPU0_G0_CPU1_G2_TX_DN<11>")
	)
	(segment
		(start 122.866404 -227.962714)
		(end 122.90679 -227.939346)
		(width 0.1143)
		(layer "In13.Cu")
		(net "GMI_CPU0_G0_CPU1_G2_TX_DN<11>")
	)
	(segment
		(start 348.588838 -228.629464)
		(end 348.580202 -228.63556)
		(width 0.1143)
		(layer "In13.Cu")
		(net "GMI_CPU0_G0_CPU1_G2_TX_DN<11>")
	)
	(segment
		(start 122.903996 -238.347758)
		(end 122.867674 -238.32693)
		(width 0.1143)
		(layer "In13.Cu")
		(net "GMI_CPU0_G0_CPU1_G2_TX_DN<11>")
	)
	(segment
		(start 348.636082 -232.826052)
		(end 348.659958 -232.840022)
		(width 0.1143)
		(layer "In13.Cu")
		(net "GMI_CPU0_G0_CPU1_G2_TX_DN<11>")
	)
	(segment
		(start 348.628208 -223.101662)
		(end 348.659704 -223.11995)
		(width 0.1143)
		(layer "In13.Cu")
		(net "GMI_CPU0_G0_CPU1_G2_TX_DN<11>")
	)
	(segment
		(start 348.58833 -233.4895)
		(end 348.572074 -233.501438)
		(width 0.1143)
		(layer "In13.Cu")
		(net "GMI_CPU0_G0_CPU1_G2_TX_DN<11>")
	)
	(segment
		(start 348.629478 -226.342448)
		(end 348.63024 -226.342956)
		(width 0.1143)
		(layer "In13.Cu")
		(net "GMI_CPU0_G0_CPU1_G2_TX_DN<11>")
	)
	(segment
		(start 158.394908 -190.105792)
		(end 162.29838 -186.905138)
		(width 0.14224)
		(layer "In13.Cu")
		(net "GMI_CPU0_G0_CPU1_G2_TX_DN<11>")
	)
	(segment
		(start 157.058868 -191.201548)
		(end 157.237684 -191.219074)
		(width 0.14224)
		(layer "In13.Cu")
		(net "GMI_CPU0_G0_CPU1_G2_TX_DN<11>")
	)
	(segment
		(start 348.589092 -223.078802)
		(end 348.628208 -223.101662)
		(width 0.1143)
		(layer "In13.Cu")
		(net "GMI_CPU0_G0_CPU1_G2_TX_DN<11>")
	)
	(segment
		(start 162.812222 -186.657742)
		(end 162.831018 -186.468258)
		(width 0.14224)
		(layer "In13.Cu")
		(net "GMI_CPU0_G0_CPU1_G2_TX_DN<11>")
	)
	(segment
		(start 122.865896 -231.845612)
		(end 122.863356 -231.844342)
		(width 0.1143)
		(layer "In13.Cu")
		(net "GMI_CPU0_G0_CPU1_G2_TX_DN<11>")
	)
	(segment
		(start 122.863864 -227.964238)
		(end 122.864626 -227.96373)
		(width 0.1143)
		(layer "In13.Cu")
		(net "GMI_CPU0_G0_CPU1_G2_TX_DN<11>")
	)
	(segment
		(start 122.866404 -226.342702)
		(end 122.90679 -226.319334)
		(width 0.1143)
		(layer "In13.Cu")
		(net "GMI_CPU0_G0_CPU1_G2_TX_DN<11>")
	)
	(segment
		(start 122.863356 -226.98456)
		(end 122.836178 -226.968812)
		(width 0.1143)
		(layer "In13.Cu")
		(net "GMI_CPU0_G0_CPU1_G2_TX_DN<11>")
	)
	(segment
		(start 151.581866 -195.692776)
		(end 152.07107 -195.29171)
		(width 0.14224)
		(layer "In13.Cu")
		(net "GMI_CPU0_G0_CPU1_G2_TX_DN<11>")
	)
	(segment
		(start 348.631256 -230.224838)
		(end 348.627954 -230.226616)
		(width 0.1143)
		(layer "In13.Cu")
		(net "GMI_CPU0_G0_CPU1_G2_TX_DN<11>")
	)
	(segment
		(start 348.629986 -233.46537)
		(end 348.628716 -233.466132)
		(width 0.1143)
		(layer "In13.Cu")
		(net "GMI_CPU0_G0_CPU1_G2_TX_DN<11>")
	)
	(segment
		(start 348.659704 -226.968558)
		(end 348.632526 -226.984306)
		(width 0.1143)
		(layer "In13.Cu")
		(net "GMI_CPU0_G0_CPU1_G2_TX_DN<11>")
	)
	(segment
		(start 348.62516 -226.988624)
		(end 348.589092 -227.009452)
		(width 0.1143)
		(layer "In13.Cu")
		(net "GMI_CPU0_G0_CPU1_G2_TX_DN<11>")
	)
	(segment
		(start 122.835162 -229.601014)
		(end 122.867166 -229.582472)
		(width 0.1143)
		(layer "In13.Cu")
		(net "GMI_CPU0_G0_CPU1_G2_TX_DN<11>")
	)
	(segment
		(start 122.867928 -230.22687)
		(end 122.864626 -230.225092)
		(width 0.1143)
		(layer "In13.Cu")
		(net "GMI_CPU0_G0_CPU1_G2_TX_DN<11>")
	)
	(segment
		(start 348.628716 -228.60635)
		(end 348.627954 -228.606858)
		(width 0.1143)
		(layer "In13.Cu")
		(net "GMI_CPU0_G0_CPU1_G2_TX_DN<11>")
	)
	(segment
		(start 162.831018 -186.468258)
		(end 163.330636 -186.058556)
		(width 0.14224)
		(layer "In13.Cu")
		(net "GMI_CPU0_G0_CPU1_G2_TX_DN<11>")
	)
	(segment
		(start 124.659898 -216.777824)
		(end 145.36039 -199.804274)
		(width 0.14224)
		(layer "In13.Cu")
		(net "GMI_CPU0_G0_CPU1_G2_TX_DN<11>")
	)
	(segment
		(start 122.867928 -231.201976)
		(end 122.867928 -231.201722)
		(width 0.1143)
		(layer "In13.Cu")
		(net "GMI_CPU0_G0_CPU1_G2_TX_DN<11>")
	)
	(segment
		(start 348.682818 -232.858564)
		(end 348.683072 -232.858564)
		(width 0.1143)
		(layer "In13.Cu")
		(net "GMI_CPU0_G0_CPU1_G2_TX_DN<11>")
	)
	(segment
		(start 122.867166 -231.846374)
		(end 122.865896 -231.845612)
		(width 0.1143)
		(layer "In13.Cu")
		(net "GMI_CPU0_G0_CPU1_G2_TX_DN<11>")
	)
	(segment
		(start 157.552136 -190.961264)
		(end 157.569662 -190.782448)
		(width 0.14224)
		(layer "In13.Cu")
		(net "GMI_CPU0_G0_CPU1_G2_TX_DN<11>")
	)
	(segment
		(start 152.26411 -195.31076)
		(end 152.59431 -195.039996)
		(width 0.14224)
		(layer "In13.Cu")
		(net "GMI_CPU0_G0_CPU1_G2_TX_DN<11>")
	)
	(segment
		(start 122.90679 -226.319334)
		(end 122.925332 -226.306126)
		(width 0.1143)
		(layer "In13.Cu")
		(net "GMI_CPU0_G0_CPU1_G2_TX_DN<11>")
	)
	(segment
		(start 348.627954 -225.366834)
		(end 348.62516 -225.368612)
		(width 0.1143)
		(layer "In13.Cu")
		(net "GMI_CPU0_G0_CPU1_G2_TX_DN<11>")
	)
	(segment
		(start 122.863356 -223.744536)
		(end 122.836178 -223.728788)
		(width 0.1143)
		(layer "In13.Cu")
		(net "GMI_CPU0_G0_CPU1_G2_TX_DN<11>")
	)
	(segment
		(start 122.867166 -229.582472)
		(end 122.867928 -229.581964)
		(width 0.1143)
		(layer "In13.Cu")
		(net "GMI_CPU0_G0_CPU1_G2_TX_DN<11>")
	)
	(segment
		(start 156.727144 -191.63792)
		(end 156.74467 -191.459104)
		(width 0.14224)
		(layer "In13.Cu")
		(net "GMI_CPU0_G0_CPU1_G2_TX_DN<11>")
	)
	(segment
		(start 348.632526 -235.084112)
		(end 348.629986 -235.085382)
		(width 0.1143)
		(layer "In13.Cu")
		(net "GMI_CPU0_G0_CPU1_G2_TX_DN<11>")
	)
	(segment
		(start 122.867928 -229.581456)
		(end 122.908822 -229.55758)
		(width 0.1143)
		(layer "In13.Cu")
		(net "GMI_CPU0_G0_CPU1_G2_TX_DN<11>")
	)
	(segment
		(start 122.899932 -230.245412)
		(end 122.871484 -230.228902)
		(width 0.1143)
		(layer "In13.Cu")
		(net "GMI_CPU0_G0_CPU1_G2_TX_DN<11>")
	)
	(segment
		(start 122.860562 -226.346004)
		(end 122.861324 -226.345496)
		(width 0.1143)
		(layer "In13.Cu")
		(net "GMI_CPU0_G0_CPU1_G2_TX_DN<11>")
	)
	(segment
		(start 348.588584 -231.869488)
		(end 348.57309 -231.88041)
		(width 0.1143)
		(layer "In13.Cu")
		(net "GMI_CPU0_G0_CPU1_G2_TX_DN<11>")
	)
	(segment
		(start 348.682056 -232.858056)
		(end 348.682818 -232.858564)
		(width 0.1143)
		(layer "In13.Cu")
		(net "GMI_CPU0_G0_CPU1_G2_TX_DN<11>")
	)
	(segment
		(start 122.90679 -227.939346)
		(end 122.934222 -227.919788)
		(width 0.1143)
		(layer "In13.Cu")
		(net "GMI_CPU0_G0_CPU1_G2_TX_DN<11>")
	)
	(segment
		(start 348.45371 -239.636808)
		(end 348.44101 -239.624108)
		(width 0.1143)
		(layer "In13.Cu")
		(net "GMI_CPU0_G0_CPU1_G2_TX_DN<11>")
	)
	(segment
		(start 122.862848 -227.964746)
		(end 122.863864 -227.964238)
		(width 0.1143)
		(layer "In13.Cu")
		(net "GMI_CPU0_G0_CPU1_G2_TX_DN<11>")
	)
	(segment
		(start 348.627954 -228.606858)
		(end 348.62516 -228.608636)
		(width 0.1143)
		(layer "In13.Cu")
		(net "GMI_CPU0_G0_CPU1_G2_TX_DN<11>")
	)
	(segment
		(start 348.632272 -232.82402)
		(end 348.633288 -232.824528)
		(width 0.1143)
		(layer "In13.Cu")
		(net "GMI_CPU0_G0_CPU1_G2_TX_DN<11>")
	)
	(segment
		(start 348.626938 -230.227124)
		(end 348.625414 -230.22814)
		(width 0.1143)
		(layer "In13.Cu")
		(net "GMI_CPU0_G0_CPU1_G2_TX_DN<11>")
	)
	(arc
		(start 348.664276 -233.444796)
		(mid 348.661617 -233.446712)
		(end 348.658942 -233.448606)
		(width 0.1143)
		(layer "In13.Cu")
		(net "GMI_CPU0_G0_CPU1_G2_TX_DN<11>")
	)
	(arc
		(start 122.835924 -236.68863)
		(mid 122.681776 -236.384338)
		(end 122.835924 -236.080046)
		(width 0.1143)
		(layer "In13.Cu")
		(net "GMI_CPU0_G0_CPU1_G2_TX_DN<11>")
	)
	(arc
		(start 348.815914 -229.904036)
		(mid 348.766387 -230.089068)
		(end 348.631256 -230.224838)
		(width 0.1143)
		(layer "In13.Cu")
		(net "GMI_CPU0_G0_CPU1_G2_TX_DN<11>")
	)
	(arc
		(start 122.90679 -237.65891)
		(mid 123.150117 -237.194344)
		(end 122.90679 -236.729778)
		(width 0.1143)
		(layer "In13.Cu")
		(net "GMI_CPU0_G0_CPU1_G2_TX_DN<11>")
	)
	(arc
		(start 122.923808 -236.02696)
		(mid 123.155558 -235.574332)
		(end 122.923808 -235.121704)
		(width 0.1143)
		(layer "In13.Cu")
		(net "GMI_CPU0_G0_CPU1_G2_TX_DN<11>")
	)
	(arc
		(start 122.81154 -233.428794)
		(mid 122.674717 -233.144493)
		(end 122.811286 -232.860088)
		(width 0.1143)
		(layer "In13.Cu")
		(net "GMI_CPU0_G0_CPU1_G2_TX_DN<11>")
	)
	(arc
		(start 348.659704 -227.979986)
		(mid 348.815632 -228.284278)
		(end 348.659704 -228.58857)
		(width 0.1143)
		(layer "In13.Cu")
		(net "GMI_CPU0_G0_CPU1_G2_TX_DN<11>")
	)
	(arc
		(start 122.836178 -226.968812)
		(mid 122.68025 -226.66452)
		(end 122.836178 -226.360228)
		(width 0.1143)
		(layer "In13.Cu")
		(net "GMI_CPU0_G0_CPU1_G2_TX_DN<11>")
	)
	(arc
		(start 122.91568 -230.25608)
		(mid 122.908604 -230.251201)
		(end 122.901456 -230.246428)
		(width 0.1143)
		(layer "In13.Cu")
		(net "GMI_CPU0_G0_CPU1_G2_TX_DN<11>")
	)
	(arc
		(start 348.589092 -236.729524)
		(mid 348.345765 -237.19409)
		(end 348.589092 -237.658656)
		(width 0.1143)
		(layer "In13.Cu")
		(net "GMI_CPU0_G0_CPU1_G2_TX_DN<11>")
	)
	(arc
		(start 122.836178 -228.588824)
		(mid 122.68025 -228.284532)
		(end 122.836178 -227.98024)
		(width 0.1143)
		(layer "In13.Cu")
		(net "GMI_CPU0_G0_CPU1_G2_TX_DN<11>")
	)
	(arc
		(start 122.908822 -229.55758)
		(mid 123.086187 -229.355613)
		(end 123.150122 -229.094538)
		(width 0.1143)
		(layer "In13.Cu")
		(net "GMI_CPU0_G0_CPU1_G2_TX_DN<11>")
	)
	(arc
		(start 122.918474 -223.778064)
		(mid 122.911401 -223.773055)
		(end 122.90425 -223.768158)
		(width 0.1143)
		(layer "In13.Cu")
		(net "GMI_CPU0_G0_CPU1_G2_TX_DN<11>")
	)
	(arc
		(start 348.572074 -233.501438)
		(mid 348.340324 -233.954066)
		(end 348.572074 -234.406694)
		(width 0.1143)
		(layer "In13.Cu")
		(net "GMI_CPU0_G0_CPU1_G2_TX_DN<11>")
	)
	(arc
		(start 348.577408 -223.77781)
		(mid 348.349924 -224.234248)
		(end 348.577408 -224.690686)
		(width 0.1143)
		(layer "In13.Cu")
		(net "GMI_CPU0_G0_CPU1_G2_TX_DN<11>")
	)
	(arc
		(start 122.918474 -224.69094)
		(mid 123.145958 -224.234502)
		(end 122.918474 -223.778064)
		(width 0.1143)
		(layer "In13.Cu")
		(net "GMI_CPU0_G0_CPU1_G2_TX_DN<11>")
	)
	(arc
		(start 122.925332 -226.306126)
		(mid 123.156997 -225.854514)
		(end 122.925332 -225.402902)
		(width 0.1143)
		(layer "In13.Cu")
		(net "GMI_CPU0_G0_CPU1_G2_TX_DN<11>")
	)
	(arc
		(start 122.923808 -234.406948)
		(mid 123.155558 -233.95432)
		(end 122.923808 -233.501692)
		(width 0.1143)
		(layer "In13.Cu")
		(net "GMI_CPU0_G0_CPU1_G2_TX_DN<11>")
	)
	(arc
		(start 348.34576 -229.094284)
		(mid 348.409706 -229.355353)
		(end 348.58706 -229.557326)
		(width 0.1143)
		(layer "In13.Cu")
		(net "GMI_CPU0_G0_CPU1_G2_TX_DN<11>")
	)
	(arc
		(start 122.81535 -235.051854)
		(mid 122.6771 -234.764505)
		(end 122.815096 -234.477052)
		(width 0.1143)
		(layer "In13.Cu")
		(net "GMI_CPU0_G0_CPU1_G2_TX_DN<11>")
	)
	(arc
		(start 348.577408 -224.690686)
		(mid 348.584482 -224.695693)
		(end 348.591632 -224.700592)
		(width 0.1143)
		(layer "In13.Cu")
		(net "GMI_CPU0_G0_CPU1_G2_TX_DN<11>")
	)
	(arc
		(start 122.836178 -223.728788)
		(mid 122.68025 -223.424496)
		(end 122.836178 -223.120204)
		(width 0.1143)
		(layer "In13.Cu")
		(net "GMI_CPU0_G0_CPU1_G2_TX_DN<11>")
	)
	(arc
		(start 348.683072 -232.858564)
		(mid 348.820212 -233.144238)
		(end 348.682818 -233.42981)
		(width 0.1143)
		(layer "In13.Cu")
		(net "GMI_CPU0_G0_CPU1_G2_TX_DN<11>")
	)
	(arc
		(start 348.635828 -239.305846)
		(mid 348.74757 -239.411455)
		(end 348.807024 -239.553242)
		(width 0.1143)
		(layer "In13.Cu")
		(net "GMI_CPU0_G0_CPU1_G2_TX_DN<11>")
	)
	(arc
		(start 123.150122 -229.09403)
		(mid 123.088172 -228.836636)
		(end 122.91568 -228.635814)
		(width 0.1143)
		(layer "In13.Cu")
		(net "GMI_CPU0_G0_CPU1_G2_TX_DN<11>")
	)
	(arc
		(start 348.581218 -238.355124)
		(mid 348.346029 -238.819387)
		(end 348.589854 -239.279176)
		(width 0.1143)
		(layer "In13.Cu")
		(net "GMI_CPU0_G0_CPU1_G2_TX_DN<11>")
	)
	(arc
		(start 348.580202 -230.255826)
		(mid 348.408184 -230.456628)
		(end 348.34576 -230.713534)
		(width 0.1143)
		(layer "In13.Cu")
		(net "GMI_CPU0_G0_CPU1_G2_TX_DN<11>")
	)
	(arc
		(start 122.835924 -222.108776)
		(mid 122.721248 -221.975442)
		(end 122.679968 -221.804484)
		(width 0.1143)
		(layer "In13.Cu")
		(net "GMI_CPU0_G0_CPU1_G2_TX_DN<11>")
	)
	(arc
		(start 348.56166 -227.02901)
		(mid 348.333248 -227.474272)
		(end 348.56166 -227.919534)
		(width 0.1143)
		(layer "In13.Cu")
		(net "GMI_CPU0_G0_CPU1_G2_TX_DN<11>")
	)
	(arc
		(start 348.589092 -238.349536)
		(mid 348.585143 -238.352313)
		(end 348.581218 -238.355124)
		(width 0.1143)
		(layer "In13.Cu")
		(net "GMI_CPU0_G0_CPU1_G2_TX_DN<11>")
	)
	(arc
		(start 122.922792 -232.787952)
		(mid 123.15505 -232.334308)
		(end 122.922792 -231.880664)
		(width 0.1143)
		(layer "In13.Cu")
		(net "GMI_CPU0_G0_CPU1_G2_TX_DN<11>")
	)
	(arc
		(start 122.836178 -231.828594)
		(mid 122.680041 -231.525469)
		(end 122.8344 -231.221534)
		(width 0.1143)
		(layer "In13.Cu")
		(net "GMI_CPU0_G0_CPU1_G2_TX_DN<11>")
	)
	(arc
		(start 348.572074 -235.12145)
		(mid 348.340324 -235.574078)
		(end 348.572074 -236.026706)
		(width 0.1143)
		(layer "In13.Cu")
		(net "GMI_CPU0_G0_CPU1_G2_TX_DN<11>")
	)
	(arc
		(start 122.914664 -238.355378)
		(mid 122.910739 -238.352567)
		(end 122.90679 -238.34979)
		(width 0.1143)
		(layer "In13.Cu")
		(net "GMI_CPU0_G0_CPU1_G2_TX_DN<11>")
	)
	(arc
		(start 348.580202 -228.63556)
		(mid 348.407757 -228.836406)
		(end 348.34576 -229.093776)
		(width 0.1143)
		(layer "In13.Cu")
		(net "GMI_CPU0_G0_CPU1_G2_TX_DN<11>")
	)
	(arc
		(start 348.659958 -236.079792)
		(mid 348.814106 -236.384084)
		(end 348.659958 -236.688376)
		(width 0.1143)
		(layer "In13.Cu")
		(net "GMI_CPU0_G0_CPU1_G2_TX_DN<11>")
	)
	(arc
		(start 348.34576 -230.713534)
		(mid 348.419999 -230.994331)
		(end 348.62516 -231.199944)
		(width 0.1143)
		(layer "In13.Cu")
		(net "GMI_CPU0_G0_CPU1_G2_TX_DN<11>")
	)
	(arc
		(start 122.836178 -225.3488)
		(mid 122.68025 -225.044508)
		(end 122.836178 -224.740216)
		(width 0.1143)
		(layer "In13.Cu")
		(net "GMI_CPU0_G0_CPU1_G2_TX_DN<11>")
	)
	(arc
		(start 348.594426 -230.246174)
		(mid 348.587277 -230.250945)
		(end 348.580202 -230.255826)
		(width 0.1143)
		(layer "In13.Cu")
		(net "GMI_CPU0_G0_CPU1_G2_TX_DN<11>")
	)
	(arc
		(start 348.57055 -225.402648)
		(mid 348.338885 -225.85426)
		(end 348.57055 -226.305872)
		(width 0.1143)
		(layer "In13.Cu")
		(net "GMI_CPU0_G0_CPU1_G2_TX_DN<11>")
	)
	(arc
		(start 122.934222 -227.919788)
		(mid 123.162634 -227.474526)
		(end 122.934222 -227.029264)
		(width 0.1143)
		(layer "In13.Cu")
		(net "GMI_CPU0_G0_CPU1_G2_TX_DN<11>")
	)
	(arc
		(start 348.57309 -231.88041)
		(mid 348.340832 -232.334054)
		(end 348.57309 -232.787698)
		(width 0.1143)
		(layer "In13.Cu")
		(net "GMI_CPU0_G0_CPU1_G2_TX_DN<11>")
	)
	(arc
		(start 348.589092 -222.14967)
		(mid 348.345765 -222.614236)
		(end 348.589092 -223.078802)
		(width 0.1143)
		(layer "In13.Cu")
		(net "GMI_CPU0_G0_CPU1_G2_TX_DN<11>")
	)
	(arc
		(start 348.659704 -226.359974)
		(mid 348.815632 -226.664266)
		(end 348.659704 -226.968558)
		(width 0.1143)
		(layer "In13.Cu")
		(net "GMI_CPU0_G0_CPU1_G2_TX_DN<11>")
	)
	(arc
		(start 122.906028 -239.27943)
		(mid 123.149857 -238.819641)
		(end 122.914664 -238.355378)
		(width 0.1143)
		(layer "In13.Cu")
		(net "GMI_CPU0_G0_CPU1_G2_TX_DN<11>")
	)
	(arc
		(start 348.661482 -229.601268)
		(mid 348.775054 -229.734114)
		(end 348.815914 -229.904036)
		(width 0.1143)
		(layer "In13.Cu")
		(net "GMI_CPU0_G0_CPU1_G2_TX_DN<11>")
	)
	(arc
		(start 122.870722 -231.200198)
		(mid 123.075939 -230.994617)
		(end 123.150122 -230.713788)
		(width 0.1143)
		(layer "In13.Cu")
		(net "GMI_CPU0_G0_CPU1_G2_TX_DN<11>")
	)
	(arc
		(start 348.659704 -224.739962)
		(mid 348.815632 -225.044254)
		(end 348.659704 -225.348546)
		(width 0.1143)
		(layer "In13.Cu")
		(net "GMI_CPU0_G0_CPU1_G2_TX_DN<11>")
	)
	(arc
		(start 122.90679 -223.079056)
		(mid 123.150117 -222.61449)
		(end 122.90679 -222.149924)
		(width 0.1143)
		(layer "In13.Cu")
		(net "GMI_CPU0_G0_CPU1_G2_TX_DN<11>")
	)
	(arc
		(start 122.688858 -239.553496)
		(mid 122.748328 -239.41172)
		(end 122.860054 -239.3061)
		(width 0.1143)
		(layer "In13.Cu")
		(net "GMI_CPU0_G0_CPU1_G2_TX_DN<11>")
	)
	(arc
		(start 123.150122 -230.713788)
		(mid 123.087593 -230.456936)
		(end 122.91568 -230.25608)
		(width 0.1143)
		(layer "In13.Cu")
		(net "GMI_CPU0_G0_CPU1_G2_TX_DN<11>")
	)
	(arc
		(start 348.659704 -223.11995)
		(mid 348.815632 -223.424242)
		(end 348.659704 -223.728534)
		(width 0.1143)
		(layer "In13.Cu")
		(net "GMI_CPU0_G0_CPU1_G2_TX_DN<11>")
	)
	(arc
		(start 122.864626 -230.225092)
		(mid 122.729459 -230.089342)
		(end 122.679968 -229.90429)
		(width 0.1143)
		(layer "In13.Cu")
		(net "GMI_CPU0_G0_CPU1_G2_TX_DN<11>")
	)
	(arc
		(start 348.591632 -223.767904)
		(mid 348.584483 -223.772804)
		(end 348.577408 -223.77781)
		(width 0.1143)
		(layer "In13.Cu")
		(net "GMI_CPU0_G0_CPU1_G2_TX_DN<11>")
	)
	(arc
		(start 122.90425 -224.700846)
		(mid 122.9114 -224.695948)
		(end 122.918474 -224.69094)
		(width 0.1143)
		(layer "In13.Cu")
		(net "GMI_CPU0_G0_CPU1_G2_TX_DN<11>")
	)
	(arc
		(start 122.835924 -238.308642)
		(mid 122.681256 -238.00435)
		(end 122.835924 -237.700058)
		(width 0.1143)
		(layer "In13.Cu")
		(net "GMI_CPU0_G0_CPU1_G2_TX_DN<11>")
	)
	(arc
		(start 348.679262 -234.475528)
		(mid 348.817829 -234.764251)
		(end 348.679008 -235.05287)
		(width 0.1143)
		(layer "In13.Cu")
		(net "GMI_CPU0_G0_CPU1_G2_TX_DN<11>")
	)
	(arc
		(start 122.679968 -229.90429)
		(mid 122.720868 -229.734389)
		(end 122.8344 -229.601522)
		(width 0.1143)
		(layer "In13.Cu")
		(net "GMI_CPU0_G0_CPU1_G2_TX_DN<11>")
	)
	(arc
		(start 348.661482 -231.22128)
		(mid 348.815648 -231.525215)
		(end 348.659704 -231.82834)
		(width 0.1143)
		(layer "In13.Cu")
		(net "GMI_CPU0_G0_CPU1_G2_TX_DN<11>")
	)
	(arc
		(start 348.659958 -237.699804)
		(mid 348.814626 -238.004096)
		(end 348.659958 -238.308388)
		(width 0.1143)
		(layer "In13.Cu")
		(net "GMI_CPU0_G0_CPU1_G2_TX_DN<11>")
	)
	(arc
		(start 348.815914 -221.868746)
		(mid 348.78127 -221.998172)
		(end 348.686628 -222.093028)
		(width 0.1143)
		(layer "In13.Cu")
		(net "GMI_CPU0_G0_CPU1_G2_TX_DN<11>")
	)
	(segment
		(start 122.587766 -243.130324)
		(end 123.054618 -242.864386)
		(width 0.12954)
		(layer "F.Cu")
		(net "GMI_CPU0_G0_CPU1_G2_TX_DN<10>")
	)
	(segment
		(start 348.907862 -243.13007)
		(end 348.44101 -242.864132)
		(width 0.12954)
		(layer "F.Cu")
		(net "GMI_CPU0_G0_CPU1_G2_TX_DN<10>")
	)
	(segment
		(start 121.950734 -230.240332)
		(end 121.955306 -230.242872)
		(width 0.1143)
		(layer "In13.Cu")
		(net "GMI_CPU0_G0_CPU1_G2_TX_DN<10>")
	)
	(segment
		(start 349.568008 -226.341686)
		(end 349.528892 -226.318826)
		(width 0.1143)
		(layer "In13.Cu")
		(net "GMI_CPU0_G0_CPU1_G2_TX_DN<10>")
	)
	(segment
		(start 349.589344 -228.594412)
		(end 349.589852 -228.594412)
		(width 0.1143)
		(layer "In13.Cu")
		(net "GMI_CPU0_G0_CPU1_G2_TX_DN<10>")
	)
	(segment
		(start 349.568008 -236.061504)
		(end 349.528892 -236.038644)
		(width 0.1143)
		(layer "In13.Cu")
		(net "GMI_CPU0_G0_CPU1_G2_TX_DN<10>")
	)
	(segment
		(start 156.24175 -190.648082)
		(end 155.917392 -190.91402)
		(width 0.14224)
		(layer "In13.Cu")
		(net "GMI_CPU0_G0_CPU1_G2_TX_DN<10>")
	)
	(segment
		(start 123.974098 -216.074498)
		(end 121.76125 -219.878148)
		(width 0.14224)
		(layer "In13.Cu")
		(net "GMI_CPU0_G0_CPU1_G2_TX_DN<10>")
	)
	(segment
		(start 121.96699 -224.699068)
		(end 121.927874 -224.721928)
		(width 0.1143)
		(layer "In13.Cu")
		(net "GMI_CPU0_G0_CPU1_G2_TX_DN<10>")
	)
	(segment
		(start 349.56877 -231.846374)
		(end 349.569532 -231.845866)
		(width 0.1143)
		(layer "In13.Cu")
		(net "GMI_CPU0_G0_CPU1_G2_TX_DN<10>")
	)
	(segment
		(start 162.591242 -185.275474)
		(end 157.957012 -189.074552)
		(width 0.14224)
		(layer "In13.Cu")
		(net "GMI_CPU0_G0_CPU1_G2_TX_DN<10>")
	)
	(segment
		(start 349.612712 -232.848912)
		(end 349.599758 -232.839768)
		(width 0.1143)
		(layer "In13.Cu")
		(net "GMI_CPU0_G0_CPU1_G2_TX_DN<10>")
	)
	(segment
		(start 153.647648 -192.78473)
		(end 153.317448 -193.055494)
		(width 0.14224)
		(layer "In13.Cu")
		(net "GMI_CPU0_G0_CPU1_G2_TX_DN<10>")
	)
	(segment
		(start 152.775412 -193.49974)
		(end 152.445212 -193.770504)
		(width 0.14224)
		(layer "In13.Cu")
		(net "GMI_CPU0_G0_CPU1_G2_TX_DN<10>")
	)
	(segment
		(start 349.568008 -237.681516)
		(end 349.528892 -237.658656)
		(width 0.1143)
		(layer "In13.Cu")
		(net "GMI_CPU0_G0_CPU1_G2_TX_DN<10>")
	)
	(segment
		(start 349.599758 -226.359974)
		(end 349.568008 -226.341686)
		(width 0.1143)
		(layer "In13.Cu")
		(net "GMI_CPU0_G0_CPU1_G2_TX_DN<10>")
	)
	(segment
		(start 156.259784 -190.465964)
		(end 156.24175 -190.648082)
		(width 0.14224)
		(layer "In13.Cu")
		(net "GMI_CPU0_G0_CPU1_G2_TX_DN<10>")
	)
	(segment
		(start 121.906538 -227.974398)
		(end 121.906284 -227.974398)
		(width 0.1143)
		(layer "In13.Cu")
		(net "GMI_CPU0_G0_CPU1_G2_TX_DN<10>")
	)
	(segment
		(start 349.54718 -223.08947)
		(end 349.546926 -223.08947)
		(width 0.1143)
		(layer "In13.Cu")
		(net "GMI_CPU0_G0_CPU1_G2_TX_DN<10>")
	)
	(segment
		(start 153.666698 -192.59169)
		(end 153.647648 -192.78473)
		(width 0.14224)
		(layer "In13.Cu")
		(net "GMI_CPU0_G0_CPU1_G2_TX_DN<10>")
	)
	(segment
		(start 349.594932 -230.211122)
		(end 349.595948 -230.210106)
		(width 0.1143)
		(layer "In13.Cu")
		(net "GMI_CPU0_G0_CPU1_G2_TX_DN<10>")
	)
	(segment
		(start 349.540576 -230.242618)
		(end 349.545148 -230.240078)
		(width 0.1143)
		(layer "In13.Cu")
		(net "GMI_CPU0_G0_CPU1_G2_TX_DN<10>")
	)
	(segment
		(start 121.927874 -241.566954)
		(end 121.96699 -241.589814)
		(width 0.1143)
		(layer "In13.Cu")
		(net "GMI_CPU0_G0_CPU1_G2_TX_DN<10>")
	)
	(segment
		(start 349.75546 -221.80423)
		(end 349.75546 -221.248986)
		(width 0.1143)
		(layer "In13.Cu")
		(net "GMI_CPU0_G0_CPU1_G2_TX_DN<10>")
	)
	(segment
		(start 349.529654 -223.769174)
		(end 349.575882 -223.74225)
		(width 0.1143)
		(layer "In13.Cu")
		(net "GMI_CPU0_G0_CPU1_G2_TX_DN<10>")
	)
	(segment
		(start 121.948702 -234.429554)
		(end 121.927366 -234.442)
		(width 0.1143)
		(layer "In13.Cu")
		(net "GMI_CPU0_G0_CPU1_G2_TX_DN<10>")
	)
	(segment
		(start 349.551244 -230.236522)
		(end 349.552006 -230.236014)
		(width 0.1143)
		(layer "In13.Cu")
		(net "GMI_CPU0_G0_CPU1_G2_TX_DN<10>")
	)
	(segment
		(start 145.905982 -198.495158)
		(end 145.905728 -198.495158)
		(width 0.14224)
		(layer "In13.Cu")
		(net "GMI_CPU0_G0_CPU1_G2_TX_DN<10>")
	)
	(segment
		(start 121.927112 -231.846628)
		(end 121.966228 -231.869234)
		(width 0.1143)
		(layer "In13.Cu")
		(net "GMI_CPU0_G0_CPU1_G2_TX_DN<10>")
	)
	(segment
		(start 349.568008 -241.5667)
		(end 349.599758 -241.548412)
		(width 0.1143)
		(layer "In13.Cu")
		(net "GMI_CPU0_G0_CPU1_G2_TX_DN<10>")
	)
	(segment
		(start 349.599758 -237.699804)
		(end 349.568008 -237.681516)
		(width 0.1143)
		(layer "In13.Cu")
		(net "GMI_CPU0_G0_CPU1_G2_TX_DN<10>")
	)
	(segment
		(start 349.568516 -223.101916)
		(end 349.54718 -223.08947)
		(width 0.1143)
		(layer "In13.Cu")
		(net "GMI_CPU0_G0_CPU1_G2_TX_DN<10>")
	)
	(segment
		(start 157.432502 -189.504574)
		(end 157.108398 -189.770258)
		(width 0.14224)
		(layer "In13.Cu")
		(net "GMI_CPU0_G0_CPU1_G2_TX_DN<10>")
	)
	(segment
		(start 121.948702 -223.089724)
		(end 121.927366 -223.10217)
		(width 0.1143)
		(layer "In13.Cu")
		(net "GMI_CPU0_G0_CPU1_G2_TX_DN<10>")
	)
	(segment
		(start 121.76125 -221.100396)
		(end 121.71553 -221.146116)
		(width 0.1143)
		(layer "In13.Cu")
		(net "GMI_CPU0_G0_CPU1_G2_TX_DN<10>")
	)
	(segment
		(start 121.927874 -239.301782)
		(end 121.896124 -239.32007)
		(width 0.1143)
		(layer "In13.Cu")
		(net "GMI_CPU0_G0_CPU1_G2_TX_DN<10>")
	)
	(segment
		(start 154.189684 -192.340484)
		(end 153.996644 -192.32118)
		(width 0.14224)
		(layer "In13.Cu")
		(net "GMI_CPU0_G0_CPU1_G2_TX_DN<10>")
	)
	(segment
		(start 121.933208 -235.089954)
		(end 121.934224 -235.090462)
		(width 0.1143)
		(layer "In13.Cu")
		(net "GMI_CPU0_G0_CPU1_G2_TX_DN<10>")
	)
	(segment
		(start 349.546926 -223.08947)
		(end 349.528892 -223.078802)
		(width 0.1143)
		(layer "In13.Cu")
		(net "GMI_CPU0_G0_CPU1_G2_TX_DN<10>")
	)
	(segment
		(start 349.589344 -227.974144)
		(end 349.588582 -227.973636)
		(width 0.1143)
		(layer "In13.Cu")
		(net "GMI_CPU0_G0_CPU1_G2_TX_DN<10>")
	)
	(segment
		(start 349.599758 -236.688376)
		(end 349.612712 -236.679232)
		(width 0.1143)
		(layer "In13.Cu")
		(net "GMI_CPU0_G0_CPU1_G2_TX_DN<10>")
	)
	(segment
		(start 121.76125 -221.071948)
		(end 121.76125 -221.100396)
		(width 0.1143)
		(layer "In13.Cu")
		(net "GMI_CPU0_G0_CPU1_G2_TX_DN<10>")
	)
	(segment
		(start 349.058992 -242.399566)
		(end 349.128588 -242.358926)
		(width 0.1143)
		(layer "In13.Cu")
		(net "GMI_CPU0_G0_CPU1_G2_TX_DN<10>")
	)
	(segment
		(start 122.367294 -242.35918)
		(end 122.397774 -242.37696)
		(width 0.1143)
		(layer "In13.Cu")
		(net "GMI_CPU0_G0_CPU1_G2_TX_DN<10>")
	)
	(segment
		(start 121.877582 -225.335338)
		(end 121.896124 -225.3488)
		(width 0.1143)
		(layer "In13.Cu")
		(net "GMI_CPU0_G0_CPU1_G2_TX_DN<10>")
	)
	(segment
		(start 349.734632 -221.100142)
		(end 349.734632 -221.093538)
		(width 0.1143)
		(layer "In13.Cu")
		(net "GMI_CPU0_G0_CPU1_G2_TX_DN<10>")
	)
	(segment
		(start 121.96699 -234.418886)
		(end 121.948956 -234.429554)
		(width 0.1143)
		(layer "In13.Cu")
		(net "GMI_CPU0_G0_CPU1_G2_TX_DN<10>")
	)
	(segment
		(start 121.934224 -235.090462)
		(end 121.966228 -235.109258)
		(width 0.1143)
		(layer "In13.Cu")
		(net "GMI_CPU0_G0_CPU1_G2_TX_DN<10>")
	)
	(segment
		(start 121.896124 -239.928654)
		(end 121.927874 -239.946942)
		(width 0.1143)
		(layer "In13.Cu")
		(net "GMI_CPU0_G0_CPU1_G2_TX_DN<10>")
	)
	(segment
		(start 121.927874 -226.34194)
		(end 121.896124 -226.360228)
		(width 0.1143)
		(layer "In13.Cu")
		(net "GMI_CPU0_G0_CPU1_G2_TX_DN<10>")
	)
	(segment
		(start 122.75693 -242.864386)
		(end 123.054618 -242.864386)
		(width 0.1143)
		(layer "In13.Cu")
		(net "GMI_CPU0_G0_CPU1_G2_TX_DN<10>")
	)
	(segment
		(start 121.896124 -233.448606)
		(end 121.96699 -233.489754)
		(width 0.1143)
		(layer "In13.Cu")
		(net "GMI_CPU0_G0_CPU1_G2_TX_DN<10>")
	)
	(segment
		(start 157.957012 -189.074552)
		(end 157.938978 -189.25667)
		(width 0.14224)
		(layer "In13.Cu")
		(net "GMI_CPU0_G0_CPU1_G2_TX_DN<10>")
	)
	(segment
		(start 349.588582 -227.973636)
		(end 349.528892 -227.938838)
		(width 0.1143)
		(layer "In13.Cu")
		(net "GMI_CPU0_G0_CPU1_G2_TX_DN<10>")
	)
	(segment
		(start 121.9073 -227.97389)
		(end 121.906538 -227.974398)
		(width 0.1143)
		(layer "In13.Cu")
		(net "GMI_CPU0_G0_CPU1_G2_TX_DN<10>")
	)
	(segment
		(start 349.565214 -229.579932)
		(end 349.528892 -229.55885)
		(width 0.1143)
		(layer "In13.Cu")
		(net "GMI_CPU0_G0_CPU1_G2_TX_DN<10>")
	)
	(segment
		(start 349.574866 -231.205278)
		(end 349.53448 -231.181656)
		(width 0.1143)
		(layer "In13.Cu")
		(net "GMI_CPU0_G0_CPU1_G2_TX_DN<10>")
	)
	(segment
		(start 155.917392 -190.91402)
		(end 155.735274 -190.895986)
		(width 0.14224)
		(layer "In13.Cu")
		(net "GMI_CPU0_G0_CPU1_G2_TX_DN<10>")
	)
	(segment
		(start 349.547434 -230.238554)
		(end 349.549466 -230.237538)
		(width 0.1143)
		(layer "In13.Cu")
		(net "GMI_CPU0_G0_CPU1_G2_TX_DN<10>")
	)
	(segment
		(start 151.903176 -194.21475)
		(end 151.572976 -194.485514)
		(width 0.14224)
		(layer "In13.Cu")
		(net "GMI_CPU0_G0_CPU1_G2_TX_DN<10>")
	)
	(segment
		(start 154.86888 -191.60617)
		(end 154.538934 -191.87668)
		(width 0.14224)
		(layer "In13.Cu")
		(net "GMI_CPU0_G0_CPU1_G2_TX_DN<10>")
	)
	(segment
		(start 349.53448 -231.181656)
		(end 349.528892 -231.178862)
		(width 0.1143)
		(layer "In13.Cu")
		(net "GMI_CPU0_G0_CPU1_G2_TX_DN<10>")
	)
	(segment
		(start 121.858532 -230.173022)
		(end 121.89841 -230.209852)
		(width 0.1143)
		(layer "In13.Cu")
		(net "GMI_CPU0_G0_CPU1_G2_TX_DN<10>")
	)
	(segment
		(start 349.6183 -224.753424)
		(end 349.599758 -224.739962)
		(width 0.1143)
		(layer "In13.Cu")
		(net "GMI_CPU0_G0_CPU1_G2_TX_DN<10>")
	)
	(segment
		(start 349.568008 -239.946688)
		(end 349.599758 -239.9284)
		(width 0.1143)
		(layer "In13.Cu")
		(net "GMI_CPU0_G0_CPU1_G2_TX_DN<10>")
	)
	(segment
		(start 153.124408 -193.03619)
		(end 152.794462 -193.3067)
		(width 0.14224)
		(layer "In13.Cu")
		(net "GMI_CPU0_G0_CPU1_G2_TX_DN<10>")
	)
	(segment
		(start 349.599758 -232.839768)
		(end 349.568008 -232.82148)
		(width 0.1143)
		(layer "In13.Cu")
		(net "GMI_CPU0_G0_CPU1_G2_TX_DN<10>")
	)
	(segment
		(start 121.927874 -224.721928)
		(end 121.896124 -224.740216)
		(width 0.1143)
		(layer "In13.Cu")
		(net "GMI_CPU0_G0_CPU1_G2_TX_DN<10>")
	)
	(segment
		(start 155.735274 -190.895986)
		(end 155.41117 -191.16167)
		(width 0.14224)
		(layer "In13.Cu")
		(net "GMI_CPU0_G0_CPU1_G2_TX_DN<10>")
	)
	(segment
		(start 349.561658 -235.090208)
		(end 349.562674 -235.0897)
		(width 0.1143)
		(layer "In13.Cu")
		(net "GMI_CPU0_G0_CPU1_G2_TX_DN<10>")
	)
	(segment
		(start 349.563436 -235.089192)
		(end 349.575882 -235.08208)
		(width 0.1143)
		(layer "In13.Cu")
		(net "GMI_CPU0_G0_CPU1_G2_TX_DN<10>")
	)
	(segment
		(start 121.96699 -229.559104)
		(end 121.894346 -229.601522)
		(width 0.1143)
		(layer "In13.Cu")
		(net "GMI_CPU0_G0_CPU1_G2_TX_DN<10>")
	)
	(segment
		(start 349.529654 -231.86898)
		(end 349.56877 -231.846374)
		(width 0.1143)
		(layer "In13.Cu")
		(net "GMI_CPU0_G0_CPU1_G2_TX_DN<10>")
	)
	(segment
		(start 349.751142 -229.94366)
		(end 349.75546 -229.896416)
		(width 0.1143)
		(layer "In13.Cu")
		(net "GMI_CPU0_G0_CPU1_G2_TX_DN<10>")
	)
	(segment
		(start 121.92 -235.082334)
		(end 121.932446 -235.089446)
		(width 0.1143)
		(layer "In13.Cu")
		(net "GMI_CPU0_G0_CPU1_G2_TX_DN<10>")
	)
	(segment
		(start 122.397774 -242.37696)
		(end 122.43689 -242.39982)
		(width 0.1143)
		(layer "In13.Cu")
		(net "GMI_CPU0_G0_CPU1_G2_TX_DN<10>")
	)
	(segment
		(start 349.599758 -239.319816)
		(end 349.568008 -239.301528)
		(width 0.1143)
		(layer "In13.Cu")
		(net "GMI_CPU0_G0_CPU1_G2_TX_DN<10>")
	)
	(segment
		(start 121.943114 -230.23576)
		(end 121.944638 -230.236776)
		(width 0.1143)
		(layer "In13.Cu")
		(net "GMI_CPU0_G0_CPU1_G2_TX_DN<10>")
	)
	(segment
		(start 349.612712 -236.088936)
		(end 349.599758 -236.079792)
		(width 0.1143)
		(layer "In13.Cu")
		(net "GMI_CPU0_G0_CPU1_G2_TX_DN<10>")
	)
	(segment
		(start 121.96699 -240.898934)
		(end 121.896124 -240.940082)
		(width 0.1143)
		(layer "In13.Cu")
		(net "GMI_CPU0_G0_CPU1_G2_TX_DN<10>")
	)
	(segment
		(start 349.546926 -234.4293)
		(end 349.528892 -234.418632)
		(width 0.1143)
		(layer "In13.Cu")
		(net "GMI_CPU0_G0_CPU1_G2_TX_DN<10>")
	)
	(segment
		(start 349.529654 -228.62921)
		(end 349.589344 -228.594412)
		(width 0.1143)
		(layer "In13.Cu")
		(net "GMI_CPU0_G0_CPU1_G2_TX_DN<10>")
	)
	(segment
		(start 349.54718 -234.4293)
		(end 349.546926 -234.4293)
		(width 0.1143)
		(layer "In13.Cu")
		(net "GMI_CPU0_G0_CPU1_G2_TX_DN<10>")
	)
	(segment
		(start 121.944638 -230.236776)
		(end 121.945654 -230.237284)
		(width 0.1143)
		(layer "In13.Cu")
		(net "GMI_CPU0_G0_CPU1_G2_TX_DN<10>")
	)
	(segment
		(start 155.39212 -191.35471)
		(end 155.06192 -191.625474)
		(width 0.14224)
		(layer "In13.Cu")
		(net "GMI_CPU0_G0_CPU1_G2_TX_DN<10>")
	)
	(segment
		(start 121.933208 -223.750124)
		(end 121.934224 -223.750632)
		(width 0.1143)
		(layer "In13.Cu")
		(net "GMI_CPU0_G0_CPU1_G2_TX_DN<10>")
	)
	(segment
		(start 349.6183 -237.713266)
		(end 349.599758 -237.699804)
		(width 0.1143)
		(layer "In13.Cu")
		(net "GMI_CPU0_G0_CPU1_G2_TX_DN<10>")
	)
	(segment
		(start 121.896124 -232.840022)
		(end 121.88317 -232.849166)
		(width 0.1143)
		(layer "In13.Cu")
		(net "GMI_CPU0_G0_CPU1_G2_TX_DN<10>")
	)
	(segment
		(start 121.896124 -236.080046)
		(end 121.88317 -236.08919)
		(width 0.1143)
		(layer "In13.Cu")
		(net "GMI_CPU0_G0_CPU1_G2_TX_DN<10>")
	)
	(segment
		(start 121.927874 -222.127064)
		(end 121.96699 -222.149924)
		(width 0.1143)
		(layer "In13.Cu")
		(net "GMI_CPU0_G0_CPU1_G2_TX_DN<10>")
	)
	(segment
		(start 121.877582 -238.29518)
		(end 121.896124 -238.308642)
		(width 0.1143)
		(layer "In13.Cu")
		(net "GMI_CPU0_G0_CPU1_G2_TX_DN<10>")
	)
	(segment
		(start 157.108398 -189.770258)
		(end 157.090364 -189.952376)
		(width 0.14224)
		(layer "In13.Cu")
		(net "GMI_CPU0_G0_CPU1_G2_TX_DN<10>")
	)
	(segment
		(start 145.905728 -198.495158)
		(end 145.125186 -198.731886)
		(width 0.14224)
		(layer "In13.Cu")
		(net "GMI_CPU0_G0_CPU1_G2_TX_DN<10>")
	)
	(segment
		(start 155.06192 -191.625474)
		(end 154.86888 -191.60617)
		(width 0.14224)
		(layer "In13.Cu")
		(net "GMI_CPU0_G0_CPU1_G2_TX_DN<10>")
	)
	(segment
		(start 122.674126 -242.781582)
		(end 122.75693 -242.864386)
		(width 0.1143)
		(layer "In13.Cu")
		(net "GMI_CPU0_G0_CPU1_G2_TX_DN<10>")
	)
	(segment
		(start 121.932446 -223.749616)
		(end 121.933208 -223.750124)
		(width 0.1143)
		(layer "In13.Cu")
		(net "GMI_CPU0_G0_CPU1_G2_TX_DN<10>")
	)
	(segment
		(start 121.896124 -224.740216)
		(end 121.877582 -224.753678)
		(width 0.1143)
		(layer "In13.Cu")
		(net "GMI_CPU0_G0_CPU1_G2_TX_DN<10>")
	)
	(segment
		(start 121.927874 -236.061758)
		(end 121.896124 -236.080046)
		(width 0.1143)
		(layer "In13.Cu")
		(net "GMI_CPU0_G0_CPU1_G2_TX_DN<10>")
	)
	(segment
		(start 152.445212 -193.770504)
		(end 152.252172 -193.7512)
		(width 0.14224)
		(layer "In13.Cu")
		(net "GMI_CPU0_G0_CPU1_G2_TX_DN<10>")
	)
	(segment
		(start 121.932446 -235.089446)
		(end 121.933208 -235.089954)
		(width 0.1143)
		(layer "In13.Cu")
		(net "GMI_CPU0_G0_CPU1_G2_TX_DN<10>")
	)
	(segment
		(start 153.317448 -193.055494)
		(end 153.124408 -193.03619)
		(width 0.14224)
		(layer "In13.Cu")
		(net "GMI_CPU0_G0_CPU1_G2_TX_DN<10>")
	)
	(segment
		(start 157.938978 -189.25667)
		(end 157.61462 -189.522862)
		(width 0.14224)
		(layer "In13.Cu")
		(net "GMI_CPU0_G0_CPU1_G2_TX_DN<10>")
	)
	(segment
		(start 349.599758 -238.308388)
		(end 349.6183 -238.294926)
		(width 0.1143)
		(layer "In13.Cu")
		(net "GMI_CPU0_G0_CPU1_G2_TX_DN<10>")
	)
	(segment
		(start 121.896124 -238.308642)
		(end 121.96699 -238.34979)
		(width 0.1143)
		(layer "In13.Cu")
		(net "GMI_CPU0_G0_CPU1_G2_TX_DN<10>")
	)
	(segment
		(start 308.421786 -185.28538)
		(end 306.652168 -184.474866)
		(width 0.14224)
		(layer "In13.Cu")
		(net "GMI_CPU0_G0_CPU1_G2_TX_DN<10>")
	)
	(segment
		(start 121.927874 -239.946942)
		(end 121.96699 -239.969802)
		(width 0.1143)
		(layer "In13.Cu")
		(net "GMI_CPU0_G0_CPU1_G2_TX_DN<10>")
	)
	(segment
		(start 156.766006 -190.218568)
		(end 156.583888 -190.20028)
		(width 0.14224)
		(layer "In13.Cu")
		(net "GMI_CPU0_G0_CPU1_G2_TX_DN<10>")
	)
	(segment
		(start 121.88317 -236.679486)
		(end 121.896124 -236.68863)
		(width 0.1143)
		(layer "In13.Cu")
		(net "GMI_CPU0_G0_CPU1_G2_TX_DN<10>")
	)
	(segment
		(start 349.601282 -229.601014)
		(end 349.565214 -229.579932)
		(width 0.1143)
		(layer "In13.Cu")
		(net "GMI_CPU0_G0_CPU1_G2_TX_DN<10>")
	)
	(segment
		(start 349.562674 -235.0897)
		(end 349.563436 -235.089192)
		(width 0.1143)
		(layer "In13.Cu")
		(net "GMI_CPU0_G0_CPU1_G2_TX_DN<10>")
	)
	(segment
		(start 121.740422 -229.895654)
		(end 121.746264 -229.949756)
		(width 0.1143)
		(layer "In13.Cu")
		(net "GMI_CPU0_G0_CPU1_G2_TX_DN<10>")
	)
	(segment
		(start 121.920762 -231.843072)
		(end 121.92635 -231.84612)
		(width 0.1143)
		(layer "In13.Cu")
		(net "GMI_CPU0_G0_CPU1_G2_TX_DN<10>")
	)
	(segment
		(start 121.89841 -230.209852)
		(end 121.943114 -230.23576)
		(width 0.1143)
		(layer "In13.Cu")
		(net "GMI_CPU0_G0_CPU1_G2_TX_DN<10>")
	)
	(segment
		(start 349.599758 -225.348546)
		(end 349.6183 -225.335084)
		(width 0.1143)
		(layer "In13.Cu")
		(net "GMI_CPU0_G0_CPU1_G2_TX_DN<10>")
	)
	(segment
		(start 349.529654 -235.109004)
		(end 349.561658 -235.090208)
		(width 0.1143)
		(layer "In13.Cu")
		(net "GMI_CPU0_G0_CPU1_G2_TX_DN<10>")
	)
	(segment
		(start 349.599758 -241.548412)
		(end 349.61957 -241.534188)
		(width 0.1143)
		(layer "In13.Cu")
		(net "GMI_CPU0_G0_CPU1_G2_TX_DN<10>")
	)
	(segment
		(start 349.528892 -225.389694)
		(end 349.599758 -225.348546)
		(width 0.1143)
		(layer "In13.Cu")
		(net "GMI_CPU0_G0_CPU1_G2_TX_DN<10>")
	)
	(segment
		(start 152.794462 -193.3067)
		(end 152.775412 -193.49974)
		(width 0.14224)
		(layer "In13.Cu")
		(net "GMI_CPU0_G0_CPU1_G2_TX_DN<10>")
	)
	(segment
		(start 121.96699 -226.31908)
		(end 121.927874 -226.34194)
		(width 0.1143)
		(layer "In13.Cu")
		(net "GMI_CPU0_G0_CPU1_G2_TX_DN<10>")
	)
	(segment
		(start 349.550228 -230.23703)
		(end 349.551244 -230.236522)
		(width 0.1143)
		(layer "In13.Cu")
		(net "GMI_CPU0_G0_CPU1_G2_TX_DN<10>")
	)
	(segment
		(start 121.896124 -226.968812)
		(end 121.927874 -226.9871)
		(width 0.1143)
		(layer "In13.Cu")
		(net "GMI_CPU0_G0_CPU1_G2_TX_DN<10>")
	)
	(segment
		(start 151.572976 -194.485514)
		(end 151.379936 -194.46621)
		(width 0.14224)
		(layer "In13.Cu")
		(net "GMI_CPU0_G0_CPU1_G2_TX_DN<10>")
	)
	(segment
		(start 121.740422 -221.24924)
		(end 121.740422 -221.804484)
		(width 0.1143)
		(layer "In13.Cu")
		(net "GMI_CPU0_G0_CPU1_G2_TX_DN<10>")
	)
	(segment
		(start 121.946416 -230.237792)
		(end 121.948448 -230.238808)
		(width 0.1143)
		(layer "In13.Cu")
		(net "GMI_CPU0_G0_CPU1_G2_TX_DN<10>")
	)
	(segment
		(start 349.552006 -230.236014)
		(end 349.594932 -230.211122)
		(width 0.1143)
		(layer "In13.Cu")
		(net "GMI_CPU0_G0_CPU1_G2_TX_DN<10>")
	)
	(segment
		(start 349.568008 -224.721674)
		(end 349.528892 -224.698814)
		(width 0.1143)
		(layer "In13.Cu")
		(net "GMI_CPU0_G0_CPU1_G2_TX_DN<10>")
	)
	(segment
		(start 306.652168 -184.474866)
		(end 302.888904 -184.474866)
		(width 0.14224)
		(layer "In13.Cu")
		(net "GMI_CPU0_G0_CPU1_G2_TX_DN<10>")
	)
	(segment
		(start 121.96699 -227.939092)
		(end 121.9073 -227.97389)
		(width 0.1143)
		(layer "In13.Cu")
		(net "GMI_CPU0_G0_CPU1_G2_TX_DN<10>")
	)
	(segment
		(start 349.596964 -230.210106)
		(end 349.631 -230.180388)
		(width 0.1143)
		(layer "In13.Cu")
		(net "GMI_CPU0_G0_CPU1_G2_TX_DN<10>")
	)
	(segment
		(start 349.61957 -240.954052)
		(end 349.599758 -240.939828)
		(width 0.1143)
		(layer "In13.Cu")
		(net "GMI_CPU0_G0_CPU1_G2_TX_DN<10>")
	)
	(segment
		(start 121.96699 -231.179116)
		(end 121.961402 -231.18191)
		(width 0.1143)
		(layer "In13.Cu")
		(net "GMI_CPU0_G0_CPU1_G2_TX_DN<10>")
	)
	(segment
		(start 121.896124 -240.940082)
		(end 121.876312 -240.954306)
		(width 0.1143)
		(layer "In13.Cu")
		(net "GMI_CPU0_G0_CPU1_G2_TX_DN<10>")
	)
	(segment
		(start 157.090364 -189.952376)
		(end 156.766006 -190.218568)
		(width 0.14224)
		(layer "In13.Cu")
		(net "GMI_CPU0_G0_CPU1_G2_TX_DN<10>")
	)
	(segment
		(start 121.906538 -228.594666)
		(end 121.966228 -228.629464)
		(width 0.1143)
		(layer "In13.Cu")
		(net "GMI_CPU0_G0_CPU1_G2_TX_DN<10>")
	)
	(segment
		(start 349.568008 -226.986846)
		(end 349.599758 -226.968558)
		(width 0.1143)
		(layer "In13.Cu")
		(net "GMI_CPU0_G0_CPU1_G2_TX_DN<10>")
	)
	(segment
		(start 167.042592 -183.68391)
		(end 162.591242 -185.275474)
		(width 0.14224)
		(layer "In13.Cu")
		(net "GMI_CPU0_G0_CPU1_G2_TX_DN<10>")
	)
	(segment
		(start 121.896124 -241.548666)
		(end 121.927874 -241.566954)
		(width 0.1143)
		(layer "In13.Cu")
		(net "GMI_CPU0_G0_CPU1_G2_TX_DN<10>")
	)
	(segment
		(start 349.568008 -239.301528)
		(end 349.528892 -239.278668)
		(width 0.1143)
		(layer "In13.Cu")
		(net "GMI_CPU0_G0_CPU1_G2_TX_DN<10>")
	)
	(segment
		(start 349.599758 -236.079792)
		(end 349.568008 -236.061504)
		(width 0.1143)
		(layer "In13.Cu")
		(net "GMI_CPU0_G0_CPU1_G2_TX_DN<10>")
	)
	(segment
		(start 157.61462 -189.522862)
		(end 157.432502 -189.504574)
		(width 0.14224)
		(layer "In13.Cu")
		(net "GMI_CPU0_G0_CPU1_G2_TX_DN<10>")
	)
	(segment
		(start 121.71553 -221.146116)
		(end 121.71553 -221.224348)
		(width 0.1143)
		(layer "In13.Cu")
		(net "GMI_CPU0_G0_CPU1_G2_TX_DN<10>")
	)
	(segment
		(start 349.568516 -234.441746)
		(end 349.54718 -234.4293)
		(width 0.1143)
		(layer "In13.Cu")
		(net "GMI_CPU0_G0_CPU1_G2_TX_DN<10>")
	)
	(segment
		(start 349.599758 -240.939828)
		(end 349.528892 -240.89868)
		(width 0.1143)
		(layer "In13.Cu")
		(net "GMI_CPU0_G0_CPU1_G2_TX_DN<10>")
	)
	(segment
		(start 348.738952 -242.864132)
		(end 348.821756 -242.781328)
		(width 0.1143)
		(layer "In13.Cu")
		(net "GMI_CPU0_G0_CPU1_G2_TX_DN<10>")
	)
	(segment
		(start 121.897394 -222.109284)
		(end 121.927874 -222.127064)
		(width 0.1143)
		(layer "In13.Cu")
		(net "GMI_CPU0_G0_CPU1_G2_TX_DN<10>")
	)
	(segment
		(start 349.734632 -221.093538)
		(end 349.734632 -219.733876)
		(width 0.14224)
		(layer "In13.Cu")
		(net "GMI_CPU0_G0_CPU1_G2_TX_DN<10>")
	)
	(segment
		(start 349.599758 -224.739962)
		(end 349.568008 -224.721674)
		(width 0.1143)
		(layer "In13.Cu")
		(net "GMI_CPU0_G0_CPU1_G2_TX_DN<10>")
	)
	(segment
		(start 121.961402 -231.18191)
		(end 121.921016 -231.205532)
		(width 0.1143)
		(layer "In13.Cu")
		(net "GMI_CPU0_G0_CPU1_G2_TX_DN<10>")
	)
	(segment
		(start 349.549466 -230.237538)
		(end 349.550228 -230.23703)
		(width 0.1143)
		(layer "In13.Cu")
		(net "GMI_CPU0_G0_CPU1_G2_TX_DN<10>")
	)
	(segment
		(start 349.589598 -227.974144)
		(end 349.589344 -227.974144)
		(width 0.1143)
		(layer "In13.Cu")
		(net "GMI_CPU0_G0_CPU1_G2_TX_DN<10>")
	)
	(segment
		(start 349.528892 -236.729524)
		(end 349.599758 -236.688376)
		(width 0.1143)
		(layer "In13.Cu")
		(net "GMI_CPU0_G0_CPU1_G2_TX_DN<10>")
	)
	(segment
		(start 121.76125 -219.878148)
		(end 121.76125 -221.071948)
		(width 0.14224)
		(layer "In13.Cu")
		(net "GMI_CPU0_G0_CPU1_G2_TX_DN<10>")
	)
	(segment
		(start 348.44101 -242.864132)
		(end 348.738952 -242.864132)
		(width 0.1143)
		(layer "In13.Cu")
		(net "GMI_CPU0_G0_CPU1_G2_TX_DN<10>")
	)
	(segment
		(start 121.88317 -233.439462)
		(end 121.896124 -233.448606)
		(width 0.1143)
		(layer "In13.Cu")
		(net "GMI_CPU0_G0_CPU1_G2_TX_DN<10>")
	)
	(segment
		(start 154.538934 -191.87668)
		(end 154.519884 -192.06972)
		(width 0.14224)
		(layer "In13.Cu")
		(net "GMI_CPU0_G0_CPU1_G2_TX_DN<10>")
	)
	(segment
		(start 121.948956 -223.089724)
		(end 121.948702 -223.089724)
		(width 0.1143)
		(layer "In13.Cu")
		(net "GMI_CPU0_G0_CPU1_G2_TX_DN<10>")
	)
	(segment
		(start 121.92 -223.742504)
		(end 121.932446 -223.749616)
		(width 0.1143)
		(layer "In13.Cu")
		(net "GMI_CPU0_G0_CPU1_G2_TX_DN<10>")
	)
	(segment
		(start 121.948956 -234.429554)
		(end 121.948702 -234.429554)
		(width 0.1143)
		(layer "In13.Cu")
		(net "GMI_CPU0_G0_CPU1_G2_TX_DN<10>")
	)
	(segment
		(start 121.955306 -230.242872)
		(end 121.96445 -230.248206)
		(width 0.1143)
		(layer "In13.Cu")
		(net "GMI_CPU0_G0_CPU1_G2_TX_DN<10>")
	)
	(segment
		(start 121.96699 -237.65891)
		(end 121.927874 -237.68177)
		(width 0.1143)
		(layer "In13.Cu")
		(net "GMI_CPU0_G0_CPU1_G2_TX_DN<10>")
	)
	(segment
		(start 154.519884 -192.06972)
		(end 154.189684 -192.340484)
		(width 0.14224)
		(layer "In13.Cu")
		(net "GMI_CPU0_G0_CPU1_G2_TX_DN<10>")
	)
	(segment
		(start 146.793712 -198.226172)
		(end 145.905982 -198.495158)
		(width 0.14224)
		(layer "In13.Cu")
		(net "GMI_CPU0_G0_CPU1_G2_TX_DN<10>")
	)
	(segment
		(start 349.528892 -233.4895)
		(end 349.599758 -233.448352)
		(width 0.1143)
		(layer "In13.Cu")
		(net "GMI_CPU0_G0_CPU1_G2_TX_DN<10>")
	)
	(segment
		(start 121.896124 -237.700058)
		(end 121.877582 -237.71352)
		(width 0.1143)
		(layer "In13.Cu")
		(net "GMI_CPU0_G0_CPU1_G2_TX_DN<10>")
	)
	(segment
		(start 145.125186 -198.731886)
		(end 123.974098 -216.074498)
		(width 0.14224)
		(layer "In13.Cu")
		(net "GMI_CPU0_G0_CPU1_G2_TX_DN<10>")
	)
	(segment
		(start 349.75546 -221.248986)
		(end 349.780352 -221.224094)
		(width 0.1143)
		(layer "In13.Cu")
		(net "GMI_CPU0_G0_CPU1_G2_TX_DN<10>")
	)
	(segment
		(start 121.927874 -226.9871)
		(end 121.96699 -227.00996)
		(width 0.1143)
		(layer "In13.Cu")
		(net "GMI_CPU0_G0_CPU1_G2_TX_DN<10>")
	)
	(segment
		(start 349.528892 -241.58956)
		(end 349.568008 -241.5667)
		(width 0.1143)
		(layer "In13.Cu")
		(net "GMI_CPU0_G0_CPU1_G2_TX_DN<10>")
	)
	(segment
		(start 121.948448 -230.238808)
		(end 121.950734 -230.240332)
		(width 0.1143)
		(layer "In13.Cu")
		(net "GMI_CPU0_G0_CPU1_G2_TX_DN<10>")
	)
	(segment
		(start 121.71553 -221.224348)
		(end 121.740422 -221.24924)
		(width 0.1143)
		(layer "In13.Cu")
		(net "GMI_CPU0_G0_CPU1_G2_TX_DN<10>")
	)
	(segment
		(start 121.96699 -236.038898)
		(end 121.927874 -236.061758)
		(width 0.1143)
		(layer "In13.Cu")
		(net "GMI_CPU0_G0_CPU1_G2_TX_DN<10>")
	)
	(segment
		(start 349.599758 -233.448352)
		(end 349.612712 -233.439208)
		(width 0.1143)
		(layer "In13.Cu")
		(net "GMI_CPU0_G0_CPU1_G2_TX_DN<10>")
	)
	(segment
		(start 121.90603 -228.594666)
		(end 121.906538 -228.594666)
		(width 0.1143)
		(layer "In13.Cu")
		(net "GMI_CPU0_G0_CPU1_G2_TX_DN<10>")
	)
	(segment
		(start 349.568008 -232.82148)
		(end 349.528892 -232.79862)
		(width 0.1143)
		(layer "In13.Cu")
		(net "GMI_CPU0_G0_CPU1_G2_TX_DN<10>")
	)
	(segment
		(start 349.780352 -221.145862)
		(end 349.734632 -221.100142)
		(width 0.1143)
		(layer "In13.Cu")
		(net "GMI_CPU0_G0_CPU1_G2_TX_DN<10>")
	)
	(segment
		(start 349.545148 -230.240078)
		(end 349.547434 -230.238554)
		(width 0.1143)
		(layer "In13.Cu")
		(net "GMI_CPU0_G0_CPU1_G2_TX_DN<10>")
	)
	(segment
		(start 121.927874 -237.68177)
		(end 121.896124 -237.700058)
		(width 0.1143)
		(layer "In13.Cu")
		(net "GMI_CPU0_G0_CPU1_G2_TX_DN<10>")
	)
	(segment
		(start 121.96699 -232.798874)
		(end 121.927874 -232.821734)
		(width 0.1143)
		(layer "In13.Cu")
		(net "GMI_CPU0_G0_CPU1_G2_TX_DN<10>")
	)
	(segment
		(start 349.528892 -238.349536)
		(end 349.599758 -238.308388)
		(width 0.1143)
		(layer "In13.Cu")
		(net "GMI_CPU0_G0_CPU1_G2_TX_DN<10>")
	)
	(segment
		(start 349.528892 -222.14967)
		(end 349.598488 -222.10903)
		(width 0.1143)
		(layer "In13.Cu")
		(net "GMI_CPU0_G0_CPU1_G2_TX_DN<10>")
	)
	(segment
		(start 349.528892 -227.009706)
		(end 349.568008 -226.986846)
		(width 0.1143)
		(layer "In13.Cu")
		(net "GMI_CPU0_G0_CPU1_G2_TX_DN<10>")
	)
	(segment
		(start 121.945654 -230.237284)
		(end 121.946416 -230.237792)
		(width 0.1143)
		(layer "In13.Cu")
		(net "GMI_CPU0_G0_CPU1_G2_TX_DN<10>")
	)
	(segment
		(start 121.934224 -223.750632)
		(end 121.966228 -223.769428)
		(width 0.1143)
		(layer "In13.Cu")
		(net "GMI_CPU0_G0_CPU1_G2_TX_DN<10>")
	)
	(segment
		(start 349.734632 -219.733876)
		(end 347.735144 -216.366344)
		(width 0.14224)
		(layer "In13.Cu")
		(net "GMI_CPU0_G0_CPU1_G2_TX_DN<10>")
	)
	(segment
		(start 155.41117 -191.16167)
		(end 155.39212 -191.35471)
		(width 0.14224)
		(layer "In13.Cu")
		(net "GMI_CPU0_G0_CPU1_G2_TX_DN<10>")
	)
	(segment
		(start 302.888904 -184.474866)
		(end 167.042592 -183.68391)
		(width 0.14224)
		(layer "In13.Cu")
		(net "GMI_CPU0_G0_CPU1_G2_TX_DN<10>")
	)
	(segment
		(start 349.595948 -230.210106)
		(end 349.596964 -230.210106)
		(width 0.1143)
		(layer "In13.Cu")
		(net "GMI_CPU0_G0_CPU1_G2_TX_DN<10>")
	)
	(segment
		(start 121.896124 -236.68863)
		(end 121.96699 -236.729778)
		(width 0.1143)
		(layer "In13.Cu")
		(net "GMI_CPU0_G0_CPU1_G2_TX_DN<10>")
	)
	(segment
		(start 151.922226 -194.02171)
		(end 151.903176 -194.21475)
		(width 0.14224)
		(layer "In13.Cu")
		(net "GMI_CPU0_G0_CPU1_G2_TX_DN<10>")
	)
	(segment
		(start 121.876312 -241.534442)
		(end 121.896124 -241.548666)
		(width 0.1143)
		(layer "In13.Cu")
		(net "GMI_CPU0_G0_CPU1_G2_TX_DN<10>")
	)
	(segment
		(start 349.531432 -230.247952)
		(end 349.540576 -230.242618)
		(width 0.1143)
		(layer "In13.Cu")
		(net "GMI_CPU0_G0_CPU1_G2_TX_DN<10>")
	)
	(segment
		(start 121.96699 -223.079056)
		(end 121.948956 -223.089724)
		(width 0.1143)
		(layer "In13.Cu")
		(net "GMI_CPU0_G0_CPU1_G2_TX_DN<10>")
	)
	(segment
		(start 156.583888 -190.20028)
		(end 156.259784 -190.465964)
		(width 0.14224)
		(layer "In13.Cu")
		(net "GMI_CPU0_G0_CPU1_G2_TX_DN<10>")
	)
	(segment
		(start 121.927874 -232.821734)
		(end 121.896124 -232.840022)
		(width 0.1143)
		(layer "In13.Cu")
		(net "GMI_CPU0_G0_CPU1_G2_TX_DN<10>")
	)
	(segment
		(start 121.92635 -231.84612)
		(end 121.927112 -231.846628)
		(width 0.1143)
		(layer "In13.Cu")
		(net "GMI_CPU0_G0_CPU1_G2_TX_DN<10>")
	)
	(segment
		(start 121.896124 -225.3488)
		(end 121.96699 -225.389948)
		(width 0.1143)
		(layer "In13.Cu")
		(net "GMI_CPU0_G0_CPU1_G2_TX_DN<10>")
	)
	(segment
		(start 349.569532 -231.845866)
		(end 349.57512 -231.842818)
		(width 0.1143)
		(layer "In13.Cu")
		(net "GMI_CPU0_G0_CPU1_G2_TX_DN<10>")
	)
	(segment
		(start 349.528892 -239.969548)
		(end 349.568008 -239.946688)
		(width 0.1143)
		(layer "In13.Cu")
		(net "GMI_CPU0_G0_CPU1_G2_TX_DN<10>")
	)
	(segment
		(start 349.780352 -221.224094)
		(end 349.780352 -221.145862)
		(width 0.1143)
		(layer "In13.Cu")
		(net "GMI_CPU0_G0_CPU1_G2_TX_DN<10>")
	)
	(segment
		(start 121.96699 -239.278922)
		(end 121.927874 -239.301782)
		(width 0.1143)
		(layer "In13.Cu")
		(net "GMI_CPU0_G0_CPU1_G2_TX_DN<10>")
	)
	(segment
		(start 312.96737 -187.8584)
		(end 308.421786 -185.28538)
		(width 0.14224)
		(layer "In13.Cu")
		(net "GMI_CPU0_G0_CPU1_G2_TX_DN<10>")
	)
	(segment
		(start 152.252172 -193.7512)
		(end 151.922226 -194.02171)
		(width 0.14224)
		(layer "In13.Cu")
		(net "GMI_CPU0_G0_CPU1_G2_TX_DN<10>")
	)
	(segment
		(start 153.996644 -192.32118)
		(end 153.666698 -192.59169)
		(width 0.14224)
		(layer "In13.Cu")
		(net "GMI_CPU0_G0_CPU1_G2_TX_DN<10>")
	)
	(segment
		(start 151.379936 -194.46621)
		(end 146.793712 -198.226172)
		(width 0.14224)
		(layer "In13.Cu")
		(net "GMI_CPU0_G0_CPU1_G2_TX_DN<10>")
	)
	(segment
		(start 347.735144 -216.366344)
		(end 312.96737 -187.8584)
		(width 0.14224)
		(layer "In13.Cu")
		(net "GMI_CPU0_G0_CPU1_G2_TX_DN<10>")
	)
	(arc
		(start 349.61957 -241.534188)
		(mid 349.768284 -241.24412)
		(end 349.61957 -240.954052)
		(width 0.1143)
		(layer "In13.Cu")
		(net "GMI_CPU0_G0_CPU1_G2_TX_DN<10>")
	)
	(arc
		(start 349.575882 -235.08208)
		(mid 349.754099 -234.759803)
		(end 349.568516 -234.441746)
		(width 0.1143)
		(layer "In13.Cu")
		(net "GMI_CPU0_G0_CPU1_G2_TX_DN<10>")
	)
	(arc
		(start 349.528892 -229.55885)
		(mid 349.285565 -229.094284)
		(end 349.528892 -228.629718)
		(width 0.1143)
		(layer "In13.Cu")
		(net "GMI_CPU0_G0_CPU1_G2_TX_DN<10>")
	)
	(arc
		(start 121.96445 -230.248206)
		(mid 122.145102 -230.450951)
		(end 122.210322 -230.71455)
		(width 0.1143)
		(layer "In13.Cu")
		(net "GMI_CPU0_G0_CPU1_G2_TX_DN<10>")
	)
	(arc
		(start 349.6183 -238.294926)
		(mid 349.767315 -238.004096)
		(end 349.6183 -237.713266)
		(width 0.1143)
		(layer "In13.Cu")
		(net "GMI_CPU0_G0_CPU1_G2_TX_DN<10>")
	)
	(arc
		(start 121.746264 -229.949756)
		(mid 121.782167 -230.071559)
		(end 121.858532 -230.173022)
		(width 0.1143)
		(layer "In13.Cu")
		(net "GMI_CPU0_G0_CPU1_G2_TX_DN<10>")
	)
	(arc
		(start 121.96699 -225.389948)
		(mid 122.210317 -225.854514)
		(end 121.96699 -226.31908)
		(width 0.1143)
		(layer "In13.Cu")
		(net "GMI_CPU0_G0_CPU1_G2_TX_DN<10>")
	)
	(arc
		(start 349.612712 -233.439208)
		(mid 349.763964 -233.14406)
		(end 349.612712 -232.848912)
		(width 0.1143)
		(layer "In13.Cu")
		(net "GMI_CPU0_G0_CPU1_G2_TX_DN<10>")
	)
	(arc
		(start 349.528892 -232.79862)
		(mid 349.285565 -232.334054)
		(end 349.528892 -231.869488)
		(width 0.1143)
		(layer "In13.Cu")
		(net "GMI_CPU0_G0_CPU1_G2_TX_DN<10>")
	)
	(arc
		(start 349.128588 -242.358926)
		(mid 349.244015 -242.22555)
		(end 349.28556 -242.054126)
		(width 0.1143)
		(layer "In13.Cu")
		(net "GMI_CPU0_G0_CPU1_G2_TX_DN<10>")
	)
	(arc
		(start 349.598488 -222.10903)
		(mid 349.713915 -221.975654)
		(end 349.75546 -221.80423)
		(width 0.1143)
		(layer "In13.Cu")
		(net "GMI_CPU0_G0_CPU1_G2_TX_DN<10>")
	)
	(arc
		(start 349.528892 -240.89868)
		(mid 349.285565 -240.434114)
		(end 349.528892 -239.969548)
		(width 0.1143)
		(layer "In13.Cu")
		(net "GMI_CPU0_G0_CPU1_G2_TX_DN<10>")
	)
	(arc
		(start 121.877582 -237.71352)
		(mid 121.728567 -238.00435)
		(end 121.877582 -238.29518)
		(width 0.1143)
		(layer "In13.Cu")
		(net "GMI_CPU0_G0_CPU1_G2_TX_DN<10>")
	)
	(arc
		(start 349.57512 -231.842818)
		(mid 349.757971 -231.523938)
		(end 349.574866 -231.205278)
		(width 0.1143)
		(layer "In13.Cu")
		(net "GMI_CPU0_G0_CPU1_G2_TX_DN<10>")
	)
	(arc
		(start 349.528892 -231.869488)
		(mid 349.529273 -231.869234)
		(end 349.529654 -231.86898)
		(width 0.1143)
		(layer "In13.Cu")
		(net "GMI_CPU0_G0_CPU1_G2_TX_DN<10>")
	)
	(arc
		(start 349.612712 -236.679232)
		(mid 349.763964 -236.384084)
		(end 349.612712 -236.088936)
		(width 0.1143)
		(layer "In13.Cu")
		(net "GMI_CPU0_G0_CPU1_G2_TX_DN<10>")
	)
	(arc
		(start 349.528892 -228.629718)
		(mid 349.529273 -228.629464)
		(end 349.529654 -228.62921)
		(width 0.1143)
		(layer "In13.Cu")
		(net "GMI_CPU0_G0_CPU1_G2_TX_DN<10>")
	)
	(arc
		(start 121.894346 -229.601522)
		(mid 121.78301 -229.730592)
		(end 121.740422 -229.895654)
		(width 0.1143)
		(layer "In13.Cu")
		(net "GMI_CPU0_G0_CPU1_G2_TX_DN<10>")
	)
	(arc
		(start 349.528892 -235.109512)
		(mid 349.529273 -235.109258)
		(end 349.529654 -235.109004)
		(width 0.1143)
		(layer "In13.Cu")
		(net "GMI_CPU0_G0_CPU1_G2_TX_DN<10>")
	)
	(arc
		(start 349.385128 -241.733578)
		(mid 349.45048 -241.655051)
		(end 349.528892 -241.58956)
		(width 0.1143)
		(layer "In13.Cu")
		(net "GMI_CPU0_G0_CPU1_G2_TX_DN<10>")
	)
	(arc
		(start 121.96699 -228.629972)
		(mid 122.210317 -229.094538)
		(end 121.96699 -229.559104)
		(width 0.1143)
		(layer "In13.Cu")
		(net "GMI_CPU0_G0_CPU1_G2_TX_DN<10>")
	)
	(arc
		(start 349.599758 -239.9284)
		(mid 349.751347 -239.624108)
		(end 349.599758 -239.319816)
		(width 0.1143)
		(layer "In13.Cu")
		(net "GMI_CPU0_G0_CPU1_G2_TX_DN<10>")
	)
	(arc
		(start 121.921016 -231.205532)
		(mid 121.738039 -231.524192)
		(end 121.920762 -231.843072)
		(width 0.1143)
		(layer "In13.Cu")
		(net "GMI_CPU0_G0_CPU1_G2_TX_DN<10>")
	)
	(arc
		(start 121.876312 -240.954306)
		(mid 121.727598 -241.244374)
		(end 121.876312 -241.534442)
		(width 0.1143)
		(layer "In13.Cu")
		(net "GMI_CPU0_G0_CPU1_G2_TX_DN<10>")
	)
	(arc
		(start 349.28556 -242.054126)
		(mid 349.31098 -241.886281)
		(end 349.385128 -241.733578)
		(width 0.1143)
		(layer "In13.Cu")
		(net "GMI_CPU0_G0_CPU1_G2_TX_DN<10>")
	)
	(arc
		(start 121.896124 -226.360228)
		(mid 121.747027 -226.66452)
		(end 121.896124 -226.968812)
		(width 0.1143)
		(layer "In13.Cu")
		(net "GMI_CPU0_G0_CPU1_G2_TX_DN<10>")
	)
	(arc
		(start 349.75546 -229.896416)
		(mid 349.713075 -229.730591)
		(end 349.601282 -229.601014)
		(width 0.1143)
		(layer "In13.Cu")
		(net "GMI_CPU0_G0_CPU1_G2_TX_DN<10>")
	)
	(arc
		(start 349.528892 -237.658656)
		(mid 349.285565 -237.19409)
		(end 349.528892 -236.729524)
		(width 0.1143)
		(layer "In13.Cu")
		(net "GMI_CPU0_G0_CPU1_G2_TX_DN<10>")
	)
	(arc
		(start 349.528892 -231.178862)
		(mid 349.350079 -230.976512)
		(end 349.28556 -230.714296)
		(width 0.1143)
		(layer "In13.Cu")
		(net "GMI_CPU0_G0_CPU1_G2_TX_DN<10>")
	)
	(arc
		(start 121.96699 -241.589814)
		(mid 122.045413 -241.655295)
		(end 122.110754 -241.733832)
		(width 0.1143)
		(layer "In13.Cu")
		(net "GMI_CPU0_G0_CPU1_G2_TX_DN<10>")
	)
	(arc
		(start 121.966228 -235.109258)
		(mid 121.966609 -235.109512)
		(end 121.96699 -235.109766)
		(width 0.1143)
		(layer "In13.Cu")
		(net "GMI_CPU0_G0_CPU1_G2_TX_DN<10>")
	)
	(arc
		(start 121.966228 -228.629464)
		(mid 121.966609 -228.629718)
		(end 121.96699 -228.629972)
		(width 0.1143)
		(layer "In13.Cu")
		(net "GMI_CPU0_G0_CPU1_G2_TX_DN<10>")
	)
	(arc
		(start 121.927366 -234.442)
		(mid 121.741846 -234.760057)
		(end 121.92 -235.082334)
		(width 0.1143)
		(layer "In13.Cu")
		(net "GMI_CPU0_G0_CPU1_G2_TX_DN<10>")
	)
	(arc
		(start 349.528892 -239.278668)
		(mid 349.285565 -238.814102)
		(end 349.528892 -238.349536)
		(width 0.1143)
		(layer "In13.Cu")
		(net "GMI_CPU0_G0_CPU1_G2_TX_DN<10>")
	)
	(arc
		(start 121.96699 -239.969802)
		(mid 122.210317 -240.434368)
		(end 121.96699 -240.898934)
		(width 0.1143)
		(layer "In13.Cu")
		(net "GMI_CPU0_G0_CPU1_G2_TX_DN<10>")
	)
	(arc
		(start 121.88317 -236.08919)
		(mid 121.731918 -236.384338)
		(end 121.88317 -236.679486)
		(width 0.1143)
		(layer "In13.Cu")
		(net "GMI_CPU0_G0_CPU1_G2_TX_DN<10>")
	)
	(arc
		(start 121.96699 -233.489754)
		(mid 122.210317 -233.95432)
		(end 121.96699 -234.418886)
		(width 0.1143)
		(layer "In13.Cu")
		(net "GMI_CPU0_G0_CPU1_G2_TX_DN<10>")
	)
	(arc
		(start 349.528892 -226.318826)
		(mid 349.285565 -225.85426)
		(end 349.528892 -225.389694)
		(width 0.1143)
		(layer "In13.Cu")
		(net "GMI_CPU0_G0_CPU1_G2_TX_DN<10>")
	)
	(arc
		(start 121.896124 -239.32007)
		(mid 121.744535 -239.624362)
		(end 121.896124 -239.928654)
		(width 0.1143)
		(layer "In13.Cu")
		(net "GMI_CPU0_G0_CPU1_G2_TX_DN<10>")
	)
	(arc
		(start 349.589852 -228.594412)
		(mid 349.768268 -228.284168)
		(end 349.589598 -227.974144)
		(width 0.1143)
		(layer "In13.Cu")
		(net "GMI_CPU0_G0_CPU1_G2_TX_DN<10>")
	)
	(arc
		(start 121.96699 -222.149924)
		(mid 122.210317 -222.61449)
		(end 121.96699 -223.079056)
		(width 0.1143)
		(layer "In13.Cu")
		(net "GMI_CPU0_G0_CPU1_G2_TX_DN<10>")
	)
	(arc
		(start 122.43689 -242.39982)
		(mid 122.588877 -242.556328)
		(end 122.670316 -242.758722)
		(width 0.1143)
		(layer "In13.Cu")
		(net "GMI_CPU0_G0_CPU1_G2_TX_DN<10>")
	)
	(arc
		(start 121.96699 -223.769936)
		(mid 122.210317 -224.234502)
		(end 121.96699 -224.699068)
		(width 0.1143)
		(layer "In13.Cu")
		(net "GMI_CPU0_G0_CPU1_G2_TX_DN<10>")
	)
	(arc
		(start 349.528892 -224.698814)
		(mid 349.285565 -224.234248)
		(end 349.528892 -223.769682)
		(width 0.1143)
		(layer "In13.Cu")
		(net "GMI_CPU0_G0_CPU1_G2_TX_DN<10>")
	)
	(arc
		(start 349.528892 -227.938838)
		(mid 349.285565 -227.474272)
		(end 349.528892 -227.009706)
		(width 0.1143)
		(layer "In13.Cu")
		(net "GMI_CPU0_G0_CPU1_G2_TX_DN<10>")
	)
	(arc
		(start 121.96699 -235.109766)
		(mid 122.210317 -235.574332)
		(end 121.96699 -236.038898)
		(width 0.1143)
		(layer "In13.Cu")
		(net "GMI_CPU0_G0_CPU1_G2_TX_DN<10>")
	)
	(arc
		(start 121.96699 -238.34979)
		(mid 122.210317 -238.814356)
		(end 121.96699 -239.278922)
		(width 0.1143)
		(layer "In13.Cu")
		(net "GMI_CPU0_G0_CPU1_G2_TX_DN<10>")
	)
	(arc
		(start 349.528892 -223.078802)
		(mid 349.285565 -222.614236)
		(end 349.528892 -222.14967)
		(width 0.1143)
		(layer "In13.Cu")
		(net "GMI_CPU0_G0_CPU1_G2_TX_DN<10>")
	)
	(arc
		(start 121.966228 -231.869234)
		(mid 121.966609 -231.869488)
		(end 121.96699 -231.869742)
		(width 0.1143)
		(layer "In13.Cu")
		(net "GMI_CPU0_G0_CPU1_G2_TX_DN<10>")
	)
	(arc
		(start 349.528892 -234.418632)
		(mid 349.285565 -233.954066)
		(end 349.528892 -233.4895)
		(width 0.1143)
		(layer "In13.Cu")
		(net "GMI_CPU0_G0_CPU1_G2_TX_DN<10>")
	)
	(arc
		(start 349.528892 -236.038644)
		(mid 349.285565 -235.574078)
		(end 349.528892 -235.109512)
		(width 0.1143)
		(layer "In13.Cu")
		(net "GMI_CPU0_G0_CPU1_G2_TX_DN<10>")
	)
	(arc
		(start 121.906284 -227.974398)
		(mid 121.727742 -228.284422)
		(end 121.90603 -228.594666)
		(width 0.1143)
		(layer "In13.Cu")
		(net "GMI_CPU0_G0_CPU1_G2_TX_DN<10>")
	)
	(arc
		(start 122.110754 -241.733832)
		(mid 122.184868 -241.886546)
		(end 122.210322 -242.05438)
		(width 0.1143)
		(layer "In13.Cu")
		(net "GMI_CPU0_G0_CPU1_G2_TX_DN<10>")
	)
	(arc
		(start 121.927366 -223.10217)
		(mid 121.741846 -223.420227)
		(end 121.92 -223.742504)
		(width 0.1143)
		(layer "In13.Cu")
		(net "GMI_CPU0_G0_CPU1_G2_TX_DN<10>")
	)
	(arc
		(start 121.96699 -227.00996)
		(mid 122.210317 -227.474526)
		(end 121.96699 -227.939092)
		(width 0.1143)
		(layer "In13.Cu")
		(net "GMI_CPU0_G0_CPU1_G2_TX_DN<10>")
	)
	(arc
		(start 349.6183 -225.335084)
		(mid 349.767315 -225.044254)
		(end 349.6183 -224.753424)
		(width 0.1143)
		(layer "In13.Cu")
		(net "GMI_CPU0_G0_CPU1_G2_TX_DN<10>")
	)
	(arc
		(start 122.210322 -230.71455)
		(mid 122.145807 -230.976769)
		(end 121.96699 -231.179116)
		(width 0.1143)
		(layer "In13.Cu")
		(net "GMI_CPU0_G0_CPU1_G2_TX_DN<10>")
	)
	(arc
		(start 349.528892 -223.769682)
		(mid 349.529273 -223.769428)
		(end 349.529654 -223.769174)
		(width 0.1143)
		(layer "In13.Cu")
		(net "GMI_CPU0_G0_CPU1_G2_TX_DN<10>")
	)
	(arc
		(start 121.96699 -236.729778)
		(mid 122.210317 -237.194344)
		(end 121.96699 -237.65891)
		(width 0.1143)
		(layer "In13.Cu")
		(net "GMI_CPU0_G0_CPU1_G2_TX_DN<10>")
	)
	(arc
		(start 349.575882 -223.74225)
		(mid 349.754099 -223.419973)
		(end 349.568516 -223.101916)
		(width 0.1143)
		(layer "In13.Cu")
		(net "GMI_CPU0_G0_CPU1_G2_TX_DN<10>")
	)
	(arc
		(start 122.210322 -242.05438)
		(mid 122.251871 -242.225802)
		(end 122.367294 -242.35918)
		(width 0.1143)
		(layer "In13.Cu")
		(net "GMI_CPU0_G0_CPU1_G2_TX_DN<10>")
	)
	(arc
		(start 121.740422 -221.804484)
		(mid 121.781971 -221.975906)
		(end 121.897394 -222.109284)
		(width 0.1143)
		(layer "In13.Cu")
		(net "GMI_CPU0_G0_CPU1_G2_TX_DN<10>")
	)
	(arc
		(start 348.825566 -242.758468)
		(mid 348.906999 -242.55607)
		(end 349.058992 -242.399566)
		(width 0.1143)
		(layer "In13.Cu")
		(net "GMI_CPU0_G0_CPU1_G2_TX_DN<10>")
	)
	(arc
		(start 348.821756 -242.781328)
		(mid 348.823544 -242.769879)
		(end 348.825566 -242.758468)
		(width 0.1143)
		(layer "In13.Cu")
		(net "GMI_CPU0_G0_CPU1_G2_TX_DN<10>")
	)
	(arc
		(start 122.670316 -242.758722)
		(mid 122.672339 -242.770132)
		(end 122.674126 -242.781582)
		(width 0.1143)
		(layer "In13.Cu")
		(net "GMI_CPU0_G0_CPU1_G2_TX_DN<10>")
	)
	(arc
		(start 349.631 -230.180388)
		(mid 349.7138 -230.07356)
		(end 349.751142 -229.94366)
		(width 0.1143)
		(layer "In13.Cu")
		(net "GMI_CPU0_G0_CPU1_G2_TX_DN<10>")
	)
	(arc
		(start 349.599758 -226.968558)
		(mid 349.748855 -226.664266)
		(end 349.599758 -226.359974)
		(width 0.1143)
		(layer "In13.Cu")
		(net "GMI_CPU0_G0_CPU1_G2_TX_DN<10>")
	)
	(arc
		(start 121.966228 -223.769428)
		(mid 121.966609 -223.769682)
		(end 121.96699 -223.769936)
		(width 0.1143)
		(layer "In13.Cu")
		(net "GMI_CPU0_G0_CPU1_G2_TX_DN<10>")
	)
	(arc
		(start 121.96699 -231.869742)
		(mid 122.210317 -232.334308)
		(end 121.96699 -232.798874)
		(width 0.1143)
		(layer "In13.Cu")
		(net "GMI_CPU0_G0_CPU1_G2_TX_DN<10>")
	)
	(arc
		(start 121.88317 -232.849166)
		(mid 121.731918 -233.144314)
		(end 121.88317 -233.439462)
		(width 0.1143)
		(layer "In13.Cu")
		(net "GMI_CPU0_G0_CPU1_G2_TX_DN<10>")
	)
	(arc
		(start 349.28556 -230.714296)
		(mid 349.350796 -230.450705)
		(end 349.531432 -230.247952)
		(width 0.1143)
		(layer "In13.Cu")
		(net "GMI_CPU0_G0_CPU1_G2_TX_DN<10>")
	)
	(arc
		(start 121.877582 -224.753678)
		(mid 121.728567 -225.044508)
		(end 121.877582 -225.335338)
		(width 0.1143)
		(layer "In13.Cu")
		(net "GMI_CPU0_G0_CPU1_G2_TX_DN<10>")
	)
	(segment
		(start 114.597942 -242.320318)
		(end 115.064794 -242.05438)
		(width 0.12954)
		(layer "F.Cu")
		(net "GMI_CPU0_G0_CPU1_G2_TX_DN<0>")
	)
	(segment
		(start 356.89794 -242.320064)
		(end 356.431088 -242.054126)
		(width 0.12954)
		(layer "F.Cu")
		(net "GMI_CPU0_G0_CPU1_G2_TX_DN<0>")
	)
	(segment
		(start 114.53749 -212.415628)
		(end 114.583464 -212.59292)
		(width 0.14224)
		(layer "In13.Cu")
		(net "GMI_CPU0_G0_CPU1_G2_TX_DN<0>")
	)
	(segment
		(start 357.548688 -240.762028)
		(end 357.558086 -240.756694)
		(width 0.1143)
		(layer "In13.Cu")
		(net "GMI_CPU0_G0_CPU1_G2_TX_DN<0>")
	)
	(segment
		(start 357.04907 -241.58956)
		(end 357.088186 -241.5667)
		(width 0.1143)
		(layer "In13.Cu")
		(net "GMI_CPU0_G0_CPU1_G2_TX_DN<0>")
	)
	(segment
		(start 114.407696 -241.566954)
		(end 114.446812 -241.589814)
		(width 0.1143)
		(layer "In13.Cu")
		(net "GMI_CPU0_G0_CPU1_G2_TX_DN<0>")
	)
	(segment
		(start 113.081054 -214.89289)
		(end 112.86871 -215.254078)
		(width 0.14224)
		(layer "In13.Cu")
		(net "GMI_CPU0_G0_CPU1_G2_TX_DN<0>")
	)
	(segment
		(start 113.437162 -239.929162)
		(end 113.467642 -239.946942)
		(width 0.1143)
		(layer "In13.Cu")
		(net "GMI_CPU0_G0_CPU1_G2_TX_DN<0>")
	)
	(segment
		(start 308.674516 -175.066452)
		(end 302.919384 -175.066452)
		(width 0.14224)
		(layer "In13.Cu")
		(net "GMI_CPU0_G0_CPU1_G2_TX_DN<0>")
	)
	(segment
		(start 357.782876 -213.942676)
		(end 357.605076 -213.89721)
		(width 0.14224)
		(layer "In13.Cu")
		(net "GMI_CPU0_G0_CPU1_G2_TX_DN<0>")
	)
	(segment
		(start 318.403732 -179.921662)
		(end 311.802526 -176.184814)
		(width 0.14224)
		(layer "In13.Cu")
		(net "GMI_CPU0_G0_CPU1_G2_TX_DN<0>")
	)
	(segment
		(start 358.460294 -239.158526)
		(end 358.498394 -239.136682)
		(width 0.1143)
		(layer "In13.Cu")
		(net "GMI_CPU0_G0_CPU1_G2_TX_DN<0>")
	)
	(segment
		(start 164.808408 -174.258224)
		(end 156.105352 -177.370486)
		(width 0.14224)
		(layer "In13.Cu")
		(net "GMI_CPU0_G0_CPU1_G2_TX_DN<0>")
	)
	(segment
		(start 358.511856 -215.42375)
		(end 358.557068 -215.246458)
		(width 0.14224)
		(layer "In13.Cu")
		(net "GMI_CPU0_G0_CPU1_G2_TX_DN<0>")
	)
	(segment
		(start 359.227882 -237.386368)
		(end 359.183432 -237.341918)
		(width 0.1143)
		(layer "In13.Cu")
		(net "GMI_CPU0_G0_CPU1_G2_TX_DN<0>")
	)
	(segment
		(start 358.725724 -215.78443)
		(end 358.511856 -215.42375)
		(width 0.14224)
		(layer "In13.Cu")
		(net "GMI_CPU0_G0_CPU1_G2_TX_DN<0>")
	)
	(segment
		(start 358.3432 -214.886286)
		(end 358.1654 -214.84082)
		(width 0.14224)
		(layer "In13.Cu")
		(net "GMI_CPU0_G0_CPU1_G2_TX_DN<0>")
	)
	(segment
		(start 357.391208 -213.536784)
		(end 357.43642 -213.359238)
		(width 0.14224)
		(layer "In13.Cu")
		(net "GMI_CPU0_G0_CPU1_G2_TX_DN<0>")
	)
	(segment
		(start 359.183432 -237.32744)
		(end 359.183432 -216.300812)
		(width 0.14224)
		(layer "In13.Cu")
		(net "GMI_CPU0_G0_CPU1_G2_TX_DN<0>")
	)
	(segment
		(start 357.558086 -240.756694)
		(end 357.558848 -240.756186)
		(width 0.1143)
		(layer "In13.Cu")
		(net "GMI_CPU0_G0_CPU1_G2_TX_DN<0>")
	)
	(segment
		(start 115.627404 -210.561428)
		(end 115.09375 -211.469478)
		(width 0.14224)
		(layer "In13.Cu")
		(net "GMI_CPU0_G0_CPU1_G2_TX_DN<0>")
	)
	(segment
		(start 356.72903 -242.054126)
		(end 356.811834 -241.971322)
		(width 0.1143)
		(layer "In13.Cu")
		(net "GMI_CPU0_G0_CPU1_G2_TX_DN<0>")
	)
	(segment
		(start 358.1654 -214.84082)
		(end 357.951532 -214.480394)
		(width 0.14224)
		(layer "In13.Cu")
		(net "GMI_CPU0_G0_CPU1_G2_TX_DN<0>")
	)
	(segment
		(start 357.996744 -214.302848)
		(end 357.782876 -213.942676)
		(width 0.14224)
		(layer "In13.Cu")
		(net "GMI_CPU0_G0_CPU1_G2_TX_DN<0>")
	)
	(segment
		(start 114.749834 -212.05444)
		(end 114.53749 -212.415628)
		(width 0.14224)
		(layer "In13.Cu")
		(net "GMI_CPU0_G0_CPU1_G2_TX_DN<0>")
	)
	(segment
		(start 357.951532 -214.480394)
		(end 357.996744 -214.302848)
		(width 0.14224)
		(layer "In13.Cu")
		(net "GMI_CPU0_G0_CPU1_G2_TX_DN<0>")
	)
	(segment
		(start 357.267256 -241.25682)
		(end 357.267256 -241.250978)
		(width 0.1143)
		(layer "In13.Cu")
		(net "GMI_CPU0_G0_CPU1_G2_TX_DN<0>")
	)
	(segment
		(start 113.935764 -240.755678)
		(end 113.937034 -240.75644)
		(width 0.1143)
		(layer "In13.Cu")
		(net "GMI_CPU0_G0_CPU1_G2_TX_DN<0>")
	)
	(segment
		(start 357.561642 -240.754662)
		(end 357.562404 -240.754154)
		(width 0.1143)
		(layer "In13.Cu")
		(net "GMI_CPU0_G0_CPU1_G2_TX_DN<0>")
	)
	(segment
		(start 114.193574 -213.00059)
		(end 113.98123 -213.361778)
		(width 0.14224)
		(layer "In13.Cu")
		(net "GMI_CPU0_G0_CPU1_G2_TX_DN<0>")
	)
	(segment
		(start 112.882934 -239.039908)
		(end 112.92078 -239.078008)
		(width 0.1143)
		(layer "In13.Cu")
		(net "GMI_CPU0_G0_CPU1_G2_TX_DN<0>")
	)
	(segment
		(start 113.637314 -213.94674)
		(end 113.42497 -214.307928)
		(width 0.14224)
		(layer "In13.Cu")
		(net "GMI_CPU0_G0_CPU1_G2_TX_DN<0>")
	)
	(segment
		(start 114.37112 -212.954616)
		(end 114.193574 -213.00059)
		(width 0.14224)
		(layer "In13.Cu")
		(net "GMI_CPU0_G0_CPU1_G2_TX_DN<0>")
	)
	(segment
		(start 114.684048 -241.971576)
		(end 114.766852 -242.05438)
		(width 0.1143)
		(layer "In13.Cu")
		(net "GMI_CPU0_G0_CPU1_G2_TX_DN<0>")
	)
	(segment
		(start 358.575102 -239.077754)
		(end 358.612948 -239.039654)
		(width 0.1143)
		(layer "In13.Cu")
		(net "GMI_CPU0_G0_CPU1_G2_TX_DN<0>")
	)
	(segment
		(start 113.467642 -239.946942)
		(end 113.506758 -239.969802)
		(width 0.1143)
		(layer "In13.Cu")
		(net "GMI_CPU0_G0_CPU1_G2_TX_DN<0>")
	)
	(segment
		(start 359.183432 -237.341918)
		(end 359.183432 -237.32744)
		(width 0.1143)
		(layer "In13.Cu")
		(net "GMI_CPU0_G0_CPU1_G2_TX_DN<0>")
	)
	(segment
		(start 113.2586 -214.846916)
		(end 113.081054 -214.89289)
		(width 0.14224)
		(layer "In13.Cu")
		(net "GMI_CPU0_G0_CPU1_G2_TX_DN<0>")
	)
	(segment
		(start 115.09375 -211.469478)
		(end 115.139724 -211.64677)
		(width 0.14224)
		(layer "In13.Cu")
		(net "GMI_CPU0_G0_CPU1_G2_TX_DN<0>")
	)
	(segment
		(start 112.997488 -239.136936)
		(end 113.035588 -239.15878)
		(width 0.1143)
		(layer "In13.Cu")
		(net "GMI_CPU0_G0_CPU1_G2_TX_DN<0>")
	)
	(segment
		(start 112.31245 -237.342172)
		(end 112.268 -237.386622)
		(width 0.1143)
		(layer "In13.Cu")
		(net "GMI_CPU0_G0_CPU1_G2_TX_DN<0>")
	)
	(segment
		(start 112.86871 -215.254078)
		(end 112.914684 -215.43137)
		(width 0.14224)
		(layer "In13.Cu")
		(net "GMI_CPU0_G0_CPU1_G2_TX_DN<0>")
	)
	(segment
		(start 357.558848 -240.756186)
		(end 357.560118 -240.755424)
		(width 0.1143)
		(layer "In13.Cu")
		(net "GMI_CPU0_G0_CPU1_G2_TX_DN<0>")
	)
	(segment
		(start 112.524794 -215.83904)
		(end 112.31245 -216.200228)
		(width 0.14224)
		(layer "In13.Cu")
		(net "GMI_CPU0_G0_CPU1_G2_TX_DN<0>")
	)
	(segment
		(start 156.105352 -177.370486)
		(end 115.627404 -210.561428)
		(width 0.14224)
		(layer "In13.Cu")
		(net "GMI_CPU0_G0_CPU1_G2_TX_DN<0>")
	)
	(segment
		(start 358.903524 -215.829642)
		(end 358.725724 -215.78443)
		(width 0.14224)
		(layer "In13.Cu")
		(net "GMI_CPU0_G0_CPU1_G2_TX_DN<0>")
	)
	(segment
		(start 113.470944 -214.48522)
		(end 113.2586 -214.846916)
		(width 0.14224)
		(layer "In13.Cu")
		(net "GMI_CPU0_G0_CPU1_G2_TX_DN<0>")
	)
	(segment
		(start 113.937796 -240.756948)
		(end 113.947194 -240.762282)
		(width 0.1143)
		(layer "In13.Cu")
		(net "GMI_CPU0_G0_CPU1_G2_TX_DN<0>")
	)
	(segment
		(start 114.92738 -212.008466)
		(end 114.749834 -212.05444)
		(width 0.14224)
		(layer "In13.Cu")
		(net "GMI_CPU0_G0_CPU1_G2_TX_DN<0>")
	)
	(segment
		(start 112.31245 -237.327694)
		(end 112.31245 -237.342172)
		(width 0.1143)
		(layer "In13.Cu")
		(net "GMI_CPU0_G0_CPU1_G2_TX_DN<0>")
	)
	(segment
		(start 115.139724 -211.64677)
		(end 114.92738 -212.008466)
		(width 0.14224)
		(layer "In13.Cu")
		(net "GMI_CPU0_G0_CPU1_G2_TX_DN<0>")
	)
	(segment
		(start 114.027204 -213.53907)
		(end 113.81486 -213.900766)
		(width 0.14224)
		(layer "In13.Cu")
		(net "GMI_CPU0_G0_CPU1_G2_TX_DN<0>")
	)
	(segment
		(start 311.802526 -176.184814)
		(end 308.674516 -175.066452)
		(width 0.14224)
		(layer "In13.Cu")
		(net "GMI_CPU0_G0_CPU1_G2_TX_DN<0>")
	)
	(segment
		(start 357.56342 -240.753646)
		(end 357.589836 -240.738406)
		(width 0.1143)
		(layer "In13.Cu")
		(net "GMI_CPU0_G0_CPU1_G2_TX_DN<0>")
	)
	(segment
		(start 358.557068 -215.246458)
		(end 358.3432 -214.886286)
		(width 0.14224)
		(layer "In13.Cu")
		(net "GMI_CPU0_G0_CPU1_G2_TX_DN<0>")
	)
	(segment
		(start 113.93424 -240.754916)
		(end 113.935764 -240.755678)
		(width 0.1143)
		(layer "In13.Cu")
		(net "GMI_CPU0_G0_CPU1_G2_TX_DN<0>")
	)
	(segment
		(start 114.766852 -242.05438)
		(end 115.064794 -242.05438)
		(width 0.1143)
		(layer "In13.Cu")
		(net "GMI_CPU0_G0_CPU1_G2_TX_DN<0>")
	)
	(segment
		(start 114.583464 -212.59292)
		(end 114.37112 -212.954616)
		(width 0.14224)
		(layer "In13.Cu")
		(net "GMI_CPU0_G0_CPU1_G2_TX_DN<0>")
	)
	(segment
		(start 113.937034 -240.75644)
		(end 113.937796 -240.756948)
		(width 0.1143)
		(layer "In13.Cu")
		(net "GMI_CPU0_G0_CPU1_G2_TX_DN<0>")
	)
	(segment
		(start 113.98123 -213.361778)
		(end 114.027204 -213.53907)
		(width 0.14224)
		(layer "In13.Cu")
		(net "GMI_CPU0_G0_CPU1_G2_TX_DN<0>")
	)
	(segment
		(start 357.560118 -240.755424)
		(end 357.561642 -240.754662)
		(width 0.1143)
		(layer "In13.Cu")
		(net "GMI_CPU0_G0_CPU1_G2_TX_DN<0>")
	)
	(segment
		(start 357.562404 -240.754154)
		(end 357.56342 -240.753646)
		(width 0.1143)
		(layer "In13.Cu")
		(net "GMI_CPU0_G0_CPU1_G2_TX_DN<0>")
	)
	(segment
		(start 357.605076 -213.89721)
		(end 357.391208 -213.536784)
		(width 0.14224)
		(layer "In13.Cu")
		(net "GMI_CPU0_G0_CPU1_G2_TX_DN<0>")
	)
	(segment
		(start 113.42497 -214.307928)
		(end 113.470944 -214.48522)
		(width 0.14224)
		(layer "In13.Cu")
		(net "GMI_CPU0_G0_CPU1_G2_TX_DN<0>")
	)
	(segment
		(start 356.431088 -242.054126)
		(end 356.72903 -242.054126)
		(width 0.1143)
		(layer "In13.Cu")
		(net "GMI_CPU0_G0_CPU1_G2_TX_DN<0>")
	)
	(segment
		(start 112.914684 -215.43137)
		(end 112.70234 -215.793066)
		(width 0.14224)
		(layer "In13.Cu")
		(net "GMI_CPU0_G0_CPU1_G2_TX_DN<0>")
	)
	(segment
		(start 359.227882 -237.555278)
		(end 359.227882 -237.386368)
		(width 0.1143)
		(layer "In13.Cu")
		(net "GMI_CPU0_G0_CPU1_G2_TX_DN<0>")
	)
	(segment
		(start 359.183432 -216.300812)
		(end 358.903524 -215.829642)
		(width 0.14224)
		(layer "In13.Cu")
		(net "GMI_CPU0_G0_CPU1_G2_TX_DN<0>")
	)
	(segment
		(start 112.268 -237.386622)
		(end 112.268 -237.555532)
		(width 0.1143)
		(layer "In13.Cu")
		(net "GMI_CPU0_G0_CPU1_G2_TX_DN<0>")
	)
	(segment
		(start 112.70234 -215.793066)
		(end 112.524794 -215.83904)
		(width 0.14224)
		(layer "In13.Cu")
		(net "GMI_CPU0_G0_CPU1_G2_TX_DN<0>")
	)
	(segment
		(start 113.906046 -240.73866)
		(end 113.93424 -240.754916)
		(width 0.1143)
		(layer "In13.Cu")
		(net "GMI_CPU0_G0_CPU1_G2_TX_DN<0>")
	)
	(segment
		(start 302.919384 -175.066452)
		(end 164.808408 -174.258224)
		(width 0.14224)
		(layer "In13.Cu")
		(net "GMI_CPU0_G0_CPU1_G2_TX_DN<0>")
	)
	(segment
		(start 114.228626 -241.251232)
		(end 114.228626 -241.257074)
		(width 0.1143)
		(layer "In13.Cu")
		(net "GMI_CPU0_G0_CPU1_G2_TX_DN<0>")
	)
	(segment
		(start 113.81486 -213.900766)
		(end 113.637314 -213.94674)
		(width 0.14224)
		(layer "In13.Cu")
		(net "GMI_CPU0_G0_CPU1_G2_TX_DN<0>")
	)
	(segment
		(start 112.31245 -216.200228)
		(end 112.31245 -237.327694)
		(width 0.14224)
		(layer "In13.Cu")
		(net "GMI_CPU0_G0_CPU1_G2_TX_DN<0>")
	)
	(segment
		(start 357.43642 -213.359238)
		(end 355.780594 -210.56981)
		(width 0.14224)
		(layer "In13.Cu")
		(net "GMI_CPU0_G0_CPU1_G2_TX_DN<0>")
	)
	(segment
		(start 355.780594 -210.56981)
		(end 318.403732 -179.921662)
		(width 0.14224)
		(layer "In13.Cu")
		(net "GMI_CPU0_G0_CPU1_G2_TX_DN<0>")
	)
	(segment
		(start 357.989124 -239.969548)
		(end 358.05872 -239.928908)
		(width 0.1143)
		(layer "In13.Cu")
		(net "GMI_CPU0_G0_CPU1_G2_TX_DN<0>")
	)
	(arc
		(start 357.745792 -240.434114)
		(mid 357.810307 -240.171895)
		(end 357.989124 -239.969548)
		(width 0.1143)
		(layer "In13.Cu")
		(net "GMI_CPU0_G0_CPU1_G2_TX_DN<0>")
	)
	(arc
		(start 113.28019 -239.624362)
		(mid 113.321739 -239.795784)
		(end 113.437162 -239.929162)
		(width 0.1143)
		(layer "In13.Cu")
		(net "GMI_CPU0_G0_CPU1_G2_TX_DN<0>")
	)
	(arc
		(start 113.947194 -240.762282)
		(mid 114.153262 -240.969145)
		(end 114.228626 -241.251232)
		(width 0.1143)
		(layer "In13.Cu")
		(net "GMI_CPU0_G0_CPU1_G2_TX_DN<0>")
	)
	(arc
		(start 356.815644 -241.948462)
		(mid 356.897077 -241.746064)
		(end 357.04907 -241.58956)
		(width 0.1143)
		(layer "In13.Cu")
		(net "GMI_CPU0_G0_CPU1_G2_TX_DN<0>")
	)
	(arc
		(start 114.228626 -241.257074)
		(mid 114.276615 -241.43602)
		(end 114.407696 -241.566954)
		(width 0.1143)
		(layer "In13.Cu")
		(net "GMI_CPU0_G0_CPU1_G2_TX_DN<0>")
	)
	(arc
		(start 112.268 -237.555532)
		(mid 112.427853 -238.358878)
		(end 112.882934 -239.039908)
		(width 0.1143)
		(layer "In13.Cu")
		(net "GMI_CPU0_G0_CPU1_G2_TX_DN<0>")
	)
	(arc
		(start 358.612948 -239.039654)
		(mid 359.067978 -238.358603)
		(end 359.227882 -237.555278)
		(width 0.1143)
		(layer "In13.Cu")
		(net "GMI_CPU0_G0_CPU1_G2_TX_DN<0>")
	)
	(arc
		(start 112.92078 -239.078008)
		(mid 112.95722 -239.109963)
		(end 112.997488 -239.136936)
		(width 0.1143)
		(layer "In13.Cu")
		(net "GMI_CPU0_G0_CPU1_G2_TX_DN<0>")
	)
	(arc
		(start 356.811834 -241.971322)
		(mid 356.813622 -241.959873)
		(end 356.815644 -241.948462)
		(width 0.1143)
		(layer "In13.Cu")
		(net "GMI_CPU0_G0_CPU1_G2_TX_DN<0>")
	)
	(arc
		(start 113.506758 -239.969802)
		(mid 113.685571 -240.172152)
		(end 113.75009 -240.434368)
		(width 0.1143)
		(layer "In13.Cu")
		(net "GMI_CPU0_G0_CPU1_G2_TX_DN<0>")
	)
	(arc
		(start 358.215692 -239.624108)
		(mid 358.280564 -239.361145)
		(end 358.460294 -239.158526)
		(width 0.1143)
		(layer "In13.Cu")
		(net "GMI_CPU0_G0_CPU1_G2_TX_DN<0>")
	)
	(arc
		(start 357.589836 -240.738406)
		(mid 357.704512 -240.605072)
		(end 357.745792 -240.434114)
		(width 0.1143)
		(layer "In13.Cu")
		(net "GMI_CPU0_G0_CPU1_G2_TX_DN<0>")
	)
	(arc
		(start 114.680238 -241.948716)
		(mid 114.682261 -241.960126)
		(end 114.684048 -241.971576)
		(width 0.1143)
		(layer "In13.Cu")
		(net "GMI_CPU0_G0_CPU1_G2_TX_DN<0>")
	)
	(arc
		(start 357.267256 -241.250978)
		(mid 357.342643 -240.968905)
		(end 357.548688 -240.762028)
		(width 0.1143)
		(layer "In13.Cu")
		(net "GMI_CPU0_G0_CPU1_G2_TX_DN<0>")
	)
	(arc
		(start 113.75009 -240.434368)
		(mid 113.791345 -240.605339)
		(end 113.906046 -240.73866)
		(width 0.1143)
		(layer "In13.Cu")
		(net "GMI_CPU0_G0_CPU1_G2_TX_DN<0>")
	)
	(arc
		(start 358.05872 -239.928908)
		(mid 358.174147 -239.795532)
		(end 358.215692 -239.624108)
		(width 0.1143)
		(layer "In13.Cu")
		(net "GMI_CPU0_G0_CPU1_G2_TX_DN<0>")
	)
	(arc
		(start 113.035588 -239.15878)
		(mid 113.215317 -239.3614)
		(end 113.28019 -239.624362)
		(width 0.1143)
		(layer "In13.Cu")
		(net "GMI_CPU0_G0_CPU1_G2_TX_DN<0>")
	)
	(arc
		(start 114.446812 -241.589814)
		(mid 114.598799 -241.746322)
		(end 114.680238 -241.948716)
		(width 0.1143)
		(layer "In13.Cu")
		(net "GMI_CPU0_G0_CPU1_G2_TX_DN<0>")
	)
	(arc
		(start 358.498394 -239.136682)
		(mid 358.538671 -239.10972)
		(end 358.575102 -239.077754)
		(width 0.1143)
		(layer "In13.Cu")
		(net "GMI_CPU0_G0_CPU1_G2_TX_DN<0>")
	)
	(arc
		(start 357.088186 -241.5667)
		(mid 357.219279 -241.435773)
		(end 357.267256 -241.25682)
		(width 0.1143)
		(layer "In13.Cu")
		(net "GMI_CPU0_G0_CPU1_G2_TX_DN<0>")
	)
	(segment
		(start 156.769816 -117.182392)
		(end 158.1912 -117.182392)
		(width 0.10668)
		(layer "F.Cu")
		(net "FM_UV_ADR_TRIGGER_N")
	)
	(segment
		(start 160.017714 -117.182392)
		(end 160.041336 -117.206014)
		(width 0.10668)
		(layer "F.Cu")
		(net "FM_UV_ADR_TRIGGER_N")
	)
	(segment
		(start 166.73195 -109.184948)
		(end 163.742116 -109.184948)
		(width 0.10668)
		(layer "F.Cu")
		(net "FM_UV_ADR_TRIGGER_N")
	)
	(segment
		(start 150.820374 -115.133374)
		(end 150.820374 -115.377468)
		(width 0.10668)
		(layer "F.Cu")
		(net "FM_UV_ADR_TRIGGER_N")
	)
	(segment
		(start 152.4 -115.377468)
		(end 153.512266 -116.489734)
		(width 0.10668)
		(layer "F.Cu")
		(net "FM_UV_ADR_TRIGGER_N")
	)
	(segment
		(start 149.611842 -114.808)
		(end 150.495 -114.808)
		(width 0.10668)
		(layer "F.Cu")
		(net "FM_UV_ADR_TRIGGER_N")
	)
	(segment
		(start 149.042374 -115.377468)
		(end 149.611842 -114.808)
		(width 0.10668)
		(layer "F.Cu")
		(net "FM_UV_ADR_TRIGGER_N")
	)
	(segment
		(start 155.855924 -117.182392)
		(end 156.769816 -117.182392)
		(width 0.10668)
		(layer "F.Cu")
		(net "FM_UV_ADR_TRIGGER_N")
	)
	(segment
		(start 150.495 -114.808)
		(end 150.820374 -115.133374)
		(width 0.10668)
		(layer "F.Cu")
		(net "FM_UV_ADR_TRIGGER_N")
	)
	(segment
		(start 155.163266 -116.489734)
		(end 155.855924 -117.182392)
		(width 0.10668)
		(layer "F.Cu")
		(net "FM_UV_ADR_TRIGGER_N")
	)
	(segment
		(start 158.1912 -117.182392)
		(end 160.017714 -117.182392)
		(width 0.10668)
		(layer "F.Cu")
		(net "FM_UV_ADR_TRIGGER_N")
	)
	(segment
		(start 163.742116 -109.184948)
		(end 163.171124 -108.613956)
		(width 0.10668)
		(layer "F.Cu")
		(net "FM_UV_ADR_TRIGGER_N")
	)
	(segment
		(start 153.512266 -116.489734)
		(end 155.163266 -116.489734)
		(width 0.10668)
		(layer "F.Cu")
		(net "FM_UV_ADR_TRIGGER_N")
	)
	(segment
		(start 150.820374 -115.377468)
		(end 152.4 -115.377468)
		(width 0.10668)
		(layer "F.Cu")
		(net "FM_UV_ADR_TRIGGER_N")
	)
	(via
		(at 158.1912 -117.182392)
		(size 0.508)
		(drill 0.254)
		(layers "F.Cu" "B.Cu")
		(net "FM_UV_ADR_TRIGGER_N")
	)
	(via
		(at 163.171124 -108.613956)
		(size 0.508)
		(drill 0.254)
		(layers "F.Cu" "B.Cu")
		(net "FM_UV_ADR_TRIGGER_N")
	)
	(segment
		(start 163.171124 -112.420908)
		(end 163.171124 -108.613956)
		(width 0.11684)
		(layer "In6.Cu")
		(net "FM_UV_ADR_TRIGGER_N")
	)
	(segment
		(start 160.420812 -113.149888)
		(end 162.442144 -113.149888)
		(width 0.11684)
		(layer "In6.Cu")
		(net "FM_UV_ADR_TRIGGER_N")
	)
	(segment
		(start 158.1912 -117.182392)
		(end 158.1912 -115.3795)
		(width 0.11684)
		(layer "In6.Cu")
		(net "FM_UV_ADR_TRIGGER_N")
	)
	(segment
		(start 162.442144 -113.149888)
		(end 163.171124 -112.420908)
		(width 0.11684)
		(layer "In6.Cu")
		(net "FM_UV_ADR_TRIGGER_N")
	)
	(segment
		(start 158.1912 -115.3795)
		(end 160.420812 -113.149888)
		(width 0.11684)
		(layer "In6.Cu")
		(net "FM_UV_ADR_TRIGGER_N")
	)
	(segment
		(start 204.145642 -111.665512)
		(end 204.554836 -111.665512)
		(width 0.10668)
		(layer "F.Cu")
		(net "FM_UART_LS_EN")
	)
	(segment
		(start 203.824586 -111.986568)
		(end 204.145642 -111.665512)
		(width 0.10668)
		(layer "F.Cu")
		(net "FM_UART_LS_EN")
	)
	(segment
		(start 189.92215 -111.452914)
		(end 190.31204 -111.063024)
		(width 0.10668)
		(layer "F.Cu")
		(net "FM_UART_LS_EN")
	)
	(segment
		(start 203.824586 -112.577372)
		(end 203.824586 -111.986568)
		(width 0.10668)
		(layer "F.Cu")
		(net "FM_UART_LS_EN")
	)
	(via
		(at 203.824586 -112.577372)
		(size 0.508)
		(drill 0.254)
		(layers "F.Cu" "B.Cu")
		(net "FM_UART_LS_EN")
	)
	(via
		(at 190.31204 -111.063024)
		(size 0.4572)
		(drill 0.254)
		(layers "F.Cu" "B.Cu")
		(net "FM_UART_LS_EN")
	)
	(segment
		(start 203.344272 -112.097058)
		(end 203.824586 -112.577372)
		(width 0.11684)
		(layer "In6.Cu")
		(net "FM_UART_LS_EN")
	)
	(segment
		(start 190.31204 -111.063024)
		(end 190.72352 -110.651544)
		(width 0.11684)
		(layer "In6.Cu")
		(net "FM_UART_LS_EN")
	)
	(segment
		(start 196.622162 -111.601758)
		(end 201.190098 -111.601758)
		(width 0.11684)
		(layer "In6.Cu")
		(net "FM_UART_LS_EN")
	)
	(segment
		(start 201.190098 -111.601758)
		(end 201.685398 -112.097058)
		(width 0.11684)
		(layer "In6.Cu")
		(net "FM_UART_LS_EN")
	)
	(segment
		(start 194.400678 -111.822484)
		(end 196.401436 -111.822484)
		(width 0.11684)
		(layer "In6.Cu")
		(net "FM_UART_LS_EN")
	)
	(segment
		(start 190.72352 -110.651544)
		(end 193.229738 -110.651544)
		(width 0.11684)
		(layer "In6.Cu")
		(net "FM_UART_LS_EN")
	)
	(segment
		(start 196.401436 -111.822484)
		(end 196.622162 -111.601758)
		(width 0.11684)
		(layer "In6.Cu")
		(net "FM_UART_LS_EN")
	)
	(segment
		(start 201.685398 -112.097058)
		(end 203.344272 -112.097058)
		(width 0.11684)
		(layer "In6.Cu")
		(net "FM_UART_LS_EN")
	)
	(segment
		(start 193.229738 -110.651544)
		(end 194.400678 -111.822484)
		(width 0.11684)
		(layer "In6.Cu")
		(net "FM_UART_LS_EN")
	)
	(segment
		(start 358.297988 -410.875988)
		(end 358.297988 -410.718)
		(width 0.10668)
		(layer "F.Cu")
		(net "FM_UART_EN")
	)
	(segment
		(start 359.059988 -412.909258)
		(end 359.059988 -411.637988)
		(width 0.10668)
		(layer "F.Cu")
		(net "FM_UART_EN")
	)
	(segment
		(start 359.059988 -411.637988)
		(end 358.297988 -410.875988)
		(width 0.10668)
		(layer "F.Cu")
		(net "FM_UART_EN")
	)
	(segment
		(start 358.297988 -410.718)
		(end 358.297988 -409.788868)
		(width 0.10668)
		(layer "F.Cu")
		(net "FM_UART_EN")
	)
	(via
		(at 358.297988 -410.718)
		(size 0.762)
		(drill 0.381)
		(layers "F.Cu" "B.Cu")
		(net "FM_UART_EN")
	)
	(segment
		(start 140.54709 -12.486132)
		(end 140.627354 -12.405868)
		(width 0.10668)
		(layer "F.Cu")
		(net "FM_UARTSW_MSB_R")
	)
	(segment
		(start 140.54709 -13.599922)
		(end 140.54709 -12.486132)
		(width 0.10668)
		(layer "F.Cu")
		(net "FM_UARTSW_MSB_R")
	)
	(via
		(at 140.627354 -12.405868)
		(size 0.508)
		(drill 0.254)
		(layers "F.Cu" "B.Cu")
		(net "FM_UARTSW_MSB_R")
	)
	(segment
		(start 140.61948 -9.483598)
		(end 140.61948 -11.161268)
		(width 0.10668)
		(layer "B.Cu")
		(net "FM_UARTSW_MSB_R")
	)
	(segment
		(start 140.462 -12.240514)
		(end 140.627354 -12.405868)
		(width 0.10668)
		(layer "B.Cu")
		(net "FM_UARTSW_MSB_R")
	)
	(segment
		(start 140.61948 -11.161268)
		(end 140.462 -11.318748)
		(width 0.10668)
		(layer "B.Cu")
		(net "FM_UARTSW_MSB_R")
	)
	(segment
		(start 140.462 -11.318748)
		(end 140.462 -12.240514)
		(width 0.10668)
		(layer "B.Cu")
		(net "FM_UARTSW_MSB_R")
	)
	(segment
		(start 181.122066 -116.252752)
		(end 180.732176 -116.642642)
		(width 0.10668)
		(layer "F.Cu")
		(net "FM_UARTSW_MSB_N")
	)
	(via
		(at 148.111464 -121.09323)
		(size 0.508)
		(drill 0.254)
		(layers "F.Cu" "B.Cu")
		(net "FM_UARTSW_MSB_N")
	)
	(via
		(at 140.61948 -7.886192)
		(size 0.508)
		(drill 0.254)
		(layers "F.Cu" "B.Cu")
		(net "FM_UARTSW_MSB_N")
	)
	(via
		(at 180.732176 -116.642642)
		(size 0.4572)
		(drill 0.254)
		(layers "F.Cu" "B.Cu")
		(net "FM_UARTSW_MSB_N")
	)
	(segment
		(start 140.61948 -8.683498)
		(end 140.61948 -7.886192)
		(width 0.10668)
		(layer "B.Cu")
		(net "FM_UARTSW_MSB_N")
	)
	(segment
		(start 180.732176 -116.642642)
		(end 180.328062 -116.238528)
		(width 0.11684)
		(layer "In2.Cu")
		(net "FM_UARTSW_MSB_N")
	)
	(segment
		(start 163.661598 -118.53926)
		(end 160.37814 -118.53926)
		(width 0.11684)
		(layer "In2.Cu")
		(net "FM_UARTSW_MSB_N")
	)
	(segment
		(start 167.454072 -117.797326)
		(end 166.137336 -119.114062)
		(width 0.11684)
		(layer "In2.Cu")
		(net "FM_UARTSW_MSB_N")
	)
	(segment
		(start 150.04542 -122.37974)
		(end 149.0091 -122.37974)
		(width 0.11684)
		(layer "In2.Cu")
		(net "FM_UARTSW_MSB_N")
	)
	(segment
		(start 160.37814 -118.53926)
		(end 157.22346 -121.69394)
		(width 0.11684)
		(layer "In2.Cu")
		(net "FM_UARTSW_MSB_N")
	)
	(segment
		(start 149.0091 -122.37974)
		(end 148.111464 -121.482104)
		(width 0.11684)
		(layer "In2.Cu")
		(net "FM_UARTSW_MSB_N")
	)
	(segment
		(start 180.328062 -116.238528)
		(end 172.517308 -116.238528)
		(width 0.11684)
		(layer "In2.Cu")
		(net "FM_UARTSW_MSB_N")
	)
	(segment
		(start 164.2364 -119.114062)
		(end 163.661598 -118.53926)
		(width 0.11684)
		(layer "In2.Cu")
		(net "FM_UARTSW_MSB_N")
	)
	(segment
		(start 168.550844 -117.797326)
		(end 167.454072 -117.797326)
		(width 0.11684)
		(layer "In2.Cu")
		(net "FM_UARTSW_MSB_N")
	)
	(segment
		(start 148.111464 -121.482104)
		(end 148.111464 -121.09323)
		(width 0.11684)
		(layer "In2.Cu")
		(net "FM_UARTSW_MSB_N")
	)
	(segment
		(start 169.674032 -117.748812)
		(end 169.4053 -118.017544)
		(width 0.11684)
		(layer "In2.Cu")
		(net "FM_UARTSW_MSB_N")
	)
	(segment
		(start 157.22346 -121.69394)
		(end 150.73122 -121.69394)
		(width 0.11684)
		(layer "In2.Cu")
		(net "FM_UARTSW_MSB_N")
	)
	(segment
		(start 172.517308 -116.238528)
		(end 171.007024 -117.748812)
		(width 0.11684)
		(layer "In2.Cu")
		(net "FM_UARTSW_MSB_N")
	)
	(segment
		(start 150.73122 -121.69394)
		(end 150.04542 -122.37974)
		(width 0.11684)
		(layer "In2.Cu")
		(net "FM_UARTSW_MSB_N")
	)
	(segment
		(start 168.771062 -118.017544)
		(end 168.550844 -117.797326)
		(width 0.11684)
		(layer "In2.Cu")
		(net "FM_UARTSW_MSB_N")
	)
	(segment
		(start 169.4053 -118.017544)
		(end 168.771062 -118.017544)
		(width 0.11684)
		(layer "In2.Cu")
		(net "FM_UARTSW_MSB_N")
	)
	(segment
		(start 171.007024 -117.748812)
		(end 169.674032 -117.748812)
		(width 0.11684)
		(layer "In2.Cu")
		(net "FM_UARTSW_MSB_N")
	)
	(segment
		(start 166.137336 -119.114062)
		(end 164.2364 -119.114062)
		(width 0.11684)
		(layer "In2.Cu")
		(net "FM_UARTSW_MSB_N")
	)
	(segment
		(start 117.294406 -49.708054)
		(end 107.112054 -49.708054)
		(width 0.11684)
		(layer "In4.Cu")
		(net "FM_UARTSW_MSB_N")
	)
	(segment
		(start 118.0338 -28.0924)
		(end 118.0338 -38.8874)
		(width 0.11684)
		(layer "In4.Cu")
		(net "FM_UARTSW_MSB_N")
	)
	(segment
		(start 119.468392 -91.612974)
		(end 134.075424 -106.220006)
		(width 0.11684)
		(layer "In4.Cu")
		(net "FM_UARTSW_MSB_N")
	)
	(segment
		(start 108.977176 -76.547726)
		(end 108.977176 -79.954374)
		(width 0.11684)
		(layer "In4.Cu")
		(net "FM_UARTSW_MSB_N")
	)
	(segment
		(start 134.075424 -106.220006)
		(end 135.536178 -106.220006)
		(width 0.11684)
		(layer "In4.Cu")
		(net "FM_UARTSW_MSB_N")
	)
	(segment
		(start 103.17226 -53.647848)
		(end 103.17226 -70.74281)
		(width 0.11684)
		(layer "In4.Cu")
		(net "FM_UARTSW_MSB_N")
	)
	(segment
		(start 111.955834 -82.933032)
		(end 111.955834 -84.9376)
		(width 0.11684)
		(layer "In4.Cu")
		(net "FM_UARTSW_MSB_N")
	)
	(segment
		(start 136.156192 -17.326102)
		(end 130.474974 -23.00732)
		(width 0.11684)
		(layer "In4.Cu")
		(net "FM_UARTSW_MSB_N")
	)
	(segment
		(start 122.451114 -27.2542)
		(end 118.872 -27.2542)
		(width 0.11684)
		(layer "In4.Cu")
		(net "FM_UARTSW_MSB_N")
	)
	(segment
		(start 140.61948 -9.303004)
		(end 138.29919 -11.623294)
		(width 0.11684)
		(layer "In4.Cu")
		(net "FM_UARTSW_MSB_N")
	)
	(segment
		(start 135.536178 -106.220006)
		(end 136.895078 -107.578906)
		(width 0.11684)
		(layer "In4.Cu")
		(net "FM_UARTSW_MSB_N")
	)
	(segment
		(start 111.955834 -84.9376)
		(end 118.631208 -91.612974)
		(width 0.11684)
		(layer "In4.Cu")
		(net "FM_UARTSW_MSB_N")
	)
	(segment
		(start 136.895078 -111.864902)
		(end 146.123406 -121.09323)
		(width 0.11684)
		(layer "In4.Cu")
		(net "FM_UARTSW_MSB_N")
	)
	(segment
		(start 108.977176 -79.954374)
		(end 111.955834 -82.933032)
		(width 0.11684)
		(layer "In4.Cu")
		(net "FM_UARTSW_MSB_N")
	)
	(segment
		(start 120.33123 -46.67123)
		(end 117.294406 -49.708054)
		(width 0.11684)
		(layer "In4.Cu")
		(net "FM_UARTSW_MSB_N")
	)
	(segment
		(start 103.17226 -70.74281)
		(end 108.977176 -76.547726)
		(width 0.11684)
		(layer "In4.Cu")
		(net "FM_UARTSW_MSB_N")
	)
	(segment
		(start 118.0338 -38.8874)
		(end 120.33123 -41.18483)
		(width 0.11684)
		(layer "In4.Cu")
		(net "FM_UARTSW_MSB_N")
	)
	(segment
		(start 146.123406 -121.09323)
		(end 148.111464 -121.09323)
		(width 0.11684)
		(layer "In4.Cu")
		(net "FM_UARTSW_MSB_N")
	)
	(segment
		(start 126.697994 -23.00732)
		(end 122.451114 -27.2542)
		(width 0.11684)
		(layer "In4.Cu")
		(net "FM_UARTSW_MSB_N")
	)
	(segment
		(start 138.29919 -14.805914)
		(end 136.156192 -16.948912)
		(width 0.11684)
		(layer "In4.Cu")
		(net "FM_UARTSW_MSB_N")
	)
	(segment
		(start 130.474974 -23.00732)
		(end 126.697994 -23.00732)
		(width 0.11684)
		(layer "In4.Cu")
		(net "FM_UARTSW_MSB_N")
	)
	(segment
		(start 118.872 -27.2542)
		(end 118.0338 -28.0924)
		(width 0.11684)
		(layer "In4.Cu")
		(net "FM_UARTSW_MSB_N")
	)
	(segment
		(start 118.631208 -91.612974)
		(end 119.468392 -91.612974)
		(width 0.11684)
		(layer "In4.Cu")
		(net "FM_UARTSW_MSB_N")
	)
	(segment
		(start 107.112054 -49.708054)
		(end 103.17226 -53.647848)
		(width 0.11684)
		(layer "In4.Cu")
		(net "FM_UARTSW_MSB_N")
	)
	(segment
		(start 136.156192 -16.948912)
		(end 136.156192 -17.326102)
		(width 0.11684)
		(layer "In4.Cu")
		(net "FM_UARTSW_MSB_N")
	)
	(segment
		(start 120.33123 -41.18483)
		(end 120.33123 -46.67123)
		(width 0.11684)
		(layer "In4.Cu")
		(net "FM_UARTSW_MSB_N")
	)
	(segment
		(start 138.29919 -11.623294)
		(end 138.29919 -14.805914)
		(width 0.11684)
		(layer "In4.Cu")
		(net "FM_UARTSW_MSB_N")
	)
	(segment
		(start 136.895078 -107.578906)
		(end 136.895078 -111.864902)
		(width 0.11684)
		(layer "In4.Cu")
		(net "FM_UARTSW_MSB_N")
	)
	(segment
		(start 140.61948 -7.886192)
		(end 140.61948 -9.303004)
		(width 0.11684)
		(layer "In4.Cu")
		(net "FM_UARTSW_MSB_N")
	)
	(segment
		(start 138.756898 -11.292332)
		(end 138.359134 -10.894568)
		(width 0.10668)
		(layer "F.Cu")
		(net "FM_UARTSW_LSB_R")
	)
	(segment
		(start 138.756898 -13.590016)
		(end 138.756898 -11.292332)
		(width 0.10668)
		(layer "F.Cu")
		(net "FM_UARTSW_LSB_R")
	)
	(segment
		(start 138.746992 -13.599922)
		(end 138.756898 -13.590016)
		(width 0.10668)
		(layer "F.Cu")
		(net "FM_UARTSW_LSB_R")
	)
	(via
		(at 138.359134 -10.894568)
		(size 0.508)
		(drill 0.254)
		(layers "F.Cu" "B.Cu")
		(net "FM_UARTSW_LSB_R")
	)
	(segment
		(start 138.005566 -10.894568)
		(end 138.359134 -10.894568)
		(width 0.10668)
		(layer "B.Cu")
		(net "FM_UARTSW_LSB_R")
	)
	(segment
		(start 136.93648 -9.825482)
		(end 138.005566 -10.894568)
		(width 0.10668)
		(layer "B.Cu")
		(net "FM_UARTSW_LSB_R")
	)
	(segment
		(start 136.93648 -9.432798)
		(end 136.93648 -9.825482)
		(width 0.10668)
		(layer "B.Cu")
		(net "FM_UARTSW_LSB_R")
	)
	(segment
		(start 181.922166 -117.852952)
		(end 181.532276 -118.242842)
		(width 0.10668)
		(layer "F.Cu")
		(net "FM_UARTSW_LSB_N")
	)
	(via
		(at 169.164 -120.356376)
		(size 0.508)
		(drill 0.254)
		(layers "F.Cu" "B.Cu")
		(net "FM_UARTSW_LSB_N")
	)
	(via
		(at 136.93648 -7.96036)
		(size 0.508)
		(drill 0.254)
		(layers "F.Cu" "B.Cu")
		(net "FM_UARTSW_LSB_N")
	)
	(via
		(at 181.532276 -118.242842)
		(size 0.4572)
		(drill 0.254)
		(layers "F.Cu" "B.Cu")
		(net "FM_UARTSW_LSB_N")
	)
	(segment
		(start 136.93648 -8.632698)
		(end 136.93648 -7.96036)
		(width 0.10668)
		(layer "B.Cu")
		(net "FM_UARTSW_LSB_N")
	)
	(segment
		(start 119.419116 -41.695116)
		(end 119.419116 -45.96257)
		(width 0.11684)
		(layer "In4.Cu")
		(net "FM_UARTSW_LSB_N")
	)
	(segment
		(start 106.083354 -48.56226)
		(end 102.53218 -52.113434)
		(width 0.11684)
		(layer "In4.Cu")
		(net "FM_UARTSW_LSB_N")
	)
	(segment
		(start 132.243322 -106.845862)
		(end 135.282178 -106.845862)
		(width 0.11684)
		(layer "In4.Cu")
		(net "FM_UARTSW_LSB_N")
	)
	(segment
		(start 121.757186 -26.5176)
		(end 118.4656 -26.5176)
		(width 0.11684)
		(layer "In4.Cu")
		(net "FM_UARTSW_LSB_N")
	)
	(segment
		(start 119.419116 -45.96257)
		(end 116.819426 -48.56226)
		(width 0.11684)
		(layer "In4.Cu")
		(net "FM_UARTSW_LSB_N")
	)
	(segment
		(start 136.93648 -7.96036)
		(end 136.93648 -8.763508)
		(width 0.11684)
		(layer "In4.Cu")
		(net "FM_UARTSW_LSB_N")
	)
	(segment
		(start 127.14605 -21.128736)
		(end 121.757186 -26.5176)
		(width 0.11684)
		(layer "In4.Cu")
		(net "FM_UARTSW_LSB_N")
	)
	(segment
		(start 164.80028 -120.965468)
		(end 168.554908 -120.965468)
		(width 0.11684)
		(layer "In4.Cu")
		(net "FM_UARTSW_LSB_N")
	)
	(segment
		(start 131.76504 -21.128736)
		(end 127.14605 -21.128736)
		(width 0.11684)
		(layer "In4.Cu")
		(net "FM_UARTSW_LSB_N")
	)
	(segment
		(start 102.53218 -52.113434)
		(end 102.53218 -71.723504)
		(width 0.11684)
		(layer "In4.Cu")
		(net "FM_UARTSW_LSB_N")
	)
	(segment
		(start 117.2972 -27.686)
		(end 117.2972 -39.5732)
		(width 0.11684)
		(layer "In4.Cu")
		(net "FM_UARTSW_LSB_N")
	)
	(segment
		(start 147.148804 -122.763788)
		(end 149.95144 -122.763788)
		(width 0.11684)
		(layer "In4.Cu")
		(net "FM_UARTSW_LSB_N")
	)
	(segment
		(start 135.282178 -106.845862)
		(end 136.337802 -107.901486)
		(width 0.11684)
		(layer "In4.Cu")
		(net "FM_UARTSW_LSB_N")
	)
	(segment
		(start 107.831382 -82.433922)
		(end 132.243322 -106.845862)
		(width 0.11684)
		(layer "In4.Cu")
		(net "FM_UARTSW_LSB_N")
	)
	(segment
		(start 134.459218 -18.434558)
		(end 131.76504 -21.128736)
		(width 0.11684)
		(layer "In4.Cu")
		(net "FM_UARTSW_LSB_N")
	)
	(segment
		(start 136.337802 -111.952786)
		(end 147.148804 -122.763788)
		(width 0.11684)
		(layer "In4.Cu")
		(net "FM_UARTSW_LSB_N")
	)
	(segment
		(start 163.52774 -122.238008)
		(end 164.80028 -120.965468)
		(width 0.11684)
		(layer "In4.Cu")
		(net "FM_UARTSW_LSB_N")
	)
	(segment
		(start 117.2972 -39.5732)
		(end 119.419116 -41.695116)
		(width 0.11684)
		(layer "In4.Cu")
		(net "FM_UARTSW_LSB_N")
	)
	(segment
		(start 102.53218 -71.723504)
		(end 107.831382 -77.022706)
		(width 0.11684)
		(layer "In4.Cu")
		(net "FM_UARTSW_LSB_N")
	)
	(segment
		(start 116.819426 -48.56226)
		(end 106.083354 -48.56226)
		(width 0.11684)
		(layer "In4.Cu")
		(net "FM_UARTSW_LSB_N")
	)
	(segment
		(start 150.47722 -122.238008)
		(end 163.52774 -122.238008)
		(width 0.11684)
		(layer "In4.Cu")
		(net "FM_UARTSW_LSB_N")
	)
	(segment
		(start 168.554908 -120.965468)
		(end 169.164 -120.356376)
		(width 0.11684)
		(layer "In4.Cu")
		(net "FM_UARTSW_LSB_N")
	)
	(segment
		(start 136.93648 -8.763508)
		(end 134.459218 -11.24077)
		(width 0.11684)
		(layer "In4.Cu")
		(net "FM_UARTSW_LSB_N")
	)
	(segment
		(start 149.95144 -122.763788)
		(end 150.47722 -122.238008)
		(width 0.11684)
		(layer "In4.Cu")
		(net "FM_UARTSW_LSB_N")
	)
	(segment
		(start 134.459218 -11.24077)
		(end 134.459218 -18.434558)
		(width 0.11684)
		(layer "In4.Cu")
		(net "FM_UARTSW_LSB_N")
	)
	(segment
		(start 118.4656 -26.5176)
		(end 117.2972 -27.686)
		(width 0.11684)
		(layer "In4.Cu")
		(net "FM_UARTSW_LSB_N")
	)
	(segment
		(start 136.337802 -107.901486)
		(end 136.337802 -111.952786)
		(width 0.11684)
		(layer "In4.Cu")
		(net "FM_UARTSW_LSB_N")
	)
	(segment
		(start 107.831382 -77.022706)
		(end 107.831382 -82.433922)
		(width 0.11684)
		(layer "In4.Cu")
		(net "FM_UARTSW_LSB_N")
	)
	(segment
		(start 175.026574 -118.631462)
		(end 181.143656 -118.631462)
		(width 0.11684)
		(layer "In6.Cu")
		(net "FM_UARTSW_LSB_N")
	)
	(segment
		(start 172.537374 -119.848376)
		(end 172.544994 -119.840756)
		(width 0.11684)
		(layer "In6.Cu")
		(net "FM_UARTSW_LSB_N")
	)
	(segment
		(start 172.979842 -119.848376)
		(end 173.80966 -119.848376)
		(width 0.11684)
		(layer "In6.Cu")
		(net "FM_UARTSW_LSB_N")
	)
	(segment
		(start 172.504608 -119.848376)
		(end 172.537374 -119.848376)
		(width 0.11684)
		(layer "In6.Cu")
		(net "FM_UARTSW_LSB_N")
	)
	(segment
		(start 173.80966 -119.848376)
		(end 175.026574 -118.631462)
		(width 0.11684)
		(layer "In6.Cu")
		(net "FM_UARTSW_LSB_N")
	)
	(segment
		(start 181.143656 -118.631462)
		(end 181.532276 -118.242842)
		(width 0.11684)
		(layer "In6.Cu")
		(net "FM_UARTSW_LSB_N")
	)
	(segment
		(start 172.544994 -119.840756)
		(end 172.972222 -119.840756)
		(width 0.11684)
		(layer "In6.Cu")
		(net "FM_UARTSW_LSB_N")
	)
	(segment
		(start 171.996608 -120.356376)
		(end 172.504608 -119.848376)
		(width 0.11684)
		(layer "In6.Cu")
		(net "FM_UARTSW_LSB_N")
	)
	(segment
		(start 169.164 -120.356376)
		(end 171.996608 -120.356376)
		(width 0.11684)
		(layer "In6.Cu")
		(net "FM_UARTSW_LSB_N")
	)
	(segment
		(start 172.972222 -119.840756)
		(end 172.979842 -119.848376)
		(width 0.11684)
		(layer "In6.Cu")
		(net "FM_UARTSW_LSB_N")
	)
	(segment
		(start 180.32222 -114.652806)
		(end 179.93233 -114.262916)
		(width 0.10668)
		(layer "F.Cu")
		(net "FM_SYS_THROTTLE_R_N")
	)
	(via
		(at 179.93233 -114.262916)
		(size 0.4572)
		(drill 0.254)
		(layers "F.Cu" "B.Cu")
		(net "FM_SYS_THROTTLE_R_N")
	)
	(via
		(at 174.255176 -114.37747)
		(size 0.6604)
		(drill 0.3302)
		(layers "F.Cu" "B.Cu")
		(net "FM_SYS_THROTTLE_R_N")
	)
	(segment
		(start 172.087032 -114.37747)
		(end 171.59605 -114.868452)
		(width 0.10668)
		(layer "B.Cu")
		(net "FM_SYS_THROTTLE_R_N")
	)
	(segment
		(start 174.536862 -114.659156)
		(end 174.255176 -114.37747)
		(width 0.10668)
		(layer "B.Cu")
		(net "FM_SYS_THROTTLE_R_N")
	)
	(segment
		(start 174.255176 -114.37747)
		(end 172.087032 -114.37747)
		(width 0.10668)
		(layer "B.Cu")
		(net "FM_SYS_THROTTLE_R_N")
	)
	(segment
		(start 179.93233 -114.262916)
		(end 179.53609 -114.659156)
		(width 0.10668)
		(layer "B.Cu")
		(net "FM_SYS_THROTTLE_R_N")
	)
	(segment
		(start 179.53609 -114.659156)
		(end 174.536862 -114.659156)
		(width 0.10668)
		(layer "B.Cu")
		(net "FM_SYS_THROTTLE_R_N")
	)
	(segment
		(start 171.59605 -114.868452)
		(end 171.59605 -115.280948)
		(width 0.10668)
		(layer "B.Cu")
		(net "FM_SYS_THROTTLE_R_N")
	)
	(segment
		(start 252.140212 -107.855004)
		(end 251.00026 -107.855004)
		(width 0.10668)
		(layer "F.Cu")
		(net "FM_SYS_THROTTLE_N")
	)
	(segment
		(start 367.124488 -14.394942)
		(end 367.509552 -14.394942)
		(width 0.10668)
		(layer "F.Cu")
		(net "FM_SYS_THROTTLE_N")
	)
	(segment
		(start 368.087148 -15.512034)
		(end 372.536974 -19.96186)
		(width 0.10668)
		(layer "F.Cu")
		(net "FM_SYS_THROTTLE_N")
	)
	(segment
		(start 367.509552 -14.394942)
		(end 368.087148 -14.972538)
		(width 0.10668)
		(layer "F.Cu")
		(net "FM_SYS_THROTTLE_N")
	)
	(segment
		(start 368.087148 -14.972538)
		(end 368.087148 -15.512034)
		(width 0.10668)
		(layer "F.Cu")
		(net "FM_SYS_THROTTLE_N")
	)
	(via
		(at 161.404046 -114.248438)
		(size 0.508)
		(drill 0.254)
		(layers "F.Cu" "B.Cu")
		(net "FM_SYS_THROTTLE_N")
	)
	(via
		(at 245.434612 -141.410944)
		(size 0.508)
		(drill 0.254)
		(layers "F.Cu" "B.Cu")
		(net "FM_SYS_THROTTLE_N")
	)
	(via
		(at 372.536974 -19.96186)
		(size 0.508)
		(drill 0.254)
		(layers "F.Cu" "B.Cu")
		(net "FM_SYS_THROTTLE_N")
	)
	(via
		(at 251.00026 -107.855004)
		(size 0.508)
		(drill 0.254)
		(layers "F.Cu" "B.Cu")
		(net "FM_SYS_THROTTLE_N")
	)
	(via
		(at 241.5413 -72.304148)
		(size 0.508)
		(drill 0.254)
		(layers "F.Cu" "B.Cu")
		(net "FM_SYS_THROTTLE_N")
	)
	(via
		(at 167.295068 -145.768822)
		(size 0.508)
		(drill 0.254)
		(layers "F.Cu" "B.Cu")
		(net "FM_SYS_THROTTLE_N")
	)
	(segment
		(start 161.351722 -115.816126)
		(end 161.351722 -114.300762)
		(width 0.10668)
		(layer "B.Cu")
		(net "FM_SYS_THROTTLE_N")
	)
	(segment
		(start 161.64433 -116.108734)
		(end 161.351722 -115.816126)
		(width 0.10668)
		(layer "B.Cu")
		(net "FM_SYS_THROTTLE_N")
	)
	(segment
		(start 168.651428 -114.772948)
		(end 170.561254 -114.772948)
		(width 0.10668)
		(layer "B.Cu")
		(net "FM_SYS_THROTTLE_N")
	)
	(segment
		(start 166.483284 -114.73688)
		(end 165.11143 -116.108734)
		(width 0.10668)
		(layer "B.Cu")
		(net "FM_SYS_THROTTLE_N")
	)
	(segment
		(start 167.516302 -115.28552)
		(end 168.138856 -115.28552)
		(width 0.10668)
		(layer "B.Cu")
		(net "FM_SYS_THROTTLE_N")
	)
	(segment
		(start 167.516302 -115.28552)
		(end 167.516302 -114.973608)
		(width 0.10668)
		(layer "B.Cu")
		(net "FM_SYS_THROTTLE_N")
	)
	(segment
		(start 168.138856 -115.28552)
		(end 168.651428 -114.772948)
		(width 0.10668)
		(layer "B.Cu")
		(net "FM_SYS_THROTTLE_N")
	)
	(segment
		(start 170.561254 -114.772948)
		(end 170.79595 -115.007644)
		(width 0.10668)
		(layer "B.Cu")
		(net "FM_SYS_THROTTLE_N")
	)
	(segment
		(start 165.11143 -116.108734)
		(end 161.64433 -116.108734)
		(width 0.10668)
		(layer "B.Cu")
		(net "FM_SYS_THROTTLE_N")
	)
	(segment
		(start 167.516302 -114.973608)
		(end 167.279574 -114.73688)
		(width 0.10668)
		(layer "B.Cu")
		(net "FM_SYS_THROTTLE_N")
	)
	(segment
		(start 170.79595 -115.007644)
		(end 170.79595 -115.280948)
		(width 0.10668)
		(layer "B.Cu")
		(net "FM_SYS_THROTTLE_N")
	)
	(segment
		(start 161.351722 -114.300762)
		(end 161.404046 -114.248438)
		(width 0.10668)
		(layer "B.Cu")
		(net "FM_SYS_THROTTLE_N")
	)
	(segment
		(start 167.279574 -114.73688)
		(end 166.483284 -114.73688)
		(width 0.10668)
		(layer "B.Cu")
		(net "FM_SYS_THROTTLE_N")
	)
	(segment
		(start 192.356994 -140.917422)
		(end 198.33463 -140.917422)
		(width 0.11684)
		(layer "In2.Cu")
		(net "FM_SYS_THROTTLE_N")
	)
	(segment
		(start 198.600822 -141.183614)
		(end 205.543404 -141.183614)
		(width 0.11684)
		(layer "In2.Cu")
		(net "FM_SYS_THROTTLE_N")
	)
	(segment
		(start 205.543404 -141.183614)
		(end 207.390492 -143.030702)
		(width 0.11684)
		(layer "In2.Cu")
		(net "FM_SYS_THROTTLE_N")
	)
	(segment
		(start 243.550948 -142.194788)
		(end 244.334792 -141.410944)
		(width 0.11684)
		(layer "In2.Cu")
		(net "FM_SYS_THROTTLE_N")
	)
	(segment
		(start 180.46065 -144.337278)
		(end 181.643274 -143.154654)
		(width 0.11684)
		(layer "In2.Cu")
		(net "FM_SYS_THROTTLE_N")
	)
	(segment
		(start 190.585852 -142.688564)
		(end 192.356994 -140.917422)
		(width 0.11684)
		(layer "In2.Cu")
		(net "FM_SYS_THROTTLE_N")
	)
	(segment
		(start 181.643274 -143.154654)
		(end 186.139836 -143.154654)
		(width 0.11684)
		(layer "In2.Cu")
		(net "FM_SYS_THROTTLE_N")
	)
	(segment
		(start 186.605926 -142.688564)
		(end 190.585852 -142.688564)
		(width 0.11684)
		(layer "In2.Cu")
		(net "FM_SYS_THROTTLE_N")
	)
	(segment
		(start 238.106204 -142.194788)
		(end 243.550948 -142.194788)
		(width 0.11684)
		(layer "In2.Cu")
		(net "FM_SYS_THROTTLE_N")
	)
	(segment
		(start 167.295068 -145.523458)
		(end 168.481248 -144.337278)
		(width 0.11684)
		(layer "In2.Cu")
		(net "FM_SYS_THROTTLE_N")
	)
	(segment
		(start 198.33463 -140.917422)
		(end 198.600822 -141.183614)
		(width 0.11684)
		(layer "In2.Cu")
		(net "FM_SYS_THROTTLE_N")
	)
	(segment
		(start 168.481248 -144.337278)
		(end 180.46065 -144.337278)
		(width 0.11684)
		(layer "In2.Cu")
		(net "FM_SYS_THROTTLE_N")
	)
	(segment
		(start 237.27029 -143.030702)
		(end 238.106204 -142.194788)
		(width 0.11684)
		(layer "In2.Cu")
		(net "FM_SYS_THROTTLE_N")
	)
	(segment
		(start 167.295068 -145.768822)
		(end 167.295068 -145.523458)
		(width 0.11684)
		(layer "In2.Cu")
		(net "FM_SYS_THROTTLE_N")
	)
	(segment
		(start 244.334792 -141.410944)
		(end 245.434612 -141.410944)
		(width 0.11684)
		(layer "In2.Cu")
		(net "FM_SYS_THROTTLE_N")
	)
	(segment
		(start 186.139836 -143.154654)
		(end 186.605926 -142.688564)
		(width 0.11684)
		(layer "In2.Cu")
		(net "FM_SYS_THROTTLE_N")
	)
	(segment
		(start 207.390492 -143.030702)
		(end 237.27029 -143.030702)
		(width 0.11684)
		(layer "In2.Cu")
		(net "FM_SYS_THROTTLE_N")
	)
	(segment
		(start 246.388128 -112.467136)
		(end 251.00026 -107.855004)
		(width 0.11684)
		(layer "In4.Cu")
		(net "FM_SYS_THROTTLE_N")
	)
	(segment
		(start 245.54815 -141.297406)
		(end 245.54815 -134.021322)
		(width 0.11684)
		(layer "In4.Cu")
		(net "FM_SYS_THROTTLE_N")
	)
	(segment
		(start 245.434612 -141.410944)
		(end 245.54815 -141.297406)
		(width 0.11684)
		(layer "In4.Cu")
		(net "FM_SYS_THROTTLE_N")
	)
	(segment
		(start 246.388128 -133.181344)
		(end 246.388128 -112.467136)
		(width 0.11684)
		(layer "In4.Cu")
		(net "FM_SYS_THROTTLE_N")
	)
	(segment
		(start 245.54815 -134.021322)
		(end 246.388128 -133.181344)
		(width 0.11684)
		(layer "In4.Cu")
		(net "FM_SYS_THROTTLE_N")
	)
	(segment
		(start 292.674802 -43.38574)
		(end 271.690338 -64.370204)
		(width 0.11684)
		(layer "In6.Cu")
		(net "FM_SYS_THROTTLE_N")
	)
	(segment
		(start 266.378944 -64.370204)
		(end 259.400294 -71.348854)
		(width 0.11684)
		(layer "In6.Cu")
		(net "FM_SYS_THROTTLE_N")
	)
	(segment
		(start 325.06539 -33.86074)
		(end 325.06539 -34.674048)
		(width 0.11684)
		(layer "In6.Cu")
		(net "FM_SYS_THROTTLE_N")
	)
	(segment
		(start 372.536974 -20.7772)
		(end 369.100608 -24.213566)
		(width 0.11684)
		(layer "In6.Cu")
		(net "FM_SYS_THROTTLE_N")
	)
	(segment
		(start 325.06539 -34.674048)
		(end 319.381124 -40.358314)
		(width 0.11684)
		(layer "In6.Cu")
		(net "FM_SYS_THROTTLE_N")
	)
	(segment
		(start 345.000834 -27.848306)
		(end 343.111836 -29.737304)
		(width 0.11684)
		(layer "In6.Cu")
		(net "FM_SYS_THROTTLE_N")
	)
	(segment
		(start 357.017574 -24.213566)
		(end 353.382834 -27.848306)
		(width 0.11684)
		(layer "In6.Cu")
		(net "FM_SYS_THROTTLE_N")
	)
	(segment
		(start 304.22596 -44.465748)
		(end 303.145952 -43.38574)
		(width 0.11684)
		(layer "In6.Cu")
		(net "FM_SYS_THROTTLE_N")
	)
	(segment
		(start 343.111836 -29.737304)
		(end 329.188826 -29.737304)
		(width 0.11684)
		(layer "In6.Cu")
		(net "FM_SYS_THROTTLE_N")
	)
	(segment
		(start 372.536974 -19.96186)
		(end 372.536974 -20.7772)
		(width 0.11684)
		(layer "In6.Cu")
		(net "FM_SYS_THROTTLE_N")
	)
	(segment
		(start 319.381124 -40.358314)
		(end 319.381124 -41.140634)
		(width 0.11684)
		(layer "In6.Cu")
		(net "FM_SYS_THROTTLE_N")
	)
	(segment
		(start 316.05601 -44.465748)
		(end 304.22596 -44.465748)
		(width 0.11684)
		(layer "In6.Cu")
		(net "FM_SYS_THROTTLE_N")
	)
	(segment
		(start 319.381124 -41.140634)
		(end 316.05601 -44.465748)
		(width 0.11684)
		(layer "In6.Cu")
		(net "FM_SYS_THROTTLE_N")
	)
	(segment
		(start 329.188826 -29.737304)
		(end 325.06539 -33.86074)
		(width 0.11684)
		(layer "In6.Cu")
		(net "FM_SYS_THROTTLE_N")
	)
	(segment
		(start 258.184142 -71.348854)
		(end 257.228848 -72.304148)
		(width 0.11684)
		(layer "In6.Cu")
		(net "FM_SYS_THROTTLE_N")
	)
	(segment
		(start 271.690338 -64.370204)
		(end 266.378944 -64.370204)
		(width 0.11684)
		(layer "In6.Cu")
		(net "FM_SYS_THROTTLE_N")
	)
	(segment
		(start 369.100608 -24.213566)
		(end 357.017574 -24.213566)
		(width 0.11684)
		(layer "In6.Cu")
		(net "FM_SYS_THROTTLE_N")
	)
	(segment
		(start 259.400294 -71.348854)
		(end 258.184142 -71.348854)
		(width 0.11684)
		(layer "In6.Cu")
		(net "FM_SYS_THROTTLE_N")
	)
	(segment
		(start 257.228848 -72.304148)
		(end 241.5413 -72.304148)
		(width 0.11684)
		(layer "In6.Cu")
		(net "FM_SYS_THROTTLE_N")
	)
	(segment
		(start 353.382834 -27.848306)
		(end 345.000834 -27.848306)
		(width 0.11684)
		(layer "In6.Cu")
		(net "FM_SYS_THROTTLE_N")
	)
	(segment
		(start 303.145952 -43.38574)
		(end 292.674802 -43.38574)
		(width 0.11684)
		(layer "In6.Cu")
		(net "FM_SYS_THROTTLE_N")
	)
	(segment
		(start 250.18746 -97.60204)
		(end 249.68454 -98.10496)
		(width 0.11684)
		(layer "In11.Cu")
		(net "FM_SYS_THROTTLE_N")
	)
	(segment
		(start 250.622308 -89.115392)
		(end 250.18746 -89.55024)
		(width 0.11684)
		(layer "In11.Cu")
		(net "FM_SYS_THROTTLE_N")
	)
	(segment
		(start 250.622308 -88.02878)
		(end 250.622308 -89.115392)
		(width 0.11684)
		(layer "In11.Cu")
		(net "FM_SYS_THROTTLE_N")
	)
	(segment
		(start 250.520708 -87.92718)
		(end 250.622308 -88.02878)
		(width 0.11684)
		(layer "In11.Cu")
		(net "FM_SYS_THROTTLE_N")
	)
	(segment
		(start 241.5413 -72.304148)
		(end 250.520708 -81.283556)
		(width 0.11684)
		(layer "In11.Cu")
		(net "FM_SYS_THROTTLE_N")
	)
	(segment
		(start 250.18746 -89.55024)
		(end 250.18746 -97.60204)
		(width 0.11684)
		(layer "In11.Cu")
		(net "FM_SYS_THROTTLE_N")
	)
	(segment
		(start 250.637548 -107.855004)
		(end 251.00026 -107.855004)
		(width 0.11684)
		(layer "In11.Cu")
		(net "FM_SYS_THROTTLE_N")
	)
	(segment
		(start 249.482356 -100.236782)
		(end 249.482356 -106.699812)
		(width 0.11684)
		(layer "In11.Cu")
		(net "FM_SYS_THROTTLE_N")
	)
	(segment
		(start 249.68454 -100.034598)
		(end 249.482356 -100.236782)
		(width 0.11684)
		(layer "In11.Cu")
		(net "FM_SYS_THROTTLE_N")
	)
	(segment
		(start 249.68454 -98.10496)
		(end 249.68454 -100.034598)
		(width 0.11684)
		(layer "In11.Cu")
		(net "FM_SYS_THROTTLE_N")
	)
	(segment
		(start 250.520708 -81.283556)
		(end 250.520708 -87.92718)
		(width 0.11684)
		(layer "In11.Cu")
		(net "FM_SYS_THROTTLE_N")
	)
	(segment
		(start 249.482356 -106.699812)
		(end 250.637548 -107.855004)
		(width 0.11684)
		(layer "In11.Cu")
		(net "FM_SYS_THROTTLE_N")
	)
	(segment
		(start 165.894766 -141.410944)
		(end 167.22725 -142.743428)
		(width 0.11684)
		(layer "In15.Cu")
		(net "FM_SYS_THROTTLE_N")
	)
	(segment
		(start 159.703008 -129.850642)
		(end 165.894766 -136.0424)
		(width 0.11684)
		(layer "In15.Cu")
		(net "FM_SYS_THROTTLE_N")
	)
	(segment
		(start 161.404046 -114.248438)
		(end 161.364422 -114.288062)
		(width 0.11684)
		(layer "In15.Cu")
		(net "FM_SYS_THROTTLE_N")
	)
	(segment
		(start 161.364422 -115.83035)
		(end 162.044126 -116.510054)
		(width 0.11684)
		(layer "In15.Cu")
		(net "FM_SYS_THROTTLE_N")
	)
	(segment
		(start 159.703008 -123.227592)
		(end 159.703008 -129.850642)
		(width 0.11684)
		(layer "In15.Cu")
		(net "FM_SYS_THROTTLE_N")
	)
	(segment
		(start 165.894766 -136.0424)
		(end 165.894766 -141.410944)
		(width 0.11684)
		(layer "In15.Cu")
		(net "FM_SYS_THROTTLE_N")
	)
	(segment
		(start 167.22725 -142.743428)
		(end 167.22725 -145.701004)
		(width 0.11684)
		(layer "In15.Cu")
		(net "FM_SYS_THROTTLE_N")
	)
	(segment
		(start 162.044126 -116.510054)
		(end 162.044126 -120.886474)
		(width 0.11684)
		(layer "In15.Cu")
		(net "FM_SYS_THROTTLE_N")
	)
	(segment
		(start 167.22725 -145.701004)
		(end 167.295068 -145.768822)
		(width 0.11684)
		(layer "In15.Cu")
		(net "FM_SYS_THROTTLE_N")
	)
	(segment
		(start 162.044126 -120.886474)
		(end 159.703008 -123.227592)
		(width 0.11684)
		(layer "In15.Cu")
		(net "FM_SYS_THROTTLE_N")
	)
	(segment
		(start 161.364422 -114.288062)
		(end 161.364422 -115.83035)
		(width 0.11684)
		(layer "In15.Cu")
		(net "FM_SYS_THROTTLE_N")
	)
	(segment
		(start 41.33596 -433.68595)
		(end 41.33596 -433.04079)
		(width 0.10668)
		(layer "F.Cu")
		(net "FM_SWB_PWR_EN_R_BUF")
	)
	(via
		(at 41.33596 -433.04079)
		(size 0.508)
		(drill 0.254)
		(layers "F.Cu" "B.Cu")
		(net "FM_SWB_PWR_EN_R_BUF")
	)
	(via
		(at 39.137082 -369.825778)
		(size 0.508)
		(drill 0.254)
		(layers "F.Cu" "B.Cu")
		(net "FM_SWB_PWR_EN_R_BUF")
	)
	(via
		(at 287.395412 -377.298458)
		(size 0.508)
		(drill 0.254)
		(layers "F.Cu" "B.Cu")
		(net "FM_SWB_PWR_EN_R_BUF")
	)
	(via
		(at 292.658292 -424.085766)
		(size 0.508)
		(drill 0.254)
		(layers "F.Cu" "B.Cu")
		(net "FM_SWB_PWR_EN_R_BUF")
	)
	(via
		(at 173.8249 -368.023394)
		(size 0.508)
		(drill 0.254)
		(layers "F.Cu" "B.Cu")
		(net "FM_SWB_PWR_EN_R_BUF")
	)
	(segment
		(start 218.2368 -371.940328)
		(end 218.964764 -371.212364)
		(width 0.10668)
		(layer "B.Cu")
		(net "FM_SWB_PWR_EN_R_BUF")
	)
	(segment
		(start 198.529194 -371.323108)
		(end 199.146414 -371.940328)
		(width 0.10668)
		(layer "B.Cu")
		(net "FM_SWB_PWR_EN_R_BUF")
	)
	(segment
		(start 287.395412 -376.225816)
		(end 287.395412 -377.298458)
		(width 0.10668)
		(layer "B.Cu")
		(net "FM_SWB_PWR_EN_R_BUF")
	)
	(segment
		(start 199.146414 -371.940328)
		(end 218.2368 -371.940328)
		(width 0.10668)
		(layer "B.Cu")
		(net "FM_SWB_PWR_EN_R_BUF")
	)
	(segment
		(start 235.497624 -368.59845)
		(end 242.560094 -368.59845)
		(width 0.10668)
		(layer "B.Cu")
		(net "FM_SWB_PWR_EN_R_BUF")
	)
	(segment
		(start 223.223328 -371.940328)
		(end 232.155746 -371.940328)
		(width 0.10668)
		(layer "B.Cu")
		(net "FM_SWB_PWR_EN_R_BUF")
	)
	(segment
		(start 245.901972 -371.940328)
		(end 280.01087 -371.940328)
		(width 0.10668)
		(layer "B.Cu")
		(net "FM_SWB_PWR_EN_R_BUF")
	)
	(segment
		(start 242.560094 -368.59845)
		(end 245.901972 -371.940328)
		(width 0.10668)
		(layer "B.Cu")
		(net "FM_SWB_PWR_EN_R_BUF")
	)
	(segment
		(start 180.49113 -370.633752)
		(end 187.291218 -370.633752)
		(width 0.10668)
		(layer "B.Cu")
		(net "FM_SWB_PWR_EN_R_BUF")
	)
	(segment
		(start 280.01087 -371.940328)
		(end 283.730954 -375.660412)
		(width 0.10668)
		(layer "B.Cu")
		(net "FM_SWB_PWR_EN_R_BUF")
	)
	(segment
		(start 187.980574 -371.323108)
		(end 198.529194 -371.323108)
		(width 0.10668)
		(layer "B.Cu")
		(net "FM_SWB_PWR_EN_R_BUF")
	)
	(segment
		(start 283.730954 -375.660412)
		(end 286.830008 -375.660412)
		(width 0.10668)
		(layer "B.Cu")
		(net "FM_SWB_PWR_EN_R_BUF")
	)
	(segment
		(start 177.880772 -368.023394)
		(end 180.49113 -370.633752)
		(width 0.10668)
		(layer "B.Cu")
		(net "FM_SWB_PWR_EN_R_BUF")
	)
	(segment
		(start 286.830008 -375.660412)
		(end 287.395412 -376.225816)
		(width 0.10668)
		(layer "B.Cu")
		(net "FM_SWB_PWR_EN_R_BUF")
	)
	(segment
		(start 187.291218 -370.633752)
		(end 187.980574 -371.323108)
		(width 0.10668)
		(layer "B.Cu")
		(net "FM_SWB_PWR_EN_R_BUF")
	)
	(segment
		(start 218.964764 -371.212364)
		(end 222.495364 -371.212364)
		(width 0.10668)
		(layer "B.Cu")
		(net "FM_SWB_PWR_EN_R_BUF")
	)
	(segment
		(start 173.8249 -368.023394)
		(end 177.880772 -368.023394)
		(width 0.10668)
		(layer "B.Cu")
		(net "FM_SWB_PWR_EN_R_BUF")
	)
	(segment
		(start 222.495364 -371.212364)
		(end 223.223328 -371.940328)
		(width 0.10668)
		(layer "B.Cu")
		(net "FM_SWB_PWR_EN_R_BUF")
	)
	(segment
		(start 232.155746 -371.940328)
		(end 235.497624 -368.59845)
		(width 0.10668)
		(layer "B.Cu")
		(net "FM_SWB_PWR_EN_R_BUF")
	)
	(segment
		(start 137.369042 -366.910874)
		(end 43.88739 -366.910874)
		(width 0.11684)
		(layer "In2.Cu")
		(net "FM_SWB_PWR_EN_R_BUF")
	)
	(segment
		(start 362.234734 -421.543734)
		(end 358.486964 -421.543734)
		(width 0.11684)
		(layer "In2.Cu")
		(net "FM_SWB_PWR_EN_R_BUF")
	)
	(segment
		(start 304.335942 -422.89349)
		(end 303.474374 -423.755058)
		(width 0.11684)
		(layer "In2.Cu")
		(net "FM_SWB_PWR_EN_R_BUF")
	)
	(segment
		(start 400.750024 -424.689778)
		(end 400.750024 -423.841164)
		(width 0.11684)
		(layer "In2.Cu")
		(net "FM_SWB_PWR_EN_R_BUF")
	)
	(segment
		(start 298.017946 -425.577)
		(end 294.149526 -425.577)
		(width 0.11684)
		(layer "In2.Cu")
		(net "FM_SWB_PWR_EN_R_BUF")
	)
	(segment
		(start 358.486964 -421.543734)
		(end 355.199188 -424.83151)
		(width 0.11684)
		(layer "In2.Cu")
		(net "FM_SWB_PWR_EN_R_BUF")
	)
	(segment
		(start 294.149526 -425.577)
		(end 292.658292 -424.085766)
		(width 0.11684)
		(layer "In2.Cu")
		(net "FM_SWB_PWR_EN_R_BUF")
	)
	(segment
		(start 43.88739 -366.910874)
		(end 40.972486 -369.825778)
		(width 0.11684)
		(layer "In2.Cu")
		(net "FM_SWB_PWR_EN_R_BUF")
	)
	(segment
		(start 301.89805 -423.755058)
		(end 301.676816 -423.533824)
		(width 0.11684)
		(layer "In2.Cu")
		(net "FM_SWB_PWR_EN_R_BUF")
	)
	(segment
		(start 303.474374 -423.755058)
		(end 301.89805 -423.755058)
		(width 0.11684)
		(layer "In2.Cu")
		(net "FM_SWB_PWR_EN_R_BUF")
	)
	(segment
		(start 171.830238 -368.023394)
		(end 169.083228 -365.276384)
		(width 0.11684)
		(layer "In2.Cu")
		(net "FM_SWB_PWR_EN_R_BUF")
	)
	(segment
		(start 139.003532 -365.276384)
		(end 137.369042 -366.910874)
		(width 0.11684)
		(layer "In2.Cu")
		(net "FM_SWB_PWR_EN_R_BUF")
	)
	(segment
		(start 368.949224 -426.78477)
		(end 364.34649 -426.78477)
		(width 0.11684)
		(layer "In2.Cu")
		(net "FM_SWB_PWR_EN_R_BUF")
	)
	(segment
		(start 40.972486 -369.825778)
		(end 39.137082 -369.825778)
		(width 0.11684)
		(layer "In2.Cu")
		(net "FM_SWB_PWR_EN_R_BUF")
	)
	(segment
		(start 376.513598 -422.791128)
		(end 373.29491 -426.009816)
		(width 0.11684)
		(layer "In2.Cu")
		(net "FM_SWB_PWR_EN_R_BUF")
	)
	(segment
		(start 300.061122 -423.533824)
		(end 298.017946 -425.577)
		(width 0.11684)
		(layer "In2.Cu")
		(net "FM_SWB_PWR_EN_R_BUF")
	)
	(segment
		(start 350.10217 -424.83151)
		(end 348.16415 -422.89349)
		(width 0.11684)
		(layer "In2.Cu")
		(net "FM_SWB_PWR_EN_R_BUF")
	)
	(segment
		(start 364.34649 -426.78477)
		(end 363.306868 -425.745148)
		(width 0.11684)
		(layer "In2.Cu")
		(net "FM_SWB_PWR_EN_R_BUF")
	)
	(segment
		(start 370.787676 -426.009816)
		(end 370.174012 -426.62348)
		(width 0.11684)
		(layer "In2.Cu")
		(net "FM_SWB_PWR_EN_R_BUF")
	)
	(segment
		(start 400.750024 -423.841164)
		(end 399.699988 -422.791128)
		(width 0.11684)
		(layer "In2.Cu")
		(net "FM_SWB_PWR_EN_R_BUF")
	)
	(segment
		(start 370.174012 -426.62348)
		(end 369.110514 -426.62348)
		(width 0.11684)
		(layer "In2.Cu")
		(net "FM_SWB_PWR_EN_R_BUF")
	)
	(segment
		(start 169.083228 -365.276384)
		(end 139.003532 -365.276384)
		(width 0.11684)
		(layer "In2.Cu")
		(net "FM_SWB_PWR_EN_R_BUF")
	)
	(segment
		(start 399.699988 -422.791128)
		(end 376.513598 -422.791128)
		(width 0.11684)
		(layer "In2.Cu")
		(net "FM_SWB_PWR_EN_R_BUF")
	)
	(segment
		(start 173.8249 -368.023394)
		(end 171.830238 -368.023394)
		(width 0.11684)
		(layer "In2.Cu")
		(net "FM_SWB_PWR_EN_R_BUF")
	)
	(segment
		(start 363.306868 -425.745148)
		(end 363.306868 -422.615868)
		(width 0.11684)
		(layer "In2.Cu")
		(net "FM_SWB_PWR_EN_R_BUF")
	)
	(segment
		(start 363.306868 -422.615868)
		(end 362.234734 -421.543734)
		(width 0.11684)
		(layer "In2.Cu")
		(net "FM_SWB_PWR_EN_R_BUF")
	)
	(segment
		(start 348.16415 -422.89349)
		(end 304.335942 -422.89349)
		(width 0.11684)
		(layer "In2.Cu")
		(net "FM_SWB_PWR_EN_R_BUF")
	)
	(segment
		(start 373.29491 -426.009816)
		(end 370.787676 -426.009816)
		(width 0.11684)
		(layer "In2.Cu")
		(net "FM_SWB_PWR_EN_R_BUF")
	)
	(segment
		(start 355.199188 -424.83151)
		(end 350.10217 -424.83151)
		(width 0.11684)
		(layer "In2.Cu")
		(net "FM_SWB_PWR_EN_R_BUF")
	)
	(segment
		(start 369.110514 -426.62348)
		(end 368.949224 -426.78477)
		(width 0.11684)
		(layer "In2.Cu")
		(net "FM_SWB_PWR_EN_R_BUF")
	)
	(segment
		(start 301.676816 -423.533824)
		(end 300.061122 -423.533824)
		(width 0.11684)
		(layer "In2.Cu")
		(net "FM_SWB_PWR_EN_R_BUF")
	)
	(segment
		(start 289.493198 -400.734784)
		(end 289.493198 -403.123908)
		(width 0.11684)
		(layer "In4.Cu")
		(net "FM_SWB_PWR_EN_R_BUF")
	)
	(segment
		(start 288.549334 -416.402266)
		(end 288.549334 -418.301678)
		(width 0.11684)
		(layer "In4.Cu")
		(net "FM_SWB_PWR_EN_R_BUF")
	)
	(segment
		(start 295.412922 -387.435344)
		(end 295.412922 -390.891522)
		(width 0.11684)
		(layer "In4.Cu")
		(net "FM_SWB_PWR_EN_R_BUF")
	)
	(segment
		(start 290.240212 -403.870922)
		(end 290.240212 -414.711388)
		(width 0.11684)
		(layer "In4.Cu")
		(net "FM_SWB_PWR_EN_R_BUF")
	)
	(segment
		(start 294.086534 -392.21791)
		(end 294.086534 -393.240006)
		(width 0.11684)
		(layer "In4.Cu")
		(net "FM_SWB_PWR_EN_R_BUF")
	)
	(segment
		(start 289.997134 -379.90018)
		(end 293.331138 -379.90018)
		(width 0.11684)
		(layer "In4.Cu")
		(net "FM_SWB_PWR_EN_R_BUF")
	)
	(segment
		(start 288.549334 -418.301678)
		(end 288.470848 -418.380164)
		(width 0.11684)
		(layer "In4.Cu")
		(net "FM_SWB_PWR_EN_R_BUF")
	)
	(segment
		(start 293.06901 -422.446196)
		(end 293.06901 -423.675048)
		(width 0.11684)
		(layer "In4.Cu")
		(net "FM_SWB_PWR_EN_R_BUF")
	)
	(segment
		(start 292.053772 -394.250672)
		(end 288.492946 -397.811498)
		(width 0.11684)
		(layer "In4.Cu")
		(net "FM_SWB_PWR_EN_R_BUF")
	)
	(segment
		(start 288.549334 -419.245796)
		(end 291.25418 -421.950642)
		(width 0.11684)
		(layer "In4.Cu")
		(net "FM_SWB_PWR_EN_R_BUF")
	)
	(segment
		(start 294.086534 -393.240006)
		(end 293.075868 -394.250672)
		(width 0.11684)
		(layer "In4.Cu")
		(net "FM_SWB_PWR_EN_R_BUF")
	)
	(segment
		(start 290.240212 -414.711388)
		(end 288.549334 -416.402266)
		(width 0.11684)
		(layer "In4.Cu")
		(net "FM_SWB_PWR_EN_R_BUF")
	)
	(segment
		(start 289.63874 -400.005804)
		(end 289.63874 -400.589242)
		(width 0.11684)
		(layer "In4.Cu")
		(net "FM_SWB_PWR_EN_R_BUF")
	)
	(segment
		(start 288.549334 -418.844222)
		(end 288.549334 -419.245796)
		(width 0.11684)
		(layer "In4.Cu")
		(net "FM_SWB_PWR_EN_R_BUF")
	)
	(segment
		(start 287.395412 -377.298458)
		(end 289.997134 -379.90018)
		(width 0.11684)
		(layer "In4.Cu")
		(net "FM_SWB_PWR_EN_R_BUF")
	)
	(segment
		(start 288.470848 -418.380164)
		(end 288.470848 -418.765736)
		(width 0.11684)
		(layer "In4.Cu")
		(net "FM_SWB_PWR_EN_R_BUF")
	)
	(segment
		(start 288.470848 -418.765736)
		(end 288.549334 -418.844222)
		(width 0.11684)
		(layer "In4.Cu")
		(net "FM_SWB_PWR_EN_R_BUF")
	)
	(segment
		(start 292.573456 -421.950642)
		(end 293.06901 -422.446196)
		(width 0.11684)
		(layer "In4.Cu")
		(net "FM_SWB_PWR_EN_R_BUF")
	)
	(segment
		(start 288.492946 -398.86001)
		(end 289.63874 -400.005804)
		(width 0.11684)
		(layer "In4.Cu")
		(net "FM_SWB_PWR_EN_R_BUF")
	)
	(segment
		(start 295.883584 -386.299202)
		(end 295.412922 -387.435344)
		(width 0.11684)
		(layer "In4.Cu")
		(net "FM_SWB_PWR_EN_R_BUF")
	)
	(segment
		(start 293.331138 -379.90018)
		(end 295.883584 -382.452626)
		(width 0.11684)
		(layer "In4.Cu")
		(net "FM_SWB_PWR_EN_R_BUF")
	)
	(segment
		(start 293.075868 -394.250672)
		(end 292.053772 -394.250672)
		(width 0.11684)
		(layer "In4.Cu")
		(net "FM_SWB_PWR_EN_R_BUF")
	)
	(segment
		(start 291.25418 -421.950642)
		(end 292.573456 -421.950642)
		(width 0.11684)
		(layer "In4.Cu")
		(net "FM_SWB_PWR_EN_R_BUF")
	)
	(segment
		(start 289.63874 -400.589242)
		(end 289.493198 -400.734784)
		(width 0.11684)
		(layer "In4.Cu")
		(net "FM_SWB_PWR_EN_R_BUF")
	)
	(segment
		(start 295.883584 -382.452626)
		(end 295.883584 -386.299202)
		(width 0.11684)
		(layer "In4.Cu")
		(net "FM_SWB_PWR_EN_R_BUF")
	)
	(segment
		(start 289.493198 -403.123908)
		(end 290.240212 -403.870922)
		(width 0.11684)
		(layer "In4.Cu")
		(net "FM_SWB_PWR_EN_R_BUF")
	)
	(segment
		(start 293.06901 -423.675048)
		(end 292.658292 -424.085766)
		(width 0.11684)
		(layer "In4.Cu")
		(net "FM_SWB_PWR_EN_R_BUF")
	)
	(segment
		(start 295.412922 -390.891522)
		(end 294.086534 -392.21791)
		(width 0.11684)
		(layer "In4.Cu")
		(net "FM_SWB_PWR_EN_R_BUF")
	)
	(segment
		(start 288.492946 -397.811498)
		(end 288.492946 -398.86001)
		(width 0.11684)
		(layer "In4.Cu")
		(net "FM_SWB_PWR_EN_R_BUF")
	)
	(segment
		(start 40.257222 -384.294888)
		(end 40.257222 -370.945918)
		(width 0.11684)
		(layer "In11.Cu")
		(net "FM_SWB_PWR_EN_R_BUF")
	)
	(segment
		(start 37.952172 -396.161514)
		(end 38.678358 -395.435328)
		(width 0.11684)
		(layer "In11.Cu")
		(net "FM_SWB_PWR_EN_R_BUF")
	)
	(segment
		(start 38.678358 -395.435328)
		(end 38.678358 -393.658852)
		(width 0.11684)
		(layer "In11.Cu")
		(net "FM_SWB_PWR_EN_R_BUF")
	)
	(segment
		(start 38.678358 -393.658852)
		(end 39.914322 -392.422888)
		(width 0.11684)
		(layer "In11.Cu")
		(net "FM_SWB_PWR_EN_R_BUF")
	)
	(segment
		(start 39.914322 -389.60044)
		(end 39.0779 -388.764018)
		(width 0.11684)
		(layer "In11.Cu")
		(net "FM_SWB_PWR_EN_R_BUF")
	)
	(segment
		(start 39.914322 -392.422888)
		(end 39.914322 -389.60044)
		(width 0.11684)
		(layer "In11.Cu")
		(net "FM_SWB_PWR_EN_R_BUF")
	)
	(segment
		(start 39.0779 -388.764018)
		(end 39.0779 -385.47421)
		(width 0.11684)
		(layer "In11.Cu")
		(net "FM_SWB_PWR_EN_R_BUF")
	)
	(segment
		(start 39.0779 -385.47421)
		(end 40.257222 -384.294888)
		(width 0.11684)
		(layer "In11.Cu")
		(net "FM_SWB_PWR_EN_R_BUF")
	)
	(segment
		(start 40.257222 -370.945918)
		(end 39.137082 -369.825778)
		(width 0.11684)
		(layer "In11.Cu")
		(net "FM_SWB_PWR_EN_R_BUF")
	)
	(segment
		(start 43.61688 -431.028856)
		(end 43.61688 -414.40227)
		(width 0.11684)
		(layer "In11.Cu")
		(net "FM_SWB_PWR_EN_R_BUF")
	)
	(segment
		(start 43.61688 -414.40227)
		(end 36.185094 -406.970484)
		(width 0.11684)
		(layer "In11.Cu")
		(net "FM_SWB_PWR_EN_R_BUF")
	)
	(segment
		(start 36.185094 -406.970484)
		(end 36.185094 -402.645118)
		(width 0.11684)
		(layer "In11.Cu")
		(net "FM_SWB_PWR_EN_R_BUF")
	)
	(segment
		(start 36.185094 -402.645118)
		(end 37.952172 -400.87804)
		(width 0.11684)
		(layer "In11.Cu")
		(net "FM_SWB_PWR_EN_R_BUF")
	)
	(segment
		(start 37.952172 -400.87804)
		(end 37.952172 -396.161514)
		(width 0.11684)
		(layer "In11.Cu")
		(net "FM_SWB_PWR_EN_R_BUF")
	)
	(segment
		(start 41.604946 -433.04079)
		(end 43.61688 -431.028856)
		(width 0.11684)
		(layer "In11.Cu")
		(net "FM_SWB_PWR_EN_R_BUF")
	)
	(segment
		(start 41.33596 -433.04079)
		(end 41.604946 -433.04079)
		(width 0.11684)
		(layer "In11.Cu")
		(net "FM_SWB_PWR_EN_R_BUF")
	)
	(segment
		(start 41.33596 -435.145688)
		(end 41.33596 -434.48605)
		(width 0.10668)
		(layer "F.Cu")
		(net "FM_SWB_PWR_EN_R1_BUF")
	)
	(segment
		(start 39.30396 -434.48605)
		(end 40.31996 -434.48605)
		(width 0.10668)
		(layer "F.Cu")
		(net "FM_SWB_PWR_EN_R1_BUF")
	)
	(segment
		(start 41.33596 -435.849014)
		(end 41.33596 -435.145688)
		(width 0.10668)
		(layer "F.Cu")
		(net "FM_SWB_PWR_EN_R1_BUF")
	)
	(segment
		(start 40.31996 -434.48605)
		(end 41.33596 -434.48605)
		(width 0.10668)
		(layer "F.Cu")
		(net "FM_SWB_PWR_EN_R1_BUF")
	)
	(via
		(at 41.33596 -435.145688)
		(size 0.508)
		(drill 0.254)
		(layers "F.Cu" "B.Cu")
		(net "FM_SWB_PWR_EN_R1_BUF")
	)
	(segment
		(start 38.0746 -435.849014)
		(end 38.76167 -435.849014)
		(width 0.10668)
		(layer "F.Cu")
		(net "FM_SWB_PWR_EN_R")
	)
	(segment
		(start 38.0746 -436.826914)
		(end 38.0746 -435.849014)
		(width 0.10668)
		(layer "F.Cu")
		(net "FM_SWB_PWR_EN_R")
	)
	(segment
		(start 195.964048 -99.89185)
		(end 195.964048 -99.278948)
		(width 0.10668)
		(layer "F.Cu")
		(net "FM_SWB_PWR_EN_R")
	)
	(segment
		(start 38.76167 -435.849014)
		(end 39.43604 -435.849014)
		(width 0.10668)
		(layer "F.Cu")
		(net "FM_SWB_PWR_EN_R")
	)
	(segment
		(start 195.961 -99.894898)
		(end 195.964048 -99.89185)
		(width 0.10668)
		(layer "F.Cu")
		(net "FM_SWB_PWR_EN_R")
	)
	(via
		(at 110.052358 -119.88038)
		(size 0.508)
		(drill 0.254)
		(layers "F.Cu" "B.Cu")
		(net "FM_SWB_PWR_EN_R")
	)
	(via
		(at 38.76167 -435.849014)
		(size 0.508)
		(drill 0.254)
		(layers "F.Cu" "B.Cu")
		(net "FM_SWB_PWR_EN_R")
	)
	(via
		(at 196.078856 -86.287864)
		(size 0.508)
		(drill 0.254)
		(layers "F.Cu" "B.Cu")
		(net "FM_SWB_PWR_EN_R")
	)
	(via
		(at 162.794188 -91.526868)
		(size 0.508)
		(drill 0.254)
		(layers "F.Cu" "B.Cu")
		(net "FM_SWB_PWR_EN_R")
	)
	(via
		(at 195.964048 -99.278948)
		(size 0.508)
		(drill 0.254)
		(layers "F.Cu" "B.Cu")
		(net "FM_SWB_PWR_EN_R")
	)
	(segment
		(start 196.190362 -86.39937)
		(end 196.190362 -91.268296)
		(width 0.11684)
		(layer "In4.Cu")
		(net "FM_SWB_PWR_EN_R")
	)
	(segment
		(start 196.078856 -86.287864)
		(end 196.190362 -86.39937)
		(width 0.11684)
		(layer "In4.Cu")
		(net "FM_SWB_PWR_EN_R")
	)
	(segment
		(start 196.374004 -91.451938)
		(end 196.374004 -95.806006)
		(width 0.11684)
		(layer "In4.Cu")
		(net "FM_SWB_PWR_EN_R")
	)
	(segment
		(start 196.374004 -95.806006)
		(end 196.73824 -96.170242)
		(width 0.11684)
		(layer "In4.Cu")
		(net "FM_SWB_PWR_EN_R")
	)
	(segment
		(start 196.190362 -91.268296)
		(end 196.374004 -91.451938)
		(width 0.11684)
		(layer "In4.Cu")
		(net "FM_SWB_PWR_EN_R")
	)
	(segment
		(start 196.73824 -96.170242)
		(end 196.73824 -98.504756)
		(width 0.11684)
		(layer "In4.Cu")
		(net "FM_SWB_PWR_EN_R")
	)
	(segment
		(start 196.73824 -98.504756)
		(end 195.964048 -99.278948)
		(width 0.11684)
		(layer "In4.Cu")
		(net "FM_SWB_PWR_EN_R")
	)
	(segment
		(start 156.36621 -108.18368)
		(end 157.943042 -106.606848)
		(width 0.11684)
		(layer "In6.Cu")
		(net "FM_SWB_PWR_EN_R")
	)
	(segment
		(start 148.34997 -114.092228)
		(end 150.189184 -114.092228)
		(width 0.11684)
		(layer "In6.Cu")
		(net "FM_SWB_PWR_EN_R")
	)
	(segment
		(start 162.179 -91.912948)
		(end 162.408108 -91.912948)
		(width 0.11684)
		(layer "In6.Cu")
		(net "FM_SWB_PWR_EN_R")
	)
	(segment
		(start 110.052358 -119.88038)
		(end 112.498886 -117.433852)
		(width 0.11684)
		(layer "In6.Cu")
		(net "FM_SWB_PWR_EN_R")
	)
	(segment
		(start 144.916652 -114.092228)
		(end 144.916652 -114.081306)
		(width 0.11684)
		(layer "In6.Cu")
		(net "FM_SWB_PWR_EN_R")
	)
	(segment
		(start 157.943042 -96.148906)
		(end 162.179 -91.912948)
		(width 0.11684)
		(layer "In6.Cu")
		(net "FM_SWB_PWR_EN_R")
	)
	(segment
		(start 147.773644 -113.515902)
		(end 148.34997 -114.092228)
		(width 0.11684)
		(layer "In6.Cu")
		(net "FM_SWB_PWR_EN_R")
	)
	(segment
		(start 142.963138 -116.045742)
		(end 144.916652 -114.092228)
		(width 0.11684)
		(layer "In6.Cu")
		(net "FM_SWB_PWR_EN_R")
	)
	(segment
		(start 137.3886 -116.045742)
		(end 142.963138 -116.045742)
		(width 0.11684)
		(layer "In6.Cu")
		(net "FM_SWB_PWR_EN_R")
	)
	(segment
		(start 157.943042 -106.606848)
		(end 157.943042 -96.148906)
		(width 0.11684)
		(layer "In6.Cu")
		(net "FM_SWB_PWR_EN_R")
	)
	(segment
		(start 154.09799 -113.305082)
		(end 154.098244 -113.305336)
		(width 0.11684)
		(layer "In6.Cu")
		(net "FM_SWB_PWR_EN_R")
	)
	(segment
		(start 145.482056 -113.515902)
		(end 147.773644 -113.515902)
		(width 0.11684)
		(layer "In6.Cu")
		(net "FM_SWB_PWR_EN_R")
	)
	(segment
		(start 156.36621 -111.386366)
		(end 156.36621 -108.18368)
		(width 0.11684)
		(layer "In6.Cu")
		(net "FM_SWB_PWR_EN_R")
	)
	(segment
		(start 154.098244 -113.305336)
		(end 154.44724 -113.305336)
		(width 0.11684)
		(layer "In6.Cu")
		(net "FM_SWB_PWR_EN_R")
	)
	(segment
		(start 144.916652 -114.081306)
		(end 145.482056 -113.515902)
		(width 0.11684)
		(layer "In6.Cu")
		(net "FM_SWB_PWR_EN_R")
	)
	(segment
		(start 162.408108 -91.912948)
		(end 162.794188 -91.526868)
		(width 0.11684)
		(layer "In6.Cu")
		(net "FM_SWB_PWR_EN_R")
	)
	(segment
		(start 112.498886 -117.433852)
		(end 136.00049 -117.433852)
		(width 0.11684)
		(layer "In6.Cu")
		(net "FM_SWB_PWR_EN_R")
	)
	(segment
		(start 150.97633 -113.305082)
		(end 154.09799 -113.305082)
		(width 0.11684)
		(layer "In6.Cu")
		(net "FM_SWB_PWR_EN_R")
	)
	(segment
		(start 154.44724 -113.305336)
		(end 156.36621 -111.386366)
		(width 0.11684)
		(layer "In6.Cu")
		(net "FM_SWB_PWR_EN_R")
	)
	(segment
		(start 136.00049 -117.433852)
		(end 137.3886 -116.045742)
		(width 0.11684)
		(layer "In6.Cu")
		(net "FM_SWB_PWR_EN_R")
	)
	(segment
		(start 150.189184 -114.092228)
		(end 150.97633 -113.305082)
		(width 0.11684)
		(layer "In6.Cu")
		(net "FM_SWB_PWR_EN_R")
	)
	(segment
		(start 8.2804 -420.80561)
		(end 9.307322 -421.832532)
		(width 0.11684)
		(layer "In11.Cu")
		(net "FM_SWB_PWR_EN_R")
	)
	(segment
		(start 94.128082 -122.771408)
		(end 88.14054 -128.75895)
		(width 0.11684)
		(layer "In11.Cu")
		(net "FM_SWB_PWR_EN_R")
	)
	(segment
		(start 9.307322 -427.48073)
		(end 11.551158 -429.724566)
		(width 0.11684)
		(layer "In11.Cu")
		(net "FM_SWB_PWR_EN_R")
	)
	(segment
		(start 110.052358 -120.871742)
		(end 108.152692 -122.771408)
		(width 0.11684)
		(layer "In11.Cu")
		(net "FM_SWB_PWR_EN_R")
	)
	(segment
		(start 32.917892 -435.342284)
		(end 33.83915 -436.263542)
		(width 0.11684)
		(layer "In11.Cu")
		(net "FM_SWB_PWR_EN_R")
	)
	(segment
		(start 108.152692 -122.771408)
		(end 94.128082 -122.771408)
		(width 0.11684)
		(layer "In11.Cu")
		(net "FM_SWB_PWR_EN_R")
	)
	(segment
		(start 30.639512 -435.838092)
		(end 31.13532 -435.342284)
		(width 0.11684)
		(layer "In11.Cu")
		(net "FM_SWB_PWR_EN_R")
	)
	(segment
		(start 3.752342 -383.855468)
		(end 6.332982 -386.436108)
		(width 0.11684)
		(layer "In11.Cu")
		(net "FM_SWB_PWR_EN_R")
	)
	(segment
		(start 3.752342 -353.063048)
		(end 3.752342 -383.855468)
		(width 0.11684)
		(layer "In11.Cu")
		(net "FM_SWB_PWR_EN_R")
	)
	(segment
		(start 3.205226 -344.025982)
		(end 3.205226 -352.515932)
		(width 0.11684)
		(layer "In11.Cu")
		(net "FM_SWB_PWR_EN_R")
	)
	(segment
		(start 3.205226 -352.515932)
		(end 3.752342 -353.063048)
		(width 0.11684)
		(layer "In11.Cu")
		(net "FM_SWB_PWR_EN_R")
	)
	(segment
		(start 7.460996 -394.92555)
		(end 7.460996 -406.15108)
		(width 0.11684)
		(layer "In11.Cu")
		(net "FM_SWB_PWR_EN_R")
	)
	(segment
		(start 3.889248 -156.473906)
		(end 3.889248 -343.34196)
		(width 0.11684)
		(layer "In11.Cu")
		(net "FM_SWB_PWR_EN_R")
	)
	(segment
		(start 6.332982 -386.436108)
		(end 8.044434 -386.436108)
		(width 0.11684)
		(layer "In11.Cu")
		(net "FM_SWB_PWR_EN_R")
	)
	(segment
		(start 33.83915 -436.263542)
		(end 35.556698 -436.263542)
		(width 0.11684)
		(layer "In11.Cu")
		(net "FM_SWB_PWR_EN_R")
	)
	(segment
		(start 19.014694 -433.128674)
		(end 19.73453 -433.128674)
		(width 0.11684)
		(layer "In11.Cu")
		(net "FM_SWB_PWR_EN_R")
	)
	(segment
		(start 35.556698 -436.263542)
		(end 35.971226 -435.849014)
		(width 0.11684)
		(layer "In11.Cu")
		(net "FM_SWB_PWR_EN_R")
	)
	(segment
		(start 10.305796 -392.08075)
		(end 7.460996 -394.92555)
		(width 0.11684)
		(layer "In11.Cu")
		(net "FM_SWB_PWR_EN_R")
	)
	(segment
		(start 8.044434 -386.436108)
		(end 10.305796 -388.69747)
		(width 0.11684)
		(layer "In11.Cu")
		(net "FM_SWB_PWR_EN_R")
	)
	(segment
		(start 9.307322 -421.832532)
		(end 9.307322 -427.48073)
		(width 0.11684)
		(layer "In11.Cu")
		(net "FM_SWB_PWR_EN_R")
	)
	(segment
		(start 19.73453 -433.128674)
		(end 22.443948 -435.838092)
		(width 0.11684)
		(layer "In11.Cu")
		(net "FM_SWB_PWR_EN_R")
	)
	(segment
		(start 48.206152 -131.502404)
		(end 28.86075 -131.502404)
		(width 0.11684)
		(layer "In11.Cu")
		(net "FM_SWB_PWR_EN_R")
	)
	(segment
		(start 28.86075 -131.502404)
		(end 3.889248 -156.473906)
		(width 0.11684)
		(layer "In11.Cu")
		(net "FM_SWB_PWR_EN_R")
	)
	(segment
		(start 7.460996 -406.15108)
		(end 8.2804 -406.970484)
		(width 0.11684)
		(layer "In11.Cu")
		(net "FM_SWB_PWR_EN_R")
	)
	(segment
		(start 35.971226 -435.849014)
		(end 38.76167 -435.849014)
		(width 0.11684)
		(layer "In11.Cu")
		(net "FM_SWB_PWR_EN_R")
	)
	(segment
		(start 50.949606 -128.75895)
		(end 48.206152 -131.502404)
		(width 0.11684)
		(layer "In11.Cu")
		(net "FM_SWB_PWR_EN_R")
	)
	(segment
		(start 110.052358 -119.88038)
		(end 110.052358 -120.871742)
		(width 0.11684)
		(layer "In11.Cu")
		(net "FM_SWB_PWR_EN_R")
	)
	(segment
		(start 31.13532 -435.342284)
		(end 32.917892 -435.342284)
		(width 0.11684)
		(layer "In11.Cu")
		(net "FM_SWB_PWR_EN_R")
	)
	(segment
		(start 11.551158 -429.724566)
		(end 15.610586 -429.724566)
		(width 0.11684)
		(layer "In11.Cu")
		(net "FM_SWB_PWR_EN_R")
	)
	(segment
		(start 8.2804 -406.970484)
		(end 8.2804 -420.80561)
		(width 0.11684)
		(layer "In11.Cu")
		(net "FM_SWB_PWR_EN_R")
	)
	(segment
		(start 15.610586 -429.724566)
		(end 19.014694 -433.128674)
		(width 0.11684)
		(layer "In11.Cu")
		(net "FM_SWB_PWR_EN_R")
	)
	(segment
		(start 88.14054 -128.75895)
		(end 50.949606 -128.75895)
		(width 0.11684)
		(layer "In11.Cu")
		(net "FM_SWB_PWR_EN_R")
	)
	(segment
		(start 3.889248 -343.34196)
		(end 3.205226 -344.025982)
		(width 0.11684)
		(layer "In11.Cu")
		(net "FM_SWB_PWR_EN_R")
	)
	(segment
		(start 10.305796 -388.69747)
		(end 10.305796 -392.08075)
		(width 0.11684)
		(layer "In11.Cu")
		(net "FM_SWB_PWR_EN_R")
	)
	(segment
		(start 22.443948 -435.838092)
		(end 30.639512 -435.838092)
		(width 0.11684)
		(layer "In11.Cu")
		(net "FM_SWB_PWR_EN_R")
	)
	(segment
		(start 195.484242 -85.69325)
		(end 186.390534 -85.69325)
		(width 0.11684)
		(layer "In15.Cu")
		(net "FM_SWB_PWR_EN_R")
	)
	(segment
		(start 166.818056 -85.194648)
		(end 162.794188 -89.218516)
		(width 0.11684)
		(layer "In15.Cu")
		(net "FM_SWB_PWR_EN_R")
	)
	(segment
		(start 196.078856 -86.287864)
		(end 195.484242 -85.69325)
		(width 0.11684)
		(layer "In15.Cu")
		(net "FM_SWB_PWR_EN_R")
	)
	(segment
		(start 162.794188 -89.218516)
		(end 162.794188 -91.526868)
		(width 0.11684)
		(layer "In15.Cu")
		(net "FM_SWB_PWR_EN_R")
	)
	(segment
		(start 185.891932 -85.194648)
		(end 166.818056 -85.194648)
		(width 0.11684)
		(layer "In15.Cu")
		(net "FM_SWB_PWR_EN_R")
	)
	(segment
		(start 186.390534 -85.69325)
		(end 185.891932 -85.194648)
		(width 0.11684)
		(layer "In15.Cu")
		(net "FM_SWB_PWR_EN_R")
	)
	(via
		(at 353.085908 -417.84778)
		(size 0.6604)
		(drill 0.3302)
		(layers "F.Cu" "B.Cu")
		(net "FM_SWB_PWRGD_N")
	)
	(segment
		(start 353.525074 -418.286946)
		(end 353.085908 -417.84778)
		(width 0.10668)
		(layer "B.Cu")
		(net "FM_SWB_PWRGD_N")
	)
	(segment
		(start 354.93579 -418.362638)
		(end 354.860098 -418.286946)
		(width 0.10668)
		(layer "B.Cu")
		(net "FM_SWB_PWRGD_N")
	)
	(segment
		(start 354.812854 -419.526466)
		(end 354.93579 -419.40353)
		(width 0.10668)
		(layer "B.Cu")
		(net "FM_SWB_PWRGD_N")
	)
	(segment
		(start 354.93579 -419.40353)
		(end 354.93579 -418.362638)
		(width 0.10668)
		(layer "B.Cu")
		(net "FM_SWB_PWRGD_N")
	)
	(segment
		(start 354.812854 -420.225982)
		(end 354.812854 -419.526466)
		(width 0.10668)
		(layer "B.Cu")
		(net "FM_SWB_PWRGD_N")
	)
	(segment
		(start 353.085908 -417.84778)
		(end 353.296728 -417.63696)
		(width 0.10668)
		(layer "B.Cu")
		(net "FM_SWB_PWRGD_N")
	)
	(segment
		(start 353.296728 -417.63696)
		(end 354.31603 -417.63696)
		(width 0.10668)
		(layer "B.Cu")
		(net "FM_SWB_PWRGD_N")
	)
	(segment
		(start 354.31603 -418.286946)
		(end 353.525074 -418.286946)
		(width 0.10668)
		(layer "B.Cu")
		(net "FM_SWB_PWRGD_N")
	)
	(segment
		(start 354.860098 -418.286946)
		(end 354.31603 -418.286946)
		(width 0.10668)
		(layer "B.Cu")
		(net "FM_SWB_PWRGD_N")
	)
	(segment
		(start 206.532734 -124.801376)
		(end 205.632558 -124.801376)
		(width 0.10668)
		(layer "F.Cu")
		(net "FM_SWB_PWRGD_ISO")
	)
	(segment
		(start 207.770984 -126.039626)
		(end 206.532734 -124.801376)
		(width 0.10668)
		(layer "F.Cu")
		(net "FM_SWB_PWRGD_ISO")
	)
	(via
		(at 359.567988 -414.277302)
		(size 0.6604)
		(drill 0.3302)
		(layers "F.Cu" "B.Cu")
		(net "FM_SWB_PWRGD_ISO")
	)
	(via
		(at 199.561196 -86.938866)
		(size 0.508)
		(drill 0.254)
		(layers "F.Cu" "B.Cu")
		(net "FM_SWB_PWRGD_ISO")
	)
	(via
		(at 357.293164 -410.548328)
		(size 0.508)
		(drill 0.254)
		(layers "F.Cu" "B.Cu")
		(net "FM_SWB_PWRGD_ISO")
	)
	(via
		(at 207.770984 -126.039626)
		(size 0.508)
		(drill 0.254)
		(layers "F.Cu" "B.Cu")
		(net "FM_SWB_PWRGD_ISO")
	)
	(segment
		(start 358.437942 -417.159694)
		(end 358.106726 -417.49091)
		(width 0.10668)
		(layer "B.Cu")
		(net "FM_SWB_PWRGD_ISO")
	)
	(segment
		(start 358.106726 -417.49091)
		(end 357.213154 -417.49091)
		(width 0.10668)
		(layer "B.Cu")
		(net "FM_SWB_PWRGD_ISO")
	)
	(segment
		(start 356.709218 -416.986974)
		(end 356.21595 -416.986974)
		(width 0.10668)
		(layer "B.Cu")
		(net "FM_SWB_PWRGD_ISO")
	)
	(segment
		(start 357.293164 -410.548328)
		(end 357.809546 -410.548328)
		(width 0.10668)
		(layer "B.Cu")
		(net "FM_SWB_PWRGD_ISO")
	)
	(segment
		(start 359.427272 -416.91687)
		(end 359.433876 -416.923474)
		(width 0.10668)
		(layer "B.Cu")
		(net "FM_SWB_PWRGD_ISO")
	)
	(segment
		(start 357.809546 -410.548328)
		(end 359.567988 -412.30677)
		(width 0.10668)
		(layer "B.Cu")
		(net "FM_SWB_PWRGD_ISO")
	)
	(segment
		(start 358.437942 -416.91687)
		(end 359.427272 -416.91687)
		(width 0.10668)
		(layer "B.Cu")
		(net "FM_SWB_PWRGD_ISO")
	)
	(segment
		(start 359.567988 -416.789362)
		(end 359.433876 -416.923474)
		(width 0.10668)
		(layer "B.Cu")
		(net "FM_SWB_PWRGD_ISO")
	)
	(segment
		(start 359.567988 -414.277302)
		(end 359.567988 -416.789362)
		(width 0.10668)
		(layer "B.Cu")
		(net "FM_SWB_PWRGD_ISO")
	)
	(segment
		(start 357.213154 -417.49091)
		(end 356.709218 -416.986974)
		(width 0.10668)
		(layer "B.Cu")
		(net "FM_SWB_PWRGD_ISO")
	)
	(segment
		(start 358.437942 -416.91687)
		(end 358.437942 -417.159694)
		(width 0.10668)
		(layer "B.Cu")
		(net "FM_SWB_PWRGD_ISO")
	)
	(segment
		(start 359.567988 -412.30677)
		(end 359.567988 -414.277302)
		(width 0.10668)
		(layer "B.Cu")
		(net "FM_SWB_PWRGD_ISO")
	)
	(segment
		(start 430.394364 -401.17776)
		(end 430.394364 -397.741648)
		(width 0.11684)
		(layer "In2.Cu")
		(net "FM_SWB_PWRGD_ISO")
	)
	(segment
		(start 359.050336 -408.791156)
		(end 360.98988 -408.791156)
		(width 0.11684)
		(layer "In2.Cu")
		(net "FM_SWB_PWRGD_ISO")
	)
	(segment
		(start 438.302654 -374.770904)
		(end 441.960254 -371.113304)
		(width 0.11684)
		(layer "In2.Cu")
		(net "FM_SWB_PWRGD_ISO")
	)
	(segment
		(start 360.98988 -408.791156)
		(end 362.200952 -407.580084)
		(width 0.11684)
		(layer "In2.Cu")
		(net "FM_SWB_PWRGD_ISO")
	)
	(segment
		(start 375.587768 -120.90146)
		(end 374.868186 -121.621042)
		(width 0.11684)
		(layer "In2.Cu")
		(net "FM_SWB_PWRGD_ISO")
	)
	(segment
		(start 240.636552 -90.186764)
		(end 214.338408 -90.186764)
		(width 0.11684)
		(layer "In2.Cu")
		(net "FM_SWB_PWRGD_ISO")
	)
	(segment
		(start 362.200952 -407.580084)
		(end 368.3635 -407.580084)
		(width 0.11684)
		(layer "In2.Cu")
		(net "FM_SWB_PWRGD_ISO")
	)
	(segment
		(start 288.403284 -107.97032)
		(end 281.462226 -101.029262)
		(width 0.11684)
		(layer "In2.Cu")
		(net "FM_SWB_PWRGD_ISO")
	)
	(segment
		(start 214.338408 -90.186764)
		(end 211.717636 -87.565992)
		(width 0.11684)
		(layer "In2.Cu")
		(net "FM_SWB_PWRGD_ISO")
	)
	(segment
		(start 434.055774 -391.107422)
		(end 438.302654 -386.860542)
		(width 0.11684)
		(layer "In2.Cu")
		(net "FM_SWB_PWRGD_ISO")
	)
	(segment
		(start 453.393556 -163.67887)
		(end 453.393556 -146.612356)
		(width 0.11684)
		(layer "In2.Cu")
		(net "FM_SWB_PWRGD_ISO")
	)
	(segment
		(start 431.073814 -396.101062)
		(end 434.055774 -393.119102)
		(width 0.11684)
		(layer "In2.Cu")
		(net "FM_SWB_PWRGD_ISO")
	)
	(segment
		(start 464.653376 -331.899006)
		(end 464.653376 -174.93869)
		(width 0.11684)
		(layer "In2.Cu")
		(net "FM_SWB_PWRGD_ISO")
	)
	(segment
		(start 368.557556 -407.77414)
		(end 423.797984 -407.77414)
		(width 0.11684)
		(layer "In2.Cu")
		(net "FM_SWB_PWRGD_ISO")
	)
	(segment
		(start 380.989332 -120.147588)
		(end 380.23546 -120.90146)
		(width 0.11684)
		(layer "In2.Cu")
		(net "FM_SWB_PWRGD_ISO")
	)
	(segment
		(start 434.055774 -393.119102)
		(end 434.055774 -391.107422)
		(width 0.11684)
		(layer "In2.Cu")
		(net "FM_SWB_PWRGD_ISO")
	)
	(segment
		(start 426.928788 -120.147588)
		(end 380.989332 -120.147588)
		(width 0.11684)
		(layer "In2.Cu")
		(net "FM_SWB_PWRGD_ISO")
	)
	(segment
		(start 307.156612 -107.97032)
		(end 288.403284 -107.97032)
		(width 0.11684)
		(layer "In2.Cu")
		(net "FM_SWB_PWRGD_ISO")
	)
	(segment
		(start 279.018238 -98.484436)
		(end 260.717792 -80.18399)
		(width 0.11684)
		(layer "In2.Cu")
		(net "FM_SWB_PWRGD_ISO")
	)
	(segment
		(start 452.900796 -343.651586)
		(end 464.653376 -331.899006)
		(width 0.11684)
		(layer "In2.Cu")
		(net "FM_SWB_PWRGD_ISO")
	)
	(segment
		(start 281.462226 -99.667314)
		(end 280.279348 -98.484436)
		(width 0.11684)
		(layer "In2.Cu")
		(net "FM_SWB_PWRGD_ISO")
	)
	(segment
		(start 357.293164 -410.548328)
		(end 359.050336 -408.791156)
		(width 0.11684)
		(layer "In2.Cu")
		(net "FM_SWB_PWRGD_ISO")
	)
	(segment
		(start 423.797984 -407.77414)
		(end 430.394364 -401.17776)
		(width 0.11684)
		(layer "In2.Cu")
		(net "FM_SWB_PWRGD_ISO")
	)
	(segment
		(start 452.900796 -364.176056)
		(end 452.900796 -343.651586)
		(width 0.11684)
		(layer "In2.Cu")
		(net "FM_SWB_PWRGD_ISO")
	)
	(segment
		(start 260.717792 -80.18399)
		(end 247.02643 -80.18399)
		(width 0.11684)
		(layer "In2.Cu")
		(net "FM_SWB_PWRGD_ISO")
	)
	(segment
		(start 246.285766 -80.924654)
		(end 246.285766 -84.53755)
		(width 0.11684)
		(layer "In2.Cu")
		(net "FM_SWB_PWRGD_ISO")
	)
	(segment
		(start 281.462226 -101.029262)
		(end 281.462226 -99.667314)
		(width 0.11684)
		(layer "In2.Cu")
		(net "FM_SWB_PWRGD_ISO")
	)
	(segment
		(start 200.188322 -87.565992)
		(end 199.561196 -86.938866)
		(width 0.11684)
		(layer "In2.Cu")
		(net "FM_SWB_PWRGD_ISO")
	)
	(segment
		(start 246.285766 -84.53755)
		(end 240.636552 -90.186764)
		(width 0.11684)
		(layer "In2.Cu")
		(net "FM_SWB_PWRGD_ISO")
	)
	(segment
		(start 247.02643 -80.18399)
		(end 246.285766 -80.924654)
		(width 0.11684)
		(layer "In2.Cu")
		(net "FM_SWB_PWRGD_ISO")
	)
	(segment
		(start 438.302654 -386.860542)
		(end 438.302654 -374.770904)
		(width 0.11684)
		(layer "In2.Cu")
		(net "FM_SWB_PWRGD_ISO")
	)
	(segment
		(start 430.394364 -397.741648)
		(end 431.073814 -396.101062)
		(width 0.11684)
		(layer "In2.Cu")
		(net "FM_SWB_PWRGD_ISO")
	)
	(segment
		(start 445.963548 -371.113304)
		(end 452.900796 -364.176056)
		(width 0.11684)
		(layer "In2.Cu")
		(net "FM_SWB_PWRGD_ISO")
	)
	(segment
		(start 280.279348 -98.484436)
		(end 279.018238 -98.484436)
		(width 0.11684)
		(layer "In2.Cu")
		(net "FM_SWB_PWRGD_ISO")
	)
	(segment
		(start 441.960254 -371.113304)
		(end 445.963548 -371.113304)
		(width 0.11684)
		(layer "In2.Cu")
		(net "FM_SWB_PWRGD_ISO")
	)
	(segment
		(start 453.393556 -146.612356)
		(end 426.928788 -120.147588)
		(width 0.11684)
		(layer "In2.Cu")
		(net "FM_SWB_PWRGD_ISO")
	)
	(segment
		(start 368.3635 -407.580084)
		(end 368.557556 -407.77414)
		(width 0.11684)
		(layer "In2.Cu")
		(net "FM_SWB_PWRGD_ISO")
	)
	(segment
		(start 320.807334 -121.621042)
		(end 307.156612 -107.97032)
		(width 0.11684)
		(layer "In2.Cu")
		(net "FM_SWB_PWRGD_ISO")
	)
	(segment
		(start 464.653376 -174.93869)
		(end 453.393556 -163.67887)
		(width 0.11684)
		(layer "In2.Cu")
		(net "FM_SWB_PWRGD_ISO")
	)
	(segment
		(start 380.23546 -120.90146)
		(end 375.587768 -120.90146)
		(width 0.11684)
		(layer "In2.Cu")
		(net "FM_SWB_PWRGD_ISO")
	)
	(segment
		(start 374.868186 -121.621042)
		(end 320.807334 -121.621042)
		(width 0.11684)
		(layer "In2.Cu")
		(net "FM_SWB_PWRGD_ISO")
	)
	(segment
		(start 211.717636 -87.565992)
		(end 200.188322 -87.565992)
		(width 0.11684)
		(layer "In2.Cu")
		(net "FM_SWB_PWRGD_ISO")
	)
	(segment
		(start 208.96453 -110.623858)
		(end 209.541364 -110.047024)
		(width 0.11684)
		(layer "In11.Cu")
		(net "FM_SWB_PWRGD_ISO")
	)
	(segment
		(start 210.752436 -109.57687)
		(end 210.752436 -102.630224)
		(width 0.11684)
		(layer "In11.Cu")
		(net "FM_SWB_PWRGD_ISO")
	)
	(segment
		(start 208.505806 -92.244672)
		(end 206.642208 -90.381074)
		(width 0.11684)
		(layer "In11.Cu")
		(net "FM_SWB_PWRGD_ISO")
	)
	(segment
		(start 208.091024 -125.719586)
		(end 208.091024 -113.506504)
		(width 0.11684)
		(layer "In11.Cu")
		(net "FM_SWB_PWRGD_ISO")
	)
	(segment
		(start 210.97367 -100.581714)
		(end 209.936334 -99.544378)
		(width 0.11684)
		(layer "In11.Cu")
		(net "FM_SWB_PWRGD_ISO")
	)
	(segment
		(start 210.752436 -102.630224)
		(end 210.97367 -102.40899)
		(width 0.11684)
		(layer "In11.Cu")
		(net "FM_SWB_PWRGD_ISO")
	)
	(segment
		(start 209.936334 -97.406714)
		(end 208.505806 -95.976186)
		(width 0.11684)
		(layer "In11.Cu")
		(net "FM_SWB_PWRGD_ISO")
	)
	(segment
		(start 207.770984 -126.039626)
		(end 208.091024 -125.719586)
		(width 0.11684)
		(layer "In11.Cu")
		(net "FM_SWB_PWRGD_ISO")
	)
	(segment
		(start 208.091024 -113.506504)
		(end 208.96453 -112.632998)
		(width 0.11684)
		(layer "In11.Cu")
		(net "FM_SWB_PWRGD_ISO")
	)
	(segment
		(start 208.96453 -112.632998)
		(end 208.96453 -110.623858)
		(width 0.11684)
		(layer "In11.Cu")
		(net "FM_SWB_PWRGD_ISO")
	)
	(segment
		(start 210.97367 -102.40899)
		(end 210.97367 -100.581714)
		(width 0.11684)
		(layer "In11.Cu")
		(net "FM_SWB_PWRGD_ISO")
	)
	(segment
		(start 206.642208 -90.381074)
		(end 205.639416 -90.381074)
		(width 0.11684)
		(layer "In11.Cu")
		(net "FM_SWB_PWRGD_ISO")
	)
	(segment
		(start 209.541364 -110.047024)
		(end 210.282282 -110.047024)
		(width 0.11684)
		(layer "In11.Cu")
		(net "FM_SWB_PWRGD_ISO")
	)
	(segment
		(start 201.128884 -88.506554)
		(end 199.561196 -86.938866)
		(width 0.11684)
		(layer "In11.Cu")
		(net "FM_SWB_PWRGD_ISO")
	)
	(segment
		(start 203.764896 -88.506554)
		(end 201.128884 -88.506554)
		(width 0.11684)
		(layer "In11.Cu")
		(net "FM_SWB_PWRGD_ISO")
	)
	(segment
		(start 209.936334 -99.544378)
		(end 209.936334 -97.406714)
		(width 0.11684)
		(layer "In11.Cu")
		(net "FM_SWB_PWRGD_ISO")
	)
	(segment
		(start 208.505806 -95.976186)
		(end 208.505806 -92.244672)
		(width 0.11684)
		(layer "In11.Cu")
		(net "FM_SWB_PWRGD_ISO")
	)
	(segment
		(start 205.639416 -90.381074)
		(end 203.764896 -88.506554)
		(width 0.11684)
		(layer "In11.Cu")
		(net "FM_SWB_PWRGD_ISO")
	)
	(segment
		(start 210.282282 -110.047024)
		(end 210.752436 -109.57687)
		(width 0.11684)
		(layer "In11.Cu")
		(net "FM_SWB_PWRGD_ISO")
	)
	(via
		(at 370.53393 -428.519082)
		(size 0.508)
		(drill 0.254)
		(layers "F.Cu" "B.Cu")
		(net "FM_SWB_PWRGD")
	)
	(via
		(at 360.36377 -420.369746)
		(size 0.508)
		(drill 0.254)
		(layers "F.Cu" "B.Cu")
		(net "FM_SWB_PWRGD")
	)
	(segment
		(start 359.475024 -420.026846)
		(end 359.139744 -419.691566)
		(width 0.10668)
		(layer "B.Cu")
		(net "FM_SWB_PWRGD")
	)
	(segment
		(start 356.729538 -417.63696)
		(end 356.21595 -417.63696)
		(width 0.10668)
		(layer "B.Cu")
		(net "FM_SWB_PWRGD")
	)
	(segment
		(start 360.02087 -420.026846)
		(end 359.475024 -420.026846)
		(width 0.10668)
		(layer "B.Cu")
		(net "FM_SWB_PWRGD")
	)
	(segment
		(start 359.138728 -419.02888)
		(end 359.139744 -419.027864)
		(width 0.10668)
		(layer "B.Cu")
		(net "FM_SWB_PWRGD")
	)
	(segment
		(start 358.130856 -419.02888)
		(end 359.138728 -419.02888)
		(width 0.10668)
		(layer "B.Cu")
		(net "FM_SWB_PWRGD")
	)
	(segment
		(start 358.130856 -419.02888)
		(end 358.121458 -419.02888)
		(width 0.10668)
		(layer "B.Cu")
		(net "FM_SWB_PWRGD")
	)
	(segment
		(start 358.121458 -419.02888)
		(end 356.729538 -417.63696)
		(width 0.10668)
		(layer "B.Cu")
		(net "FM_SWB_PWRGD")
	)
	(segment
		(start 360.36377 -420.369746)
		(end 360.02087 -420.026846)
		(width 0.10668)
		(layer "B.Cu")
		(net "FM_SWB_PWRGD")
	)
	(segment
		(start 359.139744 -419.691566)
		(end 359.139744 -419.027864)
		(width 0.10668)
		(layer "B.Cu")
		(net "FM_SWB_PWRGD")
	)
	(segment
		(start 380.849886 -424.09872)
		(end 380.450598 -424.498008)
		(width 0.11684)
		(layer "In2.Cu")
		(net "FM_SWB_PWRGD")
	)
	(segment
		(start 385.272026 -440.489848)
		(end 385.090416 -440.308238)
		(width 0.11684)
		(layer "In2.Cu")
		(net "FM_SWB_PWRGD")
	)
	(segment
		(start 385.090416 -440.308238)
		(end 385.090416 -425.0436)
		(width 0.11684)
		(layer "In2.Cu")
		(net "FM_SWB_PWRGD")
	)
	(segment
		(start 380.450598 -424.498008)
		(end 378.673106 -424.498008)
		(width 0.11684)
		(layer "In2.Cu")
		(net "FM_SWB_PWRGD")
	)
	(segment
		(start 385.7498 -440.489848)
		(end 385.272026 -440.489848)
		(width 0.11684)
		(layer "In2.Cu")
		(net "FM_SWB_PWRGD")
	)
	(segment
		(start 373.557546 -429.613568)
		(end 371.628416 -429.613568)
		(width 0.11684)
		(layer "In2.Cu")
		(net "FM_SWB_PWRGD")
	)
	(segment
		(start 384.145536 -424.09872)
		(end 380.849886 -424.09872)
		(width 0.11684)
		(layer "In2.Cu")
		(net "FM_SWB_PWRGD")
	)
	(segment
		(start 378.673106 -424.498008)
		(end 373.557546 -429.613568)
		(width 0.11684)
		(layer "In2.Cu")
		(net "FM_SWB_PWRGD")
	)
	(segment
		(start 385.090416 -425.0436)
		(end 384.145536 -424.09872)
		(width 0.11684)
		(layer "In2.Cu")
		(net "FM_SWB_PWRGD")
	)
	(segment
		(start 371.628416 -429.613568)
		(end 370.53393 -428.519082)
		(width 0.11684)
		(layer "In2.Cu")
		(net "FM_SWB_PWRGD")
	)
	(segment
		(start 362.9914 -423.556684)
		(end 362.9914 -426.174916)
		(width 0.11684)
		(layer "In4.Cu")
		(net "FM_SWB_PWRGD")
	)
	(segment
		(start 368.654076 -427.863)
		(end 368.784378 -427.993302)
		(width 0.11684)
		(layer "In4.Cu")
		(net "FM_SWB_PWRGD")
	)
	(segment
		(start 370.00815 -427.993302)
		(end 370.53393 -428.519082)
		(width 0.11684)
		(layer "In4.Cu")
		(net "FM_SWB_PWRGD")
	)
	(segment
		(start 360.36377 -420.369746)
		(end 360.36377 -420.929054)
		(width 0.11684)
		(layer "In4.Cu")
		(net "FM_SWB_PWRGD")
	)
	(segment
		(start 360.36377 -420.929054)
		(end 362.9914 -423.556684)
		(width 0.11684)
		(layer "In4.Cu")
		(net "FM_SWB_PWRGD")
	)
	(segment
		(start 368.784378 -427.993302)
		(end 370.00815 -427.993302)
		(width 0.11684)
		(layer "In4.Cu")
		(net "FM_SWB_PWRGD")
	)
	(segment
		(start 362.9914 -426.174916)
		(end 364.679484 -427.863)
		(width 0.11684)
		(layer "In4.Cu")
		(net "FM_SWB_PWRGD")
	)
	(segment
		(start 364.679484 -427.863)
		(end 368.654076 -427.863)
		(width 0.11684)
		(layer "In4.Cu")
		(net "FM_SWB_PWRGD")
	)
	(segment
		(start 428.120302 -435.764686)
		(end 426.727366 -435.764686)
		(width 0.10668)
		(layer "F.Cu")
		(net "FM_SWB_BIC_READY_N")
	)
	(segment
		(start 429.464216 -435.436772)
		(end 429.136302 -435.764686)
		(width 0.10668)
		(layer "F.Cu")
		(net "FM_SWB_BIC_READY_N")
	)
	(segment
		(start 429.136302 -435.764686)
		(end 428.120302 -435.764686)
		(width 0.10668)
		(layer "F.Cu")
		(net "FM_SWB_BIC_READY_N")
	)
	(segment
		(start 431.29708 -435.436772)
		(end 429.464216 -435.436772)
		(width 0.10668)
		(layer "F.Cu")
		(net "FM_SWB_BIC_READY_N")
	)
	(via
		(at 426.727366 -435.764686)
		(size 0.508)
		(drill 0.254)
		(layers "F.Cu" "B.Cu")
		(net "FM_SWB_BIC_READY_N")
	)
	(segment
		(start 404.96998 -423.52976)
		(end 413.478218 -423.52976)
		(width 0.10668)
		(layer "B.Cu")
		(net "FM_SWB_BIC_READY_N")
	)
	(segment
		(start 404.750016 -424.689778)
		(end 404.750016 -423.749724)
		(width 0.10668)
		(layer "B.Cu")
		(net "FM_SWB_BIC_READY_N")
	)
	(segment
		(start 415.685986 -429.515524)
		(end 419.653466 -433.483004)
		(width 0.10668)
		(layer "B.Cu")
		(net "FM_SWB_BIC_READY_N")
	)
	(segment
		(start 425.604686 -435.764686)
		(end 426.727366 -435.764686)
		(width 0.10668)
		(layer "B.Cu")
		(net "FM_SWB_BIC_READY_N")
	)
	(segment
		(start 413.478218 -423.52976)
		(end 415.685986 -425.737528)
		(width 0.10668)
		(layer "B.Cu")
		(net "FM_SWB_BIC_READY_N")
	)
	(segment
		(start 415.685986 -425.737528)
		(end 415.685986 -429.515524)
		(width 0.10668)
		(layer "B.Cu")
		(net "FM_SWB_BIC_READY_N")
	)
	(segment
		(start 404.750016 -423.749724)
		(end 404.96998 -423.52976)
		(width 0.10668)
		(layer "B.Cu")
		(net "FM_SWB_BIC_READY_N")
	)
	(segment
		(start 421.409622 -433.483004)
		(end 422.016428 -434.08981)
		(width 0.10668)
		(layer "B.Cu")
		(net "FM_SWB_BIC_READY_N")
	)
	(segment
		(start 423.92981 -434.08981)
		(end 425.604686 -435.764686)
		(width 0.10668)
		(layer "B.Cu")
		(net "FM_SWB_BIC_READY_N")
	)
	(segment
		(start 419.653466 -433.483004)
		(end 421.409622 -433.483004)
		(width 0.10668)
		(layer "B.Cu")
		(net "FM_SWB_BIC_READY_N")
	)
	(segment
		(start 422.016428 -434.08981)
		(end 423.92981 -434.08981)
		(width 0.10668)
		(layer "B.Cu")
		(net "FM_SWB_BIC_READY_N")
	)
	(segment
		(start 205.615032 -123.785376)
		(end 206.538322 -123.785376)
		(width 0.10668)
		(layer "F.Cu")
		(net "FM_SWB_BIC_READY_ISO_N")
	)
	(segment
		(start 206.538322 -123.785376)
		(end 207.617822 -124.864876)
		(width 0.10668)
		(layer "F.Cu")
		(net "FM_SWB_BIC_READY_ISO_N")
	)
	(segment
		(start 427.019466 -434.786786)
		(end 428.120302 -434.786786)
		(width 0.10668)
		(layer "F.Cu")
		(net "FM_SWB_BIC_READY_ISO_N")
	)
	(segment
		(start 431.29708 -434.786786)
		(end 429.136302 -434.786786)
		(width 0.10668)
		(layer "F.Cu")
		(net "FM_SWB_BIC_READY_ISO_N")
	)
	(segment
		(start 426.727366 -434.494686)
		(end 427.019466 -434.786786)
		(width 0.10668)
		(layer "F.Cu")
		(net "FM_SWB_BIC_READY_ISO_N")
	)
	(segment
		(start 428.120302 -434.786786)
		(end 429.136302 -434.786786)
		(width 0.10668)
		(layer "F.Cu")
		(net "FM_SWB_BIC_READY_ISO_N")
	)
	(via
		(at 207.617822 -124.864876)
		(size 0.508)
		(drill 0.254)
		(layers "F.Cu" "B.Cu")
		(net "FM_SWB_BIC_READY_ISO_N")
	)
	(via
		(at 426.727366 -434.494686)
		(size 0.508)
		(drill 0.254)
		(layers "F.Cu" "B.Cu")
		(net "FM_SWB_BIC_READY_ISO_N")
	)
	(segment
		(start 431.20564 -396.698978)
		(end 435.784498 -392.12012)
		(width 0.11684)
		(layer "In6.Cu")
		(net "FM_SWB_BIC_READY_ISO_N")
	)
	(segment
		(start 434.653944 -431.637948)
		(end 434.653944 -416.692334)
		(width 0.11684)
		(layer "In6.Cu")
		(net "FM_SWB_BIC_READY_ISO_N")
	)
	(segment
		(start 435.717442 -415.628836)
		(end 435.717442 -406.275286)
		(width 0.11684)
		(layer "In6.Cu")
		(net "FM_SWB_BIC_READY_ISO_N")
	)
	(segment
		(start 218.20632 -125.368304)
		(end 217.992706 -125.15469)
		(width 0.11684)
		(layer "In6.Cu")
		(net "FM_SWB_BIC_READY_ISO_N")
	)
	(segment
		(start 218.826842 -125.368304)
		(end 218.20632 -125.368304)
		(width 0.11684)
		(layer "In6.Cu")
		(net "FM_SWB_BIC_READY_ISO_N")
	)
	(segment
		(start 464.186016 -178.239166)
		(end 451.398386 -165.451536)
		(width 0.11684)
		(layer "In6.Cu")
		(net "FM_SWB_BIC_READY_ISO_N")
	)
	(segment
		(start 321.290696 -123.28144)
		(end 318.539368 -126.032768)
		(width 0.11684)
		(layer "In6.Cu")
		(net "FM_SWB_BIC_READY_ISO_N")
	)
	(segment
		(start 253.251716 -146.861276)
		(end 240.21669 -133.82625)
		(width 0.11684)
		(layer "In6.Cu")
		(net "FM_SWB_BIC_READY_ISO_N")
	)
	(segment
		(start 271.375886 -138.354308)
		(end 262.868918 -146.861276)
		(width 0.11684)
		(layer "In6.Cu")
		(net "FM_SWB_BIC_READY_ISO_N")
	)
	(segment
		(start 345.846908 -123.28144)
		(end 321.290696 -123.28144)
		(width 0.11684)
		(layer "In6.Cu")
		(net "FM_SWB_BIC_READY_ISO_N")
	)
	(segment
		(start 452.617586 -342.350344)
		(end 464.186016 -330.781914)
		(width 0.11684)
		(layer "In6.Cu")
		(net "FM_SWB_BIC_READY_ISO_N")
	)
	(segment
		(start 302.432466 -126.032768)
		(end 290.110926 -138.354308)
		(width 0.11684)
		(layer "In6.Cu")
		(net "FM_SWB_BIC_READY_ISO_N")
	)
	(segment
		(start 426.734986 -434.502306)
		(end 431.789586 -434.502306)
		(width 0.11684)
		(layer "In6.Cu")
		(net "FM_SWB_BIC_READY_ISO_N")
	)
	(segment
		(start 452.617586 -357.976678)
		(end 452.617586 -342.350344)
		(width 0.11684)
		(layer "In6.Cu")
		(net "FM_SWB_BIC_READY_ISO_N")
	)
	(segment
		(start 262.868918 -146.861276)
		(end 253.251716 -146.861276)
		(width 0.11684)
		(layer "In6.Cu")
		(net "FM_SWB_BIC_READY_ISO_N")
	)
	(segment
		(start 451.398386 -165.451536)
		(end 451.398386 -150.772368)
		(width 0.11684)
		(layer "In6.Cu")
		(net "FM_SWB_BIC_READY_ISO_N")
	)
	(segment
		(start 439.329576 -387.483096)
		(end 439.329576 -371.264688)
		(width 0.11684)
		(layer "In6.Cu")
		(net "FM_SWB_BIC_READY_ISO_N")
	)
	(segment
		(start 464.186016 -330.781914)
		(end 464.186016 -178.239166)
		(width 0.11684)
		(layer "In6.Cu")
		(net "FM_SWB_BIC_READY_ISO_N")
	)
	(segment
		(start 439.329576 -371.264688)
		(end 452.617586 -357.976678)
		(width 0.11684)
		(layer "In6.Cu")
		(net "FM_SWB_BIC_READY_ISO_N")
	)
	(segment
		(start 435.784498 -392.12012)
		(end 435.784498 -391.028174)
		(width 0.11684)
		(layer "In6.Cu")
		(net "FM_SWB_BIC_READY_ISO_N")
	)
	(segment
		(start 451.398386 -150.772368)
		(end 428.234856 -127.608838)
		(width 0.11684)
		(layer "In6.Cu")
		(net "FM_SWB_BIC_READY_ISO_N")
	)
	(segment
		(start 435.321202 -405.879046)
		(end 435.321202 -405.46782)
		(width 0.11684)
		(layer "In6.Cu")
		(net "FM_SWB_BIC_READY_ISO_N")
	)
	(segment
		(start 435.321202 -405.46782)
		(end 431.20564 -401.352258)
		(width 0.11684)
		(layer "In6.Cu")
		(net "FM_SWB_BIC_READY_ISO_N")
	)
	(segment
		(start 350.174306 -127.608838)
		(end 345.846908 -123.28144)
		(width 0.11684)
		(layer "In6.Cu")
		(net "FM_SWB_BIC_READY_ISO_N")
	)
	(segment
		(start 290.110926 -138.354308)
		(end 271.375886 -138.354308)
		(width 0.11684)
		(layer "In6.Cu")
		(net "FM_SWB_BIC_READY_ISO_N")
	)
	(segment
		(start 426.727366 -434.494686)
		(end 426.734986 -434.502306)
		(width 0.11684)
		(layer "In6.Cu")
		(net "FM_SWB_BIC_READY_ISO_N")
	)
	(segment
		(start 318.539368 -126.032768)
		(end 302.432466 -126.032768)
		(width 0.11684)
		(layer "In6.Cu")
		(net "FM_SWB_BIC_READY_ISO_N")
	)
	(segment
		(start 434.653944 -416.692334)
		(end 435.717442 -415.628836)
		(width 0.11684)
		(layer "In6.Cu")
		(net "FM_SWB_BIC_READY_ISO_N")
	)
	(segment
		(start 435.784498 -391.028174)
		(end 439.329576 -387.483096)
		(width 0.11684)
		(layer "In6.Cu")
		(net "FM_SWB_BIC_READY_ISO_N")
	)
	(segment
		(start 431.20564 -401.352258)
		(end 431.20564 -396.698978)
		(width 0.11684)
		(layer "In6.Cu")
		(net "FM_SWB_BIC_READY_ISO_N")
	)
	(segment
		(start 435.717442 -406.275286)
		(end 435.321202 -405.879046)
		(width 0.11684)
		(layer "In6.Cu")
		(net "FM_SWB_BIC_READY_ISO_N")
	)
	(segment
		(start 428.234856 -127.608838)
		(end 350.174306 -127.608838)
		(width 0.11684)
		(layer "In6.Cu")
		(net "FM_SWB_BIC_READY_ISO_N")
	)
	(segment
		(start 207.907636 -125.15469)
		(end 207.617822 -124.864876)
		(width 0.11684)
		(layer "In6.Cu")
		(net "FM_SWB_BIC_READY_ISO_N")
	)
	(segment
		(start 240.21669 -133.82625)
		(end 227.284788 -133.82625)
		(width 0.11684)
		(layer "In6.Cu")
		(net "FM_SWB_BIC_READY_ISO_N")
	)
	(segment
		(start 227.284788 -133.82625)
		(end 218.826842 -125.368304)
		(width 0.11684)
		(layer "In6.Cu")
		(net "FM_SWB_BIC_READY_ISO_N")
	)
	(segment
		(start 431.789586 -434.502306)
		(end 434.653944 -431.637948)
		(width 0.11684)
		(layer "In6.Cu")
		(net "FM_SWB_BIC_READY_ISO_N")
	)
	(segment
		(start 217.992706 -125.15469)
		(end 207.907636 -125.15469)
		(width 0.11684)
		(layer "In6.Cu")
		(net "FM_SWB_BIC_READY_ISO_N")
	)
	(segment
		(start 433.197 -436.086758)
		(end 434.43144 -436.086758)
		(width 0.10668)
		(layer "F.Cu")
		(net "FM_SWB_BIC_READY")
	)
	(segment
		(start 433.197 -435.436772)
		(end 433.197 -436.086758)
		(width 0.10668)
		(layer "F.Cu")
		(net "FM_SWB_BIC_READY")
	)
	(segment
		(start 434.43144 -436.086758)
		(end 434.43144 -434.867558)
		(width 0.10668)
		(layer "F.Cu")
		(net "FM_SWB_BIC_READY")
	)
	(via
		(at 434.43144 -436.086758)
		(size 0.762)
		(drill 0.381)
		(layers "F.Cu" "B.Cu")
		(net "FM_SWB_BIC_READY")
	)
	(segment
		(start 189.92215 -121.052844)
		(end 190.31204 -121.442734)
		(width 0.10668)
		(layer "F.Cu")
		(net "FM_SPD_CPU0_SWITCH_CTRL_R_N")
	)
	(via
		(at 190.31204 -121.442734)
		(size 0.4572)
		(drill 0.254)
		(layers "F.Cu" "B.Cu")
		(net "FM_SPD_CPU0_SWITCH_CTRL_R_N")
	)
	(via
		(at 192.92697 -124.853192)
		(size 0.6604)
		(drill 0.3302)
		(layers "F.Cu" "B.Cu")
		(net "FM_SPD_CPU0_SWITCH_CTRL_R_N")
	)
	(segment
		(start 191.515746 -122.086116)
		(end 191.276224 -121.846594)
		(width 0.10668)
		(layer "B.Cu")
		(net "FM_SPD_CPU0_SWITCH_CTRL_R_N")
	)
	(segment
		(start 191.276224 -121.846594)
		(end 190.955168 -121.846594)
		(width 0.10668)
		(layer "B.Cu")
		(net "FM_SPD_CPU0_SWITCH_CTRL_R_N")
	)
	(segment
		(start 192.189608 -122.639836)
		(end 191.617346 -122.639836)
		(width 0.10668)
		(layer "B.Cu")
		(net "FM_SPD_CPU0_SWITCH_CTRL_R_N")
	)
	(segment
		(start 192.92697 -124.853192)
		(end 192.92697 -123.377198)
		(width 0.10668)
		(layer "B.Cu")
		(net "FM_SPD_CPU0_SWITCH_CTRL_R_N")
	)
	(segment
		(start 191.617346 -122.639836)
		(end 191.515746 -122.538236)
		(width 0.10668)
		(layer "B.Cu")
		(net "FM_SPD_CPU0_SWITCH_CTRL_R_N")
	)
	(segment
		(start 192.92697 -125.525784)
		(end 192.92697 -124.853192)
		(width 0.10668)
		(layer "B.Cu")
		(net "FM_SPD_CPU0_SWITCH_CTRL_R_N")
	)
	(segment
		(start 192.92697 -123.377198)
		(end 192.189608 -122.639836)
		(width 0.10668)
		(layer "B.Cu")
		(net "FM_SPD_CPU0_SWITCH_CTRL_R_N")
	)
	(segment
		(start 191.515746 -122.538236)
		(end 191.515746 -122.086116)
		(width 0.10668)
		(layer "B.Cu")
		(net "FM_SPD_CPU0_SWITCH_CTRL_R_N")
	)
	(segment
		(start 190.955168 -121.846594)
		(end 190.551308 -121.442734)
		(width 0.10668)
		(layer "B.Cu")
		(net "FM_SPD_CPU0_SWITCH_CTRL_R_N")
	)
	(segment
		(start 193.205608 -126.433326)
		(end 193.205608 -125.804422)
		(width 0.10668)
		(layer "B.Cu")
		(net "FM_SPD_CPU0_SWITCH_CTRL_R_N")
	)
	(segment
		(start 193.205608 -125.804422)
		(end 192.92697 -125.525784)
		(width 0.10668)
		(layer "B.Cu")
		(net "FM_SPD_CPU0_SWITCH_CTRL_R_N")
	)
	(segment
		(start 190.551308 -121.442734)
		(end 190.31204 -121.442734)
		(width 0.10668)
		(layer "B.Cu")
		(net "FM_SPD_CPU0_SWITCH_CTRL_R_N")
	)
	(segment
		(start 431.5714 -42.357548)
		(end 430.5554 -42.357548)
		(width 0.10668)
		(layer "F.Cu")
		(net "FM_SPD_CPU0_SWITCH_CTRL_N")
	)
	(via
		(at 197.19163 -138.616182)
		(size 0.508)
		(drill 0.254)
		(layers "F.Cu" "B.Cu")
		(net "FM_SPD_CPU0_SWITCH_CTRL_N")
	)
	(via
		(at 430.5554 -42.357548)
		(size 0.508)
		(drill 0.254)
		(layers "F.Cu" "B.Cu")
		(net "FM_SPD_CPU0_SWITCH_CTRL_N")
	)
	(via
		(at 267.175742 -77.592428)
		(size 0.508)
		(drill 0.254)
		(layers "F.Cu" "B.Cu")
		(net "FM_SPD_CPU0_SWITCH_CTRL_N")
	)
	(via
		(at 264.372344 -129.767076)
		(size 0.508)
		(drill 0.254)
		(layers "F.Cu" "B.Cu")
		(net "FM_SPD_CPU0_SWITCH_CTRL_N")
	)
	(segment
		(start 197.19163 -137.353294)
		(end 197.19163 -138.616182)
		(width 0.10668)
		(layer "B.Cu")
		(net "FM_SPD_CPU0_SWITCH_CTRL_N")
	)
	(segment
		(start 195.519548 -135.681212)
		(end 197.19163 -137.353294)
		(width 0.10668)
		(layer "B.Cu")
		(net "FM_SPD_CPU0_SWITCH_CTRL_N")
	)
	(segment
		(start 194.411854 -133.034786)
		(end 195.519548 -134.14248)
		(width 0.10668)
		(layer "B.Cu")
		(net "FM_SPD_CPU0_SWITCH_CTRL_N")
	)
	(segment
		(start 193.205608 -127.233426)
		(end 193.36258 -127.390398)
		(width 0.10668)
		(layer "B.Cu")
		(net "FM_SPD_CPU0_SWITCH_CTRL_N")
	)
	(segment
		(start 195.519548 -134.14248)
		(end 195.519548 -135.681212)
		(width 0.10668)
		(layer "B.Cu")
		(net "FM_SPD_CPU0_SWITCH_CTRL_N")
	)
	(segment
		(start 193.66611 -131.833874)
		(end 193.66611 -132.686298)
		(width 0.10668)
		(layer "B.Cu")
		(net "FM_SPD_CPU0_SWITCH_CTRL_N")
	)
	(segment
		(start 193.363342 -131.531106)
		(end 193.66611 -131.833874)
		(width 0.10668)
		(layer "B.Cu")
		(net "FM_SPD_CPU0_SWITCH_CTRL_N")
	)
	(segment
		(start 193.36258 -127.390398)
		(end 193.36258 -130.728466)
		(width 0.10668)
		(layer "B.Cu")
		(net "FM_SPD_CPU0_SWITCH_CTRL_N")
	)
	(segment
		(start 194.014598 -133.034786)
		(end 194.411854 -133.034786)
		(width 0.10668)
		(layer "B.Cu")
		(net "FM_SPD_CPU0_SWITCH_CTRL_N")
	)
	(segment
		(start 193.36258 -130.728466)
		(end 193.363342 -130.729228)
		(width 0.10668)
		(layer "B.Cu")
		(net "FM_SPD_CPU0_SWITCH_CTRL_N")
	)
	(segment
		(start 193.66611 -132.686298)
		(end 194.014598 -133.034786)
		(width 0.10668)
		(layer "B.Cu")
		(net "FM_SPD_CPU0_SWITCH_CTRL_N")
	)
	(segment
		(start 193.363342 -130.729228)
		(end 193.363342 -131.531106)
		(width 0.10668)
		(layer "B.Cu")
		(net "FM_SPD_CPU0_SWITCH_CTRL_N")
	)
	(segment
		(start 429.387 -42.357548)
		(end 430.5554 -42.357548)
		(width 0.10668)
		(layer "B.Cu")
		(net "FM_SPD_CPU0_SWITCH_CTRL_N")
	)
	(segment
		(start 203.879958 -138.221466)
		(end 205.937104 -136.16432)
		(width 0.11684)
		(layer "In2.Cu")
		(net "FM_SPD_CPU0_SWITCH_CTRL_N")
	)
	(segment
		(start 212.86089 -136.16432)
		(end 213.85022 -135.17499)
		(width 0.11684)
		(layer "In2.Cu")
		(net "FM_SPD_CPU0_SWITCH_CTRL_N")
	)
	(segment
		(start 260.00964 -126.18974)
		(end 261.798816 -126.18974)
		(width 0.11684)
		(layer "In2.Cu")
		(net "FM_SPD_CPU0_SWITCH_CTRL_N")
	)
	(segment
		(start 257.208528 -128.990852)
		(end 260.00964 -126.18974)
		(width 0.11684)
		(layer "In2.Cu")
		(net "FM_SPD_CPU0_SWITCH_CTRL_N")
	)
	(segment
		(start 253.465838 -128.990852)
		(end 257.208528 -128.990852)
		(width 0.11684)
		(layer "In2.Cu")
		(net "FM_SPD_CPU0_SWITCH_CTRL_N")
	)
	(segment
		(start 200.631044 -138.221466)
		(end 203.879958 -138.221466)
		(width 0.11684)
		(layer "In2.Cu")
		(net "FM_SPD_CPU0_SWITCH_CTRL_N")
	)
	(segment
		(start 200.236328 -138.616182)
		(end 200.631044 -138.221466)
		(width 0.11684)
		(layer "In2.Cu")
		(net "FM_SPD_CPU0_SWITCH_CTRL_N")
	)
	(segment
		(start 213.85022 -135.17499)
		(end 247.2817 -135.17499)
		(width 0.11684)
		(layer "In2.Cu")
		(net "FM_SPD_CPU0_SWITCH_CTRL_N")
	)
	(segment
		(start 205.937104 -136.16432)
		(end 212.86089 -136.16432)
		(width 0.11684)
		(layer "In2.Cu")
		(net "FM_SPD_CPU0_SWITCH_CTRL_N")
	)
	(segment
		(start 197.19163 -138.616182)
		(end 200.236328 -138.616182)
		(width 0.11684)
		(layer "In2.Cu")
		(net "FM_SPD_CPU0_SWITCH_CTRL_N")
	)
	(segment
		(start 261.798816 -126.18974)
		(end 264.372344 -128.763268)
		(width 0.11684)
		(layer "In2.Cu")
		(net "FM_SPD_CPU0_SWITCH_CTRL_N")
	)
	(segment
		(start 247.2817 -135.17499)
		(end 253.465838 -128.990852)
		(width 0.11684)
		(layer "In2.Cu")
		(net "FM_SPD_CPU0_SWITCH_CTRL_N")
	)
	(segment
		(start 264.372344 -128.763268)
		(end 264.372344 -129.767076)
		(width 0.11684)
		(layer "In2.Cu")
		(net "FM_SPD_CPU0_SWITCH_CTRL_N")
	)
	(segment
		(start 267.175742 -101.82098)
		(end 267.175742 -77.592428)
		(width 0.11684)
		(layer "In4.Cu")
		(net "FM_SPD_CPU0_SWITCH_CTRL_N")
	)
	(segment
		(start 269.881858 -104.527096)
		(end 267.175742 -101.82098)
		(width 0.11684)
		(layer "In4.Cu")
		(net "FM_SPD_CPU0_SWITCH_CTRL_N")
	)
	(segment
		(start 264.372344 -117.051328)
		(end 269.881858 -111.541814)
		(width 0.11684)
		(layer "In4.Cu")
		(net "FM_SPD_CPU0_SWITCH_CTRL_N")
	)
	(segment
		(start 264.372344 -129.767076)
		(end 264.372344 -117.051328)
		(width 0.11684)
		(layer "In4.Cu")
		(net "FM_SPD_CPU0_SWITCH_CTRL_N")
	)
	(segment
		(start 269.881858 -111.541814)
		(end 269.881858 -104.527096)
		(width 0.11684)
		(layer "In4.Cu")
		(net "FM_SPD_CPU0_SWITCH_CTRL_N")
	)
	(segment
		(start 269.023592 -75.744578)
		(end 270.534384 -75.744578)
		(width 0.11684)
		(layer "In6.Cu")
		(net "FM_SPD_CPU0_SWITCH_CTRL_N")
	)
	(segment
		(start 392.542268 -44.389548)
		(end 413.7406 -44.389548)
		(width 0.11684)
		(layer "In6.Cu")
		(net "FM_SPD_CPU0_SWITCH_CTRL_N")
	)
	(segment
		(start 381.000508 -55.931308)
		(end 392.542268 -44.389548)
		(width 0.11684)
		(layer "In6.Cu")
		(net "FM_SPD_CPU0_SWITCH_CTRL_N")
	)
	(segment
		(start 288.22777 -58.279538)
		(end 307.80609 -58.279538)
		(width 0.11684)
		(layer "In6.Cu")
		(net "FM_SPD_CPU0_SWITCH_CTRL_N")
	)
	(segment
		(start 380.85649 -55.931308)
		(end 381.000508 -55.931308)
		(width 0.11684)
		(layer "In6.Cu")
		(net "FM_SPD_CPU0_SWITCH_CTRL_N")
	)
	(segment
		(start 323.284088 -55.995316)
		(end 380.792482 -55.995316)
		(width 0.11684)
		(layer "In6.Cu")
		(net "FM_SPD_CPU0_SWITCH_CTRL_N")
	)
	(segment
		(start 380.792482 -55.995316)
		(end 380.85649 -55.931308)
		(width 0.11684)
		(layer "In6.Cu")
		(net "FM_SPD_CPU0_SWITCH_CTRL_N")
	)
	(segment
		(start 307.80609 -58.279538)
		(end 310.796178 -55.28945)
		(width 0.11684)
		(layer "In6.Cu")
		(net "FM_SPD_CPU0_SWITCH_CTRL_N")
	)
	(segment
		(start 270.534384 -75.744578)
		(end 272.033746 -74.245216)
		(width 0.11684)
		(layer "In6.Cu")
		(net "FM_SPD_CPU0_SWITCH_CTRL_N")
	)
	(segment
		(start 429.8188 -43.094148)
		(end 430.5554 -42.357548)
		(width 0.11684)
		(layer "In6.Cu")
		(net "FM_SPD_CPU0_SWITCH_CTRL_N")
	)
	(segment
		(start 413.7406 -44.389548)
		(end 415.036 -43.094148)
		(width 0.11684)
		(layer "In6.Cu")
		(net "FM_SPD_CPU0_SWITCH_CTRL_N")
	)
	(segment
		(start 280.837894 -70.202806)
		(end 280.837894 -65.669414)
		(width 0.11684)
		(layer "In6.Cu")
		(net "FM_SPD_CPU0_SWITCH_CTRL_N")
	)
	(segment
		(start 280.837894 -65.669414)
		(end 288.22777 -58.279538)
		(width 0.11684)
		(layer "In6.Cu")
		(net "FM_SPD_CPU0_SWITCH_CTRL_N")
	)
	(segment
		(start 272.033746 -74.245216)
		(end 276.795484 -74.245216)
		(width 0.11684)
		(layer "In6.Cu")
		(net "FM_SPD_CPU0_SWITCH_CTRL_N")
	)
	(segment
		(start 276.795484 -74.245216)
		(end 280.837894 -70.202806)
		(width 0.11684)
		(layer "In6.Cu")
		(net "FM_SPD_CPU0_SWITCH_CTRL_N")
	)
	(segment
		(start 415.036 -43.094148)
		(end 429.8188 -43.094148)
		(width 0.11684)
		(layer "In6.Cu")
		(net "FM_SPD_CPU0_SWITCH_CTRL_N")
	)
	(segment
		(start 310.796178 -55.28945)
		(end 322.578222 -55.28945)
		(width 0.11684)
		(layer "In6.Cu")
		(net "FM_SPD_CPU0_SWITCH_CTRL_N")
	)
	(segment
		(start 322.578222 -55.28945)
		(end 323.284088 -55.995316)
		(width 0.11684)
		(layer "In6.Cu")
		(net "FM_SPD_CPU0_SWITCH_CTRL_N")
	)
	(segment
		(start 267.175742 -77.592428)
		(end 269.023592 -75.744578)
		(width 0.11684)
		(layer "In6.Cu")
		(net "FM_SPD_CPU0_SWITCH_CTRL_N")
	)
	(segment
		(start 181.437788 -14.403324)
		(end 181.437788 -14.296644)
		(width 0.10668)
		(layer "F.Cu")
		(net "FM_SOL_UART_CH_SEL_R")
	)
	(segment
		(start 183.262016 -16.549878)
		(end 183.262016 -15.76451)
		(width 0.10668)
		(layer "F.Cu")
		(net "FM_SOL_UART_CH_SEL_R")
	)
	(segment
		(start 182.493412 -15.458948)
		(end 181.437788 -14.403324)
		(width 0.10668)
		(layer "F.Cu")
		(net "FM_SOL_UART_CH_SEL_R")
	)
	(segment
		(start 182.956454 -15.458948)
		(end 182.493412 -15.458948)
		(width 0.10668)
		(layer "F.Cu")
		(net "FM_SOL_UART_CH_SEL_R")
	)
	(segment
		(start 183.262016 -15.76451)
		(end 182.956454 -15.458948)
		(width 0.10668)
		(layer "F.Cu")
		(net "FM_SOL_UART_CH_SEL_R")
	)
	(via
		(at 181.437788 -14.296644)
		(size 0.508)
		(drill 0.254)
		(layers "F.Cu" "B.Cu")
		(net "FM_SOL_UART_CH_SEL_R")
	)
	(segment
		(start 180.162962 -14.296644)
		(end 181.437788 -14.296644)
		(width 0.10668)
		(layer "B.Cu")
		(net "FM_SOL_UART_CH_SEL_R")
	)
	(segment
		(start 177.922174 -121.852944)
		(end 177.532284 -122.242834)
		(width 0.10668)
		(layer "F.Cu")
		(net "FM_SOL_UART_CH_SEL")
	)
	(via
		(at 179.239164 -12.19454)
		(size 0.508)
		(drill 0.254)
		(layers "F.Cu" "B.Cu")
		(net "FM_SOL_UART_CH_SEL")
	)
	(via
		(at 177.532284 -122.242834)
		(size 0.4572)
		(drill 0.254)
		(layers "F.Cu" "B.Cu")
		(net "FM_SOL_UART_CH_SEL")
	)
	(segment
		(start 180.162962 -13.118338)
		(end 179.239164 -12.19454)
		(width 0.10668)
		(layer "B.Cu")
		(net "FM_SOL_UART_CH_SEL")
	)
	(segment
		(start 180.162962 -13.496544)
		(end 180.162962 -13.118338)
		(width 0.10668)
		(layer "B.Cu")
		(net "FM_SOL_UART_CH_SEL")
	)
	(segment
		(start 169.566844 -92.028264)
		(end 171.115228 -90.47988)
		(width 0.11684)
		(layer "In11.Cu")
		(net "FM_SOL_UART_CH_SEL")
	)
	(segment
		(start 167.670226 -42.369486)
		(end 165.123622 -39.822882)
		(width 0.11684)
		(layer "In11.Cu")
		(net "FM_SOL_UART_CH_SEL")
	)
	(segment
		(start 164.852604 -48.360584)
		(end 167.670226 -45.542962)
		(width 0.11684)
		(layer "In11.Cu")
		(net "FM_SOL_UART_CH_SEL")
	)
	(segment
		(start 168.94048 -98.09734)
		(end 168.94048 -97.586292)
		(width 0.11684)
		(layer "In11.Cu")
		(net "FM_SOL_UART_CH_SEL")
	)
	(segment
		(start 177.532284 -122.242834)
		(end 177.532284 -121.795032)
		(width 0.11684)
		(layer "In11.Cu")
		(net "FM_SOL_UART_CH_SEL")
	)
	(segment
		(start 174.84852 -115.464336)
		(end 173.77918 -114.394996)
		(width 0.11684)
		(layer "In11.Cu")
		(net "FM_SOL_UART_CH_SEL")
	)
	(segment
		(start 166.272464 -79.407512)
		(end 166.272464 -56.589676)
		(width 0.11684)
		(layer "In11.Cu")
		(net "FM_SOL_UART_CH_SEL")
	)
	(segment
		(start 171.115228 -89.659206)
		(end 172.52442 -88.250014)
		(width 0.11684)
		(layer "In11.Cu")
		(net "FM_SOL_UART_CH_SEL")
	)
	(segment
		(start 166.272464 -56.589676)
		(end 164.852604 -55.169816)
		(width 0.11684)
		(layer "In11.Cu")
		(net "FM_SOL_UART_CH_SEL")
	)
	(segment
		(start 166.85768 -13.023596)
		(end 179.121054 -13.023596)
		(width 0.11684)
		(layer "In11.Cu")
		(net "FM_SOL_UART_CH_SEL")
	)
	(segment
		(start 172.52442 -88.250014)
		(end 172.52442 -85.659468)
		(width 0.11684)
		(layer "In11.Cu")
		(net "FM_SOL_UART_CH_SEL")
	)
	(segment
		(start 175.99914 -120.261888)
		(end 175.99914 -119.911876)
		(width 0.11684)
		(layer "In11.Cu")
		(net "FM_SOL_UART_CH_SEL")
	)
	(segment
		(start 179.121054 -13.023596)
		(end 179.239164 -12.905486)
		(width 0.11684)
		(layer "In11.Cu")
		(net "FM_SOL_UART_CH_SEL")
	)
	(segment
		(start 172.676566 -107.170982)
		(end 172.676566 -104.760522)
		(width 0.11684)
		(layer "In11.Cu")
		(net "FM_SOL_UART_CH_SEL")
	)
	(segment
		(start 177.532284 -121.795032)
		(end 175.99914 -120.261888)
		(width 0.11684)
		(layer "In11.Cu")
		(net "FM_SOL_UART_CH_SEL")
	)
	(segment
		(start 179.239164 -12.905486)
		(end 179.239164 -12.19454)
		(width 0.11684)
		(layer "In11.Cu")
		(net "FM_SOL_UART_CH_SEL")
	)
	(segment
		(start 172.52442 -85.659468)
		(end 166.272464 -79.407512)
		(width 0.11684)
		(layer "In11.Cu")
		(net "FM_SOL_UART_CH_SEL")
	)
	(segment
		(start 167.670226 -45.542962)
		(end 167.670226 -42.369486)
		(width 0.11684)
		(layer "In11.Cu")
		(net "FM_SOL_UART_CH_SEL")
	)
	(segment
		(start 171.115228 -90.47988)
		(end 171.115228 -89.659206)
		(width 0.11684)
		(layer "In11.Cu")
		(net "FM_SOL_UART_CH_SEL")
	)
	(segment
		(start 164.852604 -55.169816)
		(end 164.852604 -48.360584)
		(width 0.11684)
		(layer "In11.Cu")
		(net "FM_SOL_UART_CH_SEL")
	)
	(segment
		(start 173.77918 -108.273596)
		(end 172.676566 -107.170982)
		(width 0.11684)
		(layer "In11.Cu")
		(net "FM_SOL_UART_CH_SEL")
	)
	(segment
		(start 165.123622 -39.822882)
		(end 165.123622 -20.540726)
		(width 0.11684)
		(layer "In11.Cu")
		(net "FM_SOL_UART_CH_SEL")
	)
	(segment
		(start 169.566844 -96.959928)
		(end 169.566844 -92.028264)
		(width 0.11684)
		(layer "In11.Cu")
		(net "FM_SOL_UART_CH_SEL")
	)
	(segment
		(start 175.99914 -119.911876)
		(end 174.84852 -118.761256)
		(width 0.11684)
		(layer "In11.Cu")
		(net "FM_SOL_UART_CH_SEL")
	)
	(segment
		(start 173.77918 -114.394996)
		(end 173.77918 -108.273596)
		(width 0.11684)
		(layer "In11.Cu")
		(net "FM_SOL_UART_CH_SEL")
	)
	(segment
		(start 165.04412 -13.75537)
		(end 166.125906 -13.75537)
		(width 0.11684)
		(layer "In11.Cu")
		(net "FM_SOL_UART_CH_SEL")
	)
	(segment
		(start 164.385498 -14.413992)
		(end 165.04412 -13.75537)
		(width 0.11684)
		(layer "In11.Cu")
		(net "FM_SOL_UART_CH_SEL")
	)
	(segment
		(start 174.84852 -118.761256)
		(end 174.84852 -115.464336)
		(width 0.11684)
		(layer "In11.Cu")
		(net "FM_SOL_UART_CH_SEL")
	)
	(segment
		(start 168.94048 -97.586292)
		(end 169.566844 -96.959928)
		(width 0.11684)
		(layer "In11.Cu")
		(net "FM_SOL_UART_CH_SEL")
	)
	(segment
		(start 164.385498 -19.802602)
		(end 164.385498 -14.413992)
		(width 0.11684)
		(layer "In11.Cu")
		(net "FM_SOL_UART_CH_SEL")
	)
	(segment
		(start 172.676566 -104.760522)
		(end 169.64914 -101.733096)
		(width 0.11684)
		(layer "In11.Cu")
		(net "FM_SOL_UART_CH_SEL")
	)
	(segment
		(start 166.125906 -13.75537)
		(end 166.85768 -13.023596)
		(width 0.11684)
		(layer "In11.Cu")
		(net "FM_SOL_UART_CH_SEL")
	)
	(segment
		(start 169.64914 -98.806)
		(end 168.94048 -98.09734)
		(width 0.11684)
		(layer "In11.Cu")
		(net "FM_SOL_UART_CH_SEL")
	)
	(segment
		(start 165.123622 -20.540726)
		(end 164.385498 -19.802602)
		(width 0.11684)
		(layer "In11.Cu")
		(net "FM_SOL_UART_CH_SEL")
	)
	(segment
		(start 169.64914 -101.733096)
		(end 169.64914 -98.806)
		(width 0.11684)
		(layer "In11.Cu")
		(net "FM_SOL_UART_CH_SEL")
	)
	(segment
		(start 185.039 -128.977898)
		(end 185.039 -127.003556)
		(width 0.10668)
		(layer "F.Cu")
		(net "FM_SMERR_LED_R_N")
	)
	(segment
		(start 185.248296 -124.126752)
		(end 185.922158 -123.45289)
		(width 0.10668)
		(layer "F.Cu")
		(net "FM_SMERR_LED_R_N")
	)
	(segment
		(start 185.248296 -126.79426)
		(end 185.248296 -124.126752)
		(width 0.10668)
		(layer "F.Cu")
		(net "FM_SMERR_LED_R_N")
	)
	(segment
		(start 185.039 -127.003556)
		(end 185.248296 -126.79426)
		(width 0.10668)
		(layer "F.Cu")
		(net "FM_SMERR_LED_R_N")
	)
	(via
		(at 185.039 -127.003556)
		(size 0.762)
		(drill 0.381)
		(layers "F.Cu" "B.Cu")
		(net "FM_SMERR_LED_R_N")
	)
	(segment
		(start 185.039 -130.393948)
		(end 185.039 -129.777998)
		(width 0.10668)
		(layer "F.Cu")
		(net "FM_SMERR_LED_N")
	)
	(segment
		(start 200.570846 -126.376938)
		(end 206.342488 -126.376938)
		(width 0.10668)
		(layer "F.Cu")
		(net "FM_SMERR_LED_N")
	)
	(segment
		(start 206.342488 -126.376938)
		(end 206.549498 -126.583948)
		(width 0.10668)
		(layer "F.Cu")
		(net "FM_SMERR_LED_N")
	)
	(segment
		(start 346.549726 -29.51607)
		(end 346.549726 -30.57652)
		(width 0.10668)
		(layer "F.Cu")
		(net "FM_SMERR_LED_N")
	)
	(segment
		(start 200.011284 -125.817376)
		(end 200.570846 -126.376938)
		(width 0.10668)
		(layer "F.Cu")
		(net "FM_SMERR_LED_N")
	)
	(via
		(at 206.549498 -126.583948)
		(size 0.508)
		(drill 0.254)
		(layers "F.Cu" "B.Cu")
		(net "FM_SMERR_LED_N")
	)
	(via
		(at 346.549726 -30.57652)
		(size 0.508)
		(drill 0.254)
		(layers "F.Cu" "B.Cu")
		(net "FM_SMERR_LED_N")
	)
	(via
		(at 185.039 -130.393948)
		(size 0.508)
		(drill 0.254)
		(layers "F.Cu" "B.Cu")
		(net "FM_SMERR_LED_N")
	)
	(via
		(at 229.44836 -128.29667)
		(size 0.508)
		(drill 0.254)
		(layers "F.Cu" "B.Cu")
		(net "FM_SMERR_LED_N")
	)
	(via
		(at 200.011284 -125.817376)
		(size 0.508)
		(drill 0.254)
		(layers "F.Cu" "B.Cu")
		(net "FM_SMERR_LED_N")
	)
	(via
		(at 231.331008 -72.679814)
		(size 0.508)
		(drill 0.254)
		(layers "F.Cu" "B.Cu")
		(net "FM_SMERR_LED_N")
	)
	(segment
		(start 214.92845 -128.33731)
		(end 213.175088 -126.583948)
		(width 0.11684)
		(layer "In2.Cu")
		(net "FM_SMERR_LED_N")
	)
	(segment
		(start 228.357938 -129.387092)
		(end 218.657932 -129.387092)
		(width 0.11684)
		(layer "In2.Cu")
		(net "FM_SMERR_LED_N")
	)
	(segment
		(start 213.175088 -126.583948)
		(end 206.549498 -126.583948)
		(width 0.11684)
		(layer "In2.Cu")
		(net "FM_SMERR_LED_N")
	)
	(segment
		(start 217.60815 -128.33731)
		(end 214.92845 -128.33731)
		(width 0.11684)
		(layer "In2.Cu")
		(net "FM_SMERR_LED_N")
	)
	(segment
		(start 229.44836 -128.29667)
		(end 228.357938 -129.387092)
		(width 0.11684)
		(layer "In2.Cu")
		(net "FM_SMERR_LED_N")
	)
	(segment
		(start 218.657932 -129.387092)
		(end 217.60815 -128.33731)
		(width 0.11684)
		(layer "In2.Cu")
		(net "FM_SMERR_LED_N")
	)
	(segment
		(start 229.44836 -128.29667)
		(end 229.44836 -122.483372)
		(width 0.11684)
		(layer "In4.Cu")
		(net "FM_SMERR_LED_N")
	)
	(segment
		(start 228.34473 -121.379742)
		(end 228.34473 -75.392026)
		(width 0.11684)
		(layer "In4.Cu")
		(net "FM_SMERR_LED_N")
	)
	(segment
		(start 228.34473 -75.392026)
		(end 231.056942 -72.679814)
		(width 0.11684)
		(layer "In4.Cu")
		(net "FM_SMERR_LED_N")
	)
	(segment
		(start 231.056942 -72.679814)
		(end 231.331008 -72.679814)
		(width 0.11684)
		(layer "In4.Cu")
		(net "FM_SMERR_LED_N")
	)
	(segment
		(start 229.44836 -122.483372)
		(end 228.34473 -121.379742)
		(width 0.11684)
		(layer "In4.Cu")
		(net "FM_SMERR_LED_N")
	)
	(segment
		(start 325.90867 -35.023552)
		(end 320.224404 -40.707818)
		(width 0.11684)
		(layer "In6.Cu")
		(net "FM_SMERR_LED_N")
	)
	(segment
		(start 196.213984 -131.892294)
		(end 198.458328 -129.64795)
		(width 0.11684)
		(layer "In6.Cu")
		(net "FM_SMERR_LED_N")
	)
	(segment
		(start 344.515694 -29.96311)
		(end 343.748868 -30.729936)
		(width 0.11684)
		(layer "In6.Cu")
		(net "FM_SMERR_LED_N")
	)
	(segment
		(start 185.039 -130.393948)
		(end 185.5724 -130.927348)
		(width 0.11684)
		(layer "In6.Cu")
		(net "FM_SMERR_LED_N")
	)
	(segment
		(start 198.458328 -125.48743)
		(end 198.597774 -125.347984)
		(width 0.11684)
		(layer "In6.Cu")
		(net "FM_SMERR_LED_N")
	)
	(segment
		(start 289.600894 -47.652432)
		(end 272.039842 -65.213484)
		(width 0.11684)
		(layer "In6.Cu")
		(net "FM_SMERR_LED_N")
	)
	(segment
		(start 320.224404 -41.646602)
		(end 315.81852 -46.052486)
		(width 0.11684)
		(layer "In6.Cu")
		(net "FM_SMERR_LED_N")
	)
	(segment
		(start 192.31737 -132.036058)
		(end 192.461134 -131.892294)
		(width 0.11684)
		(layer "In6.Cu")
		(net "FM_SMERR_LED_N")
	)
	(segment
		(start 345.925648 -29.96311)
		(end 344.515694 -29.96311)
		(width 0.11684)
		(layer "In6.Cu")
		(net "FM_SMERR_LED_N")
	)
	(segment
		(start 185.5724 -130.927348)
		(end 187.691268 -130.927348)
		(width 0.11684)
		(layer "In6.Cu")
		(net "FM_SMERR_LED_N")
	)
	(segment
		(start 343.748868 -30.729936)
		(end 329.388978 -30.729936)
		(width 0.11684)
		(layer "In6.Cu")
		(net "FM_SMERR_LED_N")
	)
	(segment
		(start 259.749798 -72.192134)
		(end 258.533646 -72.192134)
		(width 0.11684)
		(layer "In6.Cu")
		(net "FM_SMERR_LED_N")
	)
	(segment
		(start 257.268726 -73.457054)
		(end 232.108248 -73.457054)
		(width 0.11684)
		(layer "In6.Cu")
		(net "FM_SMERR_LED_N")
	)
	(segment
		(start 345.930982 -29.957776)
		(end 345.925648 -29.96311)
		(width 0.11684)
		(layer "In6.Cu")
		(net "FM_SMERR_LED_N")
	)
	(segment
		(start 199.980296 -125.817376)
		(end 200.011284 -125.817376)
		(width 0.11684)
		(layer "In6.Cu")
		(net "FM_SMERR_LED_N")
	)
	(segment
		(start 198.458328 -129.64795)
		(end 198.458328 -125.48743)
		(width 0.11684)
		(layer "In6.Cu")
		(net "FM_SMERR_LED_N")
	)
	(segment
		(start 301.94631 -47.652432)
		(end 289.600894 -47.652432)
		(width 0.11684)
		(layer "In6.Cu")
		(net "FM_SMERR_LED_N")
	)
	(segment
		(start 272.039842 -65.213484)
		(end 266.728448 -65.213484)
		(width 0.11684)
		(layer "In6.Cu")
		(net "FM_SMERR_LED_N")
	)
	(segment
		(start 258.533646 -72.192134)
		(end 257.268726 -73.457054)
		(width 0.11684)
		(layer "In6.Cu")
		(net "FM_SMERR_LED_N")
	)
	(segment
		(start 306.63388 -46.521878)
		(end 303.076864 -46.521878)
		(width 0.11684)
		(layer "In6.Cu")
		(net "FM_SMERR_LED_N")
	)
	(segment
		(start 329.388978 -30.729936)
		(end 325.90867 -34.210244)
		(width 0.11684)
		(layer "In6.Cu")
		(net "FM_SMERR_LED_N")
	)
	(segment
		(start 266.728448 -65.213484)
		(end 259.749798 -72.192134)
		(width 0.11684)
		(layer "In6.Cu")
		(net "FM_SMERR_LED_N")
	)
	(segment
		(start 303.076864 -46.521878)
		(end 301.94631 -47.652432)
		(width 0.11684)
		(layer "In6.Cu")
		(net "FM_SMERR_LED_N")
	)
	(segment
		(start 320.224404 -40.707818)
		(end 320.224404 -41.646602)
		(width 0.11684)
		(layer "In6.Cu")
		(net "FM_SMERR_LED_N")
	)
	(segment
		(start 315.81852 -46.052486)
		(end 307.103272 -46.052486)
		(width 0.11684)
		(layer "In6.Cu")
		(net "FM_SMERR_LED_N")
	)
	(segment
		(start 232.108248 -73.457054)
		(end 231.331008 -72.679814)
		(width 0.11684)
		(layer "In6.Cu")
		(net "FM_SMERR_LED_N")
	)
	(segment
		(start 346.549726 -30.57652)
		(end 345.930982 -29.957776)
		(width 0.11684)
		(layer "In6.Cu")
		(net "FM_SMERR_LED_N")
	)
	(segment
		(start 198.597774 -125.347984)
		(end 199.510904 -125.347984)
		(width 0.11684)
		(layer "In6.Cu")
		(net "FM_SMERR_LED_N")
	)
	(segment
		(start 188.799978 -132.036058)
		(end 192.31737 -132.036058)
		(width 0.11684)
		(layer "In6.Cu")
		(net "FM_SMERR_LED_N")
	)
	(segment
		(start 307.103272 -46.052486)
		(end 306.63388 -46.521878)
		(width 0.11684)
		(layer "In6.Cu")
		(net "FM_SMERR_LED_N")
	)
	(segment
		(start 192.461134 -131.892294)
		(end 196.213984 -131.892294)
		(width 0.11684)
		(layer "In6.Cu")
		(net "FM_SMERR_LED_N")
	)
	(segment
		(start 325.90867 -34.210244)
		(end 325.90867 -35.023552)
		(width 0.11684)
		(layer "In6.Cu")
		(net "FM_SMERR_LED_N")
	)
	(segment
		(start 199.510904 -125.347984)
		(end 199.980296 -125.817376)
		(width 0.11684)
		(layer "In6.Cu")
		(net "FM_SMERR_LED_N")
	)
	(segment
		(start 187.691268 -130.927348)
		(end 188.799978 -132.036058)
		(width 0.11684)
		(layer "In6.Cu")
		(net "FM_SMERR_LED_N")
	)
	(segment
		(start 343.458546 -23.48865)
		(end 343.458546 -22.55139)
		(width 0.10668)
		(layer "F.Cu")
		(net "FM_SMERR_BUF_R_LED_N")
	)
	(segment
		(start 343.994486 -22.01545)
		(end 343.994486 -21.03501)
		(width 0.10668)
		(layer "F.Cu")
		(net "FM_SMERR_BUF_R_LED_N")
	)
	(segment
		(start 343.458546 -22.55139)
		(end 343.740486 -22.26945)
		(width 0.10668)
		(layer "F.Cu")
		(net "FM_SMERR_BUF_R_LED_N")
	)
	(segment
		(start 343.740486 -22.26945)
		(end 343.994486 -22.01545)
		(width 0.10668)
		(layer "F.Cu")
		(net "FM_SMERR_BUF_R_LED_N")
	)
	(segment
		(start 344.474546 -23.48865)
		(end 343.458546 -23.48865)
		(width 0.10668)
		(layer "F.Cu")
		(net "FM_SMERR_BUF_R_LED_N")
	)
	(via
		(at 343.740486 -22.26945)
		(size 0.762)
		(drill 0.381)
		(layers "F.Cu" "B.Cu")
		(net "FM_SMERR_BUF_R_LED_N")
	)
	(segment
		(start 344.474546 -25.50795)
		(end 344.474546 -24.28875)
		(width 0.10668)
		(layer "F.Cu")
		(net "FM_SMERR_BUF_LED_N")
	)
	(segment
		(start 345.599766 -27.065986)
		(end 345.599766 -26.63317)
		(width 0.10668)
		(layer "F.Cu")
		(net "FM_SMERR_BUF_LED_N")
	)
	(segment
		(start 345.599766 -26.63317)
		(end 344.474546 -25.50795)
		(width 0.10668)
		(layer "F.Cu")
		(net "FM_SMERR_BUF_LED_N")
	)
	(via
		(at 344.474546 -25.50795)
		(size 0.762)
		(drill 0.381)
		(layers "F.Cu" "B.Cu")
		(net "FM_SMERR_BUF_LED_N")
	)
	(segment
		(start 187.833 -97.917)
		(end 188.21781 -98.30181)
		(width 0.10668)
		(layer "F.Cu")
		(net "FM_SMB_RST_E1S_0_N")
	)
	(segment
		(start 188.21781 -98.30181)
		(end 188.341 -98.599498)
		(width 0.10668)
		(layer "F.Cu")
		(net "FM_SMB_RST_E1S_0_N")
	)
	(segment
		(start 187.911994 -102.283006)
		(end 187.911994 -107.063032)
		(width 0.10668)
		(layer "F.Cu")
		(net "FM_SMB_RST_E1S_0_N")
	)
	(segment
		(start 187.911994 -107.063032)
		(end 187.522104 -107.452922)
		(width 0.10668)
		(layer "F.Cu")
		(net "FM_SMB_RST_E1S_0_N")
	)
	(segment
		(start 188.341 -98.599498)
		(end 188.341 -101.854)
		(width 0.10668)
		(layer "F.Cu")
		(net "FM_SMB_RST_E1S_0_N")
	)
	(segment
		(start 188.341 -101.854)
		(end 187.911994 -102.283006)
		(width 0.10668)
		(layer "F.Cu")
		(net "FM_SMB_RST_E1S_0_N")
	)
	(segment
		(start 187.833 -97.409)
		(end 187.833 -97.917)
		(width 0.10668)
		(layer "F.Cu")
		(net "FM_SMB_RST_E1S_0_N")
	)
	(segment
		(start 187.833 -96.503998)
		(end 187.833 -97.409)
		(width 0.10668)
		(layer "F.Cu")
		(net "FM_SMB_RST_E1S_0_N")
	)
	(segment
		(start 188.849 -96.503998)
		(end 187.833 -96.503998)
		(width 0.10668)
		(layer "F.Cu")
		(net "FM_SMB_RST_E1S_0_N")
	)
	(via
		(at 187.833 -97.409)
		(size 0.762)
		(drill 0.381)
		(layers "F.Cu" "B.Cu")
		(net "FM_SMB_RST_E1S_0_N")
	)
	(via
		(at 107.061 -421.005)
		(size 0.6604)
		(drill 0.3302)
		(layers "F.Cu" "B.Cu")
		(net "FM_SMB_2_ALERT_GPU_N")
	)
	(segment
		(start 105.93705 -419.989)
		(end 106.68 -419.24605)
		(width 0.10668)
		(layer "B.Cu")
		(net "FM_SMB_2_ALERT_GPU_N")
	)
	(segment
		(start 107.061 -421.005)
		(end 105.93705 -421.005)
		(width 0.10668)
		(layer "B.Cu")
		(net "FM_SMB_2_ALERT_GPU_N")
	)
	(segment
		(start 121.666 -421.005)
		(end 117.221 -421.005)
		(width 0.10668)
		(layer "B.Cu")
		(net "FM_SMB_2_ALERT_GPU_N")
	)
	(segment
		(start 135.749792 -424.689778)
		(end 132.954014 -421.894)
		(width 0.10668)
		(layer "B.Cu")
		(net "FM_SMB_2_ALERT_GPU_N")
	)
	(segment
		(start 106.68 -419.24605)
		(end 106.68 -418.27196)
		(width 0.10668)
		(layer "B.Cu")
		(net "FM_SMB_2_ALERT_GPU_N")
	)
	(segment
		(start 116.332 -420.116)
		(end 107.95 -420.116)
		(width 0.10668)
		(layer "B.Cu")
		(net "FM_SMB_2_ALERT_GPU_N")
	)
	(segment
		(start 107.95 -420.116)
		(end 107.061 -421.005)
		(width 0.10668)
		(layer "B.Cu")
		(net "FM_SMB_2_ALERT_GPU_N")
	)
	(segment
		(start 105.93705 -421.005)
		(end 105.93705 -419.989)
		(width 0.10668)
		(layer "B.Cu")
		(net "FM_SMB_2_ALERT_GPU_N")
	)
	(segment
		(start 117.221 -421.005)
		(end 116.332 -420.116)
		(width 0.10668)
		(layer "B.Cu")
		(net "FM_SMB_2_ALERT_GPU_N")
	)
	(segment
		(start 132.954014 -421.894)
		(end 122.555 -421.894)
		(width 0.10668)
		(layer "B.Cu")
		(net "FM_SMB_2_ALERT_GPU_N")
	)
	(segment
		(start 122.555 -421.894)
		(end 121.666 -421.005)
		(width 0.10668)
		(layer "B.Cu")
		(net "FM_SMB_2_ALERT_GPU_N")
	)
	(segment
		(start 202.51039 -123.785376)
		(end 202.54087 -123.815856)
		(width 0.10668)
		(layer "F.Cu")
		(net "FM_SMB_2_ALERT_GPU_ISO_N")
	)
	(segment
		(start 197.669658 -123.785376)
		(end 202.51039 -123.785376)
		(width 0.10668)
		(layer "F.Cu")
		(net "FM_SMB_2_ALERT_GPU_ISO_N")
	)
	(via
		(at 109.728 -419.1)
		(size 0.508)
		(drill 0.254)
		(layers "F.Cu" "B.Cu")
		(net "FM_SMB_2_ALERT_GPU_ISO_N")
	)
	(via
		(at 23.086568 -420.306246)
		(size 0.508)
		(drill 0.254)
		(layers "F.Cu" "B.Cu")
		(net "FM_SMB_2_ALERT_GPU_ISO_N")
	)
	(via
		(at 201.766678 -142.238984)
		(size 0.508)
		(drill 0.254)
		(layers "F.Cu" "B.Cu")
		(net "FM_SMB_2_ALERT_GPU_ISO_N")
	)
	(via
		(at 100.698808 -400.745452)
		(size 0.508)
		(drill 0.254)
		(layers "F.Cu" "B.Cu")
		(net "FM_SMB_2_ALERT_GPU_ISO_N")
	)
	(via
		(at 202.54087 -123.815856)
		(size 0.508)
		(drill 0.254)
		(layers "F.Cu" "B.Cu")
		(net "FM_SMB_2_ALERT_GPU_ISO_N")
	)
	(segment
		(start 108.204 -418.23005)
		(end 108.712 -418.23005)
		(width 0.10668)
		(layer "B.Cu")
		(net "FM_SMB_2_ALERT_GPU_ISO_N")
	)
	(segment
		(start 108.712 -418.23005)
		(end 109.728 -418.23005)
		(width 0.10668)
		(layer "B.Cu")
		(net "FM_SMB_2_ALERT_GPU_ISO_N")
	)
	(segment
		(start 109.728 -418.23005)
		(end 109.728 -419.1)
		(width 0.10668)
		(layer "B.Cu")
		(net "FM_SMB_2_ALERT_GPU_ISO_N")
	)
	(segment
		(start 108.16209 -418.27196)
		(end 108.204 -418.23005)
		(width 0.10668)
		(layer "B.Cu")
		(net "FM_SMB_2_ALERT_GPU_ISO_N")
	)
	(segment
		(start 107.329986 -418.27196)
		(end 108.16209 -418.27196)
		(width 0.10668)
		(layer "B.Cu")
		(net "FM_SMB_2_ALERT_GPU_ISO_N")
	)
	(segment
		(start 95.102172 -398.965928)
		(end 49.590452 -398.965928)
		(width 0.11684)
		(layer "In4.Cu")
		(net "FM_SMB_2_ALERT_GPU_ISO_N")
	)
	(segment
		(start 201.381868 -132.635498)
		(end 201.381868 -137.266426)
		(width 0.11684)
		(layer "In4.Cu")
		(net "FM_SMB_2_ALERT_GPU_ISO_N")
	)
	(segment
		(start 201.189336 -137.458958)
		(end 201.189336 -141.661642)
		(width 0.11684)
		(layer "In4.Cu")
		(net "FM_SMB_2_ALERT_GPU_ISO_N")
	)
	(segment
		(start 24.119078 -419.273736)
		(end 23.086568 -420.306246)
		(width 0.11684)
		(layer "In4.Cu")
		(net "FM_SMB_2_ALERT_GPU_ISO_N")
	)
	(segment
		(start 202.54087 -123.815856)
		(end 201.252582 -125.104144)
		(width 0.11684)
		(layer "In4.Cu")
		(net "FM_SMB_2_ALERT_GPU_ISO_N")
	)
	(segment
		(start 201.381868 -137.266426)
		(end 201.189336 -137.458958)
		(width 0.11684)
		(layer "In4.Cu")
		(net "FM_SMB_2_ALERT_GPU_ISO_N")
	)
	(segment
		(start 96.881696 -400.745452)
		(end 95.102172 -398.965928)
		(width 0.11684)
		(layer "In4.Cu")
		(net "FM_SMB_2_ALERT_GPU_ISO_N")
	)
	(segment
		(start 200.76541 -132.01904)
		(end 201.381868 -132.635498)
		(width 0.11684)
		(layer "In4.Cu")
		(net "FM_SMB_2_ALERT_GPU_ISO_N")
	)
	(segment
		(start 38.860476 -411.436566)
		(end 37.771324 -412.525718)
		(width 0.11684)
		(layer "In4.Cu")
		(net "FM_SMB_2_ALERT_GPU_ISO_N")
	)
	(segment
		(start 38.860476 -409.37307)
		(end 38.860476 -411.436566)
		(width 0.11684)
		(layer "In4.Cu")
		(net "FM_SMB_2_ALERT_GPU_ISO_N")
	)
	(segment
		(start 37.197792 -402.804884)
		(end 37.197792 -407.710386)
		(width 0.11684)
		(layer "In4.Cu")
		(net "FM_SMB_2_ALERT_GPU_ISO_N")
	)
	(segment
		(start 26.692352 -419.273736)
		(end 24.119078 -419.273736)
		(width 0.11684)
		(layer "In4.Cu")
		(net "FM_SMB_2_ALERT_GPU_ISO_N")
	)
	(segment
		(start 201.252582 -127.65659)
		(end 200.76541 -128.143762)
		(width 0.11684)
		(layer "In4.Cu")
		(net "FM_SMB_2_ALERT_GPU_ISO_N")
	)
	(segment
		(start 37.771324 -412.525718)
		(end 37.771324 -413.226504)
		(width 0.11684)
		(layer "In4.Cu")
		(net "FM_SMB_2_ALERT_GPU_ISO_N")
	)
	(segment
		(start 44.57319 -401.405852)
		(end 43.522392 -400.355054)
		(width 0.11684)
		(layer "In4.Cu")
		(net "FM_SMB_2_ALERT_GPU_ISO_N")
	)
	(segment
		(start 37.771324 -413.226504)
		(end 33.35401 -417.643818)
		(width 0.11684)
		(layer "In4.Cu")
		(net "FM_SMB_2_ALERT_GPU_ISO_N")
	)
	(segment
		(start 43.522392 -400.355054)
		(end 39.647622 -400.355054)
		(width 0.11684)
		(layer "In4.Cu")
		(net "FM_SMB_2_ALERT_GPU_ISO_N")
	)
	(segment
		(start 37.197792 -407.710386)
		(end 38.860476 -409.37307)
		(width 0.11684)
		(layer "In4.Cu")
		(net "FM_SMB_2_ALERT_GPU_ISO_N")
	)
	(segment
		(start 47.150528 -401.405852)
		(end 44.57319 -401.405852)
		(width 0.11684)
		(layer "In4.Cu")
		(net "FM_SMB_2_ALERT_GPU_ISO_N")
	)
	(segment
		(start 100.698808 -400.745452)
		(end 96.881696 -400.745452)
		(width 0.11684)
		(layer "In4.Cu")
		(net "FM_SMB_2_ALERT_GPU_ISO_N")
	)
	(segment
		(start 33.35401 -417.643818)
		(end 28.32227 -417.643818)
		(width 0.11684)
		(layer "In4.Cu")
		(net "FM_SMB_2_ALERT_GPU_ISO_N")
	)
	(segment
		(start 201.252582 -125.104144)
		(end 201.252582 -127.65659)
		(width 0.11684)
		(layer "In4.Cu")
		(net "FM_SMB_2_ALERT_GPU_ISO_N")
	)
	(segment
		(start 28.32227 -417.643818)
		(end 26.692352 -419.273736)
		(width 0.11684)
		(layer "In4.Cu")
		(net "FM_SMB_2_ALERT_GPU_ISO_N")
	)
	(segment
		(start 39.647622 -400.355054)
		(end 37.197792 -402.804884)
		(width 0.11684)
		(layer "In4.Cu")
		(net "FM_SMB_2_ALERT_GPU_ISO_N")
	)
	(segment
		(start 49.590452 -398.965928)
		(end 47.150528 -401.405852)
		(width 0.11684)
		(layer "In4.Cu")
		(net "FM_SMB_2_ALERT_GPU_ISO_N")
	)
	(segment
		(start 201.189336 -141.661642)
		(end 201.766678 -142.238984)
		(width 0.11684)
		(layer "In4.Cu")
		(net "FM_SMB_2_ALERT_GPU_ISO_N")
	)
	(segment
		(start 200.76541 -128.143762)
		(end 200.76541 -132.01904)
		(width 0.11684)
		(layer "In4.Cu")
		(net "FM_SMB_2_ALERT_GPU_ISO_N")
	)
	(segment
		(start 157.899862 -142.390114)
		(end 151.08555 -135.575802)
		(width 0.11684)
		(layer "In13.Cu")
		(net "FM_SMB_2_ALERT_GPU_ISO_N")
	)
	(segment
		(start 5.254752 -185.73242)
		(end 5.254752 -334.860392)
		(width 0.11684)
		(layer "In13.Cu")
		(net "FM_SMB_2_ALERT_GPU_ISO_N")
	)
	(segment
		(start 151.08555 -135.575802)
		(end 94.158054 -135.575802)
		(width 0.11684)
		(layer "In13.Cu")
		(net "FM_SMB_2_ALERT_GPU_ISO_N")
	)
	(segment
		(start 12.009628 -415.136076)
		(end 12.009628 -416.786314)
		(width 0.11684)
		(layer "In13.Cu")
		(net "FM_SMB_2_ALERT_GPU_ISO_N")
	)
	(segment
		(start 4.015486 -357.837486)
		(end 4.718812 -358.540812)
		(width 0.11684)
		(layer "In13.Cu")
		(net "FM_SMB_2_ALERT_GPU_ISO_N")
	)
	(segment
		(start 184.72658 -143.082264)
		(end 177.539142 -143.082264)
		(width 0.11684)
		(layer "In13.Cu")
		(net "FM_SMB_2_ALERT_GPU_ISO_N")
	)
	(segment
		(start 4.718812 -358.540812)
		(end 4.718812 -366.291622)
		(width 0.11684)
		(layer "In13.Cu")
		(net "FM_SMB_2_ALERT_GPU_ISO_N")
	)
	(segment
		(start 78.764638 -135.2169)
		(end 77.170534 -136.811004)
		(width 0.11684)
		(layer "In13.Cu")
		(net "FM_SMB_2_ALERT_GPU_ISO_N")
	)
	(segment
		(start 103.722678 -406.26665)
		(end 104.618536 -407.162508)
		(width 0.11684)
		(layer "In13.Cu")
		(net "FM_SMB_2_ALERT_GPU_ISO_N")
	)
	(segment
		(start 5.610606 -384.049778)
		(end 7.13867 -385.577842)
		(width 0.11684)
		(layer "In13.Cu")
		(net "FM_SMB_2_ALERT_GPU_ISO_N")
	)
	(segment
		(start 7.097268 -396.559532)
		(end 7.097268 -402.89226)
		(width 0.11684)
		(layer "In13.Cu")
		(net "FM_SMB_2_ALERT_GPU_ISO_N")
	)
	(segment
		(start 17.159986 -173.827186)
		(end 5.254752 -185.73242)
		(width 0.11684)
		(layer "In13.Cu")
		(net "FM_SMB_2_ALERT_GPU_ISO_N")
	)
	(segment
		(start 77.170534 -136.811004)
		(end 30.163262 -136.811004)
		(width 0.11684)
		(layer "In13.Cu")
		(net "FM_SMB_2_ALERT_GPU_ISO_N")
	)
	(segment
		(start 21.366988 -418.586666)
		(end 23.086568 -420.306246)
		(width 0.11684)
		(layer "In13.Cu")
		(net "FM_SMB_2_ALERT_GPU_ISO_N")
	)
	(segment
		(start 11.354054 -411.847792)
		(end 11.354054 -414.480502)
		(width 0.11684)
		(layer "In13.Cu")
		(net "FM_SMB_2_ALERT_GPU_ISO_N")
	)
	(segment
		(start 8.482076 -385.577842)
		(end 11.193272 -388.289038)
		(width 0.11684)
		(layer "In13.Cu")
		(net "FM_SMB_2_ALERT_GPU_ISO_N")
	)
	(segment
		(start 12.741402 -408.536394)
		(end 12.741402 -410.460444)
		(width 0.11684)
		(layer "In13.Cu")
		(net "FM_SMB_2_ALERT_GPU_ISO_N")
	)
	(segment
		(start 110.236 -417.83)
		(end 110.236 -418.592)
		(width 0.11684)
		(layer "In13.Cu")
		(net "FM_SMB_2_ALERT_GPU_ISO_N")
	)
	(segment
		(start 185.514488 -142.294356)
		(end 184.72658 -143.082264)
		(width 0.11684)
		(layer "In13.Cu")
		(net "FM_SMB_2_ALERT_GPU_ISO_N")
	)
	(segment
		(start 110.49 -410.77388)
		(end 110.49 -415.798)
		(width 0.11684)
		(layer "In13.Cu")
		(net "FM_SMB_2_ALERT_GPU_ISO_N")
	)
	(segment
		(start 7.097268 -402.89226)
		(end 12.741402 -408.536394)
		(width 0.11684)
		(layer "In13.Cu")
		(net "FM_SMB_2_ALERT_GPU_ISO_N")
	)
	(segment
		(start 201.766678 -142.238984)
		(end 199.63003 -140.102336)
		(width 0.11684)
		(layer "In13.Cu")
		(net "FM_SMB_2_ALERT_GPU_ISO_N")
	)
	(segment
		(start 110.236 -418.592)
		(end 109.728 -419.1)
		(width 0.11684)
		(layer "In13.Cu")
		(net "FM_SMB_2_ALERT_GPU_ISO_N")
	)
	(segment
		(start 5.254752 -334.860392)
		(end 4.015486 -336.099658)
		(width 0.11684)
		(layer "In13.Cu")
		(net "FM_SMB_2_ALERT_GPU_ISO_N")
	)
	(segment
		(start 17.159986 -149.81428)
		(end 17.159986 -173.827186)
		(width 0.11684)
		(layer "In13.Cu")
		(net "FM_SMB_2_ALERT_GPU_ISO_N")
	)
	(segment
		(start 12.741402 -410.460444)
		(end 11.354054 -411.847792)
		(width 0.11684)
		(layer "In13.Cu")
		(net "FM_SMB_2_ALERT_GPU_ISO_N")
	)
	(segment
		(start 100.914708 -400.529552)
		(end 102.73284 -400.529552)
		(width 0.11684)
		(layer "In13.Cu")
		(net "FM_SMB_2_ALERT_GPU_ISO_N")
	)
	(segment
		(start 30.163262 -136.811004)
		(end 17.159986 -149.81428)
		(width 0.11684)
		(layer "In13.Cu")
		(net "FM_SMB_2_ALERT_GPU_ISO_N")
	)
	(segment
		(start 12.009628 -416.786314)
		(end 13.80998 -418.586666)
		(width 0.11684)
		(layer "In13.Cu")
		(net "FM_SMB_2_ALERT_GPU_ISO_N")
	)
	(segment
		(start 11.193272 -388.289038)
		(end 11.193272 -392.463528)
		(width 0.11684)
		(layer "In13.Cu")
		(net "FM_SMB_2_ALERT_GPU_ISO_N")
	)
	(segment
		(start 103.722678 -401.51939)
		(end 103.722678 -406.26665)
		(width 0.11684)
		(layer "In13.Cu")
		(net "FM_SMB_2_ALERT_GPU_ISO_N")
	)
	(segment
		(start 5.610606 -367.183416)
		(end 5.610606 -384.049778)
		(width 0.11684)
		(layer "In13.Cu")
		(net "FM_SMB_2_ALERT_GPU_ISO_N")
	)
	(segment
		(start 102.73284 -400.529552)
		(end 103.722678 -401.51939)
		(width 0.11684)
		(layer "In13.Cu")
		(net "FM_SMB_2_ALERT_GPU_ISO_N")
	)
	(segment
		(start 193.064638 -140.102336)
		(end 191.818768 -141.348206)
		(width 0.11684)
		(layer "In13.Cu")
		(net "FM_SMB_2_ALERT_GPU_ISO_N")
	)
	(segment
		(start 4.015486 -336.099658)
		(end 4.015486 -357.837486)
		(width 0.11684)
		(layer "In13.Cu")
		(net "FM_SMB_2_ALERT_GPU_ISO_N")
	)
	(segment
		(start 191.818768 -141.861794)
		(end 191.386206 -142.294356)
		(width 0.11684)
		(layer "In13.Cu")
		(net "FM_SMB_2_ALERT_GPU_ISO_N")
	)
	(segment
		(start 94.158054 -135.575802)
		(end 93.799152 -135.2169)
		(width 0.11684)
		(layer "In13.Cu")
		(net "FM_SMB_2_ALERT_GPU_ISO_N")
	)
	(segment
		(start 111.125 -416.941)
		(end 110.236 -417.83)
		(width 0.11684)
		(layer "In13.Cu")
		(net "FM_SMB_2_ALERT_GPU_ISO_N")
	)
	(segment
		(start 110.280196 -410.564076)
		(end 110.49 -410.77388)
		(width 0.11684)
		(layer "In13.Cu")
		(net "FM_SMB_2_ALERT_GPU_ISO_N")
	)
	(segment
		(start 4.718812 -366.291622)
		(end 5.610606 -367.183416)
		(width 0.11684)
		(layer "In13.Cu")
		(net "FM_SMB_2_ALERT_GPU_ISO_N")
	)
	(segment
		(start 199.63003 -140.102336)
		(end 193.064638 -140.102336)
		(width 0.11684)
		(layer "In13.Cu")
		(net "FM_SMB_2_ALERT_GPU_ISO_N")
	)
	(segment
		(start 110.49 -415.798)
		(end 111.125 -416.433)
		(width 0.11684)
		(layer "In13.Cu")
		(net "FM_SMB_2_ALERT_GPU_ISO_N")
	)
	(segment
		(start 11.354054 -414.480502)
		(end 12.009628 -415.136076)
		(width 0.11684)
		(layer "In13.Cu")
		(net "FM_SMB_2_ALERT_GPU_ISO_N")
	)
	(segment
		(start 110.109508 -407.162508)
		(end 110.280196 -407.333196)
		(width 0.11684)
		(layer "In13.Cu")
		(net "FM_SMB_2_ALERT_GPU_ISO_N")
	)
	(segment
		(start 111.125 -416.433)
		(end 111.125 -416.941)
		(width 0.11684)
		(layer "In13.Cu")
		(net "FM_SMB_2_ALERT_GPU_ISO_N")
	)
	(segment
		(start 191.386206 -142.294356)
		(end 185.514488 -142.294356)
		(width 0.11684)
		(layer "In13.Cu")
		(net "FM_SMB_2_ALERT_GPU_ISO_N")
	)
	(segment
		(start 191.818768 -141.348206)
		(end 191.818768 -141.861794)
		(width 0.11684)
		(layer "In13.Cu")
		(net "FM_SMB_2_ALERT_GPU_ISO_N")
	)
	(segment
		(start 177.539142 -143.082264)
		(end 176.846992 -142.390114)
		(width 0.11684)
		(layer "In13.Cu")
		(net "FM_SMB_2_ALERT_GPU_ISO_N")
	)
	(segment
		(start 7.13867 -385.577842)
		(end 8.482076 -385.577842)
		(width 0.11684)
		(layer "In13.Cu")
		(net "FM_SMB_2_ALERT_GPU_ISO_N")
	)
	(segment
		(start 176.846992 -142.390114)
		(end 157.899862 -142.390114)
		(width 0.11684)
		(layer "In13.Cu")
		(net "FM_SMB_2_ALERT_GPU_ISO_N")
	)
	(segment
		(start 100.698808 -400.745452)
		(end 100.914708 -400.529552)
		(width 0.11684)
		(layer "In13.Cu")
		(net "FM_SMB_2_ALERT_GPU_ISO_N")
	)
	(segment
		(start 11.193272 -392.463528)
		(end 7.097268 -396.559532)
		(width 0.11684)
		(layer "In13.Cu")
		(net "FM_SMB_2_ALERT_GPU_ISO_N")
	)
	(segment
		(start 104.618536 -407.162508)
		(end 110.109508 -407.162508)
		(width 0.11684)
		(layer "In13.Cu")
		(net "FM_SMB_2_ALERT_GPU_ISO_N")
	)
	(segment
		(start 13.80998 -418.586666)
		(end 21.366988 -418.586666)
		(width 0.11684)
		(layer "In13.Cu")
		(net "FM_SMB_2_ALERT_GPU_ISO_N")
	)
	(segment
		(start 93.799152 -135.2169)
		(end 78.764638 -135.2169)
		(width 0.11684)
		(layer "In13.Cu")
		(net "FM_SMB_2_ALERT_GPU_ISO_N")
	)
	(segment
		(start 110.280196 -407.333196)
		(end 110.280196 -410.564076)
		(width 0.11684)
		(layer "In13.Cu")
		(net "FM_SMB_2_ALERT_GPU_ISO_N")
	)
	(via
		(at 103.884476 -417.142168)
		(size 0.6604)
		(drill 0.3302)
		(layers "F.Cu" "B.Cu")
		(net "FM_SMB_2_ALERT_GPU")
	)
	(segment
		(start 106.488992 -415.98469)
		(end 106.488992 -416.181032)
		(width 0.10668)
		(layer "B.Cu")
		(net "FM_SMB_2_ALERT_GPU")
	)
	(segment
		(start 106.030014 -416.37204)
		(end 106.030014 -416.70986)
		(width 0.10668)
		(layer "B.Cu")
		(net "FM_SMB_2_ALERT_GPU")
	)
	(segment
		(start 103.884476 -417.142168)
		(end 103.759 -417.267644)
		(width 0.10668)
		(layer "B.Cu")
		(net "FM_SMB_2_ALERT_GPU")
	)
	(segment
		(start 106.157014 -415.85769)
		(end 106.361992 -415.85769)
		(width 0.10668)
		(layer "B.Cu")
		(net "FM_SMB_2_ALERT_GPU")
	)
	(segment
		(start 103.937816 -417.088828)
		(end 103.884476 -417.142168)
		(width 0.10668)
		(layer "B.Cu")
		(net "FM_SMB_2_ALERT_GPU")
	)
	(segment
		(start 106.030014 -415.98469)
		(end 106.157014 -415.85769)
		(width 0.10668)
		(layer "B.Cu")
		(net "FM_SMB_2_ALERT_GPU")
	)
	(segment
		(start 103.759 -417.267644)
		(end 103.759 -418.19195)
		(width 0.10668)
		(layer "B.Cu")
		(net "FM_SMB_2_ALERT_GPU")
	)
	(segment
		(start 106.361992 -415.85769)
		(end 106.488992 -415.98469)
		(width 0.10668)
		(layer "B.Cu")
		(net "FM_SMB_2_ALERT_GPU")
	)
	(segment
		(start 106.030014 -416.70986)
		(end 105.651046 -417.088828)
		(width 0.10668)
		(layer "B.Cu")
		(net "FM_SMB_2_ALERT_GPU")
	)
	(segment
		(start 105.651046 -417.088828)
		(end 103.937816 -417.088828)
		(width 0.10668)
		(layer "B.Cu")
		(net "FM_SMB_2_ALERT_GPU")
	)
	(segment
		(start 106.030014 -416.37204)
		(end 106.030014 -415.98469)
		(width 0.10668)
		(layer "B.Cu")
		(net "FM_SMB_2_ALERT_GPU")
	)
	(segment
		(start 106.488992 -416.181032)
		(end 106.68 -416.37204)
		(width 0.10668)
		(layer "B.Cu")
		(net "FM_SMB_2_ALERT_GPU")
	)
	(segment
		(start 115.08105 -419.75405)
		(end 116.713 -421.386)
		(width 0.10668)
		(layer "F.Cu")
		(net "FM_SMB_1_ALERT_GPU_N")
	)
	(segment
		(start 116.13896 -415.29)
		(end 115.697 -415.29)
		(width 0.10668)
		(layer "F.Cu")
		(net "FM_SMB_1_ALERT_GPU_N")
	)
	(segment
		(start 114.438938 -418.874194)
		(end 114.591338 -419.026594)
		(width 0.10668)
		(layer "F.Cu")
		(net "FM_SMB_1_ALERT_GPU_N")
	)
	(segment
		(start 115.443 -415.544)
		(end 115.443 -416.96005)
		(width 0.10668)
		(layer "F.Cu")
		(net "FM_SMB_1_ALERT_GPU_N")
	)
	(segment
		(start 115.697 -415.29)
		(end 115.443 -415.544)
		(width 0.10668)
		(layer "F.Cu")
		(net "FM_SMB_1_ALERT_GPU_N")
	)
	(segment
		(start 113.684304 -417.679378)
		(end 114.438938 -418.434012)
		(width 0.10668)
		(layer "F.Cu")
		(net "FM_SMB_1_ALERT_GPU_N")
	)
	(segment
		(start 114.591338 -419.026594)
		(end 115.08105 -419.75405)
		(width 0.10668)
		(layer "F.Cu")
		(net "FM_SMB_1_ALERT_GPU_N")
	)
	(segment
		(start 115.08359 -417.539932)
		(end 113.82375 -417.539932)
		(width 0.10668)
		(layer "F.Cu")
		(net "FM_SMB_1_ALERT_GPU_N")
	)
	(segment
		(start 114.438938 -418.434012)
		(end 114.438938 -418.874194)
		(width 0.10668)
		(layer "F.Cu")
		(net "FM_SMB_1_ALERT_GPU_N")
	)
	(segment
		(start 115.443 -416.96005)
		(end 115.08359 -417.539932)
		(width 0.10668)
		(layer "F.Cu")
		(net "FM_SMB_1_ALERT_GPU_N")
	)
	(segment
		(start 113.82375 -417.539932)
		(end 113.684304 -417.679378)
		(width 0.10668)
		(layer "F.Cu")
		(net "FM_SMB_1_ALERT_GPU_N")
	)
	(via
		(at 116.713 -421.386)
		(size 0.508)
		(drill 0.254)
		(layers "F.Cu" "B.Cu")
		(net "FM_SMB_1_ALERT_GPU_N")
	)
	(segment
		(start 122.403108 -422.250362)
		(end 121.538746 -421.386)
		(width 0.10668)
		(layer "B.Cu")
		(net "FM_SMB_1_ALERT_GPU_N")
	)
	(segment
		(start 129.310384 -422.250362)
		(end 122.403108 -422.250362)
		(width 0.10668)
		(layer "B.Cu")
		(net "FM_SMB_1_ALERT_GPU_N")
	)
	(segment
		(start 131.7498 -424.689778)
		(end 129.310384 -422.250362)
		(width 0.10668)
		(layer "B.Cu")
		(net "FM_SMB_1_ALERT_GPU_N")
	)
	(segment
		(start 121.538746 -421.386)
		(end 116.713 -421.386)
		(width 0.10668)
		(layer "B.Cu")
		(net "FM_SMB_1_ALERT_GPU_N")
	)
	(segment
		(start 116.078 -416.941254)
		(end 116.078 -417.55695)
		(width 0.10668)
		(layer "F.Cu")
		(net "FM_SMB_1_ALERT_GPU_ISO_N")
	)
	(segment
		(start 219.5195 -203.347574)
		(end 216.832688 -200.660762)
		(width 0.10668)
		(layer "F.Cu")
		(net "FM_SMB_1_ALERT_GPU_ISO_N")
	)
	(segment
		(start 117.094 -417.332668)
		(end 117.539262 -416.887406)
		(width 0.10668)
		(layer "F.Cu")
		(net "FM_SMB_1_ALERT_GPU_ISO_N")
	)
	(segment
		(start 219.810076 -203.515976)
		(end 219.641674 -203.347574)
		(width 0.10668)
		(layer "F.Cu")
		(net "FM_SMB_1_ALERT_GPU_ISO_N")
	)
	(segment
		(start 208.572862 -166.676578)
		(end 207.201262 -165.304978)
		(width 0.10668)
		(layer "F.Cu")
		(net "FM_SMB_1_ALERT_GPU_ISO_N")
	)
	(segment
		(start 205.615032 -119.721376)
		(end 206.497682 -119.721376)
		(width 0.10668)
		(layer "F.Cu")
		(net "FM_SMB_1_ALERT_GPU_ISO_N")
	)
	(segment
		(start 117.094 -417.55695)
		(end 117.094 -417.332668)
		(width 0.10668)
		(layer "F.Cu")
		(net "FM_SMB_1_ALERT_GPU_ISO_N")
	)
	(segment
		(start 207.201262 -165.304978)
		(end 207.201262 -163.631626)
		(width 0.10668)
		(layer "F.Cu")
		(net "FM_SMB_1_ALERT_GPU_ISO_N")
	)
	(segment
		(start 116.13896 -415.939986)
		(end 116.13896 -416.880294)
		(width 0.10668)
		(layer "F.Cu")
		(net "FM_SMB_1_ALERT_GPU_ISO_N")
	)
	(segment
		(start 116.13896 -416.880294)
		(end 116.078 -416.941254)
		(width 0.10668)
		(layer "F.Cu")
		(net "FM_SMB_1_ALERT_GPU_ISO_N")
	)
	(segment
		(start 216.832688 -186.61634)
		(end 208.572862 -166.676578)
		(width 0.10668)
		(layer "F.Cu")
		(net "FM_SMB_1_ALERT_GPU_ISO_N")
	)
	(segment
		(start 219.641674 -203.347574)
		(end 219.5195 -203.347574)
		(width 0.10668)
		(layer "F.Cu")
		(net "FM_SMB_1_ALERT_GPU_ISO_N")
	)
	(segment
		(start 216.832688 -200.660762)
		(end 216.832688 -186.61634)
		(width 0.10668)
		(layer "F.Cu")
		(net "FM_SMB_1_ALERT_GPU_ISO_N")
	)
	(segment
		(start 116.078 -417.55695)
		(end 117.094 -417.55695)
		(width 0.10668)
		(layer "F.Cu")
		(net "FM_SMB_1_ALERT_GPU_ISO_N")
	)
	(via
		(at 117.539262 -416.887406)
		(size 0.508)
		(drill 0.254)
		(layers "F.Cu" "B.Cu")
		(net "FM_SMB_1_ALERT_GPU_ISO_N")
	)
	(via
		(at 178.082956 -416.64763)
		(size 0.508)
		(drill 0.254)
		(layers "F.Cu" "B.Cu")
		(net "FM_SMB_1_ALERT_GPU_ISO_N")
	)
	(via
		(at 219.810076 -203.515976)
		(size 0.508)
		(drill 0.254)
		(layers "F.Cu" "B.Cu")
		(net "FM_SMB_1_ALERT_GPU_ISO_N")
	)
	(via
		(at 206.497682 -119.721376)
		(size 0.508)
		(drill 0.254)
		(layers "F.Cu" "B.Cu")
		(net "FM_SMB_1_ALERT_GPU_ISO_N")
	)
	(via
		(at 207.201262 -163.631626)
		(size 0.508)
		(drill 0.254)
		(layers "F.Cu" "B.Cu")
		(net "FM_SMB_1_ALERT_GPU_ISO_N")
	)
	(segment
		(start 170.606212 -417.006532)
		(end 170.304206 -417.308538)
		(width 0.11684)
		(layer "In2.Cu")
		(net "FM_SMB_1_ALERT_GPU_ISO_N")
	)
	(segment
		(start 169.599864 -417.031424)
		(end 166.16299 -417.031424)
		(width 0.11684)
		(layer "In2.Cu")
		(net "FM_SMB_1_ALERT_GPU_ISO_N")
	)
	(segment
		(start 170.606212 -416.307016)
		(end 170.606212 -417.006532)
		(width 0.11684)
		(layer "In2.Cu")
		(net "FM_SMB_1_ALERT_GPU_ISO_N")
	)
	(segment
		(start 172.47489 -416.384486)
		(end 172.00499 -415.914586)
		(width 0.11684)
		(layer "In2.Cu")
		(net "FM_SMB_1_ALERT_GPU_ISO_N")
	)
	(segment
		(start 153.914348 -415.683192)
		(end 152.710134 -416.887406)
		(width 0.11684)
		(layer "In2.Cu")
		(net "FM_SMB_1_ALERT_GPU_ISO_N")
	)
	(segment
		(start 172.00499 -415.914586)
		(end 170.998642 -415.914586)
		(width 0.11684)
		(layer "In2.Cu")
		(net "FM_SMB_1_ALERT_GPU_ISO_N")
	)
	(segment
		(start 164.275262 -416.430968)
		(end 163.617148 -417.089082)
		(width 0.11684)
		(layer "In2.Cu")
		(net "FM_SMB_1_ALERT_GPU_ISO_N")
	)
	(segment
		(start 163.617148 -417.089082)
		(end 162.31362 -417.089082)
		(width 0.11684)
		(layer "In2.Cu")
		(net "FM_SMB_1_ALERT_GPU_ISO_N")
	)
	(segment
		(start 178.082956 -416.64763)
		(end 176.85512 -416.64763)
		(width 0.11684)
		(layer "In2.Cu")
		(net "FM_SMB_1_ALERT_GPU_ISO_N")
	)
	(segment
		(start 162.31362 -417.089082)
		(end 160.90773 -415.683192)
		(width 0.11684)
		(layer "In2.Cu")
		(net "FM_SMB_1_ALERT_GPU_ISO_N")
	)
	(segment
		(start 165.562534 -416.430968)
		(end 164.275262 -416.430968)
		(width 0.11684)
		(layer "In2.Cu")
		(net "FM_SMB_1_ALERT_GPU_ISO_N")
	)
	(segment
		(start 166.16299 -417.031424)
		(end 165.562534 -416.430968)
		(width 0.11684)
		(layer "In2.Cu")
		(net "FM_SMB_1_ALERT_GPU_ISO_N")
	)
	(segment
		(start 169.876978 -417.308538)
		(end 169.599864 -417.031424)
		(width 0.11684)
		(layer "In2.Cu")
		(net "FM_SMB_1_ALERT_GPU_ISO_N")
	)
	(segment
		(start 175.38954 -416.291522)
		(end 175.296576 -416.384486)
		(width 0.11684)
		(layer "In2.Cu")
		(net "FM_SMB_1_ALERT_GPU_ISO_N")
	)
	(segment
		(start 176.499012 -416.291522)
		(end 175.38954 -416.291522)
		(width 0.11684)
		(layer "In2.Cu")
		(net "FM_SMB_1_ALERT_GPU_ISO_N")
	)
	(segment
		(start 170.304206 -417.308538)
		(end 169.876978 -417.308538)
		(width 0.11684)
		(layer "In2.Cu")
		(net "FM_SMB_1_ALERT_GPU_ISO_N")
	)
	(segment
		(start 160.90773 -415.683192)
		(end 153.914348 -415.683192)
		(width 0.11684)
		(layer "In2.Cu")
		(net "FM_SMB_1_ALERT_GPU_ISO_N")
	)
	(segment
		(start 152.710134 -416.887406)
		(end 117.539262 -416.887406)
		(width 0.11684)
		(layer "In2.Cu")
		(net "FM_SMB_1_ALERT_GPU_ISO_N")
	)
	(segment
		(start 175.296576 -416.384486)
		(end 172.47489 -416.384486)
		(width 0.11684)
		(layer "In2.Cu")
		(net "FM_SMB_1_ALERT_GPU_ISO_N")
	)
	(segment
		(start 170.998642 -415.914586)
		(end 170.606212 -416.307016)
		(width 0.11684)
		(layer "In2.Cu")
		(net "FM_SMB_1_ALERT_GPU_ISO_N")
	)
	(segment
		(start 176.85512 -416.64763)
		(end 176.499012 -416.291522)
		(width 0.11684)
		(layer "In2.Cu")
		(net "FM_SMB_1_ALERT_GPU_ISO_N")
	)
	(segment
		(start 207.954372 -141.992858)
		(end 207.954372 -162.878516)
		(width 0.11684)
		(layer "In4.Cu")
		(net "FM_SMB_1_ALERT_GPU_ISO_N")
	)
	(segment
		(start 206.847186 -140.885672)
		(end 207.954372 -141.992858)
		(width 0.11684)
		(layer "In4.Cu")
		(net "FM_SMB_1_ALERT_GPU_ISO_N")
	)
	(segment
		(start 206.548736 -127.363728)
		(end 205.998826 -127.363728)
		(width 0.11684)
		(layer "In4.Cu")
		(net "FM_SMB_1_ALERT_GPU_ISO_N")
	)
	(segment
		(start 207.954372 -162.878516)
		(end 207.201262 -163.631626)
		(width 0.11684)
		(layer "In4.Cu")
		(net "FM_SMB_1_ALERT_GPU_ISO_N")
	)
	(segment
		(start 206.847186 -133.323076)
		(end 206.847186 -140.885672)
		(width 0.11684)
		(layer "In4.Cu")
		(net "FM_SMB_1_ALERT_GPU_ISO_N")
	)
	(segment
		(start 206.61249 -119.721376)
		(end 207.674718 -120.783604)
		(width 0.11684)
		(layer "In4.Cu")
		(net "FM_SMB_1_ALERT_GPU_ISO_N")
	)
	(segment
		(start 205.578202 -127.784352)
		(end 205.578202 -132.054092)
		(width 0.11684)
		(layer "In4.Cu")
		(net "FM_SMB_1_ALERT_GPU_ISO_N")
	)
	(segment
		(start 206.497682 -119.721376)
		(end 206.61249 -119.721376)
		(width 0.11684)
		(layer "In4.Cu")
		(net "FM_SMB_1_ALERT_GPU_ISO_N")
	)
	(segment
		(start 205.578202 -132.054092)
		(end 206.847186 -133.323076)
		(width 0.11684)
		(layer "In4.Cu")
		(net "FM_SMB_1_ALERT_GPU_ISO_N")
	)
	(segment
		(start 207.674718 -120.783604)
		(end 207.674718 -123.137168)
		(width 0.11684)
		(layer "In4.Cu")
		(net "FM_SMB_1_ALERT_GPU_ISO_N")
	)
	(segment
		(start 208.091532 -123.553982)
		(end 208.091532 -125.053344)
		(width 0.11684)
		(layer "In4.Cu")
		(net "FM_SMB_1_ALERT_GPU_ISO_N")
	)
	(segment
		(start 207.674718 -123.137168)
		(end 208.091532 -123.553982)
		(width 0.11684)
		(layer "In4.Cu")
		(net "FM_SMB_1_ALERT_GPU_ISO_N")
	)
	(segment
		(start 208.091532 -125.053344)
		(end 207.112362 -126.032514)
		(width 0.11684)
		(layer "In4.Cu")
		(net "FM_SMB_1_ALERT_GPU_ISO_N")
	)
	(segment
		(start 205.998826 -127.363728)
		(end 205.578202 -127.784352)
		(width 0.11684)
		(layer "In4.Cu")
		(net "FM_SMB_1_ALERT_GPU_ISO_N")
	)
	(segment
		(start 207.112362 -126.800102)
		(end 206.548736 -127.363728)
		(width 0.11684)
		(layer "In4.Cu")
		(net "FM_SMB_1_ALERT_GPU_ISO_N")
	)
	(segment
		(start 207.112362 -126.032514)
		(end 207.112362 -126.800102)
		(width 0.11684)
		(layer "In4.Cu")
		(net "FM_SMB_1_ALERT_GPU_ISO_N")
	)
	(segment
		(start 178.082956 -415.741104)
		(end 177.836322 -415.49447)
		(width 0.11684)
		(layer "In15.Cu")
		(net "FM_SMB_1_ALERT_GPU_ISO_N")
	)
	(segment
		(start 215.634062 -203.908914)
		(end 216.195402 -203.347574)
		(width 0.11684)
		(layer "In15.Cu")
		(net "FM_SMB_1_ALERT_GPU_ISO_N")
	)
	(segment
		(start 191.935862 -375.781824)
		(end 205.030324 -362.687362)
		(width 0.11684)
		(layer "In15.Cu")
		(net "FM_SMB_1_ALERT_GPU_ISO_N")
	)
	(segment
		(start 190.871602 -382.836928)
		(end 190.871602 -380.325884)
		(width 0.11684)
		(layer "In15.Cu")
		(net "FM_SMB_1_ALERT_GPU_ISO_N")
	)
	(segment
		(start 180.164486 -395.80058)
		(end 190.0301 -385.934966)
		(width 0.11684)
		(layer "In15.Cu")
		(net "FM_SMB_1_ALERT_GPU_ISO_N")
	)
	(segment
		(start 177.792888 -410.158438)
		(end 176.831752 -409.197302)
		(width 0.11684)
		(layer "In15.Cu")
		(net "FM_SMB_1_ALERT_GPU_ISO_N")
	)
	(segment
		(start 219.641674 -203.347574)
		(end 219.810076 -203.515976)
		(width 0.11684)
		(layer "In15.Cu")
		(net "FM_SMB_1_ALERT_GPU_ISO_N")
	)
	(segment
		(start 177.836322 -414.490408)
		(end 178.214528 -414.112202)
		(width 0.11684)
		(layer "In15.Cu")
		(net "FM_SMB_1_ALERT_GPU_ISO_N")
	)
	(segment
		(start 190.871602 -380.325884)
		(end 191.935862 -379.261624)
		(width 0.11684)
		(layer "In15.Cu")
		(net "FM_SMB_1_ALERT_GPU_ISO_N")
	)
	(segment
		(start 176.831752 -408.060144)
		(end 176.831752 -398.349978)
		(width 0.11684)
		(layer "In15.Cu")
		(net "FM_SMB_1_ALERT_GPU_ISO_N")
	)
	(segment
		(start 205.030324 -362.687362)
		(end 205.030324 -360.397044)
		(width 0.11684)
		(layer "In15.Cu")
		(net "FM_SMB_1_ALERT_GPU_ISO_N")
	)
	(segment
		(start 215.634062 -318.351154)
		(end 215.634062 -203.908914)
		(width 0.11684)
		(layer "In15.Cu")
		(net "FM_SMB_1_ALERT_GPU_ISO_N")
	)
	(segment
		(start 178.118516 -410.430472)
		(end 177.846482 -410.158438)
		(width 0.11684)
		(layer "In15.Cu")
		(net "FM_SMB_1_ALERT_GPU_ISO_N")
	)
	(segment
		(start 176.831752 -409.197302)
		(end 176.831752 -409.057856)
		(width 0.11684)
		(layer "In15.Cu")
		(net "FM_SMB_1_ALERT_GPU_ISO_N")
	)
	(segment
		(start 190.0301 -385.934966)
		(end 190.0301 -383.67843)
		(width 0.11684)
		(layer "In15.Cu")
		(net "FM_SMB_1_ALERT_GPU_ISO_N")
	)
	(segment
		(start 176.831752 -409.057856)
		(end 176.72558 -408.951684)
		(width 0.11684)
		(layer "In15.Cu")
		(net "FM_SMB_1_ALERT_GPU_ISO_N")
	)
	(segment
		(start 222.06839 -324.785482)
		(end 215.634062 -318.351154)
		(width 0.11684)
		(layer "In15.Cu")
		(net "FM_SMB_1_ALERT_GPU_ISO_N")
	)
	(segment
		(start 216.195402 -203.347574)
		(end 219.641674 -203.347574)
		(width 0.11684)
		(layer "In15.Cu")
		(net "FM_SMB_1_ALERT_GPU_ISO_N")
	)
	(segment
		(start 179.38115 -395.80058)
		(end 180.164486 -395.80058)
		(width 0.11684)
		(layer "In15.Cu")
		(net "FM_SMB_1_ALERT_GPU_ISO_N")
	)
	(segment
		(start 176.72558 -408.166316)
		(end 176.831752 -408.060144)
		(width 0.11684)
		(layer "In15.Cu")
		(net "FM_SMB_1_ALERT_GPU_ISO_N")
	)
	(segment
		(start 190.0301 -383.67843)
		(end 190.871602 -382.836928)
		(width 0.11684)
		(layer "In15.Cu")
		(net "FM_SMB_1_ALERT_GPU_ISO_N")
	)
	(segment
		(start 222.06839 -343.358978)
		(end 222.06839 -324.785482)
		(width 0.11684)
		(layer "In15.Cu")
		(net "FM_SMB_1_ALERT_GPU_ISO_N")
	)
	(segment
		(start 191.935862 -379.261624)
		(end 191.935862 -375.781824)
		(width 0.11684)
		(layer "In15.Cu")
		(net "FM_SMB_1_ALERT_GPU_ISO_N")
	)
	(segment
		(start 178.118516 -410.484066)
		(end 178.118516 -410.430472)
		(width 0.11684)
		(layer "In15.Cu")
		(net "FM_SMB_1_ALERT_GPU_ISO_N")
	)
	(segment
		(start 205.030324 -360.397044)
		(end 222.06839 -343.358978)
		(width 0.11684)
		(layer "In15.Cu")
		(net "FM_SMB_1_ALERT_GPU_ISO_N")
	)
	(segment
		(start 178.082956 -416.64763)
		(end 178.082956 -415.741104)
		(width 0.11684)
		(layer "In15.Cu")
		(net "FM_SMB_1_ALERT_GPU_ISO_N")
	)
	(segment
		(start 177.846482 -410.158438)
		(end 177.792888 -410.158438)
		(width 0.11684)
		(layer "In15.Cu")
		(net "FM_SMB_1_ALERT_GPU_ISO_N")
	)
	(segment
		(start 177.836322 -415.49447)
		(end 177.836322 -414.490408)
		(width 0.11684)
		(layer "In15.Cu")
		(net "FM_SMB_1_ALERT_GPU_ISO_N")
	)
	(segment
		(start 178.214528 -414.112202)
		(end 178.214528 -410.580078)
		(width 0.11684)
		(layer "In15.Cu")
		(net "FM_SMB_1_ALERT_GPU_ISO_N")
	)
	(segment
		(start 176.72558 -408.951684)
		(end 176.72558 -408.166316)
		(width 0.11684)
		(layer "In15.Cu")
		(net "FM_SMB_1_ALERT_GPU_ISO_N")
	)
	(segment
		(start 178.214528 -410.580078)
		(end 178.118516 -410.484066)
		(width 0.11684)
		(layer "In15.Cu")
		(net "FM_SMB_1_ALERT_GPU_ISO_N")
	)
	(segment
		(start 176.831752 -398.349978)
		(end 179.38115 -395.80058)
		(width 0.11684)
		(layer "In15.Cu")
		(net "FM_SMB_1_ALERT_GPU_ISO_N")
	)
	(segment
		(start 113.922302 -415.29)
		(end 114.23904 -415.29)
		(width 0.10668)
		(layer "F.Cu")
		(net "FM_SMB_1_ALERT_GPU")
	)
	(segment
		(start 114.23904 -414.640014)
		(end 114.686334 -414.640014)
		(width 0.10668)
		(layer "F.Cu")
		(net "FM_SMB_1_ALERT_GPU")
	)
	(segment
		(start 113.647474 -416.17519)
		(end 113.795302 -416.027362)
		(width 0.10668)
		(layer "F.Cu")
		(net "FM_SMB_1_ALERT_GPU")
	)
	(segment
		(start 114.808 -414.76168)
		(end 114.808 -415.163)
		(width 0.10668)
		(layer "F.Cu")
		(net "FM_SMB_1_ALERT_GPU")
	)
	(segment
		(start 112.672876 -417.690808)
		(end 112.672876 -416.776916)
		(width 0.10668)
		(layer "F.Cu")
		(net "FM_SMB_1_ALERT_GPU")
	)
	(segment
		(start 114.808 -415.163)
		(end 114.681 -415.29)
		(width 0.10668)
		(layer "F.Cu")
		(net "FM_SMB_1_ALERT_GPU")
	)
	(segment
		(start 114.681 -415.29)
		(end 114.23904 -415.29)
		(width 0.10668)
		(layer "F.Cu")
		(net "FM_SMB_1_ALERT_GPU")
	)
	(segment
		(start 112.672876 -416.776916)
		(end 113.274602 -416.17519)
		(width 0.10668)
		(layer "F.Cu")
		(net "FM_SMB_1_ALERT_GPU")
	)
	(segment
		(start 114.686334 -414.640014)
		(end 114.808 -414.76168)
		(width 0.10668)
		(layer "F.Cu")
		(net "FM_SMB_1_ALERT_GPU")
	)
	(segment
		(start 113.795302 -415.417)
		(end 113.922302 -415.29)
		(width 0.10668)
		(layer "F.Cu")
		(net "FM_SMB_1_ALERT_GPU")
	)
	(segment
		(start 113.274602 -416.17519)
		(end 113.647474 -416.17519)
		(width 0.10668)
		(layer "F.Cu")
		(net "FM_SMB_1_ALERT_GPU")
	)
	(segment
		(start 113.795302 -416.027362)
		(end 113.795302 -415.417)
		(width 0.10668)
		(layer "F.Cu")
		(net "FM_SMB_1_ALERT_GPU")
	)
	(via
		(at 112.672876 -416.776916)
		(size 0.762)
		(drill 0.381)
		(layers "F.Cu" "B.Cu")
		(net "FM_SMB_1_ALERT_GPU")
	)
	(segment
		(start 190.197994 -36.0807)
		(end 190.550546 -36.433252)
		(width 0.10668)
		(layer "F.Cu")
		(net "FM_SCM_PRSNT1_R_N")
	)
	(segment
		(start 190.550546 -36.433252)
		(end 191.414654 -36.433252)
		(width 0.10668)
		(layer "F.Cu")
		(net "FM_SCM_PRSNT1_R_N")
	)
	(segment
		(start 190.19774 -36.0807)
		(end 190.197994 -36.0807)
		(width 0.10668)
		(layer "F.Cu")
		(net "FM_SCM_PRSNT1_R_N")
	)
	(segment
		(start 192.859406 -36.433252)
		(end 191.414654 -36.433252)
		(width 0.10668)
		(layer "F.Cu")
		(net "FM_SCM_PRSNT1_R_N")
	)
	(via
		(at 191.414654 -36.433252)
		(size 0.762)
		(drill 0.381)
		(layers "F.Cu" "B.Cu")
		(net "FM_SCM_PRSNT1_R_N")
	)
	(segment
		(start 137.547096 -14.796262)
		(end 138.326368 -15.575534)
		(width 0.10668)
		(layer "F.Cu")
		(net "FM_SCM_PRSNT1_N")
	)
	(segment
		(start 146.39925 -15.575534)
		(end 148.25599 -17.432274)
		(width 0.10668)
		(layer "F.Cu")
		(net "FM_SCM_PRSNT1_N")
	)
	(segment
		(start 185.922158 -107.452922)
		(end 186.312048 -107.063032)
		(width 0.10668)
		(layer "F.Cu")
		(net "FM_SCM_PRSNT1_N")
	)
	(segment
		(start 189.39764 -36.0807)
		(end 189.39764 -35.019996)
		(width 0.10668)
		(layer "F.Cu")
		(net "FM_SCM_PRSNT1_N")
	)
	(segment
		(start 189.069472 -35.017456)
		(end 188.7347 -35.352228)
		(width 0.10668)
		(layer "F.Cu")
		(net "FM_SCM_PRSNT1_N")
	)
	(segment
		(start 148.25599 -17.432274)
		(end 148.25599 -17.952212)
		(width 0.10668)
		(layer "F.Cu")
		(net "FM_SCM_PRSNT1_N")
	)
	(segment
		(start 189.39764 -35.019996)
		(end 189.40018 -35.017456)
		(width 0.10668)
		(layer "F.Cu")
		(net "FM_SCM_PRSNT1_N")
	)
	(segment
		(start 137.547096 -13.599922)
		(end 137.547096 -14.796262)
		(width 0.10668)
		(layer "F.Cu")
		(net "FM_SCM_PRSNT1_N")
	)
	(segment
		(start 138.326368 -15.575534)
		(end 146.39925 -15.575534)
		(width 0.10668)
		(layer "F.Cu")
		(net "FM_SCM_PRSNT1_N")
	)
	(segment
		(start 189.40018 -35.017456)
		(end 189.069472 -35.017456)
		(width 0.10668)
		(layer "F.Cu")
		(net "FM_SCM_PRSNT1_N")
	)
	(via
		(at 188.7347 -35.352228)
		(size 0.508)
		(drill 0.254)
		(layers "F.Cu" "B.Cu")
		(net "FM_SCM_PRSNT1_N")
	)
	(via
		(at 172.653198 -55.311802)
		(size 0.508)
		(drill 0.254)
		(layers "F.Cu" "B.Cu")
		(net "FM_SCM_PRSNT1_N")
	)
	(via
		(at 148.25599 -17.952212)
		(size 0.508)
		(drill 0.254)
		(layers "F.Cu" "B.Cu")
		(net "FM_SCM_PRSNT1_N")
	)
	(via
		(at 186.312048 -107.063032)
		(size 0.4572)
		(drill 0.254)
		(layers "F.Cu" "B.Cu")
		(net "FM_SCM_PRSNT1_N")
	)
	(segment
		(start 159.587946 -22.346412)
		(end 159.587946 -31.250636)
		(width 0.11684)
		(layer "In4.Cu")
		(net "FM_SCM_PRSNT1_N")
	)
	(segment
		(start 169.12844 -36.54552)
		(end 170.946572 -38.363652)
		(width 0.11684)
		(layer "In4.Cu")
		(net "FM_SCM_PRSNT1_N")
	)
	(segment
		(start 173.863762 -55.311802)
		(end 172.653198 -55.311802)
		(width 0.11684)
		(layer "In4.Cu")
		(net "FM_SCM_PRSNT1_N")
	)
	(segment
		(start 152.223216 -21.919438)
		(end 159.160972 -21.919438)
		(width 0.11684)
		(layer "In4.Cu")
		(net "FM_SCM_PRSNT1_N")
	)
	(segment
		(start 174.477426 -45.34027)
		(end 174.477426 -54.698138)
		(width 0.11684)
		(layer "In4.Cu")
		(net "FM_SCM_PRSNT1_N")
	)
	(segment
		(start 174.477426 -54.698138)
		(end 173.863762 -55.311802)
		(width 0.11684)
		(layer "In4.Cu")
		(net "FM_SCM_PRSNT1_N")
	)
	(segment
		(start 170.946572 -41.809416)
		(end 174.477426 -45.34027)
		(width 0.11684)
		(layer "In4.Cu")
		(net "FM_SCM_PRSNT1_N")
	)
	(segment
		(start 170.946572 -38.363652)
		(end 170.946572 -41.809416)
		(width 0.11684)
		(layer "In4.Cu")
		(net "FM_SCM_PRSNT1_N")
	)
	(segment
		(start 159.587946 -31.250636)
		(end 164.88283 -36.54552)
		(width 0.11684)
		(layer "In4.Cu")
		(net "FM_SCM_PRSNT1_N")
	)
	(segment
		(start 148.25599 -17.952212)
		(end 152.223216 -21.919438)
		(width 0.11684)
		(layer "In4.Cu")
		(net "FM_SCM_PRSNT1_N")
	)
	(segment
		(start 159.160972 -21.919438)
		(end 159.587946 -22.346412)
		(width 0.11684)
		(layer "In4.Cu")
		(net "FM_SCM_PRSNT1_N")
	)
	(segment
		(start 164.88283 -36.54552)
		(end 169.12844 -36.54552)
		(width 0.11684)
		(layer "In4.Cu")
		(net "FM_SCM_PRSNT1_N")
	)
	(segment
		(start 188.7347 -35.352228)
		(end 181.740302 -35.352228)
		(width 0.11684)
		(layer "In6.Cu")
		(net "FM_SCM_PRSNT1_N")
	)
	(segment
		(start 174.47006 -32.592772)
		(end 173.619414 -31.742126)
		(width 0.11684)
		(layer "In6.Cu")
		(net "FM_SCM_PRSNT1_N")
	)
	(segment
		(start 169.594022 -31.742126)
		(end 168.728644 -30.876748)
		(width 0.11684)
		(layer "In6.Cu")
		(net "FM_SCM_PRSNT1_N")
	)
	(segment
		(start 168.728644 -30.876748)
		(end 165.856666 -30.876748)
		(width 0.11684)
		(layer "In6.Cu")
		(net "FM_SCM_PRSNT1_N")
	)
	(segment
		(start 165.856666 -30.876748)
		(end 157.093158 -22.11324)
		(width 0.11684)
		(layer "In6.Cu")
		(net "FM_SCM_PRSNT1_N")
	)
	(segment
		(start 152.417018 -22.11324)
		(end 148.25599 -17.952212)
		(width 0.11684)
		(layer "In6.Cu")
		(net "FM_SCM_PRSNT1_N")
	)
	(segment
		(start 176.273968 -32.592772)
		(end 174.47006 -32.592772)
		(width 0.11684)
		(layer "In6.Cu")
		(net "FM_SCM_PRSNT1_N")
	)
	(segment
		(start 157.093158 -22.11324)
		(end 152.417018 -22.11324)
		(width 0.11684)
		(layer "In6.Cu")
		(net "FM_SCM_PRSNT1_N")
	)
	(segment
		(start 181.136036 -34.747962)
		(end 178.429158 -34.747962)
		(width 0.11684)
		(layer "In6.Cu")
		(net "FM_SCM_PRSNT1_N")
	)
	(segment
		(start 181.740302 -35.352228)
		(end 181.136036 -34.747962)
		(width 0.11684)
		(layer "In6.Cu")
		(net "FM_SCM_PRSNT1_N")
	)
	(segment
		(start 173.619414 -31.742126)
		(end 169.594022 -31.742126)
		(width 0.11684)
		(layer "In6.Cu")
		(net "FM_SCM_PRSNT1_N")
	)
	(segment
		(start 178.429158 -34.747962)
		(end 176.273968 -32.592772)
		(width 0.11684)
		(layer "In6.Cu")
		(net "FM_SCM_PRSNT1_N")
	)
	(segment
		(start 187.33262 -92.778072)
		(end 187.006484 -92.451936)
		(width 0.11684)
		(layer "In11.Cu")
		(net "FM_SCM_PRSNT1_N")
	)
	(segment
		(start 170.983402 -60.46089)
		(end 173.851824 -57.592468)
		(width 0.11684)
		(layer "In11.Cu")
		(net "FM_SCM_PRSNT1_N")
	)
	(segment
		(start 187.35802 -95.504508)
		(end 187.01004 -95.156528)
		(width 0.11684)
		(layer "In11.Cu")
		(net "FM_SCM_PRSNT1_N")
	)
	(segment
		(start 182.263288 -90.416634)
		(end 180.464206 -88.617552)
		(width 0.11684)
		(layer "In11.Cu")
		(net "FM_SCM_PRSNT1_N")
	)
	(segment
		(start 187.01004 -94.437708)
		(end 187.33262 -94.115128)
		(width 0.11684)
		(layer "In11.Cu")
		(net "FM_SCM_PRSNT1_N")
	)
	(segment
		(start 170.983402 -77.813154)
		(end 170.983402 -60.46089)
		(width 0.11684)
		(layer "In11.Cu")
		(net "FM_SCM_PRSNT1_N")
	)
	(segment
		(start 187.01004 -95.156528)
		(end 187.01004 -94.437708)
		(width 0.11684)
		(layer "In11.Cu")
		(net "FM_SCM_PRSNT1_N")
	)
	(segment
		(start 180.464206 -86.737698)
		(end 176.479962 -82.753454)
		(width 0.11684)
		(layer "In11.Cu")
		(net "FM_SCM_PRSNT1_N")
	)
	(segment
		(start 184.63006 -90.416634)
		(end 182.263288 -90.416634)
		(width 0.11684)
		(layer "In11.Cu")
		(net "FM_SCM_PRSNT1_N")
	)
	(segment
		(start 186.7662 -103.90124)
		(end 186.2328 -103.36784)
		(width 0.11684)
		(layer "In11.Cu")
		(net "FM_SCM_PRSNT1_N")
	)
	(segment
		(start 186.7662 -106.60888)
		(end 186.7662 -103.90124)
		(width 0.11684)
		(layer "In11.Cu")
		(net "FM_SCM_PRSNT1_N")
	)
	(segment
		(start 186.312048 -107.063032)
		(end 186.7662 -106.60888)
		(width 0.11684)
		(layer "In11.Cu")
		(net "FM_SCM_PRSNT1_N")
	)
	(segment
		(start 186.2328 -103.36784)
		(end 186.2328 -100.67798)
		(width 0.11684)
		(layer "In11.Cu")
		(net "FM_SCM_PRSNT1_N")
	)
	(segment
		(start 187.33262 -94.115128)
		(end 187.33262 -92.778072)
		(width 0.11684)
		(layer "In11.Cu")
		(net "FM_SCM_PRSNT1_N")
	)
	(segment
		(start 180.464206 -88.617552)
		(end 180.464206 -86.737698)
		(width 0.11684)
		(layer "In11.Cu")
		(net "FM_SCM_PRSNT1_N")
	)
	(segment
		(start 185.189876 -91.81211)
		(end 185.189876 -90.97645)
		(width 0.11684)
		(layer "In11.Cu")
		(net "FM_SCM_PRSNT1_N")
	)
	(segment
		(start 185.829702 -92.451936)
		(end 185.189876 -91.81211)
		(width 0.11684)
		(layer "In11.Cu")
		(net "FM_SCM_PRSNT1_N")
	)
	(segment
		(start 176.479962 -82.753454)
		(end 175.923702 -82.753454)
		(width 0.11684)
		(layer "In11.Cu")
		(net "FM_SCM_PRSNT1_N")
	)
	(segment
		(start 173.851824 -56.510428)
		(end 172.653198 -55.311802)
		(width 0.11684)
		(layer "In11.Cu")
		(net "FM_SCM_PRSNT1_N")
	)
	(segment
		(start 187.006484 -92.451936)
		(end 185.829702 -92.451936)
		(width 0.11684)
		(layer "In11.Cu")
		(net "FM_SCM_PRSNT1_N")
	)
	(segment
		(start 185.189876 -90.97645)
		(end 184.63006 -90.416634)
		(width 0.11684)
		(layer "In11.Cu")
		(net "FM_SCM_PRSNT1_N")
	)
	(segment
		(start 186.2328 -100.67798)
		(end 187.35802 -99.55276)
		(width 0.11684)
		(layer "In11.Cu")
		(net "FM_SCM_PRSNT1_N")
	)
	(segment
		(start 175.923702 -82.753454)
		(end 170.983402 -77.813154)
		(width 0.11684)
		(layer "In11.Cu")
		(net "FM_SCM_PRSNT1_N")
	)
	(segment
		(start 173.851824 -57.592468)
		(end 173.851824 -56.510428)
		(width 0.11684)
		(layer "In11.Cu")
		(net "FM_SCM_PRSNT1_N")
	)
	(segment
		(start 187.35802 -99.55276)
		(end 187.35802 -95.504508)
		(width 0.11684)
		(layer "In11.Cu")
		(net "FM_SCM_PRSNT1_N")
	)
	(segment
		(start 198.943214 -117.22481)
		(end 197.0532 -117.22481)
		(width 0.10668)
		(layer "F.Cu")
		(net "FM_RST_PERST_SCM_R_N")
	)
	(segment
		(start 197.0532 -117.22481)
		(end 196.869558 -117.041168)
		(width 0.10668)
		(layer "F.Cu")
		(net "FM_RST_PERST_SCM_R_N")
	)
	(segment
		(start 193.922142 -116.252752)
		(end 195.72351 -116.252752)
		(width 0.10668)
		(layer "F.Cu")
		(net "FM_RST_PERST_SCM_R_N")
	)
	(segment
		(start 195.72351 -116.252752)
		(end 196.144134 -116.673376)
		(width 0.10668)
		(layer "F.Cu")
		(net "FM_RST_PERST_SCM_R_N")
	)
	(segment
		(start 196.144134 -116.673376)
		(end 196.869558 -116.673376)
		(width 0.10668)
		(layer "F.Cu")
		(net "FM_RST_PERST_SCM_R_N")
	)
	(segment
		(start 196.869558 -117.041168)
		(end 196.869558 -116.673376)
		(width 0.10668)
		(layer "F.Cu")
		(net "FM_RST_PERST_SCM_R_N")
	)
	(via
		(at 198.943214 -117.22481)
		(size 0.762)
		(drill 0.381)
		(layers "F.Cu" "B.Cu")
		(net "FM_RST_PERST_SCM_R_N")
	)
	(segment
		(start 141.147038 -12.161774)
		(end 140.965936 -11.980672)
		(width 0.10668)
		(layer "F.Cu")
		(net "FM_RST_PERST_SCM_N")
	)
	(segment
		(start 141.147038 -13.599922)
		(end 141.147038 -12.161774)
		(width 0.10668)
		(layer "F.Cu")
		(net "FM_RST_PERST_SCM_N")
	)
	(segment
		(start 140.965936 -11.980672)
		(end 140.965936 -11.509248)
		(width 0.10668)
		(layer "F.Cu")
		(net "FM_RST_PERST_SCM_N")
	)
	(segment
		(start 197.669658 -116.673376)
		(end 198.322438 -116.673376)
		(width 0.10668)
		(layer "F.Cu")
		(net "FM_RST_PERST_SCM_N")
	)
	(segment
		(start 198.322438 -116.673376)
		(end 198.368158 -116.719096)
		(width 0.10668)
		(layer "F.Cu")
		(net "FM_RST_PERST_SCM_N")
	)
	(via
		(at 198.368158 -116.719096)
		(size 0.508)
		(drill 0.254)
		(layers "F.Cu" "B.Cu")
		(net "FM_RST_PERST_SCM_N")
	)
	(via
		(at 140.104114 -112.69091)
		(size 0.508)
		(drill 0.254)
		(layers "F.Cu" "B.Cu")
		(net "FM_RST_PERST_SCM_N")
	)
	(via
		(at 157.14472 -129.870708)
		(size 0.508)
		(drill 0.254)
		(layers "F.Cu" "B.Cu")
		(net "FM_RST_PERST_SCM_N")
	)
	(via
		(at 140.965936 -11.509248)
		(size 0.508)
		(drill 0.254)
		(layers "F.Cu" "B.Cu")
		(net "FM_RST_PERST_SCM_N")
	)
	(via
		(at 196.840856 -130.607816)
		(size 0.508)
		(drill 0.254)
		(layers "F.Cu" "B.Cu")
		(net "FM_RST_PERST_SCM_N")
	)
	(segment
		(start 140.104114 -111.652304)
		(end 138.976862 -110.525052)
		(width 0.11684)
		(layer "In4.Cu")
		(net "FM_RST_PERST_SCM_N")
	)
	(segment
		(start 138.976862 -110.525052)
		(end 138.976862 -109.93882)
		(width 0.11684)
		(layer "In4.Cu")
		(net "FM_RST_PERST_SCM_N")
	)
	(segment
		(start 128.638554 -39.458646)
		(end 128.638554 -35.153346)
		(width 0.11684)
		(layer "In4.Cu")
		(net "FM_RST_PERST_SCM_N")
	)
	(segment
		(start 109.58068 -76.362052)
		(end 103.5939 -70.375272)
		(width 0.11684)
		(layer "In4.Cu")
		(net "FM_RST_PERST_SCM_N")
	)
	(segment
		(start 128.638554 -35.153346)
		(end 131.19608 -32.59582)
		(width 0.11684)
		(layer "In4.Cu")
		(net "FM_RST_PERST_SCM_N")
	)
	(segment
		(start 103.5939 -70.375272)
		(end 103.5939 -53.8226)
		(width 0.11684)
		(layer "In4.Cu")
		(net "FM_RST_PERST_SCM_N")
	)
	(segment
		(start 119.55399 -91.10218)
		(end 119.55399 -89.882726)
		(width 0.11684)
		(layer "In4.Cu")
		(net "FM_RST_PERST_SCM_N")
	)
	(segment
		(start 135.3693 -32.59582)
		(end 137.10412 -30.861)
		(width 0.11684)
		(layer "In4.Cu")
		(net "FM_RST_PERST_SCM_N")
	)
	(segment
		(start 131.19608 -32.59582)
		(end 135.3693 -32.59582)
		(width 0.11684)
		(layer "In4.Cu")
		(net "FM_RST_PERST_SCM_N")
	)
	(segment
		(start 107.061 -50.3555)
		(end 117.7417 -50.3555)
		(width 0.11684)
		(layer "In4.Cu")
		(net "FM_RST_PERST_SCM_N")
	)
	(segment
		(start 109.58068 -79.909416)
		(end 109.58068 -76.362052)
		(width 0.11684)
		(layer "In4.Cu")
		(net "FM_RST_PERST_SCM_N")
	)
	(segment
		(start 103.5939 -53.8226)
		(end 107.061 -50.3555)
		(width 0.11684)
		(layer "In4.Cu")
		(net "FM_RST_PERST_SCM_N")
	)
	(segment
		(start 140.965936 -11.82878)
		(end 140.965936 -11.509248)
		(width 0.11684)
		(layer "In4.Cu")
		(net "FM_RST_PERST_SCM_N")
	)
	(segment
		(start 137.33526 -108.297218)
		(end 137.33526 -106.87558)
		(width 0.11684)
		(layer "In4.Cu")
		(net "FM_RST_PERST_SCM_N")
	)
	(segment
		(start 141.84249 -12.705334)
		(end 140.965936 -11.82878)
		(width 0.11684)
		(layer "In4.Cu")
		(net "FM_RST_PERST_SCM_N")
	)
	(segment
		(start 119.55399 -89.882726)
		(end 109.58068 -79.909416)
		(width 0.11684)
		(layer "In4.Cu")
		(net "FM_RST_PERST_SCM_N")
	)
	(segment
		(start 138.976862 -109.93882)
		(end 137.33526 -108.297218)
		(width 0.11684)
		(layer "In4.Cu")
		(net "FM_RST_PERST_SCM_N")
	)
	(segment
		(start 141.84249 -15.548864)
		(end 141.84249 -12.705334)
		(width 0.11684)
		(layer "In4.Cu")
		(net "FM_RST_PERST_SCM_N")
	)
	(segment
		(start 140.104114 -112.69091)
		(end 140.104114 -111.652304)
		(width 0.11684)
		(layer "In4.Cu")
		(net "FM_RST_PERST_SCM_N")
	)
	(segment
		(start 136.162034 -105.702354)
		(end 134.154164 -105.702354)
		(width 0.11684)
		(layer "In4.Cu")
		(net "FM_RST_PERST_SCM_N")
	)
	(segment
		(start 137.33526 -106.87558)
		(end 136.162034 -105.702354)
		(width 0.11684)
		(layer "In4.Cu")
		(net "FM_RST_PERST_SCM_N")
	)
	(segment
		(start 117.7417 -50.3555)
		(end 128.638554 -39.458646)
		(width 0.11684)
		(layer "In4.Cu")
		(net "FM_RST_PERST_SCM_N")
	)
	(segment
		(start 134.154164 -105.702354)
		(end 119.55399 -91.10218)
		(width 0.11684)
		(layer "In4.Cu")
		(net "FM_RST_PERST_SCM_N")
	)
	(segment
		(start 142.818612 -16.524986)
		(end 141.84249 -15.548864)
		(width 0.11684)
		(layer "In4.Cu")
		(net "FM_RST_PERST_SCM_N")
	)
	(segment
		(start 137.10412 -30.861)
		(end 137.10412 -26.963116)
		(width 0.11684)
		(layer "In4.Cu")
		(net "FM_RST_PERST_SCM_N")
	)
	(segment
		(start 137.10412 -26.963116)
		(end 142.818612 -21.248624)
		(width 0.11684)
		(layer "In4.Cu")
		(net "FM_RST_PERST_SCM_N")
	)
	(segment
		(start 142.818612 -21.248624)
		(end 142.818612 -16.524986)
		(width 0.11684)
		(layer "In4.Cu")
		(net "FM_RST_PERST_SCM_N")
	)
	(segment
		(start 165.524434 -131.252722)
		(end 166.168832 -130.608324)
		(width 0.11684)
		(layer "In6.Cu")
		(net "FM_RST_PERST_SCM_N")
	)
	(segment
		(start 157.14472 -129.870708)
		(end 158.520384 -131.246372)
		(width 0.11684)
		(layer "In6.Cu")
		(net "FM_RST_PERST_SCM_N")
	)
	(segment
		(start 163.02101 -131.252722)
		(end 165.524434 -131.252722)
		(width 0.11684)
		(layer "In6.Cu")
		(net "FM_RST_PERST_SCM_N")
	)
	(segment
		(start 183.55564 -130.58394)
		(end 183.55564 -130.089148)
		(width 0.11684)
		(layer "In6.Cu")
		(net "FM_RST_PERST_SCM_N")
	)
	(segment
		(start 196.399912 -130.607816)
		(end 196.840856 -130.607816)
		(width 0.11684)
		(layer "In6.Cu")
		(net "FM_RST_PERST_SCM_N")
	)
	(segment
		(start 170.301158 -131.450588)
		(end 179.22494 -131.450588)
		(width 0.11684)
		(layer "In6.Cu")
		(net "FM_RST_PERST_SCM_N")
	)
	(segment
		(start 183.26735 -130.87223)
		(end 183.55564 -130.58394)
		(width 0.11684)
		(layer "In6.Cu")
		(net "FM_RST_PERST_SCM_N")
	)
	(segment
		(start 183.55564 -130.089148)
		(end 184.147968 -129.49682)
		(width 0.11684)
		(layer "In6.Cu")
		(net "FM_RST_PERST_SCM_N")
	)
	(segment
		(start 182.63997 -130.87223)
		(end 183.26735 -130.87223)
		(width 0.11684)
		(layer "In6.Cu")
		(net "FM_RST_PERST_SCM_N")
	)
	(segment
		(start 182.4736 -131.66598)
		(end 182.4736 -131.0386)
		(width 0.11684)
		(layer "In6.Cu")
		(net "FM_RST_PERST_SCM_N")
	)
	(segment
		(start 182.245254 -131.894326)
		(end 182.4736 -131.66598)
		(width 0.11684)
		(layer "In6.Cu")
		(net "FM_RST_PERST_SCM_N")
	)
	(segment
		(start 191.638682 -130.533648)
		(end 191.958214 -130.85318)
		(width 0.11684)
		(layer "In6.Cu")
		(net "FM_RST_PERST_SCM_N")
	)
	(segment
		(start 196.154548 -130.85318)
		(end 196.399912 -130.607816)
		(width 0.11684)
		(layer "In6.Cu")
		(net "FM_RST_PERST_SCM_N")
	)
	(segment
		(start 184.147968 -129.49682)
		(end 191.000634 -129.49682)
		(width 0.11684)
		(layer "In6.Cu")
		(net "FM_RST_PERST_SCM_N")
	)
	(segment
		(start 191.638682 -130.134868)
		(end 191.638682 -130.533648)
		(width 0.11684)
		(layer "In6.Cu")
		(net "FM_RST_PERST_SCM_N")
	)
	(segment
		(start 191.958214 -130.85318)
		(end 196.154548 -130.85318)
		(width 0.11684)
		(layer "In6.Cu")
		(net "FM_RST_PERST_SCM_N")
	)
	(segment
		(start 179.668678 -131.894326)
		(end 182.245254 -131.894326)
		(width 0.11684)
		(layer "In6.Cu")
		(net "FM_RST_PERST_SCM_N")
	)
	(segment
		(start 191.000634 -129.49682)
		(end 191.638682 -130.134868)
		(width 0.11684)
		(layer "In6.Cu")
		(net "FM_RST_PERST_SCM_N")
	)
	(segment
		(start 169.458894 -130.608324)
		(end 170.301158 -131.450588)
		(width 0.11684)
		(layer "In6.Cu")
		(net "FM_RST_PERST_SCM_N")
	)
	(segment
		(start 163.01466 -131.246372)
		(end 163.02101 -131.252722)
		(width 0.11684)
		(layer "In6.Cu")
		(net "FM_RST_PERST_SCM_N")
	)
	(segment
		(start 179.22494 -131.450588)
		(end 179.668678 -131.894326)
		(width 0.11684)
		(layer "In6.Cu")
		(net "FM_RST_PERST_SCM_N")
	)
	(segment
		(start 166.168832 -130.608324)
		(end 169.458894 -130.608324)
		(width 0.11684)
		(layer "In6.Cu")
		(net "FM_RST_PERST_SCM_N")
	)
	(segment
		(start 182.4736 -131.0386)
		(end 182.63997 -130.87223)
		(width 0.11684)
		(layer "In6.Cu")
		(net "FM_RST_PERST_SCM_N")
	)
	(segment
		(start 158.520384 -131.246372)
		(end 163.01466 -131.246372)
		(width 0.11684)
		(layer "In6.Cu")
		(net "FM_RST_PERST_SCM_N")
	)
	(segment
		(start 149.807676 -118.48592)
		(end 149.494494 -118.48592)
		(width 0.11684)
		(layer "In11.Cu")
		(net "FM_RST_PERST_SCM_N")
	)
	(segment
		(start 150.4188 -119.097044)
		(end 149.807676 -118.48592)
		(width 0.11684)
		(layer "In11.Cu")
		(net "FM_RST_PERST_SCM_N")
	)
	(segment
		(start 150.4188 -123.4948)
		(end 150.4188 -119.097044)
		(width 0.11684)
		(layer "In11.Cu")
		(net "FM_RST_PERST_SCM_N")
	)
	(segment
		(start 198.368158 -116.719096)
		(end 197.430136 -117.657118)
		(width 0.11684)
		(layer "In11.Cu")
		(net "FM_RST_PERST_SCM_N")
	)
	(segment
		(start 149.494494 -118.48592)
		(end 148.508974 -117.5004)
		(width 0.11684)
		(layer "In11.Cu")
		(net "FM_RST_PERST_SCM_N")
	)
	(segment
		(start 148.508974 -117.5004)
		(end 145.676112 -117.5004)
		(width 0.11684)
		(layer "In11.Cu")
		(net "FM_RST_PERST_SCM_N")
	)
	(segment
		(start 140.866622 -112.69091)
		(end 140.104114 -112.69091)
		(width 0.11684)
		(layer "In11.Cu")
		(net "FM_RST_PERST_SCM_N")
	)
	(segment
		(start 157.14472 -129.870708)
		(end 156.794708 -129.870708)
		(width 0.11684)
		(layer "In11.Cu")
		(net "FM_RST_PERST_SCM_N")
	)
	(segment
		(start 197.916546 -129.732024)
		(end 197.040754 -130.607816)
		(width 0.11684)
		(layer "In11.Cu")
		(net "FM_RST_PERST_SCM_N")
	)
	(segment
		(start 197.430136 -126.971298)
		(end 197.916546 -127.457708)
		(width 0.11684)
		(layer "In11.Cu")
		(net "FM_RST_PERST_SCM_N")
	)
	(segment
		(start 197.430136 -117.657118)
		(end 197.430136 -126.971298)
		(width 0.11684)
		(layer "In11.Cu")
		(net "FM_RST_PERST_SCM_N")
	)
	(segment
		(start 156.794708 -129.870708)
		(end 150.4188 -123.4948)
		(width 0.11684)
		(layer "In11.Cu")
		(net "FM_RST_PERST_SCM_N")
	)
	(segment
		(start 197.040754 -130.607816)
		(end 196.840856 -130.607816)
		(width 0.11684)
		(layer "In11.Cu")
		(net "FM_RST_PERST_SCM_N")
	)
	(segment
		(start 145.676112 -117.5004)
		(end 140.866622 -112.69091)
		(width 0.11684)
		(layer "In11.Cu")
		(net "FM_RST_PERST_SCM_N")
	)
	(segment
		(start 197.916546 -127.457708)
		(end 197.916546 -129.732024)
		(width 0.11684)
		(layer "In11.Cu")
		(net "FM_RST_PERST_SCM_N")
	)
	(segment
		(start 181.991 -128.977898)
		(end 181.991 -127.765556)
		(width 0.10668)
		(layer "F.Cu")
		(net "FM_RST_CPU1_RESETL_N")
	)
	(segment
		(start 182.321708 -123.053094)
		(end 182.722012 -122.65279)
		(width 0.10668)
		(layer "F.Cu")
		(net "FM_RST_CPU1_RESETL_N")
	)
	(segment
		(start 181.991 -127.765556)
		(end 181.991 -126.05893)
		(width 0.10668)
		(layer "F.Cu")
		(net "FM_RST_CPU1_RESETL_N")
	)
	(segment
		(start 182.321708 -125.728222)
		(end 182.321708 -123.053094)
		(width 0.10668)
		(layer "F.Cu")
		(net "FM_RST_CPU1_RESETL_N")
	)
	(segment
		(start 181.991 -126.05893)
		(end 182.321708 -125.728222)
		(width 0.10668)
		(layer "F.Cu")
		(net "FM_RST_CPU1_RESETL_N")
	)
	(via
		(at 181.991 -127.765556)
		(size 0.762)
		(drill 0.381)
		(layers "F.Cu" "B.Cu")
		(net "FM_RST_CPU1_RESETL_N")
	)
	(segment
		(start 183.007 -127.003556)
		(end 183.007 -124.889768)
		(width 0.10668)
		(layer "F.Cu")
		(net "FM_RST_CPU0_RESETL_N")
	)
	(segment
		(start 183.007 -124.889768)
		(end 182.722012 -124.60478)
		(width 0.10668)
		(layer "F.Cu")
		(net "FM_RST_CPU0_RESETL_N")
	)
	(segment
		(start 182.722012 -124.60478)
		(end 182.722012 -123.45289)
		(width 0.10668)
		(layer "F.Cu")
		(net "FM_RST_CPU0_RESETL_N")
	)
	(segment
		(start 183.007 -128.977898)
		(end 183.007 -127.003556)
		(width 0.10668)
		(layer "F.Cu")
		(net "FM_RST_CPU0_RESETL_N")
	)
	(via
		(at 183.007 -127.003556)
		(size 0.762)
		(drill 0.381)
		(layers "F.Cu" "B.Cu")
		(net "FM_RST_CPU0_RESETL_N")
	)
	(segment
		(start 191.522096 -122.65279)
		(end 191.911986 -123.04268)
		(width 0.10668)
		(layer "F.Cu")
		(net "FM_ROM_SD_LS_OE")
	)
	(via
		(at 192.634108 -128.718818)
		(size 0.6604)
		(drill 0.3302)
		(layers "F.Cu" "B.Cu")
		(net "FM_ROM_SD_LS_OE")
	)
	(via
		(at 191.911986 -123.04268)
		(size 0.4572)
		(drill 0.254)
		(layers "F.Cu" "B.Cu")
		(net "FM_ROM_SD_LS_OE")
	)
	(segment
		(start 195.199 -137.232898)
		(end 195.24345 -137.188448)
		(width 0.10668)
		(layer "B.Cu")
		(net "FM_ROM_SD_LS_OE")
	)
	(segment
		(start 192.268348 -123.04268)
		(end 191.911986 -123.04268)
		(width 0.10668)
		(layer "B.Cu")
		(net "FM_ROM_SD_LS_OE")
	)
	(segment
		(start 192.634108 -125.414532)
		(end 192.375028 -125.155452)
		(width 0.10668)
		(layer "B.Cu")
		(net "FM_ROM_SD_LS_OE")
	)
	(segment
		(start 195.24345 -134.182612)
		(end 194.426078 -133.36524)
		(width 0.10668)
		(layer "B.Cu")
		(net "FM_ROM_SD_LS_OE")
	)
	(segment
		(start 192.70726 -132.169154)
		(end 193.139822 -131.736592)
		(width 0.10668)
		(layer "B.Cu")
		(net "FM_ROM_SD_LS_OE")
	)
	(segment
		(start 193.139822 -130.821938)
		(end 193.13906 -130.821176)
		(width 0.10668)
		(layer "B.Cu")
		(net "FM_ROM_SD_LS_OE")
	)
	(segment
		(start 193.139822 -131.736592)
		(end 193.139822 -130.821938)
		(width 0.10668)
		(layer "B.Cu")
		(net "FM_ROM_SD_LS_OE")
	)
	(segment
		(start 192.375028 -125.155452)
		(end 192.375028 -123.14936)
		(width 0.10668)
		(layer "B.Cu")
		(net "FM_ROM_SD_LS_OE")
	)
	(segment
		(start 194.426078 -133.36524)
		(end 193.499994 -133.36524)
		(width 0.10668)
		(layer "B.Cu")
		(net "FM_ROM_SD_LS_OE")
	)
	(segment
		(start 192.375028 -123.14936)
		(end 192.268348 -123.04268)
		(width 0.10668)
		(layer "B.Cu")
		(net "FM_ROM_SD_LS_OE")
	)
	(segment
		(start 195.24345 -137.188448)
		(end 195.24345 -134.182612)
		(width 0.10668)
		(layer "B.Cu")
		(net "FM_ROM_SD_LS_OE")
	)
	(segment
		(start 193.499994 -133.36524)
		(end 192.70726 -132.572506)
		(width 0.10668)
		(layer "B.Cu")
		(net "FM_ROM_SD_LS_OE")
	)
	(segment
		(start 193.13906 -129.22377)
		(end 192.634108 -128.718818)
		(width 0.10668)
		(layer "B.Cu")
		(net "FM_ROM_SD_LS_OE")
	)
	(segment
		(start 192.70726 -132.572506)
		(end 192.70726 -132.169154)
		(width 0.10668)
		(layer "B.Cu")
		(net "FM_ROM_SD_LS_OE")
	)
	(segment
		(start 192.634108 -128.718818)
		(end 192.634108 -125.414532)
		(width 0.10668)
		(layer "B.Cu")
		(net "FM_ROM_SD_LS_OE")
	)
	(segment
		(start 193.13906 -130.821176)
		(end 193.13906 -129.22377)
		(width 0.10668)
		(layer "B.Cu")
		(net "FM_ROM_SD_LS_OE")
	)
	(segment
		(start 192.322196 -124.845572)
		(end 192.322196 -123.45289)
		(width 0.10668)
		(layer "F.Cu")
		(net "FM_ROM_LS_EN")
	)
	(segment
		(start 193.421 -128.723898)
		(end 193.421 -127.765556)
		(width 0.10668)
		(layer "F.Cu")
		(net "FM_ROM_LS_EN")
	)
	(segment
		(start 193.167 -128.977898)
		(end 193.421 -128.723898)
		(width 0.10668)
		(layer "F.Cu")
		(net "FM_ROM_LS_EN")
	)
	(segment
		(start 193.421 -127.765556)
		(end 193.421 -125.944376)
		(width 0.10668)
		(layer "F.Cu")
		(net "FM_ROM_LS_EN")
	)
	(segment
		(start 193.421 -125.944376)
		(end 192.322196 -124.845572)
		(width 0.10668)
		(layer "F.Cu")
		(net "FM_ROM_LS_EN")
	)
	(via
		(at 193.421 -127.765556)
		(size 0.762)
		(drill 0.381)
		(layers "F.Cu" "B.Cu")
		(net "FM_ROM_LS_EN")
	)
	(segment
		(start 196.046852 -113.494566)
		(end 195.590668 -113.494566)
		(width 0.10668)
		(layer "F.Cu")
		(net "FM_PWRGD_PVDDIO_P1")
	)
	(segment
		(start 195.062856 -113.05286)
		(end 193.922142 -113.05286)
		(width 0.10668)
		(layer "F.Cu")
		(net "FM_PWRGD_PVDDIO_P1")
	)
	(segment
		(start 195.590668 -113.494566)
		(end 195.504562 -113.494566)
		(width 0.10668)
		(layer "F.Cu")
		(net "FM_PWRGD_PVDDIO_P1")
	)
	(segment
		(start 196.869558 -113.625376)
		(end 196.177662 -113.625376)
		(width 0.10668)
		(layer "F.Cu")
		(net "FM_PWRGD_PVDDIO_P1")
	)
	(segment
		(start 196.177662 -113.625376)
		(end 196.046852 -113.494566)
		(width 0.10668)
		(layer "F.Cu")
		(net "FM_PWRGD_PVDDIO_P1")
	)
	(segment
		(start 195.504562 -113.494566)
		(end 195.062856 -113.05286)
		(width 0.10668)
		(layer "F.Cu")
		(net "FM_PWRGD_PVDDIO_P1")
	)
	(via
		(at 195.590668 -113.494566)
		(size 0.508)
		(drill 0.254)
		(layers "F.Cu" "B.Cu")
		(net "FM_PWRGD_PVDDIO_P1")
	)
	(segment
		(start 189.92215 -110.652814)
		(end 190.31204 -110.262924)
		(width 0.10668)
		(layer "F.Cu")
		(net "FM_PWRGD_PVDDIO_P0")
	)
	(via
		(at 190.31204 -110.262924)
		(size 0.4572)
		(drill 0.254)
		(layers "F.Cu" "B.Cu")
		(net "FM_PWRGD_PVDDIO_P0")
	)
	(via
		(at 195.904358 -104.918256)
		(size 0.6604)
		(drill 0.3302)
		(layers "F.Cu" "B.Cu")
		(net "FM_PWRGD_PVDDIO_P0")
	)
	(segment
		(start 195.57492 -105.668064)
		(end 193.915792 -107.327192)
		(width 0.10668)
		(layer "B.Cu")
		(net "FM_PWRGD_PVDDIO_P0")
	)
	(segment
		(start 193.915792 -108.01985)
		(end 193.668904 -108.266738)
		(width 0.10668)
		(layer "B.Cu")
		(net "FM_PWRGD_PVDDIO_P0")
	)
	(segment
		(start 193.347594 -108.266738)
		(end 193.115692 -108.49864)
		(width 0.10668)
		(layer "B.Cu")
		(net "FM_PWRGD_PVDDIO_P0")
	)
	(segment
		(start 192.876424 -109.059218)
		(end 192.555368 -109.059218)
		(width 0.10668)
		(layer "B.Cu")
		(net "FM_PWRGD_PVDDIO_P0")
	)
	(segment
		(start 196.341238 -104.481376)
		(end 195.904358 -104.918256)
		(width 0.10668)
		(layer "B.Cu")
		(net "FM_PWRGD_PVDDIO_P0")
	)
	(segment
		(start 192.068958 -109.866684)
		(end 190.947548 -109.866684)
		(width 0.10668)
		(layer "B.Cu")
		(net "FM_PWRGD_PVDDIO_P0")
	)
	(segment
		(start 195.904358 -104.968548)
		(end 195.57492 -105.297986)
		(width 0.10668)
		(layer "B.Cu")
		(net "FM_PWRGD_PVDDIO_P0")
	)
	(segment
		(start 192.555368 -109.059218)
		(end 192.315846 -109.29874)
		(width 0.10668)
		(layer "B.Cu")
		(net "FM_PWRGD_PVDDIO_P0")
	)
	(segment
		(start 195.57492 -105.297986)
		(end 195.57492 -105.668064)
		(width 0.10668)
		(layer "B.Cu")
		(net "FM_PWRGD_PVDDIO_P0")
	)
	(segment
		(start 193.915792 -107.327192)
		(end 193.915792 -108.01985)
		(width 0.10668)
		(layer "B.Cu")
		(net "FM_PWRGD_PVDDIO_P0")
	)
	(segment
		(start 193.668904 -108.266738)
		(end 193.347594 -108.266738)
		(width 0.10668)
		(layer "B.Cu")
		(net "FM_PWRGD_PVDDIO_P0")
	)
	(segment
		(start 193.115692 -108.81995)
		(end 192.876424 -109.059218)
		(width 0.10668)
		(layer "B.Cu")
		(net "FM_PWRGD_PVDDIO_P0")
	)
	(segment
		(start 190.947548 -109.866684)
		(end 190.551308 -110.262924)
		(width 0.10668)
		(layer "B.Cu")
		(net "FM_PWRGD_PVDDIO_P0")
	)
	(segment
		(start 195.904358 -104.918256)
		(end 195.904358 -104.968548)
		(width 0.10668)
		(layer "B.Cu")
		(net "FM_PWRGD_PVDDIO_P0")
	)
	(segment
		(start 192.315846 -109.619796)
		(end 192.068958 -109.866684)
		(width 0.10668)
		(layer "B.Cu")
		(net "FM_PWRGD_PVDDIO_P0")
	)
	(segment
		(start 193.115692 -108.49864)
		(end 193.115692 -108.81995)
		(width 0.10668)
		(layer "B.Cu")
		(net "FM_PWRGD_PVDDIO_P0")
	)
	(segment
		(start 190.551308 -110.262924)
		(end 190.31204 -110.262924)
		(width 0.10668)
		(layer "B.Cu")
		(net "FM_PWRGD_PVDDIO_P0")
	)
	(segment
		(start 192.315846 -109.29874)
		(end 192.315846 -109.619796)
		(width 0.10668)
		(layer "B.Cu")
		(net "FM_PWRGD_PVDDIO_P0")
	)
	(segment
		(start 197.123558 -104.481376)
		(end 196.341238 -104.481376)
		(width 0.10668)
		(layer "B.Cu")
		(net "FM_PWRGD_PVDDIO_P0")
	)
	(segment
		(start 189.12205 -112.25276)
		(end 189.51194 -111.86287)
		(width 0.10668)
		(layer "F.Cu")
		(net "FM_PWRGD_PVDDCR_CPU1_P1")
	)
	(via
		(at 193.490596 -111.645192)
		(size 0.6604)
		(drill 0.3302)
		(layers "F.Cu" "B.Cu")
		(net "FM_PWRGD_PVDDCR_CPU1_P1")
	)
	(via
		(at 189.51194 -111.86287)
		(size 0.4572)
		(drill 0.254)
		(layers "F.Cu" "B.Cu")
		(net "FM_PWRGD_PVDDCR_CPU1_P1")
	)
	(segment
		(start 195.255388 -109.8804)
		(end 193.490596 -111.645192)
		(width 0.10668)
		(layer "B.Cu")
		(net "FM_PWRGD_PVDDCR_CPU1_P1")
	)
	(segment
		(start 193.490596 -111.645192)
		(end 192.876678 -112.25911)
		(width 0.10668)
		(layer "B.Cu")
		(net "FM_PWRGD_PVDDCR_CPU1_P1")
	)
	(segment
		(start 196.869558 -109.164882)
		(end 196.15404 -109.8804)
		(width 0.10668)
		(layer "B.Cu")
		(net "FM_PWRGD_PVDDCR_CPU1_P1")
	)
	(segment
		(start 192.876678 -112.25911)
		(end 189.90818 -112.25911)
		(width 0.10668)
		(layer "B.Cu")
		(net "FM_PWRGD_PVDDCR_CPU1_P1")
	)
	(segment
		(start 196.15404 -109.8804)
		(end 195.255388 -109.8804)
		(width 0.10668)
		(layer "B.Cu")
		(net "FM_PWRGD_PVDDCR_CPU1_P1")
	)
	(segment
		(start 196.869558 -108.545376)
		(end 196.869558 -109.164882)
		(width 0.10668)
		(layer "B.Cu")
		(net "FM_PWRGD_PVDDCR_CPU1_P1")
	)
	(segment
		(start 189.90818 -112.25911)
		(end 189.51194 -111.86287)
		(width 0.10668)
		(layer "B.Cu")
		(net "FM_PWRGD_PVDDCR_CPU1_P1")
	)
	(segment
		(start 188.322204 -111.452914)
		(end 188.712094 -111.063024)
		(width 0.10668)
		(layer "F.Cu")
		(net "FM_PWRGD_PVDDCR_CPU1_P0")
	)
	(via
		(at 188.712094 -111.063024)
		(size 0.4572)
		(drill 0.254)
		(layers "F.Cu" "B.Cu")
		(net "FM_PWRGD_PVDDCR_CPU1_P0")
	)
	(via
		(at 195.642484 -103.494332)
		(size 0.6604)
		(drill 0.3302)
		(layers "F.Cu" "B.Cu")
		(net "FM_PWRGD_PVDDCR_CPU1_P0")
	)
	(segment
		(start 189.354968 -109.859318)
		(end 190.476378 -109.859318)
		(width 0.10668)
		(layer "B.Cu")
		(net "FM_PWRGD_PVDDCR_CPU1_P0")
	)
	(segment
		(start 190.947548 -109.066838)
		(end 192.068704 -109.066838)
		(width 0.10668)
		(layer "B.Cu")
		(net "FM_PWRGD_PVDDCR_CPU1_P0")
	)
	(segment
		(start 192.315846 -108.819696)
		(end 192.315846 -108.49864)
		(width 0.10668)
		(layer "B.Cu")
		(net "FM_PWRGD_PVDDCR_CPU1_P0")
	)
	(segment
		(start 189.1157 -110.659418)
		(end 189.1157 -110.098586)
		(width 0.10668)
		(layer "B.Cu")
		(net "FM_PWRGD_PVDDCR_CPU1_P0")
	)
	(segment
		(start 189.1157 -110.098586)
		(end 189.354968 -109.859318)
		(width 0.10668)
		(layer "B.Cu")
		(net "FM_PWRGD_PVDDCR_CPU1_P0")
	)
	(segment
		(start 192.315846 -108.49864)
		(end 192.555368 -108.259118)
		(width 0.10668)
		(layer "B.Cu")
		(net "FM_PWRGD_PVDDCR_CPU1_P0")
	)
	(segment
		(start 193.115692 -108.01985)
		(end 193.115692 -105.615486)
		(width 0.10668)
		(layer "B.Cu")
		(net "FM_PWRGD_PVDDCR_CPU1_P0")
	)
	(segment
		(start 192.876424 -108.259118)
		(end 193.115692 -108.01985)
		(width 0.10668)
		(layer "B.Cu")
		(net "FM_PWRGD_PVDDCR_CPU1_P0")
	)
	(segment
		(start 195.236846 -103.494332)
		(end 195.642484 -103.494332)
		(width 0.10668)
		(layer "B.Cu")
		(net "FM_PWRGD_PVDDCR_CPU1_P0")
	)
	(segment
		(start 190.476378 -109.859318)
		(end 190.70828 -109.627416)
		(width 0.10668)
		(layer "B.Cu")
		(net "FM_PWRGD_PVDDCR_CPU1_P0")
	)
	(segment
		(start 190.70828 -109.306106)
		(end 190.947548 -109.066838)
		(width 0.10668)
		(layer "B.Cu")
		(net "FM_PWRGD_PVDDCR_CPU1_P0")
	)
	(segment
		(start 192.555368 -108.259118)
		(end 192.876424 -108.259118)
		(width 0.10668)
		(layer "B.Cu")
		(net "FM_PWRGD_PVDDCR_CPU1_P0")
	)
	(segment
		(start 195.67144 -103.465376)
		(end 197.123558 -103.465376)
		(width 0.10668)
		(layer "B.Cu")
		(net "FM_PWRGD_PVDDCR_CPU1_P0")
	)
	(segment
		(start 193.115692 -105.615486)
		(end 195.236846 -103.494332)
		(width 0.10668)
		(layer "B.Cu")
		(net "FM_PWRGD_PVDDCR_CPU1_P0")
	)
	(segment
		(start 188.712094 -111.063024)
		(end 189.1157 -110.659418)
		(width 0.10668)
		(layer "B.Cu")
		(net "FM_PWRGD_PVDDCR_CPU1_P0")
	)
	(segment
		(start 195.642484 -103.494332)
		(end 195.67144 -103.465376)
		(width 0.10668)
		(layer "B.Cu")
		(net "FM_PWRGD_PVDDCR_CPU1_P0")
	)
	(segment
		(start 190.70828 -109.627416)
		(end 190.70828 -109.306106)
		(width 0.10668)
		(layer "B.Cu")
		(net "FM_PWRGD_PVDDCR_CPU1_P0")
	)
	(segment
		(start 192.068704 -109.066838)
		(end 192.315846 -108.819696)
		(width 0.10668)
		(layer "B.Cu")
		(net "FM_PWRGD_PVDDCR_CPU1_P0")
	)
	(segment
		(start 192.322196 -109.852968)
		(end 192.712086 -109.463078)
		(width 0.10668)
		(layer "F.Cu")
		(net "FM_PWRGD_PVDDCR_CPU0_P1")
	)
	(segment
		(start 200.539858 -108.545376)
		(end 199.866758 -108.545376)
		(width 0.10668)
		(layer "F.Cu")
		(net "FM_PWRGD_PVDDCR_CPU0_P1")
	)
	(via
		(at 192.712086 -109.463078)
		(size 0.4572)
		(drill 0.254)
		(layers "F.Cu" "B.Cu")
		(net "FM_PWRGD_PVDDCR_CPU0_P1")
	)
	(via
		(at 199.866758 -108.545376)
		(size 0.508)
		(drill 0.254)
		(layers "F.Cu" "B.Cu")
		(net "FM_PWRGD_PVDDCR_CPU0_P1")
	)
	(segment
		(start 192.712086 -109.390942)
		(end 192.712086 -109.463078)
		(width 0.11684)
		(layer "In2.Cu")
		(net "FM_PWRGD_PVDDCR_CPU0_P1")
	)
	(segment
		(start 197.83425 -108.01985)
		(end 197.776084 -107.961684)
		(width 0.11684)
		(layer "In2.Cu")
		(net "FM_PWRGD_PVDDCR_CPU0_P1")
	)
	(segment
		(start 197.776084 -107.961684)
		(end 195.938902 -107.961684)
		(width 0.11684)
		(layer "In2.Cu")
		(net "FM_PWRGD_PVDDCR_CPU0_P1")
	)
	(segment
		(start 199.866758 -108.545376)
		(end 199.341232 -108.01985)
		(width 0.11684)
		(layer "In2.Cu")
		(net "FM_PWRGD_PVDDCR_CPU0_P1")
	)
	(segment
		(start 195.186046 -108.273088)
		(end 193.267584 -108.273088)
		(width 0.11684)
		(layer "In2.Cu")
		(net "FM_PWRGD_PVDDCR_CPU0_P1")
	)
	(segment
		(start 193.11366 -108.427012)
		(end 193.11366 -108.989368)
		(width 0.11684)
		(layer "In2.Cu")
		(net "FM_PWRGD_PVDDCR_CPU0_P1")
	)
	(segment
		(start 193.11366 -108.989368)
		(end 192.712086 -109.390942)
		(width 0.11684)
		(layer "In2.Cu")
		(net "FM_PWRGD_PVDDCR_CPU0_P1")
	)
	(segment
		(start 193.267584 -108.273088)
		(end 193.11366 -108.427012)
		(width 0.11684)
		(layer "In2.Cu")
		(net "FM_PWRGD_PVDDCR_CPU0_P1")
	)
	(segment
		(start 195.938902 -107.961684)
		(end 195.186046 -108.273088)
		(width 0.11684)
		(layer "In2.Cu")
		(net "FM_PWRGD_PVDDCR_CPU0_P1")
	)
	(segment
		(start 199.341232 -108.01985)
		(end 197.83425 -108.01985)
		(width 0.11684)
		(layer "In2.Cu")
		(net "FM_PWRGD_PVDDCR_CPU0_P1")
	)
	(segment
		(start 194.99072 -108.497624)
		(end 195.71462 -107.773724)
		(width 0.10668)
		(layer "F.Cu")
		(net "FM_PWRGD_PVDD33_S5")
	)
	(segment
		(start 194.17538 -110.652814)
		(end 194.99072 -109.837474)
		(width 0.10668)
		(layer "F.Cu")
		(net "FM_PWRGD_PVDD33_S5")
	)
	(segment
		(start 195.929504 -107.55884)
		(end 195.958968 -107.529376)
		(width 0.10668)
		(layer "F.Cu")
		(net "FM_PWRGD_PVDD33_S5")
	)
	(segment
		(start 195.958968 -107.529376)
		(end 196.869558 -107.529376)
		(width 0.10668)
		(layer "F.Cu")
		(net "FM_PWRGD_PVDD33_S5")
	)
	(segment
		(start 195.71462 -107.55884)
		(end 195.929504 -107.55884)
		(width 0.10668)
		(layer "F.Cu")
		(net "FM_PWRGD_PVDD33_S5")
	)
	(segment
		(start 194.99072 -109.837474)
		(end 194.99072 -108.497624)
		(width 0.10668)
		(layer "F.Cu")
		(net "FM_PWRGD_PVDD33_S5")
	)
	(segment
		(start 196.892672 -106.562652)
		(end 196.892672 -107.506262)
		(width 0.10668)
		(layer "F.Cu")
		(net "FM_PWRGD_PVDD33_S5")
	)
	(segment
		(start 196.873876 -106.543856)
		(end 196.892672 -106.562652)
		(width 0.10668)
		(layer "F.Cu")
		(net "FM_PWRGD_PVDD33_S5")
	)
	(segment
		(start 193.922142 -110.652814)
		(end 194.17538 -110.652814)
		(width 0.10668)
		(layer "F.Cu")
		(net "FM_PWRGD_PVDD33_S5")
	)
	(segment
		(start 196.892672 -107.506262)
		(end 196.869558 -107.529376)
		(width 0.10668)
		(layer "F.Cu")
		(net "FM_PWRGD_PVDD33_S5")
	)
	(segment
		(start 195.71462 -107.773724)
		(end 195.71462 -107.55884)
		(width 0.10668)
		(layer "F.Cu")
		(net "FM_PWRGD_PVDD33_S5")
	)
	(via
		(at 195.71462 -107.55884)
		(size 0.508)
		(drill 0.254)
		(layers "F.Cu" "B.Cu")
		(net "FM_PWRGD_PVDD33_S5")
	)
	(segment
		(start 196.40931 -111.593376)
		(end 196.182234 -111.820452)
		(width 0.10668)
		(layer "F.Cu")
		(net "FM_PWRGD_PVDD18_S5_P0")
	)
	(segment
		(start 196.182234 -111.820452)
		(end 195.437252 -111.820452)
		(width 0.10668)
		(layer "F.Cu")
		(net "FM_PWRGD_PVDD18_S5_P0")
	)
	(segment
		(start 196.869558 -111.593376)
		(end 196.869558 -111.806482)
		(width 0.10668)
		(layer "F.Cu")
		(net "FM_PWRGD_PVDD18_S5_P0")
	)
	(segment
		(start 197.102476 -112.0394)
		(end 199.068944 -112.0394)
		(width 0.10668)
		(layer "F.Cu")
		(net "FM_PWRGD_PVDD18_S5_P0")
	)
	(segment
		(start 199.068944 -112.0394)
		(end 200.445878 -112.0394)
		(width 0.10668)
		(layer "F.Cu")
		(net "FM_PWRGD_PVDD18_S5_P0")
	)
	(segment
		(start 196.869558 -111.806482)
		(end 197.102476 -112.0394)
		(width 0.10668)
		(layer "F.Cu")
		(net "FM_PWRGD_PVDD18_S5_P0")
	)
	(segment
		(start 196.869558 -111.593376)
		(end 196.40931 -111.593376)
		(width 0.10668)
		(layer "F.Cu")
		(net "FM_PWRGD_PVDD18_S5_P0")
	)
	(segment
		(start 200.445878 -112.0394)
		(end 200.552558 -111.93272)
		(width 0.10668)
		(layer "F.Cu")
		(net "FM_PWRGD_PVDD18_S5_P0")
	)
	(segment
		(start 200.552558 -111.93272)
		(end 200.552558 -111.593376)
		(width 0.10668)
		(layer "F.Cu")
		(net "FM_PWRGD_PVDD18_S5_P0")
	)
	(segment
		(start 195.004944 -112.25276)
		(end 193.922142 -112.25276)
		(width 0.10668)
		(layer "F.Cu")
		(net "FM_PWRGD_PVDD18_S5_P0")
	)
	(segment
		(start 195.437252 -111.820452)
		(end 195.004944 -112.25276)
		(width 0.10668)
		(layer "F.Cu")
		(net "FM_PWRGD_PVDD18_S5_P0")
	)
	(via
		(at 199.068944 -112.0394)
		(size 0.762)
		(drill 0.381)
		(layers "F.Cu" "B.Cu")
		(net "FM_PWRGD_PVDD18_S5_P0")
	)
	(segment
		(start 196.24294 -110.41126)
		(end 196.195442 -110.458758)
		(width 0.10668)
		(layer "F.Cu")
		(net "FM_PWRGD_PVDD11_S3_P1")
	)
	(segment
		(start 196.195442 -110.458758)
		(end 195.14439 -110.458758)
		(width 0.10668)
		(layer "F.Cu")
		(net "FM_PWRGD_PVDD11_S3_P1")
	)
	(segment
		(start 195.14439 -110.458758)
		(end 194.150234 -111.452914)
		(width 0.10668)
		(layer "F.Cu")
		(net "FM_PWRGD_PVDD11_S3_P1")
	)
	(segment
		(start 196.869558 -109.812582)
		(end 196.27088 -110.41126)
		(width 0.10668)
		(layer "F.Cu")
		(net "FM_PWRGD_PVDD11_S3_P1")
	)
	(segment
		(start 196.27088 -110.41126)
		(end 196.24294 -110.41126)
		(width 0.10668)
		(layer "F.Cu")
		(net "FM_PWRGD_PVDD11_S3_P1")
	)
	(segment
		(start 196.869558 -109.561376)
		(end 196.869558 -109.812582)
		(width 0.10668)
		(layer "F.Cu")
		(net "FM_PWRGD_PVDD11_S3_P1")
	)
	(segment
		(start 194.150234 -111.452914)
		(end 193.922142 -111.452914)
		(width 0.10668)
		(layer "F.Cu")
		(net "FM_PWRGD_PVDD11_S3_P1")
	)
	(via
		(at 196.24294 -110.41126)
		(size 0.508)
		(drill 0.254)
		(layers "F.Cu" "B.Cu")
		(net "FM_PWRGD_PVDD11_S3_P1")
	)
	(segment
		(start 192.322196 -109.052868)
		(end 192.712086 -108.662978)
		(width 0.10668)
		(layer "F.Cu")
		(net "FM_PWRGD_PVDD11_S3_P0")
	)
	(segment
		(start 199.662542 -106.513376)
		(end 199.624442 -106.475276)
		(width 0.10668)
		(layer "F.Cu")
		(net "FM_PWRGD_PVDD11_S3_P0")
	)
	(segment
		(start 200.539858 -106.513376)
		(end 199.662542 -106.513376)
		(width 0.10668)
		(layer "F.Cu")
		(net "FM_PWRGD_PVDD11_S3_P0")
	)
	(via
		(at 192.712086 -108.662978)
		(size 0.4572)
		(drill 0.254)
		(layers "F.Cu" "B.Cu")
		(net "FM_PWRGD_PVDD11_S3_P0")
	)
	(via
		(at 199.624442 -106.475276)
		(size 0.508)
		(drill 0.254)
		(layers "F.Cu" "B.Cu")
		(net "FM_PWRGD_PVDD11_S3_P0")
	)
	(segment
		(start 198.018908 -106.17962)
		(end 197.381368 -106.81716)
		(width 0.11684)
		(layer "In4.Cu")
		(net "FM_PWRGD_PVDD11_S3_P0")
	)
	(segment
		(start 193.332608 -108.265976)
		(end 192.935606 -108.662978)
		(width 0.11684)
		(layer "In4.Cu")
		(net "FM_PWRGD_PVDD11_S3_P0")
	)
	(segment
		(start 197.381368 -106.81716)
		(end 195.0847 -106.81716)
		(width 0.11684)
		(layer "In4.Cu")
		(net "FM_PWRGD_PVDD11_S3_P0")
	)
	(segment
		(start 199.624442 -106.475276)
		(end 199.624442 -106.35615)
		(width 0.11684)
		(layer "In4.Cu")
		(net "FM_PWRGD_PVDD11_S3_P0")
	)
	(segment
		(start 194.340988 -107.206796)
		(end 193.900552 -107.647232)
		(width 0.11684)
		(layer "In4.Cu")
		(net "FM_PWRGD_PVDD11_S3_P0")
	)
	(segment
		(start 193.658744 -108.265976)
		(end 193.332608 -108.265976)
		(width 0.11684)
		(layer "In4.Cu")
		(net "FM_PWRGD_PVDD11_S3_P0")
	)
	(segment
		(start 193.900552 -107.647232)
		(end 193.900552 -108.024168)
		(width 0.11684)
		(layer "In4.Cu")
		(net "FM_PWRGD_PVDD11_S3_P0")
	)
	(segment
		(start 199.447912 -106.17962)
		(end 198.018908 -106.17962)
		(width 0.11684)
		(layer "In4.Cu")
		(net "FM_PWRGD_PVDD11_S3_P0")
	)
	(segment
		(start 193.900552 -108.024168)
		(end 193.658744 -108.265976)
		(width 0.11684)
		(layer "In4.Cu")
		(net "FM_PWRGD_PVDD11_S3_P0")
	)
	(segment
		(start 199.624442 -106.35615)
		(end 199.447912 -106.17962)
		(width 0.11684)
		(layer "In4.Cu")
		(net "FM_PWRGD_PVDD11_S3_P0")
	)
	(segment
		(start 194.695064 -107.206796)
		(end 194.340988 -107.206796)
		(width 0.11684)
		(layer "In4.Cu")
		(net "FM_PWRGD_PVDD11_S3_P0")
	)
	(segment
		(start 192.935606 -108.662978)
		(end 192.712086 -108.662978)
		(width 0.11684)
		(layer "In4.Cu")
		(net "FM_PWRGD_PVDD11_S3_P0")
	)
	(segment
		(start 195.0847 -106.81716)
		(end 194.695064 -107.206796)
		(width 0.11684)
		(layer "In4.Cu")
		(net "FM_PWRGD_PVDD11_S3_P0")
	)
	(segment
		(start 183.522112 -120.252744)
		(end 183.132222 -120.642634)
		(width 0.10668)
		(layer "F.Cu")
		(net "FM_PWRGD_CPU1_PWROK")
	)
	(via
		(at 183.132222 -120.642634)
		(size 0.4572)
		(drill 0.254)
		(layers "F.Cu" "B.Cu")
		(net "FM_PWRGD_CPU1_PWROK")
	)
	(via
		(at 181.56174 -125.454664)
		(size 0.6604)
		(drill 0.3302)
		(layers "F.Cu" "B.Cu")
		(net "FM_PWRGD_CPU1_PWROK")
	)
	(segment
		(start 180.483764 -129.822448)
		(end 180.483764 -126.01956)
		(width 0.10668)
		(layer "B.Cu")
		(net "FM_PWRGD_CPU1_PWROK")
	)
	(segment
		(start 180.277262 -130.02895)
		(end 180.483764 -129.822448)
		(width 0.10668)
		(layer "B.Cu")
		(net "FM_PWRGD_CPU1_PWROK")
	)
	(segment
		(start 181.128416 -124.499116)
		(end 181.128416 -122.019568)
		(width 0.10668)
		(layer "B.Cu")
		(net "FM_PWRGD_CPU1_PWROK")
	)
	(segment
		(start 182.543704 -121.838974)
		(end 182.735982 -121.646696)
		(width 0.10668)
		(layer "B.Cu")
		(net "FM_PWRGD_CPU1_PWROK")
	)
	(segment
		(start 180.277262 -130.762248)
		(end 180.277262 -130.02895)
		(width 0.10668)
		(layer "B.Cu")
		(net "FM_PWRGD_CPU1_PWROK")
	)
	(segment
		(start 181.30901 -121.838974)
		(end 182.543704 -121.838974)
		(width 0.10668)
		(layer "B.Cu")
		(net "FM_PWRGD_CPU1_PWROK")
	)
	(segment
		(start 182.735982 -121.038874)
		(end 183.132222 -120.642634)
		(width 0.10668)
		(layer "B.Cu")
		(net "FM_PWRGD_CPU1_PWROK")
	)
	(segment
		(start 181.56174 -125.454664)
		(end 181.56174 -124.93244)
		(width 0.10668)
		(layer "B.Cu")
		(net "FM_PWRGD_CPU1_PWROK")
	)
	(segment
		(start 182.735982 -121.646696)
		(end 182.735982 -121.038874)
		(width 0.10668)
		(layer "B.Cu")
		(net "FM_PWRGD_CPU1_PWROK")
	)
	(segment
		(start 180.483764 -126.01956)
		(end 180.683408 -125.819916)
		(width 0.10668)
		(layer "B.Cu")
		(net "FM_PWRGD_CPU1_PWROK")
	)
	(segment
		(start 180.681376 -132.653278)
		(end 180.681376 -131.166362)
		(width 0.10668)
		(layer "B.Cu")
		(net "FM_PWRGD_CPU1_PWROK")
	)
	(segment
		(start 181.196488 -125.819916)
		(end 181.56174 -125.454664)
		(width 0.10668)
		(layer "B.Cu")
		(net "FM_PWRGD_CPU1_PWROK")
	)
	(segment
		(start 180.681376 -131.166362)
		(end 180.277262 -130.762248)
		(width 0.10668)
		(layer "B.Cu")
		(net "FM_PWRGD_CPU1_PWROK")
	)
	(segment
		(start 181.128416 -122.019568)
		(end 181.30901 -121.838974)
		(width 0.10668)
		(layer "B.Cu")
		(net "FM_PWRGD_CPU1_PWROK")
	)
	(segment
		(start 181.56174 -124.93244)
		(end 181.128416 -124.499116)
		(width 0.10668)
		(layer "B.Cu")
		(net "FM_PWRGD_CPU1_PWROK")
	)
	(segment
		(start 180.683408 -125.819916)
		(end 181.196488 -125.819916)
		(width 0.10668)
		(layer "B.Cu")
		(net "FM_PWRGD_CPU1_PWROK")
	)
	(segment
		(start 182.722012 -121.052844)
		(end 182.332122 -121.442734)
		(width 0.10668)
		(layer "F.Cu")
		(net "FM_PWRGD_CPU0_PWROK")
	)
	(via
		(at 180.321458 -124.660406)
		(size 0.6604)
		(drill 0.3302)
		(layers "F.Cu" "B.Cu")
		(net "FM_PWRGD_CPU0_PWROK")
	)
	(via
		(at 182.332122 -121.442734)
		(size 0.4572)
		(drill 0.254)
		(layers "F.Cu" "B.Cu")
		(net "FM_PWRGD_CPU0_PWROK")
	)
	(segment
		(start 180.321458 -124.660406)
		(end 179.997608 -124.984256)
		(width 0.10668)
		(layer "B.Cu")
		(net "FM_PWRGD_CPU0_PWROK")
	)
	(segment
		(start 180.321458 -124.570998)
		(end 180.321458 -124.660406)
		(width 0.10668)
		(layer "B.Cu")
		(net "FM_PWRGD_CPU0_PWROK")
	)
	(segment
		(start 180.553106 -121.038874)
		(end 180.335936 -121.256044)
		(width 0.10668)
		(layer "B.Cu")
		(net "FM_PWRGD_CPU0_PWROK")
	)
	(segment
		(start 179.997608 -124.984256)
		(end 179.997608 -126.433326)
		(width 0.10668)
		(layer "B.Cu")
		(net "FM_PWRGD_CPU0_PWROK")
	)
	(segment
		(start 181.928262 -121.038874)
		(end 180.553106 -121.038874)
		(width 0.10668)
		(layer "B.Cu")
		(net "FM_PWRGD_CPU0_PWROK")
	)
	(segment
		(start 182.332122 -121.442734)
		(end 181.928262 -121.038874)
		(width 0.10668)
		(layer "B.Cu")
		(net "FM_PWRGD_CPU0_PWROK")
	)
	(segment
		(start 180.335936 -124.55652)
		(end 180.321458 -124.570998)
		(width 0.10668)
		(layer "B.Cu")
		(net "FM_PWRGD_CPU0_PWROK")
	)
	(segment
		(start 180.335936 -121.256044)
		(end 180.335936 -124.55652)
		(width 0.10668)
		(layer "B.Cu")
		(net "FM_PWRGD_CPU0_PWROK")
	)
	(segment
		(start 193.507106 -112.667796)
		(end 195.506594 -112.667796)
		(width 0.10668)
		(layer "F.Cu")
		(net "FM_PVDDIO_P1_EN")
	)
	(segment
		(start 195.506594 -112.667796)
		(end 195.77685 -112.39754)
		(width 0.10668)
		(layer "F.Cu")
		(net "FM_PVDDIO_P1_EN")
	)
	(segment
		(start 195.813172 -112.39754)
		(end 196.657722 -112.39754)
		(width 0.10668)
		(layer "F.Cu")
		(net "FM_PVDDIO_P1_EN")
	)
	(segment
		(start 193.122042 -113.05286)
		(end 193.507106 -112.667796)
		(width 0.10668)
		(layer "F.Cu")
		(net "FM_PVDDIO_P1_EN")
	)
	(segment
		(start 195.77685 -112.39754)
		(end 195.813172 -112.39754)
		(width 0.10668)
		(layer "F.Cu")
		(net "FM_PVDDIO_P1_EN")
	)
	(segment
		(start 196.657722 -112.39754)
		(end 196.869558 -112.609376)
		(width 0.10668)
		(layer "F.Cu")
		(net "FM_PVDDIO_P1_EN")
	)
	(via
		(at 195.813172 -112.39754)
		(size 0.508)
		(drill 0.254)
		(layers "F.Cu" "B.Cu")
		(net "FM_PVDDIO_P1_EN")
	)
	(segment
		(start 190.721996 -110.652814)
		(end 191.111886 -110.262924)
		(width 0.10668)
		(layer "F.Cu")
		(net "FM_PVDDIO_P0_EN")
	)
	(via
		(at 195.995036 -106.318304)
		(size 0.6604)
		(drill 0.3302)
		(layers "F.Cu" "B.Cu")
		(net "FM_PVDDIO_P0_EN")
	)
	(via
		(at 191.111886 -110.262924)
		(size 0.4572)
		(drill 0.254)
		(layers "F.Cu" "B.Cu")
		(net "FM_PVDDIO_P0_EN")
	)
	(segment
		(start 196.766942 -105.936288)
		(end 196.766942 -105.875074)
		(width 0.10668)
		(layer "B.Cu")
		(net "FM_PVDDIO_P0_EN")
	)
	(segment
		(start 193.67627 -109.059218)
		(end 193.915792 -108.819696)
		(width 0.10668)
		(layer "B.Cu")
		(net "FM_PVDDIO_P0_EN")
	)
	(segment
		(start 193.915792 -108.49864)
		(end 194.147694 -108.266738)
		(width 0.10668)
		(layer "B.Cu")
		(net "FM_PVDDIO_P0_EN")
	)
	(segment
		(start 192.315846 -110.098586)
		(end 192.555114 -109.859318)
		(width 0.10668)
		(layer "B.Cu")
		(net "FM_PVDDIO_P0_EN")
	)
	(segment
		(start 194.46875 -108.266738)
		(end 194.708272 -108.027216)
		(width 0.10668)
		(layer "B.Cu")
		(net "FM_PVDDIO_P0_EN")
	)
	(segment
		(start 192.555114 -109.859318)
		(end 192.876424 -109.859318)
		(width 0.10668)
		(layer "B.Cu")
		(net "FM_PVDDIO_P0_EN")
	)
	(segment
		(start 193.355214 -109.059218)
		(end 193.67627 -109.059218)
		(width 0.10668)
		(layer "B.Cu")
		(net "FM_PVDDIO_P0_EN")
	)
	(segment
		(start 191.111886 -110.262924)
		(end 191.351408 -110.262924)
		(width 0.10668)
		(layer "B.Cu")
		(net "FM_PVDDIO_P0_EN")
	)
	(segment
		(start 195.713096 -106.318304)
		(end 195.995036 -106.318304)
		(width 0.10668)
		(layer "B.Cu")
		(net "FM_PVDDIO_P0_EN")
	)
	(segment
		(start 194.708272 -108.027216)
		(end 194.708272 -107.323128)
		(width 0.10668)
		(layer "B.Cu")
		(net "FM_PVDDIO_P0_EN")
	)
	(segment
		(start 197.123558 -105.518458)
		(end 197.123558 -105.497376)
		(width 0.10668)
		(layer "B.Cu")
		(net "FM_PVDDIO_P0_EN")
	)
	(segment
		(start 192.315846 -110.451138)
		(end 192.315846 -110.098586)
		(width 0.10668)
		(layer "B.Cu")
		(net "FM_PVDDIO_P0_EN")
	)
	(segment
		(start 196.384926 -106.318304)
		(end 196.766942 -105.936288)
		(width 0.10668)
		(layer "B.Cu")
		(net "FM_PVDDIO_P0_EN")
	)
	(segment
		(start 194.147694 -108.266738)
		(end 194.46875 -108.266738)
		(width 0.10668)
		(layer "B.Cu")
		(net "FM_PVDDIO_P0_EN")
	)
	(segment
		(start 194.708272 -107.323128)
		(end 195.713096 -106.318304)
		(width 0.10668)
		(layer "B.Cu")
		(net "FM_PVDDIO_P0_EN")
	)
	(segment
		(start 196.766942 -105.875074)
		(end 197.123558 -105.518458)
		(width 0.10668)
		(layer "B.Cu")
		(net "FM_PVDDIO_P0_EN")
	)
	(segment
		(start 193.115692 -109.29874)
		(end 193.355214 -109.059218)
		(width 0.10668)
		(layer "B.Cu")
		(net "FM_PVDDIO_P0_EN")
	)
	(segment
		(start 193.915792 -108.819696)
		(end 193.915792 -108.49864)
		(width 0.10668)
		(layer "B.Cu")
		(net "FM_PVDDIO_P0_EN")
	)
	(segment
		(start 192.10782 -110.659164)
		(end 192.315846 -110.451138)
		(width 0.10668)
		(layer "B.Cu")
		(net "FM_PVDDIO_P0_EN")
	)
	(segment
		(start 192.876424 -109.859318)
		(end 193.115692 -109.62005)
		(width 0.10668)
		(layer "B.Cu")
		(net "FM_PVDDIO_P0_EN")
	)
	(segment
		(start 195.995036 -106.318304)
		(end 196.384926 -106.318304)
		(width 0.10668)
		(layer "B.Cu")
		(net "FM_PVDDIO_P0_EN")
	)
	(segment
		(start 191.351408 -110.262924)
		(end 191.747648 -110.659164)
		(width 0.10668)
		(layer "B.Cu")
		(net "FM_PVDDIO_P0_EN")
	)
	(segment
		(start 193.115692 -109.62005)
		(end 193.115692 -109.29874)
		(width 0.10668)
		(layer "B.Cu")
		(net "FM_PVDDIO_P0_EN")
	)
	(segment
		(start 191.747648 -110.659164)
		(end 192.10782 -110.659164)
		(width 0.10668)
		(layer "B.Cu")
		(net "FM_PVDDIO_P0_EN")
	)
	(segment
		(start 189.12205 -111.452914)
		(end 189.51194 -111.063024)
		(width 0.10668)
		(layer "F.Cu")
		(net "FM_PVDDCR_CPU1_P1_R_EN")
	)
	(via
		(at 194.169284 -110.166404)
		(size 0.6604)
		(drill 0.3302)
		(layers "F.Cu" "B.Cu")
		(net "FM_PVDDCR_CPU1_P1_R_EN")
	)
	(via
		(at 189.51194 -111.063024)
		(size 0.4572)
		(drill 0.254)
		(layers "F.Cu" "B.Cu")
		(net "FM_PVDDCR_CPU1_P1_R_EN")
	)
	(segment
		(start 194.772788 -109.052868)
		(end 194.772788 -109.5629)
		(width 0.10668)
		(layer "B.Cu")
		(net "FM_PVDDCR_CPU1_P1_R_EN")
	)
	(segment
		(start 192.555368 -110.659164)
		(end 192.315846 -110.898686)
		(width 0.10668)
		(layer "B.Cu")
		(net "FM_PVDDCR_CPU1_P1_R_EN")
	)
	(segment
		(start 192.069212 -111.466376)
		(end 189.915292 -111.466376)
		(width 0.10668)
		(layer "B.Cu")
		(net "FM_PVDDCR_CPU1_P1_R_EN")
	)
	(segment
		(start 194.772788 -109.5629)
		(end 194.169284 -110.166404)
		(width 0.10668)
		(layer "B.Cu")
		(net "FM_PVDDCR_CPU1_P1_R_EN")
	)
	(segment
		(start 196.330316 -108.845604)
		(end 194.980052 -108.845604)
		(width 0.10668)
		(layer "B.Cu")
		(net "FM_PVDDCR_CPU1_P1_R_EN")
	)
	(segment
		(start 192.315846 -110.898686)
		(end 192.315846 -111.219742)
		(width 0.10668)
		(layer "B.Cu")
		(net "FM_PVDDCR_CPU1_P1_R_EN")
	)
	(segment
		(start 194.169284 -110.166404)
		(end 193.676524 -110.659164)
		(width 0.10668)
		(layer "B.Cu")
		(net "FM_PVDDCR_CPU1_P1_R_EN")
	)
	(segment
		(start 193.676524 -110.659164)
		(end 192.555368 -110.659164)
		(width 0.10668)
		(layer "B.Cu")
		(net "FM_PVDDCR_CPU1_P1_R_EN")
	)
	(segment
		(start 192.315846 -111.219742)
		(end 192.069212 -111.466376)
		(width 0.10668)
		(layer "B.Cu")
		(net "FM_PVDDCR_CPU1_P1_R_EN")
	)
	(segment
		(start 194.980052 -108.845604)
		(end 194.772788 -109.052868)
		(width 0.10668)
		(layer "B.Cu")
		(net "FM_PVDDCR_CPU1_P1_R_EN")
	)
	(segment
		(start 189.915292 -111.466376)
		(end 189.51194 -111.063024)
		(width 0.10668)
		(layer "B.Cu")
		(net "FM_PVDDCR_CPU1_P1_R_EN")
	)
	(segment
		(start 196.869558 -107.529376)
		(end 196.869558 -107.80268)
		(width 0.10668)
		(layer "B.Cu")
		(net "FM_PVDDCR_CPU1_P1_R_EN")
	)
	(segment
		(start 196.869558 -107.80268)
		(end 196.507608 -108.16463)
		(width 0.10668)
		(layer "B.Cu")
		(net "FM_PVDDCR_CPU1_P1_R_EN")
	)
	(segment
		(start 196.507608 -108.16463)
		(end 196.507608 -108.173012)
		(width 0.10668)
		(layer "B.Cu")
		(net "FM_PVDDCR_CPU1_P1_R_EN")
	)
	(segment
		(start 196.473064 -108.702856)
		(end 196.330316 -108.845604)
		(width 0.10668)
		(layer "B.Cu")
		(net "FM_PVDDCR_CPU1_P1_R_EN")
	)
	(segment
		(start 196.473064 -108.207556)
		(end 196.473064 -108.702856)
		(width 0.10668)
		(layer "B.Cu")
		(net "FM_PVDDCR_CPU1_P1_R_EN")
	)
	(segment
		(start 196.507608 -108.173012)
		(end 196.473064 -108.207556)
		(width 0.10668)
		(layer "B.Cu")
		(net "FM_PVDDCR_CPU1_P1_R_EN")
	)
	(segment
		(start 181.922166 -109.052868)
		(end 181.532276 -108.662978)
		(width 0.10668)
		(layer "F.Cu")
		(net "FM_PVDDCR_CPU1_P1_OCP_N")
	)
	(via
		(at 181.532276 -108.662978)
		(size 0.4572)
		(drill 0.254)
		(layers "F.Cu" "B.Cu")
		(net "FM_PVDDCR_CPU1_P1_OCP_N")
	)
	(via
		(at 178.689 -101.92766)
		(size 0.508)
		(drill 0.254)
		(layers "F.Cu" "B.Cu")
		(net "FM_PVDDCR_CPU1_P1_OCP_N")
	)
	(segment
		(start 178.689 -100.694998)
		(end 178.689 -101.92766)
		(width 0.10668)
		(layer "B.Cu")
		(net "FM_PVDDCR_CPU1_P1_OCP_N")
	)
	(segment
		(start 181.136036 -108.266738)
		(end 181.532276 -108.662978)
		(width 0.11684)
		(layer "In11.Cu")
		(net "FM_PVDDCR_CPU1_P1_OCP_N")
	)
	(segment
		(start 180.50764 -108.266738)
		(end 181.136036 -108.266738)
		(width 0.11684)
		(layer "In11.Cu")
		(net "FM_PVDDCR_CPU1_P1_OCP_N")
	)
	(segment
		(start 180.341524 -108.100622)
		(end 180.50764 -108.266738)
		(width 0.11684)
		(layer "In11.Cu")
		(net "FM_PVDDCR_CPU1_P1_OCP_N")
	)
	(segment
		(start 178.689 -105.138728)
		(end 180.341524 -106.791252)
		(width 0.11684)
		(layer "In11.Cu")
		(net "FM_PVDDCR_CPU1_P1_OCP_N")
	)
	(segment
		(start 180.341524 -106.791252)
		(end 180.341524 -108.100622)
		(width 0.11684)
		(layer "In11.Cu")
		(net "FM_PVDDCR_CPU1_P1_OCP_N")
	)
	(segment
		(start 178.689 -101.92766)
		(end 178.689 -105.138728)
		(width 0.11684)
		(layer "In11.Cu")
		(net "FM_PVDDCR_CPU1_P1_OCP_N")
	)
	(via
		(at 214.884 -107.533948)
		(size 0.508)
		(drill 0.254)
		(layers "F.Cu" "B.Cu")
		(net "FM_PVDDCR_CPU1_P1_EN")
	)
	(via
		(at 162.306 -92.674948)
		(size 0.508)
		(drill 0.254)
		(layers "F.Cu" "B.Cu")
		(net "FM_PVDDCR_CPU1_P1_EN")
	)
	(via
		(at 212.789516 -85.17763)
		(size 0.508)
		(drill 0.254)
		(layers "F.Cu" "B.Cu")
		(net "FM_PVDDCR_CPU1_P1_EN")
	)
	(via
		(at 112.343438 -120.508268)
		(size 0.508)
		(drill 0.254)
		(layers "F.Cu" "B.Cu")
		(net "FM_PVDDCR_CPU1_P1_EN")
	)
	(via
		(at 21.616162 -363.994954)
		(size 0.508)
		(drill 0.254)
		(layers "F.Cu" "B.Cu")
		(net "FM_PVDDCR_CPU1_P1_EN")
	)
	(segment
		(start 197.669658 -107.529376)
		(end 198.206868 -108.066586)
		(width 0.10668)
		(layer "B.Cu")
		(net "FM_PVDDCR_CPU1_P1_EN")
	)
	(segment
		(start 210.672172 -104.573832)
		(end 212.83676 -106.73842)
		(width 0.10668)
		(layer "B.Cu")
		(net "FM_PVDDCR_CPU1_P1_EN")
	)
	(segment
		(start 201.631296 -104.15016)
		(end 205.577186 -104.15016)
		(width 0.10668)
		(layer "B.Cu")
		(net "FM_PVDDCR_CPU1_P1_EN")
	)
	(segment
		(start 23.755096 -364.007146)
		(end 24.36495 -364.617)
		(width 0.10668)
		(layer "B.Cu")
		(net "FM_PVDDCR_CPU1_P1_EN")
	)
	(segment
		(start 206.000858 -104.573832)
		(end 210.672172 -104.573832)
		(width 0.10668)
		(layer "B.Cu")
		(net "FM_PVDDCR_CPU1_P1_EN")
	)
	(segment
		(start 200.610216 -107.829096)
		(end 200.610216 -105.17124)
		(width 0.10668)
		(layer "B.Cu")
		(net "FM_PVDDCR_CPU1_P1_EN")
	)
	(segment
		(start 198.206868 -108.066586)
		(end 200.372726 -108.066586)
		(width 0.10668)
		(layer "B.Cu")
		(net "FM_PVDDCR_CPU1_P1_EN")
	)
	(segment
		(start 21.616162 -363.994954)
		(end 22.485096 -363.994954)
		(width 0.10668)
		(layer "B.Cu")
		(net "FM_PVDDCR_CPU1_P1_EN")
	)
	(segment
		(start 200.372726 -108.066586)
		(end 200.610216 -107.829096)
		(width 0.10668)
		(layer "B.Cu")
		(net "FM_PVDDCR_CPU1_P1_EN")
	)
	(segment
		(start 22.497288 -364.007146)
		(end 23.755096 -364.007146)
		(width 0.10668)
		(layer "B.Cu")
		(net "FM_PVDDCR_CPU1_P1_EN")
	)
	(segment
		(start 22.485096 -363.994954)
		(end 22.497288 -364.007146)
		(width 0.10668)
		(layer "B.Cu")
		(net "FM_PVDDCR_CPU1_P1_EN")
	)
	(segment
		(start 214.088472 -106.73842)
		(end 214.884 -107.533948)
		(width 0.10668)
		(layer "B.Cu")
		(net "FM_PVDDCR_CPU1_P1_EN")
	)
	(segment
		(start 205.577186 -104.15016)
		(end 206.000858 -104.573832)
		(width 0.10668)
		(layer "B.Cu")
		(net "FM_PVDDCR_CPU1_P1_EN")
	)
	(segment
		(start 212.83676 -106.73842)
		(end 214.088472 -106.73842)
		(width 0.10668)
		(layer "B.Cu")
		(net "FM_PVDDCR_CPU1_P1_EN")
	)
	(segment
		(start 200.610216 -105.17124)
		(end 201.631296 -104.15016)
		(width 0.10668)
		(layer "B.Cu")
		(net "FM_PVDDCR_CPU1_P1_EN")
	)
	(segment
		(start 211.92236 -86.044786)
		(end 212.789516 -85.17763)
		(width 0.11684)
		(layer "In4.Cu")
		(net "FM_PVDDCR_CPU1_P1_EN")
	)
	(segment
		(start 210.41995 -97.782634)
		(end 210.41995 -91.624658)
		(width 0.11684)
		(layer "In4.Cu")
		(net "FM_PVDDCR_CPU1_P1_EN")
	)
	(segment
		(start 210.41995 -91.624658)
		(end 211.92236 -90.122248)
		(width 0.11684)
		(layer "In4.Cu")
		(net "FM_PVDDCR_CPU1_P1_EN")
	)
	(segment
		(start 213.93658 -101.299264)
		(end 210.41995 -97.782634)
		(width 0.11684)
		(layer "In4.Cu")
		(net "FM_PVDDCR_CPU1_P1_EN")
	)
	(segment
		(start 213.93658 -106.586528)
		(end 213.93658 -101.299264)
		(width 0.11684)
		(layer "In4.Cu")
		(net "FM_PVDDCR_CPU1_P1_EN")
	)
	(segment
		(start 214.884 -107.533948)
		(end 213.93658 -106.586528)
		(width 0.11684)
		(layer "In4.Cu")
		(net "FM_PVDDCR_CPU1_P1_EN")
	)
	(segment
		(start 211.92236 -90.122248)
		(end 211.92236 -86.044786)
		(width 0.11684)
		(layer "In4.Cu")
		(net "FM_PVDDCR_CPU1_P1_EN")
	)
	(segment
		(start 157.20949 -108.571792)
		(end 158.786322 -106.99496)
		(width 0.11684)
		(layer "In6.Cu")
		(net "FM_PVDDCR_CPU1_P1_EN")
	)
	(segment
		(start 141.835378 -117.460522)
		(end 142.315692 -117.940836)
		(width 0.11684)
		(layer "In6.Cu")
		(net "FM_PVDDCR_CPU1_P1_EN")
	)
	(segment
		(start 162.306 -93.450664)
		(end 162.306 -92.674948)
		(width 0.11684)
		(layer "In6.Cu")
		(net "FM_PVDDCR_CPU1_P1_EN")
	)
	(segment
		(start 158.786322 -106.99496)
		(end 158.786322 -96.970342)
		(width 0.11684)
		(layer "In6.Cu")
		(net "FM_PVDDCR_CPU1_P1_EN")
	)
	(segment
		(start 139.420092 -118.277132)
		(end 140.236702 -117.460522)
		(width 0.11684)
		(layer "In6.Cu")
		(net "FM_PVDDCR_CPU1_P1_EN")
	)
	(segment
		(start 112.343438 -120.508268)
		(end 114.574574 -118.277132)
		(width 0.11684)
		(layer "In6.Cu")
		(net "FM_PVDDCR_CPU1_P1_EN")
	)
	(segment
		(start 155.214574 -115.45189)
		(end 157.20949 -113.456974)
		(width 0.11684)
		(layer "In6.Cu")
		(net "FM_PVDDCR_CPU1_P1_EN")
	)
	(segment
		(start 140.236702 -117.460522)
		(end 141.835378 -117.460522)
		(width 0.11684)
		(layer "In6.Cu")
		(net "FM_PVDDCR_CPU1_P1_EN")
	)
	(segment
		(start 142.315692 -117.940836)
		(end 145.123916 -117.940836)
		(width 0.11684)
		(layer "In6.Cu")
		(net "FM_PVDDCR_CPU1_P1_EN")
	)
	(segment
		(start 158.786322 -96.970342)
		(end 162.306 -93.450664)
		(width 0.11684)
		(layer "In6.Cu")
		(net "FM_PVDDCR_CPU1_P1_EN")
	)
	(segment
		(start 114.574574 -118.277132)
		(end 139.420092 -118.277132)
		(width 0.11684)
		(layer "In6.Cu")
		(net "FM_PVDDCR_CPU1_P1_EN")
	)
	(segment
		(start 145.123916 -117.940836)
		(end 147.612862 -115.45189)
		(width 0.11684)
		(layer "In6.Cu")
		(net "FM_PVDDCR_CPU1_P1_EN")
	)
	(segment
		(start 157.20949 -113.456974)
		(end 157.20949 -108.571792)
		(width 0.11684)
		(layer "In6.Cu")
		(net "FM_PVDDCR_CPU1_P1_EN")
	)
	(segment
		(start 147.612862 -115.45189)
		(end 155.214574 -115.45189)
		(width 0.11684)
		(layer "In6.Cu")
		(net "FM_PVDDCR_CPU1_P1_EN")
	)
	(segment
		(start 44.14774 -136.792208)
		(end 26.256742 -136.792208)
		(width 0.11684)
		(layer "In11.Cu")
		(net "FM_PVDDCR_CPU1_P1_EN")
	)
	(segment
		(start 6.941058 -166.135304)
		(end 5.187188 -167.889174)
		(width 0.11684)
		(layer "In11.Cu")
		(net "FM_PVDDCR_CPU1_P1_EN")
	)
	(segment
		(start 8.005318 -353.69754)
		(end 14.848078 -353.69754)
		(width 0.11684)
		(layer "In11.Cu")
		(net "FM_PVDDCR_CPU1_P1_EN")
	)
	(segment
		(start 20.59813 -363.994954)
		(end 21.616162 -363.994954)
		(width 0.11684)
		(layer "In11.Cu")
		(net "FM_PVDDCR_CPU1_P1_EN")
	)
	(segment
		(start 4.480306 -350.172528)
		(end 8.005318 -353.69754)
		(width 0.11684)
		(layer "In11.Cu")
		(net "FM_PVDDCR_CPU1_P1_EN")
	)
	(segment
		(start 94.59976 -123.614688)
		(end 88.525858 -129.68859)
		(width 0.11684)
		(layer "In11.Cu")
		(net "FM_PVDDCR_CPU1_P1_EN")
	)
	(segment
		(start 14.848078 -353.69754)
		(end 17.858486 -356.707948)
		(width 0.11684)
		(layer "In11.Cu")
		(net "FM_PVDDCR_CPU1_P1_EN")
	)
	(segment
		(start 5.187188 -343.895172)
		(end 4.480306 -344.602054)
		(width 0.11684)
		(layer "In11.Cu")
		(net "FM_PVDDCR_CPU1_P1_EN")
	)
	(segment
		(start 17.05991 -145.98904)
		(end 17.05991 -162.677348)
		(width 0.11684)
		(layer "In11.Cu")
		(net "FM_PVDDCR_CPU1_P1_EN")
	)
	(segment
		(start 13.601954 -166.135304)
		(end 6.941058 -166.135304)
		(width 0.11684)
		(layer "In11.Cu")
		(net "FM_PVDDCR_CPU1_P1_EN")
	)
	(segment
		(start 51.251358 -129.68859)
		(end 44.14774 -136.792208)
		(width 0.11684)
		(layer "In11.Cu")
		(net "FM_PVDDCR_CPU1_P1_EN")
	)
	(segment
		(start 88.525858 -129.68859)
		(end 51.251358 -129.68859)
		(width 0.11684)
		(layer "In11.Cu")
		(net "FM_PVDDCR_CPU1_P1_EN")
	)
	(segment
		(start 112.343438 -120.871742)
		(end 109.600492 -123.614688)
		(width 0.11684)
		(layer "In11.Cu")
		(net "FM_PVDDCR_CPU1_P1_EN")
	)
	(segment
		(start 26.256742 -136.792208)
		(end 17.05991 -145.98904)
		(width 0.11684)
		(layer "In11.Cu")
		(net "FM_PVDDCR_CPU1_P1_EN")
	)
	(segment
		(start 112.343438 -120.508268)
		(end 112.343438 -120.871742)
		(width 0.11684)
		(layer "In11.Cu")
		(net "FM_PVDDCR_CPU1_P1_EN")
	)
	(segment
		(start 109.600492 -123.614688)
		(end 94.59976 -123.614688)
		(width 0.11684)
		(layer "In11.Cu")
		(net "FM_PVDDCR_CPU1_P1_EN")
	)
	(segment
		(start 17.858486 -356.707948)
		(end 17.858486 -361.25531)
		(width 0.11684)
		(layer "In11.Cu")
		(net "FM_PVDDCR_CPU1_P1_EN")
	)
	(segment
		(start 17.858486 -361.25531)
		(end 20.59813 -363.994954)
		(width 0.11684)
		(layer "In11.Cu")
		(net "FM_PVDDCR_CPU1_P1_EN")
	)
	(segment
		(start 5.187188 -167.889174)
		(end 5.187188 -343.895172)
		(width 0.11684)
		(layer "In11.Cu")
		(net "FM_PVDDCR_CPU1_P1_EN")
	)
	(segment
		(start 4.480306 -344.602054)
		(end 4.480306 -350.172528)
		(width 0.11684)
		(layer "In11.Cu")
		(net "FM_PVDDCR_CPU1_P1_EN")
	)
	(segment
		(start 17.05991 -162.677348)
		(end 13.601954 -166.135304)
		(width 0.11684)
		(layer "In11.Cu")
		(net "FM_PVDDCR_CPU1_P1_EN")
	)
	(segment
		(start 188.402214 -84.773008)
		(end 166.424356 -84.773008)
		(width 0.11684)
		(layer "In15.Cu")
		(net "FM_PVDDCR_CPU1_P1_EN")
	)
	(segment
		(start 209.05978 -84.69884)
		(end 209.05978 -85.885528)
		(width 0.11684)
		(layer "In15.Cu")
		(net "FM_PVDDCR_CPU1_P1_EN")
	)
	(segment
		(start 212.789516 -85.17763)
		(end 212.789516 -83.589876)
		(width 0.11684)
		(layer "In15.Cu")
		(net "FM_PVDDCR_CPU1_P1_EN")
	)
	(segment
		(start 188.717174 -85.087968)
		(end 188.402214 -84.773008)
		(width 0.11684)
		(layer "In15.Cu")
		(net "FM_PVDDCR_CPU1_P1_EN")
	)
	(segment
		(start 210.41868 -83.33994)
		(end 209.05978 -84.69884)
		(width 0.11684)
		(layer "In15.Cu")
		(net "FM_PVDDCR_CPU1_P1_EN")
	)
	(segment
		(start 194.71894 -84.059268)
		(end 193.69024 -85.087968)
		(width 0.11684)
		(layer "In15.Cu")
		(net "FM_PVDDCR_CPU1_P1_EN")
	)
	(segment
		(start 203.789788 -87.300308)
		(end 202.911964 -86.422484)
		(width 0.11684)
		(layer "In15.Cu")
		(net "FM_PVDDCR_CPU1_P1_EN")
	)
	(segment
		(start 193.69024 -85.087968)
		(end 188.717174 -85.087968)
		(width 0.11684)
		(layer "In15.Cu")
		(net "FM_PVDDCR_CPU1_P1_EN")
	)
	(segment
		(start 212.53958 -83.33994)
		(end 210.41868 -83.33994)
		(width 0.11684)
		(layer "In15.Cu")
		(net "FM_PVDDCR_CPU1_P1_EN")
	)
	(segment
		(start 196.86397 -84.059268)
		(end 194.71894 -84.059268)
		(width 0.11684)
		(layer "In15.Cu")
		(net "FM_PVDDCR_CPU1_P1_EN")
	)
	(segment
		(start 166.424356 -84.773008)
		(end 162.306 -88.891364)
		(width 0.11684)
		(layer "In15.Cu")
		(net "FM_PVDDCR_CPU1_P1_EN")
	)
	(segment
		(start 197.698868 -84.894166)
		(end 196.86397 -84.059268)
		(width 0.11684)
		(layer "In15.Cu")
		(net "FM_PVDDCR_CPU1_P1_EN")
	)
	(segment
		(start 162.306 -88.891364)
		(end 162.306 -92.674948)
		(width 0.11684)
		(layer "In15.Cu")
		(net "FM_PVDDCR_CPU1_P1_EN")
	)
	(segment
		(start 201.189844 -86.422484)
		(end 199.661526 -84.894166)
		(width 0.11684)
		(layer "In15.Cu")
		(net "FM_PVDDCR_CPU1_P1_EN")
	)
	(segment
		(start 212.789516 -83.589876)
		(end 212.53958 -83.33994)
		(width 0.11684)
		(layer "In15.Cu")
		(net "FM_PVDDCR_CPU1_P1_EN")
	)
	(segment
		(start 207.645 -87.300308)
		(end 203.789788 -87.300308)
		(width 0.11684)
		(layer "In15.Cu")
		(net "FM_PVDDCR_CPU1_P1_EN")
	)
	(segment
		(start 202.911964 -86.422484)
		(end 201.189844 -86.422484)
		(width 0.11684)
		(layer "In15.Cu")
		(net "FM_PVDDCR_CPU1_P1_EN")
	)
	(segment
		(start 209.05978 -85.885528)
		(end 207.645 -87.300308)
		(width 0.11684)
		(layer "In15.Cu")
		(net "FM_PVDDCR_CPU1_P1_EN")
	)
	(segment
		(start 199.661526 -84.894166)
		(end 197.698868 -84.894166)
		(width 0.11684)
		(layer "In15.Cu")
		(net "FM_PVDDCR_CPU1_P1_EN")
	)
	(segment
		(start 187.522104 -111.452914)
		(end 187.911994 -111.063024)
		(width 0.10668)
		(layer "F.Cu")
		(net "FM_PVDDCR_CPU1_P0_R_EN")
	)
	(via
		(at 188.152278 -105.345992)
		(size 0.6604)
		(drill 0.3302)
		(layers "F.Cu" "B.Cu")
		(net "FM_PVDDCR_CPU1_P0_R_EN")
	)
	(via
		(at 187.911994 -111.063024)
		(size 0.4572)
		(drill 0.254)
		(layers "F.Cu" "B.Cu")
		(net "FM_PVDDCR_CPU1_P0_R_EN")
	)
	(segment
		(start 187.508134 -110.659164)
		(end 187.508134 -105.990136)
		(width 0.10668)
		(layer "B.Cu")
		(net "FM_PVDDCR_CPU1_P0_R_EN")
	)
	(segment
		(start 188.3918 -105.10647)
		(end 188.3918 -101.152198)
		(width 0.10668)
		(layer "B.Cu")
		(net "FM_PVDDCR_CPU1_P0_R_EN")
	)
	(segment
		(start 188.3918 -101.152198)
		(end 188.849 -100.694998)
		(width 0.10668)
		(layer "B.Cu")
		(net "FM_PVDDCR_CPU1_P0_R_EN")
	)
	(segment
		(start 187.508134 -105.990136)
		(end 188.152278 -105.345992)
		(width 0.10668)
		(layer "B.Cu")
		(net "FM_PVDDCR_CPU1_P0_R_EN")
	)
	(segment
		(start 188.152278 -105.345992)
		(end 188.3918 -105.10647)
		(width 0.10668)
		(layer "B.Cu")
		(net "FM_PVDDCR_CPU1_P0_R_EN")
	)
	(segment
		(start 187.911994 -111.063024)
		(end 187.508134 -110.659164)
		(width 0.10668)
		(layer "B.Cu")
		(net "FM_PVDDCR_CPU1_P0_R_EN")
	)
	(segment
		(start 181.922166 -108.252768)
		(end 181.532276 -107.862878)
		(width 0.10668)
		(layer "F.Cu")
		(net "FM_PVDDCR_CPU1_P0_OCP_N")
	)
	(via
		(at 180.211476 -101.467158)
		(size 0.6604)
		(drill 0.3302)
		(layers "F.Cu" "B.Cu")
		(net "FM_PVDDCR_CPU1_P0_OCP_N")
	)
	(via
		(at 181.532276 -107.862878)
		(size 0.4572)
		(drill 0.254)
		(layers "F.Cu" "B.Cu")
		(net "FM_PVDDCR_CPU1_P0_OCP_N")
	)
	(segment
		(start 181.267862 -105.698544)
		(end 181.267862 -107.470956)
		(width 0.10668)
		(layer "B.Cu")
		(net "FM_PVDDCR_CPU1_P0_OCP_N")
	)
	(segment
		(start 179.705 -100.694998)
		(end 179.705 -100.960682)
		(width 0.10668)
		(layer "B.Cu")
		(net "FM_PVDDCR_CPU1_P0_OCP_N")
	)
	(segment
		(start 181.267862 -107.470956)
		(end 181.532276 -107.73537)
		(width 0.10668)
		(layer "B.Cu")
		(net "FM_PVDDCR_CPU1_P0_OCP_N")
	)
	(segment
		(start 180.612796 -103.573072)
		(end 180.488844 -103.697024)
		(width 0.10668)
		(layer "B.Cu")
		(net "FM_PVDDCR_CPU1_P0_OCP_N")
	)
	(segment
		(start 180.211476 -101.467158)
		(end 180.612796 -101.868478)
		(width 0.10668)
		(layer "B.Cu")
		(net "FM_PVDDCR_CPU1_P0_OCP_N")
	)
	(segment
		(start 180.612796 -101.868478)
		(end 180.612796 -103.573072)
		(width 0.10668)
		(layer "B.Cu")
		(net "FM_PVDDCR_CPU1_P0_OCP_N")
	)
	(segment
		(start 180.488844 -103.697024)
		(end 180.488844 -104.919526)
		(width 0.10668)
		(layer "B.Cu")
		(net "FM_PVDDCR_CPU1_P0_OCP_N")
	)
	(segment
		(start 181.532276 -107.73537)
		(end 181.532276 -107.862878)
		(width 0.10668)
		(layer "B.Cu")
		(net "FM_PVDDCR_CPU1_P0_OCP_N")
	)
	(segment
		(start 179.705 -100.960682)
		(end 180.211476 -101.467158)
		(width 0.10668)
		(layer "B.Cu")
		(net "FM_PVDDCR_CPU1_P0_OCP_N")
	)
	(segment
		(start 180.488844 -104.919526)
		(end 181.267862 -105.698544)
		(width 0.10668)
		(layer "B.Cu")
		(net "FM_PVDDCR_CPU1_P0_OCP_N")
	)
	(via
		(at 385.047744 -123.040648)
		(size 0.508)
		(drill 0.254)
		(layers "F.Cu" "B.Cu")
		(net "FM_PVDDCR_CPU1_P0_EN")
	)
	(via
		(at 329.184 -362.6358)
		(size 0.508)
		(drill 0.254)
		(layers "F.Cu" "B.Cu")
		(net "FM_PVDDCR_CPU1_P0_EN")
	)
	(via
		(at 195.149216 -95.087948)
		(size 0.508)
		(drill 0.254)
		(layers "F.Cu" "B.Cu")
		(net "FM_PVDDCR_CPU1_P0_EN")
	)
	(via
		(at 302.514 -362.1786)
		(size 0.508)
		(drill 0.254)
		(layers "F.Cu" "B.Cu")
		(net "FM_PVDDCR_CPU1_P0_EN")
	)
	(segment
		(start 442.989716 -162.59048)
		(end 440.156346 -162.59048)
		(width 0.10668)
		(layer "B.Cu")
		(net "FM_PVDDCR_CPU1_P0_EN")
	)
	(segment
		(start 440.156346 -162.59048)
		(end 433.69611 -156.130244)
		(width 0.10668)
		(layer "B.Cu")
		(net "FM_PVDDCR_CPU1_P0_EN")
	)
	(segment
		(start 188.378338 -92.963492)
		(end 188.378338 -99.61499)
		(width 0.10668)
		(layer "B.Cu")
		(net "FM_PVDDCR_CPU1_P0_EN")
	)
	(segment
		(start 407.444194 -343.195402)
		(end 414.037526 -336.60207)
		(width 0.10668)
		(layer "B.Cu")
		(net "FM_PVDDCR_CPU1_P0_EN")
	)
	(segment
		(start 446.731644 -177.62728)
		(end 446.731644 -166.332408)
		(width 0.10668)
		(layer "B.Cu")
		(net "FM_PVDDCR_CPU1_P0_EN")
	)
	(segment
		(start 194.497706 -91.900248)
		(end 193.553334 -90.955876)
		(width 0.10668)
		(layer "B.Cu")
		(net "FM_PVDDCR_CPU1_P0_EN")
	)
	(segment
		(start 195.149216 -95.087948)
		(end 195.149216 -93.24975)
		(width 0.10668)
		(layer "B.Cu")
		(net "FM_PVDDCR_CPU1_P0_EN")
	)
	(segment
		(start 195.149216 -93.24975)
		(end 194.497706 -92.59824)
		(width 0.10668)
		(layer "B.Cu")
		(net "FM_PVDDCR_CPU1_P0_EN")
	)
	(segment
		(start 414.037526 -329.233022)
		(end 416.461448 -326.8091)
		(width 0.10668)
		(layer "B.Cu")
		(net "FM_PVDDCR_CPU1_P0_EN")
	)
	(segment
		(start 190.385954 -90.955876)
		(end 188.378338 -92.963492)
		(width 0.10668)
		(layer "B.Cu")
		(net "FM_PVDDCR_CPU1_P0_EN")
	)
	(segment
		(start 433.69611 -147.862798)
		(end 415.716974 -129.883662)
		(width 0.10668)
		(layer "B.Cu")
		(net "FM_PVDDCR_CPU1_P0_EN")
	)
	(segment
		(start 433.69611 -156.130244)
		(end 433.69611 -147.862798)
		(width 0.10668)
		(layer "B.Cu")
		(net "FM_PVDDCR_CPU1_P0_EN")
	)
	(segment
		(start 330.439014 -363.890814)
		(end 394.764006 -363.890814)
		(width 0.10668)
		(layer "B.Cu")
		(net "FM_PVDDCR_CPU1_P0_EN")
	)
	(segment
		(start 454.025508 -326.84847)
		(end 457.69403 -323.179948)
		(width 0.10668)
		(layer "B.Cu")
		(net "FM_PVDDCR_CPU1_P0_EN")
	)
	(segment
		(start 394.734288 -135.356346)
		(end 392.828272 -135.356346)
		(width 0.10668)
		(layer "B.Cu")
		(net "FM_PVDDCR_CPU1_P0_EN")
	)
	(segment
		(start 188.378338 -99.61499)
		(end 188.658246 -99.894898)
		(width 0.10668)
		(layer "B.Cu")
		(net "FM_PVDDCR_CPU1_P0_EN")
	)
	(segment
		(start 415.716974 -129.883662)
		(end 400.206972 -129.883662)
		(width 0.10668)
		(layer "B.Cu")
		(net "FM_PVDDCR_CPU1_P0_EN")
	)
	(segment
		(start 446.731644 -166.332408)
		(end 442.989716 -162.59048)
		(width 0.10668)
		(layer "B.Cu")
		(net "FM_PVDDCR_CPU1_P0_EN")
	)
	(segment
		(start 392.828272 -135.356346)
		(end 385.047744 -127.575818)
		(width 0.10668)
		(layer "B.Cu")
		(net "FM_PVDDCR_CPU1_P0_EN")
	)
	(segment
		(start 400.206972 -129.883662)
		(end 394.734288 -135.356346)
		(width 0.10668)
		(layer "B.Cu")
		(net "FM_PVDDCR_CPU1_P0_EN")
	)
	(segment
		(start 302.514 -362.1786)
		(end 303.53635 -362.1786)
		(width 0.10668)
		(layer "B.Cu")
		(net "FM_PVDDCR_CPU1_P0_EN")
	)
	(segment
		(start 303.53635 -362.1786)
		(end 304.01895 -361.696)
		(width 0.10668)
		(layer "B.Cu")
		(net "FM_PVDDCR_CPU1_P0_EN")
	)
	(segment
		(start 401.014438 -357.640382)
		(end 406.809702 -357.640382)
		(width 0.10668)
		(layer "B.Cu")
		(net "FM_PVDDCR_CPU1_P0_EN")
	)
	(segment
		(start 416.461448 -326.8091)
		(end 453.306434 -326.8091)
		(width 0.10668)
		(layer "B.Cu")
		(net "FM_PVDDCR_CPU1_P0_EN")
	)
	(segment
		(start 414.037526 -336.60207)
		(end 414.037526 -329.233022)
		(width 0.10668)
		(layer "B.Cu")
		(net "FM_PVDDCR_CPU1_P0_EN")
	)
	(segment
		(start 188.658246 -99.894898)
		(end 188.849 -99.894898)
		(width 0.10668)
		(layer "B.Cu")
		(net "FM_PVDDCR_CPU1_P0_EN")
	)
	(segment
		(start 194.497706 -92.59824)
		(end 194.497706 -91.900248)
		(width 0.10668)
		(layer "B.Cu")
		(net "FM_PVDDCR_CPU1_P0_EN")
	)
	(segment
		(start 407.444194 -357.00589)
		(end 407.444194 -343.195402)
		(width 0.10668)
		(layer "B.Cu")
		(net "FM_PVDDCR_CPU1_P0_EN")
	)
	(segment
		(start 453.306434 -326.8091)
		(end 453.345804 -326.84847)
		(width 0.10668)
		(layer "B.Cu")
		(net "FM_PVDDCR_CPU1_P0_EN")
	)
	(segment
		(start 193.553334 -90.955876)
		(end 190.385954 -90.955876)
		(width 0.10668)
		(layer "B.Cu")
		(net "FM_PVDDCR_CPU1_P0_EN")
	)
	(segment
		(start 385.047744 -127.575818)
		(end 385.047744 -123.040648)
		(width 0.10668)
		(layer "B.Cu")
		(net "FM_PVDDCR_CPU1_P0_EN")
	)
	(segment
		(start 453.345804 -326.84847)
		(end 454.025508 -326.84847)
		(width 0.10668)
		(layer "B.Cu")
		(net "FM_PVDDCR_CPU1_P0_EN")
	)
	(segment
		(start 457.69403 -323.179948)
		(end 457.69403 -188.589666)
		(width 0.10668)
		(layer "B.Cu")
		(net "FM_PVDDCR_CPU1_P0_EN")
	)
	(segment
		(start 329.184 -362.6358)
		(end 330.439014 -363.890814)
		(width 0.10668)
		(layer "B.Cu")
		(net "FM_PVDDCR_CPU1_P0_EN")
	)
	(segment
		(start 406.809702 -357.640382)
		(end 407.444194 -357.00589)
		(width 0.10668)
		(layer "B.Cu")
		(net "FM_PVDDCR_CPU1_P0_EN")
	)
	(segment
		(start 394.764006 -363.890814)
		(end 401.014438 -357.640382)
		(width 0.10668)
		(layer "B.Cu")
		(net "FM_PVDDCR_CPU1_P0_EN")
	)
	(segment
		(start 457.69403 -188.589666)
		(end 446.731644 -177.62728)
		(width 0.10668)
		(layer "B.Cu")
		(net "FM_PVDDCR_CPU1_P0_EN")
	)
	(segment
		(start 257.422904 -99.299776)
		(end 260.772148 -95.950532)
		(width 0.11684)
		(layer "In6.Cu")
		(net "FM_PVDDCR_CPU1_P0_EN")
	)
	(segment
		(start 260.772148 -95.950532)
		(end 273.462496 -95.950532)
		(width 0.11684)
		(layer "In6.Cu")
		(net "FM_PVDDCR_CPU1_P0_EN")
	)
	(segment
		(start 278.985218 -97.464626)
		(end 281.14752 -99.626928)
		(width 0.11684)
		(layer "In6.Cu")
		(net "FM_PVDDCR_CPU1_P0_EN")
	)
	(segment
		(start 196.016626 -95.087948)
		(end 200.828656 -99.899978)
		(width 0.11684)
		(layer "In6.Cu")
		(net "FM_PVDDCR_CPU1_P0_EN")
	)
	(segment
		(start 211.820252 -100.33762)
		(end 212.124798 -100.033074)
		(width 0.11684)
		(layer "In6.Cu")
		(net "FM_PVDDCR_CPU1_P0_EN")
	)
	(segment
		(start 210.955382 -99.899978)
		(end 211.393024 -100.33762)
		(width 0.11684)
		(layer "In6.Cu")
		(net "FM_PVDDCR_CPU1_P0_EN")
	)
	(segment
		(start 221.641162 -100.320602)
		(end 251.904246 -100.320602)
		(width 0.11684)
		(layer "In6.Cu")
		(net "FM_PVDDCR_CPU1_P0_EN")
	)
	(segment
		(start 385.047744 -119.751856)
		(end 385.047744 -123.040648)
		(width 0.11684)
		(layer "In6.Cu")
		(net "FM_PVDDCR_CPU1_P0_EN")
	)
	(segment
		(start 281.14752 -99.626928)
		(end 313.423808 -99.626928)
		(width 0.11684)
		(layer "In6.Cu")
		(net "FM_PVDDCR_CPU1_P0_EN")
	)
	(segment
		(start 273.462496 -95.950532)
		(end 274.97659 -97.464626)
		(width 0.11684)
		(layer "In6.Cu")
		(net "FM_PVDDCR_CPU1_P0_EN")
	)
	(segment
		(start 274.97659 -97.464626)
		(end 278.985218 -97.464626)
		(width 0.11684)
		(layer "In6.Cu")
		(net "FM_PVDDCR_CPU1_P0_EN")
	)
	(segment
		(start 200.828656 -99.899978)
		(end 210.955382 -99.899978)
		(width 0.11684)
		(layer "In6.Cu")
		(net "FM_PVDDCR_CPU1_P0_EN")
	)
	(segment
		(start 251.904246 -100.320602)
		(end 252.925072 -99.299776)
		(width 0.11684)
		(layer "In6.Cu")
		(net "FM_PVDDCR_CPU1_P0_EN")
	)
	(segment
		(start 195.149216 -95.087948)
		(end 196.016626 -95.087948)
		(width 0.11684)
		(layer "In6.Cu")
		(net "FM_PVDDCR_CPU1_P0_EN")
	)
	(segment
		(start 211.393024 -100.33762)
		(end 211.820252 -100.33762)
		(width 0.11684)
		(layer "In6.Cu")
		(net "FM_PVDDCR_CPU1_P0_EN")
	)
	(segment
		(start 214.291418 -100.033074)
		(end 214.825834 -99.498658)
		(width 0.11684)
		(layer "In6.Cu")
		(net "FM_PVDDCR_CPU1_P0_EN")
	)
	(segment
		(start 214.825834 -99.498658)
		(end 220.819218 -99.498658)
		(width 0.11684)
		(layer "In6.Cu")
		(net "FM_PVDDCR_CPU1_P0_EN")
	)
	(segment
		(start 321.041776 -107.244896)
		(end 322.600066 -107.244896)
		(width 0.11684)
		(layer "In6.Cu")
		(net "FM_PVDDCR_CPU1_P0_EN")
	)
	(segment
		(start 212.124798 -100.033074)
		(end 214.291418 -100.033074)
		(width 0.11684)
		(layer "In6.Cu")
		(net "FM_PVDDCR_CPU1_P0_EN")
	)
	(segment
		(start 322.600066 -107.244896)
		(end 324.688962 -109.333792)
		(width 0.11684)
		(layer "In6.Cu")
		(net "FM_PVDDCR_CPU1_P0_EN")
	)
	(segment
		(start 220.819218 -99.498658)
		(end 221.641162 -100.320602)
		(width 0.11684)
		(layer "In6.Cu")
		(net "FM_PVDDCR_CPU1_P0_EN")
	)
	(segment
		(start 374.62968 -109.333792)
		(end 385.047744 -119.751856)
		(width 0.11684)
		(layer "In6.Cu")
		(net "FM_PVDDCR_CPU1_P0_EN")
	)
	(segment
		(start 313.423808 -99.626928)
		(end 321.041776 -107.244896)
		(width 0.11684)
		(layer "In6.Cu")
		(net "FM_PVDDCR_CPU1_P0_EN")
	)
	(segment
		(start 324.688962 -109.333792)
		(end 374.62968 -109.333792)
		(width 0.11684)
		(layer "In6.Cu")
		(net "FM_PVDDCR_CPU1_P0_EN")
	)
	(segment
		(start 252.925072 -99.299776)
		(end 257.422904 -99.299776)
		(width 0.11684)
		(layer "In6.Cu")
		(net "FM_PVDDCR_CPU1_P0_EN")
	)
	(segment
		(start 311.860438 -363.905038)
		(end 307.110638 -363.905038)
		(width 0.11684)
		(layer "In13.Cu")
		(net "FM_PVDDCR_CPU1_P0_EN")
	)
	(segment
		(start 328.573638 -362.025438)
		(end 323.901562 -362.025438)
		(width 0.11684)
		(layer "In13.Cu")
		(net "FM_PVDDCR_CPU1_P0_EN")
	)
	(segment
		(start 323.901562 -362.025438)
		(end 320.598038 -365.328962)
		(width 0.11684)
		(layer "In13.Cu")
		(net "FM_PVDDCR_CPU1_P0_EN")
	)
	(segment
		(start 302.6918 -362.3564)
		(end 302.514 -362.1786)
		(width 0.11684)
		(layer "In13.Cu")
		(net "FM_PVDDCR_CPU1_P0_EN")
	)
	(segment
		(start 312.114438 -364.159038)
		(end 311.860438 -363.905038)
		(width 0.11684)
		(layer "In13.Cu")
		(net "FM_PVDDCR_CPU1_P0_EN")
	)
	(segment
		(start 329.184 -362.6358)
		(end 328.573638 -362.025438)
		(width 0.11684)
		(layer "In13.Cu")
		(net "FM_PVDDCR_CPU1_P0_EN")
	)
	(segment
		(start 316.687962 -365.328962)
		(end 315.518038 -364.159038)
		(width 0.11684)
		(layer "In13.Cu")
		(net "FM_PVDDCR_CPU1_P0_EN")
	)
	(segment
		(start 320.598038 -365.328962)
		(end 316.687962 -365.328962)
		(width 0.11684)
		(layer "In13.Cu")
		(net "FM_PVDDCR_CPU1_P0_EN")
	)
	(segment
		(start 307.110638 -363.905038)
		(end 306.440332 -363.234732)
		(width 0.11684)
		(layer "In13.Cu")
		(net "FM_PVDDCR_CPU1_P0_EN")
	)
	(segment
		(start 305.135788 -363.234732)
		(end 304.257456 -362.3564)
		(width 0.11684)
		(layer "In13.Cu")
		(net "FM_PVDDCR_CPU1_P0_EN")
	)
	(segment
		(start 306.440332 -363.234732)
		(end 305.135788 -363.234732)
		(width 0.11684)
		(layer "In13.Cu")
		(net "FM_PVDDCR_CPU1_P0_EN")
	)
	(segment
		(start 315.518038 -364.159038)
		(end 312.114438 -364.159038)
		(width 0.11684)
		(layer "In13.Cu")
		(net "FM_PVDDCR_CPU1_P0_EN")
	)
	(segment
		(start 304.257456 -362.3564)
		(end 302.6918 -362.3564)
		(width 0.11684)
		(layer "In13.Cu")
		(net "FM_PVDDCR_CPU1_P0_EN")
	)
	(segment
		(start 191.522096 -109.852968)
		(end 191.911986 -109.463078)
		(width 0.10668)
		(layer "F.Cu")
		(net "FM_PVDDCR_CPU0_P1_R_EN")
	)
	(segment
		(start 200.539858 -107.529376)
		(end 199.978518 -107.529376)
		(width 0.10668)
		(layer "F.Cu")
		(net "FM_PVDDCR_CPU0_P1_R_EN")
	)
	(segment
		(start 199.752458 -107.303316)
		(end 199.07758 -107.303316)
		(width 0.10668)
		(layer "F.Cu")
		(net "FM_PVDDCR_CPU0_P1_R_EN")
	)
	(segment
		(start 199.978518 -107.529376)
		(end 199.752458 -107.303316)
		(width 0.10668)
		(layer "F.Cu")
		(net "FM_PVDDCR_CPU0_P1_R_EN")
	)
	(via
		(at 199.07758 -107.303316)
		(size 0.508)
		(drill 0.254)
		(layers "F.Cu" "B.Cu")
		(net "FM_PVDDCR_CPU0_P1_R_EN")
	)
	(via
		(at 191.911986 -109.463078)
		(size 0.4572)
		(drill 0.254)
		(layers "F.Cu" "B.Cu")
		(net "FM_PVDDCR_CPU0_P1_R_EN")
	)
	(segment
		(start 199.032876 -107.303316)
		(end 198.78929 -107.05973)
		(width 0.11684)
		(layer "In4.Cu")
		(net "FM_PVDDCR_CPU0_P1_R_EN")
	)
	(segment
		(start 192.321688 -109.053376)
		(end 191.911986 -109.463078)
		(width 0.11684)
		(layer "In4.Cu")
		(net "FM_PVDDCR_CPU0_P1_R_EN")
	)
	(segment
		(start 198.78929 -107.05973)
		(end 195.46189 -107.05973)
		(width 0.11684)
		(layer "In4.Cu")
		(net "FM_PVDDCR_CPU0_P1_R_EN")
	)
	(segment
		(start 195.46189 -107.05973)
		(end 195.114164 -107.407456)
		(width 0.11684)
		(layer "In4.Cu")
		(net "FM_PVDDCR_CPU0_P1_R_EN")
	)
	(segment
		(start 194.47129 -109.053376)
		(end 192.321688 -109.053376)
		(width 0.11684)
		(layer "In4.Cu")
		(net "FM_PVDDCR_CPU0_P1_R_EN")
	)
	(segment
		(start 195.114164 -108.410502)
		(end 194.47129 -109.053376)
		(width 0.11684)
		(layer "In4.Cu")
		(net "FM_PVDDCR_CPU0_P1_R_EN")
	)
	(segment
		(start 195.114164 -107.407456)
		(end 195.114164 -108.410502)
		(width 0.11684)
		(layer "In4.Cu")
		(net "FM_PVDDCR_CPU0_P1_R_EN")
	)
	(segment
		(start 199.07758 -107.303316)
		(end 199.032876 -107.303316)
		(width 0.11684)
		(layer "In4.Cu")
		(net "FM_PVDDCR_CPU0_P1_R_EN")
	)
	(segment
		(start 181.521608 -105.685844)
		(end 181.521608 -107.052364)
		(width 0.10668)
		(layer "F.Cu")
		(net "FM_PVDDCR_CPU0_P1_OCP_N")
	)
	(segment
		(start 182.753 -103.139748)
		(end 182.753 -104.454452)
		(width 0.10668)
		(layer "F.Cu")
		(net "FM_PVDDCR_CPU0_P1_OCP_N")
	)
	(segment
		(start 182.753 -100.694998)
		(end 182.753 -103.139748)
		(width 0.10668)
		(layer "F.Cu")
		(net "FM_PVDDCR_CPU0_P1_OCP_N")
	)
	(segment
		(start 182.753 -104.454452)
		(end 181.521608 -105.685844)
		(width 0.10668)
		(layer "F.Cu")
		(net "FM_PVDDCR_CPU0_P1_OCP_N")
	)
	(segment
		(start 181.521608 -107.052364)
		(end 181.922166 -107.452922)
		(width 0.10668)
		(layer "F.Cu")
		(net "FM_PVDDCR_CPU0_P1_OCP_N")
	)
	(via
		(at 182.753 -103.139748)
		(size 0.762)
		(drill 0.381)
		(layers "F.Cu" "B.Cu")
		(net "FM_PVDDCR_CPU0_P1_OCP_N")
	)
	(segment
		(start 181.737 -100.694998)
		(end 181.737 -101.950012)
		(width 0.10668)
		(layer "F.Cu")
		(net "FM_PVDDCR_CPU0_P0_OCP_N")
	)
	(segment
		(start 181.737 -101.950012)
		(end 181.737 -104.793034)
		(width 0.10668)
		(layer "F.Cu")
		(net "FM_PVDDCR_CPU0_P0_OCP_N")
	)
	(segment
		(start 181.122066 -105.407968)
		(end 181.122066 -106.652822)
		(width 0.10668)
		(layer "F.Cu")
		(net "FM_PVDDCR_CPU0_P0_OCP_N")
	)
	(segment
		(start 181.737 -104.793034)
		(end 181.122066 -105.407968)
		(width 0.10668)
		(layer "F.Cu")
		(net "FM_PVDDCR_CPU0_P0_OCP_N")
	)
	(via
		(at 181.737 -101.950012)
		(size 0.762)
		(drill 0.381)
		(layers "F.Cu" "B.Cu")
		(net "FM_PVDDCR_CPU0_P0_OCP_N")
	)
	(segment
		(start 190.721996 -113.05286)
		(end 191.111886 -112.66297)
		(width 0.10668)
		(layer "F.Cu")
		(net "FM_PVDD33_S5_EN")
	)
	(via
		(at 197.01637 -111.52505)
		(size 0.6604)
		(drill 0.3302)
		(layers "F.Cu" "B.Cu")
		(net "FM_PVDD33_S5_EN")
	)
	(via
		(at 191.111886 -112.66297)
		(size 0.4572)
		(drill 0.254)
		(layers "F.Cu" "B.Cu")
		(net "FM_PVDD33_S5_EN")
	)
	(segment
		(start 197.54469 -111.873284)
		(end 198.037958 -111.380016)
		(width 0.10668)
		(layer "B.Cu")
		(net "FM_PVDD33_S5_EN")
	)
	(segment
		(start 197.364604 -111.873284)
		(end 197.54469 -111.873284)
		(width 0.10668)
		(layer "B.Cu")
		(net "FM_PVDD33_S5_EN")
	)
	(segment
		(start 196.6341 -111.41964)
		(end 196.91096 -111.41964)
		(width 0.10668)
		(layer "B.Cu")
		(net "FM_PVDD33_S5_EN")
	)
	(segment
		(start 197.01637 -111.52505)
		(end 197.364604 -111.873284)
		(width 0.10668)
		(layer "B.Cu")
		(net "FM_PVDD33_S5_EN")
	)
	(segment
		(start 191.111886 -112.66297)
		(end 191.508126 -113.05921)
		(width 0.10668)
		(layer "B.Cu")
		(net "FM_PVDD33_S5_EN")
	)
	(segment
		(start 196.190108 -111.863632)
		(end 196.6341 -111.41964)
		(width 0.10668)
		(layer "B.Cu")
		(net "FM_PVDD33_S5_EN")
	)
	(segment
		(start 194.606926 -111.863632)
		(end 196.190108 -111.863632)
		(width 0.10668)
		(layer "B.Cu")
		(net "FM_PVDD33_S5_EN")
	)
	(segment
		(start 196.91096 -111.41964)
		(end 197.01637 -111.52505)
		(width 0.10668)
		(layer "B.Cu")
		(net "FM_PVDD33_S5_EN")
	)
	(segment
		(start 193.411348 -113.05921)
		(end 194.606926 -111.863632)
		(width 0.10668)
		(layer "B.Cu")
		(net "FM_PVDD33_S5_EN")
	)
	(segment
		(start 191.508126 -113.05921)
		(end 193.411348 -113.05921)
		(width 0.10668)
		(layer "B.Cu")
		(net "FM_PVDD33_S5_EN")
	)
	(segment
		(start 194.59956 -111.857536)
		(end 195.148454 -111.308642)
		(width 0.10668)
		(layer "F.Cu")
		(net "FM_PVDD18_S5_P0_EN")
	)
	(segment
		(start 193.122042 -112.25276)
		(end 193.517266 -111.857536)
		(width 0.10668)
		(layer "F.Cu")
		(net "FM_PVDD18_S5_P0_EN")
	)
	(segment
		(start 193.517266 -111.857536)
		(end 194.59956 -111.857536)
		(width 0.10668)
		(layer "F.Cu")
		(net "FM_PVDD18_S5_P0_EN")
	)
	(segment
		(start 195.416424 -111.040672)
		(end 196.406262 -111.040672)
		(width 0.10668)
		(layer "F.Cu")
		(net "FM_PVDD18_S5_P0_EN")
	)
	(segment
		(start 195.148454 -111.308642)
		(end 195.416424 -111.040672)
		(width 0.10668)
		(layer "F.Cu")
		(net "FM_PVDD18_S5_P0_EN")
	)
	(segment
		(start 196.406262 -111.040672)
		(end 196.869558 -110.577376)
		(width 0.10668)
		(layer "F.Cu")
		(net "FM_PVDD18_S5_P0_EN")
	)
	(via
		(at 195.148454 -111.308642)
		(size 0.508)
		(drill 0.254)
		(layers "F.Cu" "B.Cu")
		(net "FM_PVDD18_S5_P0_EN")
	)
	(segment
		(start 182.722012 -109.052868)
		(end 182.332122 -108.662978)
		(width 0.10668)
		(layer "F.Cu")
		(net "FM_PVDD11_S3_P1_OCP_N")
	)
	(via
		(at 181.026308 -104.6988)
		(size 0.6604)
		(drill 0.3302)
		(layers "F.Cu" "B.Cu")
		(net "FM_PVDD11_S3_P1_OCP_N")
	)
	(via
		(at 182.332122 -108.662978)
		(size 0.4572)
		(drill 0.254)
		(layers "F.Cu" "B.Cu")
		(net "FM_PVDD11_S3_P1_OCP_N")
	)
	(segment
		(start 181.026308 -104.948228)
		(end 181.488842 -105.410762)
		(width 0.10668)
		(layer "B.Cu")
		(net "FM_PVDD11_S3_P1_OCP_N")
	)
	(segment
		(start 181.026308 -101.000306)
		(end 181.026308 -104.6988)
		(width 0.10668)
		(layer "B.Cu")
		(net "FM_PVDD11_S3_P1_OCP_N")
	)
	(segment
		(start 180.721 -100.694998)
		(end 181.026308 -101.000306)
		(width 0.10668)
		(layer "B.Cu")
		(net "FM_PVDD11_S3_P1_OCP_N")
	)
	(segment
		(start 181.488842 -107.24261)
		(end 181.928516 -107.682284)
		(width 0.10668)
		(layer "B.Cu")
		(net "FM_PVDD11_S3_P1_OCP_N")
	)
	(segment
		(start 181.026308 -104.6988)
		(end 181.026308 -104.948228)
		(width 0.10668)
		(layer "B.Cu")
		(net "FM_PVDD11_S3_P1_OCP_N")
	)
	(segment
		(start 181.488842 -105.410762)
		(end 181.488842 -107.24261)
		(width 0.10668)
		(layer "B.Cu")
		(net "FM_PVDD11_S3_P1_OCP_N")
	)
	(segment
		(start 181.928516 -108.259372)
		(end 182.332122 -108.662978)
		(width 0.10668)
		(layer "B.Cu")
		(net "FM_PVDD11_S3_P1_OCP_N")
	)
	(segment
		(start 181.928516 -107.682284)
		(end 181.928516 -108.259372)
		(width 0.10668)
		(layer "B.Cu")
		(net "FM_PVDD11_S3_P1_OCP_N")
	)
	(segment
		(start 196.045582 -109.26318)
		(end 195.577206 -109.26318)
		(width 0.10668)
		(layer "F.Cu")
		(net "FM_PVDD11_S3_P1_EN")
	)
	(segment
		(start 196.763386 -108.545376)
		(end 196.045582 -109.26318)
		(width 0.10668)
		(layer "F.Cu")
		(net "FM_PVDD11_S3_P1_EN")
	)
	(segment
		(start 195.577206 -109.26318)
		(end 195.490592 -109.349794)
		(width 0.10668)
		(layer "F.Cu")
		(net "FM_PVDD11_S3_P1_EN")
	)
	(segment
		(start 196.869558 -108.545376)
		(end 196.763386 -108.545376)
		(width 0.10668)
		(layer "F.Cu")
		(net "FM_PVDD11_S3_P1_EN")
	)
	(segment
		(start 193.51752 -111.057436)
		(end 193.122042 -111.452914)
		(width 0.10668)
		(layer "F.Cu")
		(net "FM_PVDD11_S3_P1_EN")
	)
	(segment
		(start 195.32727 -109.494574)
		(end 195.32727 -109.813852)
		(width 0.10668)
		(layer "F.Cu")
		(net "FM_PVDD11_S3_P1_EN")
	)
	(segment
		(start 195.32727 -109.813852)
		(end 194.083686 -111.057436)
		(width 0.10668)
		(layer "F.Cu")
		(net "FM_PVDD11_S3_P1_EN")
	)
	(segment
		(start 195.47205 -109.349794)
		(end 195.32727 -109.494574)
		(width 0.10668)
		(layer "F.Cu")
		(net "FM_PVDD11_S3_P1_EN")
	)
	(segment
		(start 194.083686 -111.057436)
		(end 193.51752 -111.057436)
		(width 0.10668)
		(layer "F.Cu")
		(net "FM_PVDD11_S3_P1_EN")
	)
	(segment
		(start 195.490592 -109.349794)
		(end 195.47205 -109.349794)
		(width 0.10668)
		(layer "F.Cu")
		(net "FM_PVDD11_S3_P1_EN")
	)
	(via
		(at 195.490592 -109.349794)
		(size 0.508)
		(drill 0.254)
		(layers "F.Cu" "B.Cu")
		(net "FM_PVDD11_S3_P1_EN")
	)
	(segment
		(start 182.722012 -108.252768)
		(end 182.332122 -107.862878)
		(width 0.10668)
		(layer "F.Cu")
		(net "FM_PVDD11_S3_P0_OCP_N")
	)
	(via
		(at 182.332122 -107.862878)
		(size 0.4572)
		(drill 0.254)
		(layers "F.Cu" "B.Cu")
		(net "FM_PVDD11_S3_P0_OCP_N")
	)
	(via
		(at 181.60746 -103.241348)
		(size 0.6604)
		(drill 0.3302)
		(layers "F.Cu" "B.Cu")
		(net "FM_PVDD11_S3_P0_OCP_N")
	)
	(segment
		(start 182.332122 -107.62361)
		(end 182.332122 -107.862878)
		(width 0.10668)
		(layer "B.Cu")
		(net "FM_PVDD11_S3_P0_OCP_N")
	)
	(segment
		(start 181.709822 -107.00131)
		(end 182.332122 -107.62361)
		(width 0.10668)
		(layer "B.Cu")
		(net "FM_PVDD11_S3_P0_OCP_N")
	)
	(segment
		(start 181.60746 -100.824538)
		(end 181.737 -100.694998)
		(width 0.10668)
		(layer "B.Cu")
		(net "FM_PVDD11_S3_P0_OCP_N")
	)
	(segment
		(start 181.709822 -103.34371)
		(end 181.709822 -107.00131)
		(width 0.10668)
		(layer "B.Cu")
		(net "FM_PVDD11_S3_P0_OCP_N")
	)
	(segment
		(start 181.60746 -103.241348)
		(end 181.60746 -100.824538)
		(width 0.10668)
		(layer "B.Cu")
		(net "FM_PVDD11_S3_P0_OCP_N")
	)
	(segment
		(start 181.60746 -103.241348)
		(end 181.709822 -103.34371)
		(width 0.10668)
		(layer "B.Cu")
		(net "FM_PVDD11_S3_P0_OCP_N")
	)
	(segment
		(start 200.539858 -105.497376)
		(end 198.82104 -105.497376)
		(width 0.10668)
		(layer "F.Cu")
		(net "FM_PVDD11_S3_P0_EN")
	)
	(segment
		(start 191.522096 -109.052868)
		(end 191.911986 -108.662978)
		(width 0.10668)
		(layer "F.Cu")
		(net "FM_PVDD11_S3_P0_EN")
	)
	(segment
		(start 198.82104 -105.497376)
		(end 198.8058 -105.482136)
		(width 0.10668)
		(layer "F.Cu")
		(net "FM_PVDD11_S3_P0_EN")
	)
	(via
		(at 191.911986 -108.662978)
		(size 0.4572)
		(drill 0.254)
		(layers "F.Cu" "B.Cu")
		(net "FM_PVDD11_S3_P0_EN")
	)
	(via
		(at 198.8058 -105.482136)
		(size 0.508)
		(drill 0.254)
		(layers "F.Cu" "B.Cu")
		(net "FM_PVDD11_S3_P0_EN")
	)
	(segment
		(start 192.308988 -108.265976)
		(end 191.911986 -108.662978)
		(width 0.11684)
		(layer "In4.Cu")
		(net "FM_PVDD11_S3_P0_EN")
	)
	(segment
		(start 194.92214 -106.32948)
		(end 194.484244 -106.767376)
		(width 0.11684)
		(layer "In4.Cu")
		(net "FM_PVDD11_S3_P0_EN")
	)
	(segment
		(start 193.104008 -108.037376)
		(end 192.875408 -108.265976)
		(width 0.11684)
		(layer "In4.Cu")
		(net "FM_PVDD11_S3_P0_EN")
	)
	(segment
		(start 198.12 -105.482136)
		(end 197.272656 -106.32948)
		(width 0.11684)
		(layer "In4.Cu")
		(net "FM_PVDD11_S3_P0_EN")
	)
	(segment
		(start 193.104008 -107.707176)
		(end 193.104008 -108.037376)
		(width 0.11684)
		(layer "In4.Cu")
		(net "FM_PVDD11_S3_P0_EN")
	)
	(segment
		(start 197.272656 -106.32948)
		(end 194.92214 -106.32948)
		(width 0.11684)
		(layer "In4.Cu")
		(net "FM_PVDD11_S3_P0_EN")
	)
	(segment
		(start 194.043808 -106.767376)
		(end 193.104008 -107.707176)
		(width 0.11684)
		(layer "In4.Cu")
		(net "FM_PVDD11_S3_P0_EN")
	)
	(segment
		(start 192.875408 -108.265976)
		(end 192.308988 -108.265976)
		(width 0.11684)
		(layer "In4.Cu")
		(net "FM_PVDD11_S3_P0_EN")
	)
	(segment
		(start 198.8058 -105.482136)
		(end 198.12 -105.482136)
		(width 0.11684)
		(layer "In4.Cu")
		(net "FM_PVDD11_S3_P0_EN")
	)
	(segment
		(start 194.484244 -106.767376)
		(end 194.043808 -106.767376)
		(width 0.11684)
		(layer "In4.Cu")
		(net "FM_PVDD11_S3_P0_EN")
	)
	(segment
		(start 193.929 -96.503998)
		(end 193.929 -98.262948)
		(width 0.10668)
		(layer "F.Cu")
		(net "FM_PRSNT_CPU1_R_N")
	)
	(segment
		(start 190.721996 -109.852968)
		(end 191.111886 -109.463078)
		(width 0.10668)
		(layer "F.Cu")
		(net "FM_PRSNT_CPU1_R_N")
	)
	(via
		(at 191.111886 -109.463078)
		(size 0.4572)
		(drill 0.254)
		(layers "F.Cu" "B.Cu")
		(net "FM_PRSNT_CPU1_R_N")
	)
	(via
		(at 193.929 -98.262948)
		(size 0.762)
		(drill 0.254)
		(layers "F.Cu" "B.Cu")
		(net "FM_PRSNT_CPU1_R_N")
	)
	(segment
		(start 190.701168 -109.05236)
		(end 190.701168 -106.075988)
		(width 0.11684)
		(layer "In4.Cu")
		(net "FM_PRSNT_CPU1_R_N")
	)
	(segment
		(start 193.39814 -103.783892)
		(end 193.39814 -98.793808)
		(width 0.11684)
		(layer "In4.Cu")
		(net "FM_PRSNT_CPU1_R_N")
	)
	(segment
		(start 192.203578 -104.573578)
		(end 192.608454 -104.573578)
		(width 0.11684)
		(layer "In4.Cu")
		(net "FM_PRSNT_CPU1_R_N")
	)
	(segment
		(start 190.701168 -106.075988)
		(end 192.203578 -104.573578)
		(width 0.11684)
		(layer "In4.Cu")
		(net "FM_PRSNT_CPU1_R_N")
	)
	(segment
		(start 191.111886 -109.463078)
		(end 190.701168 -109.05236)
		(width 0.11684)
		(layer "In4.Cu")
		(net "FM_PRSNT_CPU1_R_N")
	)
	(segment
		(start 193.39814 -98.793808)
		(end 193.929 -98.262948)
		(width 0.11684)
		(layer "In4.Cu")
		(net "FM_PRSNT_CPU1_R_N")
	)
	(segment
		(start 192.608454 -104.573578)
		(end 193.39814 -103.783892)
		(width 0.11684)
		(layer "In4.Cu")
		(net "FM_PRSNT_CPU1_R_N")
	)
	(segment
		(start 193.929 -95.703898)
		(end 194.267582 -95.703898)
		(width 0.10668)
		(layer "F.Cu")
		(net "FM_PRSNT_CPU1_N")
	)
	(segment
		(start 194.641216 -95.330264)
		(end 194.641216 -94.706948)
		(width 0.10668)
		(layer "F.Cu")
		(net "FM_PRSNT_CPU1_N")
	)
	(segment
		(start 431.5714 -33.467548)
		(end 430.5554 -33.467548)
		(width 0.10668)
		(layer "F.Cu")
		(net "FM_PRSNT_CPU1_N")
	)
	(segment
		(start 194.267582 -95.703898)
		(end 194.641216 -95.330264)
		(width 0.10668)
		(layer "F.Cu")
		(net "FM_PRSNT_CPU1_N")
	)
	(via
		(at 196.118226 -84.718398)
		(size 0.508)
		(drill 0.254)
		(layers "F.Cu" "B.Cu")
		(net "FM_PRSNT_CPU1_N")
	)
	(via
		(at 194.641216 -94.706948)
		(size 0.508)
		(drill 0.254)
		(layers "F.Cu" "B.Cu")
		(net "FM_PRSNT_CPU1_N")
	)
	(via
		(at 430.5554 -33.467548)
		(size 0.508)
		(drill 0.254)
		(layers "F.Cu" "B.Cu")
		(net "FM_PRSNT_CPU1_N")
	)
	(segment
		(start 429.085756 -34.07791)
		(end 427.546262 -34.07791)
		(width 0.10668)
		(layer "B.Cu")
		(net "FM_PRSNT_CPU1_N")
	)
	(segment
		(start 430.5554 -33.467548)
		(end 429.387 -33.467548)
		(width 0.10668)
		(layer "B.Cu")
		(net "FM_PRSNT_CPU1_N")
	)
	(segment
		(start 429.387 -33.467548)
		(end 429.387 -33.776666)
		(width 0.10668)
		(layer "B.Cu")
		(net "FM_PRSNT_CPU1_N")
	)
	(segment
		(start 427.546262 -34.07791)
		(end 426.9359 -33.467548)
		(width 0.10668)
		(layer "B.Cu")
		(net "FM_PRSNT_CPU1_N")
	)
	(segment
		(start 429.387 -33.776666)
		(end 429.085756 -34.07791)
		(width 0.10668)
		(layer "B.Cu")
		(net "FM_PRSNT_CPU1_N")
	)
	(segment
		(start 194.641216 -94.706948)
		(end 195.192396 -94.155768)
		(width 0.11684)
		(layer "In4.Cu")
		(net "FM_PRSNT_CPU1_N")
	)
	(segment
		(start 195.192396 -85.803232)
		(end 196.118226 -84.877402)
		(width 0.11684)
		(layer "In4.Cu")
		(net "FM_PRSNT_CPU1_N")
	)
	(segment
		(start 195.192396 -93.114622)
		(end 194.746626 -92.668852)
		(width 0.11684)
		(layer "In4.Cu")
		(net "FM_PRSNT_CPU1_N")
	)
	(segment
		(start 195.192396 -94.155768)
		(end 195.192396 -93.114622)
		(width 0.11684)
		(layer "In4.Cu")
		(net "FM_PRSNT_CPU1_N")
	)
	(segment
		(start 194.746626 -92.088208)
		(end 195.192396 -91.642438)
		(width 0.11684)
		(layer "In4.Cu")
		(net "FM_PRSNT_CPU1_N")
	)
	(segment
		(start 194.746626 -92.668852)
		(end 194.746626 -92.088208)
		(width 0.11684)
		(layer "In4.Cu")
		(net "FM_PRSNT_CPU1_N")
	)
	(segment
		(start 195.192396 -91.642438)
		(end 195.192396 -85.803232)
		(width 0.11684)
		(layer "In4.Cu")
		(net "FM_PRSNT_CPU1_N")
	)
	(segment
		(start 196.118226 -84.877402)
		(end 196.118226 -84.718398)
		(width 0.11684)
		(layer "In4.Cu")
		(net "FM_PRSNT_CPU1_N")
	)
	(segment
		(start 400.04238 -32.951928)
		(end 430.03978 -32.951928)
		(width 0.11684)
		(layer "In6.Cu")
		(net "FM_PRSNT_CPU1_N")
	)
	(segment
		(start 259.588762 -81.688686)
		(end 269.358872 -71.918576)
		(width 0.11684)
		(layer "In6.Cu")
		(net "FM_PRSNT_CPU1_N")
	)
	(segment
		(start 278.511254 -67.723258)
		(end 278.511254 -64.70523)
		(width 0.11684)
		(layer "In6.Cu")
		(net "FM_PRSNT_CPU1_N")
	)
	(segment
		(start 274.315936 -71.918576)
		(end 278.511254 -67.723258)
		(width 0.11684)
		(layer "In6.Cu")
		(net "FM_PRSNT_CPU1_N")
	)
	(segment
		(start 293.674038 -55.34914)
		(end 295.09212 -53.931058)
		(width 0.11684)
		(layer "In6.Cu")
		(net "FM_PRSNT_CPU1_N")
	)
	(segment
		(start 306.632864 -52.868068)
		(end 330.417932 -52.868068)
		(width 0.11684)
		(layer "In6.Cu")
		(net "FM_PRSNT_CPU1_N")
	)
	(segment
		(start 249.508264 -81.688686)
		(end 259.588762 -81.688686)
		(width 0.11684)
		(layer "In6.Cu")
		(net "FM_PRSNT_CPU1_N")
	)
	(segment
		(start 305.569874 -53.931058)
		(end 306.632864 -52.868068)
		(width 0.11684)
		(layer "In6.Cu")
		(net "FM_PRSNT_CPU1_N")
	)
	(segment
		(start 197.27164 -85.306408)
		(end 201.895456 -85.306408)
		(width 0.11684)
		(layer "In6.Cu")
		(net "FM_PRSNT_CPU1_N")
	)
	(segment
		(start 241.416586 -89.780364)
		(end 249.508264 -81.688686)
		(width 0.11684)
		(layer "In6.Cu")
		(net "FM_PRSNT_CPU1_N")
	)
	(segment
		(start 287.867344 -55.34914)
		(end 293.674038 -55.34914)
		(width 0.11684)
		(layer "In6.Cu")
		(net "FM_PRSNT_CPU1_N")
	)
	(segment
		(start 211.195666 -89.172796)
		(end 211.803234 -89.780364)
		(width 0.11684)
		(layer "In6.Cu")
		(net "FM_PRSNT_CPU1_N")
	)
	(segment
		(start 269.358872 -71.918576)
		(end 274.315936 -71.918576)
		(width 0.11684)
		(layer "In6.Cu")
		(net "FM_PRSNT_CPU1_N")
	)
	(segment
		(start 295.09212 -53.931058)
		(end 305.569874 -53.931058)
		(width 0.11684)
		(layer "In6.Cu")
		(net "FM_PRSNT_CPU1_N")
	)
	(segment
		(start 430.03978 -32.951928)
		(end 430.5554 -33.467548)
		(width 0.11684)
		(layer "In6.Cu")
		(net "FM_PRSNT_CPU1_N")
	)
	(segment
		(start 201.895456 -85.306408)
		(end 205.761844 -89.172796)
		(width 0.11684)
		(layer "In6.Cu")
		(net "FM_PRSNT_CPU1_N")
	)
	(segment
		(start 211.803234 -89.780364)
		(end 241.416586 -89.780364)
		(width 0.11684)
		(layer "In6.Cu")
		(net "FM_PRSNT_CPU1_N")
	)
	(segment
		(start 330.697332 -53.147468)
		(end 379.84684 -53.147468)
		(width 0.11684)
		(layer "In6.Cu")
		(net "FM_PRSNT_CPU1_N")
	)
	(segment
		(start 379.84684 -53.147468)
		(end 400.04238 -32.951928)
		(width 0.11684)
		(layer "In6.Cu")
		(net "FM_PRSNT_CPU1_N")
	)
	(segment
		(start 278.511254 -64.70523)
		(end 287.867344 -55.34914)
		(width 0.11684)
		(layer "In6.Cu")
		(net "FM_PRSNT_CPU1_N")
	)
	(segment
		(start 196.68363 -84.718398)
		(end 197.27164 -85.306408)
		(width 0.11684)
		(layer "In6.Cu")
		(net "FM_PRSNT_CPU1_N")
	)
	(segment
		(start 196.118226 -84.718398)
		(end 196.68363 -84.718398)
		(width 0.11684)
		(layer "In6.Cu")
		(net "FM_PRSNT_CPU1_N")
	)
	(segment
		(start 205.761844 -89.172796)
		(end 211.195666 -89.172796)
		(width 0.11684)
		(layer "In6.Cu")
		(net "FM_PRSNT_CPU1_N")
	)
	(segment
		(start 330.417932 -52.868068)
		(end 330.697332 -53.147468)
		(width 0.11684)
		(layer "In6.Cu")
		(net "FM_PRSNT_CPU1_N")
	)
	(segment
		(start 191.877442 -105.497376)
		(end 190.721996 -106.652822)
		(width 0.10668)
		(layer "F.Cu")
		(net "FM_PRSNT_CPU0_R_N")
	)
	(segment
		(start 194.2846 -101.355398)
		(end 194.2846 -102.212648)
		(width 0.10668)
		(layer "F.Cu")
		(net "FM_PRSNT_CPU0_R_N")
	)
	(segment
		(start 194.2846 -102.212648)
		(end 193.4464 -103.050848)
		(width 0.10668)
		(layer "F.Cu")
		(net "FM_PRSNT_CPU0_R_N")
	)
	(segment
		(start 193.4464 -103.050848)
		(end 193.4464 -103.13924)
		(width 0.10668)
		(layer "F.Cu")
		(net "FM_PRSNT_CPU0_R_N")
	)
	(segment
		(start 193.4464 -103.13924)
		(end 193.4464 -104.312466)
		(width 0.10668)
		(layer "F.Cu")
		(net "FM_PRSNT_CPU0_R_N")
	)
	(segment
		(start 193.4464 -104.312466)
		(end 192.26149 -105.497376)
		(width 0.10668)
		(layer "F.Cu")
		(net "FM_PRSNT_CPU0_R_N")
	)
	(segment
		(start 194.945 -100.694998)
		(end 194.2846 -101.355398)
		(width 0.10668)
		(layer "F.Cu")
		(net "FM_PRSNT_CPU0_R_N")
	)
	(segment
		(start 192.26149 -105.497376)
		(end 191.877442 -105.497376)
		(width 0.10668)
		(layer "F.Cu")
		(net "FM_PRSNT_CPU0_R_N")
	)
	(via
		(at 193.4464 -103.13924)
		(size 0.762)
		(drill 0.381)
		(layers "F.Cu" "B.Cu")
		(net "FM_PRSNT_CPU0_R_N")
	)
	(segment
		(start 194.945 -99.894898)
		(end 194.945 -99.278948)
		(width 0.10668)
		(layer "F.Cu")
		(net "FM_PRSNT_CPU0_N")
	)
	(segment
		(start 431.5714 -34.737548)
		(end 430.5554 -34.737548)
		(width 0.10668)
		(layer "F.Cu")
		(net "FM_PRSNT_CPU0_N")
	)
	(via
		(at 430.5554 -34.737548)
		(size 0.508)
		(drill 0.254)
		(layers "F.Cu" "B.Cu")
		(net "FM_PRSNT_CPU0_N")
	)
	(via
		(at 194.945 -99.278948)
		(size 0.508)
		(drill 0.254)
		(layers "F.Cu" "B.Cu")
		(net "FM_PRSNT_CPU0_N")
	)
	(via
		(at 195.10502 -85.182202)
		(size 0.508)
		(drill 0.254)
		(layers "F.Cu" "B.Cu")
		(net "FM_PRSNT_CPU0_N")
	)
	(segment
		(start 430.5554 -34.737548)
		(end 429.387 -34.737548)
		(width 0.10668)
		(layer "B.Cu")
		(net "FM_PRSNT_CPU0_N")
	)
	(segment
		(start 429.06061 -35.373056)
		(end 427.571408 -35.373056)
		(width 0.10668)
		(layer "B.Cu")
		(net "FM_PRSNT_CPU0_N")
	)
	(segment
		(start 429.387 -35.046666)
		(end 429.06061 -35.373056)
		(width 0.10668)
		(layer "B.Cu")
		(net "FM_PRSNT_CPU0_N")
	)
	(segment
		(start 429.387 -34.737548)
		(end 429.387 -35.046666)
		(width 0.10668)
		(layer "B.Cu")
		(net "FM_PRSNT_CPU0_N")
	)
	(segment
		(start 427.571408 -35.373056)
		(end 426.9359 -34.737548)
		(width 0.10668)
		(layer "B.Cu")
		(net "FM_PRSNT_CPU0_N")
	)
	(segment
		(start 194.48018 -98.814128)
		(end 194.48018 -96.57334)
		(width 0.11684)
		(layer "In4.Cu")
		(net "FM_PRSNT_CPU0_N")
	)
	(segment
		(start 194.380104 -91.651074)
		(end 194.872356 -91.158822)
		(width 0.11684)
		(layer "In4.Cu")
		(net "FM_PRSNT_CPU0_N")
	)
	(segment
		(start 193.736976 -94.491048)
		(end 194.199256 -94.491048)
		(width 0.11684)
		(layer "In4.Cu")
		(net "FM_PRSNT_CPU0_N")
	)
	(segment
		(start 193.609976 -94.618048)
		(end 193.736976 -94.491048)
		(width 0.11684)
		(layer "In4.Cu")
		(net "FM_PRSNT_CPU0_N")
	)
	(segment
		(start 194.380104 -92.830142)
		(end 194.380104 -91.651074)
		(width 0.11684)
		(layer "In4.Cu")
		(net "FM_PRSNT_CPU0_N")
	)
	(segment
		(start 194.872356 -93.322394)
		(end 194.380104 -92.830142)
		(width 0.11684)
		(layer "In4.Cu")
		(net "FM_PRSNT_CPU0_N")
	)
	(segment
		(start 194.199256 -94.491048)
		(end 194.872356 -93.817948)
		(width 0.11684)
		(layer "In4.Cu")
		(net "FM_PRSNT_CPU0_N")
	)
	(segment
		(start 194.945 -99.278948)
		(end 194.48018 -98.814128)
		(width 0.11684)
		(layer "In4.Cu")
		(net "FM_PRSNT_CPU0_N")
	)
	(segment
		(start 194.48018 -96.57334)
		(end 193.609976 -95.703136)
		(width 0.11684)
		(layer "In4.Cu")
		(net "FM_PRSNT_CPU0_N")
	)
	(segment
		(start 194.872356 -91.158822)
		(end 194.872356 -85.371432)
		(width 0.11684)
		(layer "In4.Cu")
		(net "FM_PRSNT_CPU0_N")
	)
	(segment
		(start 194.872356 -93.817948)
		(end 194.872356 -93.322394)
		(width 0.11684)
		(layer "In4.Cu")
		(net "FM_PRSNT_CPU0_N")
	)
	(segment
		(start 194.872356 -85.371432)
		(end 195.061586 -85.182202)
		(width 0.11684)
		(layer "In4.Cu")
		(net "FM_PRSNT_CPU0_N")
	)
	(segment
		(start 195.061586 -85.182202)
		(end 195.10502 -85.182202)
		(width 0.11684)
		(layer "In4.Cu")
		(net "FM_PRSNT_CPU0_N")
	)
	(segment
		(start 193.609976 -95.703136)
		(end 193.609976 -94.618048)
		(width 0.11684)
		(layer "In4.Cu")
		(net "FM_PRSNT_CPU0_N")
	)
	(segment
		(start 195.10502 -85.182202)
		(end 195.732146 -85.809328)
		(width 0.11684)
		(layer "In6.Cu")
		(net "FM_PRSNT_CPU0_N")
	)
	(segment
		(start 279.354534 -68.072762)
		(end 279.354534 -65.054734)
		(width 0.11684)
		(layer "In6.Cu")
		(net "FM_PRSNT_CPU0_N")
	)
	(segment
		(start 279.354534 -65.054734)
		(end 287.793938 -56.61533)
		(width 0.11684)
		(layer "In6.Cu")
		(net "FM_PRSNT_CPU0_N")
	)
	(segment
		(start 205.41234 -90.016076)
		(end 210.846162 -90.016076)
		(width 0.11684)
		(layer "In6.Cu")
		(net "FM_PRSNT_CPU0_N")
	)
	(segment
		(start 287.793938 -56.61533)
		(end 304.078386 -56.61533)
		(width 0.11684)
		(layer "In6.Cu")
		(net "FM_PRSNT_CPU0_N")
	)
	(segment
		(start 399.965164 -34.221928)
		(end 430.03978 -34.221928)
		(width 0.11684)
		(layer "In6.Cu")
		(net "FM_PRSNT_CPU0_N")
	)
	(segment
		(start 380.196344 -53.990748)
		(end 399.965164 -34.221928)
		(width 0.11684)
		(layer "In6.Cu")
		(net "FM_PRSNT_CPU0_N")
	)
	(segment
		(start 241.798602 -90.623644)
		(end 249.89028 -82.531966)
		(width 0.11684)
		(layer "In6.Cu")
		(net "FM_PRSNT_CPU0_N")
	)
	(segment
		(start 201.545952 -86.149688)
		(end 205.41234 -90.016076)
		(width 0.11684)
		(layer "In6.Cu")
		(net "FM_PRSNT_CPU0_N")
	)
	(segment
		(start 306.982368 -53.711348)
		(end 330.068428 -53.711348)
		(width 0.11684)
		(layer "In6.Cu")
		(net "FM_PRSNT_CPU0_N")
	)
	(segment
		(start 196.922136 -86.149688)
		(end 201.545952 -86.149688)
		(width 0.11684)
		(layer "In6.Cu")
		(net "FM_PRSNT_CPU0_N")
	)
	(segment
		(start 330.068428 -53.711348)
		(end 330.347828 -53.990748)
		(width 0.11684)
		(layer "In6.Cu")
		(net "FM_PRSNT_CPU0_N")
	)
	(segment
		(start 249.89028 -82.531966)
		(end 259.938266 -82.531966)
		(width 0.11684)
		(layer "In6.Cu")
		(net "FM_PRSNT_CPU0_N")
	)
	(segment
		(start 304.078386 -56.61533)
		(end 306.982368 -53.711348)
		(width 0.11684)
		(layer "In6.Cu")
		(net "FM_PRSNT_CPU0_N")
	)
	(segment
		(start 269.708376 -72.761856)
		(end 274.66544 -72.761856)
		(width 0.11684)
		(layer "In6.Cu")
		(net "FM_PRSNT_CPU0_N")
	)
	(segment
		(start 195.732146 -85.809328)
		(end 196.581776 -85.809328)
		(width 0.11684)
		(layer "In6.Cu")
		(net "FM_PRSNT_CPU0_N")
	)
	(segment
		(start 430.03978 -34.221928)
		(end 430.5554 -34.737548)
		(width 0.11684)
		(layer "In6.Cu")
		(net "FM_PRSNT_CPU0_N")
	)
	(segment
		(start 259.938266 -82.531966)
		(end 269.708376 -72.761856)
		(width 0.11684)
		(layer "In6.Cu")
		(net "FM_PRSNT_CPU0_N")
	)
	(segment
		(start 274.66544 -72.761856)
		(end 279.354534 -68.072762)
		(width 0.11684)
		(layer "In6.Cu")
		(net "FM_PRSNT_CPU0_N")
	)
	(segment
		(start 210.846162 -90.016076)
		(end 211.45373 -90.623644)
		(width 0.11684)
		(layer "In6.Cu")
		(net "FM_PRSNT_CPU0_N")
	)
	(segment
		(start 196.581776 -85.809328)
		(end 196.922136 -86.149688)
		(width 0.11684)
		(layer "In6.Cu")
		(net "FM_PRSNT_CPU0_N")
	)
	(segment
		(start 211.45373 -90.623644)
		(end 241.798602 -90.623644)
		(width 0.11684)
		(layer "In6.Cu")
		(net "FM_PRSNT_CPU0_N")
	)
	(segment
		(start 330.347828 -53.990748)
		(end 380.196344 -53.990748)
		(width 0.11684)
		(layer "In6.Cu")
		(net "FM_PRSNT_CPU0_N")
	)
	(segment
		(start 191.522096 -113.85296)
		(end 191.911986 -113.46307)
		(width 0.10668)
		(layer "F.Cu")
		(net "FM_PLD_OCP_SFF_PWR_GOOD_R")
	)
	(via
		(at 191.911986 -113.46307)
		(size 0.4572)
		(drill 0.254)
		(layers "F.Cu" "B.Cu")
		(net "FM_PLD_OCP_SFF_PWR_GOOD_R")
	)
	(via
		(at 193.374772 -114.133376)
		(size 0.6604)
		(drill 0.3302)
		(layers "F.Cu" "B.Cu")
		(net "FM_PLD_OCP_SFF_PWR_GOOD_R")
	)
	(segment
		(start 196.602858 -113.427256)
		(end 196.328538 -113.427256)
		(width 0.10668)
		(layer "B.Cu")
		(net "FM_PLD_OCP_SFF_PWR_GOOD_R")
	)
	(segment
		(start 196.328538 -113.427256)
		(end 195.769992 -113.985802)
		(width 0.10668)
		(layer "B.Cu")
		(net "FM_PLD_OCP_SFF_PWR_GOOD_R")
	)
	(segment
		(start 194.350132 -113.985802)
		(end 194.202558 -114.133376)
		(width 0.10668)
		(layer "B.Cu")
		(net "FM_PLD_OCP_SFF_PWR_GOOD_R")
	)
	(segment
		(start 192.876424 -113.866676)
		(end 192.315592 -113.866676)
		(width 0.10668)
		(layer "B.Cu")
		(net "FM_PLD_OCP_SFF_PWR_GOOD_R")
	)
	(segment
		(start 195.769992 -113.985802)
		(end 194.350132 -113.985802)
		(width 0.10668)
		(layer "B.Cu")
		(net "FM_PLD_OCP_SFF_PWR_GOOD_R")
	)
	(segment
		(start 194.202558 -114.133376)
		(end 193.374772 -114.133376)
		(width 0.10668)
		(layer "B.Cu")
		(net "FM_PLD_OCP_SFF_PWR_GOOD_R")
	)
	(segment
		(start 192.315592 -113.866676)
		(end 191.911986 -113.46307)
		(width 0.10668)
		(layer "B.Cu")
		(net "FM_PLD_OCP_SFF_PWR_GOOD_R")
	)
	(segment
		(start 193.143124 -114.133376)
		(end 192.876424 -113.866676)
		(width 0.10668)
		(layer "B.Cu")
		(net "FM_PLD_OCP_SFF_PWR_GOOD_R")
	)
	(segment
		(start 193.374772 -114.133376)
		(end 193.143124 -114.133376)
		(width 0.10668)
		(layer "B.Cu")
		(net "FM_PLD_OCP_SFF_PWR_GOOD_R")
	)
	(segment
		(start 185.922158 -111.452914)
		(end 186.312048 -111.063024)
		(width 0.10668)
		(layer "F.Cu")
		(net "FM_PLD_OCP_SFF_MAIN_PWR_EN_R")
	)
	(via
		(at 186.312048 -111.063024)
		(size 0.4572)
		(drill 0.254)
		(layers "F.Cu" "B.Cu")
		(net "FM_PLD_OCP_SFF_MAIN_PWR_EN_R")
	)
	(via
		(at 184.186068 -103.241348)
		(size 0.6604)
		(drill 0.3302)
		(layers "F.Cu" "B.Cu")
		(net "FM_PLD_OCP_SFF_MAIN_PWR_EN_R")
	)
	(segment
		(start 184.328562 -109.638592)
		(end 184.328562 -103.383842)
		(width 0.10668)
		(layer "B.Cu")
		(net "FM_PLD_OCP_SFF_MAIN_PWR_EN_R")
	)
	(segment
		(start 183.769 -101.424486)
		(end 183.769 -100.694998)
		(width 0.10668)
		(layer "B.Cu")
		(net "FM_PLD_OCP_SFF_MAIN_PWR_EN_R")
	)
	(segment
		(start 186.312048 -111.063024)
		(end 186.312048 -111.049816)
		(width 0.10668)
		(layer "B.Cu")
		(net "FM_PLD_OCP_SFF_MAIN_PWR_EN_R")
	)
	(segment
		(start 184.328562 -103.383842)
		(end 184.186068 -103.241348)
		(width 0.10668)
		(layer "B.Cu")
		(net "FM_PLD_OCP_SFF_MAIN_PWR_EN_R")
	)
	(segment
		(start 184.549288 -109.859318)
		(end 184.328562 -109.638592)
		(width 0.10668)
		(layer "B.Cu")
		(net "FM_PLD_OCP_SFF_MAIN_PWR_EN_R")
	)
	(segment
		(start 184.1246 -103.17988)
		(end 184.1246 -101.780086)
		(width 0.10668)
		(layer "B.Cu")
		(net "FM_PLD_OCP_SFF_MAIN_PWR_EN_R")
	)
	(segment
		(start 185.12155 -109.859318)
		(end 184.549288 -109.859318)
		(width 0.10668)
		(layer "B.Cu")
		(net "FM_PLD_OCP_SFF_MAIN_PWR_EN_R")
	)
	(segment
		(start 186.312048 -111.049816)
		(end 185.12155 -109.859318)
		(width 0.10668)
		(layer "B.Cu")
		(net "FM_PLD_OCP_SFF_MAIN_PWR_EN_R")
	)
	(segment
		(start 184.186068 -103.241348)
		(end 184.1246 -103.17988)
		(width 0.10668)
		(layer "B.Cu")
		(net "FM_PLD_OCP_SFF_MAIN_PWR_EN_R")
	)
	(segment
		(start 184.1246 -101.780086)
		(end 183.769 -101.424486)
		(width 0.10668)
		(layer "B.Cu")
		(net "FM_PLD_OCP_SFF_MAIN_PWR_EN_R")
	)
	(segment
		(start 185.922158 -110.652814)
		(end 186.312048 -110.262924)
		(width 0.10668)
		(layer "F.Cu")
		(net "FM_PLD_OCP_SFF_AUX_PWR_R_EN")
	)
	(via
		(at 186.312048 -110.262924)
		(size 0.4572)
		(drill 0.254)
		(layers "F.Cu" "B.Cu")
		(net "FM_PLD_OCP_SFF_AUX_PWR_R_EN")
	)
	(via
		(at 185.494168 -104.666796)
		(size 0.6604)
		(drill 0.3302)
		(layers "F.Cu" "B.Cu")
		(net "FM_PLD_OCP_SFF_AUX_PWR_R_EN")
	)
	(segment
		(start 185.494168 -102.889812)
		(end 185.494168 -104.666796)
		(width 0.10668)
		(layer "B.Cu")
		(net "FM_PLD_OCP_SFF_AUX_PWR_R_EN")
	)
	(segment
		(start 185.1914 -101.16566)
		(end 185.1914 -101.39045)
		(width 0.10668)
		(layer "B.Cu")
		(net "FM_PLD_OCP_SFF_AUX_PWR_R_EN")
	)
	(segment
		(start 185.670444 -101.869494)
		(end 185.670444 -102.713536)
		(width 0.10668)
		(layer "B.Cu")
		(net "FM_PLD_OCP_SFF_AUX_PWR_R_EN")
	)
	(segment
		(start 185.801 -100.694998)
		(end 185.662062 -100.694998)
		(width 0.10668)
		(layer "B.Cu")
		(net "FM_PLD_OCP_SFF_AUX_PWR_R_EN")
	)
	(segment
		(start 185.670444 -102.713536)
		(end 185.494168 -102.889812)
		(width 0.10668)
		(layer "B.Cu")
		(net "FM_PLD_OCP_SFF_AUX_PWR_R_EN")
	)
	(segment
		(start 186.160156 -110.262924)
		(end 186.312048 -110.262924)
		(width 0.10668)
		(layer "B.Cu")
		(net "FM_PLD_OCP_SFF_AUX_PWR_R_EN")
	)
	(segment
		(start 185.662062 -100.694998)
		(end 185.1914 -101.16566)
		(width 0.10668)
		(layer "B.Cu")
		(net "FM_PLD_OCP_SFF_AUX_PWR_R_EN")
	)
	(segment
		(start 185.1914 -101.39045)
		(end 185.670444 -101.869494)
		(width 0.10668)
		(layer "B.Cu")
		(net "FM_PLD_OCP_SFF_AUX_PWR_R_EN")
	)
	(segment
		(start 185.494168 -109.596936)
		(end 186.160156 -110.262924)
		(width 0.10668)
		(layer "B.Cu")
		(net "FM_PLD_OCP_SFF_AUX_PWR_R_EN")
	)
	(segment
		(start 185.494168 -104.666796)
		(end 185.494168 -109.596936)
		(width 0.10668)
		(layer "B.Cu")
		(net "FM_PLD_OCP_SFF_AUX_PWR_R_EN")
	)
	(segment
		(start 219.47251 -135.728964)
		(end 219.416884 -135.78459)
		(width 0.10668)
		(layer "F.Cu")
		(net "FM_PLD_CPU1_PRSNT_HDT_N")
	)
	(segment
		(start 219.416884 -135.78459)
		(end 219.416884 -136.43991)
		(width 0.10668)
		(layer "F.Cu")
		(net "FM_PLD_CPU1_PRSNT_HDT_N")
	)
	(segment
		(start 219.416884 -136.43991)
		(end 217.588338 -138.268456)
		(width 0.10668)
		(layer "F.Cu")
		(net "FM_PLD_CPU1_PRSNT_HDT_N")
	)
	(segment
		(start 219.47251 -131.854194)
		(end 219.47251 -135.728964)
		(width 0.10668)
		(layer "F.Cu")
		(net "FM_PLD_CPU1_PRSNT_HDT_N")
	)
	(segment
		(start 235.113322 -156.62148)
		(end 236.571282 -156.62148)
		(width 0.10668)
		(layer "F.Cu")
		(net "FM_PLD_CPU1_PRSNT_HDT_N")
	)
	(segment
		(start 236.58957 -160.322768)
		(end 237.688882 -160.322768)
		(width 0.10668)
		(layer "F.Cu")
		(net "FM_PLD_CPU1_PRSNT_HDT_N")
	)
	(segment
		(start 236.571282 -156.62148)
		(end 236.58957 -156.639768)
		(width 0.10668)
		(layer "F.Cu")
		(net "FM_PLD_CPU1_PRSNT_HDT_N")
	)
	(segment
		(start 217.588338 -138.268456)
		(end 217.588338 -156.663644)
		(width 0.10668)
		(layer "F.Cu")
		(net "FM_PLD_CPU1_PRSNT_HDT_N")
	)
	(via
		(at 235.113322 -156.62148)
		(size 0.508)
		(drill 0.254)
		(layers "F.Cu" "B.Cu")
		(net "FM_PLD_CPU1_PRSNT_HDT_N")
	)
	(via
		(at 237.688882 -160.322768)
		(size 0.508)
		(drill 0.254)
		(layers "F.Cu" "B.Cu")
		(net "FM_PLD_CPU1_PRSNT_HDT_N")
	)
	(via
		(at 217.588338 -156.663644)
		(size 0.508)
		(drill 0.254)
		(layers "F.Cu" "B.Cu")
		(net "FM_PLD_CPU1_PRSNT_HDT_N")
	)
	(segment
		(start 235.123736 -156.631894)
		(end 235.113322 -156.62148)
		(width 0.10668)
		(layer "B.Cu")
		(net "FM_PLD_CPU1_PRSNT_HDT_N")
	)
	(segment
		(start 236.110526 -156.631894)
		(end 235.123736 -156.631894)
		(width 0.10668)
		(layer "B.Cu")
		(net "FM_PLD_CPU1_PRSNT_HDT_N")
	)
	(segment
		(start 237.688882 -160.322768)
		(end 237.688882 -158.21025)
		(width 0.10668)
		(layer "B.Cu")
		(net "FM_PLD_CPU1_PRSNT_HDT_N")
	)
	(segment
		(start 237.688882 -158.21025)
		(end 236.110526 -156.631894)
		(width 0.10668)
		(layer "B.Cu")
		(net "FM_PLD_CPU1_PRSNT_HDT_N")
	)
	(segment
		(start 232.418382 -156.663644)
		(end 233.362754 -157.608016)
		(width 0.11684)
		(layer "In2.Cu")
		(net "FM_PLD_CPU1_PRSNT_HDT_N")
	)
	(segment
		(start 234.126786 -157.608016)
		(end 235.113322 -156.62148)
		(width 0.11684)
		(layer "In2.Cu")
		(net "FM_PLD_CPU1_PRSNT_HDT_N")
	)
	(segment
		(start 233.362754 -157.608016)
		(end 234.126786 -157.608016)
		(width 0.11684)
		(layer "In2.Cu")
		(net "FM_PLD_CPU1_PRSNT_HDT_N")
	)
	(segment
		(start 217.588338 -156.663644)
		(end 232.418382 -156.663644)
		(width 0.11684)
		(layer "In2.Cu")
		(net "FM_PLD_CPU1_PRSNT_HDT_N")
	)
	(segment
		(start 188.322204 -119.452898)
		(end 188.712094 -119.842788)
		(width 0.10668)
		(layer "F.Cu")
		(net "FM_PLD_CPU1_PRSNT_HDT")
	)
	(segment
		(start 192.151 -132.750306)
		(end 192.0494 -132.648706)
		(width 0.10668)
		(layer "F.Cu")
		(net "FM_PLD_CPU1_PRSNT_HDT")
	)
	(segment
		(start 192.0494 -131.5085)
		(end 192.2272 -131.3307)
		(width 0.10668)
		(layer "F.Cu")
		(net "FM_PLD_CPU1_PRSNT_HDT")
	)
	(segment
		(start 192.0494 -132.648706)
		(end 192.0494 -131.5085)
		(width 0.10668)
		(layer "F.Cu")
		(net "FM_PLD_CPU1_PRSNT_HDT")
	)
	(segment
		(start 192.151 -133.168898)
		(end 192.151 -132.750306)
		(width 0.10668)
		(layer "F.Cu")
		(net "FM_PLD_CPU1_PRSNT_HDT")
	)
	(via
		(at 192.2272 -131.3307)
		(size 0.508)
		(drill 0.254)
		(layers "F.Cu" "B.Cu")
		(net "FM_PLD_CPU1_PRSNT_HDT")
	)
	(via
		(at 188.712094 -119.842788)
		(size 0.4572)
		(drill 0.254)
		(layers "F.Cu" "B.Cu")
		(net "FM_PLD_CPU1_PRSNT_HDT")
	)
	(segment
		(start 189.906148 -122.037856)
		(end 189.708028 -121.839736)
		(width 0.11684)
		(layer "In2.Cu")
		(net "FM_PLD_CPU1_PRSNT_HDT")
	)
	(segment
		(start 189.106048 -120.236742)
		(end 188.712094 -119.842788)
		(width 0.11684)
		(layer "In2.Cu")
		(net "FM_PLD_CPU1_PRSNT_HDT")
	)
	(segment
		(start 192.667382 -125.588522)
		(end 191.651636 -124.572776)
		(width 0.11684)
		(layer "In2.Cu")
		(net "FM_PLD_CPU1_PRSNT_HDT")
	)
	(segment
		(start 189.906148 -123.586748)
		(end 189.906148 -122.037856)
		(width 0.11684)
		(layer "In2.Cu")
		(net "FM_PLD_CPU1_PRSNT_HDT")
	)
	(segment
		(start 189.708028 -121.839736)
		(end 189.313312 -121.839736)
		(width 0.11684)
		(layer "In2.Cu")
		(net "FM_PLD_CPU1_PRSNT_HDT")
	)
	(segment
		(start 192.667382 -130.890518)
		(end 192.667382 -125.588522)
		(width 0.11684)
		(layer "In2.Cu")
		(net "FM_PLD_CPU1_PRSNT_HDT")
	)
	(segment
		(start 189.313312 -121.839736)
		(end 189.106048 -121.632472)
		(width 0.11684)
		(layer "In2.Cu")
		(net "FM_PLD_CPU1_PRSNT_HDT")
	)
	(segment
		(start 189.106048 -121.632472)
		(end 189.106048 -120.236742)
		(width 0.11684)
		(layer "In2.Cu")
		(net "FM_PLD_CPU1_PRSNT_HDT")
	)
	(segment
		(start 190.892176 -124.572776)
		(end 189.906148 -123.586748)
		(width 0.11684)
		(layer "In2.Cu")
		(net "FM_PLD_CPU1_PRSNT_HDT")
	)
	(segment
		(start 191.651636 -124.572776)
		(end 190.892176 -124.572776)
		(width 0.11684)
		(layer "In2.Cu")
		(net "FM_PLD_CPU1_PRSNT_HDT")
	)
	(segment
		(start 192.2272 -131.3307)
		(end 192.667382 -130.890518)
		(width 0.11684)
		(layer "In2.Cu")
		(net "FM_PLD_CPU1_PRSNT_HDT")
	)
	(segment
		(start 234.90936 -149.595586)
		(end 235.226606 -149.27834)
		(width 0.10668)
		(layer "F.Cu")
		(net "FM_PLD_CPU0_PRSNT_HDT_N")
	)
	(segment
		(start 236.58957 -152.956768)
		(end 235.326936 -152.956768)
		(width 0.10668)
		(layer "F.Cu")
		(net "FM_PLD_CPU0_PRSNT_HDT_N")
	)
	(segment
		(start 236.584998 -149.27834)
		(end 236.58957 -149.273768)
		(width 0.10668)
		(layer "F.Cu")
		(net "FM_PLD_CPU0_PRSNT_HDT_N")
	)
	(segment
		(start 235.326936 -152.956768)
		(end 234.90936 -152.539192)
		(width 0.10668)
		(layer "F.Cu")
		(net "FM_PLD_CPU0_PRSNT_HDT_N")
	)
	(segment
		(start 235.318046 -144.958562)
		(end 235.318046 -142.359126)
		(width 0.10668)
		(layer "F.Cu")
		(net "FM_PLD_CPU0_PRSNT_HDT_N")
	)
	(segment
		(start 235.318046 -142.359126)
		(end 235.87202 -141.805152)
		(width 0.10668)
		(layer "F.Cu")
		(net "FM_PLD_CPU0_PRSNT_HDT_N")
	)
	(segment
		(start 234.90936 -152.539192)
		(end 234.90936 -149.595586)
		(width 0.10668)
		(layer "F.Cu")
		(net "FM_PLD_CPU0_PRSNT_HDT_N")
	)
	(segment
		(start 235.226606 -149.27834)
		(end 236.584998 -149.27834)
		(width 0.10668)
		(layer "F.Cu")
		(net "FM_PLD_CPU0_PRSNT_HDT_N")
	)
	(segment
		(start 236.58957 -149.273768)
		(end 237.684564 -149.273768)
		(width 0.10668)
		(layer "F.Cu")
		(net "FM_PLD_CPU0_PRSNT_HDT_N")
	)
	(segment
		(start 235.318046 -144.958562)
		(end 235.318046 -146.762724)
		(width 0.10668)
		(layer "F.Cu")
		(net "FM_PLD_CPU0_PRSNT_HDT_N")
	)
	(via
		(at 235.318046 -146.762724)
		(size 0.508)
		(drill 0.254)
		(layers "F.Cu" "B.Cu")
		(net "FM_PLD_CPU0_PRSNT_HDT_N")
	)
	(via
		(at 237.684564 -149.273768)
		(size 0.508)
		(drill 0.254)
		(layers "F.Cu" "B.Cu")
		(net "FM_PLD_CPU0_PRSNT_HDT_N")
	)
	(segment
		(start 237.684564 -149.129242)
		(end 235.318046 -146.762724)
		(width 0.11684)
		(layer "In6.Cu")
		(net "FM_PLD_CPU0_PRSNT_HDT_N")
	)
	(segment
		(start 237.684564 -149.273768)
		(end 237.684564 -149.129242)
		(width 0.11684)
		(layer "In6.Cu")
		(net "FM_PLD_CPU0_PRSNT_HDT_N")
	)
	(segment
		(start 189.92215 -120.252744)
		(end 190.31204 -120.642634)
		(width 0.10668)
		(layer "F.Cu")
		(net "FM_PLD_CPU0_PRSNT_HDT")
	)
	(via
		(at 191.850518 -123.737878)
		(size 0.6604)
		(drill 0.3302)
		(layers "F.Cu" "B.Cu")
		(net "FM_PLD_CPU0_PRSNT_HDT")
	)
	(via
		(at 190.31204 -120.642634)
		(size 0.4572)
		(drill 0.254)
		(layers "F.Cu" "B.Cu")
		(net "FM_PLD_CPU0_PRSNT_HDT")
	)
	(segment
		(start 191.850518 -123.737878)
		(end 191.513968 -123.401328)
		(width 0.10668)
		(layer "B.Cu")
		(net "FM_PLD_CPU0_PRSNT_HDT")
	)
	(segment
		(start 189.9158 -121.613168)
		(end 189.9158 -121.038874)
		(width 0.10668)
		(layer "B.Cu")
		(net "FM_PLD_CPU0_PRSNT_HDT")
	)
	(segment
		(start 191.935862 -125.127512)
		(end 191.935862 -123.823222)
		(width 0.10668)
		(layer "B.Cu")
		(net "FM_PLD_CPU0_PRSNT_HDT")
	)
	(segment
		(start 191.935862 -123.823222)
		(end 191.850518 -123.737878)
		(width 0.10668)
		(layer "B.Cu")
		(net "FM_PLD_CPU0_PRSNT_HDT")
	)
	(segment
		(start 191.292988 -122.639836)
		(end 190.853568 -122.639836)
		(width 0.10668)
		(layer "B.Cu")
		(net "FM_PLD_CPU0_PRSNT_HDT")
	)
	(segment
		(start 191.513968 -123.401328)
		(end 191.513968 -122.860816)
		(width 0.10668)
		(layer "B.Cu")
		(net "FM_PLD_CPU0_PRSNT_HDT")
	)
	(segment
		(start 191.513968 -122.860816)
		(end 191.292988 -122.639836)
		(width 0.10668)
		(layer "B.Cu")
		(net "FM_PLD_CPU0_PRSNT_HDT")
	)
	(segment
		(start 190.141606 -121.838974)
		(end 189.9158 -121.613168)
		(width 0.10668)
		(layer "B.Cu")
		(net "FM_PLD_CPU0_PRSNT_HDT")
	)
	(segment
		(start 190.70828 -122.078496)
		(end 190.468758 -121.838974)
		(width 0.10668)
		(layer "B.Cu")
		(net "FM_PLD_CPU0_PRSNT_HDT")
	)
	(segment
		(start 190.853568 -122.639836)
		(end 190.70828 -122.494548)
		(width 0.10668)
		(layer "B.Cu")
		(net "FM_PLD_CPU0_PRSNT_HDT")
	)
	(segment
		(start 192.189608 -125.381258)
		(end 191.935862 -125.127512)
		(width 0.10668)
		(layer "B.Cu")
		(net "FM_PLD_CPU0_PRSNT_HDT")
	)
	(segment
		(start 189.9158 -121.038874)
		(end 190.31204 -120.642634)
		(width 0.10668)
		(layer "B.Cu")
		(net "FM_PLD_CPU0_PRSNT_HDT")
	)
	(segment
		(start 190.70828 -122.494548)
		(end 190.70828 -122.078496)
		(width 0.10668)
		(layer "B.Cu")
		(net "FM_PLD_CPU0_PRSNT_HDT")
	)
	(segment
		(start 192.189608 -126.433326)
		(end 192.189608 -125.381258)
		(width 0.10668)
		(layer "B.Cu")
		(net "FM_PLD_CPU0_PRSNT_HDT")
	)
	(segment
		(start 190.468758 -121.838974)
		(end 190.141606 -121.838974)
		(width 0.10668)
		(layer "B.Cu")
		(net "FM_PLD_CPU0_PRSNT_HDT")
	)
	(segment
		(start 369.649756 -321.890644)
		(end 369.649756 -322.563998)
		(width 0.10668)
		(layer "F.Cu")
		(net "FM_PASSWORD_CLEAR_R_N")
	)
	(segment
		(start 360.392726 -298.515278)
		(end 360.421428 -298.486576)
		(width 0.10668)
		(layer "F.Cu")
		(net "FM_PASSWORD_CLEAR_R_N")
	)
	(segment
		(start 369.649756 -322.563998)
		(end 369.146836 -323.066918)
		(width 0.10668)
		(layer "F.Cu")
		(net "FM_PASSWORD_CLEAR_R_N")
	)
	(segment
		(start 369.649756 -320.824606)
		(end 360.392726 -311.567576)
		(width 0.10668)
		(layer "F.Cu")
		(net "FM_PASSWORD_CLEAR_R_N")
	)
	(segment
		(start 361.89793 -293.260018)
		(end 362.364782 -293.525956)
		(width 0.10668)
		(layer "F.Cu")
		(net "FM_PASSWORD_CLEAR_R_N")
	)
	(segment
		(start 369.649756 -321.890644)
		(end 369.649756 -320.824606)
		(width 0.10668)
		(layer "F.Cu")
		(net "FM_PASSWORD_CLEAR_R_N")
	)
	(segment
		(start 360.392726 -311.567576)
		(end 360.392726 -298.515278)
		(width 0.10668)
		(layer "F.Cu")
		(net "FM_PASSWORD_CLEAR_R_N")
	)
	(via
		(at 362.364782 -293.525956)
		(size 0.4064)
		(drill 0.2032)
		(layers "F.Cu" "B.Cu")
		(net "FM_PASSWORD_CLEAR_R_N")
	)
	(via
		(at 369.649756 -321.890644)
		(size 0.762)
		(drill 0.381)
		(layers "F.Cu" "B.Cu")
		(net "FM_PASSWORD_CLEAR_R_N")
	)
	(via
		(at 360.421428 -298.486576)
		(size 0.508)
		(drill 0.254)
		(layers "F.Cu" "B.Cu")
		(net "FM_PASSWORD_CLEAR_R_N")
	)
	(segment
		(start 360.421428 -298.486576)
		(end 360.496358 -298.411646)
		(width 0.10668)
		(layer "B.Cu")
		(net "FM_PASSWORD_CLEAR_R_N")
	)
	(segment
		(start 362.079794 -293.525956)
		(end 362.364782 -293.525956)
		(width 0.10668)
		(layer "B.Cu")
		(net "FM_PASSWORD_CLEAR_R_N")
	)
	(segment
		(start 360.496358 -295.109392)
		(end 362.079794 -293.525956)
		(width 0.10668)
		(layer "B.Cu")
		(net "FM_PASSWORD_CLEAR_R_N")
	)
	(segment
		(start 360.496358 -298.411646)
		(end 360.496358 -295.109392)
		(width 0.10668)
		(layer "B.Cu")
		(net "FM_PASSWORD_CLEAR_R_N")
	)
	(segment
		(start 384.525266 -339.245448)
		(end 369.146836 -323.867018)
		(width 0.10668)
		(layer "F.Cu")
		(net "FM_PASSWORD_CLEAR_N")
	)
	(segment
		(start 398.58696 -340.131908)
		(end 397.7005 -339.245448)
		(width 0.10668)
		(layer "F.Cu")
		(net "FM_PASSWORD_CLEAR_N")
	)
	(segment
		(start 405.795734 -346.807536)
		(end 401.013168 -346.807536)
		(width 0.10668)
		(layer "F.Cu")
		(net "FM_PASSWORD_CLEAR_N")
	)
	(segment
		(start 431.5714 -32.197548)
		(end 430.5554 -32.197548)
		(width 0.10668)
		(layer "F.Cu")
		(net "FM_PASSWORD_CLEAR_N")
	)
	(segment
		(start 401.013168 -346.807536)
		(end 398.58696 -344.381328)
		(width 0.10668)
		(layer "F.Cu")
		(net "FM_PASSWORD_CLEAR_N")
	)
	(segment
		(start 398.58696 -344.381328)
		(end 398.58696 -340.131908)
		(width 0.10668)
		(layer "F.Cu")
		(net "FM_PASSWORD_CLEAR_N")
	)
	(segment
		(start 397.7005 -339.245448)
		(end 384.525266 -339.245448)
		(width 0.10668)
		(layer "F.Cu")
		(net "FM_PASSWORD_CLEAR_N")
	)
	(via
		(at 430.5554 -32.197548)
		(size 0.508)
		(drill 0.254)
		(layers "F.Cu" "B.Cu")
		(net "FM_PASSWORD_CLEAR_N")
	)
	(via
		(at 405.795734 -346.807536)
		(size 0.508)
		(drill 0.254)
		(layers "F.Cu" "B.Cu")
		(net "FM_PASSWORD_CLEAR_N")
	)
	(segment
		(start 429.387 -32.197548)
		(end 429.387 -31.181548)
		(width 0.10668)
		(layer "B.Cu")
		(net "FM_PASSWORD_CLEAR_N")
	)
	(segment
		(start 429.387 -32.197548)
		(end 430.5554 -32.197548)
		(width 0.10668)
		(layer "B.Cu")
		(net "FM_PASSWORD_CLEAR_N")
	)
	(segment
		(start 424.99915 -373.003318)
		(end 433.022248 -373.003318)
		(width 0.11684)
		(layer "In4.Cu")
		(net "FM_PASSWORD_CLEAR_N")
	)
	(segment
		(start 443.345824 -371.10543)
		(end 448.142868 -366.308386)
		(width 0.11684)
		(layer "In4.Cu")
		(net "FM_PASSWORD_CLEAR_N")
	)
	(segment
		(start 449.578476 -147.12188)
		(end 440.505596 -138.049)
		(width 0.11684)
		(layer "In4.Cu")
		(net "FM_PASSWORD_CLEAR_N")
	)
	(segment
		(start 458.814932 -186.93384)
		(end 453.75195 -181.870858)
		(width 0.11684)
		(layer "In4.Cu")
		(net "FM_PASSWORD_CLEAR_N")
	)
	(segment
		(start 440.505596 -138.049)
		(end 432.562 -138.049)
		(width 0.11684)
		(layer "In4.Cu")
		(net "FM_PASSWORD_CLEAR_N")
	)
	(segment
		(start 407.687526 -362.878878)
		(end 416.176206 -371.367558)
		(width 0.11684)
		(layer "In4.Cu")
		(net "FM_PASSWORD_CLEAR_N")
	)
	(segment
		(start 424.02252 -53.243734)
		(end 424.02252 -47.56912)
		(width 0.11684)
		(layer "In4.Cu")
		(net "FM_PASSWORD_CLEAR_N")
	)
	(segment
		(start 429.93818 -41.65346)
		(end 429.93818 -32.814768)
		(width 0.11684)
		(layer "In4.Cu")
		(net "FM_PASSWORD_CLEAR_N")
	)
	(segment
		(start 453.75195 -170.534076)
		(end 449.578476 -166.360602)
		(width 0.11684)
		(layer "In4.Cu")
		(net "FM_PASSWORD_CLEAR_N")
	)
	(segment
		(start 449.578476 -166.360602)
		(end 449.578476 -147.12188)
		(width 0.11684)
		(layer "In4.Cu")
		(net "FM_PASSWORD_CLEAR_N")
	)
	(segment
		(start 410.081476 -59.10326)
		(end 415.147252 -54.037484)
		(width 0.11684)
		(layer "In4.Cu")
		(net "FM_PASSWORD_CLEAR_N")
	)
	(segment
		(start 432.562 -138.049)
		(end 412.5087 -117.9957)
		(width 0.11684)
		(layer "In4.Cu")
		(net "FM_PASSWORD_CLEAR_N")
	)
	(segment
		(start 423.22877 -54.037484)
		(end 424.02252 -53.243734)
		(width 0.11684)
		(layer "In4.Cu")
		(net "FM_PASSWORD_CLEAR_N")
	)
	(segment
		(start 416.176206 -371.367558)
		(end 423.36339 -371.367558)
		(width 0.11684)
		(layer "In4.Cu")
		(net "FM_PASSWORD_CLEAR_N")
	)
	(segment
		(start 415.147252 -54.037484)
		(end 423.22877 -54.037484)
		(width 0.11684)
		(layer "In4.Cu")
		(net "FM_PASSWORD_CLEAR_N")
	)
	(segment
		(start 433.022248 -373.003318)
		(end 434.920136 -371.10543)
		(width 0.11684)
		(layer "In4.Cu")
		(net "FM_PASSWORD_CLEAR_N")
	)
	(segment
		(start 448.142868 -334.108806)
		(end 458.814932 -323.436742)
		(width 0.11684)
		(layer "In4.Cu")
		(net "FM_PASSWORD_CLEAR_N")
	)
	(segment
		(start 458.814932 -323.436742)
		(end 458.814932 -186.93384)
		(width 0.11684)
		(layer "In4.Cu")
		(net "FM_PASSWORD_CLEAR_N")
	)
	(segment
		(start 405.795734 -346.807536)
		(end 407.687526 -348.699328)
		(width 0.11684)
		(layer "In4.Cu")
		(net "FM_PASSWORD_CLEAR_N")
	)
	(segment
		(start 423.36339 -371.367558)
		(end 424.99915 -373.003318)
		(width 0.11684)
		(layer "In4.Cu")
		(net "FM_PASSWORD_CLEAR_N")
	)
	(segment
		(start 410.081476 -106.493564)
		(end 410.081476 -59.10326)
		(width 0.11684)
		(layer "In4.Cu")
		(net "FM_PASSWORD_CLEAR_N")
	)
	(segment
		(start 429.93818 -32.814768)
		(end 430.5554 -32.197548)
		(width 0.11684)
		(layer "In4.Cu")
		(net "FM_PASSWORD_CLEAR_N")
	)
	(segment
		(start 424.02252 -47.56912)
		(end 429.93818 -41.65346)
		(width 0.11684)
		(layer "In4.Cu")
		(net "FM_PASSWORD_CLEAR_N")
	)
	(segment
		(start 434.920136 -371.10543)
		(end 443.345824 -371.10543)
		(width 0.11684)
		(layer "In4.Cu")
		(net "FM_PASSWORD_CLEAR_N")
	)
	(segment
		(start 412.5087 -108.920788)
		(end 410.081476 -106.493564)
		(width 0.11684)
		(layer "In4.Cu")
		(net "FM_PASSWORD_CLEAR_N")
	)
	(segment
		(start 412.5087 -117.9957)
		(end 412.5087 -108.920788)
		(width 0.11684)
		(layer "In4.Cu")
		(net "FM_PASSWORD_CLEAR_N")
	)
	(segment
		(start 448.142868 -366.308386)
		(end 448.142868 -334.108806)
		(width 0.11684)
		(layer "In4.Cu")
		(net "FM_PASSWORD_CLEAR_N")
	)
	(segment
		(start 453.75195 -181.870858)
		(end 453.75195 -170.534076)
		(width 0.11684)
		(layer "In4.Cu")
		(net "FM_PASSWORD_CLEAR_N")
	)
	(segment
		(start 407.687526 -348.699328)
		(end 407.687526 -362.878878)
		(width 0.11684)
		(layer "In4.Cu")
		(net "FM_PASSWORD_CLEAR_N")
	)
	(segment
		(start 183.007 -132.20954)
		(end 183.007 -131.45516)
		(width 0.10668)
		(layer "F.Cu")
		(net "FM_P1_PCC1_R_N")
	)
	(segment
		(start 183.522112 -121.852944)
		(end 183.132222 -122.242834)
		(width 0.10668)
		(layer "F.Cu")
		(net "FM_P1_PCC1_R_N")
	)
	(segment
		(start 183.007 -131.45516)
		(end 182.9816 -131.42976)
		(width 0.10668)
		(layer "F.Cu")
		(net "FM_P1_PCC1_R_N")
	)
	(segment
		(start 182.757572 -133.161024)
		(end 182.757572 -132.458968)
		(width 0.10668)
		(layer "F.Cu")
		(net "FM_P1_PCC1_R_N")
	)
	(segment
		(start 182.757572 -132.458968)
		(end 183.007 -132.20954)
		(width 0.10668)
		(layer "F.Cu")
		(net "FM_P1_PCC1_R_N")
	)
	(via
		(at 183.132222 -122.242834)
		(size 0.4572)
		(drill 0.254)
		(layers "F.Cu" "B.Cu")
		(net "FM_P1_PCC1_R_N")
	)
	(via
		(at 182.9816 -131.42976)
		(size 0.762)
		(drill 0.254)
		(layers "F.Cu" "B.Cu")
		(net "FM_P1_PCC1_R_N")
	)
	(segment
		(start 182.738268 -122.840496)
		(end 183.132222 -122.446542)
		(width 0.11684)
		(layer "In2.Cu")
		(net "FM_P1_PCC1_R_N")
	)
	(segment
		(start 182.738268 -126.254256)
		(end 182.738268 -122.840496)
		(width 0.11684)
		(layer "In2.Cu")
		(net "FM_P1_PCC1_R_N")
	)
	(segment
		(start 183.543448 -127.059436)
		(end 182.738268 -126.254256)
		(width 0.11684)
		(layer "In2.Cu")
		(net "FM_P1_PCC1_R_N")
	)
	(segment
		(start 182.9816 -131.42976)
		(end 183.543448 -130.867912)
		(width 0.11684)
		(layer "In2.Cu")
		(net "FM_P1_PCC1_R_N")
	)
	(segment
		(start 183.132222 -122.446542)
		(end 183.132222 -122.242834)
		(width 0.11684)
		(layer "In2.Cu")
		(net "FM_P1_PCC1_R_N")
	)
	(segment
		(start 183.543448 -130.867912)
		(end 183.543448 -127.059436)
		(width 0.11684)
		(layer "In2.Cu")
		(net "FM_P1_PCC1_R_N")
	)
	(segment
		(start 182.839614 -136.449562)
		(end 182.839614 -136.486392)
		(width 0.10668)
		(layer "F.Cu")
		(net "FM_P1_PCC1_N")
	)
	(segment
		(start 182.839614 -136.486392)
		(end 182.876444 -136.486392)
		(width 0.10668)
		(layer "F.Cu")
		(net "FM_P1_PCC1_N")
	)
	(segment
		(start 182.757572 -133.961124)
		(end 182.757572 -134.430008)
		(width 0.10668)
		(layer "F.Cu")
		(net "FM_P1_PCC1_N")
	)
	(segment
		(start 18.95094 -174.31639)
		(end 28.712668 -174.31639)
		(width 0.10668)
		(layer "F.Cu")
		(net "FM_P1_PCC1_N")
	)
	(segment
		(start 183.007 -136.616948)
		(end 183.007 -137.232898)
		(width 0.10668)
		(layer "F.Cu")
		(net "FM_P1_PCC1_N")
	)
	(segment
		(start 133.464808 -131.182364)
		(end 142.05712 -139.774676)
		(width 0.10668)
		(layer "F.Cu")
		(net "FM_P1_PCC1_N")
	)
	(segment
		(start 182.757572 -134.430008)
		(end 182.547006 -134.640574)
		(width 0.10668)
		(layer "F.Cu")
		(net "FM_P1_PCC1_N")
	)
	(segment
		(start 14.669008 -205.23708)
		(end 13.379704 -205.23708)
		(width 0.10668)
		(layer "F.Cu")
		(net "FM_P1_PCC1_N")
	)
	(segment
		(start 182.547006 -134.640574)
		(end 182.547006 -136.156954)
		(width 0.10668)
		(layer "F.Cu")
		(net "FM_P1_PCC1_N")
	)
	(segment
		(start 13.379704 -205.23708)
		(end 9.324594 -201.18197)
		(width 0.10668)
		(layer "F.Cu")
		(net "FM_P1_PCC1_N")
	)
	(segment
		(start 80.58785 -294.070278)
		(end 80.120998 -294.336216)
		(width 0.10668)
		(layer "F.Cu")
		(net "FM_P1_PCC1_N")
	)
	(segment
		(start 182.876444 -136.486392)
		(end 183.007 -136.616948)
		(width 0.10668)
		(layer "F.Cu")
		(net "FM_P1_PCC1_N")
	)
	(segment
		(start 92.926408 -131.182364)
		(end 133.464808 -131.182364)
		(width 0.10668)
		(layer "F.Cu")
		(net "FM_P1_PCC1_N")
	)
	(segment
		(start 9.324594 -201.18197)
		(end 9.324594 -183.942736)
		(width 0.10668)
		(layer "F.Cu")
		(net "FM_P1_PCC1_N")
	)
	(segment
		(start 9.324594 -183.942736)
		(end 18.95094 -174.31639)
		(width 0.10668)
		(layer "F.Cu")
		(net "FM_P1_PCC1_N")
	)
	(segment
		(start 142.05712 -139.774676)
		(end 169.085006 -139.774676)
		(width 0.10668)
		(layer "F.Cu")
		(net "FM_P1_PCC1_N")
	)
	(segment
		(start 182.547006 -136.156954)
		(end 182.839614 -136.449562)
		(width 0.10668)
		(layer "F.Cu")
		(net "FM_P1_PCC1_N")
	)
	(via
		(at 14.669008 -205.23708)
		(size 0.508)
		(drill 0.254)
		(layers "F.Cu" "B.Cu")
		(net "FM_P1_PCC1_N")
	)
	(via
		(at 92.926408 -131.182364)
		(size 0.508)
		(drill 0.254)
		(layers "F.Cu" "B.Cu")
		(net "FM_P1_PCC1_N")
	)
	(via
		(at 169.085006 -139.774676)
		(size 0.508)
		(drill 0.254)
		(layers "F.Cu" "B.Cu")
		(net "FM_P1_PCC1_N")
	)
	(via
		(at 80.120998 -294.336216)
		(size 0.4064)
		(drill 0.2032)
		(layers "F.Cu" "B.Cu")
		(net "FM_P1_PCC1_N")
	)
	(via
		(at 182.839614 -136.486392)
		(size 0.508)
		(drill 0.254)
		(layers "F.Cu" "B.Cu")
		(net "FM_P1_PCC1_N")
	)
	(via
		(at 28.712668 -174.31639)
		(size 0.508)
		(drill 0.254)
		(layers "F.Cu" "B.Cu")
		(net "FM_P1_PCC1_N")
	)
	(segment
		(start 16.345408 -320.134996)
		(end 14.669008 -318.458596)
		(width 0.10668)
		(layer "B.Cu")
		(net "FM_P1_PCC1_N")
	)
	(segment
		(start 60.027566 -315.804296)
		(end 59.119516 -315.804296)
		(width 0.10668)
		(layer "B.Cu")
		(net "FM_P1_PCC1_N")
	)
	(segment
		(start 80.120998 -294.336216)
		(end 80.120998 -295.710864)
		(width 0.10668)
		(layer "B.Cu")
		(net "FM_P1_PCC1_N")
	)
	(segment
		(start 80.120998 -295.710864)
		(end 60.027566 -315.804296)
		(width 0.10668)
		(layer "B.Cu")
		(net "FM_P1_PCC1_N")
	)
	(segment
		(start 54.788816 -320.134996)
		(end 16.345408 -320.134996)
		(width 0.10668)
		(layer "B.Cu")
		(net "FM_P1_PCC1_N")
	)
	(segment
		(start 14.669008 -318.458596)
		(end 14.669008 -205.23708)
		(width 0.10668)
		(layer "B.Cu")
		(net "FM_P1_PCC1_N")
	)
	(segment
		(start 59.119516 -315.804296)
		(end 54.788816 -320.134996)
		(width 0.10668)
		(layer "B.Cu")
		(net "FM_P1_PCC1_N")
	)
	(segment
		(start 182.93588 -136.582658)
		(end 182.839614 -136.486392)
		(width 0.11684)
		(layer "In2.Cu")
		(net "FM_P1_PCC1_N")
	)
	(segment
		(start 182.93588 -136.793224)
		(end 182.93588 -136.582658)
		(width 0.11684)
		(layer "In2.Cu")
		(net "FM_P1_PCC1_N")
	)
	(segment
		(start 179.954428 -139.774676)
		(end 182.93588 -136.793224)
		(width 0.11684)
		(layer "In2.Cu")
		(net "FM_P1_PCC1_N")
	)
	(segment
		(start 169.085006 -139.774676)
		(end 179.954428 -139.774676)
		(width 0.11684)
		(layer "In2.Cu")
		(net "FM_P1_PCC1_N")
	)
	(segment
		(start 51.928014 -133.340094)
		(end 90.768678 -133.340094)
		(width 0.11684)
		(layer "In11.Cu")
		(net "FM_P1_PCC1_N")
	)
	(segment
		(start 38.718236 -154.684222)
		(end 38.718236 -146.549872)
		(width 0.11684)
		(layer "In11.Cu")
		(net "FM_P1_PCC1_N")
	)
	(segment
		(start 28.712668 -174.31639)
		(end 28.712668 -164.68979)
		(width 0.11684)
		(layer "In11.Cu")
		(net "FM_P1_PCC1_N")
	)
	(segment
		(start 28.712668 -164.68979)
		(end 38.718236 -154.684222)
		(width 0.11684)
		(layer "In11.Cu")
		(net "FM_P1_PCC1_N")
	)
	(segment
		(start 90.768678 -133.340094)
		(end 92.926408 -131.182364)
		(width 0.11684)
		(layer "In11.Cu")
		(net "FM_P1_PCC1_N")
	)
	(segment
		(start 38.718236 -146.549872)
		(end 51.928014 -133.340094)
		(width 0.11684)
		(layer "In11.Cu")
		(net "FM_P1_PCC1_N")
	)
	(segment
		(start 183.522112 -121.052844)
		(end 183.132222 -121.442734)
		(width 0.10668)
		(layer "F.Cu")
		(net "FM_P1_PCC0_R_N")
	)
	(via
		(at 183.132222 -121.442734)
		(size 0.4572)
		(drill 0.254)
		(layers "F.Cu" "B.Cu")
		(net "FM_P1_PCC0_R_N")
	)
	(via
		(at 183.045608 -124.549916)
		(size 0.6604)
		(drill 0.3302)
		(layers "F.Cu" "B.Cu")
		(net "FM_P1_PCC0_R_N")
	)
	(segment
		(start 183.132222 -121.442734)
		(end 183.132222 -121.591578)
		(width 0.10668)
		(layer "B.Cu")
		(net "FM_P1_PCC0_R_N")
	)
	(segment
		(start 182.763414 -121.960386)
		(end 182.728362 -122.045222)
		(width 0.10668)
		(layer "B.Cu")
		(net "FM_P1_PCC0_R_N")
	)
	(segment
		(start 183.045608 -124.549916)
		(end 183.045608 -126.433326)
		(width 0.10668)
		(layer "B.Cu")
		(net "FM_P1_PCC0_R_N")
	)
	(segment
		(start 183.132222 -121.591578)
		(end 182.763414 -121.960386)
		(width 0.10668)
		(layer "B.Cu")
		(net "FM_P1_PCC0_R_N")
	)
	(segment
		(start 182.728362 -122.045222)
		(end 182.728362 -124.23267)
		(width 0.10668)
		(layer "B.Cu")
		(net "FM_P1_PCC0_R_N")
	)
	(segment
		(start 182.728362 -124.23267)
		(end 183.045608 -124.549916)
		(width 0.10668)
		(layer "B.Cu")
		(net "FM_P1_PCC0_R_N")
	)
	(segment
		(start 177.85207 -185.090308)
		(end 176.482248 -183.720486)
		(width 0.10668)
		(layer "F.Cu")
		(net "FM_P1_PCC0_N")
	)
	(segment
		(start 176.482248 -183.720486)
		(end 176.482248 -172.767752)
		(width 0.10668)
		(layer "F.Cu")
		(net "FM_P1_PCC0_N")
	)
	(segment
		(start 177.85207 -186.235594)
		(end 177.85207 -185.090308)
		(width 0.10668)
		(layer "F.Cu")
		(net "FM_P1_PCC0_N")
	)
	(segment
		(start 126.347982 -223.690434)
		(end 126.814834 -223.424496)
		(width 0.10668)
		(layer "F.Cu")
		(net "FM_P1_PCC0_N")
	)
	(via
		(at 181.991 -131.409948)
		(size 0.508)
		(drill 0.254)
		(layers "F.Cu" "B.Cu")
		(net "FM_P1_PCC0_N")
	)
	(via
		(at 147.475956 -197.219316)
		(size 0.6604)
		(drill 0.3302)
		(layers "F.Cu" "B.Cu")
		(net "FM_P1_PCC0_N")
	)
	(via
		(at 126.814834 -223.424496)
		(size 0.4064)
		(drill 0.2032)
		(layers "F.Cu" "B.Cu")
		(net "FM_P1_PCC0_N")
	)
	(via
		(at 177.85207 -186.235594)
		(size 0.508)
		(drill 0.254)
		(layers "F.Cu" "B.Cu")
		(net "FM_P1_PCC0_N")
	)
	(via
		(at 176.482248 -172.767752)
		(size 0.508)
		(drill 0.254)
		(layers "F.Cu" "B.Cu")
		(net "FM_P1_PCC0_N")
	)
	(segment
		(start 181.290722 -132.110226)
		(end 181.290722 -133.158738)
		(width 0.10668)
		(layer "B.Cu")
		(net "FM_P1_PCC0_N")
	)
	(segment
		(start 163.43122 -184.054496)
		(end 176.647602 -184.054496)
		(width 0.10668)
		(layer "B.Cu")
		(net "FM_P1_PCC0_N")
	)
	(segment
		(start 150.709884 -196.775832)
		(end 163.43122 -184.054496)
		(width 0.10668)
		(layer "B.Cu")
		(net "FM_P1_PCC0_N")
	)
	(segment
		(start 181.484016 -128.795018)
		(end 181.484016 -130.902964)
		(width 0.10668)
		(layer "B.Cu")
		(net "FM_P1_PCC0_N")
	)
	(segment
		(start 131.680712 -220.170756)
		(end 130.087116 -221.764352)
		(width 0.10668)
		(layer "B.Cu")
		(net "FM_P1_PCC0_N")
	)
	(segment
		(start 147.475956 -197.219316)
		(end 147.91944 -196.775832)
		(width 0.10668)
		(layer "B.Cu")
		(net "FM_P1_PCC0_N")
	)
	(segment
		(start 130.087116 -221.764352)
		(end 129.136394 -221.764352)
		(width 0.10668)
		(layer "B.Cu")
		(net "FM_P1_PCC0_N")
	)
	(segment
		(start 181.991 -131.409948)
		(end 181.290722 -132.110226)
		(width 0.10668)
		(layer "B.Cu")
		(net "FM_P1_PCC0_N")
	)
	(segment
		(start 131.680712 -219.516706)
		(end 131.680712 -220.170756)
		(width 0.10668)
		(layer "B.Cu")
		(net "FM_P1_PCC0_N")
	)
	(segment
		(start 129.465832 -212.218524)
		(end 129.465832 -218.165426)
		(width 0.10668)
		(layer "B.Cu")
		(net "FM_P1_PCC0_N")
	)
	(segment
		(start 147.91944 -196.775832)
		(end 150.709884 -196.775832)
		(width 0.10668)
		(layer "B.Cu")
		(net "FM_P1_PCC0_N")
	)
	(segment
		(start 183.045608 -127.233426)
		(end 181.484016 -128.795018)
		(width 0.10668)
		(layer "B.Cu")
		(net "FM_P1_PCC0_N")
	)
	(segment
		(start 176.647602 -184.054496)
		(end 177.85207 -185.258964)
		(width 0.10668)
		(layer "B.Cu")
		(net "FM_P1_PCC0_N")
	)
	(segment
		(start 128.851914 -222.048832)
		(end 127.165354 -222.048832)
		(width 0.10668)
		(layer "B.Cu")
		(net "FM_P1_PCC0_N")
	)
	(segment
		(start 181.290722 -133.158738)
		(end 181.57063 -133.438646)
		(width 0.10668)
		(layer "B.Cu")
		(net "FM_P1_PCC0_N")
	)
	(segment
		(start 147.475956 -197.219316)
		(end 142.015718 -202.679554)
		(width 0.10668)
		(layer "B.Cu")
		(net "FM_P1_PCC0_N")
	)
	(segment
		(start 131.275328 -219.111322)
		(end 131.680712 -219.516706)
		(width 0.10668)
		(layer "B.Cu")
		(net "FM_P1_PCC0_N")
	)
	(segment
		(start 129.136394 -221.764352)
		(end 128.851914 -222.048832)
		(width 0.10668)
		(layer "B.Cu")
		(net "FM_P1_PCC0_N")
	)
	(segment
		(start 126.814834 -222.399352)
		(end 126.814834 -223.424496)
		(width 0.10668)
		(layer "B.Cu")
		(net "FM_P1_PCC0_N")
	)
	(segment
		(start 127.165354 -222.048832)
		(end 126.814834 -222.399352)
		(width 0.10668)
		(layer "B.Cu")
		(net "FM_P1_PCC0_N")
	)
	(segment
		(start 129.465832 -218.165426)
		(end 130.411728 -219.111322)
		(width 0.10668)
		(layer "B.Cu")
		(net "FM_P1_PCC0_N")
	)
	(segment
		(start 142.015718 -202.679554)
		(end 139.004802 -202.679554)
		(width 0.10668)
		(layer "B.Cu")
		(net "FM_P1_PCC0_N")
	)
	(segment
		(start 181.484016 -130.902964)
		(end 181.991 -131.409948)
		(width 0.10668)
		(layer "B.Cu")
		(net "FM_P1_PCC0_N")
	)
	(segment
		(start 177.85207 -185.258964)
		(end 177.85207 -186.235594)
		(width 0.10668)
		(layer "B.Cu")
		(net "FM_P1_PCC0_N")
	)
	(segment
		(start 139.004802 -202.679554)
		(end 129.465832 -212.218524)
		(width 0.10668)
		(layer "B.Cu")
		(net "FM_P1_PCC0_N")
	)
	(segment
		(start 130.411728 -219.111322)
		(end 131.275328 -219.111322)
		(width 0.10668)
		(layer "B.Cu")
		(net "FM_P1_PCC0_N")
	)
	(segment
		(start 183.482996 -132.901944)
		(end 183.482996 -138.092942)
		(width 0.11684)
		(layer "In11.Cu")
		(net "FM_P1_PCC0_N")
	)
	(segment
		(start 176.861216 -173.14672)
		(end 176.482248 -172.767752)
		(width 0.11684)
		(layer "In11.Cu")
		(net "FM_P1_PCC0_N")
	)
	(segment
		(start 183.42737 -139.9413)
		(end 183.42737 -140.740892)
		(width 0.11684)
		(layer "In11.Cu")
		(net "FM_P1_PCC0_N")
	)
	(segment
		(start 181.448456 -156.651198)
		(end 177.572924 -160.52673)
		(width 0.11684)
		(layer "In11.Cu")
		(net "FM_P1_PCC0_N")
	)
	(segment
		(start 183.546496 -139.822174)
		(end 183.42737 -139.9413)
		(width 0.11684)
		(layer "In11.Cu")
		(net "FM_P1_PCC0_N")
	)
	(segment
		(start 185.0517 -146.758152)
		(end 182.667402 -149.14245)
		(width 0.11684)
		(layer "In11.Cu")
		(net "FM_P1_PCC0_N")
	)
	(segment
		(start 177.572924 -160.52673)
		(end 177.572924 -166.951406)
		(width 0.11684)
		(layer "In11.Cu")
		(net "FM_P1_PCC0_N")
	)
	(segment
		(start 183.482996 -138.092942)
		(end 183.546496 -138.156442)
		(width 0.11684)
		(layer "In11.Cu")
		(net "FM_P1_PCC0_N")
	)
	(segment
		(start 179.60213 -173.14672)
		(end 176.861216 -173.14672)
		(width 0.11684)
		(layer "In11.Cu")
		(net "FM_P1_PCC0_N")
	)
	(segment
		(start 177.572924 -166.951406)
		(end 180.318918 -169.6974)
		(width 0.11684)
		(layer "In11.Cu")
		(net "FM_P1_PCC0_N")
	)
	(segment
		(start 181.448456 -156.294328)
		(end 181.448456 -156.651198)
		(width 0.11684)
		(layer "In11.Cu")
		(net "FM_P1_PCC0_N")
	)
	(segment
		(start 183.42737 -140.740892)
		(end 183.694324 -141.007846)
		(width 0.11684)
		(layer "In11.Cu")
		(net "FM_P1_PCC0_N")
	)
	(segment
		(start 185.0517 -144.959832)
		(end 185.0517 -146.758152)
		(width 0.11684)
		(layer "In11.Cu")
		(net "FM_P1_PCC0_N")
	)
	(segment
		(start 183.694324 -143.602456)
		(end 185.0517 -144.959832)
		(width 0.11684)
		(layer "In11.Cu")
		(net "FM_P1_PCC0_N")
	)
	(segment
		(start 180.318918 -172.429932)
		(end 179.60213 -173.14672)
		(width 0.11684)
		(layer "In11.Cu")
		(net "FM_P1_PCC0_N")
	)
	(segment
		(start 183.546496 -138.156442)
		(end 183.546496 -139.822174)
		(width 0.11684)
		(layer "In11.Cu")
		(net "FM_P1_PCC0_N")
	)
	(segment
		(start 183.694324 -141.007846)
		(end 183.694324 -143.602456)
		(width 0.11684)
		(layer "In11.Cu")
		(net "FM_P1_PCC0_N")
	)
	(segment
		(start 182.667402 -149.14245)
		(end 182.667402 -155.075382)
		(width 0.11684)
		(layer "In11.Cu")
		(net "FM_P1_PCC0_N")
	)
	(segment
		(start 182.667402 -155.075382)
		(end 181.448456 -156.294328)
		(width 0.11684)
		(layer "In11.Cu")
		(net "FM_P1_PCC0_N")
	)
	(segment
		(start 181.991 -131.409948)
		(end 183.482996 -132.901944)
		(width 0.11684)
		(layer "In11.Cu")
		(net "FM_P1_PCC0_N")
	)
	(segment
		(start 180.318918 -169.6974)
		(end 180.318918 -172.429932)
		(width 0.11684)
		(layer "In11.Cu")
		(net "FM_P1_PCC0_N")
	)
	(segment
		(start 184.322212 -120.252744)
		(end 183.932322 -120.642634)
		(width 0.10668)
		(layer "F.Cu")
		(net "FM_P0_PCC1_R_N")
	)
	(via
		(at 183.932322 -120.642634)
		(size 0.4572)
		(drill 0.254)
		(layers "F.Cu" "B.Cu")
		(net "FM_P0_PCC1_R_N")
	)
	(via
		(at 184.328562 -125.21946)
		(size 0.6604)
		(drill 0.3302)
		(layers "F.Cu" "B.Cu")
		(net "FM_P0_PCC1_R_N")
	)
	(segment
		(start 184.328562 -121.038874)
		(end 183.932322 -120.642634)
		(width 0.10668)
		(layer "B.Cu")
		(net "FM_P0_PCC1_R_N")
	)
	(segment
		(start 184.328562 -125.21946)
		(end 184.328562 -121.038874)
		(width 0.10668)
		(layer "B.Cu")
		(net "FM_P0_PCC1_R_N")
	)
	(segment
		(start 184.328562 -126.166372)
		(end 184.328562 -125.21946)
		(width 0.10668)
		(layer "B.Cu")
		(net "FM_P0_PCC1_R_N")
	)
	(segment
		(start 184.061608 -126.433326)
		(end 184.328562 -126.166372)
		(width 0.10668)
		(layer "B.Cu")
		(net "FM_P0_PCC1_R_N")
	)
	(segment
		(start 277.644352 -164.438584)
		(end 277.644352 -167.150034)
		(width 0.10668)
		(layer "F.Cu")
		(net "FM_P0_PCC1_N")
	)
	(segment
		(start 328.527918 -294.070024)
		(end 328.061066 -294.335962)
		(width 0.10668)
		(layer "F.Cu")
		(net "FM_P0_PCC1_N")
	)
	(segment
		(start 284.08249 -158.827978)
		(end 283.944568 -158.9659)
		(width 0.10668)
		(layer "F.Cu")
		(net "FM_P0_PCC1_N")
	)
	(segment
		(start 281.046936 -174.879)
		(end 288.899092 -174.879)
		(width 0.10668)
		(layer "F.Cu")
		(net "FM_P0_PCC1_N")
	)
	(segment
		(start 276.394672 -170.226736)
		(end 281.046936 -174.879)
		(width 0.10668)
		(layer "F.Cu")
		(net "FM_P0_PCC1_N")
	)
	(segment
		(start 283.944568 -158.9659)
		(end 283.117036 -158.9659)
		(width 0.10668)
		(layer "F.Cu")
		(net "FM_P0_PCC1_N")
	)
	(segment
		(start 277.644352 -167.150034)
		(end 276.394672 -168.399714)
		(width 0.10668)
		(layer "F.Cu")
		(net "FM_P0_PCC1_N")
	)
	(segment
		(start 276.394672 -168.399714)
		(end 276.394672 -170.226736)
		(width 0.10668)
		(layer "F.Cu")
		(net "FM_P0_PCC1_N")
	)
	(segment
		(start 288.899092 -174.879)
		(end 300.409102 -186.38901)
		(width 0.10668)
		(layer "F.Cu")
		(net "FM_P0_PCC1_N")
	)
	(segment
		(start 283.117036 -158.9659)
		(end 277.644352 -164.438584)
		(width 0.10668)
		(layer "F.Cu")
		(net "FM_P0_PCC1_N")
	)
	(via
		(at 300.409102 -186.38901)
		(size 0.508)
		(drill 0.254)
		(layers "F.Cu" "B.Cu")
		(net "FM_P0_PCC1_N")
	)
	(via
		(at 184.023 -132.552948)
		(size 0.508)
		(drill 0.254)
		(layers "F.Cu" "B.Cu")
		(net "FM_P0_PCC1_N")
	)
	(via
		(at 312.464958 -203.495402)
		(size 0.6604)
		(drill 0.3302)
		(layers "F.Cu" "B.Cu")
		(net "FM_P0_PCC1_N")
	)
	(via
		(at 284.08249 -158.827978)
		(size 0.508)
		(drill 0.254)
		(layers "F.Cu" "B.Cu")
		(net "FM_P0_PCC1_N")
	)
	(via
		(at 199.047862 -160.444434)
		(size 0.508)
		(drill 0.254)
		(layers "F.Cu" "B.Cu")
		(net "FM_P0_PCC1_N")
	)
	(via
		(at 328.061066 -294.335962)
		(size 0.4064)
		(drill 0.2032)
		(layers "F.Cu" "B.Cu")
		(net "FM_P0_PCC1_N")
	)
	(segment
		(start 308.911752 -188.807852)
		(end 311.4167 -191.3128)
		(width 0.10668)
		(layer "B.Cu")
		(net "FM_P0_PCC1_N")
	)
	(segment
		(start 184.061608 -128.382014)
		(end 183.459374 -128.984248)
		(width 0.10668)
		(layer "B.Cu")
		(net "FM_P0_PCC1_N")
	)
	(segment
		(start 310.762904 -199.575674)
		(end 312.464958 -201.277728)
		(width 0.10668)
		(layer "B.Cu")
		(net "FM_P0_PCC1_N")
	)
	(segment
		(start 301.661068 -187.640976)
		(end 302.689768 -187.640976)
		(width 0.10668)
		(layer "B.Cu")
		(net "FM_P0_PCC1_N")
	)
	(segment
		(start 313.977274 -212.358732)
		(end 324.15099 -222.532448)
		(width 0.10668)
		(layer "B.Cu")
		(net "FM_P0_PCC1_N")
	)
	(segment
		(start 311.4167 -191.3128)
		(end 311.4167 -195.190364)
		(width 0.10668)
		(layer "B.Cu")
		(net "FM_P0_PCC1_N")
	)
	(segment
		(start 183.459374 -131.989322)
		(end 184.023 -132.552948)
		(width 0.10668)
		(layer "B.Cu")
		(net "FM_P0_PCC1_N")
	)
	(segment
		(start 302.689768 -187.640976)
		(end 303.856644 -188.807852)
		(width 0.10668)
		(layer "B.Cu")
		(net "FM_P0_PCC1_N")
	)
	(segment
		(start 313.977274 -205.007718)
		(end 313.977274 -212.358732)
		(width 0.10668)
		(layer "B.Cu")
		(net "FM_P0_PCC1_N")
	)
	(segment
		(start 303.856644 -188.807852)
		(end 308.911752 -188.807852)
		(width 0.10668)
		(layer "B.Cu")
		(net "FM_P0_PCC1_N")
	)
	(segment
		(start 183.459374 -128.984248)
		(end 183.459374 -131.989322)
		(width 0.10668)
		(layer "B.Cu")
		(net "FM_P0_PCC1_N")
	)
	(segment
		(start 326.81799 -294.335962)
		(end 328.061066 -294.335962)
		(width 0.10668)
		(layer "B.Cu")
		(net "FM_P0_PCC1_N")
	)
	(segment
		(start 325.08444 -293.525448)
		(end 326.007476 -293.525448)
		(width 0.10668)
		(layer "B.Cu")
		(net "FM_P0_PCC1_N")
	)
	(segment
		(start 312.464958 -203.495402)
		(end 313.977274 -205.007718)
		(width 0.10668)
		(layer "B.Cu")
		(net "FM_P0_PCC1_N")
	)
	(segment
		(start 300.409102 -186.38901)
		(end 301.661068 -187.640976)
		(width 0.10668)
		(layer "B.Cu")
		(net "FM_P0_PCC1_N")
	)
	(segment
		(start 324.15099 -292.591998)
		(end 325.08444 -293.525448)
		(width 0.10668)
		(layer "B.Cu")
		(net "FM_P0_PCC1_N")
	)
	(segment
		(start 310.762904 -195.84416)
		(end 310.762904 -199.575674)
		(width 0.10668)
		(layer "B.Cu")
		(net "FM_P0_PCC1_N")
	)
	(segment
		(start 312.464958 -201.277728)
		(end 312.464958 -203.495402)
		(width 0.10668)
		(layer "B.Cu")
		(net "FM_P0_PCC1_N")
	)
	(segment
		(start 326.007476 -293.525448)
		(end 326.81799 -294.335962)
		(width 0.10668)
		(layer "B.Cu")
		(net "FM_P0_PCC1_N")
	)
	(segment
		(start 324.15099 -222.532448)
		(end 324.15099 -292.591998)
		(width 0.10668)
		(layer "B.Cu")
		(net "FM_P0_PCC1_N")
	)
	(segment
		(start 311.4167 -195.190364)
		(end 310.762904 -195.84416)
		(width 0.10668)
		(layer "B.Cu")
		(net "FM_P0_PCC1_N")
	)
	(segment
		(start 184.061608 -127.233426)
		(end 184.061608 -128.382014)
		(width 0.10668)
		(layer "B.Cu")
		(net "FM_P0_PCC1_N")
	)
	(segment
		(start 183.650382 -132.925566)
		(end 183.650382 -133.109462)
		(width 0.10668)
		(layer "B.Cu")
		(net "FM_P0_PCC1_N")
	)
	(segment
		(start 184.023 -132.552948)
		(end 183.650382 -132.925566)
		(width 0.10668)
		(layer "B.Cu")
		(net "FM_P0_PCC1_N")
	)
	(segment
		(start 183.650382 -133.109462)
		(end 183.364886 -133.394958)
		(width 0.10668)
		(layer "B.Cu")
		(net "FM_P0_PCC1_N")
	)
	(segment
		(start 253.656592 -159.39516)
		(end 263.486646 -159.39516)
		(width 0.11684)
		(layer "In6.Cu")
		(net "FM_P0_PCC1_N")
	)
	(segment
		(start 272.171414 -150.356316)
		(end 275.219668 -147.308062)
		(width 0.11684)
		(layer "In6.Cu")
		(net "FM_P0_PCC1_N")
	)
	(segment
		(start 226.643946 -157.74924)
		(end 227.957634 -159.062928)
		(width 0.11684)
		(layer "In6.Cu")
		(net "FM_P0_PCC1_N")
	)
	(segment
		(start 202.388978 -157.103318)
		(end 214.66429 -157.103318)
		(width 0.11684)
		(layer "In6.Cu")
		(net "FM_P0_PCC1_N")
	)
	(segment
		(start 227.957634 -159.062928)
		(end 253.32436 -159.062928)
		(width 0.11684)
		(layer "In6.Cu")
		(net "FM_P0_PCC1_N")
	)
	(segment
		(start 272.171414 -150.710392)
		(end 272.171414 -150.356316)
		(width 0.11684)
		(layer "In6.Cu")
		(net "FM_P0_PCC1_N")
	)
	(segment
		(start 284.393386 -158.517082)
		(end 284.08249 -158.827978)
		(width 0.11684)
		(layer "In6.Cu")
		(net "FM_P0_PCC1_N")
	)
	(segment
		(start 214.66429 -157.103318)
		(end 215.310212 -157.74924)
		(width 0.11684)
		(layer "In6.Cu")
		(net "FM_P0_PCC1_N")
	)
	(segment
		(start 263.486646 -159.39516)
		(end 272.171414 -150.710392)
		(width 0.11684)
		(layer "In6.Cu")
		(net "FM_P0_PCC1_N")
	)
	(segment
		(start 284.393386 -151.131016)
		(end 284.393386 -158.517082)
		(width 0.11684)
		(layer "In6.Cu")
		(net "FM_P0_PCC1_N")
	)
	(segment
		(start 215.310212 -157.74924)
		(end 226.643946 -157.74924)
		(width 0.11684)
		(layer "In6.Cu")
		(net "FM_P0_PCC1_N")
	)
	(segment
		(start 280.570432 -147.308062)
		(end 284.393386 -151.131016)
		(width 0.11684)
		(layer "In6.Cu")
		(net "FM_P0_PCC1_N")
	)
	(segment
		(start 275.219668 -147.308062)
		(end 280.570432 -147.308062)
		(width 0.11684)
		(layer "In6.Cu")
		(net "FM_P0_PCC1_N")
	)
	(segment
		(start 199.047862 -160.444434)
		(end 202.388978 -157.103318)
		(width 0.11684)
		(layer "In6.Cu")
		(net "FM_P0_PCC1_N")
	)
	(segment
		(start 253.32436 -159.062928)
		(end 253.656592 -159.39516)
		(width 0.11684)
		(layer "In6.Cu")
		(net "FM_P0_PCC1_N")
	)
	(segment
		(start 184.23509 -149.128988)
		(end 184.23509 -157.534102)
		(width 0.11684)
		(layer "In15.Cu")
		(net "FM_P0_PCC1_N")
	)
	(segment
		(start 181.500272 -144.296892)
		(end 182.139844 -144.936464)
		(width 0.11684)
		(layer "In15.Cu")
		(net "FM_P0_PCC1_N")
	)
	(segment
		(start 183.485282 -134.323328)
		(end 183.485282 -138.258042)
		(width 0.11684)
		(layer "In15.Cu")
		(net "FM_P0_PCC1_N")
	)
	(segment
		(start 184.023 -132.552948)
		(end 184.023 -133.78561)
		(width 0.11684)
		(layer "In15.Cu")
		(net "FM_P0_PCC1_N")
	)
	(segment
		(start 182.139844 -144.936464)
		(end 182.139844 -147.033742)
		(width 0.11684)
		(layer "In15.Cu")
		(net "FM_P0_PCC1_N")
	)
	(segment
		(start 197.937628 -161.554668)
		(end 199.047862 -160.444434)
		(width 0.11684)
		(layer "In15.Cu")
		(net "FM_P0_PCC1_N")
	)
	(segment
		(start 183.485282 -138.258042)
		(end 183.5531 -138.32586)
		(width 0.11684)
		(layer "In15.Cu")
		(net "FM_P0_PCC1_N")
	)
	(segment
		(start 183.5531 -139.01166)
		(end 181.500272 -141.064488)
		(width 0.11684)
		(layer "In15.Cu")
		(net "FM_P0_PCC1_N")
	)
	(segment
		(start 188.255656 -161.554668)
		(end 197.937628 -161.554668)
		(width 0.11684)
		(layer "In15.Cu")
		(net "FM_P0_PCC1_N")
	)
	(segment
		(start 182.139844 -147.033742)
		(end 184.23509 -149.128988)
		(width 0.11684)
		(layer "In15.Cu")
		(net "FM_P0_PCC1_N")
	)
	(segment
		(start 184.023 -133.78561)
		(end 183.485282 -134.323328)
		(width 0.11684)
		(layer "In15.Cu")
		(net "FM_P0_PCC1_N")
	)
	(segment
		(start 184.23509 -157.534102)
		(end 188.255656 -161.554668)
		(width 0.11684)
		(layer "In15.Cu")
		(net "FM_P0_PCC1_N")
	)
	(segment
		(start 181.500272 -141.064488)
		(end 181.500272 -144.296892)
		(width 0.11684)
		(layer "In15.Cu")
		(net "FM_P0_PCC1_N")
	)
	(segment
		(start 183.5531 -138.32586)
		(end 183.5531 -139.01166)
		(width 0.11684)
		(layer "In15.Cu")
		(net "FM_P0_PCC1_N")
	)
	(segment
		(start 184.023 -137.232898)
		(end 183.981344 -137.191242)
		(width 0.10668)
		(layer "F.Cu")
		(net "FM_P0_PCC0_R_N")
	)
	(segment
		(start 184.322212 -119.452898)
		(end 183.932322 -119.842788)
		(width 0.10668)
		(layer "F.Cu")
		(net "FM_P0_PCC0_R_N")
	)
	(segment
		(start 183.981344 -137.191242)
		(end 183.981344 -136.531858)
		(width 0.10668)
		(layer "F.Cu")
		(net "FM_P0_PCC0_R_N")
	)
	(via
		(at 183.932322 -119.842788)
		(size 0.4572)
		(drill 0.254)
		(layers "F.Cu" "B.Cu")
		(net "FM_P0_PCC0_R_N")
	)
	(via
		(at 183.981344 -136.531858)
		(size 0.508)
		(drill 0.254)
		(layers "F.Cu" "B.Cu")
		(net "FM_P0_PCC0_R_N")
	)
	(segment
		(start 184.107074 -136.531858)
		(end 183.981344 -136.531858)
		(width 0.11684)
		(layer "In2.Cu")
		(net "FM_P0_PCC0_R_N")
	)
	(segment
		(start 184.540398 -128.797558)
		(end 184.540398 -136.098534)
		(width 0.11684)
		(layer "In2.Cu")
		(net "FM_P0_PCC0_R_N")
	)
	(segment
		(start 184.016142 -128.273302)
		(end 184.540398 -128.797558)
		(width 0.11684)
		(layer "In2.Cu")
		(net "FM_P0_PCC0_R_N")
	)
	(segment
		(start 183.932322 -119.842788)
		(end 183.932322 -120.026176)
		(width 0.11684)
		(layer "In2.Cu")
		(net "FM_P0_PCC0_R_N")
	)
	(segment
		(start 183.932322 -120.026176)
		(end 183.52516 -120.433338)
		(width 0.11684)
		(layer "In2.Cu")
		(net "FM_P0_PCC0_R_N")
	)
	(segment
		(start 184.016142 -126.710948)
		(end 184.016142 -128.273302)
		(width 0.11684)
		(layer "In2.Cu")
		(net "FM_P0_PCC0_R_N")
	)
	(segment
		(start 184.540398 -136.098534)
		(end 184.107074 -136.531858)
		(width 0.11684)
		(layer "In2.Cu")
		(net "FM_P0_PCC0_R_N")
	)
	(segment
		(start 183.52516 -126.219966)
		(end 184.016142 -126.710948)
		(width 0.11684)
		(layer "In2.Cu")
		(net "FM_P0_PCC0_R_N")
	)
	(segment
		(start 183.52516 -120.433338)
		(end 183.52516 -126.219966)
		(width 0.11684)
		(layer "In2.Cu")
		(net "FM_P0_PCC0_R_N")
	)
	(segment
		(start 374.754902 -223.424242)
		(end 374.28805 -223.69018)
		(width 0.1524)
		(layer "F.Cu")
		(net "FM_P0_PCC0_N")
	)
	(segment
		(start 184.069736 -138.649456)
		(end 184.069736 -139.125452)
		(width 0.10668)
		(layer "F.Cu")
		(net "FM_P0_PCC0_N")
	)
	(segment
		(start 184.023 -138.60272)
		(end 184.069736 -138.649456)
		(width 0.10668)
		(layer "F.Cu")
		(net "FM_P0_PCC0_N")
	)
	(segment
		(start 183.42229 -139.772898)
		(end 183.007 -139.772898)
		(width 0.10668)
		(layer "F.Cu")
		(net "FM_P0_PCC0_N")
	)
	(segment
		(start 184.023 -138.032998)
		(end 184.023 -138.60272)
		(width 0.10668)
		(layer "F.Cu")
		(net "FM_P0_PCC0_N")
	)
	(segment
		(start 184.069736 -139.125452)
		(end 183.42229 -139.772898)
		(width 0.10668)
		(layer "F.Cu")
		(net "FM_P0_PCC0_N")
	)
	(via
		(at 184.069736 -138.649456)
		(size 0.508)
		(drill 0.254)
		(layers "F.Cu" "B.Cu")
		(net "FM_P0_PCC0_N")
	)
	(via
		(at 374.326912 -206.642208)
		(size 0.508)
		(drill 0.254)
		(layers "F.Cu" "B.Cu")
		(net "FM_P0_PCC0_N")
	)
	(via
		(at 212.104986 -167.87876)
		(size 0.508)
		(drill 0.254)
		(layers "F.Cu" "B.Cu")
		(net "FM_P0_PCC0_N")
	)
	(via
		(at 374.754902 -223.424242)
		(size 0.4064)
		(drill 0.2032)
		(layers "F.Cu" "B.Cu")
		(net "FM_P0_PCC0_N")
	)
	(via
		(at 184.722262 -155.115006)
		(size 0.508)
		(drill 0.254)
		(layers "F.Cu" "B.Cu")
		(net "FM_P0_PCC0_N")
	)
	(segment
		(start 376.574558 -222.805752)
		(end 376.361198 -223.019112)
		(width 0.1016)
		(layer "In2.Cu")
		(net "FM_P0_PCC0_N")
	)
	(segment
		(start 190.856108 -161.248852)
		(end 184.722262 -155.115006)
		(width 0.11684)
		(layer "In2.Cu")
		(net "FM_P0_PCC0_N")
	)
	(segment
		(start 374.326912 -206.642208)
		(end 373.77116 -207.19796)
		(width 0.11684)
		(layer "In2.Cu")
		(net "FM_P0_PCC0_N")
	)
	(segment
		(start 212.104986 -167.87876)
		(end 212.104986 -167.197024)
		(width 0.11684)
		(layer "In2.Cu")
		(net "FM_P0_PCC0_N")
	)
	(segment
		(start 375.160032 -223.019112)
		(end 374.754902 -223.424242)
		(width 0.1016)
		(layer "In2.Cu")
		(net "FM_P0_PCC0_N")
	)
	(segment
		(start 210.22183 -165.313868)
		(end 207.55356 -165.313868)
		(width 0.11684)
		(layer "In2.Cu")
		(net "FM_P0_PCC0_N")
	)
	(segment
		(start 376.574558 -222.272352)
		(end 376.574558 -222.805752)
		(width 0.1016)
		(layer "In2.Cu")
		(net "FM_P0_PCC0_N")
	)
	(segment
		(start 374.790208 -213.068662)
		(end 376.3391 -214.617554)
		(width 0.11684)
		(layer "In2.Cu")
		(net "FM_P0_PCC0_N")
	)
	(segment
		(start 374.790208 -211.436966)
		(end 374.790208 -213.068662)
		(width 0.11684)
		(layer "In2.Cu")
		(net "FM_P0_PCC0_N")
	)
	(segment
		(start 373.77116 -210.417918)
		(end 374.790208 -211.436966)
		(width 0.11684)
		(layer "In2.Cu")
		(net "FM_P0_PCC0_N")
	)
	(segment
		(start 207.55356 -165.313868)
		(end 204.978254 -162.738562)
		(width 0.11684)
		(layer "In2.Cu")
		(net "FM_P0_PCC0_N")
	)
	(segment
		(start 376.361198 -223.019112)
		(end 375.160032 -223.019112)
		(width 0.1016)
		(layer "In2.Cu")
		(net "FM_P0_PCC0_N")
	)
	(segment
		(start 212.104986 -167.197024)
		(end 210.22183 -165.313868)
		(width 0.11684)
		(layer "In2.Cu")
		(net "FM_P0_PCC0_N")
	)
	(segment
		(start 198.035672 -162.738562)
		(end 196.545962 -161.248852)
		(width 0.11684)
		(layer "In2.Cu")
		(net "FM_P0_PCC0_N")
	)
	(segment
		(start 376.3391 -214.617554)
		(end 376.3391 -222.036894)
		(width 0.11684)
		(layer "In2.Cu")
		(net "FM_P0_PCC0_N")
	)
	(segment
		(start 373.77116 -207.19796)
		(end 373.77116 -210.417918)
		(width 0.11684)
		(layer "In2.Cu")
		(net "FM_P0_PCC0_N")
	)
	(segment
		(start 204.978254 -162.738562)
		(end 198.035672 -162.738562)
		(width 0.11684)
		(layer "In2.Cu")
		(net "FM_P0_PCC0_N")
	)
	(segment
		(start 196.545962 -161.248852)
		(end 190.856108 -161.248852)
		(width 0.11684)
		(layer "In2.Cu")
		(net "FM_P0_PCC0_N")
	)
	(segment
		(start 376.3391 -222.036894)
		(end 376.574558 -222.272352)
		(width 0.11684)
		(layer "In2.Cu")
		(net "FM_P0_PCC0_N")
	)
	(segment
		(start 232.190798 -170.046904)
		(end 234.00258 -168.235122)
		(width 0.11684)
		(layer "In6.Cu")
		(net "FM_P0_PCC0_N")
	)
	(segment
		(start 255.69164 -167.56507)
		(end 311.760108 -167.56507)
		(width 0.11684)
		(layer "In6.Cu")
		(net "FM_P0_PCC0_N")
	)
	(segment
		(start 255.021588 -168.235122)
		(end 255.69164 -167.56507)
		(width 0.11684)
		(layer "In6.Cu")
		(net "FM_P0_PCC0_N")
	)
	(segment
		(start 311.760108 -167.56507)
		(end 315.413136 -171.218098)
		(width 0.11684)
		(layer "In6.Cu")
		(net "FM_P0_PCC0_N")
	)
	(segment
		(start 367.78946 -205.372462)
		(end 373.057166 -205.372462)
		(width 0.11684)
		(layer "In6.Cu")
		(net "FM_P0_PCC0_N")
	)
	(segment
		(start 214.27313 -170.046904)
		(end 232.190798 -170.046904)
		(width 0.11684)
		(layer "In6.Cu")
		(net "FM_P0_PCC0_N")
	)
	(segment
		(start 315.413136 -171.218098)
		(end 333.635096 -171.218098)
		(width 0.11684)
		(layer "In6.Cu")
		(net "FM_P0_PCC0_N")
	)
	(segment
		(start 234.00258 -168.235122)
		(end 255.021588 -168.235122)
		(width 0.11684)
		(layer "In6.Cu")
		(net "FM_P0_PCC0_N")
	)
	(segment
		(start 333.635096 -171.218098)
		(end 367.78946 -205.372462)
		(width 0.11684)
		(layer "In6.Cu")
		(net "FM_P0_PCC0_N")
	)
	(segment
		(start 212.104986 -167.87876)
		(end 214.27313 -170.046904)
		(width 0.11684)
		(layer "In6.Cu")
		(net "FM_P0_PCC0_N")
	)
	(segment
		(start 373.057166 -205.372462)
		(end 374.326912 -206.642208)
		(width 0.11684)
		(layer "In6.Cu")
		(net "FM_P0_PCC0_N")
	)
	(segment
		(start 183.707532 -146.62404)
		(end 183.47182 -146.62404)
		(width 0.11684)
		(layer "In15.Cu")
		(net "FM_P0_PCC0_N")
	)
	(segment
		(start 183.47182 -146.62404)
		(end 182.787036 -145.939256)
		(width 0.11684)
		(layer "In15.Cu")
		(net "FM_P0_PCC0_N")
	)
	(segment
		(start 182.787036 -145.939256)
		(end 182.787036 -144.949926)
		(width 0.11684)
		(layer "In15.Cu")
		(net "FM_P0_PCC0_N")
	)
	(segment
		(start 184.722262 -155.115006)
		(end 184.722262 -147.63877)
		(width 0.11684)
		(layer "In15.Cu")
		(net "FM_P0_PCC0_N")
	)
	(segment
		(start 184.069736 -139.058142)
		(end 184.069736 -138.649456)
		(width 0.11684)
		(layer "In15.Cu")
		(net "FM_P0_PCC0_N")
	)
	(segment
		(start 184.722262 -147.63877)
		(end 183.707532 -146.62404)
		(width 0.11684)
		(layer "In15.Cu")
		(net "FM_P0_PCC0_N")
	)
	(segment
		(start 182.787036 -144.949926)
		(end 181.899052 -144.061942)
		(width 0.11684)
		(layer "In15.Cu")
		(net "FM_P0_PCC0_N")
	)
	(segment
		(start 181.899052 -144.061942)
		(end 181.899052 -141.228826)
		(width 0.11684)
		(layer "In15.Cu")
		(net "FM_P0_PCC0_N")
	)
	(segment
		(start 181.899052 -141.228826)
		(end 184.069736 -139.058142)
		(width 0.11684)
		(layer "In15.Cu")
		(net "FM_P0_PCC0_N")
	)
	(segment
		(start 177.922174 -123.45289)
		(end 177.532284 -123.84278)
		(width 0.10668)
		(layer "F.Cu")
		(net "FM_OCP_V3_2_PWR_GOOD")
	)
	(segment
		(start 58.851038 -29.378148)
		(end 57.769252 -29.378148)
		(width 0.10668)
		(layer "F.Cu")
		(net "FM_OCP_V3_2_PWR_GOOD")
	)
	(segment
		(start 49.12868 -29.481018)
		(end 49.12868 -28.707588)
		(width 0.10668)
		(layer "F.Cu")
		(net "FM_OCP_V3_2_PWR_GOOD")
	)
	(segment
		(start 78.062074 -11.26998)
		(end 78.062074 -12.0142)
		(width 0.10668)
		(layer "F.Cu")
		(net "FM_OCP_V3_2_PWR_GOOD")
	)
	(segment
		(start 57.321196 -29.826204)
		(end 49.473866 -29.826204)
		(width 0.10668)
		(layer "F.Cu")
		(net "FM_OCP_V3_2_PWR_GOOD")
	)
	(segment
		(start 49.473866 -29.826204)
		(end 49.12868 -29.481018)
		(width 0.10668)
		(layer "F.Cu")
		(net "FM_OCP_V3_2_PWR_GOOD")
	)
	(segment
		(start 57.769252 -29.378148)
		(end 57.321196 -29.826204)
		(width 0.10668)
		(layer "F.Cu")
		(net "FM_OCP_V3_2_PWR_GOOD")
	)
	(segment
		(start 59.062366 -29.16682)
		(end 58.851038 -29.378148)
		(width 0.10668)
		(layer "F.Cu")
		(net "FM_OCP_V3_2_PWR_GOOD")
	)
	(segment
		(start 78.062074 -12.0142)
		(end 78.840584 -12.79271)
		(width 0.10668)
		(layer "F.Cu")
		(net "FM_OCP_V3_2_PWR_GOOD")
	)
	(via
		(at 78.840584 -12.79271)
		(size 0.508)
		(drill 0.254)
		(layers "F.Cu" "B.Cu")
		(net "FM_OCP_V3_2_PWR_GOOD")
	)
	(via
		(at 59.062366 -29.16682)
		(size 0.508)
		(drill 0.254)
		(layers "F.Cu" "B.Cu")
		(net "FM_OCP_V3_2_PWR_GOOD")
	)
	(via
		(at 156.439362 -125.342396)
		(size 0.508)
		(drill 0.254)
		(layers "F.Cu" "B.Cu")
		(net "FM_OCP_V3_2_PWR_GOOD")
	)
	(via
		(at 143.195802 -123.5329)
		(size 0.508)
		(drill 0.254)
		(layers "F.Cu" "B.Cu")
		(net "FM_OCP_V3_2_PWR_GOOD")
	)
	(via
		(at 177.532284 -123.84278)
		(size 0.4572)
		(drill 0.254)
		(layers "F.Cu" "B.Cu")
		(net "FM_OCP_V3_2_PWR_GOOD")
	)
	(segment
		(start 78.840584 -12.28217)
		(end 78.840584 -12.79271)
		(width 0.10668)
		(layer "B.Cu")
		(net "FM_OCP_V3_2_PWR_GOOD")
	)
	(segment
		(start 78.921864 -11.92276)
		(end 78.921864 -12.20089)
		(width 0.10668)
		(layer "B.Cu")
		(net "FM_OCP_V3_2_PWR_GOOD")
	)
	(segment
		(start 78.921864 -12.20089)
		(end 78.840584 -12.28217)
		(width 0.10668)
		(layer "B.Cu")
		(net "FM_OCP_V3_2_PWR_GOOD")
	)
	(segment
		(start 79.175864 -11.66876)
		(end 78.921864 -11.92276)
		(width 0.10668)
		(layer "B.Cu")
		(net "FM_OCP_V3_2_PWR_GOOD")
	)
	(segment
		(start 59.062366 -29.16682)
		(end 59.062366 -28.70327)
		(width 0.11684)
		(layer "In2.Cu")
		(net "FM_OCP_V3_2_PWR_GOOD")
	)
	(segment
		(start 177.532284 -123.84278)
		(end 177.532284 -124.097542)
		(width 0.11684)
		(layer "In2.Cu")
		(net "FM_OCP_V3_2_PWR_GOOD")
	)
	(segment
		(start 59.062366 -28.70327)
		(end 58.666126 -28.30703)
		(width 0.11684)
		(layer "In2.Cu")
		(net "FM_OCP_V3_2_PWR_GOOD")
	)
	(segment
		(start 58.666126 -23.10765)
		(end 60.127388 -21.646388)
		(width 0.11684)
		(layer "In2.Cu")
		(net "FM_OCP_V3_2_PWR_GOOD")
	)
	(segment
		(start 70.4469 -13.523722)
		(end 71.792084 -13.523722)
		(width 0.11684)
		(layer "In2.Cu")
		(net "FM_OCP_V3_2_PWR_GOOD")
	)
	(segment
		(start 60.127388 -12.410186)
		(end 61.193934 -11.34364)
		(width 0.11684)
		(layer "In2.Cu")
		(net "FM_OCP_V3_2_PWR_GOOD")
	)
	(segment
		(start 71.792084 -13.523722)
		(end 72.95261 -14.684248)
		(width 0.11684)
		(layer "In2.Cu")
		(net "FM_OCP_V3_2_PWR_GOOD")
	)
	(segment
		(start 61.193934 -11.34364)
		(end 68.266818 -11.34364)
		(width 0.11684)
		(layer "In2.Cu")
		(net "FM_OCP_V3_2_PWR_GOOD")
	)
	(segment
		(start 76.949046 -14.684248)
		(end 78.840584 -12.79271)
		(width 0.11684)
		(layer "In2.Cu")
		(net "FM_OCP_V3_2_PWR_GOOD")
	)
	(segment
		(start 58.666126 -28.30703)
		(end 58.666126 -23.10765)
		(width 0.11684)
		(layer "In2.Cu")
		(net "FM_OCP_V3_2_PWR_GOOD")
	)
	(segment
		(start 177.532284 -124.097542)
		(end 176.28743 -125.342396)
		(width 0.11684)
		(layer "In2.Cu")
		(net "FM_OCP_V3_2_PWR_GOOD")
	)
	(segment
		(start 176.28743 -125.342396)
		(end 156.439362 -125.342396)
		(width 0.11684)
		(layer "In2.Cu")
		(net "FM_OCP_V3_2_PWR_GOOD")
	)
	(segment
		(start 60.127388 -21.646388)
		(end 60.127388 -12.410186)
		(width 0.11684)
		(layer "In2.Cu")
		(net "FM_OCP_V3_2_PWR_GOOD")
	)
	(segment
		(start 72.95261 -14.684248)
		(end 76.949046 -14.684248)
		(width 0.11684)
		(layer "In2.Cu")
		(net "FM_OCP_V3_2_PWR_GOOD")
	)
	(segment
		(start 68.266818 -11.34364)
		(end 70.4469 -13.523722)
		(width 0.11684)
		(layer "In2.Cu")
		(net "FM_OCP_V3_2_PWR_GOOD")
	)
	(segment
		(start 99.879404 -73.160128)
		(end 102.969568 -76.250292)
		(width 0.11684)
		(layer "In4.Cu")
		(net "FM_OCP_V3_2_PWR_GOOD")
	)
	(segment
		(start 102.969568 -76.250292)
		(end 102.969568 -78.204568)
		(width 0.11684)
		(layer "In4.Cu")
		(net "FM_OCP_V3_2_PWR_GOOD")
	)
	(segment
		(start 59.72429 -34.248344)
		(end 59.72429 -36.356544)
		(width 0.11684)
		(layer "In4.Cu")
		(net "FM_OCP_V3_2_PWR_GOOD")
	)
	(segment
		(start 60.92952 -37.561774)
		(end 60.92952 -41.613074)
		(width 0.11684)
		(layer "In4.Cu")
		(net "FM_OCP_V3_2_PWR_GOOD")
	)
	(segment
		(start 62.722252 -43.405806)
		(end 82.976974 -43.405806)
		(width 0.11684)
		(layer "In4.Cu")
		(net "FM_OCP_V3_2_PWR_GOOD")
	)
	(segment
		(start 99.879404 -57.62752)
		(end 99.879404 -73.160128)
		(width 0.11684)
		(layer "In4.Cu")
		(net "FM_OCP_V3_2_PWR_GOOD")
	)
	(segment
		(start 105.198672 -80.433672)
		(end 105.198672 -84.188808)
		(width 0.11684)
		(layer "In4.Cu")
		(net "FM_OCP_V3_2_PWR_GOOD")
	)
	(segment
		(start 102.969568 -78.204568)
		(end 105.198672 -80.433672)
		(width 0.11684)
		(layer "In4.Cu")
		(net "FM_OCP_V3_2_PWR_GOOD")
	)
	(segment
		(start 143.195802 -122.185938)
		(end 143.195802 -123.5329)
		(width 0.11684)
		(layer "In4.Cu")
		(net "FM_OCP_V3_2_PWR_GOOD")
	)
	(segment
		(start 95.482664 -53.23078)
		(end 99.879404 -57.62752)
		(width 0.11684)
		(layer "In4.Cu")
		(net "FM_OCP_V3_2_PWR_GOOD")
	)
	(segment
		(start 59.062366 -29.16682)
		(end 59.062366 -33.58642)
		(width 0.11684)
		(layer "In4.Cu")
		(net "FM_OCP_V3_2_PWR_GOOD")
	)
	(segment
		(start 59.72429 -36.356544)
		(end 60.92952 -37.561774)
		(width 0.11684)
		(layer "In4.Cu")
		(net "FM_OCP_V3_2_PWR_GOOD")
	)
	(segment
		(start 59.062366 -33.58642)
		(end 59.72429 -34.248344)
		(width 0.11684)
		(layer "In4.Cu")
		(net "FM_OCP_V3_2_PWR_GOOD")
	)
	(segment
		(start 90.970608 -53.23078)
		(end 95.482664 -53.23078)
		(width 0.11684)
		(layer "In4.Cu")
		(net "FM_OCP_V3_2_PWR_GOOD")
	)
	(segment
		(start 82.976974 -43.405806)
		(end 86.791292 -47.220124)
		(width 0.11684)
		(layer "In4.Cu")
		(net "FM_OCP_V3_2_PWR_GOOD")
	)
	(segment
		(start 60.92952 -41.613074)
		(end 62.722252 -43.405806)
		(width 0.11684)
		(layer "In4.Cu")
		(net "FM_OCP_V3_2_PWR_GOOD")
	)
	(segment
		(start 105.198672 -84.188808)
		(end 143.195802 -122.185938)
		(width 0.11684)
		(layer "In4.Cu")
		(net "FM_OCP_V3_2_PWR_GOOD")
	)
	(segment
		(start 86.791292 -49.051464)
		(end 90.970608 -53.23078)
		(width 0.11684)
		(layer "In4.Cu")
		(net "FM_OCP_V3_2_PWR_GOOD")
	)
	(segment
		(start 86.791292 -47.220124)
		(end 86.791292 -49.051464)
		(width 0.11684)
		(layer "In4.Cu")
		(net "FM_OCP_V3_2_PWR_GOOD")
	)
	(segment
		(start 155.219146 -124.12218)
		(end 146.034252 -124.12218)
		(width 0.11684)
		(layer "In6.Cu")
		(net "FM_OCP_V3_2_PWR_GOOD")
	)
	(segment
		(start 146.034252 -124.12218)
		(end 144.848072 -122.936)
		(width 0.11684)
		(layer "In6.Cu")
		(net "FM_OCP_V3_2_PWR_GOOD")
	)
	(segment
		(start 156.439362 -125.342396)
		(end 155.219146 -124.12218)
		(width 0.11684)
		(layer "In6.Cu")
		(net "FM_OCP_V3_2_PWR_GOOD")
	)
	(segment
		(start 144.848072 -122.936)
		(end 143.792702 -122.936)
		(width 0.11684)
		(layer "In6.Cu")
		(net "FM_OCP_V3_2_PWR_GOOD")
	)
	(segment
		(start 143.792702 -122.936)
		(end 143.195802 -123.5329)
		(width 0.11684)
		(layer "In6.Cu")
		(net "FM_OCP_V3_2_PWR_GOOD")
	)
	(segment
		(start 452.56196 -12.204954)
		(end 453.0598 -12.702794)
		(width 0.10668)
		(layer "F.Cu")
		(net "FM_OCP_SFF_PWR_GOOD")
	)
	(segment
		(start 452.56196 -11.26998)
		(end 452.56196 -12.204954)
		(width 0.10668)
		(layer "F.Cu")
		(net "FM_OCP_SFF_PWR_GOOD")
	)
	(segment
		(start 457.323952 -98.514408)
		(end 458.629766 -98.514408)
		(width 0.10668)
		(layer "F.Cu")
		(net "FM_OCP_SFF_PWR_GOOD")
	)
	(segment
		(start 184.801256 -95.703898)
		(end 184.801256 -93.690948)
		(width 0.10668)
		(layer "F.Cu")
		(net "FM_OCP_SFF_PWR_GOOD")
	)
	(segment
		(start 456.673966 -97.864422)
		(end 457.323952 -98.514408)
		(width 0.10668)
		(layer "F.Cu")
		(net "FM_OCP_SFF_PWR_GOOD")
	)
	(via
		(at 456.673966 -97.864422)
		(size 0.508)
		(drill 0.254)
		(layers "F.Cu" "B.Cu")
		(net "FM_OCP_SFF_PWR_GOOD")
	)
	(via
		(at 184.801256 -93.690948)
		(size 0.508)
		(drill 0.254)
		(layers "F.Cu" "B.Cu")
		(net "FM_OCP_SFF_PWR_GOOD")
	)
	(via
		(at 453.0598 -12.702794)
		(size 0.508)
		(drill 0.254)
		(layers "F.Cu" "B.Cu")
		(net "FM_OCP_SFF_PWR_GOOD")
	)
	(via
		(at 234.879896 -94.541594)
		(size 0.508)
		(drill 0.254)
		(layers "F.Cu" "B.Cu")
		(net "FM_OCP_SFF_PWR_GOOD")
	)
	(segment
		(start 453.0598 -12.702794)
		(end 454.068688 -12.702794)
		(width 0.10668)
		(layer "B.Cu")
		(net "FM_OCP_SFF_PWR_GOOD")
	)
	(segment
		(start 445.865504 -94.046548)
		(end 452.856092 -94.046548)
		(width 0.11684)
		(layer "In6.Cu")
		(net "FM_OCP_SFF_PWR_GOOD")
	)
	(segment
		(start 256.0828 -91.365578)
		(end 262.707628 -91.365578)
		(width 0.11684)
		(layer "In6.Cu")
		(net "FM_OCP_SFF_PWR_GOOD")
	)
	(segment
		(start 262.707628 -91.365578)
		(end 263.20623 -90.866976)
		(width 0.11684)
		(layer "In6.Cu")
		(net "FM_OCP_SFF_PWR_GOOD")
	)
	(segment
		(start 279.135078 -91.365578)
		(end 281.407108 -93.637608)
		(width 0.11684)
		(layer "In6.Cu")
		(net "FM_OCP_SFF_PWR_GOOD")
	)
	(segment
		(start 444.015876 -92.19692)
		(end 445.865504 -94.046548)
		(width 0.11684)
		(layer "In6.Cu")
		(net "FM_OCP_SFF_PWR_GOOD")
	)
	(segment
		(start 273.987768 -90.866976)
		(end 274.48637 -91.365578)
		(width 0.11684)
		(layer "In6.Cu")
		(net "FM_OCP_SFF_PWR_GOOD")
	)
	(segment
		(start 234.879896 -94.541594)
		(end 247.017794 -94.541594)
		(width 0.11684)
		(layer "In6.Cu")
		(net "FM_OCP_SFF_PWR_GOOD")
	)
	(segment
		(start 316.369192 -93.637608)
		(end 317.778892 -95.047308)
		(width 0.11684)
		(layer "In6.Cu")
		(net "FM_OCP_SFF_PWR_GOOD")
	)
	(segment
		(start 317.778892 -95.047308)
		(end 414.473644 -95.047308)
		(width 0.11684)
		(layer "In6.Cu")
		(net "FM_OCP_SFF_PWR_GOOD")
	)
	(segment
		(start 274.48637 -91.365578)
		(end 279.135078 -91.365578)
		(width 0.11684)
		(layer "In6.Cu")
		(net "FM_OCP_SFF_PWR_GOOD")
	)
	(segment
		(start 417.324032 -92.19692)
		(end 444.015876 -92.19692)
		(width 0.11684)
		(layer "In6.Cu")
		(net "FM_OCP_SFF_PWR_GOOD")
	)
	(segment
		(start 281.407108 -93.637608)
		(end 316.369192 -93.637608)
		(width 0.11684)
		(layer "In6.Cu")
		(net "FM_OCP_SFF_PWR_GOOD")
	)
	(segment
		(start 247.017794 -94.541594)
		(end 249.107706 -92.451682)
		(width 0.11684)
		(layer "In6.Cu")
		(net "FM_OCP_SFF_PWR_GOOD")
	)
	(segment
		(start 452.856092 -94.046548)
		(end 456.673966 -97.864422)
		(width 0.11684)
		(layer "In6.Cu")
		(net "FM_OCP_SFF_PWR_GOOD")
	)
	(segment
		(start 263.20623 -90.866976)
		(end 273.987768 -90.866976)
		(width 0.11684)
		(layer "In6.Cu")
		(net "FM_OCP_SFF_PWR_GOOD")
	)
	(segment
		(start 254.996696 -92.451682)
		(end 256.0828 -91.365578)
		(width 0.11684)
		(layer "In6.Cu")
		(net "FM_OCP_SFF_PWR_GOOD")
	)
	(segment
		(start 414.473644 -95.047308)
		(end 417.324032 -92.19692)
		(width 0.11684)
		(layer "In6.Cu")
		(net "FM_OCP_SFF_PWR_GOOD")
	)
	(segment
		(start 249.107706 -92.451682)
		(end 254.996696 -92.451682)
		(width 0.11684)
		(layer "In6.Cu")
		(net "FM_OCP_SFF_PWR_GOOD")
	)
	(segment
		(start 452.8566 -12.905994)
		(end 452.8566 -13.8938)
		(width 0.11684)
		(layer "In11.Cu")
		(net "FM_OCP_SFF_PWR_GOOD")
	)
	(segment
		(start 443.041532 -82.831686)
		(end 452.923402 -92.713556)
		(width 0.11684)
		(layer "In11.Cu")
		(net "FM_OCP_SFF_PWR_GOOD")
	)
	(segment
		(start 452.8566 -13.8938)
		(end 456.289156 -17.326356)
		(width 0.11684)
		(layer "In11.Cu")
		(net "FM_OCP_SFF_PWR_GOOD")
	)
	(segment
		(start 433.778152 -36.741608)
		(end 432.31562 -38.20414)
		(width 0.11684)
		(layer "In11.Cu")
		(net "FM_OCP_SFF_PWR_GOOD")
	)
	(segment
		(start 456.289156 -29.320744)
		(end 454.332848 -31.277052)
		(width 0.11684)
		(layer "In11.Cu")
		(net "FM_OCP_SFF_PWR_GOOD")
	)
	(segment
		(start 453.0598 -12.702794)
		(end 452.8566 -12.905994)
		(width 0.11684)
		(layer "In11.Cu")
		(net "FM_OCP_SFF_PWR_GOOD")
	)
	(segment
		(start 421.327834 -48.935386)
		(end 421.327834 -55.360062)
		(width 0.11684)
		(layer "In11.Cu")
		(net "FM_OCP_SFF_PWR_GOOD")
	)
	(segment
		(start 430.038256 -45.023532)
		(end 425.239688 -45.023532)
		(width 0.11684)
		(layer "In11.Cu")
		(net "FM_OCP_SFF_PWR_GOOD")
	)
	(segment
		(start 452.923402 -92.713556)
		(end 452.923402 -94.113858)
		(width 0.11684)
		(layer "In11.Cu")
		(net "FM_OCP_SFF_PWR_GOOD")
	)
	(segment
		(start 421.327834 -58.131456)
		(end 421.327834 -59.530488)
		(width 0.11684)
		(layer "In11.Cu")
		(net "FM_OCP_SFF_PWR_GOOD")
	)
	(segment
		(start 452.923402 -94.113858)
		(end 456.673966 -97.864422)
		(width 0.11684)
		(layer "In11.Cu")
		(net "FM_OCP_SFF_PWR_GOOD")
	)
	(segment
		(start 456.289156 -17.326356)
		(end 456.289156 -29.320744)
		(width 0.11684)
		(layer "In11.Cu")
		(net "FM_OCP_SFF_PWR_GOOD")
	)
	(segment
		(start 421.327834 -55.360062)
		(end 420.892986 -55.79491)
		(width 0.11684)
		(layer "In11.Cu")
		(net "FM_OCP_SFF_PWR_GOOD")
	)
	(segment
		(start 436.456582 -36.741608)
		(end 433.778152 -36.741608)
		(width 0.11684)
		(layer "In11.Cu")
		(net "FM_OCP_SFF_PWR_GOOD")
	)
	(segment
		(start 420.227252 -77.745336)
		(end 425.313602 -82.831686)
		(width 0.11684)
		(layer "In11.Cu")
		(net "FM_OCP_SFF_PWR_GOOD")
	)
	(segment
		(start 436.9816 -36.21659)
		(end 436.456582 -36.741608)
		(width 0.11684)
		(layer "In11.Cu")
		(net "FM_OCP_SFF_PWR_GOOD")
	)
	(segment
		(start 425.313602 -82.831686)
		(end 443.041532 -82.831686)
		(width 0.11684)
		(layer "In11.Cu")
		(net "FM_OCP_SFF_PWR_GOOD")
	)
	(segment
		(start 420.892986 -55.79491)
		(end 420.892986 -57.696608)
		(width 0.11684)
		(layer "In11.Cu")
		(net "FM_OCP_SFF_PWR_GOOD")
	)
	(segment
		(start 425.239688 -45.023532)
		(end 421.327834 -48.935386)
		(width 0.11684)
		(layer "In11.Cu")
		(net "FM_OCP_SFF_PWR_GOOD")
	)
	(segment
		(start 432.31562 -42.746168)
		(end 430.038256 -45.023532)
		(width 0.11684)
		(layer "In11.Cu")
		(net "FM_OCP_SFF_PWR_GOOD")
	)
	(segment
		(start 420.892986 -57.696608)
		(end 421.327834 -58.131456)
		(width 0.11684)
		(layer "In11.Cu")
		(net "FM_OCP_SFF_PWR_GOOD")
	)
	(segment
		(start 454.332848 -31.277052)
		(end 454.332848 -34.932112)
		(width 0.11684)
		(layer "In11.Cu")
		(net "FM_OCP_SFF_PWR_GOOD")
	)
	(segment
		(start 420.227252 -60.63107)
		(end 420.227252 -77.745336)
		(width 0.11684)
		(layer "In11.Cu")
		(net "FM_OCP_SFF_PWR_GOOD")
	)
	(segment
		(start 454.332848 -34.932112)
		(end 453.04837 -36.21659)
		(width 0.11684)
		(layer "In11.Cu")
		(net "FM_OCP_SFF_PWR_GOOD")
	)
	(segment
		(start 421.327834 -59.530488)
		(end 420.227252 -60.63107)
		(width 0.11684)
		(layer "In11.Cu")
		(net "FM_OCP_SFF_PWR_GOOD")
	)
	(segment
		(start 453.04837 -36.21659)
		(end 436.9816 -36.21659)
		(width 0.11684)
		(layer "In11.Cu")
		(net "FM_OCP_SFF_PWR_GOOD")
	)
	(segment
		(start 432.31562 -38.20414)
		(end 432.31562 -42.746168)
		(width 0.11684)
		(layer "In11.Cu")
		(net "FM_OCP_SFF_PWR_GOOD")
	)
	(segment
		(start 184.850532 -93.690948)
		(end 185.488834 -93.052646)
		(width 0.11684)
		(layer "In15.Cu")
		(net "FM_OCP_SFF_PWR_GOOD")
	)
	(segment
		(start 184.801256 -93.690948)
		(end 184.850532 -93.690948)
		(width 0.11684)
		(layer "In15.Cu")
		(net "FM_OCP_SFF_PWR_GOOD")
	)
	(segment
		(start 234.997244 -91.171522)
		(end 235.252006 -91.426284)
		(width 0.11684)
		(layer "In15.Cu")
		(net "FM_OCP_SFF_PWR_GOOD")
	)
	(segment
		(start 188.979302 -90.756232)
		(end 196.22389 -90.756232)
		(width 0.11684)
		(layer "In15.Cu")
		(net "FM_OCP_SFF_PWR_GOOD")
	)
	(segment
		(start 235.252006 -91.426284)
		(end 235.252006 -94.169484)
		(width 0.11684)
		(layer "In15.Cu")
		(net "FM_OCP_SFF_PWR_GOOD")
	)
	(segment
		(start 196.22389 -90.756232)
		(end 197.755002 -92.287344)
		(width 0.11684)
		(layer "In15.Cu")
		(net "FM_OCP_SFF_PWR_GOOD")
	)
	(segment
		(start 197.755002 -92.287344)
		(end 204.208888 -92.287344)
		(width 0.11684)
		(layer "In15.Cu")
		(net "FM_OCP_SFF_PWR_GOOD")
	)
	(segment
		(start 185.488834 -93.052646)
		(end 186.682888 -93.052646)
		(width 0.11684)
		(layer "In15.Cu")
		(net "FM_OCP_SFF_PWR_GOOD")
	)
	(segment
		(start 204.208888 -92.287344)
		(end 205.32471 -91.171522)
		(width 0.11684)
		(layer "In15.Cu")
		(net "FM_OCP_SFF_PWR_GOOD")
	)
	(segment
		(start 205.32471 -91.171522)
		(end 234.997244 -91.171522)
		(width 0.11684)
		(layer "In15.Cu")
		(net "FM_OCP_SFF_PWR_GOOD")
	)
	(segment
		(start 186.682888 -93.052646)
		(end 188.979302 -90.756232)
		(width 0.11684)
		(layer "In15.Cu")
		(net "FM_OCP_SFF_PWR_GOOD")
	)
	(segment
		(start 235.252006 -94.169484)
		(end 234.879896 -94.541594)
		(width 0.11684)
		(layer "In15.Cu")
		(net "FM_OCP_SFF_PWR_GOOD")
	)
	(segment
		(start 49.78273 -35.804348)
		(end 51.317652 -35.804348)
		(width 0.10668)
		(layer "F.Cu")
		(net "FM_NCSI_OCP_V3_2_R_OE")
	)
	(segment
		(start 189.92215 -118.652798)
		(end 190.31204 -119.042688)
		(width 0.10668)
		(layer "F.Cu")
		(net "FM_NCSI_OCP_V3_2_R_OE")
	)
	(segment
		(start 51.317652 -35.804348)
		(end 51.838352 -35.283648)
		(width 0.10668)
		(layer "F.Cu")
		(net "FM_NCSI_OCP_V3_2_R_OE")
	)
	(via
		(at 51.838352 -35.283648)
		(size 0.762)
		(drill 0.254)
		(layers "F.Cu" "B.Cu")
		(net "FM_NCSI_OCP_V3_2_R_OE")
	)
	(via
		(at 173.058582 -53.930804)
		(size 0.508)
		(drill 0.254)
		(layers "F.Cu" "B.Cu")
		(net "FM_NCSI_OCP_V3_2_R_OE")
	)
	(via
		(at 190.31204 -119.042688)
		(size 0.4572)
		(drill 0.254)
		(layers "F.Cu" "B.Cu")
		(net "FM_NCSI_OCP_V3_2_R_OE")
	)
	(segment
		(start 118.20144 -54.766464)
		(end 118.827804 -55.392828)
		(width 0.11684)
		(layer "In6.Cu")
		(net "FM_NCSI_OCP_V3_2_R_OE")
	)
	(segment
		(start 66.8655 -39.931848)
		(end 71.46036 -39.931848)
		(width 0.11684)
		(layer "In6.Cu")
		(net "FM_NCSI_OCP_V3_2_R_OE")
	)
	(segment
		(start 148.654008 -53.661818)
		(end 148.654008 -52.9844)
		(width 0.11684)
		(layer "In6.Cu")
		(net "FM_NCSI_OCP_V3_2_R_OE")
	)
	(segment
		(start 165.61816 -51.27371)
		(end 168.837102 -51.27371)
		(width 0.11684)
		(layer "In6.Cu")
		(net "FM_NCSI_OCP_V3_2_R_OE")
	)
	(segment
		(start 64.39916 -38.75278)
		(end 65.686432 -38.75278)
		(width 0.11684)
		(layer "In6.Cu")
		(net "FM_NCSI_OCP_V3_2_R_OE")
	)
	(segment
		(start 136.4996 -54.79288)
		(end 136.74725 -54.54523)
		(width 0.11684)
		(layer "In6.Cu")
		(net "FM_NCSI_OCP_V3_2_R_OE")
	)
	(segment
		(start 61.54674 -39.378128)
		(end 63.773812 -39.378128)
		(width 0.11684)
		(layer "In6.Cu")
		(net "FM_NCSI_OCP_V3_2_R_OE")
	)
	(segment
		(start 72.76084 -41.232328)
		(end 76.7207 -41.232328)
		(width 0.11684)
		(layer "In6.Cu")
		(net "FM_NCSI_OCP_V3_2_R_OE")
	)
	(segment
		(start 128.788414 -54.79288)
		(end 136.4996 -54.79288)
		(width 0.11684)
		(layer "In6.Cu")
		(net "FM_NCSI_OCP_V3_2_R_OE")
	)
	(segment
		(start 127.860552 -54.314598)
		(end 128.310132 -54.314598)
		(width 0.11684)
		(layer "In6.Cu")
		(net "FM_NCSI_OCP_V3_2_R_OE")
	)
	(segment
		(start 162.41649 -51.92522)
		(end 164.96665 -51.92522)
		(width 0.11684)
		(layer "In6.Cu")
		(net "FM_NCSI_OCP_V3_2_R_OE")
	)
	(segment
		(start 128.310132 -54.314598)
		(end 128.788414 -54.79288)
		(width 0.11684)
		(layer "In6.Cu")
		(net "FM_NCSI_OCP_V3_2_R_OE")
	)
	(segment
		(start 71.46036 -39.931848)
		(end 72.76084 -41.232328)
		(width 0.11684)
		(layer "In6.Cu")
		(net "FM_NCSI_OCP_V3_2_R_OE")
	)
	(segment
		(start 88.178132 -52.68976)
		(end 102.193344 -52.68976)
		(width 0.11684)
		(layer "In6.Cu")
		(net "FM_NCSI_OCP_V3_2_R_OE")
	)
	(segment
		(start 148.654008 -52.9844)
		(end 150.364698 -51.27371)
		(width 0.11684)
		(layer "In6.Cu")
		(net "FM_NCSI_OCP_V3_2_R_OE")
	)
	(segment
		(start 173.026578 -53.8988)
		(end 173.058582 -53.930804)
		(width 0.11684)
		(layer "In6.Cu")
		(net "FM_NCSI_OCP_V3_2_R_OE")
	)
	(segment
		(start 168.837102 -51.27371)
		(end 170.768518 -53.205126)
		(width 0.11684)
		(layer "In6.Cu")
		(net "FM_NCSI_OCP_V3_2_R_OE")
	)
	(segment
		(start 147.770596 -54.54523)
		(end 148.654008 -53.661818)
		(width 0.11684)
		(layer "In6.Cu")
		(net "FM_NCSI_OCP_V3_2_R_OE")
	)
	(segment
		(start 118.827804 -55.392828)
		(end 126.782322 -55.392828)
		(width 0.11684)
		(layer "In6.Cu")
		(net "FM_NCSI_OCP_V3_2_R_OE")
	)
	(segment
		(start 171.601892 -53.205126)
		(end 172.295566 -53.8988)
		(width 0.11684)
		(layer "In6.Cu")
		(net "FM_NCSI_OCP_V3_2_R_OE")
	)
	(segment
		(start 172.295566 -53.8988)
		(end 173.026578 -53.8988)
		(width 0.11684)
		(layer "In6.Cu")
		(net "FM_NCSI_OCP_V3_2_R_OE")
	)
	(segment
		(start 164.96665 -51.92522)
		(end 165.61816 -51.27371)
		(width 0.11684)
		(layer "In6.Cu")
		(net "FM_NCSI_OCP_V3_2_R_OE")
	)
	(segment
		(start 54.892956 -38.1)
		(end 60.268612 -38.1)
		(width 0.11684)
		(layer "In6.Cu")
		(net "FM_NCSI_OCP_V3_2_R_OE")
	)
	(segment
		(start 136.74725 -54.54523)
		(end 147.770596 -54.54523)
		(width 0.11684)
		(layer "In6.Cu")
		(net "FM_NCSI_OCP_V3_2_R_OE")
	)
	(segment
		(start 76.7207 -41.232328)
		(end 88.178132 -52.68976)
		(width 0.11684)
		(layer "In6.Cu")
		(net "FM_NCSI_OCP_V3_2_R_OE")
	)
	(segment
		(start 51.838352 -35.283648)
		(end 52.076604 -35.283648)
		(width 0.11684)
		(layer "In6.Cu")
		(net "FM_NCSI_OCP_V3_2_R_OE")
	)
	(segment
		(start 63.773812 -39.378128)
		(end 64.39916 -38.75278)
		(width 0.11684)
		(layer "In6.Cu")
		(net "FM_NCSI_OCP_V3_2_R_OE")
	)
	(segment
		(start 60.268612 -38.1)
		(end 61.54674 -39.378128)
		(width 0.11684)
		(layer "In6.Cu")
		(net "FM_NCSI_OCP_V3_2_R_OE")
	)
	(segment
		(start 161.76498 -51.27371)
		(end 162.41649 -51.92522)
		(width 0.11684)
		(layer "In6.Cu")
		(net "FM_NCSI_OCP_V3_2_R_OE")
	)
	(segment
		(start 126.782322 -55.392828)
		(end 127.860552 -54.314598)
		(width 0.11684)
		(layer "In6.Cu")
		(net "FM_NCSI_OCP_V3_2_R_OE")
	)
	(segment
		(start 170.768518 -53.205126)
		(end 171.601892 -53.205126)
		(width 0.11684)
		(layer "In6.Cu")
		(net "FM_NCSI_OCP_V3_2_R_OE")
	)
	(segment
		(start 52.076604 -35.283648)
		(end 54.892956 -38.1)
		(width 0.11684)
		(layer "In6.Cu")
		(net "FM_NCSI_OCP_V3_2_R_OE")
	)
	(segment
		(start 104.270048 -54.766464)
		(end 118.20144 -54.766464)
		(width 0.11684)
		(layer "In6.Cu")
		(net "FM_NCSI_OCP_V3_2_R_OE")
	)
	(segment
		(start 150.364698 -51.27371)
		(end 161.76498 -51.27371)
		(width 0.11684)
		(layer "In6.Cu")
		(net "FM_NCSI_OCP_V3_2_R_OE")
	)
	(segment
		(start 102.193344 -52.68976)
		(end 104.270048 -54.766464)
		(width 0.11684)
		(layer "In6.Cu")
		(net "FM_NCSI_OCP_V3_2_R_OE")
	)
	(segment
		(start 65.686432 -38.75278)
		(end 66.8655 -39.931848)
		(width 0.11684)
		(layer "In6.Cu")
		(net "FM_NCSI_OCP_V3_2_R_OE")
	)
	(segment
		(start 189.3697 -104.433624)
		(end 189.3697 -93.414088)
		(width 0.11684)
		(layer "In11.Cu")
		(net "FM_NCSI_OCP_V3_2_R_OE")
	)
	(segment
		(start 171.623482 -60.881006)
		(end 174.81804 -57.686448)
		(width 0.11684)
		(layer "In11.Cu")
		(net "FM_NCSI_OCP_V3_2_R_OE")
	)
	(segment
		(start 174.81804 -57.686448)
		(end 174.81804 -55.865268)
		(width 0.11684)
		(layer "In11.Cu")
		(net "FM_NCSI_OCP_V3_2_R_OE")
	)
	(segment
		(start 182.357522 -89.58961)
		(end 181.104286 -88.336374)
		(width 0.11684)
		(layer "In11.Cu")
		(net "FM_NCSI_OCP_V3_2_R_OE")
	)
	(segment
		(start 181.104286 -86.472522)
		(end 176.69637 -82.064606)
		(width 0.11684)
		(layer "In11.Cu")
		(net "FM_NCSI_OCP_V3_2_R_OE")
	)
	(segment
		(start 176.209198 -82.064606)
		(end 171.623482 -77.47889)
		(width 0.11684)
		(layer "In11.Cu")
		(net "FM_NCSI_OCP_V3_2_R_OE")
	)
	(segment
		(start 176.69637 -82.064606)
		(end 176.209198 -82.064606)
		(width 0.11684)
		(layer "In11.Cu")
		(net "FM_NCSI_OCP_V3_2_R_OE")
	)
	(segment
		(start 181.104286 -88.336374)
		(end 181.104286 -86.472522)
		(width 0.11684)
		(layer "In11.Cu")
		(net "FM_NCSI_OCP_V3_2_R_OE")
	)
	(segment
		(start 174.81804 -55.865268)
		(end 173.058582 -54.10581)
		(width 0.11684)
		(layer "In11.Cu")
		(net "FM_NCSI_OCP_V3_2_R_OE")
	)
	(segment
		(start 185.545222 -89.58961)
		(end 182.357522 -89.58961)
		(width 0.11684)
		(layer "In11.Cu")
		(net "FM_NCSI_OCP_V3_2_R_OE")
	)
	(segment
		(start 173.058582 -54.10581)
		(end 173.058582 -53.930804)
		(width 0.11684)
		(layer "In11.Cu")
		(net "FM_NCSI_OCP_V3_2_R_OE")
	)
	(segment
		(start 171.623482 -77.47889)
		(end 171.623482 -60.881006)
		(width 0.11684)
		(layer "In11.Cu")
		(net "FM_NCSI_OCP_V3_2_R_OE")
	)
	(segment
		(start 189.3697 -93.414088)
		(end 185.545222 -89.58961)
		(width 0.11684)
		(layer "In11.Cu")
		(net "FM_NCSI_OCP_V3_2_R_OE")
	)
	(segment
		(start 190.31204 -119.042688)
		(end 189.90056 -118.631208)
		(width 0.11684)
		(layer "In11.Cu")
		(net "FM_NCSI_OCP_V3_2_R_OE")
	)
	(segment
		(start 189.90056 -104.964484)
		(end 189.3697 -104.433624)
		(width 0.11684)
		(layer "In11.Cu")
		(net "FM_NCSI_OCP_V3_2_R_OE")
	)
	(segment
		(start 189.90056 -118.631208)
		(end 189.90056 -104.964484)
		(width 0.11684)
		(layer "In11.Cu")
		(net "FM_NCSI_OCP_V3_2_R_OE")
	)
	(segment
		(start 463.065876 -96.406208)
		(end 461.43926 -96.406208)
		(width 0.10668)
		(layer "F.Cu")
		(net "FM_NCSI_OCP_SFF_R_OE")
	)
	(segment
		(start 457.082652 -89.731088)
		(end 439.777124 -89.731088)
		(width 0.10668)
		(layer "F.Cu")
		(net "FM_NCSI_OCP_SFF_R_OE")
	)
	(segment
		(start 459.304898 -94.271846)
		(end 459.304898 -91.953334)
		(width 0.10668)
		(layer "F.Cu")
		(net "FM_NCSI_OCP_SFF_R_OE")
	)
	(segment
		(start 459.304898 -91.953334)
		(end 457.082652 -89.731088)
		(width 0.10668)
		(layer "F.Cu")
		(net "FM_NCSI_OCP_SFF_R_OE")
	)
	(segment
		(start 439.777124 -89.731088)
		(end 438.237376 -91.270836)
		(width 0.10668)
		(layer "F.Cu")
		(net "FM_NCSI_OCP_SFF_R_OE")
	)
	(segment
		(start 461.43926 -96.406208)
		(end 459.304898 -94.271846)
		(width 0.10668)
		(layer "F.Cu")
		(net "FM_NCSI_OCP_SFF_R_OE")
	)
	(via
		(at 259.759196 -90.893392)
		(size 0.508)
		(drill 0.254)
		(layers "F.Cu" "B.Cu")
		(net "FM_NCSI_OCP_SFF_R_OE")
	)
	(via
		(at 253.710186 -111.033814)
		(size 0.508)
		(drill 0.254)
		(layers "F.Cu" "B.Cu")
		(net "FM_NCSI_OCP_SFF_R_OE")
	)
	(via
		(at 438.237376 -91.270836)
		(size 0.508)
		(drill 0.254)
		(layers "F.Cu" "B.Cu")
		(net "FM_NCSI_OCP_SFF_R_OE")
	)
	(via
		(at 214.07755 -113.979706)
		(size 0.508)
		(drill 0.254)
		(layers "F.Cu" "B.Cu")
		(net "FM_NCSI_OCP_SFF_R_OE")
	)
	(segment
		(start 207.879442 -113.71326)
		(end 209.427826 -112.164876)
		(width 0.10668)
		(layer "B.Cu")
		(net "FM_NCSI_OCP_SFF_R_OE")
	)
	(segment
		(start 203.455778 -113.71326)
		(end 207.879442 -113.71326)
		(width 0.10668)
		(layer "B.Cu")
		(net "FM_NCSI_OCP_SFF_R_OE")
	)
	(segment
		(start 203.066142 -114.102896)
		(end 203.455778 -113.71326)
		(width 0.10668)
		(layer "B.Cu")
		(net "FM_NCSI_OCP_SFF_R_OE")
	)
	(segment
		(start 198.01967 -113.153952)
		(end 199.008492 -113.153952)
		(width 0.10668)
		(layer "B.Cu")
		(net "FM_NCSI_OCP_SFF_R_OE")
	)
	(segment
		(start 199.008492 -113.153952)
		(end 199.206866 -112.955578)
		(width 0.10668)
		(layer "B.Cu")
		(net "FM_NCSI_OCP_SFF_R_OE")
	)
	(segment
		(start 199.458072 -112.073436)
		(end 200.387458 -112.073436)
		(width 0.10668)
		(layer "B.Cu")
		(net "FM_NCSI_OCP_SFF_R_OE")
	)
	(segment
		(start 201.422 -113.107978)
		(end 201.422 -113.544096)
		(width 0.10668)
		(layer "B.Cu")
		(net "FM_NCSI_OCP_SFF_R_OE")
	)
	(segment
		(start 201.422 -113.544096)
		(end 201.9808 -114.102896)
		(width 0.10668)
		(layer "B.Cu")
		(net "FM_NCSI_OCP_SFF_R_OE")
	)
	(segment
		(start 201.9808 -114.102896)
		(end 203.066142 -114.102896)
		(width 0.10668)
		(layer "B.Cu")
		(net "FM_NCSI_OCP_SFF_R_OE")
	)
	(segment
		(start 197.402958 -113.427256)
		(end 197.746366 -113.427256)
		(width 0.10668)
		(layer "B.Cu")
		(net "FM_NCSI_OCP_SFF_R_OE")
	)
	(segment
		(start 199.206866 -112.324642)
		(end 199.458072 -112.073436)
		(width 0.10668)
		(layer "B.Cu")
		(net "FM_NCSI_OCP_SFF_R_OE")
	)
	(segment
		(start 212.26272 -112.164876)
		(end 214.07755 -113.979706)
		(width 0.10668)
		(layer "B.Cu")
		(net "FM_NCSI_OCP_SFF_R_OE")
	)
	(segment
		(start 200.387458 -112.073436)
		(end 201.422 -113.107978)
		(width 0.10668)
		(layer "B.Cu")
		(net "FM_NCSI_OCP_SFF_R_OE")
	)
	(segment
		(start 197.746366 -113.427256)
		(end 198.01967 -113.153952)
		(width 0.10668)
		(layer "B.Cu")
		(net "FM_NCSI_OCP_SFF_R_OE")
	)
	(segment
		(start 209.427826 -112.164876)
		(end 212.26272 -112.164876)
		(width 0.10668)
		(layer "B.Cu")
		(net "FM_NCSI_OCP_SFF_R_OE")
	)
	(segment
		(start 199.206866 -112.955578)
		(end 199.206866 -112.324642)
		(width 0.10668)
		(layer "B.Cu")
		(net "FM_NCSI_OCP_SFF_R_OE")
	)
	(segment
		(start 258.873498 -101.977698)
		(end 259.759196 -101.092)
		(width 0.11684)
		(layer "In4.Cu")
		(net "FM_NCSI_OCP_SFF_R_OE")
	)
	(segment
		(start 259.759196 -101.092)
		(end 259.759196 -90.893392)
		(width 0.11684)
		(layer "In4.Cu")
		(net "FM_NCSI_OCP_SFF_R_OE")
	)
	(segment
		(start 253.710186 -111.033814)
		(end 253.710186 -110.383574)
		(width 0.11684)
		(layer "In4.Cu")
		(net "FM_NCSI_OCP_SFF_R_OE")
	)
	(segment
		(start 258.873498 -105.220262)
		(end 258.873498 -101.977698)
		(width 0.11684)
		(layer "In4.Cu")
		(net "FM_NCSI_OCP_SFF_R_OE")
	)
	(segment
		(start 253.710186 -110.383574)
		(end 258.873498 -105.220262)
		(width 0.11684)
		(layer "In4.Cu")
		(net "FM_NCSI_OCP_SFF_R_OE")
	)
	(segment
		(start 215.331294 -112.725962)
		(end 247.323864 -112.725962)
		(width 0.11684)
		(layer "In6.Cu")
		(net "FM_NCSI_OCP_SFF_R_OE")
	)
	(segment
		(start 263.010396 -90.39479)
		(end 274.183602 -90.39479)
		(width 0.11684)
		(layer "In6.Cu")
		(net "FM_NCSI_OCP_SFF_R_OE")
	)
	(segment
		(start 247.323864 -112.725962)
		(end 248.803414 -111.246412)
		(width 0.11684)
		(layer "In6.Cu")
		(net "FM_NCSI_OCP_SFF_R_OE")
	)
	(segment
		(start 274.682204 -90.893392)
		(end 314.81776 -90.893392)
		(width 0.11684)
		(layer "In6.Cu")
		(net "FM_NCSI_OCP_SFF_R_OE")
	)
	(segment
		(start 314.81776 -90.893392)
		(end 318.128396 -94.204028)
		(width 0.11684)
		(layer "In6.Cu")
		(net "FM_NCSI_OCP_SFF_R_OE")
	)
	(segment
		(start 274.183602 -90.39479)
		(end 274.682204 -90.893392)
		(width 0.11684)
		(layer "In6.Cu")
		(net "FM_NCSI_OCP_SFF_R_OE")
	)
	(segment
		(start 262.511794 -90.893392)
		(end 263.010396 -90.39479)
		(width 0.11684)
		(layer "In6.Cu")
		(net "FM_NCSI_OCP_SFF_R_OE")
	)
	(segment
		(start 248.803414 -111.246412)
		(end 253.497588 -111.246412)
		(width 0.11684)
		(layer "In6.Cu")
		(net "FM_NCSI_OCP_SFF_R_OE")
	)
	(segment
		(start 253.497588 -111.246412)
		(end 253.710186 -111.033814)
		(width 0.11684)
		(layer "In6.Cu")
		(net "FM_NCSI_OCP_SFF_R_OE")
	)
	(segment
		(start 414.12414 -94.204028)
		(end 417.057332 -91.270836)
		(width 0.11684)
		(layer "In6.Cu")
		(net "FM_NCSI_OCP_SFF_R_OE")
	)
	(segment
		(start 214.07755 -113.979706)
		(end 215.331294 -112.725962)
		(width 0.11684)
		(layer "In6.Cu")
		(net "FM_NCSI_OCP_SFF_R_OE")
	)
	(segment
		(start 259.759196 -90.893392)
		(end 262.511794 -90.893392)
		(width 0.11684)
		(layer "In6.Cu")
		(net "FM_NCSI_OCP_SFF_R_OE")
	)
	(segment
		(start 417.057332 -91.270836)
		(end 438.237376 -91.270836)
		(width 0.11684)
		(layer "In6.Cu")
		(net "FM_NCSI_OCP_SFF_R_OE")
	)
	(segment
		(start 318.128396 -94.204028)
		(end 414.12414 -94.204028)
		(width 0.11684)
		(layer "In6.Cu")
		(net "FM_NCSI_OCP_SFF_R_OE")
	)
	(segment
		(start 180.454554 -38.738048)
		(end 180.454554 -39.988744)
		(width 0.10668)
		(layer "F.Cu")
		(net "FM_M2_SSD_0_PEDET")
	)
	(segment
		(start 180.454554 -39.988744)
		(end 180.37175 -40.071548)
		(width 0.10668)
		(layer "F.Cu")
		(net "FM_M2_SSD_0_PEDET")
	)
	(segment
		(start 177.108358 -39.299896)
		(end 179.892706 -39.299896)
		(width 0.10668)
		(layer "F.Cu")
		(net "FM_M2_SSD_0_PEDET")
	)
	(segment
		(start 179.892706 -39.299896)
		(end 180.454554 -38.738048)
		(width 0.10668)
		(layer "F.Cu")
		(net "FM_M2_SSD_0_PEDET")
	)
	(via
		(at 180.454554 -38.738048)
		(size 0.762)
		(drill 0.381)
		(layers "F.Cu" "B.Cu")
		(net "FM_M2_SSD_0_PEDET")
	)
	(segment
		(start 174.066962 -16.549878)
		(end 174.066962 -17.664176)
		(width 0.10668)
		(layer "F.Cu")
		(net "FM_LPC_ESPI_SEL")
	)
	(segment
		(start 174.066962 -17.664176)
		(end 174.188374 -17.785588)
		(width 0.10668)
		(layer "F.Cu")
		(net "FM_LPC_ESPI_SEL")
	)
	(via
		(at 174.188374 -17.785588)
		(size 0.508)
		(drill 0.254)
		(layers "F.Cu" "B.Cu")
		(net "FM_LPC_ESPI_SEL")
	)
	(via
		(at 174.75962 -19.40052)
		(size 0.6604)
		(drill 0.3302)
		(layers "F.Cu" "B.Cu")
		(net "FM_LPC_ESPI_SEL")
	)
	(segment
		(start 174.188374 -18.829274)
		(end 174.75962 -19.40052)
		(width 0.10668)
		(layer "B.Cu")
		(net "FM_LPC_ESPI_SEL")
	)
	(segment
		(start 173.805088 -19.40052)
		(end 173.613826 -19.209258)
		(width 0.10668)
		(layer "B.Cu")
		(net "FM_LPC_ESPI_SEL")
	)
	(segment
		(start 174.188374 -17.785588)
		(end 174.188374 -18.829274)
		(width 0.10668)
		(layer "B.Cu")
		(net "FM_LPC_ESPI_SEL")
	)
	(segment
		(start 174.75962 -19.40052)
		(end 173.805088 -19.40052)
		(width 0.10668)
		(layer "B.Cu")
		(net "FM_LPC_ESPI_SEL")
	)
	(segment
		(start 188.322204 -123.45289)
		(end 188.712094 -123.84278)
		(width 0.10668)
		(layer "F.Cu")
		(net "FM_JTAG_BMC_OE")
	)
	(segment
		(start 199.806052 -128.778)
		(end 199.669908 -128.914144)
		(width 0.10668)
		(layer "F.Cu")
		(net "FM_JTAG_BMC_OE")
	)
	(segment
		(start 200.64095 -128.778)
		(end 199.806052 -128.778)
		(width 0.10668)
		(layer "F.Cu")
		(net "FM_JTAG_BMC_OE")
	)
	(via
		(at 199.669908 -128.914144)
		(size 0.508)
		(drill 0.254)
		(layers "F.Cu" "B.Cu")
		(net "FM_JTAG_BMC_OE")
	)
	(via
		(at 188.712094 -123.84278)
		(size 0.4572)
		(drill 0.254)
		(layers "F.Cu" "B.Cu")
		(net "FM_JTAG_BMC_OE")
	)
	(segment
		(start 188.712094 -123.84278)
		(end 188.73597 -123.84278)
		(width 0.11684)
		(layer "In15.Cu")
		(net "FM_JTAG_BMC_OE")
	)
	(segment
		(start 189.235842 -124.342652)
		(end 189.235842 -126.589028)
		(width 0.11684)
		(layer "In15.Cu")
		(net "FM_JTAG_BMC_OE")
	)
	(segment
		(start 196.394324 -128.914144)
		(end 199.669908 -128.914144)
		(width 0.11684)
		(layer "In15.Cu")
		(net "FM_JTAG_BMC_OE")
	)
	(segment
		(start 188.73597 -123.84278)
		(end 189.235842 -124.342652)
		(width 0.11684)
		(layer "In15.Cu")
		(net "FM_JTAG_BMC_OE")
	)
	(segment
		(start 189.235842 -126.589028)
		(end 189.72022 -127.073406)
		(width 0.11684)
		(layer "In15.Cu")
		(net "FM_JTAG_BMC_OE")
	)
	(segment
		(start 194.553586 -127.073406)
		(end 196.394324 -128.914144)
		(width 0.11684)
		(layer "In15.Cu")
		(net "FM_JTAG_BMC_OE")
	)
	(segment
		(start 189.72022 -127.073406)
		(end 194.553586 -127.073406)
		(width 0.11684)
		(layer "In15.Cu")
		(net "FM_JTAG_BMC_OE")
	)
	(segment
		(start 145.94713 -13.599922)
		(end 145.94713 -12.295632)
		(width 0.10668)
		(layer "F.Cu")
		(net "FW_RECOVERY")
	)
	(segment
		(start 145.94713 -12.295632)
		(end 146.134074 -12.108688)
		(width 0.10668)
		(layer "F.Cu")
		(net "FW_RECOVERY")
	)
	(via
		(at 146.134074 -12.108688)
		(size 0.508)
		(drill 0.254)
		(layers "F.Cu" "B.Cu")
		(net "FW_RECOVERY")
	)
	(segment
		(start 146.134074 -13.151612)
		(end 146.3548 -13.372338)
		(width 0.10668)
		(layer "B.Cu")
		(net "FW_RECOVERY")
	)
	(segment
		(start 146.134074 -12.108688)
		(end 146.134074 -13.151612)
		(width 0.10668)
		(layer "B.Cu")
		(net "FW_RECOVERY")
	)
	(segment
		(start 183.522112 -108.252768)
		(end 183.132222 -107.862878)
		(width 0.10668)
		(layer "F.Cu")
		(net "FM_INT_CPU0_HP_UBM_R_N")
	)
	(via
		(at 182.906162 -103.241348)
		(size 0.6604)
		(drill 0.3302)
		(layers "F.Cu" "B.Cu")
		(net "FM_INT_CPU0_HP_UBM_R_N")
	)
	(via
		(at 183.132222 -107.862878)
		(size 0.4572)
		(drill 0.254)
		(layers "F.Cu" "B.Cu")
		(net "FM_INT_CPU0_HP_UBM_R_N")
	)
	(segment
		(start 182.728362 -107.459018)
		(end 183.132222 -107.862878)
		(width 0.10668)
		(layer "B.Cu")
		(net "FM_INT_CPU0_HP_UBM_R_N")
	)
	(segment
		(start 182.906162 -101.884988)
		(end 182.753 -101.731826)
		(width 0.10668)
		(layer "B.Cu")
		(net "FM_INT_CPU0_HP_UBM_R_N")
	)
	(segment
		(start 182.906162 -103.794052)
		(end 183.238902 -104.126792)
		(width 0.10668)
		(layer "B.Cu")
		(net "FM_INT_CPU0_HP_UBM_R_N")
	)
	(segment
		(start 182.753 -101.731826)
		(end 182.753 -100.694998)
		(width 0.10668)
		(layer "B.Cu")
		(net "FM_INT_CPU0_HP_UBM_R_N")
	)
	(segment
		(start 182.906162 -103.241348)
		(end 182.906162 -101.884988)
		(width 0.10668)
		(layer "B.Cu")
		(net "FM_INT_CPU0_HP_UBM_R_N")
	)
	(segment
		(start 182.906162 -103.241348)
		(end 182.906162 -103.794052)
		(width 0.10668)
		(layer "B.Cu")
		(net "FM_INT_CPU0_HP_UBM_R_N")
	)
	(segment
		(start 183.238902 -105.586022)
		(end 182.728362 -106.096562)
		(width 0.10668)
		(layer "B.Cu")
		(net "FM_INT_CPU0_HP_UBM_R_N")
	)
	(segment
		(start 182.728362 -106.096562)
		(end 182.728362 -107.459018)
		(width 0.10668)
		(layer "B.Cu")
		(net "FM_INT_CPU0_HP_UBM_R_N")
	)
	(segment
		(start 183.238902 -104.126792)
		(end 183.238902 -105.586022)
		(width 0.10668)
		(layer "B.Cu")
		(net "FM_INT_CPU0_HP_UBM_R_N")
	)
	(segment
		(start 265.017758 -114.99596)
		(end 264.989564 -115.024154)
		(width 0.10668)
		(layer "F.Cu")
		(net "FM_INT_CPU0_HP_UBM_N")
	)
	(segment
		(start 264.989564 -115.024154)
		(end 264.989564 -125.526546)
		(width 0.10668)
		(layer "F.Cu")
		(net "FM_INT_CPU0_HP_UBM_N")
	)
	(segment
		(start 264.929366 -148.315934)
		(end 264.929366 -186.127644)
		(width 0.10668)
		(layer "F.Cu")
		(net "FM_INT_CPU0_HP_UBM_N")
	)
	(segment
		(start 265.773154 -144.907254)
		(end 265.773154 -147.472146)
		(width 0.10668)
		(layer "F.Cu")
		(net "FM_INT_CPU0_HP_UBM_N")
	)
	(segment
		(start 264.989564 -125.526546)
		(end 267.54963 -128.086612)
		(width 0.10668)
		(layer "F.Cu")
		(net "FM_INT_CPU0_HP_UBM_N")
	)
	(segment
		(start 344.226388 -304.942494)
		(end 344.755216 -304.942494)
		(width 0.10668)
		(layer "F.Cu")
		(net "FM_INT_CPU0_HP_UBM_N")
	)
	(segment
		(start 346.1893 -303.50841)
		(end 352.465894 -303.50841)
		(width 0.10668)
		(layer "F.Cu")
		(net "FM_INT_CPU0_HP_UBM_N")
	)
	(segment
		(start 267.54963 -143.130778)
		(end 265.773154 -144.907254)
		(width 0.10668)
		(layer "F.Cu")
		(net "FM_INT_CPU0_HP_UBM_N")
	)
	(segment
		(start 264.929366 -186.127644)
		(end 264.766806 -186.290204)
		(width 0.10668)
		(layer "F.Cu")
		(net "FM_INT_CPU0_HP_UBM_N")
	)
	(segment
		(start 344.755216 -304.942494)
		(end 346.1893 -303.50841)
		(width 0.10668)
		(layer "F.Cu")
		(net "FM_INT_CPU0_HP_UBM_N")
	)
	(segment
		(start 360.284268 -295.690036)
		(end 362.368084 -295.690036)
		(width 0.10668)
		(layer "F.Cu")
		(net "FM_INT_CPU0_HP_UBM_N")
	)
	(segment
		(start 265.773154 -147.472146)
		(end 264.929366 -148.315934)
		(width 0.10668)
		(layer "F.Cu")
		(net "FM_INT_CPU0_HP_UBM_N")
	)
	(segment
		(start 267.54963 -128.086612)
		(end 267.54963 -143.130778)
		(width 0.10668)
		(layer "F.Cu")
		(net "FM_INT_CPU0_HP_UBM_N")
	)
	(segment
		(start 352.465894 -303.50841)
		(end 360.284268 -295.690036)
		(width 0.10668)
		(layer "F.Cu")
		(net "FM_INT_CPU0_HP_UBM_N")
	)
	(via
		(at 182.753 -99.278948)
		(size 0.508)
		(drill 0.254)
		(layers "F.Cu" "B.Cu")
		(net "FM_INT_CPU0_HP_UBM_N")
	)
	(via
		(at 344.226388 -304.942494)
		(size 0.508)
		(drill 0.254)
		(layers "F.Cu" "B.Cu")
		(net "FM_INT_CPU0_HP_UBM_N")
	)
	(via
		(at 265.017758 -114.99596)
		(size 0.508)
		(drill 0.254)
		(layers "F.Cu" "B.Cu")
		(net "FM_INT_CPU0_HP_UBM_N")
	)
	(via
		(at 307.368194 -317.336678)
		(size 0.6604)
		(drill 0.3302)
		(layers "F.Cu" "B.Cu")
		(net "FM_INT_CPU0_HP_UBM_N")
	)
	(via
		(at 264.766806 -186.290204)
		(size 0.508)
		(drill 0.254)
		(layers "F.Cu" "B.Cu")
		(net "FM_INT_CPU0_HP_UBM_N")
	)
	(via
		(at 240.746534 -98.188018)
		(size 0.508)
		(drill 0.254)
		(layers "F.Cu" "B.Cu")
		(net "FM_INT_CPU0_HP_UBM_N")
	)
	(segment
		(start 343.826846 -304.542952)
		(end 344.226388 -304.942494)
		(width 0.10668)
		(layer "B.Cu")
		(net "FM_INT_CPU0_HP_UBM_N")
	)
	(segment
		(start 257.527806 -189.166246)
		(end 254.333502 -192.36055)
		(width 0.10668)
		(layer "B.Cu")
		(net "FM_INT_CPU0_HP_UBM_N")
	)
	(segment
		(start 302.94707 -320.501772)
		(end 303.685448 -320.501772)
		(width 0.10668)
		(layer "B.Cu")
		(net "FM_INT_CPU0_HP_UBM_N")
	)
	(segment
		(start 306.850542 -317.336678)
		(end 307.368194 -317.336678)
		(width 0.10668)
		(layer "B.Cu")
		(net "FM_INT_CPU0_HP_UBM_N")
	)
	(segment
		(start 261.39394 -322.636388)
		(end 300.812454 -322.636388)
		(width 0.10668)
		(layer "B.Cu")
		(net "FM_INT_CPU0_HP_UBM_N")
	)
	(segment
		(start 254.333502 -192.36055)
		(end 254.333502 -216.07145)
		(width 0.10668)
		(layer "B.Cu")
		(net "FM_INT_CPU0_HP_UBM_N")
	)
	(segment
		(start 343.560908 -306.47259)
		(end 343.560908 -306.828952)
		(width 0.10668)
		(layer "B.Cu")
		(net "FM_INT_CPU0_HP_UBM_N")
	)
	(segment
		(start 315.44895 -309.688992)
		(end 331.152246 -309.688992)
		(width 0.10668)
		(layer "B.Cu")
		(net "FM_INT_CPU0_HP_UBM_N")
	)
	(segment
		(start 303.685448 -320.501772)
		(end 306.850542 -317.336678)
		(width 0.10668)
		(layer "B.Cu")
		(net "FM_INT_CPU0_HP_UBM_N")
	)
	(segment
		(start 260.302502 -222.04045)
		(end 260.302502 -321.54495)
		(width 0.10668)
		(layer "B.Cu")
		(net "FM_INT_CPU0_HP_UBM_N")
	)
	(segment
		(start 344.226388 -304.942494)
		(end 344.226388 -305.80711)
		(width 0.10668)
		(layer "B.Cu")
		(net "FM_INT_CPU0_HP_UBM_N")
	)
	(segment
		(start 336.298286 -304.542952)
		(end 343.826846 -304.542952)
		(width 0.10668)
		(layer "B.Cu")
		(net "FM_INT_CPU0_HP_UBM_N")
	)
	(segment
		(start 265.697208 -187.570872)
		(end 265.306302 -187.961778)
		(width 0.10668)
		(layer "B.Cu")
		(net "FM_INT_CPU0_HP_UBM_N")
	)
	(segment
		(start 300.812454 -322.636388)
		(end 302.94707 -320.501772)
		(width 0.10668)
		(layer "B.Cu")
		(net "FM_INT_CPU0_HP_UBM_N")
	)
	(segment
		(start 344.226388 -305.80711)
		(end 343.560908 -306.47259)
		(width 0.10668)
		(layer "B.Cu")
		(net "FM_INT_CPU0_HP_UBM_N")
	)
	(segment
		(start 265.202416 -186.290204)
		(end 265.697208 -186.784996)
		(width 0.10668)
		(layer "B.Cu")
		(net "FM_INT_CPU0_HP_UBM_N")
	)
	(segment
		(start 331.152246 -309.688992)
		(end 336.298286 -304.542952)
		(width 0.10668)
		(layer "B.Cu")
		(net "FM_INT_CPU0_HP_UBM_N")
	)
	(segment
		(start 264.771886 -187.961778)
		(end 263.567418 -189.166246)
		(width 0.10668)
		(layer "B.Cu")
		(net "FM_INT_CPU0_HP_UBM_N")
	)
	(segment
		(start 264.766806 -186.290204)
		(end 265.202416 -186.290204)
		(width 0.10668)
		(layer "B.Cu")
		(net "FM_INT_CPU0_HP_UBM_N")
	)
	(segment
		(start 182.753 -99.894898)
		(end 182.753 -99.278948)
		(width 0.10668)
		(layer "B.Cu")
		(net "FM_INT_CPU0_HP_UBM_N")
	)
	(segment
		(start 263.567418 -189.166246)
		(end 257.527806 -189.166246)
		(width 0.10668)
		(layer "B.Cu")
		(net "FM_INT_CPU0_HP_UBM_N")
	)
	(segment
		(start 265.306302 -187.961778)
		(end 264.771886 -187.961778)
		(width 0.10668)
		(layer "B.Cu")
		(net "FM_INT_CPU0_HP_UBM_N")
	)
	(segment
		(start 260.302502 -321.54495)
		(end 261.39394 -322.636388)
		(width 0.10668)
		(layer "B.Cu")
		(net "FM_INT_CPU0_HP_UBM_N")
	)
	(segment
		(start 307.801264 -317.336678)
		(end 315.44895 -309.688992)
		(width 0.10668)
		(layer "B.Cu")
		(net "FM_INT_CPU0_HP_UBM_N")
	)
	(segment
		(start 254.333502 -216.07145)
		(end 260.302502 -222.04045)
		(width 0.10668)
		(layer "B.Cu")
		(net "FM_INT_CPU0_HP_UBM_N")
	)
	(segment
		(start 265.697208 -186.784996)
		(end 265.697208 -187.570872)
		(width 0.10668)
		(layer "B.Cu")
		(net "FM_INT_CPU0_HP_UBM_N")
	)
	(segment
		(start 307.368194 -317.336678)
		(end 307.801264 -317.336678)
		(width 0.10668)
		(layer "B.Cu")
		(net "FM_INT_CPU0_HP_UBM_N")
	)
	(segment
		(start 265.381486 -101.882956)
		(end 261.122922 -97.624392)
		(width 0.11684)
		(layer "In2.Cu")
		(net "FM_INT_CPU0_HP_UBM_N")
	)
	(segment
		(start 273.114516 -104.156256)
		(end 272.799302 -103.841042)
		(width 0.11684)
		(layer "In2.Cu")
		(net "FM_INT_CPU0_HP_UBM_N")
	)
	(segment
		(start 272.799302 -103.841042)
		(end 266.348718 -103.841042)
		(width 0.11684)
		(layer "In2.Cu")
		(net "FM_INT_CPU0_HP_UBM_N")
	)
	(segment
		(start 265.381486 -102.87381)
		(end 265.381486 -101.882956)
		(width 0.11684)
		(layer "In2.Cu")
		(net "FM_INT_CPU0_HP_UBM_N")
	)
	(segment
		(start 273.114516 -107.2896)
		(end 273.114516 -104.156256)
		(width 0.11684)
		(layer "In2.Cu")
		(net "FM_INT_CPU0_HP_UBM_N")
	)
	(segment
		(start 266.348718 -103.841042)
		(end 265.381486 -102.87381)
		(width 0.11684)
		(layer "In2.Cu")
		(net "FM_INT_CPU0_HP_UBM_N")
	)
	(segment
		(start 247.903238 -97.624392)
		(end 247.339612 -98.188018)
		(width 0.11684)
		(layer "In2.Cu")
		(net "FM_INT_CPU0_HP_UBM_N")
	)
	(segment
		(start 265.017758 -114.99596)
		(end 265.408156 -114.99596)
		(width 0.11684)
		(layer "In2.Cu")
		(net "FM_INT_CPU0_HP_UBM_N")
	)
	(segment
		(start 265.408156 -114.99596)
		(end 273.114516 -107.2896)
		(width 0.11684)
		(layer "In2.Cu")
		(net "FM_INT_CPU0_HP_UBM_N")
	)
	(segment
		(start 247.339612 -98.188018)
		(end 240.746534 -98.188018)
		(width 0.11684)
		(layer "In2.Cu")
		(net "FM_INT_CPU0_HP_UBM_N")
	)
	(segment
		(start 261.122922 -97.624392)
		(end 247.903238 -97.624392)
		(width 0.11684)
		(layer "In2.Cu")
		(net "FM_INT_CPU0_HP_UBM_N")
	)
	(segment
		(start 240.481866 -98.188018)
		(end 240.746534 -98.188018)
		(width 0.11684)
		(layer "In15.Cu")
		(net "FM_INT_CPU0_HP_UBM_N")
	)
	(segment
		(start 232.51287 -106.157014)
		(end 240.481866 -98.188018)
		(width 0.11684)
		(layer "In15.Cu")
		(net "FM_INT_CPU0_HP_UBM_N")
	)
	(segment
		(start 194.672204 -100.363274)
		(end 198.85152 -104.54259)
		(width 0.11684)
		(layer "In15.Cu")
		(net "FM_INT_CPU0_HP_UBM_N")
	)
	(segment
		(start 182.753 -99.278948)
		(end 182.753 -99.767136)
		(width 0.11684)
		(layer "In15.Cu")
		(net "FM_INT_CPU0_HP_UBM_N")
	)
	(segment
		(start 199.759824 -105.017824)
		(end 210.475576 -105.017824)
		(width 0.11684)
		(layer "In15.Cu")
		(net "FM_INT_CPU0_HP_UBM_N")
	)
	(segment
		(start 218.61272 -106.157014)
		(end 232.51287 -106.157014)
		(width 0.11684)
		(layer "In15.Cu")
		(net "FM_INT_CPU0_HP_UBM_N")
	)
	(segment
		(start 218.230958 -106.538776)
		(end 218.61272 -106.157014)
		(width 0.11684)
		(layer "In15.Cu")
		(net "FM_INT_CPU0_HP_UBM_N")
	)
	(segment
		(start 183.349138 -100.363274)
		(end 194.672204 -100.363274)
		(width 0.11684)
		(layer "In15.Cu")
		(net "FM_INT_CPU0_HP_UBM_N")
	)
	(segment
		(start 216.721436 -106.538776)
		(end 218.230958 -106.538776)
		(width 0.11684)
		(layer "In15.Cu")
		(net "FM_INT_CPU0_HP_UBM_N")
	)
	(segment
		(start 210.475576 -105.017824)
		(end 210.895946 -105.438194)
		(width 0.11684)
		(layer "In15.Cu")
		(net "FM_INT_CPU0_HP_UBM_N")
	)
	(segment
		(start 198.85152 -104.54259)
		(end 199.28459 -104.54259)
		(width 0.11684)
		(layer "In15.Cu")
		(net "FM_INT_CPU0_HP_UBM_N")
	)
	(segment
		(start 182.753 -99.767136)
		(end 183.349138 -100.363274)
		(width 0.11684)
		(layer "In15.Cu")
		(net "FM_INT_CPU0_HP_UBM_N")
	)
	(segment
		(start 215.620854 -105.438194)
		(end 216.721436 -106.538776)
		(width 0.11684)
		(layer "In15.Cu")
		(net "FM_INT_CPU0_HP_UBM_N")
	)
	(segment
		(start 199.28459 -104.54259)
		(end 199.759824 -105.017824)
		(width 0.11684)
		(layer "In15.Cu")
		(net "FM_INT_CPU0_HP_UBM_N")
	)
	(segment
		(start 210.895946 -105.438194)
		(end 215.620854 -105.438194)
		(width 0.11684)
		(layer "In15.Cu")
		(net "FM_INT_CPU0_HP_UBM_N")
	)
	(segment
		(start 182.162704 -165.841934)
		(end 181.704234 -166.300404)
		(width 0.10668)
		(layer "F.Cu")
		(net "FM_I3C_CPU1_MUX1_SEL")
	)
	(segment
		(start 182.162704 -165.401498)
		(end 182.162704 -165.841934)
		(width 0.10668)
		(layer "F.Cu")
		(net "FM_I3C_CPU1_MUX1_SEL")
	)
	(via
		(at 166.602918 -126.482856)
		(size 0.508)
		(drill 0.254)
		(layers "F.Cu" "B.Cu")
		(net "FM_I3C_CPU1_MUX1_SEL")
	)
	(via
		(at 181.704234 -166.300404)
		(size 0.508)
		(drill 0.254)
		(layers "F.Cu" "B.Cu")
		(net "FM_I3C_CPU1_MUX1_SEL")
	)
	(via
		(at 161.907728 -108.94949)
		(size 0.508)
		(drill 0.254)
		(layers "F.Cu" "B.Cu")
		(net "FM_I3C_CPU1_MUX1_SEL")
	)
	(segment
		(start 170.797728 -109.055408)
		(end 170.44924 -108.70692)
		(width 0.10668)
		(layer "B.Cu")
		(net "FM_I3C_CPU1_MUX1_SEL")
	)
	(segment
		(start 171.466002 -131.946142)
		(end 171.199556 -131.946142)
		(width 0.10668)
		(layer "B.Cu")
		(net "FM_I3C_CPU1_MUX1_SEL")
	)
	(segment
		(start 166.561516 -108.03636)
		(end 164.931344 -108.03636)
		(width 0.10668)
		(layer "B.Cu")
		(net "FM_I3C_CPU1_MUX1_SEL")
	)
	(segment
		(start 181.704234 -166.300404)
		(end 181.704234 -163.978336)
		(width 0.10668)
		(layer "B.Cu")
		(net "FM_I3C_CPU1_MUX1_SEL")
	)
	(segment
		(start 164.931344 -108.03636)
		(end 164.166804 -107.27182)
		(width 0.10668)
		(layer "B.Cu")
		(net "FM_I3C_CPU1_MUX1_SEL")
	)
	(segment
		(start 161.967418 -108.94949)
		(end 161.907728 -108.94949)
		(width 0.10668)
		(layer "B.Cu")
		(net "FM_I3C_CPU1_MUX1_SEL")
	)
	(segment
		(start 171.199556 -131.946142)
		(end 166.602918 -127.349504)
		(width 0.10668)
		(layer "B.Cu")
		(net "FM_I3C_CPU1_MUX1_SEL")
	)
	(segment
		(start 170.44924 -108.70692)
		(end 169.85996 -108.70692)
		(width 0.10668)
		(layer "B.Cu")
		(net "FM_I3C_CPU1_MUX1_SEL")
	)
	(segment
		(start 173.25467 -150.500588)
		(end 173.25467 -133.73481)
		(width 0.10668)
		(layer "B.Cu")
		(net "FM_I3C_CPU1_MUX1_SEL")
	)
	(segment
		(start 177.826924 -160.101026)
		(end 177.826924 -155.072842)
		(width 0.10668)
		(layer "B.Cu")
		(net "FM_I3C_CPU1_MUX1_SEL")
	)
	(segment
		(start 170.88485 -109.055408)
		(end 170.797728 -109.055408)
		(width 0.10668)
		(layer "B.Cu")
		(net "FM_I3C_CPU1_MUX1_SEL")
	)
	(segment
		(start 163.645088 -107.27182)
		(end 161.967418 -108.94949)
		(width 0.10668)
		(layer "B.Cu")
		(net "FM_I3C_CPU1_MUX1_SEL")
	)
	(segment
		(start 167.169592 -108.644436)
		(end 166.561516 -108.03636)
		(width 0.10668)
		(layer "B.Cu")
		(net "FM_I3C_CPU1_MUX1_SEL")
	)
	(segment
		(start 169.797476 -108.644436)
		(end 167.169592 -108.644436)
		(width 0.10668)
		(layer "B.Cu")
		(net "FM_I3C_CPU1_MUX1_SEL")
	)
	(segment
		(start 164.166804 -107.27182)
		(end 163.645088 -107.27182)
		(width 0.10668)
		(layer "B.Cu")
		(net "FM_I3C_CPU1_MUX1_SEL")
	)
	(segment
		(start 173.25467 -133.73481)
		(end 171.466002 -131.946142)
		(width 0.10668)
		(layer "B.Cu")
		(net "FM_I3C_CPU1_MUX1_SEL")
	)
	(segment
		(start 169.85996 -108.70692)
		(end 169.797476 -108.644436)
		(width 0.10668)
		(layer "B.Cu")
		(net "FM_I3C_CPU1_MUX1_SEL")
	)
	(segment
		(start 177.826924 -155.072842)
		(end 173.25467 -150.500588)
		(width 0.10668)
		(layer "B.Cu")
		(net "FM_I3C_CPU1_MUX1_SEL")
	)
	(segment
		(start 166.602918 -127.349504)
		(end 166.602918 -126.482856)
		(width 0.10668)
		(layer "B.Cu")
		(net "FM_I3C_CPU1_MUX1_SEL")
	)
	(segment
		(start 181.704234 -163.978336)
		(end 177.826924 -160.101026)
		(width 0.10668)
		(layer "B.Cu")
		(net "FM_I3C_CPU1_MUX1_SEL")
	)
	(segment
		(start 166.602918 -125.241812)
		(end 163.590224 -122.229118)
		(width 0.11684)
		(layer "In11.Cu")
		(net "FM_I3C_CPU1_MUX1_SEL")
	)
	(segment
		(start 166.602918 -126.482856)
		(end 166.602918 -125.241812)
		(width 0.11684)
		(layer "In11.Cu")
		(net "FM_I3C_CPU1_MUX1_SEL")
	)
	(segment
		(start 163.590224 -110.631986)
		(end 161.907728 -108.94949)
		(width 0.11684)
		(layer "In11.Cu")
		(net "FM_I3C_CPU1_MUX1_SEL")
	)
	(segment
		(start 163.590224 -122.229118)
		(end 163.590224 -110.631986)
		(width 0.11684)
		(layer "In11.Cu")
		(net "FM_I3C_CPU1_MUX1_SEL")
	)
	(segment
		(start 179.52212 -109.852968)
		(end 179.13223 -109.463078)
		(width 0.10668)
		(layer "F.Cu")
		(net "FM_I3C_CPU1_MUX1_R_SEL")
	)
	(via
		(at 175.278542 -109.466634)
		(size 0.6604)
		(drill 0.3302)
		(layers "F.Cu" "B.Cu")
		(net "FM_I3C_CPU1_MUX1_R_SEL")
	)
	(via
		(at 179.13223 -109.463078)
		(size 0.4572)
		(drill 0.254)
		(layers "F.Cu" "B.Cu")
		(net "FM_I3C_CPU1_MUX1_R_SEL")
	)
	(segment
		(start 178.92268 -109.86516)
		(end 175.677068 -109.86516)
		(width 0.10668)
		(layer "B.Cu")
		(net "FM_I3C_CPU1_MUX1_R_SEL")
	)
	(segment
		(start 174.867316 -109.055408)
		(end 171.68495 -109.055408)
		(width 0.10668)
		(layer "B.Cu")
		(net "FM_I3C_CPU1_MUX1_R_SEL")
	)
	(segment
		(start 175.278542 -109.466634)
		(end 174.867316 -109.055408)
		(width 0.10668)
		(layer "B.Cu")
		(net "FM_I3C_CPU1_MUX1_R_SEL")
	)
	(segment
		(start 179.13223 -109.463078)
		(end 179.13223 -109.65561)
		(width 0.10668)
		(layer "B.Cu")
		(net "FM_I3C_CPU1_MUX1_R_SEL")
	)
	(segment
		(start 175.677068 -109.86516)
		(end 175.278542 -109.466634)
		(width 0.10668)
		(layer "B.Cu")
		(net "FM_I3C_CPU1_MUX1_R_SEL")
	)
	(segment
		(start 179.13223 -109.65561)
		(end 178.92268 -109.86516)
		(width 0.10668)
		(layer "B.Cu")
		(net "FM_I3C_CPU1_MUX1_R_SEL")
	)
	(segment
		(start 180.32222 -110.652814)
		(end 179.93233 -110.262924)
		(width 0.10668)
		(layer "F.Cu")
		(net "FM_I3C_CPU1_MUX1_OE_R_N")
	)
	(via
		(at 175.36414 -111.10976)
		(size 0.6604)
		(drill 0.3302)
		(layers "F.Cu" "B.Cu")
		(net "FM_I3C_CPU1_MUX1_OE_R_N")
	)
	(via
		(at 179.93233 -110.262924)
		(size 0.4572)
		(drill 0.254)
		(layers "F.Cu" "B.Cu")
		(net "FM_I3C_CPU1_MUX1_OE_R_N")
	)
	(segment
		(start 175.36414 -111.10976)
		(end 175.289972 -111.183928)
		(width 0.10668)
		(layer "B.Cu")
		(net "FM_I3C_CPU1_MUX1_OE_R_N")
	)
	(segment
		(start 176.01946 -111.10976)
		(end 176.37252 -111.46282)
		(width 0.10668)
		(layer "B.Cu")
		(net "FM_I3C_CPU1_MUX1_OE_R_N")
	)
	(segment
		(start 175.36414 -111.10976)
		(end 176.01946 -111.10976)
		(width 0.10668)
		(layer "B.Cu")
		(net "FM_I3C_CPU1_MUX1_OE_R_N")
	)
	(segment
		(start 179.52974 -110.665514)
		(end 179.93233 -110.262924)
		(width 0.10668)
		(layer "B.Cu")
		(net "FM_I3C_CPU1_MUX1_OE_R_N")
	)
	(segment
		(start 179.52974 -111.24946)
		(end 179.52974 -110.665514)
		(width 0.10668)
		(layer "B.Cu")
		(net "FM_I3C_CPU1_MUX1_OE_R_N")
	)
	(segment
		(start 175.289972 -111.183928)
		(end 171.60875 -111.183928)
		(width 0.10668)
		(layer "B.Cu")
		(net "FM_I3C_CPU1_MUX1_OE_R_N")
	)
	(segment
		(start 176.37252 -111.46282)
		(end 179.31638 -111.46282)
		(width 0.10668)
		(layer "B.Cu")
		(net "FM_I3C_CPU1_MUX1_OE_R_N")
	)
	(segment
		(start 179.31638 -111.46282)
		(end 179.52974 -111.24946)
		(width 0.10668)
		(layer "B.Cu")
		(net "FM_I3C_CPU1_MUX1_OE_R_N")
	)
	(segment
		(start 183.662828 -165.401498)
		(end 183.662828 -165.603682)
		(width 0.10668)
		(layer "F.Cu")
		(net "FM_I3C_CPU1_MUX1_OE_N")
	)
	(segment
		(start 183.662828 -165.603682)
		(end 184.356248 -166.297102)
		(width 0.10668)
		(layer "F.Cu")
		(net "FM_I3C_CPU1_MUX1_OE_N")
	)
	(via
		(at 161.351722 -110.113572)
		(size 0.508)
		(drill 0.254)
		(layers "F.Cu" "B.Cu")
		(net "FM_I3C_CPU1_MUX1_OE_N")
	)
	(via
		(at 184.356248 -166.297102)
		(size 0.508)
		(drill 0.254)
		(layers "F.Cu" "B.Cu")
		(net "FM_I3C_CPU1_MUX1_OE_N")
	)
	(via
		(at 167.324532 -126.482856)
		(size 0.508)
		(drill 0.254)
		(layers "F.Cu" "B.Cu")
		(net "FM_I3C_CPU1_MUX1_OE_N")
	)
	(segment
		(start 161.684716 -109.780578)
		(end 162.41776 -109.477048)
		(width 0.10668)
		(layer "B.Cu")
		(net "FM_I3C_CPU1_MUX1_OE_N")
	)
	(segment
		(start 169.916856 -110.676436)
		(end 168.515284 -110.676436)
		(width 0.10668)
		(layer "B.Cu")
		(net "FM_I3C_CPU1_MUX1_OE_N")
	)
	(segment
		(start 169.841418 -128.999742)
		(end 169.841418 -129.55778)
		(width 0.10668)
		(layer "B.Cu")
		(net "FM_I3C_CPU1_MUX1_OE_N")
	)
	(segment
		(start 182.88762 -164.828474)
		(end 184.356248 -166.297102)
		(width 0.10668)
		(layer "B.Cu")
		(net "FM_I3C_CPU1_MUX1_OE_N")
	)
	(segment
		(start 167.324532 -126.482856)
		(end 169.841418 -128.999742)
		(width 0.10668)
		(layer "B.Cu")
		(net "FM_I3C_CPU1_MUX1_OE_N")
	)
	(segment
		(start 179.184808 -156.027374)
		(end 178.802792 -156.40939)
		(width 0.10668)
		(layer "B.Cu")
		(net "FM_I3C_CPU1_MUX1_OE_N")
	)
	(segment
		(start 169.993056 -110.752636)
		(end 169.916856 -110.676436)
		(width 0.10668)
		(layer "B.Cu")
		(net "FM_I3C_CPU1_MUX1_OE_N")
	)
	(segment
		(start 179.184808 -155.590748)
		(end 179.184808 -156.027374)
		(width 0.10668)
		(layer "B.Cu")
		(net "FM_I3C_CPU1_MUX1_OE_N")
	)
	(segment
		(start 169.841418 -129.55778)
		(end 173.82871 -133.545072)
		(width 0.10668)
		(layer "B.Cu")
		(net "FM_I3C_CPU1_MUX1_OE_N")
	)
	(segment
		(start 173.82871 -133.545072)
		(end 173.82871 -150.23465)
		(width 0.10668)
		(layer "B.Cu")
		(net "FM_I3C_CPU1_MUX1_OE_N")
	)
	(segment
		(start 167.450516 -110.752636)
		(end 166.174928 -109.477048)
		(width 0.10668)
		(layer "B.Cu")
		(net "FM_I3C_CPU1_MUX1_OE_N")
	)
	(segment
		(start 178.802792 -156.40939)
		(end 178.802792 -160.143444)
		(width 0.10668)
		(layer "B.Cu")
		(net "FM_I3C_CPU1_MUX1_OE_N")
	)
	(segment
		(start 168.515284 -110.676436)
		(end 168.439084 -110.752636)
		(width 0.10668)
		(layer "B.Cu")
		(net "FM_I3C_CPU1_MUX1_OE_N")
	)
	(segment
		(start 170.80865 -111.183928)
		(end 170.377358 -110.752636)
		(width 0.10668)
		(layer "B.Cu")
		(net "FM_I3C_CPU1_MUX1_OE_N")
	)
	(segment
		(start 178.802792 -160.143444)
		(end 182.88762 -164.228272)
		(width 0.10668)
		(layer "B.Cu")
		(net "FM_I3C_CPU1_MUX1_OE_N")
	)
	(segment
		(start 166.174928 -109.477048)
		(end 164.266626 -109.477048)
		(width 0.10668)
		(layer "B.Cu")
		(net "FM_I3C_CPU1_MUX1_OE_N")
	)
	(segment
		(start 173.82871 -150.23465)
		(end 179.184808 -155.590748)
		(width 0.10668)
		(layer "B.Cu")
		(net "FM_I3C_CPU1_MUX1_OE_N")
	)
	(segment
		(start 182.88762 -164.228272)
		(end 182.88762 -164.828474)
		(width 0.10668)
		(layer "B.Cu")
		(net "FM_I3C_CPU1_MUX1_OE_N")
	)
	(segment
		(start 162.41776 -109.477048)
		(end 164.266626 -109.477048)
		(width 0.10668)
		(layer "B.Cu")
		(net "FM_I3C_CPU1_MUX1_OE_N")
	)
	(segment
		(start 170.377358 -110.752636)
		(end 169.993056 -110.752636)
		(width 0.10668)
		(layer "B.Cu")
		(net "FM_I3C_CPU1_MUX1_OE_N")
	)
	(segment
		(start 168.439084 -110.752636)
		(end 167.450516 -110.752636)
		(width 0.10668)
		(layer "B.Cu")
		(net "FM_I3C_CPU1_MUX1_OE_N")
	)
	(segment
		(start 161.351722 -110.113572)
		(end 161.684716 -109.780578)
		(width 0.10668)
		(layer "B.Cu")
		(net "FM_I3C_CPU1_MUX1_OE_N")
	)
	(segment
		(start 162.235388 -108.417868)
		(end 161.492692 -108.417868)
		(width 0.11684)
		(layer "In11.Cu")
		(net "FM_I3C_CPU1_MUX1_OE_N")
	)
	(segment
		(start 167.324532 -125.078236)
		(end 164.21608 -121.969784)
		(width 0.11684)
		(layer "In11.Cu")
		(net "FM_I3C_CPU1_MUX1_OE_N")
	)
	(segment
		(start 161.492692 -108.417868)
		(end 161.11474 -108.79582)
		(width 0.11684)
		(layer "In11.Cu")
		(net "FM_I3C_CPU1_MUX1_OE_N")
	)
	(segment
		(start 161.11474 -109.87659)
		(end 161.351722 -110.113572)
		(width 0.11684)
		(layer "In11.Cu")
		(net "FM_I3C_CPU1_MUX1_OE_N")
	)
	(segment
		(start 161.11474 -108.79582)
		(end 161.11474 -109.87659)
		(width 0.11684)
		(layer "In11.Cu")
		(net "FM_I3C_CPU1_MUX1_OE_N")
	)
	(segment
		(start 167.324532 -126.482856)
		(end 167.324532 -125.078236)
		(width 0.11684)
		(layer "In11.Cu")
		(net "FM_I3C_CPU1_MUX1_OE_N")
	)
	(segment
		(start 164.21608 -110.39856)
		(end 162.235388 -108.417868)
		(width 0.11684)
		(layer "In11.Cu")
		(net "FM_I3C_CPU1_MUX1_OE_N")
	)
	(segment
		(start 164.21608 -121.969784)
		(end 164.21608 -110.39856)
		(width 0.11684)
		(layer "In11.Cu")
		(net "FM_I3C_CPU1_MUX1_OE_N")
	)
	(segment
		(start 160.004506 -88.217502)
		(end 159.14497 -87.357966)
		(width 0.10668)
		(layer "F.Cu")
		(net "FM_I3C_CPU1_MUX0_SEL")
	)
	(segment
		(start 169.99966 -106.812588)
		(end 169.836592 -106.64952)
		(width 0.10668)
		(layer "F.Cu")
		(net "FM_I3C_CPU1_MUX0_SEL")
	)
	(segment
		(start 170.79595 -107.152948)
		(end 170.45559 -106.812588)
		(width 0.10668)
		(layer "F.Cu")
		(net "FM_I3C_CPU1_MUX0_SEL")
	)
	(segment
		(start 169.836592 -106.64952)
		(end 167.38854 -106.64952)
		(width 0.10668)
		(layer "F.Cu")
		(net "FM_I3C_CPU1_MUX0_SEL")
	)
	(segment
		(start 36.913312 -169.996866)
		(end 35.975798 -169.996866)
		(width 0.10668)
		(layer "F.Cu")
		(net "FM_I3C_CPU1_MUX0_SEL")
	)
	(segment
		(start 170.45559 -106.812588)
		(end 169.99966 -106.812588)
		(width 0.10668)
		(layer "F.Cu")
		(net "FM_I3C_CPU1_MUX0_SEL")
	)
	(segment
		(start 38.14699 -171.230544)
		(end 36.913312 -169.996866)
		(width 0.10668)
		(layer "F.Cu")
		(net "FM_I3C_CPU1_MUX0_SEL")
	)
	(segment
		(start 167.38854 -106.64952)
		(end 165.51402 -104.775)
		(width 0.10668)
		(layer "F.Cu")
		(net "FM_I3C_CPU1_MUX0_SEL")
	)
	(segment
		(start 160.909 -104.775)
		(end 160.004506 -103.870506)
		(width 0.10668)
		(layer "F.Cu")
		(net "FM_I3C_CPU1_MUX0_SEL")
	)
	(segment
		(start 160.004506 -103.870506)
		(end 160.004506 -88.217502)
		(width 0.10668)
		(layer "F.Cu")
		(net "FM_I3C_CPU1_MUX0_SEL")
	)
	(segment
		(start 35.975798 -169.996866)
		(end 35.679634 -170.29303)
		(width 0.10668)
		(layer "F.Cu")
		(net "FM_I3C_CPU1_MUX0_SEL")
	)
	(segment
		(start 165.51402 -104.775)
		(end 160.909 -104.775)
		(width 0.10668)
		(layer "F.Cu")
		(net "FM_I3C_CPU1_MUX0_SEL")
	)
	(via
		(at 97.41535 -112.620044)
		(size 0.508)
		(drill 0.254)
		(layers "F.Cu" "B.Cu")
		(net "FM_I3C_CPU1_MUX0_SEL")
	)
	(via
		(at 159.14497 -87.357966)
		(size 0.508)
		(drill 0.254)
		(layers "F.Cu" "B.Cu")
		(net "FM_I3C_CPU1_MUX0_SEL")
	)
	(via
		(at 35.679634 -170.29303)
		(size 0.508)
		(drill 0.254)
		(layers "F.Cu" "B.Cu")
		(net "FM_I3C_CPU1_MUX0_SEL")
	)
	(segment
		(start 97.41535 -113.489994)
		(end 82.536792 -128.368552)
		(width 0.11684)
		(layer "In4.Cu")
		(net "FM_I3C_CPU1_MUX0_SEL")
	)
	(segment
		(start 97.41535 -112.620044)
		(end 97.41535 -113.489994)
		(width 0.11684)
		(layer "In4.Cu")
		(net "FM_I3C_CPU1_MUX0_SEL")
	)
	(segment
		(start 41.532556 -152.692354)
		(end 33.585658 -160.639252)
		(width 0.11684)
		(layer "In4.Cu")
		(net "FM_I3C_CPU1_MUX0_SEL")
	)
	(segment
		(start 82.536792 -128.368552)
		(end 79.480156 -128.368552)
		(width 0.11684)
		(layer "In4.Cu")
		(net "FM_I3C_CPU1_MUX0_SEL")
	)
	(segment
		(start 33.585658 -160.639252)
		(end 33.585658 -167.06215)
		(width 0.11684)
		(layer "In4.Cu")
		(net "FM_I3C_CPU1_MUX0_SEL")
	)
	(segment
		(start 35.679634 -169.156126)
		(end 35.679634 -170.29303)
		(width 0.11684)
		(layer "In4.Cu")
		(net "FM_I3C_CPU1_MUX0_SEL")
	)
	(segment
		(start 68.78447 -139.064238)
		(end 46.045628 -139.064238)
		(width 0.11684)
		(layer "In4.Cu")
		(net "FM_I3C_CPU1_MUX0_SEL")
	)
	(segment
		(start 41.532556 -143.57731)
		(end 41.532556 -152.692354)
		(width 0.11684)
		(layer "In4.Cu")
		(net "FM_I3C_CPU1_MUX0_SEL")
	)
	(segment
		(start 46.045628 -139.064238)
		(end 41.532556 -143.57731)
		(width 0.11684)
		(layer "In4.Cu")
		(net "FM_I3C_CPU1_MUX0_SEL")
	)
	(segment
		(start 79.480156 -128.368552)
		(end 68.78447 -139.064238)
		(width 0.11684)
		(layer "In4.Cu")
		(net "FM_I3C_CPU1_MUX0_SEL")
	)
	(segment
		(start 33.585658 -167.06215)
		(end 35.679634 -169.156126)
		(width 0.11684)
		(layer "In4.Cu")
		(net "FM_I3C_CPU1_MUX0_SEL")
	)
	(segment
		(start 159.134302 -87.347298)
		(end 146.365722 -87.347298)
		(width 0.11684)
		(layer "In6.Cu")
		(net "FM_I3C_CPU1_MUX0_SEL")
	)
	(segment
		(start 98.869754 -111.16564)
		(end 97.41535 -112.620044)
		(width 0.11684)
		(layer "In6.Cu")
		(net "FM_I3C_CPU1_MUX0_SEL")
	)
	(segment
		(start 159.14497 -87.357966)
		(end 159.134302 -87.347298)
		(width 0.11684)
		(layer "In6.Cu")
		(net "FM_I3C_CPU1_MUX0_SEL")
	)
	(segment
		(start 146.365722 -87.347298)
		(end 129.564638 -104.148382)
		(width 0.11684)
		(layer "In6.Cu")
		(net "FM_I3C_CPU1_MUX0_SEL")
	)
	(segment
		(start 125.098302 -111.16564)
		(end 98.869754 -111.16564)
		(width 0.11684)
		(layer "In6.Cu")
		(net "FM_I3C_CPU1_MUX0_SEL")
	)
	(segment
		(start 129.564638 -104.148382)
		(end 129.564638 -106.699304)
		(width 0.11684)
		(layer "In6.Cu")
		(net "FM_I3C_CPU1_MUX0_SEL")
	)
	(segment
		(start 129.564638 -106.699304)
		(end 125.098302 -111.16564)
		(width 0.11684)
		(layer "In6.Cu")
		(net "FM_I3C_CPU1_MUX0_SEL")
	)
	(segment
		(start 172.7708 -107.79252)
		(end 172.131228 -107.152948)
		(width 0.10668)
		(layer "F.Cu")
		(net "FM_I3C_CPU1_MUX0_R_SEL")
	)
	(segment
		(start 176.302924 -107.450636)
		(end 175.73244 -108.02112)
		(width 0.10668)
		(layer "F.Cu")
		(net "FM_I3C_CPU1_MUX0_R_SEL")
	)
	(segment
		(start 172.131228 -107.152948)
		(end 171.59605 -107.152948)
		(width 0.10668)
		(layer "F.Cu")
		(net "FM_I3C_CPU1_MUX0_R_SEL")
	)
	(segment
		(start 177.119788 -107.450636)
		(end 176.302924 -107.450636)
		(width 0.10668)
		(layer "F.Cu")
		(net "FM_I3C_CPU1_MUX0_R_SEL")
	)
	(segment
		(start 175.73244 -108.02112)
		(end 172.7708 -108.02112)
		(width 0.10668)
		(layer "F.Cu")
		(net "FM_I3C_CPU1_MUX0_R_SEL")
	)
	(segment
		(start 177.122074 -107.452922)
		(end 177.119788 -107.450636)
		(width 0.10668)
		(layer "F.Cu")
		(net "FM_I3C_CPU1_MUX0_R_SEL")
	)
	(segment
		(start 172.7708 -108.02112)
		(end 172.7708 -107.79252)
		(width 0.10668)
		(layer "F.Cu")
		(net "FM_I3C_CPU1_MUX0_R_SEL")
	)
	(via
		(at 172.7708 -108.02112)
		(size 0.762)
		(drill 0.381)
		(layers "F.Cu" "B.Cu")
		(net "FM_I3C_CPU1_MUX0_R_SEL")
	)
	(segment
		(start 171.818808 -104.993948)
		(end 171.59605 -104.993948)
		(width 0.10668)
		(layer "F.Cu")
		(net "FM_I3C_CPU1_MUX0_OE_R_N")
	)
	(segment
		(start 172.7708 -105.94594)
		(end 171.818808 -104.993948)
		(width 0.10668)
		(layer "F.Cu")
		(net "FM_I3C_CPU1_MUX0_OE_R_N")
	)
	(segment
		(start 177.521108 -106.491024)
		(end 176.659286 -105.629202)
		(width 0.10668)
		(layer "F.Cu")
		(net "FM_I3C_CPU1_MUX0_OE_R_N")
	)
	(segment
		(start 175.1838 -105.629202)
		(end 174.867062 -105.94594)
		(width 0.10668)
		(layer "F.Cu")
		(net "FM_I3C_CPU1_MUX0_OE_R_N")
	)
	(segment
		(start 174.867062 -105.94594)
		(end 172.7708 -105.94594)
		(width 0.10668)
		(layer "F.Cu")
		(net "FM_I3C_CPU1_MUX0_OE_R_N")
	)
	(segment
		(start 177.521108 -106.777536)
		(end 177.521108 -106.491024)
		(width 0.10668)
		(layer "F.Cu")
		(net "FM_I3C_CPU1_MUX0_OE_R_N")
	)
	(segment
		(start 177.922174 -107.178602)
		(end 177.521108 -106.777536)
		(width 0.10668)
		(layer "F.Cu")
		(net "FM_I3C_CPU1_MUX0_OE_R_N")
	)
	(segment
		(start 177.922174 -107.452922)
		(end 177.922174 -107.178602)
		(width 0.10668)
		(layer "F.Cu")
		(net "FM_I3C_CPU1_MUX0_OE_R_N")
	)
	(segment
		(start 176.659286 -105.629202)
		(end 175.1838 -105.629202)
		(width 0.10668)
		(layer "F.Cu")
		(net "FM_I3C_CPU1_MUX0_OE_R_N")
	)
	(via
		(at 172.7708 -105.94594)
		(size 0.762)
		(drill 0.381)
		(layers "F.Cu" "B.Cu")
		(net "FM_I3C_CPU1_MUX0_OE_R_N")
	)
	(segment
		(start 160.55594 -103.65994)
		(end 160.55594 -86.795864)
		(width 0.10668)
		(layer "F.Cu")
		(net "FM_I3C_CPU1_MUX0_OE_N")
	)
	(segment
		(start 170.758358 -105.428034)
		(end 170.587924 -105.598468)
		(width 0.10668)
		(layer "F.Cu")
		(net "FM_I3C_CPU1_MUX0_OE_N")
	)
	(segment
		(start 167.868092 -105.511092)
		(end 166.497 -104.14)
		(width 0.10668)
		(layer "F.Cu")
		(net "FM_I3C_CPU1_MUX0_OE_N")
	)
	(segment
		(start 37.98062 -172.730668)
		(end 37.221922 -173.489366)
		(width 0.10668)
		(layer "F.Cu")
		(net "FM_I3C_CPU1_MUX0_OE_N")
	)
	(segment
		(start 169.635424 -105.511092)
		(end 167.868092 -105.511092)
		(width 0.10668)
		(layer "F.Cu")
		(net "FM_I3C_CPU1_MUX0_OE_N")
	)
	(segment
		(start 38.14699 -172.730668)
		(end 37.98062 -172.730668)
		(width 0.10668)
		(layer "F.Cu")
		(net "FM_I3C_CPU1_MUX0_OE_N")
	)
	(segment
		(start 37.221922 -173.489366)
		(end 35.7124 -173.489366)
		(width 0.10668)
		(layer "F.Cu")
		(net "FM_I3C_CPU1_MUX0_OE_N")
	)
	(segment
		(start 170.830748 -103.990648)
		(end 170.830748 -104.95915)
		(width 0.10668)
		(layer "F.Cu")
		(net "FM_I3C_CPU1_MUX0_OE_N")
	)
	(segment
		(start 160.55594 -86.795864)
		(end 160.450276 -86.6902)
		(width 0.10668)
		(layer "F.Cu")
		(net "FM_I3C_CPU1_MUX0_OE_N")
	)
	(segment
		(start 166.497 -104.14)
		(end 161.036 -104.14)
		(width 0.10668)
		(layer "F.Cu")
		(net "FM_I3C_CPU1_MUX0_OE_N")
	)
	(segment
		(start 161.036 -104.14)
		(end 160.55594 -103.65994)
		(width 0.10668)
		(layer "F.Cu")
		(net "FM_I3C_CPU1_MUX0_OE_N")
	)
	(segment
		(start 170.758358 -105.03154)
		(end 170.758358 -105.428034)
		(width 0.10668)
		(layer "F.Cu")
		(net "FM_I3C_CPU1_MUX0_OE_N")
	)
	(segment
		(start 170.80738 -103.96728)
		(end 170.830748 -103.990648)
		(width 0.10668)
		(layer "F.Cu")
		(net "FM_I3C_CPU1_MUX0_OE_N")
	)
	(segment
		(start 170.830748 -104.95915)
		(end 170.79595 -104.993948)
		(width 0.10668)
		(layer "F.Cu")
		(net "FM_I3C_CPU1_MUX0_OE_N")
	)
	(segment
		(start 170.587924 -105.598468)
		(end 169.7228 -105.598468)
		(width 0.10668)
		(layer "F.Cu")
		(net "FM_I3C_CPU1_MUX0_OE_N")
	)
	(segment
		(start 170.79595 -104.993948)
		(end 170.758358 -105.03154)
		(width 0.10668)
		(layer "F.Cu")
		(net "FM_I3C_CPU1_MUX0_OE_N")
	)
	(segment
		(start 169.7228 -105.598468)
		(end 169.635424 -105.511092)
		(width 0.10668)
		(layer "F.Cu")
		(net "FM_I3C_CPU1_MUX0_OE_N")
	)
	(via
		(at 160.450276 -86.6902)
		(size 0.508)
		(drill 0.254)
		(layers "F.Cu" "B.Cu")
		(net "FM_I3C_CPU1_MUX0_OE_N")
	)
	(via
		(at 35.7124 -173.489366)
		(size 0.508)
		(drill 0.254)
		(layers "F.Cu" "B.Cu")
		(net "FM_I3C_CPU1_MUX0_OE_N")
	)
	(via
		(at 96.75749 -112.620044)
		(size 0.508)
		(drill 0.254)
		(layers "F.Cu" "B.Cu")
		(net "FM_I3C_CPU1_MUX0_OE_N")
	)
	(segment
		(start 45.593254 -138.464798)
		(end 40.709342 -143.34871)
		(width 0.11684)
		(layer "In4.Cu")
		(net "FM_I3C_CPU1_MUX0_OE_N")
	)
	(segment
		(start 82.150458 -127.769112)
		(end 79.23149 -127.769112)
		(width 0.11684)
		(layer "In4.Cu")
		(net "FM_I3C_CPU1_MUX0_OE_N")
	)
	(segment
		(start 40.709342 -143.34871)
		(end 40.709342 -152.570434)
		(width 0.11684)
		(layer "In4.Cu")
		(net "FM_I3C_CPU1_MUX0_OE_N")
	)
	(segment
		(start 68.535804 -138.464798)
		(end 45.593254 -138.464798)
		(width 0.11684)
		(layer "In4.Cu")
		(net "FM_I3C_CPU1_MUX0_OE_N")
	)
	(segment
		(start 35.021012 -169.462958)
		(end 35.021012 -172.797978)
		(width 0.11684)
		(layer "In4.Cu")
		(net "FM_I3C_CPU1_MUX0_OE_N")
	)
	(segment
		(start 35.021012 -172.797978)
		(end 35.7124 -173.489366)
		(width 0.11684)
		(layer "In4.Cu")
		(net "FM_I3C_CPU1_MUX0_OE_N")
	)
	(segment
		(start 96.75749 -112.620044)
		(end 96.75749 -113.16208)
		(width 0.11684)
		(layer "In4.Cu")
		(net "FM_I3C_CPU1_MUX0_OE_N")
	)
	(segment
		(start 79.23149 -127.769112)
		(end 68.535804 -138.464798)
		(width 0.11684)
		(layer "In4.Cu")
		(net "FM_I3C_CPU1_MUX0_OE_N")
	)
	(segment
		(start 40.709342 -152.570434)
		(end 32.786828 -160.492948)
		(width 0.11684)
		(layer "In4.Cu")
		(net "FM_I3C_CPU1_MUX0_OE_N")
	)
	(segment
		(start 32.786828 -160.492948)
		(end 32.786828 -167.228774)
		(width 0.11684)
		(layer "In4.Cu")
		(net "FM_I3C_CPU1_MUX0_OE_N")
	)
	(segment
		(start 96.75749 -113.16208)
		(end 82.150458 -127.769112)
		(width 0.11684)
		(layer "In4.Cu")
		(net "FM_I3C_CPU1_MUX0_OE_N")
	)
	(segment
		(start 32.786828 -167.228774)
		(end 35.021012 -169.462958)
		(width 0.11684)
		(layer "In4.Cu")
		(net "FM_I3C_CPU1_MUX0_OE_N")
	)
	(segment
		(start 128.831594 -103.951024)
		(end 146.09318 -86.689438)
		(width 0.11684)
		(layer "In6.Cu")
		(net "FM_I3C_CPU1_MUX0_OE_N")
	)
	(segment
		(start 160.449514 -86.689438)
		(end 160.450276 -86.6902)
		(width 0.11684)
		(layer "In6.Cu")
		(net "FM_I3C_CPU1_MUX0_OE_N")
	)
	(segment
		(start 98.609912 -110.50778)
		(end 124.700538 -110.50778)
		(width 0.11684)
		(layer "In6.Cu")
		(net "FM_I3C_CPU1_MUX0_OE_N")
	)
	(segment
		(start 146.09318 -86.689438)
		(end 160.449514 -86.689438)
		(width 0.11684)
		(layer "In6.Cu")
		(net "FM_I3C_CPU1_MUX0_OE_N")
	)
	(segment
		(start 128.831594 -106.376724)
		(end 128.831594 -103.951024)
		(width 0.11684)
		(layer "In6.Cu")
		(net "FM_I3C_CPU1_MUX0_OE_N")
	)
	(segment
		(start 96.75749 -112.620044)
		(end 96.75749 -112.360202)
		(width 0.11684)
		(layer "In6.Cu")
		(net "FM_I3C_CPU1_MUX0_OE_N")
	)
	(segment
		(start 124.700538 -110.50778)
		(end 128.831594 -106.376724)
		(width 0.11684)
		(layer "In6.Cu")
		(net "FM_I3C_CPU1_MUX0_OE_N")
	)
	(segment
		(start 96.75749 -112.360202)
		(end 98.609912 -110.50778)
		(width 0.11684)
		(layer "In6.Cu")
		(net "FM_I3C_CPU1_MUX0_OE_N")
	)
	(segment
		(start 437.136794 -167.127428)
		(end 436.49011 -167.127428)
		(width 0.10668)
		(layer "F.Cu")
		(net "FM_I3C_CPU0_MUX1_SEL")
	)
	(segment
		(start 437.848756 -167.83939)
		(end 437.136794 -167.127428)
		(width 0.10668)
		(layer "F.Cu")
		(net "FM_I3C_CPU0_MUX1_SEL")
	)
	(segment
		(start 437.848756 -167.96639)
		(end 437.848756 -167.83939)
		(width 0.10668)
		(layer "F.Cu")
		(net "FM_I3C_CPU0_MUX1_SEL")
	)
	(via
		(at 218.523312 -120.691148)
		(size 0.508)
		(drill 0.254)
		(layers "F.Cu" "B.Cu")
		(net "FM_I3C_CPU0_MUX1_SEL")
	)
	(via
		(at 436.49011 -167.127428)
		(size 0.508)
		(drill 0.254)
		(layers "F.Cu" "B.Cu")
		(net "FM_I3C_CPU0_MUX1_SEL")
	)
	(via
		(at 169.164 -111.212376)
		(size 0.508)
		(drill 0.254)
		(layers "F.Cu" "B.Cu")
		(net "FM_I3C_CPU0_MUX1_SEL")
	)
	(via
		(at 277.29942 -129.377948)
		(size 0.508)
		(drill 0.254)
		(layers "F.Cu" "B.Cu")
		(net "FM_I3C_CPU0_MUX1_SEL")
	)
	(segment
		(start 170.11904 -111.84636)
		(end 170.409362 -111.84636)
		(width 0.10668)
		(layer "B.Cu")
		(net "FM_I3C_CPU0_MUX1_SEL")
	)
	(segment
		(start 169.634408 -111.361728)
		(end 170.11904 -111.84636)
		(width 0.10668)
		(layer "B.Cu")
		(net "FM_I3C_CPU0_MUX1_SEL")
	)
	(segment
		(start 169.313352 -111.361728)
		(end 169.634408 -111.361728)
		(width 0.10668)
		(layer "B.Cu")
		(net "FM_I3C_CPU0_MUX1_SEL")
	)
	(segment
		(start 169.164 -111.212376)
		(end 169.313352 -111.361728)
		(width 0.10668)
		(layer "B.Cu")
		(net "FM_I3C_CPU0_MUX1_SEL")
	)
	(segment
		(start 170.409362 -111.84636)
		(end 170.79595 -112.232948)
		(width 0.10668)
		(layer "B.Cu")
		(net "FM_I3C_CPU0_MUX1_SEL")
	)
	(segment
		(start 290.424108 -120.531128)
		(end 295.475152 -120.531128)
		(width 0.11684)
		(layer "In2.Cu")
		(net "FM_I3C_CPU0_MUX1_SEL")
	)
	(segment
		(start 169.164 -111.212376)
		(end 169.676572 -111.724948)
		(width 0.11684)
		(layer "In2.Cu")
		(net "FM_I3C_CPU0_MUX1_SEL")
	)
	(segment
		(start 310.79694 -125.948948)
		(end 315.36132 -130.513328)
		(width 0.11684)
		(layer "In2.Cu")
		(net "FM_I3C_CPU0_MUX1_SEL")
	)
	(segment
		(start 194.373246 -113.8682)
		(end 195.678806 -115.17376)
		(width 0.11684)
		(layer "In2.Cu")
		(net "FM_I3C_CPU0_MUX1_SEL")
	)
	(segment
		(start 315.36132 -130.513328)
		(end 341.63254 -130.513328)
		(width 0.11684)
		(layer "In2.Cu")
		(net "FM_I3C_CPU0_MUX1_SEL")
	)
	(segment
		(start 437.730138 -164.294058)
		(end 437.730138 -165.124638)
		(width 0.11684)
		(layer "In2.Cu")
		(net "FM_I3C_CPU0_MUX1_SEL")
	)
	(segment
		(start 169.676572 -111.724948)
		(end 172.847 -111.724948)
		(width 0.11684)
		(layer "In2.Cu")
		(net "FM_I3C_CPU0_MUX1_SEL")
	)
	(segment
		(start 172.847 -111.724948)
		(end 174.18812 -113.066068)
		(width 0.11684)
		(layer "In2.Cu")
		(net "FM_I3C_CPU0_MUX1_SEL")
	)
	(segment
		(start 436.49011 -166.364666)
		(end 436.49011 -167.127428)
		(width 0.11684)
		(layer "In2.Cu")
		(net "FM_I3C_CPU0_MUX1_SEL")
	)
	(segment
		(start 215.846914 -118.255542)
		(end 217.27668 -119.685308)
		(width 0.11684)
		(layer "In2.Cu")
		(net "FM_I3C_CPU0_MUX1_SEL")
	)
	(segment
		(start 174.18812 -113.066068)
		(end 185.216038 -113.066068)
		(width 0.11684)
		(layer "In2.Cu")
		(net "FM_I3C_CPU0_MUX1_SEL")
	)
	(segment
		(start 429.114458 -155.678378)
		(end 437.730138 -164.294058)
		(width 0.11684)
		(layer "In2.Cu")
		(net "FM_I3C_CPU0_MUX1_SEL")
	)
	(segment
		(start 415.850324 -131.344162)
		(end 429.114458 -144.608296)
		(width 0.11684)
		(layer "In2.Cu")
		(net "FM_I3C_CPU0_MUX1_SEL")
	)
	(segment
		(start 404.066248 -133.722364)
		(end 406.44445 -131.344162)
		(width 0.11684)
		(layer "In2.Cu")
		(net "FM_I3C_CPU0_MUX1_SEL")
	)
	(segment
		(start 206.346806 -118.255542)
		(end 215.846914 -118.255542)
		(width 0.11684)
		(layer "In2.Cu")
		(net "FM_I3C_CPU0_MUX1_SEL")
	)
	(segment
		(start 195.678806 -115.17376)
		(end 200.211436 -115.17376)
		(width 0.11684)
		(layer "In2.Cu")
		(net "FM_I3C_CPU0_MUX1_SEL")
	)
	(segment
		(start 185.216038 -113.066068)
		(end 186.01817 -113.8682)
		(width 0.11684)
		(layer "In2.Cu")
		(net "FM_I3C_CPU0_MUX1_SEL")
	)
	(segment
		(start 217.517472 -119.685308)
		(end 218.523312 -120.691148)
		(width 0.11684)
		(layer "In2.Cu")
		(net "FM_I3C_CPU0_MUX1_SEL")
	)
	(segment
		(start 341.63254 -130.513328)
		(end 346.246704 -135.127492)
		(width 0.11684)
		(layer "In2.Cu")
		(net "FM_I3C_CPU0_MUX1_SEL")
	)
	(segment
		(start 429.114458 -144.608296)
		(end 429.114458 -155.678378)
		(width 0.11684)
		(layer "In2.Cu")
		(net "FM_I3C_CPU0_MUX1_SEL")
	)
	(segment
		(start 298.924472 -125.948948)
		(end 310.79694 -125.948948)
		(width 0.11684)
		(layer "In2.Cu")
		(net "FM_I3C_CPU0_MUX1_SEL")
	)
	(segment
		(start 295.475152 -120.531128)
		(end 296.73042 -121.786396)
		(width 0.11684)
		(layer "In2.Cu")
		(net "FM_I3C_CPU0_MUX1_SEL")
	)
	(segment
		(start 201.185018 -116.147342)
		(end 204.238606 -116.147342)
		(width 0.11684)
		(layer "In2.Cu")
		(net "FM_I3C_CPU0_MUX1_SEL")
	)
	(segment
		(start 204.238606 -116.147342)
		(end 206.346806 -118.255542)
		(width 0.11684)
		(layer "In2.Cu")
		(net "FM_I3C_CPU0_MUX1_SEL")
	)
	(segment
		(start 186.01817 -113.8682)
		(end 194.373246 -113.8682)
		(width 0.11684)
		(layer "In2.Cu")
		(net "FM_I3C_CPU0_MUX1_SEL")
	)
	(segment
		(start 437.730138 -165.124638)
		(end 436.49011 -166.364666)
		(width 0.11684)
		(layer "In2.Cu")
		(net "FM_I3C_CPU0_MUX1_SEL")
	)
	(segment
		(start 282.222448 -128.732788)
		(end 290.424108 -120.531128)
		(width 0.11684)
		(layer "In2.Cu")
		(net "FM_I3C_CPU0_MUX1_SEL")
	)
	(segment
		(start 353.844352 -135.127492)
		(end 355.24948 -133.722364)
		(width 0.11684)
		(layer "In2.Cu")
		(net "FM_I3C_CPU0_MUX1_SEL")
	)
	(segment
		(start 277.94458 -128.732788)
		(end 282.222448 -128.732788)
		(width 0.11684)
		(layer "In2.Cu")
		(net "FM_I3C_CPU0_MUX1_SEL")
	)
	(segment
		(start 346.246704 -135.127492)
		(end 353.844352 -135.127492)
		(width 0.11684)
		(layer "In2.Cu")
		(net "FM_I3C_CPU0_MUX1_SEL")
	)
	(segment
		(start 296.73042 -121.786396)
		(end 296.73042 -123.754896)
		(width 0.11684)
		(layer "In2.Cu")
		(net "FM_I3C_CPU0_MUX1_SEL")
	)
	(segment
		(start 296.73042 -123.754896)
		(end 298.924472 -125.948948)
		(width 0.11684)
		(layer "In2.Cu")
		(net "FM_I3C_CPU0_MUX1_SEL")
	)
	(segment
		(start 355.24948 -133.722364)
		(end 404.066248 -133.722364)
		(width 0.11684)
		(layer "In2.Cu")
		(net "FM_I3C_CPU0_MUX1_SEL")
	)
	(segment
		(start 217.27668 -119.685308)
		(end 217.517472 -119.685308)
		(width 0.11684)
		(layer "In2.Cu")
		(net "FM_I3C_CPU0_MUX1_SEL")
	)
	(segment
		(start 277.29942 -129.377948)
		(end 277.94458 -128.732788)
		(width 0.11684)
		(layer "In2.Cu")
		(net "FM_I3C_CPU0_MUX1_SEL")
	)
	(segment
		(start 406.44445 -131.344162)
		(end 415.850324 -131.344162)
		(width 0.11684)
		(layer "In2.Cu")
		(net "FM_I3C_CPU0_MUX1_SEL")
	)
	(segment
		(start 200.211436 -115.17376)
		(end 201.185018 -116.147342)
		(width 0.11684)
		(layer "In2.Cu")
		(net "FM_I3C_CPU0_MUX1_SEL")
	)
	(segment
		(start 250.731528 -125.787912)
		(end 236.999018 -125.787912)
		(width 0.11684)
		(layer "In6.Cu")
		(net "FM_I3C_CPU0_MUX1_SEL")
	)
	(segment
		(start 255.669288 -127.668782)
		(end 252.612398 -127.668782)
		(width 0.11684)
		(layer "In6.Cu")
		(net "FM_I3C_CPU0_MUX1_SEL")
	)
	(segment
		(start 277.29942 -129.377948)
		(end 276.07006 -128.148588)
		(width 0.11684)
		(layer "In6.Cu")
		(net "FM_I3C_CPU0_MUX1_SEL")
	)
	(segment
		(start 256.07645 -128.075944)
		(end 255.669288 -127.668782)
		(width 0.11684)
		(layer "In6.Cu")
		(net "FM_I3C_CPU0_MUX1_SEL")
	)
	(segment
		(start 232.715054 -121.503948)
		(end 219.336112 -121.503948)
		(width 0.11684)
		(layer "In6.Cu")
		(net "FM_I3C_CPU0_MUX1_SEL")
	)
	(segment
		(start 258.61137 -128.075944)
		(end 256.07645 -128.075944)
		(width 0.11684)
		(layer "In6.Cu")
		(net "FM_I3C_CPU0_MUX1_SEL")
	)
	(segment
		(start 262.856726 -128.148588)
		(end 262.27913 -128.726184)
		(width 0.11684)
		(layer "In6.Cu")
		(net "FM_I3C_CPU0_MUX1_SEL")
	)
	(segment
		(start 262.27913 -128.726184)
		(end 259.26161 -128.726184)
		(width 0.11684)
		(layer "In6.Cu")
		(net "FM_I3C_CPU0_MUX1_SEL")
	)
	(segment
		(start 276.07006 -128.148588)
		(end 262.856726 -128.148588)
		(width 0.11684)
		(layer "In6.Cu")
		(net "FM_I3C_CPU0_MUX1_SEL")
	)
	(segment
		(start 236.999018 -125.787912)
		(end 232.715054 -121.503948)
		(width 0.11684)
		(layer "In6.Cu")
		(net "FM_I3C_CPU0_MUX1_SEL")
	)
	(segment
		(start 219.336112 -121.503948)
		(end 218.523312 -120.691148)
		(width 0.11684)
		(layer "In6.Cu")
		(net "FM_I3C_CPU0_MUX1_SEL")
	)
	(segment
		(start 252.612398 -127.668782)
		(end 250.731528 -125.787912)
		(width 0.11684)
		(layer "In6.Cu")
		(net "FM_I3C_CPU0_MUX1_SEL")
	)
	(segment
		(start 259.26161 -128.726184)
		(end 258.61137 -128.075944)
		(width 0.11684)
		(layer "In6.Cu")
		(net "FM_I3C_CPU0_MUX1_SEL")
	)
	(segment
		(start 181.122066 -111.452914)
		(end 180.732176 -111.063024)
		(width 0.10668)
		(layer "F.Cu")
		(net "FM_I3C_CPU0_MUX1_R_SEL")
	)
	(via
		(at 180.732176 -111.063024)
		(size 0.4572)
		(drill 0.254)
		(layers "F.Cu" "B.Cu")
		(net "FM_I3C_CPU0_MUX1_R_SEL")
	)
	(via
		(at 174.23384 -112.14862)
		(size 0.6604)
		(drill 0.3302)
		(layers "F.Cu" "B.Cu")
		(net "FM_I3C_CPU0_MUX1_R_SEL")
	)
	(segment
		(start 176.36998 -111.98352)
		(end 176.64557 -112.25911)
		(width 0.10668)
		(layer "B.Cu")
		(net "FM_I3C_CPU0_MUX1_R_SEL")
	)
	(segment
		(start 171.59605 -112.232948)
		(end 171.680378 -112.14862)
		(width 0.10668)
		(layer "B.Cu")
		(net "FM_I3C_CPU0_MUX1_R_SEL")
	)
	(segment
		(start 180.33492 -111.46028)
		(end 180.732176 -111.063024)
		(width 0.10668)
		(layer "B.Cu")
		(net "FM_I3C_CPU0_MUX1_R_SEL")
	)
	(segment
		(start 174.23384 -112.14862)
		(end 174.39894 -111.98352)
		(width 0.10668)
		(layer "B.Cu")
		(net "FM_I3C_CPU0_MUX1_R_SEL")
	)
	(segment
		(start 171.680378 -112.14862)
		(end 174.23384 -112.14862)
		(width 0.10668)
		(layer "B.Cu")
		(net "FM_I3C_CPU0_MUX1_R_SEL")
	)
	(segment
		(start 180.14823 -112.25911)
		(end 180.33492 -112.07242)
		(width 0.10668)
		(layer "B.Cu")
		(net "FM_I3C_CPU0_MUX1_R_SEL")
	)
	(segment
		(start 174.39894 -111.98352)
		(end 176.36998 -111.98352)
		(width 0.10668)
		(layer "B.Cu")
		(net "FM_I3C_CPU0_MUX1_R_SEL")
	)
	(segment
		(start 176.64557 -112.25911)
		(end 180.14823 -112.25911)
		(width 0.10668)
		(layer "B.Cu")
		(net "FM_I3C_CPU0_MUX1_R_SEL")
	)
	(segment
		(start 180.33492 -112.07242)
		(end 180.33492 -111.46028)
		(width 0.10668)
		(layer "B.Cu")
		(net "FM_I3C_CPU0_MUX1_R_SEL")
	)
	(segment
		(start 178.72202 -109.052868)
		(end 178.33213 -108.662978)
		(width 0.10668)
		(layer "F.Cu")
		(net "FM_I3C_CPU0_MUX1_OE_R_N")
	)
	(via
		(at 172.763434 -106.136186)
		(size 0.6604)
		(drill 0.3302)
		(layers "F.Cu" "B.Cu")
		(net "FM_I3C_CPU0_MUX1_OE_R_N")
	)
	(via
		(at 178.33213 -108.662978)
		(size 0.4572)
		(drill 0.254)
		(layers "F.Cu" "B.Cu")
		(net "FM_I3C_CPU0_MUX1_OE_R_N")
	)
	(segment
		(start 173.75632 -106.136186)
		(end 174.982378 -107.362244)
		(width 0.10668)
		(layer "B.Cu")
		(net "FM_I3C_CPU0_MUX1_OE_R_N")
	)
	(segment
		(start 178.285902 -108.662978)
		(end 178.33213 -108.662978)
		(width 0.10668)
		(layer "B.Cu")
		(net "FM_I3C_CPU0_MUX1_OE_R_N")
	)
	(segment
		(start 176.702974 -108.266738)
		(end 177.889662 -108.266738)
		(width 0.10668)
		(layer "B.Cu")
		(net "FM_I3C_CPU0_MUX1_OE_R_N")
	)
	(segment
		(start 172.763434 -106.136186)
		(end 173.75632 -106.136186)
		(width 0.10668)
		(layer "B.Cu")
		(net "FM_I3C_CPU0_MUX1_OE_R_N")
	)
	(segment
		(start 171.595034 -106.136186)
		(end 172.763434 -106.136186)
		(width 0.10668)
		(layer "B.Cu")
		(net "FM_I3C_CPU0_MUX1_OE_R_N")
	)
	(segment
		(start 177.889662 -108.266738)
		(end 178.285902 -108.662978)
		(width 0.10668)
		(layer "B.Cu")
		(net "FM_I3C_CPU0_MUX1_OE_R_N")
	)
	(segment
		(start 174.982378 -107.362244)
		(end 175.79848 -107.362244)
		(width 0.10668)
		(layer "B.Cu")
		(net "FM_I3C_CPU0_MUX1_OE_R_N")
	)
	(segment
		(start 175.79848 -107.362244)
		(end 176.702974 -108.266738)
		(width 0.10668)
		(layer "B.Cu")
		(net "FM_I3C_CPU0_MUX1_OE_R_N")
	)
	(segment
		(start 436.139844 -169.986452)
		(end 435.87162 -169.718228)
		(width 0.10668)
		(layer "F.Cu")
		(net "FM_I3C_CPU0_MUX1_OE_N")
	)
	(segment
		(start 437.033924 -169.986452)
		(end 436.139844 -169.986452)
		(width 0.10668)
		(layer "F.Cu")
		(net "FM_I3C_CPU0_MUX1_OE_N")
	)
	(segment
		(start 437.848756 -169.466514)
		(end 437.553862 -169.466514)
		(width 0.10668)
		(layer "F.Cu")
		(net "FM_I3C_CPU0_MUX1_OE_N")
	)
	(segment
		(start 437.553862 -169.466514)
		(end 437.033924 -169.986452)
		(width 0.10668)
		(layer "F.Cu")
		(net "FM_I3C_CPU0_MUX1_OE_N")
	)
	(via
		(at 221.03588 -109.327696)
		(size 0.508)
		(drill 0.254)
		(layers "F.Cu" "B.Cu")
		(net "FM_I3C_CPU0_MUX1_OE_N")
	)
	(via
		(at 435.87162 -169.718228)
		(size 0.508)
		(drill 0.254)
		(layers "F.Cu" "B.Cu")
		(net "FM_I3C_CPU0_MUX1_OE_N")
	)
	(via
		(at 228.346 -122.183652)
		(size 0.508)
		(drill 0.254)
		(layers "F.Cu" "B.Cu")
		(net "FM_I3C_CPU0_MUX1_OE_N")
	)
	(via
		(at 168.152064 -106.145838)
		(size 0.508)
		(drill 0.254)
		(layers "F.Cu" "B.Cu")
		(net "FM_I3C_CPU0_MUX1_OE_N")
	)
	(via
		(at 275.77542 -129.377948)
		(size 0.508)
		(drill 0.254)
		(layers "F.Cu" "B.Cu")
		(net "FM_I3C_CPU0_MUX1_OE_N")
	)
	(segment
		(start 170.794934 -105.802938)
		(end 170.589956 -105.59796)
		(width 0.10668)
		(layer "B.Cu")
		(net "FM_I3C_CPU0_MUX1_OE_N")
	)
	(segment
		(start 169.47134 -105.48874)
		(end 168.480994 -105.48874)
		(width 0.10668)
		(layer "B.Cu")
		(net "FM_I3C_CPU0_MUX1_OE_N")
	)
	(segment
		(start 170.589956 -105.59796)
		(end 169.58056 -105.59796)
		(width 0.10668)
		(layer "B.Cu")
		(net "FM_I3C_CPU0_MUX1_OE_N")
	)
	(segment
		(start 170.794934 -106.136186)
		(end 170.794934 -105.802938)
		(width 0.10668)
		(layer "B.Cu")
		(net "FM_I3C_CPU0_MUX1_OE_N")
	)
	(segment
		(start 167.39743 -106.155744)
		(end 168.142158 -106.155744)
		(width 0.10668)
		(layer "B.Cu")
		(net "FM_I3C_CPU0_MUX1_OE_N")
	)
	(segment
		(start 168.152064 -105.81767)
		(end 168.152064 -106.145838)
		(width 0.10668)
		(layer "B.Cu")
		(net "FM_I3C_CPU0_MUX1_OE_N")
	)
	(segment
		(start 169.58056 -105.59796)
		(end 169.47134 -105.48874)
		(width 0.10668)
		(layer "B.Cu")
		(net "FM_I3C_CPU0_MUX1_OE_N")
	)
	(segment
		(start 168.480994 -105.48874)
		(end 168.152064 -105.81767)
		(width 0.10668)
		(layer "B.Cu")
		(net "FM_I3C_CPU0_MUX1_OE_N")
	)
	(segment
		(start 168.142158 -106.155744)
		(end 168.152064 -106.145838)
		(width 0.10668)
		(layer "B.Cu")
		(net "FM_I3C_CPU0_MUX1_OE_N")
	)
	(segment
		(start 403.689058 -133.028182)
		(end 405.972518 -130.744722)
		(width 0.11684)
		(layer "In2.Cu")
		(net "FM_I3C_CPU0_MUX1_OE_N")
	)
	(segment
		(start 353.52482 -134.528052)
		(end 355.02469 -133.028182)
		(width 0.11684)
		(layer "In2.Cu")
		(net "FM_I3C_CPU0_MUX1_OE_N")
	)
	(segment
		(start 213.133178 -102.493318)
		(end 216.510108 -105.870248)
		(width 0.11684)
		(layer "In2.Cu")
		(net "FM_I3C_CPU0_MUX1_OE_N")
	)
	(segment
		(start 429.786034 -144.423892)
		(end 429.786034 -155.399994)
		(width 0.11684)
		(layer "In2.Cu")
		(net "FM_I3C_CPU0_MUX1_OE_N")
	)
	(segment
		(start 202.574652 -100.009198)
		(end 203.013818 -100.448364)
		(width 0.11684)
		(layer "In2.Cu")
		(net "FM_I3C_CPU0_MUX1_OE_N")
	)
	(segment
		(start 198.912734 -100.009198)
		(end 202.574652 -100.009198)
		(width 0.11684)
		(layer "In2.Cu")
		(net "FM_I3C_CPU0_MUX1_OE_N")
	)
	(segment
		(start 405.972518 -130.744722)
		(end 416.106864 -130.744722)
		(width 0.11684)
		(layer "In2.Cu")
		(net "FM_I3C_CPU0_MUX1_OE_N")
	)
	(segment
		(start 355.02469 -133.028182)
		(end 403.689058 -133.028182)
		(width 0.11684)
		(layer "In2.Cu")
		(net "FM_I3C_CPU0_MUX1_OE_N")
	)
	(segment
		(start 207.729328 -99.899978)
		(end 209.919824 -102.090474)
		(width 0.11684)
		(layer "In2.Cu")
		(net "FM_I3C_CPU0_MUX1_OE_N")
	)
	(segment
		(start 209.919824 -102.090474)
		(end 209.919824 -102.190804)
		(width 0.11684)
		(layer "In2.Cu")
		(net "FM_I3C_CPU0_MUX1_OE_N")
	)
	(segment
		(start 206.754476 -99.955096)
		(end 206.809594 -99.899978)
		(width 0.11684)
		(layer "In2.Cu")
		(net "FM_I3C_CPU0_MUX1_OE_N")
	)
	(segment
		(start 342.063832 -129.913888)
		(end 346.677996 -134.528052)
		(width 0.11684)
		(layer "In2.Cu")
		(net "FM_I3C_CPU0_MUX1_OE_N")
	)
	(segment
		(start 174.62246 -102.564692)
		(end 179.086764 -102.564692)
		(width 0.11684)
		(layer "In2.Cu")
		(net "FM_I3C_CPU0_MUX1_OE_N")
	)
	(segment
		(start 174.297594 -103.01224)
		(end 174.297594 -102.889558)
		(width 0.11684)
		(layer "In2.Cu")
		(net "FM_I3C_CPU0_MUX1_OE_N")
	)
	(segment
		(start 297.32986 -121.537984)
		(end 297.32986 -123.506484)
		(width 0.11684)
		(layer "In2.Cu")
		(net "FM_I3C_CPU0_MUX1_OE_N")
	)
	(segment
		(start 204.385164 -100.922328)
		(end 204.770736 -100.922328)
		(width 0.11684)
		(layer "In2.Cu")
		(net "FM_I3C_CPU0_MUX1_OE_N")
	)
	(segment
		(start 203.9112 -100.448364)
		(end 204.385164 -100.922328)
		(width 0.11684)
		(layer "In2.Cu")
		(net "FM_I3C_CPU0_MUX1_OE_N")
	)
	(segment
		(start 275.77542 -129.377948)
		(end 277.0505 -128.102868)
		(width 0.11684)
		(layer "In2.Cu")
		(net "FM_I3C_CPU0_MUX1_OE_N")
	)
	(segment
		(start 297.32986 -123.506484)
		(end 299.172884 -125.349508)
		(width 0.11684)
		(layer "In2.Cu")
		(net "FM_I3C_CPU0_MUX1_OE_N")
	)
	(segment
		(start 189.191392 -100.886768)
		(end 198.035164 -100.886768)
		(width 0.11684)
		(layer "In2.Cu")
		(net "FM_I3C_CPU0_MUX1_OE_N")
	)
	(segment
		(start 168.152064 -106.145838)
		(end 169.7228 -104.575102)
		(width 0.11684)
		(layer "In2.Cu")
		(net "FM_I3C_CPU0_MUX1_OE_N")
	)
	(segment
		(start 315.609732 -129.913888)
		(end 342.063832 -129.913888)
		(width 0.11684)
		(layer "In2.Cu")
		(net "FM_I3C_CPU0_MUX1_OE_N")
	)
	(segment
		(start 169.7228 -104.575102)
		(end 172.734732 -104.575102)
		(width 0.11684)
		(layer "In2.Cu")
		(net "FM_I3C_CPU0_MUX1_OE_N")
	)
	(segment
		(start 206.809594 -99.899978)
		(end 207.729328 -99.899978)
		(width 0.11684)
		(layer "In2.Cu")
		(net "FM_I3C_CPU0_MUX1_OE_N")
	)
	(segment
		(start 299.172884 -125.349508)
		(end 311.045352 -125.349508)
		(width 0.11684)
		(layer "In2.Cu")
		(net "FM_I3C_CPU0_MUX1_OE_N")
	)
	(segment
		(start 416.106864 -130.744722)
		(end 429.786034 -144.423892)
		(width 0.11684)
		(layer "In2.Cu")
		(net "FM_I3C_CPU0_MUX1_OE_N")
	)
	(segment
		(start 439.2295 -164.84346)
		(end 439.2295 -166.360348)
		(width 0.11684)
		(layer "In2.Cu")
		(net "FM_I3C_CPU0_MUX1_OE_N")
	)
	(segment
		(start 277.0505 -128.102868)
		(end 282.004516 -128.102868)
		(width 0.11684)
		(layer "In2.Cu")
		(net "FM_I3C_CPU0_MUX1_OE_N")
	)
	(segment
		(start 429.786034 -155.399994)
		(end 439.2295 -164.84346)
		(width 0.11684)
		(layer "In2.Cu")
		(net "FM_I3C_CPU0_MUX1_OE_N")
	)
	(segment
		(start 220.724984 -109.638592)
		(end 221.03588 -109.327696)
		(width 0.11684)
		(layer "In2.Cu")
		(net "FM_I3C_CPU0_MUX1_OE_N")
	)
	(segment
		(start 204.770736 -100.922328)
		(end 205.737968 -99.955096)
		(width 0.11684)
		(layer "In2.Cu")
		(net "FM_I3C_CPU0_MUX1_OE_N")
	)
	(segment
		(start 179.279804 -102.371652)
		(end 187.706508 -102.371652)
		(width 0.11684)
		(layer "In2.Cu")
		(net "FM_I3C_CPU0_MUX1_OE_N")
	)
	(segment
		(start 290.175696 -119.931688)
		(end 295.723564 -119.931688)
		(width 0.11684)
		(layer "In2.Cu")
		(net "FM_I3C_CPU0_MUX1_OE_N")
	)
	(segment
		(start 210.222338 -102.493318)
		(end 213.133178 -102.493318)
		(width 0.11684)
		(layer "In2.Cu")
		(net "FM_I3C_CPU0_MUX1_OE_N")
	)
	(segment
		(start 209.919824 -102.190804)
		(end 210.222338 -102.493318)
		(width 0.11684)
		(layer "In2.Cu")
		(net "FM_I3C_CPU0_MUX1_OE_N")
	)
	(segment
		(start 439.2295 -166.360348)
		(end 435.87162 -169.718228)
		(width 0.11684)
		(layer "In2.Cu")
		(net "FM_I3C_CPU0_MUX1_OE_N")
	)
	(segment
		(start 203.013818 -100.448364)
		(end 203.9112 -100.448364)
		(width 0.11684)
		(layer "In2.Cu")
		(net "FM_I3C_CPU0_MUX1_OE_N")
	)
	(segment
		(start 216.510108 -107.912662)
		(end 218.236038 -109.638592)
		(width 0.11684)
		(layer "In2.Cu")
		(net "FM_I3C_CPU0_MUX1_OE_N")
	)
	(segment
		(start 282.004516 -128.102868)
		(end 290.175696 -119.931688)
		(width 0.11684)
		(layer "In2.Cu")
		(net "FM_I3C_CPU0_MUX1_OE_N")
	)
	(segment
		(start 172.734732 -104.575102)
		(end 174.297594 -103.01224)
		(width 0.11684)
		(layer "In2.Cu")
		(net "FM_I3C_CPU0_MUX1_OE_N")
	)
	(segment
		(start 205.737968 -99.955096)
		(end 206.754476 -99.955096)
		(width 0.11684)
		(layer "In2.Cu")
		(net "FM_I3C_CPU0_MUX1_OE_N")
	)
	(segment
		(start 216.510108 -105.870248)
		(end 216.510108 -107.912662)
		(width 0.11684)
		(layer "In2.Cu")
		(net "FM_I3C_CPU0_MUX1_OE_N")
	)
	(segment
		(start 218.236038 -109.638592)
		(end 220.724984 -109.638592)
		(width 0.11684)
		(layer "In2.Cu")
		(net "FM_I3C_CPU0_MUX1_OE_N")
	)
	(segment
		(start 346.677996 -134.528052)
		(end 353.52482 -134.528052)
		(width 0.11684)
		(layer "In2.Cu")
		(net "FM_I3C_CPU0_MUX1_OE_N")
	)
	(segment
		(start 174.297594 -102.889558)
		(end 174.62246 -102.564692)
		(width 0.11684)
		(layer "In2.Cu")
		(net "FM_I3C_CPU0_MUX1_OE_N")
	)
	(segment
		(start 311.045352 -125.349508)
		(end 315.609732 -129.913888)
		(width 0.11684)
		(layer "In2.Cu")
		(net "FM_I3C_CPU0_MUX1_OE_N")
	)
	(segment
		(start 187.706508 -102.371652)
		(end 189.191392 -100.886768)
		(width 0.11684)
		(layer "In2.Cu")
		(net "FM_I3C_CPU0_MUX1_OE_N")
	)
	(segment
		(start 198.035164 -100.886768)
		(end 198.912734 -100.009198)
		(width 0.11684)
		(layer "In2.Cu")
		(net "FM_I3C_CPU0_MUX1_OE_N")
	)
	(segment
		(start 295.723564 -119.931688)
		(end 297.32986 -121.537984)
		(width 0.11684)
		(layer "In2.Cu")
		(net "FM_I3C_CPU0_MUX1_OE_N")
	)
	(segment
		(start 179.086764 -102.564692)
		(end 179.279804 -102.371652)
		(width 0.11684)
		(layer "In2.Cu")
		(net "FM_I3C_CPU0_MUX1_OE_N")
	)
	(segment
		(start 275.77542 -129.377948)
		(end 275.77542 -129.377694)
		(width 0.11684)
		(layer "In6.Cu")
		(net "FM_I3C_CPU0_MUX1_OE_N")
	)
	(segment
		(start 255.755902 -128.794256)
		(end 255.231646 -128.27)
		(width 0.11684)
		(layer "In6.Cu")
		(net "FM_I3C_CPU0_MUX1_OE_N")
	)
	(segment
		(start 249.64009 -127.576834)
		(end 248.468642 -126.405386)
		(width 0.11684)
		(layer "In6.Cu")
		(net "FM_I3C_CPU0_MUX1_OE_N")
	)
	(segment
		(start 236.600492 -126.405386)
		(end 232.378758 -122.183652)
		(width 0.11684)
		(layer "In6.Cu")
		(net "FM_I3C_CPU0_MUX1_OE_N")
	)
	(segment
		(start 252.08357 -128.27)
		(end 251.390404 -127.576834)
		(width 0.11684)
		(layer "In6.Cu")
		(net "FM_I3C_CPU0_MUX1_OE_N")
	)
	(segment
		(start 251.390404 -127.576834)
		(end 249.64009 -127.576834)
		(width 0.11684)
		(layer "In6.Cu")
		(net "FM_I3C_CPU0_MUX1_OE_N")
	)
	(segment
		(start 258.875022 -129.355596)
		(end 258.313682 -128.794256)
		(width 0.11684)
		(layer "In6.Cu")
		(net "FM_I3C_CPU0_MUX1_OE_N")
	)
	(segment
		(start 275.145754 -128.748028)
		(end 263.273286 -128.748028)
		(width 0.11684)
		(layer "In6.Cu")
		(net "FM_I3C_CPU0_MUX1_OE_N")
	)
	(segment
		(start 275.77542 -129.377694)
		(end 275.145754 -128.748028)
		(width 0.11684)
		(layer "In6.Cu")
		(net "FM_I3C_CPU0_MUX1_OE_N")
	)
	(segment
		(start 255.231646 -128.27)
		(end 252.08357 -128.27)
		(width 0.11684)
		(layer "In6.Cu")
		(net "FM_I3C_CPU0_MUX1_OE_N")
	)
	(segment
		(start 232.378758 -122.183652)
		(end 228.346 -122.183652)
		(width 0.11684)
		(layer "In6.Cu")
		(net "FM_I3C_CPU0_MUX1_OE_N")
	)
	(segment
		(start 248.468642 -126.405386)
		(end 236.600492 -126.405386)
		(width 0.11684)
		(layer "In6.Cu")
		(net "FM_I3C_CPU0_MUX1_OE_N")
	)
	(segment
		(start 258.313682 -128.794256)
		(end 255.755902 -128.794256)
		(width 0.11684)
		(layer "In6.Cu")
		(net "FM_I3C_CPU0_MUX1_OE_N")
	)
	(segment
		(start 263.273286 -128.748028)
		(end 262.665718 -129.355596)
		(width 0.11684)
		(layer "In6.Cu")
		(net "FM_I3C_CPU0_MUX1_OE_N")
	)
	(segment
		(start 262.665718 -129.355596)
		(end 258.875022 -129.355596)
		(width 0.11684)
		(layer "In6.Cu")
		(net "FM_I3C_CPU0_MUX1_OE_N")
	)
	(segment
		(start 222.99803 -109.327696)
		(end 228.346 -114.675666)
		(width 0.11684)
		(layer "In11.Cu")
		(net "FM_I3C_CPU0_MUX1_OE_N")
	)
	(segment
		(start 228.346 -114.675666)
		(end 228.346 -122.183652)
		(width 0.11684)
		(layer "In11.Cu")
		(net "FM_I3C_CPU0_MUX1_OE_N")
	)
	(segment
		(start 221.03588 -109.327696)
		(end 222.99803 -109.327696)
		(width 0.11684)
		(layer "In11.Cu")
		(net "FM_I3C_CPU0_MUX1_OE_N")
	)
	(segment
		(start 170.394884 -106.136948)
		(end 170.184572 -106.34726)
		(width 0.10668)
		(layer "F.Cu")
		(net "FM_I3C_CPU0_MUX0_SEL")
	)
	(segment
		(start 301.063406 -147.159726)
		(end 300.4693 -146.56562)
		(width 0.10668)
		(layer "F.Cu")
		(net "FM_I3C_CPU0_MUX0_SEL")
	)
	(segment
		(start 170.79595 -106.136948)
		(end 170.394884 -106.136948)
		(width 0.10668)
		(layer "F.Cu")
		(net "FM_I3C_CPU0_MUX0_SEL")
	)
	(segment
		(start 301.160688 -147.159726)
		(end 301.063406 -147.159726)
		(width 0.10668)
		(layer "F.Cu")
		(net "FM_I3C_CPU0_MUX0_SEL")
	)
	(via
		(at 169.106596 -145.227548)
		(size 0.508)
		(drill 0.254)
		(layers "F.Cu" "B.Cu")
		(net "FM_I3C_CPU0_MUX0_SEL")
	)
	(via
		(at 300.4693 -146.56562)
		(size 0.508)
		(drill 0.254)
		(layers "F.Cu" "B.Cu")
		(net "FM_I3C_CPU0_MUX0_SEL")
	)
	(via
		(at 170.184572 -106.34726)
		(size 0.508)
		(drill 0.254)
		(layers "F.Cu" "B.Cu")
		(net "FM_I3C_CPU0_MUX0_SEL")
	)
	(segment
		(start 171.621704 -142.71244)
		(end 169.106596 -145.227548)
		(width 0.11684)
		(layer "In6.Cu")
		(net "FM_I3C_CPU0_MUX0_SEL")
	)
	(segment
		(start 196.328792 -142.04188)
		(end 193.683382 -142.04188)
		(width 0.11684)
		(layer "In6.Cu")
		(net "FM_I3C_CPU0_MUX0_SEL")
	)
	(segment
		(start 269.22095 -149.8219)
		(end 269.22095 -150.175976)
		(width 0.11684)
		(layer "In6.Cu")
		(net "FM_I3C_CPU0_MUX0_SEL")
	)
	(segment
		(start 300.4693 -146.56562)
		(end 294.896032 -146.56562)
		(width 0.11684)
		(layer "In6.Cu")
		(net "FM_I3C_CPU0_MUX0_SEL")
	)
	(segment
		(start 274.198588 -144.844262)
		(end 269.22095 -149.8219)
		(width 0.11684)
		(layer "In6.Cu")
		(net "FM_I3C_CPU0_MUX0_SEL")
	)
	(segment
		(start 269.22095 -150.175976)
		(end 265.353038 -154.043888)
		(width 0.11684)
		(layer "In6.Cu")
		(net "FM_I3C_CPU0_MUX0_SEL")
	)
	(segment
		(start 243.363496 -147.702016)
		(end 239.875314 -144.213834)
		(width 0.11684)
		(layer "In6.Cu")
		(net "FM_I3C_CPU0_MUX0_SEL")
	)
	(segment
		(start 239.875314 -144.213834)
		(end 200.772522 -144.213834)
		(width 0.11684)
		(layer "In6.Cu")
		(net "FM_I3C_CPU0_MUX0_SEL")
	)
	(segment
		(start 249.839734 -154.043888)
		(end 243.497862 -147.702016)
		(width 0.11684)
		(layer "In6.Cu")
		(net "FM_I3C_CPU0_MUX0_SEL")
	)
	(segment
		(start 265.353038 -154.043888)
		(end 249.839734 -154.043888)
		(width 0.11684)
		(layer "In6.Cu")
		(net "FM_I3C_CPU0_MUX0_SEL")
	)
	(segment
		(start 193.012822 -142.71244)
		(end 171.621704 -142.71244)
		(width 0.11684)
		(layer "In6.Cu")
		(net "FM_I3C_CPU0_MUX0_SEL")
	)
	(segment
		(start 193.683382 -142.04188)
		(end 193.012822 -142.71244)
		(width 0.11684)
		(layer "In6.Cu")
		(net "FM_I3C_CPU0_MUX0_SEL")
	)
	(segment
		(start 197.887336 -143.600424)
		(end 196.328792 -142.04188)
		(width 0.11684)
		(layer "In6.Cu")
		(net "FM_I3C_CPU0_MUX0_SEL")
	)
	(segment
		(start 243.497862 -147.702016)
		(end 243.363496 -147.702016)
		(width 0.11684)
		(layer "In6.Cu")
		(net "FM_I3C_CPU0_MUX0_SEL")
	)
	(segment
		(start 294.896032 -146.56562)
		(end 293.174674 -144.844262)
		(width 0.11684)
		(layer "In6.Cu")
		(net "FM_I3C_CPU0_MUX0_SEL")
	)
	(segment
		(start 200.772522 -144.213834)
		(end 200.159112 -143.600424)
		(width 0.11684)
		(layer "In6.Cu")
		(net "FM_I3C_CPU0_MUX0_SEL")
	)
	(segment
		(start 200.159112 -143.600424)
		(end 197.887336 -143.600424)
		(width 0.11684)
		(layer "In6.Cu")
		(net "FM_I3C_CPU0_MUX0_SEL")
	)
	(segment
		(start 293.174674 -144.844262)
		(end 274.198588 -144.844262)
		(width 0.11684)
		(layer "In6.Cu")
		(net "FM_I3C_CPU0_MUX0_SEL")
	)
	(segment
		(start 170.184572 -106.34726)
		(end 170.184572 -107.276138)
		(width 0.11684)
		(layer "In15.Cu")
		(net "FM_I3C_CPU0_MUX0_SEL")
	)
	(segment
		(start 169.336974 -127.133096)
		(end 168.242234 -128.227836)
		(width 0.11684)
		(layer "In15.Cu")
		(net "FM_I3C_CPU0_MUX0_SEL")
	)
	(segment
		(start 168.548304 -137.076434)
		(end 169.615866 -138.143996)
		(width 0.11684)
		(layer "In15.Cu")
		(net "FM_I3C_CPU0_MUX0_SEL")
	)
	(segment
		(start 169.615866 -143.700246)
		(end 169.106596 -144.209516)
		(width 0.11684)
		(layer "In15.Cu")
		(net "FM_I3C_CPU0_MUX0_SEL")
	)
	(segment
		(start 169.106596 -144.209516)
		(end 169.106596 -145.227548)
		(width 0.11684)
		(layer "In15.Cu")
		(net "FM_I3C_CPU0_MUX0_SEL")
	)
	(segment
		(start 168.673526 -129.97434)
		(end 168.673526 -133.605524)
		(width 0.11684)
		(layer "In15.Cu")
		(net "FM_I3C_CPU0_MUX0_SEL")
	)
	(segment
		(start 168.548304 -133.730746)
		(end 168.548304 -137.076434)
		(width 0.11684)
		(layer "In15.Cu")
		(net "FM_I3C_CPU0_MUX0_SEL")
	)
	(segment
		(start 169.336974 -121.425208)
		(end 169.336974 -127.133096)
		(width 0.11684)
		(layer "In15.Cu")
		(net "FM_I3C_CPU0_MUX0_SEL")
	)
	(segment
		(start 169.615866 -138.143996)
		(end 169.615866 -143.700246)
		(width 0.11684)
		(layer "In15.Cu")
		(net "FM_I3C_CPU0_MUX0_SEL")
	)
	(segment
		(start 168.242234 -129.543048)
		(end 168.673526 -129.97434)
		(width 0.11684)
		(layer "In15.Cu")
		(net "FM_I3C_CPU0_MUX0_SEL")
	)
	(segment
		(start 170.72483 -120.037352)
		(end 169.336974 -121.425208)
		(width 0.11684)
		(layer "In15.Cu")
		(net "FM_I3C_CPU0_MUX0_SEL")
	)
	(segment
		(start 168.673526 -133.605524)
		(end 168.548304 -133.730746)
		(width 0.11684)
		(layer "In15.Cu")
		(net "FM_I3C_CPU0_MUX0_SEL")
	)
	(segment
		(start 168.242234 -128.227836)
		(end 168.242234 -129.543048)
		(width 0.11684)
		(layer "In15.Cu")
		(net "FM_I3C_CPU0_MUX0_SEL")
	)
	(segment
		(start 170.184572 -107.276138)
		(end 170.72483 -107.816396)
		(width 0.11684)
		(layer "In15.Cu")
		(net "FM_I3C_CPU0_MUX0_SEL")
	)
	(segment
		(start 170.72483 -107.816396)
		(end 170.72483 -120.037352)
		(width 0.11684)
		(layer "In15.Cu")
		(net "FM_I3C_CPU0_MUX0_SEL")
	)
	(segment
		(start 173.609 -106.95432)
		(end 176.376584 -106.95432)
		(width 0.10668)
		(layer "F.Cu")
		(net "FM_I3C_CPU0_MUX0_R_SEL")
	)
	(segment
		(start 172.004228 -106.136948)
		(end 172.8216 -106.95432)
		(width 0.10668)
		(layer "F.Cu")
		(net "FM_I3C_CPU0_MUX0_R_SEL")
	)
	(segment
		(start 177.297588 -107.046776)
		(end 177.531268 -107.280456)
		(width 0.10668)
		(layer "F.Cu")
		(net "FM_I3C_CPU0_MUX0_R_SEL")
	)
	(segment
		(start 177.531268 -107.280456)
		(end 177.531268 -107.674156)
		(width 0.10668)
		(layer "F.Cu")
		(net "FM_I3C_CPU0_MUX0_R_SEL")
	)
	(segment
		(start 176.376584 -106.95432)
		(end 176.599596 -107.046776)
		(width 0.10668)
		(layer "F.Cu")
		(net "FM_I3C_CPU0_MUX0_R_SEL")
	)
	(segment
		(start 171.59605 -106.136948)
		(end 172.004228 -106.136948)
		(width 0.10668)
		(layer "F.Cu")
		(net "FM_I3C_CPU0_MUX0_R_SEL")
	)
	(segment
		(start 172.8216 -106.95432)
		(end 173.609 -106.95432)
		(width 0.10668)
		(layer "F.Cu")
		(net "FM_I3C_CPU0_MUX0_R_SEL")
	)
	(segment
		(start 176.599596 -107.046776)
		(end 177.297588 -107.046776)
		(width 0.10668)
		(layer "F.Cu")
		(net "FM_I3C_CPU0_MUX0_R_SEL")
	)
	(segment
		(start 178.333908 -107.864656)
		(end 178.72202 -108.252768)
		(width 0.10668)
		(layer "F.Cu")
		(net "FM_I3C_CPU0_MUX0_R_SEL")
	)
	(segment
		(start 177.531268 -107.674156)
		(end 177.721768 -107.864656)
		(width 0.10668)
		(layer "F.Cu")
		(net "FM_I3C_CPU0_MUX0_R_SEL")
	)
	(segment
		(start 177.721768 -107.864656)
		(end 178.333908 -107.864656)
		(width 0.10668)
		(layer "F.Cu")
		(net "FM_I3C_CPU0_MUX0_R_SEL")
	)
	(via
		(at 173.609 -106.95432)
		(size 0.762)
		(drill 0.381)
		(layers "F.Cu" "B.Cu")
		(net "FM_I3C_CPU0_MUX0_R_SEL")
	)
	(segment
		(start 176.4284 -103.9622)
		(end 177.922174 -105.455974)
		(width 0.10668)
		(layer "F.Cu")
		(net "FM_I3C_CPU0_MUX0_OE_R_N")
	)
	(segment
		(start 177.922174 -105.455974)
		(end 177.922174 -106.652822)
		(width 0.10668)
		(layer "F.Cu")
		(net "FM_I3C_CPU0_MUX0_OE_R_N")
	)
	(segment
		(start 175.641 -100.694998)
		(end 175.79594 -100.849938)
		(width 0.10668)
		(layer "F.Cu")
		(net "FM_I3C_CPU0_MUX0_OE_R_N")
	)
	(segment
		(start 175.79594 -102.50678)
		(end 176.4284 -103.13924)
		(width 0.10668)
		(layer "F.Cu")
		(net "FM_I3C_CPU0_MUX0_OE_R_N")
	)
	(segment
		(start 175.79594 -100.849938)
		(end 175.79594 -102.50678)
		(width 0.10668)
		(layer "F.Cu")
		(net "FM_I3C_CPU0_MUX0_OE_R_N")
	)
	(segment
		(start 176.4284 -103.13924)
		(end 176.4284 -103.9622)
		(width 0.10668)
		(layer "F.Cu")
		(net "FM_I3C_CPU0_MUX0_OE_R_N")
	)
	(via
		(at 176.4284 -103.13924)
		(size 0.762)
		(drill 0.381)
		(layers "F.Cu" "B.Cu")
		(net "FM_I3C_CPU0_MUX0_OE_R_N")
	)
	(segment
		(start 301.009812 -148.65985)
		(end 300.378876 -149.290786)
		(width 0.10668)
		(layer "F.Cu")
		(net "FM_I3C_CPU0_MUX0_OE_N")
	)
	(segment
		(start 174.625 -99.894898)
		(end 174.625 -99.23272)
		(width 0.10668)
		(layer "F.Cu")
		(net "FM_I3C_CPU0_MUX0_OE_N")
	)
	(segment
		(start 301.160688 -148.65985)
		(end 301.009812 -148.65985)
		(width 0.10668)
		(layer "F.Cu")
		(net "FM_I3C_CPU0_MUX0_OE_N")
	)
	(segment
		(start 174.625 -99.894898)
		(end 175.641 -99.894898)
		(width 0.10668)
		(layer "F.Cu")
		(net "FM_I3C_CPU0_MUX0_OE_N")
	)
	(via
		(at 168.771316 -146.023584)
		(size 0.508)
		(drill 0.254)
		(layers "F.Cu" "B.Cu")
		(net "FM_I3C_CPU0_MUX0_OE_N")
	)
	(via
		(at 174.625 -99.23272)
		(size 0.508)
		(drill 0.254)
		(layers "F.Cu" "B.Cu")
		(net "FM_I3C_CPU0_MUX0_OE_N")
	)
	(via
		(at 300.378876 -149.290786)
		(size 0.508)
		(drill 0.254)
		(layers "F.Cu" "B.Cu")
		(net "FM_I3C_CPU0_MUX0_OE_N")
	)
	(via
		(at 153.932128 -106.417872)
		(size 0.508)
		(drill 0.254)
		(layers "F.Cu" "B.Cu")
		(net "FM_I3C_CPU0_MUX0_OE_N")
	)
	(segment
		(start 170.347386 -98.763328)
		(end 174.155608 -98.763328)
		(width 0.11684)
		(layer "In2.Cu")
		(net "FM_I3C_CPU0_MUX0_OE_N")
	)
	(segment
		(start 154.39517 -106.417872)
		(end 155.164282 -107.186984)
		(width 0.11684)
		(layer "In2.Cu")
		(net "FM_I3C_CPU0_MUX0_OE_N")
	)
	(segment
		(start 158.979108 -106.023918)
		(end 161.492438 -106.023918)
		(width 0.11684)
		(layer "In2.Cu")
		(net "FM_I3C_CPU0_MUX0_OE_N")
	)
	(segment
		(start 162.691318 -104.825038)
		(end 162.691318 -104.463342)
		(width 0.11684)
		(layer "In2.Cu")
		(net "FM_I3C_CPU0_MUX0_OE_N")
	)
	(segment
		(start 169.374058 -99.736656)
		(end 170.347386 -98.763328)
		(width 0.11684)
		(layer "In2.Cu")
		(net "FM_I3C_CPU0_MUX0_OE_N")
	)
	(segment
		(start 167.980106 -101.276912)
		(end 169.374058 -99.88296)
		(width 0.11684)
		(layer "In2.Cu")
		(net "FM_I3C_CPU0_MUX0_OE_N")
	)
	(segment
		(start 155.164282 -107.186984)
		(end 157.816042 -107.186984)
		(width 0.11684)
		(layer "In2.Cu")
		(net "FM_I3C_CPU0_MUX0_OE_N")
	)
	(segment
		(start 169.374058 -99.88296)
		(end 169.374058 -99.736656)
		(width 0.11684)
		(layer "In2.Cu")
		(net "FM_I3C_CPU0_MUX0_OE_N")
	)
	(segment
		(start 166.972234 -101.276912)
		(end 167.980106 -101.276912)
		(width 0.11684)
		(layer "In2.Cu")
		(net "FM_I3C_CPU0_MUX0_OE_N")
	)
	(segment
		(start 162.691318 -104.463342)
		(end 164.887148 -102.267512)
		(width 0.11684)
		(layer "In2.Cu")
		(net "FM_I3C_CPU0_MUX0_OE_N")
	)
	(segment
		(start 157.816042 -107.186984)
		(end 158.979108 -106.023918)
		(width 0.11684)
		(layer "In2.Cu")
		(net "FM_I3C_CPU0_MUX0_OE_N")
	)
	(segment
		(start 161.492438 -106.023918)
		(end 162.691318 -104.825038)
		(width 0.11684)
		(layer "In2.Cu")
		(net "FM_I3C_CPU0_MUX0_OE_N")
	)
	(segment
		(start 164.887148 -102.267512)
		(end 165.981634 -102.267512)
		(width 0.11684)
		(layer "In2.Cu")
		(net "FM_I3C_CPU0_MUX0_OE_N")
	)
	(segment
		(start 165.981634 -102.267512)
		(end 166.972234 -101.276912)
		(width 0.11684)
		(layer "In2.Cu")
		(net "FM_I3C_CPU0_MUX0_OE_N")
	)
	(segment
		(start 174.155608 -98.763328)
		(end 174.625 -99.23272)
		(width 0.11684)
		(layer "In2.Cu")
		(net "FM_I3C_CPU0_MUX0_OE_N")
	)
	(segment
		(start 153.932128 -106.417872)
		(end 154.39517 -106.417872)
		(width 0.11684)
		(layer "In2.Cu")
		(net "FM_I3C_CPU0_MUX0_OE_N")
	)
	(segment
		(start 239.626902 -144.813274)
		(end 243.115084 -148.301456)
		(width 0.11684)
		(layer "In6.Cu")
		(net "FM_I3C_CPU0_MUX0_OE_N")
	)
	(segment
		(start 249.591322 -154.643328)
		(end 265.60145 -154.643328)
		(width 0.11684)
		(layer "In6.Cu")
		(net "FM_I3C_CPU0_MUX0_OE_N")
	)
	(segment
		(start 296.257472 -149.290786)
		(end 300.378876 -149.290786)
		(width 0.11684)
		(layer "In6.Cu")
		(net "FM_I3C_CPU0_MUX0_OE_N")
	)
	(segment
		(start 265.60145 -154.643328)
		(end 269.82039 -150.424388)
		(width 0.11684)
		(layer "In6.Cu")
		(net "FM_I3C_CPU0_MUX0_OE_N")
	)
	(segment
		(start 173.497748 -143.32966)
		(end 193.287142 -143.32966)
		(width 0.11684)
		(layer "In6.Cu")
		(net "FM_I3C_CPU0_MUX0_OE_N")
	)
	(segment
		(start 274.447 -145.443702)
		(end 292.410388 -145.443702)
		(width 0.11684)
		(layer "In6.Cu")
		(net "FM_I3C_CPU0_MUX0_OE_N")
	)
	(segment
		(start 170.803824 -146.023584)
		(end 173.497748 -143.32966)
		(width 0.11684)
		(layer "In6.Cu")
		(net "FM_I3C_CPU0_MUX0_OE_N")
	)
	(segment
		(start 292.410388 -145.443702)
		(end 296.257472 -149.290786)
		(width 0.11684)
		(layer "In6.Cu")
		(net "FM_I3C_CPU0_MUX0_OE_N")
	)
	(segment
		(start 199.924162 -144.22882)
		(end 200.508616 -144.813274)
		(width 0.11684)
		(layer "In6.Cu")
		(net "FM_I3C_CPU0_MUX0_OE_N")
	)
	(segment
		(start 193.975482 -142.64132)
		(end 195.283074 -142.64132)
		(width 0.11684)
		(layer "In6.Cu")
		(net "FM_I3C_CPU0_MUX0_OE_N")
	)
	(segment
		(start 196.775324 -144.13357)
		(end 197.005448 -144.22882)
		(width 0.11684)
		(layer "In6.Cu")
		(net "FM_I3C_CPU0_MUX0_OE_N")
	)
	(segment
		(start 195.283074 -142.64132)
		(end 196.775324 -144.13357)
		(width 0.11684)
		(layer "In6.Cu")
		(net "FM_I3C_CPU0_MUX0_OE_N")
	)
	(segment
		(start 269.82039 -150.424388)
		(end 269.82039 -150.070312)
		(width 0.11684)
		(layer "In6.Cu")
		(net "FM_I3C_CPU0_MUX0_OE_N")
	)
	(segment
		(start 197.005448 -144.22882)
		(end 199.924162 -144.22882)
		(width 0.11684)
		(layer "In6.Cu")
		(net "FM_I3C_CPU0_MUX0_OE_N")
	)
	(segment
		(start 200.508616 -144.813274)
		(end 239.626902 -144.813274)
		(width 0.11684)
		(layer "In6.Cu")
		(net "FM_I3C_CPU0_MUX0_OE_N")
	)
	(segment
		(start 243.24945 -148.301456)
		(end 249.591322 -154.643328)
		(width 0.11684)
		(layer "In6.Cu")
		(net "FM_I3C_CPU0_MUX0_OE_N")
	)
	(segment
		(start 168.771316 -146.023584)
		(end 170.803824 -146.023584)
		(width 0.11684)
		(layer "In6.Cu")
		(net "FM_I3C_CPU0_MUX0_OE_N")
	)
	(segment
		(start 269.82039 -150.070312)
		(end 274.447 -145.443702)
		(width 0.11684)
		(layer "In6.Cu")
		(net "FM_I3C_CPU0_MUX0_OE_N")
	)
	(segment
		(start 243.115084 -148.301456)
		(end 243.24945 -148.301456)
		(width 0.11684)
		(layer "In6.Cu")
		(net "FM_I3C_CPU0_MUX0_OE_N")
	)
	(segment
		(start 193.287142 -143.32966)
		(end 193.975482 -142.64132)
		(width 0.11684)
		(layer "In6.Cu")
		(net "FM_I3C_CPU0_MUX0_OE_N")
	)
	(segment
		(start 154.739594 -117.82425)
		(end 155.437078 -118.521734)
		(width 0.11684)
		(layer "In11.Cu")
		(net "FM_I3C_CPU0_MUX0_OE_N")
	)
	(segment
		(start 167.239442 -137.34796)
		(end 167.239442 -144.49171)
		(width 0.11684)
		(layer "In11.Cu")
		(net "FM_I3C_CPU0_MUX0_OE_N")
	)
	(segment
		(start 167.239442 -144.49171)
		(end 168.771316 -146.023584)
		(width 0.11684)
		(layer "In11.Cu")
		(net "FM_I3C_CPU0_MUX0_OE_N")
	)
	(segment
		(start 155.437078 -118.521734)
		(end 155.437078 -122.71502)
		(width 0.11684)
		(layer "In11.Cu")
		(net "FM_I3C_CPU0_MUX0_OE_N")
	)
	(segment
		(start 155.687268 -123.319032)
		(end 159.363664 -126.995428)
		(width 0.11684)
		(layer "In11.Cu")
		(net "FM_I3C_CPU0_MUX0_OE_N")
	)
	(segment
		(start 159.363664 -126.995428)
		(end 159.363664 -129.472182)
		(width 0.11684)
		(layer "In11.Cu")
		(net "FM_I3C_CPU0_MUX0_OE_N")
	)
	(segment
		(start 153.932128 -106.417872)
		(end 154.739594 -107.225338)
		(width 0.11684)
		(layer "In11.Cu")
		(net "FM_I3C_CPU0_MUX0_OE_N")
	)
	(segment
		(start 159.363664 -129.472182)
		(end 167.239442 -137.34796)
		(width 0.11684)
		(layer "In11.Cu")
		(net "FM_I3C_CPU0_MUX0_OE_N")
	)
	(segment
		(start 154.739594 -107.225338)
		(end 154.739594 -117.82425)
		(width 0.11684)
		(layer "In11.Cu")
		(net "FM_I3C_CPU0_MUX0_OE_N")
	)
	(segment
		(start 155.437078 -122.71502)
		(end 155.687268 -123.319032)
		(width 0.11684)
		(layer "In11.Cu")
		(net "FM_I3C_CPU0_MUX0_OE_N")
	)
	(segment
		(start 189.75832 -126.292864)
		(end 189.75832 -127.287782)
		(width 0.10668)
		(layer "F.Cu")
		(net "FM_HDT_HDR_RESET_N")
	)
	(segment
		(start 189.426342 -132.845556)
		(end 189.426342 -132.263642)
		(width 0.10668)
		(layer "F.Cu")
		(net "FM_HDT_HDR_RESET_N")
	)
	(segment
		(start 189.451996 -127.594106)
		(end 189.451996 -128.308862)
		(width 0.10668)
		(layer "F.Cu")
		(net "FM_HDT_HDR_RESET_N")
	)
	(segment
		(start 189.103 -133.168898)
		(end 189.426342 -132.845556)
		(width 0.10668)
		(layer "F.Cu")
		(net "FM_HDT_HDR_RESET_N")
	)
	(segment
		(start 189.92215 -123.45289)
		(end 189.484 -123.89104)
		(width 0.10668)
		(layer "F.Cu")
		(net "FM_HDT_HDR_RESET_N")
	)
	(segment
		(start 189.644528 -132.045456)
		(end 189.644528 -131.083558)
		(width 0.10668)
		(layer "F.Cu")
		(net "FM_HDT_HDR_RESET_N")
	)
	(segment
		(start 189.426342 -132.263642)
		(end 189.644528 -132.045456)
		(width 0.10668)
		(layer "F.Cu")
		(net "FM_HDT_HDR_RESET_N")
	)
	(segment
		(start 189.484 -123.89104)
		(end 189.484 -126.018544)
		(width 0.10668)
		(layer "F.Cu")
		(net "FM_HDT_HDR_RESET_N")
	)
	(segment
		(start 189.484 -126.018544)
		(end 189.75832 -126.292864)
		(width 0.10668)
		(layer "F.Cu")
		(net "FM_HDT_HDR_RESET_N")
	)
	(segment
		(start 189.75832 -127.287782)
		(end 189.451996 -127.594106)
		(width 0.10668)
		(layer "F.Cu")
		(net "FM_HDT_HDR_RESET_N")
	)
	(segment
		(start 189.451996 -128.308862)
		(end 189.644528 -128.501394)
		(width 0.10668)
		(layer "F.Cu")
		(net "FM_HDT_HDR_RESET_N")
	)
	(segment
		(start 189.644528 -128.501394)
		(end 189.644528 -131.083558)
		(width 0.10668)
		(layer "F.Cu")
		(net "FM_HDT_HDR_RESET_N")
	)
	(via
		(at 189.644528 -131.083558)
		(size 0.4064)
		(drill 0.2032)
		(layers "F.Cu" "B.Cu")
		(net "FM_HDT_HDR_RESET_N")
	)
	(segment
		(start 190.627 -130.901948)
		(end 191.135 -130.393948)
		(width 0.10668)
		(layer "F.Cu")
		(net "FM_HDT_HDR_PWROK")
	)
	(segment
		(start 190.627 -132.660898)
		(end 190.627 -130.901948)
		(width 0.10668)
		(layer "F.Cu")
		(net "FM_HDT_HDR_PWROK")
	)
	(segment
		(start 190.119 -133.168898)
		(end 190.627 -132.660898)
		(width 0.10668)
		(layer "F.Cu")
		(net "FM_HDT_HDR_PWROK")
	)
	(segment
		(start 187.522104 -118.652798)
		(end 187.911994 -119.042688)
		(width 0.10668)
		(layer "F.Cu")
		(net "FM_HDT_HDR_PWROK")
	)
	(via
		(at 187.911994 -119.042688)
		(size 0.4572)
		(drill 0.254)
		(layers "F.Cu" "B.Cu")
		(net "FM_HDT_HDR_PWROK")
	)
	(via
		(at 191.135 -130.393948)
		(size 0.508)
		(drill 0.254)
		(layers "F.Cu" "B.Cu")
		(net "FM_HDT_HDR_PWROK")
	)
	(segment
		(start 188.237114 -122.493024)
		(end 188.237114 -124.672852)
		(width 0.11684)
		(layer "In2.Cu")
		(net "FM_HDT_HDR_PWROK")
	)
	(segment
		(start 190.643256 -127.078994)
		(end 190.643256 -128.67767)
		(width 0.11684)
		(layer "In2.Cu")
		(net "FM_HDT_HDR_PWROK")
	)
	(segment
		(start 188.237114 -124.672852)
		(end 190.643256 -127.078994)
		(width 0.11684)
		(layer "In2.Cu")
		(net "FM_HDT_HDR_PWROK")
	)
	(segment
		(start 188.313568 -122.41657)
		(end 188.237114 -122.493024)
		(width 0.11684)
		(layer "In2.Cu")
		(net "FM_HDT_HDR_PWROK")
	)
	(segment
		(start 188.313568 -119.444262)
		(end 188.313568 -122.41657)
		(width 0.11684)
		(layer "In2.Cu")
		(net "FM_HDT_HDR_PWROK")
	)
	(segment
		(start 187.911994 -119.042688)
		(end 188.313568 -119.444262)
		(width 0.11684)
		(layer "In2.Cu")
		(net "FM_HDT_HDR_PWROK")
	)
	(segment
		(start 191.135 -129.169414)
		(end 191.135 -130.393948)
		(width 0.11684)
		(layer "In2.Cu")
		(net "FM_HDT_HDR_PWROK")
	)
	(segment
		(start 190.643256 -128.67767)
		(end 191.135 -129.169414)
		(width 0.11684)
		(layer "In2.Cu")
		(net "FM_HDT_HDR_PWROK")
	)
	(segment
		(start 48.19904 -439.153554)
		(end 48.19904 -439.817256)
		(width 0.10668)
		(layer "F.Cu")
		(net "FM_GPU_PWR_EN_R_BUF")
	)
	(via
		(at 99.447604 -401.922742)
		(size 0.508)
		(drill 0.254)
		(layers "F.Cu" "B.Cu")
		(net "FM_GPU_PWR_EN_R_BUF")
	)
	(via
		(at 94.115382 -421.28567)
		(size 0.508)
		(drill 0.254)
		(layers "F.Cu" "B.Cu")
		(net "FM_GPU_PWR_EN_R_BUF")
	)
	(via
		(at 48.19904 -439.817256)
		(size 0.508)
		(drill 0.254)
		(layers "F.Cu" "B.Cu")
		(net "FM_GPU_PWR_EN_R_BUF")
	)
	(segment
		(start 81.650078 -424.689778)
		(end 85.054186 -421.28567)
		(width 0.10668)
		(layer "B.Cu")
		(net "FM_GPU_PWR_EN_R_BUF")
	)
	(segment
		(start 85.054186 -421.28567)
		(end 94.115382 -421.28567)
		(width 0.10668)
		(layer "B.Cu")
		(net "FM_GPU_PWR_EN_R_BUF")
	)
	(segment
		(start 43.908218 -424.298618)
		(end 43.908218 -410.023564)
		(width 0.11684)
		(layer "In4.Cu")
		(net "FM_GPU_PWR_EN_R_BUF")
	)
	(segment
		(start 47.5742 -437.8706)
		(end 47.5742 -431.884328)
		(width 0.11684)
		(layer "In4.Cu")
		(net "FM_GPU_PWR_EN_R_BUF")
	)
	(segment
		(start 94.721934 -399.417794)
		(end 96.48444 -401.1803)
		(width 0.11684)
		(layer "In4.Cu")
		(net "FM_GPU_PWR_EN_R_BUF")
	)
	(segment
		(start 46.4058 -426.7962)
		(end 43.908218 -424.298618)
		(width 0.11684)
		(layer "In4.Cu")
		(net "FM_GPU_PWR_EN_R_BUF")
	)
	(segment
		(start 48.19904 -438.49544)
		(end 47.5742 -437.8706)
		(width 0.11684)
		(layer "In4.Cu")
		(net "FM_GPU_PWR_EN_R_BUF")
	)
	(segment
		(start 45.910246 -403.319234)
		(end 49.811686 -399.417794)
		(width 0.11684)
		(layer "In4.Cu")
		(net "FM_GPU_PWR_EN_R_BUF")
	)
	(segment
		(start 49.811686 -399.417794)
		(end 94.721934 -399.417794)
		(width 0.11684)
		(layer "In4.Cu")
		(net "FM_GPU_PWR_EN_R_BUF")
	)
	(segment
		(start 99.447604 -401.782534)
		(end 99.447604 -401.922742)
		(width 0.11684)
		(layer "In4.Cu")
		(net "FM_GPU_PWR_EN_R_BUF")
	)
	(segment
		(start 47.5742 -431.884328)
		(end 46.4058 -430.715928)
		(width 0.11684)
		(layer "In4.Cu")
		(net "FM_GPU_PWR_EN_R_BUF")
	)
	(segment
		(start 45.910246 -408.021536)
		(end 45.910246 -403.319234)
		(width 0.11684)
		(layer "In4.Cu")
		(net "FM_GPU_PWR_EN_R_BUF")
	)
	(segment
		(start 48.19904 -439.817256)
		(end 48.19904 -438.49544)
		(width 0.11684)
		(layer "In4.Cu")
		(net "FM_GPU_PWR_EN_R_BUF")
	)
	(segment
		(start 98.84537 -401.1803)
		(end 99.447604 -401.782534)
		(width 0.11684)
		(layer "In4.Cu")
		(net "FM_GPU_PWR_EN_R_BUF")
	)
	(segment
		(start 46.4058 -430.715928)
		(end 46.4058 -426.7962)
		(width 0.11684)
		(layer "In4.Cu")
		(net "FM_GPU_PWR_EN_R_BUF")
	)
	(segment
		(start 96.48444 -401.1803)
		(end 98.84537 -401.1803)
		(width 0.11684)
		(layer "In4.Cu")
		(net "FM_GPU_PWR_EN_R_BUF")
	)
	(segment
		(start 43.908218 -410.023564)
		(end 45.910246 -408.021536)
		(width 0.11684)
		(layer "In4.Cu")
		(net "FM_GPU_PWR_EN_R_BUF")
	)
	(segment
		(start 99.566476 -410.493718)
		(end 99.566476 -405.65197)
		(width 0.11684)
		(layer "In13.Cu")
		(net "FM_GPU_PWR_EN_R_BUF")
	)
	(segment
		(start 104.459532 -422.716452)
		(end 103.806498 -422.063418)
		(width 0.11684)
		(layer "In13.Cu")
		(net "FM_GPU_PWR_EN_R_BUF")
	)
	(segment
		(start 103.806498 -418.765482)
		(end 102.281736 -417.24072)
		(width 0.11684)
		(layer "In13.Cu")
		(net "FM_GPU_PWR_EN_R_BUF")
	)
	(segment
		(start 96.455484 -428.38243)
		(end 100.67036 -428.38243)
		(width 0.11684)
		(layer "In13.Cu")
		(net "FM_GPU_PWR_EN_R_BUF")
	)
	(segment
		(start 94.115382 -421.28567)
		(end 95.423482 -422.59377)
		(width 0.11684)
		(layer "In13.Cu")
		(net "FM_GPU_PWR_EN_R_BUF")
	)
	(segment
		(start 95.423482 -422.59377)
		(end 95.423482 -427.350428)
		(width 0.11684)
		(layer "In13.Cu")
		(net "FM_GPU_PWR_EN_R_BUF")
	)
	(segment
		(start 99.447604 -402.508974)
		(end 99.447604 -401.922742)
		(width 0.11684)
		(layer "In13.Cu")
		(net "FM_GPU_PWR_EN_R_BUF")
	)
	(segment
		(start 99.252532 -402.704046)
		(end 99.447604 -402.508974)
		(width 0.11684)
		(layer "In13.Cu")
		(net "FM_GPU_PWR_EN_R_BUF")
	)
	(segment
		(start 103.806498 -422.063418)
		(end 103.806498 -418.765482)
		(width 0.11684)
		(layer "In13.Cu")
		(net "FM_GPU_PWR_EN_R_BUF")
	)
	(segment
		(start 102.281736 -413.208978)
		(end 99.566476 -410.493718)
		(width 0.11684)
		(layer "In13.Cu")
		(net "FM_GPU_PWR_EN_R_BUF")
	)
	(segment
		(start 99.566476 -405.65197)
		(end 99.252532 -405.338026)
		(width 0.11684)
		(layer "In13.Cu")
		(net "FM_GPU_PWR_EN_R_BUF")
	)
	(segment
		(start 95.423482 -427.350428)
		(end 96.455484 -428.38243)
		(width 0.11684)
		(layer "In13.Cu")
		(net "FM_GPU_PWR_EN_R_BUF")
	)
	(segment
		(start 102.281736 -417.24072)
		(end 102.281736 -413.208978)
		(width 0.11684)
		(layer "In13.Cu")
		(net "FM_GPU_PWR_EN_R_BUF")
	)
	(segment
		(start 104.459532 -424.593258)
		(end 104.459532 -422.716452)
		(width 0.11684)
		(layer "In13.Cu")
		(net "FM_GPU_PWR_EN_R_BUF")
	)
	(segment
		(start 100.67036 -428.38243)
		(end 104.459532 -424.593258)
		(width 0.11684)
		(layer "In13.Cu")
		(net "FM_GPU_PWR_EN_R_BUF")
	)
	(segment
		(start 99.252532 -405.338026)
		(end 99.252532 -402.704046)
		(width 0.11684)
		(layer "In13.Cu")
		(net "FM_GPU_PWR_EN_R_BUF")
	)
	(segment
		(start 47.18304 -438.353454)
		(end 48.19904 -438.353454)
		(width 0.10668)
		(layer "F.Cu")
		(net "FM_GPU_PWR_EN_R1")
	)
	(segment
		(start 48.06696 -437.525414)
		(end 48.06696 -437.021986)
		(width 0.10668)
		(layer "F.Cu")
		(net "FM_GPU_PWR_EN_R1")
	)
	(segment
		(start 48.19904 -437.652414)
		(end 48.19396 -437.652414)
		(width 0.10668)
		(layer "F.Cu")
		(net "FM_GPU_PWR_EN_R1")
	)
	(segment
		(start 48.19396 -437.652414)
		(end 48.06696 -437.525414)
		(width 0.10668)
		(layer "F.Cu")
		(net "FM_GPU_PWR_EN_R1")
	)
	(segment
		(start 48.19904 -438.353454)
		(end 48.19904 -437.652414)
		(width 0.10668)
		(layer "F.Cu")
		(net "FM_GPU_PWR_EN_R1")
	)
	(segment
		(start 47.18304 -438.353454)
		(end 46.16704 -438.353454)
		(width 0.10668)
		(layer "F.Cu")
		(net "FM_GPU_PWR_EN_R1")
	)
	(via
		(at 48.19904 -437.652414)
		(size 0.508)
		(drill 0.254)
		(layers "F.Cu" "B.Cu")
		(net "FM_GPU_PWR_EN_R1")
	)
	(segment
		(start 45.307504 -437.021986)
		(end 46.16704 -437.021986)
		(width 0.10668)
		(layer "F.Cu")
		(net "FM_GPU_PWR_EN_R")
	)
	(segment
		(start 209.326734 -111.576866)
		(end 210.592924 -111.576866)
		(width 0.10668)
		(layer "F.Cu")
		(net "FM_GPU_PWR_EN_R")
	)
	(segment
		(start 44.46905 -437.134)
		(end 44.46905 -438.15)
		(width 0.10668)
		(layer "F.Cu")
		(net "FM_GPU_PWR_EN_R")
	)
	(segment
		(start 44.581064 -437.021986)
		(end 45.307504 -437.021986)
		(width 0.10668)
		(layer "F.Cu")
		(net "FM_GPU_PWR_EN_R")
	)
	(segment
		(start 44.46905 -437.134)
		(end 44.581064 -437.021986)
		(width 0.10668)
		(layer "F.Cu")
		(net "FM_GPU_PWR_EN_R")
	)
	(via
		(at 45.307504 -437.021986)
		(size 0.508)
		(drill 0.254)
		(layers "F.Cu" "B.Cu")
		(net "FM_GPU_PWR_EN_R")
	)
	(via
		(at 210.592924 -111.576866)
		(size 0.508)
		(drill 0.254)
		(layers "F.Cu" "B.Cu")
		(net "FM_GPU_PWR_EN_R")
	)
	(via
		(at 207.733646 -139.921234)
		(size 0.508)
		(drill 0.254)
		(layers "F.Cu" "B.Cu")
		(net "FM_GPU_PWR_EN_R")
	)
	(segment
		(start 210.0961 -113.736882)
		(end 210.310476 -113.736882)
		(width 0.11684)
		(layer "In4.Cu")
		(net "FM_GPU_PWR_EN_R")
	)
	(segment
		(start 206.693262 -131.976368)
		(end 206.693262 -130.904234)
		(width 0.11684)
		(layer "In4.Cu")
		(net "FM_GPU_PWR_EN_R")
	)
	(segment
		(start 207.317086 -130.28041)
		(end 207.317086 -127.80264)
		(width 0.11684)
		(layer "In4.Cu")
		(net "FM_GPU_PWR_EN_R")
	)
	(segment
		(start 210.592924 -111.83366)
		(end 210.592924 -111.576866)
		(width 0.11684)
		(layer "In4.Cu")
		(net "FM_GPU_PWR_EN_R")
	)
	(segment
		(start 210.958176 -112.198912)
		(end 210.592924 -111.83366)
		(width 0.11684)
		(layer "In4.Cu")
		(net "FM_GPU_PWR_EN_R")
	)
	(segment
		(start 207.317086 -127.80264)
		(end 208.99628 -126.123446)
		(width 0.11684)
		(layer "In4.Cu")
		(net "FM_GPU_PWR_EN_R")
	)
	(segment
		(start 210.310476 -113.736882)
		(end 210.958176 -113.089182)
		(width 0.11684)
		(layer "In4.Cu")
		(net "FM_GPU_PWR_EN_R")
	)
	(segment
		(start 208.99628 -123.206002)
		(end 208.629758 -122.83948)
		(width 0.11684)
		(layer "In4.Cu")
		(net "FM_GPU_PWR_EN_R")
	)
	(segment
		(start 208.99628 -126.123446)
		(end 208.99628 -123.206002)
		(width 0.11684)
		(layer "In4.Cu")
		(net "FM_GPU_PWR_EN_R")
	)
	(segment
		(start 210.958176 -113.089182)
		(end 210.958176 -112.198912)
		(width 0.11684)
		(layer "In4.Cu")
		(net "FM_GPU_PWR_EN_R")
	)
	(segment
		(start 207.733646 -139.921234)
		(end 207.733646 -133.016752)
		(width 0.11684)
		(layer "In4.Cu")
		(net "FM_GPU_PWR_EN_R")
	)
	(segment
		(start 207.733646 -133.016752)
		(end 206.693262 -131.976368)
		(width 0.11684)
		(layer "In4.Cu")
		(net "FM_GPU_PWR_EN_R")
	)
	(segment
		(start 208.629758 -122.83948)
		(end 208.629758 -115.203224)
		(width 0.11684)
		(layer "In4.Cu")
		(net "FM_GPU_PWR_EN_R")
	)
	(segment
		(start 206.693262 -130.904234)
		(end 207.317086 -130.28041)
		(width 0.11684)
		(layer "In4.Cu")
		(net "FM_GPU_PWR_EN_R")
	)
	(segment
		(start 208.629758 -115.203224)
		(end 210.0961 -113.736882)
		(width 0.11684)
		(layer "In4.Cu")
		(net "FM_GPU_PWR_EN_R")
	)
	(segment
		(start 8.990838 -411.595062)
		(end 8.990838 -410.527754)
		(width 0.11684)
		(layer "In13.Cu")
		(net "FM_GPU_PWR_EN_R")
	)
	(segment
		(start 4.171188 -358.729788)
		(end 3.593846 -358.152446)
		(width 0.11684)
		(layer "In13.Cu")
		(net "FM_GPU_PWR_EN_R")
	)
	(segment
		(start 4.833112 -334.68564)
		(end 4.833112 -185.557414)
		(width 0.11684)
		(layer "In13.Cu")
		(net "FM_GPU_PWR_EN_R")
	)
	(segment
		(start 9.789922 -423.277284)
		(end 11.256264 -421.810942)
		(width 0.11684)
		(layer "In13.Cu")
		(net "FM_GPU_PWR_EN_R")
	)
	(segment
		(start 4.833112 -185.557414)
		(end 16.730726 -173.6598)
		(width 0.11684)
		(layer "In13.Cu")
		(net "FM_GPU_PWR_EN_R")
	)
	(segment
		(start 207.423004 -139.610592)
		(end 207.733646 -139.921234)
		(width 0.11684)
		(layer "In13.Cu")
		(net "FM_GPU_PWR_EN_R")
	)
	(segment
		(start 11.256264 -419.482524)
		(end 9.287764 -417.514024)
		(width 0.11684)
		(layer "In13.Cu")
		(net "FM_GPU_PWR_EN_R")
	)
	(segment
		(start 10.76706 -388.465822)
		(end 8.30072 -385.999482)
		(width 0.11684)
		(layer "In13.Cu")
		(net "FM_GPU_PWR_EN_R")
	)
	(segment
		(start 93.974158 -134.79526)
		(end 94.33306 -135.154162)
		(width 0.11684)
		(layer "In13.Cu")
		(net "FM_GPU_PWR_EN_R")
	)
	(segment
		(start 34.269426 -433.741576)
		(end 30.40888 -433.741576)
		(width 0.11684)
		(layer "In13.Cu")
		(net "FM_GPU_PWR_EN_R")
	)
	(segment
		(start 43.612054 -432.531012)
		(end 35.47999 -432.531012)
		(width 0.11684)
		(layer "In13.Cu")
		(net "FM_GPU_PWR_EN_R")
	)
	(segment
		(start 9.448546 -408.706574)
		(end 8.422132 -407.68016)
		(width 0.11684)
		(layer "In13.Cu")
		(net "FM_GPU_PWR_EN_R")
	)
	(segment
		(start 8.02005 -406.710134)
		(end 6.671056 -405.36114)
		(width 0.11684)
		(layer "In13.Cu")
		(net "FM_GPU_PWR_EN_R")
	)
	(segment
		(start 94.33306 -135.154162)
		(end 151.271224 -135.154162)
		(width 0.11684)
		(layer "In13.Cu")
		(net "FM_GPU_PWR_EN_R")
	)
	(segment
		(start 28.565856 -431.898552)
		(end 18.75282 -431.898552)
		(width 0.11684)
		(layer "In13.Cu")
		(net "FM_GPU_PWR_EN_R")
	)
	(segment
		(start 9.287764 -414.493202)
		(end 9.448546 -414.33242)
		(width 0.11684)
		(layer "In13.Cu")
		(net "FM_GPU_PWR_EN_R")
	)
	(segment
		(start 189.419992 -141.15796)
		(end 190.96736 -139.610592)
		(width 0.11684)
		(layer "In13.Cu")
		(net "FM_GPU_PWR_EN_R")
	)
	(segment
		(start 4.171188 -383.256536)
		(end 4.171188 -358.729788)
		(width 0.11684)
		(layer "In13.Cu")
		(net "FM_GPU_PWR_EN_R")
	)
	(segment
		(start 6.914134 -385.999482)
		(end 4.171188 -383.256536)
		(width 0.11684)
		(layer "In13.Cu")
		(net "FM_GPU_PWR_EN_R")
	)
	(segment
		(start 190.96736 -139.610592)
		(end 207.423004 -139.610592)
		(width 0.11684)
		(layer "In13.Cu")
		(net "FM_GPU_PWR_EN_R")
	)
	(segment
		(start 44.644818 -433.563776)
		(end 43.612054 -432.531012)
		(width 0.11684)
		(layer "In13.Cu")
		(net "FM_GPU_PWR_EN_R")
	)
	(segment
		(start 158.048706 -141.931644)
		(end 176.991264 -141.931644)
		(width 0.11684)
		(layer "In13.Cu")
		(net "FM_GPU_PWR_EN_R")
	)
	(segment
		(start 45.307504 -437.021986)
		(end 45.817282 -436.512208)
		(width 0.11684)
		(layer "In13.Cu")
		(net "FM_GPU_PWR_EN_R")
	)
	(segment
		(start 177.720244 -142.660624)
		(end 184.530746 -142.660624)
		(width 0.11684)
		(layer "In13.Cu")
		(net "FM_GPU_PWR_EN_R")
	)
	(segment
		(start 16.730726 -173.6598)
		(end 16.730726 -149.636226)
		(width 0.11684)
		(layer "In13.Cu")
		(net "FM_GPU_PWR_EN_R")
	)
	(segment
		(start 186.03341 -141.15796)
		(end 189.419992 -141.15796)
		(width 0.11684)
		(layer "In13.Cu")
		(net "FM_GPU_PWR_EN_R")
	)
	(segment
		(start 3.593846 -358.152446)
		(end 3.593846 -335.924906)
		(width 0.11684)
		(layer "In13.Cu")
		(net "FM_GPU_PWR_EN_R")
	)
	(segment
		(start 18.75282 -431.898552)
		(end 15.594584 -428.740316)
		(width 0.11684)
		(layer "In13.Cu")
		(net "FM_GPU_PWR_EN_R")
	)
	(segment
		(start 151.271224 -135.154162)
		(end 158.048706 -141.931644)
		(width 0.11684)
		(layer "In13.Cu")
		(net "FM_GPU_PWR_EN_R")
	)
	(segment
		(start 9.287764 -417.514024)
		(end 9.287764 -414.493202)
		(width 0.11684)
		(layer "In13.Cu")
		(net "FM_GPU_PWR_EN_R")
	)
	(segment
		(start 45.817282 -436.512208)
		(end 45.817282 -435.511702)
		(width 0.11684)
		(layer "In13.Cu")
		(net "FM_GPU_PWR_EN_R")
	)
	(segment
		(start 9.448546 -410.070046)
		(end 9.448546 -408.706574)
		(width 0.11684)
		(layer "In13.Cu")
		(net "FM_GPU_PWR_EN_R")
	)
	(segment
		(start 10.597896 -428.740316)
		(end 9.789922 -427.932342)
		(width 0.11684)
		(layer "In13.Cu")
		(net "FM_GPU_PWR_EN_R")
	)
	(segment
		(start 29.985208 -136.381744)
		(end 76.99248 -136.381744)
		(width 0.11684)
		(layer "In13.Cu")
		(net "FM_GPU_PWR_EN_R")
	)
	(segment
		(start 11.256264 -421.810942)
		(end 11.256264 -419.482524)
		(width 0.11684)
		(layer "In13.Cu")
		(net "FM_GPU_PWR_EN_R")
	)
	(segment
		(start 78.578964 -134.79526)
		(end 93.974158 -134.79526)
		(width 0.11684)
		(layer "In13.Cu")
		(net "FM_GPU_PWR_EN_R")
	)
	(segment
		(start 9.448546 -414.33242)
		(end 9.448546 -412.05277)
		(width 0.11684)
		(layer "In13.Cu")
		(net "FM_GPU_PWR_EN_R")
	)
	(segment
		(start 10.76706 -392.286744)
		(end 10.76706 -388.465822)
		(width 0.11684)
		(layer "In13.Cu")
		(net "FM_GPU_PWR_EN_R")
	)
	(segment
		(start 6.671056 -405.36114)
		(end 6.671056 -396.382748)
		(width 0.11684)
		(layer "In13.Cu")
		(net "FM_GPU_PWR_EN_R")
	)
	(segment
		(start 15.594584 -428.740316)
		(end 10.597896 -428.740316)
		(width 0.11684)
		(layer "In13.Cu")
		(net "FM_GPU_PWR_EN_R")
	)
	(segment
		(start 184.530746 -142.660624)
		(end 186.03341 -141.15796)
		(width 0.11684)
		(layer "In13.Cu")
		(net "FM_GPU_PWR_EN_R")
	)
	(segment
		(start 76.99248 -136.381744)
		(end 78.578964 -134.79526)
		(width 0.11684)
		(layer "In13.Cu")
		(net "FM_GPU_PWR_EN_R")
	)
	(segment
		(start 9.448546 -412.05277)
		(end 8.990838 -411.595062)
		(width 0.11684)
		(layer "In13.Cu")
		(net "FM_GPU_PWR_EN_R")
	)
	(segment
		(start 35.47999 -432.531012)
		(end 34.269426 -433.741576)
		(width 0.11684)
		(layer "In13.Cu")
		(net "FM_GPU_PWR_EN_R")
	)
	(segment
		(start 16.730726 -149.636226)
		(end 29.985208 -136.381744)
		(width 0.11684)
		(layer "In13.Cu")
		(net "FM_GPU_PWR_EN_R")
	)
	(segment
		(start 8.30072 -385.999482)
		(end 6.914134 -385.999482)
		(width 0.11684)
		(layer "In13.Cu")
		(net "FM_GPU_PWR_EN_R")
	)
	(segment
		(start 30.40888 -433.741576)
		(end 28.565856 -431.898552)
		(width 0.11684)
		(layer "In13.Cu")
		(net "FM_GPU_PWR_EN_R")
	)
	(segment
		(start 8.990838 -410.527754)
		(end 9.448546 -410.070046)
		(width 0.11684)
		(layer "In13.Cu")
		(net "FM_GPU_PWR_EN_R")
	)
	(segment
		(start 44.644818 -434.339238)
		(end 44.644818 -433.563776)
		(width 0.11684)
		(layer "In13.Cu")
		(net "FM_GPU_PWR_EN_R")
	)
	(segment
		(start 6.671056 -396.382748)
		(end 10.76706 -392.286744)
		(width 0.11684)
		(layer "In13.Cu")
		(net "FM_GPU_PWR_EN_R")
	)
	(segment
		(start 3.593846 -335.924906)
		(end 4.833112 -334.68564)
		(width 0.11684)
		(layer "In13.Cu")
		(net "FM_GPU_PWR_EN_R")
	)
	(segment
		(start 9.789922 -427.932342)
		(end 9.789922 -423.277284)
		(width 0.11684)
		(layer "In13.Cu")
		(net "FM_GPU_PWR_EN_R")
	)
	(segment
		(start 8.422132 -407.68016)
		(end 8.02005 -406.710134)
		(width 0.11684)
		(layer "In13.Cu")
		(net "FM_GPU_PWR_EN_R")
	)
	(segment
		(start 45.817282 -435.511702)
		(end 44.644818 -434.339238)
		(width 0.11684)
		(layer "In13.Cu")
		(net "FM_GPU_PWR_EN_R")
	)
	(segment
		(start 176.991264 -141.931644)
		(end 177.720244 -142.660624)
		(width 0.11684)
		(layer "In13.Cu")
		(net "FM_GPU_PWR_EN_R")
	)
	(via
		(at 46.363382 -425.920916)
		(size 0.508)
		(drill 0.254)
		(layers "F.Cu" "B.Cu")
		(net "FM_GPU_PWRGD_N")
	)
	(segment
		(start 46.3677 -425.925234)
		(end 47.668942 -425.925234)
		(width 0.10668)
		(layer "B.Cu")
		(net "FM_GPU_PWRGD_N")
	)
	(segment
		(start 46.434502 -425.249594)
		(end 46.363382 -425.320714)
		(width 0.10668)
		(layer "B.Cu")
		(net "FM_GPU_PWRGD_N")
	)
	(segment
		(start 46.363382 -425.320714)
		(end 46.363382 -425.920916)
		(width 0.10668)
		(layer "B.Cu")
		(net "FM_GPU_PWRGD_N")
	)
	(segment
		(start 46.434502 -424.706034)
		(end 46.434502 -425.249594)
		(width 0.10668)
		(layer "B.Cu")
		(net "FM_GPU_PWRGD_N")
	)
	(segment
		(start 46.363382 -425.920916)
		(end 46.3677 -425.925234)
		(width 0.10668)
		(layer "B.Cu")
		(net "FM_GPU_PWRGD_N")
	)
	(segment
		(start 47.668942 -425.925234)
		(end 47.668942 -425.275248)
		(width 0.10668)
		(layer "B.Cu")
		(net "FM_GPU_PWRGD_N")
	)
	(segment
		(start 209.278982 -119.721376)
		(end 210.502754 -119.721376)
		(width 0.10668)
		(layer "F.Cu")
		(net "FM_GPU_PWRGD_ISO")
	)
	(via
		(at 51.327304 -436.33263)
		(size 0.508)
		(drill 0.254)
		(layers "F.Cu" "B.Cu")
		(net "FM_GPU_PWRGD_ISO")
	)
	(via
		(at 210.118198 -139.895834)
		(size 0.508)
		(drill 0.254)
		(layers "F.Cu" "B.Cu")
		(net "FM_GPU_PWRGD_ISO")
	)
	(via
		(at 210.502754 -119.721376)
		(size 0.508)
		(drill 0.254)
		(layers "F.Cu" "B.Cu")
		(net "FM_GPU_PWRGD_ISO")
	)
	(segment
		(start 49.568862 -424.625262)
		(end 49.371758 -424.625262)
		(width 0.10668)
		(layer "B.Cu")
		(net "FM_GPU_PWRGD_ISO")
	)
	(segment
		(start 48.798226 -434.779166)
		(end 48.798226 -435.314852)
		(width 0.10668)
		(layer "B.Cu")
		(net "FM_GPU_PWRGD_ISO")
	)
	(segment
		(start 48.969422 -435.486048)
		(end 49.751742 -435.486048)
		(width 0.10668)
		(layer "B.Cu")
		(net "FM_GPU_PWRGD_ISO")
	)
	(segment
		(start 48.991012 -428.852838)
		(end 48.991012 -432.678586)
		(width 0.10668)
		(layer "B.Cu")
		(net "FM_GPU_PWRGD_ISO")
	)
	(segment
		(start 48.326548 -433.34305)
		(end 48.326548 -434.307488)
		(width 0.10668)
		(layer "B.Cu")
		(net "FM_GPU_PWRGD_ISO")
	)
	(segment
		(start 49.751742 -435.486048)
		(end 50.598324 -436.33263)
		(width 0.10668)
		(layer "B.Cu")
		(net "FM_GPU_PWRGD_ISO")
	)
	(segment
		(start 50.598324 -436.33263)
		(end 51.327304 -436.33263)
		(width 0.10668)
		(layer "B.Cu")
		(net "FM_GPU_PWRGD_ISO")
	)
	(segment
		(start 49.371758 -424.625262)
		(end 48.830484 -425.166536)
		(width 0.10668)
		(layer "B.Cu")
		(net "FM_GPU_PWRGD_ISO")
	)
	(segment
		(start 48.326548 -434.307488)
		(end 48.798226 -434.779166)
		(width 0.10668)
		(layer "B.Cu")
		(net "FM_GPU_PWRGD_ISO")
	)
	(segment
		(start 48.991012 -432.678586)
		(end 48.326548 -433.34305)
		(width 0.10668)
		(layer "B.Cu")
		(net "FM_GPU_PWRGD_ISO")
	)
	(segment
		(start 48.830484 -428.69231)
		(end 48.991012 -428.852838)
		(width 0.10668)
		(layer "B.Cu")
		(net "FM_GPU_PWRGD_ISO")
	)
	(segment
		(start 51.72964 -424.625262)
		(end 52.74564 -424.625262)
		(width 0.10668)
		(layer "B.Cu")
		(net "FM_GPU_PWRGD_ISO")
	)
	(segment
		(start 48.830484 -425.166536)
		(end 48.830484 -428.69231)
		(width 0.10668)
		(layer "B.Cu")
		(net "FM_GPU_PWRGD_ISO")
	)
	(segment
		(start 51.72964 -424.625262)
		(end 49.568862 -424.625262)
		(width 0.10668)
		(layer "B.Cu")
		(net "FM_GPU_PWRGD_ISO")
	)
	(segment
		(start 48.798226 -435.314852)
		(end 48.969422 -435.486048)
		(width 0.10668)
		(layer "B.Cu")
		(net "FM_GPU_PWRGD_ISO")
	)
	(segment
		(start 210.502754 -119.721884)
		(end 210.502754 -119.721376)
		(width 0.11684)
		(layer "In4.Cu")
		(net "FM_GPU_PWRGD_ISO")
	)
	(segment
		(start 208.724246 -131.60883)
		(end 208.724246 -128.185164)
		(width 0.11684)
		(layer "In4.Cu")
		(net "FM_GPU_PWRGD_ISO")
	)
	(segment
		(start 211.362036 -120.581166)
		(end 210.502754 -119.721884)
		(width 0.11684)
		(layer "In4.Cu")
		(net "FM_GPU_PWRGD_ISO")
	)
	(segment
		(start 210.118198 -139.895834)
		(end 209.36966 -139.147296)
		(width 0.11684)
		(layer "In4.Cu")
		(net "FM_GPU_PWRGD_ISO")
	)
	(segment
		(start 209.36966 -136.997948)
		(end 209.816446 -136.551162)
		(width 0.11684)
		(layer "In4.Cu")
		(net "FM_GPU_PWRGD_ISO")
	)
	(segment
		(start 209.816446 -132.70103)
		(end 208.724246 -131.60883)
		(width 0.11684)
		(layer "In4.Cu")
		(net "FM_GPU_PWRGD_ISO")
	)
	(segment
		(start 208.724246 -128.185164)
		(end 211.362036 -125.547374)
		(width 0.11684)
		(layer "In4.Cu")
		(net "FM_GPU_PWRGD_ISO")
	)
	(segment
		(start 211.362036 -125.547374)
		(end 211.362036 -120.581166)
		(width 0.11684)
		(layer "In4.Cu")
		(net "FM_GPU_PWRGD_ISO")
	)
	(segment
		(start 209.36966 -139.147296)
		(end 209.36966 -136.997948)
		(width 0.11684)
		(layer "In4.Cu")
		(net "FM_GPU_PWRGD_ISO")
	)
	(segment
		(start 209.816446 -136.551162)
		(end 209.816446 -132.70103)
		(width 0.11684)
		(layer "In4.Cu")
		(net "FM_GPU_PWRGD_ISO")
	)
	(segment
		(start 183.509666 -141.817344)
		(end 184.587642 -140.739368)
		(width 0.11684)
		(layer "In13.Cu")
		(net "FM_GPU_PWRGD_ISO")
	)
	(segment
		(start 32.884618 -435.49697)
		(end 29.605732 -435.49697)
		(width 0.11684)
		(layer "In13.Cu")
		(net "FM_GPU_PWRGD_ISO")
	)
	(segment
		(start 48.691292 -436.33263)
		(end 47.147988 -437.875934)
		(width 0.11684)
		(layer "In13.Cu")
		(net "FM_GPU_PWRGD_ISO")
	)
	(segment
		(start 158.366206 -141.05636)
		(end 177.680112 -141.05636)
		(width 0.11684)
		(layer "In13.Cu")
		(net "FM_GPU_PWRGD_ISO")
	)
	(segment
		(start 8.91159 -422.08323)
		(end 7.9375 -421.10914)
		(width 0.11684)
		(layer "In13.Cu")
		(net "FM_GPU_PWRGD_ISO")
	)
	(segment
		(start 36.035234 -436.418736)
		(end 33.806384 -436.418736)
		(width 0.11684)
		(layer "In13.Cu")
		(net "FM_GPU_PWRGD_ISO")
	)
	(segment
		(start 151.619712 -134.309866)
		(end 158.366206 -141.05636)
		(width 0.11684)
		(layer "In13.Cu")
		(net "FM_GPU_PWRGD_ISO")
	)
	(segment
		(start 178.193954 -140.542518)
		(end 181.32044 -140.542518)
		(width 0.11684)
		(layer "In13.Cu")
		(net "FM_GPU_PWRGD_ISO")
	)
	(segment
		(start 28.855416 -434.746654)
		(end 20.211034 -434.746654)
		(width 0.11684)
		(layer "In13.Cu")
		(net "FM_GPU_PWRGD_ISO")
	)
	(segment
		(start 3.327908 -403.360128)
		(end 3.327908 -364.419642)
		(width 0.11684)
		(layer "In13.Cu")
		(net "FM_GPU_PWRGD_ISO")
	)
	(segment
		(start 94.705678 -134.296658)
		(end 116.24945 -134.296658)
		(width 0.11684)
		(layer "In13.Cu")
		(net "FM_GPU_PWRGD_ISO")
	)
	(segment
		(start 3.327908 -364.419642)
		(end 2.750566 -363.8423)
		(width 0.11684)
		(layer "In13.Cu")
		(net "FM_GPU_PWRGD_ISO")
	)
	(segment
		(start 94.351602 -133.942582)
		(end 94.705678 -134.296658)
		(width 0.11684)
		(layer "In13.Cu")
		(net "FM_GPU_PWRGD_ISO")
	)
	(segment
		(start 177.680112 -141.05636)
		(end 178.193954 -140.542518)
		(width 0.11684)
		(layer "In13.Cu")
		(net "FM_GPU_PWRGD_ISO")
	)
	(segment
		(start 39.914576 -437.383174)
		(end 39.464488 -436.933086)
		(width 0.11684)
		(layer "In13.Cu")
		(net "FM_GPU_PWRGD_ISO")
	)
	(segment
		(start 2.750566 -335.575402)
		(end 3.989832 -334.336136)
		(width 0.11684)
		(layer "In13.Cu")
		(net "FM_GPU_PWRGD_ISO")
	)
	(segment
		(start 181.32044 -140.542518)
		(end 182.595266 -141.817344)
		(width 0.11684)
		(layer "In13.Cu")
		(net "FM_GPU_PWRGD_ISO")
	)
	(segment
		(start 29.605732 -435.49697)
		(end 28.855416 -434.746654)
		(width 0.11684)
		(layer "In13.Cu")
		(net "FM_GPU_PWRGD_ISO")
	)
	(segment
		(start 119.259604 -132.80009)
		(end 120.76938 -134.309866)
		(width 0.11684)
		(layer "In13.Cu")
		(net "FM_GPU_PWRGD_ISO")
	)
	(segment
		(start 20.211034 -434.746654)
		(end 15.058136 -429.593756)
		(width 0.11684)
		(layer "In13.Cu")
		(net "FM_GPU_PWRGD_ISO")
	)
	(segment
		(start 7.9375 -421.10914)
		(end 7.9375 -408.934158)
		(width 0.11684)
		(layer "In13.Cu")
		(net "FM_GPU_PWRGD_ISO")
	)
	(segment
		(start 38.84295 -436.933086)
		(end 37.707062 -435.797198)
		(width 0.11684)
		(layer "In13.Cu")
		(net "FM_GPU_PWRGD_ISO")
	)
	(segment
		(start 120.76938 -134.309866)
		(end 151.619712 -134.309866)
		(width 0.11684)
		(layer "In13.Cu")
		(net "FM_GPU_PWRGD_ISO")
	)
	(segment
		(start 117.746018 -132.80009)
		(end 119.259604 -132.80009)
		(width 0.11684)
		(layer "In13.Cu")
		(net "FM_GPU_PWRGD_ISO")
	)
	(segment
		(start 10.244074 -429.593756)
		(end 8.91159 -428.261272)
		(width 0.11684)
		(layer "In13.Cu")
		(net "FM_GPU_PWRGD_ISO")
	)
	(segment
		(start 39.464488 -436.933086)
		(end 38.84295 -436.933086)
		(width 0.11684)
		(layer "In13.Cu")
		(net "FM_GPU_PWRGD_ISO")
	)
	(segment
		(start 15.887446 -173.298104)
		(end 15.887446 -149.286722)
		(width 0.11684)
		(layer "In13.Cu")
		(net "FM_GPU_PWRGD_ISO")
	)
	(segment
		(start 7.9375 -408.934158)
		(end 7.25551 -407.28773)
		(width 0.11684)
		(layer "In13.Cu")
		(net "FM_GPU_PWRGD_ISO")
	)
	(segment
		(start 78.238858 -133.942582)
		(end 94.351602 -133.942582)
		(width 0.11684)
		(layer "In13.Cu")
		(net "FM_GPU_PWRGD_ISO")
	)
	(segment
		(start 116.24945 -134.296658)
		(end 117.746018 -132.80009)
		(width 0.11684)
		(layer "In13.Cu")
		(net "FM_GPU_PWRGD_ISO")
	)
	(segment
		(start 3.989832 -334.336136)
		(end 3.989832 -185.195718)
		(width 0.11684)
		(layer "In13.Cu")
		(net "FM_GPU_PWRGD_ISO")
	)
	(segment
		(start 184.587642 -138.469624)
		(end 185.070242 -137.987024)
		(width 0.11684)
		(layer "In13.Cu")
		(net "FM_GPU_PWRGD_ISO")
	)
	(segment
		(start 41.586404 -437.383174)
		(end 39.914576 -437.383174)
		(width 0.11684)
		(layer "In13.Cu")
		(net "FM_GPU_PWRGD_ISO")
	)
	(segment
		(start 8.91159 -428.261272)
		(end 8.91159 -422.08323)
		(width 0.11684)
		(layer "In13.Cu")
		(net "FM_GPU_PWRGD_ISO")
	)
	(segment
		(start 208.665826 -138.443462)
		(end 210.118198 -139.895834)
		(width 0.11684)
		(layer "In13.Cu")
		(net "FM_GPU_PWRGD_ISO")
	)
	(segment
		(start 15.058136 -429.593756)
		(end 10.244074 -429.593756)
		(width 0.11684)
		(layer "In13.Cu")
		(net "FM_GPU_PWRGD_ISO")
	)
	(segment
		(start 42.079164 -437.875934)
		(end 41.586404 -437.383174)
		(width 0.11684)
		(layer "In13.Cu")
		(net "FM_GPU_PWRGD_ISO")
	)
	(segment
		(start 198.957438 -138.443462)
		(end 208.665826 -138.443462)
		(width 0.11684)
		(layer "In13.Cu")
		(net "FM_GPU_PWRGD_ISO")
	)
	(segment
		(start 51.327304 -436.33263)
		(end 48.691292 -436.33263)
		(width 0.11684)
		(layer "In13.Cu")
		(net "FM_GPU_PWRGD_ISO")
	)
	(segment
		(start 198.501 -137.987024)
		(end 198.957438 -138.443462)
		(width 0.11684)
		(layer "In13.Cu")
		(net "FM_GPU_PWRGD_ISO")
	)
	(segment
		(start 29.635704 -135.538464)
		(end 76.642976 -135.538464)
		(width 0.11684)
		(layer "In13.Cu")
		(net "FM_GPU_PWRGD_ISO")
	)
	(segment
		(start 3.989832 -185.195718)
		(end 15.887446 -173.298104)
		(width 0.11684)
		(layer "In13.Cu")
		(net "FM_GPU_PWRGD_ISO")
	)
	(segment
		(start 47.147988 -437.875934)
		(end 42.079164 -437.875934)
		(width 0.11684)
		(layer "In13.Cu")
		(net "FM_GPU_PWRGD_ISO")
	)
	(segment
		(start 182.595266 -141.817344)
		(end 183.509666 -141.817344)
		(width 0.11684)
		(layer "In13.Cu")
		(net "FM_GPU_PWRGD_ISO")
	)
	(segment
		(start 76.642976 -135.538464)
		(end 78.238858 -133.942582)
		(width 0.11684)
		(layer "In13.Cu")
		(net "FM_GPU_PWRGD_ISO")
	)
	(segment
		(start 37.707062 -435.797198)
		(end 36.656772 -435.797198)
		(width 0.11684)
		(layer "In13.Cu")
		(net "FM_GPU_PWRGD_ISO")
	)
	(segment
		(start 184.587642 -140.739368)
		(end 184.587642 -138.469624)
		(width 0.11684)
		(layer "In13.Cu")
		(net "FM_GPU_PWRGD_ISO")
	)
	(segment
		(start 2.750566 -363.8423)
		(end 2.750566 -335.575402)
		(width 0.11684)
		(layer "In13.Cu")
		(net "FM_GPU_PWRGD_ISO")
	)
	(segment
		(start 36.656772 -435.797198)
		(end 36.035234 -436.418736)
		(width 0.11684)
		(layer "In13.Cu")
		(net "FM_GPU_PWRGD_ISO")
	)
	(segment
		(start 185.070242 -137.987024)
		(end 198.501 -137.987024)
		(width 0.11684)
		(layer "In13.Cu")
		(net "FM_GPU_PWRGD_ISO")
	)
	(segment
		(start 7.25551 -407.28773)
		(end 3.327908 -403.360128)
		(width 0.11684)
		(layer "In13.Cu")
		(net "FM_GPU_PWRGD_ISO")
	)
	(segment
		(start 15.887446 -149.286722)
		(end 29.635704 -135.538464)
		(width 0.11684)
		(layer "In13.Cu")
		(net "FM_GPU_PWRGD_ISO")
	)
	(segment
		(start 33.806384 -436.418736)
		(end 32.884618 -435.49697)
		(width 0.11684)
		(layer "In13.Cu")
		(net "FM_GPU_PWRGD_ISO")
	)
	(via
		(at 98.890582 -406.099264)
		(size 0.508)
		(drill 0.254)
		(layers "F.Cu" "B.Cu")
		(net "FM_GPU_PWRGD")
	)
	(via
		(at 50.735738 -425.603162)
		(size 0.508)
		(drill 0.254)
		(layers "F.Cu" "B.Cu")
		(net "FM_GPU_PWRGD")
	)
	(segment
		(start 50.735738 -425.603162)
		(end 51.72964 -425.603162)
		(width 0.10668)
		(layer "B.Cu")
		(net "FM_GPU_PWRGD")
	)
	(segment
		(start 97.936812 -412.124398)
		(end 95.86595 -414.19526)
		(width 0.10668)
		(layer "B.Cu")
		(net "FM_GPU_PWRGD")
	)
	(segment
		(start 98.890582 -406.099264)
		(end 97.936812 -407.053034)
		(width 0.10668)
		(layer "B.Cu")
		(net "FM_GPU_PWRGD")
	)
	(segment
		(start 51.72964 -425.603162)
		(end 52.74564 -425.603162)
		(width 0.10668)
		(layer "B.Cu")
		(net "FM_GPU_PWRGD")
	)
	(segment
		(start 87.009732 -423.330116)
		(end 85.65007 -424.689778)
		(width 0.10668)
		(layer "B.Cu")
		(net "FM_GPU_PWRGD")
	)
	(segment
		(start 95.86595 -421.13073)
		(end 93.666564 -423.330116)
		(width 0.10668)
		(layer "B.Cu")
		(net "FM_GPU_PWRGD")
	)
	(segment
		(start 93.666564 -423.330116)
		(end 87.009732 -423.330116)
		(width 0.10668)
		(layer "B.Cu")
		(net "FM_GPU_PWRGD")
	)
	(segment
		(start 97.936812 -407.053034)
		(end 97.936812 -412.124398)
		(width 0.10668)
		(layer "B.Cu")
		(net "FM_GPU_PWRGD")
	)
	(segment
		(start 49.900078 -425.275248)
		(end 50.227992 -425.603162)
		(width 0.10668)
		(layer "B.Cu")
		(net "FM_GPU_PWRGD")
	)
	(segment
		(start 50.227992 -425.603162)
		(end 50.735738 -425.603162)
		(width 0.10668)
		(layer "B.Cu")
		(net "FM_GPU_PWRGD")
	)
	(segment
		(start 49.568862 -425.275248)
		(end 49.900078 -425.275248)
		(width 0.10668)
		(layer "B.Cu")
		(net "FM_GPU_PWRGD")
	)
	(segment
		(start 95.86595 -414.19526)
		(end 95.86595 -421.13073)
		(width 0.10668)
		(layer "B.Cu")
		(net "FM_GPU_PWRGD")
	)
	(segment
		(start 46.703996 -410.226764)
		(end 46.703996 -413.048196)
		(width 0.11684)
		(layer "In4.Cu")
		(net "FM_GPU_PWRGD")
	)
	(segment
		(start 48.4378 -418.719)
		(end 49.3522 -419.6334)
		(width 0.11684)
		(layer "In4.Cu")
		(net "FM_GPU_PWRGD")
	)
	(segment
		(start 51.27625 -406.654508)
		(end 51.27625 -407.675588)
		(width 0.11684)
		(layer "In4.Cu")
		(net "FM_GPU_PWRGD")
	)
	(segment
		(start 46.703996 -413.048196)
		(end 48.4378 -414.782)
		(width 0.11684)
		(layer "In4.Cu")
		(net "FM_GPU_PWRGD")
	)
	(segment
		(start 95.857822 -404.604982)
		(end 95.857822 -404.207726)
		(width 0.11684)
		(layer "In4.Cu")
		(net "FM_GPU_PWRGD")
	)
	(segment
		(start 96.893634 -405.640794)
		(end 95.857822 -404.604982)
		(width 0.11684)
		(layer "In4.Cu")
		(net "FM_GPU_PWRGD")
	)
	(segment
		(start 93.693996 -402.0439)
		(end 54.840378 -402.0439)
		(width 0.11684)
		(layer "In4.Cu")
		(net "FM_GPU_PWRGD")
	)
	(segment
		(start 50.724562 -425.603162)
		(end 50.735738 -425.603162)
		(width 0.11684)
		(layer "In4.Cu")
		(net "FM_GPU_PWRGD")
	)
	(segment
		(start 54.840378 -402.0439)
		(end 52.81422 -404.070058)
		(width 0.11684)
		(layer "In4.Cu")
		(net "FM_GPU_PWRGD")
	)
	(segment
		(start 95.857822 -404.207726)
		(end 93.693996 -402.0439)
		(width 0.11684)
		(layer "In4.Cu")
		(net "FM_GPU_PWRGD")
	)
	(segment
		(start 50.217324 -408.734514)
		(end 48.196246 -408.734514)
		(width 0.11684)
		(layer "In4.Cu")
		(net "FM_GPU_PWRGD")
	)
	(segment
		(start 49.3522 -419.6334)
		(end 49.3522 -424.2308)
		(width 0.11684)
		(layer "In4.Cu")
		(net "FM_GPU_PWRGD")
	)
	(segment
		(start 48.4378 -414.782)
		(end 48.4378 -418.719)
		(width 0.11684)
		(layer "In4.Cu")
		(net "FM_GPU_PWRGD")
	)
	(segment
		(start 98.890582 -406.099264)
		(end 98.432112 -405.640794)
		(width 0.11684)
		(layer "In4.Cu")
		(net "FM_GPU_PWRGD")
	)
	(segment
		(start 48.196246 -408.734514)
		(end 46.703996 -410.226764)
		(width 0.11684)
		(layer "In4.Cu")
		(net "FM_GPU_PWRGD")
	)
	(segment
		(start 52.81422 -405.116538)
		(end 51.27625 -406.654508)
		(width 0.11684)
		(layer "In4.Cu")
		(net "FM_GPU_PWRGD")
	)
	(segment
		(start 51.27625 -407.675588)
		(end 50.217324 -408.734514)
		(width 0.11684)
		(layer "In4.Cu")
		(net "FM_GPU_PWRGD")
	)
	(segment
		(start 98.432112 -405.640794)
		(end 96.893634 -405.640794)
		(width 0.11684)
		(layer "In4.Cu")
		(net "FM_GPU_PWRGD")
	)
	(segment
		(start 52.81422 -404.070058)
		(end 52.81422 -405.116538)
		(width 0.11684)
		(layer "In4.Cu")
		(net "FM_GPU_PWRGD")
	)
	(segment
		(start 49.3522 -424.2308)
		(end 50.724562 -425.603162)
		(width 0.11684)
		(layer "In4.Cu")
		(net "FM_GPU_PWRGD")
	)
	(segment
		(start 194.48526 -128.675638)
		(end 194.183 -128.977898)
		(width 0.10668)
		(layer "F.Cu")
		(net "FM_FORCE_ALL_PWRON_R")
	)
	(segment
		(start 193.967608 -126.215648)
		(end 194.48526 -126.7333)
		(width 0.10668)
		(layer "F.Cu")
		(net "FM_FORCE_ALL_PWRON_R")
	)
	(segment
		(start 193.967608 -125.604524)
		(end 193.967608 -126.215648)
		(width 0.10668)
		(layer "F.Cu")
		(net "FM_FORCE_ALL_PWRON_R")
	)
	(segment
		(start 194.48526 -126.7333)
		(end 194.48526 -126.99492)
		(width 0.10668)
		(layer "F.Cu")
		(net "FM_FORCE_ALL_PWRON_R")
	)
	(segment
		(start 194.48526 -126.99492)
		(end 194.48526 -128.675638)
		(width 0.10668)
		(layer "F.Cu")
		(net "FM_FORCE_ALL_PWRON_R")
	)
	(segment
		(start 191.522096 -121.852944)
		(end 191.911986 -122.242834)
		(width 0.10668)
		(layer "F.Cu")
		(net "FM_FORCE_ALL_PWRON_R")
	)
	(segment
		(start 193.7512 -125.388116)
		(end 193.967608 -125.604524)
		(width 0.10668)
		(layer "F.Cu")
		(net "FM_FORCE_ALL_PWRON_R")
	)
	(via
		(at 193.7512 -125.388116)
		(size 0.508)
		(drill 0.254)
		(layers "F.Cu" "B.Cu")
		(net "FM_FORCE_ALL_PWRON_R")
	)
	(via
		(at 194.48526 -126.99492)
		(size 0.762)
		(drill 0.381)
		(layers "F.Cu" "B.Cu")
		(net "FM_FORCE_ALL_PWRON_R")
	)
	(via
		(at 191.911986 -122.242834)
		(size 0.4572)
		(drill 0.254)
		(layers "F.Cu" "B.Cu")
		(net "FM_FORCE_ALL_PWRON_R")
	)
	(segment
		(start 191.911986 -122.481594)
		(end 192.363344 -122.932952)
		(width 0.11684)
		(layer "In2.Cu")
		(net "FM_FORCE_ALL_PWRON_R")
	)
	(segment
		(start 192.363344 -122.932952)
		(end 192.363344 -124.00026)
		(width 0.11684)
		(layer "In2.Cu")
		(net "FM_FORCE_ALL_PWRON_R")
	)
	(segment
		(start 192.363344 -124.00026)
		(end 193.7512 -125.388116)
		(width 0.11684)
		(layer "In2.Cu")
		(net "FM_FORCE_ALL_PWRON_R")
	)
	(segment
		(start 191.911986 -122.242834)
		(end 191.911986 -122.481594)
		(width 0.11684)
		(layer "In2.Cu")
		(net "FM_FORCE_ALL_PWRON_R")
	)
	(segment
		(start 193.675508 -131.699762)
		(end 193.54546 -131.569714)
		(width 0.10668)
		(layer "F.Cu")
		(net "FM_FORCE_ALL_PWRON")
	)
	(segment
		(start 193.54546 -130.394456)
		(end 194.161918 -129.777998)
		(width 0.10668)
		(layer "F.Cu")
		(net "FM_FORCE_ALL_PWRON")
	)
	(segment
		(start 193.54546 -131.569714)
		(end 193.54546 -130.394456)
		(width 0.10668)
		(layer "F.Cu")
		(net "FM_FORCE_ALL_PWRON")
	)
	(segment
		(start 194.443604 -143.034258)
		(end 194.440556 -143.034258)
		(width 0.10668)
		(layer "F.Cu")
		(net "FM_FORCE_ALL_PWRON")
	)
	(segment
		(start 194.515486 -143.10614)
		(end 194.443604 -143.034258)
		(width 0.10668)
		(layer "F.Cu")
		(net "FM_FORCE_ALL_PWRON")
	)
	(segment
		(start 194.440556 -143.034258)
		(end 193.982594 -142.576296)
		(width 0.10668)
		(layer "F.Cu")
		(net "FM_FORCE_ALL_PWRON")
	)
	(segment
		(start 193.675508 -140.493242)
		(end 193.675508 -131.699762)
		(width 0.10668)
		(layer "F.Cu")
		(net "FM_FORCE_ALL_PWRON")
	)
	(segment
		(start 193.982594 -140.800328)
		(end 193.675508 -140.493242)
		(width 0.10668)
		(layer "F.Cu")
		(net "FM_FORCE_ALL_PWRON")
	)
	(segment
		(start 431.5714 -41.087548)
		(end 430.5554 -41.087548)
		(width 0.10668)
		(layer "F.Cu")
		(net "FM_FORCE_ALL_PWRON")
	)
	(segment
		(start 194.161918 -129.777998)
		(end 194.183 -129.777998)
		(width 0.10668)
		(layer "F.Cu")
		(net "FM_FORCE_ALL_PWRON")
	)
	(segment
		(start 193.982594 -142.576296)
		(end 193.982594 -140.800328)
		(width 0.10668)
		(layer "F.Cu")
		(net "FM_FORCE_ALL_PWRON")
	)
	(via
		(at 194.515486 -143.10614)
		(size 0.508)
		(drill 0.254)
		(layers "F.Cu" "B.Cu")
		(net "FM_FORCE_ALL_PWRON")
	)
	(via
		(at 262.740648 -144.123664)
		(size 0.508)
		(drill 0.254)
		(layers "F.Cu" "B.Cu")
		(net "FM_FORCE_ALL_PWRON")
	)
	(via
		(at 430.5554 -41.087548)
		(size 0.508)
		(drill 0.254)
		(layers "F.Cu" "B.Cu")
		(net "FM_FORCE_ALL_PWRON")
	)
	(via
		(at 269.982442 -74.943462)
		(size 0.508)
		(drill 0.254)
		(layers "F.Cu" "B.Cu")
		(net "FM_FORCE_ALL_PWRON")
	)
	(segment
		(start 429.387 -41.087548)
		(end 430.5554 -41.087548)
		(width 0.10668)
		(layer "B.Cu")
		(net "FM_FORCE_ALL_PWRON")
	)
	(segment
		(start 262.740648 -144.123664)
		(end 262.740648 -144.39138)
		(width 0.11684)
		(layer "In2.Cu")
		(net "FM_FORCE_ALL_PWRON")
	)
	(segment
		(start 196.684392 -143.64716)
		(end 194.923918 -143.64716)
		(width 0.11684)
		(layer "In2.Cu")
		(net "FM_FORCE_ALL_PWRON")
	)
	(segment
		(start 207.091788 -144.08023)
		(end 205.81874 -142.807182)
		(width 0.11684)
		(layer "In2.Cu")
		(net "FM_FORCE_ALL_PWRON")
	)
	(segment
		(start 198.608442 -143.22552)
		(end 197.106032 -143.22552)
		(width 0.11684)
		(layer "In2.Cu")
		(net "FM_FORCE_ALL_PWRON")
	)
	(segment
		(start 254.286512 -144.08023)
		(end 207.091788 -144.08023)
		(width 0.11684)
		(layer "In2.Cu")
		(net "FM_FORCE_ALL_PWRON")
	)
	(segment
		(start 199.19188 -142.642082)
		(end 198.608442 -143.22552)
		(width 0.11684)
		(layer "In2.Cu")
		(net "FM_FORCE_ALL_PWRON")
	)
	(segment
		(start 262.740648 -144.39138)
		(end 261.406386 -145.725642)
		(width 0.11684)
		(layer "In2.Cu")
		(net "FM_FORCE_ALL_PWRON")
	)
	(segment
		(start 200.733152 -142.807182)
		(end 200.568052 -142.642082)
		(width 0.11684)
		(layer "In2.Cu")
		(net "FM_FORCE_ALL_PWRON")
	)
	(segment
		(start 194.515486 -143.238728)
		(end 194.515486 -143.10614)
		(width 0.11684)
		(layer "In2.Cu")
		(net "FM_FORCE_ALL_PWRON")
	)
	(segment
		(start 200.568052 -142.642082)
		(end 199.19188 -142.642082)
		(width 0.11684)
		(layer "In2.Cu")
		(net "FM_FORCE_ALL_PWRON")
	)
	(segment
		(start 197.106032 -143.22552)
		(end 196.684392 -143.64716)
		(width 0.11684)
		(layer "In2.Cu")
		(net "FM_FORCE_ALL_PWRON")
	)
	(segment
		(start 205.81874 -142.807182)
		(end 200.733152 -142.807182)
		(width 0.11684)
		(layer "In2.Cu")
		(net "FM_FORCE_ALL_PWRON")
	)
	(segment
		(start 261.406386 -145.725642)
		(end 255.931924 -145.725642)
		(width 0.11684)
		(layer "In2.Cu")
		(net "FM_FORCE_ALL_PWRON")
	)
	(segment
		(start 194.923918 -143.64716)
		(end 194.515486 -143.238728)
		(width 0.11684)
		(layer "In2.Cu")
		(net "FM_FORCE_ALL_PWRON")
	)
	(segment
		(start 255.931924 -145.725642)
		(end 254.286512 -144.08023)
		(width 0.11684)
		(layer "In2.Cu")
		(net "FM_FORCE_ALL_PWRON")
	)
	(segment
		(start 265.252962 -130.005582)
		(end 265.252962 -116.808504)
		(width 0.11684)
		(layer "In4.Cu")
		(net "FM_FORCE_ALL_PWRON")
	)
	(segment
		(start 265.252962 -116.808504)
		(end 270.328644 -111.732822)
		(width 0.11684)
		(layer "In4.Cu")
		(net "FM_FORCE_ALL_PWRON")
	)
	(segment
		(start 262.740648 -144.123664)
		(end 264.395966 -144.123664)
		(width 0.11684)
		(layer "In4.Cu")
		(net "FM_FORCE_ALL_PWRON")
	)
	(segment
		(start 269.614142 -75.311762)
		(end 269.982442 -74.943462)
		(width 0.11684)
		(layer "In4.Cu")
		(net "FM_FORCE_ALL_PWRON")
	)
	(segment
		(start 270.328644 -111.732822)
		(end 270.328644 -98.032316)
		(width 0.11684)
		(layer "In4.Cu")
		(net "FM_FORCE_ALL_PWRON")
	)
	(segment
		(start 269.614142 -97.317814)
		(end 269.614142 -75.311762)
		(width 0.11684)
		(layer "In4.Cu")
		(net "FM_FORCE_ALL_PWRON")
	)
	(segment
		(start 266.570714 -141.948916)
		(end 266.570714 -131.323334)
		(width 0.11684)
		(layer "In4.Cu")
		(net "FM_FORCE_ALL_PWRON")
	)
	(segment
		(start 266.570714 -131.323334)
		(end 265.252962 -130.005582)
		(width 0.11684)
		(layer "In4.Cu")
		(net "FM_FORCE_ALL_PWRON")
	)
	(segment
		(start 264.395966 -144.123664)
		(end 266.570714 -141.948916)
		(width 0.11684)
		(layer "In4.Cu")
		(net "FM_FORCE_ALL_PWRON")
	)
	(segment
		(start 270.328644 -98.032316)
		(end 269.614142 -97.317814)
		(width 0.11684)
		(layer "In4.Cu")
		(net "FM_FORCE_ALL_PWRON")
	)
	(segment
		(start 329.676252 -55.611268)
		(end 329.663044 -55.59806)
		(width 0.11684)
		(layer "In6.Cu")
		(net "FM_FORCE_ALL_PWRON")
	)
	(segment
		(start 309.402988 -54.900068)
		(end 306.351178 -57.951878)
		(width 0.11684)
		(layer "In6.Cu")
		(net "FM_FORCE_ALL_PWRON")
	)
	(segment
		(start 322.875148 -54.900068)
		(end 309.402988 -54.900068)
		(width 0.11684)
		(layer "In6.Cu")
		(net "FM_FORCE_ALL_PWRON")
	)
	(segment
		(start 276.662896 -73.925176)
		(end 271.000728 -73.925176)
		(width 0.11684)
		(layer "In6.Cu")
		(net "FM_FORCE_ALL_PWRON")
	)
	(segment
		(start 415.5948 -41.798748)
		(end 414.8582 -41.062148)
		(width 0.11684)
		(layer "In6.Cu")
		(net "FM_FORCE_ALL_PWRON")
	)
	(segment
		(start 280.517854 -65.536826)
		(end 280.517854 -70.070218)
		(width 0.11684)
		(layer "In6.Cu")
		(net "FM_FORCE_ALL_PWRON")
	)
	(segment
		(start 430.5554 -41.087548)
		(end 429.8442 -41.798748)
		(width 0.11684)
		(layer "In6.Cu")
		(net "FM_FORCE_ALL_PWRON")
	)
	(segment
		(start 288.102802 -57.951878)
		(end 280.517854 -65.536826)
		(width 0.11684)
		(layer "In6.Cu")
		(net "FM_FORCE_ALL_PWRON")
	)
	(segment
		(start 395.41704 -41.062148)
		(end 380.86792 -55.611268)
		(width 0.11684)
		(layer "In6.Cu")
		(net "FM_FORCE_ALL_PWRON")
	)
	(segment
		(start 280.517854 -70.070218)
		(end 276.662896 -73.925176)
		(width 0.11684)
		(layer "In6.Cu")
		(net "FM_FORCE_ALL_PWRON")
	)
	(segment
		(start 323.57314 -55.59806)
		(end 322.875148 -54.900068)
		(width 0.11684)
		(layer "In6.Cu")
		(net "FM_FORCE_ALL_PWRON")
	)
	(segment
		(start 380.86792 -55.611268)
		(end 329.676252 -55.611268)
		(width 0.11684)
		(layer "In6.Cu")
		(net "FM_FORCE_ALL_PWRON")
	)
	(segment
		(start 329.663044 -55.59806)
		(end 323.57314 -55.59806)
		(width 0.11684)
		(layer "In6.Cu")
		(net "FM_FORCE_ALL_PWRON")
	)
	(segment
		(start 429.8442 -41.798748)
		(end 415.5948 -41.798748)
		(width 0.11684)
		(layer "In6.Cu")
		(net "FM_FORCE_ALL_PWRON")
	)
	(segment
		(start 271.000728 -73.925176)
		(end 269.982442 -74.943462)
		(width 0.11684)
		(layer "In6.Cu")
		(net "FM_FORCE_ALL_PWRON")
	)
	(segment
		(start 414.8582 -41.062148)
		(end 395.41704 -41.062148)
		(width 0.11684)
		(layer "In6.Cu")
		(net "FM_FORCE_ALL_PWRON")
	)
	(segment
		(start 306.351178 -57.951878)
		(end 288.102802 -57.951878)
		(width 0.11684)
		(layer "In6.Cu")
		(net "FM_FORCE_ALL_PWRON")
	)
	(segment
		(start 181.922166 -110.652814)
		(end 181.532276 -110.262924)
		(width 0.10668)
		(layer "F.Cu")
		(net "FM_CPU1_XTRIG_L7")
	)
	(segment
		(start 178.8922 -96.503998)
		(end 178.8922 -97.15246)
		(width 0.10668)
		(layer "F.Cu")
		(net "FM_CPU1_XTRIG_L7")
	)
	(segment
		(start 178.8922 -97.15246)
		(end 177.8 -98.24466)
		(width 0.10668)
		(layer "F.Cu")
		(net "FM_CPU1_XTRIG_L7")
	)
	(via
		(at 177.8 -98.24466)
		(size 0.762)
		(drill 0.254)
		(layers "F.Cu" "B.Cu")
		(net "FM_CPU1_XTRIG_L7")
	)
	(via
		(at 181.532276 -110.262924)
		(size 0.4572)
		(drill 0.254)
		(layers "F.Cu" "B.Cu")
		(net "FM_CPU1_XTRIG_L7")
	)
	(segment
		(start 180.332888 -109.640116)
		(end 180.561488 -109.868716)
		(width 0.11684)
		(layer "In4.Cu")
		(net "FM_CPU1_XTRIG_L7")
	)
	(segment
		(start 177.8 -98.68408)
		(end 178.17719 -99.06127)
		(width 0.11684)
		(layer "In4.Cu")
		(net "FM_CPU1_XTRIG_L7")
	)
	(segment
		(start 180.561488 -109.868716)
		(end 180.939948 -109.868716)
		(width 0.11684)
		(layer "In4.Cu")
		(net "FM_CPU1_XTRIG_L7")
	)
	(segment
		(start 178.17719 -99.06127)
		(end 178.17719 -100.190808)
		(width 0.11684)
		(layer "In4.Cu")
		(net "FM_CPU1_XTRIG_L7")
	)
	(segment
		(start 179.35194 -105.065068)
		(end 180.332888 -106.046016)
		(width 0.11684)
		(layer "In4.Cu")
		(net "FM_CPU1_XTRIG_L7")
	)
	(segment
		(start 181.334156 -110.262924)
		(end 181.532276 -110.262924)
		(width 0.11684)
		(layer "In4.Cu")
		(net "FM_CPU1_XTRIG_L7")
	)
	(segment
		(start 180.939948 -109.868716)
		(end 181.334156 -110.262924)
		(width 0.11684)
		(layer "In4.Cu")
		(net "FM_CPU1_XTRIG_L7")
	)
	(segment
		(start 177.8 -98.24466)
		(end 177.8 -98.68408)
		(width 0.11684)
		(layer "In4.Cu")
		(net "FM_CPU1_XTRIG_L7")
	)
	(segment
		(start 180.332888 -106.046016)
		(end 180.332888 -109.640116)
		(width 0.11684)
		(layer "In4.Cu")
		(net "FM_CPU1_XTRIG_L7")
	)
	(segment
		(start 179.35194 -101.365558)
		(end 179.35194 -105.065068)
		(width 0.11684)
		(layer "In4.Cu")
		(net "FM_CPU1_XTRIG_L7")
	)
	(segment
		(start 178.17719 -100.190808)
		(end 179.35194 -101.365558)
		(width 0.11684)
		(layer "In4.Cu")
		(net "FM_CPU1_XTRIG_L7")
	)
	(segment
		(start 181.122066 -110.652814)
		(end 180.732176 -110.262924)
		(width 0.10668)
		(layer "F.Cu")
		(net "FM_CPU1_XTRIG_L6")
	)
	(via
		(at 180.732176 -110.262924)
		(size 0.4572)
		(drill 0.254)
		(layers "F.Cu" "B.Cu")
		(net "FM_CPU1_XTRIG_L6")
	)
	(via
		(at 174.03318 -108.3564)
		(size 0.6604)
		(drill 0.3302)
		(layers "F.Cu" "B.Cu")
		(net "FM_CPU1_XTRIG_L6")
	)
	(segment
		(start 179.53609 -109.627416)
		(end 179.53609 -109.274356)
		(width 0.10668)
		(layer "B.Cu")
		(net "FM_CPU1_XTRIG_L6")
	)
	(segment
		(start 179.767992 -109.859318)
		(end 179.53609 -109.627416)
		(width 0.10668)
		(layer "B.Cu")
		(net "FM_CPU1_XTRIG_L6")
	)
	(segment
		(start 179.321714 -109.05998)
		(end 177.05578 -109.05998)
		(width 0.10668)
		(layer "B.Cu")
		(net "FM_CPU1_XTRIG_L6")
	)
	(segment
		(start 177.05578 -109.05998)
		(end 176.3522 -108.3564)
		(width 0.10668)
		(layer "B.Cu")
		(net "FM_CPU1_XTRIG_L6")
	)
	(segment
		(start 174.03318 -108.3564)
		(end 172.86478 -107.188)
		(width 0.10668)
		(layer "B.Cu")
		(net "FM_CPU1_XTRIG_L6")
	)
	(segment
		(start 176.3522 -108.3564)
		(end 174.03318 -108.3564)
		(width 0.10668)
		(layer "B.Cu")
		(net "FM_CPU1_XTRIG_L6")
	)
	(segment
		(start 180.732176 -110.262924)
		(end 180.32857 -109.859318)
		(width 0.10668)
		(layer "B.Cu")
		(net "FM_CPU1_XTRIG_L6")
	)
	(segment
		(start 172.86478 -107.188)
		(end 171.614338 -107.188)
		(width 0.10668)
		(layer "B.Cu")
		(net "FM_CPU1_XTRIG_L6")
	)
	(segment
		(start 179.53609 -109.274356)
		(end 179.321714 -109.05998)
		(width 0.10668)
		(layer "B.Cu")
		(net "FM_CPU1_XTRIG_L6")
	)
	(segment
		(start 180.32857 -109.859318)
		(end 179.767992 -109.859318)
		(width 0.10668)
		(layer "B.Cu")
		(net "FM_CPU1_XTRIG_L6")
	)
	(segment
		(start 179.52212 -109.052868)
		(end 179.13223 -108.662978)
		(width 0.10668)
		(layer "F.Cu")
		(net "FM_CPU1_XTRIG_L5")
	)
	(via
		(at 179.13223 -108.662978)
		(size 0.4572)
		(drill 0.254)
		(layers "F.Cu" "B.Cu")
		(net "FM_CPU1_XTRIG_L5")
	)
	(via
		(at 173.529498 -105.121202)
		(size 0.6604)
		(drill 0.3302)
		(layers "F.Cu" "B.Cu")
		(net "FM_CPU1_XTRIG_L5")
	)
	(segment
		(start 175.23206 -106.823764)
		(end 173.529498 -105.121202)
		(width 0.10668)
		(layer "B.Cu")
		(net "FM_CPU1_XTRIG_L5")
	)
	(segment
		(start 178.200304 -107.926124)
		(end 176.93894 -107.926124)
		(width 0.10668)
		(layer "B.Cu")
		(net "FM_CPU1_XTRIG_L5")
	)
	(segment
		(start 171.599098 -105.121202)
		(end 173.529498 -105.121202)
		(width 0.10668)
		(layer "B.Cu")
		(net "FM_CPU1_XTRIG_L5")
	)
	(segment
		(start 179.13223 -108.662978)
		(end 178.937158 -108.662978)
		(width 0.10668)
		(layer "B.Cu")
		(net "FM_CPU1_XTRIG_L5")
	)
	(segment
		(start 178.937158 -108.662978)
		(end 178.200304 -107.926124)
		(width 0.10668)
		(layer "B.Cu")
		(net "FM_CPU1_XTRIG_L5")
	)
	(segment
		(start 175.83658 -106.823764)
		(end 175.23206 -106.823764)
		(width 0.10668)
		(layer "B.Cu")
		(net "FM_CPU1_XTRIG_L5")
	)
	(segment
		(start 176.93894 -107.926124)
		(end 175.83658 -106.823764)
		(width 0.10668)
		(layer "B.Cu")
		(net "FM_CPU1_XTRIG_L5")
	)
	(segment
		(start 179.52212 -108.252768)
		(end 179.13223 -107.862878)
		(width 0.10668)
		(layer "F.Cu")
		(net "FM_CPU1_XTRIG_L4")
	)
	(via
		(at 179.13223 -107.862878)
		(size 0.4572)
		(drill 0.254)
		(layers "F.Cu" "B.Cu")
		(net "FM_CPU1_XTRIG_L4")
	)
	(via
		(at 177.965608 -104.638348)
		(size 0.6604)
		(drill 0.3302)
		(layers "F.Cu" "B.Cu")
		(net "FM_CPU1_XTRIG_L4")
	)
	(segment
		(start 177.965608 -104.638348)
		(end 177.781712 -104.454452)
		(width 0.10668)
		(layer "B.Cu")
		(net "FM_CPU1_XTRIG_L4")
	)
	(segment
		(start 175.641 -101.340158)
		(end 175.641 -100.694998)
		(width 0.10668)
		(layer "B.Cu")
		(net "FM_CPU1_XTRIG_L4")
	)
	(segment
		(start 177.781712 -103.48087)
		(end 175.641 -101.340158)
		(width 0.10668)
		(layer "B.Cu")
		(net "FM_CPU1_XTRIG_L4")
	)
	(segment
		(start 177.781712 -104.454452)
		(end 177.781712 -103.48087)
		(width 0.10668)
		(layer "B.Cu")
		(net "FM_CPU1_XTRIG_L4")
	)
	(segment
		(start 177.965608 -104.638348)
		(end 177.965608 -106.120438)
		(width 0.10668)
		(layer "B.Cu")
		(net "FM_CPU1_XTRIG_L4")
	)
	(segment
		(start 177.965608 -106.120438)
		(end 178.72837 -106.8832)
		(width 0.10668)
		(layer "B.Cu")
		(net "FM_CPU1_XTRIG_L4")
	)
	(segment
		(start 178.72837 -106.8832)
		(end 178.72837 -107.459018)
		(width 0.10668)
		(layer "B.Cu")
		(net "FM_CPU1_XTRIG_L4")
	)
	(segment
		(start 178.72837 -107.459018)
		(end 179.13223 -107.862878)
		(width 0.10668)
		(layer "B.Cu")
		(net "FM_CPU1_XTRIG_L4")
	)
	(segment
		(start 180.975 -127.003556)
		(end 180.975 -125.980444)
		(width 0.10668)
		(layer "F.Cu")
		(net "FM_CPU1_SYS_RESET_N")
	)
	(segment
		(start 181.513988 -125.441456)
		(end 181.513988 -123.060968)
		(width 0.10668)
		(layer "F.Cu")
		(net "FM_CPU1_SYS_RESET_N")
	)
	(segment
		(start 181.513988 -123.060968)
		(end 181.922166 -122.65279)
		(width 0.10668)
		(layer "F.Cu")
		(net "FM_CPU1_SYS_RESET_N")
	)
	(segment
		(start 180.975 -128.977898)
		(end 180.975 -127.003556)
		(width 0.10668)
		(layer "F.Cu")
		(net "FM_CPU1_SYS_RESET_N")
	)
	(segment
		(start 180.975 -125.980444)
		(end 181.513988 -125.441456)
		(width 0.10668)
		(layer "F.Cu")
		(net "FM_CPU1_SYS_RESET_N")
	)
	(via
		(at 180.975 -127.003556)
		(size 0.762)
		(drill 0.381)
		(layers "F.Cu" "B.Cu")
		(net "FM_CPU1_SYS_RESET_N")
	)
	(segment
		(start 189.12205 -109.052868)
		(end 189.51194 -108.662978)
		(width 0.10668)
		(layer "F.Cu")
		(net "FM_CPU1_SP5R4")
	)
	(via
		(at 189.51194 -108.662978)
		(size 0.4572)
		(drill 0.254)
		(layers "F.Cu" "B.Cu")
		(net "FM_CPU1_SP5R4")
	)
	(via
		(at 189.585346 -106.00055)
		(size 0.6604)
		(drill 0.3302)
		(layers "F.Cu" "B.Cu")
		(net "FM_CPU1_SP5R4")
	)
	(segment
		(start 189.1157 -108.266738)
		(end 189.51194 -108.662978)
		(width 0.10668)
		(layer "B.Cu")
		(net "FM_CPU1_SP5R4")
	)
	(segment
		(start 190.919608 -101.1428)
		(end 190.919608 -104.666288)
		(width 0.10668)
		(layer "B.Cu")
		(net "FM_CPU1_SP5R4")
	)
	(segment
		(start 190.881 -101.104192)
		(end 190.919608 -101.1428)
		(width 0.10668)
		(layer "B.Cu")
		(net "FM_CPU1_SP5R4")
	)
	(segment
		(start 190.881 -100.694998)
		(end 190.881 -101.104192)
		(width 0.10668)
		(layer "B.Cu")
		(net "FM_CPU1_SP5R4")
	)
	(segment
		(start 189.585346 -106.00055)
		(end 189.1157 -106.470196)
		(width 0.10668)
		(layer "B.Cu")
		(net "FM_CPU1_SP5R4")
	)
	(segment
		(start 190.919608 -104.666288)
		(end 189.585346 -106.00055)
		(width 0.10668)
		(layer "B.Cu")
		(net "FM_CPU1_SP5R4")
	)
	(segment
		(start 189.1157 -106.470196)
		(end 189.1157 -108.266738)
		(width 0.10668)
		(layer "B.Cu")
		(net "FM_CPU1_SP5R4")
	)
	(segment
		(start 189.12205 -108.252768)
		(end 189.51194 -107.862878)
		(width 0.10668)
		(layer "F.Cu")
		(net "FM_CPU1_SP5R3")
	)
	(via
		(at 189.51194 -107.862878)
		(size 0.4572)
		(drill 0.254)
		(layers "F.Cu" "B.Cu")
		(net "FM_CPU1_SP5R3")
	)
	(via
		(at 191.516 -102.453948)
		(size 0.6604)
		(drill 0.3302)
		(layers "F.Cu" "B.Cu")
		(net "FM_CPU1_SP5R3")
	)
	(segment
		(start 191.43091 -104.874314)
		(end 191.43091 -102.539038)
		(width 0.10668)
		(layer "B.Cu")
		(net "FM_CPU1_SP5R3")
	)
	(segment
		(start 191.897 -100.694998)
		(end 191.897 -102.072948)
		(width 0.10668)
		(layer "B.Cu")
		(net "FM_CPU1_SP5R3")
	)
	(segment
		(start 189.51194 -106.793284)
		(end 191.43091 -104.874314)
		(width 0.10668)
		(layer "B.Cu")
		(net "FM_CPU1_SP5R3")
	)
	(segment
		(start 191.897 -102.072948)
		(end 191.516 -102.453948)
		(width 0.10668)
		(layer "B.Cu")
		(net "FM_CPU1_SP5R3")
	)
	(segment
		(start 189.51194 -107.862878)
		(end 189.51194 -106.793284)
		(width 0.10668)
		(layer "B.Cu")
		(net "FM_CPU1_SP5R3")
	)
	(segment
		(start 191.43091 -102.539038)
		(end 191.516 -102.453948)
		(width 0.10668)
		(layer "B.Cu")
		(net "FM_CPU1_SP5R3")
	)
	(segment
		(start 188.322204 -109.052868)
		(end 188.712094 -108.662978)
		(width 0.10668)
		(layer "F.Cu")
		(net "FM_CPU1_SP5R2")
	)
	(via
		(at 188.849 -98.288348)
		(size 0.762)
		(drill 0.254)
		(layers "F.Cu" "B.Cu")
		(net "FM_CPU1_SP5R2")
	)
	(via
		(at 188.712094 -108.662978)
		(size 0.4572)
		(drill 0.254)
		(layers "F.Cu" "B.Cu")
		(net "FM_CPU1_SP5R2")
	)
	(segment
		(start 188.838078 -97.485962)
		(end 188.849 -97.496884)
		(width 0.10668)
		(layer "B.Cu")
		(net "FM_CPU1_SP5R2")
	)
	(segment
		(start 188.849 -97.496884)
		(end 188.849 -98.288348)
		(width 0.10668)
		(layer "B.Cu")
		(net "FM_CPU1_SP5R2")
	)
	(segment
		(start 188.303408 -105.746804)
		(end 188.303408 -108.254292)
		(width 0.11684)
		(layer "In4.Cu")
		(net "FM_CPU1_SP5R2")
	)
	(segment
		(start 188.849 -98.346768)
		(end 189.395608 -98.893376)
		(width 0.11684)
		(layer "In4.Cu")
		(net "FM_CPU1_SP5R2")
	)
	(segment
		(start 189.395608 -104.654604)
		(end 188.303408 -105.746804)
		(width 0.11684)
		(layer "In4.Cu")
		(net "FM_CPU1_SP5R2")
	)
	(segment
		(start 188.303408 -108.254292)
		(end 188.712094 -108.662978)
		(width 0.11684)
		(layer "In4.Cu")
		(net "FM_CPU1_SP5R2")
	)
	(segment
		(start 189.395608 -98.893376)
		(end 189.395608 -104.654604)
		(width 0.11684)
		(layer "In4.Cu")
		(net "FM_CPU1_SP5R2")
	)
	(segment
		(start 188.849 -98.288348)
		(end 188.849 -98.346768)
		(width 0.11684)
		(layer "In4.Cu")
		(net "FM_CPU1_SP5R2")
	)
	(segment
		(start 188.322204 -108.252768)
		(end 188.712094 -107.862878)
		(width 0.10668)
		(layer "F.Cu")
		(net "FM_CPU1_SP5R1")
	)
	(via
		(at 189.465966 -104.638602)
		(size 0.6604)
		(drill 0.3302)
		(layers "F.Cu" "B.Cu")
		(net "FM_CPU1_SP5R1")
	)
	(via
		(at 188.712094 -107.862878)
		(size 0.4572)
		(drill 0.254)
		(layers "F.Cu" "B.Cu")
		(net "FM_CPU1_SP5R1")
	)
	(segment
		(start 188.712094 -107.862878)
		(end 188.712094 -105.98912)
		(width 0.10668)
		(layer "B.Cu")
		(net "FM_CPU1_SP5R1")
	)
	(segment
		(start 190.515748 -103.58882)
		(end 190.515748 -101.54158)
		(width 0.10668)
		(layer "B.Cu")
		(net "FM_CPU1_SP5R1")
	)
	(segment
		(start 189.465966 -105.235248)
		(end 189.465966 -104.638602)
		(width 0.10668)
		(layer "B.Cu")
		(net "FM_CPU1_SP5R1")
	)
	(segment
		(start 190.515748 -101.54158)
		(end 190.411608 -101.43744)
		(width 0.10668)
		(layer "B.Cu")
		(net "FM_CPU1_SP5R1")
	)
	(segment
		(start 188.712094 -105.98912)
		(end 189.465966 -105.235248)
		(width 0.10668)
		(layer "B.Cu")
		(net "FM_CPU1_SP5R1")
	)
	(segment
		(start 190.411608 -97.968308)
		(end 190.859918 -97.519998)
		(width 0.10668)
		(layer "B.Cu")
		(net "FM_CPU1_SP5R1")
	)
	(segment
		(start 190.411608 -101.43744)
		(end 190.411608 -97.968308)
		(width 0.10668)
		(layer "B.Cu")
		(net "FM_CPU1_SP5R1")
	)
	(segment
		(start 190.859918 -97.519998)
		(end 190.881 -97.519998)
		(width 0.10668)
		(layer "B.Cu")
		(net "FM_CPU1_SP5R1")
	)
	(segment
		(start 189.465966 -104.638602)
		(end 190.515748 -103.58882)
		(width 0.10668)
		(layer "B.Cu")
		(net "FM_CPU1_SP5R1")
	)
	(segment
		(start 186.722004 -118.652798)
		(end 187.111894 -119.042688)
		(width 0.10668)
		(layer "F.Cu")
		(net "FM_CPU1_SMERR_N")
	)
	(via
		(at 187.111894 -119.042688)
		(size 0.4572)
		(drill 0.254)
		(layers "F.Cu" "B.Cu")
		(net "FM_CPU1_SMERR_N")
	)
	(via
		(at 185.647584 -121.654062)
		(size 0.6604)
		(drill 0.3302)
		(layers "F.Cu" "B.Cu")
		(net "FM_CPU1_SMERR_N")
	)
	(segment
		(start 186.712606 -119.441976)
		(end 187.111894 -119.042688)
		(width 0.10668)
		(layer "B.Cu")
		(net "FM_CPU1_SMERR_N")
	)
	(segment
		(start 187.35294 -130.068066)
		(end 186.762898 -129.478024)
		(width 0.10668)
		(layer "B.Cu")
		(net "FM_CPU1_SMERR_N")
	)
	(segment
		(start 185.646822 -121.6533)
		(end 185.646822 -121.279412)
		(width 0.10668)
		(layer "B.Cu")
		(net "FM_CPU1_SMERR_N")
	)
	(segment
		(start 185.885074 -121.04116)
		(end 186.585606 -121.04116)
		(width 0.10668)
		(layer "B.Cu")
		(net "FM_CPU1_SMERR_N")
	)
	(segment
		(start 186.762898 -129.478024)
		(end 186.762898 -128.821688)
		(width 0.10668)
		(layer "B.Cu")
		(net "FM_CPU1_SMERR_N")
	)
	(segment
		(start 186.21248 -128.27127)
		(end 186.21248 -122.964956)
		(width 0.10668)
		(layer "B.Cu")
		(net "FM_CPU1_SMERR_N")
	)
	(segment
		(start 185.646822 -122.399298)
		(end 185.646822 -121.654824)
		(width 0.10668)
		(layer "B.Cu")
		(net "FM_CPU1_SMERR_N")
	)
	(segment
		(start 185.646822 -121.654824)
		(end 185.647584 -121.654062)
		(width 0.10668)
		(layer "B.Cu")
		(net "FM_CPU1_SMERR_N")
	)
	(segment
		(start 185.647584 -121.654062)
		(end 185.646822 -121.6533)
		(width 0.10668)
		(layer "B.Cu")
		(net "FM_CPU1_SMERR_N")
	)
	(segment
		(start 186.712606 -120.91416)
		(end 186.712606 -119.441976)
		(width 0.10668)
		(layer "B.Cu")
		(net "FM_CPU1_SMERR_N")
	)
	(segment
		(start 186.585606 -121.04116)
		(end 186.712606 -120.91416)
		(width 0.10668)
		(layer "B.Cu")
		(net "FM_CPU1_SMERR_N")
	)
	(segment
		(start 186.21248 -122.964956)
		(end 185.646822 -122.399298)
		(width 0.10668)
		(layer "B.Cu")
		(net "FM_CPU1_SMERR_N")
	)
	(segment
		(start 186.762898 -128.821688)
		(end 186.21248 -128.27127)
		(width 0.10668)
		(layer "B.Cu")
		(net "FM_CPU1_SMERR_N")
	)
	(segment
		(start 185.646822 -121.279412)
		(end 185.885074 -121.04116)
		(width 0.10668)
		(layer "B.Cu")
		(net "FM_CPU1_SMERR_N")
	)
	(segment
		(start 177.870612 -128.32969)
		(end 177.870612 -126.989332)
		(width 0.10668)
		(layer "F.Cu")
		(net "FM_CPU1_SLP_S5_N")
	)
	(segment
		(start 177.927 -128.386078)
		(end 177.870612 -128.32969)
		(width 0.10668)
		(layer "F.Cu")
		(net "FM_CPU1_SLP_S5_N")
	)
	(segment
		(start 177.870612 -126.989332)
		(end 177.870612 -126.568708)
		(width 0.10668)
		(layer "F.Cu")
		(net "FM_CPU1_SLP_S5_N")
	)
	(segment
		(start 179.52212 -124.177298)
		(end 179.52212 -123.45289)
		(width 0.10668)
		(layer "F.Cu")
		(net "FM_CPU1_SLP_S5_N")
	)
	(segment
		(start 178.943 -124.756418)
		(end 179.52212 -124.177298)
		(width 0.10668)
		(layer "F.Cu")
		(net "FM_CPU1_SLP_S5_N")
	)
	(segment
		(start 177.870612 -126.568708)
		(end 178.943 -125.49632)
		(width 0.10668)
		(layer "F.Cu")
		(net "FM_CPU1_SLP_S5_N")
	)
	(segment
		(start 178.943 -125.49632)
		(end 178.943 -124.756418)
		(width 0.10668)
		(layer "F.Cu")
		(net "FM_CPU1_SLP_S5_N")
	)
	(segment
		(start 177.927 -128.977898)
		(end 177.927 -128.386078)
		(width 0.10668)
		(layer "F.Cu")
		(net "FM_CPU1_SLP_S5_N")
	)
	(via
		(at 177.870612 -126.989332)
		(size 0.762)
		(drill 0.381)
		(layers "F.Cu" "B.Cu")
		(net "FM_CPU1_SLP_S5_N")
	)
	(segment
		(start 177.129186 -128.048512)
		(end 177.129186 -126.253748)
		(width 0.10668)
		(layer "F.Cu")
		(net "FM_CPU1_SLP_S3_N")
	)
	(segment
		(start 179.128928 -124.254006)
		(end 179.128928 -123.045982)
		(width 0.10668)
		(layer "F.Cu")
		(net "FM_CPU1_SLP_S3_N")
	)
	(segment
		(start 176.911 -128.266698)
		(end 177.129186 -128.048512)
		(width 0.10668)
		(layer "F.Cu")
		(net "FM_CPU1_SLP_S3_N")
	)
	(segment
		(start 177.129186 -126.253748)
		(end 179.128928 -124.254006)
		(width 0.10668)
		(layer "F.Cu")
		(net "FM_CPU1_SLP_S3_N")
	)
	(segment
		(start 176.911 -128.977898)
		(end 176.911 -128.266698)
		(width 0.10668)
		(layer "F.Cu")
		(net "FM_CPU1_SLP_S3_N")
	)
	(segment
		(start 179.128928 -123.045982)
		(end 179.52212 -122.65279)
		(width 0.10668)
		(layer "F.Cu")
		(net "FM_CPU1_SLP_S3_N")
	)
	(via
		(at 177.129186 -128.048512)
		(size 0.762)
		(drill 0.381)
		(layers "F.Cu" "B.Cu")
		(net "FM_CPU1_SLP_S3_N")
	)
	(segment
		(start 181.922166 -111.452914)
		(end 181.532276 -111.063024)
		(width 0.10668)
		(layer "F.Cu")
		(net "FM_CPU1_SA1")
	)
	(via
		(at 181.532276 -111.063024)
		(size 0.4572)
		(drill 0.254)
		(layers "F.Cu" "B.Cu")
		(net "FM_CPU1_SA1")
	)
	(via
		(at 194.945 -101.97338)
		(size 0.508)
		(drill 0.254)
		(layers "F.Cu" "B.Cu")
		(net "FM_CPU1_SA1")
	)
	(segment
		(start 194.945 -100.694998)
		(end 194.945 -101.97338)
		(width 0.10668)
		(layer "B.Cu")
		(net "FM_CPU1_SA1")
	)
	(segment
		(start 184.977024 -109.060234)
		(end 182.11927 -109.060234)
		(width 0.11684)
		(layer "In2.Cu")
		(net "FM_CPU1_SA1")
	)
	(segment
		(start 194.945 -101.97338)
		(end 194.94246 -101.97338)
		(width 0.11684)
		(layer "In2.Cu")
		(net "FM_CPU1_SA1")
	)
	(segment
		(start 194.94246 -101.97338)
		(end 194.393058 -102.522782)
		(width 0.11684)
		(layer "In2.Cu")
		(net "FM_CPU1_SA1")
	)
	(segment
		(start 185.131202 -108.906056)
		(end 184.977024 -109.060234)
		(width 0.11684)
		(layer "In2.Cu")
		(net "FM_CPU1_SA1")
	)
	(segment
		(start 194.393058 -102.522782)
		(end 193.606166 -102.522782)
		(width 0.11684)
		(layer "In2.Cu")
		(net "FM_CPU1_SA1")
	)
	(segment
		(start 181.928008 -110.667292)
		(end 181.532276 -111.063024)
		(width 0.11684)
		(layer "In2.Cu")
		(net "FM_CPU1_SA1")
	)
	(segment
		(start 185.131202 -105.535476)
		(end 185.131202 -108.906056)
		(width 0.11684)
		(layer "In2.Cu")
		(net "FM_CPU1_SA1")
	)
	(segment
		(start 185.538872 -105.127806)
		(end 185.131202 -105.535476)
		(width 0.11684)
		(layer "In2.Cu")
		(net "FM_CPU1_SA1")
	)
	(segment
		(start 182.11927 -109.060234)
		(end 181.928008 -109.251496)
		(width 0.11684)
		(layer "In2.Cu")
		(net "FM_CPU1_SA1")
	)
	(segment
		(start 193.606166 -102.522782)
		(end 192.917826 -103.211122)
		(width 0.11684)
		(layer "In2.Cu")
		(net "FM_CPU1_SA1")
	)
	(segment
		(start 192.917826 -103.211122)
		(end 191.531494 -103.211122)
		(width 0.11684)
		(layer "In2.Cu")
		(net "FM_CPU1_SA1")
	)
	(segment
		(start 189.61481 -105.127806)
		(end 185.538872 -105.127806)
		(width 0.11684)
		(layer "In2.Cu")
		(net "FM_CPU1_SA1")
	)
	(segment
		(start 181.928008 -109.251496)
		(end 181.928008 -110.667292)
		(width 0.11684)
		(layer "In2.Cu")
		(net "FM_CPU1_SA1")
	)
	(segment
		(start 191.531494 -103.211122)
		(end 189.61481 -105.127806)
		(width 0.11684)
		(layer "In2.Cu")
		(net "FM_CPU1_SA1")
	)
	(segment
		(start 183.522112 -111.452914)
		(end 183.132222 -111.063024)
		(width 0.10668)
		(layer "F.Cu")
		(net "FM_CPU1_SA0")
	)
	(via
		(at 183.132222 -111.063024)
		(size 0.4572)
		(drill 0.254)
		(layers "F.Cu" "B.Cu")
		(net "FM_CPU1_SA0")
	)
	(via
		(at 192.343532 -103.825802)
		(size 0.508)
		(drill 0.254)
		(layers "F.Cu" "B.Cu")
		(net "FM_CPU1_SA0")
	)
	(segment
		(start 193.929 -97.519998)
		(end 194.130168 -97.519998)
		(width 0.10668)
		(layer "B.Cu")
		(net "FM_CPU1_SA0")
	)
	(segment
		(start 194.130168 -97.519998)
		(end 194.463416 -97.853246)
		(width 0.10668)
		(layer "B.Cu")
		(net "FM_CPU1_SA0")
	)
	(segment
		(start 194.463416 -101.45141)
		(end 193.698114 -102.216712)
		(width 0.10668)
		(layer "B.Cu")
		(net "FM_CPU1_SA0")
	)
	(segment
		(start 194.463416 -97.853246)
		(end 194.463416 -101.45141)
		(width 0.10668)
		(layer "B.Cu")
		(net "FM_CPU1_SA0")
	)
	(segment
		(start 193.698114 -102.216712)
		(end 193.698114 -102.47122)
		(width 0.10668)
		(layer "B.Cu")
		(net "FM_CPU1_SA0")
	)
	(segment
		(start 193.698114 -102.47122)
		(end 192.343532 -103.825802)
		(width 0.10668)
		(layer "B.Cu")
		(net "FM_CPU1_SA0")
	)
	(segment
		(start 183.679592 -110.654846)
		(end 185.188606 -110.654846)
		(width 0.11684)
		(layer "In2.Cu")
		(net "FM_CPU1_SA0")
	)
	(segment
		(start 185.725816 -105.612692)
		(end 189.845188 -105.612692)
		(width 0.11684)
		(layer "In2.Cu")
		(net "FM_CPU1_SA0")
	)
	(segment
		(start 185.364882 -110.47857)
		(end 185.364882 -105.973626)
		(width 0.11684)
		(layer "In2.Cu")
		(net "FM_CPU1_SA0")
	)
	(segment
		(start 191.537082 -103.920798)
		(end 192.248536 -103.920798)
		(width 0.11684)
		(layer "In2.Cu")
		(net "FM_CPU1_SA0")
	)
	(segment
		(start 185.188606 -110.654846)
		(end 185.364882 -110.47857)
		(width 0.11684)
		(layer "In2.Cu")
		(net "FM_CPU1_SA0")
	)
	(segment
		(start 185.364882 -105.973626)
		(end 185.725816 -105.612692)
		(width 0.11684)
		(layer "In2.Cu")
		(net "FM_CPU1_SA0")
	)
	(segment
		(start 189.845188 -105.612692)
		(end 191.537082 -103.920798)
		(width 0.11684)
		(layer "In2.Cu")
		(net "FM_CPU1_SA0")
	)
	(segment
		(start 183.271414 -111.063024)
		(end 183.679592 -110.654846)
		(width 0.11684)
		(layer "In2.Cu")
		(net "FM_CPU1_SA0")
	)
	(segment
		(start 183.132222 -111.063024)
		(end 183.271414 -111.063024)
		(width 0.11684)
		(layer "In2.Cu")
		(net "FM_CPU1_SA0")
	)
	(segment
		(start 192.248536 -103.920798)
		(end 192.343532 -103.825802)
		(width 0.11684)
		(layer "In2.Cu")
		(net "FM_CPU1_SA0")
	)
	(segment
		(start 181.122066 -123.45289)
		(end 181.122066 -123.951492)
		(width 0.10668)
		(layer "F.Cu")
		(net "FM_CPU1_RSMRST_N")
	)
	(segment
		(start 179.959 -128.36779)
		(end 179.959 -128.977898)
		(width 0.10668)
		(layer "F.Cu")
		(net "FM_CPU1_RSMRST_N")
	)
	(segment
		(start 181.122066 -123.951492)
		(end 180.23078 -124.842778)
		(width 0.10668)
		(layer "F.Cu")
		(net "FM_CPU1_RSMRST_N")
	)
	(segment
		(start 180.23078 -124.842778)
		(end 180.23078 -128.09601)
		(width 0.10668)
		(layer "F.Cu")
		(net "FM_CPU1_RSMRST_N")
	)
	(segment
		(start 180.23078 -128.09601)
		(end 179.959 -128.36779)
		(width 0.10668)
		(layer "F.Cu")
		(net "FM_CPU1_RSMRST_N")
	)
	(via
		(at 180.23078 -128.09601)
		(size 0.762)
		(drill 0.381)
		(layers "F.Cu" "B.Cu")
		(net "FM_CPU1_RSMRST_N")
	)
	(segment
		(start 193.84137 -124.822712)
		(end 192.975484 -124.822712)
		(width 0.10668)
		(layer "F.Cu")
		(net "FM_CPU1_PWR_GD_IN")
	)
	(segment
		(start 194.312032 -125.920246)
		(end 194.312032 -125.293374)
		(width 0.10668)
		(layer "F.Cu")
		(net "FM_CPU1_PWR_GD_IN")
	)
	(segment
		(start 194.312032 -125.293374)
		(end 193.84137 -124.822712)
		(width 0.10668)
		(layer "F.Cu")
		(net "FM_CPU1_PWR_GD_IN")
	)
	(segment
		(start 194.707764 -136.088374)
		(end 194.707764 -135.171688)
		(width 0.10668)
		(layer "F.Cu")
		(net "FM_CPU1_PWR_GD_IN")
	)
	(segment
		(start 192.975484 -124.822712)
		(end 192.72504 -124.572268)
		(width 0.10668)
		(layer "F.Cu")
		(net "FM_CPU1_PWR_GD_IN")
	)
	(segment
		(start 192.72504 -124.572268)
		(end 192.72504 -123.055634)
		(width 0.10668)
		(layer "F.Cu")
		(net "FM_CPU1_PWR_GD_IN")
	)
	(segment
		(start 194.31 -137.232898)
		(end 194.31 -136.486138)
		(width 0.10668)
		(layer "F.Cu")
		(net "FM_CPU1_PWR_GD_IN")
	)
	(segment
		(start 192.72504 -123.055634)
		(end 192.322196 -122.65279)
		(width 0.10668)
		(layer "F.Cu")
		(net "FM_CPU1_PWR_GD_IN")
	)
	(segment
		(start 194.707764 -135.171688)
		(end 195.072 -134.807452)
		(width 0.10668)
		(layer "F.Cu")
		(net "FM_CPU1_PWR_GD_IN")
	)
	(segment
		(start 194.31 -136.486138)
		(end 194.707764 -136.088374)
		(width 0.10668)
		(layer "F.Cu")
		(net "FM_CPU1_PWR_GD_IN")
	)
	(segment
		(start 195.072 -126.680214)
		(end 194.312032 -125.920246)
		(width 0.10668)
		(layer "F.Cu")
		(net "FM_CPU1_PWR_GD_IN")
	)
	(segment
		(start 195.072 -134.807452)
		(end 195.072 -126.680214)
		(width 0.10668)
		(layer "F.Cu")
		(net "FM_CPU1_PWR_GD_IN")
	)
	(via
		(at 194.707764 -135.171688)
		(size 0.762)
		(drill 0.381)
		(layers "F.Cu" "B.Cu")
		(net "FM_CPU1_PWR_GD_IN")
	)
	(segment
		(start 194.100958 -124.628656)
		(end 193.122042 -123.64974)
		(width 0.10668)
		(layer "F.Cu")
		(net "FM_CPU1_PWRGD_OUT")
	)
	(segment
		(start 193.122042 -123.64974)
		(end 193.122042 -123.45289)
		(width 0.10668)
		(layer "F.Cu")
		(net "FM_CPU1_PWRGD_OUT")
	)
	(segment
		(start 194.54241 -124.628656)
		(end 194.100958 -124.628656)
		(width 0.10668)
		(layer "F.Cu")
		(net "FM_CPU1_PWRGD_OUT")
	)
	(segment
		(start 194.829176 -124.915422)
		(end 194.54241 -124.628656)
		(width 0.10668)
		(layer "F.Cu")
		(net "FM_CPU1_PWRGD_OUT")
	)
	(segment
		(start 194.829176 -125.927104)
		(end 194.829176 -124.915422)
		(width 0.10668)
		(layer "F.Cu")
		(net "FM_CPU1_PWRGD_OUT")
	)
	(segment
		(start 195.575428 -126.673356)
		(end 194.829176 -125.927104)
		(width 0.10668)
		(layer "F.Cu")
		(net "FM_CPU1_PWRGD_OUT")
	)
	(segment
		(start 195.843906 -129.868168)
		(end 195.575428 -129.59969)
		(width 0.10668)
		(layer "F.Cu")
		(net "FM_CPU1_PWRGD_OUT")
	)
	(segment
		(start 208.494376 -115.657376)
		(end 207.291686 -115.657376)
		(width 0.10668)
		(layer "F.Cu")
		(net "FM_CPU1_PWRGD_OUT")
	)
	(segment
		(start 195.575428 -129.59969)
		(end 195.575428 -126.673356)
		(width 0.10668)
		(layer "F.Cu")
		(net "FM_CPU1_PWRGD_OUT")
	)
	(via
		(at 195.843906 -129.868168)
		(size 0.508)
		(drill 0.254)
		(layers "F.Cu" "B.Cu")
		(net "FM_CPU1_PWRGD_OUT")
	)
	(via
		(at 216.461086 -128.831594)
		(size 0.508)
		(drill 0.254)
		(layers "F.Cu" "B.Cu")
		(net "FM_CPU1_PWRGD_OUT")
	)
	(via
		(at 217.903298 -116.801138)
		(size 0.508)
		(drill 0.254)
		(layers "F.Cu" "B.Cu")
		(net "FM_CPU1_PWRGD_OUT")
	)
	(via
		(at 207.291686 -115.657376)
		(size 0.508)
		(drill 0.254)
		(layers "F.Cu" "B.Cu")
		(net "FM_CPU1_PWRGD_OUT")
	)
	(segment
		(start 209.627978 -114.98453)
		(end 212.358986 -114.98453)
		(width 0.10668)
		(layer "B.Cu")
		(net "FM_CPU1_PWRGD_OUT")
	)
	(segment
		(start 213.162642 -115.788186)
		(end 216.890346 -115.788186)
		(width 0.10668)
		(layer "B.Cu")
		(net "FM_CPU1_PWRGD_OUT")
	)
	(segment
		(start 212.358986 -114.98453)
		(end 213.162642 -115.788186)
		(width 0.10668)
		(layer "B.Cu")
		(net "FM_CPU1_PWRGD_OUT")
	)
	(segment
		(start 207.291686 -115.657376)
		(end 208.955132 -115.657376)
		(width 0.10668)
		(layer "B.Cu")
		(net "FM_CPU1_PWRGD_OUT")
	)
	(segment
		(start 216.890346 -115.788186)
		(end 217.903298 -116.801138)
		(width 0.10668)
		(layer "B.Cu")
		(net "FM_CPU1_PWRGD_OUT")
	)
	(segment
		(start 208.955132 -115.657376)
		(end 209.627978 -114.98453)
		(width 0.10668)
		(layer "B.Cu")
		(net "FM_CPU1_PWRGD_OUT")
	)
	(segment
		(start 197.92696 -129.263902)
		(end 199.192388 -130.52933)
		(width 0.11684)
		(layer "In2.Cu")
		(net "FM_CPU1_PWRGD_OUT")
	)
	(segment
		(start 207.566006 -128.831594)
		(end 216.461086 -128.831594)
		(width 0.11684)
		(layer "In2.Cu")
		(net "FM_CPU1_PWRGD_OUT")
	)
	(segment
		(start 205.86827 -130.52933)
		(end 207.566006 -128.831594)
		(width 0.11684)
		(layer "In2.Cu")
		(net "FM_CPU1_PWRGD_OUT")
	)
	(segment
		(start 195.843906 -129.818892)
		(end 196.398896 -129.263902)
		(width 0.11684)
		(layer "In2.Cu")
		(net "FM_CPU1_PWRGD_OUT")
	)
	(segment
		(start 195.843906 -129.868168)
		(end 195.843906 -129.818892)
		(width 0.11684)
		(layer "In2.Cu")
		(net "FM_CPU1_PWRGD_OUT")
	)
	(segment
		(start 199.192388 -130.52933)
		(end 205.86827 -130.52933)
		(width 0.11684)
		(layer "In2.Cu")
		(net "FM_CPU1_PWRGD_OUT")
	)
	(segment
		(start 196.398896 -129.263902)
		(end 197.92696 -129.263902)
		(width 0.11684)
		(layer "In2.Cu")
		(net "FM_CPU1_PWRGD_OUT")
	)
	(segment
		(start 216.852754 -128.439926)
		(end 216.461086 -128.831594)
		(width 0.11684)
		(layer "In11.Cu")
		(net "FM_CPU1_PWRGD_OUT")
	)
	(segment
		(start 217.441526 -120.039384)
		(end 216.852754 -120.628156)
		(width 0.11684)
		(layer "In11.Cu")
		(net "FM_CPU1_PWRGD_OUT")
	)
	(segment
		(start 217.441526 -117.26291)
		(end 217.441526 -120.039384)
		(width 0.11684)
		(layer "In11.Cu")
		(net "FM_CPU1_PWRGD_OUT")
	)
	(segment
		(start 216.852754 -120.628156)
		(end 216.852754 -128.439926)
		(width 0.11684)
		(layer "In11.Cu")
		(net "FM_CPU1_PWRGD_OUT")
	)
	(segment
		(start 217.903298 -116.801138)
		(end 217.441526 -117.26291)
		(width 0.11684)
		(layer "In11.Cu")
		(net "FM_CPU1_PWRGD_OUT")
	)
	(segment
		(start 183.769 -101.869748)
		(end 183.769 -104.05364)
		(width 0.10668)
		(layer "F.Cu")
		(net "FM_CPU1_PROCHOT_R_N")
	)
	(segment
		(start 183.769 -100.694998)
		(end 183.769 -101.869748)
		(width 0.10668)
		(layer "F.Cu")
		(net "FM_CPU1_PROCHOT_R_N")
	)
	(segment
		(start 181.922166 -105.900474)
		(end 181.922166 -106.652822)
		(width 0.10668)
		(layer "F.Cu")
		(net "FM_CPU1_PROCHOT_R_N")
	)
	(segment
		(start 183.769 -104.05364)
		(end 181.922166 -105.900474)
		(width 0.10668)
		(layer "F.Cu")
		(net "FM_CPU1_PROCHOT_R_N")
	)
	(via
		(at 183.769 -101.869748)
		(size 0.762)
		(drill 0.381)
		(layers "F.Cu" "B.Cu")
		(net "FM_CPU1_PROCHOT_R_N")
	)
	(segment
		(start 183.515 -133.021832)
		(end 183.650128 -133.15696)
		(width 0.10668)
		(layer "F.Cu")
		(net "FM_CPU1_NV_SAVE_N")
	)
	(segment
		(start 184.023 -131.409948)
		(end 183.803036 -131.409948)
		(width 0.10668)
		(layer "F.Cu")
		(net "FM_CPU1_NV_SAVE_N")
	)
	(segment
		(start 182.722012 -120.252744)
		(end 182.332122 -120.642634)
		(width 0.10668)
		(layer "F.Cu")
		(net "FM_CPU1_NV_SAVE_N")
	)
	(segment
		(start 183.515 -131.697984)
		(end 183.515 -133.021832)
		(width 0.10668)
		(layer "F.Cu")
		(net "FM_CPU1_NV_SAVE_N")
	)
	(segment
		(start 183.803036 -131.409948)
		(end 183.515 -131.697984)
		(width 0.10668)
		(layer "F.Cu")
		(net "FM_CPU1_NV_SAVE_N")
	)
	(via
		(at 182.332122 -120.642634)
		(size 0.4572)
		(drill 0.254)
		(layers "F.Cu" "B.Cu")
		(net "FM_CPU1_NV_SAVE_N")
	)
	(via
		(at 184.023 -131.409948)
		(size 0.508)
		(drill 0.254)
		(layers "F.Cu" "B.Cu")
		(net "FM_CPU1_NV_SAVE_N")
	)
	(segment
		(start 184.023 -131.409948)
		(end 183.512968 -130.899916)
		(width 0.11684)
		(layer "In4.Cu")
		(net "FM_CPU1_NV_SAVE_N")
	)
	(segment
		(start 182.738268 -121.04878)
		(end 182.332122 -120.642634)
		(width 0.11684)
		(layer "In4.Cu")
		(net "FM_CPU1_NV_SAVE_N")
	)
	(segment
		(start 183.512968 -129.930144)
		(end 182.738268 -129.155444)
		(width 0.11684)
		(layer "In4.Cu")
		(net "FM_CPU1_NV_SAVE_N")
	)
	(segment
		(start 182.738268 -129.155444)
		(end 182.738268 -121.04878)
		(width 0.11684)
		(layer "In4.Cu")
		(net "FM_CPU1_NV_SAVE_N")
	)
	(segment
		(start 183.512968 -130.899916)
		(end 183.512968 -129.930144)
		(width 0.11684)
		(layer "In4.Cu")
		(net "FM_CPU1_NV_SAVE_N")
	)
	(segment
		(start 192.151 -128.977898)
		(end 192.405 -128.723898)
		(width 0.10668)
		(layer "F.Cu")
		(net "FM_CPU1_NMI_SYNC_FLOOD_N")
	)
	(segment
		(start 192.405 -128.723898)
		(end 192.405 -126.99492)
		(width 0.10668)
		(layer "F.Cu")
		(net "FM_CPU1_NMI_SYNC_FLOOD_N")
	)
	(segment
		(start 191.522096 -124.784866)
		(end 191.522096 -123.45289)
		(width 0.10668)
		(layer "F.Cu")
		(net "FM_CPU1_NMI_SYNC_FLOOD_N")
	)
	(segment
		(start 192.405 -126.99492)
		(end 192.405 -125.66777)
		(width 0.10668)
		(layer "F.Cu")
		(net "FM_CPU1_NMI_SYNC_FLOOD_N")
	)
	(segment
		(start 192.405 -125.66777)
		(end 191.522096 -124.784866)
		(width 0.10668)
		(layer "F.Cu")
		(net "FM_CPU1_NMI_SYNC_FLOOD_N")
	)
	(via
		(at 192.405 -126.99492)
		(size 0.762)
		(drill 0.381)
		(layers "F.Cu" "B.Cu")
		(net "FM_CPU1_NMI_SYNC_FLOOD_N")
	)
	(segment
		(start 179.705 -100.694998)
		(end 179.887372 -100.87737)
		(width 0.10668)
		(layer "F.Cu")
		(net "FM_CPU1_BMC_RST_R_N")
	)
	(segment
		(start 179.887372 -101.913182)
		(end 179.487068 -102.313486)
		(width 0.10668)
		(layer "F.Cu")
		(net "FM_CPU1_BMC_RST_R_N")
	)
	(segment
		(start 179.887372 -100.87737)
		(end 179.887372 -101.913182)
		(width 0.10668)
		(layer "F.Cu")
		(net "FM_CPU1_BMC_RST_R_N")
	)
	(segment
		(start 179.926488 -107.05719)
		(end 180.32222 -107.452922)
		(width 0.10668)
		(layer "F.Cu")
		(net "FM_CPU1_BMC_RST_R_N")
	)
	(segment
		(start 179.487068 -104.39146)
		(end 179.926488 -104.83088)
		(width 0.10668)
		(layer "F.Cu")
		(net "FM_CPU1_BMC_RST_R_N")
	)
	(segment
		(start 179.926488 -104.83088)
		(end 179.926488 -107.05719)
		(width 0.10668)
		(layer "F.Cu")
		(net "FM_CPU1_BMC_RST_R_N")
	)
	(segment
		(start 179.487068 -102.313486)
		(end 179.487068 -104.39146)
		(width 0.10668)
		(layer "F.Cu")
		(net "FM_CPU1_BMC_RST_R_N")
	)
	(via
		(at 179.887372 -101.913182)
		(size 0.762)
		(drill 0.381)
		(layers "F.Cu" "B.Cu")
		(net "FM_CPU1_BMC_RST_R_N")
	)
	(segment
		(start 180.721 -103.040942)
		(end 180.721 -100.694998)
		(width 0.10668)
		(layer "F.Cu")
		(net "FM_BMC_TPM_PRES_N_R")
	)
	(segment
		(start 180.32222 -105.434638)
		(end 180.721 -105.035858)
		(width 0.10668)
		(layer "F.Cu")
		(net "FM_BMC_TPM_PRES_N_R")
	)
	(segment
		(start 180.721 -105.035858)
		(end 180.721 -103.040942)
		(width 0.10668)
		(layer "F.Cu")
		(net "FM_BMC_TPM_PRES_N_R")
	)
	(segment
		(start 180.32222 -106.652822)
		(end 180.32222 -105.434638)
		(width 0.10668)
		(layer "F.Cu")
		(net "FM_BMC_TPM_PRES_N_R")
	)
	(via
		(at 180.721 -103.040942)
		(size 0.762)
		(drill 0.381)
		(layers "F.Cu" "B.Cu")
		(net "FM_BMC_TPM_PRES_N_R")
	)
	(segment
		(start 179.9082 -96.503998)
		(end 179.9082 -96.916748)
		(width 0.10668)
		(layer "F.Cu")
		(net "IRQ_CPU_BMC_NMI_R_N")
	)
	(segment
		(start 182.722012 -111.452914)
		(end 182.332122 -111.063024)
		(width 0.10668)
		(layer "F.Cu")
		(net "IRQ_CPU_BMC_NMI_R_N")
	)
	(segment
		(start 179.9082 -96.916748)
		(end 179.705 -97.119948)
		(width 0.10668)
		(layer "F.Cu")
		(net "IRQ_CPU_BMC_NMI_R_N")
	)
	(via
		(at 179.705 -97.119948)
		(size 0.508)
		(drill 0.254)
		(layers "F.Cu" "B.Cu")
		(net "IRQ_CPU_BMC_NMI_R_N")
	)
	(via
		(at 182.332122 -111.063024)
		(size 0.4572)
		(drill 0.254)
		(layers "F.Cu" "B.Cu")
		(net "IRQ_CPU_BMC_NMI_R_N")
	)
	(segment
		(start 180.49875 -101.496368)
		(end 180.49875 -105.414318)
		(width 0.11684)
		(layer "In4.Cu")
		(net "IRQ_CPU_BMC_NMI_R_N")
	)
	(segment
		(start 181.712108 -109.856016)
		(end 181.930548 -110.074456)
		(width 0.11684)
		(layer "In4.Cu")
		(net "IRQ_CPU_BMC_NMI_R_N")
	)
	(segment
		(start 179.705 -97.119948)
		(end 179.705 -97.605088)
		(width 0.11684)
		(layer "In4.Cu")
		(net "IRQ_CPU_BMC_NMI_R_N")
	)
	(segment
		(start 181.138068 -109.673136)
		(end 181.320948 -109.856016)
		(width 0.11684)
		(layer "In4.Cu")
		(net "IRQ_CPU_BMC_NMI_R_N")
	)
	(segment
		(start 179.234084 -100.231702)
		(end 180.49875 -101.496368)
		(width 0.11684)
		(layer "In4.Cu")
		(net "IRQ_CPU_BMC_NMI_R_N")
	)
	(segment
		(start 181.138068 -106.053636)
		(end 181.138068 -109.673136)
		(width 0.11684)
		(layer "In4.Cu")
		(net "IRQ_CPU_BMC_NMI_R_N")
	)
	(segment
		(start 181.930548 -110.074456)
		(end 181.930548 -110.66145)
		(width 0.11684)
		(layer "In4.Cu")
		(net "IRQ_CPU_BMC_NMI_R_N")
	)
	(segment
		(start 180.49875 -105.414318)
		(end 181.138068 -106.053636)
		(width 0.11684)
		(layer "In4.Cu")
		(net "IRQ_CPU_BMC_NMI_R_N")
	)
	(segment
		(start 181.930548 -110.66145)
		(end 182.332122 -111.063024)
		(width 0.11684)
		(layer "In4.Cu")
		(net "IRQ_CPU_BMC_NMI_R_N")
	)
	(segment
		(start 181.320948 -109.856016)
		(end 181.712108 -109.856016)
		(width 0.11684)
		(layer "In4.Cu")
		(net "IRQ_CPU_BMC_NMI_R_N")
	)
	(segment
		(start 179.234084 -98.076004)
		(end 179.234084 -100.231702)
		(width 0.11684)
		(layer "In4.Cu")
		(net "IRQ_CPU_BMC_NMI_R_N")
	)
	(segment
		(start 179.705 -97.605088)
		(end 179.234084 -98.076004)
		(width 0.11684)
		(layer "In4.Cu")
		(net "IRQ_CPU_BMC_NMI_R_N")
	)
	(segment
		(start 191.522096 -121.052844)
		(end 191.911986 -121.442734)
		(width 0.10668)
		(layer "F.Cu")
		(net "FM_CPU1_FORCE_SELFREFRESH")
	)
	(via
		(at 191.911986 -121.442734)
		(size 0.4572)
		(drill 0.254)
		(layers "F.Cu" "B.Cu")
		(net "FM_CPU1_FORCE_SELFREFRESH")
	)
	(via
		(at 195.408042 -125.6792)
		(size 0.6604)
		(drill 0.3302)
		(layers "F.Cu" "B.Cu")
		(net "FM_CPU1_FORCE_SELFREFRESH")
	)
	(segment
		(start 193.72199 -123.974606)
		(end 193.72199 -123.01347)
		(width 0.10668)
		(layer "B.Cu")
		(net "FM_CPU1_FORCE_SELFREFRESH")
	)
	(segment
		(start 195.14566 -124.735082)
		(end 194.781678 -124.3711)
		(width 0.10668)
		(layer "B.Cu")
		(net "FM_CPU1_FORCE_SELFREFRESH")
	)
	(segment
		(start 192.151254 -121.442734)
		(end 191.911986 -121.442734)
		(width 0.10668)
		(layer "B.Cu")
		(net "FM_CPU1_FORCE_SELFREFRESH")
	)
	(segment
		(start 192.93586 -121.840244)
		(end 192.548764 -121.840244)
		(width 0.10668)
		(layer "B.Cu")
		(net "FM_CPU1_FORCE_SELFREFRESH")
	)
	(segment
		(start 193.11112 -122.015504)
		(end 192.93586 -121.840244)
		(width 0.10668)
		(layer "B.Cu")
		(net "FM_CPU1_FORCE_SELFREFRESH")
	)
	(segment
		(start 196.323712 -126.28753)
		(end 195.54444 -126.28753)
		(width 0.10668)
		(layer "B.Cu")
		(net "FM_CPU1_FORCE_SELFREFRESH")
	)
	(segment
		(start 194.781678 -124.3711)
		(end 194.118484 -124.3711)
		(width 0.10668)
		(layer "B.Cu")
		(net "FM_CPU1_FORCE_SELFREFRESH")
	)
	(segment
		(start 196.869558 -126.833376)
		(end 196.323712 -126.28753)
		(width 0.10668)
		(layer "B.Cu")
		(net "FM_CPU1_FORCE_SELFREFRESH")
	)
	(segment
		(start 193.11112 -122.4026)
		(end 193.11112 -122.015504)
		(width 0.10668)
		(layer "B.Cu")
		(net "FM_CPU1_FORCE_SELFREFRESH")
	)
	(segment
		(start 192.548764 -121.840244)
		(end 192.151254 -121.442734)
		(width 0.10668)
		(layer "B.Cu")
		(net "FM_CPU1_FORCE_SELFREFRESH")
	)
	(segment
		(start 193.72199 -123.01347)
		(end 193.11112 -122.4026)
		(width 0.10668)
		(layer "B.Cu")
		(net "FM_CPU1_FORCE_SELFREFRESH")
	)
	(segment
		(start 194.118484 -124.3711)
		(end 193.72199 -123.974606)
		(width 0.10668)
		(layer "B.Cu")
		(net "FM_CPU1_FORCE_SELFREFRESH")
	)
	(segment
		(start 195.408042 -125.6792)
		(end 195.14566 -125.416818)
		(width 0.10668)
		(layer "B.Cu")
		(net "FM_CPU1_FORCE_SELFREFRESH")
	)
	(segment
		(start 195.408042 -126.151132)
		(end 195.408042 -125.6792)
		(width 0.10668)
		(layer "B.Cu")
		(net "FM_CPU1_FORCE_SELFREFRESH")
	)
	(segment
		(start 195.54444 -126.28753)
		(end 195.408042 -126.151132)
		(width 0.10668)
		(layer "B.Cu")
		(net "FM_CPU1_FORCE_SELFREFRESH")
	)
	(segment
		(start 195.14566 -125.416818)
		(end 195.14566 -124.735082)
		(width 0.10668)
		(layer "B.Cu")
		(net "FM_CPU1_FORCE_SELFREFRESH")
	)
	(segment
		(start 191.4398 -101.899466)
		(end 191.516 -101.823266)
		(width 0.10668)
		(layer "F.Cu")
		(net "FM_CPU1_CORETYPE2")
	)
	(segment
		(start 189.12205 -107.452922)
		(end 189.12205 -107.200954)
		(width 0.10668)
		(layer "F.Cu")
		(net "FM_CPU1_CORETYPE2")
	)
	(segment
		(start 191.3382 -102.001066)
		(end 191.4398 -101.899466)
		(width 0.10668)
		(layer "F.Cu")
		(net "FM_CPU1_CORETYPE2")
	)
	(segment
		(start 191.516 -101.823266)
		(end 191.516 -101.075998)
		(width 0.10668)
		(layer "F.Cu")
		(net "FM_CPU1_CORETYPE2")
	)
	(segment
		(start 189.520068 -106.802936)
		(end 189.520068 -105.592118)
		(width 0.10668)
		(layer "F.Cu")
		(net "FM_CPU1_CORETYPE2")
	)
	(segment
		(start 189.12205 -107.200954)
		(end 189.520068 -106.802936)
		(width 0.10668)
		(layer "F.Cu")
		(net "FM_CPU1_CORETYPE2")
	)
	(segment
		(start 189.520068 -105.592118)
		(end 191.3382 -103.773986)
		(width 0.10668)
		(layer "F.Cu")
		(net "FM_CPU1_CORETYPE2")
	)
	(segment
		(start 191.3382 -103.773986)
		(end 191.3382 -102.001066)
		(width 0.10668)
		(layer "F.Cu")
		(net "FM_CPU1_CORETYPE2")
	)
	(segment
		(start 191.516 -101.075998)
		(end 191.897 -100.694998)
		(width 0.10668)
		(layer "F.Cu")
		(net "FM_CPU1_CORETYPE2")
	)
	(via
		(at 191.4398 -101.899466)
		(size 0.762)
		(drill 0.381)
		(layers "F.Cu" "B.Cu")
		(net "FM_CPU1_CORETYPE2")
	)
	(segment
		(start 189.12205 -105.15473)
		(end 189.12205 -106.652822)
		(width 0.10668)
		(layer "F.Cu")
		(net "FM_CPU1_CORETYPE1")
	)
	(segment
		(start 190.7032 -101.320854)
		(end 190.7032 -103.121968)
		(width 0.10668)
		(layer "F.Cu")
		(net "FM_CPU1_CORETYPE1")
	)
	(segment
		(start 190.7032 -103.121968)
		(end 190.7032 -103.57358)
		(width 0.10668)
		(layer "F.Cu")
		(net "FM_CPU1_CORETYPE1")
	)
	(segment
		(start 190.7032 -103.57358)
		(end 189.12205 -105.15473)
		(width 0.10668)
		(layer "F.Cu")
		(net "FM_CPU1_CORETYPE1")
	)
	(segment
		(start 190.881 -101.143054)
		(end 190.7032 -101.320854)
		(width 0.10668)
		(layer "F.Cu")
		(net "FM_CPU1_CORETYPE1")
	)
	(segment
		(start 190.881 -100.694998)
		(end 190.881 -101.143054)
		(width 0.10668)
		(layer "F.Cu")
		(net "FM_CPU1_CORETYPE1")
	)
	(via
		(at 190.7032 -103.121968)
		(size 0.762)
		(drill 0.381)
		(layers "F.Cu" "B.Cu")
		(net "FM_CPU1_CORETYPE1")
	)
	(segment
		(start 187.522104 -109.052868)
		(end 187.911994 -108.662978)
		(width 0.10668)
		(layer "F.Cu")
		(net "FM_CPU1_CORETYPE0")
	)
	(via
		(at 187.846462 -98.62058)
		(size 0.508)
		(drill 0.254)
		(layers "F.Cu" "B.Cu")
		(net "FM_CPU1_CORETYPE0")
	)
	(via
		(at 187.911994 -108.662978)
		(size 0.4572)
		(drill 0.254)
		(layers "F.Cu" "B.Cu")
		(net "FM_CPU1_CORETYPE0")
	)
	(segment
		(start 187.871608 -97.535492)
		(end 187.822078 -97.485962)
		(width 0.10668)
		(layer "B.Cu")
		(net "FM_CPU1_CORETYPE0")
	)
	(segment
		(start 187.846462 -98.62058)
		(end 187.871608 -98.595434)
		(width 0.10668)
		(layer "B.Cu")
		(net "FM_CPU1_CORETYPE0")
	)
	(segment
		(start 187.871608 -98.595434)
		(end 187.871608 -97.535492)
		(width 0.10668)
		(layer "B.Cu")
		(net "FM_CPU1_CORETYPE0")
	)
	(segment
		(start 188.34862 -105.020364)
		(end 187.516008 -105.852976)
		(width 0.11684)
		(layer "In4.Cu")
		(net "FM_CPU1_CORETYPE0")
	)
	(segment
		(start 187.846462 -98.62058)
		(end 188.22162 -98.62058)
		(width 0.11684)
		(layer "In4.Cu")
		(net "FM_CPU1_CORETYPE0")
	)
	(segment
		(start 187.523374 -107.993942)
		(end 187.523374 -108.274358)
		(width 0.11684)
		(layer "In4.Cu")
		(net "FM_CPU1_CORETYPE0")
	)
	(segment
		(start 187.523374 -108.274358)
		(end 187.911994 -108.662978)
		(width 0.11684)
		(layer "In4.Cu")
		(net "FM_CPU1_CORETYPE0")
	)
	(segment
		(start 188.22162 -98.62058)
		(end 188.34862 -98.74758)
		(width 0.11684)
		(layer "In4.Cu")
		(net "FM_CPU1_CORETYPE0")
	)
	(segment
		(start 187.516008 -107.986576)
		(end 187.523374 -107.993942)
		(width 0.11684)
		(layer "In4.Cu")
		(net "FM_CPU1_CORETYPE0")
	)
	(segment
		(start 188.34862 -98.74758)
		(end 188.34862 -105.020364)
		(width 0.11684)
		(layer "In4.Cu")
		(net "FM_CPU1_CORETYPE0")
	)
	(segment
		(start 187.516008 -105.852976)
		(end 187.516008 -107.986576)
		(width 0.11684)
		(layer "In4.Cu")
		(net "FM_CPU1_CORETYPE0")
	)
	(segment
		(start 177.8762 -96.503998)
		(end 177.8762 -97.155508)
		(width 0.10668)
		(layer "F.Cu")
		(net "FM_CPU0_XTRIG_L7")
	)
	(segment
		(start 180.32222 -108.252768)
		(end 179.93233 -107.862878)
		(width 0.10668)
		(layer "F.Cu")
		(net "FM_CPU0_XTRIG_L7")
	)
	(via
		(at 179.93233 -107.862878)
		(size 0.4572)
		(drill 0.254)
		(layers "F.Cu" "B.Cu")
		(net "FM_CPU0_XTRIG_L7")
	)
	(via
		(at 177.8762 -97.155508)
		(size 0.508)
		(drill 0.254)
		(layers "F.Cu" "B.Cu")
		(net "FM_CPU0_XTRIG_L7")
	)
	(segment
		(start 177.984404 -102.757732)
		(end 178.769772 -103.5431)
		(width 0.11684)
		(layer "In4.Cu")
		(net "FM_CPU0_XTRIG_L7")
	)
	(segment
		(start 177.984404 -101.014022)
		(end 177.984404 -102.757732)
		(width 0.11684)
		(layer "In4.Cu")
		(net "FM_CPU0_XTRIG_L7")
	)
	(segment
		(start 177.178716 -97.852992)
		(end 177.178716 -100.208334)
		(width 0.11684)
		(layer "In4.Cu")
		(net "FM_CPU0_XTRIG_L7")
	)
	(segment
		(start 177.178716 -100.208334)
		(end 177.984404 -101.014022)
		(width 0.11684)
		(layer "In4.Cu")
		(net "FM_CPU0_XTRIG_L7")
	)
	(segment
		(start 178.769772 -105.406444)
		(end 179.93233 -106.569002)
		(width 0.11684)
		(layer "In4.Cu")
		(net "FM_CPU0_XTRIG_L7")
	)
	(segment
		(start 177.8762 -97.155508)
		(end 177.178716 -97.852992)
		(width 0.11684)
		(layer "In4.Cu")
		(net "FM_CPU0_XTRIG_L7")
	)
	(segment
		(start 178.769772 -103.5431)
		(end 178.769772 -105.406444)
		(width 0.11684)
		(layer "In4.Cu")
		(net "FM_CPU0_XTRIG_L7")
	)
	(segment
		(start 179.93233 -106.569002)
		(end 179.93233 -107.862878)
		(width 0.11684)
		(layer "In4.Cu")
		(net "FM_CPU0_XTRIG_L7")
	)
	(segment
		(start 175.4632 -96.503998)
		(end 176.04105 -96.503998)
		(width 0.10668)
		(layer "F.Cu")
		(net "FM_CPU0_XTRIG_L6")
	)
	(segment
		(start 180.32222 -109.052868)
		(end 179.93233 -108.662978)
		(width 0.10668)
		(layer "F.Cu")
		(net "FM_CPU0_XTRIG_L6")
	)
	(segment
		(start 176.04105 -96.503998)
		(end 176.657 -97.119948)
		(width 0.10668)
		(layer "F.Cu")
		(net "FM_CPU0_XTRIG_L6")
	)
	(via
		(at 176.657 -97.119948)
		(size 0.508)
		(drill 0.254)
		(layers "F.Cu" "B.Cu")
		(net "FM_CPU0_XTRIG_L6")
	)
	(via
		(at 179.93233 -108.662978)
		(size 0.4572)
		(drill 0.254)
		(layers "F.Cu" "B.Cu")
		(net "FM_CPU0_XTRIG_L6")
	)
	(segment
		(start 178.23561 -105.645712)
		(end 178.23561 -104.078278)
		(width 0.11684)
		(layer "In4.Cu")
		(net "FM_CPU0_XTRIG_L6")
	)
	(segment
		(start 176.1617 -99.982782)
		(end 176.1617 -97.869248)
		(width 0.11684)
		(layer "In4.Cu")
		(net "FM_CPU0_XTRIG_L6")
	)
	(segment
		(start 179.93233 -108.662978)
		(end 179.52847 -108.259118)
		(width 0.11684)
		(layer "In4.Cu")
		(net "FM_CPU0_XTRIG_L6")
	)
	(segment
		(start 177.208688 -103.051356)
		(end 177.208688 -101.02977)
		(width 0.11684)
		(layer "In4.Cu")
		(net "FM_CPU0_XTRIG_L6")
	)
	(segment
		(start 178.23561 -104.078278)
		(end 177.208688 -103.051356)
		(width 0.11684)
		(layer "In4.Cu")
		(net "FM_CPU0_XTRIG_L6")
	)
	(segment
		(start 176.1617 -97.869248)
		(end 176.657 -97.373948)
		(width 0.11684)
		(layer "In4.Cu")
		(net "FM_CPU0_XTRIG_L6")
	)
	(segment
		(start 179.52847 -106.938572)
		(end 178.23561 -105.645712)
		(width 0.11684)
		(layer "In4.Cu")
		(net "FM_CPU0_XTRIG_L6")
	)
	(segment
		(start 176.657 -97.373948)
		(end 176.657 -97.119948)
		(width 0.11684)
		(layer "In4.Cu")
		(net "FM_CPU0_XTRIG_L6")
	)
	(segment
		(start 179.52847 -108.259118)
		(end 179.52847 -106.938572)
		(width 0.11684)
		(layer "In4.Cu")
		(net "FM_CPU0_XTRIG_L6")
	)
	(segment
		(start 177.208688 -101.02977)
		(end 176.1617 -99.982782)
		(width 0.11684)
		(layer "In4.Cu")
		(net "FM_CPU0_XTRIG_L6")
	)
	(segment
		(start 176.657 -101.073966)
		(end 176.41062 -101.320346)
		(width 0.10668)
		(layer "F.Cu")
		(net "FM_CPU0_XTRIG_L5")
	)
	(segment
		(start 178.72202 -105.49382)
		(end 178.72202 -106.652822)
		(width 0.10668)
		(layer "F.Cu")
		(net "FM_CPU0_XTRIG_L5")
	)
	(segment
		(start 176.657 -100.694998)
		(end 176.657 -101.073966)
		(width 0.10668)
		(layer "F.Cu")
		(net "FM_CPU0_XTRIG_L5")
	)
	(segment
		(start 176.54016 -101.874066)
		(end 176.54016 -102.04958)
		(width 0.10668)
		(layer "F.Cu")
		(net "FM_CPU0_XTRIG_L5")
	)
	(segment
		(start 177.16754 -102.67696)
		(end 177.16754 -103.93934)
		(width 0.10668)
		(layer "F.Cu")
		(net "FM_CPU0_XTRIG_L5")
	)
	(segment
		(start 176.539906 -101.874066)
		(end 176.54016 -101.874066)
		(width 0.10668)
		(layer "F.Cu")
		(net "FM_CPU0_XTRIG_L5")
	)
	(segment
		(start 176.41062 -101.74478)
		(end 176.539906 -101.874066)
		(width 0.10668)
		(layer "F.Cu")
		(net "FM_CPU0_XTRIG_L5")
	)
	(segment
		(start 177.16754 -103.93934)
		(end 178.72202 -105.49382)
		(width 0.10668)
		(layer "F.Cu")
		(net "FM_CPU0_XTRIG_L5")
	)
	(segment
		(start 176.54016 -102.04958)
		(end 177.16754 -102.67696)
		(width 0.10668)
		(layer "F.Cu")
		(net "FM_CPU0_XTRIG_L5")
	)
	(segment
		(start 176.41062 -101.320346)
		(end 176.41062 -101.74478)
		(width 0.10668)
		(layer "F.Cu")
		(net "FM_CPU0_XTRIG_L5")
	)
	(via
		(at 176.54016 -101.874066)
		(size 0.762)
		(drill 0.381)
		(layers "F.Cu" "B.Cu")
		(net "FM_CPU0_XTRIG_L5")
	)
	(segment
		(start 177.673 -100.694998)
		(end 177.74158 -100.763578)
		(width 0.10668)
		(layer "F.Cu")
		(net "FM_CPU0_XTRIG_L4")
	)
	(segment
		(start 177.78603 -102.23373)
		(end 177.74158 -102.27818)
		(width 0.10668)
		(layer "F.Cu")
		(net "FM_CPU0_XTRIG_L4")
	)
	(segment
		(start 177.74158 -103.921052)
		(end 179.108608 -105.28808)
		(width 0.10668)
		(layer "F.Cu")
		(net "FM_CPU0_XTRIG_L4")
	)
	(segment
		(start 177.78603 -102.02799)
		(end 177.78603 -102.23373)
		(width 0.10668)
		(layer "F.Cu")
		(net "FM_CPU0_XTRIG_L4")
	)
	(segment
		(start 177.74158 -100.763578)
		(end 177.74158 -101.98354)
		(width 0.10668)
		(layer "F.Cu")
		(net "FM_CPU0_XTRIG_L4")
	)
	(segment
		(start 179.108608 -105.28808)
		(end 179.108608 -107.03941)
		(width 0.10668)
		(layer "F.Cu")
		(net "FM_CPU0_XTRIG_L4")
	)
	(segment
		(start 177.74158 -102.27818)
		(end 177.74158 -103.921052)
		(width 0.10668)
		(layer "F.Cu")
		(net "FM_CPU0_XTRIG_L4")
	)
	(segment
		(start 179.108608 -107.03941)
		(end 179.52212 -107.452922)
		(width 0.10668)
		(layer "F.Cu")
		(net "FM_CPU0_XTRIG_L4")
	)
	(segment
		(start 177.74158 -101.98354)
		(end 177.78603 -102.02799)
		(width 0.10668)
		(layer "F.Cu")
		(net "FM_CPU0_XTRIG_L4")
	)
	(via
		(at 177.78603 -102.23373)
		(size 0.762)
		(drill 0.381)
		(layers "F.Cu" "B.Cu")
		(net "FM_CPU0_XTRIG_L4")
	)
	(segment
		(start 178.758596 -131.776216)
		(end 178.298094 -132.236718)
		(width 0.10668)
		(layer "F.Cu")
		(net "FM_CPU0_SYS_RESET_N")
	)
	(segment
		(start 178.758596 -130.419602)
		(end 178.758596 -131.776216)
		(width 0.10668)
		(layer "F.Cu")
		(net "FM_CPU0_SYS_RESET_N")
	)
	(segment
		(start 181.122066 -121.052844)
		(end 180.732176 -121.442734)
		(width 0.10668)
		(layer "F.Cu")
		(net "FM_CPU0_SYS_RESET_N")
	)
	(segment
		(start 178.298094 -132.236718)
		(end 178.298094 -132.797296)
		(width 0.10668)
		(layer "F.Cu")
		(net "FM_CPU0_SYS_RESET_N")
	)
	(segment
		(start 178.669696 -133.168898)
		(end 178.943 -133.168898)
		(width 0.10668)
		(layer "F.Cu")
		(net "FM_CPU0_SYS_RESET_N")
	)
	(segment
		(start 178.298094 -132.797296)
		(end 178.669696 -133.168898)
		(width 0.10668)
		(layer "F.Cu")
		(net "FM_CPU0_SYS_RESET_N")
	)
	(via
		(at 180.732176 -121.442734)
		(size 0.4572)
		(drill 0.254)
		(layers "F.Cu" "B.Cu")
		(net "FM_CPU0_SYS_RESET_N")
	)
	(via
		(at 178.758596 -130.419602)
		(size 0.508)
		(drill 0.254)
		(layers "F.Cu" "B.Cu")
		(net "FM_CPU0_SYS_RESET_N")
	)
	(segment
		(start 178.758596 -130.419602)
		(end 178.758596 -129.57937)
		(width 0.11684)
		(layer "In2.Cu")
		(net "FM_CPU0_SYS_RESET_N")
	)
	(segment
		(start 178.758596 -129.57937)
		(end 178.981608 -129.356358)
		(width 0.11684)
		(layer "In2.Cu")
		(net "FM_CPU0_SYS_RESET_N")
	)
	(segment
		(start 180.332888 -121.842022)
		(end 180.732176 -121.442734)
		(width 0.11684)
		(layer "In2.Cu")
		(net "FM_CPU0_SYS_RESET_N")
	)
	(segment
		(start 178.981608 -129.356358)
		(end 178.981608 -124.717556)
		(width 0.11684)
		(layer "In2.Cu")
		(net "FM_CPU0_SYS_RESET_N")
	)
	(segment
		(start 180.332888 -123.366276)
		(end 180.332888 -121.842022)
		(width 0.11684)
		(layer "In2.Cu")
		(net "FM_CPU0_SYS_RESET_N")
	)
	(segment
		(start 178.981608 -124.717556)
		(end 180.332888 -123.366276)
		(width 0.11684)
		(layer "In2.Cu")
		(net "FM_CPU0_SYS_RESET_N")
	)
	(segment
		(start 190.332868 -106.195876)
		(end 190.332868 -107.042204)
		(width 0.10668)
		(layer "F.Cu")
		(net "FM_CPU0_SP5R4")
	)
	(segment
		(start 193.675 -101.219254)
		(end 193.675 -101.8794)
		(width 0.10668)
		(layer "F.Cu")
		(net "FM_CPU0_SP5R4")
	)
	(segment
		(start 193.675 -102.07498)
		(end 192.8114 -102.93858)
		(width 0.10668)
		(layer "F.Cu")
		(net "FM_CPU0_SP5R4")
	)
	(segment
		(start 190.332868 -107.042204)
		(end 189.92215 -107.452922)
		(width 0.10668)
		(layer "F.Cu")
		(net "FM_CPU0_SP5R4")
	)
	(segment
		(start 193.929 -100.965254)
		(end 193.675 -101.219254)
		(width 0.10668)
		(layer "F.Cu")
		(net "FM_CPU0_SP5R4")
	)
	(segment
		(start 192.8114 -102.93858)
		(end 192.8114 -104.18318)
		(width 0.10668)
		(layer "F.Cu")
		(net "FM_CPU0_SP5R4")
	)
	(segment
		(start 191.491108 -105.037636)
		(end 190.332868 -106.195876)
		(width 0.10668)
		(layer "F.Cu")
		(net "FM_CPU0_SP5R4")
	)
	(segment
		(start 193.929 -100.694998)
		(end 193.929 -100.965254)
		(width 0.10668)
		(layer "F.Cu")
		(net "FM_CPU0_SP5R4")
	)
	(segment
		(start 191.956944 -105.037636)
		(end 191.491108 -105.037636)
		(width 0.10668)
		(layer "F.Cu")
		(net "FM_CPU0_SP5R4")
	)
	(segment
		(start 192.8114 -104.18318)
		(end 191.956944 -105.037636)
		(width 0.10668)
		(layer "F.Cu")
		(net "FM_CPU0_SP5R4")
	)
	(segment
		(start 193.675 -101.8794)
		(end 193.675 -102.07498)
		(width 0.10668)
		(layer "F.Cu")
		(net "FM_CPU0_SP5R4")
	)
	(via
		(at 193.675 -101.8794)
		(size 0.762)
		(drill 0.381)
		(layers "F.Cu" "B.Cu")
		(net "FM_CPU0_SP5R4")
	)
	(segment
		(start 192.1002 -101.507798)
		(end 192.1002 -103.08336)
		(width 0.10668)
		(layer "F.Cu")
		(net "FM_CPU0_SP5R3")
	)
	(segment
		(start 189.92215 -106.019854)
		(end 189.92215 -106.652822)
		(width 0.10668)
		(layer "F.Cu")
		(net "FM_CPU0_SP5R3")
	)
	(segment
		(start 192.1002 -103.08336)
		(end 192.1002 -103.21798)
		(width 0.10668)
		(layer "F.Cu")
		(net "FM_CPU0_SP5R3")
	)
	(segment
		(start 191.7192 -103.59898)
		(end 191.7192 -104.222804)
		(width 0.10668)
		(layer "F.Cu")
		(net "FM_CPU0_SP5R3")
	)
	(segment
		(start 192.913 -100.694998)
		(end 192.1002 -101.507798)
		(width 0.10668)
		(layer "F.Cu")
		(net "FM_CPU0_SP5R3")
	)
	(segment
		(start 191.7192 -104.222804)
		(end 189.92215 -106.019854)
		(width 0.10668)
		(layer "F.Cu")
		(net "FM_CPU0_SP5R3")
	)
	(segment
		(start 192.1002 -103.21798)
		(end 191.7192 -103.59898)
		(width 0.10668)
		(layer "F.Cu")
		(net "FM_CPU0_SP5R3")
	)
	(via
		(at 192.1002 -103.08336)
		(size 0.762)
		(drill 0.381)
		(layers "F.Cu" "B.Cu")
		(net "FM_CPU0_SP5R3")
	)
	(segment
		(start 186.722004 -110.652814)
		(end 187.111894 -110.262924)
		(width 0.10668)
		(layer "F.Cu")
		(net "FM_CPU0_SP5R2")
	)
	(via
		(at 186.055 -103.16972)
		(size 0.6604)
		(drill 0.3302)
		(layers "F.Cu" "B.Cu")
		(net "FM_CPU0_SP5R2")
	)
	(via
		(at 187.111894 -110.262924)
		(size 0.4572)
		(drill 0.254)
		(layers "F.Cu" "B.Cu")
		(net "FM_CPU0_SP5R2")
	)
	(segment
		(start 186.2328 -101.005894)
		(end 186.2328 -101.66096)
		(width 0.10668)
		(layer "B.Cu")
		(net "FM_CPU0_SP5R2")
	)
	(segment
		(start 186.2328 -101.66096)
		(end 186.055 -101.83876)
		(width 0.10668)
		(layer "B.Cu")
		(net "FM_CPU0_SP5R2")
	)
	(segment
		(start 186.2328 -105.46461)
		(end 185.854848 -105.842562)
		(width 0.10668)
		(layer "B.Cu")
		(net "FM_CPU0_SP5R2")
	)
	(segment
		(start 186.817 -100.694998)
		(end 186.543696 -100.694998)
		(width 0.10668)
		(layer "B.Cu")
		(net "FM_CPU0_SP5R2")
	)
	(segment
		(start 186.055 -103.16972)
		(end 186.055 -104.2289)
		(width 0.10668)
		(layer "B.Cu")
		(net "FM_CPU0_SP5R2")
	)
	(segment
		(start 186.055 -104.2289)
		(end 186.2328 -104.4067)
		(width 0.10668)
		(layer "B.Cu")
		(net "FM_CPU0_SP5R2")
	)
	(segment
		(start 185.854848 -105.842562)
		(end 185.854848 -109.566456)
		(width 0.10668)
		(layer "B.Cu")
		(net "FM_CPU0_SP5R2")
	)
	(segment
		(start 186.543696 -100.694998)
		(end 186.2328 -101.005894)
		(width 0.10668)
		(layer "B.Cu")
		(net "FM_CPU0_SP5R2")
	)
	(segment
		(start 187.049156 -110.262924)
		(end 187.111894 -110.262924)
		(width 0.10668)
		(layer "B.Cu")
		(net "FM_CPU0_SP5R2")
	)
	(segment
		(start 186.055 -101.83876)
		(end 186.055 -103.16972)
		(width 0.10668)
		(layer "B.Cu")
		(net "FM_CPU0_SP5R2")
	)
	(segment
		(start 186.64555 -109.859318)
		(end 187.049156 -110.262924)
		(width 0.10668)
		(layer "B.Cu")
		(net "FM_CPU0_SP5R2")
	)
	(segment
		(start 186.2328 -104.4067)
		(end 186.2328 -105.46461)
		(width 0.10668)
		(layer "B.Cu")
		(net "FM_CPU0_SP5R2")
	)
	(segment
		(start 185.854848 -109.566456)
		(end 186.14771 -109.859318)
		(width 0.10668)
		(layer "B.Cu")
		(net "FM_CPU0_SP5R2")
	)
	(segment
		(start 186.14771 -109.859318)
		(end 186.64555 -109.859318)
		(width 0.10668)
		(layer "B.Cu")
		(net "FM_CPU0_SP5R2")
	)
	(segment
		(start 186.722004 -109.852968)
		(end 187.111894 -109.463078)
		(width 0.10668)
		(layer "F.Cu")
		(net "FM_CPU0_SP5R1")
	)
	(via
		(at 186.944 -102.19182)
		(size 0.6604)
		(drill 0.3302)
		(layers "F.Cu" "B.Cu")
		(net "FM_CPU0_SP5R1")
	)
	(via
		(at 187.111894 -109.463078)
		(size 0.4572)
		(drill 0.254)
		(layers "F.Cu" "B.Cu")
		(net "FM_CPU0_SP5R1")
	)
	(segment
		(start 186.4868 -97.485962)
		(end 186.341004 -97.631758)
		(width 0.10668)
		(layer "B.Cu")
		(net "FM_CPU0_SP5R1")
	)
	(segment
		(start 187.363608 -99.103434)
		(end 187.363608 -101.772212)
		(width 0.10668)
		(layer "B.Cu")
		(net "FM_CPU0_SP5R1")
	)
	(segment
		(start 186.341004 -98.420936)
		(end 186.696604 -98.776536)
		(width 0.10668)
		(layer "B.Cu")
		(net "FM_CPU0_SP5R1")
	)
	(segment
		(start 186.708288 -105.517696)
		(end 186.708288 -109.059472)
		(width 0.10668)
		(layer "B.Cu")
		(net "FM_CPU0_SP5R1")
	)
	(segment
		(start 186.708288 -109.059472)
		(end 187.111894 -109.463078)
		(width 0.10668)
		(layer "B.Cu")
		(net "FM_CPU0_SP5R1")
	)
	(segment
		(start 187.03671 -98.776536)
		(end 187.363608 -99.103434)
		(width 0.10668)
		(layer "B.Cu")
		(net "FM_CPU0_SP5R1")
	)
	(segment
		(start 186.7916 -105.434384)
		(end 186.708288 -105.517696)
		(width 0.10668)
		(layer "B.Cu")
		(net "FM_CPU0_SP5R1")
	)
	(segment
		(start 187.363608 -101.772212)
		(end 186.944 -102.19182)
		(width 0.10668)
		(layer "B.Cu")
		(net "FM_CPU0_SP5R1")
	)
	(segment
		(start 186.696604 -98.776536)
		(end 187.03671 -98.776536)
		(width 0.10668)
		(layer "B.Cu")
		(net "FM_CPU0_SP5R1")
	)
	(segment
		(start 186.944 -102.19182)
		(end 186.7916 -102.34422)
		(width 0.10668)
		(layer "B.Cu")
		(net "FM_CPU0_SP5R1")
	)
	(segment
		(start 186.341004 -97.631758)
		(end 186.341004 -98.420936)
		(width 0.10668)
		(layer "B.Cu")
		(net "FM_CPU0_SP5R1")
	)
	(segment
		(start 186.7916 -102.34422)
		(end 186.7916 -105.434384)
		(width 0.10668)
		(layer "B.Cu")
		(net "FM_CPU0_SP5R1")
	)
	(segment
		(start 186.806078 -97.485962)
		(end 186.4868 -97.485962)
		(width 0.10668)
		(layer "B.Cu")
		(net "FM_CPU0_SP5R1")
	)
	(segment
		(start 186.055 -127.765556)
		(end 186.055 -123.991878)
		(width 0.10668)
		(layer "F.Cu")
		(net "FM_CPU0_SMERR_N")
	)
	(segment
		(start 186.055 -128.977898)
		(end 186.055 -127.765556)
		(width 0.10668)
		(layer "F.Cu")
		(net "FM_CPU0_SMERR_N")
	)
	(segment
		(start 186.322208 -123.72467)
		(end 186.322208 -123.05284)
		(width 0.10668)
		(layer "F.Cu")
		(net "FM_CPU0_SMERR_N")
	)
	(segment
		(start 186.055 -123.991878)
		(end 186.322208 -123.72467)
		(width 0.10668)
		(layer "F.Cu")
		(net "FM_CPU0_SMERR_N")
	)
	(segment
		(start 186.322208 -123.05284)
		(end 185.922158 -122.65279)
		(width 0.10668)
		(layer "F.Cu")
		(net "FM_CPU0_SMERR_N")
	)
	(via
		(at 186.055 -127.765556)
		(size 0.762)
		(drill 0.381)
		(layers "F.Cu" "B.Cu")
		(net "FM_CPU0_SMERR_N")
	)
	(segment
		(start 175.311562 -126.532132)
		(end 177.306986 -124.536708)
		(width 0.10668)
		(layer "F.Cu")
		(net "FM_CPU0_SLP_S5_N")
	)
	(segment
		(start 177.306986 -124.536708)
		(end 178.020218 -124.241306)
		(width 0.10668)
		(layer "F.Cu")
		(net "FM_CPU0_SLP_S5_N")
	)
	(segment
		(start 174.879 -137.232898)
		(end 174.879 -136.020556)
		(width 0.10668)
		(layer "F.Cu")
		(net "FM_CPU0_SLP_S5_N")
	)
	(segment
		(start 175.311562 -135.587994)
		(end 175.311562 -126.532132)
		(width 0.10668)
		(layer "F.Cu")
		(net "FM_CPU0_SLP_S5_N")
	)
	(segment
		(start 178.321208 -123.053602)
		(end 178.72202 -122.65279)
		(width 0.10668)
		(layer "F.Cu")
		(net "FM_CPU0_SLP_S5_N")
	)
	(segment
		(start 174.879 -136.020556)
		(end 175.311562 -135.587994)
		(width 0.10668)
		(layer "F.Cu")
		(net "FM_CPU0_SLP_S5_N")
	)
	(segment
		(start 178.321208 -123.940316)
		(end 178.321208 -123.053602)
		(width 0.10668)
		(layer "F.Cu")
		(net "FM_CPU0_SLP_S5_N")
	)
	(segment
		(start 178.020218 -124.241306)
		(end 178.321208 -123.940316)
		(width 0.10668)
		(layer "F.Cu")
		(net "FM_CPU0_SLP_S5_N")
	)
	(via
		(at 174.879 -136.020556)
		(size 0.762)
		(drill 0.381)
		(layers "F.Cu" "B.Cu")
		(net "FM_CPU0_SLP_S5_N")
	)
	(segment
		(start 178.72202 -123.938284)
		(end 178.72202 -123.45289)
		(width 0.10668)
		(layer "F.Cu")
		(net "FM_CPU0_SLP_S3_N")
	)
	(segment
		(start 175.895 -128.977898)
		(end 176.415446 -128.457452)
		(width 0.10668)
		(layer "F.Cu")
		(net "FM_CPU0_SLP_S3_N")
	)
	(segment
		(start 176.415446 -126.244858)
		(end 178.72202 -123.938284)
		(width 0.10668)
		(layer "F.Cu")
		(net "FM_CPU0_SLP_S3_N")
	)
	(segment
		(start 176.415446 -126.977648)
		(end 176.415446 -126.244858)
		(width 0.10668)
		(layer "F.Cu")
		(net "FM_CPU0_SLP_S3_N")
	)
	(segment
		(start 176.415446 -128.457452)
		(end 176.415446 -126.977648)
		(width 0.10668)
		(layer "F.Cu")
		(net "FM_CPU0_SLP_S3_N")
	)
	(via
		(at 176.415446 -126.977648)
		(size 0.762)
		(drill 0.381)
		(layers "F.Cu" "B.Cu")
		(net "FM_CPU0_SLP_S3_N")
	)
	(segment
		(start 183.522112 -107.452922)
		(end 183.132222 -107.063032)
		(width 0.10668)
		(layer "F.Cu")
		(net "FM_CPU0_SA1")
	)
	(via
		(at 183.132222 -107.063032)
		(size 0.4572)
		(drill 0.254)
		(layers "F.Cu" "B.Cu")
		(net "FM_CPU0_SA1")
	)
	(via
		(at 189.897766 -103.165402)
		(size 0.508)
		(drill 0.254)
		(layers "F.Cu" "B.Cu")
		(net "FM_CPU0_SA1")
	)
	(segment
		(start 189.865 -100.694998)
		(end 189.865 -103.132636)
		(width 0.10668)
		(layer "B.Cu")
		(net "FM_CPU0_SA1")
	)
	(segment
		(start 189.865 -103.132636)
		(end 189.897766 -103.165402)
		(width 0.10668)
		(layer "B.Cu")
		(net "FM_CPU0_SA1")
	)
	(segment
		(start 188.963808 -104.09936)
		(end 189.897766 -103.165402)
		(width 0.11684)
		(layer "In2.Cu")
		(net "FM_CPU0_SA1")
	)
	(segment
		(start 183.132222 -107.063032)
		(end 183.132222 -107.116372)
		(width 0.11684)
		(layer "In2.Cu")
		(net "FM_CPU0_SA1")
	)
	(segment
		(start 185.274458 -104.09936)
		(end 188.963808 -104.09936)
		(width 0.11684)
		(layer "In2.Cu")
		(net "FM_CPU0_SA1")
	)
	(segment
		(start 184.341008 -107.352846)
		(end 184.341008 -105.03281)
		(width 0.11684)
		(layer "In2.Cu")
		(net "FM_CPU0_SA1")
	)
	(segment
		(start 183.478932 -107.463082)
		(end 184.230772 -107.463082)
		(width 0.11684)
		(layer "In2.Cu")
		(net "FM_CPU0_SA1")
	)
	(segment
		(start 184.341008 -105.03281)
		(end 185.274458 -104.09936)
		(width 0.11684)
		(layer "In2.Cu")
		(net "FM_CPU0_SA1")
	)
	(segment
		(start 184.230772 -107.463082)
		(end 184.341008 -107.352846)
		(width 0.11684)
		(layer "In2.Cu")
		(net "FM_CPU0_SA1")
	)
	(segment
		(start 183.132222 -107.116372)
		(end 183.478932 -107.463082)
		(width 0.11684)
		(layer "In2.Cu")
		(net "FM_CPU0_SA1")
	)
	(segment
		(start 182.722012 -109.852968)
		(end 182.332122 -109.463078)
		(width 0.10668)
		(layer "F.Cu")
		(net "FM_CPU0_SA0")
	)
	(via
		(at 192.913 -102.132892)
		(size 0.508)
		(drill 0.254)
		(layers "F.Cu" "B.Cu")
		(net "FM_CPU0_SA0")
	)
	(via
		(at 182.332122 -109.463078)
		(size 0.4572)
		(drill 0.254)
		(layers "F.Cu" "B.Cu")
		(net "FM_CPU0_SA0")
	)
	(segment
		(start 192.913 -102.132892)
		(end 192.913 -100.694998)
		(width 0.10668)
		(layer "B.Cu")
		(net "FM_CPU0_SA0")
	)
	(segment
		(start 182.332122 -109.463078)
		(end 182.252874 -109.463078)
		(width 0.11684)
		(layer "In6.Cu")
		(net "FM_CPU0_SA0")
	)
	(segment
		(start 181.922928 -109.133132)
		(end 181.922928 -104.809544)
		(width 0.11684)
		(layer "In6.Cu")
		(net "FM_CPU0_SA0")
	)
	(segment
		(start 182.432452 -104.30002)
		(end 189.796674 -104.30002)
		(width 0.11684)
		(layer "In6.Cu")
		(net "FM_CPU0_SA0")
	)
	(segment
		(start 182.252874 -109.463078)
		(end 181.922928 -109.133132)
		(width 0.11684)
		(layer "In6.Cu")
		(net "FM_CPU0_SA0")
	)
	(segment
		(start 192.841372 -102.061264)
		(end 192.913 -102.132892)
		(width 0.11684)
		(layer "In6.Cu")
		(net "FM_CPU0_SA0")
	)
	(segment
		(start 181.922928 -104.809544)
		(end 182.432452 -104.30002)
		(width 0.11684)
		(layer "In6.Cu")
		(net "FM_CPU0_SA0")
	)
	(segment
		(start 189.796674 -104.30002)
		(end 192.03543 -102.061264)
		(width 0.11684)
		(layer "In6.Cu")
		(net "FM_CPU0_SA0")
	)
	(segment
		(start 192.03543 -102.061264)
		(end 192.841372 -102.061264)
		(width 0.11684)
		(layer "In6.Cu")
		(net "FM_CPU0_SA0")
	)
	(segment
		(start 181.575456 -127.289306)
		(end 181.575456 -125.964188)
		(width 0.10668)
		(layer "F.Cu")
		(net "FM_CPU0_RSMRST_N")
	)
	(segment
		(start 181.575456 -125.964188)
		(end 181.922166 -125.617478)
		(width 0.10668)
		(layer "F.Cu")
		(net "FM_CPU0_RSMRST_N")
	)
	(segment
		(start 181.526688 -130.863594)
		(end 181.526688 -128.537462)
		(width 0.10668)
		(layer "F.Cu")
		(net "FM_CPU0_RSMRST_N")
	)
	(segment
		(start 180.970936 -132.835904)
		(end 180.970936 -132.677408)
		(width 0.10668)
		(layer "F.Cu")
		(net "FM_CPU0_RSMRST_N")
	)
	(segment
		(start 181.526688 -132.121656)
		(end 181.526688 -130.863594)
		(width 0.10668)
		(layer "F.Cu")
		(net "FM_CPU0_RSMRST_N")
	)
	(segment
		(start 181.33568 -127.529082)
		(end 181.575456 -127.289306)
		(width 0.10668)
		(layer "F.Cu")
		(net "FM_CPU0_RSMRST_N")
	)
	(segment
		(start 181.526688 -128.537462)
		(end 181.33568 -128.346454)
		(width 0.10668)
		(layer "F.Cu")
		(net "FM_CPU0_RSMRST_N")
	)
	(segment
		(start 180.970936 -132.677408)
		(end 181.526688 -132.121656)
		(width 0.10668)
		(layer "F.Cu")
		(net "FM_CPU0_RSMRST_N")
	)
	(segment
		(start 181.33568 -128.346454)
		(end 181.33568 -127.529082)
		(width 0.10668)
		(layer "F.Cu")
		(net "FM_CPU0_RSMRST_N")
	)
	(segment
		(start 181.922166 -125.617478)
		(end 181.922166 -123.45289)
		(width 0.10668)
		(layer "F.Cu")
		(net "FM_CPU0_RSMRST_N")
	)
	(via
		(at 181.526688 -130.863594)
		(size 0.4064)
		(drill 0.2032)
		(layers "F.Cu" "B.Cu")
		(net "FM_CPU0_RSMRST_N")
	)
	(segment
		(start 200.539858 -112.609376)
		(end 199.866758 -112.609376)
		(width 0.10668)
		(layer "F.Cu")
		(net "FM_CPU0_PWR_GOOD")
	)
	(segment
		(start 191.522096 -113.05286)
		(end 191.911986 -112.66297)
		(width 0.10668)
		(layer "F.Cu")
		(net "FM_CPU0_PWR_GOOD")
	)
	(via
		(at 199.866758 -112.609376)
		(size 0.508)
		(drill 0.254)
		(layers "F.Cu" "B.Cu")
		(net "FM_CPU0_PWR_GOOD")
	)
	(via
		(at 191.911986 -112.66297)
		(size 0.4572)
		(drill 0.254)
		(layers "F.Cu" "B.Cu")
		(net "FM_CPU0_PWR_GOOD")
	)
	(segment
		(start 199.401684 -113.07445)
		(end 192.194434 -113.07445)
		(width 0.11684)
		(layer "In6.Cu")
		(net "FM_CPU0_PWR_GOOD")
	)
	(segment
		(start 199.866758 -112.609376)
		(end 199.401684 -113.07445)
		(width 0.11684)
		(layer "In6.Cu")
		(net "FM_CPU0_PWR_GOOD")
	)
	(segment
		(start 191.911986 -112.792002)
		(end 191.911986 -112.66297)
		(width 0.11684)
		(layer "In6.Cu")
		(net "FM_CPU0_PWR_GOOD")
	)
	(segment
		(start 192.194434 -113.07445)
		(end 191.911986 -112.792002)
		(width 0.11684)
		(layer "In6.Cu")
		(net "FM_CPU0_PWR_GOOD")
	)
	(segment
		(start 183.522112 -124.33554)
		(end 184.023 -124.836428)
		(width 0.10668)
		(layer "F.Cu")
		(net "FM_CPU0_PWR_BTN_N")
	)
	(segment
		(start 184.023 -124.836428)
		(end 184.023 -127.765556)
		(width 0.10668)
		(layer "F.Cu")
		(net "FM_CPU0_PWR_BTN_N")
	)
	(segment
		(start 183.522112 -123.45289)
		(end 183.522112 -124.33554)
		(width 0.10668)
		(layer "F.Cu")
		(net "FM_CPU0_PWR_BTN_N")
	)
	(segment
		(start 184.023 -128.977898)
		(end 184.023 -127.765556)
		(width 0.10668)
		(layer "F.Cu")
		(net "FM_CPU0_PWR_BTN_N")
	)
	(via
		(at 184.023 -127.765556)
		(size 0.762)
		(drill 0.381)
		(layers "F.Cu" "B.Cu")
		(net "FM_CPU0_PWR_BTN_N")
	)
	(segment
		(start 181.9402 -97.414588)
		(end 181.9402 -96.503998)
		(width 0.10668)
		(layer "F.Cu")
		(net "FM_CPU0_PROCHOT_R_N")
	)
	(segment
		(start 182.78856 -98.262948)
		(end 181.9402 -97.414588)
		(width 0.10668)
		(layer "F.Cu")
		(net "FM_CPU0_PROCHOT_R_N")
	)
	(segment
		(start 183.522112 -110.652814)
		(end 183.132222 -110.262924)
		(width 0.10668)
		(layer "F.Cu")
		(net "FM_CPU0_PROCHOT_R_N")
	)
	(via
		(at 182.78856 -98.262948)
		(size 0.762)
		(drill 0.254)
		(layers "F.Cu" "B.Cu")
		(net "FM_CPU0_PROCHOT_R_N")
	)
	(via
		(at 183.132222 -110.262924)
		(size 0.4572)
		(drill 0.254)
		(layers "F.Cu" "B.Cu")
		(net "FM_CPU0_PROCHOT_R_N")
	)
	(segment
		(start 182.258208 -98.7933)
		(end 182.258208 -103.932736)
		(width 0.11684)
		(layer "In4.Cu")
		(net "FM_CPU0_PROCHOT_R_N")
	)
	(segment
		(start 182.78856 -98.262948)
		(end 182.258208 -98.7933)
		(width 0.11684)
		(layer "In4.Cu")
		(net "FM_CPU0_PROCHOT_R_N")
	)
	(segment
		(start 182.258208 -103.932736)
		(end 182.738268 -104.412796)
		(width 0.11684)
		(layer "In4.Cu")
		(net "FM_CPU0_PROCHOT_R_N")
	)
	(segment
		(start 182.738268 -104.412796)
		(end 182.738268 -109.86897)
		(width 0.11684)
		(layer "In4.Cu")
		(net "FM_CPU0_PROCHOT_R_N")
	)
	(segment
		(start 182.738268 -109.86897)
		(end 183.132222 -110.262924)
		(width 0.11684)
		(layer "In4.Cu")
		(net "FM_CPU0_PROCHOT_R_N")
	)
	(segment
		(start 181.922166 -121.852944)
		(end 181.532276 -122.242834)
		(width 0.10668)
		(layer "F.Cu")
		(net "FM_CPU0_NV_SAVE_N")
	)
	(via
		(at 181.770528 -123.711716)
		(size 0.6604)
		(drill 0.3302)
		(layers "F.Cu" "B.Cu")
		(net "FM_CPU0_NV_SAVE_N")
	)
	(via
		(at 181.532276 -122.242834)
		(size 0.4572)
		(drill 0.254)
		(layers "F.Cu" "B.Cu")
		(net "FM_CPU0_NV_SAVE_N")
	)
	(segment
		(start 181.641496 -126.433326)
		(end 182.250842 -125.82398)
		(width 0.10668)
		(layer "B.Cu")
		(net "FM_CPU0_NV_SAVE_N")
	)
	(segment
		(start 182.250842 -125.82398)
		(end 182.250842 -124.19203)
		(width 0.10668)
		(layer "B.Cu")
		(net "FM_CPU0_NV_SAVE_N")
	)
	(segment
		(start 181.770528 -123.711716)
		(end 181.770528 -122.481086)
		(width 0.10668)
		(layer "B.Cu")
		(net "FM_CPU0_NV_SAVE_N")
	)
	(segment
		(start 182.250842 -124.19203)
		(end 181.770528 -123.711716)
		(width 0.10668)
		(layer "B.Cu")
		(net "FM_CPU0_NV_SAVE_N")
	)
	(segment
		(start 181.770528 -122.481086)
		(end 181.532276 -122.242834)
		(width 0.10668)
		(layer "B.Cu")
		(net "FM_CPU0_NV_SAVE_N")
	)
	(segment
		(start 181.013608 -126.433326)
		(end 181.641496 -126.433326)
		(width 0.10668)
		(layer "B.Cu")
		(net "FM_CPU0_NV_SAVE_N")
	)
	(segment
		(start 183.522112 -118.652798)
		(end 183.132222 -119.042688)
		(width 0.10668)
		(layer "F.Cu")
		(net "FM_CPU0_NMI_SYNC_FLOOD_N")
	)
	(segment
		(start 185.49874 -133.148832)
		(end 185.49874 -133.012688)
		(width 0.10668)
		(layer "F.Cu")
		(net "FM_CPU0_NMI_SYNC_FLOOD_N")
	)
	(segment
		(start 185.49874 -133.012688)
		(end 185.039 -132.552948)
		(width 0.10668)
		(layer "F.Cu")
		(net "FM_CPU0_NMI_SYNC_FLOOD_N")
	)
	(via
		(at 183.132222 -119.042688)
		(size 0.4572)
		(drill 0.254)
		(layers "F.Cu" "B.Cu")
		(net "FM_CPU0_NMI_SYNC_FLOOD_N")
	)
	(via
		(at 185.039 -132.552948)
		(size 0.508)
		(drill 0.254)
		(layers "F.Cu" "B.Cu")
		(net "FM_CPU0_NMI_SYNC_FLOOD_N")
	)
	(segment
		(start 185.572908 -131.01447)
		(end 185.706258 -131.14782)
		(width 0.11684)
		(layer "In2.Cu")
		(net "FM_CPU0_NMI_SYNC_FLOOD_N")
	)
	(segment
		(start 184.341008 -126.089664)
		(end 185.572908 -127.321564)
		(width 0.11684)
		(layer "In2.Cu")
		(net "FM_CPU0_NMI_SYNC_FLOOD_N")
	)
	(segment
		(start 183.359806 -119.042688)
		(end 183.761634 -119.444516)
		(width 0.11684)
		(layer "In2.Cu")
		(net "FM_CPU0_NMI_SYNC_FLOOD_N")
	)
	(segment
		(start 185.572908 -127.321564)
		(end 185.572908 -131.01447)
		(width 0.11684)
		(layer "In2.Cu")
		(net "FM_CPU0_NMI_SYNC_FLOOD_N")
	)
	(segment
		(start 184.341008 -119.561356)
		(end 184.341008 -126.089664)
		(width 0.11684)
		(layer "In2.Cu")
		(net "FM_CPU0_NMI_SYNC_FLOOD_N")
	)
	(segment
		(start 185.706258 -131.88569)
		(end 185.039 -132.552948)
		(width 0.11684)
		(layer "In2.Cu")
		(net "FM_CPU0_NMI_SYNC_FLOOD_N")
	)
	(segment
		(start 183.761634 -119.444516)
		(end 184.224168 -119.444516)
		(width 0.11684)
		(layer "In2.Cu")
		(net "FM_CPU0_NMI_SYNC_FLOOD_N")
	)
	(segment
		(start 183.132222 -119.042688)
		(end 183.359806 -119.042688)
		(width 0.11684)
		(layer "In2.Cu")
		(net "FM_CPU0_NMI_SYNC_FLOOD_N")
	)
	(segment
		(start 184.224168 -119.444516)
		(end 184.341008 -119.561356)
		(width 0.11684)
		(layer "In2.Cu")
		(net "FM_CPU0_NMI_SYNC_FLOOD_N")
	)
	(segment
		(start 185.706258 -131.14782)
		(end 185.706258 -131.88569)
		(width 0.11684)
		(layer "In2.Cu")
		(net "FM_CPU0_NMI_SYNC_FLOOD_N")
	)
	(segment
		(start 189.103 -127.003556)
		(end 189.103 -125.714252)
		(width 0.10668)
		(layer "F.Cu")
		(net "FM_CPU0_HDT_CONN_TESTEN")
	)
	(segment
		(start 189.103 -128.977898)
		(end 189.103 -127.003556)
		(width 0.10668)
		(layer "F.Cu")
		(net "FM_CPU0_HDT_CONN_TESTEN")
	)
	(segment
		(start 189.103 -125.714252)
		(end 187.922408 -124.53366)
		(width 0.10668)
		(layer "F.Cu")
		(net "FM_CPU0_HDT_CONN_TESTEN")
	)
	(segment
		(start 187.922408 -124.53366)
		(end 187.922408 -123.053094)
		(width 0.10668)
		(layer "F.Cu")
		(net "FM_CPU0_HDT_CONN_TESTEN")
	)
	(segment
		(start 187.922408 -123.053094)
		(end 187.522104 -122.65279)
		(width 0.10668)
		(layer "F.Cu")
		(net "FM_CPU0_HDT_CONN_TESTEN")
	)
	(via
		(at 189.103 -127.003556)
		(size 0.762)
		(drill 0.381)
		(layers "F.Cu" "B.Cu")
		(net "FM_CPU0_HDT_CONN_TESTEN")
	)
	(segment
		(start 180.9242 -96.503998)
		(end 180.9242 -96.916748)
		(width 0.10668)
		(layer "F.Cu")
		(net "IRQ_TPM_SPI_R1_N")
	)
	(segment
		(start 180.9242 -96.916748)
		(end 180.721 -97.119948)
		(width 0.10668)
		(layer "F.Cu")
		(net "IRQ_TPM_SPI_R1_N")
	)
	(segment
		(start 182.722012 -110.652814)
		(end 182.332122 -110.262924)
		(width 0.10668)
		(layer "F.Cu")
		(net "IRQ_TPM_SPI_R1_N")
	)
	(via
		(at 182.332122 -110.262924)
		(size 0.4572)
		(drill 0.254)
		(layers "F.Cu" "B.Cu")
		(net "IRQ_TPM_SPI_R1_N")
	)
	(via
		(at 180.721 -97.119948)
		(size 0.508)
		(drill 0.254)
		(layers "F.Cu" "B.Cu")
		(net "IRQ_TPM_SPI_R1_N")
	)
	(segment
		(start 181.930548 -105.294176)
		(end 181.267608 -104.631236)
		(width 0.11684)
		(layer "In4.Cu")
		(net "IRQ_TPM_SPI_R1_N")
	)
	(segment
		(start 180.240686 -100.222304)
		(end 180.240686 -97.600262)
		(width 0.11684)
		(layer "In4.Cu")
		(net "IRQ_TPM_SPI_R1_N")
	)
	(segment
		(start 181.267608 -101.249226)
		(end 180.240686 -100.222304)
		(width 0.11684)
		(layer "In4.Cu")
		(net "IRQ_TPM_SPI_R1_N")
	)
	(segment
		(start 181.267608 -104.631236)
		(end 181.267608 -101.249226)
		(width 0.11684)
		(layer "In4.Cu")
		(net "IRQ_TPM_SPI_R1_N")
	)
	(segment
		(start 182.332122 -110.262924)
		(end 182.332122 -110.064804)
		(width 0.11684)
		(layer "In4.Cu")
		(net "IRQ_TPM_SPI_R1_N")
	)
	(segment
		(start 180.240686 -97.600262)
		(end 180.721 -97.119948)
		(width 0.11684)
		(layer "In4.Cu")
		(net "IRQ_TPM_SPI_R1_N")
	)
	(segment
		(start 181.930548 -109.66323)
		(end 181.930548 -105.294176)
		(width 0.11684)
		(layer "In4.Cu")
		(net "IRQ_TPM_SPI_R1_N")
	)
	(segment
		(start 182.332122 -110.064804)
		(end 181.930548 -109.66323)
		(width 0.11684)
		(layer "In4.Cu")
		(net "IRQ_TPM_SPI_R1_N")
	)
	(segment
		(start 181.922166 -109.852968)
		(end 181.532276 -109.463078)
		(width 0.10668)
		(layer "F.Cu")
		(net "IRQ_SMI_ACTIVE_N_R")
	)
	(via
		(at 183.543702 -102.098348)
		(size 0.6604)
		(drill 0.3302)
		(layers "F.Cu" "B.Cu")
		(net "IRQ_SMI_ACTIVE_N_R")
	)
	(via
		(at 181.532276 -109.463078)
		(size 0.4572)
		(drill 0.254)
		(layers "F.Cu" "B.Cu")
		(net "IRQ_SMI_ACTIVE_N_R")
	)
	(segment
		(start 184.281064 -97.376742)
		(end 183.877458 -97.780348)
		(width 0.10668)
		(layer "B.Cu")
		(net "IRQ_SMI_ACTIVE_N_R")
	)
	(segment
		(start 183.3245 -98.901504)
		(end 183.257952 -98.968052)
		(width 0.10668)
		(layer "B.Cu")
		(net "IRQ_SMI_ACTIVE_N_R")
	)
	(segment
		(start 183.257952 -98.968052)
		(end 183.257952 -99.643692)
		(width 0.10668)
		(layer "B.Cu")
		(net "IRQ_SMI_ACTIVE_N_R")
	)
	(segment
		(start 183.536082 -108.819696)
		(end 183.28894 -109.066838)
		(width 0.10668)
		(layer "B.Cu")
		(net "IRQ_SMI_ACTIVE_N_R")
	)
	(segment
		(start 183.877458 -97.780348)
		(end 183.616854 -97.780348)
		(width 0.10668)
		(layer "B.Cu")
		(net "IRQ_SMI_ACTIVE_N_R")
	)
	(segment
		(start 183.616854 -97.780348)
		(end 183.3245 -98.072702)
		(width 0.10668)
		(layer "B.Cu")
		(net "IRQ_SMI_ACTIVE_N_R")
	)
	(segment
		(start 183.3245 -101.879146)
		(end 183.543702 -102.098348)
		(width 0.10668)
		(layer "B.Cu")
		(net "IRQ_SMI_ACTIVE_N_R")
	)
	(segment
		(start 183.93537 -105.407968)
		(end 183.536082 -105.807256)
		(width 0.10668)
		(layer "B.Cu")
		(net "IRQ_SMI_ACTIVE_N_R")
	)
	(segment
		(start 183.543702 -102.098348)
		(end 183.536082 -102.105968)
		(width 0.10668)
		(layer "B.Cu")
		(net "IRQ_SMI_ACTIVE_N_R")
	)
	(segment
		(start 184.281064 -96.762062)
		(end 184.281064 -97.376742)
		(width 0.10668)
		(layer "B.Cu")
		(net "IRQ_SMI_ACTIVE_N_R")
	)
	(segment
		(start 183.28894 -109.066838)
		(end 181.928516 -109.066838)
		(width 0.10668)
		(layer "B.Cu")
		(net "IRQ_SMI_ACTIVE_N_R")
	)
	(segment
		(start 183.536082 -103.459026)
		(end 183.93537 -103.858314)
		(width 0.10668)
		(layer "B.Cu")
		(net "IRQ_SMI_ACTIVE_N_R")
	)
	(segment
		(start 183.93537 -103.858314)
		(end 183.93537 -105.407968)
		(width 0.10668)
		(layer "B.Cu")
		(net "IRQ_SMI_ACTIVE_N_R")
	)
	(segment
		(start 183.536082 -102.105968)
		(end 183.536082 -103.459026)
		(width 0.10668)
		(layer "B.Cu")
		(net "IRQ_SMI_ACTIVE_N_R")
	)
	(segment
		(start 183.3245 -99.71024)
		(end 183.3245 -101.879146)
		(width 0.10668)
		(layer "B.Cu")
		(net "IRQ_SMI_ACTIVE_N_R")
	)
	(segment
		(start 183.3245 -98.072702)
		(end 183.3245 -98.901504)
		(width 0.10668)
		(layer "B.Cu")
		(net "IRQ_SMI_ACTIVE_N_R")
	)
	(segment
		(start 183.257952 -99.643692)
		(end 183.3245 -99.71024)
		(width 0.10668)
		(layer "B.Cu")
		(net "IRQ_SMI_ACTIVE_N_R")
	)
	(segment
		(start 184.25795 -96.738948)
		(end 184.281064 -96.762062)
		(width 0.10668)
		(layer "B.Cu")
		(net "IRQ_SMI_ACTIVE_N_R")
	)
	(segment
		(start 181.928516 -109.066838)
		(end 181.532276 -109.463078)
		(width 0.10668)
		(layer "B.Cu")
		(net "IRQ_SMI_ACTIVE_N_R")
	)
	(segment
		(start 183.536082 -105.807256)
		(end 183.536082 -108.819696)
		(width 0.10668)
		(layer "B.Cu")
		(net "IRQ_SMI_ACTIVE_N_R")
	)
	(segment
		(start 181.122066 -109.852968)
		(end 180.732176 -109.463078)
		(width 0.10668)
		(layer "F.Cu")
		(net "IRQ_BMC_SMI_R_N")
	)
	(via
		(at 175.28667 -102.05085)
		(size 0.508)
		(drill 0.254)
		(layers "F.Cu" "B.Cu")
		(net "IRQ_BMC_SMI_R_N")
	)
	(via
		(at 180.732176 -109.463078)
		(size 0.4572)
		(drill 0.254)
		(layers "F.Cu" "B.Cu")
		(net "IRQ_BMC_SMI_R_N")
	)
	(segment
		(start 177.10404 -103.86822)
		(end 175.28667 -102.05085)
		(width 0.10668)
		(layer "B.Cu")
		(net "IRQ_BMC_SMI_R_N")
	)
	(segment
		(start 180.732176 -109.463078)
		(end 180.331618 -109.06252)
		(width 0.10668)
		(layer "B.Cu")
		(net "IRQ_BMC_SMI_R_N")
	)
	(segment
		(start 177.3555 -106.9086)
		(end 177.3555 -105.73512)
		(width 0.10668)
		(layer "B.Cu")
		(net "IRQ_BMC_SMI_R_N")
	)
	(segment
		(start 180.331618 -109.06252)
		(end 179.7431 -109.06252)
		(width 0.10668)
		(layer "B.Cu")
		(net "IRQ_BMC_SMI_R_N")
	)
	(segment
		(start 174.64024 -100.694998)
		(end 174.64024 -101.40442)
		(width 0.10668)
		(layer "B.Cu")
		(net "IRQ_BMC_SMI_R_N")
	)
	(segment
		(start 179.33924 -108.25988)
		(end 178.94554 -108.25988)
		(width 0.10668)
		(layer "B.Cu")
		(net "IRQ_BMC_SMI_R_N")
	)
	(segment
		(start 179.52974 -108.84916)
		(end 179.52974 -108.45038)
		(width 0.10668)
		(layer "B.Cu")
		(net "IRQ_BMC_SMI_R_N")
	)
	(segment
		(start 174.64024 -101.40442)
		(end 175.28667 -102.05085)
		(width 0.10668)
		(layer "B.Cu")
		(net "IRQ_BMC_SMI_R_N")
	)
	(segment
		(start 178.2445 -107.55884)
		(end 178.00574 -107.55884)
		(width 0.10668)
		(layer "B.Cu")
		(net "IRQ_BMC_SMI_R_N")
	)
	(segment
		(start 177.10404 -105.48366)
		(end 177.10404 -103.86822)
		(width 0.10668)
		(layer "B.Cu")
		(net "IRQ_BMC_SMI_R_N")
	)
	(segment
		(start 178.00574 -107.55884)
		(end 177.3555 -106.9086)
		(width 0.10668)
		(layer "B.Cu")
		(net "IRQ_BMC_SMI_R_N")
	)
	(segment
		(start 179.7431 -109.06252)
		(end 179.52974 -108.84916)
		(width 0.10668)
		(layer "B.Cu")
		(net "IRQ_BMC_SMI_R_N")
	)
	(segment
		(start 178.94554 -108.25988)
		(end 178.2445 -107.55884)
		(width 0.10668)
		(layer "B.Cu")
		(net "IRQ_BMC_SMI_R_N")
	)
	(segment
		(start 179.52974 -108.45038)
		(end 179.33924 -108.25988)
		(width 0.10668)
		(layer "B.Cu")
		(net "IRQ_BMC_SMI_R_N")
	)
	(segment
		(start 177.3555 -105.73512)
		(end 177.10404 -105.48366)
		(width 0.10668)
		(layer "B.Cu")
		(net "IRQ_BMC_SMI_R_N")
	)
	(segment
		(start 179.15636 -102.112572)
		(end 178.816 -102.452932)
		(width 0.10668)
		(layer "F.Cu")
		(net "FM_SMM_CRASHDUMP_R")
	)
	(segment
		(start 178.689 -100.694998)
		(end 179.15636 -101.162358)
		(width 0.10668)
		(layer "F.Cu")
		(net "FM_SMM_CRASHDUMP_R")
	)
	(segment
		(start 178.816 -103.124)
		(end 178.816 -104.303576)
		(width 0.10668)
		(layer "F.Cu")
		(net "FM_SMM_CRASHDUMP_R")
	)
	(segment
		(start 179.15636 -101.162358)
		(end 179.15636 -102.112572)
		(width 0.10668)
		(layer "F.Cu")
		(net "FM_SMM_CRASHDUMP_R")
	)
	(segment
		(start 179.52212 -105.009696)
		(end 179.52212 -106.652822)
		(width 0.10668)
		(layer "F.Cu")
		(net "FM_SMM_CRASHDUMP_R")
	)
	(segment
		(start 178.816 -102.452932)
		(end 178.816 -103.124)
		(width 0.10668)
		(layer "F.Cu")
		(net "FM_SMM_CRASHDUMP_R")
	)
	(segment
		(start 178.816 -104.303576)
		(end 179.52212 -105.009696)
		(width 0.10668)
		(layer "F.Cu")
		(net "FM_SMM_CRASHDUMP_R")
	)
	(via
		(at 178.816 -103.124)
		(size 0.762)
		(drill 0.381)
		(layers "F.Cu" "B.Cu")
		(net "FM_SMM_CRASHDUMP_R")
	)
	(segment
		(start 189.92215 -119.452898)
		(end 190.31204 -119.842788)
		(width 0.10668)
		(layer "F.Cu")
		(net "FM_CPU0_FORCE_SELFREFRESH")
	)
	(via
		(at 194.337178 -124.90323)
		(size 0.6604)
		(drill 0.3302)
		(layers "F.Cu" "B.Cu")
		(net "FM_CPU0_FORCE_SELFREFRESH")
	)
	(via
		(at 190.31204 -119.842788)
		(size 0.4572)
		(drill 0.254)
		(layers "F.Cu" "B.Cu")
		(net "FM_CPU0_FORCE_SELFREFRESH")
	)
	(segment
		(start 193.370708 -123.504706)
		(end 193.370708 -124.392436)
		(width 0.10668)
		(layer "B.Cu")
		(net "FM_CPU0_FORCE_SELFREFRESH")
	)
	(segment
		(start 192.068704 -121.838974)
		(end 192.313814 -122.084084)
		(width 0.10668)
		(layer "B.Cu")
		(net "FM_CPU0_FORCE_SELFREFRESH")
	)
	(segment
		(start 191.268604 -121.038874)
		(end 191.508126 -121.278396)
		(width 0.10668)
		(layer "B.Cu")
		(net "FM_CPU0_FORCE_SELFREFRESH")
	)
	(segment
		(start 193.370708 -124.392436)
		(end 193.881502 -124.90323)
		(width 0.10668)
		(layer "B.Cu")
		(net "FM_CPU0_FORCE_SELFREFRESH")
	)
	(segment
		(start 191.508126 -121.278396)
		(end 191.508126 -121.692416)
		(width 0.10668)
		(layer "B.Cu")
		(net "FM_CPU0_FORCE_SELFREFRESH")
	)
	(segment
		(start 192.313814 -122.084084)
		(end 192.313814 -122.447812)
		(width 0.10668)
		(layer "B.Cu")
		(net "FM_CPU0_FORCE_SELFREFRESH")
	)
	(segment
		(start 191.654684 -121.838974)
		(end 192.068704 -121.838974)
		(width 0.10668)
		(layer "B.Cu")
		(net "FM_CPU0_FORCE_SELFREFRESH")
	)
	(segment
		(start 194.337178 -126.190756)
		(end 194.094608 -126.433326)
		(width 0.10668)
		(layer "B.Cu")
		(net "FM_CPU0_FORCE_SELFREFRESH")
	)
	(segment
		(start 193.881502 -124.90323)
		(end 194.337178 -124.90323)
		(width 0.10668)
		(layer "B.Cu")
		(net "FM_CPU0_FORCE_SELFREFRESH")
	)
	(segment
		(start 190.70828 -120.478296)
		(end 190.70828 -120.823228)
		(width 0.10668)
		(layer "B.Cu")
		(net "FM_CPU0_FORCE_SELFREFRESH")
	)
	(segment
		(start 190.31204 -120.082056)
		(end 190.70828 -120.478296)
		(width 0.10668)
		(layer "B.Cu")
		(net "FM_CPU0_FORCE_SELFREFRESH")
	)
	(segment
		(start 190.923926 -121.038874)
		(end 191.268604 -121.038874)
		(width 0.10668)
		(layer "B.Cu")
		(net "FM_CPU0_FORCE_SELFREFRESH")
	)
	(segment
		(start 191.508126 -121.692416)
		(end 191.654684 -121.838974)
		(width 0.10668)
		(layer "B.Cu")
		(net "FM_CPU0_FORCE_SELFREFRESH")
	)
	(segment
		(start 190.31204 -119.842788)
		(end 190.31204 -120.082056)
		(width 0.10668)
		(layer "B.Cu")
		(net "FM_CPU0_FORCE_SELFREFRESH")
	)
	(segment
		(start 194.337178 -124.90323)
		(end 194.337178 -126.190756)
		(width 0.10668)
		(layer "B.Cu")
		(net "FM_CPU0_FORCE_SELFREFRESH")
	)
	(segment
		(start 192.313814 -122.447812)
		(end 193.370708 -123.504706)
		(width 0.10668)
		(layer "B.Cu")
		(net "FM_CPU0_FORCE_SELFREFRESH")
	)
	(segment
		(start 190.70828 -120.823228)
		(end 190.923926 -121.038874)
		(width 0.10668)
		(layer "B.Cu")
		(net "FM_CPU0_FORCE_SELFREFRESH")
	)
	(segment
		(start 187.522104 -108.252768)
		(end 187.911994 -107.862878)
		(width 0.10668)
		(layer "F.Cu")
		(net "FM_CPU0_CORETYPE2")
	)
	(via
		(at 188.976 -101.87686)
		(size 0.6604)
		(drill 0.3302)
		(layers "F.Cu" "B.Cu")
		(net "FM_CPU0_CORETYPE2")
	)
	(via
		(at 187.911994 -107.862878)
		(size 0.4572)
		(drill 0.254)
		(layers "F.Cu" "B.Cu")
		(net "FM_CPU0_CORETYPE2")
	)
	(segment
		(start 188.8744 -101.97846)
		(end 188.976 -101.87686)
		(width 0.10668)
		(layer "B.Cu")
		(net "FM_CPU0_CORETYPE2")
	)
	(segment
		(start 188.976 -101.87686)
		(end 189.347348 -101.505512)
		(width 0.10668)
		(layer "B.Cu")
		(net "FM_CPU0_CORETYPE2")
	)
	(segment
		(start 189.843918 -97.519998)
		(end 189.865 -97.519998)
		(width 0.10668)
		(layer "B.Cu")
		(net "FM_CPU0_CORETYPE2")
	)
	(segment
		(start 189.347348 -98.016568)
		(end 189.843918 -97.519998)
		(width 0.10668)
		(layer "B.Cu")
		(net "FM_CPU0_CORETYPE2")
	)
	(segment
		(start 187.911994 -107.862878)
		(end 187.911994 -106.347514)
		(width 0.10668)
		(layer "B.Cu")
		(net "FM_CPU0_CORETYPE2")
	)
	(segment
		(start 189.347348 -101.505512)
		(end 189.347348 -98.016568)
		(width 0.10668)
		(layer "B.Cu")
		(net "FM_CPU0_CORETYPE2")
	)
	(segment
		(start 188.8744 -105.385108)
		(end 188.8744 -101.97846)
		(width 0.10668)
		(layer "B.Cu")
		(net "FM_CPU0_CORETYPE2")
	)
	(segment
		(start 187.911994 -106.347514)
		(end 188.8744 -105.385108)
		(width 0.10668)
		(layer "B.Cu")
		(net "FM_CPU0_CORETYPE2")
	)
	(segment
		(start 188.727588 -103.364792)
		(end 188.727588 -107.047538)
		(width 0.10668)
		(layer "F.Cu")
		(net "FM_CPU0_CORETYPE1")
	)
	(segment
		(start 188.727588 -107.047538)
		(end 188.322204 -107.452922)
		(width 0.10668)
		(layer "F.Cu")
		(net "FM_CPU0_CORETYPE1")
	)
	(segment
		(start 188.976 -103.11638)
		(end 188.727588 -103.364792)
		(width 0.10668)
		(layer "F.Cu")
		(net "FM_CPU0_CORETYPE1")
	)
	(segment
		(start 189.865 -102.22738)
		(end 188.976 -103.11638)
		(width 0.10668)
		(layer "F.Cu")
		(net "FM_CPU0_CORETYPE1")
	)
	(segment
		(start 189.865 -100.694998)
		(end 189.865 -102.22738)
		(width 0.10668)
		(layer "F.Cu")
		(net "FM_CPU0_CORETYPE1")
	)
	(via
		(at 188.976 -103.11638)
		(size 0.762)
		(drill 0.381)
		(layers "F.Cu" "B.Cu")
		(net "FM_CPU0_CORETYPE1")
	)
	(segment
		(start 188.322204 -102.507796)
		(end 189.23 -101.6)
		(width 0.10668)
		(layer "F.Cu")
		(net "FM_CPU0_CORETYPE0")
	)
	(segment
		(start 188.849 -101.219)
		(end 188.849 -100.694998)
		(width 0.10668)
		(layer "F.Cu")
		(net "FM_CPU0_CORETYPE0")
	)
	(segment
		(start 188.322204 -106.652822)
		(end 188.322204 -102.507796)
		(width 0.10668)
		(layer "F.Cu")
		(net "FM_CPU0_CORETYPE0")
	)
	(segment
		(start 189.23 -101.6)
		(end 188.849 -101.219)
		(width 0.10668)
		(layer "F.Cu")
		(net "FM_CPU0_CORETYPE0")
	)
	(via
		(at 189.23 -101.6)
		(size 0.762)
		(drill 0.381)
		(layers "F.Cu" "B.Cu")
		(net "FM_CPU0_CORETYPE0")
	)
	(segment
		(start 183.522112 -119.452898)
		(end 183.132222 -119.842788)
		(width 0.10668)
		(layer "F.Cu")
		(net "FM_FPGA_DEBUG_LED_CTRL")
	)
	(segment
		(start 179.959 -137.232898)
		(end 179.88534 -137.159238)
		(width 0.10668)
		(layer "F.Cu")
		(net "FM_FPGA_DEBUG_LED_CTRL")
	)
	(segment
		(start 179.88534 -137.159238)
		(end 179.88534 -136.605264)
		(width 0.10668)
		(layer "F.Cu")
		(net "FM_FPGA_DEBUG_LED_CTRL")
	)
	(via
		(at 183.132222 -119.842788)
		(size 0.4572)
		(drill 0.254)
		(layers "F.Cu" "B.Cu")
		(net "FM_FPGA_DEBUG_LED_CTRL")
	)
	(via
		(at 179.88534 -136.605264)
		(size 0.508)
		(drill 0.254)
		(layers "F.Cu" "B.Cu")
		(net "FM_FPGA_DEBUG_LED_CTRL")
	)
	(segment
		(start 183.132222 -119.842788)
		(end 182.946802 -119.842788)
		(width 0.11684)
		(layer "In2.Cu")
		(net "FM_FPGA_DEBUG_LED_CTRL")
	)
	(segment
		(start 182.07609 -119.444008)
		(end 181.926992 -119.593106)
		(width 0.11684)
		(layer "In2.Cu")
		(net "FM_FPGA_DEBUG_LED_CTRL")
	)
	(segment
		(start 180.438044 -136.021064)
		(end 179.88534 -136.573768)
		(width 0.11684)
		(layer "In2.Cu")
		(net "FM_FPGA_DEBUG_LED_CTRL")
	)
	(segment
		(start 180.438044 -131.132326)
		(end 180.438044 -136.021064)
		(width 0.11684)
		(layer "In2.Cu")
		(net "FM_FPGA_DEBUG_LED_CTRL")
	)
	(segment
		(start 182.946802 -119.842788)
		(end 182.548022 -119.444008)
		(width 0.11684)
		(layer "In2.Cu")
		(net "FM_FPGA_DEBUG_LED_CTRL")
	)
	(segment
		(start 181.926992 -119.593106)
		(end 181.926992 -122.476768)
		(width 0.11684)
		(layer "In2.Cu")
		(net "FM_FPGA_DEBUG_LED_CTRL")
	)
	(segment
		(start 180.224684 -130.918966)
		(end 180.438044 -131.132326)
		(width 0.11684)
		(layer "In2.Cu")
		(net "FM_FPGA_DEBUG_LED_CTRL")
	)
	(segment
		(start 179.88534 -136.573768)
		(end 179.88534 -136.605264)
		(width 0.11684)
		(layer "In2.Cu")
		(net "FM_FPGA_DEBUG_LED_CTRL")
	)
	(segment
		(start 181.926992 -122.476768)
		(end 181.412642 -122.991118)
		(width 0.11684)
		(layer "In2.Cu")
		(net "FM_FPGA_DEBUG_LED_CTRL")
	)
	(segment
		(start 180.224684 -130.031998)
		(end 180.224684 -130.918966)
		(width 0.11684)
		(layer "In2.Cu")
		(net "FM_FPGA_DEBUG_LED_CTRL")
	)
	(segment
		(start 181.412642 -122.991118)
		(end 181.412642 -124.611892)
		(width 0.11684)
		(layer "In2.Cu")
		(net "FM_FPGA_DEBUG_LED_CTRL")
	)
	(segment
		(start 180.438044 -129.818638)
		(end 180.224684 -130.031998)
		(width 0.11684)
		(layer "In2.Cu")
		(net "FM_FPGA_DEBUG_LED_CTRL")
	)
	(segment
		(start 181.412642 -124.611892)
		(end 180.438044 -125.58649)
		(width 0.11684)
		(layer "In2.Cu")
		(net "FM_FPGA_DEBUG_LED_CTRL")
	)
	(segment
		(start 182.548022 -119.444008)
		(end 182.07609 -119.444008)
		(width 0.11684)
		(layer "In2.Cu")
		(net "FM_FPGA_DEBUG_LED_CTRL")
	)
	(segment
		(start 180.438044 -125.58649)
		(end 180.438044 -129.818638)
		(width 0.11684)
		(layer "In2.Cu")
		(net "FM_FPGA_DEBUG_LED_CTRL")
	)
	(segment
		(start 186.722004 -108.252768)
		(end 187.111894 -107.862878)
		(width 0.10668)
		(layer "F.Cu")
		(net "FM_CLR_CMOS")
	)
	(via
		(at 187.111894 -107.862878)
		(size 0.4572)
		(drill 0.254)
		(layers "F.Cu" "B.Cu")
		(net "FM_CLR_CMOS")
	)
	(via
		(at 187.4774 -103.83012)
		(size 0.6604)
		(drill 0.3302)
		(layers "F.Cu" "B.Cu")
		(net "FM_CLR_CMOS")
	)
	(segment
		(start 187.111894 -107.862878)
		(end 187.111894 -105.578402)
		(width 0.10668)
		(layer "B.Cu")
		(net "FM_CLR_CMOS")
	)
	(segment
		(start 187.2234 -105.466896)
		(end 187.2234 -104.08412)
		(width 0.10668)
		(layer "B.Cu")
		(net "FM_CLR_CMOS")
	)
	(segment
		(start 187.2234 -104.08412)
		(end 187.4774 -103.83012)
		(width 0.10668)
		(layer "B.Cu")
		(net "FM_CLR_CMOS")
	)
	(segment
		(start 187.111894 -105.578402)
		(end 187.2234 -105.466896)
		(width 0.10668)
		(layer "B.Cu")
		(net "FM_CLR_CMOS")
	)
	(segment
		(start 187.4774 -103.83012)
		(end 187.7822 -103.52532)
		(width 0.10668)
		(layer "B.Cu")
		(net "FM_CLR_CMOS")
	)
	(segment
		(start 187.7822 -103.52532)
		(end 187.7822 -100.779834)
		(width 0.10668)
		(layer "B.Cu")
		(net "FM_CLR_CMOS")
	)
	(segment
		(start 187.7822 -100.779834)
		(end 187.871608 -100.690426)
		(width 0.10668)
		(layer "B.Cu")
		(net "FM_CLR_CMOS")
	)
	(segment
		(start 186.722004 -107.452922)
		(end 187.127388 -107.047538)
		(width 0.10668)
		(layer "F.Cu")
		(net "FM_CLKREQ_M2_1_N")
	)
	(segment
		(start 186.550808 -100.694998)
		(end 186.817 -100.694998)
		(width 0.10668)
		(layer "F.Cu")
		(net "FM_CLKREQ_M2_1_N")
	)
	(segment
		(start 186.4106 -103.10876)
		(end 186.2328 -102.93096)
		(width 0.10668)
		(layer "F.Cu")
		(net "FM_CLKREQ_M2_1_N")
	)
	(segment
		(start 187.127388 -105.769156)
		(end 186.4106 -105.052368)
		(width 0.10668)
		(layer "F.Cu")
		(net "FM_CLKREQ_M2_1_N")
	)
	(segment
		(start 186.2328 -101.013006)
		(end 186.550808 -100.694998)
		(width 0.10668)
		(layer "F.Cu")
		(net "FM_CLKREQ_M2_1_N")
	)
	(segment
		(start 186.2328 -102.93096)
		(end 186.2328 -101.013006)
		(width 0.10668)
		(layer "F.Cu")
		(net "FM_CLKREQ_M2_1_N")
	)
	(segment
		(start 186.4106 -105.052368)
		(end 186.4106 -103.10876)
		(width 0.10668)
		(layer "F.Cu")
		(net "FM_CLKREQ_M2_1_N")
	)
	(segment
		(start 187.127388 -107.047538)
		(end 187.127388 -105.769156)
		(width 0.10668)
		(layer "F.Cu")
		(net "FM_CLKREQ_M2_1_N")
	)
	(via
		(at 186.4106 -103.10876)
		(size 0.762)
		(drill 0.381)
		(layers "F.Cu" "B.Cu")
		(net "FM_CLKREQ_M2_1_N")
	)
	(segment
		(start 358.297988 -408.988768)
		(end 357.958644 -408.649424)
		(width 0.10668)
		(layer "F.Cu")
		(net "FM_PDB_BUF_EN_R1")
	)
	(segment
		(start 191.055498 -425.429426)
		(end 191.017906 -425.391834)
		(width 0.10668)
		(layer "F.Cu")
		(net "FM_PDB_BUF_EN_R1")
	)
	(segment
		(start 357.958644 -408.649424)
		(end 357.958644 -407.872184)
		(width 0.10668)
		(layer "F.Cu")
		(net "FM_PDB_BUF_EN_R1")
	)
	(segment
		(start 191.017906 -425.391834)
		(end 190.056516 -425.391834)
		(width 0.10668)
		(layer "F.Cu")
		(net "FM_PDB_BUF_EN_R1")
	)
	(segment
		(start 192.105534 -425.429426)
		(end 193.369438 -426.69333)
		(width 0.10668)
		(layer "F.Cu")
		(net "FM_PDB_BUF_EN_R1")
	)
	(segment
		(start 191.055498 -425.429426)
		(end 192.105534 -425.429426)
		(width 0.10668)
		(layer "F.Cu")
		(net "FM_PDB_BUF_EN_R1")
	)
	(via
		(at 357.958644 -407.872184)
		(size 0.508)
		(drill 0.254)
		(layers "F.Cu" "B.Cu")
		(net "FM_PDB_BUF_EN_R1")
	)
	(via
		(at 189.230254 -385.183634)
		(size 0.508)
		(drill 0.254)
		(layers "F.Cu" "B.Cu")
		(net "FM_PDB_BUF_EN_R1")
	)
	(via
		(at 289.315398 -409.291282)
		(size 0.508)
		(drill 0.254)
		(layers "F.Cu" "B.Cu")
		(net "FM_PDB_BUF_EN_R1")
	)
	(via
		(at 285.71825 -378.470668)
		(size 0.508)
		(drill 0.254)
		(layers "F.Cu" "B.Cu")
		(net "FM_PDB_BUF_EN_R1")
	)
	(via
		(at 190.606172 -373.098822)
		(size 0.508)
		(drill 0.254)
		(layers "F.Cu" "B.Cu")
		(net "FM_PDB_BUF_EN_R1")
	)
	(via
		(at 190.056516 -425.391834)
		(size 0.508)
		(drill 0.254)
		(layers "F.Cu" "B.Cu")
		(net "FM_PDB_BUF_EN_R1")
	)
	(segment
		(start 279.530556 -373.098822)
		(end 284.902402 -378.470668)
		(width 0.10668)
		(layer "B.Cu")
		(net "FM_PDB_BUF_EN_R1")
	)
	(segment
		(start 189.5221 -419.309296)
		(end 189.6491 -419.436296)
		(width 0.10668)
		(layer "B.Cu")
		(net "FM_PDB_BUF_EN_R1")
	)
	(segment
		(start 185.081164 -419.861238)
		(end 186.071002 -419.861238)
		(width 0.10668)
		(layer "B.Cu")
		(net "FM_PDB_BUF_EN_R1")
	)
	(segment
		(start 186.622944 -419.309296)
		(end 189.5221 -419.309296)
		(width 0.10668)
		(layer "B.Cu")
		(net "FM_PDB_BUF_EN_R1")
	)
	(segment
		(start 189.841632 -425.17695)
		(end 190.056516 -425.391834)
		(width 0.10668)
		(layer "B.Cu")
		(net "FM_PDB_BUF_EN_R1")
	)
	(segment
		(start 189.6491 -421.54221)
		(end 189.841632 -421.734742)
		(width 0.10668)
		(layer "B.Cu")
		(net "FM_PDB_BUF_EN_R1")
	)
	(segment
		(start 186.071002 -419.861238)
		(end 186.622944 -419.309296)
		(width 0.10668)
		(layer "B.Cu")
		(net "FM_PDB_BUF_EN_R1")
	)
	(segment
		(start 284.902402 -378.470668)
		(end 285.71825 -378.470668)
		(width 0.10668)
		(layer "B.Cu")
		(net "FM_PDB_BUF_EN_R1")
	)
	(segment
		(start 190.606172 -373.098822)
		(end 279.530556 -373.098822)
		(width 0.10668)
		(layer "B.Cu")
		(net "FM_PDB_BUF_EN_R1")
	)
	(segment
		(start 189.841632 -421.734742)
		(end 189.841632 -425.17695)
		(width 0.10668)
		(layer "B.Cu")
		(net "FM_PDB_BUF_EN_R1")
	)
	(segment
		(start 189.6491 -419.436296)
		(end 189.6491 -421.54221)
		(width 0.10668)
		(layer "B.Cu")
		(net "FM_PDB_BUF_EN_R1")
	)
	(segment
		(start 293.10838 -408.849068)
		(end 299.961554 -408.849068)
		(width 0.11684)
		(layer "In2.Cu")
		(net "FM_PDB_BUF_EN_R1")
	)
	(segment
		(start 357.322628 -408.5082)
		(end 357.958644 -407.872184)
		(width 0.11684)
		(layer "In2.Cu")
		(net "FM_PDB_BUF_EN_R1")
	)
	(segment
		(start 304.141886 -408.5082)
		(end 357.322628 -408.5082)
		(width 0.11684)
		(layer "In2.Cu")
		(net "FM_PDB_BUF_EN_R1")
	)
	(segment
		(start 300.907704 -409.795218)
		(end 302.854868 -409.795218)
		(width 0.11684)
		(layer "In2.Cu")
		(net "FM_PDB_BUF_EN_R1")
	)
	(segment
		(start 292.666166 -409.291282)
		(end 293.10838 -408.849068)
		(width 0.11684)
		(layer "In2.Cu")
		(net "FM_PDB_BUF_EN_R1")
	)
	(segment
		(start 299.961554 -408.849068)
		(end 300.907704 -409.795218)
		(width 0.11684)
		(layer "In2.Cu")
		(net "FM_PDB_BUF_EN_R1")
	)
	(segment
		(start 302.854868 -409.795218)
		(end 304.141886 -408.5082)
		(width 0.11684)
		(layer "In2.Cu")
		(net "FM_PDB_BUF_EN_R1")
	)
	(segment
		(start 289.315398 -409.291282)
		(end 292.666166 -409.291282)
		(width 0.11684)
		(layer "In2.Cu")
		(net "FM_PDB_BUF_EN_R1")
	)
	(segment
		(start 288.025332 -393.511786)
		(end 288.852864 -394.339318)
		(width 0.11684)
		(layer "In4.Cu")
		(net "FM_PDB_BUF_EN_R1")
	)
	(segment
		(start 287.910778 -400.888962)
		(end 287.910778 -402.928836)
		(width 0.11684)
		(layer "In4.Cu")
		(net "FM_PDB_BUF_EN_R1")
	)
	(segment
		(start 288.466022 -405.721058)
		(end 288.665412 -405.920448)
		(width 0.11684)
		(layer "In4.Cu")
		(net "FM_PDB_BUF_EN_R1")
	)
	(segment
		(start 286.593788 -387.11886)
		(end 288.025332 -388.550404)
		(width 0.11684)
		(layer "In4.Cu")
		(net "FM_PDB_BUF_EN_R1")
	)
	(segment
		(start 175.22825 -407.486104)
		(end 175.742854 -406.9715)
		(width 0.11684)
		(layer "In4.Cu")
		(net "FM_PDB_BUF_EN_R1")
	)
	(segment
		(start 288.665412 -408.641296)
		(end 289.315398 -409.291282)
		(width 0.11684)
		(layer "In4.Cu")
		(net "FM_PDB_BUF_EN_R1")
	)
	(segment
		(start 175.22825 -409.045918)
		(end 175.22825 -407.486104)
		(width 0.11684)
		(layer "In4.Cu")
		(net "FM_PDB_BUF_EN_R1")
	)
	(segment
		(start 175.742854 -392.215116)
		(end 182.774336 -385.183634)
		(width 0.11684)
		(layer "In4.Cu")
		(net "FM_PDB_BUF_EN_R1")
	)
	(segment
		(start 179.63388 -411.653228)
		(end 177.83556 -411.653228)
		(width 0.11684)
		(layer "In4.Cu")
		(net "FM_PDB_BUF_EN_R1")
	)
	(segment
		(start 287.910778 -402.928836)
		(end 288.466022 -403.48408)
		(width 0.11684)
		(layer "In4.Cu")
		(net "FM_PDB_BUF_EN_R1")
	)
	(segment
		(start 182.25262 -414.271968)
		(end 179.63388 -411.653228)
		(width 0.11684)
		(layer "In4.Cu")
		(net "FM_PDB_BUF_EN_R1")
	)
	(segment
		(start 286.593788 -379.346206)
		(end 286.593788 -387.11886)
		(width 0.11684)
		(layer "In4.Cu")
		(net "FM_PDB_BUF_EN_R1")
	)
	(segment
		(start 182.774336 -385.183634)
		(end 189.230254 -385.183634)
		(width 0.11684)
		(layer "In4.Cu")
		(net "FM_PDB_BUF_EN_R1")
	)
	(segment
		(start 286.427164 -398.35963)
		(end 286.427164 -399.405348)
		(width 0.11684)
		(layer "In4.Cu")
		(net "FM_PDB_BUF_EN_R1")
	)
	(segment
		(start 288.466022 -403.48408)
		(end 288.466022 -405.721058)
		(width 0.11684)
		(layer "In4.Cu")
		(net "FM_PDB_BUF_EN_R1")
	)
	(segment
		(start 285.71825 -378.470668)
		(end 286.593788 -379.346206)
		(width 0.11684)
		(layer "In4.Cu")
		(net "FM_PDB_BUF_EN_R1")
	)
	(segment
		(start 288.852864 -395.93393)
		(end 286.427164 -398.35963)
		(width 0.11684)
		(layer "In4.Cu")
		(net "FM_PDB_BUF_EN_R1")
	)
	(segment
		(start 190.056516 -419.260528)
		(end 192.180972 -417.136072)
		(width 0.11684)
		(layer "In4.Cu")
		(net "FM_PDB_BUF_EN_R1")
	)
	(segment
		(start 192.180972 -417.136072)
		(end 192.180972 -415.397442)
		(width 0.11684)
		(layer "In4.Cu")
		(net "FM_PDB_BUF_EN_R1")
	)
	(segment
		(start 286.427164 -399.405348)
		(end 287.910778 -400.888962)
		(width 0.11684)
		(layer "In4.Cu")
		(net "FM_PDB_BUF_EN_R1")
	)
	(segment
		(start 288.665412 -405.920448)
		(end 288.665412 -408.641296)
		(width 0.11684)
		(layer "In4.Cu")
		(net "FM_PDB_BUF_EN_R1")
	)
	(segment
		(start 175.742854 -406.9715)
		(end 175.742854 -392.215116)
		(width 0.11684)
		(layer "In4.Cu")
		(net "FM_PDB_BUF_EN_R1")
	)
	(segment
		(start 191.055498 -414.271968)
		(end 182.25262 -414.271968)
		(width 0.11684)
		(layer "In4.Cu")
		(net "FM_PDB_BUF_EN_R1")
	)
	(segment
		(start 288.852864 -394.339318)
		(end 288.852864 -395.93393)
		(width 0.11684)
		(layer "In4.Cu")
		(net "FM_PDB_BUF_EN_R1")
	)
	(segment
		(start 192.180972 -415.397442)
		(end 191.055498 -414.271968)
		(width 0.11684)
		(layer "In4.Cu")
		(net "FM_PDB_BUF_EN_R1")
	)
	(segment
		(start 177.83556 -411.653228)
		(end 175.22825 -409.045918)
		(width 0.11684)
		(layer "In4.Cu")
		(net "FM_PDB_BUF_EN_R1")
	)
	(segment
		(start 190.056516 -425.391834)
		(end 190.056516 -419.260528)
		(width 0.11684)
		(layer "In4.Cu")
		(net "FM_PDB_BUF_EN_R1")
	)
	(segment
		(start 288.025332 -388.550404)
		(end 288.025332 -393.511786)
		(width 0.11684)
		(layer "In4.Cu")
		(net "FM_PDB_BUF_EN_R1")
	)
	(segment
		(start 189.230254 -385.183634)
		(end 189.230254 -383.844546)
		(width 0.11684)
		(layer "In15.Cu")
		(net "FM_PDB_BUF_EN_R1")
	)
	(segment
		(start 189.741048 -378.751846)
		(end 189.741048 -373.963946)
		(width 0.11684)
		(layer "In15.Cu")
		(net "FM_PDB_BUF_EN_R1")
	)
	(segment
		(start 190.151766 -382.923034)
		(end 190.151766 -379.162564)
		(width 0.11684)
		(layer "In15.Cu")
		(net "FM_PDB_BUF_EN_R1")
	)
	(segment
		(start 189.230254 -383.844546)
		(end 190.151766 -382.923034)
		(width 0.11684)
		(layer "In15.Cu")
		(net "FM_PDB_BUF_EN_R1")
	)
	(segment
		(start 189.741048 -373.963946)
		(end 190.606172 -373.098822)
		(width 0.11684)
		(layer "In15.Cu")
		(net "FM_PDB_BUF_EN_R1")
	)
	(segment
		(start 190.151766 -379.162564)
		(end 189.741048 -378.751846)
		(width 0.11684)
		(layer "In15.Cu")
		(net "FM_PDB_BUF_EN_R1")
	)
	(segment
		(start 143.547084 -12.197334)
		(end 143.55699 -12.187428)
		(width 0.10668)
		(layer "F.Cu")
		(net "SCM_SYS_PWRBTN_R_N")
	)
	(segment
		(start 143.547084 -13.599922)
		(end 143.547084 -12.197334)
		(width 0.10668)
		(layer "F.Cu")
		(net "SCM_SYS_PWRBTN_R_N")
	)
	(via
		(at 143.55699 -12.187428)
		(size 0.508)
		(drill 0.254)
		(layers "F.Cu" "B.Cu")
		(net "SCM_SYS_PWRBTN_R_N")
	)
	(segment
		(start 143.55699 -12.702794)
		(end 143.3068 -12.952984)
		(width 0.10668)
		(layer "B.Cu")
		(net "SCM_SYS_PWRBTN_R_N")
	)
	(segment
		(start 143.3068 -12.952984)
		(end 143.3068 -13.362178)
		(width 0.10668)
		(layer "B.Cu")
		(net "SCM_SYS_PWRBTN_R_N")
	)
	(segment
		(start 143.55699 -12.187428)
		(end 143.55699 -12.702794)
		(width 0.10668)
		(layer "B.Cu")
		(net "SCM_SYS_PWRBTN_R_N")
	)
	(segment
		(start 344.777822 -306.126134)
		(end 346.577666 -304.32629)
		(width 0.10668)
		(layer "F.Cu")
		(net "FM_BIOS_USB_RECOVERY_R")
	)
	(segment
		(start 368.288824 -322.052442)
		(end 368.288824 -320.124582)
		(width 0.10668)
		(layer "F.Cu")
		(net "FM_BIOS_USB_RECOVERY_R")
	)
	(segment
		(start 344.777822 -306.94757)
		(end 344.777822 -306.126134)
		(width 0.10668)
		(layer "F.Cu")
		(net "FM_BIOS_USB_RECOVERY_R")
	)
	(segment
		(start 368.288824 -322.90893)
		(end 368.130836 -323.066918)
		(width 0.10668)
		(layer "F.Cu")
		(net "FM_BIOS_USB_RECOVERY_R")
	)
	(segment
		(start 352.632518 -304.32629)
		(end 360.092498 -296.86631)
		(width 0.10668)
		(layer "F.Cu")
		(net "FM_BIOS_USB_RECOVERY_R")
	)
	(segment
		(start 346.577666 -304.32629)
		(end 352.632518 -304.32629)
		(width 0.10668)
		(layer "F.Cu")
		(net "FM_BIOS_USB_RECOVERY_R")
	)
	(segment
		(start 356.267258 -308.103016)
		(end 345.933268 -308.103016)
		(width 0.10668)
		(layer "F.Cu")
		(net "FM_BIOS_USB_RECOVERY_R")
	)
	(segment
		(start 368.288824 -320.124582)
		(end 356.267258 -308.103016)
		(width 0.10668)
		(layer "F.Cu")
		(net "FM_BIOS_USB_RECOVERY_R")
	)
	(segment
		(start 368.288824 -322.052442)
		(end 368.288824 -322.90893)
		(width 0.10668)
		(layer "F.Cu")
		(net "FM_BIOS_USB_RECOVERY_R")
	)
	(segment
		(start 360.092498 -296.86631)
		(end 363.358938 -296.86631)
		(width 0.10668)
		(layer "F.Cu")
		(net "FM_BIOS_USB_RECOVERY_R")
	)
	(segment
		(start 363.358938 -296.86631)
		(end 364.247938 -295.97731)
		(width 0.10668)
		(layer "F.Cu")
		(net "FM_BIOS_USB_RECOVERY_R")
	)
	(segment
		(start 345.933268 -308.103016)
		(end 344.777822 -306.94757)
		(width 0.10668)
		(layer "F.Cu")
		(net "FM_BIOS_USB_RECOVERY_R")
	)
	(segment
		(start 364.247938 -295.97731)
		(end 364.247938 -295.690036)
		(width 0.10668)
		(layer "F.Cu")
		(net "FM_BIOS_USB_RECOVERY_R")
	)
	(via
		(at 368.288824 -322.052442)
		(size 0.762)
		(drill 0.381)
		(layers "F.Cu" "B.Cu")
		(net "FM_BIOS_USB_RECOVERY_R")
	)
	(segment
		(start 431.5714 -38.547548)
		(end 430.5554 -38.547548)
		(width 0.10668)
		(layer "F.Cu")
		(net "FM_BIOS_USB_RECOVERY")
	)
	(segment
		(start 368.130836 -323.867018)
		(end 384.227578 -339.96376)
		(width 0.10668)
		(layer "F.Cu")
		(net "FM_BIOS_USB_RECOVERY")
	)
	(segment
		(start 190.721996 -123.45289)
		(end 191.111886 -123.84278)
		(width 0.10668)
		(layer "F.Cu")
		(net "FM_BIOS_USB_RECOVERY")
	)
	(segment
		(start 384.227578 -339.96376)
		(end 397.324072 -339.96376)
		(width 0.10668)
		(layer "F.Cu")
		(net "FM_BIOS_USB_RECOVERY")
	)
	(via
		(at 243.17452 -130.869182)
		(size 0.508)
		(drill 0.254)
		(layers "F.Cu" "B.Cu")
		(net "FM_BIOS_USB_RECOVERY")
	)
	(via
		(at 248.622058 -77.066648)
		(size 0.508)
		(drill 0.254)
		(layers "F.Cu" "B.Cu")
		(net "FM_BIOS_USB_RECOVERY")
	)
	(via
		(at 430.5554 -38.547548)
		(size 0.508)
		(drill 0.254)
		(layers "F.Cu" "B.Cu")
		(net "FM_BIOS_USB_RECOVERY")
	)
	(via
		(at 191.111886 -123.84278)
		(size 0.4572)
		(drill 0.254)
		(layers "F.Cu" "B.Cu")
		(net "FM_BIOS_USB_RECOVERY")
	)
	(via
		(at 397.324072 -339.96376)
		(size 0.508)
		(drill 0.254)
		(layers "F.Cu" "B.Cu")
		(net "FM_BIOS_USB_RECOVERY")
	)
	(via
		(at 401.451826 -126.4031)
		(size 0.508)
		(drill 0.254)
		(layers "F.Cu" "B.Cu")
		(net "FM_BIOS_USB_RECOVERY")
	)
	(via
		(at 196.849492 -129.871724)
		(size 0.508)
		(drill 0.254)
		(layers "F.Cu" "B.Cu")
		(net "FM_BIOS_USB_RECOVERY")
	)
	(segment
		(start 430.0474 -39.055548)
		(end 430.5554 -38.547548)
		(width 0.10668)
		(layer "B.Cu")
		(net "FM_BIOS_USB_RECOVERY")
	)
	(segment
		(start 429.387 -39.055548)
		(end 430.0474 -39.055548)
		(width 0.10668)
		(layer "B.Cu")
		(net "FM_BIOS_USB_RECOVERY")
	)
	(segment
		(start 242.35156 -131.692142)
		(end 218.408758 -131.692142)
		(width 0.11684)
		(layer "In2.Cu")
		(net "FM_BIOS_USB_RECOVERY")
	)
	(segment
		(start 404.52294 -334.456786)
		(end 405.152352 -334.456786)
		(width 0.11684)
		(layer "In2.Cu")
		(net "FM_BIOS_USB_RECOVERY")
	)
	(segment
		(start 454.772268 -327.641712)
		(end 461.007206 -321.406774)
		(width 0.11684)
		(layer "In2.Cu")
		(net "FM_BIOS_USB_RECOVERY")
	)
	(segment
		(start 449.373498 -147.946872)
		(end 425.966382 -124.539756)
		(width 0.11684)
		(layer "In2.Cu")
		(net "FM_BIOS_USB_RECOVERY")
	)
	(segment
		(start 458.354684 -183.002174)
		(end 449.373498 -174.020988)
		(width 0.11684)
		(layer "In2.Cu")
		(net "FM_BIOS_USB_RECOVERY")
	)
	(segment
		(start 461.007206 -321.406774)
		(end 461.007206 -189.459108)
		(width 0.11684)
		(layer "In2.Cu")
		(net "FM_BIOS_USB_RECOVERY")
	)
	(segment
		(start 218.408758 -131.692142)
		(end 216.14003 -129.423414)
		(width 0.11684)
		(layer "In2.Cu")
		(net "FM_BIOS_USB_RECOVERY")
	)
	(segment
		(start 197.928738 -130.95097)
		(end 196.849492 -129.871724)
		(width 0.11684)
		(layer "In2.Cu")
		(net "FM_BIOS_USB_RECOVERY")
	)
	(segment
		(start 407.701242 -332.40599)
		(end 414.83153 -327.641712)
		(width 0.11684)
		(layer "In2.Cu")
		(net "FM_BIOS_USB_RECOVERY")
	)
	(segment
		(start 216.14003 -129.423414)
		(end 207.69199 -129.423414)
		(width 0.11684)
		(layer "In2.Cu")
		(net "FM_BIOS_USB_RECOVERY")
	)
	(segment
		(start 405.152352 -334.456786)
		(end 406.851104 -332.758034)
		(width 0.11684)
		(layer "In2.Cu")
		(net "FM_BIOS_USB_RECOVERY")
	)
	(segment
		(start 461.007206 -189.459108)
		(end 458.354684 -186.806586)
		(width 0.11684)
		(layer "In2.Cu")
		(net "FM_BIOS_USB_RECOVERY")
	)
	(segment
		(start 207.69199 -129.423414)
		(end 206.164434 -130.95097)
		(width 0.11684)
		(layer "In2.Cu")
		(net "FM_BIOS_USB_RECOVERY")
	)
	(segment
		(start 403.31517 -124.539756)
		(end 401.451826 -126.4031)
		(width 0.11684)
		(layer "In2.Cu")
		(net "FM_BIOS_USB_RECOVERY")
	)
	(segment
		(start 458.354684 -186.806586)
		(end 458.354684 -183.002174)
		(width 0.11684)
		(layer "In2.Cu")
		(net "FM_BIOS_USB_RECOVERY")
	)
	(segment
		(start 397.324072 -339.96376)
		(end 399.015966 -339.96376)
		(width 0.11684)
		(layer "In2.Cu")
		(net "FM_BIOS_USB_RECOVERY")
	)
	(segment
		(start 243.17452 -130.869182)
		(end 242.35156 -131.692142)
		(width 0.11684)
		(layer "In2.Cu")
		(net "FM_BIOS_USB_RECOVERY")
	)
	(segment
		(start 425.966382 -124.539756)
		(end 403.31517 -124.539756)
		(width 0.11684)
		(layer "In2.Cu")
		(net "FM_BIOS_USB_RECOVERY")
	)
	(segment
		(start 399.015966 -339.96376)
		(end 404.52294 -334.456786)
		(width 0.11684)
		(layer "In2.Cu")
		(net "FM_BIOS_USB_RECOVERY")
	)
	(segment
		(start 406.851104 -332.758034)
		(end 407.701242 -332.40599)
		(width 0.11684)
		(layer "In2.Cu")
		(net "FM_BIOS_USB_RECOVERY")
	)
	(segment
		(start 449.373498 -174.020988)
		(end 449.373498 -147.946872)
		(width 0.11684)
		(layer "In2.Cu")
		(net "FM_BIOS_USB_RECOVERY")
	)
	(segment
		(start 414.83153 -327.641712)
		(end 454.772268 -327.641712)
		(width 0.11684)
		(layer "In2.Cu")
		(net "FM_BIOS_USB_RECOVERY")
	)
	(segment
		(start 206.164434 -130.95097)
		(end 197.928738 -130.95097)
		(width 0.11684)
		(layer "In2.Cu")
		(net "FM_BIOS_USB_RECOVERY")
	)
	(segment
		(start 243.17452 -130.869182)
		(end 244.18036 -129.863342)
		(width 0.11684)
		(layer "In4.Cu")
		(net "FM_BIOS_USB_RECOVERY")
	)
	(segment
		(start 244.18036 -129.863342)
		(end 244.18036 -81.508346)
		(width 0.11684)
		(layer "In4.Cu")
		(net "FM_BIOS_USB_RECOVERY")
	)
	(segment
		(start 244.18036 -81.508346)
		(end 248.622058 -77.066648)
		(width 0.11684)
		(layer "In4.Cu")
		(net "FM_BIOS_USB_RECOVERY")
	)
	(segment
		(start 191.111886 -123.84278)
		(end 191.111886 -124.01804)
		(width 0.11684)
		(layer "In6.Cu")
		(net "FM_BIOS_USB_RECOVERY")
	)
	(segment
		(start 193.483484 -127.146558)
		(end 195.620894 -129.283968)
		(width 0.11684)
		(layer "In6.Cu")
		(net "FM_BIOS_USB_RECOVERY")
	)
	(segment
		(start 191.111886 -124.01804)
		(end 193.483484 -126.389638)
		(width 0.11684)
		(layer "In6.Cu")
		(net "FM_BIOS_USB_RECOVERY")
	)
	(segment
		(start 196.58711 -129.283968)
		(end 196.849492 -129.54635)
		(width 0.11684)
		(layer "In6.Cu")
		(net "FM_BIOS_USB_RECOVERY")
	)
	(segment
		(start 193.483484 -126.389638)
		(end 193.483484 -127.146558)
		(width 0.11684)
		(layer "In6.Cu")
		(net "FM_BIOS_USB_RECOVERY")
	)
	(segment
		(start 196.849492 -129.54635)
		(end 196.849492 -129.871724)
		(width 0.11684)
		(layer "In6.Cu")
		(net "FM_BIOS_USB_RECOVERY")
	)
	(segment
		(start 195.620894 -129.283968)
		(end 196.58711 -129.283968)
		(width 0.11684)
		(layer "In6.Cu")
		(net "FM_BIOS_USB_RECOVERY")
	)
	(segment
		(start 430.5554 -38.547548)
		(end 427.254924 -38.547548)
		(width 0.11684)
		(layer "In11.Cu")
		(net "FM_BIOS_USB_RECOVERY")
	)
	(segment
		(start 425.38904 -43.025822)
		(end 413.07385 -55.341012)
		(width 0.11684)
		(layer "In11.Cu")
		(net "FM_BIOS_USB_RECOVERY")
	)
	(segment
		(start 413.07385 -55.341012)
		(end 406.461214 -55.341012)
		(width 0.11684)
		(layer "In11.Cu")
		(net "FM_BIOS_USB_RECOVERY")
	)
	(segment
		(start 401.451826 -60.3504)
		(end 401.451826 -126.4031)
		(width 0.11684)
		(layer "In11.Cu")
		(net "FM_BIOS_USB_RECOVERY")
	)
	(segment
		(start 427.254924 -38.547548)
		(end 425.38904 -40.413432)
		(width 0.11684)
		(layer "In11.Cu")
		(net "FM_BIOS_USB_RECOVERY")
	)
	(segment
		(start 406.461214 -55.341012)
		(end 401.451826 -60.3504)
		(width 0.11684)
		(layer "In11.Cu")
		(net "FM_BIOS_USB_RECOVERY")
	)
	(segment
		(start 425.38904 -40.413432)
		(end 425.38904 -43.025822)
		(width 0.11684)
		(layer "In11.Cu")
		(net "FM_BIOS_USB_RECOVERY")
	)
	(segment
		(start 305.228244 -30.334966)
		(end 320.209418 -30.334966)
		(width 0.11684)
		(layer "In15.Cu")
		(net "FM_BIOS_USB_RECOVERY")
	)
	(segment
		(start 320.209418 -30.334966)
		(end 328.005948 -22.538436)
		(width 0.11684)
		(layer "In15.Cu")
		(net "FM_BIOS_USB_RECOVERY")
	)
	(segment
		(start 276.581616 -73.203054)
		(end 284.965648 -64.819022)
		(width 0.11684)
		(layer "In15.Cu")
		(net "FM_BIOS_USB_RECOVERY")
	)
	(segment
		(start 248.622058 -77.066648)
		(end 249.102118 -76.586588)
		(width 0.11684)
		(layer "In15.Cu")
		(net "FM_BIOS_USB_RECOVERY")
	)
	(segment
		(start 255.03632 -78.03007)
		(end 258.9276 -78.03007)
		(width 0.11684)
		(layer "In15.Cu")
		(net "FM_BIOS_USB_RECOVERY")
	)
	(segment
		(start 258.9276 -78.03007)
		(end 263.754616 -73.203054)
		(width 0.11684)
		(layer "In15.Cu")
		(net "FM_BIOS_USB_RECOVERY")
	)
	(segment
		(start 384.201924 -28.790138)
		(end 390.345422 -22.64664)
		(width 0.11684)
		(layer "In15.Cu")
		(net "FM_BIOS_USB_RECOVERY")
	)
	(segment
		(start 263.754616 -73.203054)
		(end 276.581616 -73.203054)
		(width 0.11684)
		(layer "In15.Cu")
		(net "FM_BIOS_USB_RECOVERY")
	)
	(segment
		(start 432.041554 -26.6192)
		(end 432.041554 -37.061394)
		(width 0.11684)
		(layer "In15.Cu")
		(net "FM_BIOS_USB_RECOVERY")
	)
	(segment
		(start 284.965648 -50.597562)
		(end 305.228244 -30.334966)
		(width 0.11684)
		(layer "In15.Cu")
		(net "FM_BIOS_USB_RECOVERY")
	)
	(segment
		(start 253.592838 -76.586588)
		(end 255.03632 -78.03007)
		(width 0.11684)
		(layer "In15.Cu")
		(net "FM_BIOS_USB_RECOVERY")
	)
	(segment
		(start 390.345422 -22.64664)
		(end 428.068994 -22.64664)
		(width 0.11684)
		(layer "In15.Cu")
		(net "FM_BIOS_USB_RECOVERY")
	)
	(segment
		(start 331.797152 -22.538436)
		(end 333.25562 -23.996904)
		(width 0.11684)
		(layer "In15.Cu")
		(net "FM_BIOS_USB_RECOVERY")
	)
	(segment
		(start 249.102118 -76.586588)
		(end 253.592838 -76.586588)
		(width 0.11684)
		(layer "In15.Cu")
		(net "FM_BIOS_USB_RECOVERY")
	)
	(segment
		(start 328.005948 -22.538436)
		(end 331.797152 -22.538436)
		(width 0.11684)
		(layer "In15.Cu")
		(net "FM_BIOS_USB_RECOVERY")
	)
	(segment
		(start 284.965648 -64.819022)
		(end 284.965648 -50.597562)
		(width 0.11684)
		(layer "In15.Cu")
		(net "FM_BIOS_USB_RECOVERY")
	)
	(segment
		(start 432.041554 -37.061394)
		(end 430.5554 -38.547548)
		(width 0.11684)
		(layer "In15.Cu")
		(net "FM_BIOS_USB_RECOVERY")
	)
	(segment
		(start 377.622308 -28.790138)
		(end 384.201924 -28.790138)
		(width 0.11684)
		(layer "In15.Cu")
		(net "FM_BIOS_USB_RECOVERY")
	)
	(segment
		(start 372.829074 -23.996904)
		(end 377.622308 -28.790138)
		(width 0.11684)
		(layer "In15.Cu")
		(net "FM_BIOS_USB_RECOVERY")
	)
	(segment
		(start 428.068994 -22.64664)
		(end 432.041554 -26.6192)
		(width 0.11684)
		(layer "In15.Cu")
		(net "FM_BIOS_USB_RECOVERY")
	)
	(segment
		(start 333.25562 -23.996904)
		(end 372.829074 -23.996904)
		(width 0.11684)
		(layer "In15.Cu")
		(net "FM_BIOS_USB_RECOVERY")
	)
	(segment
		(start 375.545096 -306.70373)
		(end 375.545096 -313.39663)
		(width 0.10668)
		(layer "F.Cu")
		(net "FM_BIOS_POST_CMPLT_R_N")
	)
	(segment
		(start 382.391158 -320.242692)
		(end 382.391158 -321.524376)
		(width 0.10668)
		(layer "F.Cu")
		(net "FM_BIOS_POST_CMPLT_R_N")
	)
	(segment
		(start 375.545096 -313.39663)
		(end 382.391158 -320.242692)
		(width 0.10668)
		(layer "F.Cu")
		(net "FM_BIOS_POST_CMPLT_R_N")
	)
	(segment
		(start 368.0079 -299.166534)
		(end 375.545096 -306.70373)
		(width 0.10668)
		(layer "F.Cu")
		(net "FM_BIOS_POST_CMPLT_R_N")
	)
	(segment
		(start 368.0079 -295.690036)
		(end 368.0079 -299.166534)
		(width 0.10668)
		(layer "F.Cu")
		(net "FM_BIOS_POST_CMPLT_R_N")
	)
	(segment
		(start 382.391158 -321.524376)
		(end 382.391158 -322.786502)
		(width 0.10668)
		(layer "F.Cu")
		(net "FM_BIOS_POST_CMPLT_R_N")
	)
	(via
		(at 382.391158 -321.524376)
		(size 0.762)
		(drill 0.381)
		(layers "F.Cu" "B.Cu")
		(net "FM_BIOS_POST_CMPLT_R_N")
	)
	(segment
		(start 391.97788 -333.173324)
		(end 382.391158 -323.586602)
		(width 0.10668)
		(layer "F.Cu")
		(net "FM_BIOS_POST_CMPLT_N")
	)
	(segment
		(start 398.387824 -333.129382)
		(end 398.343882 -333.173324)
		(width 0.10668)
		(layer "F.Cu")
		(net "FM_BIOS_POST_CMPLT_N")
	)
	(segment
		(start 398.343882 -333.173324)
		(end 391.97788 -333.173324)
		(width 0.10668)
		(layer "F.Cu")
		(net "FM_BIOS_POST_CMPLT_N")
	)
	(via
		(at 398.387824 -333.129382)
		(size 0.508)
		(drill 0.254)
		(layers "F.Cu" "B.Cu")
		(net "FM_BIOS_POST_CMPLT_N")
	)
	(via
		(at 397.992854 -342.322404)
		(size 0.508)
		(drill 0.254)
		(layers "F.Cu" "B.Cu")
		(net "FM_BIOS_POST_CMPLT_N")
	)
	(segment
		(start 404.400258 -344.57005)
		(end 404.670006 -344.300302)
		(width 0.10668)
		(layer "B.Cu")
		(net "FM_BIOS_POST_CMPLT_N")
	)
	(segment
		(start 397.637508 -341.568786)
		(end 398.560036 -341.568786)
		(width 0.10668)
		(layer "B.Cu")
		(net "FM_BIOS_POST_CMPLT_N")
	)
	(segment
		(start 398.389856 -346.333318)
		(end 398.389856 -346.998036)
		(width 0.10668)
		(layer "B.Cu")
		(net "FM_BIOS_POST_CMPLT_N")
	)
	(segment
		(start 404.670006 -344.300302)
		(end 405.700738 -344.300302)
		(width 0.10668)
		(layer "B.Cu")
		(net "FM_BIOS_POST_CMPLT_N")
	)
	(segment
		(start 398.389856 -346.998036)
		(end 399.18259 -347.79077)
		(width 0.10668)
		(layer "B.Cu")
		(net "FM_BIOS_POST_CMPLT_N")
	)
	(segment
		(start 398.560036 -341.568786)
		(end 398.563592 -341.572342)
		(width 0.10668)
		(layer "B.Cu")
		(net "FM_BIOS_POST_CMPLT_N")
	)
	(segment
		(start 397.637508 -341.967058)
		(end 397.992854 -342.322404)
		(width 0.10668)
		(layer "B.Cu")
		(net "FM_BIOS_POST_CMPLT_N")
	)
	(segment
		(start 404.400258 -345.49969)
		(end 404.400258 -344.57005)
		(width 0.10668)
		(layer "B.Cu")
		(net "FM_BIOS_POST_CMPLT_N")
	)
	(segment
		(start 399.18259 -347.79077)
		(end 402.109178 -347.79077)
		(width 0.10668)
		(layer "B.Cu")
		(net "FM_BIOS_POST_CMPLT_N")
	)
	(segment
		(start 397.992854 -342.322404)
		(end 397.992854 -345.936316)
		(width 0.10668)
		(layer "B.Cu")
		(net "FM_BIOS_POST_CMPLT_N")
	)
	(segment
		(start 397.992854 -345.936316)
		(end 398.389856 -346.333318)
		(width 0.10668)
		(layer "B.Cu")
		(net "FM_BIOS_POST_CMPLT_N")
	)
	(segment
		(start 397.637508 -341.568786)
		(end 397.637508 -341.967058)
		(width 0.10668)
		(layer "B.Cu")
		(net "FM_BIOS_POST_CMPLT_N")
	)
	(segment
		(start 402.109178 -347.79077)
		(end 404.400258 -345.49969)
		(width 0.10668)
		(layer "B.Cu")
		(net "FM_BIOS_POST_CMPLT_N")
	)
	(segment
		(start 397.770096 -338.286852)
		(end 398.576546 -339.093302)
		(width 0.11684)
		(layer "In4.Cu")
		(net "FM_BIOS_POST_CMPLT_N")
	)
	(segment
		(start 398.387824 -333.129382)
		(end 397.770096 -333.74711)
		(width 0.11684)
		(layer "In4.Cu")
		(net "FM_BIOS_POST_CMPLT_N")
	)
	(segment
		(start 397.770096 -333.74711)
		(end 397.770096 -338.286852)
		(width 0.11684)
		(layer "In4.Cu")
		(net "FM_BIOS_POST_CMPLT_N")
	)
	(segment
		(start 398.576546 -341.315548)
		(end 397.992854 -341.89924)
		(width 0.11684)
		(layer "In4.Cu")
		(net "FM_BIOS_POST_CMPLT_N")
	)
	(segment
		(start 397.992854 -341.89924)
		(end 397.992854 -342.322404)
		(width 0.11684)
		(layer "In4.Cu")
		(net "FM_BIOS_POST_CMPLT_N")
	)
	(segment
		(start 398.576546 -339.093302)
		(end 398.576546 -341.315548)
		(width 0.11684)
		(layer "In4.Cu")
		(net "FM_BIOS_POST_CMPLT_N")
	)
	(segment
		(start 191.135 -137.232898)
		(end 191.135 -136.688322)
		(width 0.10668)
		(layer "F.Cu")
		(net "FM_BIOS_POST_CMPLT_BUF_R_N")
	)
	(segment
		(start 191.135 -136.688322)
		(end 191.25311 -136.570212)
		(width 0.10668)
		(layer "F.Cu")
		(net "FM_BIOS_POST_CMPLT_BUF_R_N")
	)
	(segment
		(start 189.92215 -122.65279)
		(end 190.31204 -123.04268)
		(width 0.10668)
		(layer "F.Cu")
		(net "FM_BIOS_POST_CMPLT_BUF_R_N")
	)
	(via
		(at 191.25311 -136.570212)
		(size 0.508)
		(drill 0.254)
		(layers "F.Cu" "B.Cu")
		(net "FM_BIOS_POST_CMPLT_BUF_R_N")
	)
	(via
		(at 190.31204 -123.04268)
		(size 0.4572)
		(drill 0.254)
		(layers "F.Cu" "B.Cu")
		(net "FM_BIOS_POST_CMPLT_BUF_R_N")
	)
	(segment
		(start 190.708788 -126.051056)
		(end 190.708788 -124.882656)
		(width 0.11684)
		(layer "In11.Cu")
		(net "FM_BIOS_POST_CMPLT_BUF_R_N")
	)
	(segment
		(start 191.75984 -130.654806)
		(end 191.68618 -130.581146)
		(width 0.11684)
		(layer "In11.Cu")
		(net "FM_BIOS_POST_CMPLT_BUF_R_N")
	)
	(segment
		(start 190.31204 -124.485908)
		(end 190.31204 -123.04268)
		(width 0.11684)
		(layer "In11.Cu")
		(net "FM_BIOS_POST_CMPLT_BUF_R_N")
	)
	(segment
		(start 192.126108 -132.138674)
		(end 191.75984 -131.772406)
		(width 0.11684)
		(layer "In11.Cu")
		(net "FM_BIOS_POST_CMPLT_BUF_R_N")
	)
	(segment
		(start 191.75984 -131.772406)
		(end 191.75984 -130.654806)
		(width 0.11684)
		(layer "In11.Cu")
		(net "FM_BIOS_POST_CMPLT_BUF_R_N")
	)
	(segment
		(start 191.75984 -127.102108)
		(end 190.708788 -126.051056)
		(width 0.11684)
		(layer "In11.Cu")
		(net "FM_BIOS_POST_CMPLT_BUF_R_N")
	)
	(segment
		(start 190.67018 -134.163816)
		(end 192.126108 -132.707888)
		(width 0.11684)
		(layer "In11.Cu")
		(net "FM_BIOS_POST_CMPLT_BUF_R_N")
	)
	(segment
		(start 191.68618 -130.581146)
		(end 191.68618 -130.195574)
		(width 0.11684)
		(layer "In11.Cu")
		(net "FM_BIOS_POST_CMPLT_BUF_R_N")
	)
	(segment
		(start 191.215264 -136.570212)
		(end 190.67018 -136.025128)
		(width 0.11684)
		(layer "In11.Cu")
		(net "FM_BIOS_POST_CMPLT_BUF_R_N")
	)
	(segment
		(start 190.67018 -136.025128)
		(end 190.67018 -134.163816)
		(width 0.11684)
		(layer "In11.Cu")
		(net "FM_BIOS_POST_CMPLT_BUF_R_N")
	)
	(segment
		(start 192.126108 -132.707888)
		(end 192.126108 -132.138674)
		(width 0.11684)
		(layer "In11.Cu")
		(net "FM_BIOS_POST_CMPLT_BUF_R_N")
	)
	(segment
		(start 191.25311 -136.570212)
		(end 191.215264 -136.570212)
		(width 0.11684)
		(layer "In11.Cu")
		(net "FM_BIOS_POST_CMPLT_BUF_R_N")
	)
	(segment
		(start 191.75984 -130.121914)
		(end 191.75984 -127.102108)
		(width 0.11684)
		(layer "In11.Cu")
		(net "FM_BIOS_POST_CMPLT_BUF_R_N")
	)
	(segment
		(start 190.708788 -124.882656)
		(end 190.31204 -124.485908)
		(width 0.11684)
		(layer "In11.Cu")
		(net "FM_BIOS_POST_CMPLT_BUF_R_N")
	)
	(segment
		(start 191.68618 -130.195574)
		(end 191.75984 -130.121914)
		(width 0.11684)
		(layer "In11.Cu")
		(net "FM_BIOS_POST_CMPLT_BUF_R_N")
	)
	(segment
		(start 191.135 -138.032998)
		(end 191.135 -138.648948)
		(width 0.10668)
		(layer "F.Cu")
		(net "FM_BIOS_POST_CMPLT_BUF_N")
	)
	(via
		(at 261.4168 -89.309956)
		(size 0.508)
		(drill 0.254)
		(layers "F.Cu" "B.Cu")
		(net "FM_BIOS_POST_CMPLT_BUF_N")
	)
	(via
		(at 260.234684 -129.858516)
		(size 0.508)
		(drill 0.254)
		(layers "F.Cu" "B.Cu")
		(net "FM_BIOS_POST_CMPLT_BUF_N")
	)
	(via
		(at 399.518124 -347.156786)
		(size 0.508)
		(drill 0.254)
		(layers "F.Cu" "B.Cu")
		(net "FM_BIOS_POST_CMPLT_BUF_N")
	)
	(via
		(at 191.135 -138.648948)
		(size 0.508)
		(drill 0.254)
		(layers "F.Cu" "B.Cu")
		(net "FM_BIOS_POST_CMPLT_BUF_N")
	)
	(via
		(at 392.992864 -376.126248)
		(size 0.508)
		(drill 0.254)
		(layers "F.Cu" "B.Cu")
		(net "FM_BIOS_POST_CMPLT_BUF_N")
	)
	(segment
		(start 399.518124 -345.250262)
		(end 399.518124 -347.156786)
		(width 0.10668)
		(layer "B.Cu")
		(net "FM_BIOS_POST_CMPLT_BUF_N")
	)
	(segment
		(start 398.502124 -345.250262)
		(end 399.518124 -345.250262)
		(width 0.10668)
		(layer "B.Cu")
		(net "FM_BIOS_POST_CMPLT_BUF_N")
	)
	(segment
		(start 423.353992 -374.84939)
		(end 427.79696 -370.406422)
		(width 0.11684)
		(layer "In2.Cu")
		(net "FM_BIOS_POST_CMPLT_BUF_N")
	)
	(segment
		(start 288.043112 -108.892848)
		(end 280.52268 -101.372416)
		(width 0.11684)
		(layer "In2.Cu")
		(net "FM_BIOS_POST_CMPLT_BUF_N")
	)
	(segment
		(start 257.491738 -136.891014)
		(end 260.234684 -134.148068)
		(width 0.11684)
		(layer "In2.Cu")
		(net "FM_BIOS_POST_CMPLT_BUF_N")
	)
	(segment
		(start 398.089882 -125.471174)
		(end 397.507968 -126.053088)
		(width 0.11684)
		(layer "In2.Cu")
		(net "FM_BIOS_POST_CMPLT_BUF_N")
	)
	(segment
		(start 372.316248 -124.423424)
		(end 319.952624 -124.423424)
		(width 0.11684)
		(layer "In2.Cu")
		(net "FM_BIOS_POST_CMPLT_BUF_N")
	)
	(segment
		(start 279.849326 -99.412806)
		(end 278.56815 -99.412806)
		(width 0.11684)
		(layer "In2.Cu")
		(net "FM_BIOS_POST_CMPLT_BUF_N")
	)
	(segment
		(start 203.60259 -140.07846)
		(end 204.500226 -139.180824)
		(width 0.11684)
		(layer "In2.Cu")
		(net "FM_BIOS_POST_CMPLT_BUF_N")
	)
	(segment
		(start 427.79696 -370.406422)
		(end 429.508158 -370.406422)
		(width 0.11684)
		(layer "In2.Cu")
		(net "FM_BIOS_POST_CMPLT_BUF_N")
	)
	(segment
		(start 204.500226 -139.180824)
		(end 215.255094 -139.180824)
		(width 0.11684)
		(layer "In2.Cu")
		(net "FM_BIOS_POST_CMPLT_BUF_N")
	)
	(segment
		(start 397.507968 -126.053088)
		(end 373.945912 -126.053088)
		(width 0.11684)
		(layer "In2.Cu")
		(net "FM_BIOS_POST_CMPLT_BUF_N")
	)
	(segment
		(start 445.40551 -365.586264)
		(end 448.990466 -362.001308)
		(width 0.11684)
		(layer "In2.Cu")
		(net "FM_BIOS_POST_CMPLT_BUF_N")
	)
	(segment
		(start 400.027394 -125.471174)
		(end 398.089882 -125.471174)
		(width 0.11684)
		(layer "In2.Cu")
		(net "FM_BIOS_POST_CMPLT_BUF_N")
	)
	(segment
		(start 394.269722 -374.84939)
		(end 423.353992 -374.84939)
		(width 0.11684)
		(layer "In2.Cu")
		(net "FM_BIOS_POST_CMPLT_BUF_N")
	)
	(segment
		(start 192.20307 -140.07846)
		(end 203.60259 -140.07846)
		(width 0.11684)
		(layer "In2.Cu")
		(net "FM_BIOS_POST_CMPLT_BUF_N")
	)
	(segment
		(start 450.175376 -164.749226)
		(end 450.175376 -147.843494)
		(width 0.11684)
		(layer "In2.Cu")
		(net "FM_BIOS_POST_CMPLT_BUF_N")
	)
	(segment
		(start 280.52268 -100.08616)
		(end 279.849326 -99.412806)
		(width 0.11684)
		(layer "In2.Cu")
		(net "FM_BIOS_POST_CMPLT_BUF_N")
	)
	(segment
		(start 305.590702 -108.892848)
		(end 288.043112 -108.892848)
		(width 0.11684)
		(layer "In2.Cu")
		(net "FM_BIOS_POST_CMPLT_BUF_N")
	)
	(segment
		(start 432.199034 -367.715546)
		(end 435.453028 -367.715546)
		(width 0.11684)
		(layer "In2.Cu")
		(net "FM_BIOS_POST_CMPLT_BUF_N")
	)
	(segment
		(start 260.234684 -134.148068)
		(end 260.234684 -129.858516)
		(width 0.11684)
		(layer "In2.Cu")
		(net "FM_BIOS_POST_CMPLT_BUF_N")
	)
	(segment
		(start 215.255094 -139.180824)
		(end 217.544904 -136.891014)
		(width 0.11684)
		(layer "In2.Cu")
		(net "FM_BIOS_POST_CMPLT_BUF_N")
	)
	(segment
		(start 269.121128 -94.569534)
		(end 263.357106 -88.805512)
		(width 0.11684)
		(layer "In2.Cu")
		(net "FM_BIOS_POST_CMPLT_BUF_N")
	)
	(segment
		(start 263.357106 -88.805512)
		(end 261.921244 -88.805512)
		(width 0.11684)
		(layer "In2.Cu")
		(net "FM_BIOS_POST_CMPLT_BUF_N")
	)
	(segment
		(start 401.598892 -123.899676)
		(end 400.027394 -125.471174)
		(width 0.11684)
		(layer "In2.Cu")
		(net "FM_BIOS_POST_CMPLT_BUF_N")
	)
	(segment
		(start 435.453028 -367.715546)
		(end 437.58231 -365.586264)
		(width 0.11684)
		(layer "In2.Cu")
		(net "FM_BIOS_POST_CMPLT_BUF_N")
	)
	(segment
		(start 319.952624 -124.423424)
		(end 313.41441 -117.88521)
		(width 0.11684)
		(layer "In2.Cu")
		(net "FM_BIOS_POST_CMPLT_BUF_N")
	)
	(segment
		(start 448.990466 -335.05648)
		(end 461.693768 -322.353178)
		(width 0.11684)
		(layer "In2.Cu")
		(net "FM_BIOS_POST_CMPLT_BUF_N")
	)
	(segment
		(start 278.56815 -99.412806)
		(end 273.724878 -94.569534)
		(width 0.11684)
		(layer "In2.Cu")
		(net "FM_BIOS_POST_CMPLT_BUF_N")
	)
	(segment
		(start 448.990466 -362.001308)
		(end 448.990466 -335.05648)
		(width 0.11684)
		(layer "In2.Cu")
		(net "FM_BIOS_POST_CMPLT_BUF_N")
	)
	(segment
		(start 461.693768 -176.267618)
		(end 450.175376 -164.749226)
		(width 0.11684)
		(layer "In2.Cu")
		(net "FM_BIOS_POST_CMPLT_BUF_N")
	)
	(segment
		(start 191.135 -138.648948)
		(end 191.135 -139.01039)
		(width 0.11684)
		(layer "In2.Cu")
		(net "FM_BIOS_POST_CMPLT_BUF_N")
	)
	(segment
		(start 437.58231 -365.586264)
		(end 445.40551 -365.586264)
		(width 0.11684)
		(layer "In2.Cu")
		(net "FM_BIOS_POST_CMPLT_BUF_N")
	)
	(segment
		(start 280.52268 -101.372416)
		(end 280.52268 -100.08616)
		(width 0.11684)
		(layer "In2.Cu")
		(net "FM_BIOS_POST_CMPLT_BUF_N")
	)
	(segment
		(start 313.41441 -116.716556)
		(end 305.590702 -108.892848)
		(width 0.11684)
		(layer "In2.Cu")
		(net "FM_BIOS_POST_CMPLT_BUF_N")
	)
	(segment
		(start 429.508158 -370.406422)
		(end 432.199034 -367.715546)
		(width 0.11684)
		(layer "In2.Cu")
		(net "FM_BIOS_POST_CMPLT_BUF_N")
	)
	(segment
		(start 461.693768 -322.353178)
		(end 461.693768 -176.267618)
		(width 0.11684)
		(layer "In2.Cu")
		(net "FM_BIOS_POST_CMPLT_BUF_N")
	)
	(segment
		(start 191.135 -139.01039)
		(end 192.20307 -140.07846)
		(width 0.11684)
		(layer "In2.Cu")
		(net "FM_BIOS_POST_CMPLT_BUF_N")
	)
	(segment
		(start 450.175376 -147.843494)
		(end 426.231558 -123.899676)
		(width 0.11684)
		(layer "In2.Cu")
		(net "FM_BIOS_POST_CMPLT_BUF_N")
	)
	(segment
		(start 392.992864 -376.126248)
		(end 394.269722 -374.84939)
		(width 0.11684)
		(layer "In2.Cu")
		(net "FM_BIOS_POST_CMPLT_BUF_N")
	)
	(segment
		(start 426.231558 -123.899676)
		(end 401.598892 -123.899676)
		(width 0.11684)
		(layer "In2.Cu")
		(net "FM_BIOS_POST_CMPLT_BUF_N")
	)
	(segment
		(start 261.921244 -88.805512)
		(end 261.4168 -89.309956)
		(width 0.11684)
		(layer "In2.Cu")
		(net "FM_BIOS_POST_CMPLT_BUF_N")
	)
	(segment
		(start 273.724878 -94.569534)
		(end 269.121128 -94.569534)
		(width 0.11684)
		(layer "In2.Cu")
		(net "FM_BIOS_POST_CMPLT_BUF_N")
	)
	(segment
		(start 313.41441 -117.88521)
		(end 313.41441 -116.716556)
		(width 0.11684)
		(layer "In2.Cu")
		(net "FM_BIOS_POST_CMPLT_BUF_N")
	)
	(segment
		(start 373.945912 -126.053088)
		(end 372.316248 -124.423424)
		(width 0.11684)
		(layer "In2.Cu")
		(net "FM_BIOS_POST_CMPLT_BUF_N")
	)
	(segment
		(start 217.544904 -136.891014)
		(end 257.491738 -136.891014)
		(width 0.11684)
		(layer "In2.Cu")
		(net "FM_BIOS_POST_CMPLT_BUF_N")
	)
	(segment
		(start 261.331964 -113.156492)
		(end 261.331964 -102.610666)
		(width 0.11684)
		(layer "In4.Cu")
		(net "FM_BIOS_POST_CMPLT_BUF_N")
	)
	(segment
		(start 260.234684 -129.858516)
		(end 260.778498 -129.858516)
		(width 0.11684)
		(layer "In4.Cu")
		(net "FM_BIOS_POST_CMPLT_BUF_N")
	)
	(segment
		(start 262.06958 -128.567434)
		(end 262.06958 -113.894108)
		(width 0.11684)
		(layer "In4.Cu")
		(net "FM_BIOS_POST_CMPLT_BUF_N")
	)
	(segment
		(start 262.268716 -101.673914)
		(end 262.268716 -90.311986)
		(width 0.11684)
		(layer "In4.Cu")
		(net "FM_BIOS_POST_CMPLT_BUF_N")
	)
	(segment
		(start 261.4168 -89.46007)
		(end 261.4168 -89.309956)
		(width 0.11684)
		(layer "In4.Cu")
		(net "FM_BIOS_POST_CMPLT_BUF_N")
	)
	(segment
		(start 260.778498 -129.858516)
		(end 262.06958 -128.567434)
		(width 0.11684)
		(layer "In4.Cu")
		(net "FM_BIOS_POST_CMPLT_BUF_N")
	)
	(segment
		(start 261.331964 -102.610666)
		(end 262.268716 -101.673914)
		(width 0.11684)
		(layer "In4.Cu")
		(net "FM_BIOS_POST_CMPLT_BUF_N")
	)
	(segment
		(start 262.06958 -113.894108)
		(end 261.331964 -113.156492)
		(width 0.11684)
		(layer "In4.Cu")
		(net "FM_BIOS_POST_CMPLT_BUF_N")
	)
	(segment
		(start 262.268716 -90.311986)
		(end 261.4168 -89.46007)
		(width 0.11684)
		(layer "In4.Cu")
		(net "FM_BIOS_POST_CMPLT_BUF_N")
	)
	(segment
		(start 392.992864 -376.126248)
		(end 398.66443 -376.126248)
		(width 0.11684)
		(layer "In15.Cu")
		(net "FM_BIOS_POST_CMPLT_BUF_N")
	)
	(segment
		(start 403.518878 -371.2718)
		(end 403.518878 -353.80168)
		(width 0.11684)
		(layer "In15.Cu")
		(net "FM_BIOS_POST_CMPLT_BUF_N")
	)
	(segment
		(start 402.309076 -351.484692)
		(end 401.884642 -351.060258)
		(width 0.11684)
		(layer "In15.Cu")
		(net "FM_BIOS_POST_CMPLT_BUF_N")
	)
	(segment
		(start 403.518878 -353.80168)
		(end 402.309076 -352.591878)
		(width 0.11684)
		(layer "In15.Cu")
		(net "FM_BIOS_POST_CMPLT_BUF_N")
	)
	(segment
		(start 398.66443 -376.126248)
		(end 403.518878 -371.2718)
		(width 0.11684)
		(layer "In15.Cu")
		(net "FM_BIOS_POST_CMPLT_BUF_N")
	)
	(segment
		(start 401.884642 -349.523304)
		(end 399.518124 -347.156786)
		(width 0.11684)
		(layer "In15.Cu")
		(net "FM_BIOS_POST_CMPLT_BUF_N")
	)
	(segment
		(start 401.884642 -351.060258)
		(end 401.884642 -349.523304)
		(width 0.11684)
		(layer "In15.Cu")
		(net "FM_BIOS_POST_CMPLT_BUF_N")
	)
	(segment
		(start 402.309076 -352.591878)
		(end 402.309076 -351.484692)
		(width 0.11684)
		(layer "In15.Cu")
		(net "FM_BIOS_POST_CMPLT_BUF_N")
	)
	(segment
		(start 49.778666 -31.892748)
		(end 50.20183 -32.315912)
		(width 0.10668)
		(layer "F.Cu")
		(net "FB_BMC_ISOLATE_R2")
	)
	(segment
		(start 49.778666 -30.607508)
		(end 49.778666 -31.892748)
		(width 0.10668)
		(layer "F.Cu")
		(net "FB_BMC_ISOLATE_R2")
	)
	(segment
		(start 50.20183 -32.315912)
		(end 50.20183 -33.175448)
		(width 0.10668)
		(layer "F.Cu")
		(net "FB_BMC_ISOLATE_R2")
	)
	(via
		(at 49.778666 -31.892748)
		(size 0.762)
		(drill 0.381)
		(layers "F.Cu" "B.Cu")
		(net "FB_BMC_ISOLATE_R2")
	)
	(segment
		(start 461.841596 -97.864422)
		(end 462.18221 -97.523808)
		(width 0.10668)
		(layer "F.Cu")
		(net "FB_BMC_ISOLATE_R1")
	)
	(segment
		(start 462.18221 -97.523808)
		(end 463.065876 -97.523808)
		(width 0.10668)
		(layer "F.Cu")
		(net "FB_BMC_ISOLATE_R1")
	)
	(segment
		(start 460.529686 -97.864422)
		(end 461.841596 -97.864422)
		(width 0.10668)
		(layer "F.Cu")
		(net "FB_BMC_ISOLATE_R1")
	)
	(via
		(at 461.841596 -97.864422)
		(size 0.762)
		(drill 0.381)
		(layers "F.Cu" "B.Cu")
		(net "FB_BMC_ISOLATE_R1")
	)
	(segment
		(start 210.926172 -77.662786)
		(end 210.215734 -76.952348)
		(width 0.10668)
		(layer "F.Cu")
		(net "FB_BMC_ISOLATE1")
	)
	(segment
		(start 210.926172 -79.21371)
		(end 210.926172 -77.662786)
		(width 0.10668)
		(layer "F.Cu")
		(net "FB_BMC_ISOLATE1")
	)
	(segment
		(start 48.98263 -36.820348)
		(end 48.387 -36.820348)
		(width 0.10668)
		(layer "F.Cu")
		(net "FB_BMC_ISOLATE1")
	)
	(segment
		(start 48.98263 -35.804348)
		(end 48.98263 -34.610548)
		(width 0.10668)
		(layer "F.Cu")
		(net "FB_BMC_ISOLATE1")
	)
	(segment
		(start 90.759026 -31.12135)
		(end 91.422728 -31.12135)
		(width 0.10668)
		(layer "F.Cu")
		(net "FB_BMC_ISOLATE1")
	)
	(segment
		(start 48.26 -36.693348)
		(end 48.26 -36.322)
		(width 0.10668)
		(layer "F.Cu")
		(net "FB_BMC_ISOLATE1")
	)
	(segment
		(start 49.56683 -34.610548)
		(end 48.98263 -34.610548)
		(width 0.10668)
		(layer "F.Cu")
		(net "FB_BMC_ISOLATE1")
	)
	(segment
		(start 50.20183 -33.975548)
		(end 49.56683 -34.610548)
		(width 0.10668)
		(layer "F.Cu")
		(net "FB_BMC_ISOLATE1")
	)
	(segment
		(start 48.98263 -36.820348)
		(end 48.98263 -35.804348)
		(width 0.10668)
		(layer "F.Cu")
		(net "FB_BMC_ISOLATE1")
	)
	(segment
		(start 91.422728 -31.12135)
		(end 91.882976 -30.661102)
		(width 0.10668)
		(layer "F.Cu")
		(net "FB_BMC_ISOLATE1")
	)
	(segment
		(start 48.387 -36.820348)
		(end 48.26 -36.693348)
		(width 0.10668)
		(layer "F.Cu")
		(net "FB_BMC_ISOLATE1")
	)
	(via
		(at 210.215734 -76.952348)
		(size 0.508)
		(drill 0.254)
		(layers "F.Cu" "B.Cu")
		(net "FB_BMC_ISOLATE1")
	)
	(via
		(at 191.72555 -41.502838)
		(size 0.508)
		(drill 0.254)
		(layers "F.Cu" "B.Cu")
		(net "FB_BMC_ISOLATE1")
	)
	(via
		(at 48.98263 -34.610548)
		(size 0.762)
		(drill 0.381)
		(layers "F.Cu" "B.Cu")
		(net "FB_BMC_ISOLATE1")
	)
	(via
		(at 91.882976 -30.661102)
		(size 0.508)
		(drill 0.254)
		(layers "F.Cu" "B.Cu")
		(net "FB_BMC_ISOLATE1")
	)
	(via
		(at 210.926172 -79.21371)
		(size 0.508)
		(drill 0.254)
		(layers "F.Cu" "B.Cu")
		(net "FB_BMC_ISOLATE1")
	)
	(via
		(at 203.18349 -72.853042)
		(size 0.508)
		(drill 0.254)
		(layers "F.Cu" "B.Cu")
		(net "FB_BMC_ISOLATE1")
	)
	(via
		(at 202.74407 -70.903084)
		(size 0.508)
		(drill 0.254)
		(layers "F.Cu" "B.Cu")
		(net "FB_BMC_ISOLATE1")
	)
	(via
		(at 48.26 -36.322)
		(size 0.508)
		(drill 0.254)
		(layers "F.Cu" "B.Cu")
		(net "FB_BMC_ISOLATE1")
	)
	(via
		(at 204.188822 -76.700126)
		(size 0.508)
		(drill 0.254)
		(layers "F.Cu" "B.Cu")
		(net "FB_BMC_ISOLATE1")
	)
	(segment
		(start 208.095088 -78.18247)
		(end 209.761836 -78.18247)
		(width 0.10668)
		(layer "B.Cu")
		(net "FB_BMC_ISOLATE1")
	)
	(segment
		(start 204.275182 -76.613766)
		(end 206.374746 -76.613766)
		(width 0.10668)
		(layer "B.Cu")
		(net "FB_BMC_ISOLATE1")
	)
	(segment
		(start 206.374746 -78.563724)
		(end 207.713834 -78.563724)
		(width 0.10668)
		(layer "B.Cu")
		(net "FB_BMC_ISOLATE1")
	)
	(segment
		(start 194.980052 -70.253098)
		(end 194.570858 -70.662292)
		(width 0.10668)
		(layer "B.Cu")
		(net "FB_BMC_ISOLATE1")
	)
	(segment
		(start 194.697858 -72.203056)
		(end 195.55333 -72.203056)
		(width 0.10668)
		(layer "B.Cu")
		(net "FB_BMC_ISOLATE1")
	)
	(segment
		(start 199.319642 -72.203056)
		(end 199.969628 -72.853042)
		(width 0.10668)
		(layer "B.Cu")
		(net "FB_BMC_ISOLATE1")
	)
	(segment
		(start 195.55333 -70.253098)
		(end 194.980052 -70.253098)
		(width 0.10668)
		(layer "B.Cu")
		(net "FB_BMC_ISOLATE1")
	)
	(segment
		(start 204.188822 -76.700126)
		(end 204.275182 -76.613766)
		(width 0.10668)
		(layer "B.Cu")
		(net "FB_BMC_ISOLATE1")
	)
	(segment
		(start 210.793076 -79.21371)
		(end 210.926172 -79.21371)
		(width 0.10668)
		(layer "B.Cu")
		(net "FB_BMC_ISOLATE1")
	)
	(segment
		(start 207.713834 -78.563724)
		(end 208.095088 -78.18247)
		(width 0.10668)
		(layer "B.Cu")
		(net "FB_BMC_ISOLATE1")
	)
	(segment
		(start 209.761836 -78.18247)
		(end 210.793076 -79.21371)
		(width 0.10668)
		(layer "B.Cu")
		(net "FB_BMC_ISOLATE1")
	)
	(segment
		(start 194.570858 -70.662292)
		(end 194.570858 -72.076056)
		(width 0.10668)
		(layer "B.Cu")
		(net "FB_BMC_ISOLATE1")
	)
	(segment
		(start 194.570858 -72.076056)
		(end 194.697858 -72.203056)
		(width 0.10668)
		(layer "B.Cu")
		(net "FB_BMC_ISOLATE1")
	)
	(segment
		(start 201.39533 -72.853042)
		(end 203.18349 -72.853042)
		(width 0.10668)
		(layer "B.Cu")
		(net "FB_BMC_ISOLATE1")
	)
	(segment
		(start 202.74407 -70.903084)
		(end 201.39533 -70.903084)
		(width 0.10668)
		(layer "B.Cu")
		(net "FB_BMC_ISOLATE1")
	)
	(segment
		(start 210.215734 -76.952348)
		(end 210.527138 -77.263752)
		(width 0.10668)
		(layer "B.Cu")
		(net "FB_BMC_ISOLATE1")
	)
	(segment
		(start 195.55333 -72.203056)
		(end 199.319642 -72.203056)
		(width 0.10668)
		(layer "B.Cu")
		(net "FB_BMC_ISOLATE1")
	)
	(segment
		(start 212.216746 -79.21371)
		(end 210.926172 -79.21371)
		(width 0.10668)
		(layer "B.Cu")
		(net "FB_BMC_ISOLATE1")
	)
	(segment
		(start 210.527138 -77.263752)
		(end 212.216746 -77.263752)
		(width 0.10668)
		(layer "B.Cu")
		(net "FB_BMC_ISOLATE1")
	)
	(segment
		(start 199.969628 -72.853042)
		(end 201.39533 -72.853042)
		(width 0.10668)
		(layer "B.Cu")
		(net "FB_BMC_ISOLATE1")
	)
	(segment
		(start 209.853784 -76.590398)
		(end 210.215734 -76.952348)
		(width 0.11684)
		(layer "In2.Cu")
		(net "FB_BMC_ISOLATE1")
	)
	(segment
		(start 204.29855 -76.590398)
		(end 209.853784 -76.590398)
		(width 0.11684)
		(layer "In2.Cu")
		(net "FB_BMC_ISOLATE1")
	)
	(segment
		(start 204.188822 -76.700126)
		(end 204.29855 -76.590398)
		(width 0.11684)
		(layer "In2.Cu")
		(net "FB_BMC_ISOLATE1")
	)
	(segment
		(start 204.067664 -76.578968)
		(end 204.188822 -76.700126)
		(width 0.11684)
		(layer "In4.Cu")
		(net "FB_BMC_ISOLATE1")
	)
	(segment
		(start 204.067664 -73.737216)
		(end 204.067664 -76.578968)
		(width 0.11684)
		(layer "In4.Cu")
		(net "FB_BMC_ISOLATE1")
	)
	(segment
		(start 196.275452 -60.367164)
		(end 196.275452 -46.05274)
		(width 0.11684)
		(layer "In4.Cu")
		(net "FB_BMC_ISOLATE1")
	)
	(segment
		(start 203.18349 -72.853042)
		(end 203.18349 -71.342504)
		(width 0.11684)
		(layer "In4.Cu")
		(net "FB_BMC_ISOLATE1")
	)
	(segment
		(start 202.74407 -70.903084)
		(end 201.537316 -69.69633)
		(width 0.11684)
		(layer "In4.Cu")
		(net "FB_BMC_ISOLATE1")
	)
	(segment
		(start 196.275452 -46.05274)
		(end 191.72555 -41.502838)
		(width 0.11684)
		(layer "In4.Cu")
		(net "FB_BMC_ISOLATE1")
	)
	(segment
		(start 203.18349 -72.853042)
		(end 204.067664 -73.737216)
		(width 0.11684)
		(layer "In4.Cu")
		(net "FB_BMC_ISOLATE1")
	)
	(segment
		(start 201.537316 -65.629028)
		(end 196.275452 -60.367164)
		(width 0.11684)
		(layer "In4.Cu")
		(net "FB_BMC_ISOLATE1")
	)
	(segment
		(start 201.537316 -69.69633)
		(end 201.537316 -65.629028)
		(width 0.11684)
		(layer "In4.Cu")
		(net "FB_BMC_ISOLATE1")
	)
	(segment
		(start 203.18349 -71.342504)
		(end 202.74407 -70.903084)
		(width 0.11684)
		(layer "In4.Cu")
		(net "FB_BMC_ISOLATE1")
	)
	(segment
		(start 181.561486 -38.581584)
		(end 180.319934 -37.340032)
		(width 0.11684)
		(layer "In6.Cu")
		(net "FB_BMC_ISOLATE1")
	)
	(segment
		(start 141.654276 -37.969444)
		(end 141.09446 -37.969444)
		(width 0.11684)
		(layer "In6.Cu")
		(net "FB_BMC_ISOLATE1")
	)
	(segment
		(start 152.63114 -39.918386)
		(end 147.583652 -39.918386)
		(width 0.11684)
		(layer "In6.Cu")
		(net "FB_BMC_ISOLATE1")
	)
	(segment
		(start 161.578036 -37.347906)
		(end 158.636208 -40.289734)
		(width 0.11684)
		(layer "In6.Cu")
		(net "FB_BMC_ISOLATE1")
	)
	(segment
		(start 51.80711 -27.179524)
		(end 51.80711 -28.273502)
		(width 0.11684)
		(layer "In6.Cu")
		(net "FB_BMC_ISOLATE1")
	)
	(segment
		(start 102.579932 -36.094924)
		(end 97.866962 -36.094924)
		(width 0.11684)
		(layer "In6.Cu")
		(net "FB_BMC_ISOLATE1")
	)
	(segment
		(start 55.96509 -23.021544)
		(end 51.80711 -27.179524)
		(width 0.11684)
		(layer "In6.Cu")
		(net "FB_BMC_ISOLATE1")
	)
	(segment
		(start 115.53444 -37.57422)
		(end 104.059228 -37.57422)
		(width 0.11684)
		(layer "In6.Cu")
		(net "FB_BMC_ISOLATE1")
	)
	(segment
		(start 174.613824 -36.456366)
		(end 172.865542 -34.708084)
		(width 0.11684)
		(layer "In6.Cu")
		(net "FB_BMC_ISOLATE1")
	)
	(segment
		(start 153.002488 -40.289734)
		(end 152.63114 -39.918386)
		(width 0.11684)
		(layer "In6.Cu")
		(net "FB_BMC_ISOLATE1")
	)
	(segment
		(start 64.440562 -30.3784)
		(end 63.523114 -29.460952)
		(width 0.11684)
		(layer "In6.Cu")
		(net "FB_BMC_ISOLATE1")
	)
	(segment
		(start 60.88634 -23.021544)
		(end 55.96509 -23.021544)
		(width 0.11684)
		(layer "In6.Cu")
		(net "FB_BMC_ISOLATE1")
	)
	(segment
		(start 158.636208 -40.289734)
		(end 153.002488 -40.289734)
		(width 0.11684)
		(layer "In6.Cu")
		(net "FB_BMC_ISOLATE1")
	)
	(segment
		(start 129.216404 -41.929304)
		(end 119.889524 -41.929304)
		(width 0.11684)
		(layer "In6.Cu")
		(net "FB_BMC_ISOLATE1")
	)
	(segment
		(start 177.421286 -37.340032)
		(end 176.53762 -36.456366)
		(width 0.11684)
		(layer "In6.Cu")
		(net "FB_BMC_ISOLATE1")
	)
	(segment
		(start 186.84367 -41.502838)
		(end 183.922416 -38.581584)
		(width 0.11684)
		(layer "In6.Cu")
		(net "FB_BMC_ISOLATE1")
	)
	(segment
		(start 91.882976 -30.661102)
		(end 91.041474 -29.8196)
		(width 0.11684)
		(layer "In6.Cu")
		(net "FB_BMC_ISOLATE1")
	)
	(segment
		(start 176.53762 -36.456366)
		(end 174.613824 -36.456366)
		(width 0.11684)
		(layer "In6.Cu")
		(net "FB_BMC_ISOLATE1")
	)
	(segment
		(start 141.09446 -37.969444)
		(end 138.424412 -40.639492)
		(width 0.11684)
		(layer "In6.Cu")
		(net "FB_BMC_ISOLATE1")
	)
	(segment
		(start 51.80711 -28.273502)
		(end 48.26 -31.820612)
		(width 0.11684)
		(layer "In6.Cu")
		(net "FB_BMC_ISOLATE1")
	)
	(segment
		(start 69.952362 -29.528262)
		(end 66.838576 -29.528262)
		(width 0.11684)
		(layer "In6.Cu")
		(net "FB_BMC_ISOLATE1")
	)
	(segment
		(start 92.43314 -30.661102)
		(end 91.882976 -30.661102)
		(width 0.11684)
		(layer "In6.Cu")
		(net "FB_BMC_ISOLATE1")
	)
	(segment
		(start 65.988438 -30.3784)
		(end 64.440562 -30.3784)
		(width 0.11684)
		(layer "In6.Cu")
		(net "FB_BMC_ISOLATE1")
	)
	(segment
		(start 62.00775 -24.142954)
		(end 60.88634 -23.021544)
		(width 0.11684)
		(layer "In6.Cu")
		(net "FB_BMC_ISOLATE1")
	)
	(segment
		(start 63.523114 -29.460952)
		(end 63.523114 -27.8257)
		(width 0.11684)
		(layer "In6.Cu")
		(net "FB_BMC_ISOLATE1")
	)
	(segment
		(start 142.863824 -36.759896)
		(end 141.654276 -37.969444)
		(width 0.11684)
		(layer "In6.Cu")
		(net "FB_BMC_ISOLATE1")
	)
	(segment
		(start 91.041474 -29.8196)
		(end 75.678284 -29.8196)
		(width 0.11684)
		(layer "In6.Cu")
		(net "FB_BMC_ISOLATE1")
	)
	(segment
		(start 66.838576 -29.528262)
		(end 65.988438 -30.3784)
		(width 0.11684)
		(layer "In6.Cu")
		(net "FB_BMC_ISOLATE1")
	)
	(segment
		(start 191.72555 -41.502838)
		(end 186.84367 -41.502838)
		(width 0.11684)
		(layer "In6.Cu")
		(net "FB_BMC_ISOLATE1")
	)
	(segment
		(start 138.424412 -40.639492)
		(end 130.506216 -40.639492)
		(width 0.11684)
		(layer "In6.Cu")
		(net "FB_BMC_ISOLATE1")
	)
	(segment
		(start 62.00775 -26.310336)
		(end 62.00775 -24.142954)
		(width 0.11684)
		(layer "In6.Cu")
		(net "FB_BMC_ISOLATE1")
	)
	(segment
		(start 63.523114 -27.8257)
		(end 62.00775 -26.310336)
		(width 0.11684)
		(layer "In6.Cu")
		(net "FB_BMC_ISOLATE1")
	)
	(segment
		(start 130.506216 -40.639492)
		(end 129.216404 -41.929304)
		(width 0.11684)
		(layer "In6.Cu")
		(net "FB_BMC_ISOLATE1")
	)
	(segment
		(start 104.059228 -37.57422)
		(end 102.579932 -36.094924)
		(width 0.11684)
		(layer "In6.Cu")
		(net "FB_BMC_ISOLATE1")
	)
	(segment
		(start 183.922416 -38.581584)
		(end 181.561486 -38.581584)
		(width 0.11684)
		(layer "In6.Cu")
		(net "FB_BMC_ISOLATE1")
	)
	(segment
		(start 74.090276 -31.407608)
		(end 71.831708 -31.407608)
		(width 0.11684)
		(layer "In6.Cu")
		(net "FB_BMC_ISOLATE1")
	)
	(segment
		(start 75.678284 -29.8196)
		(end 74.090276 -31.407608)
		(width 0.11684)
		(layer "In6.Cu")
		(net "FB_BMC_ISOLATE1")
	)
	(segment
		(start 97.866962 -36.094924)
		(end 92.43314 -30.661102)
		(width 0.11684)
		(layer "In6.Cu")
		(net "FB_BMC_ISOLATE1")
	)
	(segment
		(start 170.191176 -34.708084)
		(end 168.891712 -36.007548)
		(width 0.11684)
		(layer "In6.Cu")
		(net "FB_BMC_ISOLATE1")
	)
	(segment
		(start 147.583652 -39.918386)
		(end 144.425162 -36.759896)
		(width 0.11684)
		(layer "In6.Cu")
		(net "FB_BMC_ISOLATE1")
	)
	(segment
		(start 165.886638 -37.347906)
		(end 161.578036 -37.347906)
		(width 0.11684)
		(layer "In6.Cu")
		(net "FB_BMC_ISOLATE1")
	)
	(segment
		(start 167.226996 -36.007548)
		(end 165.886638 -37.347906)
		(width 0.11684)
		(layer "In6.Cu")
		(net "FB_BMC_ISOLATE1")
	)
	(segment
		(start 172.865542 -34.708084)
		(end 170.191176 -34.708084)
		(width 0.11684)
		(layer "In6.Cu")
		(net "FB_BMC_ISOLATE1")
	)
	(segment
		(start 119.889524 -41.929304)
		(end 115.53444 -37.57422)
		(width 0.11684)
		(layer "In6.Cu")
		(net "FB_BMC_ISOLATE1")
	)
	(segment
		(start 144.425162 -36.759896)
		(end 142.863824 -36.759896)
		(width 0.11684)
		(layer "In6.Cu")
		(net "FB_BMC_ISOLATE1")
	)
	(segment
		(start 180.319934 -37.340032)
		(end 177.421286 -37.340032)
		(width 0.11684)
		(layer "In6.Cu")
		(net "FB_BMC_ISOLATE1")
	)
	(segment
		(start 168.891712 -36.007548)
		(end 167.226996 -36.007548)
		(width 0.11684)
		(layer "In6.Cu")
		(net "FB_BMC_ISOLATE1")
	)
	(segment
		(start 48.26 -31.820612)
		(end 48.26 -36.322)
		(width 0.11684)
		(layer "In6.Cu")
		(net "FB_BMC_ISOLATE1")
	)
	(segment
		(start 71.831708 -31.407608)
		(end 69.952362 -29.528262)
		(width 0.11684)
		(layer "In6.Cu")
		(net "FB_BMC_ISOLATE1")
	)
	(segment
		(start 463.865976 -96.406208)
		(end 463.865976 -97.523808)
		(width 0.10668)
		(layer "F.Cu")
		(net "FB_BMC_ISOLATE")
	)
	(segment
		(start 463.862674 -98.564954)
		(end 463.862674 -97.52711)
		(width 0.10668)
		(layer "F.Cu")
		(net "FB_BMC_ISOLATE")
	)
	(segment
		(start 463.865976 -96.406208)
		(end 464.481926 -96.406208)
		(width 0.10668)
		(layer "F.Cu")
		(net "FB_BMC_ISOLATE")
	)
	(segment
		(start 463.862674 -97.52711)
		(end 463.865976 -97.523808)
		(width 0.10668)
		(layer "F.Cu")
		(net "FB_BMC_ISOLATE")
	)
	(segment
		(start 379.170438 -34.178748)
		(end 378.116338 -34.178748)
		(width 0.10668)
		(layer "F.Cu")
		(net "FB_BMC_ISOLATE")
	)
	(via
		(at 206.468218 -70.83044)
		(size 0.508)
		(drill 0.254)
		(layers "F.Cu" "B.Cu")
		(net "FB_BMC_ISOLATE")
	)
	(via
		(at 195.544694 -76.825348)
		(size 0.508)
		(drill 0.254)
		(layers "F.Cu" "B.Cu")
		(net "FB_BMC_ISOLATE")
	)
	(via
		(at 378.116338 -34.178748)
		(size 0.508)
		(drill 0.254)
		(layers "F.Cu" "B.Cu")
		(net "FB_BMC_ISOLATE")
	)
	(via
		(at 214.932006 -71.480426)
		(size 0.508)
		(drill 0.254)
		(layers "F.Cu" "B.Cu")
		(net "FB_BMC_ISOLATE")
	)
	(via
		(at 464.481926 -96.406208)
		(size 0.508)
		(drill 0.254)
		(layers "F.Cu" "B.Cu")
		(net "FB_BMC_ISOLATE")
	)
	(via
		(at 198.790814 -78.965552)
		(size 0.508)
		(drill 0.254)
		(layers "F.Cu" "B.Cu")
		(net "FB_BMC_ISOLATE")
	)
	(segment
		(start 213.76005 -69.530468)
		(end 211.847684 -69.530468)
		(width 0.10668)
		(layer "B.Cu")
		(net "FB_BMC_ISOLATE")
	)
	(segment
		(start 198.790814 -78.965552)
		(end 198.790814 -77.378814)
		(width 0.10668)
		(layer "B.Cu")
		(net "FB_BMC_ISOLATE")
	)
	(segment
		(start 207.91805 -70.83044)
		(end 209.218276 -70.83044)
		(width 0.10668)
		(layer "B.Cu")
		(net "FB_BMC_ISOLATE")
	)
	(segment
		(start 195.261992 -76.542646)
		(end 194.304158 -76.542646)
		(width 0.10668)
		(layer "B.Cu")
		(net "FB_BMC_ISOLATE")
	)
	(segment
		(start 195.54444 -76.825602)
		(end 195.54444 -78.262988)
		(width 0.10668)
		(layer "B.Cu")
		(net "FB_BMC_ISOLATE")
	)
	(segment
		(start 195.314824 -78.492604)
		(end 194.304158 -78.492604)
		(width 0.10668)
		(layer "B.Cu")
		(net "FB_BMC_ISOLATE")
	)
	(segment
		(start 209.341212 -68.86702)
		(end 207.931512 -68.86702)
		(width 0.10668)
		(layer "B.Cu")
		(net "FB_BMC_ISOLATE")
	)
	(segment
		(start 198.790814 -77.378814)
		(end 199.00646 -77.163168)
		(width 0.10668)
		(layer "B.Cu")
		(net "FB_BMC_ISOLATE")
	)
	(segment
		(start 200.146158 -79.14259)
		(end 198.967852 -79.14259)
		(width 0.10668)
		(layer "B.Cu")
		(net "FB_BMC_ISOLATE")
	)
	(segment
		(start 211.535772 -69.84238)
		(end 211.535772 -70.93712)
		(width 0.10668)
		(layer "B.Cu")
		(net "FB_BMC_ISOLATE")
	)
	(segment
		(start 195.54444 -78.262988)
		(end 195.314824 -78.492604)
		(width 0.10668)
		(layer "B.Cu")
		(net "FB_BMC_ISOLATE")
	)
	(segment
		(start 209.52333 -70.525386)
		(end 209.52333 -69.049138)
		(width 0.10668)
		(layer "B.Cu")
		(net "FB_BMC_ISOLATE")
	)
	(segment
		(start 195.544694 -76.825348)
		(end 195.54444 -76.825602)
		(width 0.10668)
		(layer "B.Cu")
		(net "FB_BMC_ISOLATE")
	)
	(segment
		(start 209.52333 -69.049138)
		(end 209.341212 -68.86702)
		(width 0.10668)
		(layer "B.Cu")
		(net "FB_BMC_ISOLATE")
	)
	(segment
		(start 195.544694 -76.825348)
		(end 195.261992 -76.542646)
		(width 0.10668)
		(layer "B.Cu")
		(net "FB_BMC_ISOLATE")
	)
	(segment
		(start 207.91805 -70.83044)
		(end 206.468218 -70.83044)
		(width 0.10668)
		(layer "B.Cu")
		(net "FB_BMC_ISOLATE")
	)
	(segment
		(start 207.931512 -68.86702)
		(end 207.91805 -68.880482)
		(width 0.10668)
		(layer "B.Cu")
		(net "FB_BMC_ISOLATE")
	)
	(segment
		(start 211.847684 -69.530468)
		(end 211.535772 -69.84238)
		(width 0.10668)
		(layer "B.Cu")
		(net "FB_BMC_ISOLATE")
	)
	(segment
		(start 209.218276 -70.83044)
		(end 209.52333 -70.525386)
		(width 0.10668)
		(layer "B.Cu")
		(net "FB_BMC_ISOLATE")
	)
	(segment
		(start 211.535772 -70.93712)
		(end 212.066124 -71.467472)
		(width 0.10668)
		(layer "B.Cu")
		(net "FB_BMC_ISOLATE")
	)
	(segment
		(start 200.116694 -77.163168)
		(end 200.146158 -77.192632)
		(width 0.10668)
		(layer "B.Cu")
		(net "FB_BMC_ISOLATE")
	)
	(segment
		(start 213.747096 -71.467472)
		(end 213.76005 -71.480426)
		(width 0.10668)
		(layer "B.Cu")
		(net "FB_BMC_ISOLATE")
	)
	(segment
		(start 213.76005 -71.480426)
		(end 214.932006 -71.480426)
		(width 0.10668)
		(layer "B.Cu")
		(net "FB_BMC_ISOLATE")
	)
	(segment
		(start 199.00646 -77.163168)
		(end 200.116694 -77.163168)
		(width 0.10668)
		(layer "B.Cu")
		(net "FB_BMC_ISOLATE")
	)
	(segment
		(start 198.967852 -79.14259)
		(end 198.790814 -78.965552)
		(width 0.10668)
		(layer "B.Cu")
		(net "FB_BMC_ISOLATE")
	)
	(segment
		(start 212.066124 -71.467472)
		(end 213.747096 -71.467472)
		(width 0.10668)
		(layer "B.Cu")
		(net "FB_BMC_ISOLATE")
	)
	(segment
		(start 464.481926 -96.406208)
		(end 455.02703 -96.406208)
		(width 0.11684)
		(layer "In2.Cu")
		(net "FB_BMC_ISOLATE")
	)
	(segment
		(start 409.761436 -82.394552)
		(end 403.54123 -76.174346)
		(width 0.11684)
		(layer "In2.Cu")
		(net "FB_BMC_ISOLATE")
	)
	(segment
		(start 399.967196 -34.178748)
		(end 378.116338 -34.178748)
		(width 0.11684)
		(layer "In2.Cu")
		(net "FB_BMC_ISOLATE")
	)
	(segment
		(start 455.02703 -96.406208)
		(end 441.015374 -82.394552)
		(width 0.11684)
		(layer "In2.Cu")
		(net "FB_BMC_ISOLATE")
	)
	(segment
		(start 403.54123 -76.174346)
		(end 403.54123 -37.752782)
		(width 0.11684)
		(layer "In2.Cu")
		(net "FB_BMC_ISOLATE")
	)
	(segment
		(start 403.54123 -37.752782)
		(end 399.967196 -34.178748)
		(width 0.11684)
		(layer "In2.Cu")
		(net "FB_BMC_ISOLATE")
	)
	(segment
		(start 441.015374 -82.394552)
		(end 409.761436 -82.394552)
		(width 0.11684)
		(layer "In2.Cu")
		(net "FB_BMC_ISOLATE")
	)
	(segment
		(start 203.820522 -73.478136)
		(end 206.468218 -70.83044)
		(width 0.11684)
		(layer "In6.Cu")
		(net "FB_BMC_ISOLATE")
	)
	(segment
		(start 199.432672 -76.052426)
		(end 202.006962 -73.478136)
		(width 0.11684)
		(layer "In6.Cu")
		(net "FB_BMC_ISOLATE")
	)
	(segment
		(start 206.468218 -70.83044)
		(end 207.492346 -70.83044)
		(width 0.11684)
		(layer "In6.Cu")
		(net "FB_BMC_ISOLATE")
	)
	(segment
		(start 202.006962 -73.478136)
		(end 203.820522 -73.478136)
		(width 0.11684)
		(layer "In6.Cu")
		(net "FB_BMC_ISOLATE")
	)
	(segment
		(start 368.497612 -48.353218)
		(end 378.116338 -38.734492)
		(width 0.11684)
		(layer "In6.Cu")
		(net "FB_BMC_ISOLATE")
	)
	(segment
		(start 257.252978 -73.92543)
		(end 258.666234 -72.512174)
		(width 0.11684)
		(layer "In6.Cu")
		(net "FB_BMC_ISOLATE")
	)
	(segment
		(start 307.676296 -48.915066)
		(end 308.238144 -48.353218)
		(width 0.11684)
		(layer "In6.Cu")
		(net "FB_BMC_ISOLATE")
	)
	(segment
		(start 228.356414 -73.92543)
		(end 257.252978 -73.92543)
		(width 0.11684)
		(layer "In6.Cu")
		(net "FB_BMC_ISOLATE")
	)
	(segment
		(start 305.591718 -48.010318)
		(end 306.496466 -48.915066)
		(width 0.11684)
		(layer "In6.Cu")
		(net "FB_BMC_ISOLATE")
	)
	(segment
		(start 198.790814 -78.965552)
		(end 199.827896 -80.002634)
		(width 0.11684)
		(layer "In6.Cu")
		(net "FB_BMC_ISOLATE")
	)
	(segment
		(start 195.544694 -76.825348)
		(end 196.317616 -76.052426)
		(width 0.11684)
		(layer "In6.Cu")
		(net "FB_BMC_ISOLATE")
	)
	(segment
		(start 261.6454 -72.512174)
		(end 262.11784 -72.039734)
		(width 0.11684)
		(layer "In6.Cu")
		(net "FB_BMC_ISOLATE")
	)
	(segment
		(start 308.238144 -48.353218)
		(end 368.497612 -48.353218)
		(width 0.11684)
		(layer "In6.Cu")
		(net "FB_BMC_ISOLATE")
	)
	(segment
		(start 209.812128 -78.578964)
		(end 223.70288 -78.578964)
		(width 0.11684)
		(layer "In6.Cu")
		(net "FB_BMC_ISOLATE")
	)
	(segment
		(start 195.544694 -76.910692)
		(end 195.544694 -76.825348)
		(width 0.11684)
		(layer "In6.Cu")
		(net "FB_BMC_ISOLATE")
	)
	(segment
		(start 378.116338 -38.734492)
		(end 378.116338 -34.178748)
		(width 0.11684)
		(layer "In6.Cu")
		(net "FB_BMC_ISOLATE")
	)
	(segment
		(start 196.317616 -76.052426)
		(end 199.432672 -76.052426)
		(width 0.11684)
		(layer "In6.Cu")
		(net "FB_BMC_ISOLATE")
	)
	(segment
		(start 223.70288 -78.578964)
		(end 228.356414 -73.92543)
		(width 0.11684)
		(layer "In6.Cu")
		(net "FB_BMC_ISOLATE")
	)
	(segment
		(start 208.142332 -71.480426)
		(end 214.932006 -71.480426)
		(width 0.11684)
		(layer "In6.Cu")
		(net "FB_BMC_ISOLATE")
	)
	(segment
		(start 197.599554 -78.965552)
		(end 195.544694 -76.910692)
		(width 0.11684)
		(layer "In6.Cu")
		(net "FB_BMC_ISOLATE")
	)
	(segment
		(start 207.492346 -70.83044)
		(end 208.142332 -71.480426)
		(width 0.11684)
		(layer "In6.Cu")
		(net "FB_BMC_ISOLATE")
	)
	(segment
		(start 263.14781 -72.039734)
		(end 269.164816 -66.022728)
		(width 0.11684)
		(layer "In6.Cu")
		(net "FB_BMC_ISOLATE")
	)
	(segment
		(start 306.496466 -48.915066)
		(end 307.676296 -48.915066)
		(width 0.11684)
		(layer "In6.Cu")
		(net "FB_BMC_ISOLATE")
	)
	(segment
		(start 271.683226 -66.022728)
		(end 289.695636 -48.010318)
		(width 0.11684)
		(layer "In6.Cu")
		(net "FB_BMC_ISOLATE")
	)
	(segment
		(start 289.695636 -48.010318)
		(end 305.591718 -48.010318)
		(width 0.11684)
		(layer "In6.Cu")
		(net "FB_BMC_ISOLATE")
	)
	(segment
		(start 199.827896 -80.002634)
		(end 208.388458 -80.002634)
		(width 0.11684)
		(layer "In6.Cu")
		(net "FB_BMC_ISOLATE")
	)
	(segment
		(start 258.666234 -72.512174)
		(end 261.6454 -72.512174)
		(width 0.11684)
		(layer "In6.Cu")
		(net "FB_BMC_ISOLATE")
	)
	(segment
		(start 262.11784 -72.039734)
		(end 263.14781 -72.039734)
		(width 0.11684)
		(layer "In6.Cu")
		(net "FB_BMC_ISOLATE")
	)
	(segment
		(start 208.388458 -80.002634)
		(end 209.812128 -78.578964)
		(width 0.11684)
		(layer "In6.Cu")
		(net "FB_BMC_ISOLATE")
	)
	(segment
		(start 198.790814 -78.965552)
		(end 197.599554 -78.965552)
		(width 0.11684)
		(layer "In6.Cu")
		(net "FB_BMC_ISOLATE")
	)
	(segment
		(start 269.164816 -66.022728)
		(end 271.683226 -66.022728)
		(width 0.11684)
		(layer "In6.Cu")
		(net "FB_BMC_ISOLATE")
	)
	(segment
		(start 371.767862 -294.070024)
		(end 372.234714 -294.335962)
		(width 0.10668)
		(layer "F.Cu")
		(net "ESPI_CPU0_R_D3")
	)
	(via
		(at 372.175278 -303.069752)
		(size 0.6604)
		(drill 0.3302)
		(layers "F.Cu" "B.Cu")
		(net "ESPI_CPU0_R_D3")
	)
	(via
		(at 372.234714 -294.335962)
		(size 0.4064)
		(drill 0.2032)
		(layers "F.Cu" "B.Cu")
		(net "ESPI_CPU0_R_D3")
	)
	(segment
		(start 372.929658 -302.435006)
		(end 372.929658 -302.158146)
		(width 0.10668)
		(layer "B.Cu")
		(net "ESPI_CPU0_R_D3")
	)
	(segment
		(start 372.929658 -300.197266)
		(end 372.822978 -300.090586)
		(width 0.10668)
		(layer "B.Cu")
		(net "ESPI_CPU0_R_D3")
	)
	(segment
		(start 393.217908 -325.813928)
		(end 390.118092 -322.714112)
		(width 0.10668)
		(layer "B.Cu")
		(net "ESPI_CPU0_R_D3")
	)
	(segment
		(start 372.929658 -299.493686)
		(end 372.929658 -299.216826)
		(width 0.10668)
		(layer "B.Cu")
		(net "ESPI_CPU0_R_D3")
	)
	(segment
		(start 372.195598 -302.051466)
		(end 372.088918 -301.944786)
		(width 0.10668)
		(layer "B.Cu")
		(net "ESPI_CPU0_R_D3")
	)
	(segment
		(start 372.929658 -300.474126)
		(end 372.929658 -300.197266)
		(width 0.10668)
		(layer "B.Cu")
		(net "ESPI_CPU0_R_D3")
	)
	(segment
		(start 372.088918 -301.667926)
		(end 372.195598 -301.561246)
		(width 0.10668)
		(layer "B.Cu")
		(net "ESPI_CPU0_R_D3")
	)
	(segment
		(start 383.435098 -317.059056)
		(end 372.175278 -305.799236)
		(width 0.10668)
		(layer "B.Cu")
		(net "ESPI_CPU0_R_D3")
	)
	(segment
		(start 372.175278 -298.023026)
		(end 372.175278 -296.234612)
		(width 0.10668)
		(layer "B.Cu")
		(net "ESPI_CPU0_R_D3")
	)
	(segment
		(start 372.929658 -298.236386)
		(end 372.822978 -298.129706)
		(width 0.10668)
		(layer "B.Cu")
		(net "ESPI_CPU0_R_D3")
	)
	(segment
		(start 371.785134 -299.003466)
		(end 371.785134 -298.726606)
		(width 0.10668)
		(layer "B.Cu")
		(net "ESPI_CPU0_R_D3")
	)
	(segment
		(start 371.785134 -300.687486)
		(end 371.891814 -300.580806)
		(width 0.10668)
		(layer "B.Cu")
		(net "ESPI_CPU0_R_D3")
	)
	(segment
		(start 371.785134 -298.726606)
		(end 371.891814 -298.619926)
		(width 0.10668)
		(layer "B.Cu")
		(net "ESPI_CPU0_R_D3")
	)
	(segment
		(start 372.929658 -298.513246)
		(end 372.929658 -298.236386)
		(width 0.10668)
		(layer "B.Cu")
		(net "ESPI_CPU0_R_D3")
	)
	(segment
		(start 372.281958 -298.129706)
		(end 372.175278 -298.023026)
		(width 0.10668)
		(layer "B.Cu")
		(net "ESPI_CPU0_R_D3")
	)
	(segment
		(start 372.822978 -300.090586)
		(end 371.891814 -300.090586)
		(width 0.10668)
		(layer "B.Cu")
		(net "ESPI_CPU0_R_D3")
	)
	(segment
		(start 393.217908 -325.878952)
		(end 393.217908 -325.813928)
		(width 0.10668)
		(layer "B.Cu")
		(net "ESPI_CPU0_R_D3")
	)
	(segment
		(start 372.088918 -301.944786)
		(end 372.088918 -301.667926)
		(width 0.10668)
		(layer "B.Cu")
		(net "ESPI_CPU0_R_D3")
	)
	(segment
		(start 372.234714 -296.175176)
		(end 372.234714 -294.335962)
		(width 0.10668)
		(layer "B.Cu")
		(net "ESPI_CPU0_R_D3")
	)
	(segment
		(start 383.435098 -317.811912)
		(end 383.435098 -317.059056)
		(width 0.10668)
		(layer "B.Cu")
		(net "ESPI_CPU0_R_D3")
	)
	(segment
		(start 372.175278 -302.648366)
		(end 372.281958 -302.541686)
		(width 0.10668)
		(layer "B.Cu")
		(net "ESPI_CPU0_R_D3")
	)
	(segment
		(start 372.822978 -299.600366)
		(end 372.929658 -299.493686)
		(width 0.10668)
		(layer "B.Cu")
		(net "ESPI_CPU0_R_D3")
	)
	(segment
		(start 372.822978 -300.580806)
		(end 372.929658 -300.474126)
		(width 0.10668)
		(layer "B.Cu")
		(net "ESPI_CPU0_R_D3")
	)
	(segment
		(start 372.175278 -296.234612)
		(end 372.234714 -296.175176)
		(width 0.10668)
		(layer "B.Cu")
		(net "ESPI_CPU0_R_D3")
	)
	(segment
		(start 371.891814 -300.090586)
		(end 371.785134 -299.983906)
		(width 0.10668)
		(layer "B.Cu")
		(net "ESPI_CPU0_R_D3")
	)
	(segment
		(start 372.822978 -302.541686)
		(end 372.929658 -302.435006)
		(width 0.10668)
		(layer "B.Cu")
		(net "ESPI_CPU0_R_D3")
	)
	(segment
		(start 371.785134 -299.983906)
		(end 371.785134 -299.707046)
		(width 0.10668)
		(layer "B.Cu")
		(net "ESPI_CPU0_R_D3")
	)
	(segment
		(start 372.175278 -303.069752)
		(end 372.175278 -302.648366)
		(width 0.10668)
		(layer "B.Cu")
		(net "ESPI_CPU0_R_D3")
	)
	(segment
		(start 372.822978 -302.051466)
		(end 372.195598 -302.051466)
		(width 0.10668)
		(layer "B.Cu")
		(net "ESPI_CPU0_R_D3")
	)
	(segment
		(start 371.891814 -299.110146)
		(end 371.785134 -299.003466)
		(width 0.10668)
		(layer "B.Cu")
		(net "ESPI_CPU0_R_D3")
	)
	(segment
		(start 372.822978 -298.129706)
		(end 372.281958 -298.129706)
		(width 0.10668)
		(layer "B.Cu")
		(net "ESPI_CPU0_R_D3")
	)
	(segment
		(start 388.337298 -322.714112)
		(end 383.435098 -317.811912)
		(width 0.10668)
		(layer "B.Cu")
		(net "ESPI_CPU0_R_D3")
	)
	(segment
		(start 372.281958 -302.541686)
		(end 372.822978 -302.541686)
		(width 0.10668)
		(layer "B.Cu")
		(net "ESPI_CPU0_R_D3")
	)
	(segment
		(start 372.929658 -299.216826)
		(end 372.822978 -299.110146)
		(width 0.10668)
		(layer "B.Cu")
		(net "ESPI_CPU0_R_D3")
	)
	(segment
		(start 372.822978 -298.619926)
		(end 372.929658 -298.513246)
		(width 0.10668)
		(layer "B.Cu")
		(net "ESPI_CPU0_R_D3")
	)
	(segment
		(start 372.929658 -301.177706)
		(end 372.822978 -301.071026)
		(width 0.10668)
		(layer "B.Cu")
		(net "ESPI_CPU0_R_D3")
	)
	(segment
		(start 372.822978 -299.110146)
		(end 371.891814 -299.110146)
		(width 0.10668)
		(layer "B.Cu")
		(net "ESPI_CPU0_R_D3")
	)
	(segment
		(start 371.891814 -298.619926)
		(end 372.822978 -298.619926)
		(width 0.10668)
		(layer "B.Cu")
		(net "ESPI_CPU0_R_D3")
	)
	(segment
		(start 371.891814 -301.071026)
		(end 371.785134 -300.964346)
		(width 0.10668)
		(layer "B.Cu")
		(net "ESPI_CPU0_R_D3")
	)
	(segment
		(start 371.891814 -299.600366)
		(end 372.822978 -299.600366)
		(width 0.10668)
		(layer "B.Cu")
		(net "ESPI_CPU0_R_D3")
	)
	(segment
		(start 371.785134 -299.707046)
		(end 371.891814 -299.600366)
		(width 0.10668)
		(layer "B.Cu")
		(net "ESPI_CPU0_R_D3")
	)
	(segment
		(start 390.118092 -322.714112)
		(end 388.337298 -322.714112)
		(width 0.10668)
		(layer "B.Cu")
		(net "ESPI_CPU0_R_D3")
	)
	(segment
		(start 372.929658 -301.454566)
		(end 372.929658 -301.177706)
		(width 0.10668)
		(layer "B.Cu")
		(net "ESPI_CPU0_R_D3")
	)
	(segment
		(start 372.822978 -301.071026)
		(end 371.891814 -301.071026)
		(width 0.10668)
		(layer "B.Cu")
		(net "ESPI_CPU0_R_D3")
	)
	(segment
		(start 372.195598 -301.561246)
		(end 372.822978 -301.561246)
		(width 0.10668)
		(layer "B.Cu")
		(net "ESPI_CPU0_R_D3")
	)
	(segment
		(start 372.929658 -302.158146)
		(end 372.822978 -302.051466)
		(width 0.10668)
		(layer "B.Cu")
		(net "ESPI_CPU0_R_D3")
	)
	(segment
		(start 372.175278 -305.799236)
		(end 372.175278 -303.069752)
		(width 0.10668)
		(layer "B.Cu")
		(net "ESPI_CPU0_R_D3")
	)
	(segment
		(start 372.822978 -301.561246)
		(end 372.929658 -301.454566)
		(width 0.10668)
		(layer "B.Cu")
		(net "ESPI_CPU0_R_D3")
	)
	(segment
		(start 371.891814 -300.580806)
		(end 372.822978 -300.580806)
		(width 0.10668)
		(layer "B.Cu")
		(net "ESPI_CPU0_R_D3")
	)
	(segment
		(start 371.785134 -300.964346)
		(end 371.785134 -300.687486)
		(width 0.10668)
		(layer "B.Cu")
		(net "ESPI_CPU0_R_D3")
	)
	(segment
		(start 372.238016 -293.260018)
		(end 372.704868 -293.525956)
		(width 0.10668)
		(layer "F.Cu")
		(net "ESPI_CPU0_R_D2")
	)
	(via
		(at 372.962678 -304.408332)
		(size 0.6604)
		(drill 0.3302)
		(layers "F.Cu" "B.Cu")
		(net "ESPI_CPU0_R_D2")
	)
	(via
		(at 372.704868 -293.525956)
		(size 0.4064)
		(drill 0.2032)
		(layers "F.Cu" "B.Cu")
		(net "ESPI_CPU0_R_D2")
	)
	(segment
		(start 372.962678 -305.95062)
		(end 383.884678 -316.87262)
		(width 0.10668)
		(layer "B.Cu")
		(net "ESPI_CPU0_R_D2")
	)
	(segment
		(start 374.077738 -300.494954)
		(end 374.184418 -300.601634)
		(width 0.10668)
		(layer "B.Cu")
		(net "ESPI_CPU0_R_D2")
	)
	(segment
		(start 374.184418 -300.878494)
		(end 374.077738 -300.985174)
		(width 0.10668)
		(layer "B.Cu")
		(net "ESPI_CPU0_R_D2")
	)
	(segment
		(start 372.704868 -294.549576)
		(end 373.109998 -294.954706)
		(width 0.10668)
		(layer "B.Cu")
		(net "ESPI_CPU0_R_D2")
	)
	(segment
		(start 373.069358 -302.946054)
		(end 372.962678 -303.052734)
		(width 0.10668)
		(layer "B.Cu")
		(net "ESPI_CPU0_R_D2")
	)
	(segment
		(start 374.113298 -301.475394)
		(end 374.219978 -301.582074)
		(width 0.10668)
		(layer "B.Cu")
		(net "ESPI_CPU0_R_D2")
	)
	(segment
		(start 373.379238 -300.111414)
		(end 373.379238 -300.388274)
		(width 0.10668)
		(layer "B.Cu")
		(net "ESPI_CPU0_R_D2")
	)
	(segment
		(start 374.118378 -299.621194)
		(end 374.118378 -299.898054)
		(width 0.10668)
		(layer "B.Cu")
		(net "ESPI_CPU0_R_D2")
	)
	(segment
		(start 374.176798 -302.839374)
		(end 374.070118 -302.946054)
		(width 0.10668)
		(layer "B.Cu")
		(net "ESPI_CPU0_R_D2")
	)
	(segment
		(start 374.011698 -299.514514)
		(end 374.118378 -299.621194)
		(width 0.10668)
		(layer "B.Cu")
		(net "ESPI_CPU0_R_D2")
	)
	(segment
		(start 372.704868 -293.525956)
		(end 372.704868 -294.549576)
		(width 0.10668)
		(layer "B.Cu")
		(net "ESPI_CPU0_R_D2")
	)
	(segment
		(start 372.685818 -297.207432)
		(end 373.205248 -297.726862)
		(width 0.10668)
		(layer "B.Cu")
		(net "ESPI_CPU0_R_D2")
	)
	(segment
		(start 390.308338 -322.264532)
		(end 392.185398 -324.141592)
		(width 0.10668)
		(layer "B.Cu")
		(net "ESPI_CPU0_R_D2")
	)
	(segment
		(start 383.884678 -316.87262)
		(end 383.884678 -317.625476)
		(width 0.10668)
		(layer "B.Cu")
		(net "ESPI_CPU0_R_D2")
	)
	(segment
		(start 373.379238 -301.368714)
		(end 373.485918 -301.475394)
		(width 0.10668)
		(layer "B.Cu")
		(net "ESPI_CPU0_R_D2")
	)
	(segment
		(start 373.485918 -301.475394)
		(end 374.113298 -301.475394)
		(width 0.10668)
		(layer "B.Cu")
		(net "ESPI_CPU0_R_D2")
	)
	(segment
		(start 374.118378 -299.898054)
		(end 374.011698 -300.004734)
		(width 0.10668)
		(layer "B.Cu")
		(net "ESPI_CPU0_R_D2")
	)
	(segment
		(start 374.077738 -300.985174)
		(end 373.485918 -300.985174)
		(width 0.10668)
		(layer "B.Cu")
		(net "ESPI_CPU0_R_D2")
	)
	(segment
		(start 392.522964 -324.141592)
		(end 393.217908 -324.836536)
		(width 0.10668)
		(layer "B.Cu")
		(net "ESPI_CPU0_R_D2")
	)
	(segment
		(start 374.070118 -302.946054)
		(end 373.069358 -302.946054)
		(width 0.10668)
		(layer "B.Cu")
		(net "ESPI_CPU0_R_D2")
	)
	(segment
		(start 374.011698 -300.004734)
		(end 373.485918 -300.004734)
		(width 0.10668)
		(layer "B.Cu")
		(net "ESPI_CPU0_R_D2")
	)
	(segment
		(start 392.185398 -324.141592)
		(end 392.522964 -324.141592)
		(width 0.10668)
		(layer "B.Cu")
		(net "ESPI_CPU0_R_D2")
	)
	(segment
		(start 373.109998 -294.954706)
		(end 373.109998 -296.033952)
		(width 0.10668)
		(layer "B.Cu")
		(net "ESPI_CPU0_R_D2")
	)
	(segment
		(start 374.219978 -301.858934)
		(end 374.113298 -301.965614)
		(width 0.10668)
		(layer "B.Cu")
		(net "ESPI_CPU0_R_D2")
	)
	(segment
		(start 373.379238 -300.388274)
		(end 373.485918 -300.494954)
		(width 0.10668)
		(layer "B.Cu")
		(net "ESPI_CPU0_R_D2")
	)
	(segment
		(start 373.379238 -298.146724)
		(end 373.379238 -299.407834)
		(width 0.10668)
		(layer "B.Cu")
		(net "ESPI_CPU0_R_D2")
	)
	(segment
		(start 372.685818 -296.458132)
		(end 372.685818 -297.207432)
		(width 0.10668)
		(layer "B.Cu")
		(net "ESPI_CPU0_R_D2")
	)
	(segment
		(start 373.109998 -296.033952)
		(end 372.685818 -296.458132)
		(width 0.10668)
		(layer "B.Cu")
		(net "ESPI_CPU0_R_D2")
	)
	(segment
		(start 373.379238 -301.091854)
		(end 373.379238 -301.368714)
		(width 0.10668)
		(layer "B.Cu")
		(net "ESPI_CPU0_R_D2")
	)
	(segment
		(start 373.485918 -301.965614)
		(end 373.379238 -302.072294)
		(width 0.10668)
		(layer "B.Cu")
		(net "ESPI_CPU0_R_D2")
	)
	(segment
		(start 373.485918 -300.985174)
		(end 373.379238 -301.091854)
		(width 0.10668)
		(layer "B.Cu")
		(net "ESPI_CPU0_R_D2")
	)
	(segment
		(start 374.070118 -302.455834)
		(end 374.176798 -302.562514)
		(width 0.10668)
		(layer "B.Cu")
		(net "ESPI_CPU0_R_D2")
	)
	(segment
		(start 373.485918 -300.494954)
		(end 374.077738 -300.494954)
		(width 0.10668)
		(layer "B.Cu")
		(net "ESPI_CPU0_R_D2")
	)
	(segment
		(start 373.205248 -297.726862)
		(end 373.379238 -298.146724)
		(width 0.10668)
		(layer "B.Cu")
		(net "ESPI_CPU0_R_D2")
	)
	(segment
		(start 373.485918 -302.455834)
		(end 374.070118 -302.455834)
		(width 0.10668)
		(layer "B.Cu")
		(net "ESPI_CPU0_R_D2")
	)
	(segment
		(start 373.379238 -299.407834)
		(end 373.485918 -299.514514)
		(width 0.10668)
		(layer "B.Cu")
		(net "ESPI_CPU0_R_D2")
	)
	(segment
		(start 374.113298 -301.965614)
		(end 373.485918 -301.965614)
		(width 0.10668)
		(layer "B.Cu")
		(net "ESPI_CPU0_R_D2")
	)
	(segment
		(start 373.379238 -302.349154)
		(end 373.485918 -302.455834)
		(width 0.10668)
		(layer "B.Cu")
		(net "ESPI_CPU0_R_D2")
	)
	(segment
		(start 374.219978 -301.582074)
		(end 374.219978 -301.858934)
		(width 0.10668)
		(layer "B.Cu")
		(net "ESPI_CPU0_R_D2")
	)
	(segment
		(start 383.884678 -317.625476)
		(end 388.523734 -322.264532)
		(width 0.10668)
		(layer "B.Cu")
		(net "ESPI_CPU0_R_D2")
	)
	(segment
		(start 372.962678 -304.408332)
		(end 372.962678 -305.95062)
		(width 0.10668)
		(layer "B.Cu")
		(net "ESPI_CPU0_R_D2")
	)
	(segment
		(start 374.184418 -300.601634)
		(end 374.184418 -300.878494)
		(width 0.10668)
		(layer "B.Cu")
		(net "ESPI_CPU0_R_D2")
	)
	(segment
		(start 373.379238 -302.072294)
		(end 373.379238 -302.349154)
		(width 0.10668)
		(layer "B.Cu")
		(net "ESPI_CPU0_R_D2")
	)
	(segment
		(start 372.962678 -303.052734)
		(end 372.962678 -304.408332)
		(width 0.10668)
		(layer "B.Cu")
		(net "ESPI_CPU0_R_D2")
	)
	(segment
		(start 393.217908 -324.836536)
		(end 393.217908 -324.862952)
		(width 0.10668)
		(layer "B.Cu")
		(net "ESPI_CPU0_R_D2")
	)
	(segment
		(start 373.485918 -300.004734)
		(end 373.379238 -300.111414)
		(width 0.10668)
		(layer "B.Cu")
		(net "ESPI_CPU0_R_D2")
	)
	(segment
		(start 373.485918 -299.514514)
		(end 374.011698 -299.514514)
		(width 0.10668)
		(layer "B.Cu")
		(net "ESPI_CPU0_R_D2")
	)
	(segment
		(start 388.523734 -322.264532)
		(end 390.308338 -322.264532)
		(width 0.10668)
		(layer "B.Cu")
		(net "ESPI_CPU0_R_D2")
	)
	(segment
		(start 374.176798 -302.562514)
		(end 374.176798 -302.839374)
		(width 0.10668)
		(layer "B.Cu")
		(net "ESPI_CPU0_R_D2")
	)
	(segment
		(start 372.707916 -292.450012)
		(end 373.174768 -292.71595)
		(width 0.10668)
		(layer "F.Cu")
		(net "ESPI_CPU0_R_D1")
	)
	(via
		(at 376.038364 -304.811684)
		(size 0.6604)
		(drill 0.3302)
		(layers "F.Cu" "B.Cu")
		(net "ESPI_CPU0_R_D1")
	)
	(via
		(at 373.174768 -292.71595)
		(size 0.4064)
		(drill 0.2032)
		(layers "F.Cu" "B.Cu")
		(net "ESPI_CPU0_R_D1")
	)
	(segment
		(start 376.038364 -303.0728)
		(end 375.931684 -303.17948)
		(width 0.10668)
		(layer "B.Cu")
		(net "ESPI_CPU0_R_D1")
	)
	(segment
		(start 383.425446 -314.65012)
		(end 383.62128 -314.845954)
		(width 0.10668)
		(layer "B.Cu")
		(net "ESPI_CPU0_R_D1")
	)
	(segment
		(start 382.92786 -314.30341)
		(end 382.833118 -314.398152)
		(width 0.10668)
		(layer "B.Cu")
		(net "ESPI_CPU0_R_D1")
	)
	(segment
		(start 384.3147 -315.539374)
		(end 384.3147 -315.69025)
		(width 0.10668)
		(layer "B.Cu")
		(net "ESPI_CPU0_R_D1")
	)
	(segment
		(start 375.497598 -303.17948)
		(end 375.390918 -303.28616)
		(width 0.10668)
		(layer "B.Cu")
		(net "ESPI_CPU0_R_D1")
	)
	(segment
		(start 384.783838 -316.499748)
		(end 384.783838 -317.252604)
		(width 0.10668)
		(layer "B.Cu")
		(net "ESPI_CPU0_R_D1")
	)
	(segment
		(start 375.497598 -302.19904)
		(end 375.390918 -302.30572)
		(width 0.10668)
		(layer "B.Cu")
		(net "ESPI_CPU0_R_D1")
	)
	(segment
		(start 373.706898 -295.685972)
		(end 373.706898 -296.95648)
		(width 0.10668)
		(layer "B.Cu")
		(net "ESPI_CPU0_R_D1")
	)
	(segment
		(start 374.214644 -297.464226)
		(end 376.038364 -301.867824)
		(width 0.10668)
		(layer "B.Cu")
		(net "ESPI_CPU0_R_D1")
	)
	(segment
		(start 382.92786 -314.152534)
		(end 382.92786 -314.30341)
		(width 0.10668)
		(layer "B.Cu")
		(net "ESPI_CPU0_R_D1")
	)
	(segment
		(start 383.179828 -314.744862)
		(end 383.27457 -314.65012)
		(width 0.10668)
		(layer "B.Cu")
		(net "ESPI_CPU0_R_D1")
	)
	(segment
		(start 376.038364 -302.09236)
		(end 375.931684 -302.19904)
		(width 0.10668)
		(layer "B.Cu")
		(net "ESPI_CPU0_R_D1")
	)
	(segment
		(start 382.732026 -313.9567)
		(end 382.92786 -314.152534)
		(width 0.10668)
		(layer "B.Cu")
		(net "ESPI_CPU0_R_D1")
	)
	(segment
		(start 376.038364 -304.811684)
		(end 375.688098 -305.16195)
		(width 0.10668)
		(layer "B.Cu")
		(net "ESPI_CPU0_R_D1")
	)
	(segment
		(start 384.783838 -317.252604)
		(end 388.711186 -321.179952)
		(width 0.10668)
		(layer "B.Cu")
		(net "ESPI_CPU0_R_D1")
	)
	(segment
		(start 375.688098 -305.16195)
		(end 375.688098 -307.404008)
		(width 0.10668)
		(layer "B.Cu")
		(net "ESPI_CPU0_R_D1")
	)
	(segment
		(start 383.028952 -314.744862)
		(end 383.179828 -314.744862)
		(width 0.10668)
		(layer "B.Cu")
		(net "ESPI_CPU0_R_D1")
	)
	(segment
		(start 384.219958 -315.935868)
		(end 384.783838 -316.499748)
		(width 0.10668)
		(layer "B.Cu")
		(net "ESPI_CPU0_R_D1")
	)
	(segment
		(start 384.118866 -315.34354)
		(end 384.3147 -315.539374)
		(width 0.10668)
		(layer "B.Cu")
		(net "ESPI_CPU0_R_D1")
	)
	(segment
		(start 375.931684 -303.6697)
		(end 376.038364 -303.77638)
		(width 0.10668)
		(layer "B.Cu")
		(net "ESPI_CPU0_R_D1")
	)
	(segment
		(start 382.486408 -314.051442)
		(end 382.58115 -313.9567)
		(width 0.10668)
		(layer "B.Cu")
		(net "ESPI_CPU0_R_D1")
	)
	(segment
		(start 375.931684 -303.17948)
		(end 375.497598 -303.17948)
		(width 0.10668)
		(layer "B.Cu")
		(net "ESPI_CPU0_R_D1")
	)
	(segment
		(start 383.722372 -315.438282)
		(end 383.873248 -315.438282)
		(width 0.10668)
		(layer "B.Cu")
		(net "ESPI_CPU0_R_D1")
	)
	(segment
		(start 382.833118 -314.549028)
		(end 383.028952 -314.744862)
		(width 0.10668)
		(layer "B.Cu")
		(net "ESPI_CPU0_R_D1")
	)
	(segment
		(start 382.58115 -313.9567)
		(end 382.732026 -313.9567)
		(width 0.10668)
		(layer "B.Cu")
		(net "ESPI_CPU0_R_D1")
	)
	(segment
		(start 375.931684 -302.19904)
		(end 375.497598 -302.19904)
		(width 0.10668)
		(layer "B.Cu")
		(net "ESPI_CPU0_R_D1")
	)
	(segment
		(start 375.390918 -302.58258)
		(end 375.497598 -302.68926)
		(width 0.10668)
		(layer "B.Cu")
		(net "ESPI_CPU0_R_D1")
	)
	(segment
		(start 383.873248 -315.438282)
		(end 383.96799 -315.34354)
		(width 0.10668)
		(layer "B.Cu")
		(net "ESPI_CPU0_R_D1")
	)
	(segment
		(start 375.497598 -302.68926)
		(end 375.931684 -302.68926)
		(width 0.10668)
		(layer "B.Cu")
		(net "ESPI_CPU0_R_D1")
	)
	(segment
		(start 383.62128 -314.845954)
		(end 383.62128 -314.99683)
		(width 0.10668)
		(layer "B.Cu")
		(net "ESPI_CPU0_R_D1")
	)
	(segment
		(start 375.390918 -303.28616)
		(end 375.390918 -303.56302)
		(width 0.10668)
		(layer "B.Cu")
		(net "ESPI_CPU0_R_D1")
	)
	(segment
		(start 376.038364 -301.867824)
		(end 376.038364 -302.09236)
		(width 0.10668)
		(layer "B.Cu")
		(net "ESPI_CPU0_R_D1")
	)
	(segment
		(start 374.067578 -295.325292)
		(end 373.706898 -295.685972)
		(width 0.10668)
		(layer "B.Cu")
		(net "ESPI_CPU0_R_D1")
	)
	(segment
		(start 383.62128 -314.99683)
		(end 383.526538 -315.091572)
		(width 0.10668)
		(layer "B.Cu")
		(net "ESPI_CPU0_R_D1")
	)
	(segment
		(start 375.688098 -307.404008)
		(end 382.335532 -314.051442)
		(width 0.10668)
		(layer "B.Cu")
		(net "ESPI_CPU0_R_D1")
	)
	(segment
		(start 375.497598 -303.6697)
		(end 375.931684 -303.6697)
		(width 0.10668)
		(layer "B.Cu")
		(net "ESPI_CPU0_R_D1")
	)
	(segment
		(start 373.602758 -294.535606)
		(end 374.067578 -295.000426)
		(width 0.10668)
		(layer "B.Cu")
		(net "ESPI_CPU0_R_D1")
	)
	(segment
		(start 384.3147 -315.69025)
		(end 384.219958 -315.784992)
		(width 0.10668)
		(layer "B.Cu")
		(net "ESPI_CPU0_R_D1")
	)
	(segment
		(start 384.219958 -315.784992)
		(end 384.219958 -315.935868)
		(width 0.10668)
		(layer "B.Cu")
		(net "ESPI_CPU0_R_D1")
	)
	(segment
		(start 374.067578 -295.000426)
		(end 374.067578 -295.325292)
		(width 0.10668)
		(layer "B.Cu")
		(net "ESPI_CPU0_R_D1")
	)
	(segment
		(start 376.038364 -303.77638)
		(end 376.038364 -304.811684)
		(width 0.10668)
		(layer "B.Cu")
		(net "ESPI_CPU0_R_D1")
	)
	(segment
		(start 375.390918 -302.30572)
		(end 375.390918 -302.58258)
		(width 0.10668)
		(layer "B.Cu")
		(net "ESPI_CPU0_R_D1")
	)
	(segment
		(start 382.335532 -314.051442)
		(end 382.486408 -314.051442)
		(width 0.10668)
		(layer "B.Cu")
		(net "ESPI_CPU0_R_D1")
	)
	(segment
		(start 373.174768 -293.718996)
		(end 373.602758 -294.146986)
		(width 0.10668)
		(layer "B.Cu")
		(net "ESPI_CPU0_R_D1")
	)
	(segment
		(start 382.833118 -314.398152)
		(end 382.833118 -314.549028)
		(width 0.10668)
		(layer "B.Cu")
		(net "ESPI_CPU0_R_D1")
	)
	(segment
		(start 383.27457 -314.65012)
		(end 383.425446 -314.65012)
		(width 0.10668)
		(layer "B.Cu")
		(net "ESPI_CPU0_R_D1")
	)
	(segment
		(start 373.706898 -296.95648)
		(end 374.214644 -297.464226)
		(width 0.10668)
		(layer "B.Cu")
		(net "ESPI_CPU0_R_D1")
	)
	(segment
		(start 383.526538 -315.242448)
		(end 383.722372 -315.438282)
		(width 0.10668)
		(layer "B.Cu")
		(net "ESPI_CPU0_R_D1")
	)
	(segment
		(start 383.96799 -315.34354)
		(end 384.118866 -315.34354)
		(width 0.10668)
		(layer "B.Cu")
		(net "ESPI_CPU0_R_D1")
	)
	(segment
		(start 383.526538 -315.091572)
		(end 383.526538 -315.242448)
		(width 0.10668)
		(layer "B.Cu")
		(net "ESPI_CPU0_R_D1")
	)
	(segment
		(start 373.602758 -294.146986)
		(end 373.602758 -294.535606)
		(width 0.10668)
		(layer "B.Cu")
		(net "ESPI_CPU0_R_D1")
	)
	(segment
		(start 376.038364 -302.79594)
		(end 376.038364 -303.0728)
		(width 0.10668)
		(layer "B.Cu")
		(net "ESPI_CPU0_R_D1")
	)
	(segment
		(start 388.711186 -321.179952)
		(end 389.331708 -321.179952)
		(width 0.10668)
		(layer "B.Cu")
		(net "ESPI_CPU0_R_D1")
	)
	(segment
		(start 373.174768 -292.71595)
		(end 373.174768 -293.718996)
		(width 0.10668)
		(layer "B.Cu")
		(net "ESPI_CPU0_R_D1")
	)
	(segment
		(start 375.390918 -303.56302)
		(end 375.497598 -303.6697)
		(width 0.10668)
		(layer "B.Cu")
		(net "ESPI_CPU0_R_D1")
	)
	(segment
		(start 375.931684 -302.68926)
		(end 376.038364 -302.79594)
		(width 0.10668)
		(layer "B.Cu")
		(net "ESPI_CPU0_R_D1")
	)
	(segment
		(start 373.17807 -294.88003)
		(end 373.644922 -295.145968)
		(width 0.10668)
		(layer "F.Cu")
		(net "ESPI_CPU0_R_D0")
	)
	(via
		(at 373.644922 -295.145968)
		(size 0.4064)
		(drill 0.2032)
		(layers "F.Cu" "B.Cu")
		(net "ESPI_CPU0_R_D0")
	)
	(via
		(at 374.801638 -302.960532)
		(size 0.6604)
		(drill 0.3302)
		(layers "F.Cu" "B.Cu")
		(net "ESPI_CPU0_R_D0")
	)
	(segment
		(start 373.83339 -297.718988)
		(end 374.801638 -300.056804)
		(width 0.10668)
		(layer "B.Cu")
		(net "ESPI_CPU0_R_D0")
	)
	(segment
		(start 375.131838 -305.482752)
		(end 373.701818 -305.482752)
		(width 0.10668)
		(layer "B.Cu")
		(net "ESPI_CPU0_R_D0")
	)
	(segment
		(start 374.694958 -305.972972)
		(end 374.801638 -306.079652)
		(width 0.10668)
		(layer "B.Cu")
		(net "ESPI_CPU0_R_D0")
	)
	(segment
		(start 375.238518 -305.099212)
		(end 375.238518 -305.376072)
		(width 0.10668)
		(layer "B.Cu")
		(net "ESPI_CPU0_R_D0")
	)
	(segment
		(start 373.727218 -303.521872)
		(end 373.620538 -303.628552)
		(width 0.10668)
		(layer "B.Cu")
		(net "ESPI_CPU0_R_D0")
	)
	(segment
		(start 392.371834 -323.692012)
		(end 393.202668 -323.692012)
		(width 0.10668)
		(layer "B.Cu")
		(net "ESPI_CPU0_R_D0")
	)
	(segment
		(start 374.801638 -302.960532)
		(end 374.801638 -303.415192)
		(width 0.10668)
		(layer "B.Cu")
		(net "ESPI_CPU0_R_D0")
	)
	(segment
		(start 373.191278 -296.625772)
		(end 373.191278 -297.076876)
		(width 0.10668)
		(layer "B.Cu")
		(net "ESPI_CPU0_R_D0")
	)
	(segment
		(start 374.801638 -307.153564)
		(end 384.334258 -316.686184)
		(width 0.10668)
		(layer "B.Cu")
		(net "ESPI_CPU0_R_D0")
	)
	(segment
		(start 373.701818 -305.482752)
		(end 373.595138 -305.589432)
		(width 0.10668)
		(layer "B.Cu")
		(net "ESPI_CPU0_R_D0")
	)
	(segment
		(start 375.206006 -304.012092)
		(end 375.312686 -304.118772)
		(width 0.10668)
		(layer "B.Cu")
		(net "ESPI_CPU0_R_D0")
	)
	(segment
		(start 373.595138 -305.866292)
		(end 373.701818 -305.972972)
		(width 0.10668)
		(layer "B.Cu")
		(net "ESPI_CPU0_R_D0")
	)
	(segment
		(start 373.620538 -303.905412)
		(end 373.727218 -304.012092)
		(width 0.10668)
		(layer "B.Cu")
		(net "ESPI_CPU0_R_D0")
	)
	(segment
		(start 373.727218 -304.502312)
		(end 373.620538 -304.608992)
		(width 0.10668)
		(layer "B.Cu")
		(net "ESPI_CPU0_R_D0")
	)
	(segment
		(start 375.238518 -305.376072)
		(end 375.131838 -305.482752)
		(width 0.10668)
		(layer "B.Cu")
		(net "ESPI_CPU0_R_D0")
	)
	(segment
		(start 374.801638 -306.079652)
		(end 374.801638 -307.153564)
		(width 0.10668)
		(layer "B.Cu")
		(net "ESPI_CPU0_R_D0")
	)
	(segment
		(start 373.727218 -304.992532)
		(end 375.131838 -304.992532)
		(width 0.10668)
		(layer "B.Cu")
		(net "ESPI_CPU0_R_D0")
	)
	(segment
		(start 374.801638 -300.056804)
		(end 374.801638 -302.960532)
		(width 0.10668)
		(layer "B.Cu")
		(net "ESPI_CPU0_R_D0")
	)
	(segment
		(start 390.494774 -321.814952)
		(end 392.371834 -323.692012)
		(width 0.10668)
		(layer "B.Cu")
		(net "ESPI_CPU0_R_D0")
	)
	(segment
		(start 373.620538 -303.628552)
		(end 373.620538 -303.905412)
		(width 0.10668)
		(layer "B.Cu")
		(net "ESPI_CPU0_R_D0")
	)
	(segment
		(start 375.312686 -304.118772)
		(end 375.312686 -304.395632)
		(width 0.10668)
		(layer "B.Cu")
		(net "ESPI_CPU0_R_D0")
	)
	(segment
		(start 373.644922 -295.145968)
		(end 373.404638 -295.386252)
		(width 0.10668)
		(layer "B.Cu")
		(net "ESPI_CPU0_R_D0")
	)
	(segment
		(start 373.404638 -295.386252)
		(end 373.404638 -296.412412)
		(width 0.10668)
		(layer "B.Cu")
		(net "ESPI_CPU0_R_D0")
	)
	(segment
		(start 375.206006 -304.502312)
		(end 373.727218 -304.502312)
		(width 0.10668)
		(layer "B.Cu")
		(net "ESPI_CPU0_R_D0")
	)
	(segment
		(start 373.595138 -305.589432)
		(end 373.595138 -305.866292)
		(width 0.10668)
		(layer "B.Cu")
		(net "ESPI_CPU0_R_D0")
	)
	(segment
		(start 388.71017 -321.814952)
		(end 390.494774 -321.814952)
		(width 0.10668)
		(layer "B.Cu")
		(net "ESPI_CPU0_R_D0")
	)
	(segment
		(start 373.620538 -304.608992)
		(end 373.620538 -304.885852)
		(width 0.10668)
		(layer "B.Cu")
		(net "ESPI_CPU0_R_D0")
	)
	(segment
		(start 375.131838 -304.992532)
		(end 375.238518 -305.099212)
		(width 0.10668)
		(layer "B.Cu")
		(net "ESPI_CPU0_R_D0")
	)
	(segment
		(start 384.334258 -317.43904)
		(end 388.71017 -321.814952)
		(width 0.10668)
		(layer "B.Cu")
		(net "ESPI_CPU0_R_D0")
	)
	(segment
		(start 374.801638 -303.415192)
		(end 374.694958 -303.521872)
		(width 0.10668)
		(layer "B.Cu")
		(net "ESPI_CPU0_R_D0")
	)
	(segment
		(start 373.701818 -305.972972)
		(end 374.694958 -305.972972)
		(width 0.10668)
		(layer "B.Cu")
		(net "ESPI_CPU0_R_D0")
	)
	(segment
		(start 373.404638 -296.412412)
		(end 373.191278 -296.625772)
		(width 0.10668)
		(layer "B.Cu")
		(net "ESPI_CPU0_R_D0")
	)
	(segment
		(start 374.694958 -303.521872)
		(end 373.727218 -303.521872)
		(width 0.10668)
		(layer "B.Cu")
		(net "ESPI_CPU0_R_D0")
	)
	(segment
		(start 384.334258 -316.686184)
		(end 384.334258 -317.43904)
		(width 0.10668)
		(layer "B.Cu")
		(net "ESPI_CPU0_R_D0")
	)
	(segment
		(start 373.620538 -304.885852)
		(end 373.727218 -304.992532)
		(width 0.10668)
		(layer "B.Cu")
		(net "ESPI_CPU0_R_D0")
	)
	(segment
		(start 375.312686 -304.395632)
		(end 375.206006 -304.502312)
		(width 0.10668)
		(layer "B.Cu")
		(net "ESPI_CPU0_R_D0")
	)
	(segment
		(start 373.191278 -297.076876)
		(end 373.83339 -297.718988)
		(width 0.10668)
		(layer "B.Cu")
		(net "ESPI_CPU0_R_D0")
	)
	(segment
		(start 373.727218 -304.012092)
		(end 375.206006 -304.012092)
		(width 0.10668)
		(layer "B.Cu")
		(net "ESPI_CPU0_R_D0")
	)
	(segment
		(start 381.775208 -315.747654)
		(end 381.926084 -315.747654)
		(width 0.10668)
		(layer "F.Cu")
		(net "ESPI_CPU0_R_CS1_N")
	)
	(segment
		(start 379.856492 -313.678062)
		(end 380.621032 -312.913522)
		(width 0.10668)
		(layer "F.Cu")
		(net "ESPI_CPU0_R_CS1_N")
	)
	(segment
		(start 393.356338 -327.890886)
		(end 394.658342 -327.890886)
		(width 0.10668)
		(layer "F.Cu")
		(net "ESPI_CPU0_R_CS1_N")
	)
	(segment
		(start 380.082044 -312.223658)
		(end 380.2761 -312.417714)
		(width 0.10668)
		(layer "F.Cu")
		(net "ESPI_CPU0_R_CS1_N")
	)
	(segment
		(start 381.494792 -313.570366)
		(end 381.688848 -313.764422)
		(width 0.10668)
		(layer "F.Cu")
		(net "ESPI_CPU0_R_CS1_N")
	)
	(segment
		(start 383.511552 -316.231778)
		(end 382.96088 -316.78245)
		(width 0.10668)
		(layer "F.Cu")
		(net "ESPI_CPU0_R_CS1_N")
	)
	(segment
		(start 380.2761 -312.417714)
		(end 380.2761 -312.56859)
		(width 0.10668)
		(layer "F.Cu")
		(net "ESPI_CPU0_R_CS1_N")
	)
	(segment
		(start 380.546356 -314.367926)
		(end 381.343916 -313.570366)
		(width 0.10668)
		(layer "F.Cu")
		(net "ESPI_CPU0_R_CS1_N")
	)
	(segment
		(start 373.64797 -295.690036)
		(end 373.64797 -297.137328)
		(width 0.10668)
		(layer "F.Cu")
		(net "ESPI_CPU0_R_CS1_N")
	)
	(segment
		(start 381.085344 -315.05779)
		(end 381.23622 -315.05779)
		(width 0.10668)
		(layer "F.Cu")
		(net "ESPI_CPU0_R_CS1_N")
	)
	(segment
		(start 381.688848 -313.764422)
		(end 381.688848 -313.915298)
		(width 0.10668)
		(layer "F.Cu")
		(net "ESPI_CPU0_R_CS1_N")
	)
	(segment
		(start 378.69495 -312.667396)
		(end 379.015752 -312.988198)
		(width 0.10668)
		(layer "F.Cu")
		(net "ESPI_CPU0_R_CS1_N")
	)
	(segment
		(start 395.312646 -326.20077)
		(end 396.355316 -325.1581)
		(width 0.10668)
		(layer "F.Cu")
		(net "ESPI_CPU0_R_CS1_N")
	)
	(segment
		(start 379.51156 -313.33313)
		(end 379.51156 -313.484006)
		(width 0.10668)
		(layer "F.Cu")
		(net "ESPI_CPU0_R_CS1_N")
	)
	(segment
		(start 382.175512 -314.269374)
		(end 382.369568 -314.46343)
		(width 0.10668)
		(layer "F.Cu")
		(net "ESPI_CPU0_R_CS1_N")
	)
	(segment
		(start 383.16662 -315.886846)
		(end 383.317496 -315.886846)
		(width 0.10668)
		(layer "F.Cu")
		(net "ESPI_CPU0_R_CS1_N")
	)
	(segment
		(start 382.465072 -316.437518)
		(end 382.615948 -316.437518)
		(width 0.10668)
		(layer "F.Cu")
		(net "ESPI_CPU0_R_CS1_N")
	)
	(segment
		(start 381.23622 -315.05779)
		(end 382.024636 -314.269374)
		(width 0.10668)
		(layer "F.Cu")
		(net "ESPI_CPU0_R_CS1_N")
	)
	(segment
		(start 382.96088 -316.78245)
		(end 382.96088 -316.933326)
		(width 0.10668)
		(layer "F.Cu")
		(net "ESPI_CPU0_R_CS1_N")
	)
	(segment
		(start 381.343916 -313.570366)
		(end 381.494792 -313.570366)
		(width 0.10668)
		(layer "F.Cu")
		(net "ESPI_CPU0_R_CS1_N")
	)
	(segment
		(start 387.960108 -321.932554)
		(end 387.960108 -322.494656)
		(width 0.10668)
		(layer "F.Cu")
		(net "ESPI_CPU0_R_CS1_N")
	)
	(segment
		(start 382.871472 -314.953142)
		(end 383.065528 -315.147198)
		(width 0.10668)
		(layer "F.Cu")
		(net "ESPI_CPU0_R_CS1_N")
	)
	(segment
		(start 382.024636 -314.269374)
		(end 382.175512 -314.269374)
		(width 0.10668)
		(layer "F.Cu")
		(net "ESPI_CPU0_R_CS1_N")
	)
	(segment
		(start 380.965964 -313.107578)
		(end 380.965964 -313.258454)
		(width 0.10668)
		(layer "F.Cu")
		(net "ESPI_CPU0_R_CS1_N")
	)
	(segment
		(start 387.960108 -322.494656)
		(end 393.356338 -327.890886)
		(width 0.10668)
		(layer "F.Cu")
		(net "ESPI_CPU0_R_CS1_N")
	)
	(segment
		(start 382.369568 -314.46343)
		(end 382.369568 -314.614306)
		(width 0.10668)
		(layer "F.Cu")
		(net "ESPI_CPU0_R_CS1_N")
	)
	(segment
		(start 383.511552 -316.080902)
		(end 383.511552 -316.231778)
		(width 0.10668)
		(layer "F.Cu")
		(net "ESPI_CPU0_R_CS1_N")
	)
	(segment
		(start 394.658342 -327.890886)
		(end 395.312646 -327.236582)
		(width 0.10668)
		(layer "F.Cu")
		(net "ESPI_CPU0_R_CS1_N")
	)
	(segment
		(start 380.771908 -312.913522)
		(end 380.965964 -313.107578)
		(width 0.10668)
		(layer "F.Cu")
		(net "ESPI_CPU0_R_CS1_N")
	)
	(segment
		(start 382.720596 -314.953142)
		(end 382.871472 -314.953142)
		(width 0.10668)
		(layer "F.Cu")
		(net "ESPI_CPU0_R_CS1_N")
	)
	(segment
		(start 382.271016 -316.243462)
		(end 382.465072 -316.437518)
		(width 0.10668)
		(layer "F.Cu")
		(net "ESPI_CPU0_R_CS1_N")
	)
	(segment
		(start 373.64797 -297.137328)
		(end 378.69495 -302.184308)
		(width 0.10668)
		(layer "F.Cu")
		(net "ESPI_CPU0_R_CS1_N")
	)
	(segment
		(start 379.166628 -312.988198)
		(end 379.931168 -312.223658)
		(width 0.10668)
		(layer "F.Cu")
		(net "ESPI_CPU0_R_CS1_N")
	)
	(segment
		(start 380.201424 -314.17387)
		(end 380.39548 -314.367926)
		(width 0.10668)
		(layer "F.Cu")
		(net "ESPI_CPU0_R_CS1_N")
	)
	(segment
		(start 380.965964 -313.258454)
		(end 380.201424 -314.022994)
		(width 0.10668)
		(layer "F.Cu")
		(net "ESPI_CPU0_R_CS1_N")
	)
	(segment
		(start 396.355316 -325.1581)
		(end 396.355316 -324.867016)
		(width 0.10668)
		(layer "F.Cu")
		(net "ESPI_CPU0_R_CS1_N")
	)
	(segment
		(start 380.2761 -312.56859)
		(end 379.51156 -313.33313)
		(width 0.10668)
		(layer "F.Cu")
		(net "ESPI_CPU0_R_CS1_N")
	)
	(segment
		(start 381.581152 -315.553598)
		(end 381.775208 -315.747654)
		(width 0.10668)
		(layer "F.Cu")
		(net "ESPI_CPU0_R_CS1_N")
	)
	(segment
		(start 379.015752 -312.988198)
		(end 379.166628 -312.988198)
		(width 0.10668)
		(layer "F.Cu")
		(net "ESPI_CPU0_R_CS1_N")
	)
	(segment
		(start 382.369568 -314.614306)
		(end 381.581152 -315.402722)
		(width 0.10668)
		(layer "F.Cu")
		(net "ESPI_CPU0_R_CS1_N")
	)
	(segment
		(start 382.615948 -316.437518)
		(end 383.16662 -315.886846)
		(width 0.10668)
		(layer "F.Cu")
		(net "ESPI_CPU0_R_CS1_N")
	)
	(segment
		(start 380.39548 -314.367926)
		(end 380.546356 -314.367926)
		(width 0.10668)
		(layer "F.Cu")
		(net "ESPI_CPU0_R_CS1_N")
	)
	(segment
		(start 380.621032 -312.913522)
		(end 380.771908 -312.913522)
		(width 0.10668)
		(layer "F.Cu")
		(net "ESPI_CPU0_R_CS1_N")
	)
	(segment
		(start 378.69495 -302.184308)
		(end 378.69495 -312.667396)
		(width 0.10668)
		(layer "F.Cu")
		(net "ESPI_CPU0_R_CS1_N")
	)
	(segment
		(start 382.271016 -316.092586)
		(end 382.271016 -316.243462)
		(width 0.10668)
		(layer "F.Cu")
		(net "ESPI_CPU0_R_CS1_N")
	)
	(segment
		(start 380.201424 -314.022994)
		(end 380.201424 -314.17387)
		(width 0.10668)
		(layer "F.Cu")
		(net "ESPI_CPU0_R_CS1_N")
	)
	(segment
		(start 381.688848 -313.915298)
		(end 380.891288 -314.712858)
		(width 0.10668)
		(layer "F.Cu")
		(net "ESPI_CPU0_R_CS1_N")
	)
	(segment
		(start 379.51156 -313.484006)
		(end 379.705616 -313.678062)
		(width 0.10668)
		(layer "F.Cu")
		(net "ESPI_CPU0_R_CS1_N")
	)
	(segment
		(start 395.312646 -327.236582)
		(end 395.312646 -326.20077)
		(width 0.10668)
		(layer "F.Cu")
		(net "ESPI_CPU0_R_CS1_N")
	)
	(segment
		(start 380.891288 -314.863734)
		(end 381.085344 -315.05779)
		(width 0.10668)
		(layer "F.Cu")
		(net "ESPI_CPU0_R_CS1_N")
	)
	(segment
		(start 379.705616 -313.678062)
		(end 379.856492 -313.678062)
		(width 0.10668)
		(layer "F.Cu")
		(net "ESPI_CPU0_R_CS1_N")
	)
	(segment
		(start 380.891288 -314.712858)
		(end 380.891288 -314.863734)
		(width 0.10668)
		(layer "F.Cu")
		(net "ESPI_CPU0_R_CS1_N")
	)
	(segment
		(start 379.931168 -312.223658)
		(end 380.082044 -312.223658)
		(width 0.10668)
		(layer "F.Cu")
		(net "ESPI_CPU0_R_CS1_N")
	)
	(segment
		(start 382.96088 -316.933326)
		(end 387.960108 -321.932554)
		(width 0.10668)
		(layer "F.Cu")
		(net "ESPI_CPU0_R_CS1_N")
	)
	(segment
		(start 381.926084 -315.747654)
		(end 382.720596 -314.953142)
		(width 0.10668)
		(layer "F.Cu")
		(net "ESPI_CPU0_R_CS1_N")
	)
	(segment
		(start 383.065528 -315.147198)
		(end 383.065528 -315.298074)
		(width 0.10668)
		(layer "F.Cu")
		(net "ESPI_CPU0_R_CS1_N")
	)
	(segment
		(start 381.581152 -315.402722)
		(end 381.581152 -315.553598)
		(width 0.10668)
		(layer "F.Cu")
		(net "ESPI_CPU0_R_CS1_N")
	)
	(segment
		(start 383.317496 -315.886846)
		(end 383.511552 -316.080902)
		(width 0.10668)
		(layer "F.Cu")
		(net "ESPI_CPU0_R_CS1_N")
	)
	(segment
		(start 383.065528 -315.298074)
		(end 382.271016 -316.092586)
		(width 0.10668)
		(layer "F.Cu")
		(net "ESPI_CPU0_R_CS1_N")
	)
	(via
		(at 396.355316 -324.867016)
		(size 0.508)
		(drill 0.254)
		(layers "F.Cu" "B.Cu")
		(net "ESPI_CPU0_R_CS1_N")
	)
	(segment
		(start 396.41018 -324.812152)
		(end 396.355316 -324.867016)
		(width 0.10668)
		(layer "B.Cu")
		(net "ESPI_CPU0_R_CS1_N")
	)
	(segment
		(start 397.480028 -324.812152)
		(end 396.41018 -324.812152)
		(width 0.10668)
		(layer "B.Cu")
		(net "ESPI_CPU0_R_CS1_N")
	)
	(segment
		(start 373.17807 -293.260018)
		(end 373.644922 -293.525956)
		(width 0.10668)
		(layer "F.Cu")
		(net "ESPI_CPU0_R_ALERT_N")
	)
	(via
		(at 387.995668 -316.188598)
		(size 0.6604)
		(drill 0.3302)
		(layers "F.Cu" "B.Cu")
		(net "ESPI_CPU0_R_ALERT_N")
	)
	(via
		(at 373.644922 -293.525956)
		(size 0.4064)
		(drill 0.2032)
		(layers "F.Cu" "B.Cu")
		(net "ESPI_CPU0_R_ALERT_N")
	)
	(segment
		(start 402.915628 -323.892672)
		(end 402.532596 -323.50964)
		(width 0.10668)
		(layer "B.Cu")
		(net "ESPI_CPU0_R_ALERT_N")
	)
	(segment
		(start 392.88593 -317.519812)
		(end 388.852156 -317.519812)
		(width 0.10668)
		(layer "B.Cu")
		(net "ESPI_CPU0_R_ALERT_N")
	)
	(segment
		(start 394.782548 -319.41643)
		(end 392.88593 -317.519812)
		(width 0.10668)
		(layer "B.Cu")
		(net "ESPI_CPU0_R_ALERT_N")
	)
	(segment
		(start 374.308878 -293.920672)
		(end 376.277378 -293.920672)
		(width 0.10668)
		(layer "B.Cu")
		(net "ESPI_CPU0_R_ALERT_N")
	)
	(segment
		(start 399.952718 -322.5292)
		(end 399.952718 -321.82308)
		(width 0.10668)
		(layer "B.Cu")
		(net "ESPI_CPU0_R_ALERT_N")
	)
	(segment
		(start 373.644922 -293.525956)
		(end 373.914162 -293.525956)
		(width 0.10668)
		(layer "B.Cu")
		(net "ESPI_CPU0_R_ALERT_N")
	)
	(segment
		(start 399.80616 -323.064886)
		(end 399.80616 -322.675758)
		(width 0.10668)
		(layer "B.Cu")
		(net "ESPI_CPU0_R_ALERT_N")
	)
	(segment
		(start 398.42948 -321.18808)
		(end 396.94104 -319.69964)
		(width 0.10668)
		(layer "B.Cu")
		(net "ESPI_CPU0_R_ALERT_N")
	)
	(segment
		(start 399.952718 -321.82308)
		(end 399.317718 -321.18808)
		(width 0.10668)
		(layer "B.Cu")
		(net "ESPI_CPU0_R_ALERT_N")
	)
	(segment
		(start 376.277378 -293.920672)
		(end 376.439938 -294.083232)
		(width 0.10668)
		(layer "B.Cu")
		(net "ESPI_CPU0_R_ALERT_N")
	)
	(segment
		(start 387.995668 -316.663324)
		(end 387.995668 -316.188598)
		(width 0.10668)
		(layer "B.Cu")
		(net "ESPI_CPU0_R_ALERT_N")
	)
	(segment
		(start 379.941074 -305.29657)
		(end 379.941074 -308.134004)
		(width 0.10668)
		(layer "B.Cu")
		(net "ESPI_CPU0_R_ALERT_N")
	)
	(segment
		(start 399.80616 -322.675758)
		(end 399.952718 -322.5292)
		(width 0.10668)
		(layer "B.Cu")
		(net "ESPI_CPU0_R_ALERT_N")
	)
	(segment
		(start 376.439938 -294.083232)
		(end 376.439938 -296.84218)
		(width 0.10668)
		(layer "B.Cu")
		(net "ESPI_CPU0_R_ALERT_N")
	)
	(segment
		(start 399.317718 -321.18808)
		(end 398.42948 -321.18808)
		(width 0.10668)
		(layer "B.Cu")
		(net "ESPI_CPU0_R_ALERT_N")
	)
	(segment
		(start 402.532596 -323.50964)
		(end 400.250914 -323.50964)
		(width 0.10668)
		(layer "B.Cu")
		(net "ESPI_CPU0_R_ALERT_N")
	)
	(segment
		(start 400.250914 -323.50964)
		(end 399.80616 -323.064886)
		(width 0.10668)
		(layer "B.Cu")
		(net "ESPI_CPU0_R_ALERT_N")
	)
	(segment
		(start 376.439938 -296.84218)
		(end 379.941074 -305.29657)
		(width 0.10668)
		(layer "B.Cu")
		(net "ESPI_CPU0_R_ALERT_N")
	)
	(segment
		(start 395.46657 -319.69964)
		(end 394.782548 -319.41643)
		(width 0.10668)
		(layer "B.Cu")
		(net "ESPI_CPU0_R_ALERT_N")
	)
	(segment
		(start 373.914162 -293.525956)
		(end 374.308878 -293.920672)
		(width 0.10668)
		(layer "B.Cu")
		(net "ESPI_CPU0_R_ALERT_N")
	)
	(segment
		(start 396.94104 -319.69964)
		(end 395.46657 -319.69964)
		(width 0.10668)
		(layer "B.Cu")
		(net "ESPI_CPU0_R_ALERT_N")
	)
	(segment
		(start 379.941074 -308.134004)
		(end 387.995668 -316.188598)
		(width 0.10668)
		(layer "B.Cu")
		(net "ESPI_CPU0_R_ALERT_N")
	)
	(segment
		(start 388.852156 -317.519812)
		(end 387.995668 -316.663324)
		(width 0.10668)
		(layer "B.Cu")
		(net "ESPI_CPU0_R_ALERT_N")
	)
	(segment
		(start 187.071 -137.232898)
		(end 187.071 -136.616948)
		(width 0.10668)
		(layer "F.Cu")
		(net "ESPI_CPU0_R1_D3")
	)
	(segment
		(start 187.522104 -119.452898)
		(end 187.911994 -119.842788)
		(width 0.10668)
		(layer "F.Cu")
		(net "ESPI_CPU0_R1_D3")
	)
	(via
		(at 187.911994 -119.842788)
		(size 0.4572)
		(drill 0.254)
		(layers "F.Cu" "B.Cu")
		(net "ESPI_CPU0_R1_D3")
	)
	(via
		(at 187.071 -136.616948)
		(size 0.508)
		(drill 0.254)
		(layers "F.Cu" "B.Cu")
		(net "ESPI_CPU0_R1_D3")
	)
	(segment
		(start 187.084208 -136.616948)
		(end 188.147452 -135.553704)
		(width 0.11684)
		(layer "In2.Cu")
		(net "ESPI_CPU0_R1_D3")
	)
	(segment
		(start 188.147452 -135.553704)
		(end 188.147452 -133.33857)
		(width 0.11684)
		(layer "In2.Cu")
		(net "ESPI_CPU0_R1_D3")
	)
	(segment
		(start 188.288168 -132.090414)
		(end 187.04814 -130.850386)
		(width 0.11684)
		(layer "In2.Cu")
		(net "ESPI_CPU0_R1_D3")
	)
	(segment
		(start 187.513468 -120.241314)
		(end 187.911994 -119.842788)
		(width 0.11684)
		(layer "In2.Cu")
		(net "ESPI_CPU0_R1_D3")
	)
	(segment
		(start 185.83402 -125.839982)
		(end 185.83402 -120.397016)
		(width 0.11684)
		(layer "In2.Cu")
		(net "ESPI_CPU0_R1_D3")
	)
	(segment
		(start 188.288168 -133.197854)
		(end 188.288168 -132.090414)
		(width 0.11684)
		(layer "In2.Cu")
		(net "ESPI_CPU0_R1_D3")
	)
	(segment
		(start 187.04814 -127.054102)
		(end 185.83402 -125.839982)
		(width 0.11684)
		(layer "In2.Cu")
		(net "ESPI_CPU0_R1_D3")
	)
	(segment
		(start 185.83402 -120.397016)
		(end 185.989722 -120.241314)
		(width 0.11684)
		(layer "In2.Cu")
		(net "ESPI_CPU0_R1_D3")
	)
	(segment
		(start 188.147452 -133.33857)
		(end 188.288168 -133.197854)
		(width 0.11684)
		(layer "In2.Cu")
		(net "ESPI_CPU0_R1_D3")
	)
	(segment
		(start 187.04814 -130.850386)
		(end 187.04814 -127.054102)
		(width 0.11684)
		(layer "In2.Cu")
		(net "ESPI_CPU0_R1_D3")
	)
	(segment
		(start 185.989722 -120.241314)
		(end 187.513468 -120.241314)
		(width 0.11684)
		(layer "In2.Cu")
		(net "ESPI_CPU0_R1_D3")
	)
	(segment
		(start 187.071 -136.616948)
		(end 187.084208 -136.616948)
		(width 0.11684)
		(layer "In2.Cu")
		(net "ESPI_CPU0_R1_D3")
	)
	(segment
		(start 187.522104 -120.252744)
		(end 187.911994 -120.642634)
		(width 0.10668)
		(layer "F.Cu")
		(net "ESPI_CPU0_R1_D2")
	)
	(segment
		(start 188.087 -138.032998)
		(end 188.087 -138.648948)
		(width 0.10668)
		(layer "F.Cu")
		(net "ESPI_CPU0_R1_D2")
	)
	(via
		(at 188.087 -138.648948)
		(size 0.508)
		(drill 0.254)
		(layers "F.Cu" "B.Cu")
		(net "ESPI_CPU0_R1_D2")
	)
	(via
		(at 187.911994 -120.642634)
		(size 0.4572)
		(drill 0.254)
		(layers "F.Cu" "B.Cu")
		(net "ESPI_CPU0_R1_D2")
	)
	(segment
		(start 188.32322 -126.063756)
		(end 188.32322 -121.05386)
		(width 0.11684)
		(layer "In11.Cu")
		(net "ESPI_CPU0_R1_D2")
	)
	(segment
		(start 186.869832 -139.225528)
		(end 186.63158 -138.987276)
		(width 0.11684)
		(layer "In11.Cu")
		(net "ESPI_CPU0_R1_D2")
	)
	(segment
		(start 188.32322 -121.05386)
		(end 187.911994 -120.642634)
		(width 0.11684)
		(layer "In11.Cu")
		(net "ESPI_CPU0_R1_D2")
	)
	(segment
		(start 188.891926 -131.342384)
		(end 188.142626 -131.342384)
		(width 0.11684)
		(layer "In11.Cu")
		(net "ESPI_CPU0_R1_D2")
	)
	(segment
		(start 188.087 -138.648948)
		(end 188.087 -138.76401)
		(width 0.11684)
		(layer "In11.Cu")
		(net "ESPI_CPU0_R1_D2")
	)
	(segment
		(start 186.63158 -134.323836)
		(end 186.846718 -134.108698)
		(width 0.11684)
		(layer "In11.Cu")
		(net "ESPI_CPU0_R1_D2")
	)
	(segment
		(start 188.142626 -131.342384)
		(end 187.456826 -130.656584)
		(width 0.11684)
		(layer "In11.Cu")
		(net "ESPI_CPU0_R1_D2")
	)
	(segment
		(start 188.087 -138.76401)
		(end 187.625482 -139.225528)
		(width 0.11684)
		(layer "In11.Cu")
		(net "ESPI_CPU0_R1_D2")
	)
	(segment
		(start 188.422788 -134.108698)
		(end 189.018926 -133.51256)
		(width 0.11684)
		(layer "In11.Cu")
		(net "ESPI_CPU0_R1_D2")
	)
	(segment
		(start 186.846718 -134.108698)
		(end 188.422788 -134.108698)
		(width 0.11684)
		(layer "In11.Cu")
		(net "ESPI_CPU0_R1_D2")
	)
	(segment
		(start 187.456826 -130.656584)
		(end 187.456826 -126.93015)
		(width 0.11684)
		(layer "In11.Cu")
		(net "ESPI_CPU0_R1_D2")
	)
	(segment
		(start 187.625482 -139.225528)
		(end 186.869832 -139.225528)
		(width 0.11684)
		(layer "In11.Cu")
		(net "ESPI_CPU0_R1_D2")
	)
	(segment
		(start 189.018926 -131.469384)
		(end 188.891926 -131.342384)
		(width 0.11684)
		(layer "In11.Cu")
		(net "ESPI_CPU0_R1_D2")
	)
	(segment
		(start 187.456826 -126.93015)
		(end 188.32322 -126.063756)
		(width 0.11684)
		(layer "In11.Cu")
		(net "ESPI_CPU0_R1_D2")
	)
	(segment
		(start 186.63158 -138.987276)
		(end 186.63158 -134.323836)
		(width 0.11684)
		(layer "In11.Cu")
		(net "ESPI_CPU0_R1_D2")
	)
	(segment
		(start 189.018926 -133.51256)
		(end 189.018926 -131.469384)
		(width 0.11684)
		(layer "In11.Cu")
		(net "ESPI_CPU0_R1_D2")
	)
	(segment
		(start 187.522104 -121.052844)
		(end 187.911994 -121.442734)
		(width 0.10668)
		(layer "F.Cu")
		(net "ESPI_CPU0_R1_D1")
	)
	(via
		(at 188.874908 -125.256036)
		(size 0.6604)
		(drill 0.3302)
		(layers "F.Cu" "B.Cu")
		(net "ESPI_CPU0_R1_D1")
	)
	(via
		(at 187.911994 -121.442734)
		(size 0.4572)
		(drill 0.254)
		(layers "F.Cu" "B.Cu")
		(net "ESPI_CPU0_R1_D1")
	)
	(segment
		(start 189.087506 -126.433326)
		(end 189.087506 -125.468634)
		(width 0.10668)
		(layer "B.Cu")
		(net "ESPI_CPU0_R1_D1")
	)
	(segment
		(start 189.151768 -124.628656)
		(end 189.151768 -123.63069)
		(width 0.10668)
		(layer "B.Cu")
		(net "ESPI_CPU0_R1_D1")
	)
	(segment
		(start 188.472572 -123.43892)
		(end 188.312806 -123.279154)
		(width 0.10668)
		(layer "B.Cu")
		(net "ESPI_CPU0_R1_D1")
	)
	(segment
		(start 189.087506 -125.468634)
		(end 188.874908 -125.256036)
		(width 0.10668)
		(layer "B.Cu")
		(net "ESPI_CPU0_R1_D1")
	)
	(segment
		(start 188.959998 -123.43892)
		(end 188.472572 -123.43892)
		(width 0.10668)
		(layer "B.Cu")
		(net "ESPI_CPU0_R1_D1")
	)
	(segment
		(start 187.911994 -121.656348)
		(end 187.911994 -121.442734)
		(width 0.10668)
		(layer "B.Cu")
		(net "ESPI_CPU0_R1_D1")
	)
	(segment
		(start 188.312806 -123.279154)
		(end 188.312806 -122.05716)
		(width 0.10668)
		(layer "B.Cu")
		(net "ESPI_CPU0_R1_D1")
	)
	(segment
		(start 188.312806 -122.05716)
		(end 187.911994 -121.656348)
		(width 0.10668)
		(layer "B.Cu")
		(net "ESPI_CPU0_R1_D1")
	)
	(segment
		(start 189.151768 -123.63069)
		(end 188.959998 -123.43892)
		(width 0.10668)
		(layer "B.Cu")
		(net "ESPI_CPU0_R1_D1")
	)
	(segment
		(start 188.874908 -124.905516)
		(end 189.151768 -124.628656)
		(width 0.10668)
		(layer "B.Cu")
		(net "ESPI_CPU0_R1_D1")
	)
	(segment
		(start 188.874908 -125.256036)
		(end 188.874908 -124.905516)
		(width 0.10668)
		(layer "B.Cu")
		(net "ESPI_CPU0_R1_D1")
	)
	(segment
		(start 189.12205 -122.65279)
		(end 189.51194 -123.04268)
		(width 0.10668)
		(layer "F.Cu")
		(net "ESPI_CPU0_R1_D0")
	)
	(via
		(at 194.183 -130.38836)
		(size 0.508)
		(drill 0.254)
		(layers "F.Cu" "B.Cu")
		(net "ESPI_CPU0_R1_D0")
	)
	(via
		(at 189.51194 -123.04268)
		(size 0.4572)
		(drill 0.254)
		(layers "F.Cu" "B.Cu")
		(net "ESPI_CPU0_R1_D0")
	)
	(segment
		(start 194.989958 -127.72263)
		(end 194.989958 -126.833376)
		(width 0.10668)
		(layer "B.Cu")
		(net "ESPI_CPU0_R1_D0")
	)
	(segment
		(start 194.183 -130.38836)
		(end 194.183 -128.529588)
		(width 0.10668)
		(layer "B.Cu")
		(net "ESPI_CPU0_R1_D0")
	)
	(segment
		(start 194.183 -128.529588)
		(end 194.989958 -127.72263)
		(width 0.10668)
		(layer "B.Cu")
		(net "ESPI_CPU0_R1_D0")
	)
	(segment
		(start 194.183 -130.38836)
		(end 191.943228 -128.148588)
		(width 0.11684)
		(layer "In6.Cu")
		(net "ESPI_CPU0_R1_D0")
	)
	(segment
		(start 191.943228 -128.148588)
		(end 191.943228 -125.473968)
		(width 0.11684)
		(layer "In6.Cu")
		(net "ESPI_CPU0_R1_D0")
	)
	(segment
		(start 191.943228 -125.473968)
		(end 189.51194 -123.04268)
		(width 0.11684)
		(layer "In6.Cu")
		(net "ESPI_CPU0_R1_D0")
	)
	(segment
		(start 174.66691 -16.549878)
		(end 174.66691 -18.593308)
		(width 0.10668)
		(layer "F.Cu")
		(net "ESPI_CPU0_D3")
	)
	(segment
		(start 187.071 -138.032998)
		(end 187.071 -138.606276)
		(width 0.10668)
		(layer "F.Cu")
		(net "ESPI_CPU0_D3")
	)
	(segment
		(start 187.071 -138.606276)
		(end 187.11418 -138.649456)
		(width 0.10668)
		(layer "F.Cu")
		(net "ESPI_CPU0_D3")
	)
	(via
		(at 187.11418 -138.649456)
		(size 0.508)
		(drill 0.254)
		(layers "F.Cu" "B.Cu")
		(net "ESPI_CPU0_D3")
	)
	(via
		(at 395.186408 -325.878952)
		(size 0.6604)
		(drill 0.3302)
		(layers "F.Cu" "B.Cu")
		(net "ESPI_CPU0_D3")
	)
	(via
		(at 396.031974 -326.93991)
		(size 0.508)
		(drill 0.254)
		(layers "F.Cu" "B.Cu")
		(net "ESPI_CPU0_D3")
	)
	(via
		(at 174.66691 -18.593308)
		(size 0.508)
		(drill 0.254)
		(layers "F.Cu" "B.Cu")
		(net "ESPI_CPU0_D3")
	)
	(segment
		(start 396.392908 -326.578976)
		(end 396.031974 -326.93991)
		(width 0.10668)
		(layer "B.Cu")
		(net "ESPI_CPU0_D3")
	)
	(segment
		(start 395.89964 -326.766682)
		(end 395.89964 -326.3392)
		(width 0.10668)
		(layer "B.Cu")
		(net "ESPI_CPU0_D3")
	)
	(segment
		(start 396.392908 -326.163432)
		(end 396.392908 -326.578976)
		(width 0.10668)
		(layer "B.Cu")
		(net "ESPI_CPU0_D3")
	)
	(segment
		(start 396.031974 -326.93991)
		(end 396.031974 -326.899016)
		(width 0.10668)
		(layer "B.Cu")
		(net "ESPI_CPU0_D3")
	)
	(segment
		(start 394.018008 -325.878952)
		(end 395.186408 -325.878952)
		(width 0.10668)
		(layer "B.Cu")
		(net "ESPI_CPU0_D3")
	)
	(segment
		(start 395.439392 -325.878952)
		(end 395.186408 -325.878952)
		(width 0.10668)
		(layer "B.Cu")
		(net "ESPI_CPU0_D3")
	)
	(segment
		(start 395.89964 -326.3392)
		(end 395.439392 -325.878952)
		(width 0.10668)
		(layer "B.Cu")
		(net "ESPI_CPU0_D3")
	)
	(segment
		(start 396.031974 -326.899016)
		(end 395.89964 -326.766682)
		(width 0.10668)
		(layer "B.Cu")
		(net "ESPI_CPU0_D3")
	)
	(segment
		(start 193.531236 -137.236708)
		(end 194.72656 -136.041384)
		(width 0.11684)
		(layer "In11.Cu")
		(net "ESPI_CPU0_D3")
	)
	(segment
		(start 178.801014 -38.490144)
		(end 176.58588 -38.490144)
		(width 0.11684)
		(layer "In11.Cu")
		(net "ESPI_CPU0_D3")
	)
	(segment
		(start 178.402996 -40.226996)
		(end 178.250088 -40.074088)
		(width 0.11684)
		(layer "In11.Cu")
		(net "ESPI_CPU0_D3")
	)
	(segment
		(start 182.33263 -42.02176)
		(end 182.179722 -41.868852)
		(width 0.11684)
		(layer "In11.Cu")
		(net "ESPI_CPU0_D3")
	)
	(segment
		(start 182.33263 -42.18686)
		(end 182.33263 -42.02176)
		(width 0.11684)
		(layer "In11.Cu")
		(net "ESPI_CPU0_D3")
	)
	(segment
		(start 198.697088 -103.282496)
		(end 198.697088 -101.628448)
		(width 0.11684)
		(layer "In11.Cu")
		(net "ESPI_CPU0_D3")
	)
	(segment
		(start 181.430168 -43.089068)
		(end 182.33263 -42.18686)
		(width 0.11684)
		(layer "In11.Cu")
		(net "ESPI_CPU0_D3")
	)
	(segment
		(start 180.90769 -40.59682)
		(end 180.74259 -40.59682)
		(width 0.11684)
		(layer "In11.Cu")
		(net "ESPI_CPU0_D3")
	)
	(segment
		(start 180.158136 -41.982136)
		(end 180.158136 -41.817036)
		(width 0.11684)
		(layer "In11.Cu")
		(net "ESPI_CPU0_D3")
	)
	(segment
		(start 179.840128 -41.499028)
		(end 179.675028 -41.499028)
		(width 0.11684)
		(layer "In11.Cu")
		(net "ESPI_CPU0_D3")
	)
	(segment
		(start 181.748176 -43.407076)
		(end 181.583076 -43.407076)
		(width 0.11684)
		(layer "In11.Cu")
		(net "ESPI_CPU0_D3")
	)
	(segment
		(start 180.158136 -41.817036)
		(end 181.060598 -40.914828)
		(width 0.11684)
		(layer "In11.Cu")
		(net "ESPI_CPU0_D3")
	)
	(segment
		(start 173.70044 -20.408138)
		(end 173.70044 -19.559778)
		(width 0.11684)
		(layer "In11.Cu")
		(net "ESPI_CPU0_D3")
	)
	(segment
		(start 182.179722 -41.868852)
		(end 182.014622 -41.868852)
		(width 0.11684)
		(layer "In11.Cu")
		(net "ESPI_CPU0_D3")
	)
	(segment
		(start 194.218052 -91.38539)
		(end 193.112898 -90.224864)
		(width 0.11684)
		(layer "In11.Cu")
		(net "ESPI_CPU0_D3")
	)
	(segment
		(start 200.383648 -106.207306)
		(end 198.441056 -104.264714)
		(width 0.11684)
		(layer "In11.Cu")
		(net "ESPI_CPU0_D3")
	)
	(segment
		(start 185.184542 -79.921862)
		(end 185.184542 -44.873672)
		(width 0.11684)
		(layer "In11.Cu")
		(net "ESPI_CPU0_D3")
	)
	(segment
		(start 179.039012 -40.863012)
		(end 178.886104 -40.710104)
		(width 0.11684)
		(layer "In11.Cu")
		(net "ESPI_CPU0_D3")
	)
	(segment
		(start 194.72656 -136.041384)
		(end 194.72656 -133.863588)
		(width 0.11684)
		(layer "In11.Cu")
		(net "ESPI_CPU0_D3")
	)
	(segment
		(start 182.014622 -41.868852)
		(end 181.11216 -42.77106)
		(width 0.11684)
		(layer "In11.Cu")
		(net "ESPI_CPU0_D3")
	)
	(segment
		(start 194.784472 -92.996004)
		(end 194.37223 -92.000832)
		(width 0.11684)
		(layer "In11.Cu")
		(net "ESPI_CPU0_D3")
	)
	(segment
		(start 182.815738 -42.504868)
		(end 182.650638 -42.504868)
		(width 0.11684)
		(layer "In11.Cu")
		(net "ESPI_CPU0_D3")
	)
	(segment
		(start 185.184542 -44.873672)
		(end 182.815738 -42.504868)
		(width 0.11684)
		(layer "In11.Cu")
		(net "ESPI_CPU0_D3")
	)
	(segment
		(start 180.271674 -39.960804)
		(end 180.106574 -39.960804)
		(width 0.11684)
		(layer "In11.Cu")
		(net "ESPI_CPU0_D3")
	)
	(segment
		(start 181.378606 -41.232836)
		(end 180.476144 -42.135044)
		(width 0.11684)
		(layer "In11.Cu")
		(net "ESPI_CPU0_D3")
	)
	(segment
		(start 179.470558 -39.324788)
		(end 178.568096 -40.226996)
		(width 0.11684)
		(layer "In11.Cu")
		(net "ESPI_CPU0_D3")
	)
	(segment
		(start 198.69912 -129.891028)
		(end 198.69912 -128.770888)
		(width 0.11684)
		(layer "In11.Cu")
		(net "ESPI_CPU0_D3")
	)
	(segment
		(start 181.696614 -41.385744)
		(end 181.543706 -41.232836)
		(width 0.11684)
		(layer "In11.Cu")
		(net "ESPI_CPU0_D3")
	)
	(segment
		(start 178.886104 -40.710104)
		(end 178.886104 -40.545004)
		(width 0.11684)
		(layer "In11.Cu")
		(net "ESPI_CPU0_D3")
	)
	(segment
		(start 173.70044 -19.559778)
		(end 174.66691 -18.593308)
		(width 0.11684)
		(layer "In11.Cu")
		(net "ESPI_CPU0_D3")
	)
	(segment
		(start 181.060598 -40.749728)
		(end 180.90769 -40.59682)
		(width 0.11684)
		(layer "In11.Cu")
		(net "ESPI_CPU0_D3")
	)
	(segment
		(start 179.788566 -39.642796)
		(end 179.788566 -39.477696)
		(width 0.11684)
		(layer "In11.Cu")
		(net "ESPI_CPU0_D3")
	)
	(segment
		(start 198.441056 -103.900732)
		(end 198.697088 -103.282496)
		(width 0.11684)
		(layer "In11.Cu")
		(net "ESPI_CPU0_D3")
	)
	(segment
		(start 181.060598 -40.914828)
		(end 181.060598 -40.749728)
		(width 0.11684)
		(layer "In11.Cu")
		(net "ESPI_CPU0_D3")
	)
	(segment
		(start 181.543706 -41.232836)
		(end 181.378606 -41.232836)
		(width 0.11684)
		(layer "In11.Cu")
		(net "ESPI_CPU0_D3")
	)
	(segment
		(start 178.886104 -40.545004)
		(end 179.788566 -39.642796)
		(width 0.11684)
		(layer "In11.Cu")
		(net "ESPI_CPU0_D3")
	)
	(segment
		(start 188.595254 -88.15578)
		(end 185.184542 -79.921862)
		(width 0.11684)
		(layer "In11.Cu")
		(net "ESPI_CPU0_D3")
	)
	(segment
		(start 187.774326 -136.068308)
		(end 188.4934 -136.068308)
		(width 0.11684)
		(layer "In11.Cu")
		(net "ESPI_CPU0_D3")
	)
	(segment
		(start 193.112898 -90.224864)
		(end 191.231012 -89.097104)
		(width 0.11684)
		(layer "In11.Cu")
		(net "ESPI_CPU0_D3")
	)
	(segment
		(start 187.11418 -138.649456)
		(end 187.11418 -138.605768)
		(width 0.11684)
		(layer "In11.Cu")
		(net "ESPI_CPU0_D3")
	)
	(segment
		(start 191.231012 -89.097104)
		(end 190.35141 -89.097104)
		(width 0.11684)
		(layer "In11.Cu")
		(net "ESPI_CPU0_D3")
	)
	(segment
		(start 180.94706 -42.77106)
		(end 180.794152 -42.618152)
		(width 0.11684)
		(layer "In11.Cu")
		(net "ESPI_CPU0_D3")
	)
	(segment
		(start 178.568096 -40.226996)
		(end 178.402996 -40.226996)
		(width 0.11684)
		(layer "In11.Cu")
		(net "ESPI_CPU0_D3")
	)
	(segment
		(start 174.070518 -20.778216)
		(end 173.70044 -20.408138)
		(width 0.11684)
		(layer "In11.Cu")
		(net "ESPI_CPU0_D3")
	)
	(segment
		(start 179.675028 -41.499028)
		(end 179.52212 -41.34612)
		(width 0.11684)
		(layer "In11.Cu")
		(net "ESPI_CPU0_D3")
	)
	(segment
		(start 187.56249 -136.280144)
		(end 187.774326 -136.068308)
		(width 0.11684)
		(layer "In11.Cu")
		(net "ESPI_CPU0_D3")
	)
	(segment
		(start 180.794152 -42.453052)
		(end 181.696614 -41.550844)
		(width 0.11684)
		(layer "In11.Cu")
		(net "ESPI_CPU0_D3")
	)
	(segment
		(start 188.4934 -136.068308)
		(end 189.6618 -137.236708)
		(width 0.11684)
		(layer "In11.Cu")
		(net "ESPI_CPU0_D3")
	)
	(segment
		(start 176.58588 -38.490144)
		(end 170.299888 -32.204152)
		(width 0.11684)
		(layer "In11.Cu")
		(net "ESPI_CPU0_D3")
	)
	(segment
		(start 198.69912 -128.770888)
		(end 200.82002 -126.649988)
		(width 0.11684)
		(layer "In11.Cu")
		(net "ESPI_CPU0_D3")
	)
	(segment
		(start 188.960506 -88.521032)
		(end 188.595254 -88.15578)
		(width 0.11684)
		(layer "In11.Cu")
		(net "ESPI_CPU0_D3")
	)
	(segment
		(start 180.794152 -42.618152)
		(end 180.794152 -42.453052)
		(width 0.11684)
		(layer "In11.Cu")
		(net "ESPI_CPU0_D3")
	)
	(segment
		(start 200.383648 -124.371608)
		(end 200.383648 -106.207306)
		(width 0.11684)
		(layer "In11.Cu")
		(net "ESPI_CPU0_D3")
	)
	(segment
		(start 179.204112 -40.863012)
		(end 179.039012 -40.863012)
		(width 0.11684)
		(layer "In11.Cu")
		(net "ESPI_CPU0_D3")
	)
	(segment
		(start 180.311044 -42.135044)
		(end 180.158136 -41.982136)
		(width 0.11684)
		(layer "In11.Cu")
		(net "ESPI_CPU0_D3")
	)
	(segment
		(start 194.72656 -133.863588)
		(end 198.69912 -129.891028)
		(width 0.11684)
		(layer "In11.Cu")
		(net "ESPI_CPU0_D3")
	)
	(segment
		(start 187.56249 -138.157458)
		(end 187.56249 -136.280144)
		(width 0.11684)
		(layer "In11.Cu")
		(net "ESPI_CPU0_D3")
	)
	(segment
		(start 181.11216 -42.77106)
		(end 180.94706 -42.77106)
		(width 0.11684)
		(layer "In11.Cu")
		(net "ESPI_CPU0_D3")
	)
	(segment
		(start 178.250088 -40.074088)
		(end 178.250088 -39.908988)
		(width 0.11684)
		(layer "In11.Cu")
		(net "ESPI_CPU0_D3")
	)
	(segment
		(start 190.35141 -89.097104)
		(end 188.960506 -88.521032)
		(width 0.11684)
		(layer "In11.Cu")
		(net "ESPI_CPU0_D3")
	)
	(segment
		(start 189.6618 -137.236708)
		(end 193.531236 -137.236708)
		(width 0.11684)
		(layer "In11.Cu")
		(net "ESPI_CPU0_D3")
	)
	(segment
		(start 182.650638 -42.504868)
		(end 181.748176 -43.407076)
		(width 0.11684)
		(layer "In11.Cu")
		(net "ESPI_CPU0_D3")
	)
	(segment
		(start 179.52212 -41.34612)
		(end 179.52212 -41.18102)
		(width 0.11684)
		(layer "In11.Cu")
		(net "ESPI_CPU0_D3")
	)
	(segment
		(start 180.424582 -40.113712)
		(end 180.271674 -39.960804)
		(width 0.11684)
		(layer "In11.Cu")
		(net "ESPI_CPU0_D3")
	)
	(segment
		(start 170.299888 -25.647396)
		(end 174.070518 -21.876766)
		(width 0.11684)
		(layer "In11.Cu")
		(net "ESPI_CPU0_D3")
	)
	(segment
		(start 200.82002 -124.80798)
		(end 200.383648 -124.371608)
		(width 0.11684)
		(layer "In11.Cu")
		(net "ESPI_CPU0_D3")
	)
	(segment
		(start 170.299888 -32.204152)
		(end 170.299888 -25.647396)
		(width 0.11684)
		(layer "In11.Cu")
		(net "ESPI_CPU0_D3")
	)
	(segment
		(start 179.52212 -41.18102)
		(end 180.424582 -40.278812)
		(width 0.11684)
		(layer "In11.Cu")
		(net "ESPI_CPU0_D3")
	)
	(segment
		(start 181.583076 -43.407076)
		(end 181.430168 -43.254168)
		(width 0.11684)
		(layer "In11.Cu")
		(net "ESPI_CPU0_D3")
	)
	(segment
		(start 180.106574 -39.960804)
		(end 179.204112 -40.863012)
		(width 0.11684)
		(layer "In11.Cu")
		(net "ESPI_CPU0_D3")
	)
	(segment
		(start 194.37223 -92.000832)
		(end 194.218052 -91.38539)
		(width 0.11684)
		(layer "In11.Cu")
		(net "ESPI_CPU0_D3")
	)
	(segment
		(start 174.070518 -21.876766)
		(end 174.070518 -20.778216)
		(width 0.11684)
		(layer "In11.Cu")
		(net "ESPI_CPU0_D3")
	)
	(segment
		(start 181.696614 -41.550844)
		(end 181.696614 -41.385744)
		(width 0.11684)
		(layer "In11.Cu")
		(net "ESPI_CPU0_D3")
	)
	(segment
		(start 179.15255 -38.84168)
		(end 178.801014 -38.490144)
		(width 0.11684)
		(layer "In11.Cu")
		(net "ESPI_CPU0_D3")
	)
	(segment
		(start 181.430168 -43.254168)
		(end 181.430168 -43.089068)
		(width 0.11684)
		(layer "In11.Cu")
		(net "ESPI_CPU0_D3")
	)
	(segment
		(start 180.74259 -40.59682)
		(end 179.840128 -41.499028)
		(width 0.11684)
		(layer "In11.Cu")
		(net "ESPI_CPU0_D3")
	)
	(segment
		(start 178.250088 -39.908988)
		(end 179.15255 -39.00678)
		(width 0.11684)
		(layer "In11.Cu")
		(net "ESPI_CPU0_D3")
	)
	(segment
		(start 180.476144 -42.135044)
		(end 180.311044 -42.135044)
		(width 0.11684)
		(layer "In11.Cu")
		(net "ESPI_CPU0_D3")
	)
	(segment
		(start 200.82002 -126.649988)
		(end 200.82002 -124.80798)
		(width 0.11684)
		(layer "In11.Cu")
		(net "ESPI_CPU0_D3")
	)
	(segment
		(start 198.697088 -101.628448)
		(end 195.670678 -94.321884)
		(width 0.11684)
		(layer "In11.Cu")
		(net "ESPI_CPU0_D3")
	)
	(segment
		(start 198.441056 -104.264714)
		(end 198.441056 -103.900732)
		(width 0.11684)
		(layer "In11.Cu")
		(net "ESPI_CPU0_D3")
	)
	(segment
		(start 179.15255 -39.00678)
		(end 179.15255 -38.84168)
		(width 0.11684)
		(layer "In11.Cu")
		(net "ESPI_CPU0_D3")
	)
	(segment
		(start 195.670678 -94.321884)
		(end 194.784472 -92.996004)
		(width 0.11684)
		(layer "In11.Cu")
		(net "ESPI_CPU0_D3")
	)
	(segment
		(start 179.788566 -39.477696)
		(end 179.635658 -39.324788)
		(width 0.11684)
		(layer "In11.Cu")
		(net "ESPI_CPU0_D3")
	)
	(segment
		(start 187.11418 -138.605768)
		(end 187.56249 -138.157458)
		(width 0.11684)
		(layer "In11.Cu")
		(net "ESPI_CPU0_D3")
	)
	(segment
		(start 180.424582 -40.278812)
		(end 180.424582 -40.113712)
		(width 0.11684)
		(layer "In11.Cu")
		(net "ESPI_CPU0_D3")
	)
	(segment
		(start 179.635658 -39.324788)
		(end 179.470558 -39.324788)
		(width 0.11684)
		(layer "In11.Cu")
		(net "ESPI_CPU0_D3")
	)
	(segment
		(start 392.709654 -313.721496)
		(end 393.041124 -314.052966)
		(width 0.11684)
		(layer "In15.Cu")
		(net "ESPI_CPU0_D3")
	)
	(segment
		(start 392.709654 -312.965338)
		(end 392.709654 -313.721496)
		(width 0.11684)
		(layer "In15.Cu")
		(net "ESPI_CPU0_D3")
	)
	(segment
		(start 393.609576 -319.670684)
		(end 392.794744 -320.485516)
		(width 0.11684)
		(layer "In15.Cu")
		(net "ESPI_CPU0_D3")
	)
	(segment
		(start 198.74103 -138.037062)
		(end 200.785984 -140.082016)
		(width 0.11684)
		(layer "In15.Cu")
		(net "ESPI_CPU0_D3")
	)
	(segment
		(start 330.50988 -177.796952)
		(end 369.936014 -217.223086)
		(width 0.11684)
		(layer "In15.Cu")
		(net "ESPI_CPU0_D3")
	)
	(segment
		(start 186.818524 -138.901424)
		(end 186.818524 -141.108938)
		(width 0.11684)
		(layer "In15.Cu")
		(net "ESPI_CPU0_D3")
	)
	(segment
		(start 395.964664 -326.8726)
		(end 396.031974 -326.93991)
		(width 0.11684)
		(layer "In15.Cu")
		(net "ESPI_CPU0_D3")
	)
	(segment
		(start 394.254736 -326.8726)
		(end 395.964664 -326.8726)
		(width 0.11684)
		(layer "In15.Cu")
		(net "ESPI_CPU0_D3")
	)
	(segment
		(start 395.10335 -219.419932)
		(end 396.712694 -221.029276)
		(width 0.11684)
		(layer "In15.Cu")
		(net "ESPI_CPU0_D3")
	)
	(segment
		(start 386.563616 -219.419932)
		(end 395.10335 -219.419932)
		(width 0.11684)
		(layer "In15.Cu")
		(net "ESPI_CPU0_D3")
	)
	(segment
		(start 187.070492 -138.649456)
		(end 186.818524 -138.901424)
		(width 0.11684)
		(layer "In15.Cu")
		(net "ESPI_CPU0_D3")
	)
	(segment
		(start 189.099952 -141.633194)
		(end 190.36284 -140.370306)
		(width 0.11684)
		(layer "In15.Cu")
		(net "ESPI_CPU0_D3")
	)
	(segment
		(start 393.147042 -315.688472)
		(end 393.147042 -318.134238)
		(width 0.11684)
		(layer "In15.Cu")
		(net "ESPI_CPU0_D3")
	)
	(segment
		(start 369.936014 -217.223086)
		(end 384.36677 -217.223086)
		(width 0.11684)
		(layer "In15.Cu")
		(net "ESPI_CPU0_D3")
	)
	(segment
		(start 392.794744 -320.485516)
		(end 392.794744 -322.947284)
		(width 0.11684)
		(layer "In15.Cu")
		(net "ESPI_CPU0_D3")
	)
	(segment
		(start 269.490698 -166.99611)
		(end 275.340572 -168.770808)
		(width 0.11684)
		(layer "In15.Cu")
		(net "ESPI_CPU0_D3")
	)
	(segment
		(start 186.818524 -141.108938)
		(end 187.34278 -141.633194)
		(width 0.11684)
		(layer "In15.Cu")
		(net "ESPI_CPU0_D3")
	)
	(segment
		(start 200.785984 -140.082016)
		(end 202.062842 -140.082016)
		(width 0.11684)
		(layer "In15.Cu")
		(net "ESPI_CPU0_D3")
	)
	(segment
		(start 393.40536 -318.757808)
		(end 393.609576 -318.962024)
		(width 0.11684)
		(layer "In15.Cu")
		(net "ESPI_CPU0_D3")
	)
	(segment
		(start 223.162876 -145.44548)
		(end 237.237778 -145.44548)
		(width 0.11684)
		(layer "In15.Cu")
		(net "ESPI_CPU0_D3")
	)
	(segment
		(start 393.147042 -318.134238)
		(end 393.40536 -318.757808)
		(width 0.11684)
		(layer "In15.Cu")
		(net "ESPI_CPU0_D3")
	)
	(segment
		(start 202.062842 -140.082016)
		(end 204.431646 -142.45082)
		(width 0.11684)
		(layer "In15.Cu")
		(net "ESPI_CPU0_D3")
	)
	(segment
		(start 308.718966 -168.770808)
		(end 330.50988 -177.796952)
		(width 0.11684)
		(layer "In15.Cu")
		(net "ESPI_CPU0_D3")
	)
	(segment
		(start 237.237778 -145.44548)
		(end 269.490698 -166.99611)
		(width 0.11684)
		(layer "In15.Cu")
		(net "ESPI_CPU0_D3")
	)
	(segment
		(start 194.53606 -140.370306)
		(end 195.475352 -139.431014)
		(width 0.11684)
		(layer "In15.Cu")
		(net "ESPI_CPU0_D3")
	)
	(segment
		(start 195.475352 -138.52906)
		(end 195.96735 -138.037062)
		(width 0.11684)
		(layer "In15.Cu")
		(net "ESPI_CPU0_D3")
	)
	(segment
		(start 393.503658 -323.656198)
		(end 393.503658 -325.108824)
		(width 0.11684)
		(layer "In15.Cu")
		(net "ESPI_CPU0_D3")
	)
	(segment
		(start 384.36677 -217.223086)
		(end 386.563616 -219.419932)
		(width 0.11684)
		(layer "In15.Cu")
		(net "ESPI_CPU0_D3")
	)
	(segment
		(start 392.794744 -322.947284)
		(end 393.503658 -323.656198)
		(width 0.11684)
		(layer "In15.Cu")
		(net "ESPI_CPU0_D3")
	)
	(segment
		(start 195.475352 -139.431014)
		(end 195.475352 -138.52906)
		(width 0.11684)
		(layer "In15.Cu")
		(net "ESPI_CPU0_D3")
	)
	(segment
		(start 393.041124 -314.052966)
		(end 393.041124 -315.582554)
		(width 0.11684)
		(layer "In15.Cu")
		(net "ESPI_CPU0_D3")
	)
	(segment
		(start 393.503658 -325.108824)
		(end 393.851892 -325.457058)
		(width 0.11684)
		(layer "In15.Cu")
		(net "ESPI_CPU0_D3")
	)
	(segment
		(start 393.609576 -318.962024)
		(end 393.609576 -319.670684)
		(width 0.11684)
		(layer "In15.Cu")
		(net "ESPI_CPU0_D3")
	)
	(segment
		(start 207.163924 -143.582644)
		(end 210.022948 -144.15135)
		(width 0.11684)
		(layer "In15.Cu")
		(net "ESPI_CPU0_D3")
	)
	(segment
		(start 204.431646 -142.45082)
		(end 207.163924 -143.582644)
		(width 0.11684)
		(layer "In15.Cu")
		(net "ESPI_CPU0_D3")
	)
	(segment
		(start 275.340572 -168.770808)
		(end 308.718966 -168.770808)
		(width 0.11684)
		(layer "In15.Cu")
		(net "ESPI_CPU0_D3")
	)
	(segment
		(start 210.022948 -144.15135)
		(end 223.162876 -145.44548)
		(width 0.11684)
		(layer "In15.Cu")
		(net "ESPI_CPU0_D3")
	)
	(segment
		(start 187.34278 -141.633194)
		(end 189.099952 -141.633194)
		(width 0.11684)
		(layer "In15.Cu")
		(net "ESPI_CPU0_D3")
	)
	(segment
		(start 187.11418 -138.649456)
		(end 187.070492 -138.649456)
		(width 0.11684)
		(layer "In15.Cu")
		(net "ESPI_CPU0_D3")
	)
	(segment
		(start 393.041124 -315.582554)
		(end 393.147042 -315.688472)
		(width 0.11684)
		(layer "In15.Cu")
		(net "ESPI_CPU0_D3")
	)
	(segment
		(start 396.712694 -221.029276)
		(end 396.712694 -308.962298)
		(width 0.11684)
		(layer "In15.Cu")
		(net "ESPI_CPU0_D3")
	)
	(segment
		(start 393.851892 -325.457058)
		(end 393.851892 -326.469756)
		(width 0.11684)
		(layer "In15.Cu")
		(net "ESPI_CPU0_D3")
	)
	(segment
		(start 195.96735 -138.037062)
		(end 198.74103 -138.037062)
		(width 0.11684)
		(layer "In15.Cu")
		(net "ESPI_CPU0_D3")
	)
	(segment
		(start 393.851892 -326.469756)
		(end 394.254736 -326.8726)
		(width 0.11684)
		(layer "In15.Cu")
		(net "ESPI_CPU0_D3")
	)
	(segment
		(start 190.36284 -140.370306)
		(end 194.53606 -140.370306)
		(width 0.11684)
		(layer "In15.Cu")
		(net "ESPI_CPU0_D3")
	)
	(segment
		(start 396.712694 -308.962298)
		(end 392.709654 -312.965338)
		(width 0.11684)
		(layer "In15.Cu")
		(net "ESPI_CPU0_D3")
	)
	(segment
		(start 188.087 -137.232898)
		(end 188.087 -136.616948)
		(width 0.10668)
		(layer "F.Cu")
		(net "ESPI_CPU0_D2")
	)
	(segment
		(start 175.267112 -16.549878)
		(end 175.267112 -17.816068)
		(width 0.10668)
		(layer "F.Cu")
		(net "ESPI_CPU0_D2")
	)
	(segment
		(start 394.811758 -324.196202)
		(end 394.811758 -324.805802)
		(width 0.10668)
		(layer "F.Cu")
		(net "ESPI_CPU0_D2")
	)
	(via
		(at 175.267112 -17.816068)
		(size 0.508)
		(drill 0.254)
		(layers "F.Cu" "B.Cu")
		(net "ESPI_CPU0_D2")
	)
	(via
		(at 394.811758 -324.805802)
		(size 0.508)
		(drill 0.254)
		(layers "F.Cu" "B.Cu")
		(net "ESPI_CPU0_D2")
	)
	(via
		(at 188.087 -136.616948)
		(size 0.508)
		(drill 0.254)
		(layers "F.Cu" "B.Cu")
		(net "ESPI_CPU0_D2")
	)
	(segment
		(start 394.018008 -324.862952)
		(end 394.297408 -325.142352)
		(width 0.10668)
		(layer "B.Cu")
		(net "ESPI_CPU0_D2")
	)
	(segment
		(start 394.297408 -325.142352)
		(end 394.475208 -325.142352)
		(width 0.10668)
		(layer "B.Cu")
		(net "ESPI_CPU0_D2")
	)
	(segment
		(start 394.475208 -325.142352)
		(end 394.811758 -324.805802)
		(width 0.10668)
		(layer "B.Cu")
		(net "ESPI_CPU0_D2")
	)
	(segment
		(start 176.760632 -38.068504)
		(end 178.975766 -38.068504)
		(width 0.11684)
		(layer "In11.Cu")
		(net "ESPI_CPU0_D2")
	)
	(segment
		(start 199.066658 -131.878578)
		(end 199.066658 -132.043678)
		(width 0.11684)
		(layer "In11.Cu")
		(net "ESPI_CPU0_D2")
	)
	(segment
		(start 200.805288 -124.135896)
		(end 201.33056 -124.661168)
		(width 0.11684)
		(layer "In11.Cu")
		(net "ESPI_CPU0_D2")
	)
	(segment
		(start 183.85028 -40.770048)
		(end 184.01538 -40.770048)
		(width 0.11684)
		(layer "In11.Cu")
		(net "ESPI_CPU0_D2")
	)
	(segment
		(start 199.129142 -101.569012)
		(end 199.129142 -103.040434)
		(width 0.11684)
		(layer "In11.Cu")
		(net "ESPI_CPU0_D2")
	)
	(segment
		(start 200.805288 -105.61574)
		(end 200.805288 -124.135896)
		(width 0.11684)
		(layer "In11.Cu")
		(net "ESPI_CPU0_D2")
	)
	(segment
		(start 181.892448 -40.985186)
		(end 182.045356 -41.138094)
		(width 0.11684)
		(layer "In11.Cu")
		(net "ESPI_CPU0_D2")
	)
	(segment
		(start 201.33056 -129.779776)
		(end 200.821798 -130.288538)
		(width 0.11684)
		(layer "In11.Cu")
		(net "ESPI_CPU0_D2")
	)
	(segment
		(start 180.773324 -39.866062)
		(end 180.938424 -39.866062)
		(width 0.11684)
		(layer "In11.Cu")
		(net "ESPI_CPU0_D2")
	)
	(segment
		(start 182.681372 -41.77411)
		(end 182.846472 -41.77411)
		(width 0.11684)
		(layer "In11.Cu")
		(net "ESPI_CPU0_D2")
	)
	(segment
		(start 182.578248 -39.498016)
		(end 182.743348 -39.498016)
		(width 0.11684)
		(layer "In11.Cu")
		(net "ESPI_CPU0_D2")
	)
	(segment
		(start 195.1482 -136.216136)
		(end 193.705988 -137.658348)
		(width 0.11684)
		(layer "In11.Cu")
		(net "ESPI_CPU0_D2")
	)
	(segment
		(start 180.302408 -39.230046)
		(end 181.306216 -38.225984)
		(width 0.11684)
		(layer "In11.Cu")
		(net "ESPI_CPU0_D2")
	)
	(segment
		(start 189.1284 -137.658348)
		(end 188.087 -136.616948)
		(width 0.11684)
		(layer "In11.Cu")
		(net "ESPI_CPU0_D2")
	)
	(segment
		(start 182.743348 -39.498016)
		(end 182.896256 -39.650924)
		(width 0.11684)
		(layer "In11.Cu")
		(net "ESPI_CPU0_D2")
	)
	(segment
		(start 170.721528 -32.0294)
		(end 176.760632 -38.068504)
		(width 0.11684)
		(layer "In11.Cu")
		(net "ESPI_CPU0_D2")
	)
	(segment
		(start 184.01538 -40.770048)
		(end 184.168288 -40.922956)
		(width 0.11684)
		(layer "In11.Cu")
		(net "ESPI_CPU0_D2")
	)
	(segment
		(start 195.656962 -91.903804)
		(end 196.512688 -93.96984)
		(width 0.11684)
		(layer "In11.Cu")
		(net "ESPI_CPU0_D2")
	)
	(segment
		(start 183.482488 -42.410126)
		(end 184.486296 -41.406064)
		(width 0.11684)
		(layer "In11.Cu")
		(net "ESPI_CPU0_D2")
	)
	(segment
		(start 170.721528 -25.822148)
		(end 170.721528 -32.0294)
		(width 0.11684)
		(layer "In11.Cu")
		(net "ESPI_CPU0_D2")
	)
	(segment
		(start 197.794626 -133.31571)
		(end 197.477888 -133.632448)
		(width 0.11684)
		(layer "In11.Cu")
		(net "ESPI_CPU0_D2")
	)
	(segment
		(start 185.122312 -42.04208)
		(end 185.287412 -42.04208)
		(width 0.11684)
		(layer "In11.Cu")
		(net "ESPI_CPU0_D2")
	)
	(segment
		(start 181.306216 -38.225984)
		(end 181.471316 -38.225984)
		(width 0.11684)
		(layer "In11.Cu")
		(net "ESPI_CPU0_D2")
	)
	(segment
		(start 182.896256 -39.816024)
		(end 181.892448 -40.820086)
		(width 0.11684)
		(layer "In11.Cu")
		(net "ESPI_CPU0_D2")
	)
	(segment
		(start 189.62624 -87.267288)
		(end 189.811914 -87.715598)
		(width 0.11684)
		(layer "In11.Cu")
		(net "ESPI_CPU0_D2")
	)
	(segment
		(start 184.436512 -43.36415)
		(end 184.436512 -43.52925)
		(width 0.11684)
		(layer "In11.Cu")
		(net "ESPI_CPU0_D2")
	)
	(segment
		(start 199.224392 -130.128264)
		(end 199.059292 -130.128264)
		(width 0.11684)
		(layer "In11.Cu")
		(net "ESPI_CPU0_D2")
	)
	(segment
		(start 181.624224 -38.378892)
		(end 181.624224 -38.543992)
		(width 0.11684)
		(layer "In11.Cu")
		(net "ESPI_CPU0_D2")
	)
	(segment
		(start 200.185782 -130.924554)
		(end 200.020682 -130.924554)
		(width 0.11684)
		(layer "In11.Cu")
		(net "ESPI_CPU0_D2")
	)
	(segment
		(start 181.892448 -40.820086)
		(end 181.892448 -40.985186)
		(width 0.11684)
		(layer "In11.Cu")
		(net "ESPI_CPU0_D2")
	)
	(segment
		(start 175.38446 -19.385534)
		(end 175.38446 -21.159216)
		(width 0.11684)
		(layer "In11.Cu")
		(net "ESPI_CPU0_D2")
	)
	(segment
		(start 181.40934 -40.502078)
		(end 181.57444 -40.502078)
		(width 0.11684)
		(layer "In11.Cu")
		(net "ESPI_CPU0_D2")
	)
	(segment
		(start 184.651396 -41.406064)
		(end 184.804304 -41.558972)
		(width 0.11684)
		(layer "In11.Cu")
		(net "ESPI_CPU0_D2")
	)
	(segment
		(start 200.020682 -130.924554)
		(end 199.224392 -130.128264)
		(width 0.11684)
		(layer "In11.Cu")
		(net "ESPI_CPU0_D2")
	)
	(segment
		(start 199.702674 -131.407662)
		(end 199.549766 -131.56057)
		(width 0.11684)
		(layer "In11.Cu")
		(net "ESPI_CPU0_D2")
	)
	(segment
		(start 175.38446 -21.159216)
		(end 170.721528 -25.822148)
		(width 0.11684)
		(layer "In11.Cu")
		(net "ESPI_CPU0_D2")
	)
	(segment
		(start 182.528464 -41.456102)
		(end 182.528464 -41.621202)
		(width 0.11684)
		(layer "In11.Cu")
		(net "ESPI_CPU0_D2")
	)
	(segment
		(start 181.471316 -38.225984)
		(end 181.624224 -38.378892)
		(width 0.11684)
		(layer "In11.Cu")
		(net "ESPI_CPU0_D2")
	)
	(segment
		(start 198.270368 -131.082288)
		(end 199.066658 -131.878578)
		(width 0.11684)
		(layer "In11.Cu")
		(net "ESPI_CPU0_D2")
	)
	(segment
		(start 180.137308 -39.230046)
		(end 180.302408 -39.230046)
		(width 0.11684)
		(layer "In11.Cu")
		(net "ESPI_CPU0_D2")
	)
	(segment
		(start 183.16448 -42.257218)
		(end 183.317388 -42.410126)
		(width 0.11684)
		(layer "In11.Cu")
		(net "ESPI_CPU0_D2")
	)
	(segment
		(start 183.532272 -40.28694)
		(end 183.532272 -40.45204)
		(width 0.11684)
		(layer "In11.Cu")
		(net "ESPI_CPU0_D2")
	)
	(segment
		(start 181.57444 -40.502078)
		(end 182.578248 -39.498016)
		(width 0.11684)
		(layer "In11.Cu")
		(net "ESPI_CPU0_D2")
	)
	(segment
		(start 185.287412 -42.04208)
		(end 185.44032 -42.194988)
		(width 0.11684)
		(layer "In11.Cu")
		(net "ESPI_CPU0_D2")
	)
	(segment
		(start 198.277734 -132.832602)
		(end 198.112634 -132.832602)
		(width 0.11684)
		(layer "In11.Cu")
		(net "ESPI_CPU0_D2")
	)
	(segment
		(start 201.33056 -124.661168)
		(end 201.33056 -129.779776)
		(width 0.11684)
		(layer "In11.Cu")
		(net "ESPI_CPU0_D2")
	)
	(segment
		(start 195.1482 -134.067296)
		(end 195.1482 -136.216136)
		(width 0.11684)
		(layer "In11.Cu")
		(net "ESPI_CPU0_D2")
	)
	(segment
		(start 197.151244 -132.036312)
		(end 196.998336 -132.18922)
		(width 0.11684)
		(layer "In11.Cu")
		(net "ESPI_CPU0_D2")
	)
	(segment
		(start 183.532272 -40.45204)
		(end 182.528464 -41.456102)
		(width 0.11684)
		(layer "In11.Cu")
		(net "ESPI_CPU0_D2")
	)
	(segment
		(start 190.889382 -88.46185)
		(end 193.152268 -89.39911)
		(width 0.11684)
		(layer "In11.Cu")
		(net "ESPI_CPU0_D2")
	)
	(segment
		(start 184.168288 -40.922956)
		(end 184.168288 -41.088056)
		(width 0.11684)
		(layer "In11.Cu")
		(net "ESPI_CPU0_D2")
	)
	(segment
		(start 190.558166 -88.46185)
		(end 190.889382 -88.46185)
		(width 0.11684)
		(layer "In11.Cu")
		(net "ESPI_CPU0_D2")
	)
	(segment
		(start 185.44032 -42.194988)
		(end 185.44032 -42.360088)
		(width 0.11684)
		(layer "In11.Cu")
		(net "ESPI_CPU0_D2")
	)
	(segment
		(start 185.44032 -42.360088)
		(end 184.436512 -43.36415)
		(width 0.11684)
		(layer "In11.Cu")
		(net "ESPI_CPU0_D2")
	)
	(segment
		(start 200.33869 -130.606546)
		(end 200.33869 -130.771646)
		(width 0.11684)
		(layer "In11.Cu")
		(net "ESPI_CPU0_D2")
	)
	(segment
		(start 182.107332 -38.862)
		(end 182.26024 -39.014908)
		(width 0.11684)
		(layer "In11.Cu")
		(net "ESPI_CPU0_D2")
	)
	(segment
		(start 184.436512 -43.52925)
		(end 185.606182 -44.69892)
		(width 0.11684)
		(layer "In11.Cu")
		(net "ESPI_CPU0_D2")
	)
	(segment
		(start 181.624224 -38.543992)
		(end 180.620416 -39.548054)
		(width 0.11684)
		(layer "In11.Cu")
		(net "ESPI_CPU0_D2")
	)
	(segment
		(start 184.486296 -41.406064)
		(end 184.651396 -41.406064)
		(width 0.11684)
		(layer "In11.Cu")
		(net "ESPI_CPU0_D2")
	)
	(segment
		(start 183.800496 -42.728134)
		(end 183.800496 -42.893234)
		(width 0.11684)
		(layer "In11.Cu")
		(net "ESPI_CPU0_D2")
	)
	(segment
		(start 200.656698 -130.288538)
		(end 199.762364 -129.394204)
		(width 0.11684)
		(layer "In11.Cu")
		(net "ESPI_CPU0_D2")
	)
	(segment
		(start 199.457564 -103.83393)
		(end 200.498456 -104.874822)
		(width 0.11684)
		(layer "In11.Cu")
		(net "ESPI_CPU0_D2")
	)
	(segment
		(start 196.512688 -93.96984)
		(end 196.512688 -95.252032)
		(width 0.11684)
		(layer "In11.Cu")
		(net "ESPI_CPU0_D2")
	)
	(segment
		(start 198.423276 -130.76428)
		(end 198.270368 -130.917188)
		(width 0.11684)
		(layer "In11.Cu")
		(net "ESPI_CPU0_D2")
	)
	(segment
		(start 197.78726 -131.400296)
		(end 197.634352 -131.553204)
		(width 0.11684)
		(layer "In11.Cu")
		(net "ESPI_CPU0_D2")
	)
	(segment
		(start 183.953404 -43.046142)
		(end 184.118504 -43.046142)
		(width 0.11684)
		(layer "In11.Cu")
		(net "ESPI_CPU0_D2")
	)
	(segment
		(start 182.528464 -41.621202)
		(end 182.681372 -41.77411)
		(width 0.11684)
		(layer "In11.Cu")
		(net "ESPI_CPU0_D2")
	)
	(segment
		(start 185.606182 -75.67295)
		(end 189.32906 -84.66074)
		(width 0.11684)
		(layer "In11.Cu")
		(net "ESPI_CPU0_D2")
	)
	(segment
		(start 199.597264 -129.394204)
		(end 199.444356 -129.547112)
		(width 0.11684)
		(layer "In11.Cu")
		(net "ESPI_CPU0_D2")
	)
	(segment
		(start 180.620416 -39.548054)
		(end 180.620416 -39.713154)
		(width 0.11684)
		(layer "In11.Cu")
		(net "ESPI_CPU0_D2")
	)
	(segment
		(start 181.256432 -40.34917)
		(end 181.40934 -40.502078)
		(width 0.11684)
		(layer "In11.Cu")
		(net "ESPI_CPU0_D2")
	)
	(segment
		(start 198.270368 -130.917188)
		(end 198.270368 -131.082288)
		(width 0.11684)
		(layer "In11.Cu")
		(net "ESPI_CPU0_D2")
	)
	(segment
		(start 193.152268 -89.39911)
		(end 195.656962 -91.903804)
		(width 0.11684)
		(layer "In11.Cu")
		(net "ESPI_CPU0_D2")
	)
	(segment
		(start 182.045356 -41.138094)
		(end 182.210456 -41.138094)
		(width 0.11684)
		(layer "In11.Cu")
		(net "ESPI_CPU0_D2")
	)
	(segment
		(start 182.26024 -39.014908)
		(end 182.26024 -39.180008)
		(width 0.11684)
		(layer "In11.Cu")
		(net "ESPI_CPU0_D2")
	)
	(segment
		(start 198.74865 -132.196586)
		(end 197.95236 -131.400296)
		(width 0.11684)
		(layer "In11.Cu")
		(net "ESPI_CPU0_D2")
	)
	(segment
		(start 182.846472 -41.77411)
		(end 183.85028 -40.770048)
		(width 0.11684)
		(layer "In11.Cu")
		(net "ESPI_CPU0_D2")
	)
	(segment
		(start 193.705988 -137.658348)
		(end 189.1284 -137.658348)
		(width 0.11684)
		(layer "In11.Cu")
		(net "ESPI_CPU0_D2")
	)
	(segment
		(start 197.634352 -131.718304)
		(end 198.430642 -132.514594)
		(width 0.11684)
		(layer "In11.Cu")
		(net "ESPI_CPU0_D2")
	)
	(segment
		(start 198.430642 -132.679694)
		(end 198.277734 -132.832602)
		(width 0.11684)
		(layer "In11.Cu")
		(net "ESPI_CPU0_D2")
	)
	(segment
		(start 197.477888 -133.632448)
		(end 195.583048 -133.632448)
		(width 0.11684)
		(layer "In11.Cu")
		(net "ESPI_CPU0_D2")
	)
	(segment
		(start 184.118504 -43.046142)
		(end 185.122312 -42.04208)
		(width 0.11684)
		(layer "In11.Cu")
		(net "ESPI_CPU0_D2")
	)
	(segment
		(start 199.702674 -131.242562)
		(end 199.702674 -131.407662)
		(width 0.11684)
		(layer "In11.Cu")
		(net "ESPI_CPU0_D2")
	)
	(segment
		(start 199.384666 -131.56057)
		(end 198.588376 -130.76428)
		(width 0.11684)
		(layer "In11.Cu")
		(net "ESPI_CPU0_D2")
	)
	(segment
		(start 197.316344 -132.036312)
		(end 197.151244 -132.036312)
		(width 0.11684)
		(layer "In11.Cu")
		(net "ESPI_CPU0_D2")
	)
	(segment
		(start 175.267112 -19.268186)
		(end 175.38446 -19.385534)
		(width 0.11684)
		(layer "In11.Cu")
		(net "ESPI_CPU0_D2")
	)
	(segment
		(start 183.800496 -42.893234)
		(end 183.953404 -43.046142)
		(width 0.11684)
		(layer "In11.Cu")
		(net "ESPI_CPU0_D2")
	)
	(segment
		(start 199.129142 -103.040434)
		(end 199.457564 -103.83393)
		(width 0.11684)
		(layer "In11.Cu")
		(net "ESPI_CPU0_D2")
	)
	(segment
		(start 197.794626 -133.15061)
		(end 197.794626 -133.31571)
		(width 0.11684)
		(layer "In11.Cu")
		(net "ESPI_CPU0_D2")
	)
	(segment
		(start 184.804304 -41.724072)
		(end 183.800496 -42.728134)
		(width 0.11684)
		(layer "In11.Cu")
		(net "ESPI_CPU0_D2")
	)
	(segment
		(start 200.821798 -130.288538)
		(end 200.656698 -130.288538)
		(width 0.11684)
		(layer "In11.Cu")
		(net "ESPI_CPU0_D2")
	)
	(segment
		(start 182.26024 -39.180008)
		(end 181.256432 -40.18407)
		(width 0.11684)
		(layer "In11.Cu")
		(net "ESPI_CPU0_D2")
	)
	(segment
		(start 199.059292 -130.128264)
		(end 198.906384 -130.281172)
		(width 0.11684)
		(layer "In11.Cu")
		(net "ESPI_CPU0_D2")
	)
	(segment
		(start 183.16448 -42.092118)
		(end 183.16448 -42.257218)
		(width 0.11684)
		(layer "In11.Cu")
		(net "ESPI_CPU0_D2")
	)
	(segment
		(start 182.896256 -39.650924)
		(end 182.896256 -39.816024)
		(width 0.11684)
		(layer "In11.Cu")
		(net "ESPI_CPU0_D2")
	)
	(segment
		(start 185.606182 -44.69892)
		(end 185.606182 -75.67295)
		(width 0.11684)
		(layer "In11.Cu")
		(net "ESPI_CPU0_D2")
	)
	(segment
		(start 182.210456 -41.138094)
		(end 183.214264 -40.134032)
		(width 0.11684)
		(layer "In11.Cu")
		(net "ESPI_CPU0_D2")
	)
	(segment
		(start 198.112634 -132.832602)
		(end 197.316344 -132.036312)
		(width 0.11684)
		(layer "In11.Cu")
		(net "ESPI_CPU0_D2")
	)
	(segment
		(start 196.512688 -95.252032)
		(end 199.129142 -101.569012)
		(width 0.11684)
		(layer "In11.Cu")
		(net "ESPI_CPU0_D2")
	)
	(segment
		(start 189.32906 -86.970108)
		(end 189.62624 -87.267288)
		(width 0.11684)
		(layer "In11.Cu")
		(net "ESPI_CPU0_D2")
	)
	(segment
		(start 181.256432 -40.18407)
		(end 181.256432 -40.34917)
		(width 0.11684)
		(layer "In11.Cu")
		(net "ESPI_CPU0_D2")
	)
	(segment
		(start 198.906384 -130.281172)
		(end 198.906384 -130.446272)
		(width 0.11684)
		(layer "In11.Cu")
		(net "ESPI_CPU0_D2")
	)
	(segment
		(start 198.91375 -132.196586)
		(end 198.74865 -132.196586)
		(width 0.11684)
		(layer "In11.Cu")
		(net "ESPI_CPU0_D2")
	)
	(segment
		(start 196.998336 -132.35432)
		(end 197.794626 -133.15061)
		(width 0.11684)
		(layer "In11.Cu")
		(net "ESPI_CPU0_D2")
	)
	(segment
		(start 184.168288 -41.088056)
		(end 183.16448 -42.092118)
		(width 0.11684)
		(layer "In11.Cu")
		(net "ESPI_CPU0_D2")
	)
	(segment
		(start 189.811914 -87.715598)
		(end 190.558166 -88.46185)
		(width 0.11684)
		(layer "In11.Cu")
		(net "ESPI_CPU0_D2")
	)
	(segment
		(start 199.444356 -129.547112)
		(end 199.444356 -129.712212)
		(width 0.11684)
		(layer "In11.Cu")
		(net "ESPI_CPU0_D2")
	)
	(segment
		(start 183.379364 -40.134032)
		(end 183.532272 -40.28694)
		(width 0.11684)
		(layer "In11.Cu")
		(net "ESPI_CPU0_D2")
	)
	(segment
		(start 195.583048 -133.632448)
		(end 195.1482 -134.067296)
		(width 0.11684)
		(layer "In11.Cu")
		(net "ESPI_CPU0_D2")
	)
	(segment
		(start 196.998336 -132.18922)
		(end 196.998336 -132.35432)
		(width 0.11684)
		(layer "In11.Cu")
		(net "ESPI_CPU0_D2")
	)
	(segment
		(start 184.804304 -41.558972)
		(end 184.804304 -41.724072)
		(width 0.11684)
		(layer "In11.Cu")
		(net "ESPI_CPU0_D2")
	)
	(segment
		(start 197.634352 -131.553204)
		(end 197.634352 -131.718304)
		(width 0.11684)
		(layer "In11.Cu")
		(net "ESPI_CPU0_D2")
	)
	(segment
		(start 180.620416 -39.713154)
		(end 180.773324 -39.866062)
		(width 0.11684)
		(layer "In11.Cu")
		(net "ESPI_CPU0_D2")
	)
	(segment
		(start 181.942232 -38.862)
		(end 182.107332 -38.862)
		(width 0.11684)
		(layer "In11.Cu")
		(net "ESPI_CPU0_D2")
	)
	(segment
		(start 199.066658 -132.043678)
		(end 198.91375 -132.196586)
		(width 0.11684)
		(layer "In11.Cu")
		(net "ESPI_CPU0_D2")
	)
	(segment
		(start 198.430642 -132.514594)
		(end 198.430642 -132.679694)
		(width 0.11684)
		(layer "In11.Cu")
		(net "ESPI_CPU0_D2")
	)
	(segment
		(start 199.549766 -131.56057)
		(end 199.384666 -131.56057)
		(width 0.11684)
		(layer "In11.Cu")
		(net "ESPI_CPU0_D2")
	)
	(segment
		(start 200.498456 -104.874822)
		(end 200.805288 -105.61574)
		(width 0.11684)
		(layer "In11.Cu")
		(net "ESPI_CPU0_D2")
	)
	(segment
		(start 199.762364 -129.394204)
		(end 199.597264 -129.394204)
		(width 0.11684)
		(layer "In11.Cu")
		(net "ESPI_CPU0_D2")
	)
	(segment
		(start 183.214264 -40.134032)
		(end 183.379364 -40.134032)
		(width 0.11684)
		(layer "In11.Cu")
		(net "ESPI_CPU0_D2")
	)
	(segment
		(start 198.906384 -130.446272)
		(end 199.702674 -131.242562)
		(width 0.11684)
		(layer "In11.Cu")
		(net "ESPI_CPU0_D2")
	)
	(segment
		(start 183.317388 -42.410126)
		(end 183.482488 -42.410126)
		(width 0.11684)
		(layer "In11.Cu")
		(net "ESPI_CPU0_D2")
	)
	(segment
		(start 199.444356 -129.712212)
		(end 200.33869 -130.606546)
		(width 0.11684)
		(layer "In11.Cu")
		(net "ESPI_CPU0_D2")
	)
	(segment
		(start 189.32906 -84.66074)
		(end 189.32906 -86.970108)
		(width 0.11684)
		(layer "In11.Cu")
		(net "ESPI_CPU0_D2")
	)
	(segment
		(start 200.33869 -130.771646)
		(end 200.185782 -130.924554)
		(width 0.11684)
		(layer "In11.Cu")
		(net "ESPI_CPU0_D2")
	)
	(segment
		(start 180.938424 -39.866062)
		(end 181.942232 -38.862)
		(width 0.11684)
		(layer "In11.Cu")
		(net "ESPI_CPU0_D2")
	)
	(segment
		(start 198.588376 -130.76428)
		(end 198.423276 -130.76428)
		(width 0.11684)
		(layer "In11.Cu")
		(net "ESPI_CPU0_D2")
	)
	(segment
		(start 175.267112 -17.816068)
		(end 175.267112 -19.268186)
		(width 0.11684)
		(layer "In11.Cu")
		(net "ESPI_CPU0_D2")
	)
	(segment
		(start 178.975766 -38.068504)
		(end 180.137308 -39.230046)
		(width 0.11684)
		(layer "In11.Cu")
		(net "ESPI_CPU0_D2")
	)
	(segment
		(start 197.95236 -131.400296)
		(end 197.78726 -131.400296)
		(width 0.11684)
		(layer "In11.Cu")
		(net "ESPI_CPU0_D2")
	)
	(segment
		(start 384.716274 -216.379806)
		(end 370.285518 -216.379806)
		(width 0.11684)
		(layer "In15.Cu")
		(net "ESPI_CPU0_D2")
	)
	(segment
		(start 202.287124 -138.914124)
		(end 200.810876 -138.914124)
		(width 0.11684)
		(layer "In15.Cu")
		(net "ESPI_CPU0_D2")
	)
	(segment
		(start 394.811758 -323.771514)
		(end 393.638024 -322.59778)
		(width 0.11684)
		(layer "In15.Cu")
		(net "ESPI_CPU0_D2")
	)
	(segment
		(start 395.078966 -311.78881)
		(end 397.555974 -309.311802)
		(width 0.11684)
		(layer "In15.Cu")
		(net "ESPI_CPU0_D2")
	)
	(segment
		(start 269.950946 -166.254176)
		(end 237.546134 -144.6022)
		(width 0.11684)
		(layer "In15.Cu")
		(net "ESPI_CPU0_D2")
	)
	(segment
		(start 195.457572 -136.766808)
		(end 194.092322 -138.132058)
		(width 0.11684)
		(layer "In15.Cu")
		(net "ESPI_CPU0_D2")
	)
	(segment
		(start 200.810876 -138.914124)
		(end 198.66356 -136.766808)
		(width 0.11684)
		(layer "In15.Cu")
		(net "ESPI_CPU0_D2")
	)
	(segment
		(start 393.638024 -322.59778)
		(end 393.638024 -320.902584)
		(width 0.11684)
		(layer "In15.Cu")
		(net "ESPI_CPU0_D2")
	)
	(segment
		(start 190.443612 -139.15898)
		(end 188.876686 -139.15898)
		(width 0.11684)
		(layer "In15.Cu")
		(net "ESPI_CPU0_D2")
	)
	(segment
		(start 209.106262 -143.030702)
		(end 207.96504 -142.803626)
		(width 0.11684)
		(layer "In15.Cu")
		(net "ESPI_CPU0_D2")
	)
	(segment
		(start 394.571982 -313.812682)
		(end 395.078966 -313.305698)
		(width 0.11684)
		(layer "In15.Cu")
		(net "ESPI_CPU0_D2")
	)
	(segment
		(start 190.685674 -138.308842)
		(end 190.685674 -138.916918)
		(width 0.11684)
		(layer "In15.Cu")
		(net "ESPI_CPU0_D2")
	)
	(segment
		(start 397.555974 -220.679772)
		(end 395.452854 -218.576652)
		(width 0.11684)
		(layer "In15.Cu")
		(net "ESPI_CPU0_D2")
	)
	(segment
		(start 188.604144 -138.22807)
		(end 188.087 -137.710926)
		(width 0.11684)
		(layer "In15.Cu")
		(net "ESPI_CPU0_D2")
	)
	(segment
		(start 370.285518 -216.379806)
		(end 330.987146 -177.081434)
		(width 0.11684)
		(layer "In15.Cu")
		(net "ESPI_CPU0_D2")
	)
	(segment
		(start 188.087 -137.710926)
		(end 188.087 -136.616948)
		(width 0.11684)
		(layer "In15.Cu")
		(net "ESPI_CPU0_D2")
	)
	(segment
		(start 394.571982 -314.807854)
		(end 394.571982 -313.812682)
		(width 0.11684)
		(layer "In15.Cu")
		(net "ESPI_CPU0_D2")
	)
	(segment
		(start 393.99845 -315.381386)
		(end 394.571982 -314.807854)
		(width 0.11684)
		(layer "In15.Cu")
		(net "ESPI_CPU0_D2")
	)
	(segment
		(start 190.685674 -138.916918)
		(end 190.443612 -139.15898)
		(width 0.11684)
		(layer "In15.Cu")
		(net "ESPI_CPU0_D2")
	)
	(segment
		(start 194.092322 -138.132058)
		(end 190.862458 -138.132058)
		(width 0.11684)
		(layer "In15.Cu")
		(net "ESPI_CPU0_D2")
	)
	(segment
		(start 190.862458 -138.132058)
		(end 190.685674 -138.308842)
		(width 0.11684)
		(layer "In15.Cu")
		(net "ESPI_CPU0_D2")
	)
	(segment
		(start 397.555974 -309.311802)
		(end 397.555974 -220.679772)
		(width 0.11684)
		(layer "In15.Cu")
		(net "ESPI_CPU0_D2")
	)
	(segment
		(start 394.811758 -324.805802)
		(end 394.811758 -323.771514)
		(width 0.11684)
		(layer "In15.Cu")
		(net "ESPI_CPU0_D2")
	)
	(segment
		(start 393.99845 -317.922402)
		(end 393.99845 -315.381386)
		(width 0.11684)
		(layer "In15.Cu")
		(net "ESPI_CPU0_D2")
	)
	(segment
		(start 386.91312 -218.576652)
		(end 384.716274 -216.379806)
		(width 0.11684)
		(layer "In15.Cu")
		(net "ESPI_CPU0_D2")
	)
	(segment
		(start 308.887622 -167.927528)
		(end 275.46681 -167.927528)
		(width 0.11684)
		(layer "In15.Cu")
		(net "ESPI_CPU0_D2")
	)
	(segment
		(start 188.604144 -138.886438)
		(end 188.604144 -138.22807)
		(width 0.11684)
		(layer "In15.Cu")
		(net "ESPI_CPU0_D2")
	)
	(segment
		(start 393.638024 -320.902584)
		(end 394.497814 -320.042794)
		(width 0.11684)
		(layer "In15.Cu")
		(net "ESPI_CPU0_D2")
	)
	(segment
		(start 394.497814 -320.042794)
		(end 394.497814 -318.60109)
		(width 0.11684)
		(layer "In15.Cu")
		(net "ESPI_CPU0_D2")
	)
	(segment
		(start 204.91196 -141.53896)
		(end 202.287124 -138.914124)
		(width 0.11684)
		(layer "In15.Cu")
		(net "ESPI_CPU0_D2")
	)
	(segment
		(start 275.46681 -167.927528)
		(end 269.950946 -166.254176)
		(width 0.11684)
		(layer "In15.Cu")
		(net "ESPI_CPU0_D2")
	)
	(segment
		(start 395.078966 -313.305698)
		(end 395.078966 -311.78881)
		(width 0.11684)
		(layer "In15.Cu")
		(net "ESPI_CPU0_D2")
	)
	(segment
		(start 225.06305 -144.6022)
		(end 209.106262 -143.030702)
		(width 0.11684)
		(layer "In15.Cu")
		(net "ESPI_CPU0_D2")
	)
	(segment
		(start 207.96504 -142.803626)
		(end 204.91196 -141.53896)
		(width 0.11684)
		(layer "In15.Cu")
		(net "ESPI_CPU0_D2")
	)
	(segment
		(start 188.876686 -139.15898)
		(end 188.604144 -138.886438)
		(width 0.11684)
		(layer "In15.Cu")
		(net "ESPI_CPU0_D2")
	)
	(segment
		(start 237.546134 -144.6022)
		(end 225.06305 -144.6022)
		(width 0.11684)
		(layer "In15.Cu")
		(net "ESPI_CPU0_D2")
	)
	(segment
		(start 330.987146 -177.081434)
		(end 308.887622 -167.927528)
		(width 0.11684)
		(layer "In15.Cu")
		(net "ESPI_CPU0_D2")
	)
	(segment
		(start 395.452854 -218.576652)
		(end 386.91312 -218.576652)
		(width 0.11684)
		(layer "In15.Cu")
		(net "ESPI_CPU0_D2")
	)
	(segment
		(start 394.125196 -318.228472)
		(end 393.99845 -317.922402)
		(width 0.11684)
		(layer "In15.Cu")
		(net "ESPI_CPU0_D2")
	)
	(segment
		(start 394.497814 -318.60109)
		(end 394.125196 -318.228472)
		(width 0.11684)
		(layer "In15.Cu")
		(net "ESPI_CPU0_D2")
	)
	(segment
		(start 198.66356 -136.766808)
		(end 195.457572 -136.766808)
		(width 0.11684)
		(layer "In15.Cu")
		(net "ESPI_CPU0_D2")
	)
	(segment
		(start 397.526002 -323.351398)
		(end 396.729458 -322.554854)
		(width 0.10668)
		(layer "F.Cu")
		(net "ESPI_CPU0_D1")
	)
	(segment
		(start 397.526002 -323.45503)
		(end 397.526002 -323.351398)
		(width 0.10668)
		(layer "F.Cu")
		(net "ESPI_CPU0_D1")
	)
	(segment
		(start 175.86706 -16.549878)
		(end 175.86706 -18.463768)
		(width 0.10668)
		(layer "F.Cu")
		(net "ESPI_CPU0_D1")
	)
	(via
		(at 175.86706 -18.463768)
		(size 0.508)
		(drill 0.254)
		(layers "F.Cu" "B.Cu")
		(net "ESPI_CPU0_D1")
	)
	(via
		(at 392.049762 -322.405756)
		(size 0.6604)
		(drill 0.3302)
		(layers "F.Cu" "B.Cu")
		(net "ESPI_CPU0_D1")
	)
	(via
		(at 189.39383 -138.65352)
		(size 0.508)
		(drill 0.254)
		(layers "F.Cu" "B.Cu")
		(net "ESPI_CPU0_D1")
	)
	(via
		(at 396.729458 -322.554854)
		(size 0.508)
		(drill 0.254)
		(layers "F.Cu" "B.Cu")
		(net "ESPI_CPU0_D1")
	)
	(segment
		(start 189.404498 -133.028436)
		(end 189.404498 -132.00634)
		(width 0.10668)
		(layer "B.Cu")
		(net "ESPI_CPU0_D1")
	)
	(segment
		(start 392.706098 -323.062092)
		(end 395.44498 -323.062092)
		(width 0.10668)
		(layer "B.Cu")
		(net "ESPI_CPU0_D1")
	)
	(segment
		(start 189.404498 -132.00634)
		(end 189.160658 -131.7625)
		(width 0.10668)
		(layer "B.Cu")
		(net "ESPI_CPU0_D1")
	)
	(segment
		(start 396.669514 -322.554854)
		(end 396.729458 -322.554854)
		(width 0.10668)
		(layer "B.Cu")
		(net "ESPI_CPU0_D1")
	)
	(segment
		(start 390.131808 -321.179952)
		(end 390.496044 -321.179952)
		(width 0.10668)
		(layer "B.Cu")
		(net "ESPI_CPU0_D1")
	)
	(segment
		(start 189.611 -130.546348)
		(end 189.611 -129.774696)
		(width 0.10668)
		(layer "B.Cu")
		(net "ESPI_CPU0_D1")
	)
	(segment
		(start 189.39383 -138.65352)
		(end 190.672466 -137.374884)
		(width 0.10668)
		(layer "B.Cu")
		(net "ESPI_CPU0_D1")
	)
	(segment
		(start 189.087506 -129.251202)
		(end 189.087506 -127.233426)
		(width 0.10668)
		(layer "B.Cu")
		(net "ESPI_CPU0_D1")
	)
	(segment
		(start 395.44498 -323.062092)
		(end 396.669514 -322.554854)
		(width 0.10668)
		(layer "B.Cu")
		(net "ESPI_CPU0_D1")
	)
	(segment
		(start 390.496044 -321.179952)
		(end 391.029444 -321.713352)
		(width 0.10668)
		(layer "B.Cu")
		(net "ESPI_CPU0_D1")
	)
	(segment
		(start 189.160658 -130.99669)
		(end 189.611 -130.546348)
		(width 0.10668)
		(layer "B.Cu")
		(net "ESPI_CPU0_D1")
	)
	(segment
		(start 190.672466 -134.296404)
		(end 189.404498 -133.028436)
		(width 0.10668)
		(layer "B.Cu")
		(net "ESPI_CPU0_D1")
	)
	(segment
		(start 392.049762 -322.405756)
		(end 392.706098 -323.062092)
		(width 0.10668)
		(layer "B.Cu")
		(net "ESPI_CPU0_D1")
	)
	(segment
		(start 189.160658 -131.7625)
		(end 189.160658 -130.99669)
		(width 0.10668)
		(layer "B.Cu")
		(net "ESPI_CPU0_D1")
	)
	(segment
		(start 391.029444 -321.713352)
		(end 391.357358 -321.713352)
		(width 0.10668)
		(layer "B.Cu")
		(net "ESPI_CPU0_D1")
	)
	(segment
		(start 189.611 -129.774696)
		(end 189.087506 -129.251202)
		(width 0.10668)
		(layer "B.Cu")
		(net "ESPI_CPU0_D1")
	)
	(segment
		(start 190.672466 -137.374884)
		(end 190.672466 -134.296404)
		(width 0.10668)
		(layer "B.Cu")
		(net "ESPI_CPU0_D1")
	)
	(segment
		(start 391.357358 -321.713352)
		(end 392.049762 -322.405756)
		(width 0.10668)
		(layer "B.Cu")
		(net "ESPI_CPU0_D1")
	)
	(segment
		(start 201.226928 -105.531412)
		(end 201.226928 -123.886976)
		(width 0.11684)
		(layer "In11.Cu")
		(net "ESPI_CPU0_D1")
	)
	(segment
		(start 199.207882 -97.628456)
		(end 199.969374 -101.457252)
		(width 0.11684)
		(layer "In11.Cu")
		(net "ESPI_CPU0_D1")
	)
	(segment
		(start 189.39383 -138.467846)
		(end 189.39383 -138.65352)
		(width 0.11684)
		(layer "In11.Cu")
		(net "ESPI_CPU0_D1")
	)
	(segment
		(start 186.027822 -75.416664)
		(end 188.962538 -82.501994)
		(width 0.11684)
		(layer "In11.Cu")
		(net "ESPI_CPU0_D1")
	)
	(segment
		(start 177.388266 -37.530024)
		(end 177.388266 -37.13226)
		(width 0.11684)
		(layer "In11.Cu")
		(net "ESPI_CPU0_D1")
	)
	(segment
		(start 171.143168 -31.854648)
		(end 176.935384 -37.646864)
		(width 0.11684)
		(layer "In11.Cu")
		(net "ESPI_CPU0_D1")
	)
	(segment
		(start 175.8061 -18.524728)
		(end 175.8061 -21.333968)
		(width 0.11684)
		(layer "In11.Cu")
		(net "ESPI_CPU0_D1")
	)
	(segment
		(start 177.837846 -37.530024)
		(end 177.954686 -37.646864)
		(width 0.11684)
		(layer "In11.Cu")
		(net "ESPI_CPU0_D1")
	)
	(segment
		(start 192.917572 -87.92464)
		(end 196.793866 -91.800934)
		(width 0.11684)
		(layer "In11.Cu")
		(net "ESPI_CPU0_D1")
	)
	(segment
		(start 191.34582 -84.885276)
		(end 191.34582 -85.856318)
		(width 0.11684)
		(layer "In11.Cu")
		(net "ESPI_CPU0_D1")
	)
	(segment
		(start 177.505106 -37.01542)
		(end 177.721006 -37.01542)
		(width 0.11684)
		(layer "In11.Cu")
		(net "ESPI_CPU0_D1")
	)
	(segment
		(start 200.708514 -103.241602)
		(end 200.708514 -104.2797)
		(width 0.11684)
		(layer "In11.Cu")
		(net "ESPI_CPU0_D1")
	)
	(segment
		(start 177.721006 -37.01542)
		(end 177.837846 -37.13226)
		(width 0.11684)
		(layer "In11.Cu")
		(net "ESPI_CPU0_D1")
	)
	(segment
		(start 201.226928 -123.886976)
		(end 201.7522 -124.412248)
		(width 0.11684)
		(layer "In11.Cu")
		(net "ESPI_CPU0_D1")
	)
	(segment
		(start 192.25387 -87.92464)
		(end 192.917572 -87.92464)
		(width 0.11684)
		(layer "In11.Cu")
		(net "ESPI_CPU0_D1")
	)
	(segment
		(start 195.56984 -136.390888)
		(end 193.88074 -138.079988)
		(width 0.11684)
		(layer "In11.Cu")
		(net "ESPI_CPU0_D1")
	)
	(segment
		(start 175.8061 -21.333968)
		(end 171.143168 -25.9969)
		(width 0.11684)
		(layer "In11.Cu")
		(net "ESPI_CPU0_D1")
	)
	(segment
		(start 199.969374 -101.457252)
		(end 200.708514 -103.241602)
		(width 0.11684)
		(layer "In11.Cu")
		(net "ESPI_CPU0_D1")
	)
	(segment
		(start 177.388266 -37.13226)
		(end 177.505106 -37.01542)
		(width 0.11684)
		(layer "In11.Cu")
		(net "ESPI_CPU0_D1")
	)
	(segment
		(start 201.7522 -124.412248)
		(end 201.7522 -129.954528)
		(width 0.11684)
		(layer "In11.Cu")
		(net "ESPI_CPU0_D1")
	)
	(segment
		(start 176.935384 -37.646864)
		(end 177.271426 -37.646864)
		(width 0.11684)
		(layer "In11.Cu")
		(net "ESPI_CPU0_D1")
	)
	(segment
		(start 191.979804 -87.650574)
		(end 192.25387 -87.92464)
		(width 0.11684)
		(layer "In11.Cu")
		(net "ESPI_CPU0_D1")
	)
	(segment
		(start 177.954686 -37.646864)
		(end 181.570122 -37.646864)
		(width 0.11684)
		(layer "In11.Cu")
		(net "ESPI_CPU0_D1")
	)
	(segment
		(start 177.271426 -37.646864)
		(end 177.388266 -37.530024)
		(width 0.11684)
		(layer "In11.Cu")
		(net "ESPI_CPU0_D1")
	)
	(segment
		(start 197.65264 -134.054088)
		(end 195.7578 -134.054088)
		(width 0.11684)
		(layer "In11.Cu")
		(net "ESPI_CPU0_D1")
	)
	(segment
		(start 201.7522 -129.954528)
		(end 197.65264 -134.054088)
		(width 0.11684)
		(layer "In11.Cu")
		(net "ESPI_CPU0_D1")
	)
	(segment
		(start 189.781688 -138.079988)
		(end 189.39383 -138.467846)
		(width 0.11684)
		(layer "In11.Cu")
		(net "ESPI_CPU0_D1")
	)
	(segment
		(start 171.143168 -25.9969)
		(end 171.143168 -31.854648)
		(width 0.11684)
		(layer "In11.Cu")
		(net "ESPI_CPU0_D1")
	)
	(segment
		(start 195.7578 -134.054088)
		(end 195.56984 -134.242048)
		(width 0.11684)
		(layer "In11.Cu")
		(net "ESPI_CPU0_D1")
	)
	(segment
		(start 191.979804 -86.490302)
		(end 191.979804 -87.650574)
		(width 0.11684)
		(layer "In11.Cu")
		(net "ESPI_CPU0_D1")
	)
	(segment
		(start 191.34582 -85.856318)
		(end 191.979804 -86.490302)
		(width 0.11684)
		(layer "In11.Cu")
		(net "ESPI_CPU0_D1")
	)
	(segment
		(start 193.88074 -138.079988)
		(end 189.781688 -138.079988)
		(width 0.11684)
		(layer "In11.Cu")
		(net "ESPI_CPU0_D1")
	)
	(segment
		(start 195.56984 -134.242048)
		(end 195.56984 -136.390888)
		(width 0.11684)
		(layer "In11.Cu")
		(net "ESPI_CPU0_D1")
	)
	(segment
		(start 175.86706 -18.463768)
		(end 175.8061 -18.524728)
		(width 0.11684)
		(layer "In11.Cu")
		(net "ESPI_CPU0_D1")
	)
	(segment
		(start 200.708514 -104.2797)
		(end 201.226928 -105.531412)
		(width 0.11684)
		(layer "In11.Cu")
		(net "ESPI_CPU0_D1")
	)
	(segment
		(start 186.027822 -42.104564)
		(end 186.027822 -75.416664)
		(width 0.11684)
		(layer "In11.Cu")
		(net "ESPI_CPU0_D1")
	)
	(segment
		(start 188.962538 -82.501994)
		(end 191.34582 -84.885276)
		(width 0.11684)
		(layer "In11.Cu")
		(net "ESPI_CPU0_D1")
	)
	(segment
		(start 196.793866 -91.800934)
		(end 199.207882 -97.628456)
		(width 0.11684)
		(layer "In11.Cu")
		(net "ESPI_CPU0_D1")
	)
	(segment
		(start 181.570122 -37.646864)
		(end 186.027822 -42.104564)
		(width 0.11684)
		(layer "In11.Cu")
		(net "ESPI_CPU0_D1")
	)
	(segment
		(start 177.837846 -37.13226)
		(end 177.837846 -37.530024)
		(width 0.11684)
		(layer "In11.Cu")
		(net "ESPI_CPU0_D1")
	)
	(segment
		(start 402.510752 -312.669936)
		(end 402.510752 -312.835036)
		(width 0.11684)
		(layer "In15.Cu")
		(net "ESPI_CPU0_D1")
	)
	(segment
		(start 331.464412 -176.365916)
		(end 370.635022 -215.536526)
		(width 0.11684)
		(layer "In15.Cu")
		(net "ESPI_CPU0_D1")
	)
	(segment
		(start 402.510752 -312.835036)
		(end 400.74342 -314.602368)
		(width 0.11684)
		(layer "In15.Cu")
		(net "ESPI_CPU0_D1")
	)
	(segment
		(start 399.966688 -310.125872)
		(end 399.966688 -310.290972)
		(width 0.11684)
		(layer "In15.Cu")
		(net "ESPI_CPU0_D1")
	)
	(segment
		(start 399.966688 -310.290972)
		(end 398.199356 -312.058304)
		(width 0.11684)
		(layer "In15.Cu")
		(net "ESPI_CPU0_D1")
	)
	(segment
		(start 190.189866 -137.710418)
		(end 193.91757 -137.710418)
		(width 0.11684)
		(layer "In15.Cu")
		(net "ESPI_CPU0_D1")
	)
	(segment
		(start 398.835372 -312.69432)
		(end 398.835372 -312.85942)
		(width 0.11684)
		(layer "In15.Cu")
		(net "ESPI_CPU0_D1")
	)
	(segment
		(start 189.39383 -138.506454)
		(end 190.189866 -137.710418)
		(width 0.11684)
		(layer "In15.Cu")
		(net "ESPI_CPU0_D1")
	)
	(segment
		(start 400.74342 -314.767468)
		(end 400.896328 -314.920376)
		(width 0.11684)
		(layer "In15.Cu")
		(net "ESPI_CPU0_D1")
	)
	(segment
		(start 395.802358 -217.733372)
		(end 398.399254 -220.330268)
		(width 0.11684)
		(layer "In15.Cu")
		(net "ESPI_CPU0_D1")
	)
	(segment
		(start 189.39383 -138.65352)
		(end 189.39383 -138.506454)
		(width 0.11684)
		(layer "In15.Cu")
		(net "ESPI_CPU0_D1")
	)
	(segment
		(start 401.085812 -311.244996)
		(end 401.23872 -311.397904)
		(width 0.11684)
		(layer "In15.Cu")
		(net "ESPI_CPU0_D1")
	)
	(segment
		(start 397.56334 -311.422288)
		(end 397.56334 -311.587388)
		(width 0.11684)
		(layer "In15.Cu")
		(net "ESPI_CPU0_D1")
	)
	(segment
		(start 398.399254 -308.558438)
		(end 399.330672 -309.489856)
		(width 0.11684)
		(layer "In15.Cu")
		(net "ESPI_CPU0_D1")
	)
	(segment
		(start 401.874736 -312.19902)
		(end 400.107404 -313.966352)
		(width 0.11684)
		(layer "In15.Cu")
		(net "ESPI_CPU0_D1")
	)
	(segment
		(start 404.38197 -318.349376)
		(end 403.73427 -318.997076)
		(width 0.11684)
		(layer "In15.Cu")
		(net "ESPI_CPU0_D1")
	)
	(segment
		(start 396.729458 -320.724276)
		(end 396.729458 -322.554854)
		(width 0.11684)
		(layer "In15.Cu")
		(net "ESPI_CPU0_D1")
	)
	(segment
		(start 195.874386 -134.069328)
		(end 196.301614 -134.069328)
		(width 0.11684)
		(layer "In15.Cu")
		(net "ESPI_CPU0_D1")
	)
	(segment
		(start 193.91757 -137.710418)
		(end 195.28282 -136.345168)
		(width 0.11684)
		(layer "In15.Cu")
		(net "ESPI_CPU0_D1")
	)
	(segment
		(start 401.23872 -311.397904)
		(end 401.23872 -311.563004)
		(width 0.11684)
		(layer "In15.Cu")
		(net "ESPI_CPU0_D1")
	)
	(segment
		(start 270.316198 -165.48354)
		(end 275.59254 -167.084248)
		(width 0.11684)
		(layer "In15.Cu")
		(net "ESPI_CPU0_D1")
	)
	(segment
		(start 195.28282 -134.660894)
		(end 195.874386 -134.069328)
		(width 0.11684)
		(layer "In15.Cu")
		(net "ESPI_CPU0_D1")
	)
	(segment
		(start 398.399254 -220.330268)
		(end 398.399254 -308.558438)
		(width 0.11684)
		(layer "In15.Cu")
		(net "ESPI_CPU0_D1")
	)
	(segment
		(start 402.82876 -313.153044)
		(end 402.99386 -313.153044)
		(width 0.11684)
		(layer "In15.Cu")
		(net "ESPI_CPU0_D1")
	)
	(segment
		(start 400.896328 -314.920376)
		(end 401.061428 -314.920376)
		(width 0.11684)
		(layer "In15.Cu")
		(net "ESPI_CPU0_D1")
	)
	(segment
		(start 399.81378 -309.972964)
		(end 399.966688 -310.125872)
		(width 0.11684)
		(layer "In15.Cu")
		(net "ESPI_CPU0_D1")
	)
	(segment
		(start 399.15338 -313.012328)
		(end 400.920712 -311.244996)
		(width 0.11684)
		(layer "In15.Cu")
		(net "ESPI_CPU0_D1")
	)
	(segment
		(start 309.056786 -167.084248)
		(end 331.464412 -176.365916)
		(width 0.11684)
		(layer "In15.Cu")
		(net "ESPI_CPU0_D1")
	)
	(segment
		(start 400.449796 -310.60898)
		(end 400.602704 -310.761888)
		(width 0.11684)
		(layer "In15.Cu")
		(net "ESPI_CPU0_D1")
	)
	(segment
		(start 400.602704 -310.761888)
		(end 400.602704 -310.926988)
		(width 0.11684)
		(layer "In15.Cu")
		(net "ESPI_CPU0_D1")
	)
	(segment
		(start 400.107404 -313.966352)
		(end 400.107404 -314.131452)
		(width 0.11684)
		(layer "In15.Cu")
		(net "ESPI_CPU0_D1")
	)
	(segment
		(start 399.471388 -313.495436)
		(end 399.624296 -313.648344)
		(width 0.11684)
		(layer "In15.Cu")
		(net "ESPI_CPU0_D1")
	)
	(segment
		(start 401.061428 -314.920376)
		(end 402.82876 -313.153044)
		(width 0.11684)
		(layer "In15.Cu")
		(net "ESPI_CPU0_D1")
	)
	(segment
		(start 397.881348 -311.740296)
		(end 399.64868 -309.972964)
		(width 0.11684)
		(layer "In15.Cu")
		(net "ESPI_CPU0_D1")
	)
	(segment
		(start 399.330672 -309.489856)
		(end 399.330672 -309.654956)
		(width 0.11684)
		(layer "In15.Cu")
		(net "ESPI_CPU0_D1")
	)
	(segment
		(start 399.471388 -313.330336)
		(end 399.471388 -313.495436)
		(width 0.11684)
		(layer "In15.Cu")
		(net "ESPI_CPU0_D1")
	)
	(segment
		(start 402.357844 -312.517028)
		(end 402.510752 -312.669936)
		(width 0.11684)
		(layer "In15.Cu")
		(net "ESPI_CPU0_D1")
	)
	(segment
		(start 401.23872 -311.563004)
		(end 399.471388 -313.330336)
		(width 0.11684)
		(layer "In15.Cu")
		(net "ESPI_CPU0_D1")
	)
	(segment
		(start 385.065778 -215.536526)
		(end 387.262624 -217.733372)
		(width 0.11684)
		(layer "In15.Cu")
		(net "ESPI_CPU0_D1")
	)
	(segment
		(start 403.73427 -318.997076)
		(end 398.456658 -318.997076)
		(width 0.11684)
		(layer "In15.Cu")
		(net "ESPI_CPU0_D1")
	)
	(segment
		(start 402.99386 -313.153044)
		(end 404.38197 -314.541154)
		(width 0.11684)
		(layer "In15.Cu")
		(net "ESPI_CPU0_D1")
	)
	(segment
		(start 210.793838 -139.400026)
		(end 232.707434 -143.75892)
		(width 0.11684)
		(layer "In15.Cu")
		(net "ESPI_CPU0_D1")
	)
	(segment
		(start 237.802928 -143.75892)
		(end 270.316198 -165.48354)
		(width 0.11684)
		(layer "In15.Cu")
		(net "ESPI_CPU0_D1")
	)
	(segment
		(start 402.192744 -312.517028)
		(end 402.357844 -312.517028)
		(width 0.11684)
		(layer "In15.Cu")
		(net "ESPI_CPU0_D1")
	)
	(segment
		(start 398.199356 -312.223404)
		(end 398.352264 -312.376312)
		(width 0.11684)
		(layer "In15.Cu")
		(net "ESPI_CPU0_D1")
	)
	(segment
		(start 401.874736 -312.03392)
		(end 401.874736 -312.19902)
		(width 0.11684)
		(layer "In15.Cu")
		(net "ESPI_CPU0_D1")
	)
	(segment
		(start 401.556728 -311.881012)
		(end 401.721828 -311.881012)
		(width 0.11684)
		(layer "In15.Cu")
		(net "ESPI_CPU0_D1")
	)
	(segment
		(start 400.260312 -314.28436)
		(end 400.425412 -314.28436)
		(width 0.11684)
		(layer "In15.Cu")
		(net "ESPI_CPU0_D1")
	)
	(segment
		(start 399.624296 -313.648344)
		(end 399.789396 -313.648344)
		(width 0.11684)
		(layer "In15.Cu")
		(net "ESPI_CPU0_D1")
	)
	(segment
		(start 398.456658 -318.997076)
		(end 396.729458 -320.724276)
		(width 0.11684)
		(layer "In15.Cu")
		(net "ESPI_CPU0_D1")
	)
	(segment
		(start 196.301614 -134.069328)
		(end 196.30771 -134.075424)
		(width 0.11684)
		(layer "In15.Cu")
		(net "ESPI_CPU0_D1")
	)
	(segment
		(start 370.635022 -215.536526)
		(end 385.065778 -215.536526)
		(width 0.11684)
		(layer "In15.Cu")
		(net "ESPI_CPU0_D1")
	)
	(segment
		(start 398.835372 -312.85942)
		(end 398.98828 -313.012328)
		(width 0.11684)
		(layer "In15.Cu")
		(net "ESPI_CPU0_D1")
	)
	(segment
		(start 397.56334 -311.587388)
		(end 397.716248 -311.740296)
		(width 0.11684)
		(layer "In15.Cu")
		(net "ESPI_CPU0_D1")
	)
	(segment
		(start 275.59254 -167.084248)
		(end 309.056786 -167.084248)
		(width 0.11684)
		(layer "In15.Cu")
		(net "ESPI_CPU0_D1")
	)
	(segment
		(start 399.330672 -309.654956)
		(end 397.56334 -311.422288)
		(width 0.11684)
		(layer "In15.Cu")
		(net "ESPI_CPU0_D1")
	)
	(segment
		(start 399.789396 -313.648344)
		(end 401.556728 -311.881012)
		(width 0.11684)
		(layer "In15.Cu")
		(net "ESPI_CPU0_D1")
	)
	(segment
		(start 398.517364 -312.376312)
		(end 400.284696 -310.60898)
		(width 0.11684)
		(layer "In15.Cu")
		(net "ESPI_CPU0_D1")
	)
	(segment
		(start 400.284696 -310.60898)
		(end 400.449796 -310.60898)
		(width 0.11684)
		(layer "In15.Cu")
		(net "ESPI_CPU0_D1")
	)
	(segment
		(start 399.64868 -309.972964)
		(end 399.81378 -309.972964)
		(width 0.11684)
		(layer "In15.Cu")
		(net "ESPI_CPU0_D1")
	)
	(segment
		(start 400.920712 -311.244996)
		(end 401.085812 -311.244996)
		(width 0.11684)
		(layer "In15.Cu")
		(net "ESPI_CPU0_D1")
	)
	(segment
		(start 398.199356 -312.058304)
		(end 398.199356 -312.223404)
		(width 0.11684)
		(layer "In15.Cu")
		(net "ESPI_CPU0_D1")
	)
	(segment
		(start 400.107404 -314.131452)
		(end 400.260312 -314.28436)
		(width 0.11684)
		(layer "In15.Cu")
		(net "ESPI_CPU0_D1")
	)
	(segment
		(start 400.425412 -314.28436)
		(end 402.192744 -312.517028)
		(width 0.11684)
		(layer "In15.Cu")
		(net "ESPI_CPU0_D1")
	)
	(segment
		(start 387.262624 -217.733372)
		(end 395.802358 -217.733372)
		(width 0.11684)
		(layer "In15.Cu")
		(net "ESPI_CPU0_D1")
	)
	(segment
		(start 400.74342 -314.602368)
		(end 400.74342 -314.767468)
		(width 0.11684)
		(layer "In15.Cu")
		(net "ESPI_CPU0_D1")
	)
	(segment
		(start 232.707434 -143.75892)
		(end 237.802928 -143.75892)
		(width 0.11684)
		(layer "In15.Cu")
		(net "ESPI_CPU0_D1")
	)
	(segment
		(start 196.30771 -134.075424)
		(end 197.938898 -134.075424)
		(width 0.11684)
		(layer "In15.Cu")
		(net "ESPI_CPU0_D1")
	)
	(segment
		(start 398.98828 -313.012328)
		(end 399.15338 -313.012328)
		(width 0.11684)
		(layer "In15.Cu")
		(net "ESPI_CPU0_D1")
	)
	(segment
		(start 400.602704 -310.926988)
		(end 398.835372 -312.69432)
		(width 0.11684)
		(layer "In15.Cu")
		(net "ESPI_CPU0_D1")
	)
	(segment
		(start 397.716248 -311.740296)
		(end 397.881348 -311.740296)
		(width 0.11684)
		(layer "In15.Cu")
		(net "ESPI_CPU0_D1")
	)
	(segment
		(start 404.38197 -314.541154)
		(end 404.38197 -318.349376)
		(width 0.11684)
		(layer "In15.Cu")
		(net "ESPI_CPU0_D1")
	)
	(segment
		(start 398.352264 -312.376312)
		(end 398.517364 -312.376312)
		(width 0.11684)
		(layer "In15.Cu")
		(net "ESPI_CPU0_D1")
	)
	(segment
		(start 195.28282 -136.345168)
		(end 195.28282 -134.660894)
		(width 0.11684)
		(layer "In15.Cu")
		(net "ESPI_CPU0_D1")
	)
	(segment
		(start 401.721828 -311.881012)
		(end 401.874736 -312.03392)
		(width 0.11684)
		(layer "In15.Cu")
		(net "ESPI_CPU0_D1")
	)
	(segment
		(start 197.938898 -134.075424)
		(end 210.793838 -139.400026)
		(width 0.11684)
		(layer "In15.Cu")
		(net "ESPI_CPU0_D1")
	)
	(segment
		(start 176.467008 -16.549878)
		(end 176.467008 -17.833848)
		(width 0.10668)
		(layer "F.Cu")
		(net "ESPI_CPU0_D0")
	)
	(segment
		(start 395.751558 -324.196202)
		(end 395.751558 -325.049896)
		(width 0.10668)
		(layer "F.Cu")
		(net "ESPI_CPU0_D0")
	)
	(segment
		(start 395.751558 -325.049896)
		(end 395.60754 -325.193914)
		(width 0.10668)
		(layer "F.Cu")
		(net "ESPI_CPU0_D0")
	)
	(via
		(at 395.173962 -324.193662)
		(size 0.6604)
		(drill 0.3302)
		(layers "F.Cu" "B.Cu")
		(net "ESPI_CPU0_D0")
	)
	(via
		(at 197.4088 -134.6835)
		(size 0.508)
		(drill 0.254)
		(layers "F.Cu" "B.Cu")
		(net "ESPI_CPU0_D0")
	)
	(via
		(at 176.467008 -17.833848)
		(size 0.508)
		(drill 0.254)
		(layers "F.Cu" "B.Cu")
		(net "ESPI_CPU0_D0")
	)
	(via
		(at 395.60754 -325.193914)
		(size 0.508)
		(drill 0.254)
		(layers "F.Cu" "B.Cu")
		(net "ESPI_CPU0_D0")
	)
	(segment
		(start 395.173962 -324.193662)
		(end 395.60754 -324.62724)
		(width 0.10668)
		(layer "B.Cu")
		(net "ESPI_CPU0_D0")
	)
	(segment
		(start 195.179188 -132.453888)
		(end 195.179188 -128.509014)
		(width 0.10668)
		(layer "B.Cu")
		(net "ESPI_CPU0_D0")
	)
	(segment
		(start 394.672312 -323.692012)
		(end 395.173962 -324.193662)
		(width 0.10668)
		(layer "B.Cu")
		(net "ESPI_CPU0_D0")
	)
	(segment
		(start 394.002768 -323.692012)
		(end 394.672312 -323.692012)
		(width 0.10668)
		(layer "B.Cu")
		(net "ESPI_CPU0_D0")
	)
	(segment
		(start 197.4088 -134.6835)
		(end 195.179188 -132.453888)
		(width 0.10668)
		(layer "B.Cu")
		(net "ESPI_CPU0_D0")
	)
	(segment
		(start 395.60754 -324.62724)
		(end 395.60754 -325.193914)
		(width 0.10668)
		(layer "B.Cu")
		(net "ESPI_CPU0_D0")
	)
	(segment
		(start 195.179188 -128.509014)
		(end 195.790058 -127.898144)
		(width 0.10668)
		(layer "B.Cu")
		(net "ESPI_CPU0_D0")
	)
	(segment
		(start 195.790058 -127.898144)
		(end 195.790058 -126.833376)
		(width 0.10668)
		(layer "B.Cu")
		(net "ESPI_CPU0_D0")
	)
	(segment
		(start 179.084224 -36.337494)
		(end 179.201064 -36.220654)
		(width 0.11684)
		(layer "In11.Cu")
		(net "ESPI_CPU0_D0")
	)
	(segment
		(start 185.941462 -38.919912)
		(end 186.106562 -38.919912)
		(width 0.11684)
		(layer "In11.Cu")
		(net "ESPI_CPU0_D0")
	)
	(segment
		(start 176.054004 -34.688526)
		(end 176.054004 -35.935412)
		(width 0.11684)
		(layer "In11.Cu")
		(net "ESPI_CPU0_D0")
	)
	(segment
		(start 179.650644 -34.688526)
		(end 179.650644 -36.842954)
		(width 0.11684)
		(layer "In11.Cu")
		(net "ESPI_CPU0_D0")
	)
	(segment
		(start 177.282856 -18.96237)
		(end 178.42484 -20.104354)
		(width 0.11684)
		(layer "In11.Cu")
		(net "ESPI_CPU0_D0")
	)
	(segment
		(start 177.402744 -34.688526)
		(end 177.519584 -34.571686)
		(width 0.11684)
		(layer "In11.Cu")
		(net "ESPI_CPU0_D0")
	)
	(segment
		(start 180.100224 -34.688526)
		(end 180.217064 -34.571686)
		(width 0.11684)
		(layer "In11.Cu")
		(net "ESPI_CPU0_D0")
	)
	(segment
		(start 185.470546 -38.283896)
		(end 185.623454 -38.436804)
		(width 0.11684)
		(layer "In11.Cu")
		(net "ESPI_CPU0_D0")
	)
	(segment
		(start 174.456598 -34.571686)
		(end 175.937164 -34.571686)
		(width 0.11684)
		(layer "In11.Cu")
		(net "ESPI_CPU0_D0")
	)
	(segment
		(start 181.593236 -36.907978)
		(end 182.761382 -35.739832)
		(width 0.11684)
		(layer "In11.Cu")
		(net "ESPI_CPU0_D0")
	)
	(segment
		(start 180.666644 -36.337494)
		(end 180.882544 -36.337494)
		(width 0.11684)
		(layer "In11.Cu")
		(net "ESPI_CPU0_D0")
	)
	(segment
		(start 194.030346 -88.202262)
		(end 196.995796 -91.167712)
		(width 0.11684)
		(layer "In11.Cu")
		(net "ESPI_CPU0_D0")
	)
	(segment
		(start 181.911244 -37.225986)
		(end 181.911244 -37.391086)
		(width 0.11684)
		(layer "In11.Cu")
		(net "ESPI_CPU0_D0")
	)
	(segment
		(start 177.285904 -36.337494)
		(end 177.402744 -36.220654)
		(width 0.11684)
		(layer "In11.Cu")
		(net "ESPI_CPU0_D0")
	)
	(segment
		(start 177.969164 -36.337494)
		(end 178.185064 -36.337494)
		(width 0.11684)
		(layer "In11.Cu")
		(net "ESPI_CPU0_D0")
	)
	(segment
		(start 176.467008 -17.833848)
		(end 176.467008 -18.580354)
		(width 0.11684)
		(layer "In11.Cu")
		(net "ESPI_CPU0_D0")
	)
	(segment
		(start 178.185064 -36.337494)
		(end 178.301904 -36.220654)
		(width 0.11684)
		(layer "In11.Cu")
		(net "ESPI_CPU0_D0")
	)
	(segment
		(start 178.634644 -34.571686)
		(end 178.751484 -34.688526)
		(width 0.11684)
		(layer "In11.Cu")
		(net "ESPI_CPU0_D0")
	)
	(segment
		(start 178.868324 -36.337494)
		(end 179.084224 -36.337494)
		(width 0.11684)
		(layer "In11.Cu")
		(net "ESPI_CPU0_D0")
	)
	(segment
		(start 182.54726 -38.027102)
		(end 182.700168 -38.18001)
		(width 0.11684)
		(layer "In11.Cu")
		(net "ESPI_CPU0_D0")
	)
	(segment
		(start 202.17384 -124.199142)
		(end 202.17384 -130.372866)
		(width 0.11684)
		(layer "In11.Cu")
		(net "ESPI_CPU0_D0")
	)
	(segment
		(start 183.183276 -38.663118)
		(end 183.336184 -38.816026)
		(width 0.11684)
		(layer "In11.Cu")
		(net "ESPI_CPU0_D0")
	)
	(segment
		(start 171.564808 -26.61412)
		(end 171.564808 -31.679896)
		(width 0.11684)
		(layer "In11.Cu")
		(net "ESPI_CPU0_D0")
	)
	(segment
		(start 201.148696 -104.24033)
		(end 201.775822 -105.754424)
		(width 0.11684)
		(layer "In11.Cu")
		(net "ESPI_CPU0_D0")
	)
	(segment
		(start 180.999384 -36.220654)
		(end 180.999384 -35.207702)
		(width 0.11684)
		(layer "In11.Cu")
		(net "ESPI_CPU0_D0")
	)
	(segment
		(start 181.275228 -36.58997)
		(end 181.275228 -36.75507)
		(width 0.11684)
		(layer "In11.Cu")
		(net "ESPI_CPU0_D0")
	)
	(segment
		(start 183.715406 -36.528756)
		(end 183.715406 -36.693856)
		(width 0.11684)
		(layer "In11.Cu")
		(net "ESPI_CPU0_D0")
	)
	(segment
		(start 201.148696 -103.177848)
		(end 201.148696 -104.24033)
		(width 0.11684)
		(layer "In11.Cu")
		(net "ESPI_CPU0_D0")
	)
	(segment
		(start 171.564808 -31.679896)
		(end 174.456598 -34.571686)
		(width 0.11684)
		(layer "In11.Cu")
		(net "ESPI_CPU0_D0")
	)
	(segment
		(start 176.836324 -34.571686)
		(end 176.953164 -34.688526)
		(width 0.11684)
		(layer "In11.Cu")
		(net "ESPI_CPU0_D0")
	)
	(segment
		(start 177.836068 -22.88286)
		(end 175.296068 -22.88286)
		(width 0.11684)
		(layer "In11.Cu")
		(net "ESPI_CPU0_D0")
	)
	(segment
		(start 176.953164 -34.688526)
		(end 176.953164 -36.220654)
		(width 0.11684)
		(layer "In11.Cu")
		(net "ESPI_CPU0_D0")
	)
	(segment
		(start 179.975764 -36.952174)
		(end 180.100224 -36.827714)
		(width 0.11684)
		(layer "In11.Cu")
		(net "ESPI_CPU0_D0")
	)
	(segment
		(start 184.83453 -37.64788)
		(end 184.987438 -37.800788)
		(width 0.11684)
		(layer "In11.Cu")
		(net "ESPI_CPU0_D0")
	)
	(segment
		(start 184.987438 -37.965888)
		(end 183.819292 -39.134034)
		(width 0.11684)
		(layer "In11.Cu")
		(net "ESPI_CPU0_D0")
	)
	(segment
		(start 180.432964 -34.571686)
		(end 180.549804 -34.688526)
		(width 0.11684)
		(layer "In11.Cu")
		(net "ESPI_CPU0_D0")
	)
	(segment
		(start 201.775822 -105.754424)
		(end 201.775822 -123.801124)
		(width 0.11684)
		(layer "In11.Cu")
		(net "ESPI_CPU0_D0")
	)
	(segment
		(start 185.305446 -38.283896)
		(end 185.470546 -38.283896)
		(width 0.11684)
		(layer "In11.Cu")
		(net "ESPI_CPU0_D0")
	)
	(segment
		(start 186.449462 -39.262812)
		(end 186.449462 -75.288648)
		(width 0.11684)
		(layer "In11.Cu")
		(net "ESPI_CPU0_D0")
	)
	(segment
		(start 193.159634 -86.573106)
		(end 194.030346 -88.202262)
		(width 0.11684)
		(layer "In11.Cu")
		(net "ESPI_CPU0_D0")
	)
	(segment
		(start 177.735484 -34.571686)
		(end 177.852324 -34.688526)
		(width 0.11684)
		(layer "In11.Cu")
		(net "ESPI_CPU0_D0")
	)
	(segment
		(start 184.66943 -37.64788)
		(end 184.83453 -37.64788)
		(width 0.11684)
		(layer "In11.Cu")
		(net "ESPI_CPU0_D0")
	)
	(segment
		(start 189.26302 -82.079846)
		(end 191.939926 -84.756752)
		(width 0.11684)
		(layer "In11.Cu")
		(net "ESPI_CPU0_D0")
	)
	(segment
		(start 183.397398 -36.375848)
		(end 183.562498 -36.375848)
		(width 0.11684)
		(layer "In11.Cu")
		(net "ESPI_CPU0_D0")
	)
	(segment
		(start 183.336184 -38.816026)
		(end 183.501284 -38.816026)
		(width 0.11684)
		(layer "In11.Cu")
		(net "ESPI_CPU0_D0")
	)
	(segment
		(start 182.229252 -37.543994)
		(end 183.397398 -36.375848)
		(width 0.11684)
		(layer "In11.Cu")
		(net "ESPI_CPU0_D0")
	)
	(segment
		(start 184.1373 -39.452042)
		(end 185.305446 -38.283896)
		(width 0.11684)
		(layer "In11.Cu")
		(net "ESPI_CPU0_D0")
	)
	(segment
		(start 182.54726 -37.862002)
		(end 182.54726 -38.027102)
		(width 0.11684)
		(layer "In11.Cu")
		(net "ESPI_CPU0_D0")
	)
	(segment
		(start 179.317904 -34.571686)
		(end 179.533804 -34.571686)
		(width 0.11684)
		(layer "In11.Cu")
		(net "ESPI_CPU0_D0")
	)
	(segment
		(start 175.296068 -22.88286)
		(end 171.564808 -26.61412)
		(width 0.11684)
		(layer "In11.Cu")
		(net "ESPI_CPU0_D0")
	)
	(segment
		(start 176.953164 -36.220654)
		(end 177.070004 -36.337494)
		(width 0.11684)
		(layer "In11.Cu")
		(net "ESPI_CPU0_D0")
	)
	(segment
		(start 181.16296 -35.044126)
		(end 181.572916 -35.044126)
		(width 0.11684)
		(layer "In11.Cu")
		(net "ESPI_CPU0_D0")
	)
	(segment
		(start 191.939926 -85.353398)
		(end 193.159634 -86.573106)
		(width 0.11684)
		(layer "In11.Cu")
		(net "ESPI_CPU0_D0")
	)
	(segment
		(start 183.562498 -36.375848)
		(end 183.715406 -36.528756)
		(width 0.11684)
		(layer "In11.Cu")
		(net "ESPI_CPU0_D0")
	)
	(segment
		(start 183.07939 -36.05784)
		(end 181.911244 -37.225986)
		(width 0.11684)
		(layer "In11.Cu")
		(net "ESPI_CPU0_D0")
	)
	(segment
		(start 182.064152 -37.543994)
		(end 182.229252 -37.543994)
		(width 0.11684)
		(layer "In11.Cu")
		(net "ESPI_CPU0_D0")
	)
	(segment
		(start 176.467008 -18.580354)
		(end 176.849024 -18.96237)
		(width 0.11684)
		(layer "In11.Cu")
		(net "ESPI_CPU0_D0")
	)
	(segment
		(start 184.773316 -40.088058)
		(end 185.941462 -38.919912)
		(width 0.11684)
		(layer "In11.Cu")
		(net "ESPI_CPU0_D0")
	)
	(segment
		(start 179.201064 -36.220654)
		(end 179.201064 -34.688526)
		(width 0.11684)
		(layer "In11.Cu")
		(net "ESPI_CPU0_D0")
	)
	(segment
		(start 182.042562 -35.822636)
		(end 181.275228 -36.58997)
		(width 0.11684)
		(layer "In11.Cu")
		(net "ESPI_CPU0_D0")
	)
	(segment
		(start 176.620424 -34.571686)
		(end 176.836324 -34.571686)
		(width 0.11684)
		(layer "In11.Cu")
		(net "ESPI_CPU0_D0")
	)
	(segment
		(start 176.849024 -18.96237)
		(end 177.282856 -18.96237)
		(width 0.11684)
		(layer "In11.Cu")
		(net "ESPI_CPU0_D0")
	)
	(segment
		(start 182.042562 -35.513772)
		(end 182.042562 -35.822636)
		(width 0.11684)
		(layer "In11.Cu")
		(net "ESPI_CPU0_D0")
	)
	(segment
		(start 178.301904 -36.220654)
		(end 178.301904 -34.688526)
		(width 0.11684)
		(layer "In11.Cu")
		(net "ESPI_CPU0_D0")
	)
	(segment
		(start 182.926482 -35.739832)
		(end 183.07939 -35.89274)
		(width 0.11684)
		(layer "In11.Cu")
		(net "ESPI_CPU0_D0")
	)
	(segment
		(start 184.455308 -39.77005)
		(end 184.455308 -39.93515)
		(width 0.11684)
		(layer "In11.Cu")
		(net "ESPI_CPU0_D0")
	)
	(segment
		(start 176.386744 -36.052252)
		(end 176.503584 -35.935412)
		(width 0.11684)
		(layer "In11.Cu")
		(net "ESPI_CPU0_D0")
	)
	(segment
		(start 176.170844 -36.052252)
		(end 176.386744 -36.052252)
		(width 0.11684)
		(layer "In11.Cu")
		(net "ESPI_CPU0_D0")
	)
	(segment
		(start 180.549804 -34.688526)
		(end 180.549804 -36.220654)
		(width 0.11684)
		(layer "In11.Cu")
		(net "ESPI_CPU0_D0")
	)
	(segment
		(start 184.351422 -37.329872)
		(end 183.183276 -38.498018)
		(width 0.11684)
		(layer "In11.Cu")
		(net "ESPI_CPU0_D0")
	)
	(segment
		(start 179.201064 -34.688526)
		(end 179.317904 -34.571686)
		(width 0.11684)
		(layer "In11.Cu")
		(net "ESPI_CPU0_D0")
	)
	(segment
		(start 179.650644 -36.842954)
		(end 179.759864 -36.952174)
		(width 0.11684)
		(layer "In11.Cu")
		(net "ESPI_CPU0_D0")
	)
	(segment
		(start 178.42484 -20.104354)
		(end 178.42484 -22.294088)
		(width 0.11684)
		(layer "In11.Cu")
		(net "ESPI_CPU0_D0")
	)
	(segment
		(start 191.939926 -84.756752)
		(end 191.939926 -85.353398)
		(width 0.11684)
		(layer "In11.Cu")
		(net "ESPI_CPU0_D0")
	)
	(segment
		(start 184.198514 -37.011864)
		(end 184.351422 -37.164772)
		(width 0.11684)
		(layer "In11.Cu")
		(net "ESPI_CPU0_D0")
	)
	(segment
		(start 197.863206 -134.6835)
		(end 197.4088 -134.6835)
		(width 0.11684)
		(layer "In11.Cu")
		(net "ESPI_CPU0_D0")
	)
	(segment
		(start 178.751484 -36.220654)
		(end 178.868324 -36.337494)
		(width 0.11684)
		(layer "In11.Cu")
		(net "ESPI_CPU0_D0")
	)
	(segment
		(start 183.07939 -35.89274)
		(end 183.07939 -36.05784)
		(width 0.11684)
		(layer "In11.Cu")
		(net "ESPI_CPU0_D0")
	)
	(segment
		(start 181.275228 -36.75507)
		(end 181.428136 -36.907978)
		(width 0.11684)
		(layer "In11.Cu")
		(net "ESPI_CPU0_D0")
	)
	(segment
		(start 176.503584 -35.935412)
		(end 176.503584 -34.688526)
		(width 0.11684)
		(layer "In11.Cu")
		(net "ESPI_CPU0_D0")
	)
	(segment
		(start 178.418744 -34.571686)
		(end 178.634644 -34.571686)
		(width 0.11684)
		(layer "In11.Cu")
		(net "ESPI_CPU0_D0")
	)
	(segment
		(start 196.995796 -91.167712)
		(end 199.723756 -97.753424)
		(width 0.11684)
		(layer "In11.Cu")
		(net "ESPI_CPU0_D0")
	)
	(segment
		(start 180.999384 -35.207702)
		(end 181.16296 -35.044126)
		(width 0.11684)
		(layer "In11.Cu")
		(net "ESPI_CPU0_D0")
	)
	(segment
		(start 183.715406 -36.693856)
		(end 182.54726 -37.862002)
		(width 0.11684)
		(layer "In11.Cu")
		(net "ESPI_CPU0_D0")
	)
	(segment
		(start 182.700168 -38.18001)
		(end 182.865268 -38.18001)
		(width 0.11684)
		(layer "In11.Cu")
		(net "ESPI_CPU0_D0")
	)
	(segment
		(start 183.819292 -39.134034)
		(end 183.819292 -39.299134)
		(width 0.11684)
		(layer "In11.Cu")
		(net "ESPI_CPU0_D0")
	)
	(segment
		(start 181.428136 -36.907978)
		(end 181.593236 -36.907978)
		(width 0.11684)
		(layer "In11.Cu")
		(net "ESPI_CPU0_D0")
	)
	(segment
		(start 177.402744 -36.220654)
		(end 177.402744 -34.688526)
		(width 0.11684)
		(layer "In11.Cu")
		(net "ESPI_CPU0_D0")
	)
	(segment
		(start 184.351422 -37.164772)
		(end 184.351422 -37.329872)
		(width 0.11684)
		(layer "In11.Cu")
		(net "ESPI_CPU0_D0")
	)
	(segment
		(start 186.449462 -75.288648)
		(end 189.26302 -82.079846)
		(width 0.11684)
		(layer "In11.Cu")
		(net "ESPI_CPU0_D0")
	)
	(segment
		(start 185.623454 -38.436804)
		(end 185.623454 -38.601904)
		(width 0.11684)
		(layer "In11.Cu")
		(net "ESPI_CPU0_D0")
	)
	(segment
		(start 179.533804 -34.571686)
		(end 179.650644 -34.688526)
		(width 0.11684)
		(layer "In11.Cu")
		(net "ESPI_CPU0_D0")
	)
	(segment
		(start 180.549804 -36.220654)
		(end 180.666644 -36.337494)
		(width 0.11684)
		(layer "In11.Cu")
		(net "ESPI_CPU0_D0")
	)
	(segment
		(start 185.623454 -38.601904)
		(end 184.455308 -39.77005)
		(width 0.11684)
		(layer "In11.Cu")
		(net "ESPI_CPU0_D0")
	)
	(segment
		(start 180.217064 -34.571686)
		(end 180.432964 -34.571686)
		(width 0.11684)
		(layer "In11.Cu")
		(net "ESPI_CPU0_D0")
	)
	(segment
		(start 183.819292 -39.299134)
		(end 183.9722 -39.452042)
		(width 0.11684)
		(layer "In11.Cu")
		(net "ESPI_CPU0_D0")
	)
	(segment
		(start 177.519584 -34.571686)
		(end 177.735484 -34.571686)
		(width 0.11684)
		(layer "In11.Cu")
		(net "ESPI_CPU0_D0")
	)
	(segment
		(start 199.723756 -97.753424)
		(end 200.4822 -101.567996)
		(width 0.11684)
		(layer "In11.Cu")
		(net "ESPI_CPU0_D0")
	)
	(segment
		(start 183.9722 -39.452042)
		(end 184.1373 -39.452042)
		(width 0.11684)
		(layer "In11.Cu")
		(net "ESPI_CPU0_D0")
	)
	(segment
		(start 176.503584 -34.688526)
		(end 176.620424 -34.571686)
		(width 0.11684)
		(layer "In11.Cu")
		(net "ESPI_CPU0_D0")
	)
	(segment
		(start 180.100224 -36.827714)
		(end 180.100224 -34.688526)
		(width 0.11684)
		(layer "In11.Cu")
		(net "ESPI_CPU0_D0")
	)
	(segment
		(start 178.751484 -34.688526)
		(end 178.751484 -36.220654)
		(width 0.11684)
		(layer "In11.Cu")
		(net "ESPI_CPU0_D0")
	)
	(segment
		(start 178.42484 -22.294088)
		(end 177.836068 -22.88286)
		(width 0.11684)
		(layer "In11.Cu")
		(net "ESPI_CPU0_D0")
	)
	(segment
		(start 183.501284 -38.816026)
		(end 184.66943 -37.64788)
		(width 0.11684)
		(layer "In11.Cu")
		(net "ESPI_CPU0_D0")
	)
	(segment
		(start 186.106562 -38.919912)
		(end 186.449462 -39.262812)
		(width 0.11684)
		(layer "In11.Cu")
		(net "ESPI_CPU0_D0")
	)
	(segment
		(start 184.608216 -40.088058)
		(end 184.773316 -40.088058)
		(width 0.11684)
		(layer "In11.Cu")
		(net "ESPI_CPU0_D0")
	)
	(segment
		(start 180.882544 -36.337494)
		(end 180.999384 -36.220654)
		(width 0.11684)
		(layer "In11.Cu")
		(net "ESPI_CPU0_D0")
	)
	(segment
		(start 177.070004 -36.337494)
		(end 177.285904 -36.337494)
		(width 0.11684)
		(layer "In11.Cu")
		(net "ESPI_CPU0_D0")
	)
	(segment
		(start 181.572916 -35.044126)
		(end 182.042562 -35.513772)
		(width 0.11684)
		(layer "In11.Cu")
		(net "ESPI_CPU0_D0")
	)
	(segment
		(start 177.852324 -36.220654)
		(end 177.969164 -36.337494)
		(width 0.11684)
		(layer "In11.Cu")
		(net "ESPI_CPU0_D0")
	)
	(segment
		(start 200.4822 -101.567996)
		(end 201.148696 -103.177848)
		(width 0.11684)
		(layer "In11.Cu")
		(net "ESPI_CPU0_D0")
	)
	(segment
		(start 183.183276 -38.498018)
		(end 183.183276 -38.663118)
		(width 0.11684)
		(layer "In11.Cu")
		(net "ESPI_CPU0_D0")
	)
	(segment
		(start 184.987438 -37.800788)
		(end 184.987438 -37.965888)
		(width 0.11684)
		(layer "In11.Cu")
		(net "ESPI_CPU0_D0")
	)
	(segment
		(start 176.054004 -35.935412)
		(end 176.170844 -36.052252)
		(width 0.11684)
		(layer "In11.Cu")
		(net "ESPI_CPU0_D0")
	)
	(segment
		(start 182.761382 -35.739832)
		(end 182.926482 -35.739832)
		(width 0.11684)
		(layer "In11.Cu")
		(net "ESPI_CPU0_D0")
	)
	(segment
		(start 175.937164 -34.571686)
		(end 176.054004 -34.688526)
		(width 0.11684)
		(layer "In11.Cu")
		(net "ESPI_CPU0_D0")
	)
	(segment
		(start 177.852324 -34.688526)
		(end 177.852324 -36.220654)
		(width 0.11684)
		(layer "In11.Cu")
		(net "ESPI_CPU0_D0")
	)
	(segment
		(start 179.759864 -36.952174)
		(end 179.975764 -36.952174)
		(width 0.11684)
		(layer "In11.Cu")
		(net "ESPI_CPU0_D0")
	)
	(segment
		(start 182.865268 -38.18001)
		(end 184.033414 -37.011864)
		(width 0.11684)
		(layer "In11.Cu")
		(net "ESPI_CPU0_D0")
	)
	(segment
		(start 181.911244 -37.391086)
		(end 182.064152 -37.543994)
		(width 0.11684)
		(layer "In11.Cu")
		(net "ESPI_CPU0_D0")
	)
	(segment
		(start 184.455308 -39.93515)
		(end 184.608216 -40.088058)
		(width 0.11684)
		(layer "In11.Cu")
		(net "ESPI_CPU0_D0")
	)
	(segment
		(start 201.775822 -123.801124)
		(end 202.17384 -124.199142)
		(width 0.11684)
		(layer "In11.Cu")
		(net "ESPI_CPU0_D0")
	)
	(segment
		(start 178.301904 -34.688526)
		(end 178.418744 -34.571686)
		(width 0.11684)
		(layer "In11.Cu")
		(net "ESPI_CPU0_D0")
	)
	(segment
		(start 184.033414 -37.011864)
		(end 184.198514 -37.011864)
		(width 0.11684)
		(layer "In11.Cu")
		(net "ESPI_CPU0_D0")
	)
	(segment
		(start 202.17384 -130.372866)
		(end 197.863206 -134.6835)
		(width 0.11684)
		(layer "In11.Cu")
		(net "ESPI_CPU0_D0")
	)
	(segment
		(start 395.718538 -314.004706)
		(end 395.835378 -313.887866)
		(width 0.11684)
		(layer "In15.Cu")
		(net "ESPI_CPU0_D0")
	)
	(segment
		(start 397.795496 -312.533284)
		(end 395.656562 -312.533284)
		(width 0.11684)
		(layer "In15.Cu")
		(net "ESPI_CPU0_D0")
	)
	(segment
		(start 395.60754 -325.193914)
		(end 395.60754 -323.970904)
		(width 0.11684)
		(layer "In15.Cu")
		(net "ESPI_CPU0_D0")
	)
	(segment
		(start 398.629124 -313.887866)
		(end 398.751806 -313.765184)
		(width 0.11684)
		(layer "In15.Cu")
		(net "ESPI_CPU0_D0")
	)
	(segment
		(start 394.941806 -320.265298)
		(end 394.941806 -318.425068)
		(width 0.11684)
		(layer "In15.Cu")
		(net "ESPI_CPU0_D0")
	)
	(segment
		(start 387.087872 -218.155012)
		(end 384.891026 -215.958166)
		(width 0.11684)
		(layer "In15.Cu")
		(net "ESPI_CPU0_D0")
	)
	(segment
		(start 395.539722 -311.924446)
		(end 397.977614 -309.486554)
		(width 0.11684)
		(layer "In15.Cu")
		(net "ESPI_CPU0_D0")
	)
	(segment
		(start 395.718538 -314.267088)
		(end 395.718538 -314.004706)
		(width 0.11684)
		(layer "In15.Cu")
		(net "ESPI_CPU0_D0")
	)
	(segment
		(start 308.972458 -167.505888)
		(end 275.529802 -167.505888)
		(width 0.11684)
		(layer "In15.Cu")
		(net "ESPI_CPU0_D0")
	)
	(segment
		(start 395.539722 -313.315604)
		(end 395.539722 -313.099704)
		(width 0.11684)
		(layer "In15.Cu")
		(net "ESPI_CPU0_D0")
	)
	(segment
		(start 397.795496 -312.982864)
		(end 397.912336 -312.866024)
		(width 0.11684)
		(layer "In15.Cu")
		(net "ESPI_CPU0_D0")
	)
	(segment
		(start 394.49502 -317.978282)
		(end 394.438124 -317.840868)
		(width 0.11684)
		(layer "In15.Cu")
		(net "ESPI_CPU0_D0")
	)
	(segment
		(start 395.60754 -323.970904)
		(end 394.059664 -322.423028)
		(width 0.11684)
		(layer "In15.Cu")
		(net "ESPI_CPU0_D0")
	)
	(segment
		(start 398.751806 -313.765184)
		(end 398.751806 -313.549284)
		(width 0.11684)
		(layer "In15.Cu")
		(net "ESPI_CPU0_D0")
	)
	(segment
		(start 395.656562 -313.432444)
		(end 395.539722 -313.315604)
		(width 0.11684)
		(layer "In15.Cu")
		(net "ESPI_CPU0_D0")
	)
	(segment
		(start 395.627606 -218.155012)
		(end 387.087872 -218.155012)
		(width 0.11684)
		(layer "In15.Cu")
		(net "ESPI_CPU0_D0")
	)
	(segment
		(start 331.225652 -176.723548)
		(end 308.972458 -167.505888)
		(width 0.11684)
		(layer "In15.Cu")
		(net "ESPI_CPU0_D0")
	)
	(segment
		(start 397.977614 -220.50502)
		(end 395.627606 -218.155012)
		(width 0.11684)
		(layer "In15.Cu")
		(net "ESPI_CPU0_D0")
	)
	(segment
		(start 394.438124 -315.547502)
		(end 395.718538 -314.267088)
		(width 0.11684)
		(layer "In15.Cu")
		(net "ESPI_CPU0_D0")
	)
	(segment
		(start 398.634966 -313.432444)
		(end 395.656562 -313.432444)
		(width 0.11684)
		(layer "In15.Cu")
		(net "ESPI_CPU0_D0")
	)
	(segment
		(start 395.656562 -312.533284)
		(end 395.539722 -312.416444)
		(width 0.11684)
		(layer "In15.Cu")
		(net "ESPI_CPU0_D0")
	)
	(segment
		(start 227.724462 -144.18056)
		(end 215.688418 -142.995142)
		(width 0.11684)
		(layer "In15.Cu")
		(net "ESPI_CPU0_D0")
	)
	(segment
		(start 398.751806 -313.549284)
		(end 398.634966 -313.432444)
		(width 0.11684)
		(layer "In15.Cu")
		(net "ESPI_CPU0_D0")
	)
	(segment
		(start 395.539722 -312.416444)
		(end 395.539722 -311.924446)
		(width 0.11684)
		(layer "In15.Cu")
		(net "ESPI_CPU0_D0")
	)
	(segment
		(start 198.905622 -135.303514)
		(end 197.4088 -134.6835)
		(width 0.11684)
		(layer "In15.Cu")
		(net "ESPI_CPU0_D0")
	)
	(segment
		(start 275.529802 -167.505888)
		(end 270.133572 -165.868858)
		(width 0.11684)
		(layer "In15.Cu")
		(net "ESPI_CPU0_D0")
	)
	(segment
		(start 207.245712 -140.43406)
		(end 201.48042 -137.878312)
		(width 0.11684)
		(layer "In15.Cu")
		(net "ESPI_CPU0_D0")
	)
	(segment
		(start 384.891026 -215.958166)
		(end 370.46027 -215.958166)
		(width 0.11684)
		(layer "In15.Cu")
		(net "ESPI_CPU0_D0")
	)
	(segment
		(start 394.059664 -321.14744)
		(end 394.941806 -320.265298)
		(width 0.11684)
		(layer "In15.Cu")
		(net "ESPI_CPU0_D0")
	)
	(segment
		(start 395.656562 -312.982864)
		(end 397.795496 -312.982864)
		(width 0.11684)
		(layer "In15.Cu")
		(net "ESPI_CPU0_D0")
	)
	(segment
		(start 215.688418 -142.995142)
		(end 207.245712 -140.43406)
		(width 0.11684)
		(layer "In15.Cu")
		(net "ESPI_CPU0_D0")
	)
	(segment
		(start 394.059664 -322.423028)
		(end 394.059664 -321.14744)
		(width 0.11684)
		(layer "In15.Cu")
		(net "ESPI_CPU0_D0")
	)
	(segment
		(start 201.48042 -137.878312)
		(end 198.905622 -135.303514)
		(width 0.11684)
		(layer "In15.Cu")
		(net "ESPI_CPU0_D0")
	)
	(segment
		(start 237.674658 -144.18056)
		(end 227.724462 -144.18056)
		(width 0.11684)
		(layer "In15.Cu")
		(net "ESPI_CPU0_D0")
	)
	(segment
		(start 370.46027 -215.958166)
		(end 331.225652 -176.723548)
		(width 0.11684)
		(layer "In15.Cu")
		(net "ESPI_CPU0_D0")
	)
	(segment
		(start 395.539722 -313.099704)
		(end 395.656562 -312.982864)
		(width 0.11684)
		(layer "In15.Cu")
		(net "ESPI_CPU0_D0")
	)
	(segment
		(start 270.133572 -165.868858)
		(end 237.674658 -144.18056)
		(width 0.11684)
		(layer "In15.Cu")
		(net "ESPI_CPU0_D0")
	)
	(segment
		(start 394.941806 -318.425068)
		(end 394.49502 -317.978282)
		(width 0.11684)
		(layer "In15.Cu")
		(net "ESPI_CPU0_D0")
	)
	(segment
		(start 397.912336 -312.866024)
		(end 397.912336 -312.650124)
		(width 0.11684)
		(layer "In15.Cu")
		(net "ESPI_CPU0_D0")
	)
	(segment
		(start 394.438124 -317.840868)
		(end 394.438124 -315.547502)
		(width 0.11684)
		(layer "In15.Cu")
		(net "ESPI_CPU0_D0")
	)
	(segment
		(start 397.977614 -309.486554)
		(end 397.977614 -220.50502)
		(width 0.11684)
		(layer "In15.Cu")
		(net "ESPI_CPU0_D0")
	)
	(segment
		(start 397.912336 -312.650124)
		(end 397.795496 -312.533284)
		(width 0.11684)
		(layer "In15.Cu")
		(net "ESPI_CPU0_D0")
	)
	(segment
		(start 395.835378 -313.887866)
		(end 398.629124 -313.887866)
		(width 0.11684)
		(layer "In15.Cu")
		(net "ESPI_CPU0_D0")
	)
	(segment
		(start 188.18733 -133.173724)
		(end 188.18733 -131.817618)
		(width 0.10668)
		(layer "F.Cu")
		(net "ESPI_CPU0_CS1_R_N")
	)
	(segment
		(start 188.58738 -130.793236)
		(end 188.58738 -129.627122)
		(width 0.10668)
		(layer "F.Cu")
		(net "ESPI_CPU0_CS1_R_N")
	)
	(segment
		(start 188.504576 -128.25349)
		(end 188.504576 -128.202944)
		(width 0.10668)
		(layer "F.Cu")
		(net "ESPI_CPU0_CS1_R_N")
	)
	(segment
		(start 188.504576 -129.544318)
		(end 188.504576 -128.25349)
		(width 0.10668)
		(layer "F.Cu")
		(net "ESPI_CPU0_CS1_R_N")
	)
	(segment
		(start 188.5188 -125.805184)
		(end 187.522104 -124.808488)
		(width 0.10668)
		(layer "F.Cu")
		(net "ESPI_CPU0_CS1_R_N")
	)
	(segment
		(start 188.504068 -128.202436)
		(end 188.504068 -127.143002)
		(width 0.10668)
		(layer "F.Cu")
		(net "ESPI_CPU0_CS1_R_N")
	)
	(segment
		(start 188.5188 -127.12827)
		(end 188.5188 -125.805184)
		(width 0.10668)
		(layer "F.Cu")
		(net "ESPI_CPU0_CS1_R_N")
	)
	(segment
		(start 187.522104 -124.808488)
		(end 187.522104 -123.45289)
		(width 0.10668)
		(layer "F.Cu")
		(net "ESPI_CPU0_CS1_R_N")
	)
	(segment
		(start 188.504068 -127.143002)
		(end 188.5188 -127.12827)
		(width 0.10668)
		(layer "F.Cu")
		(net "ESPI_CPU0_CS1_R_N")
	)
	(segment
		(start 188.214 -131.790948)
		(end 188.214 -131.166616)
		(width 0.10668)
		(layer "F.Cu")
		(net "ESPI_CPU0_CS1_R_N")
	)
	(segment
		(start 188.504576 -128.202944)
		(end 188.504068 -128.202436)
		(width 0.10668)
		(layer "F.Cu")
		(net "ESPI_CPU0_CS1_R_N")
	)
	(segment
		(start 188.58738 -129.627122)
		(end 188.504576 -129.544318)
		(width 0.10668)
		(layer "F.Cu")
		(net "ESPI_CPU0_CS1_R_N")
	)
	(segment
		(start 188.214 -131.166616)
		(end 188.58738 -130.793236)
		(width 0.10668)
		(layer "F.Cu")
		(net "ESPI_CPU0_CS1_R_N")
	)
	(segment
		(start 188.18733 -131.817618)
		(end 188.214 -131.790948)
		(width 0.10668)
		(layer "F.Cu")
		(net "ESPI_CPU0_CS1_R_N")
	)
	(via
		(at 188.504576 -128.25349)
		(size 0.762)
		(drill 0.381)
		(layers "F.Cu" "B.Cu")
		(net "ESPI_CPU0_CS1_R_N")
	)
	(via
		(at 188.214 -131.790948)
		(size 0.762)
		(drill 0.381)
		(layers "F.Cu" "B.Cu")
		(net "ESPI_CPU0_CS1_R_N")
	)
	(segment
		(start 188.18733 -135.10641)
		(end 188.18733 -133.973824)
		(width 0.10668)
		(layer "F.Cu")
		(net "ESPI_CPU0_CS1_N")
	)
	(segment
		(start 178.146202 -18.4023)
		(end 178.074574 -18.4023)
		(width 0.10668)
		(layer "F.Cu")
		(net "ESPI_CPU0_CS1_N")
	)
	(segment
		(start 188.430154 -140.600176)
		(end 188.719206 -140.311124)
		(width 0.10668)
		(layer "F.Cu")
		(net "ESPI_CPU0_CS1_N")
	)
	(segment
		(start 188.719206 -140.311124)
		(end 188.719206 -135.638286)
		(width 0.10668)
		(layer "F.Cu")
		(net "ESPI_CPU0_CS1_N")
	)
	(segment
		(start 178.267106 -18.281396)
		(end 178.146202 -18.4023)
		(width 0.10668)
		(layer "F.Cu")
		(net "ESPI_CPU0_CS1_N")
	)
	(segment
		(start 178.267106 -16.549878)
		(end 178.267106 -18.281396)
		(width 0.10668)
		(layer "F.Cu")
		(net "ESPI_CPU0_CS1_N")
	)
	(segment
		(start 188.719206 -135.638286)
		(end 188.18733 -135.10641)
		(width 0.10668)
		(layer "F.Cu")
		(net "ESPI_CPU0_CS1_N")
	)
	(via
		(at 188.430154 -140.600176)
		(size 0.508)
		(drill 0.254)
		(layers "F.Cu" "B.Cu")
		(net "ESPI_CPU0_CS1_N")
	)
	(via
		(at 405.682958 -325.701152)
		(size 0.508)
		(drill 0.254)
		(layers "F.Cu" "B.Cu")
		(net "ESPI_CPU0_CS1_N")
	)
	(via
		(at 178.074574 -18.4023)
		(size 0.508)
		(drill 0.254)
		(layers "F.Cu" "B.Cu")
		(net "ESPI_CPU0_CS1_N")
	)
	(via
		(at 402.353526 -325.045324)
		(size 0.6604)
		(drill 0.3302)
		(layers "F.Cu" "B.Cu")
		(net "ESPI_CPU0_CS1_N")
	)
	(segment
		(start 405.682958 -325.478902)
		(end 405.682958 -325.701152)
		(width 0.10668)
		(layer "B.Cu")
		(net "ESPI_CPU0_CS1_N")
	)
	(segment
		(start 398.280128 -324.812152)
		(end 398.280128 -324.415912)
		(width 0.10668)
		(layer "B.Cu")
		(net "ESPI_CPU0_CS1_N")
	)
	(segment
		(start 401.864322 -324.67804)
		(end 402.231606 -325.045324)
		(width 0.10668)
		(layer "B.Cu")
		(net "ESPI_CPU0_CS1_N")
	)
	(segment
		(start 399.83918 -324.67804)
		(end 401.864322 -324.67804)
		(width 0.10668)
		(layer "B.Cu")
		(net "ESPI_CPU0_CS1_N")
	)
	(segment
		(start 398.53362 -324.16242)
		(end 399.32356 -324.16242)
		(width 0.10668)
		(layer "B.Cu")
		(net "ESPI_CPU0_CS1_N")
	)
	(segment
		(start 399.32356 -324.16242)
		(end 399.83918 -324.67804)
		(width 0.10668)
		(layer "B.Cu")
		(net "ESPI_CPU0_CS1_N")
	)
	(segment
		(start 402.82241 -325.045324)
		(end 403.004782 -324.862952)
		(width 0.10668)
		(layer "B.Cu")
		(net "ESPI_CPU0_CS1_N")
	)
	(segment
		(start 402.353526 -325.045324)
		(end 402.82241 -325.045324)
		(width 0.10668)
		(layer "B.Cu")
		(net "ESPI_CPU0_CS1_N")
	)
	(segment
		(start 406.298908 -324.862952)
		(end 405.682958 -325.478902)
		(width 0.10668)
		(layer "B.Cu")
		(net "ESPI_CPU0_CS1_N")
	)
	(segment
		(start 398.280128 -324.415912)
		(end 398.53362 -324.16242)
		(width 0.10668)
		(layer "B.Cu")
		(net "ESPI_CPU0_CS1_N")
	)
	(segment
		(start 402.231606 -325.045324)
		(end 402.353526 -325.045324)
		(width 0.10668)
		(layer "B.Cu")
		(net "ESPI_CPU0_CS1_N")
	)
	(segment
		(start 403.004782 -324.862952)
		(end 406.298908 -324.862952)
		(width 0.10668)
		(layer "B.Cu")
		(net "ESPI_CPU0_CS1_N")
	)
	(segment
		(start 201.699114 -101.75494)
		(end 201.699114 -102.062026)
		(width 0.11684)
		(layer "In11.Cu")
		(net "ESPI_CPU0_CS1_N")
	)
	(segment
		(start 183.357266 -25.876758)
		(end 183.357266 -28.316682)
		(width 0.11684)
		(layer "In11.Cu")
		(net "ESPI_CPU0_CS1_N")
	)
	(segment
		(start 198.039228 -135.763)
		(end 196.977 -135.763)
		(width 0.11684)
		(layer "In11.Cu")
		(net "ESPI_CPU0_CS1_N")
	)
	(segment
		(start 204.367384 -116.484146)
		(end 204.367384 -129.434844)
		(width 0.11684)
		(layer "In11.Cu")
		(net "ESPI_CPU0_CS1_N")
	)
	(segment
		(start 179.293012 -21.812504)
		(end 183.357266 -25.876758)
		(width 0.11684)
		(layer "In11.Cu")
		(net "ESPI_CPU0_CS1_N")
	)
	(segment
		(start 178.074574 -18.4023)
		(end 179.293012 -19.620738)
		(width 0.11684)
		(layer "In11.Cu")
		(net "ESPI_CPU0_CS1_N")
	)
	(segment
		(start 179.293012 -19.620738)
		(end 179.293012 -21.812504)
		(width 0.11684)
		(layer "In11.Cu")
		(net "ESPI_CPU0_CS1_N")
	)
	(segment
		(start 189.64275 -141.069822)
		(end 188.899546 -141.069822)
		(width 0.11684)
		(layer "In11.Cu")
		(net "ESPI_CPU0_CS1_N")
	)
	(segment
		(start 201.699114 -102.062026)
		(end 202.042522 -102.891336)
		(width 0.11684)
		(layer "In11.Cu")
		(net "ESPI_CPU0_CS1_N")
	)
	(segment
		(start 198.99757 -91.482926)
		(end 200.264268 -94.541086)
		(width 0.11684)
		(layer "In11.Cu")
		(net "ESPI_CPU0_CS1_N")
	)
	(segment
		(start 189.952376 -79.337154)
		(end 190.59017 -79.974948)
		(width 0.11684)
		(layer "In11.Cu")
		(net "ESPI_CPU0_CS1_N")
	)
	(segment
		(start 189.07379 -78.787244)
		(end 189.39129 -79.104744)
		(width 0.11684)
		(layer "In11.Cu")
		(net "ESPI_CPU0_CS1_N")
	)
	(segment
		(start 200.264268 -94.541086)
		(end 201.699114 -101.75494)
		(width 0.11684)
		(layer "In11.Cu")
		(net "ESPI_CPU0_CS1_N")
	)
	(segment
		(start 196.85 -135.89)
		(end 196.85 -136.952228)
		(width 0.11684)
		(layer "In11.Cu")
		(net "ESPI_CPU0_CS1_N")
	)
	(segment
		(start 202.042522 -102.891336)
		(end 202.202796 -103.05161)
		(width 0.11684)
		(layer "In11.Cu")
		(net "ESPI_CPU0_CS1_N")
	)
	(segment
		(start 202.234038 -103.127048)
		(end 202.2348 -103.12781)
		(width 0.11684)
		(layer "In11.Cu")
		(net "ESPI_CPU0_CS1_N")
	)
	(segment
		(start 196.977 -135.763)
		(end 196.85 -135.89)
		(width 0.11684)
		(layer "In11.Cu")
		(net "ESPI_CPU0_CS1_N")
	)
	(segment
		(start 202.202796 -103.05161)
		(end 202.234038 -103.127048)
		(width 0.11684)
		(layer "In11.Cu")
		(net "ESPI_CPU0_CS1_N")
	)
	(segment
		(start 190.59017 -79.974948)
		(end 194.150488 -86.635844)
		(width 0.11684)
		(layer "In11.Cu")
		(net "ESPI_CPU0_CS1_N")
	)
	(segment
		(start 183.357266 -28.316682)
		(end 187.292742 -32.252158)
		(width 0.11684)
		(layer "In11.Cu")
		(net "ESPI_CPU0_CS1_N")
	)
	(segment
		(start 196.85 -136.952228)
		(end 195.574158 -138.22807)
		(width 0.11684)
		(layer "In11.Cu")
		(net "ESPI_CPU0_CS1_N")
	)
	(segment
		(start 187.292742 -74.487024)
		(end 189.07379 -78.787244)
		(width 0.11684)
		(layer "In11.Cu")
		(net "ESPI_CPU0_CS1_N")
	)
	(segment
		(start 204.348334 -108.230924)
		(end 204.348334 -116.465096)
		(width 0.11684)
		(layer "In11.Cu")
		(net "ESPI_CPU0_CS1_N")
	)
	(segment
		(start 189.39129 -79.104744)
		(end 189.952376 -79.337154)
		(width 0.11684)
		(layer "In11.Cu")
		(net "ESPI_CPU0_CS1_N")
	)
	(segment
		(start 194.150488 -86.635844)
		(end 198.99757 -91.482926)
		(width 0.11684)
		(layer "In11.Cu")
		(net "ESPI_CPU0_CS1_N")
	)
	(segment
		(start 195.574158 -138.22807)
		(end 195.574158 -138.872214)
		(width 0.11684)
		(layer "In11.Cu")
		(net "ESPI_CPU0_CS1_N")
	)
	(segment
		(start 190.420498 -140.292074)
		(end 189.64275 -141.069822)
		(width 0.11684)
		(layer "In11.Cu")
		(net "ESPI_CPU0_CS1_N")
	)
	(segment
		(start 202.2348 -103.12781)
		(end 204.348334 -108.230924)
		(width 0.11684)
		(layer "In11.Cu")
		(net "ESPI_CPU0_CS1_N")
	)
	(segment
		(start 204.367384 -129.434844)
		(end 198.039228 -135.763)
		(width 0.11684)
		(layer "In11.Cu")
		(net "ESPI_CPU0_CS1_N")
	)
	(segment
		(start 194.154298 -140.292074)
		(end 190.420498 -140.292074)
		(width 0.11684)
		(layer "In11.Cu")
		(net "ESPI_CPU0_CS1_N")
	)
	(segment
		(start 204.348334 -116.465096)
		(end 204.367384 -116.484146)
		(width 0.11684)
		(layer "In11.Cu")
		(net "ESPI_CPU0_CS1_N")
	)
	(segment
		(start 188.899546 -141.069822)
		(end 188.430154 -140.600176)
		(width 0.11684)
		(layer "In11.Cu")
		(net "ESPI_CPU0_CS1_N")
	)
	(segment
		(start 195.574158 -138.872214)
		(end 194.154298 -140.292074)
		(width 0.11684)
		(layer "In11.Cu")
		(net "ESPI_CPU0_CS1_N")
	)
	(segment
		(start 187.292742 -32.252158)
		(end 187.292742 -74.487024)
		(width 0.11684)
		(layer "In11.Cu")
		(net "ESPI_CPU0_CS1_N")
	)
	(segment
		(start 370.809774 -215.114886)
		(end 385.24053 -215.114886)
		(width 0.11684)
		(layer "In15.Cu")
		(net "ESPI_CPU0_CS1_N")
	)
	(segment
		(start 194.783202 -134.578852)
		(end 194.86118 -134.500874)
		(width 0.11684)
		(layer "In15.Cu")
		(net "ESPI_CPU0_CS1_N")
	)
	(segment
		(start 270.49857 -165.098222)
		(end 275.655278 -166.662608)
		(width 0.11684)
		(layer "In15.Cu")
		(net "ESPI_CPU0_CS1_N")
	)
	(segment
		(start 402.585682 -319.613534)
		(end 399.097246 -323.10197)
		(width 0.11684)
		(layer "In15.Cu")
		(net "ESPI_CPU0_CS1_N")
	)
	(segment
		(start 215.581992 -139.875006)
		(end 232.987596 -143.33728)
		(width 0.11684)
		(layer "In15.Cu")
		(net "ESPI_CPU0_CS1_N")
	)
	(segment
		(start 404.27529 -325.179944)
		(end 404.855934 -325.179944)
		(width 0.11684)
		(layer "In15.Cu")
		(net "ESPI_CPU0_CS1_N")
	)
	(segment
		(start 275.655278 -166.662608)
		(end 309.141368 -166.662608)
		(width 0.11684)
		(layer "In15.Cu")
		(net "ESPI_CPU0_CS1_N")
	)
	(segment
		(start 194.783202 -134.753604)
		(end 194.783202 -134.578852)
		(width 0.11684)
		(layer "In15.Cu")
		(net "ESPI_CPU0_CS1_N")
	)
	(segment
		(start 194.86118 -134.486142)
		(end 195.699634 -133.647688)
		(width 0.11684)
		(layer "In15.Cu")
		(net "ESPI_CPU0_CS1_N")
	)
	(segment
		(start 404.805642 -313.886342)
		(end 404.805642 -318.586104)
		(width 0.11684)
		(layer "In15.Cu")
		(net "ESPI_CPU0_CS1_N")
	)
	(segment
		(start 309.141368 -166.662608)
		(end 331.702664 -176.007776)
		(width 0.11684)
		(layer "In15.Cu")
		(net "ESPI_CPU0_CS1_N")
	)
	(segment
		(start 403.778212 -319.613534)
		(end 402.585682 -319.613534)
		(width 0.11684)
		(layer "In15.Cu")
		(net "ESPI_CPU0_CS1_N")
	)
	(segment
		(start 404.855934 -325.179944)
		(end 405.377904 -325.396098)
		(width 0.11684)
		(layer "In15.Cu")
		(net "ESPI_CPU0_CS1_N")
	)
	(segment
		(start 189.362842 -135.404606)
		(end 192.301368 -135.404606)
		(width 0.11684)
		(layer "In15.Cu")
		(net "ESPI_CPU0_CS1_N")
	)
	(segment
		(start 194.314064 -135.222742)
		(end 194.783202 -134.753604)
		(width 0.11684)
		(layer "In15.Cu")
		(net "ESPI_CPU0_CS1_N")
	)
	(segment
		(start 194.86118 -134.500874)
		(end 194.86118 -134.486142)
		(width 0.11684)
		(layer "In15.Cu")
		(net "ESPI_CPU0_CS1_N")
	)
	(segment
		(start 206.68996 -135.54837)
		(end 209.222594 -137.241026)
		(width 0.11684)
		(layer "In15.Cu")
		(net "ESPI_CPU0_CS1_N")
	)
	(segment
		(start 188.430154 -140.600176)
		(end 188.34989 -140.600176)
		(width 0.11684)
		(layer "In15.Cu")
		(net "ESPI_CPU0_CS1_N")
	)
	(segment
		(start 395.97711 -217.311732)
		(end 398.820894 -220.155516)
		(width 0.11684)
		(layer "In15.Cu")
		(net "ESPI_CPU0_CS1_N")
	)
	(segment
		(start 398.820894 -220.155516)
		(end 398.820894 -307.901594)
		(width 0.11684)
		(layer "In15.Cu")
		(net "ESPI_CPU0_CS1_N")
	)
	(segment
		(start 400.65833 -326.678036)
		(end 404.27529 -325.179944)
		(width 0.11684)
		(layer "In15.Cu")
		(net "ESPI_CPU0_CS1_N")
	)
	(segment
		(start 192.483232 -135.222742)
		(end 194.314064 -135.222742)
		(width 0.11684)
		(layer "In15.Cu")
		(net "ESPI_CPU0_CS1_N")
	)
	(segment
		(start 398.820894 -307.901594)
		(end 404.805642 -313.886342)
		(width 0.11684)
		(layer "In15.Cu")
		(net "ESPI_CPU0_CS1_N")
	)
	(segment
		(start 232.987596 -143.33728)
		(end 237.931198 -143.33728)
		(width 0.11684)
		(layer "In15.Cu")
		(net "ESPI_CPU0_CS1_N")
	)
	(segment
		(start 385.24053 -215.114886)
		(end 387.437376 -217.311732)
		(width 0.11684)
		(layer "In15.Cu")
		(net "ESPI_CPU0_CS1_N")
	)
	(segment
		(start 195.699634 -133.647688)
		(end 202.100688 -133.647688)
		(width 0.11684)
		(layer "In15.Cu")
		(net "ESPI_CPU0_CS1_N")
	)
	(segment
		(start 188.157104 -135.90397)
		(end 189.362842 -135.404606)
		(width 0.11684)
		(layer "In15.Cu")
		(net "ESPI_CPU0_CS1_N")
	)
	(segment
		(start 399.397982 -326.678036)
		(end 400.65833 -326.678036)
		(width 0.11684)
		(layer "In15.Cu")
		(net "ESPI_CPU0_CS1_N")
	)
	(segment
		(start 405.377904 -325.396098)
		(end 405.682958 -325.701152)
		(width 0.11684)
		(layer "In15.Cu")
		(net "ESPI_CPU0_CS1_N")
	)
	(segment
		(start 187.58154 -136.479534)
		(end 188.157104 -135.90397)
		(width 0.11684)
		(layer "In15.Cu")
		(net "ESPI_CPU0_CS1_N")
	)
	(segment
		(start 188.34989 -140.600176)
		(end 187.58154 -139.831826)
		(width 0.11684)
		(layer "In15.Cu")
		(net "ESPI_CPU0_CS1_N")
	)
	(segment
		(start 192.301368 -135.404606)
		(end 192.483232 -135.222742)
		(width 0.11684)
		(layer "In15.Cu")
		(net "ESPI_CPU0_CS1_N")
	)
	(segment
		(start 202.100688 -133.647688)
		(end 206.68996 -135.54837)
		(width 0.11684)
		(layer "In15.Cu")
		(net "ESPI_CPU0_CS1_N")
	)
	(segment
		(start 209.222594 -137.241026)
		(end 215.581992 -139.875006)
		(width 0.11684)
		(layer "In15.Cu")
		(net "ESPI_CPU0_CS1_N")
	)
	(segment
		(start 404.805642 -318.586104)
		(end 403.778212 -319.613534)
		(width 0.11684)
		(layer "In15.Cu")
		(net "ESPI_CPU0_CS1_N")
	)
	(segment
		(start 331.702664 -176.007776)
		(end 370.809774 -215.114886)
		(width 0.11684)
		(layer "In15.Cu")
		(net "ESPI_CPU0_CS1_N")
	)
	(segment
		(start 237.931198 -143.33728)
		(end 270.49857 -165.098222)
		(width 0.11684)
		(layer "In15.Cu")
		(net "ESPI_CPU0_CS1_N")
	)
	(segment
		(start 399.097246 -326.3773)
		(end 399.397982 -326.678036)
		(width 0.11684)
		(layer "In15.Cu")
		(net "ESPI_CPU0_CS1_N")
	)
	(segment
		(start 399.097246 -323.10197)
		(end 399.097246 -326.3773)
		(width 0.11684)
		(layer "In15.Cu")
		(net "ESPI_CPU0_CS1_N")
	)
	(segment
		(start 387.437376 -217.311732)
		(end 395.97711 -217.311732)
		(width 0.11684)
		(layer "In15.Cu")
		(net "ESPI_CPU0_CS1_N")
	)
	(segment
		(start 187.58154 -139.831826)
		(end 187.58154 -136.479534)
		(width 0.11684)
		(layer "In15.Cu")
		(net "ESPI_CPU0_CS1_N")
	)
	(segment
		(start 185.039 -137.232898)
		(end 185.039 -136.538208)
		(width 0.10668)
		(layer "F.Cu")
		(net "ESPI_CPU0_ALERT_R_N")
	)
	(segment
		(start 185.039 -136.538208)
		(end 185.058304 -136.518904)
		(width 0.10668)
		(layer "F.Cu")
		(net "ESPI_CPU0_ALERT_R_N")
	)
	(segment
		(start 187.522104 -121.852944)
		(end 187.911994 -122.242834)
		(width 0.10668)
		(layer "F.Cu")
		(net "ESPI_CPU0_ALERT_R_N")
	)
	(via
		(at 187.911994 -122.242834)
		(size 0.4572)
		(drill 0.254)
		(layers "F.Cu" "B.Cu")
		(net "ESPI_CPU0_ALERT_R_N")
	)
	(via
		(at 185.058304 -136.518904)
		(size 0.508)
		(drill 0.254)
		(layers "F.Cu" "B.Cu")
		(net "ESPI_CPU0_ALERT_R_N")
	)
	(segment
		(start 186.981338 -130.795014)
		(end 187.967112 -131.780788)
		(width 0.11684)
		(layer "In11.Cu")
		(net "ESPI_CPU0_ALERT_R_N")
	)
	(segment
		(start 187.911994 -122.242834)
		(end 187.912502 -122.243342)
		(width 0.11684)
		(layer "In11.Cu")
		(net "ESPI_CPU0_ALERT_R_N")
	)
	(segment
		(start 187.912502 -123.592082)
		(end 186.981338 -124.523246)
		(width 0.11684)
		(layer "In11.Cu")
		(net "ESPI_CPU0_ALERT_R_N")
	)
	(segment
		(start 186.009026 -133.293612)
		(end 185.59018 -133.712458)
		(width 0.11684)
		(layer "In11.Cu")
		(net "ESPI_CPU0_ALERT_R_N")
	)
	(segment
		(start 185.59018 -135.987028)
		(end 185.058304 -136.518904)
		(width 0.11684)
		(layer "In11.Cu")
		(net "ESPI_CPU0_ALERT_R_N")
	)
	(segment
		(start 185.59018 -133.712458)
		(end 185.59018 -135.987028)
		(width 0.11684)
		(layer "In11.Cu")
		(net "ESPI_CPU0_ALERT_R_N")
	)
	(segment
		(start 188.332618 -133.293612)
		(end 186.009026 -133.293612)
		(width 0.11684)
		(layer "In11.Cu")
		(net "ESPI_CPU0_ALERT_R_N")
	)
	(segment
		(start 187.912502 -122.243342)
		(end 187.912502 -123.592082)
		(width 0.11684)
		(layer "In11.Cu")
		(net "ESPI_CPU0_ALERT_R_N")
	)
	(segment
		(start 186.981338 -124.523246)
		(end 186.981338 -130.795014)
		(width 0.11684)
		(layer "In11.Cu")
		(net "ESPI_CPU0_ALERT_R_N")
	)
	(segment
		(start 188.279024 -131.780788)
		(end 188.563504 -132.065268)
		(width 0.11684)
		(layer "In11.Cu")
		(net "ESPI_CPU0_ALERT_R_N")
	)
	(segment
		(start 188.563504 -133.062726)
		(end 188.332618 -133.293612)
		(width 0.11684)
		(layer "In11.Cu")
		(net "ESPI_CPU0_ALERT_R_N")
	)
	(segment
		(start 188.563504 -132.065268)
		(end 188.563504 -133.062726)
		(width 0.11684)
		(layer "In11.Cu")
		(net "ESPI_CPU0_ALERT_R_N")
	)
	(segment
		(start 187.967112 -131.780788)
		(end 188.279024 -131.780788)
		(width 0.11684)
		(layer "In11.Cu")
		(net "ESPI_CPU0_ALERT_R_N")
	)
	(segment
		(start 177.666904 -16.549878)
		(end 177.666904 -17.775428)
		(width 0.10668)
		(layer "F.Cu")
		(net "ESPI_CPU0_ALERT_N")
	)
	(via
		(at 188.2648 -146.67738)
		(size 0.508)
		(drill 0.254)
		(layers "F.Cu" "B.Cu")
		(net "ESPI_CPU0_ALERT_N")
	)
	(via
		(at 177.666904 -17.775428)
		(size 0.508)
		(drill 0.254)
		(layers "F.Cu" "B.Cu")
		(net "ESPI_CPU0_ALERT_N")
	)
	(segment
		(start 188.760862 -146.67738)
		(end 189.479174 -145.959068)
		(width 0.10668)
		(layer "B.Cu")
		(net "ESPI_CPU0_ALERT_N")
	)
	(segment
		(start 188.2648 -146.67738)
		(end 188.760862 -146.67738)
		(width 0.10668)
		(layer "B.Cu")
		(net "ESPI_CPU0_ALERT_N")
	)
	(segment
		(start 187.714636 -147.227544)
		(end 187.714636 -147.587208)
		(width 0.10668)
		(layer "B.Cu")
		(net "ESPI_CPU0_ALERT_N")
	)
	(segment
		(start 188.2648 -146.67738)
		(end 187.714636 -147.227544)
		(width 0.10668)
		(layer "B.Cu")
		(net "ESPI_CPU0_ALERT_N")
	)
	(segment
		(start 187.714636 -147.587208)
		(end 187.4647 -147.837144)
		(width 0.10668)
		(layer "B.Cu")
		(net "ESPI_CPU0_ALERT_N")
	)
	(segment
		(start 189.479174 -145.959068)
		(end 189.479174 -145.585434)
		(width 0.10668)
		(layer "B.Cu")
		(net "ESPI_CPU0_ALERT_N")
	)
	(segment
		(start 187.4647 -147.837144)
		(end 186.080908 -147.837144)
		(width 0.10668)
		(layer "B.Cu")
		(net "ESPI_CPU0_ALERT_N")
	)
	(segment
		(start 188.501274 -145.585434)
		(end 189.479174 -145.585434)
		(width 0.10668)
		(layer "B.Cu")
		(net "ESPI_CPU0_ALERT_N")
	)
	(segment
		(start 180.545232 -19.237452)
		(end 180.545232 -21.782532)
		(width 0.11684)
		(layer "In11.Cu")
		(net "ESPI_CPU0_ALERT_N")
	)
	(segment
		(start 177.666904 -17.775428)
		(end 177.907188 -17.535144)
		(width 0.11684)
		(layer "In11.Cu")
		(net "ESPI_CPU0_ALERT_N")
	)
	(segment
		(start 203.421488 -135.52043)
		(end 203.421488 -136.494774)
		(width 0.11684)
		(layer "In11.Cu")
		(net "ESPI_CPU0_ALERT_N")
	)
	(segment
		(start 200.741026 -93.26626)
		(end 202.456288 -95.356172)
		(width 0.11684)
		(layer "In11.Cu")
		(net "ESPI_CPU0_ALERT_N")
	)
	(segment
		(start 188.29528 -31.989776)
		(end 188.29528 -73.784206)
		(width 0.11684)
		(layer "In11.Cu")
		(net "ESPI_CPU0_ALERT_N")
	)
	(segment
		(start 178.842924 -17.535144)
		(end 180.545232 -19.237452)
		(width 0.11684)
		(layer "In11.Cu")
		(net "ESPI_CPU0_ALERT_N")
	)
	(segment
		(start 205.261464 -129.832608)
		(end 205.786228 -130.357372)
		(width 0.11684)
		(layer "In11.Cu")
		(net "ESPI_CPU0_ALERT_N")
	)
	(segment
		(start 203.073254 -96.279462)
		(end 203.073254 -97.995994)
		(width 0.11684)
		(layer "In11.Cu")
		(net "ESPI_CPU0_ALERT_N")
	)
	(segment
		(start 205.242414 -107.631992)
		(end 205.242414 -116.094256)
		(width 0.11684)
		(layer "In11.Cu")
		(net "ESPI_CPU0_ALERT_N")
	)
	(segment
		(start 202.590146 -137.77849)
		(end 198.938134 -141.430502)
		(width 0.11684)
		(layer "In11.Cu")
		(net "ESPI_CPU0_ALERT_N")
	)
	(segment
		(start 193.387472 -142.19936)
		(end 192.513712 -143.07312)
		(width 0.11684)
		(layer "In11.Cu")
		(net "ESPI_CPU0_ALERT_N")
	)
	(segment
		(start 188.2648 -145.698718)
		(end 188.2648 -146.67738)
		(width 0.11684)
		(layer "In11.Cu")
		(net "ESPI_CPU0_ALERT_N")
	)
	(segment
		(start 184.251346 -25.488646)
		(end 184.251346 -27.945842)
		(width 0.11684)
		(layer "In11.Cu")
		(net "ESPI_CPU0_ALERT_N")
	)
	(segment
		(start 205.261464 -116.113306)
		(end 205.261464 -129.832608)
		(width 0.11684)
		(layer "In11.Cu")
		(net "ESPI_CPU0_ALERT_N")
	)
	(segment
		(start 199.717152 -90.794586)
		(end 200.741026 -93.26626)
		(width 0.11684)
		(layer "In11.Cu")
		(net "ESPI_CPU0_ALERT_N")
	)
	(segment
		(start 194.94881 -141.430502)
		(end 194.179952 -142.19936)
		(width 0.11684)
		(layer "In11.Cu")
		(net "ESPI_CPU0_ALERT_N")
	)
	(segment
		(start 192.513712 -143.07312)
		(end 190.890398 -143.07312)
		(width 0.11684)
		(layer "In11.Cu")
		(net "ESPI_CPU0_ALERT_N")
	)
	(segment
		(start 203.417932 -103.226362)
		(end 205.242414 -107.631992)
		(width 0.11684)
		(layer "In11.Cu")
		(net "ESPI_CPU0_ALERT_N")
	)
	(segment
		(start 198.938134 -141.430502)
		(end 194.94881 -141.430502)
		(width 0.11684)
		(layer "In11.Cu")
		(net "ESPI_CPU0_ALERT_N")
	)
	(segment
		(start 205.786228 -133.15569)
		(end 203.421488 -135.52043)
		(width 0.11684)
		(layer "In11.Cu")
		(net "ESPI_CPU0_ALERT_N")
	)
	(segment
		(start 194.712844 -85.790278)
		(end 199.717152 -90.794586)
		(width 0.11684)
		(layer "In11.Cu")
		(net "ESPI_CPU0_ALERT_N")
	)
	(segment
		(start 205.242414 -116.094256)
		(end 205.261464 -116.113306)
		(width 0.11684)
		(layer "In11.Cu")
		(net "ESPI_CPU0_ALERT_N")
	)
	(segment
		(start 203.417932 -99.728782)
		(end 203.417932 -103.226362)
		(width 0.11684)
		(layer "In11.Cu")
		(net "ESPI_CPU0_ALERT_N")
	)
	(segment
		(start 205.786228 -130.357372)
		(end 205.786228 -133.15569)
		(width 0.11684)
		(layer "In11.Cu")
		(net "ESPI_CPU0_ALERT_N")
	)
	(segment
		(start 194.179952 -142.19936)
		(end 193.387472 -142.19936)
		(width 0.11684)
		(layer "In11.Cu")
		(net "ESPI_CPU0_ALERT_N")
	)
	(segment
		(start 190.890398 -143.07312)
		(end 188.2648 -145.698718)
		(width 0.11684)
		(layer "In11.Cu")
		(net "ESPI_CPU0_ALERT_N")
	)
	(segment
		(start 177.907188 -17.535144)
		(end 178.842924 -17.535144)
		(width 0.11684)
		(layer "In11.Cu")
		(net "ESPI_CPU0_ALERT_N")
	)
	(segment
		(start 203.421488 -136.494774)
		(end 202.590146 -137.326116)
		(width 0.11684)
		(layer "In11.Cu")
		(net "ESPI_CPU0_ALERT_N")
	)
	(segment
		(start 202.590146 -137.326116)
		(end 202.590146 -137.77849)
		(width 0.11684)
		(layer "In11.Cu")
		(net "ESPI_CPU0_ALERT_N")
	)
	(segment
		(start 188.29528 -73.784206)
		(end 194.712844 -85.790278)
		(width 0.11684)
		(layer "In11.Cu")
		(net "ESPI_CPU0_ALERT_N")
	)
	(segment
		(start 180.545232 -21.782532)
		(end 184.251346 -25.488646)
		(width 0.11684)
		(layer "In11.Cu")
		(net "ESPI_CPU0_ALERT_N")
	)
	(segment
		(start 203.073254 -97.995994)
		(end 203.417932 -99.728782)
		(width 0.11684)
		(layer "In11.Cu")
		(net "ESPI_CPU0_ALERT_N")
	)
	(segment
		(start 184.251346 -27.945842)
		(end 188.29528 -31.989776)
		(width 0.11684)
		(layer "In11.Cu")
		(net "ESPI_CPU0_ALERT_N")
	)
	(segment
		(start 202.456288 -95.356172)
		(end 203.073254 -96.279462)
		(width 0.11684)
		(layer "In11.Cu")
		(net "ESPI_CPU0_ALERT_N")
	)
	(segment
		(start 236.599984 -49.165002)
		(end 234.540044 -49.165002)
		(width 0.10668)
		(layer "F.Cu")
		(net "E1S_0_PWRDIS")
	)
	(via
		(at 234.540044 -49.165002)
		(size 0.508)
		(drill 0.254)
		(layers "F.Cu" "B.Cu")
		(net "E1S_0_PWRDIS")
	)
	(segment
		(start 235.40593 -49.165002)
		(end 234.540044 -49.165002)
		(width 0.10668)
		(layer "B.Cu")
		(net "E1S_0_PWRDIS")
	)
	(segment
		(start 236.601 -51.209448)
		(end 236.601 -50.193448)
		(width 0.10668)
		(layer "B.Cu")
		(net "E1S_0_PWRDIS")
	)
	(segment
		(start 235.836206 -49.595278)
		(end 235.40593 -49.165002)
		(width 0.10668)
		(layer "B.Cu")
		(net "E1S_0_PWRDIS")
	)
	(segment
		(start 236.601 -50.193448)
		(end 236.00283 -49.595278)
		(width 0.10668)
		(layer "B.Cu")
		(net "E1S_0_PWRDIS")
	)
	(segment
		(start 236.00283 -49.595278)
		(end 235.836206 -49.595278)
		(width 0.10668)
		(layer "B.Cu")
		(net "E1S_0_PWRDIS")
	)
	(segment
		(start 159.874712 -111.518954)
		(end 160.599374 -112.243616)
		(width 0.10668)
		(layer "F.Cu")
		(net "E1S_0_PRSNT_N")
	)
	(segment
		(start 220.581982 -48.65243)
		(end 223.021652 -51.0921)
		(width 0.10668)
		(layer "F.Cu")
		(net "E1S_0_PRSNT_N")
	)
	(segment
		(start 228.064568 -49.165002)
		(end 232.000044 -49.165002)
		(width 0.10668)
		(layer "F.Cu")
		(net "E1S_0_PRSNT_N")
	)
	(segment
		(start 193.86931 -93.485208)
		(end 194.305682 -93.485208)
		(width 0.10668)
		(layer "F.Cu")
		(net "E1S_0_PRSNT_N")
	)
	(segment
		(start 226.13747 -51.0921)
		(end 228.064568 -49.165002)
		(width 0.10668)
		(layer "F.Cu")
		(net "E1S_0_PRSNT_N")
	)
	(segment
		(start 159.874712 -111.221774)
		(end 159.874712 -111.518954)
		(width 0.10668)
		(layer "F.Cu")
		(net "E1S_0_PRSNT_N")
	)
	(segment
		(start 192.786 -92.401898)
		(end 193.86931 -93.485208)
		(width 0.10668)
		(layer "F.Cu")
		(net "E1S_0_PRSNT_N")
	)
	(segment
		(start 223.021652 -51.0921)
		(end 226.13747 -51.0921)
		(width 0.10668)
		(layer "F.Cu")
		(net "E1S_0_PRSNT_N")
	)
	(segment
		(start 217.478102 -48.65243)
		(end 220.581982 -48.65243)
		(width 0.10668)
		(layer "F.Cu")
		(net "E1S_0_PRSNT_N")
	)
	(via
		(at 194.305682 -93.485208)
		(size 0.508)
		(drill 0.254)
		(layers "F.Cu" "B.Cu")
		(net "E1S_0_PRSNT_N")
	)
	(via
		(at 217.478102 -48.65243)
		(size 0.508)
		(drill 0.254)
		(layers "F.Cu" "B.Cu")
		(net "E1S_0_PRSNT_N")
	)
	(via
		(at 194.5513 -48.429926)
		(size 0.508)
		(drill 0.254)
		(layers "F.Cu" "B.Cu")
		(net "E1S_0_PRSNT_N")
	)
	(via
		(at 160.599374 -112.243616)
		(size 0.508)
		(drill 0.254)
		(layers "F.Cu" "B.Cu")
		(net "E1S_0_PRSNT_N")
	)
	(segment
		(start 193.67754 -94.069662)
		(end 193.67754 -95.98279)
		(width 0.10668)
		(layer "B.Cu")
		(net "E1S_0_PRSNT_N")
	)
	(segment
		(start 193.872104 -100.694998)
		(end 193.929 -100.694998)
		(width 0.10668)
		(layer "B.Cu")
		(net "E1S_0_PRSNT_N")
	)
	(segment
		(start 194.261994 -93.485208)
		(end 193.67754 -94.069662)
		(width 0.10668)
		(layer "B.Cu")
		(net "E1S_0_PRSNT_N")
	)
	(segment
		(start 194.305682 -93.485208)
		(end 194.261994 -93.485208)
		(width 0.10668)
		(layer "B.Cu")
		(net "E1S_0_PRSNT_N")
	)
	(segment
		(start 193.412872 -96.247458)
		(end 193.412872 -100.235766)
		(width 0.10668)
		(layer "B.Cu")
		(net "E1S_0_PRSNT_N")
	)
	(segment
		(start 193.67754 -95.98279)
		(end 193.412872 -96.247458)
		(width 0.10668)
		(layer "B.Cu")
		(net "E1S_0_PRSNT_N")
	)
	(segment
		(start 193.412872 -100.235766)
		(end 193.872104 -100.694998)
		(width 0.10668)
		(layer "B.Cu")
		(net "E1S_0_PRSNT_N")
	)
	(segment
		(start 194.847464 -66.366898)
		(end 194.847464 -60.354464)
		(width 0.11684)
		(layer "In4.Cu")
		(net "E1S_0_PRSNT_N")
	)
	(segment
		(start 199.348344 -79.330804)
		(end 199.348344 -74.690478)
		(width 0.11684)
		(layer "In4.Cu")
		(net "E1S_0_PRSNT_N")
	)
	(segment
		(start 195.80352 -71.145654)
		(end 195.80352 -67.322954)
		(width 0.11684)
		(layer "In4.Cu")
		(net "E1S_0_PRSNT_N")
	)
	(segment
		(start 194.847464 -48.72609)
		(end 194.5513 -48.429926)
		(width 0.11684)
		(layer "In4.Cu")
		(net "E1S_0_PRSNT_N")
	)
	(segment
		(start 194.847464 -60.354464)
		(end 193.929 -59.436)
		(width 0.11684)
		(layer "In4.Cu")
		(net "E1S_0_PRSNT_N")
	)
	(segment
		(start 199.348344 -74.690478)
		(end 195.80352 -71.145654)
		(width 0.11684)
		(layer "In4.Cu")
		(net "E1S_0_PRSNT_N")
	)
	(segment
		(start 194.847464 -54.453536)
		(end 194.847464 -48.72609)
		(width 0.11684)
		(layer "In4.Cu")
		(net "E1S_0_PRSNT_N")
	)
	(segment
		(start 193.802 -92.981526)
		(end 193.802 -84.877148)
		(width 0.11684)
		(layer "In4.Cu")
		(net "E1S_0_PRSNT_N")
	)
	(segment
		(start 193.929 -59.436)
		(end 193.929 -55.372)
		(width 0.11684)
		(layer "In4.Cu")
		(net "E1S_0_PRSNT_N")
	)
	(segment
		(start 193.929 -55.372)
		(end 194.847464 -54.453536)
		(width 0.11684)
		(layer "In4.Cu")
		(net "E1S_0_PRSNT_N")
	)
	(segment
		(start 193.802 -84.877148)
		(end 199.348344 -79.330804)
		(width 0.11684)
		(layer "In4.Cu")
		(net "E1S_0_PRSNT_N")
	)
	(segment
		(start 194.305682 -93.485208)
		(end 193.802 -92.981526)
		(width 0.11684)
		(layer "In4.Cu")
		(net "E1S_0_PRSNT_N")
	)
	(segment
		(start 195.80352 -67.322954)
		(end 194.847464 -66.366898)
		(width 0.11684)
		(layer "In4.Cu")
		(net "E1S_0_PRSNT_N")
	)
	(segment
		(start 182.125874 -92.406216)
		(end 183.270144 -93.550486)
		(width 0.11684)
		(layer "In15.Cu")
		(net "E1S_0_PRSNT_N")
	)
	(segment
		(start 197.056502 -46.306486)
		(end 210.85429 -46.306486)
		(width 0.11684)
		(layer "In15.Cu")
		(net "E1S_0_PRSNT_N")
	)
	(segment
		(start 160.599374 -110.065312)
		(end 161.315146 -109.34954)
		(width 0.11684)
		(layer "In15.Cu")
		(net "E1S_0_PRSNT_N")
	)
	(segment
		(start 194.827144 -48.535844)
		(end 197.056502 -46.306486)
		(width 0.11684)
		(layer "In15.Cu")
		(net "E1S_0_PRSNT_N")
	)
	(segment
		(start 171.172632 -90.767662)
		(end 177.442114 -90.767662)
		(width 0.11684)
		(layer "In15.Cu")
		(net "E1S_0_PRSNT_N")
	)
	(segment
		(start 161.315146 -109.34954)
		(end 161.315146 -106.99623)
		(width 0.11684)
		(layer "In15.Cu")
		(net "E1S_0_PRSNT_N")
	)
	(segment
		(start 166.459662 -102.355142)
		(end 166.459662 -95.480632)
		(width 0.11684)
		(layer "In15.Cu")
		(net "E1S_0_PRSNT_N")
	)
	(segment
		(start 165.114224 -103.197152)
		(end 165.617652 -103.197152)
		(width 0.11684)
		(layer "In15.Cu")
		(net "E1S_0_PRSNT_N")
	)
	(segment
		(start 190.688214 -93.226128)
		(end 194.046602 -93.226128)
		(width 0.11684)
		(layer "In15.Cu")
		(net "E1S_0_PRSNT_N")
	)
	(segment
		(start 185.356754 -96.030796)
		(end 188.635386 -96.030796)
		(width 0.11684)
		(layer "In15.Cu")
		(net "E1S_0_PRSNT_N")
	)
	(segment
		(start 179.080668 -92.406216)
		(end 182.125874 -92.406216)
		(width 0.11684)
		(layer "In15.Cu")
		(net "E1S_0_PRSNT_N")
	)
	(segment
		(start 161.315146 -106.99623)
		(end 165.114224 -103.197152)
		(width 0.11684)
		(layer "In15.Cu")
		(net "E1S_0_PRSNT_N")
	)
	(segment
		(start 166.459662 -95.480632)
		(end 171.172632 -90.767662)
		(width 0.11684)
		(layer "In15.Cu")
		(net "E1S_0_PRSNT_N")
	)
	(segment
		(start 190.36284 -93.932502)
		(end 190.36284 -93.551502)
		(width 0.11684)
		(layer "In15.Cu")
		(net "E1S_0_PRSNT_N")
	)
	(segment
		(start 177.442114 -90.767662)
		(end 179.080668 -92.406216)
		(width 0.11684)
		(layer "In15.Cu")
		(net "E1S_0_PRSNT_N")
	)
	(segment
		(start 183.270144 -93.944186)
		(end 185.356754 -96.030796)
		(width 0.11684)
		(layer "In15.Cu")
		(net "E1S_0_PRSNT_N")
	)
	(segment
		(start 190.36284 -93.551502)
		(end 190.688214 -93.226128)
		(width 0.11684)
		(layer "In15.Cu")
		(net "E1S_0_PRSNT_N")
	)
	(segment
		(start 194.657218 -48.535844)
		(end 194.827144 -48.535844)
		(width 0.11684)
		(layer "In15.Cu")
		(net "E1S_0_PRSNT_N")
	)
	(segment
		(start 213.200234 -48.65243)
		(end 217.478102 -48.65243)
		(width 0.11684)
		(layer "In15.Cu")
		(net "E1S_0_PRSNT_N")
	)
	(segment
		(start 165.617652 -103.197152)
		(end 166.459662 -102.355142)
		(width 0.11684)
		(layer "In15.Cu")
		(net "E1S_0_PRSNT_N")
	)
	(segment
		(start 210.85429 -46.306486)
		(end 213.200234 -48.65243)
		(width 0.11684)
		(layer "In15.Cu")
		(net "E1S_0_PRSNT_N")
	)
	(segment
		(start 189.38748 -95.278702)
		(end 189.38748 -94.907862)
		(width 0.11684)
		(layer "In15.Cu")
		(net "E1S_0_PRSNT_N")
	)
	(segment
		(start 160.599374 -112.243616)
		(end 160.599374 -110.065312)
		(width 0.11684)
		(layer "In15.Cu")
		(net "E1S_0_PRSNT_N")
	)
	(segment
		(start 194.5513 -48.429926)
		(end 194.657218 -48.535844)
		(width 0.11684)
		(layer "In15.Cu")
		(net "E1S_0_PRSNT_N")
	)
	(segment
		(start 189.38748 -94.907862)
		(end 190.36284 -93.932502)
		(width 0.11684)
		(layer "In15.Cu")
		(net "E1S_0_PRSNT_N")
	)
	(segment
		(start 194.046602 -93.226128)
		(end 194.305682 -93.485208)
		(width 0.11684)
		(layer "In15.Cu")
		(net "E1S_0_PRSNT_N")
	)
	(segment
		(start 188.635386 -96.030796)
		(end 189.38748 -95.278702)
		(width 0.11684)
		(layer "In15.Cu")
		(net "E1S_0_PRSNT_N")
	)
	(segment
		(start 183.270144 -93.550486)
		(end 183.270144 -93.944186)
		(width 0.11684)
		(layer "In15.Cu")
		(net "E1S_0_PRSNT_N")
	)
	(segment
		(start 224.6122 -48.78197)
		(end 225.022918 -48.78197)
		(width 0.10668)
		(layer "F.Cu")
		(net "E1S_0_PERST1_CLKREQ_N")
	)
	(segment
		(start 163.219384 -111.300514)
		(end 162.359594 -111.300514)
		(width 0.10668)
		(layer "F.Cu")
		(net "E1S_0_PERST1_CLKREQ_N")
	)
	(segment
		(start 163.30295 -111.216948)
		(end 163.219384 -111.300514)
		(width 0.10668)
		(layer "F.Cu")
		(net "E1S_0_PERST1_CLKREQ_N")
	)
	(segment
		(start 228.10216 -48.565054)
		(end 232.000044 -48.565054)
		(width 0.10668)
		(layer "F.Cu")
		(net "E1S_0_PERST1_CLKREQ_N")
	)
	(segment
		(start 225.022918 -48.78197)
		(end 225.895154 -49.654206)
		(width 0.10668)
		(layer "F.Cu")
		(net "E1S_0_PERST1_CLKREQ_N")
	)
	(segment
		(start 224.6122 -48.78197)
		(end 224.6122 -47.612046)
		(width 0.10668)
		(layer "F.Cu")
		(net "E1S_0_PERST1_CLKREQ_N")
	)
	(segment
		(start 225.895154 -49.654206)
		(end 227.013008 -49.654206)
		(width 0.10668)
		(layer "F.Cu")
		(net "E1S_0_PERST1_CLKREQ_N")
	)
	(segment
		(start 227.013008 -49.654206)
		(end 228.10216 -48.565054)
		(width 0.10668)
		(layer "F.Cu")
		(net "E1S_0_PERST1_CLKREQ_N")
	)
	(via
		(at 225.895154 -49.654206)
		(size 0.508)
		(drill 0.254)
		(layers "F.Cu" "B.Cu")
		(net "E1S_0_PERST1_CLKREQ_N")
	)
	(via
		(at 230.891842 -74.862436)
		(size 0.508)
		(drill 0.254)
		(layers "F.Cu" "B.Cu")
		(net "E1S_0_PERST1_CLKREQ_N")
	)
	(via
		(at 162.359594 -111.300514)
		(size 0.508)
		(drill 0.254)
		(layers "F.Cu" "B.Cu")
		(net "E1S_0_PERST1_CLKREQ_N")
	)
	(segment
		(start 226.664012 -79.090266)
		(end 230.891842 -74.862436)
		(width 0.11684)
		(layer "In6.Cu")
		(net "E1S_0_PERST1_CLKREQ_N")
	)
	(segment
		(start 175.390048 -82.648044)
		(end 177.836068 -82.648044)
		(width 0.11684)
		(layer "In6.Cu")
		(net "E1S_0_PERST1_CLKREQ_N")
	)
	(segment
		(start 172.018706 -88.423242)
		(end 172.763434 -87.678514)
		(width 0.11684)
		(layer "In6.Cu")
		(net "E1S_0_PERST1_CLKREQ_N")
	)
	(segment
		(start 189.117224 -82.082386)
		(end 191.148462 -82.082386)
		(width 0.11684)
		(layer "In6.Cu")
		(net "E1S_0_PERST1_CLKREQ_N")
	)
	(segment
		(start 220.468444 -79.090266)
		(end 226.664012 -79.090266)
		(width 0.11684)
		(layer "In6.Cu")
		(net "E1S_0_PERST1_CLKREQ_N")
	)
	(segment
		(start 160.551114 -97.59188)
		(end 169.719752 -88.423242)
		(width 0.11684)
		(layer "In6.Cu")
		(net "E1S_0_PERST1_CLKREQ_N")
	)
	(segment
		(start 192.811908 -80.41894)
		(end 195.977764 -80.41894)
		(width 0.11684)
		(layer "In6.Cu")
		(net "E1S_0_PERST1_CLKREQ_N")
	)
	(segment
		(start 195.977764 -80.41894)
		(end 196.423534 -80.86471)
		(width 0.11684)
		(layer "In6.Cu")
		(net "E1S_0_PERST1_CLKREQ_N")
	)
	(segment
		(start 191.148462 -82.082386)
		(end 192.811908 -80.41894)
		(width 0.11684)
		(layer "In6.Cu")
		(net "E1S_0_PERST1_CLKREQ_N")
	)
	(segment
		(start 188.551312 -82.648298)
		(end 189.117224 -82.082386)
		(width 0.11684)
		(layer "In6.Cu")
		(net "E1S_0_PERST1_CLKREQ_N")
	)
	(segment
		(start 172.763434 -87.678514)
		(end 172.763434 -86.510876)
		(width 0.11684)
		(layer "In6.Cu")
		(net "E1S_0_PERST1_CLKREQ_N")
	)
	(segment
		(start 172.763434 -86.510876)
		(end 172.798486 -86.475824)
		(width 0.11684)
		(layer "In6.Cu")
		(net "E1S_0_PERST1_CLKREQ_N")
	)
	(segment
		(start 161.816542 -109.76229)
		(end 161.397696 -109.343444)
		(width 0.11684)
		(layer "In6.Cu")
		(net "E1S_0_PERST1_CLKREQ_N")
	)
	(segment
		(start 161.397696 -109.343444)
		(end 161.397696 -106.442002)
		(width 0.11684)
		(layer "In6.Cu")
		(net "E1S_0_PERST1_CLKREQ_N")
	)
	(segment
		(start 160.551114 -105.59542)
		(end 160.551114 -97.59188)
		(width 0.11684)
		(layer "In6.Cu")
		(net "E1S_0_PERST1_CLKREQ_N")
	)
	(segment
		(start 177.836068 -82.648044)
		(end 177.836322 -82.648298)
		(width 0.11684)
		(layer "In6.Cu")
		(net "E1S_0_PERST1_CLKREQ_N")
	)
	(segment
		(start 162.359594 -111.300514)
		(end 161.816542 -110.757462)
		(width 0.11684)
		(layer "In6.Cu")
		(net "E1S_0_PERST1_CLKREQ_N")
	)
	(segment
		(start 196.423534 -80.86471)
		(end 218.694 -80.86471)
		(width 0.11684)
		(layer "In6.Cu")
		(net "E1S_0_PERST1_CLKREQ_N")
	)
	(segment
		(start 161.816542 -110.757462)
		(end 161.816542 -109.76229)
		(width 0.11684)
		(layer "In6.Cu")
		(net "E1S_0_PERST1_CLKREQ_N")
	)
	(segment
		(start 177.836322 -82.648298)
		(end 188.551312 -82.648298)
		(width 0.11684)
		(layer "In6.Cu")
		(net "E1S_0_PERST1_CLKREQ_N")
	)
	(segment
		(start 169.719752 -88.423242)
		(end 172.018706 -88.423242)
		(width 0.11684)
		(layer "In6.Cu")
		(net "E1S_0_PERST1_CLKREQ_N")
	)
	(segment
		(start 175.04664 -82.648298)
		(end 175.389794 -82.648298)
		(width 0.11684)
		(layer "In6.Cu")
		(net "E1S_0_PERST1_CLKREQ_N")
	)
	(segment
		(start 172.798486 -84.896452)
		(end 175.04664 -82.648298)
		(width 0.11684)
		(layer "In6.Cu")
		(net "E1S_0_PERST1_CLKREQ_N")
	)
	(segment
		(start 172.798486 -86.475824)
		(end 172.798486 -84.896452)
		(width 0.11684)
		(layer "In6.Cu")
		(net "E1S_0_PERST1_CLKREQ_N")
	)
	(segment
		(start 161.397696 -106.442002)
		(end 160.551114 -105.59542)
		(width 0.11684)
		(layer "In6.Cu")
		(net "E1S_0_PERST1_CLKREQ_N")
	)
	(segment
		(start 218.694 -80.86471)
		(end 220.468444 -79.090266)
		(width 0.11684)
		(layer "In6.Cu")
		(net "E1S_0_PERST1_CLKREQ_N")
	)
	(segment
		(start 175.389794 -82.648298)
		(end 175.390048 -82.648044)
		(width 0.11684)
		(layer "In6.Cu")
		(net "E1S_0_PERST1_CLKREQ_N")
	)
	(segment
		(start 229.692962 -73.663556)
		(end 230.891842 -74.862436)
		(width 0.11684)
		(layer "In11.Cu")
		(net "E1S_0_PERST1_CLKREQ_N")
	)
	(segment
		(start 229.692962 -53.452014)
		(end 229.692962 -73.663556)
		(width 0.11684)
		(layer "In11.Cu")
		(net "E1S_0_PERST1_CLKREQ_N")
	)
	(segment
		(start 225.895154 -49.654206)
		(end 229.692962 -53.452014)
		(width 0.11684)
		(layer "In11.Cu")
		(net "E1S_0_PERST1_CLKREQ_N")
	)
	(segment
		(start 86.868 -222.070422)
		(end 86.868 -221.208854)
		(width 0.10668)
		(layer "F.Cu")
		(net "CPU1_XTRIG_R2_L7")
	)
	(segment
		(start 86.868 -221.208854)
		(end 89.733374 -218.34348)
		(width 0.10668)
		(layer "F.Cu")
		(net "CPU1_XTRIG_R2_L7")
	)
	(via
		(at 91.204034 -213.077552)
		(size 0.6604)
		(drill 0.3302)
		(layers "F.Cu" "B.Cu")
		(net "CPU1_XTRIG_R2_L7")
	)
	(via
		(at 89.733374 -218.34348)
		(size 0.508)
		(drill 0.254)
		(layers "F.Cu" "B.Cu")
		(net "CPU1_XTRIG_R2_L7")
	)
	(segment
		(start 91.204034 -213.839552)
		(end 89.633044 -215.410542)
		(width 0.10668)
		(layer "B.Cu")
		(net "CPU1_XTRIG_R2_L7")
	)
	(segment
		(start 91.204034 -211.9884)
		(end 91.204034 -213.077552)
		(width 0.10668)
		(layer "B.Cu")
		(net "CPU1_XTRIG_R2_L7")
	)
	(segment
		(start 90.057986 -208.253584)
		(end 90.057986 -210.842352)
		(width 0.10668)
		(layer "B.Cu")
		(net "CPU1_XTRIG_R2_L7")
	)
	(segment
		(start 90.057986 -210.842352)
		(end 91.204034 -211.9884)
		(width 0.10668)
		(layer "B.Cu")
		(net "CPU1_XTRIG_R2_L7")
	)
	(segment
		(start 89.614502 -207.8101)
		(end 90.057986 -208.253584)
		(width 0.10668)
		(layer "B.Cu")
		(net "CPU1_XTRIG_R2_L7")
	)
	(segment
		(start 89.633044 -218.24315)
		(end 89.733374 -218.34348)
		(width 0.10668)
		(layer "B.Cu")
		(net "CPU1_XTRIG_R2_L7")
	)
	(segment
		(start 89.633044 -215.410542)
		(end 89.633044 -218.24315)
		(width 0.10668)
		(layer "B.Cu")
		(net "CPU1_XTRIG_R2_L7")
	)
	(segment
		(start 91.204034 -213.077552)
		(end 91.204034 -213.839552)
		(width 0.10668)
		(layer "B.Cu")
		(net "CPU1_XTRIG_R2_L7")
	)
	(segment
		(start 90.55989 -216.06891)
		(end 90.55989 -215.825832)
		(width 0.10668)
		(layer "F.Cu")
		(net "CPU1_XTRIG_R2_L6")
	)
	(segment
		(start 85.927946 -222.070422)
		(end 85.927946 -220.700854)
		(width 0.10668)
		(layer "F.Cu")
		(net "CPU1_XTRIG_R2_L6")
	)
	(segment
		(start 85.927946 -220.700854)
		(end 90.55989 -216.06891)
		(width 0.10668)
		(layer "F.Cu")
		(net "CPU1_XTRIG_R2_L6")
	)
	(via
		(at 90.55989 -215.825832)
		(size 0.508)
		(drill 0.254)
		(layers "F.Cu" "B.Cu")
		(net "CPU1_XTRIG_R2_L6")
	)
	(via
		(at 91.458034 -211.172552)
		(size 0.6604)
		(drill 0.3302)
		(layers "F.Cu" "B.Cu")
		(net "CPU1_XTRIG_R2_L6")
	)
	(segment
		(start 91.895676 -211.610194)
		(end 91.458034 -211.172552)
		(width 0.10668)
		(layer "B.Cu")
		(net "CPU1_XTRIG_R2_L6")
	)
	(segment
		(start 90.55989 -215.448896)
		(end 91.895676 -214.11311)
		(width 0.10668)
		(layer "B.Cu")
		(net "CPU1_XTRIG_R2_L6")
	)
	(segment
		(start 91.895676 -214.11311)
		(end 91.895676 -211.610194)
		(width 0.10668)
		(layer "B.Cu")
		(net "CPU1_XTRIG_R2_L6")
	)
	(segment
		(start 91.458034 -211.172552)
		(end 90.503502 -210.21802)
		(width 0.10668)
		(layer "B.Cu")
		(net "CPU1_XTRIG_R2_L6")
	)
	(segment
		(start 90.503502 -210.21802)
		(end 90.503502 -207.8101)
		(width 0.10668)
		(layer "B.Cu")
		(net "CPU1_XTRIG_R2_L6")
	)
	(segment
		(start 90.55989 -215.825832)
		(end 90.55989 -215.448896)
		(width 0.10668)
		(layer "B.Cu")
		(net "CPU1_XTRIG_R2_L6")
	)
	(segment
		(start 90.65133 -218.386914)
		(end 90.58529 -218.386914)
		(width 0.10668)
		(layer "F.Cu")
		(net "CPU1_XTRIG_R2_L5")
	)
	(segment
		(start 86.868 -222.735648)
		(end 86.868 -223.690434)
		(width 0.10668)
		(layer "F.Cu")
		(net "CPU1_XTRIG_R2_L5")
	)
	(segment
		(start 87.345774 -222.257874)
		(end 86.868 -222.735648)
		(width 0.10668)
		(layer "F.Cu")
		(net "CPU1_XTRIG_R2_L5")
	)
	(segment
		(start 90.58529 -218.386914)
		(end 87.345774 -221.62643)
		(width 0.10668)
		(layer "F.Cu")
		(net "CPU1_XTRIG_R2_L5")
	)
	(segment
		(start 87.345774 -221.62643)
		(end 87.345774 -222.257874)
		(width 0.10668)
		(layer "F.Cu")
		(net "CPU1_XTRIG_R2_L5")
	)
	(via
		(at 91.280234 -209.470752)
		(size 0.6604)
		(drill 0.3302)
		(layers "F.Cu" "B.Cu")
		(net "CPU1_XTRIG_R2_L5")
	)
	(via
		(at 90.65133 -218.386914)
		(size 0.508)
		(drill 0.254)
		(layers "F.Cu" "B.Cu")
		(net "CPU1_XTRIG_R2_L5")
	)
	(segment
		(start 92.376244 -210.566762)
		(end 91.280234 -209.470752)
		(width 0.10668)
		(layer "B.Cu")
		(net "CPU1_XTRIG_R2_L5")
	)
	(segment
		(start 90.151712 -217.704416)
		(end 90.151712 -217.103198)
		(width 0.10668)
		(layer "B.Cu")
		(net "CPU1_XTRIG_R2_L5")
	)
	(segment
		(start 91.280234 -209.470752)
		(end 91.392502 -209.358484)
		(width 0.10668)
		(layer "B.Cu")
		(net "CPU1_XTRIG_R2_L5")
	)
	(segment
		(start 90.151712 -217.103198)
		(end 91.213432 -216.041478)
		(width 0.10668)
		(layer "B.Cu")
		(net "CPU1_XTRIG_R2_L5")
	)
	(segment
		(start 90.65133 -218.204034)
		(end 90.151712 -217.704416)
		(width 0.10668)
		(layer "B.Cu")
		(net "CPU1_XTRIG_R2_L5")
	)
	(segment
		(start 91.392502 -209.358484)
		(end 91.392502 -207.8101)
		(width 0.10668)
		(layer "B.Cu")
		(net "CPU1_XTRIG_R2_L5")
	)
	(segment
		(start 91.213432 -216.041478)
		(end 91.213432 -215.430354)
		(width 0.10668)
		(layer "B.Cu")
		(net "CPU1_XTRIG_R2_L5")
	)
	(segment
		(start 91.213432 -215.430354)
		(end 92.376244 -214.267542)
		(width 0.10668)
		(layer "B.Cu")
		(net "CPU1_XTRIG_R2_L5")
	)
	(segment
		(start 92.376244 -214.267542)
		(end 92.376244 -210.566762)
		(width 0.10668)
		(layer "B.Cu")
		(net "CPU1_XTRIG_R2_L5")
	)
	(segment
		(start 90.65133 -218.386914)
		(end 90.65133 -218.204034)
		(width 0.10668)
		(layer "B.Cu")
		(net "CPU1_XTRIG_R2_L5")
	)
	(segment
		(start 85.927946 -223.690434)
		(end 85.927946 -222.652082)
		(width 0.10668)
		(layer "F.Cu")
		(net "CPU1_XTRIG_R2_L4")
	)
	(segment
		(start 86.389464 -222.190564)
		(end 86.389464 -220.821504)
		(width 0.10668)
		(layer "F.Cu")
		(net "CPU1_XTRIG_R2_L4")
	)
	(segment
		(start 86.389464 -220.821504)
		(end 89.79154 -217.419428)
		(width 0.10668)
		(layer "F.Cu")
		(net "CPU1_XTRIG_R2_L4")
	)
	(segment
		(start 89.79154 -217.419428)
		(end 90.7796 -217.419428)
		(width 0.10668)
		(layer "F.Cu")
		(net "CPU1_XTRIG_R2_L4")
	)
	(segment
		(start 85.927946 -222.652082)
		(end 86.389464 -222.190564)
		(width 0.10668)
		(layer "F.Cu")
		(net "CPU1_XTRIG_R2_L4")
	)
	(via
		(at 90.7796 -217.419428)
		(size 0.508)
		(drill 0.254)
		(layers "F.Cu" "B.Cu")
		(net "CPU1_XTRIG_R2_L4")
	)
	(via
		(at 92.626434 -209.510884)
		(size 0.6604)
		(drill 0.3302)
		(layers "F.Cu" "B.Cu")
		(net "CPU1_XTRIG_R2_L4")
	)
	(segment
		(start 91.650566 -216.548462)
		(end 91.650566 -215.705436)
		(width 0.10668)
		(layer "B.Cu")
		(net "CPU1_XTRIG_R2_L4")
	)
	(segment
		(start 92.875862 -209.760312)
		(end 92.626434 -209.510884)
		(width 0.10668)
		(layer "B.Cu")
		(net "CPU1_XTRIG_R2_L4")
	)
	(segment
		(start 92.626434 -209.510884)
		(end 92.626434 -208.129632)
		(width 0.10668)
		(layer "B.Cu")
		(net "CPU1_XTRIG_R2_L4")
	)
	(segment
		(start 90.7796 -217.419428)
		(end 91.650566 -216.548462)
		(width 0.10668)
		(layer "B.Cu")
		(net "CPU1_XTRIG_R2_L4")
	)
	(segment
		(start 92.626434 -208.129632)
		(end 92.281502 -207.7847)
		(width 0.10668)
		(layer "B.Cu")
		(net "CPU1_XTRIG_R2_L4")
	)
	(segment
		(start 92.875862 -214.48014)
		(end 92.875862 -209.760312)
		(width 0.10668)
		(layer "B.Cu")
		(net "CPU1_XTRIG_R2_L4")
	)
	(segment
		(start 91.650566 -215.705436)
		(end 92.875862 -214.48014)
		(width 0.10668)
		(layer "B.Cu")
		(net "CPU1_XTRIG_R2_L4")
	)
	(segment
		(start 5.849874 -50.094896)
		(end 5.849874 -46.903894)
		(width 0.10668)
		(layer "F.Cu")
		(net "CPU1_XTRIG_R1_L7")
	)
	(segment
		(start 4.747514 -45.801534)
		(end 4.747514 -44.506642)
		(width 0.10668)
		(layer "F.Cu")
		(net "CPU1_XTRIG_R1_L7")
	)
	(segment
		(start 5.849874 -46.903894)
		(end 4.747514 -45.801534)
		(width 0.10668)
		(layer "F.Cu")
		(net "CPU1_XTRIG_R1_L7")
	)
	(via
		(at 4.747514 -45.801534)
		(size 0.762)
		(drill 0.381)
		(layers "F.Cu" "B.Cu")
		(net "CPU1_XTRIG_R1_L7")
	)
	(segment
		(start 4.149852 -51.155092)
		(end 4.149852 -47.850298)
		(width 0.10668)
		(layer "F.Cu")
		(net "CPU1_XTRIG_R1_L6")
	)
	(segment
		(start 4.359656 -51.364896)
		(end 4.149852 -51.155092)
		(width 0.10668)
		(layer "F.Cu")
		(net "CPU1_XTRIG_R1_L6")
	)
	(segment
		(start 2.255266 -45.955712)
		(end 2.992628 -45.21835)
		(width 0.10668)
		(layer "F.Cu")
		(net "CPU1_XTRIG_R1_L6")
	)
	(segment
		(start 5.849874 -51.364896)
		(end 4.359656 -51.364896)
		(width 0.10668)
		(layer "F.Cu")
		(net "CPU1_XTRIG_R1_L6")
	)
	(segment
		(start 2.992628 -45.21835)
		(end 2.992628 -44.462954)
		(width 0.10668)
		(layer "F.Cu")
		(net "CPU1_XTRIG_R1_L6")
	)
	(segment
		(start 4.149852 -47.850298)
		(end 2.255266 -45.955712)
		(width 0.10668)
		(layer "F.Cu")
		(net "CPU1_XTRIG_R1_L6")
	)
	(via
		(at 2.255266 -45.955712)
		(size 0.762)
		(drill 0.381)
		(layers "F.Cu" "B.Cu")
		(net "CPU1_XTRIG_R1_L6")
	)
	(segment
		(start 2.178304 -55.82539)
		(end 2.178304 -57.9755)
		(width 0.10668)
		(layer "F.Cu")
		(net "CPU1_XTRIG_R1_L5")
	)
	(segment
		(start 2.178304 -57.9755)
		(end 2.677922 -58.475118)
		(width 0.10668)
		(layer "F.Cu")
		(net "CPU1_XTRIG_R1_L5")
	)
	(segment
		(start 5.082794 -52.634896)
		(end 2.035302 -55.682388)
		(width 0.10668)
		(layer "F.Cu")
		(net "CPU1_XTRIG_R1_L5")
	)
	(segment
		(start 2.035302 -55.682388)
		(end 2.178304 -55.82539)
		(width 0.10668)
		(layer "F.Cu")
		(net "CPU1_XTRIG_R1_L5")
	)
	(segment
		(start 5.849874 -52.634896)
		(end 5.082794 -52.634896)
		(width 0.10668)
		(layer "F.Cu")
		(net "CPU1_XTRIG_R1_L5")
	)
	(via
		(at 2.035302 -55.682388)
		(size 0.762)
		(drill 0.381)
		(layers "F.Cu" "B.Cu")
		(net "CPU1_XTRIG_R1_L5")
	)
	(segment
		(start 4.61645 -53.904896)
		(end 3.687318 -54.834028)
		(width 0.10668)
		(layer "F.Cu")
		(net "CPU1_XTRIG_R1_L4")
	)
	(segment
		(start 3.687318 -57.76214)
		(end 4.38912 -58.463942)
		(width 0.10668)
		(layer "F.Cu")
		(net "CPU1_XTRIG_R1_L4")
	)
	(segment
		(start 5.849874 -53.904896)
		(end 4.61645 -53.904896)
		(width 0.10668)
		(layer "F.Cu")
		(net "CPU1_XTRIG_R1_L4")
	)
	(segment
		(start 4.38912 -58.463942)
		(end 4.410202 -58.463942)
		(width 0.10668)
		(layer "F.Cu")
		(net "CPU1_XTRIG_R1_L4")
	)
	(segment
		(start 3.687318 -54.834028)
		(end 3.687318 -56.816752)
		(width 0.10668)
		(layer "F.Cu")
		(net "CPU1_XTRIG_R1_L4")
	)
	(segment
		(start 3.687318 -56.816752)
		(end 3.687318 -57.76214)
		(width 0.10668)
		(layer "F.Cu")
		(net "CPU1_XTRIG_R1_L4")
	)
	(via
		(at 3.687318 -56.816752)
		(size 0.762)
		(drill 0.381)
		(layers "F.Cu" "B.Cu")
		(net "CPU1_XTRIG_R1_L4")
	)
	(segment
		(start 178.8922 -95.291148)
		(end 178.689 -95.087948)
		(width 0.10668)
		(layer "F.Cu")
		(net "CPU1_XTRIG_L7")
	)
	(segment
		(start 4.747514 -43.706542)
		(end 4.747514 -42.470832)
		(width 0.10668)
		(layer "F.Cu")
		(net "CPU1_XTRIG_L7")
	)
	(segment
		(start 178.8922 -95.703898)
		(end 178.8922 -95.291148)
		(width 0.10668)
		(layer "F.Cu")
		(net "CPU1_XTRIG_L7")
	)
	(via
		(at 329.061826 -98.948494)
		(size 0.508)
		(drill 0.254)
		(layers "F.Cu" "B.Cu")
		(net "CPU1_XTRIG_L7")
	)
	(via
		(at 89.614502 -206.295752)
		(size 0.508)
		(drill 0.254)
		(layers "F.Cu" "B.Cu")
		(net "CPU1_XTRIG_L7")
	)
	(via
		(at 4.747514 -42.470832)
		(size 0.508)
		(drill 0.254)
		(layers "F.Cu" "B.Cu")
		(net "CPU1_XTRIG_L7")
	)
	(via
		(at 178.689 -95.087948)
		(size 0.508)
		(drill 0.254)
		(layers "F.Cu" "B.Cu")
		(net "CPU1_XTRIG_L7")
	)
	(segment
		(start 89.614502 -206.295752)
		(end 89.614502 -205.5495)
		(width 0.10668)
		(layer "B.Cu")
		(net "CPU1_XTRIG_L7")
	)
	(segment
		(start 89.614502 -207.01)
		(end 89.614502 -206.295752)
		(width 0.10668)
		(layer "B.Cu")
		(net "CPU1_XTRIG_L7")
	)
	(segment
		(start 137.45718 -104.15143)
		(end 132.334254 -109.274356)
		(width 0.11684)
		(layer "In2.Cu")
		(net "CPU1_XTRIG_L7")
	)
	(segment
		(start 178.07178 -95.705168)
		(end 176.205896 -95.705168)
		(width 0.11684)
		(layer "In2.Cu")
		(net "CPU1_XTRIG_L7")
	)
	(segment
		(start 137.9728 -174.51705)
		(end 102.041198 -201.123804)
		(width 0.11684)
		(layer "In2.Cu")
		(net "CPU1_XTRIG_L7")
	)
	(segment
		(start 146.578574 -103.286052)
		(end 144.129252 -103.286052)
		(width 0.11684)
		(layer "In2.Cu")
		(net "CPU1_XTRIG_L7")
	)
	(segment
		(start 157.531308 -104.824784)
		(end 155.205684 -104.824784)
		(width 0.11684)
		(layer "In2.Cu")
		(net "CPU1_XTRIG_L7")
	)
	(segment
		(start 161.89452 -101.190298)
		(end 161.610802 -100.90658)
		(width 0.11684)
		(layer "In2.Cu")
		(net "CPU1_XTRIG_L7")
	)
	(segment
		(start 163.376356 -100.556314)
		(end 163.376356 -100.828856)
		(width 0.11684)
		(layer "In2.Cu")
		(net "CPU1_XTRIG_L7")
	)
	(segment
		(start 163.376356 -100.828856)
		(end 163.014914 -101.190298)
		(width 0.11684)
		(layer "In2.Cu")
		(net "CPU1_XTRIG_L7")
	)
	(segment
		(start 166.407846 -98.654616)
		(end 165.278054 -98.654616)
		(width 0.11684)
		(layer "In2.Cu")
		(net "CPU1_XTRIG_L7")
	)
	(segment
		(start 178.689 -95.087948)
		(end 178.07178 -95.705168)
		(width 0.11684)
		(layer "In2.Cu")
		(net "CPU1_XTRIG_L7")
	)
	(segment
		(start 159.11957 -102.835964)
		(end 159.11957 -103.236522)
		(width 0.11684)
		(layer "In2.Cu")
		(net "CPU1_XTRIG_L7")
	)
	(segment
		(start 144.5768 -146.067272)
		(end 144.5768 -167.91305)
		(width 0.11684)
		(layer "In2.Cu")
		(net "CPU1_XTRIG_L7")
	)
	(segment
		(start 144.5768 -167.91305)
		(end 137.9728 -174.51705)
		(width 0.11684)
		(layer "In2.Cu")
		(net "CPU1_XTRIG_L7")
	)
	(segment
		(start 161.610802 -100.90658)
		(end 161.048954 -100.90658)
		(width 0.11684)
		(layer "In2.Cu")
		(net "CPU1_XTRIG_L7")
	)
	(segment
		(start 155.205684 -104.824784)
		(end 154.3939 -104.013)
		(width 0.11684)
		(layer "In2.Cu")
		(net "CPU1_XTRIG_L7")
	)
	(segment
		(start 175.849788 -95.34906)
		(end 169.713402 -95.34906)
		(width 0.11684)
		(layer "In2.Cu")
		(net "CPU1_XTRIG_L7")
	)
	(segment
		(start 91.162632 -204.747622)
		(end 89.614502 -206.295752)
		(width 0.11684)
		(layer "In2.Cu")
		(net "CPU1_XTRIG_L7")
	)
	(segment
		(start 169.713402 -95.34906)
		(end 166.407846 -98.654616)
		(width 0.11684)
		(layer "In2.Cu")
		(net "CPU1_XTRIG_L7")
	)
	(segment
		(start 132.334254 -133.824726)
		(end 144.5768 -146.067272)
		(width 0.11684)
		(layer "In2.Cu")
		(net "CPU1_XTRIG_L7")
	)
	(segment
		(start 163.014914 -101.190298)
		(end 161.89452 -101.190298)
		(width 0.11684)
		(layer "In2.Cu")
		(net "CPU1_XTRIG_L7")
	)
	(segment
		(start 144.129252 -103.286052)
		(end 143.263874 -104.15143)
		(width 0.11684)
		(layer "In2.Cu")
		(net "CPU1_XTRIG_L7")
	)
	(segment
		(start 96.090994 -204.747622)
		(end 91.162632 -204.747622)
		(width 0.11684)
		(layer "In2.Cu")
		(net "CPU1_XTRIG_L7")
	)
	(segment
		(start 165.278054 -98.654616)
		(end 163.376356 -100.556314)
		(width 0.11684)
		(layer "In2.Cu")
		(net "CPU1_XTRIG_L7")
	)
	(segment
		(start 154.3939 -104.013)
		(end 147.305522 -104.013)
		(width 0.11684)
		(layer "In2.Cu")
		(net "CPU1_XTRIG_L7")
	)
	(segment
		(start 132.334254 -109.274356)
		(end 132.334254 -133.824726)
		(width 0.11684)
		(layer "In2.Cu")
		(net "CPU1_XTRIG_L7")
	)
	(segment
		(start 176.205896 -95.705168)
		(end 175.849788 -95.34906)
		(width 0.11684)
		(layer "In2.Cu")
		(net "CPU1_XTRIG_L7")
	)
	(segment
		(start 100.622354 -202.542648)
		(end 98.295968 -202.542648)
		(width 0.11684)
		(layer "In2.Cu")
		(net "CPU1_XTRIG_L7")
	)
	(segment
		(start 102.041198 -201.123804)
		(end 100.622354 -202.542648)
		(width 0.11684)
		(layer "In2.Cu")
		(net "CPU1_XTRIG_L7")
	)
	(segment
		(start 161.048954 -100.90658)
		(end 159.11957 -102.835964)
		(width 0.11684)
		(layer "In2.Cu")
		(net "CPU1_XTRIG_L7")
	)
	(segment
		(start 159.11957 -103.236522)
		(end 157.531308 -104.824784)
		(width 0.11684)
		(layer "In2.Cu")
		(net "CPU1_XTRIG_L7")
	)
	(segment
		(start 98.295968 -202.542648)
		(end 96.090994 -204.747622)
		(width 0.11684)
		(layer "In2.Cu")
		(net "CPU1_XTRIG_L7")
	)
	(segment
		(start 143.263874 -104.15143)
		(end 137.45718 -104.15143)
		(width 0.11684)
		(layer "In2.Cu")
		(net "CPU1_XTRIG_L7")
	)
	(segment
		(start 147.305522 -104.013)
		(end 146.578574 -103.286052)
		(width 0.11684)
		(layer "In2.Cu")
		(net "CPU1_XTRIG_L7")
	)
	(segment
		(start 4.215892 -41.571672)
		(end 2.7178 -41.571672)
		(width 0.11684)
		(layer "In4.Cu")
		(net "CPU1_XTRIG_L7")
	)
	(segment
		(start 62.63513 -84.61502)
		(end 89.434416 -111.414306)
		(width 0.11684)
		(layer "In4.Cu")
		(net "CPU1_XTRIG_L7")
	)
	(segment
		(start 2.6289 -55.164228)
		(end 3.338068 -55.873396)
		(width 0.11684)
		(layer "In4.Cu")
		(net "CPU1_XTRIG_L7")
	)
	(segment
		(start 11.390884 -61.78169)
		(end 16.178784 -56.99379)
		(width 0.11684)
		(layer "In4.Cu")
		(net "CPU1_XTRIG_L7")
	)
	(segment
		(start 91.270328 -123.2027)
		(end 84.139532 -130.333496)
		(width 0.11684)
		(layer "In4.Cu")
		(net "CPU1_XTRIG_L7")
	)
	(segment
		(start 69.207634 -140.085318)
		(end 48.28921 -140.085318)
		(width 0.11684)
		(layer "In4.Cu")
		(net "CPU1_XTRIG_L7")
	)
	(segment
		(start 84.139532 -130.333496)
		(end 78.959456 -130.333496)
		(width 0.11684)
		(layer "In4.Cu")
		(net "CPU1_XTRIG_L7")
	)
	(segment
		(start 98.044254 -113.765838)
		(end 91.270328 -120.539764)
		(width 0.11684)
		(layer "In4.Cu")
		(net "CPU1_XTRIG_L7")
	)
	(segment
		(start 3.338068 -55.873396)
		(end 3.338068 -61.07303)
		(width 0.11684)
		(layer "In4.Cu")
		(net "CPU1_XTRIG_L7")
	)
	(segment
		(start 67.65798 -199.684132)
		(end 68.550028 -200.57618)
		(width 0.11684)
		(layer "In4.Cu")
		(net "CPU1_XTRIG_L7")
	)
	(segment
		(start 53.490876 -186.038998)
		(end 53.490876 -188.3664)
		(width 0.11684)
		(layer "In4.Cu")
		(net "CPU1_XTRIG_L7")
	)
	(segment
		(start 48.28921 -140.085318)
		(end 44.677076 -143.697452)
		(width 0.11684)
		(layer "In4.Cu")
		(net "CPU1_XTRIG_L7")
	)
	(segment
		(start 44.677076 -143.697452)
		(end 44.677076 -177.225198)
		(width 0.11684)
		(layer "In4.Cu")
		(net "CPU1_XTRIG_L7")
	)
	(segment
		(start 32.67456 -76.023724)
		(end 41.265856 -84.61502)
		(width 0.11684)
		(layer "In4.Cu")
		(net "CPU1_XTRIG_L7")
	)
	(segment
		(start 56.247538 -191.123062)
		(end 62.386464 -191.123062)
		(width 0.11684)
		(layer "In4.Cu")
		(net "CPU1_XTRIG_L7")
	)
	(segment
		(start 3.338068 -61.07303)
		(end 4.046728 -61.78169)
		(width 0.11684)
		(layer "In4.Cu")
		(net "CPU1_XTRIG_L7")
	)
	(segment
		(start 2.122932 -42.16654)
		(end 2.122932 -54.658006)
		(width 0.11684)
		(layer "In4.Cu")
		(net "CPU1_XTRIG_L7")
	)
	(segment
		(start 67.65798 -196.394578)
		(end 67.65798 -199.684132)
		(width 0.11684)
		(layer "In4.Cu")
		(net "CPU1_XTRIG_L7")
	)
	(segment
		(start 71.839582 -200.57618)
		(end 77.559154 -206.295752)
		(width 0.11684)
		(layer "In4.Cu")
		(net "CPU1_XTRIG_L7")
	)
	(segment
		(start 32.67456 -61.8363)
		(end 32.67456 -76.023724)
		(width 0.11684)
		(layer "In4.Cu")
		(net "CPU1_XTRIG_L7")
	)
	(segment
		(start 4.046728 -61.78169)
		(end 11.390884 -61.78169)
		(width 0.11684)
		(layer "In4.Cu")
		(net "CPU1_XTRIG_L7")
	)
	(segment
		(start 77.559154 -206.295752)
		(end 89.614502 -206.295752)
		(width 0.11684)
		(layer "In4.Cu")
		(net "CPU1_XTRIG_L7")
	)
	(segment
		(start 2.7178 -41.571672)
		(end 2.122932 -42.16654)
		(width 0.11684)
		(layer "In4.Cu")
		(net "CPU1_XTRIG_L7")
	)
	(segment
		(start 97.121218 -111.414306)
		(end 98.044254 -112.337342)
		(width 0.11684)
		(layer "In4.Cu")
		(net "CPU1_XTRIG_L7")
	)
	(segment
		(start 16.178784 -56.99379)
		(end 27.83205 -56.99379)
		(width 0.11684)
		(layer "In4.Cu")
		(net "CPU1_XTRIG_L7")
	)
	(segment
		(start 53.490876 -188.3664)
		(end 56.247538 -191.123062)
		(width 0.11684)
		(layer "In4.Cu")
		(net "CPU1_XTRIG_L7")
	)
	(segment
		(start 62.386464 -191.123062)
		(end 67.65798 -196.394578)
		(width 0.11684)
		(layer "In4.Cu")
		(net "CPU1_XTRIG_L7")
	)
	(segment
		(start 41.265856 -84.61502)
		(end 62.63513 -84.61502)
		(width 0.11684)
		(layer "In4.Cu")
		(net "CPU1_XTRIG_L7")
	)
	(segment
		(start 4.747514 -42.470832)
		(end 4.747514 -42.103294)
		(width 0.11684)
		(layer "In4.Cu")
		(net "CPU1_XTRIG_L7")
	)
	(segment
		(start 98.044254 -112.337342)
		(end 98.044254 -113.765838)
		(width 0.11684)
		(layer "In4.Cu")
		(net "CPU1_XTRIG_L7")
	)
	(segment
		(start 2.6289 -55.163974)
		(end 2.6289 -55.164228)
		(width 0.11684)
		(layer "In4.Cu")
		(net "CPU1_XTRIG_L7")
	)
	(segment
		(start 91.270328 -120.539764)
		(end 91.270328 -123.2027)
		(width 0.11684)
		(layer "In4.Cu")
		(net "CPU1_XTRIG_L7")
	)
	(segment
		(start 44.677076 -177.225198)
		(end 53.490876 -186.038998)
		(width 0.11684)
		(layer "In4.Cu")
		(net "CPU1_XTRIG_L7")
	)
	(segment
		(start 2.122932 -54.658006)
		(end 2.6289 -55.163974)
		(width 0.11684)
		(layer "In4.Cu")
		(net "CPU1_XTRIG_L7")
	)
	(segment
		(start 78.959456 -130.333496)
		(end 69.207634 -140.085318)
		(width 0.11684)
		(layer "In4.Cu")
		(net "CPU1_XTRIG_L7")
	)
	(segment
		(start 4.747514 -42.103294)
		(end 4.215892 -41.571672)
		(width 0.11684)
		(layer "In4.Cu")
		(net "CPU1_XTRIG_L7")
	)
	(segment
		(start 89.434416 -111.414306)
		(end 97.121218 -111.414306)
		(width 0.11684)
		(layer "In4.Cu")
		(net "CPU1_XTRIG_L7")
	)
	(segment
		(start 68.550028 -200.57618)
		(end 71.839582 -200.57618)
		(width 0.11684)
		(layer "In4.Cu")
		(net "CPU1_XTRIG_L7")
	)
	(segment
		(start 27.83205 -56.99379)
		(end 32.67456 -61.8363)
		(width 0.11684)
		(layer "In4.Cu")
		(net "CPU1_XTRIG_L7")
	)
	(segment
		(start 179.200302 -92.426028)
		(end 178.065938 -93.560392)
		(width 0.11684)
		(layer "In6.Cu")
		(net "CPU1_XTRIG_L7")
	)
	(segment
		(start 223.082866 -97.046034)
		(end 222.277178 -97.851722)
		(width 0.11684)
		(layer "In6.Cu")
		(net "CPU1_XTRIG_L7")
	)
	(segment
		(start 222.277178 -97.851722)
		(end 207.346042 -97.851722)
		(width 0.11684)
		(layer "In6.Cu")
		(net "CPU1_XTRIG_L7")
	)
	(segment
		(start 207.346042 -97.851722)
		(end 207.023716 -97.529396)
		(width 0.11684)
		(layer "In6.Cu")
		(net "CPU1_XTRIG_L7")
	)
	(segment
		(start 207.023716 -97.529396)
		(end 201.694542 -97.529396)
		(width 0.11684)
		(layer "In6.Cu")
		(net "CPU1_XTRIG_L7")
	)
	(segment
		(start 280.806652 -97.155)
		(end 279.618186 -95.966534)
		(width 0.11684)
		(layer "In6.Cu")
		(net "CPU1_XTRIG_L7")
	)
	(segment
		(start 201.694542 -97.529396)
		(end 198.256144 -94.090998)
		(width 0.11684)
		(layer "In6.Cu")
		(net "CPU1_XTRIG_L7")
	)
	(segment
		(start 247.471946 -97.849944)
		(end 246.510048 -98.811842)
		(width 0.11684)
		(layer "In6.Cu")
		(net "CPU1_XTRIG_L7")
	)
	(segment
		(start 329.061826 -98.948494)
		(end 328.285856 -98.172524)
		(width 0.11684)
		(layer "In6.Cu")
		(net "CPU1_XTRIG_L7")
	)
	(segment
		(start 274.093178 -94.863412)
		(end 259.906516 -94.863412)
		(width 0.11684)
		(layer "In6.Cu")
		(net "CPU1_XTRIG_L7")
	)
	(segment
		(start 198.256144 -94.090998)
		(end 198.256144 -93.933518)
		(width 0.11684)
		(layer "In6.Cu")
		(net "CPU1_XTRIG_L7")
	)
	(segment
		(start 259.906516 -94.863412)
		(end 256.919984 -97.849944)
		(width 0.11684)
		(layer "In6.Cu")
		(net "CPU1_XTRIG_L7")
	)
	(segment
		(start 179.200302 -91.347544)
		(end 179.200302 -92.426028)
		(width 0.11684)
		(layer "In6.Cu")
		(net "CPU1_XTRIG_L7")
	)
	(segment
		(start 235.279438 -97.789746)
		(end 232.526078 -97.789746)
		(width 0.11684)
		(layer "In6.Cu")
		(net "CPU1_XTRIG_L7")
	)
	(segment
		(start 236.301534 -98.811842)
		(end 235.279438 -97.789746)
		(width 0.11684)
		(layer "In6.Cu")
		(net "CPU1_XTRIG_L7")
	)
	(segment
		(start 195.308728 -90.986102)
		(end 179.561744 -90.986102)
		(width 0.11684)
		(layer "In6.Cu")
		(net "CPU1_XTRIG_L7")
	)
	(segment
		(start 328.285856 -98.172524)
		(end 315.881512 -98.172524)
		(width 0.11684)
		(layer "In6.Cu")
		(net "CPU1_XTRIG_L7")
	)
	(segment
		(start 275.1963 -95.966534)
		(end 274.093178 -94.863412)
		(width 0.11684)
		(layer "In6.Cu")
		(net "CPU1_XTRIG_L7")
	)
	(segment
		(start 246.510048 -98.811842)
		(end 236.301534 -98.811842)
		(width 0.11684)
		(layer "In6.Cu")
		(net "CPU1_XTRIG_L7")
	)
	(segment
		(start 232.526078 -97.789746)
		(end 231.782366 -97.046034)
		(width 0.11684)
		(layer "In6.Cu")
		(net "CPU1_XTRIG_L7")
	)
	(segment
		(start 279.618186 -95.966534)
		(end 275.1963 -95.966534)
		(width 0.11684)
		(layer "In6.Cu")
		(net "CPU1_XTRIG_L7")
	)
	(segment
		(start 198.256144 -93.933518)
		(end 195.308728 -90.986102)
		(width 0.11684)
		(layer "In6.Cu")
		(net "CPU1_XTRIG_L7")
	)
	(segment
		(start 178.065938 -94.464886)
		(end 178.689 -95.087948)
		(width 0.11684)
		(layer "In6.Cu")
		(net "CPU1_XTRIG_L7")
	)
	(segment
		(start 178.065938 -93.560392)
		(end 178.065938 -94.464886)
		(width 0.11684)
		(layer "In6.Cu")
		(net "CPU1_XTRIG_L7")
	)
	(segment
		(start 256.919984 -97.849944)
		(end 247.471946 -97.849944)
		(width 0.11684)
		(layer "In6.Cu")
		(net "CPU1_XTRIG_L7")
	)
	(segment
		(start 314.863988 -97.155)
		(end 280.806652 -97.155)
		(width 0.11684)
		(layer "In6.Cu")
		(net "CPU1_XTRIG_L7")
	)
	(segment
		(start 231.782366 -97.046034)
		(end 223.082866 -97.046034)
		(width 0.11684)
		(layer "In6.Cu")
		(net "CPU1_XTRIG_L7")
	)
	(segment
		(start 179.561744 -90.986102)
		(end 179.200302 -91.347544)
		(width 0.11684)
		(layer "In6.Cu")
		(net "CPU1_XTRIG_L7")
	)
	(segment
		(start 315.881512 -98.172524)
		(end 314.863988 -97.155)
		(width 0.11684)
		(layer "In6.Cu")
		(net "CPU1_XTRIG_L7")
	)
	(segment
		(start 333.412846 -55.979822)
		(end 333.412846 -84.527136)
		(width 0.11684)
		(layer "In11.Cu")
		(net "CPU1_XTRIG_L7")
	)
	(segment
		(start 344.412316 -41.710102)
		(end 344.295476 -41.826942)
		(width 0.11684)
		(layer "In11.Cu")
		(net "CPU1_XTRIG_L7")
	)
	(segment
		(start 333.412846 -84.527136)
		(end 329.061826 -88.878156)
		(width 0.11684)
		(layer "In11.Cu")
		(net "CPU1_XTRIG_L7")
	)
	(segment
		(start 344.295476 -45.097192)
		(end 333.412846 -55.979822)
		(width 0.11684)
		(layer "In11.Cu")
		(net "CPU1_XTRIG_L7")
	)
	(segment
		(start 345.76004 -41.710102)
		(end 344.412316 -41.710102)
		(width 0.11684)
		(layer "In11.Cu")
		(net "CPU1_XTRIG_L7")
	)
	(segment
		(start 344.295476 -41.826942)
		(end 344.295476 -45.097192)
		(width 0.11684)
		(layer "In11.Cu")
		(net "CPU1_XTRIG_L7")
	)
	(segment
		(start 329.061826 -88.878156)
		(end 329.061826 -98.948494)
		(width 0.11684)
		(layer "In11.Cu")
		(net "CPU1_XTRIG_L7")
	)
	(segment
		(start 2.992628 -43.662854)
		(end 2.992628 -42.427144)
		(width 0.10668)
		(layer "F.Cu")
		(net "CPU1_XTRIG_L6")
	)
	(via
		(at 167.475916 -100.060252)
		(size 0.508)
		(drill 0.254)
		(layers "F.Cu" "B.Cu")
		(net "CPU1_XTRIG_L6")
	)
	(via
		(at 330.765404 -98.89617)
		(size 0.508)
		(drill 0.254)
		(layers "F.Cu" "B.Cu")
		(net "CPU1_XTRIG_L6")
	)
	(via
		(at 90.503502 -206.295752)
		(size 0.508)
		(drill 0.254)
		(layers "F.Cu" "B.Cu")
		(net "CPU1_XTRIG_L6")
	)
	(via
		(at 2.992628 -42.427144)
		(size 0.508)
		(drill 0.254)
		(layers "F.Cu" "B.Cu")
		(net "CPU1_XTRIG_L6")
	)
	(segment
		(start 90.503502 -206.295752)
		(end 90.503502 -205.5495)
		(width 0.10668)
		(layer "B.Cu")
		(net "CPU1_XTRIG_L6")
	)
	(segment
		(start 166.800276 -106.356404)
		(end 167.149018 -106.705146)
		(width 0.10668)
		(layer "B.Cu")
		(net "CPU1_XTRIG_L6")
	)
	(segment
		(start 168.266364 -107.188)
		(end 170.814238 -107.188)
		(width 0.10668)
		(layer "B.Cu")
		(net "CPU1_XTRIG_L6")
	)
	(segment
		(start 167.28186 -103.03764)
		(end 166.800276 -103.519224)
		(width 0.10668)
		(layer "B.Cu")
		(net "CPU1_XTRIG_L6")
	)
	(segment
		(start 166.800276 -103.519224)
		(end 166.800276 -106.356404)
		(width 0.10668)
		(layer "B.Cu")
		(net "CPU1_XTRIG_L6")
	)
	(segment
		(start 90.503502 -207.01)
		(end 90.503502 -206.295752)
		(width 0.10668)
		(layer "B.Cu")
		(net "CPU1_XTRIG_L6")
	)
	(segment
		(start 167.28186 -100.254308)
		(end 167.28186 -103.03764)
		(width 0.10668)
		(layer "B.Cu")
		(net "CPU1_XTRIG_L6")
	)
	(segment
		(start 167.149018 -106.705146)
		(end 167.78351 -106.705146)
		(width 0.10668)
		(layer "B.Cu")
		(net "CPU1_XTRIG_L6")
	)
	(segment
		(start 167.475916 -100.060252)
		(end 167.28186 -100.254308)
		(width 0.10668)
		(layer "B.Cu")
		(net "CPU1_XTRIG_L6")
	)
	(segment
		(start 167.78351 -106.705146)
		(end 168.266364 -107.188)
		(width 0.10668)
		(layer "B.Cu")
		(net "CPU1_XTRIG_L6")
	)
	(segment
		(start 165.594538 -99.530916)
		(end 165.174676 -99.950778)
		(width 0.11684)
		(layer "In2.Cu")
		(net "CPU1_XTRIG_L6")
	)
	(segment
		(start 166.94658 -99.530916)
		(end 165.594538 -99.530916)
		(width 0.11684)
		(layer "In2.Cu")
		(net "CPU1_XTRIG_L6")
	)
	(segment
		(start 144.53235 -103.707692)
		(end 143.636238 -104.603804)
		(width 0.11684)
		(layer "In2.Cu")
		(net "CPU1_XTRIG_L6")
	)
	(segment
		(start 146.987006 -104.436926)
		(end 146.257772 -103.707692)
		(width 0.11684)
		(layer "In2.Cu")
		(net "CPU1_XTRIG_L6")
	)
	(segment
		(start 138.467338 -174.704756)
		(end 102.332536 -201.461878)
		(width 0.11684)
		(layer "In2.Cu")
		(net "CPU1_XTRIG_L6")
	)
	(segment
		(start 159.457136 -104.061006)
		(end 157.352238 -106.165904)
		(width 0.11684)
		(layer "In2.Cu")
		(net "CPU1_XTRIG_L6")
	)
	(segment
		(start 143.636238 -104.603804)
		(end 137.601198 -104.603804)
		(width 0.11684)
		(layer "In2.Cu")
		(net "CPU1_XTRIG_L6")
	)
	(segment
		(start 133.432804 -113.156492)
		(end 132.92963 -113.659666)
		(width 0.11684)
		(layer "In2.Cu")
		(net "CPU1_XTRIG_L6")
	)
	(segment
		(start 137.601198 -104.603804)
		(end 133.432804 -108.772198)
		(width 0.11684)
		(layer "In2.Cu")
		(net "CPU1_XTRIG_L6")
	)
	(segment
		(start 132.92963 -113.659666)
		(end 132.92963 -133.790944)
		(width 0.11684)
		(layer "In2.Cu")
		(net "CPU1_XTRIG_L6")
	)
	(segment
		(start 151.286464 -104.436926)
		(end 146.987006 -104.436926)
		(width 0.11684)
		(layer "In2.Cu")
		(net "CPU1_XTRIG_L6")
	)
	(segment
		(start 157.352238 -106.165904)
		(end 156.715714 -106.165904)
		(width 0.11684)
		(layer "In2.Cu")
		(net "CPU1_XTRIG_L6")
	)
	(segment
		(start 165.174676 -100.521008)
		(end 161.634678 -104.061006)
		(width 0.11684)
		(layer "In2.Cu")
		(net "CPU1_XTRIG_L6")
	)
	(segment
		(start 156.715714 -106.165904)
		(end 155.81503 -105.26522)
		(width 0.11684)
		(layer "In2.Cu")
		(net "CPU1_XTRIG_L6")
	)
	(segment
		(start 155.81503 -105.26522)
		(end 152.114758 -105.26522)
		(width 0.11684)
		(layer "In2.Cu")
		(net "CPU1_XTRIG_L6")
	)
	(segment
		(start 133.432804 -108.772198)
		(end 133.432804 -113.156492)
		(width 0.11684)
		(layer "In2.Cu")
		(net "CPU1_XTRIG_L6")
	)
	(segment
		(start 102.332536 -201.461878)
		(end 100.757482 -203.036678)
		(width 0.11684)
		(layer "In2.Cu")
		(net "CPU1_XTRIG_L6")
	)
	(segment
		(start 146.257772 -103.707692)
		(end 144.53235 -103.707692)
		(width 0.11684)
		(layer "In2.Cu")
		(net "CPU1_XTRIG_L6")
	)
	(segment
		(start 145.014442 -168.157652)
		(end 138.467338 -174.704756)
		(width 0.11684)
		(layer "In2.Cu")
		(net "CPU1_XTRIG_L6")
	)
	(segment
		(start 91.606878 -205.192376)
		(end 90.503502 -206.295752)
		(width 0.11684)
		(layer "In2.Cu")
		(net "CPU1_XTRIG_L6")
	)
	(segment
		(start 96.275398 -205.192376)
		(end 91.606878 -205.192376)
		(width 0.11684)
		(layer "In2.Cu")
		(net "CPU1_XTRIG_L6")
	)
	(segment
		(start 167.475916 -100.060252)
		(end 166.94658 -99.530916)
		(width 0.11684)
		(layer "In2.Cu")
		(net "CPU1_XTRIG_L6")
	)
	(segment
		(start 132.92963 -133.790944)
		(end 145.014442 -145.875756)
		(width 0.11684)
		(layer "In2.Cu")
		(net "CPU1_XTRIG_L6")
	)
	(segment
		(start 161.634678 -104.061006)
		(end 159.457136 -104.061006)
		(width 0.11684)
		(layer "In2.Cu")
		(net "CPU1_XTRIG_L6")
	)
	(segment
		(start 152.114758 -105.26522)
		(end 151.286464 -104.436926)
		(width 0.11684)
		(layer "In2.Cu")
		(net "CPU1_XTRIG_L6")
	)
	(segment
		(start 145.014442 -145.875756)
		(end 145.014442 -168.157652)
		(width 0.11684)
		(layer "In2.Cu")
		(net "CPU1_XTRIG_L6")
	)
	(segment
		(start 100.757482 -203.036678)
		(end 98.431096 -203.036678)
		(width 0.11684)
		(layer "In2.Cu")
		(net "CPU1_XTRIG_L6")
	)
	(segment
		(start 165.174676 -99.950778)
		(end 165.174676 -100.521008)
		(width 0.11684)
		(layer "In2.Cu")
		(net "CPU1_XTRIG_L6")
	)
	(segment
		(start 98.431096 -203.036678)
		(end 96.275398 -205.192376)
		(width 0.11684)
		(layer "In2.Cu")
		(net "CPU1_XTRIG_L6")
	)
	(segment
		(start 4.259834 -61.26734)
		(end 11.177778 -61.26734)
		(width 0.11684)
		(layer "In4.Cu")
		(net "CPU1_XTRIG_L6")
	)
	(segment
		(start 62.813438 -84.184744)
		(end 89.612724 -110.98403)
		(width 0.11684)
		(layer "In4.Cu")
		(net "CPU1_XTRIG_L6")
	)
	(segment
		(start 48.372522 -140.598398)
		(end 45.21454 -143.75638)
		(width 0.11684)
		(layer "In4.Cu")
		(net "CPU1_XTRIG_L6")
	)
	(segment
		(start 33.104836 -61.657992)
		(end 33.104836 -75.845416)
		(width 0.11684)
		(layer "In4.Cu")
		(net "CPU1_XTRIG_L6")
	)
	(segment
		(start 11.177778 -61.26734)
		(end 15.881604 -56.563514)
		(width 0.11684)
		(layer "In4.Cu")
		(net "CPU1_XTRIG_L6")
	)
	(segment
		(start 91.700604 -123.381008)
		(end 84.31784 -130.763772)
		(width 0.11684)
		(layer "In4.Cu")
		(net "CPU1_XTRIG_L6")
	)
	(segment
		(start 89.882726 -205.674976)
		(end 90.503502 -206.295752)
		(width 0.11684)
		(layer "In4.Cu")
		(net "CPU1_XTRIG_L6")
	)
	(segment
		(start 53.912516 -188.191648)
		(end 56.42229 -190.701422)
		(width 0.11684)
		(layer "In4.Cu")
		(net "CPU1_XTRIG_L6")
	)
	(segment
		(start 3.852418 -55.66029)
		(end 3.852418 -60.859924)
		(width 0.11684)
		(layer "In4.Cu")
		(net "CPU1_XTRIG_L6")
	)
	(segment
		(start 91.700604 -120.718072)
		(end 91.700604 -123.381008)
		(width 0.11684)
		(layer "In4.Cu")
		(net "CPU1_XTRIG_L6")
	)
	(segment
		(start 41.444164 -84.184744)
		(end 62.813438 -84.184744)
		(width 0.11684)
		(layer "In4.Cu")
		(net "CPU1_XTRIG_L6")
	)
	(segment
		(start 56.42229 -190.701422)
		(end 62.561216 -190.701422)
		(width 0.11684)
		(layer "In4.Cu")
		(net "CPU1_XTRIG_L6")
	)
	(segment
		(start 69.290946 -140.598398)
		(end 48.372522 -140.598398)
		(width 0.11684)
		(layer "In4.Cu")
		(net "CPU1_XTRIG_L6")
	)
	(segment
		(start 45.21454 -177.16627)
		(end 53.912516 -185.864246)
		(width 0.11684)
		(layer "In4.Cu")
		(net "CPU1_XTRIG_L6")
	)
	(segment
		(start 2.992628 -42.427144)
		(end 2.992628 -54.8005)
		(width 0.11684)
		(layer "In4.Cu")
		(net "CPU1_XTRIG_L6")
	)
	(segment
		(start 53.912516 -185.864246)
		(end 53.912516 -188.191648)
		(width 0.11684)
		(layer "In4.Cu")
		(net "CPU1_XTRIG_L6")
	)
	(segment
		(start 79.125572 -130.763772)
		(end 69.290946 -140.598398)
		(width 0.11684)
		(layer "In4.Cu")
		(net "CPU1_XTRIG_L6")
	)
	(segment
		(start 2.992628 -54.8005)
		(end 3.852418 -55.66029)
		(width 0.11684)
		(layer "In4.Cu")
		(net "CPU1_XTRIG_L6")
	)
	(segment
		(start 98.47453 -113.944146)
		(end 91.700604 -120.718072)
		(width 0.11684)
		(layer "In4.Cu")
		(net "CPU1_XTRIG_L6")
	)
	(segment
		(start 3.852418 -60.859924)
		(end 4.259834 -61.26734)
		(width 0.11684)
		(layer "In4.Cu")
		(net "CPU1_XTRIG_L6")
	)
	(segment
		(start 77.53477 -205.674976)
		(end 89.882726 -205.674976)
		(width 0.11684)
		(layer "In4.Cu")
		(net "CPU1_XTRIG_L6")
	)
	(segment
		(start 98.47453 -112.159034)
		(end 98.47453 -113.944146)
		(width 0.11684)
		(layer "In4.Cu")
		(net "CPU1_XTRIG_L6")
	)
	(segment
		(start 33.104836 -75.845416)
		(end 41.444164 -84.184744)
		(width 0.11684)
		(layer "In4.Cu")
		(net "CPU1_XTRIG_L6")
	)
	(segment
		(start 45.21454 -143.75638)
		(end 45.21454 -177.16627)
		(width 0.11684)
		(layer "In4.Cu")
		(net "CPU1_XTRIG_L6")
	)
	(segment
		(start 84.31784 -130.763772)
		(end 79.125572 -130.763772)
		(width 0.11684)
		(layer "In4.Cu")
		(net "CPU1_XTRIG_L6")
	)
	(segment
		(start 89.612724 -110.98403)
		(end 97.299526 -110.98403)
		(width 0.11684)
		(layer "In4.Cu")
		(net "CPU1_XTRIG_L6")
	)
	(segment
		(start 97.299526 -110.98403)
		(end 98.47453 -112.159034)
		(width 0.11684)
		(layer "In4.Cu")
		(net "CPU1_XTRIG_L6")
	)
	(segment
		(start 28.010358 -56.563514)
		(end 33.104836 -61.657992)
		(width 0.11684)
		(layer "In4.Cu")
		(net "CPU1_XTRIG_L6")
	)
	(segment
		(start 62.561216 -190.701422)
		(end 77.53477 -205.674976)
		(width 0.11684)
		(layer "In4.Cu")
		(net "CPU1_XTRIG_L6")
	)
	(segment
		(start 15.881604 -56.563514)
		(end 28.010358 -56.563514)
		(width 0.11684)
		(layer "In4.Cu")
		(net "CPU1_XTRIG_L6")
	)
	(segment
		(start 179.21224 -90.142822)
		(end 197.159372 -90.142822)
		(width 0.11684)
		(layer "In6.Cu")
		(net "CPU1_XTRIG_L6")
	)
	(segment
		(start 202.75677 -95.74022)
		(end 208.242408 -95.74022)
		(width 0.11684)
		(layer "In6.Cu")
		(net "CPU1_XTRIG_L6")
	)
	(segment
		(start 176.627536 -93.011498)
		(end 177.051462 -93.011498)
		(width 0.11684)
		(layer "In6.Cu")
		(net "CPU1_XTRIG_L6")
	)
	(segment
		(start 177.051462 -93.011498)
		(end 178.357022 -91.705938)
		(width 0.11684)
		(layer "In6.Cu")
		(net "CPU1_XTRIG_L6")
	)
	(segment
		(start 314.790836 -95.728028)
		(end 316.262766 -97.199958)
		(width 0.11684)
		(layer "In6.Cu")
		(net "CPU1_XTRIG_L6")
	)
	(segment
		(start 178.357022 -90.99804)
		(end 179.21224 -90.142822)
		(width 0.11684)
		(layer "In6.Cu")
		(net "CPU1_XTRIG_L6")
	)
	(segment
		(start 173.195742 -98.661728)
		(end 175.61814 -96.23933)
		(width 0.11684)
		(layer "In6.Cu")
		(net "CPU1_XTRIG_L6")
	)
	(segment
		(start 231.967024 -96.037654)
		(end 232.847134 -96.917764)
		(width 0.11684)
		(layer "In6.Cu")
		(net "CPU1_XTRIG_L6")
	)
	(segment
		(start 259.557012 -94.020132)
		(end 274.532852 -94.020132)
		(width 0.11684)
		(layer "In6.Cu")
		(net "CPU1_XTRIG_L6")
	)
	(segment
		(start 208.71942 -96.217232)
		(end 211.886292 -96.217232)
		(width 0.11684)
		(layer "In6.Cu")
		(net "CPU1_XTRIG_L6")
	)
	(segment
		(start 256.65938 -96.917764)
		(end 259.557012 -94.020132)
		(width 0.11684)
		(layer "In6.Cu")
		(net "CPU1_XTRIG_L6")
	)
	(segment
		(start 232.847134 -96.917764)
		(end 256.65938 -96.917764)
		(width 0.11684)
		(layer "In6.Cu")
		(net "CPU1_XTRIG_L6")
	)
	(segment
		(start 213.107778 -94.995746)
		(end 216.38006 -94.995746)
		(width 0.11684)
		(layer "In6.Cu")
		(net "CPU1_XTRIG_L6")
	)
	(segment
		(start 316.262766 -97.199958)
		(end 329.12939 -97.199958)
		(width 0.11684)
		(layer "In6.Cu")
		(net "CPU1_XTRIG_L6")
	)
	(segment
		(start 280.572464 -95.728028)
		(end 314.790836 -95.728028)
		(width 0.11684)
		(layer "In6.Cu")
		(net "CPU1_XTRIG_L6")
	)
	(segment
		(start 329.12939 -97.199958)
		(end 330.765404 -98.835972)
		(width 0.11684)
		(layer "In6.Cu")
		(net "CPU1_XTRIG_L6")
	)
	(segment
		(start 175.61814 -94.020894)
		(end 176.627536 -93.011498)
		(width 0.11684)
		(layer "In6.Cu")
		(net "CPU1_XTRIG_L6")
	)
	(segment
		(start 168.906444 -100.060252)
		(end 170.304968 -98.661728)
		(width 0.11684)
		(layer "In6.Cu")
		(net "CPU1_XTRIG_L6")
	)
	(segment
		(start 178.357022 -91.705938)
		(end 178.357022 -90.99804)
		(width 0.11684)
		(layer "In6.Cu")
		(net "CPU1_XTRIG_L6")
	)
	(segment
		(start 220.631004 -96.037654)
		(end 231.967024 -96.037654)
		(width 0.11684)
		(layer "In6.Cu")
		(net "CPU1_XTRIG_L6")
	)
	(segment
		(start 216.38006 -94.995746)
		(end 217.991944 -96.60763)
		(width 0.11684)
		(layer "In6.Cu")
		(net "CPU1_XTRIG_L6")
	)
	(segment
		(start 175.61814 -96.23933)
		(end 175.61814 -94.020894)
		(width 0.11684)
		(layer "In6.Cu")
		(net "CPU1_XTRIG_L6")
	)
	(segment
		(start 274.532852 -94.020132)
		(end 275.413724 -94.901004)
		(width 0.11684)
		(layer "In6.Cu")
		(net "CPU1_XTRIG_L6")
	)
	(segment
		(start 330.765404 -98.835972)
		(end 330.765404 -98.89617)
		(width 0.11684)
		(layer "In6.Cu")
		(net "CPU1_XTRIG_L6")
	)
	(segment
		(start 167.475916 -100.060252)
		(end 168.906444 -100.060252)
		(width 0.11684)
		(layer "In6.Cu")
		(net "CPU1_XTRIG_L6")
	)
	(segment
		(start 208.242408 -95.74022)
		(end 208.71942 -96.217232)
		(width 0.11684)
		(layer "In6.Cu")
		(net "CPU1_XTRIG_L6")
	)
	(segment
		(start 275.413724 -94.901004)
		(end 279.74544 -94.901004)
		(width 0.11684)
		(layer "In6.Cu")
		(net "CPU1_XTRIG_L6")
	)
	(segment
		(start 197.159372 -90.142822)
		(end 202.75677 -95.74022)
		(width 0.11684)
		(layer "In6.Cu")
		(net "CPU1_XTRIG_L6")
	)
	(segment
		(start 170.304968 -98.661728)
		(end 173.195742 -98.661728)
		(width 0.11684)
		(layer "In6.Cu")
		(net "CPU1_XTRIG_L6")
	)
	(segment
		(start 211.886292 -96.217232)
		(end 213.107778 -94.995746)
		(width 0.11684)
		(layer "In6.Cu")
		(net "CPU1_XTRIG_L6")
	)
	(segment
		(start 279.74544 -94.901004)
		(end 280.572464 -95.728028)
		(width 0.11684)
		(layer "In6.Cu")
		(net "CPU1_XTRIG_L6")
	)
	(segment
		(start 220.061028 -96.60763)
		(end 220.631004 -96.037654)
		(width 0.11684)
		(layer "In6.Cu")
		(net "CPU1_XTRIG_L6")
	)
	(segment
		(start 217.991944 -96.60763)
		(end 220.061028 -96.60763)
		(width 0.11684)
		(layer "In6.Cu")
		(net "CPU1_XTRIG_L6")
	)
	(segment
		(start 335.483708 -60.385706)
		(end 335.483708 -84.865718)
		(width 0.11684)
		(layer "In11.Cu")
		(net "CPU1_XTRIG_L6")
	)
	(segment
		(start 346.762832 -49.106582)
		(end 335.483708 -60.385706)
		(width 0.11684)
		(layer "In11.Cu")
		(net "CPU1_XTRIG_L6")
	)
	(segment
		(start 330.765404 -89.584022)
		(end 330.765404 -98.89617)
		(width 0.11684)
		(layer "In11.Cu")
		(net "CPU1_XTRIG_L6")
	)
	(segment
		(start 346.762832 -43.24731)
		(end 346.762832 -49.106582)
		(width 0.11684)
		(layer "In11.Cu")
		(net "CPU1_XTRIG_L6")
	)
	(segment
		(start 348.30004 -41.710102)
		(end 346.762832 -43.24731)
		(width 0.11684)
		(layer "In11.Cu")
		(net "CPU1_XTRIG_L6")
	)
	(segment
		(start 335.483708 -84.865718)
		(end 330.765404 -89.584022)
		(width 0.11684)
		(layer "In11.Cu")
		(net "CPU1_XTRIG_L6")
	)
	(segment
		(start 3.63982 -60.237116)
		(end 4.999736 -60.237116)
		(width 0.10668)
		(layer "F.Cu")
		(net "CPU1_XTRIG_L5")
	)
	(segment
		(start 2.677922 -59.275218)
		(end 3.63982 -60.237116)
		(width 0.10668)
		(layer "F.Cu")
		(net "CPU1_XTRIG_L5")
	)
	(via
		(at 91.392502 -206.295752)
		(size 0.508)
		(drill 0.254)
		(layers "F.Cu" "B.Cu")
		(net "CPU1_XTRIG_L5")
	)
	(via
		(at 4.999736 -60.237116)
		(size 0.508)
		(drill 0.254)
		(layers "F.Cu" "B.Cu")
		(net "CPU1_XTRIG_L5")
	)
	(via
		(at 167.969438 -104.103678)
		(size 0.508)
		(drill 0.254)
		(layers "F.Cu" "B.Cu")
		(net "CPU1_XTRIG_L5")
	)
	(via
		(at 331.578204 -98.89617)
		(size 0.508)
		(drill 0.254)
		(layers "F.Cu" "B.Cu")
		(net "CPU1_XTRIG_L5")
	)
	(segment
		(start 170.798998 -104.745282)
		(end 170.798998 -105.121202)
		(width 0.10668)
		(layer "B.Cu")
		(net "CPU1_XTRIG_L5")
	)
	(segment
		(start 91.392502 -206.295752)
		(end 91.392502 -205.5495)
		(width 0.10668)
		(layer "B.Cu")
		(net "CPU1_XTRIG_L5")
	)
	(segment
		(start 170.381676 -104.32796)
		(end 170.798998 -104.745282)
		(width 0.10668)
		(layer "B.Cu")
		(net "CPU1_XTRIG_L5")
	)
	(segment
		(start 167.969438 -104.175306)
		(end 168.122092 -104.32796)
		(width 0.10668)
		(layer "B.Cu")
		(net "CPU1_XTRIG_L5")
	)
	(segment
		(start 91.392502 -207.01)
		(end 91.392502 -206.295752)
		(width 0.10668)
		(layer "B.Cu")
		(net "CPU1_XTRIG_L5")
	)
	(segment
		(start 167.969438 -104.103678)
		(end 167.969438 -104.175306)
		(width 0.10668)
		(layer "B.Cu")
		(net "CPU1_XTRIG_L5")
	)
	(segment
		(start 168.122092 -104.32796)
		(end 170.381676 -104.32796)
		(width 0.10668)
		(layer "B.Cu")
		(net "CPU1_XTRIG_L5")
	)
	(segment
		(start 151.216614 -111.7473)
		(end 143.106394 -111.7473)
		(width 0.11684)
		(layer "In2.Cu")
		(net "CPU1_XTRIG_L5")
	)
	(segment
		(start 140.650468 -114.203226)
		(end 134.134352 -114.203226)
		(width 0.11684)
		(layer "In2.Cu")
		(net "CPU1_XTRIG_L5")
	)
	(segment
		(start 143.106394 -111.7473)
		(end 140.650468 -114.203226)
		(width 0.11684)
		(layer "In2.Cu")
		(net "CPU1_XTRIG_L5")
	)
	(segment
		(start 164.98697 -105.762806)
		(end 162.439858 -108.309918)
		(width 0.11684)
		(layer "In2.Cu")
		(net "CPU1_XTRIG_L5")
	)
	(segment
		(start 91.984322 -206.887572)
		(end 91.392502 -206.295752)
		(width 0.11684)
		(layer "In2.Cu")
		(net "CPU1_XTRIG_L5")
	)
	(segment
		(start 133.77291 -114.564668)
		(end 133.77291 -133.36016)
		(width 0.11684)
		(layer "In2.Cu")
		(net "CPU1_XTRIG_L5")
	)
	(segment
		(start 160.216342 -110.141258)
		(end 152.822656 -110.141258)
		(width 0.11684)
		(layer "In2.Cu")
		(net "CPU1_XTRIG_L5")
	)
	(segment
		(start 101.130862 -203.937362)
		(end 98.804476 -203.937362)
		(width 0.11684)
		(layer "In2.Cu")
		(net "CPU1_XTRIG_L5")
	)
	(segment
		(start 98.804476 -203.937362)
		(end 95.854266 -206.887572)
		(width 0.11684)
		(layer "In2.Cu")
		(net "CPU1_XTRIG_L5")
	)
	(segment
		(start 167.969438 -104.103678)
		(end 167.611044 -104.103678)
		(width 0.11684)
		(layer "In2.Cu")
		(net "CPU1_XTRIG_L5")
	)
	(segment
		(start 161.01695 -109.34065)
		(end 160.216342 -110.141258)
		(width 0.11684)
		(layer "In2.Cu")
		(net "CPU1_XTRIG_L5")
	)
	(segment
		(start 161.01695 -108.96727)
		(end 161.01695 -109.34065)
		(width 0.11684)
		(layer "In2.Cu")
		(net "CPU1_XTRIG_L5")
	)
	(segment
		(start 138.741658 -175.62322)
		(end 102.922578 -202.146408)
		(width 0.11684)
		(layer "In2.Cu")
		(net "CPU1_XTRIG_L5")
	)
	(segment
		(start 133.77291 -133.36016)
		(end 145.857722 -145.444972)
		(width 0.11684)
		(layer "In2.Cu")
		(net "CPU1_XTRIG_L5")
	)
	(segment
		(start 167.611044 -104.103678)
		(end 166.686738 -105.027984)
		(width 0.11684)
		(layer "In2.Cu")
		(net "CPU1_XTRIG_L5")
	)
	(segment
		(start 145.857722 -145.444972)
		(end 145.857722 -168.507156)
		(width 0.11684)
		(layer "In2.Cu")
		(net "CPU1_XTRIG_L5")
	)
	(segment
		(start 145.857722 -168.507156)
		(end 138.741658 -175.62322)
		(width 0.11684)
		(layer "In2.Cu")
		(net "CPU1_XTRIG_L5")
	)
	(segment
		(start 165.360096 -105.027984)
		(end 164.98697 -105.40111)
		(width 0.11684)
		(layer "In2.Cu")
		(net "CPU1_XTRIG_L5")
	)
	(segment
		(start 164.98697 -105.40111)
		(end 164.98697 -105.762806)
		(width 0.11684)
		(layer "In2.Cu")
		(net "CPU1_XTRIG_L5")
	)
	(segment
		(start 95.854266 -206.887572)
		(end 91.984322 -206.887572)
		(width 0.11684)
		(layer "In2.Cu")
		(net "CPU1_XTRIG_L5")
	)
	(segment
		(start 152.822656 -110.141258)
		(end 151.216614 -111.7473)
		(width 0.11684)
		(layer "In2.Cu")
		(net "CPU1_XTRIG_L5")
	)
	(segment
		(start 161.674302 -108.309918)
		(end 161.01695 -108.96727)
		(width 0.11684)
		(layer "In2.Cu")
		(net "CPU1_XTRIG_L5")
	)
	(segment
		(start 162.439858 -108.309918)
		(end 161.674302 -108.309918)
		(width 0.11684)
		(layer "In2.Cu")
		(net "CPU1_XTRIG_L5")
	)
	(segment
		(start 166.686738 -105.027984)
		(end 165.360096 -105.027984)
		(width 0.11684)
		(layer "In2.Cu")
		(net "CPU1_XTRIG_L5")
	)
	(segment
		(start 102.922578 -202.146408)
		(end 101.130862 -203.937362)
		(width 0.11684)
		(layer "In2.Cu")
		(net "CPU1_XTRIG_L5")
	)
	(segment
		(start 134.134352 -114.203226)
		(end 133.77291 -114.564668)
		(width 0.11684)
		(layer "In2.Cu")
		(net "CPU1_XTRIG_L5")
	)
	(segment
		(start 45.707046 -143.860266)
		(end 45.707046 -177.062384)
		(width 0.11684)
		(layer "In4.Cu")
		(net "CPU1_XTRIG_L5")
	)
	(segment
		(start 77.693774 -205.237588)
		(end 90.334338 -205.237588)
		(width 0.11684)
		(layer "In4.Cu")
		(net "CPU1_XTRIG_L5")
	)
	(segment
		(start 33.549336 -61.473842)
		(end 33.549336 -75.661266)
		(width 0.11684)
		(layer "In4.Cu")
		(net "CPU1_XTRIG_L5")
	)
	(segment
		(start 11.460226 -60.237116)
		(end 15.578328 -56.119014)
		(width 0.11684)
		(layer "In4.Cu")
		(net "CPU1_XTRIG_L5")
	)
	(segment
		(start 92.145104 -120.902222)
		(end 92.145104 -123.565158)
		(width 0.11684)
		(layer "In4.Cu")
		(net "CPU1_XTRIG_L5")
	)
	(segment
		(start 79.277464 -131.208272)
		(end 69.465698 -141.020038)
		(width 0.11684)
		(layer "In4.Cu")
		(net "CPU1_XTRIG_L5")
	)
	(segment
		(start 28.194508 -56.119014)
		(end 33.549336 -61.473842)
		(width 0.11684)
		(layer "In4.Cu")
		(net "CPU1_XTRIG_L5")
	)
	(segment
		(start 54.334156 -185.689494)
		(end 54.334156 -188.016896)
		(width 0.11684)
		(layer "In4.Cu")
		(net "CPU1_XTRIG_L5")
	)
	(segment
		(start 69.465698 -141.020038)
		(end 48.547274 -141.020038)
		(width 0.11684)
		(layer "In4.Cu")
		(net "CPU1_XTRIG_L5")
	)
	(segment
		(start 15.578328 -56.119014)
		(end 28.194508 -56.119014)
		(width 0.11684)
		(layer "In4.Cu")
		(net "CPU1_XTRIG_L5")
	)
	(segment
		(start 56.597042 -190.279782)
		(end 62.735968 -190.279782)
		(width 0.11684)
		(layer "In4.Cu")
		(net "CPU1_XTRIG_L5")
	)
	(segment
		(start 98.91903 -111.974884)
		(end 98.91903 -114.128296)
		(width 0.11684)
		(layer "In4.Cu")
		(net "CPU1_XTRIG_L5")
	)
	(segment
		(start 89.796874 -110.53953)
		(end 97.483676 -110.53953)
		(width 0.11684)
		(layer "In4.Cu")
		(net "CPU1_XTRIG_L5")
	)
	(segment
		(start 4.999736 -60.237116)
		(end 11.460226 -60.237116)
		(width 0.11684)
		(layer "In4.Cu")
		(net "CPU1_XTRIG_L5")
	)
	(segment
		(start 97.483676 -110.53953)
		(end 98.91903 -111.974884)
		(width 0.11684)
		(layer "In4.Cu")
		(net "CPU1_XTRIG_L5")
	)
	(segment
		(start 84.50199 -131.208272)
		(end 79.277464 -131.208272)
		(width 0.11684)
		(layer "In4.Cu")
		(net "CPU1_XTRIG_L5")
	)
	(segment
		(start 54.334156 -188.016896)
		(end 56.597042 -190.279782)
		(width 0.11684)
		(layer "In4.Cu")
		(net "CPU1_XTRIG_L5")
	)
	(segment
		(start 48.547274 -141.020038)
		(end 45.707046 -143.860266)
		(width 0.11684)
		(layer "In4.Cu")
		(net "CPU1_XTRIG_L5")
	)
	(segment
		(start 41.628314 -83.740244)
		(end 62.997588 -83.740244)
		(width 0.11684)
		(layer "In4.Cu")
		(net "CPU1_XTRIG_L5")
	)
	(segment
		(start 33.549336 -75.661266)
		(end 41.628314 -83.740244)
		(width 0.11684)
		(layer "In4.Cu")
		(net "CPU1_XTRIG_L5")
	)
	(segment
		(start 62.735968 -190.279782)
		(end 77.693774 -205.237588)
		(width 0.11684)
		(layer "In4.Cu")
		(net "CPU1_XTRIG_L5")
	)
	(segment
		(start 90.334338 -205.237588)
		(end 91.392502 -206.295752)
		(width 0.11684)
		(layer "In4.Cu")
		(net "CPU1_XTRIG_L5")
	)
	(segment
		(start 45.707046 -177.062384)
		(end 54.334156 -185.689494)
		(width 0.11684)
		(layer "In4.Cu")
		(net "CPU1_XTRIG_L5")
	)
	(segment
		(start 62.997588 -83.740244)
		(end 89.796874 -110.53953)
		(width 0.11684)
		(layer "In4.Cu")
		(net "CPU1_XTRIG_L5")
	)
	(segment
		(start 92.145104 -123.565158)
		(end 84.50199 -131.208272)
		(width 0.11684)
		(layer "In4.Cu")
		(net "CPU1_XTRIG_L5")
	)
	(segment
		(start 98.91903 -114.128296)
		(end 92.145104 -120.902222)
		(width 0.11684)
		(layer "In4.Cu")
		(net "CPU1_XTRIG_L5")
	)
	(segment
		(start 178.71313 -89.721182)
		(end 175.1965 -93.237812)
		(width 0.11684)
		(layer "In6.Cu")
		(net "CPU1_XTRIG_L5")
	)
	(segment
		(start 314.965588 -95.306388)
		(end 280.747216 -95.306388)
		(width 0.11684)
		(layer "In6.Cu")
		(net "CPU1_XTRIG_L5")
	)
	(segment
		(start 263.859772 -92.531184)
		(end 263.386824 -93.004132)
		(width 0.11684)
		(layer "In6.Cu")
		(net "CPU1_XTRIG_L5")
	)
	(segment
		(start 331.578204 -98.89617)
		(end 331.578204 -98.835972)
		(width 0.11684)
		(layer "In6.Cu")
		(net "CPU1_XTRIG_L5")
	)
	(segment
		(start 219.886276 -96.18599)
		(end 218.16695 -96.18599)
		(width 0.11684)
		(layer "In6.Cu")
		(net "CPU1_XTRIG_L5")
	)
	(segment
		(start 166.858696 -100.325936)
		(end 167.969438 -101.436678)
		(width 0.11684)
		(layer "In6.Cu")
		(net "CPU1_XTRIG_L5")
	)
	(segment
		(start 203.9366 -94.567502)
		(end 202.53579 -93.166692)
		(width 0.11684)
		(layer "In6.Cu")
		(net "CPU1_XTRIG_L5")
	)
	(segment
		(start 175.1965 -96.064578)
		(end 173.02099 -98.240088)
		(width 0.11684)
		(layer "In6.Cu")
		(net "CPU1_XTRIG_L5")
	)
	(segment
		(start 220.456252 -95.616014)
		(end 219.886276 -96.18599)
		(width 0.11684)
		(layer "In6.Cu")
		(net "CPU1_XTRIG_L5")
	)
	(segment
		(start 167.969438 -101.436678)
		(end 167.969438 -104.103678)
		(width 0.11684)
		(layer "In6.Cu")
		(net "CPU1_XTRIG_L5")
	)
	(segment
		(start 280.747216 -95.306388)
		(end 278.44496 -93.004132)
		(width 0.11684)
		(layer "In6.Cu")
		(net "CPU1_XTRIG_L5")
	)
	(segment
		(start 232.14203 -95.616014)
		(end 220.456252 -95.616014)
		(width 0.11684)
		(layer "In6.Cu")
		(net "CPU1_XTRIG_L5")
	)
	(segment
		(start 272.72361 -92.531184)
		(end 263.859772 -92.531184)
		(width 0.11684)
		(layer "In6.Cu")
		(net "CPU1_XTRIG_L5")
	)
	(segment
		(start 167.243506 -99.419664)
		(end 166.858696 -99.804474)
		(width 0.11684)
		(layer "In6.Cu")
		(net "CPU1_XTRIG_L5")
	)
	(segment
		(start 170.130216 -98.240088)
		(end 168.950386 -99.419664)
		(width 0.11684)
		(layer "In6.Cu")
		(net "CPU1_XTRIG_L5")
	)
	(segment
		(start 233.02214 -96.496124)
		(end 232.14203 -95.616014)
		(width 0.11684)
		(layer "In6.Cu")
		(net "CPU1_XTRIG_L5")
	)
	(segment
		(start 316.437518 -96.778318)
		(end 314.965588 -95.306388)
		(width 0.11684)
		(layer "In6.Cu")
		(net "CPU1_XTRIG_L5")
	)
	(segment
		(start 263.386824 -93.004132)
		(end 259.97662 -93.004132)
		(width 0.11684)
		(layer "In6.Cu")
		(net "CPU1_XTRIG_L5")
	)
	(segment
		(start 331.578204 -98.835972)
		(end 329.52055 -96.778318)
		(width 0.11684)
		(layer "In6.Cu")
		(net "CPU1_XTRIG_L5")
	)
	(segment
		(start 166.858696 -99.804474)
		(end 166.858696 -100.325936)
		(width 0.11684)
		(layer "In6.Cu")
		(net "CPU1_XTRIG_L5")
	)
	(segment
		(start 273.196558 -93.004132)
		(end 272.72361 -92.531184)
		(width 0.11684)
		(layer "In6.Cu")
		(net "CPU1_XTRIG_L5")
	)
	(segment
		(start 197.334378 -89.721182)
		(end 178.71313 -89.721182)
		(width 0.11684)
		(layer "In6.Cu")
		(net "CPU1_XTRIG_L5")
	)
	(segment
		(start 216.548462 -94.567502)
		(end 203.9366 -94.567502)
		(width 0.11684)
		(layer "In6.Cu")
		(net "CPU1_XTRIG_L5")
	)
	(segment
		(start 200.779888 -93.166692)
		(end 197.334378 -89.721182)
		(width 0.11684)
		(layer "In6.Cu")
		(net "CPU1_XTRIG_L5")
	)
	(segment
		(start 278.44496 -93.004132)
		(end 273.196558 -93.004132)
		(width 0.11684)
		(layer "In6.Cu")
		(net "CPU1_XTRIG_L5")
	)
	(segment
		(start 202.53579 -93.166692)
		(end 200.779888 -93.166692)
		(width 0.11684)
		(layer "In6.Cu")
		(net "CPU1_XTRIG_L5")
	)
	(segment
		(start 168.950386 -99.419664)
		(end 167.243506 -99.419664)
		(width 0.11684)
		(layer "In6.Cu")
		(net "CPU1_XTRIG_L5")
	)
	(segment
		(start 175.1965 -93.237812)
		(end 175.1965 -96.064578)
		(width 0.11684)
		(layer "In6.Cu")
		(net "CPU1_XTRIG_L5")
	)
	(segment
		(start 329.52055 -96.778318)
		(end 316.437518 -96.778318)
		(width 0.11684)
		(layer "In6.Cu")
		(net "CPU1_XTRIG_L5")
	)
	(segment
		(start 173.02099 -98.240088)
		(end 170.130216 -98.240088)
		(width 0.11684)
		(layer "In6.Cu")
		(net "CPU1_XTRIG_L5")
	)
	(segment
		(start 218.16695 -96.18599)
		(end 216.548462 -94.567502)
		(width 0.11684)
		(layer "In6.Cu")
		(net "CPU1_XTRIG_L5")
	)
	(segment
		(start 259.97662 -93.004132)
		(end 256.484628 -96.496124)
		(width 0.11684)
		(layer "In6.Cu")
		(net "CPU1_XTRIG_L5")
	)
	(segment
		(start 256.484628 -96.496124)
		(end 233.02214 -96.496124)
		(width 0.11684)
		(layer "In6.Cu")
		(net "CPU1_XTRIG_L5")
	)
	(segment
		(start 349.318072 -47.784766)
		(end 336.100674 -61.002164)
		(width 0.11684)
		(layer "In11.Cu")
		(net "CPU1_XTRIG_L5")
	)
	(segment
		(start 350.84004 -41.710102)
		(end 349.318072 -43.23207)
		(width 0.11684)
		(layer "In11.Cu")
		(net "CPU1_XTRIG_L5")
	)
	(segment
		(start 336.100674 -61.002164)
		(end 336.100674 -85.398356)
		(width 0.11684)
		(layer "In11.Cu")
		(net "CPU1_XTRIG_L5")
	)
	(segment
		(start 349.318072 -43.23207)
		(end 349.318072 -47.784766)
		(width 0.11684)
		(layer "In11.Cu")
		(net "CPU1_XTRIG_L5")
	)
	(segment
		(start 331.578204 -89.920826)
		(end 331.578204 -98.89617)
		(width 0.11684)
		(layer "In11.Cu")
		(net "CPU1_XTRIG_L5")
	)
	(segment
		(start 336.100674 -85.398356)
		(end 331.578204 -89.920826)
		(width 0.11684)
		(layer "In11.Cu")
		(net "CPU1_XTRIG_L5")
	)
	(segment
		(start 4.410202 -59.264042)
		(end 4.853178 -59.264042)
		(width 0.10668)
		(layer "F.Cu")
		(net "CPU1_XTRIG_L4")
	)
	(segment
		(start 4.853178 -59.264042)
		(end 5.691886 -58.425334)
		(width 0.10668)
		(layer "F.Cu")
		(net "CPU1_XTRIG_L4")
	)
	(via
		(at 329.952604 -98.89617)
		(size 0.508)
		(drill 0.254)
		(layers "F.Cu" "B.Cu")
		(net "CPU1_XTRIG_L4")
	)
	(via
		(at 92.281502 -206.270352)
		(size 0.508)
		(drill 0.254)
		(layers "F.Cu" "B.Cu")
		(net "CPU1_XTRIG_L4")
	)
	(via
		(at 175.641 -97.145348)
		(size 0.508)
		(drill 0.254)
		(layers "F.Cu" "B.Cu")
		(net "CPU1_XTRIG_L4")
	)
	(via
		(at 5.691886 -58.425334)
		(size 0.508)
		(drill 0.254)
		(layers "F.Cu" "B.Cu")
		(net "CPU1_XTRIG_L4")
	)
	(segment
		(start 92.281502 -206.270352)
		(end 92.281502 -205.5495)
		(width 0.10668)
		(layer "B.Cu")
		(net "CPU1_XTRIG_L4")
	)
	(segment
		(start 92.281502 -206.9846)
		(end 92.281502 -206.270352)
		(width 0.10668)
		(layer "B.Cu")
		(net "CPU1_XTRIG_L4")
	)
	(segment
		(start 175.641 -98.894138)
		(end 175.641 -99.894898)
		(width 0.10668)
		(layer "B.Cu")
		(net "CPU1_XTRIG_L4")
	)
	(segment
		(start 175.641 -97.5487)
		(end 175.1584 -98.0313)
		(width 0.10668)
		(layer "B.Cu")
		(net "CPU1_XTRIG_L4")
	)
	(segment
		(start 175.641 -97.145348)
		(end 175.641 -97.5487)
		(width 0.10668)
		(layer "B.Cu")
		(net "CPU1_XTRIG_L4")
	)
	(segment
		(start 175.1584 -98.0313)
		(end 175.1584 -98.411538)
		(width 0.10668)
		(layer "B.Cu")
		(net "CPU1_XTRIG_L4")
	)
	(segment
		(start 175.1584 -98.411538)
		(end 175.641 -98.894138)
		(width 0.10668)
		(layer "B.Cu")
		(net "CPU1_XTRIG_L4")
	)
	(segment
		(start 133.902196 -108.899198)
		(end 133.902196 -113.457736)
		(width 0.11684)
		(layer "In2.Cu")
		(net "CPU1_XTRIG_L4")
	)
	(segment
		(start 151.211534 -105.007664)
		(end 147.648422 -105.007664)
		(width 0.11684)
		(layer "In2.Cu")
		(net "CPU1_XTRIG_L4")
	)
	(segment
		(start 133.35127 -133.583426)
		(end 145.436082 -145.668238)
		(width 0.11684)
		(layer "In2.Cu")
		(net "CPU1_XTRIG_L4")
	)
	(segment
		(start 133.902196 -113.457736)
		(end 133.35127 -114.008662)
		(width 0.11684)
		(layer "In2.Cu")
		(net "CPU1_XTRIG_L4")
	)
	(segment
		(start 136.037574 -106.76382)
		(end 133.902196 -108.899198)
		(width 0.11684)
		(layer "In2.Cu")
		(net "CPU1_XTRIG_L4")
	)
	(segment
		(start 170.165776 -98.097086)
		(end 168.746678 -99.516184)
		(width 0.11684)
		(layer "In2.Cu")
		(net "CPU1_XTRIG_L4")
	)
	(segment
		(start 138.631168 -175.137318)
		(end 102.623874 -201.799952)
		(width 0.11684)
		(layer "In2.Cu")
		(net "CPU1_XTRIG_L4")
	)
	(segment
		(start 102.623874 -201.799952)
		(end 100.941886 -203.481432)
		(width 0.11684)
		(layer "In2.Cu")
		(net "CPU1_XTRIG_L4")
	)
	(segment
		(start 175.641 -97.145348)
		(end 174.689262 -98.097086)
		(width 0.11684)
		(layer "In2.Cu")
		(net "CPU1_XTRIG_L4")
	)
	(segment
		(start 166.514526 -100.88626)
		(end 165.405816 -100.88626)
		(width 0.11684)
		(layer "In2.Cu")
		(net "CPU1_XTRIG_L4")
	)
	(segment
		(start 168.746678 -99.662488)
		(end 167.731694 -100.677472)
		(width 0.11684)
		(layer "In2.Cu")
		(net "CPU1_XTRIG_L4")
	)
	(segment
		(start 165.405816 -100.88626)
		(end 161.74847 -104.543606)
		(width 0.11684)
		(layer "In2.Cu")
		(net "CPU1_XTRIG_L4")
	)
	(segment
		(start 100.941886 -203.481432)
		(end 98.6155 -203.481432)
		(width 0.11684)
		(layer "In2.Cu")
		(net "CPU1_XTRIG_L4")
	)
	(segment
		(start 151.89073 -105.68686)
		(end 151.211534 -105.007664)
		(width 0.11684)
		(layer "In2.Cu")
		(net "CPU1_XTRIG_L4")
	)
	(segment
		(start 166.723314 -100.677472)
		(end 166.514526 -100.88626)
		(width 0.11684)
		(layer "In2.Cu")
		(net "CPU1_XTRIG_L4")
	)
	(segment
		(start 147.648422 -105.007664)
		(end 145.892266 -106.76382)
		(width 0.11684)
		(layer "In2.Cu")
		(net "CPU1_XTRIG_L4")
	)
	(segment
		(start 161.74847 -104.543606)
		(end 159.589978 -104.543606)
		(width 0.11684)
		(layer "In2.Cu")
		(net "CPU1_XTRIG_L4")
	)
	(segment
		(start 145.436082 -145.668238)
		(end 145.436082 -168.332404)
		(width 0.11684)
		(layer "In2.Cu")
		(net "CPU1_XTRIG_L4")
	)
	(segment
		(start 168.746678 -99.516184)
		(end 168.746678 -99.662488)
		(width 0.11684)
		(layer "In2.Cu")
		(net "CPU1_XTRIG_L4")
	)
	(segment
		(start 145.436082 -168.332404)
		(end 138.631168 -175.137318)
		(width 0.11684)
		(layer "In2.Cu")
		(net "CPU1_XTRIG_L4")
	)
	(segment
		(start 95.82658 -206.270352)
		(end 92.281502 -206.270352)
		(width 0.11684)
		(layer "In2.Cu")
		(net "CPU1_XTRIG_L4")
	)
	(segment
		(start 155.640278 -105.68686)
		(end 151.89073 -105.68686)
		(width 0.11684)
		(layer "In2.Cu")
		(net "CPU1_XTRIG_L4")
	)
	(segment
		(start 167.731694 -100.677472)
		(end 166.723314 -100.677472)
		(width 0.11684)
		(layer "In2.Cu")
		(net "CPU1_XTRIG_L4")
	)
	(segment
		(start 174.689262 -98.097086)
		(end 170.165776 -98.097086)
		(width 0.11684)
		(layer "In2.Cu")
		(net "CPU1_XTRIG_L4")
	)
	(segment
		(start 98.6155 -203.481432)
		(end 95.82658 -206.270352)
		(width 0.11684)
		(layer "In2.Cu")
		(net "CPU1_XTRIG_L4")
	)
	(segment
		(start 145.892266 -106.76382)
		(end 136.037574 -106.76382)
		(width 0.11684)
		(layer "In2.Cu")
		(net "CPU1_XTRIG_L4")
	)
	(segment
		(start 156.540962 -106.587544)
		(end 155.640278 -105.68686)
		(width 0.11684)
		(layer "In2.Cu")
		(net "CPU1_XTRIG_L4")
	)
	(segment
		(start 133.35127 -114.008662)
		(end 133.35127 -133.583426)
		(width 0.11684)
		(layer "In2.Cu")
		(net "CPU1_XTRIG_L4")
	)
	(segment
		(start 157.54604 -106.587544)
		(end 156.540962 -106.587544)
		(width 0.11684)
		(layer "In2.Cu")
		(net "CPU1_XTRIG_L4")
	)
	(segment
		(start 159.589978 -104.543606)
		(end 157.54604 -106.587544)
		(width 0.11684)
		(layer "In2.Cu")
		(net "CPU1_XTRIG_L4")
	)
	(segment
		(start 54.755796 -185.514742)
		(end 54.755796 -187.842144)
		(width 0.11684)
		(layer "In4.Cu")
		(net "CPU1_XTRIG_L4")
	)
	(segment
		(start 62.910974 -189.858142)
		(end 77.78242 -204.729588)
		(width 0.11684)
		(layer "In4.Cu")
		(net "CPU1_XTRIG_L4")
	)
	(segment
		(start 33.970976 -75.486514)
		(end 41.803066 -83.318604)
		(width 0.11684)
		(layer "In4.Cu")
		(net "CPU1_XTRIG_L4")
	)
	(segment
		(start 89.971626 -110.11789)
		(end 97.658428 -110.11789)
		(width 0.11684)
		(layer "In4.Cu")
		(net "CPU1_XTRIG_L4")
	)
	(segment
		(start 77.78242 -204.729588)
		(end 90.740738 -204.729588)
		(width 0.11684)
		(layer "In4.Cu")
		(net "CPU1_XTRIG_L4")
	)
	(segment
		(start 90.740738 -204.729588)
		(end 92.281502 -206.270352)
		(width 0.11684)
		(layer "In4.Cu")
		(net "CPU1_XTRIG_L4")
	)
	(segment
		(start 79.452216 -131.629912)
		(end 69.548756 -141.533372)
		(width 0.11684)
		(layer "In4.Cu")
		(net "CPU1_XTRIG_L4")
	)
	(segment
		(start 56.771794 -189.858142)
		(end 62.910974 -189.858142)
		(width 0.11684)
		(layer "In4.Cu")
		(net "CPU1_XTRIG_L4")
	)
	(segment
		(start 47.00143 -143.162274)
		(end 47.00143 -177.760376)
		(width 0.11684)
		(layer "In4.Cu")
		(net "CPU1_XTRIG_L4")
	)
	(segment
		(start 54.755796 -187.842144)
		(end 56.771794 -189.858142)
		(width 0.11684)
		(layer "In4.Cu")
		(net "CPU1_XTRIG_L4")
	)
	(segment
		(start 41.803066 -83.318604)
		(end 63.17234 -83.318604)
		(width 0.11684)
		(layer "In4.Cu")
		(net "CPU1_XTRIG_L4")
	)
	(segment
		(start 69.548756 -141.533372)
		(end 48.630332 -141.533372)
		(width 0.11684)
		(layer "In4.Cu")
		(net "CPU1_XTRIG_L4")
	)
	(segment
		(start 12.675616 -58.425334)
		(end 15.403576 -55.697374)
		(width 0.11684)
		(layer "In4.Cu")
		(net "CPU1_XTRIG_L4")
	)
	(segment
		(start 33.970976 -61.29909)
		(end 33.970976 -75.486514)
		(width 0.11684)
		(layer "In4.Cu")
		(net "CPU1_XTRIG_L4")
	)
	(segment
		(start 15.403576 -55.697374)
		(end 28.36926 -55.697374)
		(width 0.11684)
		(layer "In4.Cu")
		(net "CPU1_XTRIG_L4")
	)
	(segment
		(start 63.17234 -83.318604)
		(end 89.971626 -110.11789)
		(width 0.11684)
		(layer "In4.Cu")
		(net "CPU1_XTRIG_L4")
	)
	(segment
		(start 5.691886 -58.425334)
		(end 12.675616 -58.425334)
		(width 0.11684)
		(layer "In4.Cu")
		(net "CPU1_XTRIG_L4")
	)
	(segment
		(start 92.566744 -121.076974)
		(end 92.566744 -123.73991)
		(width 0.11684)
		(layer "In4.Cu")
		(net "CPU1_XTRIG_L4")
	)
	(segment
		(start 28.36926 -55.697374)
		(end 33.970976 -61.29909)
		(width 0.11684)
		(layer "In4.Cu")
		(net "CPU1_XTRIG_L4")
	)
	(segment
		(start 48.630332 -141.533372)
		(end 47.00143 -143.162274)
		(width 0.11684)
		(layer "In4.Cu")
		(net "CPU1_XTRIG_L4")
	)
	(segment
		(start 99.34067 -114.303048)
		(end 92.566744 -121.076974)
		(width 0.11684)
		(layer "In4.Cu")
		(net "CPU1_XTRIG_L4")
	)
	(segment
		(start 47.00143 -177.760376)
		(end 54.755796 -185.514742)
		(width 0.11684)
		(layer "In4.Cu")
		(net "CPU1_XTRIG_L4")
	)
	(segment
		(start 97.658428 -110.11789)
		(end 99.34067 -111.800132)
		(width 0.11684)
		(layer "In4.Cu")
		(net "CPU1_XTRIG_L4")
	)
	(segment
		(start 92.566744 -123.73991)
		(end 84.676742 -131.629912)
		(width 0.11684)
		(layer "In4.Cu")
		(net "CPU1_XTRIG_L4")
	)
	(segment
		(start 84.676742 -131.629912)
		(end 79.452216 -131.629912)
		(width 0.11684)
		(layer "In4.Cu")
		(net "CPU1_XTRIG_L4")
	)
	(segment
		(start 99.34067 -111.800132)
		(end 99.34067 -114.303048)
		(width 0.11684)
		(layer "In4.Cu")
		(net "CPU1_XTRIG_L4")
	)
	(segment
		(start 259.731764 -94.441772)
		(end 274.342352 -94.441772)
		(width 0.11684)
		(layer "In6.Cu")
		(net "CPU1_XTRIG_L4")
	)
	(segment
		(start 176.03978 -94.83217)
		(end 176.582324 -94.289626)
		(width 0.11684)
		(layer "In6.Cu")
		(net "CPU1_XTRIG_L4")
	)
	(segment
		(start 215.469216 -97.39122)
		(end 220.065854 -97.39122)
		(width 0.11684)
		(layer "In6.Cu")
		(net "CPU1_XTRIG_L4")
	)
	(segment
		(start 176.03978 -96.746568)
		(end 176.03978 -94.83217)
		(width 0.11684)
		(layer "In6.Cu")
		(net "CPU1_XTRIG_L4")
	)
	(segment
		(start 201.099166 -96.337628)
		(end 202.595734 -96.337628)
		(width 0.11684)
		(layer "In6.Cu")
		(net "CPU1_XTRIG_L4")
	)
	(segment
		(start 232.672128 -97.339404)
		(end 256.834132 -97.339404)
		(width 0.11684)
		(layer "In6.Cu")
		(net "CPU1_XTRIG_L4")
	)
	(segment
		(start 177.512218 -93.872812)
		(end 177.512218 -93.517466)
		(width 0.11684)
		(layer "In6.Cu")
		(net "CPU1_XTRIG_L4")
	)
	(segment
		(start 231.792018 -96.459294)
		(end 232.672128 -97.339404)
		(width 0.11684)
		(layer "In6.Cu")
		(net "CPU1_XTRIG_L4")
	)
	(segment
		(start 328.708512 -97.652078)
		(end 329.952604 -98.89617)
		(width 0.11684)
		(layer "In6.Cu")
		(net "CPU1_XTRIG_L4")
	)
	(segment
		(start 202.771502 -96.16186)
		(end 208.067656 -96.16186)
		(width 0.11684)
		(layer "In6.Cu")
		(net "CPU1_XTRIG_L4")
	)
	(segment
		(start 179.386992 -90.564462)
		(end 195.48348 -90.564462)
		(width 0.11684)
		(layer "In6.Cu")
		(net "CPU1_XTRIG_L4")
	)
	(segment
		(start 177.095404 -94.289626)
		(end 177.512218 -93.872812)
		(width 0.11684)
		(layer "In6.Cu")
		(net "CPU1_XTRIG_L4")
	)
	(segment
		(start 275.363686 -95.463106)
		(end 279.71115 -95.463106)
		(width 0.11684)
		(layer "In6.Cu")
		(net "CPU1_XTRIG_L4")
	)
	(segment
		(start 212.225128 -96.474788)
		(end 214.552784 -96.474788)
		(width 0.11684)
		(layer "In6.Cu")
		(net "CPU1_XTRIG_L4")
	)
	(segment
		(start 198.772526 -94.010988)
		(end 201.099166 -96.337628)
		(width 0.11684)
		(layer "In6.Cu")
		(net "CPU1_XTRIG_L4")
	)
	(segment
		(start 316.075314 -97.652078)
		(end 328.708512 -97.652078)
		(width 0.11684)
		(layer "In6.Cu")
		(net "CPU1_XTRIG_L4")
	)
	(segment
		(start 280.428192 -96.180148)
		(end 314.603384 -96.180148)
		(width 0.11684)
		(layer "In6.Cu")
		(net "CPU1_XTRIG_L4")
	)
	(segment
		(start 279.71115 -95.463106)
		(end 280.428192 -96.180148)
		(width 0.11684)
		(layer "In6.Cu")
		(net "CPU1_XTRIG_L4")
	)
	(segment
		(start 220.99778 -96.459294)
		(end 231.792018 -96.459294)
		(width 0.11684)
		(layer "In6.Cu")
		(net "CPU1_XTRIG_L4")
	)
	(segment
		(start 208.544668 -96.638872)
		(end 212.061044 -96.638872)
		(width 0.11684)
		(layer "In6.Cu")
		(net "CPU1_XTRIG_L4")
	)
	(segment
		(start 208.067656 -96.16186)
		(end 208.544668 -96.638872)
		(width 0.11684)
		(layer "In6.Cu")
		(net "CPU1_XTRIG_L4")
	)
	(segment
		(start 178.778662 -91.172792)
		(end 179.386992 -90.564462)
		(width 0.11684)
		(layer "In6.Cu")
		(net "CPU1_XTRIG_L4")
	)
	(segment
		(start 177.512218 -93.517466)
		(end 178.778662 -92.251022)
		(width 0.11684)
		(layer "In6.Cu")
		(net "CPU1_XTRIG_L4")
	)
	(segment
		(start 212.061044 -96.638872)
		(end 212.225128 -96.474788)
		(width 0.11684)
		(layer "In6.Cu")
		(net "CPU1_XTRIG_L4")
	)
	(segment
		(start 195.48348 -90.564462)
		(end 198.772526 -93.853508)
		(width 0.11684)
		(layer "In6.Cu")
		(net "CPU1_XTRIG_L4")
	)
	(segment
		(start 178.778662 -92.251022)
		(end 178.778662 -91.172792)
		(width 0.11684)
		(layer "In6.Cu")
		(net "CPU1_XTRIG_L4")
	)
	(segment
		(start 274.342352 -94.441772)
		(end 275.363686 -95.463106)
		(width 0.11684)
		(layer "In6.Cu")
		(net "CPU1_XTRIG_L4")
	)
	(segment
		(start 314.603384 -96.180148)
		(end 316.075314 -97.652078)
		(width 0.11684)
		(layer "In6.Cu")
		(net "CPU1_XTRIG_L4")
	)
	(segment
		(start 198.772526 -93.853508)
		(end 198.772526 -94.010988)
		(width 0.11684)
		(layer "In6.Cu")
		(net "CPU1_XTRIG_L4")
	)
	(segment
		(start 256.834132 -97.339404)
		(end 259.731764 -94.441772)
		(width 0.11684)
		(layer "In6.Cu")
		(net "CPU1_XTRIG_L4")
	)
	(segment
		(start 214.552784 -96.474788)
		(end 215.469216 -97.39122)
		(width 0.11684)
		(layer "In6.Cu")
		(net "CPU1_XTRIG_L4")
	)
	(segment
		(start 176.582324 -94.289626)
		(end 177.095404 -94.289626)
		(width 0.11684)
		(layer "In6.Cu")
		(net "CPU1_XTRIG_L4")
	)
	(segment
		(start 175.641 -97.145348)
		(end 176.03978 -96.746568)
		(width 0.11684)
		(layer "In6.Cu")
		(net "CPU1_XTRIG_L4")
	)
	(segment
		(start 220.065854 -97.39122)
		(end 220.99778 -96.459294)
		(width 0.11684)
		(layer "In6.Cu")
		(net "CPU1_XTRIG_L4")
	)
	(segment
		(start 202.595734 -96.337628)
		(end 202.771502 -96.16186)
		(width 0.11684)
		(layer "In6.Cu")
		(net "CPU1_XTRIG_L4")
	)
	(segment
		(start 346.079572 -43.00474)
		(end 345.176856 -43.00474)
		(width 0.11684)
		(layer "In11.Cu")
		(net "CPU1_XTRIG_L4")
	)
	(segment
		(start 353.38004 -41.710102)
		(end 352.240088 -40.57015)
		(width 0.11684)
		(layer "In11.Cu")
		(net "CPU1_XTRIG_L4")
	)
	(segment
		(start 344.758264 -47.526194)
		(end 333.897478 -58.38698)
		(width 0.11684)
		(layer "In11.Cu")
		(net "CPU1_XTRIG_L4")
	)
	(segment
		(start 347.842332 -40.57015)
		(end 347.027246 -41.385236)
		(width 0.11684)
		(layer "In11.Cu")
		(net "CPU1_XTRIG_L4")
	)
	(segment
		(start 344.758264 -43.423332)
		(end 344.758264 -47.526194)
		(width 0.11684)
		(layer "In11.Cu")
		(net "CPU1_XTRIG_L4")
	)
	(segment
		(start 347.027246 -41.385236)
		(end 347.027246 -42.057066)
		(width 0.11684)
		(layer "In11.Cu")
		(net "CPU1_XTRIG_L4")
	)
	(segment
		(start 333.897478 -58.38698)
		(end 333.897478 -85.302344)
		(width 0.11684)
		(layer "In11.Cu")
		(net "CPU1_XTRIG_L4")
	)
	(segment
		(start 333.897478 -85.302344)
		(end 329.952604 -89.247218)
		(width 0.11684)
		(layer "In11.Cu")
		(net "CPU1_XTRIG_L4")
	)
	(segment
		(start 352.240088 -40.57015)
		(end 347.842332 -40.57015)
		(width 0.11684)
		(layer "In11.Cu")
		(net "CPU1_XTRIG_L4")
	)
	(segment
		(start 345.176856 -43.00474)
		(end 344.758264 -43.423332)
		(width 0.11684)
		(layer "In11.Cu")
		(net "CPU1_XTRIG_L4")
	)
	(segment
		(start 329.952604 -89.247218)
		(end 329.952604 -98.89617)
		(width 0.11684)
		(layer "In11.Cu")
		(net "CPU1_XTRIG_L4")
	)
	(segment
		(start 347.027246 -42.057066)
		(end 346.079572 -43.00474)
		(width 0.11684)
		(layer "In11.Cu")
		(net "CPU1_XTRIG_L4")
	)
	(segment
		(start 125.707902 -266.530328)
		(end 126.174754 -266.796266)
		(width 0.10668)
		(layer "F.Cu")
		(net "CPU1_VDDBT_RTC_G")
	)
	(segment
		(start 149.249384 -321.733672)
		(end 149.249384 -320.717672)
		(width 0.10668)
		(layer "F.Cu")
		(net "CPU1_VDDBT_RTC_G")
	)
	(segment
		(start 148.740114 -320.717672)
		(end 148.404834 -321.052952)
		(width 0.10668)
		(layer "F.Cu")
		(net "CPU1_VDDBT_RTC_G")
	)
	(segment
		(start 149.249384 -320.717672)
		(end 148.740114 -320.717672)
		(width 0.10668)
		(layer "F.Cu")
		(net "CPU1_VDDBT_RTC_G")
	)
	(via
		(at 126.174754 -266.796266)
		(size 0.4064)
		(drill 0.2032)
		(layers "F.Cu" "B.Cu")
		(net "CPU1_VDDBT_RTC_G")
	)
	(via
		(at 148.404834 -321.052952)
		(size 0.508)
		(drill 0.254)
		(layers "F.Cu" "B.Cu")
		(net "CPU1_VDDBT_RTC_G")
	)
	(segment
		(start 126.877064 -268.81963)
		(end 126.879858 -268.821408)
		(width 0.11684)
		(layer "In4.Cu")
		(net "CPU1_VDDBT_RTC_G")
	)
	(segment
		(start 128.726438 -283.382212)
		(end 128.759712 -283.401516)
		(width 0.11684)
		(layer "In4.Cu")
		(net "CPU1_VDDBT_RTC_G")
	)
	(segment
		(start 127.349758 -269.63116)
		(end 127.385572 -269.651988)
		(width 0.11684)
		(layer "In4.Cu")
		(net "CPU1_VDDBT_RTC_G")
	)
	(segment
		(start 141.172184 -308.651402)
		(end 141.172184 -311.895236)
		(width 0.11684)
		(layer "In4.Cu")
		(net "CPU1_VDDBT_RTC_G")
	)
	(segment
		(start 128.759712 -272.061432)
		(end 128.795272 -272.082006)
		(width 0.11684)
		(layer "In4.Cu")
		(net "CPU1_VDDBT_RTC_G")
	)
	(segment
		(start 128.759712 -274.491196)
		(end 128.757426 -274.49272)
		(width 0.11684)
		(layer "In4.Cu")
		(net "CPU1_VDDBT_RTC_G")
	)
	(segment
		(start 126.409704 -278.54148)
		(end 126.374144 -278.562054)
		(width 0.11684)
		(layer "In4.Cu")
		(net "CPU1_VDDBT_RTC_G")
	)
	(segment
		(start 141.172184 -311.895236)
		(end 142.11808 -312.841132)
		(width 0.11684)
		(layer "In4.Cu")
		(net "CPU1_VDDBT_RTC_G")
	)
	(segment
		(start 128.994916 -290.286186)
		(end 128.994662 -290.286186)
		(width 0.11684)
		(layer "In4.Cu")
		(net "CPU1_VDDBT_RTC_G")
	)
	(segment
		(start 126.879858 -280.161492)
		(end 126.914148 -280.181558)
		(width 0.11684)
		(layer "In4.Cu")
		(net "CPU1_VDDBT_RTC_G")
	)
	(segment
		(start 128.323086 -275.282152)
		(end 128.289812 -275.301456)
		(width 0.11684)
		(layer "In4.Cu")
		(net "CPU1_VDDBT_RTC_G")
	)
	(segment
		(start 127.787654 -281.762962)
		(end 127.819658 -281.781504)
		(width 0.11684)
		(layer "In4.Cu")
		(net "CPU1_VDDBT_RTC_G")
	)
	(segment
		(start 126.879858 -268.821408)
		(end 126.914148 -268.841474)
		(width 0.11684)
		(layer "In4.Cu")
		(net "CPU1_VDDBT_RTC_G")
	)
	(segment
		(start 127.787654 -270.422878)
		(end 127.819658 -270.44142)
		(width 0.11684)
		(layer "In4.Cu")
		(net "CPU1_VDDBT_RTC_G")
	)
	(segment
		(start 129.229866 -289.881056)
		(end 129.22758 -289.88258)
		(width 0.11684)
		(layer "In4.Cu")
		(net "CPU1_VDDBT_RTC_G")
	)
	(segment
		(start 131.10972 -293.93134)
		(end 131.14528 -293.951914)
		(width 0.11684)
		(layer "In4.Cu")
		(net "CPU1_VDDBT_RTC_G")
	)
	(segment
		(start 142.11808 -312.841132)
		(end 142.11808 -314.446666)
		(width 0.11684)
		(layer "In4.Cu")
		(net "CPU1_VDDBT_RTC_G")
	)
	(segment
		(start 129.194052 -290.670488)
		(end 129.229866 -290.691316)
		(width 0.11684)
		(layer "In4.Cu")
		(net "CPU1_VDDBT_RTC_G")
	)
	(segment
		(start 129.696718 -288.259266)
		(end 129.699766 -288.261298)
		(width 0.11684)
		(layer "In4.Cu")
		(net "CPU1_VDDBT_RTC_G")
	)
	(segment
		(start 126.374144 -279.330658)
		(end 126.409704 -279.351232)
		(width 0.11684)
		(layer "In4.Cu")
		(net "CPU1_VDDBT_RTC_G")
	)
	(segment
		(start 127.819658 -270.44142)
		(end 127.857758 -270.463518)
		(width 0.11684)
		(layer "In4.Cu")
		(net "CPU1_VDDBT_RTC_G")
	)
	(segment
		(start 131.10972 -294.741092)
		(end 131.076446 -294.760396)
		(width 0.11684)
		(layer "In4.Cu")
		(net "CPU1_VDDBT_RTC_G")
	)
	(segment
		(start 126.879858 -277.73122)
		(end 126.844044 -277.752048)
		(width 0.11684)
		(layer "In4.Cu")
		(net "CPU1_VDDBT_RTC_G")
	)
	(segment
		(start 128.795272 -274.470622)
		(end 128.759712 -274.491196)
		(width 0.11684)
		(layer "In4.Cu")
		(net "CPU1_VDDBT_RTC_G")
	)
	(segment
		(start 129.661666 -291.47897)
		(end 129.699766 -291.501068)
		(width 0.11684)
		(layer "In4.Cu")
		(net "CPU1_VDDBT_RTC_G")
	)
	(segment
		(start 126.374144 -267.990574)
		(end 126.409704 -268.011148)
		(width 0.11684)
		(layer "In4.Cu")
		(net "CPU1_VDDBT_RTC_G")
	)
	(segment
		(start 127.819658 -281.781504)
		(end 127.857758 -281.803602)
		(width 0.11684)
		(layer "In4.Cu")
		(net "CPU1_VDDBT_RTC_G")
	)
	(segment
		(start 126.409704 -279.351232)
		(end 126.442978 -279.370536)
		(width 0.11684)
		(layer "In4.Cu")
		(net "CPU1_VDDBT_RTC_G")
	)
	(segment
		(start 130.60426 -293.100506)
		(end 130.63982 -293.12108)
		(width 0.11684)
		(layer "In4.Cu")
		(net "CPU1_VDDBT_RTC_G")
	)
	(segment
		(start 129.229866 -272.871184)
		(end 129.26187 -272.889726)
		(width 0.11684)
		(layer "In4.Cu")
		(net "CPU1_VDDBT_RTC_G")
	)
	(segment
		(start 128.726438 -272.042128)
		(end 128.759712 -272.061432)
		(width 0.11684)
		(layer "In4.Cu")
		(net "CPU1_VDDBT_RTC_G")
	)
	(segment
		(start 130.404616 -297.883834)
		(end 141.172184 -308.651402)
		(width 0.11684)
		(layer "In4.Cu")
		(net "CPU1_VDDBT_RTC_G")
	)
	(segment
		(start 128.289812 -275.301456)
		(end 128.254252 -275.32203)
		(width 0.11684)
		(layer "In4.Cu")
		(net "CPU1_VDDBT_RTC_G")
	)
	(segment
		(start 130.169666 -292.311328)
		(end 130.207766 -292.333426)
		(width 0.11684)
		(layer "In4.Cu")
		(net "CPU1_VDDBT_RTC_G")
	)
	(segment
		(start 129.699766 -288.261298)
		(end 129.737866 -288.283396)
		(width 0.11684)
		(layer "In4.Cu")
		(net "CPU1_VDDBT_RTC_G")
	)
	(segment
		(start 128.289812 -282.591256)
		(end 128.323086 -282.61056)
		(width 0.11684)
		(layer "In4.Cu")
		(net "CPU1_VDDBT_RTC_G")
	)
	(segment
		(start 130.207766 -286.619188)
		(end 130.169666 -286.641286)
		(width 0.11684)
		(layer "In4.Cu")
		(net "CPU1_VDDBT_RTC_G")
	)
	(segment
		(start 129.699766 -285.021528)
		(end 129.737866 -285.043626)
		(width 0.11684)
		(layer "In4.Cu")
		(net "CPU1_VDDBT_RTC_G")
	)
	(segment
		(start 130.404616 -296.780966)
		(end 130.404616 -297.883834)
		(width 0.11684)
		(layer "In4.Cu")
		(net "CPU1_VDDBT_RTC_G")
	)
	(segment
		(start 127.819658 -276.111208)
		(end 127.787654 -276.12975)
		(width 0.11684)
		(layer "In4.Cu")
		(net "CPU1_VDDBT_RTC_G")
	)
	(segment
		(start 129.73558 -289.050476)
		(end 129.699766 -289.071304)
		(width 0.11684)
		(layer "In4.Cu")
		(net "CPU1_VDDBT_RTC_G")
	)
	(segment
		(start 129.229866 -290.691316)
		(end 129.264156 -290.711382)
		(width 0.11684)
		(layer "In4.Cu")
		(net "CPU1_VDDBT_RTC_G")
	)
	(segment
		(start 129.73558 -287.430464)
		(end 129.663952 -287.47212)
		(width 0.11684)
		(layer "In4.Cu")
		(net "CPU1_VDDBT_RTC_G")
	)
	(segment
		(start 143.281146 -315.609732)
		(end 143.281146 -317.646304)
		(width 0.11684)
		(layer "In4.Cu")
		(net "CPU1_VDDBT_RTC_G")
	)
	(segment
		(start 131.10972 -294.741346)
		(end 131.10972 -294.741092)
		(width 0.11684)
		(layer "In4.Cu")
		(net "CPU1_VDDBT_RTC_G")
	)
	(segment
		(start 129.663952 -285.0007)
		(end 129.699766 -285.021528)
		(width 0.11684)
		(layer "In4.Cu")
		(net "CPU1_VDDBT_RTC_G")
	)
	(segment
		(start 130.641598 -295.552368)
		(end 130.604768 -295.573958)
		(width 0.11684)
		(layer "In4.Cu")
		(net "CPU1_VDDBT_RTC_G")
	)
	(segment
		(start 130.169666 -286.641286)
		(end 130.135376 -286.661352)
		(width 0.11684)
		(layer "In4.Cu")
		(net "CPU1_VDDBT_RTC_G")
	)
	(segment
		(start 129.699766 -291.501068)
		(end 129.73558 -291.521896)
		(width 0.11684)
		(layer "In4.Cu")
		(net "CPU1_VDDBT_RTC_G")
	)
	(segment
		(start 145.276316 -318.814958)
		(end 147.51431 -321.052952)
		(width 0.11684)
		(layer "In4.Cu")
		(net "CPU1_VDDBT_RTC_G")
	)
	(segment
		(start 127.311658 -269.609062)
		(end 127.349758 -269.63116)
		(width 0.11684)
		(layer "In4.Cu")
		(net "CPU1_VDDBT_RTC_G")
	)
	(segment
		(start 129.229866 -284.211268)
		(end 129.26187 -284.22981)
		(width 0.11684)
		(layer "In4.Cu")
		(net "CPU1_VDDBT_RTC_G")
	)
	(segment
		(start 130.87477 -295.146222)
		(end 130.87477 -295.160192)
		(width 0.11684)
		(layer "In4.Cu")
		(net "CPU1_VDDBT_RTC_G")
	)
	(segment
		(start 127.349758 -280.971244)
		(end 127.385572 -280.992072)
		(width 0.11684)
		(layer "In4.Cu")
		(net "CPU1_VDDBT_RTC_G")
	)
	(segment
		(start 129.264156 -289.86099)
		(end 129.229866 -289.881056)
		(width 0.11684)
		(layer "In4.Cu")
		(net "CPU1_VDDBT_RTC_G")
	)
	(segment
		(start 126.409704 -268.011148)
		(end 126.442978 -268.030452)
		(width 0.11684)
		(layer "In4.Cu")
		(net "CPU1_VDDBT_RTC_G")
	)
	(segment
		(start 131.112006 -294.739822)
		(end 131.10972 -294.741346)
		(width 0.11684)
		(layer "In4.Cu")
		(net "CPU1_VDDBT_RTC_G")
	)
	(segment
		(start 128.254252 -271.230598)
		(end 128.289812 -271.251172)
		(width 0.11684)
		(layer "In4.Cu")
		(net "CPU1_VDDBT_RTC_G")
	)
	(segment
		(start 129.191766 -272.849086)
		(end 129.229866 -272.871184)
		(width 0.11684)
		(layer "In4.Cu")
		(net "CPU1_VDDBT_RTC_G")
	)
	(segment
		(start 129.229866 -273.681444)
		(end 129.191766 -273.703542)
		(width 0.11684)
		(layer "In4.Cu")
		(net "CPU1_VDDBT_RTC_G")
	)
	(segment
		(start 128.759712 -283.401516)
		(end 128.795272 -283.42209)
		(width 0.11684)
		(layer "In4.Cu")
		(net "CPU1_VDDBT_RTC_G")
	)
	(segment
		(start 130.169666 -285.83128)
		(end 130.17246 -285.833058)
		(width 0.11684)
		(layer "In4.Cu")
		(net "CPU1_VDDBT_RTC_G")
	)
	(segment
		(start 126.914148 -277.711154)
		(end 126.879858 -277.73122)
		(width 0.11684)
		(layer "In4.Cu")
		(net "CPU1_VDDBT_RTC_G")
	)
	(segment
		(start 147.51431 -321.052952)
		(end 148.404834 -321.052952)
		(width 0.11684)
		(layer "In4.Cu")
		(net "CPU1_VDDBT_RTC_G")
	)
	(segment
		(start 130.135376 -285.811214)
		(end 130.169666 -285.83128)
		(width 0.11684)
		(layer "In4.Cu")
		(net "CPU1_VDDBT_RTC_G")
	)
	(segment
		(start 127.385572 -276.90064)
		(end 127.349758 -276.921468)
		(width 0.11684)
		(layer "In4.Cu")
		(net "CPU1_VDDBT_RTC_G")
	)
	(segment
		(start 130.63982 -293.12108)
		(end 130.673094 -293.140384)
		(width 0.11684)
		(layer "In4.Cu")
		(net "CPU1_VDDBT_RTC_G")
	)
	(segment
		(start 128.289812 -271.251172)
		(end 128.323086 -271.270476)
		(width 0.11684)
		(layer "In4.Cu")
		(net "CPU1_VDDBT_RTC_G")
	)
	(segment
		(start 126.442978 -278.522176)
		(end 126.409704 -278.54148)
		(width 0.11684)
		(layer "In4.Cu")
		(net "CPU1_VDDBT_RTC_G")
	)
	(segment
		(start 129.699766 -289.071304)
		(end 129.661666 -289.093402)
		(width 0.11684)
		(layer "In4.Cu")
		(net "CPU1_VDDBT_RTC_G")
	)
	(segment
		(start 143.281146 -317.646304)
		(end 144.4498 -318.814958)
		(width 0.11684)
		(layer "In4.Cu")
		(net "CPU1_VDDBT_RTC_G")
	)
	(segment
		(start 129.231898 -273.680174)
		(end 129.229866 -273.681444)
		(width 0.11684)
		(layer "In4.Cu")
		(net "CPU1_VDDBT_RTC_G")
	)
	(segment
		(start 127.349758 -276.921468)
		(end 127.311658 -276.943566)
		(width 0.11684)
		(layer "In4.Cu")
		(net "CPU1_VDDBT_RTC_G")
	)
	(segment
		(start 128.254252 -282.570682)
		(end 128.289812 -282.591256)
		(width 0.11684)
		(layer "In4.Cu")
		(net "CPU1_VDDBT_RTC_G")
	)
	(segment
		(start 129.191766 -284.18917)
		(end 129.229866 -284.211268)
		(width 0.11684)
		(layer "In4.Cu")
		(net "CPU1_VDDBT_RTC_G")
	)
	(segment
		(start 142.11808 -314.446666)
		(end 143.281146 -315.609732)
		(width 0.11684)
		(layer "In4.Cu")
		(net "CPU1_VDDBT_RTC_G")
	)
	(segment
		(start 126.844044 -280.140664)
		(end 126.879858 -280.161492)
		(width 0.11684)
		(layer "In4.Cu")
		(net "CPU1_VDDBT_RTC_G")
	)
	(segment
		(start 130.137662 -292.292786)
		(end 130.169666 -292.311328)
		(width 0.11684)
		(layer "In4.Cu")
		(net "CPU1_VDDBT_RTC_G")
	)
	(segment
		(start 127.857758 -276.08911)
		(end 127.819658 -276.111208)
		(width 0.11684)
		(layer "In4.Cu")
		(net "CPU1_VDDBT_RTC_G")
	)
	(segment
		(start 126.174754 -266.796266)
		(end 126.174754 -267.606272)
		(width 0.11684)
		(layer "In4.Cu")
		(net "CPU1_VDDBT_RTC_G")
	)
	(segment
		(start 130.406394 -295.957244)
		(end 130.404616 -296.780966)
		(width 0.11684)
		(layer "In4.Cu")
		(net "CPU1_VDDBT_RTC_G")
	)
	(segment
		(start 127.311658 -280.949146)
		(end 127.349758 -280.971244)
		(width 0.11684)
		(layer "In4.Cu")
		(net "CPU1_VDDBT_RTC_G")
	)
	(segment
		(start 131.076446 -293.912036)
		(end 131.10972 -293.93134)
		(width 0.11684)
		(layer "In4.Cu")
		(net "CPU1_VDDBT_RTC_G")
	)
	(segment
		(start 144.4498 -318.814958)
		(end 145.276316 -318.814958)
		(width 0.11684)
		(layer "In4.Cu")
		(net "CPU1_VDDBT_RTC_G")
	)
	(arc
		(start 126.374144 -278.562054)
		(mid 126.1748 -278.946356)
		(end 126.374144 -279.330658)
		(width 0.11684)
		(layer "In4.Cu")
		(net "CPU1_VDDBT_RTC_G")
	)
	(arc
		(start 129.663952 -287.47212)
		(mid 129.51741 -287.639958)
		(end 129.464562 -287.856422)
		(width 0.11684)
		(layer "In4.Cu")
		(net "CPU1_VDDBT_RTC_G")
	)
	(arc
		(start 128.795272 -272.082006)
		(mid 128.941814 -272.249844)
		(end 128.994662 -272.466308)
		(width 0.11684)
		(layer "In4.Cu")
		(net "CPU1_VDDBT_RTC_G")
	)
	(arc
		(start 126.914148 -280.181558)
		(mid 127.061451 -280.349434)
		(end 127.114554 -280.566368)
		(width 0.11684)
		(layer "In4.Cu")
		(net "CPU1_VDDBT_RTC_G")
	)
	(arc
		(start 130.87477 -295.160192)
		(mid 130.808954 -295.386467)
		(end 130.641598 -295.552368)
		(width 0.11684)
		(layer "In4.Cu")
		(net "CPU1_VDDBT_RTC_G")
	)
	(arc
		(start 130.135376 -286.661352)
		(mid 129.988073 -286.829228)
		(end 129.93497 -287.046162)
		(width 0.11684)
		(layer "In4.Cu")
		(net "CPU1_VDDBT_RTC_G")
	)
	(arc
		(start 127.114554 -280.566368)
		(mid 127.16673 -280.781633)
		(end 127.311658 -280.949146)
		(width 0.11684)
		(layer "In4.Cu")
		(net "CPU1_VDDBT_RTC_G")
	)
	(arc
		(start 129.737866 -285.043626)
		(mid 129.882823 -285.211124)
		(end 129.93497 -285.426404)
		(width 0.11684)
		(layer "In4.Cu")
		(net "CPU1_VDDBT_RTC_G")
	)
	(arc
		(start 126.844044 -277.752048)
		(mid 126.697502 -277.919886)
		(end 126.644654 -278.13635)
		(width 0.11684)
		(layer "In4.Cu")
		(net "CPU1_VDDBT_RTC_G")
	)
	(arc
		(start 128.054862 -275.706332)
		(mid 128.002686 -275.921597)
		(end 127.857758 -276.08911)
		(width 0.11684)
		(layer "In4.Cu")
		(net "CPU1_VDDBT_RTC_G")
	)
	(arc
		(start 128.323086 -271.270476)
		(mid 128.471302 -271.438624)
		(end 128.524762 -271.656302)
		(width 0.11684)
		(layer "In4.Cu")
		(net "CPU1_VDDBT_RTC_G")
	)
	(arc
		(start 129.93497 -291.906198)
		(mid 129.988724 -292.124438)
		(end 130.137662 -292.292786)
		(width 0.11684)
		(layer "In4.Cu")
		(net "CPU1_VDDBT_RTC_G")
	)
	(arc
		(start 129.26187 -284.22981)
		(mid 129.410849 -284.398136)
		(end 129.464562 -284.616398)
		(width 0.11684)
		(layer "In4.Cu")
		(net "CPU1_VDDBT_RTC_G")
	)
	(arc
		(start 128.323086 -282.61056)
		(mid 128.471302 -282.778708)
		(end 128.524762 -282.996386)
		(width 0.11684)
		(layer "In4.Cu")
		(net "CPU1_VDDBT_RTC_G")
	)
	(arc
		(start 129.73558 -291.521896)
		(mid 129.882122 -291.689734)
		(end 129.93497 -291.906198)
		(width 0.11684)
		(layer "In4.Cu")
		(net "CPU1_VDDBT_RTC_G")
	)
	(arc
		(start 128.254252 -275.32203)
		(mid 128.10771 -275.489868)
		(end 128.054862 -275.706332)
		(width 0.11684)
		(layer "In4.Cu")
		(net "CPU1_VDDBT_RTC_G")
	)
	(arc
		(start 131.14528 -293.951914)
		(mid 131.291822 -294.119752)
		(end 131.34467 -294.336216)
		(width 0.11684)
		(layer "In4.Cu")
		(net "CPU1_VDDBT_RTC_G")
	)
	(arc
		(start 126.644654 -279.756362)
		(mid 126.69746 -279.972847)
		(end 126.844044 -280.140664)
		(width 0.11684)
		(layer "In4.Cu")
		(net "CPU1_VDDBT_RTC_G")
	)
	(arc
		(start 127.385572 -280.992072)
		(mid 127.532114 -281.15991)
		(end 127.584962 -281.376374)
		(width 0.11684)
		(layer "In4.Cu")
		(net "CPU1_VDDBT_RTC_G")
	)
	(arc
		(start 129.191766 -273.703542)
		(mid 129.046809 -273.87104)
		(end 128.994662 -274.08632)
		(width 0.11684)
		(layer "In4.Cu")
		(net "CPU1_VDDBT_RTC_G")
	)
	(arc
		(start 129.464562 -287.856422)
		(mid 129.526756 -288.088896)
		(end 129.696718 -288.259266)
		(width 0.11684)
		(layer "In4.Cu")
		(net "CPU1_VDDBT_RTC_G")
	)
	(arc
		(start 127.114554 -269.226284)
		(mid 127.16673 -269.441549)
		(end 127.311658 -269.609062)
		(width 0.11684)
		(layer "In4.Cu")
		(net "CPU1_VDDBT_RTC_G")
	)
	(arc
		(start 129.93497 -285.426404)
		(mid 129.988074 -285.643338)
		(end 130.135376 -285.811214)
		(width 0.11684)
		(layer "In4.Cu")
		(net "CPU1_VDDBT_RTC_G")
	)
	(arc
		(start 131.34467 -294.336216)
		(mid 131.28226 -294.569084)
		(end 131.112006 -294.739822)
		(width 0.11684)
		(layer "In4.Cu")
		(net "CPU1_VDDBT_RTC_G")
	)
	(arc
		(start 129.26187 -272.889726)
		(mid 129.410849 -273.058052)
		(end 129.464562 -273.276314)
		(width 0.11684)
		(layer "In4.Cu")
		(net "CPU1_VDDBT_RTC_G")
	)
	(arc
		(start 127.584962 -281.376374)
		(mid 127.638716 -281.594614)
		(end 127.787654 -281.762962)
		(width 0.11684)
		(layer "In4.Cu")
		(net "CPU1_VDDBT_RTC_G")
	)
	(arc
		(start 129.464562 -273.276314)
		(mid 129.402236 -273.509358)
		(end 129.231898 -273.680174)
		(width 0.11684)
		(layer "In4.Cu")
		(net "CPU1_VDDBT_RTC_G")
	)
	(arc
		(start 129.661666 -289.093402)
		(mid 129.516709 -289.2609)
		(end 129.464562 -289.47618)
		(width 0.11684)
		(layer "In4.Cu")
		(net "CPU1_VDDBT_RTC_G")
	)
	(arc
		(start 127.857758 -281.803602)
		(mid 128.002715 -281.9711)
		(end 128.054862 -282.18638)
		(width 0.11684)
		(layer "In4.Cu")
		(net "CPU1_VDDBT_RTC_G")
	)
	(arc
		(start 131.076446 -294.760396)
		(mid 130.92823 -294.928544)
		(end 130.87477 -295.146222)
		(width 0.11684)
		(layer "In4.Cu")
		(net "CPU1_VDDBT_RTC_G")
	)
	(arc
		(start 128.524762 -282.996386)
		(mid 128.578222 -283.214064)
		(end 128.726438 -283.382212)
		(width 0.11684)
		(layer "In4.Cu")
		(net "CPU1_VDDBT_RTC_G")
	)
	(arc
		(start 126.442978 -268.030452)
		(mid 126.591194 -268.1986)
		(end 126.644654 -268.416278)
		(width 0.11684)
		(layer "In4.Cu")
		(net "CPU1_VDDBT_RTC_G")
	)
	(arc
		(start 127.311658 -276.943566)
		(mid 127.166701 -277.111064)
		(end 127.114554 -277.326344)
		(width 0.11684)
		(layer "In4.Cu")
		(net "CPU1_VDDBT_RTC_G")
	)
	(arc
		(start 129.737866 -288.283396)
		(mid 129.882823 -288.450894)
		(end 129.93497 -288.666174)
		(width 0.11684)
		(layer "In4.Cu")
		(net "CPU1_VDDBT_RTC_G")
	)
	(arc
		(start 126.644654 -268.416278)
		(mid 126.706903 -268.649053)
		(end 126.877064 -268.81963)
		(width 0.11684)
		(layer "In4.Cu")
		(net "CPU1_VDDBT_RTC_G")
	)
	(arc
		(start 127.787654 -276.12975)
		(mid 127.638675 -276.298076)
		(end 127.584962 -276.516338)
		(width 0.11684)
		(layer "In4.Cu")
		(net "CPU1_VDDBT_RTC_G")
	)
	(arc
		(start 129.22758 -289.88258)
		(mid 129.057309 -290.053288)
		(end 128.994916 -290.286186)
		(width 0.11684)
		(layer "In4.Cu")
		(net "CPU1_VDDBT_RTC_G")
	)
	(arc
		(start 128.994662 -272.466308)
		(mid 129.046838 -272.681573)
		(end 129.191766 -272.849086)
		(width 0.11684)
		(layer "In4.Cu")
		(net "CPU1_VDDBT_RTC_G")
	)
	(arc
		(start 130.87477 -293.52621)
		(mid 130.92823 -293.743888)
		(end 131.076446 -293.912036)
		(width 0.11684)
		(layer "In4.Cu")
		(net "CPU1_VDDBT_RTC_G")
	)
	(arc
		(start 128.795272 -283.42209)
		(mid 128.941814 -283.589928)
		(end 128.994662 -283.806392)
		(width 0.11684)
		(layer "In4.Cu")
		(net "CPU1_VDDBT_RTC_G")
	)
	(arc
		(start 128.994662 -290.286186)
		(mid 129.047468 -290.502671)
		(end 129.194052 -290.670488)
		(width 0.11684)
		(layer "In4.Cu")
		(net "CPU1_VDDBT_RTC_G")
	)
	(arc
		(start 128.994662 -283.806392)
		(mid 129.046838 -284.021657)
		(end 129.191766 -284.18917)
		(width 0.11684)
		(layer "In4.Cu")
		(net "CPU1_VDDBT_RTC_G")
	)
	(arc
		(start 127.114554 -277.326344)
		(mid 127.06145 -277.543278)
		(end 126.914148 -277.711154)
		(width 0.11684)
		(layer "In4.Cu")
		(net "CPU1_VDDBT_RTC_G")
	)
	(arc
		(start 130.17246 -285.833058)
		(mid 130.342566 -286.003667)
		(end 130.40487 -286.23641)
		(width 0.11684)
		(layer "In4.Cu")
		(net "CPU1_VDDBT_RTC_G")
	)
	(arc
		(start 126.914148 -268.841474)
		(mid 127.061451 -269.00935)
		(end 127.114554 -269.226284)
		(width 0.11684)
		(layer "In4.Cu")
		(net "CPU1_VDDBT_RTC_G")
	)
	(arc
		(start 128.757426 -274.49272)
		(mid 128.587066 -274.663397)
		(end 128.524762 -274.896326)
		(width 0.11684)
		(layer "In4.Cu")
		(net "CPU1_VDDBT_RTC_G")
	)
	(arc
		(start 128.524762 -274.896326)
		(mid 128.471302 -275.114004)
		(end 128.323086 -275.282152)
		(width 0.11684)
		(layer "In4.Cu")
		(net "CPU1_VDDBT_RTC_G")
	)
	(arc
		(start 128.054862 -282.18638)
		(mid 128.107668 -282.402865)
		(end 128.254252 -282.570682)
		(width 0.11684)
		(layer "In4.Cu")
		(net "CPU1_VDDBT_RTC_G")
	)
	(arc
		(start 130.604768 -295.573958)
		(mid 130.459219 -295.741592)
		(end 130.406394 -295.957244)
		(width 0.11684)
		(layer "In4.Cu")
		(net "CPU1_VDDBT_RTC_G")
	)
	(arc
		(start 128.054862 -270.846296)
		(mid 128.107668 -271.062781)
		(end 128.254252 -271.230598)
		(width 0.11684)
		(layer "In4.Cu")
		(net "CPU1_VDDBT_RTC_G")
	)
	(arc
		(start 130.40487 -286.23641)
		(mid 130.352694 -286.451675)
		(end 130.207766 -286.619188)
		(width 0.11684)
		(layer "In4.Cu")
		(net "CPU1_VDDBT_RTC_G")
	)
	(arc
		(start 130.207766 -292.333426)
		(mid 130.352723 -292.500924)
		(end 130.40487 -292.716204)
		(width 0.11684)
		(layer "In4.Cu")
		(net "CPU1_VDDBT_RTC_G")
	)
	(arc
		(start 127.857758 -270.463518)
		(mid 128.002715 -270.631016)
		(end 128.054862 -270.846296)
		(width 0.11684)
		(layer "In4.Cu")
		(net "CPU1_VDDBT_RTC_G")
	)
	(arc
		(start 129.93497 -287.046162)
		(mid 129.882164 -287.262647)
		(end 129.73558 -287.430464)
		(width 0.11684)
		(layer "In4.Cu")
		(net "CPU1_VDDBT_RTC_G")
	)
	(arc
		(start 128.524762 -271.656302)
		(mid 128.578222 -271.87398)
		(end 128.726438 -272.042128)
		(width 0.11684)
		(layer "In4.Cu")
		(net "CPU1_VDDBT_RTC_G")
	)
	(arc
		(start 127.584962 -276.516338)
		(mid 127.532156 -276.732823)
		(end 127.385572 -276.90064)
		(width 0.11684)
		(layer "In4.Cu")
		(net "CPU1_VDDBT_RTC_G")
	)
	(arc
		(start 126.644654 -278.13635)
		(mid 126.591194 -278.354028)
		(end 126.442978 -278.522176)
		(width 0.11684)
		(layer "In4.Cu")
		(net "CPU1_VDDBT_RTC_G")
	)
	(arc
		(start 127.385572 -269.651988)
		(mid 127.532114 -269.819826)
		(end 127.584962 -270.03629)
		(width 0.11684)
		(layer "In4.Cu")
		(net "CPU1_VDDBT_RTC_G")
	)
	(arc
		(start 129.464562 -289.47618)
		(mid 129.411458 -289.693114)
		(end 129.264156 -289.86099)
		(width 0.11684)
		(layer "In4.Cu")
		(net "CPU1_VDDBT_RTC_G")
	)
	(arc
		(start 127.584962 -270.03629)
		(mid 127.638716 -270.25453)
		(end 127.787654 -270.422878)
		(width 0.11684)
		(layer "In4.Cu")
		(net "CPU1_VDDBT_RTC_G")
	)
	(arc
		(start 130.40487 -292.716204)
		(mid 130.457676 -292.932689)
		(end 130.60426 -293.100506)
		(width 0.11684)
		(layer "In4.Cu")
		(net "CPU1_VDDBT_RTC_G")
	)
	(arc
		(start 129.93497 -288.666174)
		(mid 129.882164 -288.882659)
		(end 129.73558 -289.050476)
		(width 0.11684)
		(layer "In4.Cu")
		(net "CPU1_VDDBT_RTC_G")
	)
	(arc
		(start 126.174754 -267.606272)
		(mid 126.22756 -267.822757)
		(end 126.374144 -267.990574)
		(width 0.11684)
		(layer "In4.Cu")
		(net "CPU1_VDDBT_RTC_G")
	)
	(arc
		(start 128.994662 -274.08632)
		(mid 128.941856 -274.302805)
		(end 128.795272 -274.470622)
		(width 0.11684)
		(layer "In4.Cu")
		(net "CPU1_VDDBT_RTC_G")
	)
	(arc
		(start 126.442978 -279.370536)
		(mid 126.591194 -279.538684)
		(end 126.644654 -279.756362)
		(width 0.11684)
		(layer "In4.Cu")
		(net "CPU1_VDDBT_RTC_G")
	)
	(arc
		(start 129.464562 -284.616398)
		(mid 129.517368 -284.832883)
		(end 129.663952 -285.0007)
		(width 0.11684)
		(layer "In4.Cu")
		(net "CPU1_VDDBT_RTC_G")
	)
	(arc
		(start 130.673094 -293.140384)
		(mid 130.82131 -293.308532)
		(end 130.87477 -293.52621)
		(width 0.11684)
		(layer "In4.Cu")
		(net "CPU1_VDDBT_RTC_G")
	)
	(arc
		(start 129.264156 -290.711382)
		(mid 129.411459 -290.879258)
		(end 129.464562 -291.096192)
		(width 0.11684)
		(layer "In4.Cu")
		(net "CPU1_VDDBT_RTC_G")
	)
	(arc
		(start 129.464562 -291.096192)
		(mid 129.516738 -291.311457)
		(end 129.661666 -291.47897)
		(width 0.11684)
		(layer "In4.Cu")
		(net "CPU1_VDDBT_RTC_G")
	)
	(segment
		(start 183.407812 -94.06001)
		(end 183.776874 -93.690948)
		(width 0.10668)
		(layer "F.Cu")
		(net "CPU1_THERMTRIP_R_N")
	)
	(segment
		(start 182.9562 -96.503998)
		(end 183.407812 -96.052386)
		(width 0.10668)
		(layer "F.Cu")
		(net "CPU1_THERMTRIP_R_N")
	)
	(segment
		(start 183.522112 -109.852968)
		(end 183.132222 -109.463078)
		(width 0.10668)
		(layer "F.Cu")
		(net "CPU1_THERMTRIP_R_N")
	)
	(segment
		(start 183.407812 -96.052386)
		(end 183.407812 -94.06001)
		(width 0.10668)
		(layer "F.Cu")
		(net "CPU1_THERMTRIP_R_N")
	)
	(via
		(at 183.776874 -93.690948)
		(size 0.508)
		(drill 0.254)
		(layers "F.Cu" "B.Cu")
		(net "CPU1_THERMTRIP_R_N")
	)
	(via
		(at 183.132222 -109.463078)
		(size 0.4572)
		(drill 0.254)
		(layers "F.Cu" "B.Cu")
		(net "CPU1_THERMTRIP_R_N")
	)
	(segment
		(start 183.491886 -93.975936)
		(end 183.776874 -93.690948)
		(width 0.10668)
		(layer "B.Cu")
		(net "CPU1_THERMTRIP_R_N")
	)
	(segment
		(start 182.737252 -96.712786)
		(end 182.737252 -96.148652)
		(width 0.10668)
		(layer "B.Cu")
		(net "CPU1_THERMTRIP_R_N")
	)
	(segment
		(start 183.491886 -95.394018)
		(end 183.491886 -93.975936)
		(width 0.10668)
		(layer "B.Cu")
		(net "CPU1_THERMTRIP_R_N")
	)
	(segment
		(start 182.737252 -96.148652)
		(end 183.491886 -95.394018)
		(width 0.10668)
		(layer "B.Cu")
		(net "CPU1_THERMTRIP_R_N")
	)
	(segment
		(start 183.279288 -98.048826)
		(end 182.791608 -97.561146)
		(width 0.11684)
		(layer "In4.Cu")
		(net "CPU1_THERMTRIP_R_N")
	)
	(segment
		(start 183.279288 -103.650796)
		(end 183.279288 -98.048826)
		(width 0.11684)
		(layer "In4.Cu")
		(net "CPU1_THERMTRIP_R_N")
	)
	(segment
		(start 182.791608 -97.561146)
		(end 182.791608 -97.22739)
		(width 0.11684)
		(layer "In4.Cu")
		(net "CPU1_THERMTRIP_R_N")
	)
	(segment
		(start 183.132222 -109.229398)
		(end 183.525668 -108.835952)
		(width 0.11684)
		(layer "In4.Cu")
		(net "CPU1_THERMTRIP_R_N")
	)
	(segment
		(start 182.791608 -97.22739)
		(end 183.776874 -96.242124)
		(width 0.11684)
		(layer "In4.Cu")
		(net "CPU1_THERMTRIP_R_N")
	)
	(segment
		(start 183.525668 -108.835952)
		(end 183.525668 -103.897176)
		(width 0.11684)
		(layer "In4.Cu")
		(net "CPU1_THERMTRIP_R_N")
	)
	(segment
		(start 183.132222 -109.463078)
		(end 183.132222 -109.229398)
		(width 0.11684)
		(layer "In4.Cu")
		(net "CPU1_THERMTRIP_R_N")
	)
	(segment
		(start 183.776874 -96.242124)
		(end 183.776874 -93.690948)
		(width 0.11684)
		(layer "In4.Cu")
		(net "CPU1_THERMTRIP_R_N")
	)
	(segment
		(start 183.525668 -103.897176)
		(end 183.279288 -103.650796)
		(width 0.11684)
		(layer "In4.Cu")
		(net "CPU1_THERMTRIP_R_N")
	)
	(segment
		(start 182.9562 -95.703898)
		(end 182.9562 -95.291148)
		(width 0.10668)
		(layer "F.Cu")
		(net "CPU1_THERMTRIP_N")
	)
	(segment
		(start 136.55294 -307.309774)
		(end 140.175488 -310.932322)
		(width 0.10668)
		(layer "F.Cu")
		(net "CPU1_THERMTRIP_N")
	)
	(segment
		(start 225.54311 -167.333422)
		(end 224.467674 -166.257986)
		(width 0.10668)
		(layer "F.Cu")
		(net "CPU1_THERMTRIP_N")
	)
	(segment
		(start 182.9562 -95.291148)
		(end 182.753 -95.087948)
		(width 0.10668)
		(layer "F.Cu")
		(net "CPU1_THERMTRIP_N")
	)
	(segment
		(start 225.54311 -200.857358)
		(end 225.54311 -167.333422)
		(width 0.10668)
		(layer "F.Cu")
		(net "CPU1_THERMTRIP_N")
	)
	(segment
		(start 143.327882 -311.946544)
		(end 143.327882 -312.722768)
		(width 0.10668)
		(layer "F.Cu")
		(net "CPU1_THERMTRIP_N")
	)
	(segment
		(start 136.55294 -298.284646)
		(end 136.55294 -307.309774)
		(width 0.10668)
		(layer "F.Cu")
		(net "CPU1_THERMTRIP_N")
	)
	(segment
		(start 142.31366 -310.932322)
		(end 143.327882 -311.946544)
		(width 0.10668)
		(layer "F.Cu")
		(net "CPU1_THERMTRIP_N")
	)
	(segment
		(start 224.467674 -166.257986)
		(end 224.467674 -165.52926)
		(width 0.10668)
		(layer "F.Cu")
		(net "CPU1_THERMTRIP_N")
	)
	(segment
		(start 138.867896 -295.96969)
		(end 136.55294 -298.284646)
		(width 0.10668)
		(layer "F.Cu")
		(net "CPU1_THERMTRIP_N")
	)
	(segment
		(start 224.64014 -201.760328)
		(end 225.54311 -200.857358)
		(width 0.10668)
		(layer "F.Cu")
		(net "CPU1_THERMTRIP_N")
	)
	(segment
		(start 138.867896 -295.69029)
		(end 138.867896 -295.96969)
		(width 0.10668)
		(layer "F.Cu")
		(net "CPU1_THERMTRIP_N")
	)
	(segment
		(start 140.175488 -310.932322)
		(end 142.31366 -310.932322)
		(width 0.10668)
		(layer "F.Cu")
		(net "CPU1_THERMTRIP_N")
	)
	(via
		(at 182.753 -95.087948)
		(size 0.508)
		(drill 0.254)
		(layers "F.Cu" "B.Cu")
		(net "CPU1_THERMTRIP_N")
	)
	(via
		(at 213.450678 -97.234502)
		(size 0.508)
		(drill 0.254)
		(layers "F.Cu" "B.Cu")
		(net "CPU1_THERMTRIP_N")
	)
	(via
		(at 224.467674 -165.52926)
		(size 0.508)
		(drill 0.254)
		(layers "F.Cu" "B.Cu")
		(net "CPU1_THERMTRIP_N")
	)
	(via
		(at 224.64014 -201.760328)
		(size 0.508)
		(drill 0.254)
		(layers "F.Cu" "B.Cu")
		(net "CPU1_THERMTRIP_N")
	)
	(via
		(at 143.327882 -312.722768)
		(size 0.508)
		(drill 0.254)
		(layers "F.Cu" "B.Cu")
		(net "CPU1_THERMTRIP_N")
	)
	(segment
		(start 144.522444 -313.45505)
		(end 143.790162 -312.722768)
		(width 0.10668)
		(layer "B.Cu")
		(net "CPU1_THERMTRIP_N")
	)
	(segment
		(start 143.790162 -312.722768)
		(end 143.327882 -312.722768)
		(width 0.10668)
		(layer "B.Cu")
		(net "CPU1_THERMTRIP_N")
	)
	(segment
		(start 187.009786 -94.155768)
		(end 183.68518 -94.155768)
		(width 0.11684)
		(layer "In2.Cu")
		(net "CPU1_THERMTRIP_N")
	)
	(segment
		(start 195.428108 -93.950028)
		(end 194.112896 -93.950028)
		(width 0.11684)
		(layer "In2.Cu")
		(net "CPU1_THERMTRIP_N")
	)
	(segment
		(start 187.28182 -93.584522)
		(end 187.28182 -93.883734)
		(width 0.11684)
		(layer "In2.Cu")
		(net "CPU1_THERMTRIP_N")
	)
	(segment
		(start 187.640214 -93.226128)
		(end 187.28182 -93.584522)
		(width 0.11684)
		(layer "In2.Cu")
		(net "CPU1_THERMTRIP_N")
	)
	(segment
		(start 203.138786 -93.746574)
		(end 200.738994 -93.746574)
		(width 0.11684)
		(layer "In2.Cu")
		(net "CPU1_THERMTRIP_N")
	)
	(segment
		(start 200.738994 -93.746574)
		(end 199.314308 -95.17126)
		(width 0.11684)
		(layer "In2.Cu")
		(net "CPU1_THERMTRIP_N")
	)
	(segment
		(start 199.314308 -95.17126)
		(end 196.64934 -95.17126)
		(width 0.11684)
		(layer "In2.Cu")
		(net "CPU1_THERMTRIP_N")
	)
	(segment
		(start 183.68518 -94.155768)
		(end 182.753 -95.087948)
		(width 0.11684)
		(layer "In2.Cu")
		(net "CPU1_THERMTRIP_N")
	)
	(segment
		(start 212.256624 -96.040448)
		(end 210.934046 -96.040448)
		(width 0.11684)
		(layer "In2.Cu")
		(net "CPU1_THERMTRIP_N")
	)
	(segment
		(start 203.634848 -94.242636)
		(end 203.138786 -93.746574)
		(width 0.11684)
		(layer "In2.Cu")
		(net "CPU1_THERMTRIP_N")
	)
	(segment
		(start 193.388996 -93.226128)
		(end 187.640214 -93.226128)
		(width 0.11684)
		(layer "In2.Cu")
		(net "CPU1_THERMTRIP_N")
	)
	(segment
		(start 210.934046 -96.040448)
		(end 209.136234 -94.242636)
		(width 0.11684)
		(layer "In2.Cu")
		(net "CPU1_THERMTRIP_N")
	)
	(segment
		(start 196.64934 -95.17126)
		(end 195.428108 -93.950028)
		(width 0.11684)
		(layer "In2.Cu")
		(net "CPU1_THERMTRIP_N")
	)
	(segment
		(start 213.450678 -97.234502)
		(end 212.256624 -96.040448)
		(width 0.11684)
		(layer "In2.Cu")
		(net "CPU1_THERMTRIP_N")
	)
	(segment
		(start 194.112896 -93.950028)
		(end 193.388996 -93.226128)
		(width 0.11684)
		(layer "In2.Cu")
		(net "CPU1_THERMTRIP_N")
	)
	(segment
		(start 187.28182 -93.883734)
		(end 187.009786 -94.155768)
		(width 0.11684)
		(layer "In2.Cu")
		(net "CPU1_THERMTRIP_N")
	)
	(segment
		(start 209.136234 -94.242636)
		(end 203.634848 -94.242636)
		(width 0.11684)
		(layer "In2.Cu")
		(net "CPU1_THERMTRIP_N")
	)
	(segment
		(start 220.973904 -202.898248)
		(end 222.111824 -201.760328)
		(width 0.11684)
		(layer "In4.Cu")
		(net "CPU1_THERMTRIP_N")
	)
	(segment
		(start 205.827376 -321.815714)
		(end 212.620098 -315.022992)
		(width 0.11684)
		(layer "In4.Cu")
		(net "CPU1_THERMTRIP_N")
	)
	(segment
		(start 151.664162 -324.257162)
		(end 152.950672 -324.257162)
		(width 0.11684)
		(layer "In4.Cu")
		(net "CPU1_THERMTRIP_N")
	)
	(segment
		(start 161.318702 -321.815714)
		(end 205.827376 -321.815714)
		(width 0.11684)
		(layer "In4.Cu")
		(net "CPU1_THERMTRIP_N")
	)
	(segment
		(start 146.37004 -316.8269)
		(end 146.37004 -318.65951)
		(width 0.11684)
		(layer "In4.Cu")
		(net "CPU1_THERMTRIP_N")
	)
	(segment
		(start 149.1615 -319.794636)
		(end 150.387558 -321.020694)
		(width 0.11684)
		(layer "In4.Cu")
		(net "CPU1_THERMTRIP_N")
	)
	(segment
		(start 220.12656 -204.146912)
		(end 220.973904 -203.299568)
		(width 0.11684)
		(layer "In4.Cu")
		(net "CPU1_THERMTRIP_N")
	)
	(segment
		(start 222.111824 -201.760328)
		(end 224.64014 -201.760328)
		(width 0.11684)
		(layer "In4.Cu")
		(net "CPU1_THERMTRIP_N")
	)
	(segment
		(start 215.812116 -97.234502)
		(end 223.083374 -104.50576)
		(width 0.11684)
		(layer "In4.Cu")
		(net "CPU1_THERMTRIP_N")
	)
	(segment
		(start 144.522444 -314.979304)
		(end 146.37004 -316.8269)
		(width 0.11684)
		(layer "In4.Cu")
		(net "CPU1_THERMTRIP_N")
	)
	(segment
		(start 143.327882 -312.722768)
		(end 143.790162 -312.722768)
		(width 0.11684)
		(layer "In4.Cu")
		(net "CPU1_THERMTRIP_N")
	)
	(segment
		(start 212.620098 -315.022992)
		(end 212.620098 -211.252054)
		(width 0.11684)
		(layer "In4.Cu")
		(net "CPU1_THERMTRIP_N")
	)
	(segment
		(start 220.973904 -203.299568)
		(end 220.973904 -202.898248)
		(width 0.11684)
		(layer "In4.Cu")
		(net "CPU1_THERMTRIP_N")
	)
	(segment
		(start 147.505166 -319.794636)
		(end 149.1615 -319.794636)
		(width 0.11684)
		(layer "In4.Cu")
		(net "CPU1_THERMTRIP_N")
	)
	(segment
		(start 159.809688 -323.324728)
		(end 161.318702 -321.815714)
		(width 0.11684)
		(layer "In4.Cu")
		(net "CPU1_THERMTRIP_N")
	)
	(segment
		(start 223.083374 -104.50576)
		(end 223.083374 -164.14496)
		(width 0.11684)
		(layer "In4.Cu")
		(net "CPU1_THERMTRIP_N")
	)
	(segment
		(start 146.37004 -318.65951)
		(end 147.505166 -319.794636)
		(width 0.11684)
		(layer "In4.Cu")
		(net "CPU1_THERMTRIP_N")
	)
	(segment
		(start 150.387558 -322.980558)
		(end 151.664162 -324.257162)
		(width 0.11684)
		(layer "In4.Cu")
		(net "CPU1_THERMTRIP_N")
	)
	(segment
		(start 212.620098 -211.252054)
		(end 219.72524 -204.146912)
		(width 0.11684)
		(layer "In4.Cu")
		(net "CPU1_THERMTRIP_N")
	)
	(segment
		(start 219.72524 -204.146912)
		(end 220.12656 -204.146912)
		(width 0.11684)
		(layer "In4.Cu")
		(net "CPU1_THERMTRIP_N")
	)
	(segment
		(start 153.883106 -323.324728)
		(end 159.809688 -323.324728)
		(width 0.11684)
		(layer "In4.Cu")
		(net "CPU1_THERMTRIP_N")
	)
	(segment
		(start 213.450678 -97.234502)
		(end 215.812116 -97.234502)
		(width 0.11684)
		(layer "In4.Cu")
		(net "CPU1_THERMTRIP_N")
	)
	(segment
		(start 223.083374 -164.14496)
		(end 224.467674 -165.52926)
		(width 0.11684)
		(layer "In4.Cu")
		(net "CPU1_THERMTRIP_N")
	)
	(segment
		(start 152.950672 -324.257162)
		(end 153.883106 -323.324728)
		(width 0.11684)
		(layer "In4.Cu")
		(net "CPU1_THERMTRIP_N")
	)
	(segment
		(start 144.522444 -313.45505)
		(end 144.522444 -314.979304)
		(width 0.11684)
		(layer "In4.Cu")
		(net "CPU1_THERMTRIP_N")
	)
	(segment
		(start 143.790162 -312.722768)
		(end 144.522444 -313.45505)
		(width 0.11684)
		(layer "In4.Cu")
		(net "CPU1_THERMTRIP_N")
	)
	(segment
		(start 150.387558 -321.020694)
		(end 150.387558 -322.980558)
		(width 0.11684)
		(layer "In4.Cu")
		(net "CPU1_THERMTRIP_N")
	)
	(segment
		(start 113.487962 -292.450266)
		(end 112.99952 -292.450266)
		(width 0.10668)
		(layer "F.Cu")
		(net "CPU1_SPD_HOST_CTRL_R_N")
	)
	(segment
		(start 132.425694 -321.458844)
		(end 140.993114 -321.458844)
		(width 0.10668)
		(layer "F.Cu")
		(net "CPU1_SPD_HOST_CTRL_R_N")
	)
	(segment
		(start 111.932212 -300.965362)
		(end 132.425694 -321.458844)
		(width 0.10668)
		(layer "F.Cu")
		(net "CPU1_SPD_HOST_CTRL_R_N")
	)
	(segment
		(start 112.590834 -297.253152)
		(end 111.932212 -297.911774)
		(width 0.10668)
		(layer "F.Cu")
		(net "CPU1_SPD_HOST_CTRL_R_N")
	)
	(segment
		(start 112.590834 -292.858952)
		(end 112.590834 -297.253152)
		(width 0.10668)
		(layer "F.Cu")
		(net "CPU1_SPD_HOST_CTRL_R_N")
	)
	(segment
		(start 141.55801 -321.458844)
		(end 141.722348 -321.294506)
		(width 0.10668)
		(layer "F.Cu")
		(net "CPU1_SPD_HOST_CTRL_R_N")
	)
	(segment
		(start 141.722348 -321.294506)
		(end 143.385286 -321.294506)
		(width 0.10668)
		(layer "F.Cu")
		(net "CPU1_SPD_HOST_CTRL_R_N")
	)
	(segment
		(start 112.99952 -292.450266)
		(end 112.590834 -292.858952)
		(width 0.10668)
		(layer "F.Cu")
		(net "CPU1_SPD_HOST_CTRL_R_N")
	)
	(segment
		(start 111.932212 -297.911774)
		(end 111.932212 -300.965362)
		(width 0.10668)
		(layer "F.Cu")
		(net "CPU1_SPD_HOST_CTRL_R_N")
	)
	(segment
		(start 140.993114 -321.458844)
		(end 141.55801 -321.458844)
		(width 0.10668)
		(layer "F.Cu")
		(net "CPU1_SPD_HOST_CTRL_R_N")
	)
	(via
		(at 140.993114 -321.458844)
		(size 0.762)
		(drill 0.381)
		(layers "F.Cu" "B.Cu")
		(net "CPU1_SPD_HOST_CTRL_R_N")
	)
	(segment
		(start 185.122058 -118.652798)
		(end 184.732168 -119.042688)
		(width 0.10668)
		(layer "F.Cu")
		(net "CPU1_SPD_HOST_CTRL_R1_N")
	)
	(via
		(at 187.75299 -132.434076)
		(size 0.508)
		(drill 0.254)
		(layers "F.Cu" "B.Cu")
		(net "CPU1_SPD_HOST_CTRL_R1_N")
	)
	(via
		(at 184.732168 -119.042688)
		(size 0.4572)
		(drill 0.254)
		(layers "F.Cu" "B.Cu")
		(net "CPU1_SPD_HOST_CTRL_R1_N")
	)
	(segment
		(start 188.710824 -136.258046)
		(end 188.23051 -135.777732)
		(width 0.10668)
		(layer "B.Cu")
		(net "CPU1_SPD_HOST_CTRL_R1_N")
	)
	(segment
		(start 188.23051 -132.91185)
		(end 187.75299 -132.43433)
		(width 0.10668)
		(layer "B.Cu")
		(net "CPU1_SPD_HOST_CTRL_R1_N")
	)
	(segment
		(start 187.75299 -132.43433)
		(end 187.75299 -132.434076)
		(width 0.10668)
		(layer "B.Cu")
		(net "CPU1_SPD_HOST_CTRL_R1_N")
	)
	(segment
		(start 188.23051 -135.777732)
		(end 188.23051 -132.91185)
		(width 0.10668)
		(layer "B.Cu")
		(net "CPU1_SPD_HOST_CTRL_R1_N")
	)
	(segment
		(start 185.527188 -119.837708)
		(end 184.732168 -119.042688)
		(width 0.11684)
		(layer "In2.Cu")
		(net "CPU1_SPD_HOST_CTRL_R1_N")
	)
	(segment
		(start 187.75299 -132.434076)
		(end 187.752736 -132.43433)
		(width 0.11684)
		(layer "In2.Cu")
		(net "CPU1_SPD_HOST_CTRL_R1_N")
	)
	(segment
		(start 186.877452 -132.43433)
		(end 186.378596 -131.935474)
		(width 0.11684)
		(layer "In2.Cu")
		(net "CPU1_SPD_HOST_CTRL_R1_N")
	)
	(segment
		(start 186.6265 -127.4699)
		(end 185.241438 -126.084838)
		(width 0.11684)
		(layer "In2.Cu")
		(net "CPU1_SPD_HOST_CTRL_R1_N")
	)
	(segment
		(start 186.378596 -131.935474)
		(end 186.378596 -131.342384)
		(width 0.11684)
		(layer "In2.Cu")
		(net "CPU1_SPD_HOST_CTRL_R1_N")
	)
	(segment
		(start 185.241438 -126.084838)
		(end 185.241438 -124.563378)
		(width 0.11684)
		(layer "In2.Cu")
		(net "CPU1_SPD_HOST_CTRL_R1_N")
	)
	(segment
		(start 187.752736 -132.43433)
		(end 186.877452 -132.43433)
		(width 0.11684)
		(layer "In2.Cu")
		(net "CPU1_SPD_HOST_CTRL_R1_N")
	)
	(segment
		(start 186.6265 -131.09448)
		(end 186.6265 -127.4699)
		(width 0.11684)
		(layer "In2.Cu")
		(net "CPU1_SPD_HOST_CTRL_R1_N")
	)
	(segment
		(start 185.241438 -124.563378)
		(end 185.527188 -123.873514)
		(width 0.11684)
		(layer "In2.Cu")
		(net "CPU1_SPD_HOST_CTRL_R1_N")
	)
	(segment
		(start 185.527188 -123.873514)
		(end 185.527188 -119.837708)
		(width 0.11684)
		(layer "In2.Cu")
		(net "CPU1_SPD_HOST_CTRL_R1_N")
	)
	(segment
		(start 186.378596 -131.342384)
		(end 186.6265 -131.09448)
		(width 0.11684)
		(layer "In2.Cu")
		(net "CPU1_SPD_HOST_CTRL_R1_N")
	)
	(segment
		(start 171.055284 -364.36935)
		(end 171.519088 -364.36935)
		(width 0.10668)
		(layer "F.Cu")
		(net "CPU1_SPD_HOST_CTRL_N")
	)
	(segment
		(start 212.132926 -196.523864)
		(end 209.511392 -199.145398)
		(width 0.10668)
		(layer "F.Cu")
		(net "CPU1_SPD_HOST_CTRL_N")
	)
	(segment
		(start 190.97879 -169.347896)
		(end 191.403478 -168.923208)
		(width 0.10668)
		(layer "F.Cu")
		(net "CPU1_SPD_HOST_CTRL_N")
	)
	(segment
		(start 192.170812 -168.923208)
		(end 193.825114 -170.57751)
		(width 0.10668)
		(layer "F.Cu")
		(net "CPU1_SPD_HOST_CTRL_N")
	)
	(segment
		(start 159.786574 -358.11841)
		(end 164.804344 -358.11841)
		(width 0.10668)
		(layer "F.Cu")
		(net "CPU1_SPD_HOST_CTRL_N")
	)
	(segment
		(start 191.403478 -168.923208)
		(end 192.170812 -168.923208)
		(width 0.10668)
		(layer "F.Cu")
		(net "CPU1_SPD_HOST_CTRL_N")
	)
	(segment
		(start 144.386554 -322.095622)
		(end 144.386554 -328.651108)
		(width 0.10668)
		(layer "F.Cu")
		(net "CPU1_SPD_HOST_CTRL_N")
	)
	(segment
		(start 209.511392 -199.475852)
		(end 209.384392 -199.602852)
		(width 0.10668)
		(layer "F.Cu")
		(net "CPU1_SPD_HOST_CTRL_N")
	)
	(segment
		(start 212.132926 -188.983112)
		(end 212.132926 -196.523864)
		(width 0.10668)
		(layer "F.Cu")
		(net "CPU1_SPD_HOST_CTRL_N")
	)
	(segment
		(start 153.030936 -337.29549)
		(end 153.030936 -351.362772)
		(width 0.10668)
		(layer "F.Cu")
		(net "CPU1_SPD_HOST_CTRL_N")
	)
	(segment
		(start 143.385286 -322.094606)
		(end 144.385538 -322.094606)
		(width 0.10668)
		(layer "F.Cu")
		(net "CPU1_SPD_HOST_CTRL_N")
	)
	(segment
		(start 209.904076 -183.602376)
		(end 212.132926 -188.983112)
		(width 0.10668)
		(layer "F.Cu")
		(net "CPU1_SPD_HOST_CTRL_N")
	)
	(segment
		(start 196.87921 -170.57751)
		(end 209.904076 -183.602376)
		(width 0.10668)
		(layer "F.Cu")
		(net "CPU1_SPD_HOST_CTRL_N")
	)
	(segment
		(start 153.030936 -351.362772)
		(end 159.786574 -358.11841)
		(width 0.10668)
		(layer "F.Cu")
		(net "CPU1_SPD_HOST_CTRL_N")
	)
	(segment
		(start 144.386554 -328.651108)
		(end 153.030936 -337.29549)
		(width 0.10668)
		(layer "F.Cu")
		(net "CPU1_SPD_HOST_CTRL_N")
	)
	(segment
		(start 193.825114 -170.57751)
		(end 196.87921 -170.57751)
		(width 0.10668)
		(layer "F.Cu")
		(net "CPU1_SPD_HOST_CTRL_N")
	)
	(segment
		(start 209.384392 -199.602852)
		(end 208.98866 -199.602852)
		(width 0.10668)
		(layer "F.Cu")
		(net "CPU1_SPD_HOST_CTRL_N")
	)
	(segment
		(start 164.804344 -358.11841)
		(end 171.055284 -364.36935)
		(width 0.10668)
		(layer "F.Cu")
		(net "CPU1_SPD_HOST_CTRL_N")
	)
	(segment
		(start 209.511392 -199.145398)
		(end 209.511392 -199.475852)
		(width 0.10668)
		(layer "F.Cu")
		(net "CPU1_SPD_HOST_CTRL_N")
	)
	(segment
		(start 144.385538 -322.094606)
		(end 144.386554 -322.095622)
		(width 0.10668)
		(layer "F.Cu")
		(net "CPU1_SPD_HOST_CTRL_N")
	)
	(via
		(at 190.951104 -143.374872)
		(size 0.6604)
		(drill 0.3302)
		(layers "F.Cu" "B.Cu")
		(net "CPU1_SPD_HOST_CTRL_N")
	)
	(via
		(at 171.519088 -364.36935)
		(size 0.508)
		(drill 0.254)
		(layers "F.Cu" "B.Cu")
		(net "CPU1_SPD_HOST_CTRL_N")
	)
	(via
		(at 190.97879 -169.347896)
		(size 0.508)
		(drill 0.254)
		(layers "F.Cu" "B.Cu")
		(net "CPU1_SPD_HOST_CTRL_N")
	)
	(via
		(at 208.98866 -199.602852)
		(size 0.508)
		(drill 0.254)
		(layers "F.Cu" "B.Cu")
		(net "CPU1_SPD_HOST_CTRL_N")
	)
	(segment
		(start 186.563 -140.97)
		(end 186.804046 -141.211046)
		(width 0.10668)
		(layer "B.Cu")
		(net "CPU1_SPD_HOST_CTRL_N")
	)
	(segment
		(start 191.389 -143.812768)
		(end 190.951104 -143.374872)
		(width 0.10668)
		(layer "B.Cu")
		(net "CPU1_SPD_HOST_CTRL_N")
	)
	(segment
		(start 190.97879 -169.347896)
		(end 189.596522 -167.965628)
		(width 0.10668)
		(layer "B.Cu")
		(net "CPU1_SPD_HOST_CTRL_N")
	)
	(segment
		(start 186.184794 -150.87346)
		(end 191.389 -145.669254)
		(width 0.10668)
		(layer "B.Cu")
		(net "CPU1_SPD_HOST_CTRL_N")
	)
	(segment
		(start 187.57646 -139.563856)
		(end 186.563 -140.577316)
		(width 0.10668)
		(layer "B.Cu")
		(net "CPU1_SPD_HOST_CTRL_N")
	)
	(segment
		(start 187.57646 -138.19251)
		(end 187.57646 -139.563856)
		(width 0.10668)
		(layer "B.Cu")
		(net "CPU1_SPD_HOST_CTRL_N")
	)
	(segment
		(start 185.356246 -162.108642)
		(end 185.356246 -153.650696)
		(width 0.10668)
		(layer "B.Cu")
		(net "CPU1_SPD_HOST_CTRL_N")
	)
	(segment
		(start 188.710824 -137.058146)
		(end 187.57646 -138.19251)
		(width 0.10668)
		(layer "B.Cu")
		(net "CPU1_SPD_HOST_CTRL_N")
	)
	(segment
		(start 186.804046 -141.211046)
		(end 188.787278 -141.211046)
		(width 0.10668)
		(layer "B.Cu")
		(net "CPU1_SPD_HOST_CTRL_N")
	)
	(segment
		(start 189.596522 -167.965628)
		(end 189.596522 -166.348918)
		(width 0.10668)
		(layer "B.Cu")
		(net "CPU1_SPD_HOST_CTRL_N")
	)
	(segment
		(start 186.184794 -152.822148)
		(end 186.184794 -150.87346)
		(width 0.10668)
		(layer "B.Cu")
		(net "CPU1_SPD_HOST_CTRL_N")
	)
	(segment
		(start 188.787278 -141.211046)
		(end 190.951104 -143.374872)
		(width 0.10668)
		(layer "B.Cu")
		(net "CPU1_SPD_HOST_CTRL_N")
	)
	(segment
		(start 186.563 -140.577316)
		(end 186.563 -140.97)
		(width 0.10668)
		(layer "B.Cu")
		(net "CPU1_SPD_HOST_CTRL_N")
	)
	(segment
		(start 185.356246 -153.650696)
		(end 186.184794 -152.822148)
		(width 0.10668)
		(layer "B.Cu")
		(net "CPU1_SPD_HOST_CTRL_N")
	)
	(segment
		(start 191.389 -145.669254)
		(end 191.389 -143.812768)
		(width 0.10668)
		(layer "B.Cu")
		(net "CPU1_SPD_HOST_CTRL_N")
	)
	(segment
		(start 189.596522 -166.348918)
		(end 185.356246 -162.108642)
		(width 0.10668)
		(layer "B.Cu")
		(net "CPU1_SPD_HOST_CTRL_N")
	)
	(segment
		(start 213.565994 -321.540886)
		(end 214.246714 -322.221606)
		(width 0.11684)
		(layer "In6.Cu")
		(net "CPU1_SPD_HOST_CTRL_N")
	)
	(segment
		(start 224.48774 -332.502256)
		(end 224.48774 -358.484932)
		(width 0.11684)
		(layer "In6.Cu")
		(net "CPU1_SPD_HOST_CTRL_N")
	)
	(segment
		(start 171.968922 -364.819184)
		(end 171.519088 -364.36935)
		(width 0.11684)
		(layer "In6.Cu")
		(net "CPU1_SPD_HOST_CTRL_N")
	)
	(segment
		(start 224.48774 -358.484932)
		(end 222.132906 -360.839766)
		(width 0.11684)
		(layer "In6.Cu")
		(net "CPU1_SPD_HOST_CTRL_N")
	)
	(segment
		(start 214.714328 -322.221606)
		(end 214.875364 -322.06057)
		(width 0.11684)
		(layer "In6.Cu")
		(net "CPU1_SPD_HOST_CTRL_N")
	)
	(segment
		(start 208.98866 -199.602852)
		(end 209.42808 -199.602852)
		(width 0.11684)
		(layer "In6.Cu")
		(net "CPU1_SPD_HOST_CTRL_N")
	)
	(segment
		(start 176.077118 -364.819184)
		(end 171.968922 -364.819184)
		(width 0.11684)
		(layer "In6.Cu")
		(net "CPU1_SPD_HOST_CTRL_N")
	)
	(segment
		(start 222.132906 -363.82833)
		(end 220.785436 -365.1758)
		(width 0.11684)
		(layer "In6.Cu")
		(net "CPU1_SPD_HOST_CTRL_N")
	)
	(segment
		(start 209.42808 -199.602852)
		(end 213.565994 -203.740766)
		(width 0.11684)
		(layer "In6.Cu")
		(net "CPU1_SPD_HOST_CTRL_N")
	)
	(segment
		(start 223.98736 -330.786994)
		(end 223.98736 -332.001876)
		(width 0.11684)
		(layer "In6.Cu")
		(net "CPU1_SPD_HOST_CTRL_N")
	)
	(segment
		(start 220.785436 -367.374424)
		(end 219.077794 -369.082066)
		(width 0.11684)
		(layer "In6.Cu")
		(net "CPU1_SPD_HOST_CTRL_N")
	)
	(segment
		(start 180.34 -369.082066)
		(end 176.077118 -364.819184)
		(width 0.11684)
		(layer "In6.Cu")
		(net "CPU1_SPD_HOST_CTRL_N")
	)
	(segment
		(start 220.785436 -365.1758)
		(end 220.785436 -367.374424)
		(width 0.11684)
		(layer "In6.Cu")
		(net "CPU1_SPD_HOST_CTRL_N")
	)
	(segment
		(start 222.132906 -360.839766)
		(end 222.132906 -363.82833)
		(width 0.11684)
		(layer "In6.Cu")
		(net "CPU1_SPD_HOST_CTRL_N")
	)
	(segment
		(start 213.565994 -203.740766)
		(end 213.565994 -321.540886)
		(width 0.11684)
		(layer "In6.Cu")
		(net "CPU1_SPD_HOST_CTRL_N")
	)
	(segment
		(start 214.875364 -322.06057)
		(end 215.260936 -322.06057)
		(width 0.11684)
		(layer "In6.Cu")
		(net "CPU1_SPD_HOST_CTRL_N")
	)
	(segment
		(start 214.246714 -322.221606)
		(end 214.714328 -322.221606)
		(width 0.11684)
		(layer "In6.Cu")
		(net "CPU1_SPD_HOST_CTRL_N")
	)
	(segment
		(start 223.98736 -332.001876)
		(end 224.48774 -332.502256)
		(width 0.11684)
		(layer "In6.Cu")
		(net "CPU1_SPD_HOST_CTRL_N")
	)
	(segment
		(start 219.077794 -369.082066)
		(end 180.34 -369.082066)
		(width 0.11684)
		(layer "In6.Cu")
		(net "CPU1_SPD_HOST_CTRL_N")
	)
	(segment
		(start 215.260936 -322.06057)
		(end 223.98736 -330.786994)
		(width 0.11684)
		(layer "In6.Cu")
		(net "CPU1_SPD_HOST_CTRL_N")
	)
	(segment
		(start 25.13584 -144.97304)
		(end 17.205706 -152.903174)
		(width 0.10668)
		(layer "F.Cu")
		(net "CPU1_SP5R4")
	)
	(segment
		(start 87.876126 -123.558808)
		(end 87.876126 -126.30277)
		(width 0.10668)
		(layer "F.Cu")
		(net "CPU1_SP5R4")
	)
	(segment
		(start 87.876126 -126.30277)
		(end 77.62748 -136.551416)
		(width 0.10668)
		(layer "F.Cu")
		(net "CPU1_SP5R4")
	)
	(segment
		(start 157.362398 -135.49376)
		(end 156.59862 -134.729982)
		(width 0.10668)
		(layer "F.Cu")
		(net "CPU1_SP5R4")
	)
	(segment
		(start 143.650716 -134.729982)
		(end 135.452612 -126.531878)
		(width 0.10668)
		(layer "F.Cu")
		(net "CPU1_SP5R4")
	)
	(segment
		(start 17.205706 -152.903174)
		(end 17.205706 -173.249082)
		(width 0.10668)
		(layer "F.Cu")
		(net "CPU1_SP5R4")
	)
	(segment
		(start 12.777724 -327.678796)
		(end 13.438632 -328.339704)
		(width 0.10668)
		(layer "F.Cu")
		(net "CPU1_SP5R4")
	)
	(segment
		(start 156.59862 -134.729982)
		(end 143.650716 -134.729982)
		(width 0.10668)
		(layer "F.Cu")
		(net "CPU1_SP5R4")
	)
	(segment
		(start 7.149592 -202.224132)
		(end 12.777724 -207.852264)
		(width 0.10668)
		(layer "F.Cu")
		(net "CPU1_SP5R4")
	)
	(segment
		(start 13.438632 -328.339704)
		(end 13.995146 -328.339704)
		(width 0.10668)
		(layer "F.Cu")
		(net "CPU1_SP5R4")
	)
	(segment
		(start 43.875198 -136.551416)
		(end 35.453574 -144.97304)
		(width 0.10668)
		(layer "F.Cu")
		(net "CPU1_SP5R4")
	)
	(segment
		(start 12.777724 -207.852264)
		(end 12.777724 -327.678796)
		(width 0.10668)
		(layer "F.Cu")
		(net "CPU1_SP5R4")
	)
	(segment
		(start 138.397996 -294.880284)
		(end 138.864848 -295.146222)
		(width 0.10668)
		(layer "F.Cu")
		(net "CPU1_SP5R4")
	)
	(segment
		(start 162.498278 -135.49376)
		(end 157.362398 -135.49376)
		(width 0.10668)
		(layer "F.Cu")
		(net "CPU1_SP5R4")
	)
	(segment
		(start 131.830826 -126.531878)
		(end 117.846094 -112.547146)
		(width 0.10668)
		(layer "F.Cu")
		(net "CPU1_SP5R4")
	)
	(segment
		(start 17.205706 -173.249082)
		(end 7.149592 -183.305196)
		(width 0.10668)
		(layer "F.Cu")
		(net "CPU1_SP5R4")
	)
	(segment
		(start 77.62748 -136.551416)
		(end 43.875198 -136.551416)
		(width 0.10668)
		(layer "F.Cu")
		(net "CPU1_SP5R4")
	)
	(segment
		(start 35.453574 -144.97304)
		(end 25.13584 -144.97304)
		(width 0.10668)
		(layer "F.Cu")
		(net "CPU1_SP5R4")
	)
	(segment
		(start 98.887788 -112.547146)
		(end 87.876126 -123.558808)
		(width 0.10668)
		(layer "F.Cu")
		(net "CPU1_SP5R4")
	)
	(segment
		(start 117.846094 -112.547146)
		(end 98.887788 -112.547146)
		(width 0.10668)
		(layer "F.Cu")
		(net "CPU1_SP5R4")
	)
	(segment
		(start 135.452612 -126.531878)
		(end 131.830826 -126.531878)
		(width 0.10668)
		(layer "F.Cu")
		(net "CPU1_SP5R4")
	)
	(segment
		(start 7.149592 -183.305196)
		(end 7.149592 -202.224132)
		(width 0.10668)
		(layer "F.Cu")
		(net "CPU1_SP5R4")
	)
	(via
		(at 108.61421 -325.225918)
		(size 0.508)
		(drill 0.254)
		(layers "F.Cu" "B.Cu")
		(net "CPU1_SP5R4")
	)
	(via
		(at 155.079954 -320.798952)
		(size 0.508)
		(drill 0.254)
		(layers "F.Cu" "B.Cu")
		(net "CPU1_SP5R4")
	)
	(via
		(at 13.995146 -328.339704)
		(size 0.508)
		(drill 0.254)
		(layers "F.Cu" "B.Cu")
		(net "CPU1_SP5R4")
	)
	(via
		(at 157.6832 -120.5738)
		(size 0.508)
		(drill 0.254)
		(layers "F.Cu" "B.Cu")
		(net "CPU1_SP5R4")
	)
	(via
		(at 162.498278 -135.49376)
		(size 0.508)
		(drill 0.254)
		(layers "F.Cu" "B.Cu")
		(net "CPU1_SP5R4")
	)
	(via
		(at 138.864848 -295.146222)
		(size 0.4064)
		(drill 0.2032)
		(layers "F.Cu" "B.Cu")
		(net "CPU1_SP5R4")
	)
	(via
		(at 190.881 -99.278948)
		(size 0.508)
		(drill 0.254)
		(layers "F.Cu" "B.Cu")
		(net "CPU1_SP5R4")
	)
	(via
		(at 172.481748 -115.60556)
		(size 0.508)
		(drill 0.254)
		(layers "F.Cu" "B.Cu")
		(net "CPU1_SP5R4")
	)
	(segment
		(start 155.751784 -320.798952)
		(end 155.079954 -320.798952)
		(width 0.10668)
		(layer "B.Cu")
		(net "CPU1_SP5R4")
	)
	(segment
		(start 190.881 -99.894898)
		(end 190.919608 -99.85629)
		(width 0.10668)
		(layer "B.Cu")
		(net "CPU1_SP5R4")
	)
	(segment
		(start 93.943932 -312.26125)
		(end 108.10494 -312.26125)
		(width 0.10668)
		(layer "B.Cu")
		(net "CPU1_SP5R4")
	)
	(segment
		(start 190.919608 -99.85629)
		(end 190.919608 -99.317556)
		(width 0.10668)
		(layer "B.Cu")
		(net "CPU1_SP5R4")
	)
	(segment
		(start 60.789312 -325.485252)
		(end 60.789312 -321.66179)
		(width 0.10668)
		(layer "B.Cu")
		(net "CPU1_SP5R4")
	)
	(segment
		(start 18.089626 -326.665336)
		(end 59.609228 -326.665336)
		(width 0.10668)
		(layer "B.Cu")
		(net "CPU1_SP5R4")
	)
	(segment
		(start 16.415258 -328.339704)
		(end 18.089626 -326.665336)
		(width 0.10668)
		(layer "B.Cu")
		(net "CPU1_SP5R4")
	)
	(segment
		(start 69.661278 -312.789824)
		(end 93.415358 -312.789824)
		(width 0.10668)
		(layer "B.Cu")
		(net "CPU1_SP5R4")
	)
	(segment
		(start 93.415358 -312.789824)
		(end 93.943932 -312.26125)
		(width 0.10668)
		(layer "B.Cu")
		(net "CPU1_SP5R4")
	)
	(segment
		(start 109.498384 -325.225918)
		(end 108.61421 -325.225918)
		(width 0.10668)
		(layer "B.Cu")
		(net "CPU1_SP5R4")
	)
	(segment
		(start 60.789312 -321.66179)
		(end 69.661278 -312.789824)
		(width 0.10668)
		(layer "B.Cu")
		(net "CPU1_SP5R4")
	)
	(segment
		(start 13.995146 -328.339704)
		(end 16.415258 -328.339704)
		(width 0.10668)
		(layer "B.Cu")
		(net "CPU1_SP5R4")
	)
	(segment
		(start 190.919608 -99.317556)
		(end 190.881 -99.278948)
		(width 0.10668)
		(layer "B.Cu")
		(net "CPU1_SP5R4")
	)
	(segment
		(start 108.10494 -312.26125)
		(end 110.8583 -315.01461)
		(width 0.10668)
		(layer "B.Cu")
		(net "CPU1_SP5R4")
	)
	(segment
		(start 110.8583 -323.866002)
		(end 109.498384 -325.225918)
		(width 0.10668)
		(layer "B.Cu")
		(net "CPU1_SP5R4")
	)
	(segment
		(start 59.609228 -326.665336)
		(end 60.789312 -325.485252)
		(width 0.10668)
		(layer "B.Cu")
		(net "CPU1_SP5R4")
	)
	(segment
		(start 110.8583 -315.01461)
		(end 110.8583 -323.866002)
		(width 0.10668)
		(layer "B.Cu")
		(net "CPU1_SP5R4")
	)
	(segment
		(start 148.41474 -313.97448)
		(end 152.60066 -313.97448)
		(width 0.11684)
		(layer "In2.Cu")
		(net "CPU1_SP5R4")
	)
	(segment
		(start 138.864848 -295.146222)
		(end 138.864848 -306.647596)
		(width 0.11684)
		(layer "In2.Cu")
		(net "CPU1_SP5R4")
	)
	(segment
		(start 138.864848 -306.647596)
		(end 142.66164 -310.444388)
		(width 0.11684)
		(layer "In2.Cu")
		(net "CPU1_SP5R4")
	)
	(segment
		(start 155.78582 -320.798952)
		(end 155.079954 -320.798952)
		(width 0.11684)
		(layer "In2.Cu")
		(net "CPU1_SP5R4")
	)
	(segment
		(start 156.413962 -316.33795)
		(end 156.413962 -320.17081)
		(width 0.11684)
		(layer "In2.Cu")
		(net "CPU1_SP5R4")
	)
	(segment
		(start 155.557982 -324.387718)
		(end 155.557982 -321.80022)
		(width 0.11684)
		(layer "In2.Cu")
		(net "CPU1_SP5R4")
	)
	(segment
		(start 154.325574 -315.699394)
		(end 155.775406 -315.699394)
		(width 0.11684)
		(layer "In2.Cu")
		(net "CPU1_SP5R4")
	)
	(segment
		(start 108.68406 -325.295768)
		(end 154.649932 -325.295768)
		(width 0.11684)
		(layer "In2.Cu")
		(net "CPU1_SP5R4")
	)
	(segment
		(start 155.775406 -315.699394)
		(end 156.413962 -316.33795)
		(width 0.11684)
		(layer "In2.Cu")
		(net "CPU1_SP5R4")
	)
	(segment
		(start 155.079954 -321.322192)
		(end 155.079954 -320.798952)
		(width 0.11684)
		(layer "In2.Cu")
		(net "CPU1_SP5R4")
	)
	(segment
		(start 108.61421 -325.225918)
		(end 108.68406 -325.295768)
		(width 0.11684)
		(layer "In2.Cu")
		(net "CPU1_SP5R4")
	)
	(segment
		(start 144.884648 -310.444388)
		(end 148.41474 -313.97448)
		(width 0.11684)
		(layer "In2.Cu")
		(net "CPU1_SP5R4")
	)
	(segment
		(start 155.557982 -321.80022)
		(end 155.079954 -321.322192)
		(width 0.11684)
		(layer "In2.Cu")
		(net "CPU1_SP5R4")
	)
	(segment
		(start 156.413962 -320.17081)
		(end 155.78582 -320.798952)
		(width 0.11684)
		(layer "In2.Cu")
		(net "CPU1_SP5R4")
	)
	(segment
		(start 142.66164 -310.444388)
		(end 144.884648 -310.444388)
		(width 0.11684)
		(layer "In2.Cu")
		(net "CPU1_SP5R4")
	)
	(segment
		(start 152.60066 -313.97448)
		(end 154.325574 -315.699394)
		(width 0.11684)
		(layer "In2.Cu")
		(net "CPU1_SP5R4")
	)
	(segment
		(start 154.649932 -325.295768)
		(end 155.557982 -324.387718)
		(width 0.11684)
		(layer "In2.Cu")
		(net "CPU1_SP5R4")
	)
	(segment
		(start 172.481748 -115.60556)
		(end 172.481748 -117.294152)
		(width 0.11684)
		(layer "In4.Cu")
		(net "CPU1_SP5R4")
	)
	(segment
		(start 157.8102 -120.7008)
		(end 157.6832 -120.5738)
		(width 0.11684)
		(layer "In4.Cu")
		(net "CPU1_SP5R4")
	)
	(segment
		(start 162.867848 -119.021352)
		(end 161.1884 -120.7008)
		(width 0.11684)
		(layer "In4.Cu")
		(net "CPU1_SP5R4")
	)
	(segment
		(start 161.1884 -120.7008)
		(end 157.8102 -120.7008)
		(width 0.11684)
		(layer "In4.Cu")
		(net "CPU1_SP5R4")
	)
	(segment
		(start 166.391336 -119.021352)
		(end 162.867848 -119.021352)
		(width 0.11684)
		(layer "In4.Cu")
		(net "CPU1_SP5R4")
	)
	(segment
		(start 170.946826 -118.829074)
		(end 166.583614 -118.829074)
		(width 0.11684)
		(layer "In4.Cu")
		(net "CPU1_SP5R4")
	)
	(segment
		(start 166.583614 -118.829074)
		(end 166.391336 -119.021352)
		(width 0.11684)
		(layer "In4.Cu")
		(net "CPU1_SP5R4")
	)
	(segment
		(start 172.481748 -117.294152)
		(end 170.946826 -118.829074)
		(width 0.11684)
		(layer "In4.Cu")
		(net "CPU1_SP5R4")
	)
	(segment
		(start 189.930532 -100.250244)
		(end 190.881 -99.299776)
		(width 0.11684)
		(layer "In6.Cu")
		(net "CPU1_SP5R4")
	)
	(segment
		(start 172.72 -115.60556)
		(end 173.510448 -114.815112)
		(width 0.11684)
		(layer "In6.Cu")
		(net "CPU1_SP5R4")
	)
	(segment
		(start 182.327804 -102.35311)
		(end 184.43067 -100.250244)
		(width 0.11684)
		(layer "In6.Cu")
		(net "CPU1_SP5R4")
	)
	(segment
		(start 173.510448 -114.815112)
		(end 173.510448 -110.607094)
		(width 0.11684)
		(layer "In6.Cu")
		(net "CPU1_SP5R4")
	)
	(segment
		(start 172.481748 -115.60556)
		(end 172.72 -115.60556)
		(width 0.11684)
		(layer "In6.Cu")
		(net "CPU1_SP5R4")
	)
	(segment
		(start 181.764432 -102.35311)
		(end 182.327804 -102.35311)
		(width 0.11684)
		(layer "In6.Cu")
		(net "CPU1_SP5R4")
	)
	(segment
		(start 173.510448 -110.607094)
		(end 181.764432 -102.35311)
		(width 0.11684)
		(layer "In6.Cu")
		(net "CPU1_SP5R4")
	)
	(segment
		(start 184.43067 -100.250244)
		(end 189.930532 -100.250244)
		(width 0.11684)
		(layer "In6.Cu")
		(net "CPU1_SP5R4")
	)
	(segment
		(start 190.881 -99.299776)
		(end 190.881 -99.278948)
		(width 0.11684)
		(layer "In6.Cu")
		(net "CPU1_SP5R4")
	)
	(segment
		(start 162.498278 -135.49376)
		(end 160.826704 -135.49376)
		(width 0.11684)
		(layer "In15.Cu")
		(net "CPU1_SP5R4")
	)
	(segment
		(start 158.54045 -129.445512)
		(end 159.27197 -128.713992)
		(width 0.11684)
		(layer "In15.Cu")
		(net "CPU1_SP5R4")
	)
	(segment
		(start 158.54045 -133.207506)
		(end 158.54045 -129.445512)
		(width 0.11684)
		(layer "In15.Cu")
		(net "CPU1_SP5R4")
	)
	(segment
		(start 157.6832 -121.233692)
		(end 157.6832 -120.5738)
		(width 0.11684)
		(layer "In15.Cu")
		(net "CPU1_SP5R4")
	)
	(segment
		(start 159.27197 -122.822462)
		(end 157.6832 -121.233692)
		(width 0.11684)
		(layer "In15.Cu")
		(net "CPU1_SP5R4")
	)
	(segment
		(start 160.826704 -135.49376)
		(end 158.54045 -133.207506)
		(width 0.11684)
		(layer "In15.Cu")
		(net "CPU1_SP5R4")
	)
	(segment
		(start 159.27197 -128.713992)
		(end 159.27197 -122.822462)
		(width 0.11684)
		(layer "In15.Cu")
		(net "CPU1_SP5R4")
	)
	(segment
		(start 79.177896 -294.880284)
		(end 78.269846 -295.788334)
		(width 0.10668)
		(layer "F.Cu")
		(net "CPU1_SP5R3")
	)
	(segment
		(start 88.494616 -301.737268)
		(end 88.494616 -306.300378)
		(width 0.10668)
		(layer "F.Cu")
		(net "CPU1_SP5R3")
	)
	(segment
		(start 85.925914 -299.168566)
		(end 88.494616 -301.737268)
		(width 0.10668)
		(layer "F.Cu")
		(net "CPU1_SP5R3")
	)
	(segment
		(start 78.269846 -295.788334)
		(end 78.269846 -296.8752)
		(width 0.10668)
		(layer "F.Cu")
		(net "CPU1_SP5R3")
	)
	(segment
		(start 80.563212 -299.168566)
		(end 85.925914 -299.168566)
		(width 0.10668)
		(layer "F.Cu")
		(net "CPU1_SP5R3")
	)
	(segment
		(start 88.494616 -306.300378)
		(end 88.36279 -306.432204)
		(width 0.10668)
		(layer "F.Cu")
		(net "CPU1_SP5R3")
	)
	(segment
		(start 78.269846 -296.8752)
		(end 80.563212 -299.168566)
		(width 0.10668)
		(layer "F.Cu")
		(net "CPU1_SP5R3")
	)
	(via
		(at 88.36279 -306.432204)
		(size 0.508)
		(drill 0.254)
		(layers "F.Cu" "B.Cu")
		(net "CPU1_SP5R3")
	)
	(via
		(at 192.112138 -91.656154)
		(size 0.508)
		(drill 0.254)
		(layers "F.Cu" "B.Cu")
		(net "CPU1_SP5R3")
	)
	(via
		(at 96.426782 -125.461268)
		(size 0.508)
		(drill 0.254)
		(layers "F.Cu" "B.Cu")
		(net "CPU1_SP5R3")
	)
	(via
		(at 15.378938 -324.113144)
		(size 0.508)
		(drill 0.254)
		(layers "F.Cu" "B.Cu")
		(net "CPU1_SP5R3")
	)
	(via
		(at 159.102552 -83.956144)
		(size 0.508)
		(drill 0.254)
		(layers "F.Cu" "B.Cu")
		(net "CPU1_SP5R3")
	)
	(via
		(at 154.129994 -109.100112)
		(size 0.508)
		(drill 0.254)
		(layers "F.Cu" "B.Cu")
		(net "CPU1_SP5R3")
	)
	(via
		(at 189.914784 -84.524088)
		(size 0.508)
		(drill 0.254)
		(layers "F.Cu" "B.Cu")
		(net "CPU1_SP5R3")
	)
	(via
		(at 58.615834 -319.78727)
		(size 0.6604)
		(drill 0.3302)
		(layers "F.Cu" "B.Cu")
		(net "CPU1_SP5R3")
	)
	(segment
		(start 191.623696 -99.894898)
		(end 191.389 -99.660202)
		(width 0.10668)
		(layer "B.Cu")
		(net "CPU1_SP5R3")
	)
	(segment
		(start 192.368932 -92.292932)
		(end 192.112138 -92.036138)
		(width 0.10668)
		(layer "B.Cu")
		(net "CPU1_SP5R3")
	)
	(segment
		(start 191.897 -99.894898)
		(end 191.623696 -99.894898)
		(width 0.10668)
		(layer "B.Cu")
		(net "CPU1_SP5R3")
	)
	(segment
		(start 86.879684 -310.359806)
		(end 88.36279 -308.8767)
		(width 0.10668)
		(layer "B.Cu")
		(net "CPU1_SP5R3")
	)
	(segment
		(start 91.249246 -306.06619)
		(end 91.908884 -305.406552)
		(width 0.10668)
		(layer "B.Cu")
		(net "CPU1_SP5R3")
	)
	(segment
		(start 192.112138 -92.036138)
		(end 192.112138 -91.656154)
		(width 0.10668)
		(layer "B.Cu")
		(net "CPU1_SP5R3")
	)
	(segment
		(start 68.582032 -310.359806)
		(end 86.879684 -310.359806)
		(width 0.10668)
		(layer "B.Cu")
		(net "CPU1_SP5R3")
	)
	(segment
		(start 18.007584 -321.949826)
		(end 56.453278 -321.949826)
		(width 0.10668)
		(layer "B.Cu")
		(net "CPU1_SP5R3")
	)
	(segment
		(start 191.389 -97.617534)
		(end 192.368932 -96.637602)
		(width 0.10668)
		(layer "B.Cu")
		(net "CPU1_SP5R3")
	)
	(segment
		(start 15.844266 -324.113144)
		(end 18.007584 -321.949826)
		(width 0.10668)
		(layer "B.Cu")
		(net "CPU1_SP5R3")
	)
	(segment
		(start 58.615834 -319.78727)
		(end 59.154568 -319.78727)
		(width 0.10668)
		(layer "B.Cu")
		(net "CPU1_SP5R3")
	)
	(segment
		(start 59.154568 -319.78727)
		(end 68.582032 -310.359806)
		(width 0.10668)
		(layer "B.Cu")
		(net "CPU1_SP5R3")
	)
	(segment
		(start 15.378938 -324.113144)
		(end 15.844266 -324.113144)
		(width 0.10668)
		(layer "B.Cu")
		(net "CPU1_SP5R3")
	)
	(segment
		(start 191.389 -99.660202)
		(end 191.389 -97.617534)
		(width 0.10668)
		(layer "B.Cu")
		(net "CPU1_SP5R3")
	)
	(segment
		(start 159.92983 -84.783422)
		(end 159.102552 -83.956144)
		(width 0.10668)
		(layer "B.Cu")
		(net "CPU1_SP5R3")
	)
	(segment
		(start 189.914784 -84.524088)
		(end 184.26684 -84.524088)
		(width 0.10668)
		(layer "B.Cu")
		(net "CPU1_SP5R3")
	)
	(segment
		(start 88.36279 -306.432204)
		(end 88.728804 -306.06619)
		(width 0.10668)
		(layer "B.Cu")
		(net "CPU1_SP5R3")
	)
	(segment
		(start 184.26684 -84.524088)
		(end 183.550052 -83.8073)
		(width 0.10668)
		(layer "B.Cu")
		(net "CPU1_SP5R3")
	)
	(segment
		(start 169.314622 -83.8073)
		(end 168.3385 -84.783422)
		(width 0.10668)
		(layer "B.Cu")
		(net "CPU1_SP5R3")
	)
	(segment
		(start 88.36279 -308.8767)
		(end 88.36279 -306.432204)
		(width 0.10668)
		(layer "B.Cu")
		(net "CPU1_SP5R3")
	)
	(segment
		(start 192.368932 -96.637602)
		(end 192.368932 -92.292932)
		(width 0.10668)
		(layer "B.Cu")
		(net "CPU1_SP5R3")
	)
	(segment
		(start 88.728804 -306.06619)
		(end 91.249246 -306.06619)
		(width 0.10668)
		(layer "B.Cu")
		(net "CPU1_SP5R3")
	)
	(segment
		(start 183.550052 -83.8073)
		(end 169.314622 -83.8073)
		(width 0.10668)
		(layer "B.Cu")
		(net "CPU1_SP5R3")
	)
	(segment
		(start 56.453278 -321.949826)
		(end 58.615834 -319.78727)
		(width 0.10668)
		(layer "B.Cu")
		(net "CPU1_SP5R3")
	)
	(segment
		(start 168.3385 -84.783422)
		(end 159.92983 -84.783422)
		(width 0.10668)
		(layer "B.Cu")
		(net "CPU1_SP5R3")
	)
	(segment
		(start 154.129994 -109.100112)
		(end 155.206954 -109.100112)
		(width 0.11684)
		(layer "In4.Cu")
		(net "CPU1_SP5R3")
	)
	(segment
		(start 156.490162 -97.670874)
		(end 156.490162 -97.01784)
		(width 0.11684)
		(layer "In4.Cu")
		(net "CPU1_SP5R3")
	)
	(segment
		(start 157.299914 -89.49436)
		(end 157.299914 -85.758782)
		(width 0.11684)
		(layer "In4.Cu")
		(net "CPU1_SP5R3")
	)
	(segment
		(start 156.490162 -97.01784)
		(end 156.124402 -96.65208)
		(width 0.11684)
		(layer "In4.Cu")
		(net "CPU1_SP5R3")
	)
	(segment
		(start 192.112138 -91.656154)
		(end 192.112138 -90.998294)
		(width 0.11684)
		(layer "In4.Cu")
		(net "CPU1_SP5R3")
	)
	(segment
		(start 156.124402 -90.669872)
		(end 157.299914 -89.49436)
		(width 0.11684)
		(layer "In4.Cu")
		(net "CPU1_SP5R3")
	)
	(segment
		(start 156.254958 -97.906078)
		(end 156.490162 -97.670874)
		(width 0.11684)
		(layer "In4.Cu")
		(net "CPU1_SP5R3")
	)
	(segment
		(start 156.254958 -108.052108)
		(end 156.254958 -97.906078)
		(width 0.11684)
		(layer "In4.Cu")
		(net "CPU1_SP5R3")
	)
	(segment
		(start 192.040256 -86.64956)
		(end 189.914784 -84.524088)
		(width 0.11684)
		(layer "In4.Cu")
		(net "CPU1_SP5R3")
	)
	(segment
		(start 157.299914 -85.758782)
		(end 159.102552 -83.956144)
		(width 0.11684)
		(layer "In4.Cu")
		(net "CPU1_SP5R3")
	)
	(segment
		(start 156.124402 -96.65208)
		(end 156.124402 -90.669872)
		(width 0.11684)
		(layer "In4.Cu")
		(net "CPU1_SP5R3")
	)
	(segment
		(start 155.206954 -109.100112)
		(end 156.254958 -108.052108)
		(width 0.11684)
		(layer "In4.Cu")
		(net "CPU1_SP5R3")
	)
	(segment
		(start 192.040256 -90.926412)
		(end 192.040256 -86.64956)
		(width 0.11684)
		(layer "In4.Cu")
		(net "CPU1_SP5R3")
	)
	(segment
		(start 192.112138 -90.998294)
		(end 192.040256 -90.926412)
		(width 0.11684)
		(layer "In4.Cu")
		(net "CPU1_SP5R3")
	)
	(segment
		(start 112.006888 -116.136166)
		(end 135.223504 -116.136166)
		(width 0.11684)
		(layer "In6.Cu")
		(net "CPU1_SP5R3")
	)
	(segment
		(start 110.636304 -117.50675)
		(end 112.006888 -116.136166)
		(width 0.11684)
		(layer "In6.Cu")
		(net "CPU1_SP5R3")
	)
	(segment
		(start 95.709486 -120.611138)
		(end 98.813874 -117.50675)
		(width 0.11684)
		(layer "In6.Cu")
		(net "CPU1_SP5R3")
	)
	(segment
		(start 142.553944 -112.01908)
		(end 151.70277 -112.01908)
		(width 0.11684)
		(layer "In6.Cu")
		(net "CPU1_SP5R3")
	)
	(segment
		(start 136.702038 -114.657632)
		(end 139.915392 -114.657632)
		(width 0.11684)
		(layer "In6.Cu")
		(net "CPU1_SP5R3")
	)
	(segment
		(start 98.813874 -117.50675)
		(end 110.636304 -117.50675)
		(width 0.11684)
		(layer "In6.Cu")
		(net "CPU1_SP5R3")
	)
	(segment
		(start 135.223504 -116.136166)
		(end 136.702038 -114.657632)
		(width 0.11684)
		(layer "In6.Cu")
		(net "CPU1_SP5R3")
	)
	(segment
		(start 139.915392 -114.657632)
		(end 142.553944 -112.01908)
		(width 0.11684)
		(layer "In6.Cu")
		(net "CPU1_SP5R3")
	)
	(segment
		(start 95.709486 -124.743972)
		(end 95.709486 -120.611138)
		(width 0.11684)
		(layer "In6.Cu")
		(net "CPU1_SP5R3")
	)
	(segment
		(start 154.129994 -109.591856)
		(end 154.129994 -109.100112)
		(width 0.11684)
		(layer "In6.Cu")
		(net "CPU1_SP5R3")
	)
	(segment
		(start 151.70277 -112.01908)
		(end 154.129994 -109.591856)
		(width 0.11684)
		(layer "In6.Cu")
		(net "CPU1_SP5R3")
	)
	(segment
		(start 96.426782 -125.461268)
		(end 95.709486 -124.743972)
		(width 0.11684)
		(layer "In6.Cu")
		(net "CPU1_SP5R3")
	)
	(segment
		(start 12.106656 -171.2341)
		(end 12.106656 -323.141086)
		(width 0.11684)
		(layer "In11.Cu")
		(net "CPU1_SP5R3")
	)
	(segment
		(start 20.544282 -145.76679)
		(end 20.544282 -162.796474)
		(width 0.11684)
		(layer "In11.Cu")
		(net "CPU1_SP5R3")
	)
	(segment
		(start 26.933652 -139.37742)
		(end 20.544282 -145.76679)
		(width 0.11684)
		(layer "In11.Cu")
		(net "CPU1_SP5R3")
	)
	(segment
		(start 12.644374 -323.678804)
		(end 14.795754 -323.678804)
		(width 0.11684)
		(layer "In11.Cu")
		(net "CPU1_SP5R3")
	)
	(segment
		(start 15.230094 -324.113144)
		(end 15.378938 -324.113144)
		(width 0.11684)
		(layer "In11.Cu")
		(net "CPU1_SP5R3")
	)
	(segment
		(start 96.254316 -125.461268)
		(end 88.79713 -132.918454)
		(width 0.11684)
		(layer "In11.Cu")
		(net "CPU1_SP5R3")
	)
	(segment
		(start 44.720764 -139.37742)
		(end 26.933652 -139.37742)
		(width 0.11684)
		(layer "In11.Cu")
		(net "CPU1_SP5R3")
	)
	(segment
		(start 20.544282 -162.796474)
		(end 12.106656 -171.2341)
		(width 0.11684)
		(layer "In11.Cu")
		(net "CPU1_SP5R3")
	)
	(segment
		(start 52.101242 -131.996942)
		(end 44.720764 -139.37742)
		(width 0.11684)
		(layer "In11.Cu")
		(net "CPU1_SP5R3")
	)
	(segment
		(start 86.717632 -132.918454)
		(end 85.79612 -131.996942)
		(width 0.11684)
		(layer "In11.Cu")
		(net "CPU1_SP5R3")
	)
	(segment
		(start 88.79713 -132.918454)
		(end 86.717632 -132.918454)
		(width 0.11684)
		(layer "In11.Cu")
		(net "CPU1_SP5R3")
	)
	(segment
		(start 14.795754 -323.678804)
		(end 15.230094 -324.113144)
		(width 0.11684)
		(layer "In11.Cu")
		(net "CPU1_SP5R3")
	)
	(segment
		(start 85.79612 -131.996942)
		(end 52.101242 -131.996942)
		(width 0.11684)
		(layer "In11.Cu")
		(net "CPU1_SP5R3")
	)
	(segment
		(start 96.426782 -125.461268)
		(end 96.254316 -125.461268)
		(width 0.11684)
		(layer "In11.Cu")
		(net "CPU1_SP5R3")
	)
	(segment
		(start 12.106656 -323.141086)
		(end 12.644374 -323.678804)
		(width 0.11684)
		(layer "In11.Cu")
		(net "CPU1_SP5R3")
	)
	(segment
		(start 72.91705 -203.025756)
		(end 75.445874 -205.55458)
		(width 0.10668)
		(layer "F.Cu")
		(net "CPU1_SP5R2")
	)
	(segment
		(start 84.204556 -205.55458)
		(end 88.478106 -209.82813)
		(width 0.10668)
		(layer "F.Cu")
		(net "CPU1_SP5R2")
	)
	(segment
		(start 88.478106 -216.145618)
		(end 83.655154 -220.96857)
		(width 0.10668)
		(layer "F.Cu")
		(net "CPU1_SP5R2")
	)
	(segment
		(start 83.655154 -222.250254)
		(end 84.047838 -222.642938)
		(width 0.10668)
		(layer "F.Cu")
		(net "CPU1_SP5R2")
	)
	(segment
		(start 84.047838 -222.642938)
		(end 84.047838 -223.690434)
		(width 0.10668)
		(layer "F.Cu")
		(net "CPU1_SP5R2")
	)
	(segment
		(start 75.445874 -205.55458)
		(end 84.204556 -205.55458)
		(width 0.10668)
		(layer "F.Cu")
		(net "CPU1_SP5R2")
	)
	(segment
		(start 83.655154 -220.96857)
		(end 83.655154 -222.250254)
		(width 0.10668)
		(layer "F.Cu")
		(net "CPU1_SP5R2")
	)
	(segment
		(start 88.478106 -209.82813)
		(end 88.478106 -216.145618)
		(width 0.10668)
		(layer "F.Cu")
		(net "CPU1_SP5R2")
	)
	(segment
		(start 72.455532 -203.025756)
		(end 72.91705 -203.025756)
		(width 0.10668)
		(layer "F.Cu")
		(net "CPU1_SP5R2")
	)
	(via
		(at 72.455532 -203.025756)
		(size 0.508)
		(drill 0.254)
		(layers "F.Cu" "B.Cu")
		(net "CPU1_SP5R2")
	)
	(via
		(at 111.019336 -127.47371)
		(size 0.508)
		(drill 0.254)
		(layers "F.Cu" "B.Cu")
		(net "CPU1_SP5R2")
	)
	(via
		(at 188.849 -93.690948)
		(size 0.508)
		(drill 0.254)
		(layers "F.Cu" "B.Cu")
		(net "CPU1_SP5R2")
	)
	(segment
		(start 188.859414 -96.685862)
		(end 189.358778 -96.186498)
		(width 0.10668)
		(layer "B.Cu")
		(net "CPU1_SP5R2")
	)
	(segment
		(start 71.265034 -203.679552)
		(end 71.696834 -203.247752)
		(width 0.10668)
		(layer "B.Cu")
		(net "CPU1_SP5R2")
	)
	(segment
		(start 189.358778 -96.186498)
		(end 189.358778 -94.200726)
		(width 0.10668)
		(layer "B.Cu")
		(net "CPU1_SP5R2")
	)
	(segment
		(start 71.696834 -203.247752)
		(end 72.233536 -203.247752)
		(width 0.10668)
		(layer "B.Cu")
		(net "CPU1_SP5R2")
	)
	(segment
		(start 70.572884 -203.679552)
		(end 71.265034 -203.679552)
		(width 0.10668)
		(layer "B.Cu")
		(net "CPU1_SP5R2")
	)
	(segment
		(start 72.233536 -203.247752)
		(end 72.455532 -203.025756)
		(width 0.10668)
		(layer "B.Cu")
		(net "CPU1_SP5R2")
	)
	(segment
		(start 188.838078 -96.685862)
		(end 188.859414 -96.685862)
		(width 0.10668)
		(layer "B.Cu")
		(net "CPU1_SP5R2")
	)
	(segment
		(start 189.358778 -94.200726)
		(end 188.849 -93.690948)
		(width 0.10668)
		(layer "B.Cu")
		(net "CPU1_SP5R2")
	)
	(segment
		(start 176.360582 -104.26319)
		(end 171.734226 -108.889546)
		(width 0.11684)
		(layer "In6.Cu")
		(net "CPU1_SP5R2")
	)
	(segment
		(start 153.0604 -125.83414)
		(end 112.658906 -125.83414)
		(width 0.11684)
		(layer "In6.Cu")
		(net "CPU1_SP5R2")
	)
	(segment
		(start 183.877712 -97.793048)
		(end 182.600854 -97.793048)
		(width 0.11684)
		(layer "In6.Cu")
		(net "CPU1_SP5R2")
	)
	(segment
		(start 188.212222 -94.327726)
		(end 187.343034 -94.327726)
		(width 0.11684)
		(layer "In6.Cu")
		(net "CPU1_SP5R2")
	)
	(segment
		(start 182.600854 -97.793048)
		(end 182.245 -98.148902)
		(width 0.11684)
		(layer "In6.Cu")
		(net "CPU1_SP5R2")
	)
	(segment
		(start 155.049728 -124.63018)
		(end 154.26436 -124.63018)
		(width 0.11684)
		(layer "In6.Cu")
		(net "CPU1_SP5R2")
	)
	(segment
		(start 112.658906 -125.83414)
		(end 111.019336 -127.47371)
		(width 0.11684)
		(layer "In6.Cu")
		(net "CPU1_SP5R2")
	)
	(segment
		(start 182.245 -99.428554)
		(end 177.410364 -104.26319)
		(width 0.11684)
		(layer "In6.Cu")
		(net "CPU1_SP5R2")
	)
	(segment
		(start 188.849 -93.690948)
		(end 188.212222 -94.327726)
		(width 0.11684)
		(layer "In6.Cu")
		(net "CPU1_SP5R2")
	)
	(segment
		(start 154.26436 -124.63018)
		(end 153.0604 -125.83414)
		(width 0.11684)
		(layer "In6.Cu")
		(net "CPU1_SP5R2")
	)
	(segment
		(start 182.245 -98.148902)
		(end 182.245 -99.428554)
		(width 0.11684)
		(layer "In6.Cu")
		(net "CPU1_SP5R2")
	)
	(segment
		(start 162.20821 -118.911878)
		(end 162.20821 -120.720866)
		(width 0.11684)
		(layer "In6.Cu")
		(net "CPU1_SP5R2")
	)
	(segment
		(start 156.226764 -125.807216)
		(end 155.049728 -124.63018)
		(width 0.11684)
		(layer "In6.Cu")
		(net "CPU1_SP5R2")
	)
	(segment
		(start 187.343034 -94.327726)
		(end 183.877712 -97.793048)
		(width 0.11684)
		(layer "In6.Cu")
		(net "CPU1_SP5R2")
	)
	(segment
		(start 166.32682 -114.793268)
		(end 162.20821 -118.911878)
		(width 0.11684)
		(layer "In6.Cu")
		(net "CPU1_SP5R2")
	)
	(segment
		(start 162.20821 -120.720866)
		(end 157.12186 -125.807216)
		(width 0.11684)
		(layer "In6.Cu")
		(net "CPU1_SP5R2")
	)
	(segment
		(start 177.410364 -104.26319)
		(end 176.360582 -104.26319)
		(width 0.11684)
		(layer "In6.Cu")
		(net "CPU1_SP5R2")
	)
	(segment
		(start 169.420286 -114.793268)
		(end 166.32682 -114.793268)
		(width 0.11684)
		(layer "In6.Cu")
		(net "CPU1_SP5R2")
	)
	(segment
		(start 157.12186 -125.807216)
		(end 156.226764 -125.807216)
		(width 0.11684)
		(layer "In6.Cu")
		(net "CPU1_SP5R2")
	)
	(segment
		(start 171.734226 -108.889546)
		(end 171.734226 -112.479328)
		(width 0.11684)
		(layer "In6.Cu")
		(net "CPU1_SP5R2")
	)
	(segment
		(start 171.734226 -112.479328)
		(end 169.420286 -114.793268)
		(width 0.11684)
		(layer "In6.Cu")
		(net "CPU1_SP5R2")
	)
	(segment
		(start 60.261754 -193.058288)
		(end 63.378334 -196.174868)
		(width 0.11684)
		(layer "In11.Cu")
		(net "CPU1_SP5R2")
	)
	(segment
		(start 58.960512 -191.788796)
		(end 60.230004 -193.058288)
		(width 0.11684)
		(layer "In11.Cu")
		(net "CPU1_SP5R2")
	)
	(segment
		(start 94.370398 -132.78866)
		(end 93.397324 -133.761734)
		(width 0.11684)
		(layer "In11.Cu")
		(net "CPU1_SP5R2")
	)
	(segment
		(start 106.206036 -132.78866)
		(end 94.370398 -132.78866)
		(width 0.11684)
		(layer "In11.Cu")
		(net "CPU1_SP5R2")
	)
	(segment
		(start 40.362378 -191.788796)
		(end 58.960512 -191.788796)
		(width 0.11684)
		(layer "In11.Cu")
		(net "CPU1_SP5R2")
	)
	(segment
		(start 60.230004 -193.058288)
		(end 60.261754 -193.058288)
		(width 0.11684)
		(layer "In11.Cu")
		(net "CPU1_SP5R2")
	)
	(segment
		(start 93.397324 -133.761734)
		(end 52.102766 -133.761734)
		(width 0.11684)
		(layer "In11.Cu")
		(net "CPU1_SP5R2")
	)
	(segment
		(start 111.019336 -127.97536)
		(end 106.206036 -132.78866)
		(width 0.11684)
		(layer "In11.Cu")
		(net "CPU1_SP5R2")
	)
	(segment
		(start 52.102766 -133.761734)
		(end 39.139876 -146.724624)
		(width 0.11684)
		(layer "In11.Cu")
		(net "CPU1_SP5R2")
	)
	(segment
		(start 30.891988 -178.007264)
		(end 36.807902 -183.923178)
		(width 0.11684)
		(layer "In11.Cu")
		(net "CPU1_SP5R2")
	)
	(segment
		(start 36.807902 -183.923178)
		(end 36.807902 -188.23432)
		(width 0.11684)
		(layer "In11.Cu")
		(net "CPU1_SP5R2")
	)
	(segment
		(start 63.378334 -196.174868)
		(end 63.378334 -197.744842)
		(width 0.11684)
		(layer "In11.Cu")
		(net "CPU1_SP5R2")
	)
	(segment
		(start 70.695058 -203.025756)
		(end 72.455532 -203.025756)
		(width 0.11684)
		(layer "In11.Cu")
		(net "CPU1_SP5R2")
	)
	(segment
		(start 39.139876 -146.724624)
		(end 39.139876 -154.858974)
		(width 0.11684)
		(layer "In11.Cu")
		(net "CPU1_SP5R2")
	)
	(segment
		(start 30.891988 -163.106862)
		(end 30.891988 -178.007264)
		(width 0.11684)
		(layer "In11.Cu")
		(net "CPU1_SP5R2")
	)
	(segment
		(start 63.378334 -197.744842)
		(end 67.52209 -201.888598)
		(width 0.11684)
		(layer "In11.Cu")
		(net "CPU1_SP5R2")
	)
	(segment
		(start 39.139876 -154.858974)
		(end 30.891988 -163.106862)
		(width 0.11684)
		(layer "In11.Cu")
		(net "CPU1_SP5R2")
	)
	(segment
		(start 111.019336 -127.47371)
		(end 111.019336 -127.97536)
		(width 0.11684)
		(layer "In11.Cu")
		(net "CPU1_SP5R2")
	)
	(segment
		(start 67.52209 -201.888598)
		(end 69.5579 -201.888598)
		(width 0.11684)
		(layer "In11.Cu")
		(net "CPU1_SP5R2")
	)
	(segment
		(start 69.5579 -201.888598)
		(end 70.695058 -203.025756)
		(width 0.11684)
		(layer "In11.Cu")
		(net "CPU1_SP5R2")
	)
	(segment
		(start 36.807902 -188.23432)
		(end 40.362378 -191.788796)
		(width 0.11684)
		(layer "In11.Cu")
		(net "CPU1_SP5R2")
	)
	(segment
		(start 129.16789 -223.690434)
		(end 129.634742 -223.424496)
		(width 0.10668)
		(layer "F.Cu")
		(net "CPU1_SP5R1")
	)
	(segment
		(start 168.54932 -178.677316)
		(end 168.54932 -185.803286)
		(width 0.10668)
		(layer "F.Cu")
		(net "CPU1_SP5R1")
	)
	(segment
		(start 173.063408 -173.05147)
		(end 173.063408 -174.163228)
		(width 0.10668)
		(layer "F.Cu")
		(net "CPU1_SP5R1")
	)
	(segment
		(start 173.063408 -174.163228)
		(end 168.54932 -178.677316)
		(width 0.10668)
		(layer "F.Cu")
		(net "CPU1_SP5R1")
	)
	(via
		(at 160.885124 -126.482856)
		(size 0.508)
		(drill 0.254)
		(layers "F.Cu" "B.Cu")
		(net "CPU1_SP5R1")
	)
	(via
		(at 190.881 -93.690948)
		(size 0.508)
		(drill 0.254)
		(layers "F.Cu" "B.Cu")
		(net "CPU1_SP5R1")
	)
	(via
		(at 173.063408 -173.05147)
		(size 0.508)
		(drill 0.254)
		(layers "F.Cu" "B.Cu")
		(net "CPU1_SP5R1")
	)
	(via
		(at 157.539436 -190.91021)
		(size 0.6604)
		(drill 0.3302)
		(layers "F.Cu" "B.Cu")
		(net "CPU1_SP5R1")
	)
	(via
		(at 129.634742 -223.424496)
		(size 0.4064)
		(drill 0.2032)
		(layers "F.Cu" "B.Cu")
		(net "CPU1_SP5R1")
	)
	(via
		(at 168.54932 -185.803286)
		(size 0.508)
		(drill 0.254)
		(layers "F.Cu" "B.Cu")
		(net "CPU1_SP5R1")
	)
	(segment
		(start 174.3075 -168.189656)
		(end 174.3075 -158.7881)
		(width 0.10668)
		(layer "B.Cu")
		(net "CPU1_SP5R1")
	)
	(segment
		(start 162.529266 -132.422646)
		(end 162.529266 -129.999486)
		(width 0.10668)
		(layer "B.Cu")
		(net "CPU1_SP5R1")
	)
	(segment
		(start 130.37693 -222.094552)
		(end 129.81178 -222.094552)
		(width 0.10668)
		(layer "B.Cu")
		(net "CPU1_SP5R1")
	)
	(segment
		(start 129.81178 -222.094552)
		(end 129.634742 -222.27159)
		(width 0.10668)
		(layer "B.Cu")
		(net "CPU1_SP5R1")
	)
	(segment
		(start 130.672078 -218.690698)
		(end 131.498086 -218.690698)
		(width 0.10668)
		(layer "B.Cu")
		(net "CPU1_SP5R1")
	)
	(segment
		(start 167.990774 -185.24474)
		(end 163.204906 -185.24474)
		(width 0.10668)
		(layer "B.Cu")
		(net "CPU1_SP5R1")
	)
	(segment
		(start 157.539436 -190.91021)
		(end 151.205946 -197.2437)
		(width 0.10668)
		(layer "B.Cu")
		(net "CPU1_SP5R1")
	)
	(segment
		(start 169.875708 -154.356308)
		(end 169.875708 -139.769088)
		(width 0.10668)
		(layer "B.Cu")
		(net "CPU1_SP5R1")
	)
	(segment
		(start 162.529266 -129.999486)
		(end 160.885124 -128.355344)
		(width 0.10668)
		(layer "B.Cu")
		(net "CPU1_SP5R1")
	)
	(segment
		(start 174.3075 -158.7881)
		(end 169.875708 -154.356308)
		(width 0.10668)
		(layer "B.Cu")
		(net "CPU1_SP5R1")
	)
	(segment
		(start 145.331434 -203.279502)
		(end 138.899646 -203.279502)
		(width 0.10668)
		(layer "B.Cu")
		(net "CPU1_SP5R1")
	)
	(segment
		(start 173.063408 -169.433748)
		(end 174.3075 -168.189656)
		(width 0.10668)
		(layer "B.Cu")
		(net "CPU1_SP5R1")
	)
	(segment
		(start 173.063408 -173.05147)
		(end 173.063408 -169.433748)
		(width 0.10668)
		(layer "B.Cu")
		(net "CPU1_SP5R1")
	)
	(segment
		(start 130.084576 -212.094572)
		(end 130.084576 -218.103196)
		(width 0.10668)
		(layer "B.Cu")
		(net "CPU1_SP5R1")
	)
	(segment
		(start 168.54932 -185.803286)
		(end 167.990774 -185.24474)
		(width 0.10668)
		(layer "B.Cu")
		(net "CPU1_SP5R1")
	)
	(segment
		(start 131.986274 -219.178886)
		(end 131.986274 -220.485208)
		(width 0.10668)
		(layer "B.Cu")
		(net "CPU1_SP5R1")
	)
	(segment
		(start 148.593048 -197.2437)
		(end 145.331434 -200.505314)
		(width 0.10668)
		(layer "B.Cu")
		(net "CPU1_SP5R1")
	)
	(segment
		(start 169.875708 -139.769088)
		(end 162.529266 -132.422646)
		(width 0.10668)
		(layer "B.Cu")
		(net "CPU1_SP5R1")
	)
	(segment
		(start 131.498086 -218.690698)
		(end 131.986274 -219.178886)
		(width 0.10668)
		(layer "B.Cu")
		(net "CPU1_SP5R1")
	)
	(segment
		(start 130.084576 -218.103196)
		(end 130.672078 -218.690698)
		(width 0.10668)
		(layer "B.Cu")
		(net "CPU1_SP5R1")
	)
	(segment
		(start 190.881 -96.719898)
		(end 190.881 -93.690948)
		(width 0.10668)
		(layer "B.Cu")
		(net "CPU1_SP5R1")
	)
	(segment
		(start 163.204906 -185.24474)
		(end 157.539436 -190.91021)
		(width 0.10668)
		(layer "B.Cu")
		(net "CPU1_SP5R1")
	)
	(segment
		(start 131.986274 -220.485208)
		(end 130.37693 -222.094552)
		(width 0.10668)
		(layer "B.Cu")
		(net "CPU1_SP5R1")
	)
	(segment
		(start 138.899646 -203.279502)
		(end 130.084576 -212.094572)
		(width 0.10668)
		(layer "B.Cu")
		(net "CPU1_SP5R1")
	)
	(segment
		(start 145.331434 -200.505314)
		(end 145.331434 -203.279502)
		(width 0.10668)
		(layer "B.Cu")
		(net "CPU1_SP5R1")
	)
	(segment
		(start 151.205946 -197.2437)
		(end 148.593048 -197.2437)
		(width 0.10668)
		(layer "B.Cu")
		(net "CPU1_SP5R1")
	)
	(segment
		(start 129.634742 -222.27159)
		(end 129.634742 -223.424496)
		(width 0.10668)
		(layer "B.Cu")
		(net "CPU1_SP5R1")
	)
	(segment
		(start 160.885124 -128.355344)
		(end 160.885124 -126.482856)
		(width 0.10668)
		(layer "B.Cu")
		(net "CPU1_SP5R1")
	)
	(segment
		(start 163.271962 -121.040144)
		(end 160.885124 -123.426982)
		(width 0.11684)
		(layer "In15.Cu")
		(net "CPU1_SP5R1")
	)
	(segment
		(start 177.967894 -93.226128)
		(end 177.905664 -93.163898)
		(width 0.11684)
		(layer "In15.Cu")
		(net "CPU1_SP5R1")
	)
	(segment
		(start 182.763922 -96.772476)
		(end 181.268624 -95.277178)
		(width 0.11684)
		(layer "In15.Cu")
		(net "CPU1_SP5R1")
	)
	(segment
		(start 167.87114 -95.118174)
		(end 167.87114 -95.914464)
		(width 0.11684)
		(layer "In15.Cu")
		(net "CPU1_SP5R1")
	)
	(segment
		(start 167.87114 -95.914464)
		(end 168.093136 -96.13646)
		(width 0.11684)
		(layer "In15.Cu")
		(net "CPU1_SP5R1")
	)
	(segment
		(start 181.268624 -93.720412)
		(end 180.77434 -93.226128)
		(width 0.11684)
		(layer "In15.Cu")
		(net "CPU1_SP5R1")
	)
	(segment
		(start 164.211762 -105.148634)
		(end 164.211762 -108.35005)
		(width 0.11684)
		(layer "In15.Cu")
		(net "CPU1_SP5R1")
	)
	(segment
		(start 160.885124 -123.426982)
		(end 160.885124 -126.482856)
		(width 0.11684)
		(layer "In15.Cu")
		(net "CPU1_SP5R1")
	)
	(segment
		(start 163.271962 -109.28985)
		(end 163.271962 -121.040144)
		(width 0.11684)
		(layer "In15.Cu")
		(net "CPU1_SP5R1")
	)
	(segment
		(start 190.881 -95.10776)
		(end 189.216284 -96.772476)
		(width 0.11684)
		(layer "In15.Cu")
		(net "CPU1_SP5R1")
	)
	(segment
		(start 165.421564 -103.938832)
		(end 164.211762 -105.148634)
		(width 0.11684)
		(layer "In15.Cu")
		(net "CPU1_SP5R1")
	)
	(segment
		(start 168.093136 -96.13646)
		(end 168.093136 -101.770688)
		(width 0.11684)
		(layer "In15.Cu")
		(net "CPU1_SP5R1")
	)
	(segment
		(start 190.881 -93.690948)
		(end 190.881 -95.10776)
		(width 0.11684)
		(layer "In15.Cu")
		(net "CPU1_SP5R1")
	)
	(segment
		(start 177.905664 -93.163898)
		(end 169.825416 -93.163898)
		(width 0.11684)
		(layer "In15.Cu")
		(net "CPU1_SP5R1")
	)
	(segment
		(start 180.77434 -93.226128)
		(end 177.967894 -93.226128)
		(width 0.11684)
		(layer "In15.Cu")
		(net "CPU1_SP5R1")
	)
	(segment
		(start 165.924992 -103.938832)
		(end 165.421564 -103.938832)
		(width 0.11684)
		(layer "In15.Cu")
		(net "CPU1_SP5R1")
	)
	(segment
		(start 169.825416 -93.163898)
		(end 167.87114 -95.118174)
		(width 0.11684)
		(layer "In15.Cu")
		(net "CPU1_SP5R1")
	)
	(segment
		(start 168.093136 -101.770688)
		(end 165.924992 -103.938832)
		(width 0.11684)
		(layer "In15.Cu")
		(net "CPU1_SP5R1")
	)
	(segment
		(start 181.268624 -95.277178)
		(end 181.268624 -93.720412)
		(width 0.11684)
		(layer "In15.Cu")
		(net "CPU1_SP5R1")
	)
	(segment
		(start 164.211762 -108.35005)
		(end 163.271962 -109.28985)
		(width 0.11684)
		(layer "In15.Cu")
		(net "CPU1_SP5R1")
	)
	(segment
		(start 189.216284 -96.772476)
		(end 182.763922 -96.772476)
		(width 0.11684)
		(layer "In15.Cu")
		(net "CPU1_SP5R1")
	)
	(segment
		(start 77.628496 -301.9552)
		(end 76.651612 -304.313844)
		(width 0.10668)
		(layer "F.Cu")
		(net "CPU1_SMERR_N")
	)
	(segment
		(start 18.721324 -153.269696)
		(end 25.508712 -146.482308)
		(width 0.10668)
		(layer "F.Cu")
		(net "CPU1_SMERR_N")
	)
	(segment
		(start 136.987788 -296.05478)
		(end 135.290306 -297.752262)
		(width 0.10668)
		(layer "F.Cu")
		(net "CPU1_SMERR_N")
	)
	(segment
		(start 25.508712 -146.482308)
		(end 36.314126 -146.482308)
		(width 0.10668)
		(layer "F.Cu")
		(net "CPU1_SMERR_N")
	)
	(segment
		(start 135.290306 -307.399436)
		(end 141.527276 -313.636406)
		(width 0.10668)
		(layer "F.Cu")
		(net "CPU1_SMERR_N")
	)
	(segment
		(start 87.481156 -301.929546)
		(end 85.50656 -299.95495)
		(width 0.10668)
		(layer "F.Cu")
		(net "CPU1_SMERR_N")
	)
	(segment
		(start 85.50656 -299.95495)
		(end 79.628746 -299.95495)
		(width 0.10668)
		(layer "F.Cu")
		(net "CPU1_SMERR_N")
	)
	(segment
		(start 87.481156 -306.465478)
		(end 87.481156 -301.929546)
		(width 0.10668)
		(layer "F.Cu")
		(net "CPU1_SMERR_N")
	)
	(segment
		(start 78.355698 -137.90295)
		(end 89.342468 -126.91618)
		(width 0.10668)
		(layer "F.Cu")
		(net "CPU1_SMERR_N")
	)
	(segment
		(start 44.893484 -137.90295)
		(end 78.355698 -137.90295)
		(width 0.10668)
		(layer "F.Cu")
		(net "CPU1_SMERR_N")
	)
	(segment
		(start 14.099286 -317.924942)
		(end 14.099286 -207.116426)
		(width 0.10668)
		(layer "F.Cu")
		(net "CPU1_SMERR_N")
	)
	(segment
		(start 108.694474 -320.552572)
		(end 101.036374 -312.894472)
		(width 0.10668)
		(layer "F.Cu")
		(net "CPU1_SMERR_N")
	)
	(segment
		(start 79.628746 -299.95495)
		(end 77.628496 -301.9552)
		(width 0.10668)
		(layer "F.Cu")
		(net "CPU1_SMERR_N")
	)
	(segment
		(start 91.23045 -312.894472)
		(end 87.476076 -309.140098)
		(width 0.10668)
		(layer "F.Cu")
		(net "CPU1_SMERR_N")
	)
	(segment
		(start 142.379954 -313.636406)
		(end 143.425926 -314.682378)
		(width 0.10668)
		(layer "F.Cu")
		(net "CPU1_SMERR_N")
	)
	(segment
		(start 141.527276 -313.636406)
		(end 142.379954 -313.636406)
		(width 0.10668)
		(layer "F.Cu")
		(net "CPU1_SMERR_N")
	)
	(segment
		(start 16.179546 -320.005202)
		(end 14.099286 -317.924942)
		(width 0.10668)
		(layer "F.Cu")
		(net "CPU1_SMERR_N")
	)
	(segment
		(start 8.526272 -201.543412)
		(end 8.526272 -183.720232)
		(width 0.10668)
		(layer "F.Cu")
		(net "CPU1_SMERR_N")
	)
	(segment
		(start 76.651612 -307.29428)
		(end 74.280522 -309.66537)
		(width 0.10668)
		(layer "F.Cu")
		(net "CPU1_SMERR_N")
	)
	(segment
		(start 133.759448 -128.09347)
		(end 142.84579 -137.179812)
		(width 0.10668)
		(layer "F.Cu")
		(net "CPU1_SMERR_N")
	)
	(segment
		(start 14.099286 -207.116426)
		(end 8.526272 -201.543412)
		(width 0.10668)
		(layer "F.Cu")
		(net "CPU1_SMERR_N")
	)
	(segment
		(start 117.62994 -114.26698)
		(end 131.45643 -128.09347)
		(width 0.10668)
		(layer "F.Cu")
		(net "CPU1_SMERR_N")
	)
	(segment
		(start 89.342468 -124.304298)
		(end 99.379786 -114.26698)
		(width 0.10668)
		(layer "F.Cu")
		(net "CPU1_SMERR_N")
	)
	(segment
		(start 107.718098 -323.124576)
		(end 108.694474 -322.1482)
		(width 0.10668)
		(layer "F.Cu")
		(net "CPU1_SMERR_N")
	)
	(segment
		(start 8.526272 -183.720232)
		(end 18.721324 -173.52518)
		(width 0.10668)
		(layer "F.Cu")
		(net "CPU1_SMERR_N")
	)
	(segment
		(start 87.476076 -306.470558)
		(end 87.481156 -306.465478)
		(width 0.10668)
		(layer "F.Cu")
		(net "CPU1_SMERR_N")
	)
	(segment
		(start 99.379786 -114.26698)
		(end 117.62994 -114.26698)
		(width 0.10668)
		(layer "F.Cu")
		(net "CPU1_SMERR_N")
	)
	(segment
		(start 135.290306 -297.752262)
		(end 135.290306 -307.399436)
		(width 0.10668)
		(layer "F.Cu")
		(net "CPU1_SMERR_N")
	)
	(segment
		(start 89.342468 -126.91618)
		(end 89.342468 -124.304298)
		(width 0.10668)
		(layer "F.Cu")
		(net "CPU1_SMERR_N")
	)
	(segment
		(start 136.987788 -295.69029)
		(end 136.987788 -296.05478)
		(width 0.10668)
		(layer "F.Cu")
		(net "CPU1_SMERR_N")
	)
	(segment
		(start 87.476076 -309.140098)
		(end 87.476076 -306.470558)
		(width 0.10668)
		(layer "F.Cu")
		(net "CPU1_SMERR_N")
	)
	(segment
		(start 72.350884 -309.66537)
		(end 62.011052 -320.005202)
		(width 0.10668)
		(layer "F.Cu")
		(net "CPU1_SMERR_N")
	)
	(segment
		(start 142.84579 -137.179812)
		(end 164.996368 -137.179812)
		(width 0.10668)
		(layer "F.Cu")
		(net "CPU1_SMERR_N")
	)
	(segment
		(start 76.651612 -304.313844)
		(end 76.651612 -307.29428)
		(width 0.10668)
		(layer "F.Cu")
		(net "CPU1_SMERR_N")
	)
	(segment
		(start 108.694474 -322.1482)
		(end 108.694474 -320.552572)
		(width 0.10668)
		(layer "F.Cu")
		(net "CPU1_SMERR_N")
	)
	(segment
		(start 131.45643 -128.09347)
		(end 133.759448 -128.09347)
		(width 0.10668)
		(layer "F.Cu")
		(net "CPU1_SMERR_N")
	)
	(segment
		(start 101.036374 -312.894472)
		(end 91.23045 -312.894472)
		(width 0.10668)
		(layer "F.Cu")
		(net "CPU1_SMERR_N")
	)
	(segment
		(start 36.314126 -146.482308)
		(end 44.893484 -137.90295)
		(width 0.10668)
		(layer "F.Cu")
		(net "CPU1_SMERR_N")
	)
	(segment
		(start 74.280522 -309.66537)
		(end 72.350884 -309.66537)
		(width 0.10668)
		(layer "F.Cu")
		(net "CPU1_SMERR_N")
	)
	(segment
		(start 18.721324 -173.52518)
		(end 18.721324 -153.269696)
		(width 0.10668)
		(layer "F.Cu")
		(net "CPU1_SMERR_N")
	)
	(segment
		(start 62.011052 -320.005202)
		(end 16.179546 -320.005202)
		(width 0.10668)
		(layer "F.Cu")
		(net "CPU1_SMERR_N")
	)
	(segment
		(start 107.702096 -323.124576)
		(end 107.718098 -323.124576)
		(width 0.10668)
		(layer "F.Cu")
		(net "CPU1_SMERR_N")
	)
	(via
		(at 185.08853 -139.939522)
		(size 0.508)
		(drill 0.254)
		(layers "F.Cu" "B.Cu")
		(net "CPU1_SMERR_N")
	)
	(via
		(at 143.425926 -314.682378)
		(size 0.508)
		(drill 0.254)
		(layers "F.Cu" "B.Cu")
		(net "CPU1_SMERR_N")
	)
	(via
		(at 107.702096 -323.124576)
		(size 0.508)
		(drill 0.254)
		(layers "F.Cu" "B.Cu")
		(net "CPU1_SMERR_N")
	)
	(via
		(at 164.996368 -137.179812)
		(size 0.508)
		(drill 0.254)
		(layers "F.Cu" "B.Cu")
		(net "CPU1_SMERR_N")
	)
	(segment
		(start 143.834866 -314.49391)
		(end 143.646398 -314.682378)
		(width 0.10668)
		(layer "B.Cu")
		(net "CPU1_SMERR_N")
	)
	(segment
		(start 144.527524 -314.49391)
		(end 143.834866 -314.49391)
		(width 0.10668)
		(layer "B.Cu")
		(net "CPU1_SMERR_N")
	)
	(segment
		(start 187.638944 -137.404094)
		(end 187.638944 -136.359646)
		(width 0.10668)
		(layer "B.Cu")
		(net "CPU1_SMERR_N")
	)
	(segment
		(start 143.646398 -314.682378)
		(end 143.425926 -314.682378)
		(width 0.10668)
		(layer "B.Cu")
		(net "CPU1_SMERR_N")
	)
	(segment
		(start 187.627006 -131.802124)
		(end 187.627006 -131.407408)
		(width 0.10668)
		(layer "B.Cu")
		(net "CPU1_SMERR_N")
	)
	(segment
		(start 187.21705 -132.21208)
		(end 187.627006 -131.802124)
		(width 0.10668)
		(layer "B.Cu")
		(net "CPU1_SMERR_N")
	)
	(segment
		(start 185.08853 -139.939522)
		(end 186.080146 -139.939522)
		(width 0.10668)
		(layer "B.Cu")
		(net "CPU1_SMERR_N")
	)
	(segment
		(start 188.00699 -135.9916)
		(end 188.00699 -133.763004)
		(width 0.10668)
		(layer "B.Cu")
		(net "CPU1_SMERR_N")
	)
	(segment
		(start 187.638944 -136.359646)
		(end 188.00699 -135.9916)
		(width 0.10668)
		(layer "B.Cu")
		(net "CPU1_SMERR_N")
	)
	(segment
		(start 187.627006 -131.407408)
		(end 187.35294 -131.133342)
		(width 0.10668)
		(layer "B.Cu")
		(net "CPU1_SMERR_N")
	)
	(segment
		(start 187.35294 -131.133342)
		(end 187.35294 -130.868166)
		(width 0.10668)
		(layer "B.Cu")
		(net "CPU1_SMERR_N")
	)
	(segment
		(start 186.67984 -138.363198)
		(end 187.638944 -137.404094)
		(width 0.10668)
		(layer "B.Cu")
		(net "CPU1_SMERR_N")
	)
	(segment
		(start 188.00699 -133.763004)
		(end 187.21705 -132.973064)
		(width 0.10668)
		(layer "B.Cu")
		(net "CPU1_SMERR_N")
	)
	(segment
		(start 186.080146 -139.939522)
		(end 186.67984 -139.339828)
		(width 0.10668)
		(layer "B.Cu")
		(net "CPU1_SMERR_N")
	)
	(segment
		(start 186.67984 -139.339828)
		(end 186.67984 -138.363198)
		(width 0.10668)
		(layer "B.Cu")
		(net "CPU1_SMERR_N")
	)
	(segment
		(start 187.21705 -132.973064)
		(end 187.21705 -132.21208)
		(width 0.10668)
		(layer "B.Cu")
		(net "CPU1_SMERR_N")
	)
	(segment
		(start 142.491714 -314.49391)
		(end 134.068058 -322.917566)
		(width 0.11684)
		(layer "In2.Cu")
		(net "CPU1_SMERR_N")
	)
	(segment
		(start 143.237458 -314.49391)
		(end 142.491714 -314.49391)
		(width 0.11684)
		(layer "In2.Cu")
		(net "CPU1_SMERR_N")
	)
	(segment
		(start 164.338 -138.81481)
		(end 164.338 -137.83818)
		(width 0.11684)
		(layer "In2.Cu")
		(net "CPU1_SMERR_N")
	)
	(segment
		(start 143.425926 -314.682378)
		(end 143.237458 -314.49391)
		(width 0.11684)
		(layer "In2.Cu")
		(net "CPU1_SMERR_N")
	)
	(segment
		(start 108.047028 -323.124576)
		(end 107.702096 -323.124576)
		(width 0.11684)
		(layer "In2.Cu")
		(net "CPU1_SMERR_N")
	)
	(segment
		(start 179.975002 -140.257784)
		(end 165.780974 -140.257784)
		(width 0.11684)
		(layer "In2.Cu")
		(net "CPU1_SMERR_N")
	)
	(segment
		(start 180.293264 -139.939522)
		(end 179.975002 -140.257784)
		(width 0.11684)
		(layer "In2.Cu")
		(net "CPU1_SMERR_N")
	)
	(segment
		(start 165.780974 -140.257784)
		(end 164.338 -138.81481)
		(width 0.11684)
		(layer "In2.Cu")
		(net "CPU1_SMERR_N")
	)
	(segment
		(start 134.068058 -322.917566)
		(end 108.254038 -322.917566)
		(width 0.11684)
		(layer "In2.Cu")
		(net "CPU1_SMERR_N")
	)
	(segment
		(start 108.254038 -322.917566)
		(end 108.047028 -323.124576)
		(width 0.11684)
		(layer "In2.Cu")
		(net "CPU1_SMERR_N")
	)
	(segment
		(start 164.338 -137.83818)
		(end 164.996368 -137.179812)
		(width 0.11684)
		(layer "In2.Cu")
		(net "CPU1_SMERR_N")
	)
	(segment
		(start 185.08853 -139.939522)
		(end 180.293264 -139.939522)
		(width 0.11684)
		(layer "In2.Cu")
		(net "CPU1_SMERR_N")
	)
	(segment
		(start 67.808348 -135.795004)
		(end 43.462194 -135.795004)
		(width 0.10668)
		(layer "F.Cu")
		(net "CPU1_SLP_S5_N")
	)
	(segment
		(start 24.753316 -144.104868)
		(end 16.462248 -152.395936)
		(width 0.10668)
		(layer "F.Cu")
		(net "CPU1_SLP_S5_N")
	)
	(segment
		(start 35.15233 -144.104868)
		(end 24.753316 -144.104868)
		(width 0.10668)
		(layer "F.Cu")
		(net "CPU1_SLP_S5_N")
	)
	(segment
		(start 6.37286 -183.061356)
		(end 6.37286 -322.661788)
		(width 0.10668)
		(layer "F.Cu")
		(net "CPU1_SLP_S5_N")
	)
	(segment
		(start 6.37286 -322.661788)
		(end 13.574776 -329.863704)
		(width 0.10668)
		(layer "F.Cu")
		(net "CPU1_SLP_S5_N")
	)
	(segment
		(start 43.462194 -135.795004)
		(end 35.15233 -144.104868)
		(width 0.10668)
		(layer "F.Cu")
		(net "CPU1_SLP_S5_N")
	)
	(segment
		(start 177.927 -129.777998)
		(end 177.655474 -130.049524)
		(width 0.10668)
		(layer "F.Cu")
		(net "CPU1_SLP_S5_N")
	)
	(segment
		(start 70.750938 -132.852414)
		(end 67.808348 -135.795004)
		(width 0.10668)
		(layer "F.Cu")
		(net "CPU1_SLP_S5_N")
	)
	(segment
		(start 143.567912 -294.070278)
		(end 144.034764 -294.336216)
		(width 0.10668)
		(layer "F.Cu")
		(net "CPU1_SLP_S5_N")
	)
	(segment
		(start 16.462248 -152.395936)
		(end 16.462248 -172.971968)
		(width 0.10668)
		(layer "F.Cu")
		(net "CPU1_SLP_S5_N")
	)
	(segment
		(start 177.655474 -130.049524)
		(end 177.655474 -130.389376)
		(width 0.10668)
		(layer "F.Cu")
		(net "CPU1_SLP_S5_N")
	)
	(segment
		(start 13.574776 -329.863704)
		(end 13.995146 -329.863704)
		(width 0.10668)
		(layer "F.Cu")
		(net "CPU1_SLP_S5_N")
	)
	(segment
		(start 16.462248 -172.971968)
		(end 6.37286 -183.061356)
		(width 0.10668)
		(layer "F.Cu")
		(net "CPU1_SLP_S5_N")
	)
	(via
		(at 70.750938 -132.852414)
		(size 0.508)
		(drill 0.254)
		(layers "F.Cu" "B.Cu")
		(net "CPU1_SLP_S5_N")
	)
	(via
		(at 13.995146 -329.863704)
		(size 0.508)
		(drill 0.254)
		(layers "F.Cu" "B.Cu")
		(net "CPU1_SLP_S5_N")
	)
	(via
		(at 144.034764 -294.336216)
		(size 0.4064)
		(drill 0.2032)
		(layers "F.Cu" "B.Cu")
		(net "CPU1_SLP_S5_N")
	)
	(via
		(at 108.61421 -323.955918)
		(size 0.508)
		(drill 0.254)
		(layers "F.Cu" "B.Cu")
		(net "CPU1_SLP_S5_N")
	)
	(via
		(at 154.67076 -321.561714)
		(size 0.508)
		(drill 0.254)
		(layers "F.Cu" "B.Cu")
		(net "CPU1_SLP_S5_N")
	)
	(via
		(at 177.655474 -130.389376)
		(size 0.508)
		(drill 0.254)
		(layers "F.Cu" "B.Cu")
		(net "CPU1_SLP_S5_N")
	)
	(segment
		(start 61.567822 -325.932038)
		(end 61.567822 -321.904106)
		(width 0.10668)
		(layer "B.Cu")
		(net "CPU1_SLP_S5_N")
	)
	(segment
		(start 17.140682 -329.863704)
		(end 19.530822 -327.473564)
		(width 0.10668)
		(layer "B.Cu")
		(net "CPU1_SLP_S5_N")
	)
	(segment
		(start 155.751784 -321.814952)
		(end 155.40863 -321.814952)
		(width 0.10668)
		(layer "B.Cu")
		(net "CPU1_SLP_S5_N")
	)
	(segment
		(start 109.239812 -323.955918)
		(end 108.61421 -323.955918)
		(width 0.10668)
		(layer "B.Cu")
		(net "CPU1_SLP_S5_N")
	)
	(segment
		(start 60.026296 -327.473564)
		(end 61.567822 -325.932038)
		(width 0.10668)
		(layer "B.Cu")
		(net "CPU1_SLP_S5_N")
	)
	(segment
		(start 107.73029 -312.98261)
		(end 110.043468 -315.295788)
		(width 0.10668)
		(layer "B.Cu")
		(net "CPU1_SLP_S5_N")
	)
	(segment
		(start 155.155392 -321.561714)
		(end 154.67076 -321.561714)
		(width 0.10668)
		(layer "B.Cu")
		(net "CPU1_SLP_S5_N")
	)
	(segment
		(start 110.043468 -323.152262)
		(end 109.239812 -323.955918)
		(width 0.10668)
		(layer "B.Cu")
		(net "CPU1_SLP_S5_N")
	)
	(segment
		(start 61.567822 -321.904106)
		(end 69.960744 -313.511184)
		(width 0.10668)
		(layer "B.Cu")
		(net "CPU1_SLP_S5_N")
	)
	(segment
		(start 19.530822 -327.473564)
		(end 60.026296 -327.473564)
		(width 0.10668)
		(layer "B.Cu")
		(net "CPU1_SLP_S5_N")
	)
	(segment
		(start 93.71457 -313.511184)
		(end 94.243144 -312.98261)
		(width 0.10668)
		(layer "B.Cu")
		(net "CPU1_SLP_S5_N")
	)
	(segment
		(start 94.243144 -312.98261)
		(end 107.73029 -312.98261)
		(width 0.10668)
		(layer "B.Cu")
		(net "CPU1_SLP_S5_N")
	)
	(segment
		(start 110.043468 -315.295788)
		(end 110.043468 -323.152262)
		(width 0.10668)
		(layer "B.Cu")
		(net "CPU1_SLP_S5_N")
	)
	(segment
		(start 69.960744 -313.511184)
		(end 93.71457 -313.511184)
		(width 0.10668)
		(layer "B.Cu")
		(net "CPU1_SLP_S5_N")
	)
	(segment
		(start 13.995146 -329.863704)
		(end 17.140682 -329.863704)
		(width 0.10668)
		(layer "B.Cu")
		(net "CPU1_SLP_S5_N")
	)
	(segment
		(start 155.40863 -321.814952)
		(end 155.155392 -321.561714)
		(width 0.10668)
		(layer "B.Cu")
		(net "CPU1_SLP_S5_N")
	)
	(segment
		(start 154.67076 -322.168266)
		(end 154.67076 -321.561714)
		(width 0.11684)
		(layer "In2.Cu")
		(net "CPU1_SLP_S5_N")
	)
	(segment
		(start 146.895058 -323.955918)
		(end 147.336764 -324.397624)
		(width 0.11684)
		(layer "In2.Cu")
		(net "CPU1_SLP_S5_N")
	)
	(segment
		(start 108.61421 -323.955918)
		(end 146.895058 -323.955918)
		(width 0.11684)
		(layer "In2.Cu")
		(net "CPU1_SLP_S5_N")
	)
	(segment
		(start 152.441402 -324.397624)
		(end 154.67076 -322.168266)
		(width 0.11684)
		(layer "In2.Cu")
		(net "CPU1_SLP_S5_N")
	)
	(segment
		(start 147.336764 -324.397624)
		(end 152.441402 -324.397624)
		(width 0.11684)
		(layer "In2.Cu")
		(net "CPU1_SLP_S5_N")
	)
	(segment
		(start 112.705134 -128.36017)
		(end 113.172494 -127.89281)
		(width 0.11684)
		(layer "In6.Cu")
		(net "CPU1_SLP_S5_N")
	)
	(segment
		(start 170.82897 -130.389376)
		(end 177.655474 -130.389376)
		(width 0.11684)
		(layer "In6.Cu")
		(net "CPU1_SLP_S5_N")
	)
	(segment
		(start 160.913318 -130.211322)
		(end 161.389822 -129.734818)
		(width 0.11684)
		(layer "In6.Cu")
		(net "CPU1_SLP_S5_N")
	)
	(segment
		(start 159.144208 -130.211322)
		(end 160.913318 -130.211322)
		(width 0.11684)
		(layer "In6.Cu")
		(net "CPU1_SLP_S5_N")
	)
	(segment
		(start 162.869118 -129.765044)
		(end 170.204638 -129.765044)
		(width 0.11684)
		(layer "In6.Cu")
		(net "CPU1_SLP_S5_N")
	)
	(segment
		(start 75.983592 -127.18034)
		(end 108.928408 -127.18034)
		(width 0.11684)
		(layer "In6.Cu")
		(net "CPU1_SLP_S5_N")
	)
	(segment
		(start 70.750938 -132.852414)
		(end 70.750938 -132.412994)
		(width 0.11684)
		(layer "In6.Cu")
		(net "CPU1_SLP_S5_N")
	)
	(segment
		(start 108.928408 -127.18034)
		(end 110.108238 -128.36017)
		(width 0.11684)
		(layer "In6.Cu")
		(net "CPU1_SLP_S5_N")
	)
	(segment
		(start 162.838892 -129.734818)
		(end 162.869118 -129.765044)
		(width 0.11684)
		(layer "In6.Cu")
		(net "CPU1_SLP_S5_N")
	)
	(segment
		(start 170.204638 -129.765044)
		(end 170.82897 -130.389376)
		(width 0.11684)
		(layer "In6.Cu")
		(net "CPU1_SLP_S5_N")
	)
	(segment
		(start 161.389822 -129.734818)
		(end 162.838892 -129.734818)
		(width 0.11684)
		(layer "In6.Cu")
		(net "CPU1_SLP_S5_N")
	)
	(segment
		(start 70.750938 -132.412994)
		(end 75.983592 -127.18034)
		(width 0.11684)
		(layer "In6.Cu")
		(net "CPU1_SLP_S5_N")
	)
	(segment
		(start 110.108238 -128.36017)
		(end 112.705134 -128.36017)
		(width 0.11684)
		(layer "In6.Cu")
		(net "CPU1_SLP_S5_N")
	)
	(segment
		(start 157.612842 -128.679956)
		(end 159.144208 -130.211322)
		(width 0.11684)
		(layer "In6.Cu")
		(net "CPU1_SLP_S5_N")
	)
	(segment
		(start 114.312446 -127.89281)
		(end 115.099592 -128.679956)
		(width 0.11684)
		(layer "In6.Cu")
		(net "CPU1_SLP_S5_N")
	)
	(segment
		(start 113.172494 -127.89281)
		(end 114.312446 -127.89281)
		(width 0.11684)
		(layer "In6.Cu")
		(net "CPU1_SLP_S5_N")
	)
	(segment
		(start 115.099592 -128.679956)
		(end 157.612842 -128.679956)
		(width 0.11684)
		(layer "In6.Cu")
		(net "CPU1_SLP_S5_N")
	)
	(segment
		(start 143.103854 -294.997632)
		(end 143.103854 -295.990772)
		(width 0.11684)
		(layer "In11.Cu")
		(net "CPU1_SLP_S5_N")
	)
	(segment
		(start 156.708094 -314.847732)
		(end 156.708094 -320.186812)
		(width 0.11684)
		(layer "In11.Cu")
		(net "CPU1_SLP_S5_N")
	)
	(segment
		(start 143.878554 -302.018192)
		(end 156.708094 -314.847732)
		(width 0.11684)
		(layer "In11.Cu")
		(net "CPU1_SLP_S5_N")
	)
	(segment
		(start 143.103854 -295.990772)
		(end 143.878554 -296.765472)
		(width 0.11684)
		(layer "In11.Cu")
		(net "CPU1_SLP_S5_N")
	)
	(segment
		(start 155.333192 -321.561714)
		(end 154.67076 -321.561714)
		(width 0.11684)
		(layer "In11.Cu")
		(net "CPU1_SLP_S5_N")
	)
	(segment
		(start 156.708094 -320.186812)
		(end 155.333192 -321.561714)
		(width 0.11684)
		(layer "In11.Cu")
		(net "CPU1_SLP_S5_N")
	)
	(segment
		(start 144.034764 -294.336216)
		(end 143.76527 -294.336216)
		(width 0.11684)
		(layer "In11.Cu")
		(net "CPU1_SLP_S5_N")
	)
	(segment
		(start 143.878554 -296.765472)
		(end 143.878554 -302.018192)
		(width 0.11684)
		(layer "In11.Cu")
		(net "CPU1_SLP_S5_N")
	)
	(segment
		(start 143.76527 -294.336216)
		(end 143.103854 -294.997632)
		(width 0.11684)
		(layer "In11.Cu")
		(net "CPU1_SLP_S5_N")
	)
	(segment
		(start 156.99486 -313.514486)
		(end 156.99486 -320.323718)
		(width 0.10668)
		(layer "F.Cu")
		(net "CPU1_SLP_S3_N")
	)
	(segment
		(start 163.14674 -136.086342)
		(end 157.291532 -136.086342)
		(width 0.10668)
		(layer "F.Cu")
		(net "CPU1_SLP_S3_N")
	)
	(segment
		(start 99.152456 -112.858042)
		(end 88.333072 -123.677426)
		(width 0.10668)
		(layer "F.Cu")
		(net "CPU1_SLP_S3_N")
	)
	(segment
		(start 156.99486 -320.323718)
		(end 156.360114 -320.958464)
		(width 0.10668)
		(layer "F.Cu")
		(net "CPU1_SLP_S3_N")
	)
	(segment
		(start 156.429202 -135.224012)
		(end 142.993618 -135.224012)
		(width 0.10668)
		(layer "F.Cu")
		(net "CPU1_SLP_S3_N")
	)
	(segment
		(start 88.333072 -123.677426)
		(end 88.333072 -126.38786)
		(width 0.10668)
		(layer "F.Cu")
		(net "CPU1_SLP_S3_N")
	)
	(segment
		(start 35.682174 -145.349468)
		(end 25.223216 -145.349468)
		(width 0.10668)
		(layer "F.Cu")
		(net "CPU1_SLP_S3_N")
	)
	(segment
		(start 176.911 -129.777998)
		(end 176.911 -131.748276)
		(width 0.10668)
		(layer "F.Cu")
		(net "CPU1_SLP_S3_N")
	)
	(segment
		(start 117.59565 -112.858042)
		(end 99.152456 -112.858042)
		(width 0.10668)
		(layer "F.Cu")
		(net "CPU1_SLP_S3_N")
	)
	(segment
		(start 176.304194 -132.355082)
		(end 176.304194 -136.621774)
		(width 0.10668)
		(layer "F.Cu")
		(net "CPU1_SLP_S3_N")
	)
	(segment
		(start 17.652238 -173.283626)
		(end 7.492492 -183.443372)
		(width 0.10668)
		(layer "F.Cu")
		(net "CPU1_SLP_S3_N")
	)
	(segment
		(start 88.333072 -126.38786)
		(end 77.836776 -136.884156)
		(width 0.10668)
		(layer "F.Cu")
		(net "CPU1_SLP_S3_N")
	)
	(segment
		(start 131.72186 -126.984252)
		(end 117.59565 -112.858042)
		(width 0.10668)
		(layer "F.Cu")
		(net "CPU1_SLP_S3_N")
	)
	(segment
		(start 7.492492 -202.063096)
		(end 13.070586 -207.64119)
		(width 0.10668)
		(layer "F.Cu")
		(net "CPU1_SLP_S3_N")
	)
	(segment
		(start 25.223216 -145.349468)
		(end 17.652238 -152.920446)
		(width 0.10668)
		(layer "F.Cu")
		(net "CPU1_SLP_S3_N")
	)
	(segment
		(start 13.070586 -327.099168)
		(end 13.549122 -327.577704)
		(width 0.10668)
		(layer "F.Cu")
		(net "CPU1_SLP_S3_N")
	)
	(segment
		(start 17.652238 -152.920446)
		(end 17.652238 -173.283626)
		(width 0.10668)
		(layer "F.Cu")
		(net "CPU1_SLP_S3_N")
	)
	(segment
		(start 13.549122 -327.577704)
		(end 13.995146 -327.577704)
		(width 0.10668)
		(layer "F.Cu")
		(net "CPU1_SLP_S3_N")
	)
	(segment
		(start 77.836776 -136.884156)
		(end 44.147486 -136.884156)
		(width 0.10668)
		(layer "F.Cu")
		(net "CPU1_SLP_S3_N")
	)
	(segment
		(start 44.147486 -136.884156)
		(end 35.682174 -145.349468)
		(width 0.10668)
		(layer "F.Cu")
		(net "CPU1_SLP_S3_N")
	)
	(segment
		(start 176.911 -131.748276)
		(end 176.304194 -132.355082)
		(width 0.10668)
		(layer "F.Cu")
		(net "CPU1_SLP_S3_N")
	)
	(segment
		(start 157.291532 -136.086342)
		(end 156.429202 -135.224012)
		(width 0.10668)
		(layer "F.Cu")
		(net "CPU1_SLP_S3_N")
	)
	(segment
		(start 142.627858 -299.147484)
		(end 156.99486 -313.514486)
		(width 0.10668)
		(layer "F.Cu")
		(net "CPU1_SLP_S3_N")
	)
	(segment
		(start 7.492492 -183.443372)
		(end 7.492492 -202.063096)
		(width 0.10668)
		(layer "F.Cu")
		(net "CPU1_SLP_S3_N")
	)
	(segment
		(start 142.993618 -135.224012)
		(end 134.753858 -126.984252)
		(width 0.10668)
		(layer "F.Cu")
		(net "CPU1_SLP_S3_N")
	)
	(segment
		(start 156.360114 -320.958464)
		(end 156.360114 -325.637652)
		(width 0.10668)
		(layer "F.Cu")
		(net "CPU1_SLP_S3_N")
	)
	(segment
		(start 13.070586 -207.64119)
		(end 13.070586 -327.099168)
		(width 0.10668)
		(layer "F.Cu")
		(net "CPU1_SLP_S3_N")
	)
	(segment
		(start 134.753858 -126.984252)
		(end 131.72186 -126.984252)
		(width 0.10668)
		(layer "F.Cu")
		(net "CPU1_SLP_S3_N")
	)
	(segment
		(start 142.627858 -295.69029)
		(end 142.627858 -299.147484)
		(width 0.10668)
		(layer "F.Cu")
		(net "CPU1_SLP_S3_N")
	)
	(via
		(at 156.360114 -325.637652)
		(size 0.508)
		(drill 0.254)
		(layers "F.Cu" "B.Cu")
		(net "CPU1_SLP_S3_N")
	)
	(via
		(at 176.304194 -136.621774)
		(size 0.508)
		(drill 0.254)
		(layers "F.Cu" "B.Cu")
		(net "CPU1_SLP_S3_N")
	)
	(via
		(at 163.14674 -136.086342)
		(size 0.508)
		(drill 0.254)
		(layers "F.Cu" "B.Cu")
		(net "CPU1_SLP_S3_N")
	)
	(via
		(at 108.61421 -325.860918)
		(size 0.508)
		(drill 0.254)
		(layers "F.Cu" "B.Cu")
		(net "CPU1_SLP_S3_N")
	)
	(via
		(at 13.995146 -327.577704)
		(size 0.508)
		(drill 0.254)
		(layers "F.Cu" "B.Cu")
		(net "CPU1_SLP_S3_N")
	)
	(segment
		(start 155.754324 -325.031862)
		(end 156.360114 -325.637652)
		(width 0.10668)
		(layer "B.Cu")
		(net "CPU1_SLP_S3_N")
	)
	(segment
		(start 111.151924 -314.892944)
		(end 111.151924 -324.470522)
		(width 0.10668)
		(layer "B.Cu")
		(net "CPU1_SLP_S3_N")
	)
	(segment
		(start 155.754324 -324.781672)
		(end 155.754324 -325.031862)
		(width 0.10668)
		(layer "B.Cu")
		(net "CPU1_SLP_S3_N")
	)
	(segment
		(start 15.201138 -326.371712)
		(end 59.387486 -326.371712)
		(width 0.10668)
		(layer "B.Cu")
		(net "CPU1_SLP_S3_N")
	)
	(segment
		(start 109.761528 -325.860918)
		(end 108.61421 -325.860918)
		(width 0.10668)
		(layer "B.Cu")
		(net "CPU1_SLP_S3_N")
	)
	(segment
		(start 60.34532 -325.413878)
		(end 60.34532 -321.639184)
		(width 0.10668)
		(layer "B.Cu")
		(net "CPU1_SLP_S3_N")
	)
	(segment
		(start 111.151924 -324.470522)
		(end 109.761528 -325.860918)
		(width 0.10668)
		(layer "B.Cu")
		(net "CPU1_SLP_S3_N")
	)
	(segment
		(start 108.23575 -311.97677)
		(end 111.151924 -314.892944)
		(width 0.10668)
		(layer "B.Cu")
		(net "CPU1_SLP_S3_N")
	)
	(segment
		(start 69.524372 -312.460132)
		(end 93.342714 -312.460132)
		(width 0.10668)
		(layer "B.Cu")
		(net "CPU1_SLP_S3_N")
	)
	(segment
		(start 93.826076 -311.97677)
		(end 108.23575 -311.97677)
		(width 0.10668)
		(layer "B.Cu")
		(net "CPU1_SLP_S3_N")
	)
	(segment
		(start 60.34532 -321.639184)
		(end 69.524372 -312.460132)
		(width 0.10668)
		(layer "B.Cu")
		(net "CPU1_SLP_S3_N")
	)
	(segment
		(start 13.995146 -327.577704)
		(end 15.201138 -326.371712)
		(width 0.10668)
		(layer "B.Cu")
		(net "CPU1_SLP_S3_N")
	)
	(segment
		(start 59.387486 -326.371712)
		(end 60.34532 -325.413878)
		(width 0.10668)
		(layer "B.Cu")
		(net "CPU1_SLP_S3_N")
	)
	(segment
		(start 93.342714 -312.460132)
		(end 93.826076 -311.97677)
		(width 0.10668)
		(layer "B.Cu")
		(net "CPU1_SLP_S3_N")
	)
	(segment
		(start 109.34192 -325.717408)
		(end 155.78709 -325.717408)
		(width 0.11684)
		(layer "In2.Cu")
		(net "CPU1_SLP_S3_N")
	)
	(segment
		(start 155.78709 -325.717408)
		(end 155.866846 -325.637652)
		(width 0.11684)
		(layer "In2.Cu")
		(net "CPU1_SLP_S3_N")
	)
	(segment
		(start 176.304194 -136.621774)
		(end 175.638968 -137.287)
		(width 0.11684)
		(layer "In2.Cu")
		(net "CPU1_SLP_S3_N")
	)
	(segment
		(start 165.631368 -135.323834)
		(end 163.909248 -135.323834)
		(width 0.11684)
		(layer "In2.Cu")
		(net "CPU1_SLP_S3_N")
	)
	(segment
		(start 155.866846 -325.637652)
		(end 156.360114 -325.637652)
		(width 0.11684)
		(layer "In2.Cu")
		(net "CPU1_SLP_S3_N")
	)
	(segment
		(start 109.19841 -325.860918)
		(end 109.34192 -325.717408)
		(width 0.11684)
		(layer "In2.Cu")
		(net "CPU1_SLP_S3_N")
	)
	(segment
		(start 175.638968 -137.287)
		(end 167.594534 -137.287)
		(width 0.11684)
		(layer "In2.Cu")
		(net "CPU1_SLP_S3_N")
	)
	(segment
		(start 163.909248 -135.323834)
		(end 163.14674 -136.086342)
		(width 0.11684)
		(layer "In2.Cu")
		(net "CPU1_SLP_S3_N")
	)
	(segment
		(start 108.61421 -325.860918)
		(end 109.19841 -325.860918)
		(width 0.11684)
		(layer "In2.Cu")
		(net "CPU1_SLP_S3_N")
	)
	(segment
		(start 167.594534 -137.287)
		(end 165.631368 -135.323834)
		(width 0.11684)
		(layer "In2.Cu")
		(net "CPU1_SLP_S3_N")
	)
	(segment
		(start 195.625466 -95.95612)
		(end 195.625466 -94.82074)
		(width 0.10668)
		(layer "F.Cu")
		(net "CPU1_SA1")
	)
	(segment
		(start 195.964048 -98.262948)
		(end 196.1515 -98.075496)
		(width 0.10668)
		(layer "F.Cu")
		(net "CPU1_SA1")
	)
	(segment
		(start 189.347856 -93.924628)
		(end 189.347856 -92.163646)
		(width 0.10668)
		(layer "F.Cu")
		(net "CPU1_SA1")
	)
	(segment
		(start 189.619128 -94.1959)
		(end 189.347856 -93.924628)
		(width 0.10668)
		(layer "F.Cu")
		(net "CPU1_SA1")
	)
	(segment
		(start 163.65347 -93.855794)
		(end 163.65347 -98.453194)
		(width 0.10668)
		(layer "F.Cu")
		(net "CPU1_SA1")
	)
	(segment
		(start 167.367712 -90.141552)
		(end 163.65347 -93.855794)
		(width 0.10668)
		(layer "F.Cu")
		(net "CPU1_SA1")
	)
	(segment
		(start 195.000626 -94.1959)
		(end 189.619128 -94.1959)
		(width 0.10668)
		(layer "F.Cu")
		(net "CPU1_SA1")
	)
	(segment
		(start 196.1515 -96.482154)
		(end 195.625466 -95.95612)
		(width 0.10668)
		(layer "F.Cu")
		(net "CPU1_SA1")
	)
	(segment
		(start 195.625466 -94.82074)
		(end 195.000626 -94.1959)
		(width 0.10668)
		(layer "F.Cu")
		(net "CPU1_SA1")
	)
	(segment
		(start 189.347856 -92.163646)
		(end 187.325762 -90.141552)
		(width 0.10668)
		(layer "F.Cu")
		(net "CPU1_SA1")
	)
	(segment
		(start 196.1515 -98.075496)
		(end 196.1515 -96.482154)
		(width 0.10668)
		(layer "F.Cu")
		(net "CPU1_SA1")
	)
	(segment
		(start 95.627952 -295.69029)
		(end 95.1611 -295.956228)
		(width 0.10668)
		(layer "F.Cu")
		(net "CPU1_SA1")
	)
	(segment
		(start 163.65347 -98.453194)
		(end 163.224718 -98.881946)
		(width 0.10668)
		(layer "F.Cu")
		(net "CPU1_SA1")
	)
	(segment
		(start 187.325762 -90.141552)
		(end 167.367712 -90.141552)
		(width 0.10668)
		(layer "F.Cu")
		(net "CPU1_SA1")
	)
	(via
		(at 195.964048 -98.262948)
		(size 0.508)
		(drill 0.254)
		(layers "F.Cu" "B.Cu")
		(net "CPU1_SA1")
	)
	(via
		(at 163.224718 -98.881946)
		(size 0.508)
		(drill 0.254)
		(layers "F.Cu" "B.Cu")
		(net "CPU1_SA1")
	)
	(via
		(at 95.1611 -295.956228)
		(size 0.4064)
		(drill 0.2032)
		(layers "F.Cu" "B.Cu")
		(net "CPU1_SA1")
	)
	(segment
		(start 195.83019 -98.262948)
		(end 195.964048 -98.262948)
		(width 0.10668)
		(layer "B.Cu")
		(net "CPU1_SA1")
	)
	(segment
		(start 95.1611 -298.249594)
		(end 95.1611 -295.956228)
		(width 0.10668)
		(layer "B.Cu")
		(net "CPU1_SA1")
	)
	(segment
		(start 83.10499 -299.569378)
		(end 78.472538 -299.569378)
		(width 0.10668)
		(layer "B.Cu")
		(net "CPU1_SA1")
	)
	(segment
		(start 38.380162 -161.990786)
		(end 38.380162 -161.985706)
		(width 0.10668)
		(layer "B.Cu")
		(net "CPU1_SA1")
	)
	(segment
		(start 143.158464 -116.55552)
		(end 146.867372 -116.55552)
		(width 0.10668)
		(layer "B.Cu")
		(net "CPU1_SA1")
	)
	(segment
		(start 38.380162 -161.985706)
		(end 41.84396 -158.521908)
		(width 0.10668)
		(layer "B.Cu")
		(net "CPU1_SA1")
	)
	(segment
		(start 84.619338 -301.083726)
		(end 83.10499 -299.569378)
		(width 0.10668)
		(layer "B.Cu")
		(net "CPU1_SA1")
	)
	(segment
		(start 91.093544 -302.052736)
		(end 89.459308 -303.686972)
		(width 0.10668)
		(layer "B.Cu")
		(net "CPU1_SA1")
	)
	(segment
		(start 159.597598 -106.254804)
		(end 161.360866 -106.254804)
		(width 0.10668)
		(layer "B.Cu")
		(net "CPU1_SA1")
	)
	(segment
		(start 84.619338 -302.735742)
		(end 84.619338 -301.083726)
		(width 0.10668)
		(layer "B.Cu")
		(net "CPU1_SA1")
	)
	(segment
		(start 69.426328 -117.240812)
		(end 142.473172 -117.240812)
		(width 0.10668)
		(layer "B.Cu")
		(net "CPU1_SA1")
	)
	(segment
		(start 55.877206 -321.324224)
		(end 17.394936 -321.324224)
		(width 0.10668)
		(layer "B.Cu")
		(net "CPU1_SA1")
	)
	(segment
		(start 148.16709 -115.255802)
		(end 148.16709 -113.13922)
		(width 0.10668)
		(layer "B.Cu")
		(net "CPU1_SA1")
	)
	(segment
		(start 195.429378 -99.714812)
		(end 195.429378 -98.66376)
		(width 0.10668)
		(layer "B.Cu")
		(net "CPU1_SA1")
	)
	(segment
		(start 91.40952 -300.876208)
		(end 92.534486 -300.876208)
		(width 0.10668)
		(layer "B.Cu")
		(net "CPU1_SA1")
	)
	(segment
		(start 148.743416 -112.562894)
		(end 152.002744 -112.562894)
		(width 0.10668)
		(layer "B.Cu")
		(net "CPU1_SA1")
	)
	(segment
		(start 91.116912 -301.168816)
		(end 91.40952 -300.876208)
		(width 0.10668)
		(layer "B.Cu")
		(net "CPU1_SA1")
	)
	(segment
		(start 84.883752 -303.374044)
		(end 84.619338 -302.735742)
		(width 0.10668)
		(layer "B.Cu")
		(net "CPU1_SA1")
	)
	(segment
		(start 157.540706 -108.311696)
		(end 159.597598 -106.254804)
		(width 0.10668)
		(layer "B.Cu")
		(net "CPU1_SA1")
	)
	(segment
		(start 163.224718 -104.390952)
		(end 163.224718 -98.881946)
		(width 0.10668)
		(layer "B.Cu")
		(net "CPU1_SA1")
	)
	(segment
		(start 194.945 -99.894898)
		(end 195.249292 -99.894898)
		(width 0.10668)
		(layer "B.Cu")
		(net "CPU1_SA1")
	)
	(segment
		(start 152.002744 -112.562894)
		(end 156.253942 -108.311696)
		(width 0.10668)
		(layer "B.Cu")
		(net "CPU1_SA1")
	)
	(segment
		(start 12.887198 -187.48375)
		(end 38.380162 -161.990786)
		(width 0.10668)
		(layer "B.Cu")
		(net "CPU1_SA1")
	)
	(segment
		(start 195.249292 -99.894898)
		(end 195.429378 -99.714812)
		(width 0.10668)
		(layer "B.Cu")
		(net "CPU1_SA1")
	)
	(segment
		(start 17.394936 -321.324224)
		(end 15.394178 -323.324982)
		(width 0.10668)
		(layer "B.Cu")
		(net "CPU1_SA1")
	)
	(segment
		(start 41.84396 -158.521908)
		(end 41.84396 -144.82318)
		(width 0.10668)
		(layer "B.Cu")
		(net "CPU1_SA1")
	)
	(segment
		(start 59.32424 -318.717676)
		(end 58.483754 -318.717676)
		(width 0.10668)
		(layer "B.Cu")
		(net "CPU1_SA1")
	)
	(segment
		(start 89.459308 -303.686972)
		(end 85.19668 -303.686972)
		(width 0.10668)
		(layer "B.Cu")
		(net "CPU1_SA1")
	)
	(segment
		(start 12.887198 -322.198238)
		(end 12.887198 -187.48375)
		(width 0.10668)
		(layer "B.Cu")
		(net "CPU1_SA1")
	)
	(segment
		(start 142.473172 -117.240812)
		(end 143.158464 -116.55552)
		(width 0.10668)
		(layer "B.Cu")
		(net "CPU1_SA1")
	)
	(segment
		(start 15.394178 -323.324982)
		(end 14.013942 -323.324982)
		(width 0.10668)
		(layer "B.Cu")
		(net "CPU1_SA1")
	)
	(segment
		(start 148.16709 -113.13922)
		(end 148.743416 -112.562894)
		(width 0.10668)
		(layer "B.Cu")
		(net "CPU1_SA1")
	)
	(segment
		(start 91.093544 -301.716948)
		(end 91.116912 -301.69358)
		(width 0.10668)
		(layer "B.Cu")
		(net "CPU1_SA1")
	)
	(segment
		(start 14.013942 -323.324982)
		(end 12.887198 -322.198238)
		(width 0.10668)
		(layer "B.Cu")
		(net "CPU1_SA1")
	)
	(segment
		(start 156.253942 -108.311696)
		(end 157.540706 -108.311696)
		(width 0.10668)
		(layer "B.Cu")
		(net "CPU1_SA1")
	)
	(segment
		(start 92.534486 -300.876208)
		(end 95.1611 -298.249594)
		(width 0.10668)
		(layer "B.Cu")
		(net "CPU1_SA1")
	)
	(segment
		(start 78.472538 -299.569378)
		(end 59.32424 -318.717676)
		(width 0.10668)
		(layer "B.Cu")
		(net "CPU1_SA1")
	)
	(segment
		(start 161.360866 -106.254804)
		(end 163.224718 -104.390952)
		(width 0.10668)
		(layer "B.Cu")
		(net "CPU1_SA1")
	)
	(segment
		(start 146.867372 -116.55552)
		(end 148.16709 -115.255802)
		(width 0.10668)
		(layer "B.Cu")
		(net "CPU1_SA1")
	)
	(segment
		(start 91.116912 -301.69358)
		(end 91.116912 -301.168816)
		(width 0.10668)
		(layer "B.Cu")
		(net "CPU1_SA1")
	)
	(segment
		(start 195.429378 -98.66376)
		(end 195.83019 -98.262948)
		(width 0.10668)
		(layer "B.Cu")
		(net "CPU1_SA1")
	)
	(segment
		(start 58.483754 -318.717676)
		(end 55.877206 -321.324224)
		(width 0.10668)
		(layer "B.Cu")
		(net "CPU1_SA1")
	)
	(segment
		(start 41.84396 -144.82318)
		(end 69.426328 -117.240812)
		(width 0.10668)
		(layer "B.Cu")
		(net "CPU1_SA1")
	)
	(segment
		(start 85.19668 -303.686972)
		(end 84.883752 -303.374044)
		(width 0.10668)
		(layer "B.Cu")
		(net "CPU1_SA1")
	)
	(segment
		(start 91.093544 -301.716948)
		(end 91.093544 -302.052736)
		(width 0.10668)
		(layer "B.Cu")
		(net "CPU1_SA1")
	)
	(segment
		(start 161.877756 -99.99472)
		(end 162.85718 -99.99472)
		(width 0.10668)
		(layer "F.Cu")
		(net "CPU1_SA0")
	)
	(segment
		(start 96.568006 -295.69029)
		(end 96.101154 -295.956228)
		(width 0.10668)
		(layer "F.Cu")
		(net "CPU1_SA0")
	)
	(segment
		(start 164.01161 -94.227142)
		(end 167.73652 -90.502232)
		(width 0.10668)
		(layer "F.Cu")
		(net "CPU1_SA0")
	)
	(segment
		(start 162.85718 -99.99472)
		(end 164.01161 -98.84029)
		(width 0.10668)
		(layer "F.Cu")
		(net "CPU1_SA0")
	)
	(segment
		(start 167.73652 -90.502232)
		(end 186.773566 -90.502232)
		(width 0.10668)
		(layer "F.Cu")
		(net "CPU1_SA0")
	)
	(segment
		(start 188.786008 -94.508828)
		(end 193.623692 -94.508828)
		(width 0.10668)
		(layer "F.Cu")
		(net "CPU1_SA0")
	)
	(segment
		(start 193.623692 -94.508828)
		(end 194.140074 -95.02521)
		(width 0.10668)
		(layer "F.Cu")
		(net "CPU1_SA0")
	)
	(segment
		(start 186.773566 -90.502232)
		(end 188.329316 -92.057982)
		(width 0.10668)
		(layer "F.Cu")
		(net "CPU1_SA0")
	)
	(segment
		(start 188.329316 -92.057982)
		(end 188.329316 -94.052136)
		(width 0.10668)
		(layer "F.Cu")
		(net "CPU1_SA0")
	)
	(segment
		(start 164.01161 -98.84029)
		(end 164.01161 -94.227142)
		(width 0.10668)
		(layer "F.Cu")
		(net "CPU1_SA0")
	)
	(segment
		(start 188.329316 -94.052136)
		(end 188.786008 -94.508828)
		(width 0.10668)
		(layer "F.Cu")
		(net "CPU1_SA0")
	)
	(segment
		(start 194.140074 -95.02521)
		(end 194.140074 -95.097854)
		(width 0.10668)
		(layer "F.Cu")
		(net "CPU1_SA0")
	)
	(via
		(at 161.877756 -99.99472)
		(size 0.508)
		(drill 0.254)
		(layers "F.Cu" "B.Cu")
		(net "CPU1_SA0")
	)
	(via
		(at 96.101154 -295.956228)
		(size 0.4064)
		(drill 0.2032)
		(layers "F.Cu" "B.Cu")
		(net "CPU1_SA0")
	)
	(via
		(at 194.140074 -95.097854)
		(size 0.508)
		(drill 0.254)
		(layers "F.Cu" "B.Cu")
		(net "CPU1_SA0")
	)
	(segment
		(start 93.091 -300.827694)
		(end 93.091 -302.26635)
		(width 0.10668)
		(layer "B.Cu")
		(net "CPU1_SA0")
	)
	(segment
		(start 12.594336 -322.349114)
		(end 13.883894 -323.638672)
		(width 0.10668)
		(layer "B.Cu")
		(net "CPU1_SA0")
	)
	(segment
		(start 56.007254 -321.637914)
		(end 58.613802 -319.031366)
		(width 0.10668)
		(layer "B.Cu")
		(net "CPU1_SA0")
	)
	(segment
		(start 41.53027 -144.693132)
		(end 41.53027 -158.39186)
		(width 0.10668)
		(layer "B.Cu")
		(net "CPU1_SA0")
	)
	(segment
		(start 161.678112 -104.459532)
		(end 160.44164 -104.459532)
		(width 0.10668)
		(layer "B.Cu")
		(net "CPU1_SA0")
	)
	(segment
		(start 95.74276 -297.118532)
		(end 95.74276 -298.175934)
		(width 0.10668)
		(layer "B.Cu")
		(net "CPU1_SA0")
	)
	(segment
		(start 160.44164 -104.459532)
		(end 157.1371 -107.764072)
		(width 0.10668)
		(layer "B.Cu")
		(net "CPU1_SA0")
	)
	(segment
		(start 162.004502 -100.121466)
		(end 162.004502 -101.002846)
		(width 0.10668)
		(layer "B.Cu")
		(net "CPU1_SA0")
	)
	(segment
		(start 162.004502 -101.002846)
		(end 162.836098 -101.834442)
		(width 0.10668)
		(layer "B.Cu")
		(net "CPU1_SA0")
	)
	(segment
		(start 147.821396 -115.091718)
		(end 146.755104 -116.15801)
		(width 0.10668)
		(layer "B.Cu")
		(net "CPU1_SA0")
	)
	(segment
		(start 96.101154 -296.760138)
		(end 95.74276 -297.118532)
		(width 0.10668)
		(layer "B.Cu")
		(net "CPU1_SA0")
	)
	(segment
		(start 59.450732 -319.031366)
		(end 68.406772 -310.075326)
		(width 0.10668)
		(layer "B.Cu")
		(net "CPU1_SA0")
	)
	(segment
		(start 95.74276 -298.175934)
		(end 93.091 -300.827694)
		(width 0.10668)
		(layer "B.Cu")
		(net "CPU1_SA0")
	)
	(segment
		(start 162.836098 -103.301546)
		(end 161.678112 -104.459532)
		(width 0.10668)
		(layer "B.Cu")
		(net "CPU1_SA0")
	)
	(segment
		(start 96.101154 -295.956228)
		(end 96.101154 -296.760138)
		(width 0.10668)
		(layer "B.Cu")
		(net "CPU1_SA0")
	)
	(segment
		(start 151.636984 -112.249204)
		(end 148.570442 -112.249204)
		(width 0.10668)
		(layer "B.Cu")
		(net "CPU1_SA0")
	)
	(segment
		(start 142.86357 -116.15801)
		(end 142.094458 -116.927122)
		(width 0.10668)
		(layer "B.Cu")
		(net "CPU1_SA0")
	)
	(segment
		(start 87.023702 -306.662582)
		(end 87.023702 -305.53914)
		(width 0.10668)
		(layer "B.Cu")
		(net "CPU1_SA0")
	)
	(segment
		(start 91.093544 -302.854106)
		(end 91.093544 -303.255172)
		(width 0.10668)
		(layer "B.Cu")
		(net "CPU1_SA0")
	)
	(segment
		(start 147.821396 -112.99825)
		(end 147.821396 -115.091718)
		(width 0.10668)
		(layer "B.Cu")
		(net "CPU1_SA0")
	)
	(segment
		(start 146.755104 -116.15801)
		(end 142.86357 -116.15801)
		(width 0.10668)
		(layer "B.Cu")
		(net "CPU1_SA0")
	)
	(segment
		(start 91.230196 -302.717454)
		(end 91.093544 -302.854106)
		(width 0.10668)
		(layer "B.Cu")
		(net "CPU1_SA0")
	)
	(segment
		(start 142.094458 -116.927122)
		(end 69.29628 -116.927122)
		(width 0.10668)
		(layer "B.Cu")
		(net "CPU1_SA0")
	)
	(segment
		(start 13.883894 -323.638672)
		(end 15.531338 -323.638672)
		(width 0.10668)
		(layer "B.Cu")
		(net "CPU1_SA0")
	)
	(segment
		(start 38.066472 -161.860738)
		(end 12.594336 -187.332874)
		(width 0.10668)
		(layer "B.Cu")
		(net "CPU1_SA0")
	)
	(segment
		(start 87.023702 -305.53914)
		(end 88.237568 -304.325274)
		(width 0.10668)
		(layer "B.Cu")
		(net "CPU1_SA0")
	)
	(segment
		(start 162.836098 -101.834442)
		(end 162.836098 -103.301546)
		(width 0.10668)
		(layer "B.Cu")
		(net "CPU1_SA0")
	)
	(segment
		(start 38.066472 -161.855658)
		(end 38.066472 -161.860738)
		(width 0.10668)
		(layer "B.Cu")
		(net "CPU1_SA0")
	)
	(segment
		(start 12.594336 -187.332874)
		(end 12.594336 -322.349114)
		(width 0.10668)
		(layer "B.Cu")
		(net "CPU1_SA0")
	)
	(segment
		(start 41.53027 -158.39186)
		(end 38.066472 -161.855658)
		(width 0.10668)
		(layer "B.Cu")
		(net "CPU1_SA0")
	)
	(segment
		(start 92.639896 -302.717454)
		(end 91.230196 -302.717454)
		(width 0.10668)
		(layer "B.Cu")
		(net "CPU1_SA0")
	)
	(segment
		(start 83.610958 -310.075326)
		(end 87.023702 -306.662582)
		(width 0.10668)
		(layer "B.Cu")
		(net "CPU1_SA0")
	)
	(segment
		(start 148.570442 -112.249204)
		(end 147.821396 -112.99825)
		(width 0.10668)
		(layer "B.Cu")
		(net "CPU1_SA0")
	)
	(segment
		(start 161.877756 -99.99472)
		(end 162.004502 -100.121466)
		(width 0.10668)
		(layer "B.Cu")
		(net "CPU1_SA0")
	)
	(segment
		(start 194.140074 -96.508824)
		(end 194.140074 -95.097854)
		(width 0.10668)
		(layer "B.Cu")
		(net "CPU1_SA0")
	)
	(segment
		(start 69.29628 -116.927122)
		(end 41.53027 -144.693132)
		(width 0.10668)
		(layer "B.Cu")
		(net "CPU1_SA0")
	)
	(segment
		(start 91.093544 -304.103532)
		(end 90.871802 -304.325274)
		(width 0.10668)
		(layer "B.Cu")
		(net "CPU1_SA0")
	)
	(segment
		(start 15.531338 -323.638672)
		(end 17.532096 -321.637914)
		(width 0.10668)
		(layer "B.Cu")
		(net "CPU1_SA0")
	)
	(segment
		(start 68.406772 -310.075326)
		(end 83.610958 -310.075326)
		(width 0.10668)
		(layer "B.Cu")
		(net "CPU1_SA0")
	)
	(segment
		(start 88.237568 -304.325274)
		(end 90.871802 -304.325274)
		(width 0.10668)
		(layer "B.Cu")
		(net "CPU1_SA0")
	)
	(segment
		(start 58.613802 -319.031366)
		(end 59.450732 -319.031366)
		(width 0.10668)
		(layer "B.Cu")
		(net "CPU1_SA0")
	)
	(segment
		(start 93.091 -302.26635)
		(end 92.639896 -302.717454)
		(width 0.10668)
		(layer "B.Cu")
		(net "CPU1_SA0")
	)
	(segment
		(start 157.1371 -107.764072)
		(end 156.122116 -107.764072)
		(width 0.10668)
		(layer "B.Cu")
		(net "CPU1_SA0")
	)
	(segment
		(start 17.532096 -321.637914)
		(end 56.007254 -321.637914)
		(width 0.10668)
		(layer "B.Cu")
		(net "CPU1_SA0")
	)
	(segment
		(start 193.929 -96.719898)
		(end 194.140074 -96.508824)
		(width 0.10668)
		(layer "B.Cu")
		(net "CPU1_SA0")
	)
	(segment
		(start 91.093544 -303.255172)
		(end 91.093544 -304.103532)
		(width 0.10668)
		(layer "B.Cu")
		(net "CPU1_SA0")
	)
	(segment
		(start 156.122116 -107.764072)
		(end 151.636984 -112.249204)
		(width 0.10668)
		(layer "B.Cu")
		(net "CPU1_SA0")
	)
	(segment
		(start 193.714624 -169.63009)
		(end 196.517768 -169.63009)
		(width 0.10668)
		(layer "F.Cu")
		(net "CPU1_PWR_GD_IN")
	)
	(segment
		(start 407.153872 -351.43059)
		(end 397.618204 -360.966258)
		(width 0.10668)
		(layer "F.Cu")
		(net "CPU1_PWR_GD_IN")
	)
	(segment
		(start 212.417406 -188.802772)
		(end 212.417406 -197.519036)
		(width 0.10668)
		(layer "F.Cu")
		(net "CPU1_PWR_GD_IN")
	)
	(segment
		(start 145.156428 -319.050416)
		(end 145.156428 -313.456828)
		(width 0.10668)
		(layer "F.Cu")
		(net "CPU1_PWR_GD_IN")
	)
	(segment
		(start 244.752622 -368.635026)
		(end 229.440486 -368.635026)
		(width 0.10668)
		(layer "F.Cu")
		(net "CPU1_PWR_GD_IN")
	)
	(segment
		(start 144.609058 -312.909458)
		(end 144.609058 -311.57799)
		(width 0.10668)
		(layer "F.Cu")
		(net "CPU1_PWR_GD_IN")
	)
	(segment
		(start 278.327612 -371.998494)
		(end 248.11609 -371.998494)
		(width 0.10668)
		(layer "F.Cu")
		(net "CPU1_PWR_GD_IN")
	)
	(segment
		(start 139.530074 -296.297604)
		(end 139.80795 -296.019728)
		(width 0.10668)
		(layer "F.Cu")
		(net "CPU1_PWR_GD_IN")
	)
	(segment
		(start 165.226746 -357.8225)
		(end 159.986472 -357.8225)
		(width 0.10668)
		(layer "F.Cu")
		(net "CPU1_PWR_GD_IN")
	)
	(segment
		(start 137.683748 -298.753784)
		(end 139.530074 -296.907458)
		(width 0.10668)
		(layer "F.Cu")
		(net "CPU1_PWR_GD_IN")
	)
	(segment
		(start 194.66814 -138.391138)
		(end 194.66814 -142.24762)
		(width 0.10668)
		(layer "F.Cu")
		(net "CPU1_PWR_GD_IN")
	)
	(segment
		(start 153.595832 -351.43186)
		(end 153.595832 -337.061302)
		(width 0.10668)
		(layer "F.Cu")
		(net "CPU1_PWR_GD_IN")
	)
	(segment
		(start 407.873454 -326.686672)
		(end 407.599642 -326.686672)
		(width 0.10668)
		(layer "F.Cu")
		(net "CPU1_PWR_GD_IN")
	)
	(segment
		(start 185.285888 -373.693182)
		(end 183.62676 -372.034054)
		(width 0.10668)
		(layer "F.Cu")
		(net "CPU1_PWR_GD_IN")
	)
	(segment
		(start 248.11609 -371.998494)
		(end 244.752622 -368.635026)
		(width 0.10668)
		(layer "F.Cu")
		(net "CPU1_PWR_GD_IN")
	)
	(segment
		(start 153.595832 -337.061302)
		(end 145.841466 -329.306936)
		(width 0.10668)
		(layer "F.Cu")
		(net "CPU1_PWR_GD_IN")
	)
	(segment
		(start 229.440486 -368.635026)
		(end 224.38233 -373.693182)
		(width 0.10668)
		(layer "F.Cu")
		(net "CPU1_PWR_GD_IN")
	)
	(segment
		(start 296.480738 -376.338846)
		(end 282.667964 -376.338846)
		(width 0.10668)
		(layer "F.Cu")
		(net "CPU1_PWR_GD_IN")
	)
	(segment
		(start 172.710348 -364.612682)
		(end 171.805854 -363.708188)
		(width 0.10668)
		(layer "F.Cu")
		(net "CPU1_PWR_GD_IN")
	)
	(segment
		(start 405.49322 -343.949528)
		(end 407.153872 -345.61018)
		(width 0.10668)
		(layer "F.Cu")
		(net "CPU1_PWR_GD_IN")
	)
	(segment
		(start 194.66814 -142.24762)
		(end 195.15836 -142.73784)
		(width 0.10668)
		(layer "F.Cu")
		(net "CPU1_PWR_GD_IN")
	)
	(segment
		(start 349.034862 -374.49125)
		(end 298.328334 -374.49125)
		(width 0.10668)
		(layer "F.Cu")
		(net "CPU1_PWR_GD_IN")
	)
	(segment
		(start 139.80795 -296.019728)
		(end 139.80795 -295.69029)
		(width 0.10668)
		(layer "F.Cu")
		(net "CPU1_PWR_GD_IN")
	)
	(segment
		(start 406.351232 -329.847702)
		(end 405.49322 -330.705714)
		(width 0.10668)
		(layer "F.Cu")
		(net "CPU1_PWR_GD_IN")
	)
	(segment
		(start 139.530074 -296.907458)
		(end 139.530074 -296.297604)
		(width 0.10668)
		(layer "F.Cu")
		(net "CPU1_PWR_GD_IN")
	)
	(segment
		(start 405.49322 -330.705714)
		(end 405.49322 -343.949528)
		(width 0.10668)
		(layer "F.Cu")
		(net "CPU1_PWR_GD_IN")
	)
	(segment
		(start 137.683748 -306.80533)
		(end 137.683748 -298.753784)
		(width 0.10668)
		(layer "F.Cu")
		(net "CPU1_PWR_GD_IN")
	)
	(segment
		(start 406.351232 -327.935082)
		(end 406.351232 -329.847702)
		(width 0.10668)
		(layer "F.Cu")
		(net "CPU1_PWR_GD_IN")
	)
	(segment
		(start 195.15836 -142.73784)
		(end 195.15836 -143.174212)
		(width 0.10668)
		(layer "F.Cu")
		(net "CPU1_PWR_GD_IN")
	)
	(segment
		(start 140.5636 -309.685182)
		(end 137.683748 -306.80533)
		(width 0.10668)
		(layer "F.Cu")
		(net "CPU1_PWR_GD_IN")
	)
	(segment
		(start 407.153872 -345.61018)
		(end 407.153872 -351.43059)
		(width 0.10668)
		(layer "F.Cu")
		(net "CPU1_PWR_GD_IN")
	)
	(segment
		(start 196.517768 -169.63009)
		(end 210.103212 -183.215534)
		(width 0.10668)
		(layer "F.Cu")
		(net "CPU1_PWR_GD_IN")
	)
	(segment
		(start 171.112434 -363.708188)
		(end 165.226746 -357.8225)
		(width 0.10668)
		(layer "F.Cu")
		(net "CPU1_PWR_GD_IN")
	)
	(segment
		(start 183.62676 -372.034054)
		(end 175.264826 -372.034054)
		(width 0.10668)
		(layer "F.Cu")
		(net "CPU1_PWR_GD_IN")
	)
	(segment
		(start 212.417406 -197.519036)
		(end 209.693256 -200.243186)
		(width 0.10668)
		(layer "F.Cu")
		(net "CPU1_PWR_GD_IN")
	)
	(segment
		(start 142.71625 -309.685182)
		(end 140.5636 -309.685182)
		(width 0.10668)
		(layer "F.Cu")
		(net "CPU1_PWR_GD_IN")
	)
	(segment
		(start 145.156428 -313.456828)
		(end 144.609058 -312.909458)
		(width 0.10668)
		(layer "F.Cu")
		(net "CPU1_PWR_GD_IN")
	)
	(segment
		(start 144.609058 -311.57799)
		(end 142.71625 -309.685182)
		(width 0.10668)
		(layer "F.Cu")
		(net "CPU1_PWR_GD_IN")
	)
	(segment
		(start 194.31 -138.032998)
		(end 194.66814 -138.391138)
		(width 0.10668)
		(layer "F.Cu")
		(net "CPU1_PWR_GD_IN")
	)
	(segment
		(start 175.264826 -372.034054)
		(end 172.710348 -369.479576)
		(width 0.10668)
		(layer "F.Cu")
		(net "CPU1_PWR_GD_IN")
	)
	(segment
		(start 282.667964 -376.338846)
		(end 278.327612 -371.998494)
		(width 0.10668)
		(layer "F.Cu")
		(net "CPU1_PWR_GD_IN")
	)
	(segment
		(start 362.559854 -360.966258)
		(end 349.034862 -374.49125)
		(width 0.10668)
		(layer "F.Cu")
		(net "CPU1_PWR_GD_IN")
	)
	(segment
		(start 407.599642 -326.686672)
		(end 406.351232 -327.935082)
		(width 0.10668)
		(layer "F.Cu")
		(net "CPU1_PWR_GD_IN")
	)
	(segment
		(start 159.986472 -357.8225)
		(end 153.595832 -351.43186)
		(width 0.10668)
		(layer "F.Cu")
		(net "CPU1_PWR_GD_IN")
	)
	(segment
		(start 145.841466 -319.735454)
		(end 145.156428 -319.050416)
		(width 0.10668)
		(layer "F.Cu")
		(net "CPU1_PWR_GD_IN")
	)
	(segment
		(start 210.103212 -183.215534)
		(end 212.417406 -188.802772)
		(width 0.10668)
		(layer "F.Cu")
		(net "CPU1_PWR_GD_IN")
	)
	(segment
		(start 298.328334 -374.49125)
		(end 296.480738 -376.338846)
		(width 0.10668)
		(layer "F.Cu")
		(net "CPU1_PWR_GD_IN")
	)
	(segment
		(start 224.38233 -373.693182)
		(end 185.285888 -373.693182)
		(width 0.10668)
		(layer "F.Cu")
		(net "CPU1_PWR_GD_IN")
	)
	(segment
		(start 209.693256 -200.243186)
		(end 208.984088 -200.243186)
		(width 0.10668)
		(layer "F.Cu")
		(net "CPU1_PWR_GD_IN")
	)
	(segment
		(start 397.618204 -360.966258)
		(end 362.559854 -360.966258)
		(width 0.10668)
		(layer "F.Cu")
		(net "CPU1_PWR_GD_IN")
	)
	(segment
		(start 171.805854 -363.708188)
		(end 171.112434 -363.708188)
		(width 0.10668)
		(layer "F.Cu")
		(net "CPU1_PWR_GD_IN")
	)
	(segment
		(start 172.710348 -369.479576)
		(end 172.710348 -364.612682)
		(width 0.10668)
		(layer "F.Cu")
		(net "CPU1_PWR_GD_IN")
	)
	(segment
		(start 145.841466 -329.306936)
		(end 145.841466 -319.735454)
		(width 0.10668)
		(layer "F.Cu")
		(net "CPU1_PWR_GD_IN")
	)
	(via
		(at 193.714624 -169.63009)
		(size 0.508)
		(drill 0.254)
		(layers "F.Cu" "B.Cu")
		(net "CPU1_PWR_GD_IN")
	)
	(via
		(at 193.745866 -144.983962)
		(size 0.6604)
		(drill 0.3302)
		(layers "F.Cu" "B.Cu")
		(net "CPU1_PWR_GD_IN")
	)
	(via
		(at 171.112434 -363.708188)
		(size 0.508)
		(drill 0.254)
		(layers "F.Cu" "B.Cu")
		(net "CPU1_PWR_GD_IN")
	)
	(via
		(at 195.15836 -143.174212)
		(size 0.508)
		(drill 0.254)
		(layers "F.Cu" "B.Cu")
		(net "CPU1_PWR_GD_IN")
	)
	(via
		(at 407.873454 -326.686672)
		(size 0.508)
		(drill 0.254)
		(layers "F.Cu" "B.Cu")
		(net "CPU1_PWR_GD_IN")
	)
	(via
		(at 208.984088 -200.243186)
		(size 0.508)
		(drill 0.254)
		(layers "F.Cu" "B.Cu")
		(net "CPU1_PWR_GD_IN")
	)
	(segment
		(start 407.099008 -325.912226)
		(end 407.873454 -326.686672)
		(width 0.10668)
		(layer "B.Cu")
		(net "CPU1_PWR_GD_IN")
	)
	(segment
		(start 407.099008 -325.878952)
		(end 407.099008 -325.912226)
		(width 0.10668)
		(layer "B.Cu")
		(net "CPU1_PWR_GD_IN")
	)
	(segment
		(start 193.745866 -144.983962)
		(end 195.15836 -143.571468)
		(width 0.10668)
		(layer "B.Cu")
		(net "CPU1_PWR_GD_IN")
	)
	(segment
		(start 187.095892 -159.646366)
		(end 187.095892 -151.633936)
		(width 0.10668)
		(layer "B.Cu")
		(net "CPU1_PWR_GD_IN")
	)
	(segment
		(start 187.095892 -151.633936)
		(end 193.745866 -144.983962)
		(width 0.10668)
		(layer "B.Cu")
		(net "CPU1_PWR_GD_IN")
	)
	(segment
		(start 195.15836 -143.571468)
		(end 195.15836 -143.174212)
		(width 0.10668)
		(layer "B.Cu")
		(net "CPU1_PWR_GD_IN")
	)
	(segment
		(start 193.714624 -166.265098)
		(end 187.095892 -159.646366)
		(width 0.10668)
		(layer "B.Cu")
		(net "CPU1_PWR_GD_IN")
	)
	(segment
		(start 193.714624 -169.63009)
		(end 193.714624 -166.265098)
		(width 0.10668)
		(layer "B.Cu")
		(net "CPU1_PWR_GD_IN")
	)
	(segment
		(start 220.363796 -367.199672)
		(end 218.903042 -368.660426)
		(width 0.11684)
		(layer "In6.Cu")
		(net "CPU1_PWR_GD_IN")
	)
	(segment
		(start 213.144354 -204.403452)
		(end 213.144354 -321.772534)
		(width 0.11684)
		(layer "In6.Cu")
		(net "CPU1_PWR_GD_IN")
	)
	(segment
		(start 224.0661 -358.31018)
		(end 221.711266 -360.665014)
		(width 0.11684)
		(layer "In6.Cu")
		(net "CPU1_PWR_GD_IN")
	)
	(segment
		(start 176.25187 -364.397544)
		(end 172.48251 -364.397544)
		(width 0.11684)
		(layer "In6.Cu")
		(net "CPU1_PWR_GD_IN")
	)
	(segment
		(start 180.514752 -368.660426)
		(end 176.25187 -364.397544)
		(width 0.11684)
		(layer "In6.Cu")
		(net "CPU1_PWR_GD_IN")
	)
	(segment
		(start 221.711266 -363.653578)
		(end 220.363796 -365.001048)
		(width 0.11684)
		(layer "In6.Cu")
		(net "CPU1_PWR_GD_IN")
	)
	(segment
		(start 172.48251 -364.397544)
		(end 171.793154 -363.708188)
		(width 0.11684)
		(layer "In6.Cu")
		(net "CPU1_PWR_GD_IN")
	)
	(segment
		(start 218.903042 -368.660426)
		(end 180.514752 -368.660426)
		(width 0.11684)
		(layer "In6.Cu")
		(net "CPU1_PWR_GD_IN")
	)
	(segment
		(start 208.984088 -200.243186)
		(end 213.144354 -204.403452)
		(width 0.11684)
		(layer "In6.Cu")
		(net "CPU1_PWR_GD_IN")
	)
	(segment
		(start 220.363796 -365.001048)
		(end 220.363796 -367.199672)
		(width 0.11684)
		(layer "In6.Cu")
		(net "CPU1_PWR_GD_IN")
	)
	(segment
		(start 224.0661 -332.69428)
		(end 224.0661 -358.31018)
		(width 0.11684)
		(layer "In6.Cu")
		(net "CPU1_PWR_GD_IN")
	)
	(segment
		(start 221.711266 -360.665014)
		(end 221.711266 -363.653578)
		(width 0.11684)
		(layer "In6.Cu")
		(net "CPU1_PWR_GD_IN")
	)
	(segment
		(start 171.793154 -363.708188)
		(end 171.112434 -363.708188)
		(width 0.11684)
		(layer "In6.Cu")
		(net "CPU1_PWR_GD_IN")
	)
	(segment
		(start 213.144354 -321.772534)
		(end 224.0661 -332.69428)
		(width 0.11684)
		(layer "In6.Cu")
		(net "CPU1_PWR_GD_IN")
	)
	(segment
		(start 113.957862 -294.880284)
		(end 114.424714 -295.146222)
		(width 0.10668)
		(layer "F.Cu")
		(net "CPU1_PWRGD_OUT")
	)
	(segment
		(start 209.294476 -115.657376)
		(end 210.502754 -115.657376)
		(width 0.10668)
		(layer "F.Cu")
		(net "CPU1_PWRGD_OUT")
	)
	(via
		(at 210.502754 -115.657376)
		(size 0.508)
		(drill 0.254)
		(layers "F.Cu" "B.Cu")
		(net "CPU1_PWRGD_OUT")
	)
	(via
		(at 114.424714 -295.146222)
		(size 0.4064)
		(drill 0.2032)
		(layers "F.Cu" "B.Cu")
		(net "CPU1_PWRGD_OUT")
	)
	(via
		(at 198.131684 -83.380072)
		(size 0.508)
		(drill 0.254)
		(layers "F.Cu" "B.Cu")
		(net "CPU1_PWRGD_OUT")
	)
	(via
		(at 143.359378 -109.636052)
		(size 0.508)
		(drill 0.254)
		(layers "F.Cu" "B.Cu")
		(net "CPU1_PWRGD_OUT")
	)
	(via
		(at 137.917682 -84.970874)
		(size 0.508)
		(drill 0.254)
		(layers "F.Cu" "B.Cu")
		(net "CPU1_PWRGD_OUT")
	)
	(segment
		(start 94.860364 -307.80228)
		(end 94.860364 -307.730652)
		(width 0.10668)
		(layer "B.Cu")
		(net "CPU1_PWRGD_OUT")
	)
	(segment
		(start 57.474358 -323.031866)
		(end 69.064378 -311.441846)
		(width 0.10668)
		(layer "B.Cu")
		(net "CPU1_PWRGD_OUT")
	)
	(segment
		(start 136.308338 -115.66906)
		(end 68.774564 -115.66906)
		(width 0.10668)
		(layer "B.Cu")
		(net "CPU1_PWRGD_OUT")
	)
	(segment
		(start 40.272208 -158.006542)
		(end 11.512296 -186.766454)
		(width 0.10668)
		(layer "B.Cu")
		(net "CPU1_PWRGD_OUT")
	)
	(segment
		(start 114.17681 -295.146222)
		(end 114.424714 -295.146222)
		(width 0.10668)
		(layer "B.Cu")
		(net "CPU1_PWRGD_OUT")
	)
	(segment
		(start 94.860364 -306.714652)
		(end 94.860364 -305.736752)
		(width 0.10668)
		(layer "B.Cu")
		(net "CPU1_PWRGD_OUT")
	)
	(segment
		(start 11.512296 -186.766454)
		(end 11.512296 -322.833492)
		(width 0.10668)
		(layer "B.Cu")
		(net "CPU1_PWRGD_OUT")
	)
	(segment
		(start 92.87256 -311.441846)
		(end 95.233744 -309.080662)
		(width 0.10668)
		(layer "B.Cu")
		(net "CPU1_PWRGD_OUT")
	)
	(segment
		(start 103.59644 -305.726592)
		(end 114.17681 -295.146222)
		(width 0.10668)
		(layer "B.Cu")
		(net "CPU1_PWRGD_OUT")
	)
	(segment
		(start 95.233744 -308.17566)
		(end 94.860364 -307.80228)
		(width 0.10668)
		(layer "B.Cu")
		(net "CPU1_PWRGD_OUT")
	)
	(segment
		(start 94.860364 -305.736752)
		(end 94.870524 -305.726592)
		(width 0.10668)
		(layer "B.Cu")
		(net "CPU1_PWRGD_OUT")
	)
	(segment
		(start 11.512296 -322.833492)
		(end 13.973048 -325.294244)
		(width 0.10668)
		(layer "B.Cu")
		(net "CPU1_PWRGD_OUT")
	)
	(segment
		(start 13.973048 -325.294244)
		(end 16.20266 -325.294244)
		(width 0.10668)
		(layer "B.Cu")
		(net "CPU1_PWRGD_OUT")
	)
	(segment
		(start 69.064378 -311.441846)
		(end 92.87256 -311.441846)
		(width 0.10668)
		(layer "B.Cu")
		(net "CPU1_PWRGD_OUT")
	)
	(segment
		(start 40.272208 -144.171416)
		(end 40.272208 -158.006542)
		(width 0.10668)
		(layer "B.Cu")
		(net "CPU1_PWRGD_OUT")
	)
	(segment
		(start 94.860364 -306.714652)
		(end 94.860364 -307.730652)
		(width 0.10668)
		(layer "B.Cu")
		(net "CPU1_PWRGD_OUT")
	)
	(segment
		(start 142.341346 -109.636052)
		(end 136.308338 -115.66906)
		(width 0.10668)
		(layer "B.Cu")
		(net "CPU1_PWRGD_OUT")
	)
	(segment
		(start 18.465038 -323.031866)
		(end 57.474358 -323.031866)
		(width 0.10668)
		(layer "B.Cu")
		(net "CPU1_PWRGD_OUT")
	)
	(segment
		(start 143.359378 -109.636052)
		(end 142.341346 -109.636052)
		(width 0.10668)
		(layer "B.Cu")
		(net "CPU1_PWRGD_OUT")
	)
	(segment
		(start 68.774564 -115.66906)
		(end 40.272208 -144.171416)
		(width 0.10668)
		(layer "B.Cu")
		(net "CPU1_PWRGD_OUT")
	)
	(segment
		(start 95.233744 -309.080662)
		(end 95.233744 -308.17566)
		(width 0.10668)
		(layer "B.Cu")
		(net "CPU1_PWRGD_OUT")
	)
	(segment
		(start 94.870524 -305.726592)
		(end 103.59644 -305.726592)
		(width 0.10668)
		(layer "B.Cu")
		(net "CPU1_PWRGD_OUT")
	)
	(segment
		(start 16.20266 -325.294244)
		(end 18.465038 -323.031866)
		(width 0.10668)
		(layer "B.Cu")
		(net "CPU1_PWRGD_OUT")
	)
	(segment
		(start 182.214012 -83.488784)
		(end 182.784496 -84.059268)
		(width 0.11684)
		(layer "In2.Cu")
		(net "CPU1_PWRGD_OUT")
	)
	(segment
		(start 182.784496 -84.059268)
		(end 197.452488 -84.059268)
		(width 0.11684)
		(layer "In2.Cu")
		(net "CPU1_PWRGD_OUT")
	)
	(segment
		(start 137.917682 -84.970874)
		(end 158.771844 -84.970874)
		(width 0.11684)
		(layer "In2.Cu")
		(net "CPU1_PWRGD_OUT")
	)
	(segment
		(start 160.253934 -83.488784)
		(end 182.214012 -83.488784)
		(width 0.11684)
		(layer "In2.Cu")
		(net "CPU1_PWRGD_OUT")
	)
	(segment
		(start 197.452488 -84.059268)
		(end 198.131684 -83.380072)
		(width 0.11684)
		(layer "In2.Cu")
		(net "CPU1_PWRGD_OUT")
	)
	(segment
		(start 158.771844 -84.970874)
		(end 160.253934 -83.488784)
		(width 0.11684)
		(layer "In2.Cu")
		(net "CPU1_PWRGD_OUT")
	)
	(segment
		(start 142.012416 -89.065608)
		(end 142.012416 -105.764584)
		(width 0.11684)
		(layer "In4.Cu")
		(net "CPU1_PWRGD_OUT")
	)
	(segment
		(start 137.917682 -84.970874)
		(end 142.012416 -89.065608)
		(width 0.11684)
		(layer "In4.Cu")
		(net "CPU1_PWRGD_OUT")
	)
	(segment
		(start 142.5956 -106.347768)
		(end 142.5956 -108.872274)
		(width 0.11684)
		(layer "In4.Cu")
		(net "CPU1_PWRGD_OUT")
	)
	(segment
		(start 142.5956 -108.872274)
		(end 143.359378 -109.636052)
		(width 0.11684)
		(layer "In4.Cu")
		(net "CPU1_PWRGD_OUT")
	)
	(segment
		(start 142.012416 -105.764584)
		(end 142.5956 -106.347768)
		(width 0.11684)
		(layer "In4.Cu")
		(net "CPU1_PWRGD_OUT")
	)
	(segment
		(start 212.27415 -114.283744)
		(end 212.27415 -111.98225)
		(width 0.11684)
		(layer "In11.Cu")
		(net "CPU1_PWRGD_OUT")
	)
	(segment
		(start 212.27415 -111.98225)
		(end 213.331806 -110.924594)
		(width 0.11684)
		(layer "In11.Cu")
		(net "CPU1_PWRGD_OUT")
	)
	(segment
		(start 204.170534 -87.540338)
		(end 201.886312 -85.256116)
		(width 0.11684)
		(layer "In11.Cu")
		(net "CPU1_PWRGD_OUT")
	)
	(segment
		(start 201.886312 -85.256116)
		(end 200.007728 -85.256116)
		(width 0.11684)
		(layer "In11.Cu")
		(net "CPU1_PWRGD_OUT")
	)
	(segment
		(start 213.331806 -110.924594)
		(end 213.331806 -106.570018)
		(width 0.11684)
		(layer "In11.Cu")
		(net "CPU1_PWRGD_OUT")
	)
	(segment
		(start 214.521542 -93.454982)
		(end 208.606898 -87.540338)
		(width 0.11684)
		(layer "In11.Cu")
		(net "CPU1_PWRGD_OUT")
	)
	(segment
		(start 210.619594 -115.062508)
		(end 211.495386 -115.062508)
		(width 0.11684)
		(layer "In11.Cu")
		(net "CPU1_PWRGD_OUT")
	)
	(segment
		(start 210.502754 -115.179348)
		(end 210.619594 -115.062508)
		(width 0.11684)
		(layer "In11.Cu")
		(net "CPU1_PWRGD_OUT")
	)
	(segment
		(start 200.007728 -85.256116)
		(end 198.131684 -83.380072)
		(width 0.11684)
		(layer "In11.Cu")
		(net "CPU1_PWRGD_OUT")
	)
	(segment
		(start 211.495386 -115.062508)
		(end 212.27415 -114.283744)
		(width 0.11684)
		(layer "In11.Cu")
		(net "CPU1_PWRGD_OUT")
	)
	(segment
		(start 210.502754 -115.657376)
		(end 210.502754 -115.179348)
		(width 0.11684)
		(layer "In11.Cu")
		(net "CPU1_PWRGD_OUT")
	)
	(segment
		(start 208.606898 -87.540338)
		(end 204.170534 -87.540338)
		(width 0.11684)
		(layer "In11.Cu")
		(net "CPU1_PWRGD_OUT")
	)
	(segment
		(start 213.331806 -106.570018)
		(end 214.521542 -105.380282)
		(width 0.11684)
		(layer "In11.Cu")
		(net "CPU1_PWRGD_OUT")
	)
	(segment
		(start 214.521542 -105.380282)
		(end 214.521542 -93.454982)
		(width 0.11684)
		(layer "In11.Cu")
		(net "CPU1_PWRGD_OUT")
	)
	(segment
		(start 84.0867 -205.83906)
		(end 75.328018 -205.83906)
		(width 0.10668)
		(layer "F.Cu")
		(net "CPU1_PROCHOT_N")
	)
	(segment
		(start 61.809884 -188.971682)
		(end 66.870834 -194.032632)
		(width 0.10668)
		(layer "F.Cu")
		(net "CPU1_PROCHOT_N")
	)
	(segment
		(start 66.870834 -194.032632)
		(end 66.870834 -196.084952)
		(width 0.10668)
		(layer "F.Cu")
		(net "CPU1_PROCHOT_N")
	)
	(segment
		(start 66.870834 -198.142352)
		(end 66.870834 -196.084952)
		(width 0.10668)
		(layer "F.Cu")
		(net "CPU1_PROCHOT_N")
	)
	(segment
		(start 88.193626 -209.945986)
		(end 84.0867 -205.83906)
		(width 0.10668)
		(layer "F.Cu")
		(net "CPU1_PROCHOT_N")
	)
	(segment
		(start 69.635624 -200.309226)
		(end 69.037708 -200.309226)
		(width 0.10668)
		(layer "F.Cu")
		(net "CPU1_PROCHOT_N")
	)
	(segment
		(start 75.328018 -205.83906)
		(end 73.406 -203.917042)
		(width 0.10668)
		(layer "F.Cu")
		(net "CPU1_PROCHOT_N")
	)
	(segment
		(start 71.250302 -201.923904)
		(end 69.635624 -200.309226)
		(width 0.10668)
		(layer "F.Cu")
		(net "CPU1_PROCHOT_N")
	)
	(segment
		(start 83.107784 -222.070422)
		(end 83.107784 -221.055692)
		(width 0.10668)
		(layer "F.Cu")
		(net "CPU1_PROCHOT_N")
	)
	(segment
		(start 71.250302 -202.470766)
		(end 71.250302 -201.923904)
		(width 0.10668)
		(layer "F.Cu")
		(net "CPU1_PROCHOT_N")
	)
	(segment
		(start 73.406 -203.917042)
		(end 72.195182 -203.415646)
		(width 0.10668)
		(layer "F.Cu")
		(net "CPU1_PROCHOT_N")
	)
	(segment
		(start 183.769 -99.894898)
		(end 183.769 -99.278948)
		(width 0.10668)
		(layer "F.Cu")
		(net "CPU1_PROCHOT_N")
	)
	(segment
		(start 88.193626 -215.96985)
		(end 88.193626 -209.945986)
		(width 0.10668)
		(layer "F.Cu")
		(net "CPU1_PROCHOT_N")
	)
	(segment
		(start 72.195182 -203.415646)
		(end 71.250302 -202.470766)
		(width 0.10668)
		(layer "F.Cu")
		(net "CPU1_PROCHOT_N")
	)
	(segment
		(start 69.037708 -200.309226)
		(end 66.870834 -198.142352)
		(width 0.10668)
		(layer "F.Cu")
		(net "CPU1_PROCHOT_N")
	)
	(segment
		(start 83.107784 -221.055692)
		(end 88.193626 -215.96985)
		(width 0.10668)
		(layer "F.Cu")
		(net "CPU1_PROCHOT_N")
	)
	(segment
		(start 59.177174 -188.971682)
		(end 61.809884 -188.971682)
		(width 0.10668)
		(layer "F.Cu")
		(net "CPU1_PROCHOT_N")
	)
	(via
		(at 66.870834 -196.084952)
		(size 0.762)
		(drill 0.381)
		(layers "F.Cu" "B.Cu")
		(net "CPU1_PROCHOT_N")
	)
	(via
		(at 59.177174 -188.971682)
		(size 0.508)
		(drill 0.254)
		(layers "F.Cu" "B.Cu")
		(net "CPU1_PROCHOT_N")
	)
	(via
		(at 116.185696 -126.486412)
		(size 0.508)
		(drill 0.254)
		(layers "F.Cu" "B.Cu")
		(net "CPU1_PROCHOT_N")
	)
	(via
		(at 183.769 -99.278948)
		(size 0.508)
		(drill 0.254)
		(layers "F.Cu" "B.Cu")
		(net "CPU1_PROCHOT_N")
	)
	(segment
		(start 59.233562 -190.24727)
		(end 59.233562 -189.02807)
		(width 0.10668)
		(layer "B.Cu")
		(net "CPU1_PROCHOT_N")
	)
	(segment
		(start 59.233562 -189.02807)
		(end 59.177174 -188.971682)
		(width 0.10668)
		(layer "B.Cu")
		(net "CPU1_PROCHOT_N")
	)
	(segment
		(start 162.664394 -120.861074)
		(end 162.664394 -119.052086)
		(width 0.11684)
		(layer "In6.Cu")
		(net "CPU1_PROCHOT_N")
	)
	(segment
		(start 176.89322 -106.651552)
		(end 177.120804 -106.423968)
		(width 0.11684)
		(layer "In6.Cu")
		(net "CPU1_PROCHOT_N")
	)
	(segment
		(start 177.120804 -106.361738)
		(end 183.802528 -99.680014)
		(width 0.11684)
		(layer "In6.Cu")
		(net "CPU1_PROCHOT_N")
	)
	(segment
		(start 162.664394 -119.052086)
		(end 165.952932 -115.763548)
		(width 0.11684)
		(layer "In6.Cu")
		(net "CPU1_PROCHOT_N")
	)
	(segment
		(start 177.120804 -106.423968)
		(end 177.120804 -106.361738)
		(width 0.11684)
		(layer "In6.Cu")
		(net "CPU1_PROCHOT_N")
	)
	(segment
		(start 172.896784 -113.217198)
		(end 172.896784 -110.585758)
		(width 0.11684)
		(layer "In6.Cu")
		(net "CPU1_PROCHOT_N")
	)
	(segment
		(start 172.896784 -110.585758)
		(end 176.83099 -106.651552)
		(width 0.11684)
		(layer "In6.Cu")
		(net "CPU1_PROCHOT_N")
	)
	(segment
		(start 155.517342 -126.52502)
		(end 155.813506 -126.228856)
		(width 0.11684)
		(layer "In6.Cu")
		(net "CPU1_PROCHOT_N")
	)
	(segment
		(start 155.813506 -126.228856)
		(end 157.296612 -126.228856)
		(width 0.11684)
		(layer "In6.Cu")
		(net "CPU1_PROCHOT_N")
	)
	(segment
		(start 153.16454 -126.486412)
		(end 153.203148 -126.52502)
		(width 0.11684)
		(layer "In6.Cu")
		(net "CPU1_PROCHOT_N")
	)
	(segment
		(start 153.203148 -126.52502)
		(end 155.517342 -126.52502)
		(width 0.11684)
		(layer "In6.Cu")
		(net "CPU1_PROCHOT_N")
	)
	(segment
		(start 170.350434 -115.763548)
		(end 172.896784 -113.217198)
		(width 0.11684)
		(layer "In6.Cu")
		(net "CPU1_PROCHOT_N")
	)
	(segment
		(start 183.802528 -99.312476)
		(end 183.769 -99.278948)
		(width 0.11684)
		(layer "In6.Cu")
		(net "CPU1_PROCHOT_N")
	)
	(segment
		(start 116.185696 -126.486412)
		(end 153.16454 -126.486412)
		(width 0.11684)
		(layer "In6.Cu")
		(net "CPU1_PROCHOT_N")
	)
	(segment
		(start 165.952932 -115.763548)
		(end 170.350434 -115.763548)
		(width 0.11684)
		(layer "In6.Cu")
		(net "CPU1_PROCHOT_N")
	)
	(segment
		(start 157.296612 -126.228856)
		(end 162.664394 -120.861074)
		(width 0.11684)
		(layer "In6.Cu")
		(net "CPU1_PROCHOT_N")
	)
	(segment
		(start 176.83099 -106.651552)
		(end 176.89322 -106.651552)
		(width 0.11684)
		(layer "In6.Cu")
		(net "CPU1_PROCHOT_N")
	)
	(segment
		(start 183.802528 -99.680014)
		(end 183.802528 -99.312476)
		(width 0.11684)
		(layer "In6.Cu")
		(net "CPU1_PROCHOT_N")
	)
	(segment
		(start 36.708588 -160.868614)
		(end 36.708588 -180.245512)
		(width 0.11684)
		(layer "In11.Cu")
		(net "CPU1_PROCHOT_N")
	)
	(segment
		(start 41.669716 -155.907486)
		(end 36.708588 -160.868614)
		(width 0.11684)
		(layer "In11.Cu")
		(net "CPU1_PROCHOT_N")
	)
	(segment
		(start 39.337742 -182.874666)
		(end 39.337742 -187.185808)
		(width 0.11684)
		(layer "In11.Cu")
		(net "CPU1_PROCHOT_N")
	)
	(segment
		(start 53.151278 -136.291574)
		(end 41.669716 -147.773136)
		(width 0.11684)
		(layer "In11.Cu")
		(net "CPU1_PROCHOT_N")
	)
	(segment
		(start 36.708588 -180.245512)
		(end 39.337742 -182.874666)
		(width 0.11684)
		(layer "In11.Cu")
		(net "CPU1_PROCHOT_N")
	)
	(segment
		(start 39.337742 -187.185808)
		(end 41.123616 -188.971682)
		(width 0.11684)
		(layer "In11.Cu")
		(net "CPU1_PROCHOT_N")
	)
	(segment
		(start 115.480846 -127.191262)
		(end 115.480846 -130.021076)
		(width 0.11684)
		(layer "In11.Cu")
		(net "CPU1_PROCHOT_N")
	)
	(segment
		(start 115.480846 -130.021076)
		(end 109.210348 -136.291574)
		(width 0.11684)
		(layer "In11.Cu")
		(net "CPU1_PROCHOT_N")
	)
	(segment
		(start 41.123616 -188.971682)
		(end 59.177174 -188.971682)
		(width 0.11684)
		(layer "In11.Cu")
		(net "CPU1_PROCHOT_N")
	)
	(segment
		(start 116.185696 -126.486412)
		(end 115.480846 -127.191262)
		(width 0.11684)
		(layer "In11.Cu")
		(net "CPU1_PROCHOT_N")
	)
	(segment
		(start 41.669716 -147.773136)
		(end 41.669716 -155.907486)
		(width 0.11684)
		(layer "In11.Cu")
		(net "CPU1_PROCHOT_N")
	)
	(segment
		(start 109.210348 -136.291574)
		(end 53.151278 -136.291574)
		(width 0.11684)
		(layer "In11.Cu")
		(net "CPU1_PROCHOT_N")
	)
	(segment
		(start 68.323714 -198.944992)
		(end 70.73011 -198.944992)
		(width 0.10668)
		(layer "F.Cu")
		(net "CPU1_NV_SAVE_N")
	)
	(segment
		(start 84.633562 -204.158342)
		(end 91.39174 -210.91652)
		(width 0.10668)
		(layer "F.Cu")
		(net "CPU1_NV_SAVE_N")
	)
	(segment
		(start 91.26347 -217.92565)
		(end 91.26347 -218.64066)
		(width 0.10668)
		(layer "F.Cu")
		(net "CPU1_NV_SAVE_N")
	)
	(segment
		(start 87.775034 -221.78264)
		(end 87.775034 -222.443294)
		(width 0.10668)
		(layer "F.Cu")
		(net "CPU1_NV_SAVE_N")
	)
	(segment
		(start 90.905076 -218.999054)
		(end 90.55862 -218.999054)
		(width 0.10668)
		(layer "F.Cu")
		(net "CPU1_NV_SAVE_N")
	)
	(segment
		(start 91.39174 -210.91652)
		(end 91.39174 -217.79738)
		(width 0.10668)
		(layer "F.Cu")
		(net "CPU1_NV_SAVE_N")
	)
	(segment
		(start 183.006746 -135.502396)
		(end 183.01462 -135.494522)
		(width 0.10668)
		(layer "F.Cu")
		(net "CPU1_NV_SAVE_N")
	)
	(segment
		(start 87.775034 -222.443294)
		(end 87.3379 -222.880428)
		(width 0.10668)
		(layer "F.Cu")
		(net "CPU1_NV_SAVE_N")
	)
	(segment
		(start 91.39174 -217.79738)
		(end 91.26347 -217.92565)
		(width 0.10668)
		(layer "F.Cu")
		(net "CPU1_NV_SAVE_N")
	)
	(segment
		(start 91.26347 -218.64066)
		(end 90.905076 -218.999054)
		(width 0.10668)
		(layer "F.Cu")
		(net "CPU1_NV_SAVE_N")
	)
	(segment
		(start 70.73011 -198.944992)
		(end 70.730872 -198.945246)
		(width 0.10668)
		(layer "F.Cu")
		(net "CPU1_NV_SAVE_N")
	)
	(segment
		(start 90.55862 -218.999054)
		(end 87.775034 -221.78264)
		(width 0.10668)
		(layer "F.Cu")
		(net "CPU1_NV_SAVE_N")
	)
	(segment
		(start 70.730872 -198.945246)
		(end 75.943968 -204.158342)
		(width 0.10668)
		(layer "F.Cu")
		(net "CPU1_NV_SAVE_N")
	)
	(segment
		(start 75.943968 -204.158342)
		(end 84.633562 -204.158342)
		(width 0.10668)
		(layer "F.Cu")
		(net "CPU1_NV_SAVE_N")
	)
	(segment
		(start 183.01462 -134.592568)
		(end 183.650128 -133.95706)
		(width 0.10668)
		(layer "F.Cu")
		(net "CPU1_NV_SAVE_N")
	)
	(segment
		(start 183.01462 -135.494522)
		(end 183.01462 -134.592568)
		(width 0.10668)
		(layer "F.Cu")
		(net "CPU1_NV_SAVE_N")
	)
	(via
		(at 68.323714 -198.944992)
		(size 0.508)
		(drill 0.254)
		(layers "F.Cu" "B.Cu")
		(net "CPU1_NV_SAVE_N")
	)
	(via
		(at 119.034052 -130.580384)
		(size 0.508)
		(drill 0.254)
		(layers "F.Cu" "B.Cu")
		(net "CPU1_NV_SAVE_N")
	)
	(via
		(at 183.006746 -135.502396)
		(size 0.508)
		(drill 0.254)
		(layers "F.Cu" "B.Cu")
		(net "CPU1_NV_SAVE_N")
	)
	(segment
		(start 67.992244 -198.944992)
		(end 68.323714 -198.944992)
		(width 0.10668)
		(layer "B.Cu")
		(net "CPU1_NV_SAVE_N")
	)
	(segment
		(start 67.601084 -199.336152)
		(end 67.992244 -198.944992)
		(width 0.10668)
		(layer "B.Cu")
		(net "CPU1_NV_SAVE_N")
	)
	(segment
		(start 45.482764 -149.517862)
		(end 45.482764 -169.331894)
		(width 0.11684)
		(layer "In2.Cu")
		(net "CPU1_NV_SAVE_N")
	)
	(segment
		(start 101.718618 -131.002278)
		(end 98.907854 -128.191514)
		(width 0.11684)
		(layer "In2.Cu")
		(net "CPU1_NV_SAVE_N")
	)
	(segment
		(start 118.612158 -131.002278)
		(end 101.718618 -131.002278)
		(width 0.11684)
		(layer "In2.Cu")
		(net "CPU1_NV_SAVE_N")
	)
	(segment
		(start 87.20709 -130.580384)
		(end 76.7715 -130.580384)
		(width 0.11684)
		(layer "In2.Cu")
		(net "CPU1_NV_SAVE_N")
	)
	(segment
		(start 87.642954 -130.14452)
		(end 87.20709 -130.580384)
		(width 0.11684)
		(layer "In2.Cu")
		(net "CPU1_NV_SAVE_N")
	)
	(segment
		(start 93.520006 -130.14452)
		(end 87.642954 -130.14452)
		(width 0.11684)
		(layer "In2.Cu")
		(net "CPU1_NV_SAVE_N")
	)
	(segment
		(start 45.482764 -169.331894)
		(end 44.459398 -170.35526)
		(width 0.11684)
		(layer "In2.Cu")
		(net "CPU1_NV_SAVE_N")
	)
	(segment
		(start 61.560202 -190.534036)
		(end 68.323714 -197.297548)
		(width 0.11684)
		(layer "In2.Cu")
		(net "CPU1_NV_SAVE_N")
	)
	(segment
		(start 44.459398 -184.88152)
		(end 50.111914 -190.534036)
		(width 0.11684)
		(layer "In2.Cu")
		(net "CPU1_NV_SAVE_N")
	)
	(segment
		(start 50.111914 -190.534036)
		(end 61.560202 -190.534036)
		(width 0.11684)
		(layer "In2.Cu")
		(net "CPU1_NV_SAVE_N")
	)
	(segment
		(start 68.323714 -197.297548)
		(end 68.323714 -198.944992)
		(width 0.11684)
		(layer "In2.Cu")
		(net "CPU1_NV_SAVE_N")
	)
	(segment
		(start 76.7715 -130.580384)
		(end 72.206358 -135.145526)
		(width 0.11684)
		(layer "In2.Cu")
		(net "CPU1_NV_SAVE_N")
	)
	(segment
		(start 98.907854 -128.191514)
		(end 95.473012 -128.191514)
		(width 0.11684)
		(layer "In2.Cu")
		(net "CPU1_NV_SAVE_N")
	)
	(segment
		(start 119.034052 -130.580384)
		(end 118.612158 -131.002278)
		(width 0.11684)
		(layer "In2.Cu")
		(net "CPU1_NV_SAVE_N")
	)
	(segment
		(start 72.206358 -135.145526)
		(end 59.8551 -135.145526)
		(width 0.11684)
		(layer "In2.Cu")
		(net "CPU1_NV_SAVE_N")
	)
	(segment
		(start 59.8551 -135.145526)
		(end 45.482764 -149.517862)
		(width 0.11684)
		(layer "In2.Cu")
		(net "CPU1_NV_SAVE_N")
	)
	(segment
		(start 95.473012 -128.191514)
		(end 93.520006 -130.14452)
		(width 0.11684)
		(layer "In2.Cu")
		(net "CPU1_NV_SAVE_N")
	)
	(segment
		(start 44.459398 -170.35526)
		(end 44.459398 -184.88152)
		(width 0.11684)
		(layer "In2.Cu")
		(net "CPU1_NV_SAVE_N")
	)
	(segment
		(start 182.443374 -136.065768)
		(end 172.857922 -136.065768)
		(width 0.11684)
		(layer "In6.Cu")
		(net "CPU1_NV_SAVE_N")
	)
	(segment
		(start 170.628818 -133.836664)
		(end 163.841176 -133.836664)
		(width 0.11684)
		(layer "In6.Cu")
		(net "CPU1_NV_SAVE_N")
	)
	(segment
		(start 183.006746 -135.502396)
		(end 182.443374 -136.065768)
		(width 0.11684)
		(layer "In6.Cu")
		(net "CPU1_NV_SAVE_N")
	)
	(segment
		(start 156.879036 -132.511292)
		(end 154.948128 -130.580384)
		(width 0.11684)
		(layer "In6.Cu")
		(net "CPU1_NV_SAVE_N")
	)
	(segment
		(start 162.515804 -132.511292)
		(end 156.879036 -132.511292)
		(width 0.11684)
		(layer "In6.Cu")
		(net "CPU1_NV_SAVE_N")
	)
	(segment
		(start 172.857922 -136.065768)
		(end 170.628818 -133.836664)
		(width 0.11684)
		(layer "In6.Cu")
		(net "CPU1_NV_SAVE_N")
	)
	(segment
		(start 163.841176 -133.836664)
		(end 162.515804 -132.511292)
		(width 0.11684)
		(layer "In6.Cu")
		(net "CPU1_NV_SAVE_N")
	)
	(segment
		(start 154.948128 -130.580384)
		(end 119.034052 -130.580384)
		(width 0.11684)
		(layer "In6.Cu")
		(net "CPU1_NV_SAVE_N")
	)
	(segment
		(start 152.562052 -128.491996)
		(end 160.212532 -128.491996)
		(width 0.10668)
		(layer "F.Cu")
		(net "CPU1_NMI_SYNC_FLOOD_N")
	)
	(segment
		(start 192.151 -129.777998)
		(end 192.151 -130.38836)
		(width 0.10668)
		(layer "F.Cu")
		(net "CPU1_NMI_SYNC_FLOOD_N")
	)
	(segment
		(start 118.187978 -295.69029)
		(end 118.65483 -295.956228)
		(width 0.10668)
		(layer "F.Cu")
		(net "CPU1_NMI_SYNC_FLOOD_N")
	)
	(segment
		(start 134.39013 -114.820446)
		(end 134.39013 -116.57965)
		(width 0.10668)
		(layer "F.Cu")
		(net "CPU1_NMI_SYNC_FLOOD_N")
	)
	(segment
		(start 134.39013 -116.57965)
		(end 141.876272 -124.065792)
		(width 0.10668)
		(layer "F.Cu")
		(net "CPU1_NMI_SYNC_FLOOD_N")
	)
	(segment
		(start 141.876272 -124.065792)
		(end 152.562052 -128.491996)
		(width 0.10668)
		(layer "F.Cu")
		(net "CPU1_NMI_SYNC_FLOOD_N")
	)
	(via
		(at 192.151 -130.38836)
		(size 0.508)
		(drill 0.254)
		(layers "F.Cu" "B.Cu")
		(net "CPU1_NMI_SYNC_FLOOD_N")
	)
	(via
		(at 134.39013 -114.820446)
		(size 0.508)
		(drill 0.254)
		(layers "F.Cu" "B.Cu")
		(net "CPU1_NMI_SYNC_FLOOD_N")
	)
	(via
		(at 118.65483 -295.956228)
		(size 0.4064)
		(drill 0.2032)
		(layers "F.Cu" "B.Cu")
		(net "CPU1_NMI_SYNC_FLOOD_N")
	)
	(via
		(at 160.212532 -128.491996)
		(size 0.508)
		(drill 0.254)
		(layers "F.Cu" "B.Cu")
		(net "CPU1_NMI_SYNC_FLOOD_N")
	)
	(segment
		(start 13.673836 -326.015604)
		(end 59.237118 -326.015604)
		(width 0.10668)
		(layer "B.Cu")
		(net "CPU1_NMI_SYNC_FLOOD_N")
	)
	(segment
		(start 93.199204 -312.171588)
		(end 96.34728 -309.023512)
		(width 0.10668)
		(layer "B.Cu")
		(net "CPU1_NMI_SYNC_FLOOD_N")
	)
	(segment
		(start 59.237118 -326.015604)
		(end 59.91733 -325.335392)
		(width 0.10668)
		(layer "B.Cu")
		(net "CPU1_NMI_SYNC_FLOOD_N")
	)
	(segment
		(start 107.448858 -114.581178)
		(end 107.28452 -114.745516)
		(width 0.10668)
		(layer "B.Cu")
		(net "CPU1_NMI_SYNC_FLOOD_N")
	)
	(segment
		(start 118.204488 -292.967664)
		(end 118.562882 -293.326058)
		(width 0.10668)
		(layer "B.Cu")
		(net "CPU1_NMI_SYNC_FLOOD_N")
	)
	(segment
		(start 115.923568 -295.493186)
		(end 115.923568 -294.824912)
		(width 0.10668)
		(layer "B.Cu")
		(net "CPU1_NMI_SYNC_FLOOD_N")
	)
	(segment
		(start 116.24945 -294.075358)
		(end 115.91544 -293.741348)
		(width 0.10668)
		(layer "B.Cu")
		(net "CPU1_NMI_SYNC_FLOOD_N")
	)
	(segment
		(start 116.33073 -292.861746)
		(end 116.33073 -292.519608)
		(width 0.10668)
		(layer "B.Cu")
		(net "CPU1_NMI_SYNC_FLOOD_N")
	)
	(segment
		(start 104.862122 -309.023512)
		(end 116.216684 -297.66895)
		(width 0.10668)
		(layer "B.Cu")
		(net "CPU1_NMI_SYNC_FLOOD_N")
	)
	(segment
		(start 69.355208 -312.171588)
		(end 93.199204 -312.171588)
		(width 0.10668)
		(layer "B.Cu")
		(net "CPU1_NMI_SYNC_FLOOD_N")
	)
	(segment
		(start 118.204488 -292.503098)
		(end 118.204488 -292.967664)
		(width 0.10668)
		(layer "B.Cu")
		(net "CPU1_NMI_SYNC_FLOOD_N")
	)
	(segment
		(start 68.321936 -114.745516)
		(end 39.407338 -143.660114)
		(width 0.10668)
		(layer "B.Cu")
		(net "CPU1_NMI_SYNC_FLOOD_N")
	)
	(segment
		(start 10.790936 -323.132704)
		(end 13.673836 -326.015604)
		(width 0.10668)
		(layer "B.Cu")
		(net "CPU1_NMI_SYNC_FLOOD_N")
	)
	(segment
		(start 10.790936 -186.466988)
		(end 10.790936 -323.132704)
		(width 0.10668)
		(layer "B.Cu")
		(net "CPU1_NMI_SYNC_FLOOD_N")
	)
	(segment
		(start 153.71191 -324.233032)
		(end 154.488896 -323.911214)
		(width 0.10668)
		(layer "B.Cu")
		(net "CPU1_NMI_SYNC_FLOOD_N")
	)
	(segment
		(start 116.216684 -297.66895)
		(end 116.216684 -295.786302)
		(width 0.10668)
		(layer "B.Cu")
		(net "CPU1_NMI_SYNC_FLOOD_N")
	)
	(segment
		(start 155.079954 -324.052692)
		(end 155.500324 -324.052692)
		(width 0.10668)
		(layer "B.Cu")
		(net "CPU1_NMI_SYNC_FLOOD_N")
	)
	(segment
		(start 118.65483 -298.864528)
		(end 142.997174 -323.206872)
		(width 0.10668)
		(layer "B.Cu")
		(net "CPU1_NMI_SYNC_FLOOD_N")
	)
	(segment
		(start 116.55679 -292.293548)
		(end 117.994938 -292.293548)
		(width 0.10668)
		(layer "B.Cu")
		(net "CPU1_NMI_SYNC_FLOOD_N")
	)
	(segment
		(start 118.562882 -293.326058)
		(end 118.562882 -293.684452)
		(width 0.10668)
		(layer "B.Cu")
		(net "CPU1_NMI_SYNC_FLOOD_N")
	)
	(segment
		(start 116.24945 -294.49903)
		(end 116.24945 -294.075358)
		(width 0.10668)
		(layer "B.Cu")
		(net "CPU1_NMI_SYNC_FLOOD_N")
	)
	(segment
		(start 116.216684 -295.786302)
		(end 115.923568 -295.493186)
		(width 0.10668)
		(layer "B.Cu")
		(net "CPU1_NMI_SYNC_FLOOD_N")
	)
	(segment
		(start 155.500324 -324.052692)
		(end 155.754324 -323.798692)
		(width 0.10668)
		(layer "B.Cu")
		(net "CPU1_NMI_SYNC_FLOOD_N")
	)
	(segment
		(start 134.39013 -114.820446)
		(end 134.150862 -114.581178)
		(width 0.10668)
		(layer "B.Cu")
		(net "CPU1_NMI_SYNC_FLOOD_N")
	)
	(segment
		(start 150.963884 -324.233032)
		(end 153.71191 -324.233032)
		(width 0.10668)
		(layer "B.Cu")
		(net "CPU1_NMI_SYNC_FLOOD_N")
	)
	(segment
		(start 115.91544 -293.741348)
		(end 115.91544 -293.277036)
		(width 0.10668)
		(layer "B.Cu")
		(net "CPU1_NMI_SYNC_FLOOD_N")
	)
	(segment
		(start 118.562882 -293.684452)
		(end 119.043704 -294.165274)
		(width 0.10668)
		(layer "B.Cu")
		(net "CPU1_NMI_SYNC_FLOOD_N")
	)
	(segment
		(start 107.28452 -114.745516)
		(end 68.321936 -114.745516)
		(width 0.10668)
		(layer "B.Cu")
		(net "CPU1_NMI_SYNC_FLOOD_N")
	)
	(segment
		(start 154.488896 -323.911214)
		(end 154.938476 -323.911214)
		(width 0.10668)
		(layer "B.Cu")
		(net "CPU1_NMI_SYNC_FLOOD_N")
	)
	(segment
		(start 118.65483 -294.953182)
		(end 118.65483 -295.956228)
		(width 0.10668)
		(layer "B.Cu")
		(net "CPU1_NMI_SYNC_FLOOD_N")
	)
	(segment
		(start 39.407338 -157.850586)
		(end 10.790936 -186.466988)
		(width 0.10668)
		(layer "B.Cu")
		(net "CPU1_NMI_SYNC_FLOOD_N")
	)
	(segment
		(start 118.65483 -295.956228)
		(end 118.65483 -298.864528)
		(width 0.10668)
		(layer "B.Cu")
		(net "CPU1_NMI_SYNC_FLOOD_N")
	)
	(segment
		(start 59.91733 -325.335392)
		(end 59.91733 -321.609466)
		(width 0.10668)
		(layer "B.Cu")
		(net "CPU1_NMI_SYNC_FLOOD_N")
	)
	(segment
		(start 142.997174 -323.206872)
		(end 149.937724 -323.206872)
		(width 0.10668)
		(layer "B.Cu")
		(net "CPU1_NMI_SYNC_FLOOD_N")
	)
	(segment
		(start 119.043704 -294.564308)
		(end 118.65483 -294.953182)
		(width 0.10668)
		(layer "B.Cu")
		(net "CPU1_NMI_SYNC_FLOOD_N")
	)
	(segment
		(start 116.33073 -292.519608)
		(end 116.55679 -292.293548)
		(width 0.10668)
		(layer "B.Cu")
		(net "CPU1_NMI_SYNC_FLOOD_N")
	)
	(segment
		(start 115.91544 -293.277036)
		(end 116.33073 -292.861746)
		(width 0.10668)
		(layer "B.Cu")
		(net "CPU1_NMI_SYNC_FLOOD_N")
	)
	(segment
		(start 119.043704 -294.165274)
		(end 119.043704 -294.564308)
		(width 0.10668)
		(layer "B.Cu")
		(net "CPU1_NMI_SYNC_FLOOD_N")
	)
	(segment
		(start 149.937724 -323.206872)
		(end 150.963884 -324.233032)
		(width 0.10668)
		(layer "B.Cu")
		(net "CPU1_NMI_SYNC_FLOOD_N")
	)
	(segment
		(start 59.91733 -321.609466)
		(end 69.355208 -312.171588)
		(width 0.10668)
		(layer "B.Cu")
		(net "CPU1_NMI_SYNC_FLOOD_N")
	)
	(segment
		(start 96.34728 -309.023512)
		(end 104.862122 -309.023512)
		(width 0.10668)
		(layer "B.Cu")
		(net "CPU1_NMI_SYNC_FLOOD_N")
	)
	(segment
		(start 134.150862 -114.581178)
		(end 107.448858 -114.581178)
		(width 0.10668)
		(layer "B.Cu")
		(net "CPU1_NMI_SYNC_FLOOD_N")
	)
	(segment
		(start 115.923568 -294.824912)
		(end 116.24945 -294.49903)
		(width 0.10668)
		(layer "B.Cu")
		(net "CPU1_NMI_SYNC_FLOOD_N")
	)
	(segment
		(start 154.938476 -323.911214)
		(end 155.079954 -324.052692)
		(width 0.10668)
		(layer "B.Cu")
		(net "CPU1_NMI_SYNC_FLOOD_N")
	)
	(segment
		(start 117.994938 -292.293548)
		(end 118.204488 -292.503098)
		(width 0.10668)
		(layer "B.Cu")
		(net "CPU1_NMI_SYNC_FLOOD_N")
	)
	(segment
		(start 39.407338 -143.660114)
		(end 39.407338 -157.850586)
		(width 0.10668)
		(layer "B.Cu")
		(net "CPU1_NMI_SYNC_FLOOD_N")
	)
	(segment
		(start 171.447206 -128.030732)
		(end 172.784516 -129.368042)
		(width 0.11684)
		(layer "In6.Cu")
		(net "CPU1_NMI_SYNC_FLOOD_N")
	)
	(segment
		(start 167.480996 -128.030732)
		(end 171.447206 -128.030732)
		(width 0.11684)
		(layer "In6.Cu")
		(net "CPU1_NMI_SYNC_FLOOD_N")
	)
	(segment
		(start 192.151 -130.040888)
		(end 192.151 -130.38836)
		(width 0.11684)
		(layer "In6.Cu")
		(net "CPU1_NMI_SYNC_FLOOD_N")
	)
	(segment
		(start 191.020446 -128.910334)
		(end 192.151 -130.040888)
		(width 0.11684)
		(layer "In6.Cu")
		(net "CPU1_NMI_SYNC_FLOOD_N")
	)
	(segment
		(start 183.289194 -128.910334)
		(end 191.020446 -128.910334)
		(width 0.11684)
		(layer "In6.Cu")
		(net "CPU1_NMI_SYNC_FLOOD_N")
	)
	(segment
		(start 182.831486 -129.368042)
		(end 183.289194 -128.910334)
		(width 0.11684)
		(layer "In6.Cu")
		(net "CPU1_NMI_SYNC_FLOOD_N")
	)
	(segment
		(start 172.784516 -129.368042)
		(end 182.831486 -129.368042)
		(width 0.11684)
		(layer "In6.Cu")
		(net "CPU1_NMI_SYNC_FLOOD_N")
	)
	(segment
		(start 163.354766 -128.921764)
		(end 166.589964 -128.921764)
		(width 0.11684)
		(layer "In6.Cu")
		(net "CPU1_NMI_SYNC_FLOOD_N")
	)
	(segment
		(start 166.589964 -128.921764)
		(end 167.480996 -128.030732)
		(width 0.11684)
		(layer "In6.Cu")
		(net "CPU1_NMI_SYNC_FLOOD_N")
	)
	(segment
		(start 160.212532 -128.491996)
		(end 162.924998 -128.491996)
		(width 0.11684)
		(layer "In6.Cu")
		(net "CPU1_NMI_SYNC_FLOOD_N")
	)
	(segment
		(start 162.924998 -128.491996)
		(end 163.354766 -128.921764)
		(width 0.11684)
		(layer "In6.Cu")
		(net "CPU1_NMI_SYNC_FLOOD_N")
	)
	(segment
		(start 188.322204 -118.652798)
		(end 188.712094 -119.042688)
		(width 0.10668)
		(layer "F.Cu")
		(net "CPU1_JTAG_BUF_R_OE")
	)
	(via
		(at 188.712094 -119.042688)
		(size 0.4572)
		(drill 0.254)
		(layers "F.Cu" "B.Cu")
		(net "CPU1_JTAG_BUF_R_OE")
	)
	(via
		(at 186.9948 -125.222)
		(size 0.6604)
		(drill 0.3302)
		(layers "F.Cu" "B.Cu")
		(net "CPU1_JTAG_BUF_R_OE")
	)
	(segment
		(start 188.308234 -120.83415)
		(end 188.308234 -119.446548)
		(width 0.10668)
		(layer "B.Cu")
		(net "CPU1_JTAG_BUF_R_OE")
	)
	(segment
		(start 187.748926 -121.045224)
		(end 188.09716 -121.045224)
		(width 0.10668)
		(layer "B.Cu")
		(net "CPU1_JTAG_BUF_R_OE")
	)
	(segment
		(start 187.055506 -125.468634)
		(end 186.9948 -125.407928)
		(width 0.10668)
		(layer "B.Cu")
		(net "CPU1_JTAG_BUF_R_OE")
	)
	(segment
		(start 188.09716 -121.045224)
		(end 188.308234 -120.83415)
		(width 0.10668)
		(layer "B.Cu")
		(net "CPU1_JTAG_BUF_R_OE")
	)
	(segment
		(start 186.9948 -125.222)
		(end 187.510674 -123.976384)
		(width 0.10668)
		(layer "B.Cu")
		(net "CPU1_JTAG_BUF_R_OE")
	)
	(segment
		(start 187.510674 -121.283476)
		(end 187.748926 -121.045224)
		(width 0.10668)
		(layer "B.Cu")
		(net "CPU1_JTAG_BUF_R_OE")
	)
	(segment
		(start 186.9948 -125.407928)
		(end 186.9948 -125.222)
		(width 0.10668)
		(layer "B.Cu")
		(net "CPU1_JTAG_BUF_R_OE")
	)
	(segment
		(start 188.308234 -119.446548)
		(end 188.712094 -119.042688)
		(width 0.10668)
		(layer "B.Cu")
		(net "CPU1_JTAG_BUF_R_OE")
	)
	(segment
		(start 187.055506 -126.433326)
		(end 187.055506 -125.468634)
		(width 0.10668)
		(layer "B.Cu")
		(net "CPU1_JTAG_BUF_R_OE")
	)
	(segment
		(start 187.510674 -123.976384)
		(end 187.510674 -121.283476)
		(width 0.10668)
		(layer "B.Cu")
		(net "CPU1_JTAG_BUF_R_OE")
	)
	(segment
		(start 275.765768 -101.661468)
		(end 275.047964 -102.379272)
		(width 0.10668)
		(layer "F.Cu")
		(net "CPU1_JTAG_BUF_OE")
	)
	(segment
		(start 276.825964 -101.661468)
		(end 275.765768 -101.661468)
		(width 0.10668)
		(layer "F.Cu")
		(net "CPU1_JTAG_BUF_OE")
	)
	(segment
		(start 278.56815 -99.919282)
		(end 276.825964 -101.661468)
		(width 0.10668)
		(layer "F.Cu")
		(net "CPU1_JTAG_BUF_OE")
	)
	(segment
		(start 278.666194 -99.919282)
		(end 278.56815 -99.919282)
		(width 0.10668)
		(layer "F.Cu")
		(net "CPU1_JTAG_BUF_OE")
	)
	(via
		(at 188.372496 -147.499578)
		(size 0.508)
		(drill 0.254)
		(layers "F.Cu" "B.Cu")
		(net "CPU1_JTAG_BUF_OE")
	)
	(via
		(at 188.087 -130.393948)
		(size 0.508)
		(drill 0.254)
		(layers "F.Cu" "B.Cu")
		(net "CPU1_JTAG_BUF_OE")
	)
	(via
		(at 275.047964 -102.379272)
		(size 0.508)
		(drill 0.254)
		(layers "F.Cu" "B.Cu")
		(net "CPU1_JTAG_BUF_OE")
	)
	(via
		(at 266.942824 -150.13686)
		(size 0.508)
		(drill 0.254)
		(layers "F.Cu" "B.Cu")
		(net "CPU1_JTAG_BUF_OE")
	)
	(segment
		(start 188.087 -128.562608)
		(end 187.055506 -127.531114)
		(width 0.10668)
		(layer "B.Cu")
		(net "CPU1_JTAG_BUF_OE")
	)
	(segment
		(start 187.055506 -127.531114)
		(end 187.055506 -127.233426)
		(width 0.10668)
		(layer "B.Cu")
		(net "CPU1_JTAG_BUF_OE")
	)
	(segment
		(start 188.087 -130.393948)
		(end 188.087 -128.562608)
		(width 0.10668)
		(layer "B.Cu")
		(net "CPU1_JTAG_BUF_OE")
	)
	(segment
		(start 232.645966 -147.472146)
		(end 236.795564 -147.472146)
		(width 0.11684)
		(layer "In2.Cu")
		(net "CPU1_JTAG_BUF_OE")
	)
	(segment
		(start 221.072456 -147.001738)
		(end 221.490286 -146.583908)
		(width 0.11684)
		(layer "In2.Cu")
		(net "CPU1_JTAG_BUF_OE")
	)
	(segment
		(start 200.611994 -145.412714)
		(end 217.628216 -145.412714)
		(width 0.11684)
		(layer "In2.Cu")
		(net "CPU1_JTAG_BUF_OE")
	)
	(segment
		(start 196.851778 -145.412714)
		(end 197.609714 -144.654778)
		(width 0.11684)
		(layer "In2.Cu")
		(net "CPU1_JTAG_BUF_OE")
	)
	(segment
		(start 237.534958 -148.21154)
		(end 246.691912 -148.21154)
		(width 0.11684)
		(layer "In2.Cu")
		(net "CPU1_JTAG_BUF_OE")
	)
	(segment
		(start 257.694684 -152.769062)
		(end 264.310622 -152.769062)
		(width 0.11684)
		(layer "In2.Cu")
		(net "CPU1_JTAG_BUF_OE")
	)
	(segment
		(start 221.490286 -146.583908)
		(end 231.757728 -146.583908)
		(width 0.11684)
		(layer "In2.Cu")
		(net "CPU1_JTAG_BUF_OE")
	)
	(segment
		(start 188.372496 -147.499578)
		(end 188.905388 -146.966686)
		(width 0.11684)
		(layer "In2.Cu")
		(net "CPU1_JTAG_BUF_OE")
	)
	(segment
		(start 264.310622 -152.769062)
		(end 266.942824 -150.13686)
		(width 0.11684)
		(layer "In2.Cu")
		(net "CPU1_JTAG_BUF_OE")
	)
	(segment
		(start 219.21724 -147.001738)
		(end 221.072456 -147.001738)
		(width 0.11684)
		(layer "In2.Cu")
		(net "CPU1_JTAG_BUF_OE")
	)
	(segment
		(start 192.656968 -145.412714)
		(end 196.851778 -145.412714)
		(width 0.11684)
		(layer "In2.Cu")
		(net "CPU1_JTAG_BUF_OE")
	)
	(segment
		(start 236.795564 -147.472146)
		(end 237.534958 -148.21154)
		(width 0.11684)
		(layer "In2.Cu")
		(net "CPU1_JTAG_BUF_OE")
	)
	(segment
		(start 231.757728 -146.583908)
		(end 232.645966 -147.472146)
		(width 0.11684)
		(layer "In2.Cu")
		(net "CPU1_JTAG_BUF_OE")
	)
	(segment
		(start 197.609714 -144.654778)
		(end 199.854058 -144.654778)
		(width 0.11684)
		(layer "In2.Cu")
		(net "CPU1_JTAG_BUF_OE")
	)
	(segment
		(start 217.628216 -145.412714)
		(end 219.21724 -147.001738)
		(width 0.11684)
		(layer "In2.Cu")
		(net "CPU1_JTAG_BUF_OE")
	)
	(segment
		(start 199.854058 -144.654778)
		(end 200.611994 -145.412714)
		(width 0.11684)
		(layer "In2.Cu")
		(net "CPU1_JTAG_BUF_OE")
	)
	(segment
		(start 188.905388 -146.966686)
		(end 192.656968 -145.412714)
		(width 0.11684)
		(layer "In2.Cu")
		(net "CPU1_JTAG_BUF_OE")
	)
	(segment
		(start 246.691912 -148.21154)
		(end 257.694684 -152.769062)
		(width 0.11684)
		(layer "In2.Cu")
		(net "CPU1_JTAG_BUF_OE")
	)
	(segment
		(start 189.322202 -135.749792)
		(end 188.48578 -134.91337)
		(width 0.11684)
		(layer "In4.Cu")
		(net "CPU1_JTAG_BUF_OE")
	)
	(segment
		(start 275.047964 -103.227632)
		(end 275.624036 -103.803704)
		(width 0.11684)
		(layer "In4.Cu")
		(net "CPU1_JTAG_BUF_OE")
	)
	(segment
		(start 188.372496 -147.499578)
		(end 189.358016 -146.514058)
		(width 0.11684)
		(layer "In4.Cu")
		(net "CPU1_JTAG_BUF_OE")
	)
	(segment
		(start 188.49848 -130.805428)
		(end 188.087 -130.393948)
		(width 0.11684)
		(layer "In4.Cu")
		(net "CPU1_JTAG_BUF_OE")
	)
	(segment
		(start 189.911736 -140.222478)
		(end 188.77661 -139.087352)
		(width 0.11684)
		(layer "In4.Cu")
		(net "CPU1_JTAG_BUF_OE")
	)
	(segment
		(start 274.44827 -115.350544)
		(end 267.551916 -122.246898)
		(width 0.11684)
		(layer "In4.Cu")
		(net "CPU1_JTAG_BUF_OE")
	)
	(segment
		(start 274.44827 -111.035592)
		(end 274.44827 -115.350544)
		(width 0.11684)
		(layer "In4.Cu")
		(net "CPU1_JTAG_BUF_OE")
	)
	(segment
		(start 275.624036 -103.803704)
		(end 275.624036 -109.859826)
		(width 0.11684)
		(layer "In4.Cu")
		(net "CPU1_JTAG_BUF_OE")
	)
	(segment
		(start 275.047964 -102.379272)
		(end 275.047964 -103.227632)
		(width 0.11684)
		(layer "In4.Cu")
		(net "CPU1_JTAG_BUF_OE")
	)
	(segment
		(start 188.533024 -130.805428)
		(end 188.49848 -130.805428)
		(width 0.11684)
		(layer "In4.Cu")
		(net "CPU1_JTAG_BUF_OE")
	)
	(segment
		(start 188.48578 -134.91337)
		(end 188.48578 -134.489952)
		(width 0.11684)
		(layer "In4.Cu")
		(net "CPU1_JTAG_BUF_OE")
	)
	(segment
		(start 189.911736 -140.824712)
		(end 189.911736 -140.222478)
		(width 0.11684)
		(layer "In4.Cu")
		(net "CPU1_JTAG_BUF_OE")
	)
	(segment
		(start 188.77661 -138.159998)
		(end 189.322202 -137.614406)
		(width 0.11684)
		(layer "In4.Cu")
		(net "CPU1_JTAG_BUF_OE")
	)
	(segment
		(start 270.703548 -128.8796)
		(end 270.703548 -146.376136)
		(width 0.11684)
		(layer "In4.Cu")
		(net "CPU1_JTAG_BUF_OE")
	)
	(segment
		(start 189.322202 -137.614406)
		(end 189.322202 -135.749792)
		(width 0.11684)
		(layer "In4.Cu")
		(net "CPU1_JTAG_BUF_OE")
	)
	(segment
		(start 267.551916 -125.727968)
		(end 270.703548 -128.8796)
		(width 0.11684)
		(layer "In4.Cu")
		(net "CPU1_JTAG_BUF_OE")
	)
	(segment
		(start 189.358016 -141.378432)
		(end 189.911736 -140.824712)
		(width 0.11684)
		(layer "In4.Cu")
		(net "CPU1_JTAG_BUF_OE")
	)
	(segment
		(start 275.624036 -109.859826)
		(end 274.44827 -111.035592)
		(width 0.11684)
		(layer "In4.Cu")
		(net "CPU1_JTAG_BUF_OE")
	)
	(segment
		(start 189.358016 -146.514058)
		(end 189.358016 -141.378432)
		(width 0.11684)
		(layer "In4.Cu")
		(net "CPU1_JTAG_BUF_OE")
	)
	(segment
		(start 188.867288 -131.139692)
		(end 188.533024 -130.805428)
		(width 0.11684)
		(layer "In4.Cu")
		(net "CPU1_JTAG_BUF_OE")
	)
	(segment
		(start 188.77661 -139.087352)
		(end 188.77661 -138.159998)
		(width 0.11684)
		(layer "In4.Cu")
		(net "CPU1_JTAG_BUF_OE")
	)
	(segment
		(start 270.703548 -146.376136)
		(end 266.942824 -150.13686)
		(width 0.11684)
		(layer "In4.Cu")
		(net "CPU1_JTAG_BUF_OE")
	)
	(segment
		(start 267.551916 -122.246898)
		(end 267.551916 -125.727968)
		(width 0.11684)
		(layer "In4.Cu")
		(net "CPU1_JTAG_BUF_OE")
	)
	(segment
		(start 188.48578 -134.489952)
		(end 188.867288 -134.108444)
		(width 0.11684)
		(layer "In4.Cu")
		(net "CPU1_JTAG_BUF_OE")
	)
	(segment
		(start 188.867288 -134.108444)
		(end 188.867288 -131.139692)
		(width 0.11684)
		(layer "In4.Cu")
		(net "CPU1_JTAG_BUF_OE")
	)
	(segment
		(start 229.460044 -157.196028)
		(end 230.05923 -156.596842)
		(width 0.10668)
		(layer "F.Cu")
		(net "CPU1_HDT_BYPASS_SEL")
	)
	(segment
		(start 217.216736 -136.73455)
		(end 215.377014 -136.73455)
		(width 0.10668)
		(layer "F.Cu")
		(net "CPU1_HDT_BYPASS_SEL")
	)
	(segment
		(start 213.851998 -136.73455)
		(end 213.835488 -136.71804)
		(width 0.10668)
		(layer "F.Cu")
		(net "CPU1_HDT_BYPASS_SEL")
	)
	(segment
		(start 232.889806 -159.672528)
		(end 231.990392 -159.672528)
		(width 0.10668)
		(layer "F.Cu")
		(net "CPU1_HDT_BYPASS_SEL")
	)
	(segment
		(start 231.91724 -155.989528)
		(end 232.889806 -155.989528)
		(width 0.10668)
		(layer "F.Cu")
		(net "CPU1_HDT_BYPASS_SEL")
	)
	(segment
		(start 232.889806 -155.989528)
		(end 233.931206 -155.989528)
		(width 0.10668)
		(layer "F.Cu")
		(net "CPU1_HDT_BYPASS_SEL")
	)
	(segment
		(start 230.300784 -160.373822)
		(end 229.460044 -159.533082)
		(width 0.10668)
		(layer "F.Cu")
		(net "CPU1_HDT_BYPASS_SEL")
	)
	(segment
		(start 231.289098 -160.373822)
		(end 230.300784 -160.373822)
		(width 0.10668)
		(layer "F.Cu")
		(net "CPU1_HDT_BYPASS_SEL")
	)
	(segment
		(start 230.05923 -156.596842)
		(end 231.309926 -156.596842)
		(width 0.10668)
		(layer "F.Cu")
		(net "CPU1_HDT_BYPASS_SEL")
	)
	(segment
		(start 215.377014 -136.73455)
		(end 213.851998 -136.73455)
		(width 0.10668)
		(layer "F.Cu")
		(net "CPU1_HDT_BYPASS_SEL")
	)
	(segment
		(start 192.151 -134.511796)
		(end 192.071244 -134.591552)
		(width 0.10668)
		(layer "F.Cu")
		(net "CPU1_HDT_BYPASS_SEL")
	)
	(segment
		(start 231.990392 -159.672528)
		(end 231.289098 -160.373822)
		(width 0.10668)
		(layer "F.Cu")
		(net "CPU1_HDT_BYPASS_SEL")
	)
	(segment
		(start 231.309926 -156.596842)
		(end 231.91724 -155.989528)
		(width 0.10668)
		(layer "F.Cu")
		(net "CPU1_HDT_BYPASS_SEL")
	)
	(segment
		(start 192.151 -133.968998)
		(end 192.151 -134.511796)
		(width 0.10668)
		(layer "F.Cu")
		(net "CPU1_HDT_BYPASS_SEL")
	)
	(segment
		(start 229.460044 -159.533082)
		(end 229.460044 -157.196028)
		(width 0.10668)
		(layer "F.Cu")
		(net "CPU1_HDT_BYPASS_SEL")
	)
	(via
		(at 215.377014 -136.73455)
		(size 0.508)
		(drill 0.254)
		(layers "F.Cu" "B.Cu")
		(net "CPU1_HDT_BYPASS_SEL")
	)
	(via
		(at 192.071244 -134.591552)
		(size 0.508)
		(drill 0.254)
		(layers "F.Cu" "B.Cu")
		(net "CPU1_HDT_BYPASS_SEL")
	)
	(via
		(at 233.931206 -155.989528)
		(size 0.508)
		(drill 0.254)
		(layers "F.Cu" "B.Cu")
		(net "CPU1_HDT_BYPASS_SEL")
	)
	(segment
		(start 202.083924 -135.609076)
		(end 196.82968 -135.609076)
		(width 0.11684)
		(layer "In6.Cu")
		(net "CPU1_HDT_BYPASS_SEL")
	)
	(segment
		(start 194.695064 -135.207248)
		(end 192.68694 -135.207248)
		(width 0.11684)
		(layer "In6.Cu")
		(net "CPU1_HDT_BYPASS_SEL")
	)
	(segment
		(start 203.073 -134.62)
		(end 202.083924 -135.609076)
		(width 0.11684)
		(layer "In6.Cu")
		(net "CPU1_HDT_BYPASS_SEL")
	)
	(segment
		(start 196.82968 -135.609076)
		(end 196.403214 -136.035542)
		(width 0.11684)
		(layer "In6.Cu")
		(net "CPU1_HDT_BYPASS_SEL")
	)
	(segment
		(start 195.523358 -136.035542)
		(end 194.695064 -135.207248)
		(width 0.11684)
		(layer "In6.Cu")
		(net "CPU1_HDT_BYPASS_SEL")
	)
	(segment
		(start 215.377014 -136.73455)
		(end 214.597234 -136.73455)
		(width 0.11684)
		(layer "In6.Cu")
		(net "CPU1_HDT_BYPASS_SEL")
	)
	(segment
		(start 196.403214 -136.035542)
		(end 195.523358 -136.035542)
		(width 0.11684)
		(layer "In6.Cu")
		(net "CPU1_HDT_BYPASS_SEL")
	)
	(segment
		(start 206.631794 -134.62)
		(end 203.073 -134.62)
		(width 0.11684)
		(layer "In6.Cu")
		(net "CPU1_HDT_BYPASS_SEL")
	)
	(segment
		(start 214.597234 -136.73455)
		(end 213.231984 -135.3693)
		(width 0.11684)
		(layer "In6.Cu")
		(net "CPU1_HDT_BYPASS_SEL")
	)
	(segment
		(start 207.381094 -135.3693)
		(end 206.631794 -134.62)
		(width 0.11684)
		(layer "In6.Cu")
		(net "CPU1_HDT_BYPASS_SEL")
	)
	(segment
		(start 213.231984 -135.3693)
		(end 207.381094 -135.3693)
		(width 0.11684)
		(layer "In6.Cu")
		(net "CPU1_HDT_BYPASS_SEL")
	)
	(segment
		(start 192.68694 -135.207248)
		(end 192.071244 -134.591552)
		(width 0.11684)
		(layer "In6.Cu")
		(net "CPU1_HDT_BYPASS_SEL")
	)
	(segment
		(start 232.070656 -154.128978)
		(end 233.931206 -155.989528)
		(width 0.11684)
		(layer "In11.Cu")
		(net "CPU1_HDT_BYPASS_SEL")
	)
	(segment
		(start 217.39352 -141.62659)
		(end 217.39352 -150.22957)
		(width 0.11684)
		(layer "In11.Cu")
		(net "CPU1_HDT_BYPASS_SEL")
	)
	(segment
		(start 215.377014 -136.73455)
		(end 215.377014 -139.610084)
		(width 0.11684)
		(layer "In11.Cu")
		(net "CPU1_HDT_BYPASS_SEL")
	)
	(segment
		(start 215.377014 -139.610084)
		(end 217.39352 -141.62659)
		(width 0.11684)
		(layer "In11.Cu")
		(net "CPU1_HDT_BYPASS_SEL")
	)
	(segment
		(start 217.39352 -150.22957)
		(end 221.292928 -154.128978)
		(width 0.11684)
		(layer "In11.Cu")
		(net "CPU1_HDT_BYPASS_SEL")
	)
	(segment
		(start 221.292928 -154.128978)
		(end 232.070656 -154.128978)
		(width 0.11684)
		(layer "In11.Cu")
		(net "CPU1_HDT_BYPASS_SEL")
	)
	(segment
		(start 100.641658 -313.463432)
		(end 107.938316 -320.76009)
		(width 0.10668)
		(layer "F.Cu")
		(net "FM_CPU1_BMC_RST_N")
	)
	(segment
		(start 133.69798 -294.880284)
		(end 134.164832 -295.146222)
		(width 0.10668)
		(layer "F.Cu")
		(net "FM_CPU1_BMC_RST_N")
	)
	(segment
		(start 86.856316 -302.25873)
		(end 86.856316 -309.376318)
		(width 0.10668)
		(layer "F.Cu")
		(net "FM_CPU1_BMC_RST_N")
	)
	(segment
		(start 7.795006 -201.821034)
		(end 13.487146 -207.513174)
		(width 0.10668)
		(layer "F.Cu")
		(net "FM_CPU1_BMC_RST_N")
	)
	(segment
		(start 107.938316 -320.76009)
		(end 107.938316 -321.618356)
		(width 0.10668)
		(layer "F.Cu")
		(net "FM_CPU1_BMC_RST_N")
	)
	(segment
		(start 88.683592 -126.63678)
		(end 78.083156 -137.237216)
		(width 0.10668)
		(layer "F.Cu")
		(net "FM_CPU1_BMC_RST_N")
	)
	(segment
		(start 179.705 -99.894898)
		(end 179.705 -99.278948)
		(width 0.10668)
		(layer "F.Cu")
		(net "FM_CPU1_BMC_RST_N")
	)
	(segment
		(start 107.938316 -321.618356)
		(end 107.702096 -321.854576)
		(width 0.10668)
		(layer "F.Cu")
		(net "FM_CPU1_BMC_RST_N")
	)
	(segment
		(start 99.210622 -113.458752)
		(end 88.683592 -123.985782)
		(width 0.10668)
		(layer "F.Cu")
		(net "FM_CPU1_BMC_RST_N")
	)
	(segment
		(start 25.263856 -145.7325)
		(end 17.995138 -153.001218)
		(width 0.10668)
		(layer "F.Cu")
		(net "FM_CPU1_BMC_RST_N")
	)
	(segment
		(start 17.995138 -153.001218)
		(end 17.995138 -173.40453)
		(width 0.10668)
		(layer "F.Cu")
		(net "FM_CPU1_BMC_RST_N")
	)
	(segment
		(start 7.795006 -183.604662)
		(end 7.795006 -201.821034)
		(width 0.10668)
		(layer "F.Cu")
		(net "FM_CPU1_BMC_RST_N")
	)
	(segment
		(start 78.083156 -137.237216)
		(end 44.541694 -137.237216)
		(width 0.10668)
		(layer "F.Cu")
		(net "FM_CPU1_BMC_RST_N")
	)
	(segment
		(start 79.887826 -300.57979)
		(end 85.177376 -300.57979)
		(width 0.10668)
		(layer "F.Cu")
		(net "FM_CPU1_BMC_RST_N")
	)
	(segment
		(start 13.487146 -318.196722)
		(end 15.920466 -320.630042)
		(width 0.10668)
		(layer "F.Cu")
		(net "FM_CPU1_BMC_RST_N")
	)
	(segment
		(start 90.94343 -313.463432)
		(end 100.641658 -313.463432)
		(width 0.10668)
		(layer "F.Cu")
		(net "FM_CPU1_BMC_RST_N")
	)
	(segment
		(start 62.270132 -320.630042)
		(end 72.609964 -310.29021)
		(width 0.10668)
		(layer "F.Cu")
		(net "FM_CPU1_BMC_RST_N")
	)
	(segment
		(start 74.539602 -310.29021)
		(end 77.276452 -307.55336)
		(width 0.10668)
		(layer "F.Cu")
		(net "FM_CPU1_BMC_RST_N")
	)
	(segment
		(start 131.721352 -127.438404)
		(end 117.7417 -113.458752)
		(width 0.10668)
		(layer "F.Cu")
		(net "FM_CPU1_BMC_RST_N")
	)
	(segment
		(start 134.38251 -127.438404)
		(end 131.721352 -127.438404)
		(width 0.10668)
		(layer "F.Cu")
		(net "FM_CPU1_BMC_RST_N")
	)
	(segment
		(start 15.920466 -320.630042)
		(end 62.270132 -320.630042)
		(width 0.10668)
		(layer "F.Cu")
		(net "FM_CPU1_BMC_RST_N")
	)
	(segment
		(start 155.421584 -135.935212)
		(end 142.879318 -135.935212)
		(width 0.10668)
		(layer "F.Cu")
		(net "FM_CPU1_BMC_RST_N")
	)
	(segment
		(start 142.879318 -135.935212)
		(end 134.38251 -127.438404)
		(width 0.10668)
		(layer "F.Cu")
		(net "FM_CPU1_BMC_RST_N")
	)
	(segment
		(start 13.487146 -207.513174)
		(end 13.487146 -318.196722)
		(width 0.10668)
		(layer "F.Cu")
		(net "FM_CPU1_BMC_RST_N")
	)
	(segment
		(start 44.541694 -137.237216)
		(end 36.04641 -145.7325)
		(width 0.10668)
		(layer "F.Cu")
		(net "FM_CPU1_BMC_RST_N")
	)
	(segment
		(start 77.276452 -307.55336)
		(end 77.276452 -304.612294)
		(width 0.10668)
		(layer "F.Cu")
		(net "FM_CPU1_BMC_RST_N")
	)
	(segment
		(start 85.177376 -300.57979)
		(end 86.856316 -302.25873)
		(width 0.10668)
		(layer "F.Cu")
		(net "FM_CPU1_BMC_RST_N")
	)
	(segment
		(start 86.856316 -309.376318)
		(end 90.94343 -313.463432)
		(width 0.10668)
		(layer "F.Cu")
		(net "FM_CPU1_BMC_RST_N")
	)
	(segment
		(start 17.995138 -173.40453)
		(end 7.795006 -183.604662)
		(width 0.10668)
		(layer "F.Cu")
		(net "FM_CPU1_BMC_RST_N")
	)
	(segment
		(start 72.609964 -310.29021)
		(end 74.539602 -310.29021)
		(width 0.10668)
		(layer "F.Cu")
		(net "FM_CPU1_BMC_RST_N")
	)
	(segment
		(start 117.7417 -113.458752)
		(end 99.210622 -113.458752)
		(width 0.10668)
		(layer "F.Cu")
		(net "FM_CPU1_BMC_RST_N")
	)
	(segment
		(start 36.04641 -145.7325)
		(end 25.263856 -145.7325)
		(width 0.10668)
		(layer "F.Cu")
		(net "FM_CPU1_BMC_RST_N")
	)
	(segment
		(start 78.281276 -302.18634)
		(end 79.887826 -300.57979)
		(width 0.10668)
		(layer "F.Cu")
		(net "FM_CPU1_BMC_RST_N")
	)
	(segment
		(start 77.276452 -304.612294)
		(end 78.281276 -302.18634)
		(width 0.10668)
		(layer "F.Cu")
		(net "FM_CPU1_BMC_RST_N")
	)
	(segment
		(start 88.683592 -123.985782)
		(end 88.683592 -126.63678)
		(width 0.10668)
		(layer "F.Cu")
		(net "FM_CPU1_BMC_RST_N")
	)
	(via
		(at 145.318734 -111.007652)
		(size 0.508)
		(drill 0.254)
		(layers "F.Cu" "B.Cu")
		(net "FM_CPU1_BMC_RST_N")
	)
	(via
		(at 155.421584 -135.935212)
		(size 0.508)
		(drill 0.254)
		(layers "F.Cu" "B.Cu")
		(net "FM_CPU1_BMC_RST_N")
	)
	(via
		(at 142.581884 -312.050938)
		(size 0.508)
		(drill 0.254)
		(layers "F.Cu" "B.Cu")
		(net "FM_CPU1_BMC_RST_N")
	)
	(via
		(at 107.702096 -321.854576)
		(size 0.508)
		(drill 0.254)
		(layers "F.Cu" "B.Cu")
		(net "FM_CPU1_BMC_RST_N")
	)
	(via
		(at 134.164832 -295.146222)
		(size 0.4064)
		(drill 0.2032)
		(layers "F.Cu" "B.Cu")
		(net "FM_CPU1_BMC_RST_N")
	)
	(via
		(at 179.705 -99.278948)
		(size 0.508)
		(drill 0.254)
		(layers "F.Cu" "B.Cu")
		(net "FM_CPU1_BMC_RST_N")
	)
	(segment
		(start 142.166848 -314.194698)
		(end 143.46682 -315.49467)
		(width 0.10668)
		(layer "B.Cu")
		(net "FM_CPU1_BMC_RST_N")
	)
	(segment
		(start 142.581884 -312.050938)
		(end 142.166848 -312.465974)
		(width 0.10668)
		(layer "B.Cu")
		(net "FM_CPU1_BMC_RST_N")
	)
	(segment
		(start 142.166848 -312.465974)
		(end 142.166848 -314.194698)
		(width 0.10668)
		(layer "B.Cu")
		(net "FM_CPU1_BMC_RST_N")
	)
	(segment
		(start 143.46682 -315.49467)
		(end 144.532604 -315.49467)
		(width 0.10668)
		(layer "B.Cu")
		(net "FM_CPU1_BMC_RST_N")
	)
	(segment
		(start 163.290758 -105.07345)
		(end 163.290758 -104.711754)
		(width 0.11684)
		(layer "In2.Cu")
		(net "FM_CPU1_BMC_RST_N")
	)
	(segment
		(start 142.581884 -312.050938)
		(end 141.512036 -312.050938)
		(width 0.11684)
		(layer "In2.Cu")
		(net "FM_CPU1_BMC_RST_N")
	)
	(segment
		(start 134.919974 -294.687752)
		(end 134.787894 -294.819832)
		(width 0.11684)
		(layer "In2.Cu")
		(net "FM_CPU1_BMC_RST_N")
	)
	(segment
		(start 145.318734 -110.049564)
		(end 148.993352 -106.374946)
		(width 0.11684)
		(layer "In2.Cu")
		(net "FM_CPU1_BMC_RST_N")
	)
	(segment
		(start 134.787894 -294.819832)
		(end 134.491222 -294.819832)
		(width 0.11684)
		(layer "In2.Cu")
		(net "FM_CPU1_BMC_RST_N")
	)
	(segment
		(start 107.702096 -321.854576)
		(end 132.778246 -321.854576)
		(width 0.11684)
		(layer "In2.Cu")
		(net "FM_CPU1_BMC_RST_N")
	)
	(segment
		(start 135.864854 -294.705532)
		(end 135.755634 -294.814752)
		(width 0.11684)
		(layer "In2.Cu")
		(net "FM_CPU1_BMC_RST_N")
	)
	(segment
		(start 168.228518 -101.876352)
		(end 170.208702 -99.896168)
		(width 0.11684)
		(layer "In2.Cu")
		(net "FM_CPU1_BMC_RST_N")
	)
	(segment
		(start 159.24784 -106.623358)
		(end 161.74085 -106.623358)
		(width 0.11684)
		(layer "In2.Cu")
		(net "FM_CPU1_BMC_RST_N")
	)
	(segment
		(start 163.290758 -104.711754)
		(end 164.80536 -103.197152)
		(width 0.11684)
		(layer "In2.Cu")
		(net "FM_CPU1_BMC_RST_N")
	)
	(segment
		(start 151.189944 -106.374946)
		(end 152.027128 -107.21213)
		(width 0.11684)
		(layer "In2.Cu")
		(net "FM_CPU1_BMC_RST_N")
	)
	(segment
		(start 145.318734 -111.007652)
		(end 145.318734 -110.049564)
		(width 0.11684)
		(layer "In2.Cu")
		(net "FM_CPU1_BMC_RST_N")
	)
	(segment
		(start 154.905964 -107.786424)
		(end 158.084774 -107.786424)
		(width 0.11684)
		(layer "In2.Cu")
		(net "FM_CPU1_BMC_RST_N")
	)
	(segment
		(start 148.993352 -106.374946)
		(end 151.189944 -106.374946)
		(width 0.11684)
		(layer "In2.Cu")
		(net "FM_CPU1_BMC_RST_N")
	)
	(segment
		(start 152.027128 -107.21213)
		(end 154.33167 -107.21213)
		(width 0.11684)
		(layer "In2.Cu")
		(net "FM_CPU1_BMC_RST_N")
	)
	(segment
		(start 136.250934 -294.705532)
		(end 135.864854 -294.705532)
		(width 0.11684)
		(layer "In2.Cu")
		(net "FM_CPU1_BMC_RST_N")
	)
	(segment
		(start 154.33167 -107.21213)
		(end 154.905964 -107.786424)
		(width 0.11684)
		(layer "In2.Cu")
		(net "FM_CPU1_BMC_RST_N")
	)
	(segment
		(start 136.466834 -307.005736)
		(end 136.466834 -294.921432)
		(width 0.11684)
		(layer "In2.Cu")
		(net "FM_CPU1_BMC_RST_N")
	)
	(segment
		(start 141.512036 -312.050938)
		(end 136.466834 -307.005736)
		(width 0.11684)
		(layer "In2.Cu")
		(net "FM_CPU1_BMC_RST_N")
	)
	(segment
		(start 132.778246 -321.854576)
		(end 142.581884 -312.050938)
		(width 0.11684)
		(layer "In2.Cu")
		(net "FM_CPU1_BMC_RST_N")
	)
	(segment
		(start 179.08778 -99.896168)
		(end 179.705 -99.278948)
		(width 0.11684)
		(layer "In2.Cu")
		(net "FM_CPU1_BMC_RST_N")
	)
	(segment
		(start 164.80536 -103.197152)
		(end 166.131748 -103.197152)
		(width 0.11684)
		(layer "In2.Cu")
		(net "FM_CPU1_BMC_RST_N")
	)
	(segment
		(start 166.131748 -103.197152)
		(end 167.452548 -101.876352)
		(width 0.11684)
		(layer "In2.Cu")
		(net "FM_CPU1_BMC_RST_N")
	)
	(segment
		(start 135.755634 -294.814752)
		(end 135.417814 -294.814752)
		(width 0.11684)
		(layer "In2.Cu")
		(net "FM_CPU1_BMC_RST_N")
	)
	(segment
		(start 158.084774 -107.786424)
		(end 159.24784 -106.623358)
		(width 0.11684)
		(layer "In2.Cu")
		(net "FM_CPU1_BMC_RST_N")
	)
	(segment
		(start 135.290814 -294.687752)
		(end 134.919974 -294.687752)
		(width 0.11684)
		(layer "In2.Cu")
		(net "FM_CPU1_BMC_RST_N")
	)
	(segment
		(start 134.491222 -294.819832)
		(end 134.164832 -295.146222)
		(width 0.11684)
		(layer "In2.Cu")
		(net "FM_CPU1_BMC_RST_N")
	)
	(segment
		(start 161.74085 -106.623358)
		(end 163.290758 -105.07345)
		(width 0.11684)
		(layer "In2.Cu")
		(net "FM_CPU1_BMC_RST_N")
	)
	(segment
		(start 136.466834 -294.921432)
		(end 136.250934 -294.705532)
		(width 0.11684)
		(layer "In2.Cu")
		(net "FM_CPU1_BMC_RST_N")
	)
	(segment
		(start 170.208702 -99.896168)
		(end 179.08778 -99.896168)
		(width 0.11684)
		(layer "In2.Cu")
		(net "FM_CPU1_BMC_RST_N")
	)
	(segment
		(start 135.417814 -294.814752)
		(end 135.290814 -294.687752)
		(width 0.11684)
		(layer "In2.Cu")
		(net "FM_CPU1_BMC_RST_N")
	)
	(segment
		(start 167.452548 -101.876352)
		(end 168.228518 -101.876352)
		(width 0.11684)
		(layer "In2.Cu")
		(net "FM_CPU1_BMC_RST_N")
	)
	(segment
		(start 155.421584 -135.935212)
		(end 155.111704 -135.935212)
		(width 0.11684)
		(layer "In15.Cu")
		(net "FM_CPU1_BMC_RST_N")
	)
	(segment
		(start 145.50263 -126.326138)
		(end 145.50263 -119.470424)
		(width 0.11684)
		(layer "In15.Cu")
		(net "FM_CPU1_BMC_RST_N")
	)
	(segment
		(start 144.088612 -112.237774)
		(end 145.318734 -111.007652)
		(width 0.11684)
		(layer "In15.Cu")
		(net "FM_CPU1_BMC_RST_N")
	)
	(segment
		(start 155.111704 -135.935212)
		(end 145.50263 -126.326138)
		(width 0.11684)
		(layer "In15.Cu")
		(net "FM_CPU1_BMC_RST_N")
	)
	(segment
		(start 144.088612 -118.056406)
		(end 144.088612 -112.237774)
		(width 0.11684)
		(layer "In15.Cu")
		(net "FM_CPU1_BMC_RST_N")
	)
	(segment
		(start 145.50263 -119.470424)
		(end 144.088612 -118.056406)
		(width 0.11684)
		(layer "In15.Cu")
		(net "FM_CPU1_BMC_RST_N")
	)
	(segment
		(start 90.987626 -219.31884)
		(end 91.54795 -218.758516)
		(width 0.10668)
		(layer "F.Cu")
		(net "CPU1_FORCE_SELFREFRESH")
	)
	(segment
		(start 88.277954 -222.880428)
		(end 88.277954 -221.682056)
		(width 0.10668)
		(layer "F.Cu")
		(net "CPU1_FORCE_SELFREFRESH")
	)
	(segment
		(start 91.67622 -210.79714)
		(end 91.51112 -210.63204)
		(width 0.10668)
		(layer "F.Cu")
		(net "CPU1_FORCE_SELFREFRESH")
	)
	(segment
		(start 84.751418 -203.873862)
		(end 76.061824 -203.873862)
		(width 0.10668)
		(layer "F.Cu")
		(net "CPU1_FORCE_SELFREFRESH")
	)
	(segment
		(start 91.54795 -218.04503)
		(end 91.67622 -217.91676)
		(width 0.10668)
		(layer "F.Cu")
		(net "CPU1_FORCE_SELFREFRESH")
	)
	(segment
		(start 91.54795 -218.758516)
		(end 91.54795 -218.04503)
		(width 0.10668)
		(layer "F.Cu")
		(net "CPU1_FORCE_SELFREFRESH")
	)
	(segment
		(start 90.64117 -219.31884)
		(end 90.987626 -219.31884)
		(width 0.10668)
		(layer "F.Cu")
		(net "CPU1_FORCE_SELFREFRESH")
	)
	(segment
		(start 91.51112 -210.63204)
		(end 91.509596 -210.63204)
		(width 0.10668)
		(layer "F.Cu")
		(net "CPU1_FORCE_SELFREFRESH")
	)
	(segment
		(start 91.509596 -210.63204)
		(end 84.751418 -203.873862)
		(width 0.10668)
		(layer "F.Cu")
		(net "CPU1_FORCE_SELFREFRESH")
	)
	(segment
		(start 88.277954 -221.682056)
		(end 90.64117 -219.31884)
		(width 0.10668)
		(layer "F.Cu")
		(net "CPU1_FORCE_SELFREFRESH")
	)
	(segment
		(start 91.67622 -217.91676)
		(end 91.67622 -210.79714)
		(width 0.10668)
		(layer "F.Cu")
		(net "CPU1_FORCE_SELFREFRESH")
	)
	(segment
		(start 70.457314 -198.269352)
		(end 68.874894 -198.269352)
		(width 0.10668)
		(layer "F.Cu")
		(net "CPU1_FORCE_SELFREFRESH")
	)
	(segment
		(start 76.061824 -203.873862)
		(end 70.457314 -198.269352)
		(width 0.10668)
		(layer "F.Cu")
		(net "CPU1_FORCE_SELFREFRESH")
	)
	(via
		(at 68.874894 -198.269352)
		(size 0.508)
		(drill 0.254)
		(layers "F.Cu" "B.Cu")
		(net "CPU1_FORCE_SELFREFRESH")
	)
	(via
		(at 198.971154 -126.802134)
		(size 0.508)
		(drill 0.254)
		(layers "F.Cu" "B.Cu")
		(net "CPU1_FORCE_SELFREFRESH")
	)
	(via
		(at 114.829336 -130.01498)
		(size 0.508)
		(drill 0.254)
		(layers "F.Cu" "B.Cu")
		(net "CPU1_FORCE_SELFREFRESH")
	)
	(segment
		(start 197.669658 -126.833376)
		(end 198.939912 -126.833376)
		(width 0.10668)
		(layer "B.Cu")
		(net "CPU1_FORCE_SELFREFRESH")
	)
	(segment
		(start 67.601084 -198.269352)
		(end 67.601084 -196.95414)
		(width 0.10668)
		(layer "B.Cu")
		(net "CPU1_FORCE_SELFREFRESH")
	)
	(segment
		(start 198.939912 -126.833376)
		(end 198.971154 -126.802134)
		(width 0.10668)
		(layer "B.Cu")
		(net "CPU1_FORCE_SELFREFRESH")
	)
	(segment
		(start 67.601084 -198.269352)
		(end 68.874894 -198.269352)
		(width 0.10668)
		(layer "B.Cu")
		(net "CPU1_FORCE_SELFREFRESH")
	)
	(segment
		(start 183.048402 -133.170168)
		(end 183.139842 -133.078728)
		(width 0.11684)
		(layer "In6.Cu")
		(net "CPU1_FORCE_SELFREFRESH")
	)
	(segment
		(start 195.623942 -133.078728)
		(end 198.971154 -129.731516)
		(width 0.11684)
		(layer "In6.Cu")
		(net "CPU1_FORCE_SELFREFRESH")
	)
	(segment
		(start 155.210764 -129.55016)
		(end 157.328616 -131.668012)
		(width 0.11684)
		(layer "In6.Cu")
		(net "CPU1_FORCE_SELFREFRESH")
	)
	(segment
		(start 183.139842 -133.078728)
		(end 195.623942 -133.078728)
		(width 0.11684)
		(layer "In6.Cu")
		(net "CPU1_FORCE_SELFREFRESH")
	)
	(segment
		(start 162.981386 -131.78409)
		(end 170.038268 -131.78409)
		(width 0.11684)
		(layer "In6.Cu")
		(net "CPU1_FORCE_SELFREFRESH")
	)
	(segment
		(start 114.829336 -130.01498)
		(end 115.294156 -129.55016)
		(width 0.11684)
		(layer "In6.Cu")
		(net "CPU1_FORCE_SELFREFRESH")
	)
	(segment
		(start 180.712364 -133.170168)
		(end 183.048402 -133.170168)
		(width 0.11684)
		(layer "In6.Cu")
		(net "CPU1_FORCE_SELFREFRESH")
	)
	(segment
		(start 170.126406 -131.872228)
		(end 179.004976 -131.872228)
		(width 0.11684)
		(layer "In6.Cu")
		(net "CPU1_FORCE_SELFREFRESH")
	)
	(segment
		(start 179.004976 -131.872228)
		(end 180.211476 -133.078728)
		(width 0.11684)
		(layer "In6.Cu")
		(net "CPU1_FORCE_SELFREFRESH")
	)
	(segment
		(start 115.294156 -129.55016)
		(end 155.210764 -129.55016)
		(width 0.11684)
		(layer "In6.Cu")
		(net "CPU1_FORCE_SELFREFRESH")
	)
	(segment
		(start 170.038268 -131.78409)
		(end 170.126406 -131.872228)
		(width 0.11684)
		(layer "In6.Cu")
		(net "CPU1_FORCE_SELFREFRESH")
	)
	(segment
		(start 198.971154 -129.731516)
		(end 198.971154 -126.802134)
		(width 0.11684)
		(layer "In6.Cu")
		(net "CPU1_FORCE_SELFREFRESH")
	)
	(segment
		(start 162.865308 -131.668012)
		(end 162.981386 -131.78409)
		(width 0.11684)
		(layer "In6.Cu")
		(net "CPU1_FORCE_SELFREFRESH")
	)
	(segment
		(start 180.211476 -133.078728)
		(end 180.620924 -133.078728)
		(width 0.11684)
		(layer "In6.Cu")
		(net "CPU1_FORCE_SELFREFRESH")
	)
	(segment
		(start 180.620924 -133.078728)
		(end 180.712364 -133.170168)
		(width 0.11684)
		(layer "In6.Cu")
		(net "CPU1_FORCE_SELFREFRESH")
	)
	(segment
		(start 157.328616 -131.668012)
		(end 162.865308 -131.668012)
		(width 0.11684)
		(layer "In6.Cu")
		(net "CPU1_FORCE_SELFREFRESH")
	)
	(segment
		(start 38.916102 -183.049418)
		(end 38.916102 -187.36056)
		(width 0.11684)
		(layer "In11.Cu")
		(net "CPU1_FORCE_SELFREFRESH")
	)
	(segment
		(start 114.829336 -130.01498)
		(end 108.974382 -135.869934)
		(width 0.11684)
		(layer "In11.Cu")
		(net "CPU1_FORCE_SELFREFRESH")
	)
	(segment
		(start 38.916102 -187.36056)
		(end 40.992044 -189.436502)
		(width 0.11684)
		(layer "In11.Cu")
		(net "CPU1_FORCE_SELFREFRESH")
	)
	(segment
		(start 41.248076 -147.598384)
		(end 41.248076 -155.732734)
		(width 0.11684)
		(layer "In11.Cu")
		(net "CPU1_FORCE_SELFREFRESH")
	)
	(segment
		(start 40.992044 -189.436502)
		(end 60.481464 -189.436502)
		(width 0.11684)
		(layer "In11.Cu")
		(net "CPU1_FORCE_SELFREFRESH")
	)
	(segment
		(start 41.248076 -155.732734)
		(end 33.000188 -163.980622)
		(width 0.11684)
		(layer "In11.Cu")
		(net "CPU1_FORCE_SELFREFRESH")
	)
	(segment
		(start 60.481464 -189.436502)
		(end 68.874894 -197.829932)
		(width 0.11684)
		(layer "In11.Cu")
		(net "CPU1_FORCE_SELFREFRESH")
	)
	(segment
		(start 33.000188 -177.133504)
		(end 38.916102 -183.049418)
		(width 0.11684)
		(layer "In11.Cu")
		(net "CPU1_FORCE_SELFREFRESH")
	)
	(segment
		(start 52.976526 -135.869934)
		(end 41.248076 -147.598384)
		(width 0.11684)
		(layer "In11.Cu")
		(net "CPU1_FORCE_SELFREFRESH")
	)
	(segment
		(start 108.974382 -135.869934)
		(end 52.976526 -135.869934)
		(width 0.11684)
		(layer "In11.Cu")
		(net "CPU1_FORCE_SELFREFRESH")
	)
	(segment
		(start 68.874894 -197.829932)
		(end 68.874894 -198.269352)
		(width 0.11684)
		(layer "In11.Cu")
		(net "CPU1_FORCE_SELFREFRESH")
	)
	(segment
		(start 33.000188 -163.980622)
		(end 33.000188 -177.133504)
		(width 0.11684)
		(layer "In11.Cu")
		(net "CPU1_FORCE_SELFREFRESH")
	)
	(segment
		(start 191.897 -99.894898)
		(end 191.897 -99.278948)
		(width 0.10668)
		(layer "F.Cu")
		(net "CPU1_CORETYPE2")
	)
	(segment
		(start 83.577938 -224.50044)
		(end 83.111086 -224.234502)
		(width 0.10668)
		(layer "F.Cu")
		(net "CPU1_CORETYPE2")
	)
	(via
		(at 83.111086 -224.234502)
		(size 0.4064)
		(drill 0.2032)
		(layers "F.Cu" "B.Cu")
		(net "CPU1_CORETYPE2")
	)
	(via
		(at 191.897 -99.278948)
		(size 0.508)
		(drill 0.254)
		(layers "F.Cu" "B.Cu")
		(net "CPU1_CORETYPE2")
	)
	(via
		(at 116.952014 -126.959868)
		(size 0.508)
		(drill 0.254)
		(layers "F.Cu" "B.Cu")
		(net "CPU1_CORETYPE2")
	)
	(segment
		(start 68.318634 -207.197198)
		(end 83.660234 -222.538798)
		(width 0.10668)
		(layer "B.Cu")
		(net "CPU1_CORETYPE2")
	)
	(segment
		(start 68.318634 -203.901802)
		(end 68.318634 -207.197198)
		(width 0.10668)
		(layer "B.Cu")
		(net "CPU1_CORETYPE2")
	)
	(segment
		(start 83.660234 -223.186752)
		(end 83.111086 -223.7359)
		(width 0.10668)
		(layer "B.Cu")
		(net "CPU1_CORETYPE2")
	)
	(segment
		(start 83.660234 -222.538798)
		(end 83.660234 -223.186752)
		(width 0.10668)
		(layer "B.Cu")
		(net "CPU1_CORETYPE2")
	)
	(segment
		(start 83.111086 -223.7359)
		(end 83.111086 -224.234502)
		(width 0.10668)
		(layer "B.Cu")
		(net "CPU1_CORETYPE2")
	)
	(segment
		(start 181.000654 -103.844852)
		(end 187.331096 -103.844852)
		(width 0.11684)
		(layer "In6.Cu")
		(net "CPU1_CORETYPE2")
	)
	(segment
		(start 163.21278 -120.90908)
		(end 163.21278 -119.254016)
		(width 0.11684)
		(layer "In6.Cu")
		(net "CPU1_CORETYPE2")
	)
	(segment
		(start 174.142146 -114.779806)
		(end 174.142146 -110.70336)
		(width 0.11684)
		(layer "In6.Cu")
		(net "CPU1_CORETYPE2")
	)
	(segment
		(start 155.678886 -126.959868)
		(end 155.988258 -126.650496)
		(width 0.11684)
		(layer "In6.Cu")
		(net "CPU1_CORETYPE2")
	)
	(segment
		(start 166.594282 -117.125496)
		(end 166.953438 -116.76634)
		(width 0.11684)
		(layer "In6.Cu")
		(net "CPU1_CORETYPE2")
	)
	(segment
		(start 165.3413 -117.125496)
		(end 166.594282 -117.125496)
		(width 0.11684)
		(layer "In6.Cu")
		(net "CPU1_CORETYPE2")
	)
	(segment
		(start 157.471364 -126.650496)
		(end 163.21278 -120.90908)
		(width 0.11684)
		(layer "In6.Cu")
		(net "CPU1_CORETYPE2")
	)
	(segment
		(start 166.953438 -116.76634)
		(end 172.155612 -116.76634)
		(width 0.11684)
		(layer "In6.Cu")
		(net "CPU1_CORETYPE2")
	)
	(segment
		(start 116.952014 -126.959868)
		(end 155.678886 -126.959868)
		(width 0.11684)
		(layer "In6.Cu")
		(net "CPU1_CORETYPE2")
	)
	(segment
		(start 174.142146 -110.70336)
		(end 181.000654 -103.844852)
		(width 0.11684)
		(layer "In6.Cu")
		(net "CPU1_CORETYPE2")
	)
	(segment
		(start 163.21278 -119.254016)
		(end 165.3413 -117.125496)
		(width 0.11684)
		(layer "In6.Cu")
		(net "CPU1_CORETYPE2")
	)
	(segment
		(start 155.988258 -126.650496)
		(end 157.471364 -126.650496)
		(width 0.11684)
		(layer "In6.Cu")
		(net "CPU1_CORETYPE2")
	)
	(segment
		(start 172.155612 -116.76634)
		(end 174.142146 -114.779806)
		(width 0.11684)
		(layer "In6.Cu")
		(net "CPU1_CORETYPE2")
	)
	(segment
		(start 187.331096 -103.844852)
		(end 191.897 -99.278948)
		(width 0.11684)
		(layer "In6.Cu")
		(net "CPU1_CORETYPE2")
	)
	(segment
		(start 37.551868 -179.896008)
		(end 40.181022 -182.525162)
		(width 0.11684)
		(layer "In11.Cu")
		(net "CPU1_CORETYPE2")
	)
	(segment
		(start 86.251288 -137.134854)
		(end 84.996274 -138.389868)
		(width 0.11684)
		(layer "In11.Cu")
		(net "CPU1_CORETYPE2")
	)
	(segment
		(start 73.603358 -209.019902)
		(end 83.474306 -218.89085)
		(width 0.11684)
		(layer "In11.Cu")
		(net "CPU1_CORETYPE2")
	)
	(segment
		(start 42.51325 -156.256736)
		(end 37.551868 -161.218118)
		(width 0.11684)
		(layer "In11.Cu")
		(net "CPU1_CORETYPE2")
	)
	(segment
		(start 116.952014 -126.959868)
		(end 116.952014 -130.308096)
		(width 0.11684)
		(layer "In11.Cu")
		(net "CPU1_CORETYPE2")
	)
	(segment
		(start 40.181022 -182.525162)
		(end 40.181022 -186.836304)
		(width 0.11684)
		(layer "In11.Cu")
		(net "CPU1_CORETYPE2")
	)
	(segment
		(start 37.551868 -161.218118)
		(end 37.551868 -179.896008)
		(width 0.11684)
		(layer "In11.Cu")
		(net "CPU1_CORETYPE2")
	)
	(segment
		(start 116.952014 -130.308096)
		(end 110.125256 -137.134854)
		(width 0.11684)
		(layer "In11.Cu")
		(net "CPU1_CORETYPE2")
	)
	(segment
		(start 110.125256 -137.134854)
		(end 86.251288 -137.134854)
		(width 0.11684)
		(layer "In11.Cu")
		(net "CPU1_CORETYPE2")
	)
	(segment
		(start 83.474306 -218.89085)
		(end 83.474306 -223.871282)
		(width 0.11684)
		(layer "In11.Cu")
		(net "CPU1_CORETYPE2")
	)
	(segment
		(start 73.603358 -201.365612)
		(end 73.603358 -209.019902)
		(width 0.11684)
		(layer "In11.Cu")
		(net "CPU1_CORETYPE2")
	)
	(segment
		(start 41.42994 -188.085222)
		(end 60.322968 -188.085222)
		(width 0.11684)
		(layer "In11.Cu")
		(net "CPU1_CORETYPE2")
	)
	(segment
		(start 83.474306 -223.871282)
		(end 83.111086 -224.234502)
		(width 0.11684)
		(layer "In11.Cu")
		(net "CPU1_CORETYPE2")
	)
	(segment
		(start 40.181022 -186.836304)
		(end 41.42994 -188.085222)
		(width 0.11684)
		(layer "In11.Cu")
		(net "CPU1_CORETYPE2")
	)
	(segment
		(start 42.51325 -148.122386)
		(end 42.51325 -156.256736)
		(width 0.11684)
		(layer "In11.Cu")
		(net "CPU1_CORETYPE2")
	)
	(segment
		(start 80.908652 -138.389868)
		(end 79.91602 -137.397236)
		(width 0.11684)
		(layer "In11.Cu")
		(net "CPU1_CORETYPE2")
	)
	(segment
		(start 53.2384 -137.397236)
		(end 42.51325 -148.122386)
		(width 0.11684)
		(layer "In11.Cu")
		(net "CPU1_CORETYPE2")
	)
	(segment
		(start 60.322968 -188.085222)
		(end 73.603358 -201.365612)
		(width 0.11684)
		(layer "In11.Cu")
		(net "CPU1_CORETYPE2")
	)
	(segment
		(start 84.996274 -138.389868)
		(end 80.908652 -138.389868)
		(width 0.11684)
		(layer "In11.Cu")
		(net "CPU1_CORETYPE2")
	)
	(segment
		(start 79.91602 -137.397236)
		(end 53.2384 -137.397236)
		(width 0.11684)
		(layer "In11.Cu")
		(net "CPU1_CORETYPE2")
	)
	(segment
		(start 190.608204 -99.894898)
		(end 190.373 -99.659694)
		(width 0.10668)
		(layer "F.Cu")
		(net "CPU1_CORETYPE1")
	)
	(segment
		(start 72.034146 -203.656946)
		(end 70.965822 -202.588622)
		(width 0.10668)
		(layer "F.Cu")
		(net "CPU1_CORETYPE1")
	)
	(segment
		(start 190.857886 -98.262948)
		(end 190.919608 -98.262948)
		(width 0.10668)
		(layer "F.Cu")
		(net "CPU1_CORETYPE1")
	)
	(segment
		(start 69.529452 -200.60539)
		(end 68.489068 -200.60539)
		(width 0.10668)
		(layer "F.Cu")
		(net "CPU1_CORETYPE1")
	)
	(segment
		(start 82.637884 -221.123256)
		(end 87.909146 -215.851994)
		(width 0.10668)
		(layer "F.Cu")
		(net "CPU1_CORETYPE1")
	)
	(segment
		(start 73.245218 -204.158596)
		(end 72.034146 -203.656946)
		(width 0.10668)
		(layer "F.Cu")
		(net "CPU1_CORETYPE1")
	)
	(segment
		(start 83.926934 -206.12354)
		(end 75.210162 -206.12354)
		(width 0.10668)
		(layer "F.Cu")
		(net "CPU1_CORETYPE1")
	)
	(segment
		(start 190.373 -98.747834)
		(end 190.857886 -98.262948)
		(width 0.10668)
		(layer "F.Cu")
		(net "CPU1_CORETYPE1")
	)
	(segment
		(start 70.965822 -202.04176)
		(end 69.529452 -200.60539)
		(width 0.10668)
		(layer "F.Cu")
		(net "CPU1_CORETYPE1")
	)
	(segment
		(start 68.489068 -200.60539)
		(end 65.19164 -197.307962)
		(width 0.10668)
		(layer "F.Cu")
		(net "CPU1_CORETYPE1")
	)
	(segment
		(start 65.19164 -196.387974)
		(end 65.296034 -196.28358)
		(width 0.10668)
		(layer "F.Cu")
		(net "CPU1_CORETYPE1")
	)
	(segment
		(start 82.637884 -222.880428)
		(end 82.637884 -221.123256)
		(width 0.10668)
		(layer "F.Cu")
		(net "CPU1_CORETYPE1")
	)
	(segment
		(start 190.373 -99.659694)
		(end 190.373 -98.747834)
		(width 0.10668)
		(layer "F.Cu")
		(net "CPU1_CORETYPE1")
	)
	(segment
		(start 83.998562 -206.153258)
		(end 83.926934 -206.12354)
		(width 0.10668)
		(layer "F.Cu")
		(net "CPU1_CORETYPE1")
	)
	(segment
		(start 87.909146 -215.851994)
		(end 87.909146 -210.063842)
		(width 0.10668)
		(layer "F.Cu")
		(net "CPU1_CORETYPE1")
	)
	(segment
		(start 70.965822 -202.588622)
		(end 70.965822 -202.04176)
		(width 0.10668)
		(layer "F.Cu")
		(net "CPU1_CORETYPE1")
	)
	(segment
		(start 65.19164 -197.307962)
		(end 65.19164 -196.387974)
		(width 0.10668)
		(layer "F.Cu")
		(net "CPU1_CORETYPE1")
	)
	(segment
		(start 87.909146 -210.063842)
		(end 83.998562 -206.153258)
		(width 0.10668)
		(layer "F.Cu")
		(net "CPU1_CORETYPE1")
	)
	(segment
		(start 190.881 -99.894898)
		(end 190.608204 -99.894898)
		(width 0.10668)
		(layer "F.Cu")
		(net "CPU1_CORETYPE1")
	)
	(segment
		(start 75.210162 -206.12354)
		(end 73.245218 -204.158596)
		(width 0.10668)
		(layer "F.Cu")
		(net "CPU1_CORETYPE1")
	)
	(via
		(at 190.919608 -98.262948)
		(size 0.508)
		(drill 0.254)
		(layers "F.Cu" "B.Cu")
		(net "CPU1_CORETYPE1")
	)
	(via
		(at 65.296034 -196.28358)
		(size 0.508)
		(drill 0.254)
		(layers "F.Cu" "B.Cu")
		(net "CPU1_CORETYPE1")
	)
	(segment
		(start 64.019684 -196.186552)
		(end 65.199006 -196.186552)
		(width 0.10668)
		(layer "B.Cu")
		(net "CPU1_CORETYPE1")
	)
	(segment
		(start 65.199006 -196.186552)
		(end 65.296034 -196.28358)
		(width 0.10668)
		(layer "B.Cu")
		(net "CPU1_CORETYPE1")
	)
	(segment
		(start 72.031606 -134.723886)
		(end 106.651806 -100.103686)
		(width 0.11684)
		(layer "In2.Cu")
		(net "CPU1_CORETYPE1")
	)
	(segment
		(start 189.041786 -99.743768)
		(end 189.347602 -99.437952)
		(width 0.11684)
		(layer "In2.Cu")
		(net "CPU1_CORETYPE1")
	)
	(segment
		(start 43.29938 -168.8592)
		(end 45.061124 -167.097456)
		(width 0.11684)
		(layer "In2.Cu")
		(net "CPU1_CORETYPE1")
	)
	(segment
		(start 65.296034 -196.28358)
		(end 59.96813 -190.955676)
		(width 0.11684)
		(layer "In2.Cu")
		(net "CPU1_CORETYPE1")
	)
	(segment
		(start 181.197758 -94.9071)
		(end 181.197758 -95.206312)
		(width 0.11684)
		(layer "In2.Cu")
		(net "CPU1_CORETYPE1")
	)
	(segment
		(start 59.680348 -134.723886)
		(end 72.031606 -134.723886)
		(width 0.11684)
		(layer "In2.Cu")
		(net "CPU1_CORETYPE1")
	)
	(segment
		(start 187.37453 -99.439476)
		(end 187.678822 -99.743768)
		(width 0.11684)
		(layer "In2.Cu")
		(net "CPU1_CORETYPE1")
	)
	(segment
		(start 157.85465 -102.40645)
		(end 157.85465 -102.311708)
		(width 0.11684)
		(layer "In2.Cu")
		(net "CPU1_CORETYPE1")
	)
	(segment
		(start 43.29938 -184.317894)
		(end 43.29938 -168.8592)
		(width 0.11684)
		(layer "In2.Cu")
		(net "CPU1_CORETYPE1")
	)
	(segment
		(start 187.37453 -98.162872)
		(end 187.37453 -99.439476)
		(width 0.11684)
		(layer "In2.Cu")
		(net "CPU1_CORETYPE1")
	)
	(segment
		(start 189.347602 -99.13874)
		(end 189.75578 -98.730562)
		(width 0.11684)
		(layer "In2.Cu")
		(net "CPU1_CORETYPE1")
	)
	(segment
		(start 163.928298 -96.23806)
		(end 166.731696 -96.23806)
		(width 0.11684)
		(layer "In2.Cu")
		(net "CPU1_CORETYPE1")
	)
	(segment
		(start 180.761386 -94.470728)
		(end 181.197758 -94.9071)
		(width 0.11684)
		(layer "In2.Cu")
		(net "CPU1_CORETYPE1")
	)
	(segment
		(start 181.197758 -95.206312)
		(end 182.271416 -96.27997)
		(width 0.11684)
		(layer "In2.Cu")
		(net "CPU1_CORETYPE1")
	)
	(segment
		(start 155.960572 -102.925372)
		(end 157.335728 -102.925372)
		(width 0.11684)
		(layer "In2.Cu")
		(net "CPU1_CORETYPE1")
	)
	(segment
		(start 106.651806 -100.103686)
		(end 153.138886 -100.103686)
		(width 0.11684)
		(layer "In2.Cu")
		(net "CPU1_CORETYPE1")
	)
	(segment
		(start 182.271416 -96.27997)
		(end 185.491628 -96.27997)
		(width 0.11684)
		(layer "In2.Cu")
		(net "CPU1_CORETYPE1")
	)
	(segment
		(start 59.96813 -190.955676)
		(end 49.937162 -190.955676)
		(width 0.11684)
		(layer "In2.Cu")
		(net "CPU1_CORETYPE1")
	)
	(segment
		(start 185.491628 -96.27997)
		(end 187.37453 -98.162872)
		(width 0.11684)
		(layer "In2.Cu")
		(net "CPU1_CORETYPE1")
	)
	(segment
		(start 166.731696 -96.23806)
		(end 168.499028 -94.470728)
		(width 0.11684)
		(layer "In2.Cu")
		(net "CPU1_CORETYPE1")
	)
	(segment
		(start 45.061124 -149.34311)
		(end 59.680348 -134.723886)
		(width 0.11684)
		(layer "In2.Cu")
		(net "CPU1_CORETYPE1")
	)
	(segment
		(start 187.678822 -99.743768)
		(end 189.041786 -99.743768)
		(width 0.11684)
		(layer "In2.Cu")
		(net "CPU1_CORETYPE1")
	)
	(segment
		(start 157.85465 -102.311708)
		(end 163.928298 -96.23806)
		(width 0.11684)
		(layer "In2.Cu")
		(net "CPU1_CORETYPE1")
	)
	(segment
		(start 45.061124 -167.097456)
		(end 45.061124 -149.34311)
		(width 0.11684)
		(layer "In2.Cu")
		(net "CPU1_CORETYPE1")
	)
	(segment
		(start 153.138886 -100.103686)
		(end 155.960572 -102.925372)
		(width 0.11684)
		(layer "In2.Cu")
		(net "CPU1_CORETYPE1")
	)
	(segment
		(start 49.937162 -190.955676)
		(end 43.29938 -184.317894)
		(width 0.11684)
		(layer "In2.Cu")
		(net "CPU1_CORETYPE1")
	)
	(segment
		(start 189.75578 -98.730562)
		(end 190.451994 -98.730562)
		(width 0.11684)
		(layer "In2.Cu")
		(net "CPU1_CORETYPE1")
	)
	(segment
		(start 189.347602 -99.437952)
		(end 189.347602 -99.13874)
		(width 0.11684)
		(layer "In2.Cu")
		(net "CPU1_CORETYPE1")
	)
	(segment
		(start 168.499028 -94.470728)
		(end 180.761386 -94.470728)
		(width 0.11684)
		(layer "In2.Cu")
		(net "CPU1_CORETYPE1")
	)
	(segment
		(start 190.451994 -98.730562)
		(end 190.919608 -98.262948)
		(width 0.11684)
		(layer "In2.Cu")
		(net "CPU1_CORETYPE1")
	)
	(segment
		(start 157.335728 -102.925372)
		(end 157.85465 -102.40645)
		(width 0.11684)
		(layer "In2.Cu")
		(net "CPU1_CORETYPE1")
	)
	(segment
		(start 87.624666 -215.734138)
		(end 87.624666 -210.181698)
		(width 0.10668)
		(layer "F.Cu")
		(net "CPU1_CORETYPE0")
	)
	(segment
		(start 82.167984 -223.690434)
		(end 82.167984 -221.19082)
		(width 0.10668)
		(layer "F.Cu")
		(net "CPU1_CORETYPE0")
	)
	(segment
		(start 83.932776 -206.489808)
		(end 83.807046 -206.437738)
		(width 0.10668)
		(layer "F.Cu")
		(net "CPU1_CORETYPE0")
	)
	(segment
		(start 75.122024 -206.437738)
		(end 73.1647 -204.480414)
		(width 0.10668)
		(layer "F.Cu")
		(net "CPU1_CORETYPE0")
	)
	(segment
		(start 83.807046 -206.437738)
		(end 75.122024 -206.437738)
		(width 0.10668)
		(layer "F.Cu")
		(net "CPU1_CORETYPE0")
	)
	(segment
		(start 70.681342 -202.159616)
		(end 69.411596 -200.88987)
		(width 0.10668)
		(layer "F.Cu")
		(net "CPU1_CORETYPE0")
	)
	(segment
		(start 82.167984 -221.19082)
		(end 87.624666 -215.734138)
		(width 0.10668)
		(layer "F.Cu")
		(net "CPU1_CORETYPE0")
	)
	(segment
		(start 87.624666 -210.181698)
		(end 83.932776 -206.489808)
		(width 0.10668)
		(layer "F.Cu")
		(net "CPU1_CORETYPE0")
	)
	(segment
		(start 70.681342 -202.706478)
		(end 70.681342 -202.159616)
		(width 0.10668)
		(layer "F.Cu")
		(net "CPU1_CORETYPE0")
	)
	(segment
		(start 64.686434 -197.205092)
		(end 64.686434 -197.202552)
		(width 0.10668)
		(layer "F.Cu")
		(net "CPU1_CORETYPE0")
	)
	(segment
		(start 68.371212 -200.88987)
		(end 64.686434 -197.205092)
		(width 0.10668)
		(layer "F.Cu")
		(net "CPU1_CORETYPE0")
	)
	(segment
		(start 69.411596 -200.88987)
		(end 68.371212 -200.88987)
		(width 0.10668)
		(layer "F.Cu")
		(net "CPU1_CORETYPE0")
	)
	(segment
		(start 73.1647 -204.480414)
		(end 71.953882 -203.979018)
		(width 0.10668)
		(layer "F.Cu")
		(net "CPU1_CORETYPE0")
	)
	(segment
		(start 71.953882 -203.979018)
		(end 70.681342 -202.706478)
		(width 0.10668)
		(layer "F.Cu")
		(net "CPU1_CORETYPE0")
	)
	(via
		(at 64.686434 -197.202552)
		(size 0.508)
		(drill 0.254)
		(layers "F.Cu" "B.Cu")
		(net "CPU1_CORETYPE0")
	)
	(via
		(at 187.833 -93.690948)
		(size 0.508)
		(drill 0.254)
		(layers "F.Cu" "B.Cu")
		(net "CPU1_CORETYPE0")
	)
	(segment
		(start 64.019684 -197.202552)
		(end 64.686434 -197.202552)
		(width 0.10668)
		(layer "B.Cu")
		(net "CPU1_CORETYPE0")
	)
	(segment
		(start 187.35294 -96.216724)
		(end 187.35294 -94.171008)
		(width 0.10668)
		(layer "B.Cu")
		(net "CPU1_CORETYPE0")
	)
	(segment
		(start 187.822078 -96.685862)
		(end 187.35294 -96.216724)
		(width 0.10668)
		(layer "B.Cu")
		(net "CPU1_CORETYPE0")
	)
	(segment
		(start 187.35294 -94.171008)
		(end 187.833 -93.690948)
		(width 0.10668)
		(layer "B.Cu")
		(net "CPU1_CORETYPE0")
	)
	(segment
		(start 71.856854 -134.302246)
		(end 106.477054 -99.682046)
		(width 0.11684)
		(layer "In2.Cu")
		(net "CPU1_CORETYPE0")
	)
	(segment
		(start 44.639484 -149.168358)
		(end 59.505596 -134.302246)
		(width 0.11684)
		(layer "In2.Cu")
		(net "CPU1_CORETYPE0")
	)
	(segment
		(start 166.556944 -95.81642)
		(end 169.209466 -93.163898)
		(width 0.11684)
		(layer "In2.Cu")
		(net "CPU1_CORETYPE0")
	)
	(segment
		(start 157.43301 -102.136956)
		(end 163.753546 -95.81642)
		(width 0.11684)
		(layer "In2.Cu")
		(net "CPU1_CORETYPE0")
	)
	(segment
		(start 49.76241 -191.377316)
		(end 42.87774 -184.492646)
		(width 0.11684)
		(layer "In2.Cu")
		(net "CPU1_CORETYPE0")
	)
	(segment
		(start 42.87774 -168.339008)
		(end 44.639484 -166.577264)
		(width 0.11684)
		(layer "In2.Cu")
		(net "CPU1_CORETYPE0")
	)
	(segment
		(start 163.753546 -95.81642)
		(end 166.556944 -95.81642)
		(width 0.11684)
		(layer "In2.Cu")
		(net "CPU1_CORETYPE0")
	)
	(segment
		(start 182.20436 -95.196914)
		(end 182.60314 -95.595694)
		(width 0.11684)
		(layer "In2.Cu")
		(net "CPU1_CORETYPE0")
	)
	(segment
		(start 64.686434 -197.202552)
		(end 58.861198 -191.377316)
		(width 0.11684)
		(layer "In2.Cu")
		(net "CPU1_CORETYPE0")
	)
	(segment
		(start 182.60314 -95.595694)
		(end 186.367674 -95.595694)
		(width 0.11684)
		(layer "In2.Cu")
		(net "CPU1_CORETYPE0")
	)
	(segment
		(start 157.43301 -102.231698)
		(end 157.43301 -102.136956)
		(width 0.11684)
		(layer "In2.Cu")
		(net "CPU1_CORETYPE0")
	)
	(segment
		(start 58.861198 -191.377316)
		(end 49.76241 -191.377316)
		(width 0.11684)
		(layer "In2.Cu")
		(net "CPU1_CORETYPE0")
	)
	(segment
		(start 182.20436 -93.500702)
		(end 182.20436 -95.196914)
		(width 0.11684)
		(layer "In2.Cu")
		(net "CPU1_CORETYPE0")
	)
	(segment
		(start 44.639484 -166.577264)
		(end 44.639484 -149.168358)
		(width 0.11684)
		(layer "In2.Cu")
		(net "CPU1_CORETYPE0")
	)
	(segment
		(start 157.160976 -102.503732)
		(end 157.43301 -102.231698)
		(width 0.11684)
		(layer "In2.Cu")
		(net "CPU1_CORETYPE0")
	)
	(segment
		(start 181.867556 -93.163898)
		(end 182.20436 -93.500702)
		(width 0.11684)
		(layer "In2.Cu")
		(net "CPU1_CORETYPE0")
	)
	(segment
		(start 187.833 -94.130368)
		(end 187.833 -93.690948)
		(width 0.11684)
		(layer "In2.Cu")
		(net "CPU1_CORETYPE0")
	)
	(segment
		(start 156.231082 -102.503732)
		(end 157.160976 -102.503732)
		(width 0.11684)
		(layer "In2.Cu")
		(net "CPU1_CORETYPE0")
	)
	(segment
		(start 59.505596 -134.302246)
		(end 71.856854 -134.302246)
		(width 0.11684)
		(layer "In2.Cu")
		(net "CPU1_CORETYPE0")
	)
	(segment
		(start 42.87774 -184.492646)
		(end 42.87774 -168.339008)
		(width 0.11684)
		(layer "In2.Cu")
		(net "CPU1_CORETYPE0")
	)
	(segment
		(start 153.409396 -99.682046)
		(end 156.231082 -102.503732)
		(width 0.11684)
		(layer "In2.Cu")
		(net "CPU1_CORETYPE0")
	)
	(segment
		(start 169.209466 -93.163898)
		(end 181.867556 -93.163898)
		(width 0.11684)
		(layer "In2.Cu")
		(net "CPU1_CORETYPE0")
	)
	(segment
		(start 106.477054 -99.682046)
		(end 153.409396 -99.682046)
		(width 0.11684)
		(layer "In2.Cu")
		(net "CPU1_CORETYPE0")
	)
	(segment
		(start 186.367674 -95.595694)
		(end 187.833 -94.130368)
		(width 0.11684)
		(layer "In2.Cu")
		(net "CPU1_CORETYPE0")
	)
	(segment
		(start 90.559636 -220.6498)
		(end 90.925142 -220.6498)
		(width 0.10668)
		(layer "F.Cu")
		(net "CPU1_BP3")
	)
	(segment
		(start 89.687908 -221.521528)
		(end 90.559636 -220.6498)
		(width 0.10668)
		(layer "F.Cu")
		(net "CPU1_BP3")
	)
	(segment
		(start 90.925142 -220.6498)
		(end 92.664534 -218.910408)
		(width 0.10668)
		(layer "F.Cu")
		(net "CPU1_BP3")
	)
	(segment
		(start 26.91765 -50.099214)
		(end 23.81885 -50.099214)
		(width 0.10668)
		(layer "F.Cu")
		(net "CPU1_BP3")
	)
	(segment
		(start 89.687908 -222.070422)
		(end 89.687908 -221.521528)
		(width 0.10668)
		(layer "F.Cu")
		(net "CPU1_BP3")
	)
	(via
		(at 23.81885 -50.099214)
		(size 0.508)
		(drill 0.254)
		(layers "F.Cu" "B.Cu")
		(net "CPU1_BP3")
	)
	(via
		(at 92.664534 -218.910408)
		(size 0.508)
		(drill 0.254)
		(layers "F.Cu" "B.Cu")
		(net "CPU1_BP3")
	)
	(segment
		(start 93.366082 -205.74508)
		(end 93.366082 -214.801958)
		(width 0.10668)
		(layer "B.Cu")
		(net "CPU1_BP3")
	)
	(segment
		(start 92.104464 -216.063576)
		(end 92.104464 -218.350338)
		(width 0.10668)
		(layer "B.Cu")
		(net "CPU1_BP3")
	)
	(segment
		(start 93.366082 -214.801958)
		(end 92.104464 -216.063576)
		(width 0.10668)
		(layer "B.Cu")
		(net "CPU1_BP3")
	)
	(segment
		(start 92.104464 -218.350338)
		(end 92.664534 -218.910408)
		(width 0.10668)
		(layer "B.Cu")
		(net "CPU1_BP3")
	)
	(segment
		(start 93.170502 -205.5495)
		(end 93.366082 -205.74508)
		(width 0.10668)
		(layer "B.Cu")
		(net "CPU1_BP3")
	)
	(segment
		(start 56.946546 -189.436502)
		(end 63.085726 -189.436502)
		(width 0.11684)
		(layer "In4.Cu")
		(net "CPU1_BP3")
	)
	(segment
		(start 95.86849 -203.57592)
		(end 96.190054 -203.897484)
		(width 0.11684)
		(layer "In4.Cu")
		(net "CPU1_BP3")
	)
	(segment
		(start 63.085726 -189.436502)
		(end 77.225144 -203.57592)
		(width 0.11684)
		(layer "In4.Cu")
		(net "CPU1_BP3")
	)
	(segment
		(start 92.104464 -216.12987)
		(end 92.104464 -218.350338)
		(width 0.11684)
		(layer "In4.Cu")
		(net "CPU1_BP3")
	)
	(segment
		(start 23.80107 -50.099214)
		(end 23.342854 -50.55743)
		(width 0.11684)
		(layer "In4.Cu")
		(net "CPU1_BP3")
	)
	(segment
		(start 47.42307 -143.337026)
		(end 47.42307 -177.585624)
		(width 0.11684)
		(layer "In4.Cu")
		(net "CPU1_BP3")
	)
	(segment
		(start 47.42307 -177.585624)
		(end 55.177436 -185.33999)
		(width 0.11684)
		(layer "In4.Cu")
		(net "CPU1_BP3")
	)
	(segment
		(start 91.407234 -208.030826)
		(end 91.407234 -215.43264)
		(width 0.11684)
		(layer "In4.Cu")
		(net "CPU1_BP3")
	)
	(segment
		(start 23.00732 -55.275734)
		(end 28.544012 -55.275734)
		(width 0.11684)
		(layer "In4.Cu")
		(net "CPU1_BP3")
	)
	(segment
		(start 94.058232 -205.379828)
		(end 91.407234 -208.030826)
		(width 0.11684)
		(layer "In4.Cu")
		(net "CPU1_BP3")
	)
	(segment
		(start 92.104464 -218.350338)
		(end 92.664534 -218.910408)
		(width 0.11684)
		(layer "In4.Cu")
		(net "CPU1_BP3")
	)
	(segment
		(start 23.342854 -50.55743)
		(end 23.342854 -51.354228)
		(width 0.11684)
		(layer "In4.Cu")
		(net "CPU1_BP3")
	)
	(segment
		(start 21.853906 -52.31892)
		(end 21.853906 -54.12232)
		(width 0.11684)
		(layer "In4.Cu")
		(net "CPU1_BP3")
	)
	(segment
		(start 90.146378 -109.69625)
		(end 97.83318 -109.69625)
		(width 0.11684)
		(layer "In4.Cu")
		(net "CPU1_BP3")
	)
	(segment
		(start 99.76231 -111.62538)
		(end 99.76231 -114.4778)
		(width 0.11684)
		(layer "In4.Cu")
		(net "CPU1_BP3")
	)
	(segment
		(start 22.294342 -51.878484)
		(end 21.853906 -52.31892)
		(width 0.11684)
		(layer "In4.Cu")
		(net "CPU1_BP3")
	)
	(segment
		(start 34.392616 -75.311762)
		(end 41.977818 -82.896964)
		(width 0.11684)
		(layer "In4.Cu")
		(net "CPU1_BP3")
	)
	(segment
		(start 84.851494 -132.051552)
		(end 79.626968 -132.051552)
		(width 0.11684)
		(layer "In4.Cu")
		(net "CPU1_BP3")
	)
	(segment
		(start 96.190054 -203.897484)
		(end 96.190054 -204.601572)
		(width 0.11684)
		(layer "In4.Cu")
		(net "CPU1_BP3")
	)
	(segment
		(start 96.190054 -204.601572)
		(end 95.411798 -205.379828)
		(width 0.11684)
		(layer "In4.Cu")
		(net "CPU1_BP3")
	)
	(segment
		(start 34.392616 -61.124338)
		(end 34.392616 -75.311762)
		(width 0.11684)
		(layer "In4.Cu")
		(net "CPU1_BP3")
	)
	(segment
		(start 55.177436 -187.667392)
		(end 56.946546 -189.436502)
		(width 0.11684)
		(layer "In4.Cu")
		(net "CPU1_BP3")
	)
	(segment
		(start 63.347092 -82.896964)
		(end 90.146378 -109.69625)
		(width 0.11684)
		(layer "In4.Cu")
		(net "CPU1_BP3")
	)
	(segment
		(start 28.544012 -55.275734)
		(end 34.392616 -61.124338)
		(width 0.11684)
		(layer "In4.Cu")
		(net "CPU1_BP3")
	)
	(segment
		(start 21.853906 -54.12232)
		(end 23.00732 -55.275734)
		(width 0.11684)
		(layer "In4.Cu")
		(net "CPU1_BP3")
	)
	(segment
		(start 48.800766 -141.95933)
		(end 47.42307 -143.337026)
		(width 0.11684)
		(layer "In4.Cu")
		(net "CPU1_BP3")
	)
	(segment
		(start 79.626968 -132.051552)
		(end 69.71919 -141.95933)
		(width 0.11684)
		(layer "In4.Cu")
		(net "CPU1_BP3")
	)
	(segment
		(start 22.818598 -51.878484)
		(end 22.294342 -51.878484)
		(width 0.11684)
		(layer "In4.Cu")
		(net "CPU1_BP3")
	)
	(segment
		(start 23.342854 -51.354228)
		(end 22.818598 -51.878484)
		(width 0.11684)
		(layer "In4.Cu")
		(net "CPU1_BP3")
	)
	(segment
		(start 55.177436 -185.33999)
		(end 55.177436 -187.667392)
		(width 0.11684)
		(layer "In4.Cu")
		(net "CPU1_BP3")
	)
	(segment
		(start 92.988384 -121.251726)
		(end 92.988384 -123.914662)
		(width 0.11684)
		(layer "In4.Cu")
		(net "CPU1_BP3")
	)
	(segment
		(start 69.71919 -141.95933)
		(end 48.800766 -141.95933)
		(width 0.11684)
		(layer "In4.Cu")
		(net "CPU1_BP3")
	)
	(segment
		(start 92.988384 -123.914662)
		(end 84.851494 -132.051552)
		(width 0.11684)
		(layer "In4.Cu")
		(net "CPU1_BP3")
	)
	(segment
		(start 97.83318 -109.69625)
		(end 99.76231 -111.62538)
		(width 0.11684)
		(layer "In4.Cu")
		(net "CPU1_BP3")
	)
	(segment
		(start 41.977818 -82.896964)
		(end 63.347092 -82.896964)
		(width 0.11684)
		(layer "In4.Cu")
		(net "CPU1_BP3")
	)
	(segment
		(start 77.225144 -203.57592)
		(end 95.86849 -203.57592)
		(width 0.11684)
		(layer "In4.Cu")
		(net "CPU1_BP3")
	)
	(segment
		(start 95.411798 -205.379828)
		(end 94.058232 -205.379828)
		(width 0.11684)
		(layer "In4.Cu")
		(net "CPU1_BP3")
	)
	(segment
		(start 23.81885 -50.099214)
		(end 23.80107 -50.099214)
		(width 0.11684)
		(layer "In4.Cu")
		(net "CPU1_BP3")
	)
	(segment
		(start 99.76231 -114.4778)
		(end 92.988384 -121.251726)
		(width 0.11684)
		(layer "In4.Cu")
		(net "CPU1_BP3")
	)
	(segment
		(start 91.407234 -215.43264)
		(end 92.104464 -216.12987)
		(width 0.11684)
		(layer "In4.Cu")
		(net "CPU1_BP3")
	)
	(segment
		(start 90.434668 -219.927678)
		(end 90.821002 -219.927678)
		(width 0.10668)
		(layer "F.Cu")
		(net "CPU1_BP2")
	)
	(segment
		(start 26.91765 -51.369214)
		(end 23.81885 -51.369214)
		(width 0.10668)
		(layer "F.Cu")
		(net "CPU1_BP2")
	)
	(segment
		(start 90.821002 -219.927678)
		(end 91.92006 -218.82862)
		(width 0.10668)
		(layer "F.Cu")
		(net "CPU1_BP2")
	)
	(segment
		(start 91.92006 -218.82862)
		(end 91.92006 -218.48826)
		(width 0.10668)
		(layer "F.Cu")
		(net "CPU1_BP2")
	)
	(segment
		(start 88.747854 -221.614492)
		(end 90.434668 -219.927678)
		(width 0.10668)
		(layer "F.Cu")
		(net "CPU1_BP2")
	)
	(segment
		(start 88.747854 -222.070422)
		(end 88.747854 -221.614492)
		(width 0.10668)
		(layer "F.Cu")
		(net "CPU1_BP2")
	)
	(segment
		(start 92.683838 -217.724482)
		(end 92.683838 -216.551256)
		(width 0.10668)
		(layer "F.Cu")
		(net "CPU1_BP2")
	)
	(segment
		(start 91.92006 -218.48826)
		(end 92.683838 -217.724482)
		(width 0.10668)
		(layer "F.Cu")
		(net "CPU1_BP2")
	)
	(via
		(at 23.81885 -51.369214)
		(size 0.508)
		(drill 0.254)
		(layers "F.Cu" "B.Cu")
		(net "CPU1_BP2")
	)
	(via
		(at 92.683838 -216.551256)
		(size 0.508)
		(drill 0.254)
		(layers "F.Cu" "B.Cu")
		(net "CPU1_BP2")
	)
	(segment
		(start 94.059502 -205.5495)
		(end 93.853 -205.756002)
		(width 0.10668)
		(layer "B.Cu")
		(net "CPU1_BP2")
	)
	(segment
		(start 93.853 -205.756002)
		(end 93.853 -215.203532)
		(width 0.10668)
		(layer "B.Cu")
		(net "CPU1_BP2")
	)
	(segment
		(start 92.683838 -216.372694)
		(end 92.683838 -216.551256)
		(width 0.10668)
		(layer "B.Cu")
		(net "CPU1_BP2")
	)
	(segment
		(start 93.853 -215.203532)
		(end 92.683838 -216.372694)
		(width 0.10668)
		(layer "B.Cu")
		(net "CPU1_BP2")
	)
	(segment
		(start 23.269448 -52.088288)
		(end 23.269448 -54.174898)
		(width 0.11684)
		(layer "In4.Cu")
		(net "CPU1_BP2")
	)
	(segment
		(start 23.81885 -51.538886)
		(end 23.269448 -52.088288)
		(width 0.11684)
		(layer "In4.Cu")
		(net "CPU1_BP2")
	)
	(segment
		(start 35.105594 -75.33259)
		(end 42.230548 -82.457544)
		(width 0.11684)
		(layer "In4.Cu")
		(net "CPU1_BP2")
	)
	(segment
		(start 54.34838 -180.859176)
		(end 54.34838 -182.039514)
		(width 0.11684)
		(layer "In4.Cu")
		(net "CPU1_BP2")
	)
	(segment
		(start 92.683838 -210.569048)
		(end 92.683838 -216.551256)
		(width 0.11684)
		(layer "In4.Cu")
		(net "CPU1_BP2")
	)
	(segment
		(start 54.34838 -182.039514)
		(end 56.601106 -184.29224)
		(width 0.11684)
		(layer "In4.Cu")
		(net "CPU1_BP2")
	)
	(segment
		(start 97.982532 -109.234732)
		(end 100.248212 -111.500412)
		(width 0.11684)
		(layer "In4.Cu")
		(net "CPU1_BP2")
	)
	(segment
		(start 58.576972 -184.29224)
		(end 77.418692 -203.13396)
		(width 0.11684)
		(layer "In4.Cu")
		(net "CPU1_BP2")
	)
	(segment
		(start 35.105594 -61.09208)
		(end 35.105594 -75.33259)
		(width 0.11684)
		(layer "In4.Cu")
		(net "CPU1_BP2")
	)
	(segment
		(start 100.248212 -111.500412)
		(end 100.248212 -114.610134)
		(width 0.11684)
		(layer "In4.Cu")
		(net "CPU1_BP2")
	)
	(segment
		(start 94.04858 -126.91364)
		(end 85.56244 -135.39978)
		(width 0.11684)
		(layer "In4.Cu")
		(net "CPU1_BP2")
	)
	(segment
		(start 96.680274 -203.620116)
		(end 96.680274 -204.723492)
		(width 0.11684)
		(layer "In4.Cu")
		(net "CPU1_BP2")
	)
	(segment
		(start 23.269448 -54.174898)
		(end 23.83409 -54.73954)
		(width 0.11684)
		(layer "In4.Cu")
		(net "CPU1_BP2")
	)
	(segment
		(start 49.144936 -142.38859)
		(end 47.858172 -143.675354)
		(width 0.11684)
		(layer "In4.Cu")
		(net "CPU1_BP2")
	)
	(segment
		(start 85.56244 -135.39978)
		(end 77.686916 -135.39978)
		(width 0.11684)
		(layer "In4.Cu")
		(net "CPU1_BP2")
	)
	(segment
		(start 94.04858 -120.809766)
		(end 94.04858 -126.91364)
		(width 0.11684)
		(layer "In4.Cu")
		(net "CPU1_BP2")
	)
	(segment
		(start 77.686916 -135.39978)
		(end 70.698106 -142.38859)
		(width 0.11684)
		(layer "In4.Cu")
		(net "CPU1_BP2")
	)
	(segment
		(start 95.483426 -205.92034)
		(end 94.15018 -205.92034)
		(width 0.11684)
		(layer "In4.Cu")
		(net "CPU1_BP2")
	)
	(segment
		(start 96.194118 -203.13396)
		(end 96.680274 -203.620116)
		(width 0.11684)
		(layer "In4.Cu")
		(net "CPU1_BP2")
	)
	(segment
		(start 28.753054 -54.73954)
		(end 35.105594 -61.09208)
		(width 0.11684)
		(layer "In4.Cu")
		(net "CPU1_BP2")
	)
	(segment
		(start 90.374978 -109.234732)
		(end 97.982532 -109.234732)
		(width 0.11684)
		(layer "In4.Cu")
		(net "CPU1_BP2")
	)
	(segment
		(start 42.230548 -82.457544)
		(end 63.59779 -82.457544)
		(width 0.11684)
		(layer "In4.Cu")
		(net "CPU1_BP2")
	)
	(segment
		(start 96.680274 -204.723492)
		(end 95.483426 -205.92034)
		(width 0.11684)
		(layer "In4.Cu")
		(net "CPU1_BP2")
	)
	(segment
		(start 23.83409 -54.73954)
		(end 28.753054 -54.73954)
		(width 0.11684)
		(layer "In4.Cu")
		(net "CPU1_BP2")
	)
	(segment
		(start 94.15018 -205.92034)
		(end 91.911424 -208.159096)
		(width 0.11684)
		(layer "In4.Cu")
		(net "CPU1_BP2")
	)
	(segment
		(start 91.911424 -209.796634)
		(end 92.683838 -210.569048)
		(width 0.11684)
		(layer "In4.Cu")
		(net "CPU1_BP2")
	)
	(segment
		(start 100.248212 -114.610134)
		(end 94.04858 -120.809766)
		(width 0.11684)
		(layer "In4.Cu")
		(net "CPU1_BP2")
	)
	(segment
		(start 56.601106 -184.29224)
		(end 58.576972 -184.29224)
		(width 0.11684)
		(layer "In4.Cu")
		(net "CPU1_BP2")
	)
	(segment
		(start 77.418692 -203.13396)
		(end 96.194118 -203.13396)
		(width 0.11684)
		(layer "In4.Cu")
		(net "CPU1_BP2")
	)
	(segment
		(start 63.59779 -82.457544)
		(end 90.374978 -109.234732)
		(width 0.11684)
		(layer "In4.Cu")
		(net "CPU1_BP2")
	)
	(segment
		(start 91.911424 -208.159096)
		(end 91.911424 -209.796634)
		(width 0.11684)
		(layer "In4.Cu")
		(net "CPU1_BP2")
	)
	(segment
		(start 47.858172 -174.368968)
		(end 54.34838 -180.859176)
		(width 0.11684)
		(layer "In4.Cu")
		(net "CPU1_BP2")
	)
	(segment
		(start 47.858172 -143.675354)
		(end 47.858172 -174.368968)
		(width 0.11684)
		(layer "In4.Cu")
		(net "CPU1_BP2")
	)
	(segment
		(start 23.81885 -51.369214)
		(end 23.81885 -51.538886)
		(width 0.11684)
		(layer "In4.Cu")
		(net "CPU1_BP2")
	)
	(segment
		(start 70.698106 -142.38859)
		(end 49.144936 -142.38859)
		(width 0.11684)
		(layer "In4.Cu")
		(net "CPU1_BP2")
	)
	(segment
		(start 93.885004 -218.622118)
		(end 91.50477 -221.002352)
		(width 0.10668)
		(layer "F.Cu")
		(net "CPU1_BP1")
	)
	(segment
		(start 90.199464 -221.408752)
		(end 90.199464 -222.190564)
		(width 0.10668)
		(layer "F.Cu")
		(net "CPU1_BP1")
	)
	(segment
		(start 26.91765 -52.639214)
		(end 23.81885 -52.639214)
		(width 0.10668)
		(layer "F.Cu")
		(net "CPU1_BP1")
	)
	(segment
		(start 90.605864 -221.002352)
		(end 90.199464 -221.408752)
		(width 0.10668)
		(layer "F.Cu")
		(net "CPU1_BP1")
	)
	(segment
		(start 89.687908 -222.70212)
		(end 89.687908 -223.690434)
		(width 0.10668)
		(layer "F.Cu")
		(net "CPU1_BP1")
	)
	(segment
		(start 91.50477 -221.002352)
		(end 90.605864 -221.002352)
		(width 0.10668)
		(layer "F.Cu")
		(net "CPU1_BP1")
	)
	(segment
		(start 90.199464 -222.190564)
		(end 89.687908 -222.70212)
		(width 0.10668)
		(layer "F.Cu")
		(net "CPU1_BP1")
	)
	(via
		(at 93.885004 -218.622118)
		(size 0.508)
		(drill 0.254)
		(layers "F.Cu" "B.Cu")
		(net "CPU1_BP1")
	)
	(via
		(at 23.81885 -52.639214)
		(size 0.508)
		(drill 0.254)
		(layers "F.Cu" "B.Cu")
		(net "CPU1_BP1")
	)
	(segment
		(start 94.948502 -205.5495)
		(end 95.25 -205.850998)
		(width 0.10668)
		(layer "B.Cu")
		(net "CPU1_BP1")
	)
	(segment
		(start 92.698062 -217.326464)
		(end 92.698062 -218.011502)
		(width 0.10668)
		(layer "B.Cu")
		(net "CPU1_BP1")
	)
	(segment
		(start 93.143578 -216.880948)
		(end 92.698062 -217.326464)
		(width 0.10668)
		(layer "B.Cu")
		(net "CPU1_BP1")
	)
	(segment
		(start 94.234 -216.880948)
		(end 93.143578 -216.880948)
		(width 0.10668)
		(layer "B.Cu")
		(net "CPU1_BP1")
	)
	(segment
		(start 93.308678 -218.622118)
		(end 93.885004 -218.622118)
		(width 0.10668)
		(layer "B.Cu")
		(net "CPU1_BP1")
	)
	(segment
		(start 95.25 -205.850998)
		(end 95.25 -215.864948)
		(width 0.10668)
		(layer "B.Cu")
		(net "CPU1_BP1")
	)
	(segment
		(start 92.698062 -218.011502)
		(end 93.308678 -218.622118)
		(width 0.10668)
		(layer "B.Cu")
		(net "CPU1_BP1")
	)
	(segment
		(start 95.25 -215.864948)
		(end 94.234 -216.880948)
		(width 0.10668)
		(layer "B.Cu")
		(net "CPU1_BP1")
	)
	(segment
		(start 94.44228 -206.83728)
		(end 93.808042 -207.471518)
		(width 0.11684)
		(layer "In4.Cu")
		(net "CPU1_BP1")
	)
	(segment
		(start 93.808042 -207.471518)
		(end 93.808042 -218.545156)
		(width 0.11684)
		(layer "In4.Cu")
		(net "CPU1_BP1")
	)
	(segment
		(start 28.448 -52.639214)
		(end 36.167314 -60.358528)
		(width 0.11684)
		(layer "In4.Cu")
		(net "CPU1_BP1")
	)
	(segment
		(start 85.942424 -136.455404)
		(end 77.9018 -136.455404)
		(width 0.11684)
		(layer "In4.Cu")
		(net "CPU1_BP1")
	)
	(segment
		(start 36.167314 -75.080114)
		(end 42.670984 -81.583784)
		(width 0.11684)
		(layer "In4.Cu")
		(net "CPU1_BP1")
	)
	(segment
		(start 95.989902 -206.83728)
		(end 94.44228 -206.83728)
		(width 0.11684)
		(layer "In4.Cu")
		(net "CPU1_BP1")
	)
	(segment
		(start 94.9706 -121.902474)
		(end 94.9706 -127.427228)
		(width 0.11684)
		(layer "In4.Cu")
		(net "CPU1_BP1")
	)
	(segment
		(start 93.808042 -218.545156)
		(end 93.885004 -218.622118)
		(width 0.11684)
		(layer "In4.Cu")
		(net "CPU1_BP1")
	)
	(segment
		(start 58.94578 -183.43118)
		(end 77.77734 -202.26274)
		(width 0.11684)
		(layer "In4.Cu")
		(net "CPU1_BP1")
	)
	(segment
		(start 101.27996 -111.20374)
		(end 101.27996 -115.593114)
		(width 0.11684)
		(layer "In4.Cu")
		(net "CPU1_BP1")
	)
	(segment
		(start 94.9706 -127.427228)
		(end 85.942424 -136.455404)
		(width 0.11684)
		(layer "In4.Cu")
		(net "CPU1_BP1")
	)
	(segment
		(start 36.167314 -60.358528)
		(end 36.167314 -75.080114)
		(width 0.11684)
		(layer "In4.Cu")
		(net "CPU1_BP1")
	)
	(segment
		(start 48.752252 -174.02048)
		(end 55.21706 -180.485288)
		(width 0.11684)
		(layer "In4.Cu")
		(net "CPU1_BP1")
	)
	(segment
		(start 48.752252 -144.053306)
		(end 48.752252 -174.02048)
		(width 0.11684)
		(layer "In4.Cu")
		(net "CPU1_BP1")
	)
	(segment
		(start 42.670984 -81.583784)
		(end 64.129158 -81.583784)
		(width 0.11684)
		(layer "In4.Cu")
		(net "CPU1_BP1")
	)
	(segment
		(start 97.56394 -205.263242)
		(end 95.989902 -206.83728)
		(width 0.11684)
		(layer "In4.Cu")
		(net "CPU1_BP1")
	)
	(segment
		(start 77.77734 -202.26274)
		(end 96.692974 -202.26274)
		(width 0.11684)
		(layer "In4.Cu")
		(net "CPU1_BP1")
	)
	(segment
		(start 77.9018 -136.455404)
		(end 71.099934 -143.25727)
		(width 0.11684)
		(layer "In4.Cu")
		(net "CPU1_BP1")
	)
	(segment
		(start 56.954674 -183.43118)
		(end 58.94578 -183.43118)
		(width 0.11684)
		(layer "In4.Cu")
		(net "CPU1_BP1")
	)
	(segment
		(start 55.21706 -181.693566)
		(end 56.954674 -183.43118)
		(width 0.11684)
		(layer "In4.Cu")
		(net "CPU1_BP1")
	)
	(segment
		(start 71.099934 -143.25727)
		(end 49.548288 -143.25727)
		(width 0.11684)
		(layer "In4.Cu")
		(net "CPU1_BP1")
	)
	(segment
		(start 96.692974 -202.26274)
		(end 97.56394 -203.133706)
		(width 0.11684)
		(layer "In4.Cu")
		(net "CPU1_BP1")
	)
	(segment
		(start 101.27996 -115.593114)
		(end 94.9706 -121.902474)
		(width 0.11684)
		(layer "In4.Cu")
		(net "CPU1_BP1")
	)
	(segment
		(start 64.129158 -81.583784)
		(end 90.812874 -108.2675)
		(width 0.11684)
		(layer "In4.Cu")
		(net "CPU1_BP1")
	)
	(segment
		(start 49.548288 -143.25727)
		(end 48.752252 -144.053306)
		(width 0.11684)
		(layer "In4.Cu")
		(net "CPU1_BP1")
	)
	(segment
		(start 55.21706 -180.485288)
		(end 55.21706 -181.693566)
		(width 0.11684)
		(layer "In4.Cu")
		(net "CPU1_BP1")
	)
	(segment
		(start 98.34372 -108.2675)
		(end 101.27996 -111.20374)
		(width 0.11684)
		(layer "In4.Cu")
		(net "CPU1_BP1")
	)
	(segment
		(start 90.812874 -108.2675)
		(end 98.34372 -108.2675)
		(width 0.11684)
		(layer "In4.Cu")
		(net "CPU1_BP1")
	)
	(segment
		(start 97.56394 -203.133706)
		(end 97.56394 -205.263242)
		(width 0.11684)
		(layer "In4.Cu")
		(net "CPU1_BP1")
	)
	(segment
		(start 23.81885 -52.639214)
		(end 28.448 -52.639214)
		(width 0.11684)
		(layer "In4.Cu")
		(net "CPU1_BP1")
	)
	(segment
		(start 90.88501 -220.267276)
		(end 90.542364 -220.267276)
		(width 0.10668)
		(layer "F.Cu")
		(net "CPU1_BP0")
	)
	(segment
		(start 92.20327 -218.60637)
		(end 92.20327 -218.949016)
		(width 0.10668)
		(layer "F.Cu")
		(net "CPU1_BP0")
	)
	(segment
		(start 93.183456 -217.747596)
		(end 93.062044 -217.747596)
		(width 0.10668)
		(layer "F.Cu")
		(net "CPU1_BP0")
	)
	(segment
		(start 93.062044 -217.747596)
		(end 92.20327 -218.60637)
		(width 0.10668)
		(layer "F.Cu")
		(net "CPU1_BP0")
	)
	(segment
		(start 88.747854 -222.753174)
		(end 88.747854 -223.690434)
		(width 0.10668)
		(layer "F.Cu")
		(net "CPU1_BP0")
	)
	(segment
		(start 89.183464 -222.317564)
		(end 88.747854 -222.753174)
		(width 0.10668)
		(layer "F.Cu")
		(net "CPU1_BP0")
	)
	(segment
		(start 89.183464 -221.626176)
		(end 89.183464 -222.317564)
		(width 0.10668)
		(layer "F.Cu")
		(net "CPU1_BP0")
	)
	(segment
		(start 90.542364 -220.267276)
		(end 89.183464 -221.626176)
		(width 0.10668)
		(layer "F.Cu")
		(net "CPU1_BP0")
	)
	(segment
		(start 26.91765 -53.909214)
		(end 23.81885 -53.909214)
		(width 0.10668)
		(layer "F.Cu")
		(net "CPU1_BP0")
	)
	(segment
		(start 92.20327 -218.949016)
		(end 90.88501 -220.267276)
		(width 0.10668)
		(layer "F.Cu")
		(net "CPU1_BP0")
	)
	(via
		(at 93.183456 -217.747596)
		(size 0.508)
		(drill 0.254)
		(layers "F.Cu" "B.Cu")
		(net "CPU1_BP0")
	)
	(via
		(at 23.81885 -53.909214)
		(size 0.508)
		(drill 0.254)
		(layers "F.Cu" "B.Cu")
		(net "CPU1_BP0")
	)
	(segment
		(start 94.004384 -217.999564)
		(end 93.435424 -217.999564)
		(width 0.10668)
		(layer "B.Cu")
		(net "CPU1_BP0")
	)
	(segment
		(start 93.435424 -217.999564)
		(end 93.183456 -217.747596)
		(width 0.10668)
		(layer "B.Cu")
		(net "CPU1_BP0")
	)
	(segment
		(start 95.837502 -205.5495)
		(end 95.837502 -216.166446)
		(width 0.10668)
		(layer "B.Cu")
		(net "CPU1_BP0")
	)
	(segment
		(start 95.837502 -216.166446)
		(end 94.004384 -217.999564)
		(width 0.10668)
		(layer "B.Cu")
		(net "CPU1_BP0")
	)
	(segment
		(start 77.61478 -202.69962)
		(end 96.435926 -202.69962)
		(width 0.11684)
		(layer "In4.Cu")
		(net "CPU1_BP0")
	)
	(segment
		(start 100.743512 -111.289592)
		(end 100.743512 -115.501166)
		(width 0.11684)
		(layer "In4.Cu")
		(net "CPU1_BP0")
	)
	(segment
		(start 97.134934 -204.88656)
		(end 95.643446 -206.378048)
		(width 0.11684)
		(layer "In4.Cu")
		(net "CPU1_BP0")
	)
	(segment
		(start 48.319182 -174.22495)
		(end 54.78018 -180.685948)
		(width 0.11684)
		(layer "In4.Cu")
		(net "CPU1_BP0")
	)
	(segment
		(start 35.707574 -75.283822)
		(end 42.444416 -82.020664)
		(width 0.11684)
		(layer "In4.Cu")
		(net "CPU1_BP0")
	)
	(segment
		(start 100.743512 -115.501166)
		(end 94.52102 -121.723658)
		(width 0.11684)
		(layer "In4.Cu")
		(net "CPU1_BP0")
	)
	(segment
		(start 95.643446 -206.378048)
		(end 94.289372 -206.378048)
		(width 0.11684)
		(layer "In4.Cu")
		(net "CPU1_BP0")
	)
	(segment
		(start 94.52102 -121.723658)
		(end 94.52102 -127.17018)
		(width 0.11684)
		(layer "In4.Cu")
		(net "CPU1_BP0")
	)
	(segment
		(start 70.932294 -142.81531)
		(end 49.36236 -142.81531)
		(width 0.11684)
		(layer "In4.Cu")
		(net "CPU1_BP0")
	)
	(segment
		(start 35.707574 -60.75172)
		(end 35.707574 -75.283822)
		(width 0.11684)
		(layer "In4.Cu")
		(net "CPU1_BP0")
	)
	(segment
		(start 63.86195 -82.020664)
		(end 90.555318 -108.714032)
		(width 0.11684)
		(layer "In4.Cu")
		(net "CPU1_BP0")
	)
	(segment
		(start 94.289372 -206.378048)
		(end 93.183456 -207.483964)
		(width 0.11684)
		(layer "In4.Cu")
		(net "CPU1_BP0")
	)
	(segment
		(start 56.784494 -183.8579)
		(end 58.77306 -183.8579)
		(width 0.11684)
		(layer "In4.Cu")
		(net "CPU1_BP0")
	)
	(segment
		(start 28.865068 -53.909214)
		(end 35.707574 -60.75172)
		(width 0.11684)
		(layer "In4.Cu")
		(net "CPU1_BP0")
	)
	(segment
		(start 54.78018 -180.685948)
		(end 54.78018 -181.853586)
		(width 0.11684)
		(layer "In4.Cu")
		(net "CPU1_BP0")
	)
	(segment
		(start 97.134934 -203.398628)
		(end 97.134934 -204.88656)
		(width 0.11684)
		(layer "In4.Cu")
		(net "CPU1_BP0")
	)
	(segment
		(start 90.555318 -108.714032)
		(end 98.167952 -108.714032)
		(width 0.11684)
		(layer "In4.Cu")
		(net "CPU1_BP0")
	)
	(segment
		(start 94.52102 -127.17018)
		(end 85.771736 -135.919464)
		(width 0.11684)
		(layer "In4.Cu")
		(net "CPU1_BP0")
	)
	(segment
		(start 54.78018 -181.853586)
		(end 56.784494 -183.8579)
		(width 0.11684)
		(layer "In4.Cu")
		(net "CPU1_BP0")
	)
	(segment
		(start 85.771736 -135.919464)
		(end 77.82814 -135.919464)
		(width 0.11684)
		(layer "In4.Cu")
		(net "CPU1_BP0")
	)
	(segment
		(start 49.36236 -142.81531)
		(end 48.319182 -143.858488)
		(width 0.11684)
		(layer "In4.Cu")
		(net "CPU1_BP0")
	)
	(segment
		(start 42.444416 -82.020664)
		(end 63.86195 -82.020664)
		(width 0.11684)
		(layer "In4.Cu")
		(net "CPU1_BP0")
	)
	(segment
		(start 96.435926 -202.69962)
		(end 97.134934 -203.398628)
		(width 0.11684)
		(layer "In4.Cu")
		(net "CPU1_BP0")
	)
	(segment
		(start 48.319182 -143.858488)
		(end 48.319182 -174.22495)
		(width 0.11684)
		(layer "In4.Cu")
		(net "CPU1_BP0")
	)
	(segment
		(start 58.77306 -183.8579)
		(end 77.61478 -202.69962)
		(width 0.11684)
		(layer "In4.Cu")
		(net "CPU1_BP0")
	)
	(segment
		(start 23.81885 -53.909214)
		(end 28.865068 -53.909214)
		(width 0.11684)
		(layer "In4.Cu")
		(net "CPU1_BP0")
	)
	(segment
		(start 77.82814 -135.919464)
		(end 70.932294 -142.81531)
		(width 0.11684)
		(layer "In4.Cu")
		(net "CPU1_BP0")
	)
	(segment
		(start 93.183456 -207.483964)
		(end 93.183456 -217.747596)
		(width 0.11684)
		(layer "In4.Cu")
		(net "CPU1_BP0")
	)
	(segment
		(start 98.167952 -108.714032)
		(end 100.743512 -111.289592)
		(width 0.11684)
		(layer "In4.Cu")
		(net "CPU1_BP0")
	)
	(segment
		(start 329.355958 -195.805552)
		(end 329.355958 -194.453002)
		(width 0.10668)
		(layer "F.Cu")
		(net "CPU0_XTRIG_R2_L7")
	)
	(segment
		(start 337.897216 -208.657698)
		(end 329.355958 -200.11644)
		(width 0.10668)
		(layer "F.Cu")
		(net "CPU0_XTRIG_R2_L7")
	)
	(segment
		(start 337.897216 -216.73312)
		(end 337.897216 -208.657698)
		(width 0.10668)
		(layer "F.Cu")
		(net "CPU0_XTRIG_R2_L7")
	)
	(segment
		(start 329.355958 -200.11644)
		(end 329.355958 -195.805552)
		(width 0.10668)
		(layer "F.Cu")
		(net "CPU0_XTRIG_R2_L7")
	)
	(segment
		(start 334.808068 -219.822268)
		(end 337.897216 -216.73312)
		(width 0.10668)
		(layer "F.Cu")
		(net "CPU0_XTRIG_R2_L7")
	)
	(segment
		(start 334.808068 -222.070168)
		(end 334.808068 -219.822268)
		(width 0.10668)
		(layer "F.Cu")
		(net "CPU0_XTRIG_R2_L7")
	)
	(via
		(at 329.355958 -195.805552)
		(size 0.762)
		(drill 0.381)
		(layers "F.Cu" "B.Cu")
		(net "CPU0_XTRIG_R2_L7")
	)
	(segment
		(start 328.339958 -197.786752)
		(end 327.831958 -197.278752)
		(width 0.10668)
		(layer "F.Cu")
		(net "CPU0_XTRIG_R2_L6")
	)
	(segment
		(start 327.831958 -197.278752)
		(end 327.831958 -195.932552)
		(width 0.10668)
		(layer "F.Cu")
		(net "CPU0_XTRIG_R2_L6")
	)
	(segment
		(start 337.485736 -216.534492)
		(end 337.485736 -208.828386)
		(width 0.10668)
		(layer "F.Cu")
		(net "CPU0_XTRIG_R2_L6")
	)
	(segment
		(start 333.868014 -222.070168)
		(end 333.868014 -220.152214)
		(width 0.10668)
		(layer "F.Cu")
		(net "CPU0_XTRIG_R2_L6")
	)
	(segment
		(start 327.831958 -194.961002)
		(end 328.339958 -194.453002)
		(width 0.10668)
		(layer "F.Cu")
		(net "CPU0_XTRIG_R2_L6")
	)
	(segment
		(start 328.339958 -199.682608)
		(end 328.339958 -197.786752)
		(width 0.10668)
		(layer "F.Cu")
		(net "CPU0_XTRIG_R2_L6")
	)
	(segment
		(start 337.485736 -208.828386)
		(end 328.339958 -199.682608)
		(width 0.10668)
		(layer "F.Cu")
		(net "CPU0_XTRIG_R2_L6")
	)
	(segment
		(start 327.831958 -195.932552)
		(end 327.831958 -194.961002)
		(width 0.10668)
		(layer "F.Cu")
		(net "CPU0_XTRIG_R2_L6")
	)
	(segment
		(start 333.868014 -220.152214)
		(end 337.485736 -216.534492)
		(width 0.10668)
		(layer "F.Cu")
		(net "CPU0_XTRIG_R2_L6")
	)
	(via
		(at 327.831958 -195.932552)
		(size 0.762)
		(drill 0.381)
		(layers "F.Cu" "B.Cu")
		(net "CPU0_XTRIG_R2_L6")
	)
	(segment
		(start 334.808068 -223.69018)
		(end 334.341216 -223.424242)
		(width 0.10668)
		(layer "F.Cu")
		(net "CPU0_XTRIG_R2_L5")
	)
	(via
		(at 330.059792 -203.476352)
		(size 0.6604)
		(drill 0.3302)
		(layers "F.Cu" "B.Cu")
		(net "CPU0_XTRIG_R2_L5")
	)
	(via
		(at 334.341216 -223.424242)
		(size 0.4064)
		(drill 0.2032)
		(layers "F.Cu" "B.Cu")
		(net "CPU0_XTRIG_R2_L5")
	)
	(segment
		(start 334.341216 -207.757776)
		(end 334.341216 -223.424242)
		(width 0.10668)
		(layer "B.Cu")
		(net "CPU0_XTRIG_R2_L5")
	)
	(segment
		(start 330.059792 -203.476352)
		(end 334.341216 -207.757776)
		(width 0.10668)
		(layer "B.Cu")
		(net "CPU0_XTRIG_R2_L5")
	)
	(segment
		(start 329.371452 -202.788012)
		(end 330.059792 -203.476352)
		(width 0.10668)
		(layer "B.Cu")
		(net "CPU0_XTRIG_R2_L5")
	)
	(segment
		(start 327.616058 -203.529946)
		(end 328.357992 -202.788012)
		(width 0.10668)
		(layer "B.Cu")
		(net "CPU0_XTRIG_R2_L5")
	)
	(segment
		(start 328.357992 -202.788012)
		(end 329.371452 -202.788012)
		(width 0.10668)
		(layer "B.Cu")
		(net "CPU0_XTRIG_R2_L5")
	)
	(segment
		(start 333.868014 -223.69018)
		(end 333.401162 -223.424242)
		(width 0.10668)
		(layer "F.Cu")
		(net "CPU0_XTRIG_R2_L4")
	)
	(via
		(at 328.789792 -203.476352)
		(size 0.6604)
		(drill 0.3302)
		(layers "F.Cu" "B.Cu")
		(net "CPU0_XTRIG_R2_L4")
	)
	(via
		(at 333.401162 -223.424242)
		(size 0.4064)
		(drill 0.2032)
		(layers "F.Cu" "B.Cu")
		(net "CPU0_XTRIG_R2_L4")
	)
	(segment
		(start 333.401162 -222.468948)
		(end 333.401162 -223.424242)
		(width 0.10668)
		(layer "B.Cu")
		(net "CPU0_XTRIG_R2_L4")
	)
	(segment
		(start 328.789792 -203.476352)
		(end 333.692246 -208.378806)
		(width 0.10668)
		(layer "B.Cu")
		(net "CPU0_XTRIG_R2_L4")
	)
	(segment
		(start 333.692246 -222.177864)
		(end 333.401162 -222.468948)
		(width 0.10668)
		(layer "B.Cu")
		(net "CPU0_XTRIG_R2_L4")
	)
	(segment
		(start 325.799958 -204.317346)
		(end 327.948798 -204.317346)
		(width 0.10668)
		(layer "B.Cu")
		(net "CPU0_XTRIG_R2_L4")
	)
	(segment
		(start 333.692246 -208.378806)
		(end 333.692246 -222.177864)
		(width 0.10668)
		(layer "B.Cu")
		(net "CPU0_XTRIG_R2_L4")
	)
	(segment
		(start 327.948798 -204.317346)
		(end 328.789792 -203.476352)
		(width 0.10668)
		(layer "B.Cu")
		(net "CPU0_XTRIG_R2_L4")
	)
	(segment
		(start 348.65437 -63.904876)
		(end 344.849958 -63.904876)
		(width 0.10668)
		(layer "F.Cu")
		(net "CPU0_XTRIG_R1_L7")
	)
	(segment
		(start 350.04756 -63.904876)
		(end 348.65437 -63.904876)
		(width 0.10668)
		(layer "F.Cu")
		(net "CPU0_XTRIG_R1_L7")
	)
	(via
		(at 348.65437 -63.904876)
		(size 0.762)
		(drill 0.381)
		(layers "F.Cu" "B.Cu")
		(net "CPU0_XTRIG_R1_L7")
	)
	(segment
		(start 350.04756 -62.634876)
		(end 348.65437 -62.634876)
		(width 0.10668)
		(layer "F.Cu")
		(net "CPU0_XTRIG_R1_L6")
	)
	(segment
		(start 344.849958 -62.634876)
		(end 348.65437 -62.634876)
		(width 0.10668)
		(layer "F.Cu")
		(net "CPU0_XTRIG_R1_L6")
	)
	(via
		(at 348.65437 -62.634876)
		(size 0.762)
		(drill 0.381)
		(layers "F.Cu" "B.Cu")
		(net "CPU0_XTRIG_R1_L6")
	)
	(segment
		(start 344.849958 -61.364876)
		(end 348.65437 -61.364876)
		(width 0.10668)
		(layer "F.Cu")
		(net "CPU0_XTRIG_R1_L5")
	)
	(segment
		(start 350.04756 -61.364876)
		(end 348.65437 -61.364876)
		(width 0.10668)
		(layer "F.Cu")
		(net "CPU0_XTRIG_R1_L5")
	)
	(via
		(at 348.65437 -61.364876)
		(size 0.762)
		(drill 0.381)
		(layers "F.Cu" "B.Cu")
		(net "CPU0_XTRIG_R1_L5")
	)
	(segment
		(start 344.849958 -60.094876)
		(end 348.65437 -60.094876)
		(width 0.10668)
		(layer "F.Cu")
		(net "CPU0_XTRIG_R1_L4")
	)
	(segment
		(start 350.04756 -60.094876)
		(end 348.65437 -60.094876)
		(width 0.10668)
		(layer "F.Cu")
		(net "CPU0_XTRIG_R1_L4")
	)
	(via
		(at 348.65437 -60.094876)
		(size 0.762)
		(drill 0.381)
		(layers "F.Cu" "B.Cu")
		(net "CPU0_XTRIG_R1_L4")
	)
	(segment
		(start 331.4954 -169.011346)
		(end 329.355958 -171.150788)
		(width 0.10668)
		(layer "F.Cu")
		(net "CPU0_XTRIG_L7")
	)
	(segment
		(start 177.8762 -95.703898)
		(end 177.8762 -95.291148)
		(width 0.10668)
		(layer "F.Cu")
		(net "CPU0_XTRIG_L7")
	)
	(segment
		(start 329.355958 -171.150788)
		(end 329.355958 -193.652902)
		(width 0.10668)
		(layer "F.Cu")
		(net "CPU0_XTRIG_L7")
	)
	(segment
		(start 350.84766 -63.904876)
		(end 352.001328 -65.058544)
		(width 0.10668)
		(layer "F.Cu")
		(net "CPU0_XTRIG_L7")
	)
	(segment
		(start 177.8762 -95.291148)
		(end 177.673 -95.087948)
		(width 0.10668)
		(layer "F.Cu")
		(net "CPU0_XTRIG_L7")
	)
	(segment
		(start 404.083012 -60.7695)
		(end 404.698962 -60.7695)
		(width 0.10668)
		(layer "F.Cu")
		(net "CPU0_XTRIG_L7")
	)
	(segment
		(start 330.371958 -193.564002)
		(end 329.444858 -193.564002)
		(width 0.10668)
		(layer "F.Cu")
		(net "CPU0_XTRIG_L7")
	)
	(segment
		(start 329.444858 -193.564002)
		(end 329.355958 -193.652902)
		(width 0.10668)
		(layer "F.Cu")
		(net "CPU0_XTRIG_L7")
	)
	(segment
		(start 352.001328 -65.058544)
		(end 354.406708 -65.058544)
		(width 0.10668)
		(layer "F.Cu")
		(net "CPU0_XTRIG_L7")
	)
	(segment
		(start 331.4954 -168.1734)
		(end 331.4954 -169.011346)
		(width 0.10668)
		(layer "F.Cu")
		(net "CPU0_XTRIG_L7")
	)
	(via
		(at 331.4954 -168.1734)
		(size 0.508)
		(drill 0.254)
		(layers "F.Cu" "B.Cu")
		(net "CPU0_XTRIG_L7")
	)
	(via
		(at 169.212768 -152.05964)
		(size 0.508)
		(drill 0.254)
		(layers "F.Cu" "B.Cu")
		(net "CPU0_XTRIG_L7")
	)
	(via
		(at 177.673 -95.087948)
		(size 0.508)
		(drill 0.254)
		(layers "F.Cu" "B.Cu")
		(net "CPU0_XTRIG_L7")
	)
	(via
		(at 404.698962 -60.7695)
		(size 0.508)
		(drill 0.254)
		(layers "F.Cu" "B.Cu")
		(net "CPU0_XTRIG_L7")
	)
	(via
		(at 354.406708 -65.058544)
		(size 0.508)
		(drill 0.254)
		(layers "F.Cu" "B.Cu")
		(net "CPU0_XTRIG_L7")
	)
	(via
		(at 363.5756 -135.4836)
		(size 0.508)
		(drill 0.254)
		(layers "F.Cu" "B.Cu")
		(net "CPU0_XTRIG_L7")
	)
	(via
		(at 284.561534 -161.501328)
		(size 0.508)
		(drill 0.254)
		(layers "F.Cu" "B.Cu")
		(net "CPU0_XTRIG_L7")
	)
	(segment
		(start 331.1398 -167.1574)
		(end 331.4954 -167.513)
		(width 0.11684)
		(layer "In6.Cu")
		(net "CPU0_XTRIG_L7")
	)
	(segment
		(start 270.090646 -163.027614)
		(end 226.737926 -163.027614)
		(width 0.11684)
		(layer "In6.Cu")
		(net "CPU0_XTRIG_L7")
	)
	(segment
		(start 329.9206 -167.6908)
		(end 330.454 -167.1574)
		(width 0.11684)
		(layer "In6.Cu")
		(net "CPU0_XTRIG_L7")
	)
	(segment
		(start 226.737926 -163.027614)
		(end 223.401128 -159.690816)
		(width 0.11684)
		(layer "In6.Cu")
		(net "CPU0_XTRIG_L7")
	)
	(segment
		(start 284.561534 -161.501328)
		(end 281.864562 -161.501328)
		(width 0.11684)
		(layer "In6.Cu")
		(net "CPU0_XTRIG_L7")
	)
	(segment
		(start 213.796372 -159.690816)
		(end 206.898494 -166.588694)
		(width 0.11684)
		(layer "In6.Cu")
		(net "CPU0_XTRIG_L7")
	)
	(segment
		(start 284.992572 -163.586668)
		(end 313.04611 -163.586668)
		(width 0.11684)
		(layer "In6.Cu")
		(net "CPU0_XTRIG_L7")
	)
	(segment
		(start 330.454 -167.1574)
		(end 331.1398 -167.1574)
		(width 0.11684)
		(layer "In6.Cu")
		(net "CPU0_XTRIG_L7")
	)
	(segment
		(start 196.831204 -163.129214)
		(end 190.036196 -163.129214)
		(width 0.11684)
		(layer "In6.Cu")
		(net "CPU0_XTRIG_L7")
	)
	(segment
		(start 271.328896 -161.789364)
		(end 270.090646 -163.027614)
		(width 0.11684)
		(layer "In6.Cu")
		(net "CPU0_XTRIG_L7")
	)
	(segment
		(start 281.576526 -161.789364)
		(end 271.328896 -161.789364)
		(width 0.11684)
		(layer "In6.Cu")
		(net "CPU0_XTRIG_L7")
	)
	(segment
		(start 317.150242 -167.6908)
		(end 329.9206 -167.6908)
		(width 0.11684)
		(layer "In6.Cu")
		(net "CPU0_XTRIG_L7")
	)
	(segment
		(start 223.401128 -159.690816)
		(end 213.796372 -159.690816)
		(width 0.11684)
		(layer "In6.Cu")
		(net "CPU0_XTRIG_L7")
	)
	(segment
		(start 284.561534 -161.501328)
		(end 284.561534 -163.15563)
		(width 0.11684)
		(layer "In6.Cu")
		(net "CPU0_XTRIG_L7")
	)
	(segment
		(start 313.04611 -163.586668)
		(end 317.150242 -167.6908)
		(width 0.11684)
		(layer "In6.Cu")
		(net "CPU0_XTRIG_L7")
	)
	(segment
		(start 171.36618 -153.576528)
		(end 170.729656 -153.576528)
		(width 0.11684)
		(layer "In6.Cu")
		(net "CPU0_XTRIG_L7")
	)
	(segment
		(start 181.400958 -158.195518)
		(end 179.763166 -156.557726)
		(width 0.11684)
		(layer "In6.Cu")
		(net "CPU0_XTRIG_L7")
	)
	(segment
		(start 174.347378 -156.557726)
		(end 171.36618 -153.576528)
		(width 0.11684)
		(layer "In6.Cu")
		(net "CPU0_XTRIG_L7")
	)
	(segment
		(start 284.561534 -163.15563)
		(end 284.992572 -163.586668)
		(width 0.11684)
		(layer "In6.Cu")
		(net "CPU0_XTRIG_L7")
	)
	(segment
		(start 281.864562 -161.501328)
		(end 281.576526 -161.789364)
		(width 0.11684)
		(layer "In6.Cu")
		(net "CPU0_XTRIG_L7")
	)
	(segment
		(start 179.763166 -156.557726)
		(end 174.347378 -156.557726)
		(width 0.11684)
		(layer "In6.Cu")
		(net "CPU0_XTRIG_L7")
	)
	(segment
		(start 185.1025 -158.195518)
		(end 181.400958 -158.195518)
		(width 0.11684)
		(layer "In6.Cu")
		(net "CPU0_XTRIG_L7")
	)
	(segment
		(start 170.729656 -153.576528)
		(end 169.212768 -152.05964)
		(width 0.11684)
		(layer "In6.Cu")
		(net "CPU0_XTRIG_L7")
	)
	(segment
		(start 331.4954 -167.513)
		(end 331.4954 -168.1734)
		(width 0.11684)
		(layer "In6.Cu")
		(net "CPU0_XTRIG_L7")
	)
	(segment
		(start 190.036196 -163.129214)
		(end 185.1025 -158.195518)
		(width 0.11684)
		(layer "In6.Cu")
		(net "CPU0_XTRIG_L7")
	)
	(segment
		(start 200.290684 -166.588694)
		(end 196.831204 -163.129214)
		(width 0.11684)
		(layer "In6.Cu")
		(net "CPU0_XTRIG_L7")
	)
	(segment
		(start 206.898494 -166.588694)
		(end 200.290684 -166.588694)
		(width 0.11684)
		(layer "In6.Cu")
		(net "CPU0_XTRIG_L7")
	)
	(segment
		(start 368.091212 -132.59816)
		(end 365.205772 -135.4836)
		(width 0.11684)
		(layer "In11.Cu")
		(net "CPU0_XTRIG_L7")
	)
	(segment
		(start 409.43022 -77.52969)
		(end 405.81961 -81.1403)
		(width 0.11684)
		(layer "In11.Cu")
		(net "CPU0_XTRIG_L7")
	)
	(segment
		(start 405.81961 -124.573538)
		(end 397.794988 -132.59816)
		(width 0.11684)
		(layer "In11.Cu")
		(net "CPU0_XTRIG_L7")
	)
	(segment
		(start 405.81961 -81.1403)
		(end 405.81961 -124.573538)
		(width 0.11684)
		(layer "In11.Cu")
		(net "CPU0_XTRIG_L7")
	)
	(segment
		(start 409.43022 -70.462902)
		(end 409.43022 -77.52969)
		(width 0.11684)
		(layer "In11.Cu")
		(net "CPU0_XTRIG_L7")
	)
	(segment
		(start 365.205772 -135.4836)
		(end 363.5756 -135.4836)
		(width 0.11684)
		(layer "In11.Cu")
		(net "CPU0_XTRIG_L7")
	)
	(segment
		(start 403.660102 -61.269626)
		(end 403.660102 -64.692784)
		(width 0.11684)
		(layer "In11.Cu")
		(net "CPU0_XTRIG_L7")
	)
	(segment
		(start 404.698962 -60.7695)
		(end 404.160228 -60.7695)
		(width 0.11684)
		(layer "In11.Cu")
		(net "CPU0_XTRIG_L7")
	)
	(segment
		(start 403.660102 -64.692784)
		(end 409.43022 -70.462902)
		(width 0.11684)
		(layer "In11.Cu")
		(net "CPU0_XTRIG_L7")
	)
	(segment
		(start 404.160228 -60.7695)
		(end 403.660102 -61.269626)
		(width 0.11684)
		(layer "In11.Cu")
		(net "CPU0_XTRIG_L7")
	)
	(segment
		(start 397.794988 -132.59816)
		(end 368.091212 -132.59816)
		(width 0.11684)
		(layer "In11.Cu")
		(net "CPU0_XTRIG_L7")
	)
	(segment
		(start 343.15273 -130.0734)
		(end 331.21727 -130.0734)
		(width 0.11684)
		(layer "In13.Cu")
		(net "CPU0_XTRIG_L7")
	)
	(segment
		(start 344.14333 -131.064)
		(end 343.15273 -130.0734)
		(width 0.11684)
		(layer "In13.Cu")
		(net "CPU0_XTRIG_L7")
	)
	(segment
		(start 331.21727 -130.0734)
		(end 313.3344 -147.95627)
		(width 0.11684)
		(layer "In13.Cu")
		(net "CPU0_XTRIG_L7")
	)
	(segment
		(start 313.3344 -147.95627)
		(end 313.3344 -164.15893)
		(width 0.11684)
		(layer "In13.Cu")
		(net "CPU0_XTRIG_L7")
	)
	(segment
		(start 331.5208 -169.1132)
		(end 331.5208 -168.1988)
		(width 0.11684)
		(layer "In13.Cu")
		(net "CPU0_XTRIG_L7")
	)
	(segment
		(start 363.5756 -135.4836)
		(end 359.156 -131.064)
		(width 0.11684)
		(layer "In13.Cu")
		(net "CPU0_XTRIG_L7")
	)
	(segment
		(start 313.3344 -164.15893)
		(end 319.05067 -169.8752)
		(width 0.11684)
		(layer "In13.Cu")
		(net "CPU0_XTRIG_L7")
	)
	(segment
		(start 331.5208 -168.1988)
		(end 331.4954 -168.1734)
		(width 0.11684)
		(layer "In13.Cu")
		(net "CPU0_XTRIG_L7")
	)
	(segment
		(start 330.7588 -169.8752)
		(end 331.5208 -169.1132)
		(width 0.11684)
		(layer "In13.Cu")
		(net "CPU0_XTRIG_L7")
	)
	(segment
		(start 319.05067 -169.8752)
		(end 330.7588 -169.8752)
		(width 0.11684)
		(layer "In13.Cu")
		(net "CPU0_XTRIG_L7")
	)
	(segment
		(start 359.156 -131.064)
		(end 344.14333 -131.064)
		(width 0.11684)
		(layer "In13.Cu")
		(net "CPU0_XTRIG_L7")
	)
	(segment
		(start 170.068494 -135.571484)
		(end 171.270676 -136.773666)
		(width 0.11684)
		(layer "In15.Cu")
		(net "CPU0_XTRIG_L7")
	)
	(segment
		(start 174.91964 -96.52508)
		(end 174.91964 -98.38436)
		(width 0.11684)
		(layer "In15.Cu")
		(net "CPU0_XTRIG_L7")
	)
	(segment
		(start 345.76004 -61.311536)
		(end 349.507048 -65.058544)
		(width 0.11684)
		(layer "In15.Cu")
		(net "CPU0_XTRIG_L7")
	)
	(segment
		(start 171.270676 -126.785116)
		(end 170.068494 -127.987298)
		(width 0.11684)
		(layer "In15.Cu")
		(net "CPU0_XTRIG_L7")
	)
	(segment
		(start 396.518892 -50.530252)
		(end 382.894078 -50.530252)
		(width 0.11684)
		(layer "In15.Cu")
		(net "CPU0_XTRIG_L7")
	)
	(segment
		(start 404.698962 -60.7695)
		(end 403.530816 -59.601354)
		(width 0.11684)
		(layer "In15.Cu")
		(net "CPU0_XTRIG_L7")
	)
	(segment
		(start 357.336852 -64.075056)
		(end 356.353364 -65.058544)
		(width 0.11684)
		(layer "In15.Cu")
		(net "CPU0_XTRIG_L7")
	)
	(segment
		(start 171.270676 -147.009866)
		(end 169.223182 -149.05736)
		(width 0.11684)
		(layer "In15.Cu")
		(net "CPU0_XTRIG_L7")
	)
	(segment
		(start 170.068494 -127.987298)
		(end 170.068494 -135.571484)
		(width 0.11684)
		(layer "In15.Cu")
		(net "CPU0_XTRIG_L7")
	)
	(segment
		(start 356.353364 -65.058544)
		(end 354.406708 -65.058544)
		(width 0.11684)
		(layer "In15.Cu")
		(net "CPU0_XTRIG_L7")
	)
	(segment
		(start 403.530816 -59.601354)
		(end 403.530816 -57.542176)
		(width 0.11684)
		(layer "In15.Cu")
		(net "CPU0_XTRIG_L7")
	)
	(segment
		(start 177.002694 -95.758254)
		(end 175.686466 -95.758254)
		(width 0.11684)
		(layer "In15.Cu")
		(net "CPU0_XTRIG_L7")
	)
	(segment
		(start 175.2981 -99.67468)
		(end 173.538896 -101.433884)
		(width 0.11684)
		(layer "In15.Cu")
		(net "CPU0_XTRIG_L7")
	)
	(segment
		(start 171.270676 -136.773666)
		(end 171.270676 -147.009866)
		(width 0.11684)
		(layer "In15.Cu")
		(net "CPU0_XTRIG_L7")
	)
	(segment
		(start 175.686466 -95.758254)
		(end 174.91964 -96.52508)
		(width 0.11684)
		(layer "In15.Cu")
		(net "CPU0_XTRIG_L7")
	)
	(segment
		(start 382.894078 -50.530252)
		(end 369.349274 -64.075056)
		(width 0.11684)
		(layer "In15.Cu")
		(net "CPU0_XTRIG_L7")
	)
	(segment
		(start 349.507048 -65.058544)
		(end 354.406708 -65.058544)
		(width 0.11684)
		(layer "In15.Cu")
		(net "CPU0_XTRIG_L7")
	)
	(segment
		(start 174.91964 -98.38436)
		(end 175.2981 -98.76282)
		(width 0.11684)
		(layer "In15.Cu")
		(net "CPU0_XTRIG_L7")
	)
	(segment
		(start 177.673 -95.087948)
		(end 177.002694 -95.758254)
		(width 0.11684)
		(layer "In15.Cu")
		(net "CPU0_XTRIG_L7")
	)
	(segment
		(start 175.2981 -98.76282)
		(end 175.2981 -99.67468)
		(width 0.11684)
		(layer "In15.Cu")
		(net "CPU0_XTRIG_L7")
	)
	(segment
		(start 403.530816 -57.542176)
		(end 396.518892 -50.530252)
		(width 0.11684)
		(layer "In15.Cu")
		(net "CPU0_XTRIG_L7")
	)
	(segment
		(start 169.223182 -149.05736)
		(end 169.223182 -152.049226)
		(width 0.11684)
		(layer "In15.Cu")
		(net "CPU0_XTRIG_L7")
	)
	(segment
		(start 369.349274 -64.075056)
		(end 357.336852 -64.075056)
		(width 0.11684)
		(layer "In15.Cu")
		(net "CPU0_XTRIG_L7")
	)
	(segment
		(start 171.270676 -121.104152)
		(end 171.270676 -126.785116)
		(width 0.11684)
		(layer "In15.Cu")
		(net "CPU0_XTRIG_L7")
	)
	(segment
		(start 169.223182 -152.049226)
		(end 169.212768 -152.05964)
		(width 0.11684)
		(layer "In15.Cu")
		(net "CPU0_XTRIG_L7")
	)
	(segment
		(start 173.538896 -101.433884)
		(end 173.3042 -102.000558)
		(width 0.11684)
		(layer "In15.Cu")
		(net "CPU0_XTRIG_L7")
	)
	(segment
		(start 173.3042 -102.34676)
		(end 171.769786 -103.881174)
		(width 0.11684)
		(layer "In15.Cu")
		(net "CPU0_XTRIG_L7")
	)
	(segment
		(start 173.3042 -102.000558)
		(end 173.3042 -102.34676)
		(width 0.11684)
		(layer "In15.Cu")
		(net "CPU0_XTRIG_L7")
	)
	(segment
		(start 171.769786 -120.605042)
		(end 171.270676 -121.104152)
		(width 0.11684)
		(layer "In15.Cu")
		(net "CPU0_XTRIG_L7")
	)
	(segment
		(start 171.769786 -103.881174)
		(end 171.769786 -120.605042)
		(width 0.11684)
		(layer "In15.Cu")
		(net "CPU0_XTRIG_L7")
	)
	(segment
		(start 345.76004 -44.250102)
		(end 345.76004 -61.311536)
		(width 0.11684)
		(layer "In15.Cu")
		(net "CPU0_XTRIG_L7")
	)
	(segment
		(start 176.04105 -95.703898)
		(end 176.657 -95.087948)
		(width 0.10668)
		(layer "F.Cu")
		(net "CPU0_XTRIG_L6")
	)
	(segment
		(start 175.4632 -95.703898)
		(end 176.04105 -95.703898)
		(width 0.10668)
		(layer "F.Cu")
		(net "CPU0_XTRIG_L6")
	)
	(segment
		(start 352.001328 -63.788544)
		(end 354.406708 -63.788544)
		(width 0.10668)
		(layer "F.Cu")
		(net "CPU0_XTRIG_L6")
	)
	(segment
		(start 404.083012 -59.4995)
		(end 404.698962 -59.4995)
		(width 0.10668)
		(layer "F.Cu")
		(net "CPU0_XTRIG_L6")
	)
	(segment
		(start 328.339958 -171.278042)
		(end 328.339958 -193.652902)
		(width 0.10668)
		(layer "F.Cu")
		(net "CPU0_XTRIG_L6")
	)
	(segment
		(start 328.316844 -193.676016)
		(end 328.339958 -193.652902)
		(width 0.10668)
		(layer "F.Cu")
		(net "CPU0_XTRIG_L6")
	)
	(segment
		(start 327.7743 -193.540634)
		(end 327.909682 -193.676016)
		(width 0.10668)
		(layer "F.Cu")
		(net "CPU0_XTRIG_L6")
	)
	(segment
		(start 330.835 -168.783)
		(end 328.339958 -171.278042)
		(width 0.10668)
		(layer "F.Cu")
		(net "CPU0_XTRIG_L6")
	)
	(segment
		(start 327.323958 -193.564002)
		(end 327.347326 -193.540634)
		(width 0.10668)
		(layer "F.Cu")
		(net "CPU0_XTRIG_L6")
	)
	(segment
		(start 327.909682 -193.676016)
		(end 328.316844 -193.676016)
		(width 0.10668)
		(layer "F.Cu")
		(net "CPU0_XTRIG_L6")
	)
	(segment
		(start 350.84766 -62.634876)
		(end 352.001328 -63.788544)
		(width 0.10668)
		(layer "F.Cu")
		(net "CPU0_XTRIG_L6")
	)
	(segment
		(start 327.347326 -193.540634)
		(end 327.7743 -193.540634)
		(width 0.10668)
		(layer "F.Cu")
		(net "CPU0_XTRIG_L6")
	)
	(via
		(at 354.406708 -63.788544)
		(size 0.508)
		(drill 0.254)
		(layers "F.Cu" "B.Cu")
		(net "CPU0_XTRIG_L6")
	)
	(via
		(at 364.5916 -136.1948)
		(size 0.508)
		(drill 0.254)
		(layers "F.Cu" "B.Cu")
		(net "CPU0_XTRIG_L6")
	)
	(via
		(at 168.399968 -152.05964)
		(size 0.508)
		(drill 0.254)
		(layers "F.Cu" "B.Cu")
		(net "CPU0_XTRIG_L6")
	)
	(via
		(at 404.698962 -59.4995)
		(size 0.508)
		(drill 0.254)
		(layers "F.Cu" "B.Cu")
		(net "CPU0_XTRIG_L6")
	)
	(via
		(at 176.657 -95.087948)
		(size 0.508)
		(drill 0.254)
		(layers "F.Cu" "B.Cu")
		(net "CPU0_XTRIG_L6")
	)
	(via
		(at 330.835 -168.783)
		(size 0.508)
		(drill 0.254)
		(layers "F.Cu" "B.Cu")
		(net "CPU0_XTRIG_L6")
	)
	(segment
		(start 283.763974 -163.62553)
		(end 283.763974 -162.303206)
		(width 0.11684)
		(layer "In6.Cu")
		(net "CPU0_XTRIG_L6")
	)
	(segment
		(start 271.548098 -162.318192)
		(end 270.309848 -163.556442)
		(width 0.11684)
		(layer "In6.Cu")
		(net "CPU0_XTRIG_L6")
	)
	(segment
		(start 214.015574 -160.219644)
		(end 207.117696 -167.117522)
		(width 0.11684)
		(layer "In6.Cu")
		(net "CPU0_XTRIG_L6")
	)
	(segment
		(start 196.612002 -163.658042)
		(end 189.930786 -163.658042)
		(width 0.11684)
		(layer "In6.Cu")
		(net "CPU0_XTRIG_L6")
	)
	(segment
		(start 270.309848 -163.556442)
		(end 226.518724 -163.556442)
		(width 0.11684)
		(layer "In6.Cu")
		(net "CPU0_XTRIG_L6")
	)
	(segment
		(start 283.763974 -162.303206)
		(end 283.41955 -161.958782)
		(width 0.11684)
		(layer "In6.Cu")
		(net "CPU0_XTRIG_L6")
	)
	(segment
		(start 200.071482 -167.117522)
		(end 196.612002 -163.658042)
		(width 0.11684)
		(layer "In6.Cu")
		(net "CPU0_XTRIG_L6")
	)
	(segment
		(start 189.930786 -163.658042)
		(end 184.99709 -158.724346)
		(width 0.11684)
		(layer "In6.Cu")
		(net "CPU0_XTRIG_L6")
	)
	(segment
		(start 223.181926 -160.219644)
		(end 214.015574 -160.219644)
		(width 0.11684)
		(layer "In6.Cu")
		(net "CPU0_XTRIG_L6")
	)
	(segment
		(start 284.232604 -164.09416)
		(end 283.763974 -163.62553)
		(width 0.11684)
		(layer "In6.Cu")
		(net "CPU0_XTRIG_L6")
	)
	(segment
		(start 171.146978 -154.105356)
		(end 169.960544 -154.105356)
		(width 0.11684)
		(layer "In6.Cu")
		(net "CPU0_XTRIG_L6")
	)
	(segment
		(start 181.200552 -158.724346)
		(end 179.56276 -157.086554)
		(width 0.11684)
		(layer "In6.Cu")
		(net "CPU0_XTRIG_L6")
	)
	(segment
		(start 282.018994 -162.318192)
		(end 271.548098 -162.318192)
		(width 0.11684)
		(layer "In6.Cu")
		(net "CPU0_XTRIG_L6")
	)
	(segment
		(start 330.835 -168.783)
		(end 317.64605 -168.783)
		(width 0.11684)
		(layer "In6.Cu")
		(net "CPU0_XTRIG_L6")
	)
	(segment
		(start 207.117696 -167.117522)
		(end 200.071482 -167.117522)
		(width 0.11684)
		(layer "In6.Cu")
		(net "CPU0_XTRIG_L6")
	)
	(segment
		(start 312.95721 -164.09416)
		(end 284.232604 -164.09416)
		(width 0.11684)
		(layer "In6.Cu")
		(net "CPU0_XTRIG_L6")
	)
	(segment
		(start 179.56276 -157.086554)
		(end 174.128176 -157.086554)
		(width 0.11684)
		(layer "In6.Cu")
		(net "CPU0_XTRIG_L6")
	)
	(segment
		(start 169.960544 -154.105356)
		(end 168.399968 -152.54478)
		(width 0.11684)
		(layer "In6.Cu")
		(net "CPU0_XTRIG_L6")
	)
	(segment
		(start 283.41955 -161.958782)
		(end 282.378404 -161.958782)
		(width 0.11684)
		(layer "In6.Cu")
		(net "CPU0_XTRIG_L6")
	)
	(segment
		(start 282.378404 -161.958782)
		(end 282.018994 -162.318192)
		(width 0.11684)
		(layer "In6.Cu")
		(net "CPU0_XTRIG_L6")
	)
	(segment
		(start 168.399968 -152.54478)
		(end 168.399968 -152.05964)
		(width 0.11684)
		(layer "In6.Cu")
		(net "CPU0_XTRIG_L6")
	)
	(segment
		(start 226.518724 -163.556442)
		(end 223.181926 -160.219644)
		(width 0.11684)
		(layer "In6.Cu")
		(net "CPU0_XTRIG_L6")
	)
	(segment
		(start 317.64605 -168.783)
		(end 312.95721 -164.09416)
		(width 0.11684)
		(layer "In6.Cu")
		(net "CPU0_XTRIG_L6")
	)
	(segment
		(start 174.128176 -157.086554)
		(end 171.146978 -154.105356)
		(width 0.11684)
		(layer "In6.Cu")
		(net "CPU0_XTRIG_L6")
	)
	(segment
		(start 184.99709 -158.724346)
		(end 181.200552 -158.724346)
		(width 0.11684)
		(layer "In6.Cu")
		(net "CPU0_XTRIG_L6")
	)
	(segment
		(start 409.85186 -77.807058)
		(end 409.85186 -70.28815)
		(width 0.11684)
		(layer "In11.Cu")
		(net "CPU0_XTRIG_L6")
	)
	(segment
		(start 404.343616 -61.42228)
		(end 405.065484 -61.42228)
		(width 0.11684)
		(layer "In11.Cu")
		(net "CPU0_XTRIG_L6")
	)
	(segment
		(start 368.225578 -133.10616)
		(end 397.939006 -133.10616)
		(width 0.11684)
		(layer "In11.Cu")
		(net "CPU0_XTRIG_L6")
	)
	(segment
		(start 397.939006 -133.10616)
		(end 406.285446 -124.75972)
		(width 0.11684)
		(layer "In11.Cu")
		(net "CPU0_XTRIG_L6")
	)
	(segment
		(start 406.285446 -124.75972)
		(end 406.285446 -81.373472)
		(width 0.11684)
		(layer "In11.Cu")
		(net "CPU0_XTRIG_L6")
	)
	(segment
		(start 406.285446 -81.373472)
		(end 409.85186 -77.807058)
		(width 0.11684)
		(layer "In11.Cu")
		(net "CPU0_XTRIG_L6")
	)
	(segment
		(start 364.5916 -136.1948)
		(end 365.136938 -136.1948)
		(width 0.11684)
		(layer "In11.Cu")
		(net "CPU0_XTRIG_L6")
	)
	(segment
		(start 405.39797 -60.198508)
		(end 404.698962 -59.4995)
		(width 0.11684)
		(layer "In11.Cu")
		(net "CPU0_XTRIG_L6")
	)
	(segment
		(start 404.081742 -64.518032)
		(end 404.081742 -61.684154)
		(width 0.11684)
		(layer "In11.Cu")
		(net "CPU0_XTRIG_L6")
	)
	(segment
		(start 404.081742 -61.684154)
		(end 404.343616 -61.42228)
		(width 0.11684)
		(layer "In11.Cu")
		(net "CPU0_XTRIG_L6")
	)
	(segment
		(start 365.136938 -136.1948)
		(end 368.225578 -133.10616)
		(width 0.11684)
		(layer "In11.Cu")
		(net "CPU0_XTRIG_L6")
	)
	(segment
		(start 409.85186 -70.28815)
		(end 404.081742 -64.518032)
		(width 0.11684)
		(layer "In11.Cu")
		(net "CPU0_XTRIG_L6")
	)
	(segment
		(start 405.39797 -61.089794)
		(end 405.39797 -60.198508)
		(width 0.11684)
		(layer "In11.Cu")
		(net "CPU0_XTRIG_L6")
	)
	(segment
		(start 405.065484 -61.42228)
		(end 405.39797 -61.089794)
		(width 0.11684)
		(layer "In11.Cu")
		(net "CPU0_XTRIG_L6")
	)
	(segment
		(start 313.7662 -163.97986)
		(end 313.7662 -148.13534)
		(width 0.11684)
		(layer "In13.Cu")
		(net "CPU0_XTRIG_L6")
	)
	(segment
		(start 330.1746 -169.4434)
		(end 319.22974 -169.4434)
		(width 0.11684)
		(layer "In13.Cu")
		(net "CPU0_XTRIG_L6")
	)
	(segment
		(start 331.39634 -130.5052)
		(end 342.97366 -130.5052)
		(width 0.11684)
		(layer "In13.Cu")
		(net "CPU0_XTRIG_L6")
	)
	(segment
		(start 342.97366 -130.5052)
		(end 343.96426 -131.4958)
		(width 0.11684)
		(layer "In13.Cu")
		(net "CPU0_XTRIG_L6")
	)
	(segment
		(start 358.6988 -131.4958)
		(end 363.3978 -136.1948)
		(width 0.11684)
		(layer "In13.Cu")
		(net "CPU0_XTRIG_L6")
	)
	(segment
		(start 363.3978 -136.1948)
		(end 364.5916 -136.1948)
		(width 0.11684)
		(layer "In13.Cu")
		(net "CPU0_XTRIG_L6")
	)
	(segment
		(start 313.7662 -148.13534)
		(end 331.39634 -130.5052)
		(width 0.11684)
		(layer "In13.Cu")
		(net "CPU0_XTRIG_L6")
	)
	(segment
		(start 330.835 -168.783)
		(end 330.1746 -169.4434)
		(width 0.11684)
		(layer "In13.Cu")
		(net "CPU0_XTRIG_L6")
	)
	(segment
		(start 319.22974 -169.4434)
		(end 313.7662 -163.97986)
		(width 0.11684)
		(layer "In13.Cu")
		(net "CPU0_XTRIG_L6")
	)
	(segment
		(start 343.96426 -131.4958)
		(end 358.6988 -131.4958)
		(width 0.11684)
		(layer "In13.Cu")
		(net "CPU0_XTRIG_L6")
	)
	(segment
		(start 170.849036 -138.06297)
		(end 170.838622 -138.073384)
		(width 0.11684)
		(layer "In15.Cu")
		(net "CPU0_XTRIG_L6")
	)
	(segment
		(start 348.30004 -44.250102)
		(end 348.30004 -62.055248)
		(width 0.11684)
		(layer "In15.Cu")
		(net "CPU0_XTRIG_L6")
	)
	(segment
		(start 170.838622 -146.582638)
		(end 168.399968 -149.021292)
		(width 0.11684)
		(layer "In15.Cu")
		(net "CPU0_XTRIG_L6")
	)
	(segment
		(start 169.94378 -101.936804)
		(end 171.337732 -103.330756)
		(width 0.11684)
		(layer "In15.Cu")
		(net "CPU0_XTRIG_L6")
	)
	(segment
		(start 348.30004 -62.055248)
		(end 350.033336 -63.788544)
		(width 0.11684)
		(layer "In15.Cu")
		(net "CPU0_XTRIG_L6")
	)
	(segment
		(start 176.411636 -94.842584)
		(end 170.77055 -94.842584)
		(width 0.11684)
		(layer "In15.Cu")
		(net "CPU0_XTRIG_L6")
	)
	(segment
		(start 356.95509 -63.788544)
		(end 354.406708 -63.788544)
		(width 0.11684)
		(layer "In15.Cu")
		(net "CPU0_XTRIG_L6")
	)
	(segment
		(start 170.838622 -138.073384)
		(end 170.838622 -146.582638)
		(width 0.11684)
		(layer "In15.Cu")
		(net "CPU0_XTRIG_L6")
	)
	(segment
		(start 170.26128 -95.351854)
		(end 170.26128 -98.28784)
		(width 0.11684)
		(layer "In15.Cu")
		(net "CPU0_XTRIG_L6")
	)
	(segment
		(start 169.612056 -127.780288)
		(end 169.612056 -135.724138)
		(width 0.11684)
		(layer "In15.Cu")
		(net "CPU0_XTRIG_L6")
	)
	(segment
		(start 171.337732 -103.330756)
		(end 171.337732 -120.425972)
		(width 0.11684)
		(layer "In15.Cu")
		(net "CPU0_XTRIG_L6")
	)
	(segment
		(start 170.849036 -136.961118)
		(end 170.849036 -138.06297)
		(width 0.11684)
		(layer "In15.Cu")
		(net "CPU0_XTRIG_L6")
	)
	(segment
		(start 396.795752 -49.861978)
		(end 382.617218 -49.861978)
		(width 0.11684)
		(layer "In15.Cu")
		(net "CPU0_XTRIG_L6")
	)
	(segment
		(start 170.26128 -98.28784)
		(end 169.94378 -98.60534)
		(width 0.11684)
		(layer "In15.Cu")
		(net "CPU0_XTRIG_L6")
	)
	(segment
		(start 404.698962 -57.765188)
		(end 396.795752 -49.861978)
		(width 0.11684)
		(layer "In15.Cu")
		(net "CPU0_XTRIG_L6")
	)
	(segment
		(start 357.336852 -63.406782)
		(end 356.95509 -63.788544)
		(width 0.11684)
		(layer "In15.Cu")
		(net "CPU0_XTRIG_L6")
	)
	(segment
		(start 369.072414 -63.406782)
		(end 357.336852 -63.406782)
		(width 0.11684)
		(layer "In15.Cu")
		(net "CPU0_XTRIG_L6")
	)
	(segment
		(start 169.94378 -98.60534)
		(end 169.94378 -101.936804)
		(width 0.11684)
		(layer "In15.Cu")
		(net "CPU0_XTRIG_L6")
	)
	(segment
		(start 404.698962 -59.4995)
		(end 404.698962 -57.765188)
		(width 0.11684)
		(layer "In15.Cu")
		(net "CPU0_XTRIG_L6")
	)
	(segment
		(start 170.838622 -126.553722)
		(end 169.612056 -127.780288)
		(width 0.11684)
		(layer "In15.Cu")
		(net "CPU0_XTRIG_L6")
	)
	(segment
		(start 170.77055 -94.842584)
		(end 170.26128 -95.351854)
		(width 0.11684)
		(layer "In15.Cu")
		(net "CPU0_XTRIG_L6")
	)
	(segment
		(start 170.838622 -120.925082)
		(end 170.838622 -126.553722)
		(width 0.11684)
		(layer "In15.Cu")
		(net "CPU0_XTRIG_L6")
	)
	(segment
		(start 171.337732 -120.425972)
		(end 170.838622 -120.925082)
		(width 0.11684)
		(layer "In15.Cu")
		(net "CPU0_XTRIG_L6")
	)
	(segment
		(start 176.657 -95.087948)
		(end 176.411636 -94.842584)
		(width 0.11684)
		(layer "In15.Cu")
		(net "CPU0_XTRIG_L6")
	)
	(segment
		(start 169.612056 -135.724138)
		(end 170.849036 -136.961118)
		(width 0.11684)
		(layer "In15.Cu")
		(net "CPU0_XTRIG_L6")
	)
	(segment
		(start 382.617218 -49.861978)
		(end 369.072414 -63.406782)
		(width 0.11684)
		(layer "In15.Cu")
		(net "CPU0_XTRIG_L6")
	)
	(segment
		(start 168.399968 -149.021292)
		(end 168.399968 -152.05964)
		(width 0.11684)
		(layer "In15.Cu")
		(net "CPU0_XTRIG_L6")
	)
	(segment
		(start 350.033336 -63.788544)
		(end 354.406708 -63.788544)
		(width 0.11684)
		(layer "In15.Cu")
		(net "CPU0_XTRIG_L6")
	)
	(segment
		(start 313.355736 -197.412102)
		(end 313.74461 -197.412102)
		(width 0.10668)
		(layer "F.Cu")
		(net "CPU0_XTRIG_L5")
	)
	(segment
		(start 287.731962 -170.83405)
		(end 297.341036 -170.83405)
		(width 0.10668)
		(layer "F.Cu")
		(net "CPU0_XTRIG_L5")
	)
	(segment
		(start 297.341036 -170.83405)
		(end 312.10758 -185.600594)
		(width 0.10668)
		(layer "F.Cu")
		(net "CPU0_XTRIG_L5")
	)
	(segment
		(start 404.083012 -62.0395)
		(end 404.698962 -62.0395)
		(width 0.10668)
		(layer "F.Cu")
		(net "CPU0_XTRIG_L5")
	)
	(segment
		(start 312.10758 -185.600594)
		(end 312.10758 -196.163946)
		(width 0.10668)
		(layer "F.Cu")
		(net "CPU0_XTRIG_L5")
	)
	(segment
		(start 312.10758 -196.163946)
		(end 313.355736 -197.412102)
		(width 0.10668)
		(layer "F.Cu")
		(net "CPU0_XTRIG_L5")
	)
	(segment
		(start 176.657 -99.894898)
		(end 176.657 -99.278948)
		(width 0.10668)
		(layer "F.Cu")
		(net "CPU0_XTRIG_L5")
	)
	(segment
		(start 350.84766 -61.364876)
		(end 351.46361 -61.364876)
		(width 0.10668)
		(layer "F.Cu")
		(net "CPU0_XTRIG_L5")
	)
	(segment
		(start 282.49626 -165.598348)
		(end 287.731962 -170.83405)
		(width 0.10668)
		(layer "F.Cu")
		(net "CPU0_XTRIG_L5")
	)
	(via
		(at 404.698962 -62.0395)
		(size 0.508)
		(drill 0.254)
		(layers "F.Cu" "B.Cu")
		(net "CPU0_XTRIG_L5")
	)
	(via
		(at 351.46361 -61.364876)
		(size 0.508)
		(drill 0.254)
		(layers "F.Cu" "B.Cu")
		(net "CPU0_XTRIG_L5")
	)
	(via
		(at 176.657 -99.278948)
		(size 0.508)
		(drill 0.254)
		(layers "F.Cu" "B.Cu")
		(net "CPU0_XTRIG_L5")
	)
	(via
		(at 399.624804 -138.011154)
		(size 0.508)
		(drill 0.254)
		(layers "F.Cu" "B.Cu")
		(net "CPU0_XTRIG_L5")
	)
	(via
		(at 313.74461 -197.412102)
		(size 0.508)
		(drill 0.254)
		(layers "F.Cu" "B.Cu")
		(net "CPU0_XTRIG_L5")
	)
	(via
		(at 282.49626 -165.598348)
		(size 0.508)
		(drill 0.254)
		(layers "F.Cu" "B.Cu")
		(net "CPU0_XTRIG_L5")
	)
	(via
		(at 178.955446 -166.430452)
		(size 0.508)
		(drill 0.254)
		(layers "F.Cu" "B.Cu")
		(net "CPU0_XTRIG_L5")
	)
	(segment
		(start 326.815958 -203.529946)
		(end 326.815958 -202.513946)
		(width 0.10668)
		(layer "B.Cu")
		(net "CPU0_XTRIG_L5")
	)
	(segment
		(start 327.35139 -201.978514)
		(end 327.35139 -201.243184)
		(width 0.10668)
		(layer "B.Cu")
		(net "CPU0_XTRIG_L5")
	)
	(segment
		(start 313.74461 -198.440548)
		(end 313.74461 -197.412102)
		(width 0.10668)
		(layer "B.Cu")
		(net "CPU0_XTRIG_L5")
	)
	(segment
		(start 316.321694 -201.017632)
		(end 313.74461 -198.440548)
		(width 0.10668)
		(layer "B.Cu")
		(net "CPU0_XTRIG_L5")
	)
	(segment
		(start 326.815958 -202.513946)
		(end 327.35139 -201.978514)
		(width 0.10668)
		(layer "B.Cu")
		(net "CPU0_XTRIG_L5")
	)
	(segment
		(start 327.35139 -201.243184)
		(end 327.125838 -201.017632)
		(width 0.10668)
		(layer "B.Cu")
		(net "CPU0_XTRIG_L5")
	)
	(segment
		(start 327.125838 -201.017632)
		(end 316.321694 -201.017632)
		(width 0.10668)
		(layer "B.Cu")
		(net "CPU0_XTRIG_L5")
	)
	(segment
		(start 396.22476 -138.011154)
		(end 395.444726 -138.791188)
		(width 0.11684)
		(layer "In2.Cu")
		(net "CPU0_XTRIG_L5")
	)
	(segment
		(start 282.913074 -166.015162)
		(end 282.49626 -165.598348)
		(width 0.11684)
		(layer "In2.Cu")
		(net "CPU0_XTRIG_L5")
	)
	(segment
		(start 343.401142 -146.661378)
		(end 331.465682 -146.661378)
		(width 0.11684)
		(layer "In2.Cu")
		(net "CPU0_XTRIG_L5")
	)
	(segment
		(start 390.25068 -138.791188)
		(end 386.825744 -135.366252)
		(width 0.11684)
		(layer "In2.Cu")
		(net "CPU0_XTRIG_L5")
	)
	(segment
		(start 372.4656 -149.4282)
		(end 363.333284 -149.4282)
		(width 0.11684)
		(layer "In2.Cu")
		(net "CPU0_XTRIG_L5")
	)
	(segment
		(start 377.185174 -135.366252)
		(end 372.9863 -139.565126)
		(width 0.11684)
		(layer "In2.Cu")
		(net "CPU0_XTRIG_L5")
	)
	(segment
		(start 358.459024 -144.55394)
		(end 345.50858 -144.55394)
		(width 0.11684)
		(layer "In2.Cu")
		(net "CPU0_XTRIG_L5")
	)
	(segment
		(start 330.4032 -164.26434)
		(end 330.4032 -167.182546)
		(width 0.11684)
		(layer "In2.Cu")
		(net "CPU0_XTRIG_L5")
	)
	(segment
		(start 372.9863 -144.19199)
		(end 373.920004 -145.125694)
		(width 0.11684)
		(layer "In2.Cu")
		(net "CPU0_XTRIG_L5")
	)
	(segment
		(start 373.920004 -145.125694)
		(end 373.920004 -147.973796)
		(width 0.11684)
		(layer "In2.Cu")
		(net "CPU0_XTRIG_L5")
	)
	(segment
		(start 373.920004 -147.973796)
		(end 372.4656 -149.4282)
		(width 0.11684)
		(layer "In2.Cu")
		(net "CPU0_XTRIG_L5")
	)
	(segment
		(start 372.9863 -139.565126)
		(end 372.9863 -144.19199)
		(width 0.11684)
		(layer "In2.Cu")
		(net "CPU0_XTRIG_L5")
	)
	(segment
		(start 363.333284 -149.4282)
		(end 358.459024 -144.55394)
		(width 0.11684)
		(layer "In2.Cu")
		(net "CPU0_XTRIG_L5")
	)
	(segment
		(start 302.448976 -170.79341)
		(end 297.670728 -166.015162)
		(width 0.11684)
		(layer "In2.Cu")
		(net "CPU0_XTRIG_L5")
	)
	(segment
		(start 395.444726 -138.791188)
		(end 390.25068 -138.791188)
		(width 0.11684)
		(layer "In2.Cu")
		(net "CPU0_XTRIG_L5")
	)
	(segment
		(start 399.624804 -138.011154)
		(end 396.22476 -138.011154)
		(width 0.11684)
		(layer "In2.Cu")
		(net "CPU0_XTRIG_L5")
	)
	(segment
		(start 297.670728 -166.015162)
		(end 282.913074 -166.015162)
		(width 0.11684)
		(layer "In2.Cu")
		(net "CPU0_XTRIG_L5")
	)
	(segment
		(start 386.825744 -135.366252)
		(end 377.185174 -135.366252)
		(width 0.11684)
		(layer "In2.Cu")
		(net "CPU0_XTRIG_L5")
	)
	(segment
		(start 345.50858 -144.55394)
		(end 343.401142 -146.661378)
		(width 0.11684)
		(layer "In2.Cu")
		(net "CPU0_XTRIG_L5")
	)
	(segment
		(start 331.465682 -146.661378)
		(end 328.24674 -149.88032)
		(width 0.11684)
		(layer "In2.Cu")
		(net "CPU0_XTRIG_L5")
	)
	(segment
		(start 326.792336 -170.79341)
		(end 302.448976 -170.79341)
		(width 0.11684)
		(layer "In2.Cu")
		(net "CPU0_XTRIG_L5")
	)
	(segment
		(start 328.24674 -149.88032)
		(end 328.24674 -162.10788)
		(width 0.11684)
		(layer "In2.Cu")
		(net "CPU0_XTRIG_L5")
	)
	(segment
		(start 330.4032 -167.182546)
		(end 326.792336 -170.79341)
		(width 0.11684)
		(layer "In2.Cu")
		(net "CPU0_XTRIG_L5")
	)
	(segment
		(start 328.24674 -162.10788)
		(end 330.4032 -164.26434)
		(width 0.11684)
		(layer "In2.Cu")
		(net "CPU0_XTRIG_L5")
	)
	(segment
		(start 198.396606 -169.225722)
		(end 196.723762 -167.552878)
		(width 0.11684)
		(layer "In6.Cu")
		(net "CPU0_XTRIG_L5")
	)
	(segment
		(start 225.62058 -165.722808)
		(end 222.396812 -162.49904)
		(width 0.11684)
		(layer "In6.Cu")
		(net "CPU0_XTRIG_L5")
	)
	(segment
		(start 208.074006 -169.225722)
		(end 198.396606 -169.225722)
		(width 0.11684)
		(layer "In6.Cu")
		(net "CPU0_XTRIG_L5")
	)
	(segment
		(start 178.955446 -166.491412)
		(end 178.955446 -166.430452)
		(width 0.11684)
		(layer "In6.Cu")
		(net "CPU0_XTRIG_L5")
	)
	(segment
		(start 180.016912 -167.552878)
		(end 178.955446 -166.491412)
		(width 0.11684)
		(layer "In6.Cu")
		(net "CPU0_XTRIG_L5")
	)
	(segment
		(start 281.549094 -166.545514)
		(end 272.031206 -166.545514)
		(width 0.11684)
		(layer "In6.Cu")
		(net "CPU0_XTRIG_L5")
	)
	(segment
		(start 214.800688 -162.49904)
		(end 208.074006 -169.225722)
		(width 0.11684)
		(layer "In6.Cu")
		(net "CPU0_XTRIG_L5")
	)
	(segment
		(start 222.396812 -162.49904)
		(end 214.800688 -162.49904)
		(width 0.11684)
		(layer "In6.Cu")
		(net "CPU0_XTRIG_L5")
	)
	(segment
		(start 196.723762 -167.552878)
		(end 180.016912 -167.552878)
		(width 0.11684)
		(layer "In6.Cu")
		(net "CPU0_XTRIG_L5")
	)
	(segment
		(start 271.2085 -165.722808)
		(end 225.62058 -165.722808)
		(width 0.11684)
		(layer "In6.Cu")
		(net "CPU0_XTRIG_L5")
	)
	(segment
		(start 272.031206 -166.545514)
		(end 271.2085 -165.722808)
		(width 0.11684)
		(layer "In6.Cu")
		(net "CPU0_XTRIG_L5")
	)
	(segment
		(start 282.49626 -165.598348)
		(end 281.549094 -166.545514)
		(width 0.11684)
		(layer "In6.Cu")
		(net "CPU0_XTRIG_L5")
	)
	(segment
		(start 407.286714 -81.885028)
		(end 410.839666 -78.332076)
		(width 0.11684)
		(layer "In11.Cu")
		(net "CPU0_XTRIG_L5")
	)
	(segment
		(start 410.839666 -68.180204)
		(end 404.698962 -62.0395)
		(width 0.11684)
		(layer "In11.Cu")
		(net "CPU0_XTRIG_L5")
	)
	(segment
		(start 399.624804 -138.011154)
		(end 399.624804 -132.701284)
		(width 0.11684)
		(layer "In11.Cu")
		(net "CPU0_XTRIG_L5")
	)
	(segment
		(start 407.286714 -125.039374)
		(end 407.286714 -81.885028)
		(width 0.11684)
		(layer "In11.Cu")
		(net "CPU0_XTRIG_L5")
	)
	(segment
		(start 410.839666 -78.332076)
		(end 410.839666 -68.180204)
		(width 0.11684)
		(layer "In11.Cu")
		(net "CPU0_XTRIG_L5")
	)
	(segment
		(start 399.624804 -132.701284)
		(end 407.286714 -125.039374)
		(width 0.11684)
		(layer "In11.Cu")
		(net "CPU0_XTRIG_L5")
	)
	(segment
		(start 180.004466 -164.258244)
		(end 178.955446 -165.307264)
		(width 0.11684)
		(layer "In15.Cu")
		(net "CPU0_XTRIG_L5")
	)
	(segment
		(start 171.716446 -130.739642)
		(end 171.361862 -131.094226)
		(width 0.11684)
		(layer "In15.Cu")
		(net "CPU0_XTRIG_L5")
	)
	(segment
		(start 172.83303 -122.915934)
		(end 171.716446 -124.032518)
		(width 0.11684)
		(layer "In15.Cu")
		(net "CPU0_XTRIG_L5")
	)
	(segment
		(start 406.740614 -62.0395)
		(end 404.698962 -62.0395)
		(width 0.11684)
		(layer "In15.Cu")
		(net "CPU0_XTRIG_L5")
	)
	(segment
		(start 175.241966 -100.891594)
		(end 174.6377 -101.49586)
		(width 0.11684)
		(layer "In15.Cu")
		(net "CPU0_XTRIG_L5")
	)
	(segment
		(start 174.6377 -102.374954)
		(end 173.172628 -103.840026)
		(width 0.11684)
		(layer "In15.Cu")
		(net "CPU0_XTRIG_L5")
	)
	(segment
		(start 350.138492 -44.95165)
		(end 350.138492 -60.039758)
		(width 0.11684)
		(layer "In15.Cu")
		(net "CPU0_XTRIG_L5")
	)
	(segment
		(start 176.657 -99.278948)
		(end 176.657 -100.355654)
		(width 0.11684)
		(layer "In15.Cu")
		(net "CPU0_XTRIG_L5")
	)
	(segment
		(start 176.657 -100.355654)
		(end 176.12106 -100.891594)
		(width 0.11684)
		(layer "In15.Cu")
		(net "CPU0_XTRIG_L5")
	)
	(segment
		(start 350.84004 -44.250102)
		(end 350.138492 -44.95165)
		(width 0.11684)
		(layer "In15.Cu")
		(net "CPU0_XTRIG_L5")
	)
	(segment
		(start 171.361862 -136.066276)
		(end 171.716446 -136.42086)
		(width 0.11684)
		(layer "In15.Cu")
		(net "CPU0_XTRIG_L5")
	)
	(segment
		(start 351.46361 -61.364876)
		(end 369.840764 -61.364876)
		(width 0.11684)
		(layer "In15.Cu")
		(net "CPU0_XTRIG_L5")
	)
	(segment
		(start 180.004466 -162.048952)
		(end 180.004466 -164.258244)
		(width 0.11684)
		(layer "In15.Cu")
		(net "CPU0_XTRIG_L5")
	)
	(segment
		(start 171.716446 -153.760932)
		(end 180.004466 -162.048952)
		(width 0.11684)
		(layer "In15.Cu")
		(net "CPU0_XTRIG_L5")
	)
	(segment
		(start 172.83303 -119.964962)
		(end 172.83303 -122.915934)
		(width 0.11684)
		(layer "In15.Cu")
		(net "CPU0_XTRIG_L5")
	)
	(segment
		(start 350.138492 -60.039758)
		(end 351.46361 -61.364876)
		(width 0.11684)
		(layer "In15.Cu")
		(net "CPU0_XTRIG_L5")
	)
	(segment
		(start 173.172628 -119.625364)
		(end 172.83303 -119.964962)
		(width 0.11684)
		(layer "In15.Cu")
		(net "CPU0_XTRIG_L5")
	)
	(segment
		(start 171.716446 -136.42086)
		(end 171.716446 -153.760932)
		(width 0.11684)
		(layer "In15.Cu")
		(net "CPU0_XTRIG_L5")
	)
	(segment
		(start 369.840764 -61.364876)
		(end 382.244092 -48.961548)
		(width 0.11684)
		(layer "In15.Cu")
		(net "CPU0_XTRIG_L5")
	)
	(segment
		(start 408.502358 -60.277756)
		(end 406.740614 -62.0395)
		(width 0.11684)
		(layer "In15.Cu")
		(net "CPU0_XTRIG_L5")
	)
	(segment
		(start 403.121622 -48.961548)
		(end 408.502358 -54.342284)
		(width 0.11684)
		(layer "In15.Cu")
		(net "CPU0_XTRIG_L5")
	)
	(segment
		(start 171.361862 -131.094226)
		(end 171.361862 -136.066276)
		(width 0.11684)
		(layer "In15.Cu")
		(net "CPU0_XTRIG_L5")
	)
	(segment
		(start 174.6377 -101.49586)
		(end 174.6377 -102.374954)
		(width 0.11684)
		(layer "In15.Cu")
		(net "CPU0_XTRIG_L5")
	)
	(segment
		(start 171.716446 -124.032518)
		(end 171.716446 -130.739642)
		(width 0.11684)
		(layer "In15.Cu")
		(net "CPU0_XTRIG_L5")
	)
	(segment
		(start 382.244092 -48.961548)
		(end 403.121622 -48.961548)
		(width 0.11684)
		(layer "In15.Cu")
		(net "CPU0_XTRIG_L5")
	)
	(segment
		(start 173.172628 -103.840026)
		(end 173.172628 -119.625364)
		(width 0.11684)
		(layer "In15.Cu")
		(net "CPU0_XTRIG_L5")
	)
	(segment
		(start 178.955446 -165.307264)
		(end 178.955446 -166.430452)
		(width 0.11684)
		(layer "In15.Cu")
		(net "CPU0_XTRIG_L5")
	)
	(segment
		(start 408.502358 -54.342284)
		(end 408.502358 -60.277756)
		(width 0.11684)
		(layer "In15.Cu")
		(net "CPU0_XTRIG_L5")
	)
	(segment
		(start 176.12106 -100.891594)
		(end 175.241966 -100.891594)
		(width 0.11684)
		(layer "In15.Cu")
		(net "CPU0_XTRIG_L5")
	)
	(segment
		(start 313.43981 -195.752466)
		(end 313.203336 -195.98894)
		(width 0.10668)
		(layer "F.Cu")
		(net "CPU0_XTRIG_L4")
	)
	(segment
		(start 283.60116 -165.37178)
		(end 293.887144 -165.37178)
		(width 0.10668)
		(layer "F.Cu")
		(net "CPU0_XTRIG_L4")
	)
	(segment
		(start 177.673 -99.894898)
		(end 177.673 -99.278948)
		(width 0.10668)
		(layer "F.Cu")
		(net "CPU0_XTRIG_L4")
	)
	(segment
		(start 293.887144 -165.37178)
		(end 313.43981 -184.924446)
		(width 0.10668)
		(layer "F.Cu")
		(net "CPU0_XTRIG_L4")
	)
	(segment
		(start 313.203336 -195.98894)
		(end 313.203336 -196.235828)
		(width 0.10668)
		(layer "F.Cu")
		(net "CPU0_XTRIG_L4")
	)
	(segment
		(start 313.43981 -184.924446)
		(end 313.43981 -195.752466)
		(width 0.10668)
		(layer "F.Cu")
		(net "CPU0_XTRIG_L4")
	)
	(segment
		(start 350.84766 -60.094876)
		(end 351.46361 -60.094876)
		(width 0.10668)
		(layer "F.Cu")
		(net "CPU0_XTRIG_L4")
	)
	(via
		(at 313.203336 -196.235828)
		(size 0.508)
		(drill 0.254)
		(layers "F.Cu" "B.Cu")
		(net "CPU0_XTRIG_L4")
	)
	(via
		(at 332.1558 -168.8084)
		(size 0.508)
		(drill 0.254)
		(layers "F.Cu" "B.Cu")
		(net "CPU0_XTRIG_L4")
	)
	(via
		(at 283.60116 -165.37178)
		(size 0.508)
		(drill 0.254)
		(layers "F.Cu" "B.Cu")
		(net "CPU0_XTRIG_L4")
	)
	(via
		(at 363.5502 -136.8552)
		(size 0.508)
		(drill 0.254)
		(layers "F.Cu" "B.Cu")
		(net "CPU0_XTRIG_L4")
	)
	(via
		(at 404.789132 -64.01054)
		(size 0.508)
		(drill 0.254)
		(layers "F.Cu" "B.Cu")
		(net "CPU0_XTRIG_L4")
	)
	(via
		(at 179.789582 -166.45255)
		(size 0.508)
		(drill 0.254)
		(layers "F.Cu" "B.Cu")
		(net "CPU0_XTRIG_L4")
	)
	(via
		(at 177.673 -99.278948)
		(size 0.508)
		(drill 0.254)
		(layers "F.Cu" "B.Cu")
		(net "CPU0_XTRIG_L4")
	)
	(via
		(at 351.46361 -60.094876)
		(size 0.508)
		(drill 0.254)
		(layers "F.Cu" "B.Cu")
		(net "CPU0_XTRIG_L4")
	)
	(segment
		(start 325.799958 -202.513946)
		(end 324.101206 -202.513946)
		(width 0.10668)
		(layer "B.Cu")
		(net "CPU0_XTRIG_L4")
	)
	(segment
		(start 318.662558 -202.511152)
		(end 317.22822 -202.511152)
		(width 0.10668)
		(layer "B.Cu")
		(net "CPU0_XTRIG_L4")
	)
	(segment
		(start 318.894714 -202.278996)
		(end 318.662558 -202.511152)
		(width 0.10668)
		(layer "B.Cu")
		(net "CPU0_XTRIG_L4")
	)
	(segment
		(start 313.089036 -196.350128)
		(end 313.203336 -196.235828)
		(width 0.10668)
		(layer "B.Cu")
		(net "CPU0_XTRIG_L4")
	)
	(segment
		(start 323.866256 -202.278996)
		(end 318.894714 -202.278996)
		(width 0.10668)
		(layer "B.Cu")
		(net "CPU0_XTRIG_L4")
	)
	(segment
		(start 317.22822 -202.511152)
		(end 313.089036 -198.371968)
		(width 0.10668)
		(layer "B.Cu")
		(net "CPU0_XTRIG_L4")
	)
	(segment
		(start 313.089036 -198.371968)
		(end 313.089036 -196.350128)
		(width 0.10668)
		(layer "B.Cu")
		(net "CPU0_XTRIG_L4")
	)
	(segment
		(start 325.799958 -203.517246)
		(end 325.799958 -202.513946)
		(width 0.10668)
		(layer "B.Cu")
		(net "CPU0_XTRIG_L4")
	)
	(segment
		(start 324.101206 -202.513946)
		(end 323.866256 -202.278996)
		(width 0.10668)
		(layer "B.Cu")
		(net "CPU0_XTRIG_L4")
	)
	(segment
		(start 281.693112 -164.981128)
		(end 283.210508 -164.981128)
		(width 0.11684)
		(layer "In6.Cu")
		(net "CPU0_XTRIG_L4")
	)
	(segment
		(start 179.789582 -166.45255)
		(end 180.466492 -167.12946)
		(width 0.11684)
		(layer "In6.Cu")
		(net "CPU0_XTRIG_L4")
	)
	(segment
		(start 207.896714 -168.804082)
		(end 214.623396 -162.0774)
		(width 0.11684)
		(layer "In6.Cu")
		(net "CPU0_XTRIG_L4")
	)
	(segment
		(start 180.466492 -167.12946)
		(end 196.899276 -167.12946)
		(width 0.11684)
		(layer "In6.Cu")
		(net "CPU0_XTRIG_L4")
	)
	(segment
		(start 331.216 -169.7482)
		(end 332.1558 -168.8084)
		(width 0.11684)
		(layer "In6.Cu")
		(net "CPU0_XTRIG_L4")
	)
	(segment
		(start 196.899276 -167.12946)
		(end 198.573898 -168.804082)
		(width 0.11684)
		(layer "In6.Cu")
		(net "CPU0_XTRIG_L4")
	)
	(segment
		(start 271.921478 -165.29939)
		(end 272.745962 -166.123874)
		(width 0.11684)
		(layer "In6.Cu")
		(net "CPU0_XTRIG_L4")
	)
	(segment
		(start 214.623396 -162.0774)
		(end 222.574104 -162.0774)
		(width 0.11684)
		(layer "In6.Cu")
		(net "CPU0_XTRIG_L4")
	)
	(segment
		(start 284.353 -164.61994)
		(end 312.886598 -164.61994)
		(width 0.11684)
		(layer "In6.Cu")
		(net "CPU0_XTRIG_L4")
	)
	(segment
		(start 318.014858 -169.7482)
		(end 331.216 -169.7482)
		(width 0.11684)
		(layer "In6.Cu")
		(net "CPU0_XTRIG_L4")
	)
	(segment
		(start 283.210508 -164.981128)
		(end 283.60116 -165.37178)
		(width 0.11684)
		(layer "In6.Cu")
		(net "CPU0_XTRIG_L4")
	)
	(segment
		(start 222.574104 -162.0774)
		(end 225.796094 -165.29939)
		(width 0.11684)
		(layer "In6.Cu")
		(net "CPU0_XTRIG_L4")
	)
	(segment
		(start 280.550366 -166.123874)
		(end 281.693112 -164.981128)
		(width 0.11684)
		(layer "In6.Cu")
		(net "CPU0_XTRIG_L4")
	)
	(segment
		(start 312.886598 -164.61994)
		(end 318.014858 -169.7482)
		(width 0.11684)
		(layer "In6.Cu")
		(net "CPU0_XTRIG_L4")
	)
	(segment
		(start 272.745962 -166.123874)
		(end 280.550366 -166.123874)
		(width 0.11684)
		(layer "In6.Cu")
		(net "CPU0_XTRIG_L4")
	)
	(segment
		(start 225.796094 -165.29939)
		(end 271.921478 -165.29939)
		(width 0.11684)
		(layer "In6.Cu")
		(net "CPU0_XTRIG_L4")
	)
	(segment
		(start 198.573898 -168.804082)
		(end 207.896714 -168.804082)
		(width 0.11684)
		(layer "In6.Cu")
		(net "CPU0_XTRIG_L4")
	)
	(segment
		(start 283.60116 -165.37178)
		(end 284.353 -164.61994)
		(width 0.11684)
		(layer "In6.Cu")
		(net "CPU0_XTRIG_L4")
	)
	(segment
		(start 410.346398 -69.725032)
		(end 410.346398 -77.964284)
		(width 0.11684)
		(layer "In11.Cu")
		(net "CPU0_XTRIG_L4")
	)
	(segment
		(start 365.07293 -136.8552)
		(end 363.5502 -136.8552)
		(width 0.11684)
		(layer "In11.Cu")
		(net "CPU0_XTRIG_L4")
	)
	(segment
		(start 406.751282 -81.5594)
		(end 406.751282 -124.922788)
		(width 0.11684)
		(layer "In11.Cu")
		(net "CPU0_XTRIG_L4")
	)
	(segment
		(start 398.14627 -133.5278)
		(end 368.40033 -133.5278)
		(width 0.11684)
		(layer "In11.Cu")
		(net "CPU0_XTRIG_L4")
	)
	(segment
		(start 406.751282 -124.922788)
		(end 398.14627 -133.5278)
		(width 0.11684)
		(layer "In11.Cu")
		(net "CPU0_XTRIG_L4")
	)
	(segment
		(start 404.789132 -64.167766)
		(end 410.346398 -69.725032)
		(width 0.11684)
		(layer "In11.Cu")
		(net "CPU0_XTRIG_L4")
	)
	(segment
		(start 368.40033 -133.5278)
		(end 365.07293 -136.8552)
		(width 0.11684)
		(layer "In11.Cu")
		(net "CPU0_XTRIG_L4")
	)
	(segment
		(start 404.789132 -64.01054)
		(end 404.789132 -64.167766)
		(width 0.11684)
		(layer "In11.Cu")
		(net "CPU0_XTRIG_L4")
	)
	(segment
		(start 410.346398 -77.964284)
		(end 406.751282 -81.5594)
		(width 0.11684)
		(layer "In11.Cu")
		(net "CPU0_XTRIG_L4")
	)
	(segment
		(start 330.39812 -167.1828)
		(end 331.483208 -167.1828)
		(width 0.11684)
		(layer "In13.Cu")
		(net "CPU0_XTRIG_L4")
	)
	(segment
		(start 358.14 -131.9276)
		(end 343.78519 -131.9276)
		(width 0.11684)
		(layer "In13.Cu")
		(net "CPU0_XTRIG_L4")
	)
	(segment
		(start 331.483208 -167.1828)
		(end 332.1558 -167.855392)
		(width 0.11684)
		(layer "In13.Cu")
		(net "CPU0_XTRIG_L4")
	)
	(segment
		(start 331.57541 -130.937)
		(end 314.198 -148.31441)
		(width 0.11684)
		(layer "In13.Cu")
		(net "CPU0_XTRIG_L4")
	)
	(segment
		(start 314.198 -163.80079)
		(end 319.40881 -169.0116)
		(width 0.11684)
		(layer "In13.Cu")
		(net "CPU0_XTRIG_L4")
	)
	(segment
		(start 319.40881 -169.0116)
		(end 328.56932 -169.0116)
		(width 0.11684)
		(layer "In13.Cu")
		(net "CPU0_XTRIG_L4")
	)
	(segment
		(start 342.79459 -130.937)
		(end 331.57541 -130.937)
		(width 0.11684)
		(layer "In13.Cu")
		(net "CPU0_XTRIG_L4")
	)
	(segment
		(start 343.78519 -131.9276)
		(end 342.79459 -130.937)
		(width 0.11684)
		(layer "In13.Cu")
		(net "CPU0_XTRIG_L4")
	)
	(segment
		(start 363.0676 -136.8552)
		(end 358.14 -131.9276)
		(width 0.11684)
		(layer "In13.Cu")
		(net "CPU0_XTRIG_L4")
	)
	(segment
		(start 332.1558 -167.855392)
		(end 332.1558 -168.8084)
		(width 0.11684)
		(layer "In13.Cu")
		(net "CPU0_XTRIG_L4")
	)
	(segment
		(start 328.56932 -169.0116)
		(end 330.39812 -167.1828)
		(width 0.11684)
		(layer "In13.Cu")
		(net "CPU0_XTRIG_L4")
	)
	(segment
		(start 363.5502 -136.8552)
		(end 363.0676 -136.8552)
		(width 0.11684)
		(layer "In13.Cu")
		(net "CPU0_XTRIG_L4")
	)
	(segment
		(start 314.198 -148.31441)
		(end 314.198 -163.80079)
		(width 0.11684)
		(layer "In13.Cu")
		(net "CPU0_XTRIG_L4")
	)
	(segment
		(start 406.299162 -63.517526)
		(end 405.282146 -63.517526)
		(width 0.11684)
		(layer "In15.Cu")
		(net "CPU0_XTRIG_L4")
	)
	(segment
		(start 175.41748 -106.280712)
		(end 173.668436 -108.029756)
		(width 0.11684)
		(layer "In15.Cu")
		(net "CPU0_XTRIG_L4")
	)
	(segment
		(start 177.673 -99.278948)
		(end 177.673 -104.025192)
		(width 0.11684)
		(layer "In15.Cu")
		(net "CPU0_XTRIG_L4")
	)
	(segment
		(start 172.146468 -124.290074)
		(end 172.146468 -131.019804)
		(width 0.11684)
		(layer "In15.Cu")
		(net "CPU0_XTRIG_L4")
	)
	(segment
		(start 351.036382 -46.59376)
		(end 351.036382 -59.667648)
		(width 0.11684)
		(layer "In15.Cu")
		(net "CPU0_XTRIG_L4")
	)
	(segment
		(start 171.818554 -131.347718)
		(end 171.818554 -135.913368)
		(width 0.11684)
		(layer "In15.Cu")
		(net "CPU0_XTRIG_L4")
	)
	(segment
		(start 353.38004 -44.250102)
		(end 351.036382 -46.59376)
		(width 0.11684)
		(layer "In15.Cu")
		(net "CPU0_XTRIG_L4")
	)
	(segment
		(start 175.92802 -104.2797)
		(end 175.41748 -104.79024)
		(width 0.11684)
		(layer "In15.Cu")
		(net "CPU0_XTRIG_L4")
	)
	(segment
		(start 409.235148 -60.58154)
		(end 406.299162 -63.517526)
		(width 0.11684)
		(layer "In15.Cu")
		(net "CPU0_XTRIG_L4")
	)
	(segment
		(start 173.286674 -123.149868)
		(end 172.146468 -124.290074)
		(width 0.11684)
		(layer "In15.Cu")
		(net "CPU0_XTRIG_L4")
	)
	(segment
		(start 173.668436 -108.029756)
		(end 173.668436 -119.83085)
		(width 0.11684)
		(layer "In15.Cu")
		(net "CPU0_XTRIG_L4")
	)
	(segment
		(start 351.036382 -59.667648)
		(end 351.46361 -60.094876)
		(width 0.11684)
		(layer "In15.Cu")
		(net "CPU0_XTRIG_L4")
	)
	(segment
		(start 173.668436 -119.83085)
		(end 173.286674 -120.212612)
		(width 0.11684)
		(layer "In15.Cu")
		(net "CPU0_XTRIG_L4")
	)
	(segment
		(start 173.286674 -120.212612)
		(end 173.286674 -123.149868)
		(width 0.11684)
		(layer "In15.Cu")
		(net "CPU0_XTRIG_L4")
	)
	(segment
		(start 171.818554 -135.913368)
		(end 172.146468 -136.241282)
		(width 0.11684)
		(layer "In15.Cu")
		(net "CPU0_XTRIG_L4")
	)
	(segment
		(start 177.673 -104.025192)
		(end 177.418492 -104.2797)
		(width 0.11684)
		(layer "In15.Cu")
		(net "CPU0_XTRIG_L4")
	)
	(segment
		(start 175.41748 -104.79024)
		(end 175.41748 -106.280712)
		(width 0.11684)
		(layer "In15.Cu")
		(net "CPU0_XTRIG_L4")
	)
	(segment
		(start 351.46361 -60.094876)
		(end 370.07419 -60.094876)
		(width 0.11684)
		(layer "In15.Cu")
		(net "CPU0_XTRIG_L4")
	)
	(segment
		(start 181.61381 -162.912044)
		(end 181.61381 -164.397944)
		(width 0.11684)
		(layer "In15.Cu")
		(net "CPU0_XTRIG_L4")
	)
	(segment
		(start 179.789582 -166.222172)
		(end 179.789582 -166.45255)
		(width 0.11684)
		(layer "In15.Cu")
		(net "CPU0_XTRIG_L4")
	)
	(segment
		(start 172.146468 -131.019804)
		(end 171.818554 -131.347718)
		(width 0.11684)
		(layer "In15.Cu")
		(net "CPU0_XTRIG_L4")
	)
	(segment
		(start 181.61381 -164.397944)
		(end 179.789582 -166.222172)
		(width 0.11684)
		(layer "In15.Cu")
		(net "CPU0_XTRIG_L4")
	)
	(segment
		(start 177.418492 -104.2797)
		(end 175.92802 -104.2797)
		(width 0.11684)
		(layer "In15.Cu")
		(net "CPU0_XTRIG_L4")
	)
	(segment
		(start 172.146468 -153.444702)
		(end 181.61381 -162.912044)
		(width 0.11684)
		(layer "In15.Cu")
		(net "CPU0_XTRIG_L4")
	)
	(segment
		(start 405.282146 -63.517526)
		(end 404.789132 -64.01054)
		(width 0.11684)
		(layer "In15.Cu")
		(net "CPU0_XTRIG_L4")
	)
	(segment
		(start 381.940308 -48.228758)
		(end 403.425406 -48.228758)
		(width 0.11684)
		(layer "In15.Cu")
		(net "CPU0_XTRIG_L4")
	)
	(segment
		(start 370.07419 -60.094876)
		(end 381.940308 -48.228758)
		(width 0.11684)
		(layer "In15.Cu")
		(net "CPU0_XTRIG_L4")
	)
	(segment
		(start 172.146468 -136.241282)
		(end 172.146468 -153.444702)
		(width 0.11684)
		(layer "In15.Cu")
		(net "CPU0_XTRIG_L4")
	)
	(segment
		(start 409.235148 -54.0385)
		(end 409.235148 -60.58154)
		(width 0.11684)
		(layer "In15.Cu")
		(net "CPU0_XTRIG_L4")
	)
	(segment
		(start 403.425406 -48.228758)
		(end 409.235148 -54.0385)
		(width 0.11684)
		(layer "In15.Cu")
		(net "CPU0_XTRIG_L4")
	)
	(segment
		(start 182.722012 -107.452922)
		(end 182.332122 -107.063032)
		(width 0.10668)
		(layer "F.Cu")
		(net "CPU0_THERMTRIP_R_N")
	)
	(via
		(at 182.332122 -107.063032)
		(size 0.4572)
		(drill 0.254)
		(layers "F.Cu" "B.Cu")
		(net "CPU0_THERMTRIP_R_N")
	)
	(via
		(at 182.245 -102.098348)
		(size 0.6604)
		(drill 0.3302)
		(layers "F.Cu" "B.Cu")
		(net "CPU0_THERMTRIP_R_N")
	)
	(segment
		(start 181.935882 -105.593388)
		(end 181.935882 -106.666792)
		(width 0.10668)
		(layer "B.Cu")
		(net "CPU0_THERMTRIP_R_N")
	)
	(segment
		(start 182.737252 -97.512886)
		(end 182.726584 -97.523554)
		(width 0.10668)
		(layer "B.Cu")
		(net "CPU0_THERMTRIP_R_N")
	)
	(segment
		(start 181.935882 -106.666792)
		(end 182.332122 -107.063032)
		(width 0.10668)
		(layer "B.Cu")
		(net "CPU0_THERMTRIP_R_N")
	)
	(segment
		(start 182.139336 -104.126538)
		(end 182.139336 -105.389934)
		(width 0.10668)
		(layer "B.Cu")
		(net "CPU0_THERMTRIP_R_N")
	)
	(segment
		(start 182.726584 -97.523554)
		(end 181.534562 -97.523554)
		(width 0.10668)
		(layer "B.Cu")
		(net "CPU0_THERMTRIP_R_N")
	)
	(segment
		(start 182.245 -98.005138)
		(end 182.726584 -97.523554)
		(width 0.10668)
		(layer "B.Cu")
		(net "CPU0_THERMTRIP_R_N")
	)
	(segment
		(start 182.245 -104.020874)
		(end 182.139336 -104.126538)
		(width 0.10668)
		(layer "B.Cu")
		(net "CPU0_THERMTRIP_R_N")
	)
	(segment
		(start 182.139336 -105.389934)
		(end 181.935882 -105.593388)
		(width 0.10668)
		(layer "B.Cu")
		(net "CPU0_THERMTRIP_R_N")
	)
	(segment
		(start 182.245 -102.098348)
		(end 182.245 -104.020874)
		(width 0.10668)
		(layer "B.Cu")
		(net "CPU0_THERMTRIP_R_N")
	)
	(segment
		(start 182.245 -102.098348)
		(end 182.245 -98.005138)
		(width 0.10668)
		(layer "B.Cu")
		(net "CPU0_THERMTRIP_R_N")
	)
	(segment
		(start 393.584684 -316.61862)
		(end 393.584684 -317.278004)
		(width 0.10668)
		(layer "F.Cu")
		(net "CPU0_THERMTRIP_N")
	)
	(segment
		(start 382.514094 -309.167784)
		(end 389.59282 -316.24651)
		(width 0.10668)
		(layer "F.Cu")
		(net "CPU0_THERMTRIP_N")
	)
	(segment
		(start 225.82759 -166.898574)
		(end 225.022664 -166.093648)
		(width 0.10668)
		(layer "F.Cu")
		(net "CPU0_THERMTRIP_N")
	)
	(segment
		(start 382.514094 -301.991522)
		(end 382.514094 -309.167784)
		(width 0.10668)
		(layer "F.Cu")
		(net "CPU0_THERMTRIP_N")
	)
	(segment
		(start 225.82759 -201.233278)
		(end 225.82759 -166.898574)
		(width 0.10668)
		(layer "F.Cu")
		(net "CPU0_THERMTRIP_N")
	)
	(segment
		(start 223.262444 -203.798424)
		(end 225.82759 -201.233278)
		(width 0.10668)
		(layer "F.Cu")
		(net "CPU0_THERMTRIP_N")
	)
	(segment
		(start 391.418318 -316.24651)
		(end 391.931652 -315.733176)
		(width 0.10668)
		(layer "F.Cu")
		(net "CPU0_THERMTRIP_N")
	)
	(segment
		(start 390.801098 -316.24651)
		(end 391.418318 -316.24651)
		(width 0.10668)
		(layer "F.Cu")
		(net "CPU0_THERMTRIP_N")
	)
	(segment
		(start 386.807964 -295.690036)
		(end 386.807964 -297.697652)
		(width 0.10668)
		(layer "F.Cu")
		(net "CPU0_THERMTRIP_N")
	)
	(segment
		(start 222.874586 -203.798424)
		(end 223.262444 -203.798424)
		(width 0.10668)
		(layer "F.Cu")
		(net "CPU0_THERMTRIP_N")
	)
	(segment
		(start 393.584684 -317.278004)
		(end 396.279878 -319.973198)
		(width 0.10668)
		(layer "F.Cu")
		(net "CPU0_THERMTRIP_N")
	)
	(segment
		(start 392.69924 -315.733176)
		(end 393.584684 -316.61862)
		(width 0.10668)
		(layer "F.Cu")
		(net "CPU0_THERMTRIP_N")
	)
	(segment
		(start 396.279878 -319.973198)
		(end 396.279878 -320.748152)
		(width 0.10668)
		(layer "F.Cu")
		(net "CPU0_THERMTRIP_N")
	)
	(segment
		(start 391.931652 -315.733176)
		(end 392.69924 -315.733176)
		(width 0.10668)
		(layer "F.Cu")
		(net "CPU0_THERMTRIP_N")
	)
	(segment
		(start 389.59282 -316.24651)
		(end 390.801098 -316.24651)
		(width 0.10668)
		(layer "F.Cu")
		(net "CPU0_THERMTRIP_N")
	)
	(segment
		(start 386.807964 -297.697652)
		(end 382.514094 -301.991522)
		(width 0.10668)
		(layer "F.Cu")
		(net "CPU0_THERMTRIP_N")
	)
	(via
		(at 222.874586 -203.798424)
		(size 0.508)
		(drill 0.254)
		(layers "F.Cu" "B.Cu")
		(net "CPU0_THERMTRIP_N")
	)
	(via
		(at 225.022664 -166.093648)
		(size 0.508)
		(drill 0.254)
		(layers "F.Cu" "B.Cu")
		(net "CPU0_THERMTRIP_N")
	)
	(via
		(at 211.637626 -95.501968)
		(size 0.508)
		(drill 0.254)
		(layers "F.Cu" "B.Cu")
		(net "CPU0_THERMTRIP_N")
	)
	(via
		(at 185.311034 -92.209112)
		(size 0.6604)
		(drill 0.3302)
		(layers "F.Cu" "B.Cu")
		(net "CPU0_THERMTRIP_N")
	)
	(via
		(at 390.801098 -316.24651)
		(size 0.508)
		(drill 0.254)
		(layers "F.Cu" "B.Cu")
		(net "CPU0_THERMTRIP_N")
	)
	(via
		(at 186.478164 -91.638628)
		(size 0.508)
		(drill 0.254)
		(layers "F.Cu" "B.Cu")
		(net "CPU0_THERMTRIP_N")
	)
	(segment
		(start 185.311034 -92.209112)
		(end 185.90768 -92.209112)
		(width 0.10668)
		(layer "B.Cu")
		(net "CPU0_THERMTRIP_N")
	)
	(segment
		(start 182.939944 -92.726256)
		(end 182.27294 -93.39326)
		(width 0.10668)
		(layer "B.Cu")
		(net "CPU0_THERMTRIP_N")
	)
	(segment
		(start 184.79389 -92.726256)
		(end 182.939944 -92.726256)
		(width 0.10668)
		(layer "B.Cu")
		(net "CPU0_THERMTRIP_N")
	)
	(segment
		(start 185.311034 -92.209112)
		(end 184.79389 -92.726256)
		(width 0.10668)
		(layer "B.Cu")
		(net "CPU0_THERMTRIP_N")
	)
	(segment
		(start 185.90768 -92.209112)
		(end 186.478164 -91.638628)
		(width 0.10668)
		(layer "B.Cu")
		(net "CPU0_THERMTRIP_N")
	)
	(segment
		(start 181.534562 -96.281748)
		(end 181.534562 -96.723454)
		(width 0.10668)
		(layer "B.Cu")
		(net "CPU0_THERMTRIP_N")
	)
	(segment
		(start 182.27294 -93.39326)
		(end 182.27294 -95.54337)
		(width 0.10668)
		(layer "B.Cu")
		(net "CPU0_THERMTRIP_N")
	)
	(segment
		(start 182.27294 -95.54337)
		(end 181.534562 -96.281748)
		(width 0.10668)
		(layer "B.Cu")
		(net "CPU0_THERMTRIP_N")
	)
	(segment
		(start 210.991958 -95.501968)
		(end 209.310986 -93.820996)
		(width 0.11684)
		(layer "In2.Cu")
		(net "CPU0_THERMTRIP_N")
	)
	(segment
		(start 252.250448 -320.699638)
		(end 252.250448 -329.39101)
		(width 0.11684)
		(layer "In2.Cu")
		(net "CPU0_THERMTRIP_N")
	)
	(segment
		(start 187.451492 -92.611956)
		(end 186.478164 -91.638628)
		(width 0.11684)
		(layer "In2.Cu")
		(net "CPU0_THERMTRIP_N")
	)
	(segment
		(start 288.078672 -369.505738)
		(end 290.715954 -372.14302)
		(width 0.11684)
		(layer "In2.Cu")
		(net "CPU0_THERMTRIP_N")
	)
	(segment
		(start 282.291028 -369.505738)
		(end 288.078672 -369.505738)
		(width 0.11684)
		(layer "In2.Cu")
		(net "CPU0_THERMTRIP_N")
	)
	(segment
		(start 253.70917 -319.240916)
		(end 252.250448 -320.699638)
		(width 0.11684)
		(layer "In2.Cu")
		(net "CPU0_THERMTRIP_N")
	)
	(segment
		(start 250.095004 -331.546454)
		(end 250.095004 -342.619076)
		(width 0.11684)
		(layer "In2.Cu")
		(net "CPU0_THERMTRIP_N")
	)
	(segment
		(start 382.973072 -321.690238)
		(end 388.4168 -316.24651)
		(width 0.11684)
		(layer "In2.Cu")
		(net "CPU0_THERMTRIP_N")
	)
	(segment
		(start 219.248482 -204.263498)
		(end 218.86926 -204.64272)
		(width 0.11684)
		(layer "In2.Cu")
		(net "CPU0_THERMTRIP_N")
	)
	(segment
		(start 218.86926 -205.756002)
		(end 221.231968 -208.11871)
		(width 0.11684)
		(layer "In2.Cu")
		(net "CPU0_THERMTRIP_N")
	)
	(segment
		(start 218.86926 -204.64272)
		(end 218.86926 -205.756002)
		(width 0.11684)
		(layer "In2.Cu")
		(net "CPU0_THERMTRIP_N")
	)
	(segment
		(start 222.874586 -203.798424)
		(end 222.409512 -204.263498)
		(width 0.11684)
		(layer "In2.Cu")
		(net "CPU0_THERMTRIP_N")
	)
	(segment
		(start 221.231968 -208.11871)
		(end 221.231968 -244.49278)
		(width 0.11684)
		(layer "In2.Cu")
		(net "CPU0_THERMTRIP_N")
	)
	(segment
		(start 256.527808 -349.05188)
		(end 256.528062 -349.05188)
		(width 0.11684)
		(layer "In2.Cu")
		(net "CPU0_THERMTRIP_N")
	)
	(segment
		(start 203.313538 -93.324934)
		(end 200.564242 -93.324934)
		(width 0.11684)
		(layer "In2.Cu")
		(net "CPU0_THERMTRIP_N")
	)
	(segment
		(start 290.715954 -372.14302)
		(end 322.39077 -372.14302)
		(width 0.11684)
		(layer "In2.Cu")
		(net "CPU0_THERMTRIP_N")
	)
	(segment
		(start 250.095004 -342.619076)
		(end 256.527808 -349.05188)
		(width 0.11684)
		(layer "In2.Cu")
		(net "CPU0_THERMTRIP_N")
	)
	(segment
		(start 222.409512 -204.263498)
		(end 219.248482 -204.263498)
		(width 0.11684)
		(layer "In2.Cu")
		(net "CPU0_THERMTRIP_N")
	)
	(segment
		(start 209.310986 -93.820996)
		(end 203.8096 -93.820996)
		(width 0.11684)
		(layer "In2.Cu")
		(net "CPU0_THERMTRIP_N")
	)
	(segment
		(start 252.250448 -329.39101)
		(end 250.095004 -331.546454)
		(width 0.11684)
		(layer "In2.Cu")
		(net "CPU0_THERMTRIP_N")
	)
	(segment
		(start 382.973072 -335.736692)
		(end 382.973072 -321.690238)
		(width 0.11684)
		(layer "In2.Cu")
		(net "CPU0_THERMTRIP_N")
	)
	(segment
		(start 253.70917 -269.56385)
		(end 253.70917 -319.240916)
		(width 0.11684)
		(layer "In2.Cu")
		(net "CPU0_THERMTRIP_N")
	)
	(segment
		(start 351.747582 -366.962182)
		(end 382.973072 -335.736692)
		(width 0.11684)
		(layer "In2.Cu")
		(net "CPU0_THERMTRIP_N")
	)
	(segment
		(start 388.4168 -316.24651)
		(end 390.801098 -316.24651)
		(width 0.11684)
		(layer "In2.Cu")
		(net "CPU0_THERMTRIP_N")
	)
	(segment
		(start 271.892268 -364.416086)
		(end 277.201376 -364.416086)
		(width 0.11684)
		(layer "In2.Cu")
		(net "CPU0_THERMTRIP_N")
	)
	(segment
		(start 211.637626 -95.501968)
		(end 210.991958 -95.501968)
		(width 0.11684)
		(layer "In2.Cu")
		(net "CPU0_THERMTRIP_N")
	)
	(segment
		(start 200.564242 -93.324934)
		(end 199.139556 -94.74962)
		(width 0.11684)
		(layer "In2.Cu")
		(net "CPU0_THERMTRIP_N")
	)
	(segment
		(start 203.8096 -93.820996)
		(end 203.313538 -93.324934)
		(width 0.11684)
		(layer "In2.Cu")
		(net "CPU0_THERMTRIP_N")
	)
	(segment
		(start 253.128018 -266.642596)
		(end 253.70917 -269.56385)
		(width 0.11684)
		(layer "In2.Cu")
		(net "CPU0_THERMTRIP_N")
	)
	(segment
		(start 199.139556 -94.74962)
		(end 196.824092 -94.74962)
		(width 0.11684)
		(layer "In2.Cu")
		(net "CPU0_THERMTRIP_N")
	)
	(segment
		(start 322.39077 -372.14302)
		(end 351.747582 -366.962182)
		(width 0.11684)
		(layer "In2.Cu")
		(net "CPU0_THERMTRIP_N")
	)
	(segment
		(start 241.935508 -255.450086)
		(end 253.128018 -266.642596)
		(width 0.11684)
		(layer "In2.Cu")
		(net "CPU0_THERMTRIP_N")
	)
	(segment
		(start 196.824092 -94.74962)
		(end 194.686428 -92.611956)
		(width 0.11684)
		(layer "In2.Cu")
		(net "CPU0_THERMTRIP_N")
	)
	(segment
		(start 194.686428 -92.611956)
		(end 187.451492 -92.611956)
		(width 0.11684)
		(layer "In2.Cu")
		(net "CPU0_THERMTRIP_N")
	)
	(segment
		(start 277.201376 -364.416086)
		(end 282.291028 -369.505738)
		(width 0.11684)
		(layer "In2.Cu")
		(net "CPU0_THERMTRIP_N")
	)
	(segment
		(start 221.231968 -244.49278)
		(end 232.189274 -255.450086)
		(width 0.11684)
		(layer "In2.Cu")
		(net "CPU0_THERMTRIP_N")
	)
	(segment
		(start 256.528062 -349.05188)
		(end 271.892268 -364.416086)
		(width 0.11684)
		(layer "In2.Cu")
		(net "CPU0_THERMTRIP_N")
	)
	(segment
		(start 232.189274 -255.450086)
		(end 241.935508 -255.450086)
		(width 0.11684)
		(layer "In2.Cu")
		(net "CPU0_THERMTRIP_N")
	)
	(segment
		(start 213.354412 -96.70669)
		(end 216.141554 -96.70669)
		(width 0.11684)
		(layer "In4.Cu")
		(net "CPU0_THERMTRIP_N")
	)
	(segment
		(start 212.14969 -95.501968)
		(end 213.354412 -96.70669)
		(width 0.11684)
		(layer "In4.Cu")
		(net "CPU0_THERMTRIP_N")
	)
	(segment
		(start 223.592644 -104.15778)
		(end 223.592644 -163.857178)
		(width 0.11684)
		(layer "In4.Cu")
		(net "CPU0_THERMTRIP_N")
	)
	(segment
		(start 211.637626 -95.501968)
		(end 212.14969 -95.501968)
		(width 0.11684)
		(layer "In4.Cu")
		(net "CPU0_THERMTRIP_N")
	)
	(segment
		(start 225.022664 -165.287198)
		(end 225.022664 -166.093648)
		(width 0.11684)
		(layer "In4.Cu")
		(net "CPU0_THERMTRIP_N")
	)
	(segment
		(start 223.592644 -163.857178)
		(end 225.022664 -165.287198)
		(width 0.11684)
		(layer "In4.Cu")
		(net "CPU0_THERMTRIP_N")
	)
	(segment
		(start 216.141554 -96.70669)
		(end 223.592644 -104.15778)
		(width 0.11684)
		(layer "In4.Cu")
		(net "CPU0_THERMTRIP_N")
	)
	(segment
		(start 188.322204 -120.252744)
		(end 188.712094 -120.642634)
		(width 0.10668)
		(layer "F.Cu")
		(net "CPU0_SPD_HOST_CTRL_R1_N")
	)
	(via
		(at 188.712094 -120.642634)
		(size 0.4572)
		(drill 0.254)
		(layers "F.Cu" "B.Cu")
		(net "CPU0_SPD_HOST_CTRL_R1_N")
	)
	(via
		(at 190.49746 -125.16485)
		(size 0.6604)
		(drill 0.3302)
		(layers "F.Cu" "B.Cu")
		(net "CPU0_SPD_HOST_CTRL_R1_N")
	)
	(segment
		(start 189.108334 -122.449082)
		(end 189.299088 -122.639836)
		(width 0.10668)
		(layer "B.Cu")
		(net "CPU0_SPD_HOST_CTRL_R1_N")
	)
	(segment
		(start 190.716154 -126.17704)
		(end 191.000888 -126.461774)
		(width 0.10668)
		(layer "B.Cu")
		(net "CPU0_SPD_HOST_CTRL_R1_N")
	)
	(segment
		(start 189.9158 -123.207018)
		(end 190.291974 -123.583192)
		(width 0.10668)
		(layer "B.Cu")
		(net "CPU0_SPD_HOST_CTRL_R1_N")
	)
	(segment
		(start 188.868812 -121.838974)
		(end 189.108334 -122.078496)
		(width 0.10668)
		(layer "B.Cu")
		(net "CPU0_SPD_HOST_CTRL_R1_N")
	)
	(segment
		(start 190.49746 -125.16485)
		(end 190.49746 -125.480064)
		(width 0.10668)
		(layer "B.Cu")
		(net "CPU0_SPD_HOST_CTRL_R1_N")
	)
	(segment
		(start 188.547756 -121.838974)
		(end 188.868812 -121.838974)
		(width 0.10668)
		(layer "B.Cu")
		(net "CPU0_SPD_HOST_CTRL_R1_N")
	)
	(segment
		(start 188.315854 -121.607072)
		(end 188.547756 -121.838974)
		(width 0.10668)
		(layer "B.Cu")
		(net "CPU0_SPD_HOST_CTRL_R1_N")
	)
	(segment
		(start 190.49746 -125.480064)
		(end 190.716154 -125.698758)
		(width 0.10668)
		(layer "B.Cu")
		(net "CPU0_SPD_HOST_CTRL_R1_N")
	)
	(segment
		(start 190.291974 -123.583192)
		(end 190.291974 -124.959364)
		(width 0.10668)
		(layer "B.Cu")
		(net "CPU0_SPD_HOST_CTRL_R1_N")
	)
	(segment
		(start 189.733174 -122.639836)
		(end 189.9158 -122.822462)
		(width 0.10668)
		(layer "B.Cu")
		(net "CPU0_SPD_HOST_CTRL_R1_N")
	)
	(segment
		(start 190.291974 -124.959364)
		(end 190.49746 -125.16485)
		(width 0.10668)
		(layer "B.Cu")
		(net "CPU0_SPD_HOST_CTRL_R1_N")
	)
	(segment
		(start 190.716154 -125.698758)
		(end 190.716154 -126.17704)
		(width 0.10668)
		(layer "B.Cu")
		(net "CPU0_SPD_HOST_CTRL_R1_N")
	)
	(segment
		(start 189.108334 -122.078496)
		(end 189.108334 -122.449082)
		(width 0.10668)
		(layer "B.Cu")
		(net "CPU0_SPD_HOST_CTRL_R1_N")
	)
	(segment
		(start 189.9158 -122.822462)
		(end 189.9158 -123.207018)
		(width 0.10668)
		(layer "B.Cu")
		(net "CPU0_SPD_HOST_CTRL_R1_N")
	)
	(segment
		(start 188.712094 -120.642634)
		(end 188.712094 -120.84431)
		(width 0.10668)
		(layer "B.Cu")
		(net "CPU0_SPD_HOST_CTRL_R1_N")
	)
	(segment
		(start 188.712094 -120.84431)
		(end 188.315854 -121.24055)
		(width 0.10668)
		(layer "B.Cu")
		(net "CPU0_SPD_HOST_CTRL_R1_N")
	)
	(segment
		(start 188.315854 -121.24055)
		(end 188.315854 -121.607072)
		(width 0.10668)
		(layer "B.Cu")
		(net "CPU0_SPD_HOST_CTRL_R1_N")
	)
	(segment
		(start 189.299088 -122.639836)
		(end 189.733174 -122.639836)
		(width 0.10668)
		(layer "B.Cu")
		(net "CPU0_SPD_HOST_CTRL_R1_N")
	)
	(segment
		(start 361.42803 -292.450012)
		(end 361.894882 -292.71595)
		(width 0.10668)
		(layer "F.Cu")
		(net "CPU0_SPD_HOST_CTRL_N")
	)
	(via
		(at 361.894882 -292.71595)
		(size 0.4064)
		(drill 0.2032)
		(layers "F.Cu" "B.Cu")
		(net "CPU0_SPD_HOST_CTRL_N")
	)
	(via
		(at 404.093934 -332.556104)
		(size 0.508)
		(drill 0.254)
		(layers "F.Cu" "B.Cu")
		(net "CPU0_SPD_HOST_CTRL_N")
	)
	(via
		(at 190.159894 -131.33324)
		(size 0.508)
		(drill 0.254)
		(layers "F.Cu" "B.Cu")
		(net "CPU0_SPD_HOST_CTRL_N")
	)
	(via
		(at 215.24849 -141.095984)
		(size 0.508)
		(drill 0.254)
		(layers "F.Cu" "B.Cu")
		(net "CPU0_SPD_HOST_CTRL_N")
	)
	(segment
		(start 396.735554 -334.01635)
		(end 390.917684 -334.01635)
		(width 0.10668)
		(layer "B.Cu")
		(net "CPU0_SPD_HOST_CTRL_N")
	)
	(segment
		(start 404.584408 -332.06563)
		(end 404.584408 -331.249782)
		(width 0.10668)
		(layer "B.Cu")
		(net "CPU0_SPD_HOST_CTRL_N")
	)
	(segment
		(start 362.401358 -294.193214)
		(end 362.774738 -293.819834)
		(width 0.10668)
		(layer "B.Cu")
		(net "CPU0_SPD_HOST_CTRL_N")
	)
	(segment
		(start 191.556386 -130.968496)
		(end 191.683386 -130.841496)
		(width 0.10668)
		(layer "B.Cu")
		(net "CPU0_SPD_HOST_CTRL_N")
	)
	(segment
		(start 400.074892 -334.01635)
		(end 397.527018 -334.01635)
		(width 0.10668)
		(layer "B.Cu")
		(net "CPU0_SPD_HOST_CTRL_N")
	)
	(segment
		(start 191.683386 -130.841496)
		(end 191.683386 -130.132328)
		(width 0.10668)
		(layer "B.Cu")
		(net "CPU0_SPD_HOST_CTRL_N")
	)
	(segment
		(start 362.401358 -294.554656)
		(end 362.401358 -294.193214)
		(width 0.10668)
		(layer "B.Cu")
		(net "CPU0_SPD_HOST_CTRL_N")
	)
	(segment
		(start 404.093934 -332.556104)
		(end 403.713188 -332.93685)
		(width 0.10668)
		(layer "B.Cu")
		(net "CPU0_SPD_HOST_CTRL_N")
	)
	(segment
		(start 362.788454 -294.941752)
		(end 362.401358 -294.554656)
		(width 0.10668)
		(layer "B.Cu")
		(net "CPU0_SPD_HOST_CTRL_N")
	)
	(segment
		(start 362.774738 -293.819834)
		(end 362.774738 -293.351712)
		(width 0.10668)
		(layer "B.Cu")
		(net "CPU0_SPD_HOST_CTRL_N")
	)
	(segment
		(start 191.683386 -130.132328)
		(end 190.59906 -129.048002)
		(width 0.10668)
		(layer "B.Cu")
		(net "CPU0_SPD_HOST_CTRL_N")
	)
	(segment
		(start 397.526764 -334.016604)
		(end 396.735808 -334.016604)
		(width 0.10668)
		(layer "B.Cu")
		(net "CPU0_SPD_HOST_CTRL_N")
	)
	(segment
		(start 190.159894 -131.33324)
		(end 190.467742 -131.33324)
		(width 0.10668)
		(layer "B.Cu")
		(net "CPU0_SPD_HOST_CTRL_N")
	)
	(segment
		(start 371.636798 -312.937906)
		(end 362.788454 -304.089562)
		(width 0.10668)
		(layer "B.Cu")
		(net "CPU0_SPD_HOST_CTRL_N")
	)
	(segment
		(start 397.527018 -334.01635)
		(end 397.526764 -334.016604)
		(width 0.10668)
		(layer "B.Cu")
		(net "CPU0_SPD_HOST_CTRL_N")
	)
	(segment
		(start 190.467742 -131.33324)
		(end 190.832486 -130.968496)
		(width 0.10668)
		(layer "B.Cu")
		(net "CPU0_SPD_HOST_CTRL_N")
	)
	(segment
		(start 390.917684 -334.01635)
		(end 371.636798 -314.735464)
		(width 0.10668)
		(layer "B.Cu")
		(net "CPU0_SPD_HOST_CTRL_N")
	)
	(segment
		(start 362.138976 -292.71595)
		(end 361.894882 -292.71595)
		(width 0.10668)
		(layer "B.Cu")
		(net "CPU0_SPD_HOST_CTRL_N")
	)
	(segment
		(start 362.774738 -293.351712)
		(end 362.138976 -292.71595)
		(width 0.10668)
		(layer "B.Cu")
		(net "CPU0_SPD_HOST_CTRL_N")
	)
	(segment
		(start 396.735808 -334.016604)
		(end 396.735554 -334.01635)
		(width 0.10668)
		(layer "B.Cu")
		(net "CPU0_SPD_HOST_CTRL_N")
	)
	(segment
		(start 404.093934 -332.556104)
		(end 404.584408 -332.06563)
		(width 0.10668)
		(layer "B.Cu")
		(net "CPU0_SPD_HOST_CTRL_N")
	)
	(segment
		(start 403.713188 -332.93685)
		(end 401.154392 -332.93685)
		(width 0.10668)
		(layer "B.Cu")
		(net "CPU0_SPD_HOST_CTRL_N")
	)
	(segment
		(start 371.636798 -314.735464)
		(end 371.636798 -312.937906)
		(width 0.10668)
		(layer "B.Cu")
		(net "CPU0_SPD_HOST_CTRL_N")
	)
	(segment
		(start 190.832486 -130.968496)
		(end 191.556386 -130.968496)
		(width 0.10668)
		(layer "B.Cu")
		(net "CPU0_SPD_HOST_CTRL_N")
	)
	(segment
		(start 362.788454 -304.089562)
		(end 362.788454 -294.941752)
		(width 0.10668)
		(layer "B.Cu")
		(net "CPU0_SPD_HOST_CTRL_N")
	)
	(segment
		(start 190.59906 -127.663702)
		(end 191.000888 -127.261874)
		(width 0.10668)
		(layer "B.Cu")
		(net "CPU0_SPD_HOST_CTRL_N")
	)
	(segment
		(start 401.154392 -332.93685)
		(end 400.074892 -334.01635)
		(width 0.10668)
		(layer "B.Cu")
		(net "CPU0_SPD_HOST_CTRL_N")
	)
	(segment
		(start 190.59906 -129.048002)
		(end 190.59906 -127.663702)
		(width 0.10668)
		(layer "B.Cu")
		(net "CPU0_SPD_HOST_CTRL_N")
	)
	(segment
		(start 343.361518 -126.65456)
		(end 322.689728 -126.65456)
		(width 0.11684)
		(layer "In6.Cu")
		(net "CPU0_SPD_HOST_CTRL_N")
	)
	(segment
		(start 250.787154 -151.757888)
		(end 244.445282 -145.416016)
		(width 0.11684)
		(layer "In6.Cu")
		(net "CPU0_SPD_HOST_CTRL_N")
	)
	(segment
		(start 239.812322 -140.917422)
		(end 215.427052 -140.917422)
		(width 0.11684)
		(layer "In6.Cu")
		(net "CPU0_SPD_HOST_CTRL_N")
	)
	(segment
		(start 244.445282 -145.416016)
		(end 244.310916 -145.416016)
		(width 0.11684)
		(layer "In6.Cu")
		(net "CPU0_SPD_HOST_CTRL_N")
	)
	(segment
		(start 441.564268 -160.993328)
		(end 439.396632 -160.993328)
		(width 0.11684)
		(layer "In6.Cu")
		(net "CPU0_SPD_HOST_CTRL_N")
	)
	(segment
		(start 432.422046 -154.018742)
		(end 432.422046 -146.870166)
		(width 0.11684)
		(layer "In6.Cu")
		(net "CPU0_SPD_HOST_CTRL_N")
	)
	(segment
		(start 360.600244 -130.30454)
		(end 359.367836 -131.536948)
		(width 0.11684)
		(layer "In6.Cu")
		(net "CPU0_SPD_HOST_CTRL_N")
	)
	(segment
		(start 413.218884 -327.543668)
		(end 454.659746 -327.543668)
		(width 0.11684)
		(layer "In6.Cu")
		(net "CPU0_SPD_HOST_CTRL_N")
	)
	(segment
		(start 461.656176 -320.547238)
		(end 461.656176 -188.146436)
		(width 0.11684)
		(layer "In6.Cu")
		(net "CPU0_SPD_HOST_CTRL_N")
	)
	(segment
		(start 415.85642 -130.30454)
		(end 360.600244 -130.30454)
		(width 0.11684)
		(layer "In6.Cu")
		(net "CPU0_SPD_HOST_CTRL_N")
	)
	(segment
		(start 244.310916 -145.416016)
		(end 239.812322 -140.917422)
		(width 0.11684)
		(layer "In6.Cu")
		(net "CPU0_SPD_HOST_CTRL_N")
	)
	(segment
		(start 461.656176 -188.146436)
		(end 450.578982 -177.069242)
		(width 0.11684)
		(layer "In6.Cu")
		(net "CPU0_SPD_HOST_CTRL_N")
	)
	(segment
		(start 454.659746 -327.543668)
		(end 461.656176 -320.547238)
		(width 0.11684)
		(layer "In6.Cu")
		(net "CPU0_SPD_HOST_CTRL_N")
	)
	(segment
		(start 322.689728 -126.65456)
		(end 319.666366 -129.677922)
		(width 0.11684)
		(layer "In6.Cu")
		(net "CPU0_SPD_HOST_CTRL_N")
	)
	(segment
		(start 450.578982 -170.008042)
		(end 441.564268 -160.993328)
		(width 0.11684)
		(layer "In6.Cu")
		(net "CPU0_SPD_HOST_CTRL_N")
	)
	(segment
		(start 409.24988 -331.512672)
		(end 413.218884 -327.543668)
		(width 0.11684)
		(layer "In6.Cu")
		(net "CPU0_SPD_HOST_CTRL_N")
	)
	(segment
		(start 407.795222 -331.325728)
		(end 407.982166 -331.512672)
		(width 0.11684)
		(layer "In6.Cu")
		(net "CPU0_SPD_HOST_CTRL_N")
	)
	(segment
		(start 215.427052 -140.917422)
		(end 215.24849 -141.095984)
		(width 0.11684)
		(layer "In6.Cu")
		(net "CPU0_SPD_HOST_CTRL_N")
	)
	(segment
		(start 359.367836 -131.536948)
		(end 348.243906 -131.536948)
		(width 0.11684)
		(layer "In6.Cu")
		(net "CPU0_SPD_HOST_CTRL_N")
	)
	(segment
		(start 272.971768 -141.973808)
		(end 263.187688 -151.757888)
		(width 0.11684)
		(layer "In6.Cu")
		(net "CPU0_SPD_HOST_CTRL_N")
	)
	(segment
		(start 404.093934 -332.556104)
		(end 405.32431 -331.325728)
		(width 0.11684)
		(layer "In6.Cu")
		(net "CPU0_SPD_HOST_CTRL_N")
	)
	(segment
		(start 407.982166 -331.512672)
		(end 409.24988 -331.512672)
		(width 0.11684)
		(layer "In6.Cu")
		(net "CPU0_SPD_HOST_CTRL_N")
	)
	(segment
		(start 405.32431 -331.325728)
		(end 407.795222 -331.325728)
		(width 0.11684)
		(layer "In6.Cu")
		(net "CPU0_SPD_HOST_CTRL_N")
	)
	(segment
		(start 432.422046 -146.870166)
		(end 415.85642 -130.30454)
		(width 0.11684)
		(layer "In6.Cu")
		(net "CPU0_SPD_HOST_CTRL_N")
	)
	(segment
		(start 291.563552 -141.973808)
		(end 272.971768 -141.973808)
		(width 0.11684)
		(layer "In6.Cu")
		(net "CPU0_SPD_HOST_CTRL_N")
	)
	(segment
		(start 439.396632 -160.993328)
		(end 432.422046 -154.018742)
		(width 0.11684)
		(layer "In6.Cu")
		(net "CPU0_SPD_HOST_CTRL_N")
	)
	(segment
		(start 303.859438 -129.677922)
		(end 291.563552 -141.973808)
		(width 0.11684)
		(layer "In6.Cu")
		(net "CPU0_SPD_HOST_CTRL_N")
	)
	(segment
		(start 263.187688 -151.757888)
		(end 250.787154 -151.757888)
		(width 0.11684)
		(layer "In6.Cu")
		(net "CPU0_SPD_HOST_CTRL_N")
	)
	(segment
		(start 319.666366 -129.677922)
		(end 303.859438 -129.677922)
		(width 0.11684)
		(layer "In6.Cu")
		(net "CPU0_SPD_HOST_CTRL_N")
	)
	(segment
		(start 348.243906 -131.536948)
		(end 343.361518 -126.65456)
		(width 0.11684)
		(layer "In6.Cu")
		(net "CPU0_SPD_HOST_CTRL_N")
	)
	(segment
		(start 450.578982 -177.069242)
		(end 450.578982 -170.008042)
		(width 0.11684)
		(layer "In6.Cu")
		(net "CPU0_SPD_HOST_CTRL_N")
	)
	(segment
		(start 195.216526 -134.246112)
		(end 194.416934 -133.44652)
		(width 0.11684)
		(layer "In13.Cu")
		(net "CPU0_SPD_HOST_CTRL_N")
	)
	(segment
		(start 195.216526 -135.53948)
		(end 195.216526 -134.246112)
		(width 0.11684)
		(layer "In13.Cu")
		(net "CPU0_SPD_HOST_CTRL_N")
	)
	(segment
		(start 203.258928 -135.653272)
		(end 196.979794 -135.653272)
		(width 0.11684)
		(layer "In13.Cu")
		(net "CPU0_SPD_HOST_CTRL_N")
	)
	(segment
		(start 190.693802 -132.984748)
		(end 190.693802 -131.867148)
		(width 0.11684)
		(layer "In13.Cu")
		(net "CPU0_SPD_HOST_CTRL_N")
	)
	(segment
		(start 194.416934 -133.44652)
		(end 191.155574 -133.44652)
		(width 0.11684)
		(layer "In13.Cu")
		(net "CPU0_SPD_HOST_CTRL_N")
	)
	(segment
		(start 190.693802 -131.867148)
		(end 190.159894 -131.33324)
		(width 0.11684)
		(layer "In13.Cu")
		(net "CPU0_SPD_HOST_CTRL_N")
	)
	(segment
		(start 215.132158 -141.095984)
		(end 210.746594 -136.71042)
		(width 0.11684)
		(layer "In13.Cu")
		(net "CPU0_SPD_HOST_CTRL_N")
	)
	(segment
		(start 196.979794 -135.653272)
		(end 196.802248 -135.830818)
		(width 0.11684)
		(layer "In13.Cu")
		(net "CPU0_SPD_HOST_CTRL_N")
	)
	(segment
		(start 195.507864 -135.830818)
		(end 195.216526 -135.53948)
		(width 0.11684)
		(layer "In13.Cu")
		(net "CPU0_SPD_HOST_CTRL_N")
	)
	(segment
		(start 196.802248 -135.830818)
		(end 195.507864 -135.830818)
		(width 0.11684)
		(layer "In13.Cu")
		(net "CPU0_SPD_HOST_CTRL_N")
	)
	(segment
		(start 215.24849 -141.095984)
		(end 215.132158 -141.095984)
		(width 0.11684)
		(layer "In13.Cu")
		(net "CPU0_SPD_HOST_CTRL_N")
	)
	(segment
		(start 210.746594 -136.71042)
		(end 204.316076 -136.71042)
		(width 0.11684)
		(layer "In13.Cu")
		(net "CPU0_SPD_HOST_CTRL_N")
	)
	(segment
		(start 191.155574 -133.44652)
		(end 190.693802 -132.984748)
		(width 0.11684)
		(layer "In13.Cu")
		(net "CPU0_SPD_HOST_CTRL_N")
	)
	(segment
		(start 204.316076 -136.71042)
		(end 203.258928 -135.653272)
		(width 0.11684)
		(layer "In13.Cu")
		(net "CPU0_SPD_HOST_CTRL_N")
	)
	(segment
		(start 383.147316 -299.244766)
		(end 386.338064 -296.054018)
		(width 0.10668)
		(layer "F.Cu")
		(net "CPU0_SP5R4")
	)
	(segment
		(start 392.17092 -319.611248)
		(end 392.312652 -319.611248)
		(width 0.10668)
		(layer "F.Cu")
		(net "CPU0_SP5R4")
	)
	(segment
		(start 193.02222 -99.260914)
		(end 193.651632 -99.890326)
		(width 0.10668)
		(layer "F.Cu")
		(net "CPU0_SP5R4")
	)
	(segment
		(start 381.741934 -309.47614)
		(end 381.741934 -301.065438)
		(width 0.10668)
		(layer "F.Cu")
		(net "CPU0_SP5R4")
	)
	(segment
		(start 381.741934 -301.065438)
		(end 383.147316 -299.660056)
		(width 0.10668)
		(layer "F.Cu")
		(net "CPU0_SP5R4")
	)
	(segment
		(start 392.312652 -319.611248)
		(end 393.087606 -318.836294)
		(width 0.10668)
		(layer "F.Cu")
		(net "CPU0_SP5R4")
	)
	(segment
		(start 192.913 -99.260914)
		(end 193.02222 -99.260914)
		(width 0.10668)
		(layer "F.Cu")
		(net "CPU0_SP5R4")
	)
	(segment
		(start 393.087606 -318.041528)
		(end 392.583416 -317.537338)
		(width 0.10668)
		(layer "F.Cu")
		(net "CPU0_SP5R4")
	)
	(segment
		(start 392.583416 -317.537338)
		(end 389.803132 -317.537338)
		(width 0.10668)
		(layer "F.Cu")
		(net "CPU0_SP5R4")
	)
	(segment
		(start 391.881868 -321.545712)
		(end 391.881868 -319.9003)
		(width 0.10668)
		(layer "F.Cu")
		(net "CPU0_SP5R4")
	)
	(segment
		(start 193.924428 -99.890326)
		(end 193.929 -99.894898)
		(width 0.10668)
		(layer "F.Cu")
		(net "CPU0_SP5R4")
	)
	(segment
		(start 393.087606 -318.836294)
		(end 393.087606 -318.041528)
		(width 0.10668)
		(layer "F.Cu")
		(net "CPU0_SP5R4")
	)
	(segment
		(start 392.963908 -322.627752)
		(end 391.881868 -321.545712)
		(width 0.10668)
		(layer "F.Cu")
		(net "CPU0_SP5R4")
	)
	(segment
		(start 386.338064 -296.054018)
		(end 386.338064 -294.88003)
		(width 0.10668)
		(layer "F.Cu")
		(net "CPU0_SP5R4")
	)
	(segment
		(start 383.147316 -299.660056)
		(end 383.147316 -299.244766)
		(width 0.10668)
		(layer "F.Cu")
		(net "CPU0_SP5R4")
	)
	(segment
		(start 389.803132 -317.537338)
		(end 381.741934 -309.47614)
		(width 0.10668)
		(layer "F.Cu")
		(net "CPU0_SP5R4")
	)
	(segment
		(start 391.881868 -319.9003)
		(end 392.17092 -319.611248)
		(width 0.10668)
		(layer "F.Cu")
		(net "CPU0_SP5R4")
	)
	(segment
		(start 193.651632 -99.890326)
		(end 193.924428 -99.890326)
		(width 0.10668)
		(layer "F.Cu")
		(net "CPU0_SP5R4")
	)
	(via
		(at 192.913 -99.260914)
		(size 0.508)
		(drill 0.254)
		(layers "F.Cu" "B.Cu")
		(net "CPU0_SP5R4")
	)
	(via
		(at 391.881868 -321.545712)
		(size 0.762)
		(drill 0.381)
		(layers "F.Cu" "B.Cu")
		(net "CPU0_SP5R4")
	)
	(via
		(at 287.61436 -119.812308)
		(size 0.508)
		(drill 0.254)
		(layers "F.Cu" "B.Cu")
		(net "CPU0_SP5R4")
	)
	(via
		(at 392.17092 -319.611248)
		(size 0.508)
		(drill 0.254)
		(layers "F.Cu" "B.Cu")
		(net "CPU0_SP5R4")
	)
	(via
		(at 266.06881 -112.878616)
		(size 0.508)
		(drill 0.254)
		(layers "F.Cu" "B.Cu")
		(net "CPU0_SP5R4")
	)
	(segment
		(start 288.163 -119.263668)
		(end 288.163 -118.455948)
		(width 0.10668)
		(layer "B.Cu")
		(net "CPU0_SP5R4")
	)
	(segment
		(start 282.194 -115.407948)
		(end 280.67 -113.883948)
		(width 0.10668)
		(layer "B.Cu")
		(net "CPU0_SP5R4")
	)
	(segment
		(start 288.163 -118.455948)
		(end 285.115 -115.407948)
		(width 0.10668)
		(layer "B.Cu")
		(net "CPU0_SP5R4")
	)
	(segment
		(start 287.61436 -119.812308)
		(end 288.163 -119.263668)
		(width 0.10668)
		(layer "B.Cu")
		(net "CPU0_SP5R4")
	)
	(segment
		(start 271.465548 -113.883948)
		(end 270.39443 -114.955066)
		(width 0.10668)
		(layer "B.Cu")
		(net "CPU0_SP5R4")
	)
	(segment
		(start 268.14526 -114.955066)
		(end 266.06881 -112.878616)
		(width 0.10668)
		(layer "B.Cu")
		(net "CPU0_SP5R4")
	)
	(segment
		(start 280.67 -113.883948)
		(end 271.465548 -113.883948)
		(width 0.10668)
		(layer "B.Cu")
		(net "CPU0_SP5R4")
	)
	(segment
		(start 270.39443 -114.955066)
		(end 268.14526 -114.955066)
		(width 0.10668)
		(layer "B.Cu")
		(net "CPU0_SP5R4")
	)
	(segment
		(start 285.115 -115.407948)
		(end 282.194 -115.407948)
		(width 0.10668)
		(layer "B.Cu")
		(net "CPU0_SP5R4")
	)
	(segment
		(start 288.669984 -118.756684)
		(end 296.165016 -118.756684)
		(width 0.11684)
		(layer "In2.Cu")
		(net "CPU0_SP5R4")
	)
	(segment
		(start 344.10396 -126.6698)
		(end 348.280228 -130.846068)
		(width 0.11684)
		(layer "In2.Cu")
		(net "CPU0_SP5R4")
	)
	(segment
		(start 408.890724 -323.916802)
		(end 393.617704 -323.916802)
		(width 0.11684)
		(layer "In2.Cu")
		(net "CPU0_SP5R4")
	)
	(segment
		(start 203.436982 -99.427284)
		(end 202.997816 -98.988118)
		(width 0.11684)
		(layer "In2.Cu")
		(net "CPU0_SP5R4")
	)
	(segment
		(start 215.205056 -103.11384)
		(end 213.186772 -101.095556)
		(width 0.11684)
		(layer "In2.Cu")
		(net "CPU0_SP5R4")
	)
	(segment
		(start 434.000656 -140.879576)
		(end 433.998624 -140.881608)
		(width 0.11684)
		(layer "In2.Cu")
		(net "CPU0_SP5R4")
	)
	(segment
		(start 402.264626 -129.514346)
		(end 404.311104 -127.467868)
		(width 0.11684)
		(layer "In2.Cu")
		(net "CPU0_SP5R4")
	)
	(segment
		(start 303.926748 -120.92432)
		(end 305.6636 -119.187468)
		(width 0.11684)
		(layer "In2.Cu")
		(net "CPU0_SP5R4")
	)
	(segment
		(start 309.918862 -119.187468)
		(end 317.401194 -126.6698)
		(width 0.11684)
		(layer "In2.Cu")
		(net "CPU0_SP5R4")
	)
	(segment
		(start 433.998624 -154.966162)
		(end 441.738258 -162.705796)
		(width 0.11684)
		(layer "In2.Cu")
		(net "CPU0_SP5R4")
	)
	(segment
		(start 193.446654 -99.794568)
		(end 192.913 -99.260914)
		(width 0.11684)
		(layer "In2.Cu")
		(net "CPU0_SP5R4")
	)
	(segment
		(start 220.158564 -106.807254)
		(end 216.46515 -103.11384)
		(width 0.11684)
		(layer "In2.Cu")
		(net "CPU0_SP5R4")
	)
	(segment
		(start 198.375778 -98.988118)
		(end 197.569328 -99.794568)
		(width 0.11684)
		(layer "In2.Cu")
		(net "CPU0_SP5R4")
	)
	(segment
		(start 445.626744 -166.078408)
		(end 445.626744 -174.080932)
		(width 0.11684)
		(layer "In2.Cu")
		(net "CPU0_SP5R4")
	)
	(segment
		(start 208.485232 -98.878898)
		(end 206.38643 -98.878898)
		(width 0.11684)
		(layer "In2.Cu")
		(net "CPU0_SP5R4")
	)
	(segment
		(start 455.604626 -187.86983)
		(end 458.477366 -190.74257)
		(width 0.11684)
		(layer "In2.Cu")
		(net "CPU0_SP5R4")
	)
	(segment
		(start 197.569328 -99.794568)
		(end 193.446654 -99.794568)
		(width 0.11684)
		(layer "In2.Cu")
		(net "CPU0_SP5R4")
	)
	(segment
		(start 204.213714 -99.427284)
		(end 203.436982 -99.427284)
		(width 0.11684)
		(layer "In2.Cu")
		(net "CPU0_SP5R4")
	)
	(segment
		(start 455.604626 -184.058814)
		(end 455.604626 -187.86983)
		(width 0.11684)
		(layer "In2.Cu")
		(net "CPU0_SP5R4")
	)
	(segment
		(start 305.6636 -119.187468)
		(end 309.918862 -119.187468)
		(width 0.11684)
		(layer "In2.Cu")
		(net "CPU0_SP5R4")
	)
	(segment
		(start 352.481134 -130.846068)
		(end 353.812856 -129.514346)
		(width 0.11684)
		(layer "In2.Cu")
		(net "CPU0_SP5R4")
	)
	(segment
		(start 433.998624 -140.881608)
		(end 433.998624 -154.966162)
		(width 0.11684)
		(layer "In2.Cu")
		(net "CPU0_SP5R4")
	)
	(segment
		(start 391.385044 -320.397124)
		(end 392.17092 -319.611248)
		(width 0.11684)
		(layer "In2.Cu")
		(net "CPU0_SP5R4")
	)
	(segment
		(start 259.827776 -110.611666)
		(end 254.710692 -110.611666)
		(width 0.11684)
		(layer "In2.Cu")
		(net "CPU0_SP5R4")
	)
	(segment
		(start 404.311104 -127.467868)
		(end 421.36568 -127.467868)
		(width 0.11684)
		(layer "In2.Cu")
		(net "CPU0_SP5R4")
	)
	(segment
		(start 456.644502 -319.768728)
		(end 454.47204 -321.94119)
		(width 0.11684)
		(layer "In2.Cu")
		(net "CPU0_SP5R4")
	)
	(segment
		(start 442.254132 -162.705796)
		(end 445.626744 -166.078408)
		(width 0.11684)
		(layer "In2.Cu")
		(net "CPU0_SP5R4")
	)
	(segment
		(start 266.06881 -112.878616)
		(end 266.06881 -112.901222)
		(width 0.11684)
		(layer "In2.Cu")
		(net "CPU0_SP5R4")
	)
	(segment
		(start 216.46515 -103.11384)
		(end 215.205056 -103.11384)
		(width 0.11684)
		(layer "In2.Cu")
		(net "CPU0_SP5R4")
	)
	(segment
		(start 458.477366 -190.74257)
		(end 458.477366 -198.61911)
		(width 0.11684)
		(layer "In2.Cu")
		(net "CPU0_SP5R4")
	)
	(segment
		(start 445.626744 -174.080932)
		(end 455.604626 -184.058814)
		(width 0.11684)
		(layer "In2.Cu")
		(net "CPU0_SP5R4")
	)
	(segment
		(start 298.332652 -120.92432)
		(end 303.926748 -120.92432)
		(width 0.11684)
		(layer "In2.Cu")
		(net "CPU0_SP5R4")
	)
	(segment
		(start 456.644502 -200.451974)
		(end 456.644502 -319.768728)
		(width 0.11684)
		(layer "In2.Cu")
		(net "CPU0_SP5R4")
	)
	(segment
		(start 204.706982 -98.934016)
		(end 204.213714 -99.427284)
		(width 0.11684)
		(layer "In2.Cu")
		(net "CPU0_SP5R4")
	)
	(segment
		(start 221.762574 -108.17479)
		(end 221.157546 -108.17479)
		(width 0.11684)
		(layer "In2.Cu")
		(net "CPU0_SP5R4")
	)
	(segment
		(start 296.165016 -118.756684)
		(end 298.332652 -120.92432)
		(width 0.11684)
		(layer "In2.Cu")
		(net "CPU0_SP5R4")
	)
	(segment
		(start 421.36568 -127.467868)
		(end 434.000656 -140.102844)
		(width 0.11684)
		(layer "In2.Cu")
		(net "CPU0_SP5R4")
	)
	(segment
		(start 254.710692 -110.611666)
		(end 254.115062 -110.016036)
		(width 0.11684)
		(layer "In2.Cu")
		(net "CPU0_SP5R4")
	)
	(segment
		(start 213.186772 -101.095556)
		(end 210.70189 -101.095556)
		(width 0.11684)
		(layer "In2.Cu")
		(net "CPU0_SP5R4")
	)
	(segment
		(start 391.385044 -321.684142)
		(end 391.385044 -320.397124)
		(width 0.11684)
		(layer "In2.Cu")
		(net "CPU0_SP5R4")
	)
	(segment
		(start 206.331312 -98.934016)
		(end 204.706982 -98.934016)
		(width 0.11684)
		(layer "In2.Cu")
		(net "CPU0_SP5R4")
	)
	(segment
		(start 441.738258 -162.705796)
		(end 442.254132 -162.705796)
		(width 0.11684)
		(layer "In2.Cu")
		(net "CPU0_SP5R4")
	)
	(segment
		(start 410.866336 -321.94119)
		(end 408.890724 -323.916802)
		(width 0.11684)
		(layer "In2.Cu")
		(net "CPU0_SP5R4")
	)
	(segment
		(start 266.06881 -112.901222)
		(end 265.204956 -113.765076)
		(width 0.11684)
		(layer "In2.Cu")
		(net "CPU0_SP5R4")
	)
	(segment
		(start 210.70189 -101.095556)
		(end 208.485232 -98.878898)
		(width 0.11684)
		(layer "In2.Cu")
		(net "CPU0_SP5R4")
	)
	(segment
		(start 262.981186 -113.765076)
		(end 259.827776 -110.611666)
		(width 0.11684)
		(layer "In2.Cu")
		(net "CPU0_SP5R4")
	)
	(segment
		(start 393.617704 -323.916802)
		(end 391.385044 -321.684142)
		(width 0.11684)
		(layer "In2.Cu")
		(net "CPU0_SP5R4")
	)
	(segment
		(start 353.812856 -129.514346)
		(end 402.264626 -129.514346)
		(width 0.11684)
		(layer "In2.Cu")
		(net "CPU0_SP5R4")
	)
	(segment
		(start 458.477366 -198.61911)
		(end 456.644502 -200.451974)
		(width 0.11684)
		(layer "In2.Cu")
		(net "CPU0_SP5R4")
	)
	(segment
		(start 221.157546 -108.17479)
		(end 220.158564 -107.175808)
		(width 0.11684)
		(layer "In2.Cu")
		(net "CPU0_SP5R4")
	)
	(segment
		(start 220.158564 -107.175808)
		(end 220.158564 -106.807254)
		(width 0.11684)
		(layer "In2.Cu")
		(net "CPU0_SP5R4")
	)
	(segment
		(start 317.401194 -126.6698)
		(end 344.10396 -126.6698)
		(width 0.11684)
		(layer "In2.Cu")
		(net "CPU0_SP5R4")
	)
	(segment
		(start 454.47204 -321.94119)
		(end 410.866336 -321.94119)
		(width 0.11684)
		(layer "In2.Cu")
		(net "CPU0_SP5R4")
	)
	(segment
		(start 348.280228 -130.846068)
		(end 352.481134 -130.846068)
		(width 0.11684)
		(layer "In2.Cu")
		(net "CPU0_SP5R4")
	)
	(segment
		(start 287.61436 -119.812308)
		(end 288.669984 -118.756684)
		(width 0.11684)
		(layer "In2.Cu")
		(net "CPU0_SP5R4")
	)
	(segment
		(start 206.38643 -98.878898)
		(end 206.331312 -98.934016)
		(width 0.11684)
		(layer "In2.Cu")
		(net "CPU0_SP5R4")
	)
	(segment
		(start 434.000656 -140.102844)
		(end 434.000656 -140.879576)
		(width 0.11684)
		(layer "In2.Cu")
		(net "CPU0_SP5R4")
	)
	(segment
		(start 254.115062 -110.016036)
		(end 223.60382 -110.016036)
		(width 0.11684)
		(layer "In2.Cu")
		(net "CPU0_SP5R4")
	)
	(segment
		(start 223.60382 -110.016036)
		(end 221.762574 -108.17479)
		(width 0.11684)
		(layer "In2.Cu")
		(net "CPU0_SP5R4")
	)
	(segment
		(start 202.997816 -98.988118)
		(end 198.375778 -98.988118)
		(width 0.11684)
		(layer "In2.Cu")
		(net "CPU0_SP5R4")
	)
	(segment
		(start 265.204956 -113.765076)
		(end 262.981186 -113.765076)
		(width 0.11684)
		(layer "In2.Cu")
		(net "CPU0_SP5R4")
	)
	(segment
		(start 326.873108 -310.144668)
		(end 324.84441 -308.11597)
		(width 0.10668)
		(layer "F.Cu")
		(net "CPU0_SP5R3")
	)
	(segment
		(start 192.913 -98.262948)
		(end 192.913 -96.503998)
		(width 0.10668)
		(layer "F.Cu")
		(net "CPU0_SP5R3")
	)
	(segment
		(start 326.410828 -295.587166)
		(end 327.117964 -294.88003)
		(width 0.10668)
		(layer "F.Cu")
		(net "CPU0_SP5R3")
	)
	(segment
		(start 333.17561 -310.144668)
		(end 326.873108 -310.144668)
		(width 0.10668)
		(layer "F.Cu")
		(net "CPU0_SP5R3")
	)
	(segment
		(start 266.657582 -128.536954)
		(end 266.657582 -142.70482)
		(width 0.10668)
		(layer "F.Cu")
		(net "CPU0_SP5R3")
	)
	(segment
		(start 192.405 -97.185226)
		(end 192.405 -99.787202)
		(width 0.10668)
		(layer "F.Cu")
		(net "CPU0_SP5R3")
	)
	(segment
		(start 262.864346 -112.878616)
		(end 262.864346 -114.36096)
		(width 0.10668)
		(layer "F.Cu")
		(net "CPU0_SP5R3")
	)
	(segment
		(start 192.512696 -99.894898)
		(end 192.913 -99.894898)
		(width 0.10668)
		(layer "F.Cu")
		(net "CPU0_SP5R3")
	)
	(segment
		(start 262.983218 -184.621678)
		(end 261.66826 -185.936636)
		(width 0.10668)
		(layer "F.Cu")
		(net "CPU0_SP5R3")
	)
	(segment
		(start 264.445496 -144.916906)
		(end 264.445496 -146.821144)
		(width 0.10668)
		(layer "F.Cu")
		(net "CPU0_SP5R3")
	)
	(segment
		(start 326.410828 -300.848776)
		(end 326.410828 -295.587166)
		(width 0.10668)
		(layer "F.Cu")
		(net "CPU0_SP5R3")
	)
	(segment
		(start 192.913 -96.503998)
		(end 192.908428 -96.499426)
		(width 0.10668)
		(layer "F.Cu")
		(net "CPU0_SP5R3")
	)
	(segment
		(start 262.983218 -148.283422)
		(end 262.983218 -184.621678)
		(width 0.10668)
		(layer "F.Cu")
		(net "CPU0_SP5R3")
	)
	(segment
		(start 261.66826 -185.936636)
		(end 261.66826 -186.695842)
		(width 0.10668)
		(layer "F.Cu")
		(net "CPU0_SP5R3")
	)
	(segment
		(start 264.445496 -146.821144)
		(end 262.983218 -148.283422)
		(width 0.10668)
		(layer "F.Cu")
		(net "CPU0_SP5R3")
	)
	(segment
		(start 192.908428 -96.499426)
		(end 191.7192 -96.499426)
		(width 0.10668)
		(layer "F.Cu")
		(net "CPU0_SP5R3")
	)
	(segment
		(start 192.405 -99.787202)
		(end 192.512696 -99.894898)
		(width 0.10668)
		(layer "F.Cu")
		(net "CPU0_SP5R3")
	)
	(segment
		(start 263.72058 -115.217194)
		(end 263.72058 -125.599952)
		(width 0.10668)
		(layer "F.Cu")
		(net "CPU0_SP5R3")
	)
	(segment
		(start 324.84441 -302.415194)
		(end 326.410828 -300.848776)
		(width 0.10668)
		(layer "F.Cu")
		(net "CPU0_SP5R3")
	)
	(segment
		(start 262.864346 -114.36096)
		(end 263.72058 -115.217194)
		(width 0.10668)
		(layer "F.Cu")
		(net "CPU0_SP5R3")
	)
	(segment
		(start 266.657582 -142.70482)
		(end 264.445496 -144.916906)
		(width 0.10668)
		(layer "F.Cu")
		(net "CPU0_SP5R3")
	)
	(segment
		(start 324.84441 -308.11597)
		(end 324.84441 -302.415194)
		(width 0.10668)
		(layer "F.Cu")
		(net "CPU0_SP5R3")
	)
	(segment
		(start 263.72058 -125.599952)
		(end 266.657582 -128.536954)
		(width 0.10668)
		(layer "F.Cu")
		(net "CPU0_SP5R3")
	)
	(segment
		(start 191.7192 -96.499426)
		(end 192.405 -97.185226)
		(width 0.10668)
		(layer "F.Cu")
		(net "CPU0_SP5R3")
	)
	(via
		(at 191.7192 -96.499426)
		(size 0.762)
		(drill 0.381)
		(layers "F.Cu" "B.Cu")
		(net "CPU0_SP5R3")
	)
	(via
		(at 192.913 -98.262948)
		(size 0.508)
		(drill 0.254)
		(layers "F.Cu" "B.Cu")
		(net "CPU0_SP5R3")
	)
	(via
		(at 262.864346 -112.878616)
		(size 0.508)
		(drill 0.254)
		(layers "F.Cu" "B.Cu")
		(net "CPU0_SP5R3")
	)
	(via
		(at 261.66826 -186.695842)
		(size 0.508)
		(drill 0.254)
		(layers "F.Cu" "B.Cu")
		(net "CPU0_SP5R3")
	)
	(via
		(at 333.17561 -310.144668)
		(size 0.508)
		(drill 0.254)
		(layers "F.Cu" "B.Cu")
		(net "CPU0_SP5R3")
	)
	(segment
		(start 299.561758 -326.060816)
		(end 303.422304 -322.20027)
		(width 0.10668)
		(layer "B.Cu")
		(net "CPU0_SP5R3")
	)
	(segment
		(start 262.111236 -326.060816)
		(end 299.561758 -326.060816)
		(width 0.10668)
		(layer "B.Cu")
		(net "CPU0_SP5R3")
	)
	(segment
		(start 258.572 -222.758)
		(end 258.572 -322.52158)
		(width 0.10668)
		(layer "B.Cu")
		(net "CPU0_SP5R3")
	)
	(segment
		(start 256.810256 -187.435744)
		(end 252.603 -191.643)
		(width 0.10668)
		(layer "B.Cu")
		(net "CPU0_SP5R3")
	)
	(segment
		(start 252.603 -216.789)
		(end 258.572 -222.758)
		(width 0.10668)
		(layer "B.Cu")
		(net "CPU0_SP5R3")
	)
	(segment
		(start 307.808376 -319.452498)
		(end 315.910976 -311.349898)
		(width 0.10668)
		(layer "B.Cu")
		(net "CPU0_SP5R3")
	)
	(segment
		(start 252.603 -191.643)
		(end 252.603 -216.789)
		(width 0.10668)
		(layer "B.Cu")
		(net "CPU0_SP5R3")
	)
	(segment
		(start 331.97038 -311.349898)
		(end 333.17561 -310.144668)
		(width 0.10668)
		(layer "B.Cu")
		(net "CPU0_SP5R3")
	)
	(segment
		(start 261.54126 -187.435744)
		(end 256.810256 -187.435744)
		(width 0.10668)
		(layer "B.Cu")
		(net "CPU0_SP5R3")
	)
	(segment
		(start 261.66826 -187.308744)
		(end 261.54126 -187.435744)
		(width 0.10668)
		(layer "B.Cu")
		(net "CPU0_SP5R3")
	)
	(segment
		(start 307.037486 -319.452498)
		(end 307.808376 -319.452498)
		(width 0.10668)
		(layer "B.Cu")
		(net "CPU0_SP5R3")
	)
	(segment
		(start 304.289714 -322.20027)
		(end 307.037486 -319.452498)
		(width 0.10668)
		(layer "B.Cu")
		(net "CPU0_SP5R3")
	)
	(segment
		(start 303.422304 -322.20027)
		(end 304.289714 -322.20027)
		(width 0.10668)
		(layer "B.Cu")
		(net "CPU0_SP5R3")
	)
	(segment
		(start 315.910976 -311.349898)
		(end 331.97038 -311.349898)
		(width 0.10668)
		(layer "B.Cu")
		(net "CPU0_SP5R3")
	)
	(segment
		(start 258.572 -322.52158)
		(end 262.111236 -326.060816)
		(width 0.10668)
		(layer "B.Cu")
		(net "CPU0_SP5R3")
	)
	(segment
		(start 261.66826 -186.695842)
		(end 261.66826 -187.308744)
		(width 0.10668)
		(layer "B.Cu")
		(net "CPU0_SP5R3")
	)
	(segment
		(start 227.89642 -109.500162)
		(end 219.109036 -100.712778)
		(width 0.11684)
		(layer "In2.Cu")
		(net "CPU0_SP5R3")
	)
	(segment
		(start 196.290184 -98.727768)
		(end 193.37782 -98.727768)
		(width 0.11684)
		(layer "In2.Cu")
		(net "CPU0_SP5R3")
	)
	(segment
		(start 212.38337 -99.210368)
		(end 210.009486 -99.210368)
		(width 0.11684)
		(layer "In2.Cu")
		(net "CPU0_SP5R3")
	)
	(segment
		(start 201.537062 -97.71634)
		(end 201.136504 -98.116898)
		(width 0.11684)
		(layer "In2.Cu")
		(net "CPU0_SP5R3")
	)
	(segment
		(start 204.39761 -97.582736)
		(end 204.264006 -97.71634)
		(width 0.11684)
		(layer "In2.Cu")
		(net "CPU0_SP5R3")
	)
	(segment
		(start 193.37782 -98.727768)
		(end 192.913 -98.262948)
		(width 0.11684)
		(layer "In2.Cu")
		(net "CPU0_SP5R3")
	)
	(segment
		(start 208.381854 -97.582736)
		(end 204.39761 -97.582736)
		(width 0.11684)
		(layer "In2.Cu")
		(net "CPU0_SP5R3")
	)
	(segment
		(start 201.136504 -98.116898)
		(end 196.901054 -98.116898)
		(width 0.11684)
		(layer "In2.Cu")
		(net "CPU0_SP5R3")
	)
	(segment
		(start 212.669882 -99.385882)
		(end 212.558884 -99.385882)
		(width 0.11684)
		(layer "In2.Cu")
		(net "CPU0_SP5R3")
	)
	(segment
		(start 210.009486 -99.210368)
		(end 208.381854 -97.582736)
		(width 0.11684)
		(layer "In2.Cu")
		(net "CPU0_SP5R3")
	)
	(segment
		(start 219.109036 -100.712778)
		(end 213.996778 -100.712778)
		(width 0.11684)
		(layer "In2.Cu")
		(net "CPU0_SP5R3")
	)
	(segment
		(start 213.996778 -100.712778)
		(end 212.669882 -99.385882)
		(width 0.11684)
		(layer "In2.Cu")
		(net "CPU0_SP5R3")
	)
	(segment
		(start 204.264006 -97.71634)
		(end 201.537062 -97.71634)
		(width 0.11684)
		(layer "In2.Cu")
		(net "CPU0_SP5R3")
	)
	(segment
		(start 258.772406 -109.779308)
		(end 258.49326 -109.500162)
		(width 0.11684)
		(layer "In2.Cu")
		(net "CPU0_SP5R3")
	)
	(segment
		(start 196.901054 -98.116898)
		(end 196.290184 -98.727768)
		(width 0.11684)
		(layer "In2.Cu")
		(net "CPU0_SP5R3")
	)
	(segment
		(start 258.49326 -109.500162)
		(end 227.89642 -109.500162)
		(width 0.11684)
		(layer "In2.Cu")
		(net "CPU0_SP5R3")
	)
	(segment
		(start 212.558884 -99.385882)
		(end 212.38337 -99.210368)
		(width 0.11684)
		(layer "In2.Cu")
		(net "CPU0_SP5R3")
	)
	(segment
		(start 259.765038 -109.779308)
		(end 258.772406 -109.779308)
		(width 0.11684)
		(layer "In2.Cu")
		(net "CPU0_SP5R3")
	)
	(segment
		(start 262.864346 -112.878616)
		(end 259.765038 -109.779308)
		(width 0.11684)
		(layer "In2.Cu")
		(net "CPU0_SP5R3")
	)
	(segment
		(start 296.972482 -171.703492)
		(end 311.237122 -185.968132)
		(width 0.10668)
		(layer "F.Cu")
		(net "CPU0_SP5R2")
	)
	(segment
		(start 281.451304 -164.280596)
		(end 281.451304 -164.429186)
		(width 0.10668)
		(layer "F.Cu")
		(net "CPU0_SP5R2")
	)
	(segment
		(start 281.024076 -164.856414)
		(end 281.024076 -166.66718)
		(width 0.10668)
		(layer "F.Cu")
		(net "CPU0_SP5R2")
	)
	(segment
		(start 315.876178 -200.968864)
		(end 319.68059 -200.968864)
		(width 0.10668)
		(layer "F.Cu")
		(net "CPU0_SP5R2")
	)
	(segment
		(start 311.237122 -196.329808)
		(end 315.876178 -200.968864)
		(width 0.10668)
		(layer "F.Cu")
		(net "CPU0_SP5R2")
	)
	(segment
		(start 286.060388 -171.703492)
		(end 296.972482 -171.703492)
		(width 0.10668)
		(layer "F.Cu")
		(net "CPU0_SP5R2")
	)
	(segment
		(start 281.451304 -164.429186)
		(end 281.024076 -164.856414)
		(width 0.10668)
		(layer "F.Cu")
		(net "CPU0_SP5R2")
	)
	(segment
		(start 331.987906 -223.69018)
		(end 331.521054 -223.424242)
		(width 0.10668)
		(layer "F.Cu")
		(net "CPU0_SP5R2")
	)
	(segment
		(start 281.024076 -166.66718)
		(end 286.060388 -171.703492)
		(width 0.10668)
		(layer "F.Cu")
		(net "CPU0_SP5R2")
	)
	(segment
		(start 322.204334 -203.492608)
		(end 322.206112 -203.492608)
		(width 0.10668)
		(layer "F.Cu")
		(net "CPU0_SP5R2")
	)
	(segment
		(start 319.68059 -200.968864)
		(end 322.204334 -203.492608)
		(width 0.10668)
		(layer "F.Cu")
		(net "CPU0_SP5R2")
	)
	(segment
		(start 322.206112 -203.492608)
		(end 323.894958 -205.181454)
		(width 0.10668)
		(layer "F.Cu")
		(net "CPU0_SP5R2")
	)
	(segment
		(start 311.237122 -185.968132)
		(end 311.237122 -196.329808)
		(width 0.10668)
		(layer "F.Cu")
		(net "CPU0_SP5R2")
	)
	(segment
		(start 323.894958 -205.181454)
		(end 323.894958 -205.476602)
		(width 0.10668)
		(layer "F.Cu")
		(net "CPU0_SP5R2")
	)
	(via
		(at 323.894958 -205.476602)
		(size 0.508)
		(drill 0.254)
		(layers "F.Cu" "B.Cu")
		(net "CPU0_SP5R2")
	)
	(via
		(at 146.77263 -111.036354)
		(size 0.508)
		(drill 0.254)
		(layers "F.Cu" "B.Cu")
		(net "CPU0_SP5R2")
	)
	(via
		(at 281.451304 -164.280596)
		(size 0.508)
		(drill 0.254)
		(layers "F.Cu" "B.Cu")
		(net "CPU0_SP5R2")
	)
	(via
		(at 331.521054 -223.424242)
		(size 0.4064)
		(drill 0.2032)
		(layers "F.Cu" "B.Cu")
		(net "CPU0_SP5R2")
	)
	(via
		(at 167.287702 -152.281636)
		(size 0.508)
		(drill 0.254)
		(layers "F.Cu" "B.Cu")
		(net "CPU0_SP5R2")
	)
	(via
		(at 185.801 -98.262948)
		(size 0.508)
		(drill 0.254)
		(layers "F.Cu" "B.Cu")
		(net "CPU0_SP5R2")
	)
	(segment
		(start 323.894958 -205.476602)
		(end 324.510908 -206.092552)
		(width 0.10668)
		(layer "B.Cu")
		(net "CPU0_SP5R2")
	)
	(segment
		(start 323.386958 -204.317346)
		(end 323.894958 -204.825346)
		(width 0.10668)
		(layer "B.Cu")
		(net "CPU0_SP5R2")
	)
	(segment
		(start 332.454758 -222.805498)
		(end 331.836014 -223.424242)
		(width 0.10668)
		(layer "B.Cu")
		(net "CPU0_SP5R2")
	)
	(segment
		(start 333.140558 -210.956144)
		(end 333.140558 -221.738952)
		(width 0.10668)
		(layer "B.Cu")
		(net "CPU0_SP5R2")
	)
	(segment
		(start 186.2836 -99.584002)
		(end 186.594496 -99.894898)
		(width 0.10668)
		(layer "B.Cu")
		(net "CPU0_SP5R2")
	)
	(segment
		(start 333.140558 -221.738952)
		(end 332.454758 -222.424752)
		(width 0.10668)
		(layer "B.Cu")
		(net "CPU0_SP5R2")
	)
	(segment
		(start 185.801 -98.262948)
		(end 185.801 -98.406204)
		(width 0.10668)
		(layer "B.Cu")
		(net "CPU0_SP5R2")
	)
	(segment
		(start 185.801 -98.406204)
		(end 186.2836 -98.888804)
		(width 0.10668)
		(layer "B.Cu")
		(net "CPU0_SP5R2")
	)
	(segment
		(start 323.894958 -204.825346)
		(end 323.894958 -205.476602)
		(width 0.10668)
		(layer "B.Cu")
		(net "CPU0_SP5R2")
	)
	(segment
		(start 324.510908 -206.092552)
		(end 328.276966 -206.092552)
		(width 0.10668)
		(layer "B.Cu")
		(net "CPU0_SP5R2")
	)
	(segment
		(start 332.454758 -222.424752)
		(end 332.454758 -222.805498)
		(width 0.10668)
		(layer "B.Cu")
		(net "CPU0_SP5R2")
	)
	(segment
		(start 186.594496 -99.894898)
		(end 186.817 -99.894898)
		(width 0.10668)
		(layer "B.Cu")
		(net "CPU0_SP5R2")
	)
	(segment
		(start 328.276966 -206.092552)
		(end 333.140558 -210.956144)
		(width 0.10668)
		(layer "B.Cu")
		(net "CPU0_SP5R2")
	)
	(segment
		(start 331.836014 -223.424242)
		(end 331.521054 -223.424242)
		(width 0.10668)
		(layer "B.Cu")
		(net "CPU0_SP5R2")
	)
	(segment
		(start 186.2836 -98.888804)
		(end 186.2836 -99.584002)
		(width 0.10668)
		(layer "B.Cu")
		(net "CPU0_SP5R2")
	)
	(segment
		(start 166.33698 -104.184704)
		(end 167.802052 -102.719632)
		(width 0.11684)
		(layer "In2.Cu")
		(net "CPU0_SP5R2")
	)
	(segment
		(start 171.20997 -102.644194)
		(end 172.823632 -101.030532)
		(width 0.11684)
		(layer "In2.Cu")
		(net "CPU0_SP5R2")
	)
	(segment
		(start 185.801 -98.992182)
		(end 185.801 -98.262948)
		(width 0.11684)
		(layer "In2.Cu")
		(net "CPU0_SP5R2")
	)
	(segment
		(start 167.802052 -102.719632)
		(end 168.578022 -102.719632)
		(width 0.11684)
		(layer "In2.Cu")
		(net "CPU0_SP5R2")
	)
	(segment
		(start 164.134038 -105.422954)
		(end 164.134038 -105.061258)
		(width 0.11684)
		(layer "In2.Cu")
		(net "CPU0_SP5R2")
	)
	(segment
		(start 159.389064 -108.726986)
		(end 160.649412 -107.466638)
		(width 0.11684)
		(layer "In2.Cu")
		(net "CPU0_SP5R2")
	)
	(segment
		(start 149.342856 -107.218226)
		(end 150.829264 -107.218226)
		(width 0.11684)
		(layer "In2.Cu")
		(net "CPU0_SP5R2")
	)
	(segment
		(start 152.24633 -108.635292)
		(end 154.363674 -108.635292)
		(width 0.11684)
		(layer "In2.Cu")
		(net "CPU0_SP5R2")
	)
	(segment
		(start 172.823632 -101.030532)
		(end 183.76265 -101.030532)
		(width 0.11684)
		(layer "In2.Cu")
		(net "CPU0_SP5R2")
	)
	(segment
		(start 154.455368 -108.726986)
		(end 159.389064 -108.726986)
		(width 0.11684)
		(layer "In2.Cu")
		(net "CPU0_SP5R2")
	)
	(segment
		(start 183.76265 -101.030532)
		(end 185.801 -98.992182)
		(width 0.11684)
		(layer "In2.Cu")
		(net "CPU0_SP5R2")
	)
	(segment
		(start 146.77263 -111.036354)
		(end 146.77263 -109.788452)
		(width 0.11684)
		(layer "In2.Cu")
		(net "CPU0_SP5R2")
	)
	(segment
		(start 168.578022 -102.719632)
		(end 168.65346 -102.644194)
		(width 0.11684)
		(layer "In2.Cu")
		(net "CPU0_SP5R2")
	)
	(segment
		(start 160.649412 -107.466638)
		(end 162.090354 -107.466638)
		(width 0.11684)
		(layer "In2.Cu")
		(net "CPU0_SP5R2")
	)
	(segment
		(start 162.090354 -107.466638)
		(end 164.134038 -105.422954)
		(width 0.11684)
		(layer "In2.Cu")
		(net "CPU0_SP5R2")
	)
	(segment
		(start 146.77263 -109.788452)
		(end 149.342856 -107.218226)
		(width 0.11684)
		(layer "In2.Cu")
		(net "CPU0_SP5R2")
	)
	(segment
		(start 168.65346 -102.644194)
		(end 171.20997 -102.644194)
		(width 0.11684)
		(layer "In2.Cu")
		(net "CPU0_SP5R2")
	)
	(segment
		(start 165.010592 -104.184704)
		(end 166.33698 -104.184704)
		(width 0.11684)
		(layer "In2.Cu")
		(net "CPU0_SP5R2")
	)
	(segment
		(start 150.829264 -107.218226)
		(end 152.24633 -108.635292)
		(width 0.11684)
		(layer "In2.Cu")
		(net "CPU0_SP5R2")
	)
	(segment
		(start 154.363674 -108.635292)
		(end 154.455368 -108.726986)
		(width 0.11684)
		(layer "In2.Cu")
		(net "CPU0_SP5R2")
	)
	(segment
		(start 164.134038 -105.061258)
		(end 165.010592 -104.184704)
		(width 0.11684)
		(layer "In2.Cu")
		(net "CPU0_SP5R2")
	)
	(segment
		(start 226.16922 -164.399722)
		(end 223.003618 -161.23412)
		(width 0.11684)
		(layer "In6.Cu")
		(net "CPU0_SP5R2")
	)
	(segment
		(start 199.042782 -167.960802)
		(end 197.002908 -165.920928)
		(width 0.11684)
		(layer "In6.Cu")
		(net "CPU0_SP5R2")
	)
	(segment
		(start 197.002908 -165.920928)
		(end 189.641988 -165.920928)
		(width 0.11684)
		(layer "In6.Cu")
		(net "CPU0_SP5R2")
	)
	(segment
		(start 280.927556 -163.756848)
		(end 271.302734 -163.756848)
		(width 0.11684)
		(layer "In6.Cu")
		(net "CPU0_SP5R2")
	)
	(segment
		(start 214.193882 -161.23412)
		(end 207.4672 -167.960802)
		(width 0.11684)
		(layer "In6.Cu")
		(net "CPU0_SP5R2")
	)
	(segment
		(start 184.063132 -160.342072)
		(end 175.348138 -160.342072)
		(width 0.11684)
		(layer "In6.Cu")
		(net "CPU0_SP5R2")
	)
	(segment
		(start 270.65986 -164.399722)
		(end 226.16922 -164.399722)
		(width 0.11684)
		(layer "In6.Cu")
		(net "CPU0_SP5R2")
	)
	(segment
		(start 223.003618 -161.23412)
		(end 214.193882 -161.23412)
		(width 0.11684)
		(layer "In6.Cu")
		(net "CPU0_SP5R2")
	)
	(segment
		(start 189.641988 -165.920928)
		(end 184.063132 -160.342072)
		(width 0.11684)
		(layer "In6.Cu")
		(net "CPU0_SP5R2")
	)
	(segment
		(start 175.348138 -160.342072)
		(end 167.287702 -152.281636)
		(width 0.11684)
		(layer "In6.Cu")
		(net "CPU0_SP5R2")
	)
	(segment
		(start 281.451304 -164.280596)
		(end 280.927556 -163.756848)
		(width 0.11684)
		(layer "In6.Cu")
		(net "CPU0_SP5R2")
	)
	(segment
		(start 271.302734 -163.756848)
		(end 270.65986 -164.399722)
		(width 0.11684)
		(layer "In6.Cu")
		(net "CPU0_SP5R2")
	)
	(segment
		(start 207.4672 -167.960802)
		(end 199.042782 -167.960802)
		(width 0.11684)
		(layer "In6.Cu")
		(net "CPU0_SP5R2")
	)
	(segment
		(start 146.23034 -115.945666)
		(end 147.086066 -115.08994)
		(width 0.11684)
		(layer "In15.Cu")
		(net "CPU0_SP5R2")
	)
	(segment
		(start 165.57752 -146.368262)
		(end 165.57752 -143.631666)
		(width 0.11684)
		(layer "In15.Cu")
		(net "CPU0_SP5R2")
	)
	(segment
		(start 167.287702 -152.281636)
		(end 166.0779 -151.071834)
		(width 0.11684)
		(layer "In15.Cu")
		(net "CPU0_SP5R2")
	)
	(segment
		(start 166.0779 -148.935186)
		(end 165.439852 -148.297138)
		(width 0.11684)
		(layer "In15.Cu")
		(net "CPU0_SP5R2")
	)
	(segment
		(start 147.086066 -113.58753)
		(end 146.77263 -113.274094)
		(width 0.11684)
		(layer "In15.Cu")
		(net "CPU0_SP5R2")
	)
	(segment
		(start 165.57752 -143.631666)
		(end 146.77263 -124.826776)
		(width 0.11684)
		(layer "In15.Cu")
		(net "CPU0_SP5R2")
	)
	(segment
		(start 146.23034 -118.544086)
		(end 146.23034 -115.945666)
		(width 0.11684)
		(layer "In15.Cu")
		(net "CPU0_SP5R2")
	)
	(segment
		(start 165.439852 -148.297138)
		(end 165.439852 -146.50593)
		(width 0.11684)
		(layer "In15.Cu")
		(net "CPU0_SP5R2")
	)
	(segment
		(start 166.0779 -151.071834)
		(end 166.0779 -148.935186)
		(width 0.11684)
		(layer "In15.Cu")
		(net "CPU0_SP5R2")
	)
	(segment
		(start 146.77263 -113.274094)
		(end 146.77263 -111.036354)
		(width 0.11684)
		(layer "In15.Cu")
		(net "CPU0_SP5R2")
	)
	(segment
		(start 165.439852 -146.50593)
		(end 165.57752 -146.368262)
		(width 0.11684)
		(layer "In15.Cu")
		(net "CPU0_SP5R2")
	)
	(segment
		(start 146.77263 -119.086376)
		(end 146.23034 -118.544086)
		(width 0.11684)
		(layer "In15.Cu")
		(net "CPU0_SP5R2")
	)
	(segment
		(start 146.77263 -124.826776)
		(end 146.77263 -119.086376)
		(width 0.11684)
		(layer "In15.Cu")
		(net "CPU0_SP5R2")
	)
	(segment
		(start 147.086066 -115.08994)
		(end 147.086066 -113.58753)
		(width 0.11684)
		(layer "In15.Cu")
		(net "CPU0_SP5R2")
	)
	(segment
		(start 186.804046 -93.703902)
		(end 186.817 -93.690948)
		(width 0.10668)
		(layer "F.Cu")
		(net "CPU0_SP5R1")
	)
	(segment
		(start 377.57481 -223.424242)
		(end 377.107958 -223.69018)
		(width 0.10668)
		(layer "F.Cu")
		(net "CPU0_SP5R1")
	)
	(segment
		(start 186.804046 -94.476062)
		(end 186.804046 -93.703902)
		(width 0.10668)
		(layer "F.Cu")
		(net "CPU0_SP5R1")
	)
	(via
		(at 234.468162 -92.164408)
		(size 0.508)
		(drill 0.254)
		(layers "F.Cu" "B.Cu")
		(net "CPU0_SP5R1")
	)
	(via
		(at 377.57481 -223.424242)
		(size 0.4064)
		(drill 0.2032)
		(layers "F.Cu" "B.Cu")
		(net "CPU0_SP5R1")
	)
	(via
		(at 186.817 -93.690948)
		(size 0.508)
		(drill 0.254)
		(layers "F.Cu" "B.Cu")
		(net "CPU0_SP5R1")
	)
	(via
		(at 373.3673 -206.560928)
		(size 0.508)
		(drill 0.254)
		(layers "F.Cu" "B.Cu")
		(net "CPU0_SP5R1")
	)
	(via
		(at 240.182908 -168.821862)
		(size 0.508)
		(drill 0.254)
		(layers "F.Cu" "B.Cu")
		(net "CPU0_SP5R1")
	)
	(segment
		(start 186.806078 -96.276922)
		(end 186.817 -96.266)
		(width 0.10668)
		(layer "B.Cu")
		(net "CPU0_SP5R1")
	)
	(segment
		(start 186.817 -96.266)
		(end 186.817 -93.690948)
		(width 0.10668)
		(layer "B.Cu")
		(net "CPU0_SP5R1")
	)
	(segment
		(start 186.806078 -96.685862)
		(end 186.806078 -96.276922)
		(width 0.10668)
		(layer "B.Cu")
		(net "CPU0_SP5R1")
	)
	(segment
		(start 373.95912 -205.969108)
		(end 373.3673 -206.560928)
		(width 0.11684)
		(layer "In2.Cu")
		(net "CPU0_SP5R1")
	)
	(segment
		(start 377.57481 -214.286338)
		(end 375.39168 -212.103208)
		(width 0.11684)
		(layer "In2.Cu")
		(net "CPU0_SP5R1")
	)
	(segment
		(start 375.39168 -212.103208)
		(end 375.39168 -209.487008)
		(width 0.11684)
		(layer "In2.Cu")
		(net "CPU0_SP5R1")
	)
	(segment
		(start 375.39168 -209.487008)
		(end 374.96242 -209.057748)
		(width 0.11684)
		(layer "In2.Cu")
		(net "CPU0_SP5R1")
	)
	(segment
		(start 374.96242 -209.057748)
		(end 374.96242 -206.385668)
		(width 0.11684)
		(layer "In2.Cu")
		(net "CPU0_SP5R1")
	)
	(segment
		(start 374.54586 -205.969108)
		(end 373.95912 -205.969108)
		(width 0.11684)
		(layer "In2.Cu")
		(net "CPU0_SP5R1")
	)
	(segment
		(start 374.96242 -206.385668)
		(end 374.54586 -205.969108)
		(width 0.11684)
		(layer "In2.Cu")
		(net "CPU0_SP5R1")
	)
	(segment
		(start 377.57481 -223.424242)
		(end 377.57481 -214.286338)
		(width 0.11684)
		(layer "In2.Cu")
		(net "CPU0_SP5R1")
	)
	(segment
		(start 333.460344 -171.639738)
		(end 314.75299 -171.639738)
		(width 0.11684)
		(layer "In6.Cu")
		(net "CPU0_SP5R1")
	)
	(segment
		(start 372.910862 -206.10449)
		(end 367.925096 -206.10449)
		(width 0.11684)
		(layer "In6.Cu")
		(net "CPU0_SP5R1")
	)
	(segment
		(start 367.925096 -206.10449)
		(end 333.460344 -171.639738)
		(width 0.11684)
		(layer "In6.Cu")
		(net "CPU0_SP5R1")
	)
	(segment
		(start 255.943354 -167.98671)
		(end 255.108202 -168.821862)
		(width 0.11684)
		(layer "In6.Cu")
		(net "CPU0_SP5R1")
	)
	(segment
		(start 311.099962 -167.98671)
		(end 255.943354 -167.98671)
		(width 0.11684)
		(layer "In6.Cu")
		(net "CPU0_SP5R1")
	)
	(segment
		(start 255.108202 -168.821862)
		(end 240.182908 -168.821862)
		(width 0.11684)
		(layer "In6.Cu")
		(net "CPU0_SP5R1")
	)
	(segment
		(start 373.3673 -206.560928)
		(end 372.910862 -206.10449)
		(width 0.11684)
		(layer "In6.Cu")
		(net "CPU0_SP5R1")
	)
	(segment
		(start 314.75299 -171.639738)
		(end 311.099962 -167.98671)
		(width 0.11684)
		(layer "In6.Cu")
		(net "CPU0_SP5R1")
	)
	(segment
		(start 235.78693 -93.483176)
		(end 235.78693 -95.406972)
		(width 0.11684)
		(layer "In11.Cu")
		(net "CPU0_SP5R1")
	)
	(segment
		(start 243.17198 -132.16001)
		(end 243.17198 -161.013902)
		(width 0.11684)
		(layer "In11.Cu")
		(net "CPU0_SP5R1")
	)
	(segment
		(start 234.468162 -123.456192)
		(end 243.17198 -132.16001)
		(width 0.11684)
		(layer "In11.Cu")
		(net "CPU0_SP5R1")
	)
	(segment
		(start 243.17198 -161.013902)
		(end 241.524028 -162.661854)
		(width 0.11684)
		(layer "In11.Cu")
		(net "CPU0_SP5R1")
	)
	(segment
		(start 234.468162 -96.72574)
		(end 234.468162 -123.456192)
		(width 0.11684)
		(layer "In11.Cu")
		(net "CPU0_SP5R1")
	)
	(segment
		(start 241.524028 -167.480742)
		(end 240.182908 -168.821862)
		(width 0.11684)
		(layer "In11.Cu")
		(net "CPU0_SP5R1")
	)
	(segment
		(start 235.78693 -95.406972)
		(end 234.468162 -96.72574)
		(width 0.11684)
		(layer "In11.Cu")
		(net "CPU0_SP5R1")
	)
	(segment
		(start 241.524028 -162.661854)
		(end 241.524028 -167.480742)
		(width 0.11684)
		(layer "In11.Cu")
		(net "CPU0_SP5R1")
	)
	(segment
		(start 234.468162 -92.164408)
		(end 235.78693 -93.483176)
		(width 0.11684)
		(layer "In11.Cu")
		(net "CPU0_SP5R1")
	)
	(segment
		(start 206.573882 -91.661234)
		(end 233.964988 -91.661234)
		(width 0.11684)
		(layer "In15.Cu")
		(net "CPU0_SP5R1")
	)
	(segment
		(start 186.817 -93.690948)
		(end 186.817 -93.657928)
		(width 0.11684)
		(layer "In15.Cu")
		(net "CPU0_SP5R1")
	)
	(segment
		(start 202.440794 -92.769182)
		(end 203.358496 -93.686884)
		(width 0.11684)
		(layer "In15.Cu")
		(net "CPU0_SP5R1")
	)
	(segment
		(start 197.54469 -92.769182)
		(end 202.440794 -92.769182)
		(width 0.11684)
		(layer "In15.Cu")
		(net "CPU0_SP5R1")
	)
	(segment
		(start 186.817 -93.657928)
		(end 189.292484 -91.182444)
		(width 0.11684)
		(layer "In15.Cu")
		(net "CPU0_SP5R1")
	)
	(segment
		(start 203.358496 -93.686884)
		(end 204.548232 -93.686884)
		(width 0.11684)
		(layer "In15.Cu")
		(net "CPU0_SP5R1")
	)
	(segment
		(start 204.548232 -93.686884)
		(end 206.573882 -91.661234)
		(width 0.11684)
		(layer "In15.Cu")
		(net "CPU0_SP5R1")
	)
	(segment
		(start 233.964988 -91.661234)
		(end 234.468162 -92.164408)
		(width 0.11684)
		(layer "In15.Cu")
		(net "CPU0_SP5R1")
	)
	(segment
		(start 189.292484 -91.182444)
		(end 195.957952 -91.182444)
		(width 0.11684)
		(layer "In15.Cu")
		(net "CPU0_SP5R1")
	)
	(segment
		(start 195.957952 -91.182444)
		(end 197.54469 -92.769182)
		(width 0.11684)
		(layer "In15.Cu")
		(net "CPU0_SP5R1")
	)
	(segment
		(start 380.110238 -300.507654)
		(end 380.110238 -309.104284)
		(width 0.10668)
		(layer "F.Cu")
		(net "CPU0_SMERR_N")
	)
	(segment
		(start 390.863328 -319.409318)
		(end 390.863328 -322.559172)
		(width 0.10668)
		(layer "F.Cu")
		(net "CPU0_SMERR_N")
	)
	(segment
		(start 380.110238 -309.104284)
		(end 389.27532 -318.269366)
		(width 0.10668)
		(layer "F.Cu")
		(net "CPU0_SMERR_N")
	)
	(segment
		(start 389.27532 -318.269366)
		(end 391.712196 -318.269366)
		(width 0.10668)
		(layer "F.Cu")
		(net "CPU0_SMERR_N")
	)
	(segment
		(start 384.927856 -295.690036)
		(end 380.110238 -300.507654)
		(width 0.10668)
		(layer "F.Cu")
		(net "CPU0_SMERR_N")
	)
	(segment
		(start 391.712196 -318.269366)
		(end 391.857738 -318.414908)
		(width 0.10668)
		(layer "F.Cu")
		(net "CPU0_SMERR_N")
	)
	(segment
		(start 186.055 -130.393948)
		(end 186.055 -129.777998)
		(width 0.10668)
		(layer "F.Cu")
		(net "CPU0_SMERR_N")
	)
	(segment
		(start 391.857738 -318.414908)
		(end 390.863328 -319.409318)
		(width 0.10668)
		(layer "F.Cu")
		(net "CPU0_SMERR_N")
	)
	(segment
		(start 390.863328 -322.559172)
		(end 392.963908 -324.659752)
		(width 0.10668)
		(layer "F.Cu")
		(net "CPU0_SMERR_N")
	)
	(via
		(at 287.61436 -118.923308)
		(size 0.508)
		(drill 0.254)
		(layers "F.Cu" "B.Cu")
		(net "CPU0_SMERR_N")
	)
	(via
		(at 391.857738 -318.414908)
		(size 0.508)
		(drill 0.254)
		(layers "F.Cu" "B.Cu")
		(net "CPU0_SMERR_N")
	)
	(via
		(at 186.055 -130.393948)
		(size 0.508)
		(drill 0.254)
		(layers "F.Cu" "B.Cu")
		(net "CPU0_SMERR_N")
	)
	(via
		(at 260.225286 -127.042672)
		(size 0.508)
		(drill 0.254)
		(layers "F.Cu" "B.Cu")
		(net "CPU0_SMERR_N")
	)
	(segment
		(start 261.387844 -122.788172)
		(end 265.93546 -127.335788)
		(width 0.10668)
		(layer "B.Cu")
		(net "CPU0_SMERR_N")
	)
	(segment
		(start 260.55193 -122.788172)
		(end 261.387844 -122.788172)
		(width 0.10668)
		(layer "B.Cu")
		(net "CPU0_SMERR_N")
	)
	(segment
		(start 260.225286 -127.042672)
		(end 260.225286 -123.114816)
		(width 0.10668)
		(layer "B.Cu")
		(net "CPU0_SMERR_N")
	)
	(segment
		(start 265.93546 -127.335788)
		(end 277.033736 -127.335788)
		(width 0.10668)
		(layer "B.Cu")
		(net "CPU0_SMERR_N")
	)
	(segment
		(start 277.033736 -127.335788)
		(end 285.446216 -118.923308)
		(width 0.10668)
		(layer "B.Cu")
		(net "CPU0_SMERR_N")
	)
	(segment
		(start 285.446216 -118.923308)
		(end 287.61436 -118.923308)
		(width 0.10668)
		(layer "B.Cu")
		(net "CPU0_SMERR_N")
	)
	(segment
		(start 260.225286 -123.114816)
		(end 260.55193 -122.788172)
		(width 0.10668)
		(layer "B.Cu")
		(net "CPU0_SMERR_N")
	)
	(segment
		(start 352.353118 -130.343656)
		(end 348.74708 -130.343656)
		(width 0.11684)
		(layer "In2.Cu")
		(net "CPU0_SMERR_N")
	)
	(segment
		(start 458.899006 -318.194182)
		(end 458.899006 -190.54318)
		(width 0.11684)
		(layer "In2.Cu")
		(net "CPU0_SMERR_N")
	)
	(segment
		(start 391.857738 -319.227962)
		(end 390.847834 -320.237866)
		(width 0.11684)
		(layer "In2.Cu")
		(net "CPU0_SMERR_N")
	)
	(segment
		(start 303.805844 -120.325388)
		(end 298.559728 -120.325388)
		(width 0.11684)
		(layer "In2.Cu")
		(net "CPU0_SMERR_N")
	)
	(segment
		(start 191.628776 -138.905488)
		(end 192.399412 -139.676124)
		(width 0.11684)
		(layer "In2.Cu")
		(net "CPU0_SMERR_N")
	)
	(segment
		(start 257.34518 -136.500108)
		(end 259.56768 -134.277608)
		(width 0.11684)
		(layer "In2.Cu")
		(net "CPU0_SMERR_N")
	)
	(segment
		(start 456.040998 -183.854598)
		(end 446.238122 -174.051722)
		(width 0.11684)
		(layer "In2.Cu")
		(net "CPU0_SMERR_N")
	)
	(segment
		(start 458.899006 -190.54318)
		(end 456.040998 -187.685172)
		(width 0.11684)
		(layer "In2.Cu")
		(net "CPU0_SMERR_N")
	)
	(segment
		(start 295.384728 -117.150388)
		(end 289.38728 -117.150388)
		(width 0.11684)
		(layer "In2.Cu")
		(net "CPU0_SMERR_N")
	)
	(segment
		(start 393.077954 -324.353174)
		(end 409.68549 -324.353174)
		(width 0.11684)
		(layer "In2.Cu")
		(net "CPU0_SMERR_N")
	)
	(segment
		(start 187.037218 -137.538206)
		(end 190.27013 -137.538206)
		(width 0.11684)
		(layer "In2.Cu")
		(net "CPU0_SMERR_N")
	)
	(segment
		(start 192.399412 -139.676124)
		(end 203.552044 -139.676124)
		(width 0.11684)
		(layer "In2.Cu")
		(net "CPU0_SMERR_N")
	)
	(segment
		(start 411.651958 -322.386706)
		(end 454.706482 -322.386706)
		(width 0.11684)
		(layer "In2.Cu")
		(net "CPU0_SMERR_N")
	)
	(segment
		(start 191.628776 -138.263122)
		(end 191.628776 -138.905488)
		(width 0.11684)
		(layer "In2.Cu")
		(net "CPU0_SMERR_N")
	)
	(segment
		(start 190.27013 -137.538206)
		(end 190.668656 -137.936732)
		(width 0.11684)
		(layer "In2.Cu")
		(net "CPU0_SMERR_N")
	)
	(segment
		(start 454.706482 -322.386706)
		(end 458.899006 -318.194182)
		(width 0.11684)
		(layer "In2.Cu")
		(net "CPU0_SMERR_N")
	)
	(segment
		(start 402.330158 -128.655318)
		(end 354.041456 -128.655318)
		(width 0.11684)
		(layer "In2.Cu")
		(net "CPU0_SMERR_N")
	)
	(segment
		(start 310.017922 -118.68658)
		(end 305.444652 -118.68658)
		(width 0.11684)
		(layer "In2.Cu")
		(net "CPU0_SMERR_N")
	)
	(segment
		(start 289.38728 -117.150388)
		(end 287.61436 -118.923308)
		(width 0.11684)
		(layer "In2.Cu")
		(net "CPU0_SMERR_N")
	)
	(segment
		(start 190.668656 -137.936732)
		(end 191.302386 -137.936732)
		(width 0.11684)
		(layer "In2.Cu")
		(net "CPU0_SMERR_N")
	)
	(segment
		(start 421.231568 -126.674372)
		(end 404.311104 -126.674372)
		(width 0.11684)
		(layer "In2.Cu")
		(net "CPU0_SMERR_N")
	)
	(segment
		(start 354.041456 -128.655318)
		(end 352.353118 -130.343656)
		(width 0.11684)
		(layer "In2.Cu")
		(net "CPU0_SMERR_N")
	)
	(segment
		(start 186.563 -134.183628)
		(end 186.563 -137.063988)
		(width 0.11684)
		(layer "In2.Cu")
		(net "CPU0_SMERR_N")
	)
	(segment
		(start 217.483182 -136.500108)
		(end 257.34518 -136.500108)
		(width 0.11684)
		(layer "In2.Cu")
		(net "CPU0_SMERR_N")
	)
	(segment
		(start 390.847834 -322.123054)
		(end 393.077954 -324.353174)
		(width 0.11684)
		(layer "In2.Cu")
		(net "CPU0_SMERR_N")
	)
	(segment
		(start 442.673486 -162.180016)
		(end 441.836556 -162.180016)
		(width 0.11684)
		(layer "In2.Cu")
		(net "CPU0_SMERR_N")
	)
	(segment
		(start 434.480462 -139.923266)
		(end 421.231568 -126.674372)
		(width 0.11684)
		(layer "In2.Cu")
		(net "CPU0_SMERR_N")
	)
	(segment
		(start 186.055 -130.393948)
		(end 186.055 -133.675628)
		(width 0.11684)
		(layer "In2.Cu")
		(net "CPU0_SMERR_N")
	)
	(segment
		(start 404.311104 -126.674372)
		(end 402.330158 -128.655318)
		(width 0.11684)
		(layer "In2.Cu")
		(net "CPU0_SMERR_N")
	)
	(segment
		(start 203.552044 -139.676124)
		(end 204.37983 -138.848338)
		(width 0.11684)
		(layer "In2.Cu")
		(net "CPU0_SMERR_N")
	)
	(segment
		(start 204.37983 -138.848338)
		(end 215.134952 -138.848338)
		(width 0.11684)
		(layer "In2.Cu")
		(net "CPU0_SMERR_N")
	)
	(segment
		(start 259.56768 -134.277608)
		(end 259.56768 -128.585468)
		(width 0.11684)
		(layer "In2.Cu")
		(net "CPU0_SMERR_N")
	)
	(segment
		(start 434.480462 -154.823922)
		(end 434.480462 -139.923266)
		(width 0.11684)
		(layer "In2.Cu")
		(net "CPU0_SMERR_N")
	)
	(segment
		(start 215.134952 -138.848338)
		(end 217.483182 -136.500108)
		(width 0.11684)
		(layer "In2.Cu")
		(net "CPU0_SMERR_N")
	)
	(segment
		(start 344.530172 -126.126748)
		(end 317.45809 -126.126748)
		(width 0.11684)
		(layer "In2.Cu")
		(net "CPU0_SMERR_N")
	)
	(segment
		(start 348.74708 -130.343656)
		(end 344.530172 -126.126748)
		(width 0.11684)
		(layer "In2.Cu")
		(net "CPU0_SMERR_N")
	)
	(segment
		(start 191.302386 -137.936732)
		(end 191.628776 -138.263122)
		(width 0.11684)
		(layer "In2.Cu")
		(net "CPU0_SMERR_N")
	)
	(segment
		(start 259.56768 -128.585468)
		(end 260.225286 -127.927862)
		(width 0.11684)
		(layer "In2.Cu")
		(net "CPU0_SMERR_N")
	)
	(segment
		(start 260.225286 -127.927862)
		(end 260.225286 -127.042672)
		(width 0.11684)
		(layer "In2.Cu")
		(net "CPU0_SMERR_N")
	)
	(segment
		(start 446.238122 -174.051722)
		(end 446.238122 -165.744652)
		(width 0.11684)
		(layer "In2.Cu")
		(net "CPU0_SMERR_N")
	)
	(segment
		(start 305.444652 -118.68658)
		(end 303.805844 -120.325388)
		(width 0.11684)
		(layer "In2.Cu")
		(net "CPU0_SMERR_N")
	)
	(segment
		(start 456.040998 -187.685172)
		(end 456.040998 -183.854598)
		(width 0.11684)
		(layer "In2.Cu")
		(net "CPU0_SMERR_N")
	)
	(segment
		(start 446.238122 -165.744652)
		(end 442.673486 -162.180016)
		(width 0.11684)
		(layer "In2.Cu")
		(net "CPU0_SMERR_N")
	)
	(segment
		(start 186.055 -133.675628)
		(end 186.563 -134.183628)
		(width 0.11684)
		(layer "In2.Cu")
		(net "CPU0_SMERR_N")
	)
	(segment
		(start 409.68549 -324.353174)
		(end 411.651958 -322.386706)
		(width 0.11684)
		(layer "In2.Cu")
		(net "CPU0_SMERR_N")
	)
	(segment
		(start 317.45809 -126.126748)
		(end 310.017922 -118.68658)
		(width 0.11684)
		(layer "In2.Cu")
		(net "CPU0_SMERR_N")
	)
	(segment
		(start 441.836556 -162.180016)
		(end 434.480462 -154.823922)
		(width 0.11684)
		(layer "In2.Cu")
		(net "CPU0_SMERR_N")
	)
	(segment
		(start 390.847834 -320.237866)
		(end 390.847834 -322.123054)
		(width 0.11684)
		(layer "In2.Cu")
		(net "CPU0_SMERR_N")
	)
	(segment
		(start 298.559728 -120.325388)
		(end 295.384728 -117.150388)
		(width 0.11684)
		(layer "In2.Cu")
		(net "CPU0_SMERR_N")
	)
	(segment
		(start 186.563 -137.063988)
		(end 187.037218 -137.538206)
		(width 0.11684)
		(layer "In2.Cu")
		(net "CPU0_SMERR_N")
	)
	(segment
		(start 391.857738 -318.414908)
		(end 391.857738 -319.227962)
		(width 0.11684)
		(layer "In2.Cu")
		(net "CPU0_SMERR_N")
	)
	(segment
		(start 174.879 -138.907012)
		(end 174.879 -138.032998)
		(width 0.10668)
		(layer "F.Cu")
		(net "CPU0_SLP_S5_N")
	)
	(segment
		(start 404.48865 -320.27241)
		(end 404.48865 -315.9125)
		(width 0.10668)
		(layer "F.Cu")
		(net "CPU0_SLP_S5_N")
	)
	(segment
		(start 393.96797 -313.294522)
		(end 393.831318 -313.15787)
		(width 0.10668)
		(layer "F.Cu")
		(net "CPU0_SLP_S5_N")
	)
	(segment
		(start 177.674778 -141.70279)
		(end 174.879 -138.907012)
		(width 0.10668)
		(layer "F.Cu")
		(net "CPU0_SLP_S5_N")
	)
	(segment
		(start 216.140792 -164.88791)
		(end 216.140792 -162.898582)
		(width 0.10668)
		(layer "F.Cu")
		(net "CPU0_SLP_S5_N")
	)
	(segment
		(start 391.50798 -294.070024)
		(end 391.974832 -294.335962)
		(width 0.10668)
		(layer "F.Cu")
		(net "CPU0_SLP_S5_N")
	)
	(segment
		(start 222.27667 -195.556378)
		(end 222.27667 -171.023788)
		(width 0.10668)
		(layer "F.Cu")
		(net "CPU0_SLP_S5_N")
	)
	(segment
		(start 220.597984 -197.235064)
		(end 222.27667 -195.556378)
		(width 0.10668)
		(layer "F.Cu")
		(net "CPU0_SLP_S5_N")
	)
	(segment
		(start 202.370436 -149.128226)
		(end 187.716668 -143.058388)
		(width 0.10668)
		(layer "F.Cu")
		(net "CPU0_SLP_S5_N")
	)
	(segment
		(start 404.158958 -320.602102)
		(end 404.48865 -320.27241)
		(width 0.10668)
		(layer "F.Cu")
		(net "CPU0_SLP_S5_N")
	)
	(segment
		(start 216.140792 -162.898582)
		(end 202.370436 -149.128226)
		(width 0.10668)
		(layer "F.Cu")
		(net "CPU0_SLP_S5_N")
	)
	(segment
		(start 401.870672 -313.294522)
		(end 393.96797 -313.294522)
		(width 0.10668)
		(layer "F.Cu")
		(net "CPU0_SLP_S5_N")
	)
	(segment
		(start 180.947314 -143.058388)
		(end 177.674778 -141.70279)
		(width 0.10668)
		(layer "F.Cu")
		(net "CPU0_SLP_S5_N")
	)
	(segment
		(start 222.27667 -171.023788)
		(end 216.140792 -164.88791)
		(width 0.10668)
		(layer "F.Cu")
		(net "CPU0_SLP_S5_N")
	)
	(segment
		(start 187.716668 -143.058388)
		(end 180.947314 -143.058388)
		(width 0.10668)
		(layer "F.Cu")
		(net "CPU0_SLP_S5_N")
	)
	(segment
		(start 404.48865 -315.9125)
		(end 401.870672 -313.294522)
		(width 0.10668)
		(layer "F.Cu")
		(net "CPU0_SLP_S5_N")
	)
	(via
		(at 391.974832 -294.335962)
		(size 0.4064)
		(drill 0.2032)
		(layers "F.Cu" "B.Cu")
		(net "CPU0_SLP_S5_N")
	)
	(via
		(at 220.597984 -197.235064)
		(size 0.762)
		(drill 0.254)
		(layers "F.Cu" "B.Cu")
		(net "CPU0_SLP_S5_N")
	)
	(via
		(at 393.831318 -313.15787)
		(size 0.508)
		(drill 0.254)
		(layers "F.Cu" "B.Cu")
		(net "CPU0_SLP_S5_N")
	)
	(via
		(at 388.443724 -299.076872)
		(size 0.508)
		(drill 0.254)
		(layers "F.Cu" "B.Cu")
		(net "CPU0_SLP_S5_N")
	)
	(segment
		(start 389.869426 -293.925244)
		(end 389.859774 -293.930832)
		(width 0.10668)
		(layer "B.Cu")
		(net "CPU0_SLP_S5_N")
	)
	(segment
		(start 387.97992 -293.930832)
		(end 387.977126 -293.93261)
		(width 0.10668)
		(layer "B.Cu")
		(net "CPU0_SLP_S5_N")
	)
	(segment
		(start 387.744716 -294.335962)
		(end 387.744716 -298.377864)
		(width 0.10668)
		(layer "B.Cu")
		(net "CPU0_SLP_S5_N")
	)
	(segment
		(start 391.974832 -294.335962)
		(end 391.269728 -293.930832)
		(width 0.10668)
		(layer "B.Cu")
		(net "CPU0_SLP_S5_N")
	)
	(segment
		(start 387.744716 -298.377864)
		(end 388.443724 -299.076872)
		(width 0.10668)
		(layer "B.Cu")
		(net "CPU0_SLP_S5_N")
	)
	(segment
		(start 389.389874 -293.930832)
		(end 389.380222 -293.925244)
		(width 0.10668)
		(layer "B.Cu")
		(net "CPU0_SLP_S5_N")
	)
	(arc
		(start 389.380222 -293.925244)
		(mid 389.149237 -293.867543)
		(end 388.91972 -293.930832)
		(width 0.10668)
		(layer "B.Cu")
		(net "CPU0_SLP_S5_N")
	)
	(arc
		(start 390.799828 -293.930832)
		(mid 390.564878 -293.994065)
		(end 390.329928 -293.930832)
		(width 0.10668)
		(layer "B.Cu")
		(net "CPU0_SLP_S5_N")
	)
	(arc
		(start 391.269728 -293.930832)
		(mid 391.034778 -293.867633)
		(end 390.799828 -293.930832)
		(width 0.10668)
		(layer "B.Cu")
		(net "CPU0_SLP_S5_N")
	)
	(arc
		(start 389.859774 -293.930832)
		(mid 389.624824 -293.994065)
		(end 389.389874 -293.930832)
		(width 0.10668)
		(layer "B.Cu")
		(net "CPU0_SLP_S5_N")
	)
	(arc
		(start 388.91972 -293.930832)
		(mid 388.68477 -293.994065)
		(end 388.44982 -293.930832)
		(width 0.10668)
		(layer "B.Cu")
		(net "CPU0_SLP_S5_N")
	)
	(arc
		(start 390.329928 -293.930832)
		(mid 390.100411 -293.86754)
		(end 389.869426 -293.925244)
		(width 0.10668)
		(layer "B.Cu")
		(net "CPU0_SLP_S5_N")
	)
	(arc
		(start 387.977126 -293.93261)
		(mid 387.80702 -294.103219)
		(end 387.744716 -294.335962)
		(width 0.10668)
		(layer "B.Cu")
		(net "CPU0_SLP_S5_N")
	)
	(arc
		(start 388.44982 -293.930832)
		(mid 388.21487 -293.867633)
		(end 387.97992 -293.930832)
		(width 0.10668)
		(layer "B.Cu")
		(net "CPU0_SLP_S5_N")
	)
	(segment
		(start 380.864872 -317.086488)
		(end 388.115048 -309.836312)
		(width 0.11684)
		(layer "In2.Cu")
		(net "CPU0_SLP_S5_N")
	)
	(segment
		(start 224.182686 -244.445028)
		(end 232.444798 -252.70714)
		(width 0.11684)
		(layer "In2.Cu")
		(net "CPU0_SLP_S5_N")
	)
	(segment
		(start 255.919224 -269.861284)
		(end 255.919224 -345.277694)
		(width 0.11684)
		(layer "In2.Cu")
		(net "CPU0_SLP_S5_N")
	)
	(segment
		(start 222.06331 -199.930512)
		(end 224.182686 -202.049888)
		(width 0.11684)
		(layer "In2.Cu")
		(net "CPU0_SLP_S5_N")
	)
	(segment
		(start 299.537628 -368.277902)
		(end 301.294546 -370.03482)
		(width 0.11684)
		(layer "In2.Cu")
		(net "CPU0_SLP_S5_N")
	)
	(segment
		(start 282.576016 -366.808512)
		(end 291.782246 -366.808512)
		(width 0.11684)
		(layer "In2.Cu")
		(net "CPU0_SLP_S5_N")
	)
	(segment
		(start 389.234172 -308.10327)
		(end 387.315456 -306.184554)
		(width 0.11684)
		(layer "In2.Cu")
		(net "CPU0_SLP_S5_N")
	)
	(segment
		(start 394.332714 -311.682892)
		(end 390.753092 -308.10327)
		(width 0.11684)
		(layer "In2.Cu")
		(net "CPU0_SLP_S5_N")
	)
	(segment
		(start 390.753092 -308.10327)
		(end 389.234172 -308.10327)
		(width 0.11684)
		(layer "In2.Cu")
		(net "CPU0_SLP_S5_N")
	)
	(segment
		(start 220.597984 -197.235064)
		(end 222.06331 -198.70039)
		(width 0.11684)
		(layer "In2.Cu")
		(net "CPU0_SLP_S5_N")
	)
	(segment
		(start 388.443724 -302.184308)
		(end 388.443724 -299.076872)
		(width 0.11684)
		(layer "In2.Cu")
		(net "CPU0_SLP_S5_N")
	)
	(segment
		(start 393.831318 -313.15787)
		(end 394.332714 -312.656474)
		(width 0.11684)
		(layer "In2.Cu")
		(net "CPU0_SLP_S5_N")
	)
	(segment
		(start 254.949706 -264.985754)
		(end 255.919224 -269.861284)
		(width 0.11684)
		(layer "In2.Cu")
		(net "CPU0_SLP_S5_N")
	)
	(segment
		(start 224.182686 -202.049888)
		(end 224.182686 -244.445028)
		(width 0.11684)
		(layer "In2.Cu")
		(net "CPU0_SLP_S5_N")
	)
	(segment
		(start 394.332714 -312.656474)
		(end 394.332714 -311.682892)
		(width 0.11684)
		(layer "In2.Cu")
		(net "CPU0_SLP_S5_N")
	)
	(segment
		(start 388.115048 -309.836312)
		(end 390.798304 -309.836312)
		(width 0.11684)
		(layer "In2.Cu")
		(net "CPU0_SLP_S5_N")
	)
	(segment
		(start 242.671092 -252.70714)
		(end 254.949706 -264.985754)
		(width 0.11684)
		(layer "In2.Cu")
		(net "CPU0_SLP_S5_N")
	)
	(segment
		(start 274.681442 -358.913938)
		(end 282.576016 -366.808512)
		(width 0.11684)
		(layer "In2.Cu")
		(net "CPU0_SLP_S5_N")
	)
	(segment
		(start 269.555468 -358.913938)
		(end 274.681442 -358.913938)
		(width 0.11684)
		(layer "In2.Cu")
		(net "CPU0_SLP_S5_N")
	)
	(segment
		(start 387.315456 -306.184554)
		(end 387.315456 -303.312576)
		(width 0.11684)
		(layer "In2.Cu")
		(net "CPU0_SLP_S5_N")
	)
	(segment
		(start 301.294546 -370.03482)
		(end 317.99657 -370.03482)
		(width 0.11684)
		(layer "In2.Cu")
		(net "CPU0_SLP_S5_N")
	)
	(segment
		(start 291.782246 -366.808512)
		(end 293.251636 -368.277902)
		(width 0.11684)
		(layer "In2.Cu")
		(net "CPU0_SLP_S5_N")
	)
	(segment
		(start 255.919224 -345.277694)
		(end 269.555468 -358.913938)
		(width 0.11684)
		(layer "In2.Cu")
		(net "CPU0_SLP_S5_N")
	)
	(segment
		(start 387.315456 -303.312576)
		(end 388.443724 -302.184308)
		(width 0.11684)
		(layer "In2.Cu")
		(net "CPU0_SLP_S5_N")
	)
	(segment
		(start 380.864872 -334.85074)
		(end 380.864872 -317.086488)
		(width 0.11684)
		(layer "In2.Cu")
		(net "CPU0_SLP_S5_N")
	)
	(segment
		(start 293.251636 -368.277902)
		(end 299.537628 -368.277902)
		(width 0.11684)
		(layer "In2.Cu")
		(net "CPU0_SLP_S5_N")
	)
	(segment
		(start 390.798304 -309.836312)
		(end 393.831318 -312.869326)
		(width 0.11684)
		(layer "In2.Cu")
		(net "CPU0_SLP_S5_N")
	)
	(segment
		(start 232.444798 -252.70714)
		(end 242.671092 -252.70714)
		(width 0.11684)
		(layer "In2.Cu")
		(net "CPU0_SLP_S5_N")
	)
	(segment
		(start 222.06331 -198.70039)
		(end 222.06331 -199.930512)
		(width 0.11684)
		(layer "In2.Cu")
		(net "CPU0_SLP_S5_N")
	)
	(segment
		(start 351.697544 -364.018068)
		(end 380.864872 -334.85074)
		(width 0.11684)
		(layer "In2.Cu")
		(net "CPU0_SLP_S5_N")
	)
	(segment
		(start 393.831318 -312.869326)
		(end 393.831318 -313.15787)
		(width 0.11684)
		(layer "In2.Cu")
		(net "CPU0_SLP_S5_N")
	)
	(segment
		(start 317.99657 -370.03482)
		(end 351.697544 -364.018068)
		(width 0.11684)
		(layer "In2.Cu")
		(net "CPU0_SLP_S5_N")
	)
	(segment
		(start 202.39863 -148.730716)
		(end 187.85586 -142.707106)
		(width 0.10668)
		(layer "F.Cu")
		(net "CPU0_SLP_S3_N")
	)
	(segment
		(start 401.625816 -319.08496)
		(end 403.142958 -320.602102)
		(width 0.10668)
		(layer "F.Cu")
		(net "CPU0_SLP_S3_N")
	)
	(segment
		(start 393.246864 -312.49493)
		(end 393.246864 -313.589924)
		(width 0.10668)
		(layer "F.Cu")
		(net "CPU0_SLP_S3_N")
	)
	(segment
		(start 396.26286 -319.08496)
		(end 401.625816 -319.08496)
		(width 0.10668)
		(layer "F.Cu")
		(net "CPU0_SLP_S3_N")
	)
	(segment
		(start 181.102762 -142.707106)
		(end 178.0667 -141.449552)
		(width 0.10668)
		(layer "F.Cu")
		(net "CPU0_SLP_S3_N")
	)
	(segment
		(start 175.659034 -139.041886)
		(end 175.659034 -130.423158)
		(width 0.10668)
		(layer "F.Cu")
		(net "CPU0_SLP_S3_N")
	)
	(segment
		(start 216.518998 -164.739828)
		(end 216.518998 -162.851084)
		(width 0.10668)
		(layer "F.Cu")
		(net "CPU0_SLP_S3_N")
	)
	(segment
		(start 393.246864 -313.589924)
		(end 393.28344 -313.6265)
		(width 0.10668)
		(layer "F.Cu")
		(net "CPU0_SLP_S3_N")
	)
	(segment
		(start 394.18387 -313.6265)
		(end 394.563092 -314.005722)
		(width 0.10668)
		(layer "F.Cu")
		(net "CPU0_SLP_S3_N")
	)
	(segment
		(start 394.563092 -314.005722)
		(end 394.563092 -314.85332)
		(width 0.10668)
		(layer "F.Cu")
		(net "CPU0_SLP_S3_N")
	)
	(segment
		(start 394.267182 -317.089282)
		(end 396.26286 -319.08496)
		(width 0.10668)
		(layer "F.Cu")
		(net "CPU0_SLP_S3_N")
	)
	(segment
		(start 388.121144 -298.60494)
		(end 388.121144 -298.605448)
		(width 0.10668)
		(layer "F.Cu")
		(net "CPU0_SLP_S3_N")
	)
	(segment
		(start 386.368798 -310.852312)
		(end 391.604246 -310.852312)
		(width 0.10668)
		(layer "F.Cu")
		(net "CPU0_SLP_S3_N")
	)
	(segment
		(start 390.567926 -295.690036)
		(end 390.567926 -296.158158)
		(width 0.10668)
		(layer "F.Cu")
		(net "CPU0_SLP_S3_N")
	)
	(segment
		(start 391.604246 -310.852312)
		(end 393.246864 -312.49493)
		(width 0.10668)
		(layer "F.Cu")
		(net "CPU0_SLP_S3_N")
	)
	(segment
		(start 388.121144 -298.605448)
		(end 384.636772 -302.08982)
		(width 0.10668)
		(layer "F.Cu")
		(net "CPU0_SLP_S3_N")
	)
	(segment
		(start 221.130114 -199.500998)
		(end 221.130114 -198.043546)
		(width 0.10668)
		(layer "F.Cu")
		(net "CPU0_SLP_S3_N")
	)
	(segment
		(start 393.28344 -313.6265)
		(end 394.18387 -313.6265)
		(width 0.10668)
		(layer "F.Cu")
		(net "CPU0_SLP_S3_N")
	)
	(segment
		(start 221.130114 -198.043546)
		(end 222.56115 -196.61251)
		(width 0.10668)
		(layer "F.Cu")
		(net "CPU0_SLP_S3_N")
	)
	(segment
		(start 175.895 -130.187192)
		(end 175.895 -129.777998)
		(width 0.10668)
		(layer "F.Cu")
		(net "CPU0_SLP_S3_N")
	)
	(segment
		(start 187.85586 -142.707106)
		(end 181.102762 -142.707106)
		(width 0.10668)
		(layer "F.Cu")
		(net "CPU0_SLP_S3_N")
	)
	(segment
		(start 384.636772 -302.08982)
		(end 384.636772 -309.120286)
		(width 0.10668)
		(layer "F.Cu")
		(net "CPU0_SLP_S3_N")
	)
	(segment
		(start 390.567926 -296.158158)
		(end 388.121144 -298.60494)
		(width 0.10668)
		(layer "F.Cu")
		(net "CPU0_SLP_S3_N")
	)
	(segment
		(start 394.563092 -314.85332)
		(end 394.267182 -315.14923)
		(width 0.10668)
		(layer "F.Cu")
		(net "CPU0_SLP_S3_N")
	)
	(segment
		(start 216.518998 -162.851084)
		(end 202.39863 -148.730716)
		(width 0.10668)
		(layer "F.Cu")
		(net "CPU0_SLP_S3_N")
	)
	(segment
		(start 384.636772 -309.120286)
		(end 386.368798 -310.852312)
		(width 0.10668)
		(layer "F.Cu")
		(net "CPU0_SLP_S3_N")
	)
	(segment
		(start 178.0667 -141.449552)
		(end 175.659034 -139.041886)
		(width 0.10668)
		(layer "F.Cu")
		(net "CPU0_SLP_S3_N")
	)
	(segment
		(start 394.267182 -315.14923)
		(end 394.267182 -317.089282)
		(width 0.10668)
		(layer "F.Cu")
		(net "CPU0_SLP_S3_N")
	)
	(segment
		(start 222.56115 -196.61251)
		(end 222.56115 -170.78198)
		(width 0.10668)
		(layer "F.Cu")
		(net "CPU0_SLP_S3_N")
	)
	(segment
		(start 175.659034 -130.423158)
		(end 175.895 -130.187192)
		(width 0.10668)
		(layer "F.Cu")
		(net "CPU0_SLP_S3_N")
	)
	(segment
		(start 222.56115 -170.78198)
		(end 216.518998 -164.739828)
		(width 0.10668)
		(layer "F.Cu")
		(net "CPU0_SLP_S3_N")
	)
	(via
		(at 393.28344 -313.6265)
		(size 0.508)
		(drill 0.254)
		(layers "F.Cu" "B.Cu")
		(net "CPU0_SLP_S3_N")
	)
	(via
		(at 221.130114 -199.500998)
		(size 0.508)
		(drill 0.254)
		(layers "F.Cu" "B.Cu")
		(net "CPU0_SLP_S3_N")
	)
	(segment
		(start 274.572984 -359.402126)
		(end 269.334996 -359.402126)
		(width 0.11684)
		(layer "In2.Cu")
		(net "CPU0_SLP_S3_N")
	)
	(segment
		(start 391.970514 -311.845198)
		(end 390.619996 -310.49468)
		(width 0.11684)
		(layer "In2.Cu")
		(net "CPU0_SLP_S3_N")
	)
	(segment
		(start 381.286512 -317.3349)
		(end 381.286512 -335.02854)
		(width 0.11684)
		(layer "In2.Cu")
		(net "CPU0_SLP_S3_N")
	)
	(segment
		(start 254.889 -344.95613)
		(end 254.889 -330.214986)
		(width 0.11684)
		(layer "In2.Cu")
		(net "CPU0_SLP_S3_N")
	)
	(segment
		(start 299.484542 -368.821462)
		(end 292.189154 -368.821462)
		(width 0.11684)
		(layer "In2.Cu")
		(net "CPU0_SLP_S3_N")
	)
	(segment
		(start 223.761046 -202.447652)
		(end 221.130114 -199.81672)
		(width 0.11684)
		(layer "In2.Cu")
		(net "CPU0_SLP_S3_N")
	)
	(segment
		(start 393.28344 -313.6265)
		(end 391.970514 -312.313574)
		(width 0.11684)
		(layer "In2.Cu")
		(net "CPU0_SLP_S3_N")
	)
	(segment
		(start 221.130114 -199.81672)
		(end 221.130114 -199.500998)
		(width 0.11684)
		(layer "In2.Cu")
		(net "CPU0_SLP_S3_N")
	)
	(segment
		(start 269.334996 -359.402126)
		(end 254.889 -344.95613)
		(width 0.11684)
		(layer "In2.Cu")
		(net "CPU0_SLP_S3_N")
	)
	(segment
		(start 351.550224 -364.764828)
		(end 319.662048 -370.45646)
		(width 0.11684)
		(layer "In2.Cu")
		(net "CPU0_SLP_S3_N")
	)
	(segment
		(start 292.189154 -368.821462)
		(end 290.700714 -367.333022)
		(width 0.11684)
		(layer "In2.Cu")
		(net "CPU0_SLP_S3_N")
	)
	(segment
		(start 254.889 -330.214986)
		(end 255.467612 -329.636374)
		(width 0.11684)
		(layer "In2.Cu")
		(net "CPU0_SLP_S3_N")
	)
	(segment
		(start 290.700714 -367.333022)
		(end 282.50388 -367.333022)
		(width 0.11684)
		(layer "In2.Cu")
		(net "CPU0_SLP_S3_N")
	)
	(segment
		(start 242.450874 -253.242318)
		(end 232.383584 -253.242318)
		(width 0.11684)
		(layer "In2.Cu")
		(net "CPU0_SLP_S3_N")
	)
	(segment
		(start 255.467612 -269.753334)
		(end 254.599694 -265.391138)
		(width 0.11684)
		(layer "In2.Cu")
		(net "CPU0_SLP_S3_N")
	)
	(segment
		(start 388.126732 -310.49468)
		(end 381.286512 -317.3349)
		(width 0.11684)
		(layer "In2.Cu")
		(net "CPU0_SLP_S3_N")
	)
	(segment
		(start 390.619996 -310.49468)
		(end 388.126732 -310.49468)
		(width 0.11684)
		(layer "In2.Cu")
		(net "CPU0_SLP_S3_N")
	)
	(segment
		(start 255.467612 -329.636374)
		(end 255.467612 -269.753334)
		(width 0.11684)
		(layer "In2.Cu")
		(net "CPU0_SLP_S3_N")
	)
	(segment
		(start 301.11954 -370.45646)
		(end 299.484542 -368.821462)
		(width 0.11684)
		(layer "In2.Cu")
		(net "CPU0_SLP_S3_N")
	)
	(segment
		(start 254.599694 -265.391138)
		(end 242.450874 -253.242318)
		(width 0.11684)
		(layer "In2.Cu")
		(net "CPU0_SLP_S3_N")
	)
	(segment
		(start 223.761046 -244.61978)
		(end 223.761046 -202.447652)
		(width 0.11684)
		(layer "In2.Cu")
		(net "CPU0_SLP_S3_N")
	)
	(segment
		(start 232.383584 -253.242318)
		(end 223.761046 -244.61978)
		(width 0.11684)
		(layer "In2.Cu")
		(net "CPU0_SLP_S3_N")
	)
	(segment
		(start 282.50388 -367.333022)
		(end 274.572984 -359.402126)
		(width 0.11684)
		(layer "In2.Cu")
		(net "CPU0_SLP_S3_N")
	)
	(segment
		(start 391.970514 -312.313574)
		(end 391.970514 -311.845198)
		(width 0.11684)
		(layer "In2.Cu")
		(net "CPU0_SLP_S3_N")
	)
	(segment
		(start 319.662048 -370.45646)
		(end 301.11954 -370.45646)
		(width 0.11684)
		(layer "In2.Cu")
		(net "CPU0_SLP_S3_N")
	)
	(segment
		(start 381.286512 -335.02854)
		(end 351.550224 -364.764828)
		(width 0.11684)
		(layer "In2.Cu")
		(net "CPU0_SLP_S3_N")
	)
	(segment
		(start 263.342628 -148.372068)
		(end 263.342628 -184.988708)
		(width 0.10668)
		(layer "F.Cu")
		(net "CPU0_SA1")
	)
	(segment
		(start 343.56802 -295.690036)
		(end 342.77173 -296.486326)
		(width 0.10668)
		(layer "F.Cu")
		(net "CPU0_SA1")
	)
	(segment
		(start 339.355938 -296.486326)
		(end 337.065366 -298.776898)
		(width 0.10668)
		(layer "F.Cu")
		(net "CPU0_SA1")
	)
	(segment
		(start 262.314944 -186.016392)
		(end 262.314944 -186.77128)
		(width 0.10668)
		(layer "F.Cu")
		(net "CPU0_SA1")
	)
	(segment
		(start 264.859262 -146.855434)
		(end 263.342628 -148.372068)
		(width 0.10668)
		(layer "F.Cu")
		(net "CPU0_SA1")
	)
	(segment
		(start 266.955778 -142.820898)
		(end 264.859262 -144.917414)
		(width 0.10668)
		(layer "F.Cu")
		(net "CPU0_SA1")
	)
	(segment
		(start 264.022332 -112.991138)
		(end 264.022332 -125.457458)
		(width 0.10668)
		(layer "F.Cu")
		(net "CPU0_SA1")
	)
	(segment
		(start 263.90981 -112.878616)
		(end 264.022332 -112.991138)
		(width 0.10668)
		(layer "F.Cu")
		(net "CPU0_SA1")
	)
	(segment
		(start 337.065366 -298.776898)
		(end 337.065366 -306.524152)
		(width 0.10668)
		(layer "F.Cu")
		(net "CPU0_SA1")
	)
	(segment
		(start 264.859262 -144.917414)
		(end 264.859262 -146.855434)
		(width 0.10668)
		(layer "F.Cu")
		(net "CPU0_SA1")
	)
	(segment
		(start 342.77173 -296.486326)
		(end 339.355938 -296.486326)
		(width 0.10668)
		(layer "F.Cu")
		(net "CPU0_SA1")
	)
	(segment
		(start 264.022332 -125.457458)
		(end 266.955778 -128.390904)
		(width 0.10668)
		(layer "F.Cu")
		(net "CPU0_SA1")
	)
	(segment
		(start 266.955778 -128.390904)
		(end 266.955778 -142.820898)
		(width 0.10668)
		(layer "F.Cu")
		(net "CPU0_SA1")
	)
	(segment
		(start 263.342628 -184.988708)
		(end 262.314944 -186.016392)
		(width 0.10668)
		(layer "F.Cu")
		(net "CPU0_SA1")
	)
	(via
		(at 189.865 -99.278948)
		(size 0.508)
		(drill 0.254)
		(layers "F.Cu" "B.Cu")
		(net "CPU0_SA1")
	)
	(via
		(at 263.90981 -112.878616)
		(size 0.762)
		(drill 0.254)
		(layers "F.Cu" "B.Cu")
		(net "CPU0_SA1")
	)
	(via
		(at 337.065366 -306.524152)
		(size 0.508)
		(drill 0.254)
		(layers "F.Cu" "B.Cu")
		(net "CPU0_SA1")
	)
	(via
		(at 262.314944 -186.77128)
		(size 0.508)
		(drill 0.254)
		(layers "F.Cu" "B.Cu")
		(net "CPU0_SA1")
	)
	(segment
		(start 306.724812 -319.168018)
		(end 307.69052 -319.168018)
		(width 0.10668)
		(layer "B.Cu")
		(net "CPU0_SA1")
	)
	(segment
		(start 262.286242 -325.638668)
		(end 299.497496 -325.638668)
		(width 0.10668)
		(layer "B.Cu")
		(net "CPU0_SA1")
	)
	(segment
		(start 337.687158 -308.528974)
		(end 337.687158 -308.813962)
		(width 0.10668)
		(layer "B.Cu")
		(net "CPU0_SA1")
	)
	(segment
		(start 299.497496 -325.638668)
		(end 303.234344 -321.90182)
		(width 0.10668)
		(layer "B.Cu")
		(net "CPU0_SA1")
	)
	(segment
		(start 253.025148 -216.613994)
		(end 258.994148 -222.582994)
		(width 0.10668)
		(layer "B.Cu")
		(net "CPU0_SA1")
	)
	(segment
		(start 256.985262 -187.857892)
		(end 253.025148 -191.818006)
		(width 0.10668)
		(layer "B.Cu")
		(net "CPU0_SA1")
	)
	(segment
		(start 303.234344 -321.90182)
		(end 303.99101 -321.90182)
		(width 0.10668)
		(layer "B.Cu")
		(net "CPU0_SA1")
	)
	(segment
		(start 262.314944 -186.77128)
		(end 262.314944 -187.730892)
		(width 0.10668)
		(layer "B.Cu")
		(net "CPU0_SA1")
	)
	(segment
		(start 303.99101 -321.90182)
		(end 306.724812 -319.168018)
		(width 0.10668)
		(layer "B.Cu")
		(net "CPU0_SA1")
	)
	(segment
		(start 253.025148 -191.818006)
		(end 253.025148 -216.613994)
		(width 0.10668)
		(layer "B.Cu")
		(net "CPU0_SA1")
	)
	(segment
		(start 189.865 -99.894898)
		(end 189.865 -99.278948)
		(width 0.10668)
		(layer "B.Cu")
		(net "CPU0_SA1")
	)
	(segment
		(start 258.994148 -222.582994)
		(end 258.994148 -322.346574)
		(width 0.10668)
		(layer "B.Cu")
		(net "CPU0_SA1")
	)
	(segment
		(start 262.187944 -187.857892)
		(end 256.985262 -187.857892)
		(width 0.10668)
		(layer "B.Cu")
		(net "CPU0_SA1")
	)
	(segment
		(start 335.932018 -306.524152)
		(end 337.065366 -306.524152)
		(width 0.10668)
		(layer "B.Cu")
		(net "CPU0_SA1")
	)
	(segment
		(start 262.314944 -187.730892)
		(end 262.187944 -187.857892)
		(width 0.10668)
		(layer "B.Cu")
		(net "CPU0_SA1")
	)
	(segment
		(start 315.905896 -310.952642)
		(end 331.503528 -310.952642)
		(width 0.10668)
		(layer "B.Cu")
		(net "CPU0_SA1")
	)
	(segment
		(start 258.994148 -322.346574)
		(end 262.286242 -325.638668)
		(width 0.10668)
		(layer "B.Cu")
		(net "CPU0_SA1")
	)
	(segment
		(start 307.69052 -319.168018)
		(end 315.905896 -310.952642)
		(width 0.10668)
		(layer "B.Cu")
		(net "CPU0_SA1")
	)
	(segment
		(start 337.065366 -307.907182)
		(end 337.687158 -308.528974)
		(width 0.10668)
		(layer "B.Cu")
		(net "CPU0_SA1")
	)
	(segment
		(start 331.503528 -310.952642)
		(end 335.932018 -306.524152)
		(width 0.10668)
		(layer "B.Cu")
		(net "CPU0_SA1")
	)
	(segment
		(start 337.065366 -306.524152)
		(end 337.065366 -307.907182)
		(width 0.10668)
		(layer "B.Cu")
		(net "CPU0_SA1")
	)
	(segment
		(start 191.421766 -99.395788)
		(end 191.421766 -98.080576)
		(width 0.11684)
		(layer "In2.Cu")
		(net "CPU0_SA1")
	)
	(segment
		(start 213.918292 -98.542602)
		(end 215.245188 -99.869498)
		(width 0.11684)
		(layer "In2.Cu")
		(net "CPU0_SA1")
	)
	(segment
		(start 215.245188 -99.869498)
		(end 219.45854 -99.869498)
		(width 0.11684)
		(layer "In2.Cu")
		(net "CPU0_SA1")
	)
	(segment
		(start 228.191568 -108.602526)
		(end 258.889754 -108.602526)
		(width 0.11684)
		(layer "In2.Cu")
		(net "CPU0_SA1")
	)
	(segment
		(start 210.623658 -98.336862)
		(end 212.702648 -98.336862)
		(width 0.11684)
		(layer "In2.Cu")
		(net "CPU0_SA1")
	)
	(segment
		(start 200.787254 -97.273364)
		(end 202.167998 -95.89262)
		(width 0.11684)
		(layer "In2.Cu")
		(net "CPU0_SA1")
	)
	(segment
		(start 259.174996 -108.887768)
		(end 260.358382 -108.887768)
		(width 0.11684)
		(layer "In2.Cu")
		(net "CPU0_SA1")
	)
	(segment
		(start 191.073786 -99.743768)
		(end 191.421766 -99.395788)
		(width 0.11684)
		(layer "In2.Cu")
		(net "CPU0_SA1")
	)
	(segment
		(start 263.90981 -112.439196)
		(end 263.90981 -112.878616)
		(width 0.11684)
		(layer "In2.Cu")
		(net "CPU0_SA1")
	)
	(segment
		(start 189.865 -99.278948)
		(end 190.32982 -99.743768)
		(width 0.11684)
		(layer "In2.Cu")
		(net "CPU0_SA1")
	)
	(segment
		(start 208.179416 -95.89262)
		(end 210.623658 -98.336862)
		(width 0.11684)
		(layer "In2.Cu")
		(net "CPU0_SA1")
	)
	(segment
		(start 219.45854 -99.869498)
		(end 228.191568 -108.602526)
		(width 0.11684)
		(layer "In2.Cu")
		(net "CPU0_SA1")
	)
	(segment
		(start 191.421766 -98.080576)
		(end 192.228978 -97.273364)
		(width 0.11684)
		(layer "In2.Cu")
		(net "CPU0_SA1")
	)
	(segment
		(start 190.32982 -99.743768)
		(end 191.073786 -99.743768)
		(width 0.11684)
		(layer "In2.Cu")
		(net "CPU0_SA1")
	)
	(segment
		(start 192.228978 -97.273364)
		(end 200.787254 -97.273364)
		(width 0.11684)
		(layer "In2.Cu")
		(net "CPU0_SA1")
	)
	(segment
		(start 212.702648 -98.336862)
		(end 212.908388 -98.542602)
		(width 0.11684)
		(layer "In2.Cu")
		(net "CPU0_SA1")
	)
	(segment
		(start 260.358382 -108.887768)
		(end 263.90981 -112.439196)
		(width 0.11684)
		(layer "In2.Cu")
		(net "CPU0_SA1")
	)
	(segment
		(start 202.167998 -95.89262)
		(end 208.179416 -95.89262)
		(width 0.11684)
		(layer "In2.Cu")
		(net "CPU0_SA1")
	)
	(segment
		(start 258.889754 -108.602526)
		(end 259.174996 -108.887768)
		(width 0.11684)
		(layer "In2.Cu")
		(net "CPU0_SA1")
	)
	(segment
		(start 212.908388 -98.542602)
		(end 213.918292 -98.542602)
		(width 0.11684)
		(layer "In2.Cu")
		(net "CPU0_SA1")
	)
	(segment
		(start 265.195304 -144.995392)
		(end 265.195304 -146.978116)
		(width 0.10668)
		(layer "F.Cu")
		(net "CPU0_SA0")
	)
	(segment
		(start 337.563968 -298.680886)
		(end 337.563968 -307.286152)
		(width 0.10668)
		(layer "F.Cu")
		(net "CPU0_SA0")
	)
	(segment
		(start 339.535008 -296.709846)
		(end 337.563968 -298.680886)
		(width 0.10668)
		(layer "F.Cu")
		(net "CPU0_SA0")
	)
	(segment
		(start 343.488264 -296.709846)
		(end 339.535008 -296.709846)
		(width 0.10668)
		(layer "F.Cu")
		(net "CPU0_SA0")
	)
	(segment
		(start 263.639554 -148.533866)
		(end 263.639554 -185.337704)
		(width 0.10668)
		(layer "F.Cu")
		(net "CPU0_SA0")
	)
	(segment
		(start 264.506202 -125.475492)
		(end 267.24102 -128.21031)
		(width 0.10668)
		(layer "F.Cu")
		(net "CPU0_SA0")
	)
	(segment
		(start 263.639554 -185.337704)
		(end 262.958326 -186.018932)
		(width 0.10668)
		(layer "F.Cu")
		(net "CPU0_SA0")
	)
	(segment
		(start 264.506202 -113.044224)
		(end 264.506202 -125.475492)
		(width 0.10668)
		(layer "F.Cu")
		(net "CPU0_SA0")
	)
	(segment
		(start 267.24102 -128.21031)
		(end 267.24102 -142.949676)
		(width 0.10668)
		(layer "F.Cu")
		(net "CPU0_SA0")
	)
	(segment
		(start 344.508074 -295.690036)
		(end 343.488264 -296.709846)
		(width 0.10668)
		(layer "F.Cu")
		(net "CPU0_SA0")
	)
	(segment
		(start 262.958326 -186.018932)
		(end 262.958326 -186.810396)
		(width 0.10668)
		(layer "F.Cu")
		(net "CPU0_SA0")
	)
	(segment
		(start 264.67181 -112.878616)
		(end 264.506202 -113.044224)
		(width 0.10668)
		(layer "F.Cu")
		(net "CPU0_SA0")
	)
	(segment
		(start 267.24102 -142.949676)
		(end 265.195304 -144.995392)
		(width 0.10668)
		(layer "F.Cu")
		(net "CPU0_SA0")
	)
	(segment
		(start 265.195304 -146.978116)
		(end 263.639554 -148.533866)
		(width 0.10668)
		(layer "F.Cu")
		(net "CPU0_SA0")
	)
	(via
		(at 262.958326 -186.810396)
		(size 0.508)
		(drill 0.254)
		(layers "F.Cu" "B.Cu")
		(net "CPU0_SA0")
	)
	(via
		(at 337.563968 -307.286152)
		(size 0.508)
		(drill 0.254)
		(layers "F.Cu" "B.Cu")
		(net "CPU0_SA0")
	)
	(via
		(at 191.897 -98.262948)
		(size 0.508)
		(drill 0.254)
		(layers "F.Cu" "B.Cu")
		(net "CPU0_SA0")
	)
	(via
		(at 264.67181 -112.878616)
		(size 0.508)
		(drill 0.254)
		(layers "F.Cu" "B.Cu")
		(net "CPU0_SA0")
	)
	(segment
		(start 191.897 -98.389948)
		(end 191.897 -98.262948)
		(width 0.10668)
		(layer "B.Cu")
		(net "CPU0_SA0")
	)
	(segment
		(start 192.405 -98.897948)
		(end 191.897 -98.389948)
		(width 0.10668)
		(layer "B.Cu")
		(net "CPU0_SA0")
	)
	(segment
		(start 259.382514 -222.421958)
		(end 253.413514 -216.452958)
		(width 0.10668)
		(layer "B.Cu")
		(net "CPU0_SA0")
	)
	(segment
		(start 301.1297 -323.389244)
		(end 260.58622 -323.389244)
		(width 0.10668)
		(layer "B.Cu")
		(net "CPU0_SA0")
	)
	(segment
		(start 315.78804 -310.668162)
		(end 307.572664 -318.883538)
		(width 0.10668)
		(layer "B.Cu")
		(net "CPU0_SA0")
	)
	(segment
		(start 192.913 -99.894898)
		(end 192.512696 -99.894898)
		(width 0.10668)
		(layer "B.Cu")
		(net "CPU0_SA0")
	)
	(segment
		(start 259.382514 -322.185538)
		(end 259.382514 -222.421958)
		(width 0.10668)
		(layer "B.Cu")
		(net "CPU0_SA0")
	)
	(segment
		(start 253.413514 -191.979042)
		(end 257.146298 -188.246258)
		(width 0.10668)
		(layer "B.Cu")
		(net "CPU0_SA0")
	)
	(segment
		(start 338.511388 -308.813962)
		(end 338.830158 -308.813962)
		(width 0.10668)
		(layer "B.Cu")
		(net "CPU0_SA0")
	)
	(segment
		(start 306.45989 -318.883538)
		(end 303.948592 -321.394836)
		(width 0.10668)
		(layer "B.Cu")
		(net "CPU0_SA0")
	)
	(segment
		(start 303.948592 -321.394836)
		(end 303.124108 -321.394836)
		(width 0.10668)
		(layer "B.Cu")
		(net "CPU0_SA0")
	)
	(segment
		(start 339.846158 -308.813962)
		(end 338.830158 -308.813962)
		(width 0.10668)
		(layer "B.Cu")
		(net "CPU0_SA0")
	)
	(segment
		(start 307.572664 -318.883538)
		(end 306.45989 -318.883538)
		(width 0.10668)
		(layer "B.Cu")
		(net "CPU0_SA0")
	)
	(segment
		(start 262.958326 -188.119258)
		(end 262.958326 -186.810396)
		(width 0.10668)
		(layer "B.Cu")
		(net "CPU0_SA0")
	)
	(segment
		(start 303.124108 -321.394836)
		(end 301.1297 -323.389244)
		(width 0.10668)
		(layer "B.Cu")
		(net "CPU0_SA0")
	)
	(segment
		(start 337.563968 -306.25415)
		(end 337.365848 -306.05603)
		(width 0.10668)
		(layer "B.Cu")
		(net "CPU0_SA0")
	)
	(segment
		(start 262.831326 -188.246258)
		(end 262.958326 -188.119258)
		(width 0.10668)
		(layer "B.Cu")
		(net "CPU0_SA0")
	)
	(segment
		(start 253.413514 -216.452958)
		(end 253.413514 -191.979042)
		(width 0.10668)
		(layer "B.Cu")
		(net "CPU0_SA0")
	)
	(segment
		(start 337.563968 -307.286152)
		(end 337.563968 -306.25415)
		(width 0.10668)
		(layer "B.Cu")
		(net "CPU0_SA0")
	)
	(segment
		(start 192.405 -99.787202)
		(end 192.405 -98.897948)
		(width 0.10668)
		(layer "B.Cu")
		(net "CPU0_SA0")
	)
	(segment
		(start 337.563968 -307.866542)
		(end 338.511388 -308.813962)
		(width 0.10668)
		(layer "B.Cu")
		(net "CPU0_SA0")
	)
	(segment
		(start 331.208634 -310.668162)
		(end 315.78804 -310.668162)
		(width 0.10668)
		(layer "B.Cu")
		(net "CPU0_SA0")
	)
	(segment
		(start 337.365848 -306.05603)
		(end 335.820766 -306.05603)
		(width 0.10668)
		(layer "B.Cu")
		(net "CPU0_SA0")
	)
	(segment
		(start 260.58622 -323.389244)
		(end 259.382514 -322.185538)
		(width 0.10668)
		(layer "B.Cu")
		(net "CPU0_SA0")
	)
	(segment
		(start 335.820766 -306.05603)
		(end 331.208634 -310.668162)
		(width 0.10668)
		(layer "B.Cu")
		(net "CPU0_SA0")
	)
	(segment
		(start 257.146298 -188.246258)
		(end 262.831326 -188.246258)
		(width 0.10668)
		(layer "B.Cu")
		(net "CPU0_SA0")
	)
	(segment
		(start 337.563968 -307.286152)
		(end 337.563968 -307.866542)
		(width 0.10668)
		(layer "B.Cu")
		(net "CPU0_SA0")
	)
	(segment
		(start 192.512696 -99.894898)
		(end 192.405 -99.787202)
		(width 0.10668)
		(layer "B.Cu")
		(net "CPU0_SA0")
	)
	(segment
		(start 264.20699 -113.343436)
		(end 264.67181 -112.878616)
		(width 0.11684)
		(layer "In2.Cu")
		(net "CPU0_SA0")
	)
	(segment
		(start 258.65963 -109.051344)
		(end 258.965954 -109.357668)
		(width 0.11684)
		(layer "In2.Cu")
		(net "CPU0_SA0")
	)
	(segment
		(start 201.36231 -97.2947)
		(end 204.089254 -97.2947)
		(width 0.11684)
		(layer "In2.Cu")
		(net "CPU0_SA0")
	)
	(segment
		(start 192.46469 -97.695258)
		(end 200.961752 -97.695258)
		(width 0.11684)
		(layer "In2.Cu")
		(net "CPU0_SA0")
	)
	(segment
		(start 263.717024 -113.343436)
		(end 264.20699 -113.343436)
		(width 0.11684)
		(layer "In2.Cu")
		(net "CPU0_SA0")
	)
	(segment
		(start 208.004664 -96.31426)
		(end 210.448906 -98.758502)
		(width 0.11684)
		(layer "In2.Cu")
		(net "CPU0_SA0")
	)
	(segment
		(start 204.089254 -97.2947)
		(end 205.069694 -96.31426)
		(width 0.11684)
		(layer "In2.Cu")
		(net "CPU0_SA0")
	)
	(segment
		(start 205.069694 -96.31426)
		(end 208.004664 -96.31426)
		(width 0.11684)
		(layer "In2.Cu")
		(net "CPU0_SA0")
	)
	(segment
		(start 260.001004 -109.357668)
		(end 263.444228 -112.800892)
		(width 0.11684)
		(layer "In2.Cu")
		(net "CPU0_SA0")
	)
	(segment
		(start 214.17153 -100.291138)
		(end 219.283788 -100.291138)
		(width 0.11684)
		(layer "In2.Cu")
		(net "CPU0_SA0")
	)
	(segment
		(start 212.527896 -98.758502)
		(end 212.733636 -98.964242)
		(width 0.11684)
		(layer "In2.Cu")
		(net "CPU0_SA0")
	)
	(segment
		(start 228.043994 -109.051344)
		(end 258.65963 -109.051344)
		(width 0.11684)
		(layer "In2.Cu")
		(net "CPU0_SA0")
	)
	(segment
		(start 200.961752 -97.695258)
		(end 201.36231 -97.2947)
		(width 0.11684)
		(layer "In2.Cu")
		(net "CPU0_SA0")
	)
	(segment
		(start 212.844634 -98.964242)
		(end 214.17153 -100.291138)
		(width 0.11684)
		(layer "In2.Cu")
		(net "CPU0_SA0")
	)
	(segment
		(start 210.448906 -98.758502)
		(end 212.527896 -98.758502)
		(width 0.11684)
		(layer "In2.Cu")
		(net "CPU0_SA0")
	)
	(segment
		(start 191.897 -98.262948)
		(end 192.46469 -97.695258)
		(width 0.11684)
		(layer "In2.Cu")
		(net "CPU0_SA0")
	)
	(segment
		(start 258.965954 -109.357668)
		(end 260.001004 -109.357668)
		(width 0.11684)
		(layer "In2.Cu")
		(net "CPU0_SA0")
	)
	(segment
		(start 212.733636 -98.964242)
		(end 212.844634 -98.964242)
		(width 0.11684)
		(layer "In2.Cu")
		(net "CPU0_SA0")
	)
	(segment
		(start 263.444228 -112.800892)
		(end 263.444228 -113.07064)
		(width 0.11684)
		(layer "In2.Cu")
		(net "CPU0_SA0")
	)
	(segment
		(start 219.283788 -100.291138)
		(end 228.043994 -109.051344)
		(width 0.11684)
		(layer "In2.Cu")
		(net "CPU0_SA0")
	)
	(segment
		(start 263.444228 -113.07064)
		(end 263.717024 -113.343436)
		(width 0.11684)
		(layer "In2.Cu")
		(net "CPU0_SA0")
	)
	(segment
		(start 365.187992 -294.070024)
		(end 365.654844 -294.335962)
		(width 0.10668)
		(layer "F.Cu")
		(net "CPU0_ROM_TYPE_SELECT")
	)
	(via
		(at 365.654844 -294.335962)
		(size 0.4064)
		(drill 0.2032)
		(layers "F.Cu" "B.Cu")
		(net "CPU0_ROM_TYPE_SELECT")
	)
	(via
		(at 365.654844 -303.169574)
		(size 0.6604)
		(drill 0.3302)
		(layers "F.Cu" "B.Cu")
		(net "CPU0_ROM_TYPE_SELECT")
	)
	(segment
		(start 372.275608 -312.473086)
		(end 365.654844 -305.852322)
		(width 0.10668)
		(layer "B.Cu")
		(net "CPU0_ROM_TYPE_SELECT")
	)
	(segment
		(start 397.013684 -333.346044)
		(end 397.01343 -333.34579)
		(width 0.10668)
		(layer "B.Cu")
		(net "CPU0_ROM_TYPE_SELECT")
	)
	(segment
		(start 372.275608 -312.62828)
		(end 372.275608 -312.473086)
		(width 0.10668)
		(layer "B.Cu")
		(net "CPU0_ROM_TYPE_SELECT")
	)
	(segment
		(start 397.249142 -333.34579)
		(end 397.248888 -333.346044)
		(width 0.10668)
		(layer "B.Cu")
		(net "CPU0_ROM_TYPE_SELECT")
	)
	(segment
		(start 372.307358 -312.66003)
		(end 372.275608 -312.62828)
		(width 0.10668)
		(layer "B.Cu")
		(net "CPU0_ROM_TYPE_SELECT")
	)
	(segment
		(start 397.01343 -333.34579)
		(end 391.449052 -333.34579)
		(width 0.10668)
		(layer "B.Cu")
		(net "CPU0_ROM_TYPE_SELECT")
	)
	(segment
		(start 402.086572 -330.82484)
		(end 402.086572 -331.769212)
		(width 0.10668)
		(layer "B.Cu")
		(net "CPU0_ROM_TYPE_SELECT")
	)
	(segment
		(start 372.307358 -314.204096)
		(end 372.307358 -312.66003)
		(width 0.10668)
		(layer "B.Cu")
		(net "CPU0_ROM_TYPE_SELECT")
	)
	(segment
		(start 397.410178 -333.34579)
		(end 397.249142 -333.34579)
		(width 0.10668)
		(layer "B.Cu")
		(net "CPU0_ROM_TYPE_SELECT")
	)
	(segment
		(start 397.248888 -333.346044)
		(end 397.013684 -333.346044)
		(width 0.10668)
		(layer "B.Cu")
		(net "CPU0_ROM_TYPE_SELECT")
	)
	(segment
		(start 365.654844 -305.852322)
		(end 365.654844 -303.169574)
		(width 0.10668)
		(layer "B.Cu")
		(net "CPU0_ROM_TYPE_SELECT")
	)
	(segment
		(start 402.086572 -331.769212)
		(end 401.656042 -332.199742)
		(width 0.10668)
		(layer "B.Cu")
		(net "CPU0_ROM_TYPE_SELECT")
	)
	(segment
		(start 403.581108 -329.330304)
		(end 402.086572 -330.82484)
		(width 0.10668)
		(layer "B.Cu")
		(net "CPU0_ROM_TYPE_SELECT")
	)
	(segment
		(start 400.31797 -332.593442)
		(end 398.162526 -332.593442)
		(width 0.10668)
		(layer "B.Cu")
		(net "CPU0_ROM_TYPE_SELECT")
	)
	(segment
		(start 365.654844 -303.169574)
		(end 365.654844 -294.335962)
		(width 0.10668)
		(layer "B.Cu")
		(net "CPU0_ROM_TYPE_SELECT")
	)
	(segment
		(start 398.162526 -332.593442)
		(end 397.410178 -333.34579)
		(width 0.10668)
		(layer "B.Cu")
		(net "CPU0_ROM_TYPE_SELECT")
	)
	(segment
		(start 401.656042 -332.199742)
		(end 400.71167 -332.199742)
		(width 0.10668)
		(layer "B.Cu")
		(net "CPU0_ROM_TYPE_SELECT")
	)
	(segment
		(start 403.581108 -329.003152)
		(end 403.581108 -327.987152)
		(width 0.10668)
		(layer "B.Cu")
		(net "CPU0_ROM_TYPE_SELECT")
	)
	(segment
		(start 391.449052 -333.34579)
		(end 372.307358 -314.204096)
		(width 0.10668)
		(layer "B.Cu")
		(net "CPU0_ROM_TYPE_SELECT")
	)
	(segment
		(start 403.581108 -329.003152)
		(end 403.581108 -329.330304)
		(width 0.10668)
		(layer "B.Cu")
		(net "CPU0_ROM_TYPE_SELECT")
	)
	(segment
		(start 400.71167 -332.199742)
		(end 400.31797 -332.593442)
		(width 0.10668)
		(layer "B.Cu")
		(net "CPU0_ROM_TYPE_SELECT")
	)
	(segment
		(start 393.426188 -314.474352)
		(end 391.8204 -312.868564)
		(width 0.10668)
		(layer "F.Cu")
		(net "CPU0_PWR_GOOD")
	)
	(segment
		(start 201.339958 -112.609376)
		(end 202.502008 -112.609376)
		(width 0.10668)
		(layer "F.Cu")
		(net "CPU0_PWR_GOOD")
	)
	(segment
		(start 399.953988 -319.445132)
		(end 396.216632 -319.445132)
		(width 0.10668)
		(layer "F.Cu")
		(net "CPU0_PWR_GOOD")
	)
	(segment
		(start 384.354832 -309.382414)
		(end 384.354832 -309.240682)
		(width 0.10668)
		(layer "F.Cu")
		(net "CPU0_PWR_GOOD")
	)
	(segment
		(start 389.049006 -311.233058)
		(end 386.205476 -311.233058)
		(width 0.10668)
		(layer "F.Cu")
		(net "CPU0_PWR_GOOD")
	)
	(segment
		(start 220.354398 -200.62952)
		(end 220.354398 -198.453248)
		(width 0.10668)
		(layer "F.Cu")
		(net "CPU0_PWR_GOOD")
	)
	(segment
		(start 220.608906 -200.884028)
		(end 220.354398 -200.62952)
		(width 0.10668)
		(layer "F.Cu")
		(net "CPU0_PWR_GOOD")
	)
	(segment
		(start 205.933802 -157.568138)
		(end 204.520546 -157.568138)
		(width 0.10668)
		(layer "F.Cu")
		(net "CPU0_PWR_GOOD")
	)
	(segment
		(start 213.368382 -165.95471)
		(end 208.011522 -160.59785)
		(width 0.10668)
		(layer "F.Cu")
		(net "CPU0_PWR_GOOD")
	)
	(segment
		(start 396.216632 -319.445132)
		(end 393.982702 -317.211202)
		(width 0.10668)
		(layer "F.Cu")
		(net "CPU0_PWR_GOOD")
	)
	(segment
		(start 384.352292 -301.971964)
		(end 384.354832 -301.969424)
		(width 0.10668)
		(layer "F.Cu")
		(net "CPU0_PWR_GOOD")
	)
	(segment
		(start 220.354398 -198.453248)
		(end 219.484448 -197.583298)
		(width 0.10668)
		(layer "F.Cu")
		(net "CPU0_PWR_GOOD")
	)
	(segment
		(start 386.205476 -311.233058)
		(end 384.354832 -309.382414)
		(width 0.10668)
		(layer "F.Cu")
		(net "CPU0_PWR_GOOD")
	)
	(segment
		(start 388.355078 -297.890438)
		(end 388.355078 -296.297096)
		(width 0.10668)
		(layer "F.Cu")
		(net "CPU0_PWR_GOOD")
	)
	(segment
		(start 390.684512 -312.868564)
		(end 389.049006 -311.233058)
		(width 0.10668)
		(layer "F.Cu")
		(net "CPU0_PWR_GOOD")
	)
	(segment
		(start 384.354832 -309.240682)
		(end 384.352292 -309.238142)
		(width 0.10668)
		(layer "F.Cu")
		(net "CPU0_PWR_GOOD")
	)
	(segment
		(start 388.355078 -296.297096)
		(end 387.748018 -295.690036)
		(width 0.10668)
		(layer "F.Cu")
		(net "CPU0_PWR_GOOD")
	)
	(segment
		(start 393.982702 -317.211202)
		(end 393.982702 -314.474352)
		(width 0.10668)
		(layer "F.Cu")
		(net "CPU0_PWR_GOOD")
	)
	(segment
		(start 384.354832 -301.890684)
		(end 388.355078 -297.890438)
		(width 0.10668)
		(layer "F.Cu")
		(net "CPU0_PWR_GOOD")
	)
	(segment
		(start 401.110958 -320.602102)
		(end 399.953988 -319.445132)
		(width 0.10668)
		(layer "F.Cu")
		(net "CPU0_PWR_GOOD")
	)
	(segment
		(start 384.352292 -309.238142)
		(end 384.352292 -301.971964)
		(width 0.10668)
		(layer "F.Cu")
		(net "CPU0_PWR_GOOD")
	)
	(segment
		(start 401.110958 -320.602102)
		(end 402.126958 -320.602102)
		(width 0.10668)
		(layer "F.Cu")
		(net "CPU0_PWR_GOOD")
	)
	(segment
		(start 219.484448 -197.583298)
		(end 219.484448 -180.718714)
		(width 0.10668)
		(layer "F.Cu")
		(net "CPU0_PWR_GOOD")
	)
	(segment
		(start 393.982702 -314.474352)
		(end 393.426188 -314.474352)
		(width 0.10668)
		(layer "F.Cu")
		(net "CPU0_PWR_GOOD")
	)
	(segment
		(start 219.484448 -180.718714)
		(end 213.368382 -165.95471)
		(width 0.10668)
		(layer "F.Cu")
		(net "CPU0_PWR_GOOD")
	)
	(segment
		(start 208.011522 -159.645858)
		(end 205.933802 -157.568138)
		(width 0.10668)
		(layer "F.Cu")
		(net "CPU0_PWR_GOOD")
	)
	(segment
		(start 208.011522 -160.59785)
		(end 208.011522 -159.645858)
		(width 0.10668)
		(layer "F.Cu")
		(net "CPU0_PWR_GOOD")
	)
	(segment
		(start 384.354832 -301.969424)
		(end 384.354832 -301.890684)
		(width 0.10668)
		(layer "F.Cu")
		(net "CPU0_PWR_GOOD")
	)
	(segment
		(start 391.8204 -312.868564)
		(end 390.684512 -312.868564)
		(width 0.10668)
		(layer "F.Cu")
		(net "CPU0_PWR_GOOD")
	)
	(via
		(at 220.608906 -200.884028)
		(size 0.508)
		(drill 0.254)
		(layers "F.Cu" "B.Cu")
		(net "CPU0_PWR_GOOD")
	)
	(via
		(at 204.520546 -157.568138)
		(size 0.508)
		(drill 0.254)
		(layers "F.Cu" "B.Cu")
		(net "CPU0_PWR_GOOD")
	)
	(via
		(at 393.982702 -314.474352)
		(size 0.508)
		(drill 0.254)
		(layers "F.Cu" "B.Cu")
		(net "CPU0_PWR_GOOD")
	)
	(via
		(at 202.502008 -112.609376)
		(size 0.508)
		(drill 0.254)
		(layers "F.Cu" "B.Cu")
		(net "CPU0_PWR_GOOD")
	)
	(segment
		(start 223.339406 -202.682602)
		(end 221.540832 -200.884028)
		(width 0.11684)
		(layer "In2.Cu")
		(net "CPU0_PWR_GOOD")
	)
	(segment
		(start 232.456228 -253.911354)
		(end 223.339406 -244.794532)
		(width 0.11684)
		(layer "In2.Cu")
		(net "CPU0_PWR_GOOD")
	)
	(segment
		(start 296.77868 -370.140484)
		(end 295.997122 -370.140484)
		(width 0.11684)
		(layer "In2.Cu")
		(net "CPU0_PWR_GOOD")
	)
	(segment
		(start 270.75638 -361.490514)
		(end 252.197362 -342.931496)
		(width 0.11684)
		(layer "In2.Cu")
		(net "CPU0_PWR_GOOD")
	)
	(segment
		(start 391.003028 -312.447178)
		(end 389.702548 -311.146698)
		(width 0.11684)
		(layer "In2.Cu")
		(net "CPU0_PWR_GOOD")
	)
	(segment
		(start 295.997122 -370.140484)
		(end 295.662096 -369.805458)
		(width 0.11684)
		(layer "In2.Cu")
		(net "CPU0_PWR_GOOD")
	)
	(segment
		(start 242.270026 -253.911354)
		(end 232.456228 -253.911354)
		(width 0.11684)
		(layer "In2.Cu")
		(net "CPU0_PWR_GOOD")
	)
	(segment
		(start 282.39212 -367.817654)
		(end 276.06498 -361.490514)
		(width 0.11684)
		(layer "In2.Cu")
		(net "CPU0_PWR_GOOD")
	)
	(segment
		(start 254.97409 -269.437104)
		(end 254.274066 -265.915394)
		(width 0.11684)
		(layer "In2.Cu")
		(net "CPU0_PWR_GOOD")
	)
	(segment
		(start 297.516296 -370.8781)
		(end 296.77868 -370.140484)
		(width 0.11684)
		(layer "In2.Cu")
		(net "CPU0_PWR_GOOD")
	)
	(segment
		(start 320.914014 -370.8781)
		(end 297.516296 -370.8781)
		(width 0.11684)
		(layer "In2.Cu")
		(net "CPU0_PWR_GOOD")
	)
	(segment
		(start 221.540832 -200.884028)
		(end 220.608906 -200.884028)
		(width 0.11684)
		(layer "In2.Cu")
		(net "CPU0_PWR_GOOD")
	)
	(segment
		(start 389.702548 -311.146698)
		(end 388.365238 -311.146698)
		(width 0.11684)
		(layer "In2.Cu")
		(net "CPU0_PWR_GOOD")
	)
	(segment
		(start 351.493836 -365.420656)
		(end 320.914014 -370.8781)
		(width 0.11684)
		(layer "In2.Cu")
		(net "CPU0_PWR_GOOD")
	)
	(segment
		(start 393.982702 -314.474352)
		(end 393.462764 -314.474352)
		(width 0.11684)
		(layer "In2.Cu")
		(net "CPU0_PWR_GOOD")
	)
	(segment
		(start 223.339406 -244.794532)
		(end 223.339406 -202.682602)
		(width 0.11684)
		(layer "In2.Cu")
		(net "CPU0_PWR_GOOD")
	)
	(segment
		(start 393.462764 -314.474352)
		(end 391.43559 -312.447178)
		(width 0.11684)
		(layer "In2.Cu")
		(net "CPU0_PWR_GOOD")
	)
	(segment
		(start 291.072824 -369.805458)
		(end 289.08502 -367.817654)
		(width 0.11684)
		(layer "In2.Cu")
		(net "CPU0_PWR_GOOD")
	)
	(segment
		(start 388.365238 -311.146698)
		(end 381.708152 -317.803784)
		(width 0.11684)
		(layer "In2.Cu")
		(net "CPU0_PWR_GOOD")
	)
	(segment
		(start 295.662096 -369.805458)
		(end 291.072824 -369.805458)
		(width 0.11684)
		(layer "In2.Cu")
		(net "CPU0_PWR_GOOD")
	)
	(segment
		(start 381.708152 -335.20634)
		(end 351.493836 -365.420656)
		(width 0.11684)
		(layer "In2.Cu")
		(net "CPU0_PWR_GOOD")
	)
	(segment
		(start 276.06498 -361.490514)
		(end 270.75638 -361.490514)
		(width 0.11684)
		(layer "In2.Cu")
		(net "CPU0_PWR_GOOD")
	)
	(segment
		(start 252.197362 -332.003654)
		(end 254.97409 -329.226926)
		(width 0.11684)
		(layer "In2.Cu")
		(net "CPU0_PWR_GOOD")
	)
	(segment
		(start 391.43559 -312.447178)
		(end 391.003028 -312.447178)
		(width 0.11684)
		(layer "In2.Cu")
		(net "CPU0_PWR_GOOD")
	)
	(segment
		(start 254.274066 -265.915394)
		(end 242.270026 -253.911354)
		(width 0.11684)
		(layer "In2.Cu")
		(net "CPU0_PWR_GOOD")
	)
	(segment
		(start 252.197362 -342.931496)
		(end 252.197362 -332.003654)
		(width 0.11684)
		(layer "In2.Cu")
		(net "CPU0_PWR_GOOD")
	)
	(segment
		(start 381.708152 -317.803784)
		(end 381.708152 -335.20634)
		(width 0.11684)
		(layer "In2.Cu")
		(net "CPU0_PWR_GOOD")
	)
	(segment
		(start 289.08502 -367.817654)
		(end 282.39212 -367.817654)
		(width 0.11684)
		(layer "In2.Cu")
		(net "CPU0_PWR_GOOD")
	)
	(segment
		(start 254.97409 -329.226926)
		(end 254.97409 -269.437104)
		(width 0.11684)
		(layer "In2.Cu")
		(net "CPU0_PWR_GOOD")
	)
	(segment
		(start 203.247498 -120.185942)
		(end 203.0222 -119.641874)
		(width 0.11684)
		(layer "In4.Cu")
		(net "CPU0_PWR_GOOD")
	)
	(segment
		(start 202.86218 -132.923026)
		(end 201.60869 -131.669536)
		(width 0.11684)
		(layer "In4.Cu")
		(net "CPU0_PWR_GOOD")
	)
	(segment
		(start 202.86218 -137.922508)
		(end 202.86218 -132.923026)
		(width 0.11684)
		(layer "In4.Cu")
		(net "CPU0_PWR_GOOD")
	)
	(segment
		(start 204.363828 -124.09043)
		(end 204.363828 -121.558558)
		(width 0.11684)
		(layer "In4.Cu")
		(net "CPU0_PWR_GOOD")
	)
	(segment
		(start 204.068172 -139.1285)
		(end 202.86218 -137.922508)
		(width 0.11684)
		(layer "In4.Cu")
		(net "CPU0_PWR_GOOD")
	)
	(segment
		(start 203.0222 -119.641874)
		(end 203.0222 -113.132616)
		(width 0.11684)
		(layer "In4.Cu")
		(net "CPU0_PWR_GOOD")
	)
	(segment
		(start 202.252834 -125.457204)
		(end 203.401676 -124.308362)
		(width 0.11684)
		(layer "In4.Cu")
		(net "CPU0_PWR_GOOD")
	)
	(segment
		(start 202.252834 -127.849376)
		(end 202.252834 -125.457204)
		(width 0.11684)
		(layer "In4.Cu")
		(net "CPU0_PWR_GOOD")
	)
	(segment
		(start 203.869036 -120.80748)
		(end 203.247498 -120.185942)
		(width 0.11684)
		(layer "In4.Cu")
		(net "CPU0_PWR_GOOD")
	)
	(segment
		(start 203.869036 -121.063766)
		(end 203.869036 -120.80748)
		(width 0.11684)
		(layer "In4.Cu")
		(net "CPU0_PWR_GOOD")
	)
	(segment
		(start 201.60869 -131.669536)
		(end 201.60869 -128.49352)
		(width 0.11684)
		(layer "In4.Cu")
		(net "CPU0_PWR_GOOD")
	)
	(segment
		(start 202.502008 -112.612424)
		(end 202.502008 -112.609376)
		(width 0.11684)
		(layer "In4.Cu")
		(net "CPU0_PWR_GOOD")
	)
	(segment
		(start 203.401676 -124.308362)
		(end 204.145896 -124.308362)
		(width 0.11684)
		(layer "In4.Cu")
		(net "CPU0_PWR_GOOD")
	)
	(segment
		(start 204.363828 -121.558558)
		(end 203.869036 -121.063766)
		(width 0.11684)
		(layer "In4.Cu")
		(net "CPU0_PWR_GOOD")
	)
	(segment
		(start 204.520546 -157.568138)
		(end 204.068172 -157.115764)
		(width 0.11684)
		(layer "In4.Cu")
		(net "CPU0_PWR_GOOD")
	)
	(segment
		(start 204.145896 -124.308362)
		(end 204.363828 -124.09043)
		(width 0.11684)
		(layer "In4.Cu")
		(net "CPU0_PWR_GOOD")
	)
	(segment
		(start 201.60869 -128.49352)
		(end 202.252834 -127.849376)
		(width 0.11684)
		(layer "In4.Cu")
		(net "CPU0_PWR_GOOD")
	)
	(segment
		(start 204.068172 -157.115764)
		(end 204.068172 -139.1285)
		(width 0.11684)
		(layer "In4.Cu")
		(net "CPU0_PWR_GOOD")
	)
	(segment
		(start 203.0222 -113.132616)
		(end 202.502008 -112.612424)
		(width 0.11684)
		(layer "In4.Cu")
		(net "CPU0_PWR_GOOD")
	)
	(segment
		(start 361.89793 -294.88003)
		(end 362.364782 -295.145968)
		(width 0.10668)
		(layer "F.Cu")
		(net "CPU0_PWR_GD_OUT")
	)
	(via
		(at 362.364782 -295.145968)
		(size 0.4064)
		(drill 0.2032)
		(layers "F.Cu" "B.Cu")
		(net "CPU0_PWR_GD_OUT")
	)
	(via
		(at 402.87194 -333.487014)
		(size 0.6604)
		(drill 0.3302)
		(layers "F.Cu" "B.Cu")
		(net "CPU0_PWR_GD_OUT")
	)
	(segment
		(start 405.210264 -332.327758)
		(end 405.210264 -329.65263)
		(width 0.10668)
		(layer "B.Cu")
		(net "CPU0_PWR_GD_OUT")
	)
	(segment
		(start 397.644874 -334.30083)
		(end 397.64462 -334.301084)
		(width 0.10668)
		(layer "B.Cu")
		(net "CPU0_PWR_GD_OUT")
	)
	(segment
		(start 404.051008 -333.487014)
		(end 405.210264 -332.327758)
		(width 0.10668)
		(layer "B.Cu")
		(net "CPU0_PWR_GD_OUT")
	)
	(segment
		(start 406.298908 -325.878952)
		(end 406.298908 -326.894952)
		(width 0.10668)
		(layer "B.Cu")
		(net "CPU0_PWR_GD_OUT")
	)
	(segment
		(start 406.298908 -328.053192)
		(end 406.298908 -327.910952)
		(width 0.10668)
		(layer "B.Cu")
		(net "CPU0_PWR_GD_OUT")
	)
	(segment
		(start 405.786082 -328.566018)
		(end 406.298908 -328.053192)
		(width 0.10668)
		(layer "B.Cu")
		(net "CPU0_PWR_GD_OUT")
	)
	(segment
		(start 406.298908 -326.894952)
		(end 406.298908 -327.910952)
		(width 0.10668)
		(layer "B.Cu")
		(net "CPU0_PWR_GD_OUT")
	)
	(segment
		(start 402.87194 -333.487014)
		(end 401.006564 -333.487014)
		(width 0.10668)
		(layer "B.Cu")
		(net "CPU0_PWR_GD_OUT")
	)
	(segment
		(start 397.64462 -334.301084)
		(end 396.617952 -334.301084)
		(width 0.10668)
		(layer "B.Cu")
		(net "CPU0_PWR_GD_OUT")
	)
	(segment
		(start 390.799828 -334.30083)
		(end 371.352318 -314.85332)
		(width 0.10668)
		(layer "B.Cu")
		(net "CPU0_PWR_GD_OUT")
	)
	(segment
		(start 396.617952 -334.301084)
		(end 396.617698 -334.30083)
		(width 0.10668)
		(layer "B.Cu")
		(net "CPU0_PWR_GD_OUT")
	)
	(segment
		(start 362.364782 -304.068226)
		(end 362.364782 -295.145968)
		(width 0.10668)
		(layer "B.Cu")
		(net "CPU0_PWR_GD_OUT")
	)
	(segment
		(start 405.210264 -329.65263)
		(end 405.786082 -329.076812)
		(width 0.10668)
		(layer "B.Cu")
		(net "CPU0_PWR_GD_OUT")
	)
	(segment
		(start 371.352318 -314.85332)
		(end 371.352318 -313.055762)
		(width 0.10668)
		(layer "B.Cu")
		(net "CPU0_PWR_GD_OUT")
	)
	(segment
		(start 405.786082 -329.076812)
		(end 405.786082 -328.566018)
		(width 0.10668)
		(layer "B.Cu")
		(net "CPU0_PWR_GD_OUT")
	)
	(segment
		(start 396.617698 -334.30083)
		(end 390.799828 -334.30083)
		(width 0.10668)
		(layer "B.Cu")
		(net "CPU0_PWR_GD_OUT")
	)
	(segment
		(start 371.352318 -313.055762)
		(end 362.364782 -304.068226)
		(width 0.10668)
		(layer "B.Cu")
		(net "CPU0_PWR_GD_OUT")
	)
	(segment
		(start 401.006564 -333.487014)
		(end 400.192748 -334.30083)
		(width 0.10668)
		(layer "B.Cu")
		(net "CPU0_PWR_GD_OUT")
	)
	(segment
		(start 400.192748 -334.30083)
		(end 397.644874 -334.30083)
		(width 0.10668)
		(layer "B.Cu")
		(net "CPU0_PWR_GD_OUT")
	)
	(segment
		(start 402.87194 -333.487014)
		(end 404.051008 -333.487014)
		(width 0.10668)
		(layer "B.Cu")
		(net "CPU0_PWR_GD_OUT")
	)
	(segment
		(start 298.159932 -52.63007)
		(end 296.389044 -52.63007)
		(width 0.10668)
		(layer "F.Cu")
		(net "CPU0_PWR_BTN_N")
	)
	(segment
		(start 296.389044 -52.63007)
		(end 295.721024 -53.29809)
		(width 0.10668)
		(layer "F.Cu")
		(net "CPU0_PWR_BTN_N")
	)
	(segment
		(start 295.721024 -53.29809)
		(end 293.438072 -53.29809)
		(width 0.10668)
		(layer "F.Cu")
		(net "CPU0_PWR_BTN_N")
	)
	(segment
		(start 293.438072 -53.29809)
		(end 293.438072 -53.935376)
		(width 0.10668)
		(layer "F.Cu")
		(net "CPU0_PWR_BTN_N")
	)
	(segment
		(start 184.023 -129.777998)
		(end 184.023 -130.393948)
		(width 0.10668)
		(layer "F.Cu")
		(net "CPU0_PWR_BTN_N")
	)
	(segment
		(start 389.157972 -294.88003)
		(end 389.624824 -295.145968)
		(width 0.10668)
		(layer "F.Cu")
		(net "CPU0_PWR_BTN_N")
	)
	(via
		(at 184.023 -130.393948)
		(size 0.508)
		(drill 0.254)
		(layers "F.Cu" "B.Cu")
		(net "CPU0_PWR_BTN_N")
	)
	(via
		(at 284.753558 -129.920492)
		(size 0.508)
		(drill 0.254)
		(layers "F.Cu" "B.Cu")
		(net "CPU0_PWR_BTN_N")
	)
	(via
		(at 306.47386 -122.276362)
		(size 0.508)
		(drill 0.254)
		(layers "F.Cu" "B.Cu")
		(net "CPU0_PWR_BTN_N")
	)
	(via
		(at 389.624824 -295.145968)
		(size 0.4064)
		(drill 0.2032)
		(layers "F.Cu" "B.Cu")
		(net "CPU0_PWR_BTN_N")
	)
	(via
		(at 406.010618 -321.954906)
		(size 0.508)
		(drill 0.254)
		(layers "F.Cu" "B.Cu")
		(net "CPU0_PWR_BTN_N")
	)
	(via
		(at 293.438072 -53.935376)
		(size 0.508)
		(drill 0.254)
		(layers "F.Cu" "B.Cu")
		(net "CPU0_PWR_BTN_N")
	)
	(segment
		(start 406.010618 -314.700158)
		(end 395.988032 -304.677572)
		(width 0.10668)
		(layer "B.Cu")
		(net "CPU0_PWR_BTN_N")
	)
	(segment
		(start 395.988032 -304.677572)
		(end 395.988032 -301.747174)
		(width 0.10668)
		(layer "B.Cu")
		(net "CPU0_PWR_BTN_N")
	)
	(segment
		(start 389.624824 -295.383966)
		(end 389.624824 -295.145968)
		(width 0.10668)
		(layer "B.Cu")
		(net "CPU0_PWR_BTN_N")
	)
	(segment
		(start 406.010618 -321.954906)
		(end 406.010618 -314.700158)
		(width 0.10668)
		(layer "B.Cu")
		(net "CPU0_PWR_BTN_N")
	)
	(segment
		(start 395.988032 -301.747174)
		(end 389.624824 -295.383966)
		(width 0.10668)
		(layer "B.Cu")
		(net "CPU0_PWR_BTN_N")
	)
	(segment
		(start 406.010618 -321.954906)
		(end 406.911048 -321.054476)
		(width 0.11684)
		(layer "In2.Cu")
		(net "CPU0_PWR_BTN_N")
	)
	(segment
		(start 309.644796 -120.223788)
		(end 307.463444 -120.223788)
		(width 0.11684)
		(layer "In2.Cu")
		(net "CPU0_PWR_BTN_N")
	)
	(segment
		(start 455.757788 -200.143364)
		(end 457.46289 -198.438262)
		(width 0.11684)
		(layer "In2.Cu")
		(net "CPU0_PWR_BTN_N")
	)
	(segment
		(start 352.628708 -131.948174)
		(end 347.855286 -131.948174)
		(width 0.11684)
		(layer "In2.Cu")
		(net "CPU0_PWR_BTN_N")
	)
	(segment
		(start 457.46289 -191.242188)
		(end 457.46289 -191.067436)
		(width 0.11684)
		(layer "In2.Cu")
		(net "CPU0_PWR_BTN_N")
	)
	(segment
		(start 444.583058 -174.23003)
		(end 444.583058 -166.227506)
		(width 0.11684)
		(layer "In2.Cu")
		(net "CPU0_PWR_BTN_N")
	)
	(segment
		(start 454.104502 -321.054476)
		(end 455.757788 -319.40119)
		(width 0.11684)
		(layer "In2.Cu")
		(net "CPU0_PWR_BTN_N")
	)
	(segment
		(start 454.662794 -184.309766)
		(end 444.583058 -174.23003)
		(width 0.11684)
		(layer "In2.Cu")
		(net "CPU0_PWR_BTN_N")
	)
	(segment
		(start 441.904628 -163.549076)
		(end 441.388754 -163.549076)
		(width 0.11684)
		(layer "In2.Cu")
		(net "CPU0_PWR_BTN_N")
	)
	(segment
		(start 406.911048 -321.054476)
		(end 454.104502 -321.054476)
		(width 0.11684)
		(layer "In2.Cu")
		(net "CPU0_PWR_BTN_N")
	)
	(segment
		(start 455.757788 -319.40119)
		(end 455.757788 -200.143364)
		(width 0.11684)
		(layer "In2.Cu")
		(net "CPU0_PWR_BTN_N")
	)
	(segment
		(start 306.47386 -121.213372)
		(end 306.47386 -122.276362)
		(width 0.11684)
		(layer "In2.Cu")
		(net "CPU0_PWR_BTN_N")
	)
	(segment
		(start 402.521674 -130.630422)
		(end 353.94646 -130.630422)
		(width 0.11684)
		(layer "In2.Cu")
		(net "CPU0_PWR_BTN_N")
	)
	(segment
		(start 432.660552 -143.90624)
		(end 417.101274 -128.346962)
		(width 0.11684)
		(layer "In2.Cu")
		(net "CPU0_PWR_BTN_N")
	)
	(segment
		(start 444.583058 -166.227506)
		(end 441.904628 -163.549076)
		(width 0.11684)
		(layer "In2.Cu")
		(net "CPU0_PWR_BTN_N")
	)
	(segment
		(start 417.101274 -128.346962)
		(end 404.805134 -128.346962)
		(width 0.11684)
		(layer "In2.Cu")
		(net "CPU0_PWR_BTN_N")
	)
	(segment
		(start 457.46289 -191.067436)
		(end 454.662794 -188.26734)
		(width 0.11684)
		(layer "In2.Cu")
		(net "CPU0_PWR_BTN_N")
	)
	(segment
		(start 343.42324 -127.516128)
		(end 316.937136 -127.516128)
		(width 0.11684)
		(layer "In2.Cu")
		(net "CPU0_PWR_BTN_N")
	)
	(segment
		(start 404.805134 -128.346962)
		(end 402.521674 -130.630422)
		(width 0.11684)
		(layer "In2.Cu")
		(net "CPU0_PWR_BTN_N")
	)
	(segment
		(start 457.46289 -198.438262)
		(end 457.46289 -195.2117)
		(width 0.11684)
		(layer "In2.Cu")
		(net "CPU0_PWR_BTN_N")
	)
	(segment
		(start 441.388754 -163.549076)
		(end 432.660552 -154.820874)
		(width 0.11684)
		(layer "In2.Cu")
		(net "CPU0_PWR_BTN_N")
	)
	(segment
		(start 353.94646 -130.630422)
		(end 352.628708 -131.948174)
		(width 0.11684)
		(layer "In2.Cu")
		(net "CPU0_PWR_BTN_N")
	)
	(segment
		(start 457.464668 -195.209922)
		(end 457.464668 -191.243966)
		(width 0.11684)
		(layer "In2.Cu")
		(net "CPU0_PWR_BTN_N")
	)
	(segment
		(start 454.662794 -188.26734)
		(end 454.662794 -184.309766)
		(width 0.11684)
		(layer "In2.Cu")
		(net "CPU0_PWR_BTN_N")
	)
	(segment
		(start 457.464668 -191.243966)
		(end 457.46289 -191.242188)
		(width 0.11684)
		(layer "In2.Cu")
		(net "CPU0_PWR_BTN_N")
	)
	(segment
		(start 347.855286 -131.948174)
		(end 343.42324 -127.516128)
		(width 0.11684)
		(layer "In2.Cu")
		(net "CPU0_PWR_BTN_N")
	)
	(segment
		(start 457.46289 -195.2117)
		(end 457.464668 -195.209922)
		(width 0.11684)
		(layer "In2.Cu")
		(net "CPU0_PWR_BTN_N")
	)
	(segment
		(start 432.660552 -154.820874)
		(end 432.660552 -143.90624)
		(width 0.11684)
		(layer "In2.Cu")
		(net "CPU0_PWR_BTN_N")
	)
	(segment
		(start 307.463444 -120.223788)
		(end 306.47386 -121.213372)
		(width 0.11684)
		(layer "In2.Cu")
		(net "CPU0_PWR_BTN_N")
	)
	(segment
		(start 316.937136 -127.516128)
		(end 309.644796 -120.223788)
		(width 0.11684)
		(layer "In2.Cu")
		(net "CPU0_PWR_BTN_N")
	)
	(segment
		(start 309.986426 -113.329974)
		(end 309.986426 -121.506234)
		(width 0.11684)
		(layer "In4.Cu")
		(net "CPU0_PWR_BTN_N")
	)
	(segment
		(start 309.986426 -121.506234)
		(end 309.216298 -122.276362)
		(width 0.11684)
		(layer "In4.Cu")
		(net "CPU0_PWR_BTN_N")
	)
	(segment
		(start 309.216298 -122.276362)
		(end 306.47386 -122.276362)
		(width 0.11684)
		(layer "In4.Cu")
		(net "CPU0_PWR_BTN_N")
	)
	(segment
		(start 301.379128 -63.972948)
		(end 301.379128 -104.722676)
		(width 0.11684)
		(layer "In4.Cu")
		(net "CPU0_PWR_BTN_N")
	)
	(segment
		(start 293.438072 -53.935376)
		(end 293.438072 -56.031892)
		(width 0.11684)
		(layer "In4.Cu")
		(net "CPU0_PWR_BTN_N")
	)
	(segment
		(start 293.438072 -56.031892)
		(end 301.379128 -63.972948)
		(width 0.11684)
		(layer "In4.Cu")
		(net "CPU0_PWR_BTN_N")
	)
	(segment
		(start 301.379128 -104.722676)
		(end 309.986426 -113.329974)
		(width 0.11684)
		(layer "In4.Cu")
		(net "CPU0_PWR_BTN_N")
	)
	(segment
		(start 286.29356 -98.37166)
		(end 287.62706 -99.70516)
		(width 0.11684)
		(layer "In11.Cu")
		(net "CPU0_PWR_BTN_N")
	)
	(segment
		(start 284.753558 -118.687342)
		(end 284.753558 -129.920492)
		(width 0.11684)
		(layer "In11.Cu")
		(net "CPU0_PWR_BTN_N")
	)
	(segment
		(start 287.62706 -115.81384)
		(end 284.753558 -118.687342)
		(width 0.11684)
		(layer "In11.Cu")
		(net "CPU0_PWR_BTN_N")
	)
	(segment
		(start 286.29356 -61.079888)
		(end 286.29356 -98.37166)
		(width 0.11684)
		(layer "In11.Cu")
		(net "CPU0_PWR_BTN_N")
	)
	(segment
		(start 293.438072 -53.935376)
		(end 286.29356 -61.079888)
		(width 0.11684)
		(layer "In11.Cu")
		(net "CPU0_PWR_BTN_N")
	)
	(segment
		(start 287.62706 -99.70516)
		(end 287.62706 -115.81384)
		(width 0.11684)
		(layer "In11.Cu")
		(net "CPU0_PWR_BTN_N")
	)
	(segment
		(start 272.251678 -130.309366)
		(end 270.40332 -128.461008)
		(width 0.11684)
		(layer "In15.Cu")
		(net "CPU0_PWR_BTN_N")
	)
	(segment
		(start 207.649572 -133.02869)
		(end 206.58201 -131.961128)
		(width 0.11684)
		(layer "In15.Cu")
		(net "CPU0_PWR_BTN_N")
	)
	(segment
		(start 252.741176 -128.461008)
		(end 251.561092 -129.641092)
		(width 0.11684)
		(layer "In15.Cu")
		(net "CPU0_PWR_BTN_N")
	)
	(segment
		(start 246.188992 -133.02869)
		(end 207.649572 -133.02869)
		(width 0.11684)
		(layer "In15.Cu")
		(net "CPU0_PWR_BTN_N")
	)
	(segment
		(start 283.153104 -129.920492)
		(end 282.76423 -130.309366)
		(width 0.11684)
		(layer "In15.Cu")
		(net "CPU0_PWR_BTN_N")
	)
	(segment
		(start 284.753558 -129.920492)
		(end 283.153104 -129.920492)
		(width 0.11684)
		(layer "In15.Cu")
		(net "CPU0_PWR_BTN_N")
	)
	(segment
		(start 206.58201 -131.961128)
		(end 194.078352 -131.961128)
		(width 0.11684)
		(layer "In15.Cu")
		(net "CPU0_PWR_BTN_N")
	)
	(segment
		(start 251.561092 -129.641092)
		(end 249.57659 -129.641092)
		(width 0.11684)
		(layer "In15.Cu")
		(net "CPU0_PWR_BTN_N")
	)
	(segment
		(start 194.078352 -131.961128)
		(end 193.000884 -130.88366)
		(width 0.11684)
		(layer "In15.Cu")
		(net "CPU0_PWR_BTN_N")
	)
	(segment
		(start 249.57659 -129.641092)
		(end 246.188992 -133.02869)
		(width 0.11684)
		(layer "In15.Cu")
		(net "CPU0_PWR_BTN_N")
	)
	(segment
		(start 282.76423 -130.309366)
		(end 272.251678 -130.309366)
		(width 0.11684)
		(layer "In15.Cu")
		(net "CPU0_PWR_BTN_N")
	)
	(segment
		(start 184.227978 -129.754884)
		(end 184.023 -129.959862)
		(width 0.11684)
		(layer "In15.Cu")
		(net "CPU0_PWR_BTN_N")
	)
	(segment
		(start 193.000884 -130.88366)
		(end 193.000884 -130.47218)
		(width 0.11684)
		(layer "In15.Cu")
		(net "CPU0_PWR_BTN_N")
	)
	(segment
		(start 184.023 -129.959862)
		(end 184.023 -130.393948)
		(width 0.11684)
		(layer "In15.Cu")
		(net "CPU0_PWR_BTN_N")
	)
	(segment
		(start 193.000884 -130.47218)
		(end 192.283588 -129.754884)
		(width 0.11684)
		(layer "In15.Cu")
		(net "CPU0_PWR_BTN_N")
	)
	(segment
		(start 192.283588 -129.754884)
		(end 184.227978 -129.754884)
		(width 0.11684)
		(layer "In15.Cu")
		(net "CPU0_PWR_BTN_N")
	)
	(segment
		(start 270.40332 -128.461008)
		(end 252.741176 -128.461008)
		(width 0.11684)
		(layer "In15.Cu")
		(net "CPU0_PWR_BTN_N")
	)
	(segment
		(start 248.968006 -98.62439)
		(end 248.968006 -108.180378)
		(width 0.10668)
		(layer "F.Cu")
		(net "CPU0_PROCHOT_N")
	)
	(segment
		(start 322.954142 -193.740786)
		(end 323.513958 -194.300602)
		(width 0.10668)
		(layer "F.Cu")
		(net "CPU0_PROCHOT_N")
	)
	(segment
		(start 265.766296 -111.50854)
		(end 266.52855 -112.270794)
		(width 0.10668)
		(layer "F.Cu")
		(net "CPU0_PROCHOT_N")
	)
	(segment
		(start 266.52855 -114.460528)
		(end 265.341354 -115.647724)
		(width 0.10668)
		(layer "F.Cu")
		(net "CPU0_PROCHOT_N")
	)
	(segment
		(start 331.047852 -221.2213)
		(end 336.31124 -215.957912)
		(width 0.10668)
		(layer "F.Cu")
		(net "CPU0_PROCHOT_N")
	)
	(segment
		(start 322.954142 -178.132994)
		(end 322.954142 -193.740786)
		(width 0.10668)
		(layer "F.Cu")
		(net "CPU0_PROCHOT_N")
	)
	(segment
		(start 294.505126 -144.005808)
		(end 306.943252 -144.005808)
		(width 0.10668)
		(layer "F.Cu")
		(net "CPU0_PROCHOT_N")
	)
	(segment
		(start 267.815568 -147.981924)
		(end 290.52901 -147.981924)
		(width 0.10668)
		(layer "F.Cu")
		(net "CPU0_PROCHOT_N")
	)
	(segment
		(start 267.851128 -127.83947)
		(end 267.851128 -143.293338)
		(width 0.10668)
		(layer "F.Cu")
		(net "CPU0_PROCHOT_N")
	)
	(segment
		(start 266.33805 -146.504406)
		(end 267.815568 -147.981924)
		(width 0.10668)
		(layer "F.Cu")
		(net "CPU0_PROCHOT_N")
	)
	(segment
		(start 265.341354 -115.647724)
		(end 265.341354 -125.329696)
		(width 0.10668)
		(layer "F.Cu")
		(net "CPU0_PROCHOT_N")
	)
	(segment
		(start 265.341354 -125.329696)
		(end 267.851128 -127.83947)
		(width 0.10668)
		(layer "F.Cu")
		(net "CPU0_PROCHOT_N")
	)
	(segment
		(start 267.851128 -143.293338)
		(end 266.33805 -144.806416)
		(width 0.10668)
		(layer "F.Cu")
		(net "CPU0_PROCHOT_N")
	)
	(segment
		(start 336.31124 -209.275934)
		(end 323.513958 -196.478652)
		(width 0.10668)
		(layer "F.Cu")
		(net "CPU0_PROCHOT_N")
	)
	(segment
		(start 290.52901 -147.981924)
		(end 294.505126 -144.005808)
		(width 0.10668)
		(layer "F.Cu")
		(net "CPU0_PROCHOT_N")
	)
	(segment
		(start 266.52855 -112.270794)
		(end 266.52855 -114.460528)
		(width 0.10668)
		(layer "F.Cu")
		(net "CPU0_PROCHOT_N")
	)
	(segment
		(start 314.720986 -151.783542)
		(end 314.720986 -169.899838)
		(width 0.10668)
		(layer "F.Cu")
		(net "CPU0_PROCHOT_N")
	)
	(segment
		(start 331.047852 -222.070168)
		(end 331.047852 -221.2213)
		(width 0.10668)
		(layer "F.Cu")
		(net "CPU0_PROCHOT_N")
	)
	(segment
		(start 252.296168 -111.50854)
		(end 265.766296 -111.50854)
		(width 0.10668)
		(layer "F.Cu")
		(net "CPU0_PROCHOT_N")
	)
	(segment
		(start 248.968006 -108.180378)
		(end 252.296168 -111.50854)
		(width 0.10668)
		(layer "F.Cu")
		(net "CPU0_PROCHOT_N")
	)
	(segment
		(start 306.943252 -144.005808)
		(end 314.720986 -151.783542)
		(width 0.10668)
		(layer "F.Cu")
		(net "CPU0_PROCHOT_N")
	)
	(segment
		(start 314.720986 -169.899838)
		(end 322.954142 -178.132994)
		(width 0.10668)
		(layer "F.Cu")
		(net "CPU0_PROCHOT_N")
	)
	(segment
		(start 249.09526 -98.497136)
		(end 248.968006 -98.62439)
		(width 0.10668)
		(layer "F.Cu")
		(net "CPU0_PROCHOT_N")
	)
	(segment
		(start 336.31124 -215.957912)
		(end 336.31124 -209.275934)
		(width 0.10668)
		(layer "F.Cu")
		(net "CPU0_PROCHOT_N")
	)
	(segment
		(start 323.513958 -196.478652)
		(end 323.513958 -194.326002)
		(width 0.10668)
		(layer "F.Cu")
		(net "CPU0_PROCHOT_N")
	)
	(segment
		(start 266.33805 -144.806416)
		(end 266.33805 -146.504406)
		(width 0.10668)
		(layer "F.Cu")
		(net "CPU0_PROCHOT_N")
	)
	(segment
		(start 323.513958 -194.300602)
		(end 323.513958 -194.326002)
		(width 0.10668)
		(layer "F.Cu")
		(net "CPU0_PROCHOT_N")
	)
	(segment
		(start 181.9402 -95.291148)
		(end 181.737 -95.087948)
		(width 0.10668)
		(layer "F.Cu")
		(net "CPU0_PROCHOT_N")
	)
	(segment
		(start 181.9402 -95.703898)
		(end 181.9402 -95.291148)
		(width 0.10668)
		(layer "F.Cu")
		(net "CPU0_PROCHOT_N")
	)
	(via
		(at 249.09526 -98.497136)
		(size 0.508)
		(drill 0.254)
		(layers "F.Cu" "B.Cu")
		(net "CPU0_PROCHOT_N")
	)
	(via
		(at 181.737 -95.087948)
		(size 0.508)
		(drill 0.254)
		(layers "F.Cu" "B.Cu")
		(net "CPU0_PROCHOT_N")
	)
	(segment
		(start 206.83728 -97.951036)
		(end 201.51979 -97.951036)
		(width 0.11684)
		(layer "In6.Cu")
		(net "CPU0_PROCHOT_N")
	)
	(segment
		(start 193.25463 -92.211652)
		(end 182.55869 -92.211652)
		(width 0.11684)
		(layer "In6.Cu")
		(net "CPU0_PROCHOT_N")
	)
	(segment
		(start 181.27218 -94.623128)
		(end 181.737 -95.087948)
		(width 0.11684)
		(layer "In6.Cu")
		(net "CPU0_PROCHOT_N")
	)
	(segment
		(start 195.666614 -91.94038)
		(end 193.525902 -91.94038)
		(width 0.11684)
		(layer "In6.Cu")
		(net "CPU0_PROCHOT_N")
	)
	(segment
		(start 248.358914 -99.233482)
		(end 236.126782 -99.233482)
		(width 0.11684)
		(layer "In6.Cu")
		(net "CPU0_PROCHOT_N")
	)
	(segment
		(start 235.166662 -98.273362)
		(end 207.159606 -98.273362)
		(width 0.11684)
		(layer "In6.Cu")
		(net "CPU0_PROCHOT_N")
	)
	(segment
		(start 181.27218 -93.498162)
		(end 181.27218 -94.623128)
		(width 0.11684)
		(layer "In6.Cu")
		(net "CPU0_PROCHOT_N")
	)
	(segment
		(start 193.525902 -91.94038)
		(end 193.25463 -92.211652)
		(width 0.11684)
		(layer "In6.Cu")
		(net "CPU0_PROCHOT_N")
	)
	(segment
		(start 236.126782 -99.233482)
		(end 235.166662 -98.273362)
		(width 0.11684)
		(layer "In6.Cu")
		(net "CPU0_PROCHOT_N")
	)
	(segment
		(start 249.09526 -98.497136)
		(end 248.358914 -99.233482)
		(width 0.11684)
		(layer "In6.Cu")
		(net "CPU0_PROCHOT_N")
	)
	(segment
		(start 197.834504 -94.26575)
		(end 197.834504 -94.10827)
		(width 0.11684)
		(layer "In6.Cu")
		(net "CPU0_PROCHOT_N")
	)
	(segment
		(start 182.55869 -92.211652)
		(end 181.27218 -93.498162)
		(width 0.11684)
		(layer "In6.Cu")
		(net "CPU0_PROCHOT_N")
	)
	(segment
		(start 207.159606 -98.273362)
		(end 206.83728 -97.951036)
		(width 0.11684)
		(layer "In6.Cu")
		(net "CPU0_PROCHOT_N")
	)
	(segment
		(start 201.51979 -97.951036)
		(end 197.834504 -94.26575)
		(width 0.11684)
		(layer "In6.Cu")
		(net "CPU0_PROCHOT_N")
	)
	(segment
		(start 197.834504 -94.10827)
		(end 195.666614 -91.94038)
		(width 0.11684)
		(layer "In6.Cu")
		(net "CPU0_PROCHOT_N")
	)
	(segment
		(start 281.395932 -166.445438)
		(end 286.234378 -171.283884)
		(width 0.10668)
		(layer "F.Cu")
		(net "CPU0_NV_SAVE_N")
	)
	(segment
		(start 281.395932 -165.259258)
		(end 281.395932 -166.445438)
		(width 0.10668)
		(layer "F.Cu")
		(net "CPU0_NV_SAVE_N")
	)
	(segment
		(start 283.074618 -163.580572)
		(end 281.395932 -165.259258)
		(width 0.10668)
		(layer "F.Cu")
		(net "CPU0_NV_SAVE_N")
	)
	(segment
		(start 315.402722 -200.044812)
		(end 316.226444 -200.044812)
		(width 0.10668)
		(layer "F.Cu")
		(net "CPU0_NV_SAVE_N")
	)
	(segment
		(start 283.074618 -162.763708)
		(end 283.074618 -163.580572)
		(width 0.10668)
		(layer "F.Cu")
		(net "CPU0_NV_SAVE_N")
	)
	(segment
		(start 335.277968 -222.880174)
		(end 334.811116 -222.614236)
		(width 0.10668)
		(layer "F.Cu")
		(net "CPU0_NV_SAVE_N")
	)
	(segment
		(start 311.65673 -185.794142)
		(end 311.65673 -196.29882)
		(width 0.10668)
		(layer "F.Cu")
		(net "CPU0_NV_SAVE_N")
	)
	(segment
		(start 297.146472 -171.283884)
		(end 311.65673 -185.794142)
		(width 0.10668)
		(layer "F.Cu")
		(net "CPU0_NV_SAVE_N")
	)
	(segment
		(start 311.65673 -196.29882)
		(end 315.402722 -200.044812)
		(width 0.10668)
		(layer "F.Cu")
		(net "CPU0_NV_SAVE_N")
	)
	(segment
		(start 286.234378 -171.283884)
		(end 297.146472 -171.283884)
		(width 0.10668)
		(layer "F.Cu")
		(net "CPU0_NV_SAVE_N")
	)
	(via
		(at 183.958484 -159.496506)
		(size 0.508)
		(drill 0.254)
		(layers "F.Cu" "B.Cu")
		(net "CPU0_NV_SAVE_N")
	)
	(via
		(at 180.750718 -130.436874)
		(size 0.508)
		(drill 0.254)
		(layers "F.Cu" "B.Cu")
		(net "CPU0_NV_SAVE_N")
	)
	(via
		(at 334.811116 -222.614236)
		(size 0.4064)
		(drill 0.2032)
		(layers "F.Cu" "B.Cu")
		(net "CPU0_NV_SAVE_N")
	)
	(via
		(at 324.955408 -200.107296)
		(size 0.6604)
		(drill 0.3302)
		(layers "F.Cu" "B.Cu")
		(net "CPU0_NV_SAVE_N")
	)
	(via
		(at 283.074618 -162.763708)
		(size 0.508)
		(drill 0.254)
		(layers "F.Cu" "B.Cu")
		(net "CPU0_NV_SAVE_N")
	)
	(via
		(at 316.226444 -200.044812)
		(size 0.508)
		(drill 0.254)
		(layers "F.Cu" "B.Cu")
		(net "CPU0_NV_SAVE_N")
	)
	(segment
		(start 316.545722 -200.606152)
		(end 323.161152 -200.606152)
		(width 0.10668)
		(layer "B.Cu")
		(net "CPU0_NV_SAVE_N")
	)
	(segment
		(start 180.943504 -130.244088)
		(end 180.750718 -130.436874)
		(width 0.10668)
		(layer "B.Cu")
		(net "CPU0_NV_SAVE_N")
	)
	(segment
		(start 180.943504 -127.30353)
		(end 180.943504 -130.244088)
		(width 0.10668)
		(layer "B.Cu")
		(net "CPU0_NV_SAVE_N")
	)
	(segment
		(start 325.278242 -200.43013)
		(end 328.03338 -200.43013)
		(width 0.10668)
		(layer "B.Cu")
		(net "CPU0_NV_SAVE_N")
	)
	(segment
		(start 316.226444 -200.044812)
		(end 316.226444 -200.286874)
		(width 0.10668)
		(layer "B.Cu")
		(net "CPU0_NV_SAVE_N")
	)
	(segment
		(start 328.03338 -200.43013)
		(end 334.811116 -207.207866)
		(width 0.10668)
		(layer "B.Cu")
		(net "CPU0_NV_SAVE_N")
	)
	(segment
		(start 324.828408 -199.980296)
		(end 324.955408 -200.107296)
		(width 0.10668)
		(layer "B.Cu")
		(net "CPU0_NV_SAVE_N")
	)
	(segment
		(start 316.226444 -200.286874)
		(end 316.545722 -200.606152)
		(width 0.10668)
		(layer "B.Cu")
		(net "CPU0_NV_SAVE_N")
	)
	(segment
		(start 323.787008 -199.980296)
		(end 324.828408 -199.980296)
		(width 0.10668)
		(layer "B.Cu")
		(net "CPU0_NV_SAVE_N")
	)
	(segment
		(start 334.811116 -207.207866)
		(end 334.811116 -222.614236)
		(width 0.10668)
		(layer "B.Cu")
		(net "CPU0_NV_SAVE_N")
	)
	(segment
		(start 181.013608 -127.233426)
		(end 180.943504 -127.30353)
		(width 0.10668)
		(layer "B.Cu")
		(net "CPU0_NV_SAVE_N")
	)
	(segment
		(start 324.955408 -200.107296)
		(end 325.278242 -200.43013)
		(width 0.10668)
		(layer "B.Cu")
		(net "CPU0_NV_SAVE_N")
	)
	(segment
		(start 323.161152 -200.606152)
		(end 323.787008 -199.980296)
		(width 0.10668)
		(layer "B.Cu")
		(net "CPU0_NV_SAVE_N")
	)
	(segment
		(start 270.485108 -163.978082)
		(end 226.343972 -163.978082)
		(width 0.11684)
		(layer "In6.Cu")
		(net "CPU0_NV_SAVE_N")
	)
	(segment
		(start 226.343972 -163.978082)
		(end 223.17837 -160.81248)
		(width 0.11684)
		(layer "In6.Cu")
		(net "CPU0_NV_SAVE_N")
	)
	(segment
		(start 214.01913 -160.81248)
		(end 207.292448 -167.539162)
		(width 0.11684)
		(layer "In6.Cu")
		(net "CPU0_NV_SAVE_N")
	)
	(segment
		(start 223.17837 -160.81248)
		(end 214.01913 -160.81248)
		(width 0.11684)
		(layer "In6.Cu")
		(net "CPU0_NV_SAVE_N")
	)
	(segment
		(start 271.699482 -162.763708)
		(end 270.485108 -163.978082)
		(width 0.11684)
		(layer "In6.Cu")
		(net "CPU0_NV_SAVE_N")
	)
	(segment
		(start 207.292448 -167.539162)
		(end 199.692514 -167.539162)
		(width 0.11684)
		(layer "In6.Cu")
		(net "CPU0_NV_SAVE_N")
	)
	(segment
		(start 199.692514 -167.539162)
		(end 196.275706 -164.122354)
		(width 0.11684)
		(layer "In6.Cu")
		(net "CPU0_NV_SAVE_N")
	)
	(segment
		(start 188.584332 -164.122354)
		(end 183.958484 -159.496506)
		(width 0.11684)
		(layer "In6.Cu")
		(net "CPU0_NV_SAVE_N")
	)
	(segment
		(start 196.275706 -164.122354)
		(end 188.584332 -164.122354)
		(width 0.11684)
		(layer "In6.Cu")
		(net "CPU0_NV_SAVE_N")
	)
	(segment
		(start 283.074618 -162.763708)
		(end 271.699482 -162.763708)
		(width 0.11684)
		(layer "In6.Cu")
		(net "CPU0_NV_SAVE_N")
	)
	(segment
		(start 183.312308 -149.438614)
		(end 183.312308 -158.85033)
		(width 0.11684)
		(layer "In15.Cu")
		(net "CPU0_NV_SAVE_N")
	)
	(segment
		(start 180.58384 -139.146788)
		(end 179.072286 -139.146788)
		(width 0.11684)
		(layer "In15.Cu")
		(net "CPU0_NV_SAVE_N")
	)
	(segment
		(start 181.394354 -131.08051)
		(end 181.394354 -131.788154)
		(width 0.11684)
		(layer "In15.Cu")
		(net "CPU0_NV_SAVE_N")
	)
	(segment
		(start 181.229508 -147.355814)
		(end 183.312308 -149.438614)
		(width 0.11684)
		(layer "In15.Cu")
		(net "CPU0_NV_SAVE_N")
	)
	(segment
		(start 179.072286 -139.146788)
		(end 178.085496 -140.133578)
		(width 0.11684)
		(layer "In15.Cu")
		(net "CPU0_NV_SAVE_N")
	)
	(segment
		(start 180.750718 -130.436874)
		(end 181.394354 -131.08051)
		(width 0.11684)
		(layer "In15.Cu")
		(net "CPU0_NV_SAVE_N")
	)
	(segment
		(start 178.085496 -140.133578)
		(end 178.085496 -142.67053)
		(width 0.11684)
		(layer "In15.Cu")
		(net "CPU0_NV_SAVE_N")
	)
	(segment
		(start 181.229508 -145.814542)
		(end 181.229508 -147.355814)
		(width 0.11684)
		(layer "In15.Cu")
		(net "CPU0_NV_SAVE_N")
	)
	(segment
		(start 181.37378 -131.808728)
		(end 181.37378 -138.356848)
		(width 0.11684)
		(layer "In15.Cu")
		(net "CPU0_NV_SAVE_N")
	)
	(segment
		(start 178.085496 -142.67053)
		(end 181.229508 -145.814542)
		(width 0.11684)
		(layer "In15.Cu")
		(net "CPU0_NV_SAVE_N")
	)
	(segment
		(start 181.394354 -131.788154)
		(end 181.37378 -131.808728)
		(width 0.11684)
		(layer "In15.Cu")
		(net "CPU0_NV_SAVE_N")
	)
	(segment
		(start 183.312308 -158.85033)
		(end 183.958484 -159.496506)
		(width 0.11684)
		(layer "In15.Cu")
		(net "CPU0_NV_SAVE_N")
	)
	(segment
		(start 181.37378 -138.356848)
		(end 180.58384 -139.146788)
		(width 0.11684)
		(layer "In15.Cu")
		(net "CPU0_NV_SAVE_N")
	)
	(segment
		(start 185.039 -134.408672)
		(end 185.49874 -133.948932)
		(width 0.10668)
		(layer "F.Cu")
		(net "CPU0_NMI_SYNC_FLOOD_N")
	)
	(segment
		(start 366.594898 -295.955974)
		(end 366.128046 -295.690036)
		(width 0.10668)
		(layer "F.Cu")
		(net "CPU0_NMI_SYNC_FLOOD_N")
	)
	(segment
		(start 185.039 -134.584948)
		(end 185.039 -134.408672)
		(width 0.10668)
		(layer "F.Cu")
		(net "CPU0_NMI_SYNC_FLOOD_N")
	)
	(via
		(at 366.594898 -295.955974)
		(size 0.4064)
		(drill 0.2032)
		(layers "F.Cu" "B.Cu")
		(net "CPU0_NMI_SYNC_FLOOD_N")
	)
	(via
		(at 214.28837 -141.143482)
		(size 0.508)
		(drill 0.254)
		(layers "F.Cu" "B.Cu")
		(net "CPU0_NMI_SYNC_FLOOD_N")
	)
	(via
		(at 366.27943 -304.951638)
		(size 0.6604)
		(drill 0.3302)
		(layers "F.Cu" "B.Cu")
		(net "CPU0_NMI_SYNC_FLOOD_N")
	)
	(via
		(at 400.056096 -331.818742)
		(size 0.508)
		(drill 0.254)
		(layers "F.Cu" "B.Cu")
		(net "CPU0_NMI_SYNC_FLOOD_N")
	)
	(via
		(at 185.039 -134.584948)
		(size 0.508)
		(drill 0.254)
		(layers "F.Cu" "B.Cu")
		(net "CPU0_NMI_SYNC_FLOOD_N")
	)
	(segment
		(start 366.594898 -304.63617)
		(end 366.27943 -304.951638)
		(width 0.10668)
		(layer "B.Cu")
		(net "CPU0_NMI_SYNC_FLOOD_N")
	)
	(segment
		(start 366.594898 -295.955974)
		(end 366.594898 -304.63617)
		(width 0.10668)
		(layer "B.Cu")
		(net "CPU0_NMI_SYNC_FLOOD_N")
	)
	(segment
		(start 391.944098 -333.06131)
		(end 372.592092 -313.709304)
		(width 0.10668)
		(layer "B.Cu")
		(net "CPU0_NMI_SYNC_FLOOD_N")
	)
	(segment
		(start 372.592092 -313.709304)
		(end 372.592092 -312.24982)
		(width 0.10668)
		(layer "B.Cu")
		(net "CPU0_NMI_SYNC_FLOOD_N")
	)
	(segment
		(start 400.056096 -331.818742)
		(end 399.621756 -332.253082)
		(width 0.10668)
		(layer "B.Cu")
		(net "CPU0_NMI_SYNC_FLOOD_N")
	)
	(segment
		(start 397.233902 -333.06131)
		(end 391.944098 -333.06131)
		(width 0.10668)
		(layer "B.Cu")
		(net "CPU0_NMI_SYNC_FLOOD_N")
	)
	(segment
		(start 399.621756 -332.253082)
		(end 398.04213 -332.253082)
		(width 0.10668)
		(layer "B.Cu")
		(net "CPU0_NMI_SYNC_FLOOD_N")
	)
	(segment
		(start 366.27943 -305.937158)
		(end 366.27943 -304.951638)
		(width 0.10668)
		(layer "B.Cu")
		(net "CPU0_NMI_SYNC_FLOOD_N")
	)
	(segment
		(start 372.592092 -312.24982)
		(end 366.27943 -305.937158)
		(width 0.10668)
		(layer "B.Cu")
		(net "CPU0_NMI_SYNC_FLOOD_N")
	)
	(segment
		(start 401.11807 -331.760576)
		(end 400.114262 -331.760576)
		(width 0.10668)
		(layer "B.Cu")
		(net "CPU0_NMI_SYNC_FLOOD_N")
	)
	(segment
		(start 400.114262 -331.760576)
		(end 400.056096 -331.818742)
		(width 0.10668)
		(layer "B.Cu")
		(net "CPU0_NMI_SYNC_FLOOD_N")
	)
	(segment
		(start 398.04213 -332.253082)
		(end 397.233902 -333.06131)
		(width 0.10668)
		(layer "B.Cu")
		(net "CPU0_NMI_SYNC_FLOOD_N")
	)
	(segment
		(start 244.136164 -145.837656)
		(end 244.27053 -145.837656)
		(width 0.11684)
		(layer "In6.Cu")
		(net "CPU0_NMI_SYNC_FLOOD_N")
	)
	(segment
		(start 409.662884 -330.503276)
		(end 401.371562 -330.503276)
		(width 0.11684)
		(layer "In6.Cu")
		(net "CPU0_NMI_SYNC_FLOOD_N")
	)
	(segment
		(start 217.313764 -141.560804)
		(end 217.535506 -141.339062)
		(width 0.11684)
		(layer "In6.Cu")
		(net "CPU0_NMI_SYNC_FLOOD_N")
	)
	(segment
		(start 439.44032 -161.633408)
		(end 441.607956 -161.633408)
		(width 0.11684)
		(layer "In6.Cu")
		(net "CPU0_NMI_SYNC_FLOOD_N")
	)
	(segment
		(start 432.000406 -147.044918)
		(end 432.000406 -154.193494)
		(width 0.11684)
		(layer "In6.Cu")
		(net "CPU0_NMI_SYNC_FLOOD_N")
	)
	(segment
		(start 441.607956 -161.633408)
		(end 449.938902 -169.964354)
		(width 0.11684)
		(layer "In6.Cu")
		(net "CPU0_NMI_SYNC_FLOOD_N")
	)
	(segment
		(start 432.000406 -154.193494)
		(end 439.44032 -161.633408)
		(width 0.11684)
		(layer "In6.Cu")
		(net "CPU0_NMI_SYNC_FLOOD_N")
	)
	(segment
		(start 360.774996 -130.72618)
		(end 415.681668 -130.72618)
		(width 0.11684)
		(layer "In6.Cu")
		(net "CPU0_NMI_SYNC_FLOOD_N")
	)
	(segment
		(start 273.14652 -142.395448)
		(end 291.738304 -142.395448)
		(width 0.11684)
		(layer "In6.Cu")
		(net "CPU0_NMI_SYNC_FLOOD_N")
	)
	(segment
		(start 322.86448 -127.0762)
		(end 343.186766 -127.0762)
		(width 0.11684)
		(layer "In6.Cu")
		(net "CPU0_NMI_SYNC_FLOOD_N")
	)
	(segment
		(start 449.938902 -177.031142)
		(end 461.234536 -188.326776)
		(width 0.11684)
		(layer "In6.Cu")
		(net "CPU0_NMI_SYNC_FLOOD_N")
	)
	(segment
		(start 239.63757 -141.339062)
		(end 244.136164 -145.837656)
		(width 0.11684)
		(layer "In6.Cu")
		(net "CPU0_NMI_SYNC_FLOOD_N")
	)
	(segment
		(start 461.234536 -188.326776)
		(end 461.234536 -320.372486)
		(width 0.11684)
		(layer "In6.Cu")
		(net "CPU0_NMI_SYNC_FLOOD_N")
	)
	(segment
		(start 291.738304 -142.395448)
		(end 304.03419 -130.099562)
		(width 0.11684)
		(layer "In6.Cu")
		(net "CPU0_NMI_SYNC_FLOOD_N")
	)
	(segment
		(start 343.186766 -127.0762)
		(end 348.069154 -131.958588)
		(width 0.11684)
		(layer "In6.Cu")
		(net "CPU0_NMI_SYNC_FLOOD_N")
	)
	(segment
		(start 244.27053 -145.837656)
		(end 250.612402 -152.179528)
		(width 0.11684)
		(layer "In6.Cu")
		(net "CPU0_NMI_SYNC_FLOOD_N")
	)
	(segment
		(start 250.612402 -152.179528)
		(end 263.36244 -152.179528)
		(width 0.11684)
		(layer "In6.Cu")
		(net "CPU0_NMI_SYNC_FLOOD_N")
	)
	(segment
		(start 263.36244 -152.179528)
		(end 273.14652 -142.395448)
		(width 0.11684)
		(layer "In6.Cu")
		(net "CPU0_NMI_SYNC_FLOOD_N")
	)
	(segment
		(start 401.371562 -330.503276)
		(end 400.056096 -331.818742)
		(width 0.11684)
		(layer "In6.Cu")
		(net "CPU0_NMI_SYNC_FLOOD_N")
	)
	(segment
		(start 359.542588 -131.958588)
		(end 360.774996 -130.72618)
		(width 0.11684)
		(layer "In6.Cu")
		(net "CPU0_NMI_SYNC_FLOOD_N")
	)
	(segment
		(start 454.484994 -327.122028)
		(end 413.044132 -327.122028)
		(width 0.11684)
		(layer "In6.Cu")
		(net "CPU0_NMI_SYNC_FLOOD_N")
	)
	(segment
		(start 214.705692 -141.560804)
		(end 217.313764 -141.560804)
		(width 0.11684)
		(layer "In6.Cu")
		(net "CPU0_NMI_SYNC_FLOOD_N")
	)
	(segment
		(start 461.234536 -320.372486)
		(end 454.484994 -327.122028)
		(width 0.11684)
		(layer "In6.Cu")
		(net "CPU0_NMI_SYNC_FLOOD_N")
	)
	(segment
		(start 217.535506 -141.339062)
		(end 239.63757 -141.339062)
		(width 0.11684)
		(layer "In6.Cu")
		(net "CPU0_NMI_SYNC_FLOOD_N")
	)
	(segment
		(start 319.841118 -130.099562)
		(end 322.86448 -127.0762)
		(width 0.11684)
		(layer "In6.Cu")
		(net "CPU0_NMI_SYNC_FLOOD_N")
	)
	(segment
		(start 413.044132 -327.122028)
		(end 409.662884 -330.503276)
		(width 0.11684)
		(layer "In6.Cu")
		(net "CPU0_NMI_SYNC_FLOOD_N")
	)
	(segment
		(start 304.03419 -130.099562)
		(end 319.841118 -130.099562)
		(width 0.11684)
		(layer "In6.Cu")
		(net "CPU0_NMI_SYNC_FLOOD_N")
	)
	(segment
		(start 348.069154 -131.958588)
		(end 359.542588 -131.958588)
		(width 0.11684)
		(layer "In6.Cu")
		(net "CPU0_NMI_SYNC_FLOOD_N")
	)
	(segment
		(start 214.28837 -141.143482)
		(end 214.705692 -141.560804)
		(width 0.11684)
		(layer "In6.Cu")
		(net "CPU0_NMI_SYNC_FLOOD_N")
	)
	(segment
		(start 449.938902 -169.964354)
		(end 449.938902 -177.031142)
		(width 0.11684)
		(layer "In6.Cu")
		(net "CPU0_NMI_SYNC_FLOOD_N")
	)
	(segment
		(start 415.681668 -130.72618)
		(end 432.000406 -147.044918)
		(width 0.11684)
		(layer "In6.Cu")
		(net "CPU0_NMI_SYNC_FLOOD_N")
	)
	(segment
		(start 193.60515 -137.099548)
		(end 193.95059 -136.754108)
		(width 0.11684)
		(layer "In13.Cu")
		(net "CPU0_NMI_SYNC_FLOOD_N")
	)
	(segment
		(start 189.52845 -137.099548)
		(end 193.60515 -137.099548)
		(width 0.11684)
		(layer "In13.Cu")
		(net "CPU0_NMI_SYNC_FLOOD_N")
	)
	(segment
		(start 187.492894 -135.063992)
		(end 189.52845 -137.099548)
		(width 0.11684)
		(layer "In13.Cu")
		(net "CPU0_NMI_SYNC_FLOOD_N")
	)
	(segment
		(start 203.70419 -136.754108)
		(end 204.085444 -137.135362)
		(width 0.11684)
		(layer "In13.Cu")
		(net "CPU0_NMI_SYNC_FLOOD_N")
	)
	(segment
		(start 185.518044 -135.063992)
		(end 187.492894 -135.063992)
		(width 0.11684)
		(layer "In13.Cu")
		(net "CPU0_NMI_SYNC_FLOOD_N")
	)
	(segment
		(start 214.256874 -141.143482)
		(end 214.28837 -141.143482)
		(width 0.11684)
		(layer "In13.Cu")
		(net "CPU0_NMI_SYNC_FLOOD_N")
	)
	(segment
		(start 193.95059 -136.754108)
		(end 203.70419 -136.754108)
		(width 0.11684)
		(layer "In13.Cu")
		(net "CPU0_NMI_SYNC_FLOOD_N")
	)
	(segment
		(start 210.248754 -137.135362)
		(end 214.256874 -141.143482)
		(width 0.11684)
		(layer "In13.Cu")
		(net "CPU0_NMI_SYNC_FLOOD_N")
	)
	(segment
		(start 185.039 -134.584948)
		(end 185.518044 -135.063992)
		(width 0.11684)
		(layer "In13.Cu")
		(net "CPU0_NMI_SYNC_FLOOD_N")
	)
	(segment
		(start 204.085444 -137.135362)
		(end 210.248754 -137.135362)
		(width 0.11684)
		(layer "In13.Cu")
		(net "CPU0_NMI_SYNC_FLOOD_N")
	)
	(segment
		(start 181.868064 -132.675884)
		(end 181.868064 -133.1849)
		(width 0.10668)
		(layer "F.Cu")
		(net "CPU0_JTAG_BUF_R_OE")
	)
	(segment
		(start 181.991 -132.552948)
		(end 181.868064 -132.675884)
		(width 0.10668)
		(layer "F.Cu")
		(net "CPU0_JTAG_BUF_R_OE")
	)
	(segment
		(start 182.722012 -121.852944)
		(end 182.332122 -122.242834)
		(width 0.10668)
		(layer "F.Cu")
		(net "CPU0_JTAG_BUF_R_OE")
	)
	(via
		(at 181.991 -132.552948)
		(size 0.508)
		(drill 0.254)
		(layers "F.Cu" "B.Cu")
		(net "CPU0_JTAG_BUF_R_OE")
	)
	(via
		(at 182.332122 -122.242834)
		(size 0.4572)
		(drill 0.254)
		(layers "F.Cu" "B.Cu")
		(net "CPU0_JTAG_BUF_R_OE")
	)
	(segment
		(start 181.361588 -131.923536)
		(end 181.991 -132.552948)
		(width 0.11684)
		(layer "In2.Cu")
		(net "CPU0_JTAG_BUF_R_OE")
	)
	(segment
		(start 181.765194 -126.37897)
		(end 181.361588 -126.782576)
		(width 0.11684)
		(layer "In2.Cu")
		(net "CPU0_JTAG_BUF_R_OE")
	)
	(segment
		(start 181.765194 -123.04522)
		(end 181.765194 -126.37897)
		(width 0.11684)
		(layer "In2.Cu")
		(net "CPU0_JTAG_BUF_R_OE")
	)
	(segment
		(start 181.399434 -131.048506)
		(end 181.361588 -131.086352)
		(width 0.11684)
		(layer "In2.Cu")
		(net "CPU0_JTAG_BUF_R_OE")
	)
	(segment
		(start 181.361588 -131.086352)
		(end 181.361588 -131.923536)
		(width 0.11684)
		(layer "In2.Cu")
		(net "CPU0_JTAG_BUF_R_OE")
	)
	(segment
		(start 182.332122 -122.242834)
		(end 182.332122 -122.478292)
		(width 0.11684)
		(layer "In2.Cu")
		(net "CPU0_JTAG_BUF_R_OE")
	)
	(segment
		(start 182.332122 -122.478292)
		(end 181.765194 -123.04522)
		(width 0.11684)
		(layer "In2.Cu")
		(net "CPU0_JTAG_BUF_R_OE")
	)
	(segment
		(start 181.399434 -129.850896)
		(end 181.399434 -131.048506)
		(width 0.11684)
		(layer "In2.Cu")
		(net "CPU0_JTAG_BUF_R_OE")
	)
	(segment
		(start 181.361588 -126.782576)
		(end 181.361588 -129.81305)
		(width 0.11684)
		(layer "In2.Cu")
		(net "CPU0_JTAG_BUF_R_OE")
	)
	(segment
		(start 181.361588 -129.81305)
		(end 181.399434 -129.850896)
		(width 0.11684)
		(layer "In2.Cu")
		(net "CPU0_JTAG_BUF_R_OE")
	)
	(segment
		(start 250.613672 -96.265746)
		(end 250.613672 -98.630994)
		(width 0.10668)
		(layer "F.Cu")
		(net "CPU0_JTAG_BUF_OE")
	)
	(segment
		(start 181.868064 -134.713472)
		(end 181.868064 -133.985)
		(width 0.10668)
		(layer "F.Cu")
		(net "CPU0_JTAG_BUF_OE")
	)
	(segment
		(start 189.42685 -142.87627)
		(end 188.779658 -142.229078)
		(width 0.10668)
		(layer "F.Cu")
		(net "CPU0_JTAG_BUF_OE")
	)
	(segment
		(start 250.613672 -98.630994)
		(end 250.359672 -98.884994)
		(width 0.10668)
		(layer "F.Cu")
		(net "CPU0_JTAG_BUF_OE")
	)
	(segment
		(start 188.779658 -142.229078)
		(end 182.522622 -142.229078)
		(width 0.10668)
		(layer "F.Cu")
		(net "CPU0_JTAG_BUF_OE")
	)
	(segment
		(start 182.522622 -142.229078)
		(end 181.96179 -141.668246)
		(width 0.10668)
		(layer "F.Cu")
		(net "CPU0_JTAG_BUF_OE")
	)
	(segment
		(start 181.991 -134.836408)
		(end 181.868064 -134.713472)
		(width 0.10668)
		(layer "F.Cu")
		(net "CPU0_JTAG_BUF_OE")
	)
	(segment
		(start 201.097642 -146.036284)
		(end 197.055486 -146.036284)
		(width 0.10668)
		(layer "F.Cu")
		(net "CPU0_JTAG_BUF_OE")
	)
	(segment
		(start 197.055486 -146.036284)
		(end 189.42685 -142.87627)
		(width 0.10668)
		(layer "F.Cu")
		(net "CPU0_JTAG_BUF_OE")
	)
	(segment
		(start 181.96179 -141.668246)
		(end 181.96179 -136.223756)
		(width 0.10668)
		(layer "F.Cu")
		(net "CPU0_JTAG_BUF_OE")
	)
	(segment
		(start 181.96179 -136.223756)
		(end 181.991 -136.194546)
		(width 0.10668)
		(layer "F.Cu")
		(net "CPU0_JTAG_BUF_OE")
	)
	(segment
		(start 181.991 -136.194546)
		(end 181.991 -134.836408)
		(width 0.10668)
		(layer "F.Cu")
		(net "CPU0_JTAG_BUF_OE")
	)
	(via
		(at 250.359672 -98.884994)
		(size 0.508)
		(drill 0.254)
		(layers "F.Cu" "B.Cu")
		(net "CPU0_JTAG_BUF_OE")
	)
	(via
		(at 201.097642 -146.036284)
		(size 0.508)
		(drill 0.254)
		(layers "F.Cu" "B.Cu")
		(net "CPU0_JTAG_BUF_OE")
	)
	(via
		(at 242.508278 -150.63343)
		(size 0.508)
		(drill 0.254)
		(layers "F.Cu" "B.Cu")
		(net "CPU0_JTAG_BUF_OE")
	)
	(segment
		(start 231.078786 -148.308314)
		(end 218.329002 -148.308314)
		(width 0.11684)
		(layer "In2.Cu")
		(net "CPU0_JTAG_BUF_OE")
	)
	(segment
		(start 240.531396 -148.656548)
		(end 237.38332 -148.656548)
		(width 0.11684)
		(layer "In2.Cu")
		(net "CPU0_JTAG_BUF_OE")
	)
	(segment
		(start 242.508278 -150.63343)
		(end 240.531396 -148.656548)
		(width 0.11684)
		(layer "In2.Cu")
		(net "CPU0_JTAG_BUF_OE")
	)
	(segment
		(start 231.470454 -147.916646)
		(end 231.078786 -148.308314)
		(width 0.11684)
		(layer "In2.Cu")
		(net "CPU0_JTAG_BUF_OE")
	)
	(segment
		(start 218.329002 -148.308314)
		(end 215.855042 -145.834354)
		(width 0.11684)
		(layer "In2.Cu")
		(net "CPU0_JTAG_BUF_OE")
	)
	(segment
		(start 215.855042 -145.834354)
		(end 202.488546 -145.834354)
		(width 0.11684)
		(layer "In2.Cu")
		(net "CPU0_JTAG_BUF_OE")
	)
	(segment
		(start 236.643418 -147.916646)
		(end 231.470454 -147.916646)
		(width 0.11684)
		(layer "In2.Cu")
		(net "CPU0_JTAG_BUF_OE")
	)
	(segment
		(start 237.38332 -148.656548)
		(end 236.643418 -147.916646)
		(width 0.11684)
		(layer "In2.Cu")
		(net "CPU0_JTAG_BUF_OE")
	)
	(segment
		(start 202.286616 -146.036284)
		(end 201.097642 -146.036284)
		(width 0.11684)
		(layer "In2.Cu")
		(net "CPU0_JTAG_BUF_OE")
	)
	(segment
		(start 202.488546 -145.834354)
		(end 202.286616 -146.036284)
		(width 0.11684)
		(layer "In2.Cu")
		(net "CPU0_JTAG_BUF_OE")
	)
	(segment
		(start 242.508278 -139.309856)
		(end 245.382288 -132.371338)
		(width 0.11684)
		(layer "In4.Cu")
		(net "CPU0_JTAG_BUF_OE")
	)
	(segment
		(start 245.382288 -103.862378)
		(end 250.359672 -98.884994)
		(width 0.11684)
		(layer "In4.Cu")
		(net "CPU0_JTAG_BUF_OE")
	)
	(segment
		(start 245.382288 -132.371338)
		(end 245.382288 -103.862378)
		(width 0.11684)
		(layer "In4.Cu")
		(net "CPU0_JTAG_BUF_OE")
	)
	(segment
		(start 242.508278 -150.63343)
		(end 242.508278 -139.309856)
		(width 0.11684)
		(layer "In4.Cu")
		(net "CPU0_JTAG_BUF_OE")
	)
	(segment
		(start 384.024632 -65.941702)
		(end 384.390392 -65.941702)
		(width 0.10668)
		(layer "F.Cu")
		(net "CPU0_HDT_CONN_TESTEN")
	)
	(segment
		(start 270.200628 -69.902832)
		(end 270.607028 -69.902832)
		(width 0.10668)
		(layer "F.Cu")
		(net "CPU0_HDT_CONN_TESTEN")
	)
	(segment
		(start 385.811776 -64.3255)
		(end 385.811776 -65.55232)
		(width 0.10668)
		(layer "F.Cu")
		(net "CPU0_HDT_CONN_TESTEN")
	)
	(segment
		(start 295.014904 -94.022418)
		(end 289.080448 -88.087962)
		(width 0.10668)
		(layer "F.Cu")
		(net "CPU0_HDT_CONN_TESTEN")
	)
	(segment
		(start 383.349754 -65.266824)
		(end 384.024632 -65.941702)
		(width 0.10668)
		(layer "F.Cu")
		(net "CPU0_HDT_CONN_TESTEN")
	)
	(segment
		(start 295.014904 -104.210612)
		(end 295.014904 -94.022418)
		(width 0.10668)
		(layer "F.Cu")
		(net "CPU0_HDT_CONN_TESTEN")
	)
	(segment
		(start 272.631154 -133.304026)
		(end 274.444714 -131.490466)
		(width 0.10668)
		(layer "F.Cu")
		(net "CPU0_HDT_CONN_TESTEN")
	)
	(segment
		(start 280.59126 -131.490466)
		(end 286.469074 -125.612652)
		(width 0.10668)
		(layer "F.Cu")
		(net "CPU0_HDT_CONN_TESTEN")
	)
	(segment
		(start 385.422394 -65.941702)
		(end 384.390392 -65.941702)
		(width 0.10668)
		(layer "F.Cu")
		(net "CPU0_HDT_CONN_TESTEN")
	)
	(segment
		(start 382.806702 -60.629546)
		(end 383.349754 -61.172598)
		(width 0.10668)
		(layer "F.Cu")
		(net "CPU0_HDT_CONN_TESTEN")
	)
	(segment
		(start 286.469074 -112.756442)
		(end 295.014904 -104.210612)
		(width 0.10668)
		(layer "F.Cu")
		(net "CPU0_HDT_CONN_TESTEN")
	)
	(segment
		(start 272.420334 -67.683126)
		(end 272.523204 -67.683126)
		(width 0.10668)
		(layer "F.Cu")
		(net "CPU0_HDT_CONN_TESTEN")
	)
	(segment
		(start 272.523204 -67.683126)
		(end 281.289252 -58.917078)
		(width 0.10668)
		(layer "F.Cu")
		(net "CPU0_HDT_CONN_TESTEN")
	)
	(segment
		(start 281.289252 -58.917078)
		(end 357.305864 -58.917078)
		(width 0.10668)
		(layer "F.Cu")
		(net "CPU0_HDT_CONN_TESTEN")
	)
	(segment
		(start 359.018332 -60.629546)
		(end 382.806702 -60.629546)
		(width 0.10668)
		(layer "F.Cu")
		(net "CPU0_HDT_CONN_TESTEN")
	)
	(segment
		(start 271.55267 -68.55079)
		(end 272.420334 -67.683126)
		(width 0.10668)
		(layer "F.Cu")
		(net "CPU0_HDT_CONN_TESTEN")
	)
	(segment
		(start 385.811776 -65.55232)
		(end 385.422394 -65.941702)
		(width 0.10668)
		(layer "F.Cu")
		(net "CPU0_HDT_CONN_TESTEN")
	)
	(segment
		(start 268.790674 -132.902452)
		(end 269.192248 -133.304026)
		(width 0.10668)
		(layer "F.Cu")
		(net "CPU0_HDT_CONN_TESTEN")
	)
	(segment
		(start 383.349754 -61.172598)
		(end 383.349754 -65.266824)
		(width 0.10668)
		(layer "F.Cu")
		(net "CPU0_HDT_CONN_TESTEN")
	)
	(segment
		(start 271.55267 -68.95719)
		(end 271.55267 -68.55079)
		(width 0.10668)
		(layer "F.Cu")
		(net "CPU0_HDT_CONN_TESTEN")
	)
	(segment
		(start 289.080448 -88.087962)
		(end 281.77236 -88.087962)
		(width 0.10668)
		(layer "F.Cu")
		(net "CPU0_HDT_CONN_TESTEN")
	)
	(segment
		(start 281.77236 -88.087962)
		(end 269.370302 -75.685904)
		(width 0.10668)
		(layer "F.Cu")
		(net "CPU0_HDT_CONN_TESTEN")
	)
	(segment
		(start 269.192248 -133.304026)
		(end 272.631154 -133.304026)
		(width 0.10668)
		(layer "F.Cu")
		(net "CPU0_HDT_CONN_TESTEN")
	)
	(segment
		(start 269.370302 -70.733158)
		(end 270.200628 -69.902832)
		(width 0.10668)
		(layer "F.Cu")
		(net "CPU0_HDT_CONN_TESTEN")
	)
	(segment
		(start 357.305864 -58.917078)
		(end 359.018332 -60.629546)
		(width 0.10668)
		(layer "F.Cu")
		(net "CPU0_HDT_CONN_TESTEN")
	)
	(segment
		(start 189.103 -129.777998)
		(end 189.103 -130.393948)
		(width 0.10668)
		(layer "F.Cu")
		(net "CPU0_HDT_CONN_TESTEN")
	)
	(segment
		(start 270.607028 -69.902832)
		(end 271.55267 -68.95719)
		(width 0.10668)
		(layer "F.Cu")
		(net "CPU0_HDT_CONN_TESTEN")
	)
	(segment
		(start 286.469074 -125.612652)
		(end 286.469074 -112.756442)
		(width 0.10668)
		(layer "F.Cu")
		(net "CPU0_HDT_CONN_TESTEN")
	)
	(segment
		(start 269.370302 -75.685904)
		(end 269.370302 -70.733158)
		(width 0.10668)
		(layer "F.Cu")
		(net "CPU0_HDT_CONN_TESTEN")
	)
	(segment
		(start 274.444714 -131.490466)
		(end 280.59126 -131.490466)
		(width 0.10668)
		(layer "F.Cu")
		(net "CPU0_HDT_CONN_TESTEN")
	)
	(via
		(at 189.103 -130.393948)
		(size 0.508)
		(drill 0.254)
		(layers "F.Cu" "B.Cu")
		(net "CPU0_HDT_CONN_TESTEN")
	)
	(via
		(at 268.790674 -132.902452)
		(size 0.508)
		(drill 0.254)
		(layers "F.Cu" "B.Cu")
		(net "CPU0_HDT_CONN_TESTEN")
	)
	(segment
		(start 263.894316 -131.50977)
		(end 262.233156 -131.50977)
		(width 0.11684)
		(layer "In15.Cu")
		(net "CPU0_HDT_CONN_TESTEN")
	)
	(segment
		(start 190.051436 -133.47446)
		(end 189.103 -132.526024)
		(width 0.11684)
		(layer "In15.Cu")
		(net "CPU0_HDT_CONN_TESTEN")
	)
	(segment
		(start 248.446544 -134.07517)
		(end 206.95793 -134.07517)
		(width 0.11684)
		(layer "In15.Cu")
		(net "CPU0_HDT_CONN_TESTEN")
	)
	(segment
		(start 189.103 -132.526024)
		(end 189.103 -130.393948)
		(width 0.11684)
		(layer "In15.Cu")
		(net "CPU0_HDT_CONN_TESTEN")
	)
	(segment
		(start 252.147578 -130.374136)
		(end 248.446544 -134.07517)
		(width 0.11684)
		(layer "In15.Cu")
		(net "CPU0_HDT_CONN_TESTEN")
	)
	(segment
		(start 265.286998 -132.902452)
		(end 263.894316 -131.50977)
		(width 0.11684)
		(layer "In15.Cu")
		(net "CPU0_HDT_CONN_TESTEN")
	)
	(segment
		(start 262.233156 -131.50977)
		(end 261.174484 -132.568442)
		(width 0.11684)
		(layer "In15.Cu")
		(net "CPU0_HDT_CONN_TESTEN")
	)
	(segment
		(start 206.95793 -134.07517)
		(end 205.687168 -132.804408)
		(width 0.11684)
		(layer "In15.Cu")
		(net "CPU0_HDT_CONN_TESTEN")
	)
	(segment
		(start 205.687168 -132.804408)
		(end 195.35013 -132.804408)
		(width 0.11684)
		(layer "In15.Cu")
		(net "CPU0_HDT_CONN_TESTEN")
	)
	(segment
		(start 261.174484 -132.568442)
		(end 257.003804 -132.568442)
		(width 0.11684)
		(layer "In15.Cu")
		(net "CPU0_HDT_CONN_TESTEN")
	)
	(segment
		(start 257.003804 -132.568442)
		(end 254.809498 -130.374136)
		(width 0.11684)
		(layer "In15.Cu")
		(net "CPU0_HDT_CONN_TESTEN")
	)
	(segment
		(start 268.790674 -132.902452)
		(end 265.286998 -132.902452)
		(width 0.11684)
		(layer "In15.Cu")
		(net "CPU0_HDT_CONN_TESTEN")
	)
	(segment
		(start 195.35013 -132.804408)
		(end 194.680078 -133.47446)
		(width 0.11684)
		(layer "In15.Cu")
		(net "CPU0_HDT_CONN_TESTEN")
	)
	(segment
		(start 254.809498 -130.374136)
		(end 252.147578 -130.374136)
		(width 0.11684)
		(layer "In15.Cu")
		(net "CPU0_HDT_CONN_TESTEN")
	)
	(segment
		(start 194.680078 -133.47446)
		(end 190.051436 -133.47446)
		(width 0.11684)
		(layer "In15.Cu")
		(net "CPU0_HDT_CONN_TESTEN")
	)
	(segment
		(start 233.823256 -148.63191)
		(end 232.898188 -148.63191)
		(width 0.10668)
		(layer "F.Cu")
		(net "CPU0_HDT_BYPASS_SEL")
	)
	(segment
		(start 232.898188 -148.63191)
		(end 232.889806 -148.623528)
		(width 0.10668)
		(layer "F.Cu")
		(net "CPU0_HDT_BYPASS_SEL")
	)
	(segment
		(start 233.687874 -144.959324)
		(end 233.687874 -146.772884)
		(width 0.10668)
		(layer "F.Cu")
		(net "CPU0_HDT_BYPASS_SEL")
	)
	(segment
		(start 234.1753 -148.983954)
		(end 233.823256 -148.63191)
		(width 0.10668)
		(layer "F.Cu")
		(net "CPU0_HDT_BYPASS_SEL")
	)
	(segment
		(start 232.889806 -152.306528)
		(end 233.596688 -152.306528)
		(width 0.10668)
		(layer "F.Cu")
		(net "CPU0_HDT_BYPASS_SEL")
	)
	(segment
		(start 233.687874 -142.771114)
		(end 233.671872 -142.755112)
		(width 0.10668)
		(layer "F.Cu")
		(net "CPU0_HDT_BYPASS_SEL")
	)
	(segment
		(start 233.596688 -152.306528)
		(end 234.1753 -151.727916)
		(width 0.10668)
		(layer "F.Cu")
		(net "CPU0_HDT_BYPASS_SEL")
	)
	(segment
		(start 231.680512 -148.623528)
		(end 231.64292 -148.66112)
		(width 0.10668)
		(layer "F.Cu")
		(net "CPU0_HDT_BYPASS_SEL")
	)
	(segment
		(start 234.1753 -151.727916)
		(end 234.1753 -148.983954)
		(width 0.10668)
		(layer "F.Cu")
		(net "CPU0_HDT_BYPASS_SEL")
	)
	(segment
		(start 233.687874 -144.959324)
		(end 233.687874 -142.771114)
		(width 0.10668)
		(layer "F.Cu")
		(net "CPU0_HDT_BYPASS_SEL")
	)
	(segment
		(start 232.889806 -148.623528)
		(end 231.680512 -148.623528)
		(width 0.10668)
		(layer "F.Cu")
		(net "CPU0_HDT_BYPASS_SEL")
	)
	(via
		(at 191.05753 -140.909294)
		(size 0.508)
		(drill 0.254)
		(layers "F.Cu" "B.Cu")
		(net "CPU0_HDT_BYPASS_SEL")
	)
	(via
		(at 231.64292 -148.66112)
		(size 0.508)
		(drill 0.254)
		(layers "F.Cu" "B.Cu")
		(net "CPU0_HDT_BYPASS_SEL")
	)
	(via
		(at 233.687874 -146.772884)
		(size 0.508)
		(drill 0.254)
		(layers "F.Cu" "B.Cu")
		(net "CPU0_HDT_BYPASS_SEL")
	)
	(segment
		(start 194.826128 -136.173718)
		(end 193.557652 -137.442194)
		(width 0.10668)
		(layer "B.Cu")
		(net "CPU0_HDT_BYPASS_SEL")
	)
	(segment
		(start 193.557652 -139.0523)
		(end 193.805048 -139.299696)
		(width 0.10668)
		(layer "B.Cu")
		(net "CPU0_HDT_BYPASS_SEL")
	)
	(segment
		(start 193.557652 -137.442194)
		(end 193.557652 -139.0523)
		(width 0.10668)
		(layer "B.Cu")
		(net "CPU0_HDT_BYPASS_SEL")
	)
	(segment
		(start 192.72758 -130.29438)
		(end 192.72758 -130.991864)
		(width 0.10668)
		(layer "B.Cu")
		(net "CPU0_HDT_BYPASS_SEL")
	)
	(segment
		(start 192.728342 -131.563364)
		(end 192.30848 -131.983226)
		(width 0.10668)
		(layer "B.Cu")
		(net "CPU0_HDT_BYPASS_SEL")
	)
	(segment
		(start 192.30848 -131.983226)
		(end 192.30848 -132.907532)
		(width 0.10668)
		(layer "B.Cu")
		(net "CPU0_HDT_BYPASS_SEL")
	)
	(segment
		(start 192.189608 -127.233426)
		(end 192.189608 -127.879094)
		(width 0.10668)
		(layer "B.Cu")
		(net "CPU0_HDT_BYPASS_SEL")
	)
	(segment
		(start 191.934846 -129.501646)
		(end 192.72758 -130.29438)
		(width 0.10668)
		(layer "B.Cu")
		(net "CPU0_HDT_BYPASS_SEL")
	)
	(segment
		(start 194.826128 -134.347458)
		(end 194.826128 -136.173718)
		(width 0.10668)
		(layer "B.Cu")
		(net "CPU0_HDT_BYPASS_SEL")
	)
	(segment
		(start 193.805048 -141.114272)
		(end 192.835276 -142.084044)
		(width 0.10668)
		(layer "B.Cu")
		(net "CPU0_HDT_BYPASS_SEL")
	)
	(segment
		(start 193.196718 -133.79577)
		(end 194.27444 -133.79577)
		(width 0.10668)
		(layer "B.Cu")
		(net "CPU0_HDT_BYPASS_SEL")
	)
	(segment
		(start 192.30848 -132.907532)
		(end 193.196718 -133.79577)
		(width 0.10668)
		(layer "B.Cu")
		(net "CPU0_HDT_BYPASS_SEL")
	)
	(segment
		(start 194.27444 -133.79577)
		(end 194.826128 -134.347458)
		(width 0.10668)
		(layer "B.Cu")
		(net "CPU0_HDT_BYPASS_SEL")
	)
	(segment
		(start 192.72758 -130.991864)
		(end 192.728342 -130.992626)
		(width 0.10668)
		(layer "B.Cu")
		(net "CPU0_HDT_BYPASS_SEL")
	)
	(segment
		(start 193.805048 -139.299696)
		(end 193.805048 -141.114272)
		(width 0.10668)
		(layer "B.Cu")
		(net "CPU0_HDT_BYPASS_SEL")
	)
	(segment
		(start 191.934846 -128.133856)
		(end 191.934846 -129.501646)
		(width 0.10668)
		(layer "B.Cu")
		(net "CPU0_HDT_BYPASS_SEL")
	)
	(segment
		(start 192.23228 -142.084044)
		(end 191.05753 -140.909294)
		(width 0.10668)
		(layer "B.Cu")
		(net "CPU0_HDT_BYPASS_SEL")
	)
	(segment
		(start 192.728342 -130.992626)
		(end 192.728342 -131.563364)
		(width 0.10668)
		(layer "B.Cu")
		(net "CPU0_HDT_BYPASS_SEL")
	)
	(segment
		(start 192.835276 -142.084044)
		(end 192.23228 -142.084044)
		(width 0.10668)
		(layer "B.Cu")
		(net "CPU0_HDT_BYPASS_SEL")
	)
	(segment
		(start 192.189608 -127.879094)
		(end 191.934846 -128.133856)
		(width 0.10668)
		(layer "B.Cu")
		(net "CPU0_HDT_BYPASS_SEL")
	)
	(segment
		(start 231.64292 -148.66112)
		(end 233.531156 -146.772884)
		(width 0.11684)
		(layer "In6.Cu")
		(net "CPU0_HDT_BYPASS_SEL")
	)
	(segment
		(start 233.531156 -146.772884)
		(end 233.687874 -146.772884)
		(width 0.11684)
		(layer "In6.Cu")
		(net "CPU0_HDT_BYPASS_SEL")
	)
	(segment
		(start 196.979794 -142.448026)
		(end 192.596262 -142.448026)
		(width 0.11684)
		(layer "In15.Cu")
		(net "CPU0_HDT_BYPASS_SEL")
	)
	(segment
		(start 209.68843 -148.66112)
		(end 205.1558 -148.66112)
		(width 0.11684)
		(layer "In15.Cu")
		(net "CPU0_HDT_BYPASS_SEL")
	)
	(segment
		(start 200.610216 -144.115536)
		(end 198.647304 -144.115536)
		(width 0.11684)
		(layer "In15.Cu")
		(net "CPU0_HDT_BYPASS_SEL")
	)
	(segment
		(start 213.541864 -149.112986)
		(end 210.140296 -149.112986)
		(width 0.11684)
		(layer "In15.Cu")
		(net "CPU0_HDT_BYPASS_SEL")
	)
	(segment
		(start 231.64292 -148.66112)
		(end 213.99373 -148.66112)
		(width 0.11684)
		(layer "In15.Cu")
		(net "CPU0_HDT_BYPASS_SEL")
	)
	(segment
		(start 205.1558 -148.66112)
		(end 200.610216 -144.115536)
		(width 0.11684)
		(layer "In15.Cu")
		(net "CPU0_HDT_BYPASS_SEL")
	)
	(segment
		(start 198.647304 -144.115536)
		(end 196.979794 -142.448026)
		(width 0.11684)
		(layer "In15.Cu")
		(net "CPU0_HDT_BYPASS_SEL")
	)
	(segment
		(start 213.99373 -148.66112)
		(end 213.541864 -149.112986)
		(width 0.11684)
		(layer "In15.Cu")
		(net "CPU0_HDT_BYPASS_SEL")
	)
	(segment
		(start 210.140296 -149.112986)
		(end 209.68843 -148.66112)
		(width 0.11684)
		(layer "In15.Cu")
		(net "CPU0_HDT_BYPASS_SEL")
	)
	(segment
		(start 192.596262 -142.448026)
		(end 191.05753 -140.909294)
		(width 0.11684)
		(layer "In15.Cu")
		(net "CPU0_HDT_BYPASS_SEL")
	)
	(segment
		(start 317.798958 -198.68134)
		(end 315.670692 -196.553074)
		(width 0.10668)
		(layer "F.Cu")
		(net "CPU0_FORCE_SELFREFRESH")
	)
	(segment
		(start 317.798958 -199.259952)
		(end 317.798958 -198.68134)
		(width 0.10668)
		(layer "F.Cu")
		(net "CPU0_FORCE_SELFREFRESH")
	)
	(segment
		(start 307.521864 -167.113712)
		(end 307.521864 -161.579814)
		(width 0.10668)
		(layer "F.Cu")
		(net "CPU0_FORCE_SELFREFRESH")
	)
	(segment
		(start 288.384996 -154.780742)
		(end 287.74517 -154.780742)
		(width 0.10668)
		(layer "F.Cu")
		(net "CPU0_FORCE_SELFREFRESH")
	)
	(segment
		(start 309.35803 -178.12893)
		(end 309.35803 -168.949878)
		(width 0.10668)
		(layer "F.Cu")
		(net "CPU0_FORCE_SELFREFRESH")
	)
	(segment
		(start 304.75428 -158.81223)
		(end 292.416484 -158.81223)
		(width 0.10668)
		(layer "F.Cu")
		(net "CPU0_FORCE_SELFREFRESH")
	)
	(segment
		(start 315.670692 -196.553074)
		(end 315.496956 -196.13372)
		(width 0.10668)
		(layer "F.Cu")
		(net "CPU0_FORCE_SELFREFRESH")
	)
	(segment
		(start 315.496956 -184.267856)
		(end 309.35803 -178.12893)
		(width 0.10668)
		(layer "F.Cu")
		(net "CPU0_FORCE_SELFREFRESH")
	)
	(segment
		(start 336.218022 -222.880174)
		(end 335.75117 -222.614236)
		(width 0.10668)
		(layer "F.Cu")
		(net "CPU0_FORCE_SELFREFRESH")
	)
	(segment
		(start 307.521864 -161.579814)
		(end 304.75428 -158.81223)
		(width 0.10668)
		(layer "F.Cu")
		(net "CPU0_FORCE_SELFREFRESH")
	)
	(segment
		(start 315.496956 -196.13372)
		(end 315.496956 -184.267856)
		(width 0.10668)
		(layer "F.Cu")
		(net "CPU0_FORCE_SELFREFRESH")
	)
	(segment
		(start 309.35803 -168.949878)
		(end 307.521864 -167.113712)
		(width 0.10668)
		(layer "F.Cu")
		(net "CPU0_FORCE_SELFREFRESH")
	)
	(segment
		(start 292.416484 -158.81223)
		(end 288.384996 -154.780742)
		(width 0.10668)
		(layer "F.Cu")
		(net "CPU0_FORCE_SELFREFRESH")
	)
	(via
		(at 194.183 -132.552948)
		(size 0.508)
		(drill 0.254)
		(layers "F.Cu" "B.Cu")
		(net "CPU0_FORCE_SELFREFRESH")
	)
	(via
		(at 287.74517 -154.780742)
		(size 0.508)
		(drill 0.254)
		(layers "F.Cu" "B.Cu")
		(net "CPU0_FORCE_SELFREFRESH")
	)
	(via
		(at 324.955408 -198.837296)
		(size 0.6604)
		(drill 0.3302)
		(layers "F.Cu" "B.Cu")
		(net "CPU0_FORCE_SELFREFRESH")
	)
	(via
		(at 260.986016 -123.351798)
		(size 0.508)
		(drill 0.254)
		(layers "F.Cu" "B.Cu")
		(net "CPU0_FORCE_SELFREFRESH")
	)
	(via
		(at 335.75117 -222.614236)
		(size 0.4064)
		(drill 0.2032)
		(layers "F.Cu" "B.Cu")
		(net "CPU0_FORCE_SELFREFRESH")
	)
	(via
		(at 317.798958 -199.259952)
		(size 0.508)
		(drill 0.254)
		(layers "F.Cu" "B.Cu")
		(net "CPU0_FORCE_SELFREFRESH")
	)
	(segment
		(start 194.183 -132.552948)
		(end 194.183 -131.948428)
		(width 0.10668)
		(layer "B.Cu")
		(net "CPU0_FORCE_SELFREFRESH")
	)
	(segment
		(start 335.75117 -222.614236)
		(end 335.180686 -222.043752)
		(width 0.10668)
		(layer "B.Cu")
		(net "CPU0_FORCE_SELFREFRESH")
	)
	(segment
		(start 318.227202 -199.874124)
		(end 318.227202 -199.629268)
		(width 0.10668)
		(layer "B.Cu")
		(net "CPU0_FORCE_SELFREFRESH")
	)
	(segment
		(start 318.227202 -199.629268)
		(end 318.397382 -199.459088)
		(width 0.10668)
		(layer "B.Cu")
		(net "CPU0_FORCE_SELFREFRESH")
	)
	(segment
		(start 317.798958 -199.695308)
		(end 318.102488 -199.998838)
		(width 0.10668)
		(layer "B.Cu")
		(net "CPU0_FORCE_SELFREFRESH")
	)
	(segment
		(start 193.647822 -131.41325)
		(end 193.647822 -130.611372)
		(width 0.10668)
		(layer "B.Cu")
		(net "CPU0_FORCE_SELFREFRESH")
	)
	(segment
		(start 335.180686 -207.126586)
		(end 326.891396 -198.837296)
		(width 0.10668)
		(layer "B.Cu")
		(net "CPU0_FORCE_SELFREFRESH")
	)
	(segment
		(start 321.409822 -199.459088)
		(end 322.497958 -198.370952)
		(width 0.10668)
		(layer "B.Cu")
		(net "CPU0_FORCE_SELFREFRESH")
	)
	(segment
		(start 335.180686 -222.043752)
		(end 335.180686 -207.126586)
		(width 0.10668)
		(layer "B.Cu")
		(net "CPU0_FORCE_SELFREFRESH")
	)
	(segment
		(start 288.333434 -151.47163)
		(end 288.333434 -154.192478)
		(width 0.10668)
		(layer "B.Cu")
		(net "CPU0_FORCE_SELFREFRESH")
	)
	(segment
		(start 288.333434 -154.192478)
		(end 287.74517 -154.780742)
		(width 0.10668)
		(layer "B.Cu")
		(net "CPU0_FORCE_SELFREFRESH")
	)
	(segment
		(start 317.798958 -199.259952)
		(end 317.798958 -199.695308)
		(width 0.10668)
		(layer "B.Cu")
		(net "CPU0_FORCE_SELFREFRESH")
	)
	(segment
		(start 324.828408 -198.964296)
		(end 323.787008 -198.964296)
		(width 0.10668)
		(layer "B.Cu")
		(net "CPU0_FORCE_SELFREFRESH")
	)
	(segment
		(start 194.183 -131.948428)
		(end 193.647822 -131.41325)
		(width 0.10668)
		(layer "B.Cu")
		(net "CPU0_FORCE_SELFREFRESH")
	)
	(segment
		(start 260.986016 -123.351798)
		(end 260.986016 -123.86691)
		(width 0.10668)
		(layer "B.Cu")
		(net "CPU0_FORCE_SELFREFRESH")
	)
	(segment
		(start 326.891396 -198.837296)
		(end 324.955408 -198.837296)
		(width 0.10668)
		(layer "B.Cu")
		(net "CPU0_FORCE_SELFREFRESH")
	)
	(segment
		(start 318.102488 -199.998838)
		(end 318.227202 -199.874124)
		(width 0.10668)
		(layer "B.Cu")
		(net "CPU0_FORCE_SELFREFRESH")
	)
	(segment
		(start 268.333474 -131.47167)
		(end 288.333434 -151.47163)
		(width 0.10668)
		(layer "B.Cu")
		(net "CPU0_FORCE_SELFREFRESH")
	)
	(segment
		(start 194.094608 -127.815594)
		(end 194.094608 -127.233426)
		(width 0.10668)
		(layer "B.Cu")
		(net "CPU0_FORCE_SELFREFRESH")
	)
	(segment
		(start 323.387212 -198.370952)
		(end 323.787008 -198.770748)
		(width 0.10668)
		(layer "B.Cu")
		(net "CPU0_FORCE_SELFREFRESH")
	)
	(segment
		(start 323.787008 -198.770748)
		(end 323.787008 -198.964296)
		(width 0.10668)
		(layer "B.Cu")
		(net "CPU0_FORCE_SELFREFRESH")
	)
	(segment
		(start 193.64706 -130.61061)
		(end 193.64706 -128.263142)
		(width 0.10668)
		(layer "B.Cu")
		(net "CPU0_FORCE_SELFREFRESH")
	)
	(segment
		(start 322.497958 -198.370952)
		(end 323.387212 -198.370952)
		(width 0.10668)
		(layer "B.Cu")
		(net "CPU0_FORCE_SELFREFRESH")
	)
	(segment
		(start 268.333474 -131.214368)
		(end 268.333474 -131.47167)
		(width 0.10668)
		(layer "B.Cu")
		(net "CPU0_FORCE_SELFREFRESH")
	)
	(segment
		(start 324.955408 -198.837296)
		(end 324.828408 -198.964296)
		(width 0.10668)
		(layer "B.Cu")
		(net "CPU0_FORCE_SELFREFRESH")
	)
	(segment
		(start 318.397382 -199.459088)
		(end 321.409822 -199.459088)
		(width 0.10668)
		(layer "B.Cu")
		(net "CPU0_FORCE_SELFREFRESH")
	)
	(segment
		(start 193.647822 -130.611372)
		(end 193.64706 -130.61061)
		(width 0.10668)
		(layer "B.Cu")
		(net "CPU0_FORCE_SELFREFRESH")
	)
	(segment
		(start 260.986016 -123.86691)
		(end 268.333474 -131.214368)
		(width 0.10668)
		(layer "B.Cu")
		(net "CPU0_FORCE_SELFREFRESH")
	)
	(segment
		(start 193.64706 -128.263142)
		(end 194.094608 -127.815594)
		(width 0.10668)
		(layer "B.Cu")
		(net "CPU0_FORCE_SELFREFRESH")
	)
	(segment
		(start 203.371704 -131.88823)
		(end 206.09179 -131.88823)
		(width 0.11684)
		(layer "In2.Cu")
		(net "CPU0_FORCE_SELFREFRESH")
	)
	(segment
		(start 215.98509 -129.91592)
		(end 218.388438 -132.319268)
		(width 0.11684)
		(layer "In2.Cu")
		(net "CPU0_FORCE_SELFREFRESH")
	)
	(segment
		(start 244.70741 -132.319268)
		(end 250.597924 -126.428754)
		(width 0.11684)
		(layer "In2.Cu")
		(net "CPU0_FORCE_SELFREFRESH")
	)
	(segment
		(start 202.706986 -132.552948)
		(end 203.371704 -131.88823)
		(width 0.11684)
		(layer "In2.Cu")
		(net "CPU0_FORCE_SELFREFRESH")
	)
	(segment
		(start 250.597924 -126.428754)
		(end 250.597924 -125.480318)
		(width 0.11684)
		(layer "In2.Cu")
		(net "CPU0_FORCE_SELFREFRESH")
	)
	(segment
		(start 255.120394 -124.932186)
		(end 255.375156 -124.677424)
		(width 0.11684)
		(layer "In2.Cu")
		(net "CPU0_FORCE_SELFREFRESH")
	)
	(segment
		(start 257.269488 -124.677424)
		(end 258.595114 -123.351798)
		(width 0.11684)
		(layer "In2.Cu")
		(net "CPU0_FORCE_SELFREFRESH")
	)
	(segment
		(start 251.146056 -124.932186)
		(end 255.120394 -124.932186)
		(width 0.11684)
		(layer "In2.Cu")
		(net "CPU0_FORCE_SELFREFRESH")
	)
	(segment
		(start 194.183 -132.552948)
		(end 202.706986 -132.552948)
		(width 0.11684)
		(layer "In2.Cu")
		(net "CPU0_FORCE_SELFREFRESH")
	)
	(segment
		(start 208.0641 -129.91592)
		(end 215.98509 -129.91592)
		(width 0.11684)
		(layer "In2.Cu")
		(net "CPU0_FORCE_SELFREFRESH")
	)
	(segment
		(start 206.09179 -131.88823)
		(end 208.0641 -129.91592)
		(width 0.11684)
		(layer "In2.Cu")
		(net "CPU0_FORCE_SELFREFRESH")
	)
	(segment
		(start 218.388438 -132.319268)
		(end 244.70741 -132.319268)
		(width 0.11684)
		(layer "In2.Cu")
		(net "CPU0_FORCE_SELFREFRESH")
	)
	(segment
		(start 255.375156 -124.677424)
		(end 257.269488 -124.677424)
		(width 0.11684)
		(layer "In2.Cu")
		(net "CPU0_FORCE_SELFREFRESH")
	)
	(segment
		(start 258.595114 -123.351798)
		(end 260.986016 -123.351798)
		(width 0.11684)
		(layer "In2.Cu")
		(net "CPU0_FORCE_SELFREFRESH")
	)
	(segment
		(start 250.597924 -125.480318)
		(end 251.146056 -124.932186)
		(width 0.11684)
		(layer "In2.Cu")
		(net "CPU0_FORCE_SELFREFRESH")
	)
	(segment
		(start 368.947954 -294.070024)
		(end 369.414806 -294.335962)
		(width 0.10668)
		(layer "F.Cu")
		(net "CPU0_ESPI_CS0_N")
	)
	(via
		(at 369.556538 -303.130712)
		(size 0.6604)
		(drill 0.3302)
		(layers "F.Cu" "B.Cu")
		(net "CPU0_ESPI_CS0_N")
	)
	(via
		(at 369.414806 -294.335962)
		(size 0.4064)
		(drill 0.2032)
		(layers "F.Cu" "B.Cu")
		(net "CPU0_ESPI_CS0_N")
	)
	(segment
		(start 401.57908 -326.077834)
		(end 401.261834 -326.844152)
		(width 0.10668)
		(layer "B.Cu")
		(net "CPU0_ESPI_CS0_N")
	)
	(segment
		(start 387.657594 -325.00316)
		(end 375.51614 -312.861706)
		(width 0.10668)
		(layer "B.Cu")
		(net "CPU0_ESPI_CS0_N")
	)
	(segment
		(start 401.57908 -325.508366)
		(end 401.57908 -326.077834)
		(width 0.10668)
		(layer "B.Cu")
		(net "CPU0_ESPI_CS0_N")
	)
	(segment
		(start 399.080228 -324.812152)
		(end 399.535396 -325.26732)
		(width 0.10668)
		(layer "B.Cu")
		(net "CPU0_ESPI_CS0_N")
	)
	(segment
		(start 369.556538 -305.195478)
		(end 369.556538 -303.130712)
		(width 0.10668)
		(layer "B.Cu")
		(net "CPU0_ESPI_CS0_N")
	)
	(segment
		(start 394.913612 -329.536552)
		(end 392.338052 -328.470006)
		(width 0.10668)
		(layer "B.Cu")
		(net "CPU0_ESPI_CS0_N")
	)
	(segment
		(start 375.51614 -312.861706)
		(end 375.51614 -311.840626)
		(width 0.10668)
		(layer "B.Cu")
		(net "CPU0_ESPI_CS0_N")
	)
	(segment
		(start 370.351558 -295.259506)
		(end 370.351558 -294.896032)
		(width 0.10668)
		(layer "B.Cu")
		(net "CPU0_ESPI_CS0_N")
	)
	(segment
		(start 369.786916 -294.708072)
		(end 369.414806 -294.335962)
		(width 0.10668)
		(layer "B.Cu")
		(net "CPU0_ESPI_CS0_N")
	)
	(segment
		(start 391.164572 -326.544178)
		(end 389.623554 -325.00316)
		(width 0.10668)
		(layer "B.Cu")
		(net "CPU0_ESPI_CS0_N")
	)
	(segment
		(start 392.338052 -328.470006)
		(end 391.164572 -327.296526)
		(width 0.10668)
		(layer "B.Cu")
		(net "CPU0_ESPI_CS0_N")
	)
	(segment
		(start 369.556538 -303.130712)
		(end 369.556538 -296.054526)
		(width 0.10668)
		(layer "B.Cu")
		(net "CPU0_ESPI_CS0_N")
	)
	(segment
		(start 398.569434 -329.536552)
		(end 394.913612 -329.536552)
		(width 0.10668)
		(layer "B.Cu")
		(net "CPU0_ESPI_CS0_N")
	)
	(segment
		(start 370.163598 -294.708072)
		(end 369.786916 -294.708072)
		(width 0.10668)
		(layer "B.Cu")
		(net "CPU0_ESPI_CS0_N")
	)
	(segment
		(start 370.351558 -294.896032)
		(end 370.163598 -294.708072)
		(width 0.10668)
		(layer "B.Cu")
		(net "CPU0_ESPI_CS0_N")
	)
	(segment
		(start 401.261834 -326.844152)
		(end 398.569434 -329.536552)
		(width 0.10668)
		(layer "B.Cu")
		(net "CPU0_ESPI_CS0_N")
	)
	(segment
		(start 369.556538 -296.054526)
		(end 370.351558 -295.259506)
		(width 0.10668)
		(layer "B.Cu")
		(net "CPU0_ESPI_CS0_N")
	)
	(segment
		(start 391.164572 -327.296526)
		(end 391.164572 -326.544178)
		(width 0.10668)
		(layer "B.Cu")
		(net "CPU0_ESPI_CS0_N")
	)
	(segment
		(start 399.535396 -325.26732)
		(end 401.338034 -325.26732)
		(width 0.10668)
		(layer "B.Cu")
		(net "CPU0_ESPI_CS0_N")
	)
	(segment
		(start 401.338034 -325.26732)
		(end 401.57908 -325.508366)
		(width 0.10668)
		(layer "B.Cu")
		(net "CPU0_ESPI_CS0_N")
	)
	(segment
		(start 375.51614 -311.840626)
		(end 370.04117 -306.365656)
		(width 0.10668)
		(layer "B.Cu")
		(net "CPU0_ESPI_CS0_N")
	)
	(segment
		(start 370.04117 -306.365656)
		(end 369.556538 -305.195478)
		(width 0.10668)
		(layer "B.Cu")
		(net "CPU0_ESPI_CS0_N")
	)
	(segment
		(start 389.623554 -325.00316)
		(end 387.657594 -325.00316)
		(width 0.10668)
		(layer "B.Cu")
		(net "CPU0_ESPI_CS0_N")
	)
	(segment
		(start 374.588024 -295.690036)
		(end 375.101612 -296.107612)
		(width 0.10668)
		(layer "F.Cu")
		(net "CPU0_ESPI0_ALERT_N")
	)
	(via
		(at 375.101612 -296.107612)
		(size 0.4064)
		(drill 0.2032)
		(layers "F.Cu" "B.Cu")
		(net "CPU0_ESPI0_ALERT_N")
	)
	(via
		(at 379.430534 -305.605688)
		(size 0.6604)
		(drill 0.3302)
		(layers "F.Cu" "B.Cu")
		(net "CPU0_ESPI0_ALERT_N")
	)
	(segment
		(start 394.577824 -319.85839)
		(end 392.69797 -317.978536)
		(width 0.10668)
		(layer "B.Cu")
		(net "CPU0_ESPI0_ALERT_N")
	)
	(segment
		(start 402.584666 -324.362572)
		(end 402.183854 -323.96176)
		(width 0.10668)
		(layer "B.Cu")
		(net "CPU0_ESPI0_ALERT_N")
	)
	(segment
		(start 379.430534 -305.448462)
		(end 379.430534 -305.605688)
		(width 0.10668)
		(layer "B.Cu")
		(net "CPU0_ESPI0_ALERT_N")
	)
	(segment
		(start 387.138926 -316.474348)
		(end 387.138926 -316.004956)
		(width 0.10668)
		(layer "B.Cu")
		(net "CPU0_ESPI0_ALERT_N")
	)
	(segment
		(start 375.101612 -296.107612)
		(end 375.889012 -296.895012)
		(width 0.10668)
		(layer "B.Cu")
		(net "CPU0_ESPI0_ALERT_N")
	)
	(segment
		(start 404.515828 -324.130162)
		(end 404.283418 -324.362572)
		(width 0.10668)
		(layer "B.Cu")
		(net "CPU0_ESPI0_ALERT_N")
	)
	(segment
		(start 399.34896 -322.940934)
		(end 397.46047 -321.052444)
		(width 0.10668)
		(layer "B.Cu")
		(net "CPU0_ESPI0_ALERT_N")
	)
	(segment
		(start 399.981674 -323.96176)
		(end 399.34896 -323.329046)
		(width 0.10668)
		(layer "B.Cu")
		(net "CPU0_ESPI0_ALERT_N")
	)
	(segment
		(start 404.283418 -324.362572)
		(end 402.584666 -324.362572)
		(width 0.10668)
		(layer "B.Cu")
		(net "CPU0_ESPI0_ALERT_N")
	)
	(segment
		(start 392.69797 -317.978536)
		(end 388.643114 -317.978536)
		(width 0.10668)
		(layer "B.Cu")
		(net "CPU0_ESPI0_ALERT_N")
	)
	(segment
		(start 397.46047 -321.052444)
		(end 394.577824 -319.85839)
		(width 0.10668)
		(layer "B.Cu")
		(net "CPU0_ESPI0_ALERT_N")
	)
	(segment
		(start 379.430534 -308.296564)
		(end 379.430534 -305.605688)
		(width 0.10668)
		(layer "B.Cu")
		(net "CPU0_ESPI0_ALERT_N")
	)
	(segment
		(start 387.138926 -316.004956)
		(end 379.430534 -308.296564)
		(width 0.10668)
		(layer "B.Cu")
		(net "CPU0_ESPI0_ALERT_N")
	)
	(segment
		(start 375.889012 -296.895012)
		(end 379.430534 -305.448462)
		(width 0.10668)
		(layer "B.Cu")
		(net "CPU0_ESPI0_ALERT_N")
	)
	(segment
		(start 399.34896 -323.329046)
		(end 399.34896 -322.940934)
		(width 0.10668)
		(layer "B.Cu")
		(net "CPU0_ESPI0_ALERT_N")
	)
	(segment
		(start 404.515828 -323.892672)
		(end 404.515828 -324.130162)
		(width 0.10668)
		(layer "B.Cu")
		(net "CPU0_ESPI0_ALERT_N")
	)
	(segment
		(start 388.643114 -317.978536)
		(end 387.138926 -316.474348)
		(width 0.10668)
		(layer "B.Cu")
		(net "CPU0_ESPI0_ALERT_N")
	)
	(segment
		(start 402.183854 -323.96176)
		(end 399.981674 -323.96176)
		(width 0.10668)
		(layer "B.Cu")
		(net "CPU0_ESPI0_ALERT_N")
	)
	(segment
		(start 317.668148 -203.911962)
		(end 320.339212 -203.911962)
		(width 0.10668)
		(layer "F.Cu")
		(net "CPU0_CORETYPE2")
	)
	(segment
		(start 314.331858 -200.575672)
		(end 317.668148 -203.911962)
		(width 0.10668)
		(layer "F.Cu")
		(net "CPU0_CORETYPE2")
	)
	(segment
		(start 279.85466 -164.328094)
		(end 279.85466 -166.580312)
		(width 0.10668)
		(layer "F.Cu")
		(net "CPU0_CORETYPE2")
	)
	(segment
		(start 310.47182 -186.285378)
		(end 310.47182 -196.714872)
		(width 0.10668)
		(layer "F.Cu")
		(net "CPU0_CORETYPE2")
	)
	(segment
		(start 331.518006 -224.500186)
		(end 331.051154 -224.234248)
		(width 0.10668)
		(layer "F.Cu")
		(net "CPU0_CORETYPE2")
	)
	(segment
		(start 289.150298 -156.377132)
		(end 289.150298 -156.463492)
		(width 0.10668)
		(layer "F.Cu")
		(net "CPU0_CORETYPE2")
	)
	(segment
		(start 190.394336 -90.56243)
		(end 189.865 -91.091766)
		(width 0.10668)
		(layer "F.Cu")
		(net "CPU0_CORETYPE2")
	)
	(segment
		(start 218.877134 -94.790006)
		(end 210.604354 -94.790006)
		(width 0.10668)
		(layer "F.Cu")
		(net "CPU0_CORETYPE2")
	)
	(segment
		(start 222.587058 -125.355858)
		(end 219.577158 -122.345958)
		(width 0.10668)
		(layer "F.Cu")
		(net "CPU0_CORETYPE2")
	)
	(segment
		(start 219.577158 -122.345958)
		(end 219.577158 -115.46078)
		(width 0.10668)
		(layer "F.Cu")
		(net "CPU0_CORETYPE2")
	)
	(segment
		(start 285.042102 -160.571688)
		(end 283.611066 -160.571688)
		(width 0.10668)
		(layer "F.Cu")
		(net "CPU0_CORETYPE2")
	)
	(segment
		(start 189.865 -91.091766)
		(end 189.865 -93.690948)
		(width 0.10668)
		(layer "F.Cu")
		(net "CPU0_CORETYPE2")
	)
	(segment
		(start 219.577158 -115.46078)
		(end 222.15348 -112.884458)
		(width 0.10668)
		(layer "F.Cu")
		(net "CPU0_CORETYPE2")
	)
	(segment
		(start 296.655236 -172.468794)
		(end 310.47182 -186.285378)
		(width 0.10668)
		(layer "F.Cu")
		(net "CPU0_CORETYPE2")
	)
	(segment
		(start 310.47182 -196.714872)
		(end 314.331858 -200.57491)
		(width 0.10668)
		(layer "F.Cu")
		(net "CPU0_CORETYPE2")
	)
	(segment
		(start 206.511906 -90.697558)
		(end 202.837796 -90.697558)
		(width 0.10668)
		(layer "F.Cu")
		(net "CPU0_CORETYPE2")
	)
	(segment
		(start 279.85466 -166.580312)
		(end 285.743142 -172.468794)
		(width 0.10668)
		(layer "F.Cu")
		(net "CPU0_CORETYPE2")
	)
	(segment
		(start 283.611066 -160.571688)
		(end 279.85466 -164.328094)
		(width 0.10668)
		(layer "F.Cu")
		(net "CPU0_CORETYPE2")
	)
	(segment
		(start 289.150298 -156.463492)
		(end 285.042102 -160.571688)
		(width 0.10668)
		(layer "F.Cu")
		(net "CPU0_CORETYPE2")
	)
	(segment
		(start 222.15348 -112.884458)
		(end 222.15348 -97.180654)
		(width 0.10668)
		(layer "F.Cu")
		(net "CPU0_CORETYPE2")
	)
	(segment
		(start 222.044006 -137.657332)
		(end 222.587058 -137.11428)
		(width 0.10668)
		(layer "F.Cu")
		(net "CPU0_CORETYPE2")
	)
	(segment
		(start 285.743142 -172.468794)
		(end 296.655236 -172.468794)
		(width 0.10668)
		(layer "F.Cu")
		(net "CPU0_CORETYPE2")
	)
	(segment
		(start 222.587058 -137.11428)
		(end 222.587058 -125.355858)
		(width 0.10668)
		(layer "F.Cu")
		(net "CPU0_CORETYPE2")
	)
	(segment
		(start 210.604354 -94.790006)
		(end 206.511906 -90.697558)
		(width 0.10668)
		(layer "F.Cu")
		(net "CPU0_CORETYPE2")
	)
	(segment
		(start 219.820744 -95.733616)
		(end 218.877134 -94.790006)
		(width 0.10668)
		(layer "F.Cu")
		(net "CPU0_CORETYPE2")
	)
	(segment
		(start 220.706442 -95.733616)
		(end 219.820744 -95.733616)
		(width 0.10668)
		(layer "F.Cu")
		(net "CPU0_CORETYPE2")
	)
	(segment
		(start 200.710546 -90.56243)
		(end 190.394336 -90.56243)
		(width 0.10668)
		(layer "F.Cu")
		(net "CPU0_CORETYPE2")
	)
	(segment
		(start 220.404182 -146.182588)
		(end 222.044006 -144.542764)
		(width 0.10668)
		(layer "F.Cu")
		(net "CPU0_CORETYPE2")
	)
	(segment
		(start 320.339212 -203.911962)
		(end 321.708272 -205.281022)
		(width 0.10668)
		(layer "F.Cu")
		(net "CPU0_CORETYPE2")
	)
	(segment
		(start 314.331858 -200.57491)
		(end 314.331858 -200.575672)
		(width 0.10668)
		(layer "F.Cu")
		(net "CPU0_CORETYPE2")
	)
	(segment
		(start 321.708272 -205.281022)
		(end 321.708272 -205.505812)
		(width 0.10668)
		(layer "F.Cu")
		(net "CPU0_CORETYPE2")
	)
	(segment
		(start 222.15348 -97.180654)
		(end 220.706442 -95.733616)
		(width 0.10668)
		(layer "F.Cu")
		(net "CPU0_CORETYPE2")
	)
	(segment
		(start 200.93686 -90.336116)
		(end 200.710546 -90.56243)
		(width 0.10668)
		(layer "F.Cu")
		(net "CPU0_CORETYPE2")
	)
	(segment
		(start 222.044006 -144.542764)
		(end 222.044006 -137.657332)
		(width 0.10668)
		(layer "F.Cu")
		(net "CPU0_CORETYPE2")
	)
	(segment
		(start 202.476354 -90.336116)
		(end 200.93686 -90.336116)
		(width 0.10668)
		(layer "F.Cu")
		(net "CPU0_CORETYPE2")
	)
	(segment
		(start 202.837796 -90.697558)
		(end 202.476354 -90.336116)
		(width 0.10668)
		(layer "F.Cu")
		(net "CPU0_CORETYPE2")
	)
	(via
		(at 289.150298 -156.377132)
		(size 0.508)
		(drill 0.254)
		(layers "F.Cu" "B.Cu")
		(net "CPU0_CORETYPE2")
	)
	(via
		(at 189.865 -93.690948)
		(size 0.508)
		(drill 0.254)
		(layers "F.Cu" "B.Cu")
		(net "CPU0_CORETYPE2")
	)
	(via
		(at 321.708272 -205.505812)
		(size 0.508)
		(drill 0.254)
		(layers "F.Cu" "B.Cu")
		(net "CPU0_CORETYPE2")
	)
	(via
		(at 220.404182 -146.182588)
		(size 0.508)
		(drill 0.254)
		(layers "F.Cu" "B.Cu")
		(net "CPU0_CORETYPE2")
	)
	(via
		(at 331.051154 -224.234248)
		(size 0.4064)
		(drill 0.2032)
		(layers "F.Cu" "B.Cu")
		(net "CPU0_CORETYPE2")
	)
	(segment
		(start 331.540358 -222.805752)
		(end 331.540358 -221.834456)
		(width 0.10668)
		(layer "B.Cu")
		(net "CPU0_CORETYPE2")
	)
	(segment
		(start 321.608958 -204.825346)
		(end 321.100958 -204.317346)
		(width 0.10668)
		(layer "B.Cu")
		(net "CPU0_CORETYPE2")
	)
	(segment
		(start 321.708272 -212.00237)
		(end 321.708272 -205.505812)
		(width 0.10668)
		(layer "B.Cu")
		(net "CPU0_CORETYPE2")
	)
	(segment
		(start 331.051154 -223.294956)
		(end 331.540358 -222.805752)
		(width 0.10668)
		(layer "B.Cu")
		(net "CPU0_CORETYPE2")
	)
	(segment
		(start 321.608958 -205.406498)
		(end 321.608958 -204.825346)
		(width 0.10668)
		(layer "B.Cu")
		(net "CPU0_CORETYPE2")
	)
	(segment
		(start 190.379096 -96.205802)
		(end 190.379096 -94.205044)
		(width 0.10668)
		(layer "B.Cu")
		(net "CPU0_CORETYPE2")
	)
	(segment
		(start 331.051154 -224.234248)
		(end 331.051154 -223.294956)
		(width 0.10668)
		(layer "B.Cu")
		(net "CPU0_CORETYPE2")
	)
	(segment
		(start 190.379096 -94.205044)
		(end 189.865 -93.690948)
		(width 0.10668)
		(layer "B.Cu")
		(net "CPU0_CORETYPE2")
	)
	(segment
		(start 321.708272 -205.505812)
		(end 321.608958 -205.406498)
		(width 0.10668)
		(layer "B.Cu")
		(net "CPU0_CORETYPE2")
	)
	(segment
		(start 189.865 -96.719898)
		(end 190.379096 -96.205802)
		(width 0.10668)
		(layer "B.Cu")
		(net "CPU0_CORETYPE2")
	)
	(segment
		(start 331.540358 -221.834456)
		(end 321.708272 -212.00237)
		(width 0.10668)
		(layer "B.Cu")
		(net "CPU0_CORETYPE2")
	)
	(segment
		(start 289.150298 -156.377132)
		(end 289.150298 -154.098752)
		(width 0.11684)
		(layer "In6.Cu")
		(net "CPU0_CORETYPE2")
	)
	(segment
		(start 270.41983 -150.6728)
		(end 265.849862 -155.242768)
		(width 0.11684)
		(layer "In6.Cu")
		(net "CPU0_CORETYPE2")
	)
	(segment
		(start 281.094688 -146.043142)
		(end 274.695412 -146.043142)
		(width 0.11684)
		(layer "In6.Cu")
		(net "CPU0_CORETYPE2")
	)
	(segment
		(start 265.849862 -155.242768)
		(end 249.34291 -155.242768)
		(width 0.11684)
		(layer "In6.Cu")
		(net "CPU0_CORETYPE2")
	)
	(segment
		(start 242.866672 -148.900896)
		(end 239.837468 -145.871692)
		(width 0.11684)
		(layer "In6.Cu")
		(net "CPU0_CORETYPE2")
	)
	(segment
		(start 220.715078 -145.871692)
		(end 220.404182 -146.182588)
		(width 0.11684)
		(layer "In6.Cu")
		(net "CPU0_CORETYPE2")
	)
	(segment
		(start 270.41983 -150.318724)
		(end 270.41983 -150.6728)
		(width 0.11684)
		(layer "In6.Cu")
		(net "CPU0_CORETYPE2")
	)
	(segment
		(start 274.695412 -146.043142)
		(end 270.41983 -150.318724)
		(width 0.11684)
		(layer "In6.Cu")
		(net "CPU0_CORETYPE2")
	)
	(segment
		(start 243.001038 -148.900896)
		(end 242.866672 -148.900896)
		(width 0.11684)
		(layer "In6.Cu")
		(net "CPU0_CORETYPE2")
	)
	(segment
		(start 249.34291 -155.242768)
		(end 243.001038 -148.900896)
		(width 0.11684)
		(layer "In6.Cu")
		(net "CPU0_CORETYPE2")
	)
	(segment
		(start 289.150298 -154.098752)
		(end 281.094688 -146.043142)
		(width 0.11684)
		(layer "In6.Cu")
		(net "CPU0_CORETYPE2")
	)
	(segment
		(start 239.837468 -145.871692)
		(end 220.715078 -145.871692)
		(width 0.11684)
		(layer "In6.Cu")
		(net "CPU0_CORETYPE2")
	)
	(segment
		(start 313.768232 -201.139298)
		(end 317.337948 -204.709014)
		(width 0.10668)
		(layer "F.Cu")
		(net "CPU0_CORETYPE1")
	)
	(segment
		(start 309.675784 -197.044818)
		(end 313.768232 -201.138282)
		(width 0.10668)
		(layer "F.Cu")
		(net "CPU0_CORETYPE1")
	)
	(segment
		(start 320.148458 -205.451456)
		(end 320.148458 -205.488032)
		(width 0.10668)
		(layer "F.Cu")
		(net "CPU0_CORETYPE1")
	)
	(segment
		(start 313.768232 -201.138282)
		(end 313.768232 -201.139298)
		(width 0.10668)
		(layer "F.Cu")
		(net "CPU0_CORETYPE1")
	)
	(segment
		(start 285.413196 -173.26483)
		(end 296.32529 -173.26483)
		(width 0.10668)
		(layer "F.Cu")
		(net "CPU0_CORETYPE1")
	)
	(segment
		(start 330.577952 -222.880174)
		(end 330.1111 -222.614236)
		(width 0.10668)
		(layer "F.Cu")
		(net "CPU0_CORETYPE1")
	)
	(segment
		(start 283.28112 -159.775652)
		(end 279.058624 -163.998148)
		(width 0.10668)
		(layer "F.Cu")
		(net "CPU0_CORETYPE1")
	)
	(segment
		(start 319.406016 -204.709014)
		(end 320.148458 -205.451456)
		(width 0.10668)
		(layer "F.Cu")
		(net "CPU0_CORETYPE1")
	)
	(segment
		(start 279.058624 -163.998148)
		(end 279.058624 -166.910258)
		(width 0.10668)
		(layer "F.Cu")
		(net "CPU0_CORETYPE1")
	)
	(segment
		(start 286.864298 -157.490922)
		(end 284.579568 -159.775652)
		(width 0.10668)
		(layer "F.Cu")
		(net "CPU0_CORETYPE1")
	)
	(segment
		(start 279.058624 -166.910258)
		(end 285.413196 -173.26483)
		(width 0.10668)
		(layer "F.Cu")
		(net "CPU0_CORETYPE1")
	)
	(segment
		(start 309.675784 -186.615324)
		(end 309.675784 -197.044818)
		(width 0.10668)
		(layer "F.Cu")
		(net "CPU0_CORETYPE1")
	)
	(segment
		(start 317.337948 -204.709014)
		(end 319.406016 -204.709014)
		(width 0.10668)
		(layer "F.Cu")
		(net "CPU0_CORETYPE1")
	)
	(segment
		(start 284.579568 -159.775652)
		(end 283.28112 -159.775652)
		(width 0.10668)
		(layer "F.Cu")
		(net "CPU0_CORETYPE1")
	)
	(segment
		(start 189.357 -98.747834)
		(end 189.853316 -98.251518)
		(width 0.10668)
		(layer "F.Cu")
		(net "CPU0_CORETYPE1")
	)
	(segment
		(start 189.357 -99.659694)
		(end 189.357 -98.747834)
		(width 0.10668)
		(layer "F.Cu")
		(net "CPU0_CORETYPE1")
	)
	(segment
		(start 189.865 -99.894898)
		(end 189.592204 -99.894898)
		(width 0.10668)
		(layer "F.Cu")
		(net "CPU0_CORETYPE1")
	)
	(segment
		(start 189.592204 -99.894898)
		(end 189.357 -99.659694)
		(width 0.10668)
		(layer "F.Cu")
		(net "CPU0_CORETYPE1")
	)
	(segment
		(start 286.864298 -156.377132)
		(end 286.864298 -157.490922)
		(width 0.10668)
		(layer "F.Cu")
		(net "CPU0_CORETYPE1")
	)
	(segment
		(start 296.32529 -173.26483)
		(end 309.675784 -186.615324)
		(width 0.10668)
		(layer "F.Cu")
		(net "CPU0_CORETYPE1")
	)
	(via
		(at 330.1111 -222.614236)
		(size 0.4064)
		(drill 0.2032)
		(layers "F.Cu" "B.Cu")
		(net "CPU0_CORETYPE1")
	)
	(via
		(at 239.843056 -149.322536)
		(size 0.508)
		(drill 0.254)
		(layers "F.Cu" "B.Cu")
		(net "CPU0_CORETYPE1")
	)
	(via
		(at 286.864298 -156.377132)
		(size 0.508)
		(drill 0.254)
		(layers "F.Cu" "B.Cu")
		(net "CPU0_CORETYPE1")
	)
	(via
		(at 320.148458 -205.488032)
		(size 0.508)
		(drill 0.254)
		(layers "F.Cu" "B.Cu")
		(net "CPU0_CORETYPE1")
	)
	(via
		(at 239.843056 -106.782362)
		(size 0.508)
		(drill 0.254)
		(layers "F.Cu" "B.Cu")
		(net "CPU0_CORETYPE1")
	)
	(via
		(at 189.853316 -98.251518)
		(size 0.508)
		(drill 0.254)
		(layers "F.Cu" "B.Cu")
		(net "CPU0_CORETYPE1")
	)
	(segment
		(start 330.1111 -222.188024)
		(end 330.1111 -222.614236)
		(width 0.10668)
		(layer "B.Cu")
		(net "CPU0_CORETYPE1")
	)
	(segment
		(start 319.322958 -204.317346)
		(end 319.830958 -204.825346)
		(width 0.10668)
		(layer "B.Cu")
		(net "CPU0_CORETYPE1")
	)
	(segment
		(start 319.830958 -204.825346)
		(end 319.830958 -205.170532)
		(width 0.10668)
		(layer "B.Cu")
		(net "CPU0_CORETYPE1")
	)
	(segment
		(start 320.148458 -212.225382)
		(end 330.1111 -222.188024)
		(width 0.10668)
		(layer "B.Cu")
		(net "CPU0_CORETYPE1")
	)
	(segment
		(start 319.830958 -205.170532)
		(end 320.148458 -205.488032)
		(width 0.10668)
		(layer "B.Cu")
		(net "CPU0_CORETYPE1")
	)
	(segment
		(start 320.148458 -205.488032)
		(end 320.148458 -212.225382)
		(width 0.10668)
		(layer "B.Cu")
		(net "CPU0_CORETYPE1")
	)
	(segment
		(start 219.633292 -99.447858)
		(end 227.432616 -107.247182)
		(width 0.11684)
		(layer "In2.Cu")
		(net "CPU0_CORETYPE1")
	)
	(segment
		(start 214.093044 -98.120962)
		(end 215.41994 -99.447858)
		(width 0.11684)
		(layer "In2.Cu")
		(net "CPU0_CORETYPE1")
	)
	(segment
		(start 199.601582 -96.149922)
		(end 200.343516 -95.407988)
		(width 0.11684)
		(layer "In2.Cu")
		(net "CPU0_CORETYPE1")
	)
	(segment
		(start 210.79841 -97.915222)
		(end 212.8774 -97.915222)
		(width 0.11684)
		(layer "In2.Cu")
		(net "CPU0_CORETYPE1")
	)
	(segment
		(start 202.01763 -95.407988)
		(end 202.068176 -95.458534)
		(width 0.11684)
		(layer "In2.Cu")
		(net "CPU0_CORETYPE1")
	)
	(segment
		(start 191.954912 -96.149922)
		(end 199.601582 -96.149922)
		(width 0.11684)
		(layer "In2.Cu")
		(net "CPU0_CORETYPE1")
	)
	(segment
		(start 202.068176 -95.458534)
		(end 208.341722 -95.458534)
		(width 0.11684)
		(layer "In2.Cu")
		(net "CPU0_CORETYPE1")
	)
	(segment
		(start 215.41994 -99.447858)
		(end 219.633292 -99.447858)
		(width 0.11684)
		(layer "In2.Cu")
		(net "CPU0_CORETYPE1")
	)
	(segment
		(start 208.341722 -95.458534)
		(end 210.79841 -97.915222)
		(width 0.11684)
		(layer "In2.Cu")
		(net "CPU0_CORETYPE1")
	)
	(segment
		(start 189.853316 -98.251518)
		(end 191.954912 -96.149922)
		(width 0.11684)
		(layer "In2.Cu")
		(net "CPU0_CORETYPE1")
	)
	(segment
		(start 239.400842 -107.247182)
		(end 239.843056 -106.804968)
		(width 0.11684)
		(layer "In2.Cu")
		(net "CPU0_CORETYPE1")
	)
	(segment
		(start 239.843056 -106.804968)
		(end 239.843056 -106.782362)
		(width 0.11684)
		(layer "In2.Cu")
		(net "CPU0_CORETYPE1")
	)
	(segment
		(start 212.8774 -97.915222)
		(end 213.08314 -98.120962)
		(width 0.11684)
		(layer "In2.Cu")
		(net "CPU0_CORETYPE1")
	)
	(segment
		(start 227.432616 -107.247182)
		(end 239.400842 -107.247182)
		(width 0.11684)
		(layer "In2.Cu")
		(net "CPU0_CORETYPE1")
	)
	(segment
		(start 200.343516 -95.407988)
		(end 202.01763 -95.407988)
		(width 0.11684)
		(layer "In2.Cu")
		(net "CPU0_CORETYPE1")
	)
	(segment
		(start 213.08314 -98.120962)
		(end 214.093044 -98.120962)
		(width 0.11684)
		(layer "In2.Cu")
		(net "CPU0_CORETYPE1")
	)
	(segment
		(start 239.843056 -106.782362)
		(end 239.843056 -149.322536)
		(width 0.11684)
		(layer "In4.Cu")
		(net "CPU0_CORETYPE1")
	)
	(segment
		(start 270.84147 -150.493476)
		(end 274.870164 -146.464782)
		(width 0.11684)
		(layer "In6.Cu")
		(net "CPU0_CORETYPE1")
	)
	(segment
		(start 266.024614 -155.664408)
		(end 270.84147 -150.847552)
		(width 0.11684)
		(layer "In6.Cu")
		(net "CPU0_CORETYPE1")
	)
	(segment
		(start 270.84147 -150.847552)
		(end 270.84147 -150.493476)
		(width 0.11684)
		(layer "In6.Cu")
		(net "CPU0_CORETYPE1")
	)
	(segment
		(start 280.919936 -146.464782)
		(end 286.864298 -152.409144)
		(width 0.11684)
		(layer "In6.Cu")
		(net "CPU0_CORETYPE1")
	)
	(segment
		(start 249.168158 -155.664408)
		(end 266.024614 -155.664408)
		(width 0.11684)
		(layer "In6.Cu")
		(net "CPU0_CORETYPE1")
	)
	(segment
		(start 239.843056 -149.322536)
		(end 242.826286 -149.322536)
		(width 0.11684)
		(layer "In6.Cu")
		(net "CPU0_CORETYPE1")
	)
	(segment
		(start 242.826286 -149.322536)
		(end 249.168158 -155.664408)
		(width 0.11684)
		(layer "In6.Cu")
		(net "CPU0_CORETYPE1")
	)
	(segment
		(start 274.870164 -146.464782)
		(end 280.919936 -146.464782)
		(width 0.11684)
		(layer "In6.Cu")
		(net "CPU0_CORETYPE1")
	)
	(segment
		(start 286.864298 -152.409144)
		(end 286.864298 -156.377132)
		(width 0.11684)
		(layer "In6.Cu")
		(net "CPU0_CORETYPE1")
	)
	(segment
		(start 309.371746 -197.170802)
		(end 313.460384 -201.260456)
		(width 0.10668)
		(layer "F.Cu")
		(net "CPU0_CORETYPE0")
	)
	(segment
		(start 319.22339 -205.470252)
		(end 319.411858 -205.470252)
		(width 0.10668)
		(layer "F.Cu")
		(net "CPU0_CORETYPE0")
	)
	(segment
		(start 313.460384 -201.260456)
		(end 313.460384 -201.261472)
		(width 0.10668)
		(layer "F.Cu")
		(net "CPU0_CORETYPE0")
	)
	(segment
		(start 278.754586 -167.036242)
		(end 285.287212 -173.568868)
		(width 0.10668)
		(layer "F.Cu")
		(net "CPU0_CORETYPE0")
	)
	(segment
		(start 296.199306 -173.568868)
		(end 309.371746 -186.741308)
		(width 0.10668)
		(layer "F.Cu")
		(net "CPU0_CORETYPE0")
	)
	(segment
		(start 286.102298 -156.377132)
		(end 286.102298 -157.675072)
		(width 0.10668)
		(layer "F.Cu")
		(net "CPU0_CORETYPE0")
	)
	(segment
		(start 285.287212 -173.568868)
		(end 296.199306 -173.568868)
		(width 0.10668)
		(layer "F.Cu")
		(net "CPU0_CORETYPE0")
	)
	(segment
		(start 283.155136 -159.471614)
		(end 278.754586 -163.872164)
		(width 0.10668)
		(layer "F.Cu")
		(net "CPU0_CORETYPE0")
	)
	(segment
		(start 188.887608 -99.85629)
		(end 188.887608 -99.317556)
		(width 0.10668)
		(layer "F.Cu")
		(net "CPU0_CORETYPE0")
	)
	(segment
		(start 284.305756 -159.471614)
		(end 283.155136 -159.471614)
		(width 0.10668)
		(layer "F.Cu")
		(net "CPU0_CORETYPE0")
	)
	(segment
		(start 313.460384 -201.261472)
		(end 317.211964 -205.013052)
		(width 0.10668)
		(layer "F.Cu")
		(net "CPU0_CORETYPE0")
	)
	(segment
		(start 286.102298 -157.675072)
		(end 284.305756 -159.471614)
		(width 0.10668)
		(layer "F.Cu")
		(net "CPU0_CORETYPE0")
	)
	(segment
		(start 330.108052 -223.69018)
		(end 329.6412 -223.424242)
		(width 0.10668)
		(layer "F.Cu")
		(net "CPU0_CORETYPE0")
	)
	(segment
		(start 317.211964 -205.013052)
		(end 318.76619 -205.013052)
		(width 0.10668)
		(layer "F.Cu")
		(net "CPU0_CORETYPE0")
	)
	(segment
		(start 309.371746 -186.741308)
		(end 309.371746 -197.170802)
		(width 0.10668)
		(layer "F.Cu")
		(net "CPU0_CORETYPE0")
	)
	(segment
		(start 188.887608 -99.317556)
		(end 188.849 -99.278948)
		(width 0.10668)
		(layer "F.Cu")
		(net "CPU0_CORETYPE0")
	)
	(segment
		(start 318.76619 -205.013052)
		(end 319.22339 -205.470252)
		(width 0.10668)
		(layer "F.Cu")
		(net "CPU0_CORETYPE0")
	)
	(segment
		(start 278.754586 -163.872164)
		(end 278.754586 -167.036242)
		(width 0.10668)
		(layer "F.Cu")
		(net "CPU0_CORETYPE0")
	)
	(segment
		(start 188.849 -99.894898)
		(end 188.887608 -99.85629)
		(width 0.10668)
		(layer "F.Cu")
		(net "CPU0_CORETYPE0")
	)
	(via
		(at 239.208056 -149.322536)
		(size 0.508)
		(drill 0.254)
		(layers "F.Cu" "B.Cu")
		(net "CPU0_CORETYPE0")
	)
	(via
		(at 188.849 -99.278948)
		(size 0.508)
		(drill 0.254)
		(layers "F.Cu" "B.Cu")
		(net "CPU0_CORETYPE0")
	)
	(via
		(at 239.208056 -106.782362)
		(size 0.508)
		(drill 0.254)
		(layers "F.Cu" "B.Cu")
		(net "CPU0_CORETYPE0")
	)
	(via
		(at 319.411858 -205.470252)
		(size 0.508)
		(drill 0.254)
		(layers "F.Cu" "B.Cu")
		(net "CPU0_CORETYPE0")
	)
	(via
		(at 329.6412 -223.424242)
		(size 0.4064)
		(drill 0.2032)
		(layers "F.Cu" "B.Cu")
		(net "CPU0_CORETYPE0")
	)
	(via
		(at 286.102298 -156.377132)
		(size 0.762)
		(drill 0.254)
		(layers "F.Cu" "B.Cu")
		(net "CPU0_CORETYPE0")
	)
	(segment
		(start 318.306958 -204.317346)
		(end 318.306958 -204.359002)
		(width 0.10668)
		(layer "B.Cu")
		(net "CPU0_CORETYPE0")
	)
	(segment
		(start 319.411858 -205.470252)
		(end 319.411858 -212.15985)
		(width 0.10668)
		(layer "B.Cu")
		(net "CPU0_CORETYPE0")
	)
	(segment
		(start 318.306958 -204.359002)
		(end 319.411858 -205.463902)
		(width 0.10668)
		(layer "B.Cu")
		(net "CPU0_CORETYPE0")
	)
	(segment
		(start 319.411858 -212.15985)
		(end 329.6412 -222.389192)
		(width 0.10668)
		(layer "B.Cu")
		(net "CPU0_CORETYPE0")
	)
	(segment
		(start 329.6412 -222.389192)
		(end 329.6412 -223.424242)
		(width 0.10668)
		(layer "B.Cu")
		(net "CPU0_CORETYPE0")
	)
	(segment
		(start 319.411858 -205.463902)
		(end 319.411858 -205.470252)
		(width 0.10668)
		(layer "B.Cu")
		(net "CPU0_CORETYPE0")
	)
	(segment
		(start 215.594692 -99.026218)
		(end 214.267796 -97.699322)
		(width 0.11684)
		(layer "In2.Cu")
		(net "CPU0_CORETYPE0")
	)
	(segment
		(start 213.052152 -97.493582)
		(end 211.790788 -97.493582)
		(width 0.11684)
		(layer "In2.Cu")
		(net "CPU0_CORETYPE0")
	)
	(segment
		(start 202.964034 -94.168214)
		(end 200.986898 -94.168214)
		(width 0.11684)
		(layer "In2.Cu")
		(net "CPU0_CORETYPE0")
	)
	(segment
		(start 214.267796 -97.699322)
		(end 213.257892 -97.699322)
		(width 0.11684)
		(layer "In2.Cu")
		(net "CPU0_CORETYPE0")
	)
	(segment
		(start 188.38418 -98.814128)
		(end 188.849 -99.278948)
		(width 0.11684)
		(layer "In2.Cu")
		(net "CPU0_CORETYPE0")
	)
	(segment
		(start 211.790788 -97.493582)
		(end 209.3341 -95.036894)
		(width 0.11684)
		(layer "In2.Cu")
		(net "CPU0_CORETYPE0")
	)
	(segment
		(start 228.705156 -106.782362)
		(end 220.949012 -99.026218)
		(width 0.11684)
		(layer "In2.Cu")
		(net "CPU0_CORETYPE0")
	)
	(segment
		(start 239.208056 -106.782362)
		(end 228.705156 -106.782362)
		(width 0.11684)
		(layer "In2.Cu")
		(net "CPU0_CORETYPE0")
	)
	(segment
		(start 200.986898 -94.168214)
		(end 199.427084 -95.728028)
		(width 0.11684)
		(layer "In2.Cu")
		(net "CPU0_CORETYPE0")
	)
	(segment
		(start 213.257892 -97.699322)
		(end 213.052152 -97.493582)
		(width 0.11684)
		(layer "In2.Cu")
		(net "CPU0_CORETYPE0")
	)
	(segment
		(start 220.949012 -99.026218)
		(end 215.594692 -99.026218)
		(width 0.11684)
		(layer "In2.Cu")
		(net "CPU0_CORETYPE0")
	)
	(segment
		(start 203.832714 -95.036894)
		(end 202.964034 -94.168214)
		(width 0.11684)
		(layer "In2.Cu")
		(net "CPU0_CORETYPE0")
	)
	(segment
		(start 188.38418 -98.095562)
		(end 188.38418 -98.814128)
		(width 0.11684)
		(layer "In2.Cu")
		(net "CPU0_CORETYPE0")
	)
	(segment
		(start 190.751714 -95.728028)
		(end 188.38418 -98.095562)
		(width 0.11684)
		(layer "In2.Cu")
		(net "CPU0_CORETYPE0")
	)
	(segment
		(start 199.427084 -95.728028)
		(end 190.751714 -95.728028)
		(width 0.11684)
		(layer "In2.Cu")
		(net "CPU0_CORETYPE0")
	)
	(segment
		(start 209.3341 -95.036894)
		(end 203.832714 -95.036894)
		(width 0.11684)
		(layer "In2.Cu")
		(net "CPU0_CORETYPE0")
	)
	(segment
		(start 239.208056 -106.782362)
		(end 239.208056 -149.322536)
		(width 0.11684)
		(layer "In4.Cu")
		(net "CPU0_CORETYPE0")
	)
	(segment
		(start 242.79225 -149.884892)
		(end 248.993406 -156.086048)
		(width 0.11684)
		(layer "In6.Cu")
		(net "CPU0_CORETYPE0")
	)
	(segment
		(start 239.747806 -149.884892)
		(end 242.79225 -149.884892)
		(width 0.11684)
		(layer "In6.Cu")
		(net "CPU0_CORETYPE0")
	)
	(segment
		(start 286.102298 -152.243536)
		(end 286.102298 -156.377132)
		(width 0.11684)
		(layer "In6.Cu")
		(net "CPU0_CORETYPE0")
	)
	(segment
		(start 248.993406 -156.086048)
		(end 266.199366 -156.086048)
		(width 0.11684)
		(layer "In6.Cu")
		(net "CPU0_CORETYPE0")
	)
	(segment
		(start 280.745184 -146.886422)
		(end 286.102298 -152.243536)
		(width 0.11684)
		(layer "In6.Cu")
		(net "CPU0_CORETYPE0")
	)
	(segment
		(start 239.208056 -149.322536)
		(end 239.208056 -149.345142)
		(width 0.11684)
		(layer "In6.Cu")
		(net "CPU0_CORETYPE0")
	)
	(segment
		(start 271.26311 -151.022304)
		(end 271.26311 -150.668228)
		(width 0.11684)
		(layer "In6.Cu")
		(net "CPU0_CORETYPE0")
	)
	(segment
		(start 239.208056 -149.345142)
		(end 239.747806 -149.884892)
		(width 0.11684)
		(layer "In6.Cu")
		(net "CPU0_CORETYPE0")
	)
	(segment
		(start 266.199366 -156.086048)
		(end 271.26311 -151.022304)
		(width 0.11684)
		(layer "In6.Cu")
		(net "CPU0_CORETYPE0")
	)
	(segment
		(start 271.26311 -150.668228)
		(end 275.044916 -146.886422)
		(width 0.11684)
		(layer "In6.Cu")
		(net "CPU0_CORETYPE0")
	)
	(segment
		(start 275.044916 -146.886422)
		(end 280.745184 -146.886422)
		(width 0.11684)
		(layer "In6.Cu")
		(net "CPU0_CORETYPE0")
	)
	(segment
		(start 307.807868 -169.266108)
		(end 305.798728 -167.256968)
		(width 0.10668)
		(layer "F.Cu")
		(net "CPU0_BP3")
	)
	(segment
		(start 303.555908 -163.37915)
		(end 302.777906 -162.601148)
		(width 0.10668)
		(layer "F.Cu")
		(net "CPU0_BP3")
	)
	(segment
		(start 313.9694 -196.556376)
		(end 313.9694 -196.43852)
		(width 0.10668)
		(layer "F.Cu")
		(net "CPU0_BP3")
	)
	(segment
		(start 313.995054 -184.831482)
		(end 307.807868 -178.644296)
		(width 0.10668)
		(layer "F.Cu")
		(net "CPU0_BP3")
	)
	(segment
		(start 313.9694 -196.43852)
		(end 313.995054 -196.412866)
		(width 0.10668)
		(layer "F.Cu")
		(net "CPU0_BP3")
	)
	(segment
		(start 305.798728 -167.256968)
		(end 305.798728 -166.398194)
		(width 0.10668)
		(layer "F.Cu")
		(net "CPU0_BP3")
	)
	(segment
		(start 337.627976 -222.070168)
		(end 337.627976 -221.274894)
		(width 0.10668)
		(layer "F.Cu")
		(net "CPU0_BP3")
	)
	(segment
		(start 318.85001 -60.094876)
		(end 317.26251 -60.094876)
		(width 0.10668)
		(layer "F.Cu")
		(net "CPU0_BP3")
	)
	(segment
		(start 302.777906 -162.601148)
		(end 302.777906 -162.176968)
		(width 0.10668)
		(layer "F.Cu")
		(net "CPU0_BP3")
	)
	(segment
		(start 303.555908 -164.155374)
		(end 303.555908 -163.37915)
		(width 0.10668)
		(layer "F.Cu")
		(net "CPU0_BP3")
	)
	(segment
		(start 305.798728 -166.398194)
		(end 303.555908 -164.155374)
		(width 0.10668)
		(layer "F.Cu")
		(net "CPU0_BP3")
	)
	(segment
		(start 307.807868 -178.644296)
		(end 307.807868 -169.266108)
		(width 0.10668)
		(layer "F.Cu")
		(net "CPU0_BP3")
	)
	(segment
		(start 313.995054 -196.412866)
		(end 313.995054 -184.831482)
		(width 0.10668)
		(layer "F.Cu")
		(net "CPU0_BP3")
	)
	(via
		(at 302.777906 -162.176968)
		(size 0.508)
		(drill 0.254)
		(layers "F.Cu" "B.Cu")
		(net "CPU0_BP3")
	)
	(via
		(at 337.627976 -221.274894)
		(size 0.508)
		(drill 0.254)
		(layers "F.Cu" "B.Cu")
		(net "CPU0_BP3")
	)
	(via
		(at 317.26251 -60.094876)
		(size 0.508)
		(drill 0.254)
		(layers "F.Cu" "B.Cu")
		(net "CPU0_BP3")
	)
	(via
		(at 313.9694 -196.556376)
		(size 0.508)
		(drill 0.254)
		(layers "F.Cu" "B.Cu")
		(net "CPU0_BP3")
	)
	(segment
		(start 323.279008 -195.342002)
		(end 323.279008 -195.662296)
		(width 0.10668)
		(layer "B.Cu")
		(net "CPU0_BP3")
	)
	(segment
		(start 314.733178 -195.068952)
		(end 323.005958 -195.068952)
		(width 0.10668)
		(layer "B.Cu")
		(net "CPU0_BP3")
	)
	(segment
		(start 323.005958 -195.068952)
		(end 323.279008 -195.342002)
		(width 0.10668)
		(layer "B.Cu")
		(net "CPU0_BP3")
	)
	(segment
		(start 337.269582 -220.9165)
		(end 337.627976 -221.274894)
		(width 0.10668)
		(layer "B.Cu")
		(net "CPU0_BP3")
	)
	(segment
		(start 313.995054 -195.807076)
		(end 314.733178 -195.068952)
		(width 0.10668)
		(layer "B.Cu")
		(net "CPU0_BP3")
	)
	(segment
		(start 323.279008 -195.662296)
		(end 325.423276 -195.662296)
		(width 0.10668)
		(layer "B.Cu")
		(net "CPU0_BP3")
	)
	(segment
		(start 313.9694 -196.43852)
		(end 313.995054 -196.412866)
		(width 0.10668)
		(layer "B.Cu")
		(net "CPU0_BP3")
	)
	(segment
		(start 313.995054 -196.412866)
		(end 313.995054 -195.807076)
		(width 0.10668)
		(layer "B.Cu")
		(net "CPU0_BP3")
	)
	(segment
		(start 325.423276 -195.662296)
		(end 337.269582 -207.508602)
		(width 0.10668)
		(layer "B.Cu")
		(net "CPU0_BP3")
	)
	(segment
		(start 313.9694 -196.556376)
		(end 313.9694 -196.43852)
		(width 0.10668)
		(layer "B.Cu")
		(net "CPU0_BP3")
	)
	(segment
		(start 337.269582 -207.508602)
		(end 337.269582 -220.9165)
		(width 0.10668)
		(layer "B.Cu")
		(net "CPU0_BP3")
	)
	(segment
		(start 315.08446 -72.176386)
		(end 315.08446 -62.272926)
		(width 0.11684)
		(layer "In11.Cu")
		(net "CPU0_BP3")
	)
	(segment
		(start 326.82688 -83.918806)
		(end 315.08446 -72.176386)
		(width 0.11684)
		(layer "In11.Cu")
		(net "CPU0_BP3")
	)
	(segment
		(start 302.776128 -160.490408)
		(end 297.17746 -154.89174)
		(width 0.11684)
		(layer "In11.Cu")
		(net "CPU0_BP3")
	)
	(segment
		(start 310.66994 -104.93502)
		(end 326.82688 -88.77808)
		(width 0.11684)
		(layer "In11.Cu")
		(net "CPU0_BP3")
	)
	(segment
		(start 297.17746 -135.58774)
		(end 310.66994 -122.09526)
		(width 0.11684)
		(layer "In11.Cu")
		(net "CPU0_BP3")
	)
	(segment
		(start 302.776128 -162.17519)
		(end 302.776128 -160.490408)
		(width 0.11684)
		(layer "In11.Cu")
		(net "CPU0_BP3")
	)
	(segment
		(start 326.82688 -88.77808)
		(end 326.82688 -83.918806)
		(width 0.11684)
		(layer "In11.Cu")
		(net "CPU0_BP3")
	)
	(segment
		(start 297.17746 -154.89174)
		(end 297.17746 -135.58774)
		(width 0.11684)
		(layer "In11.Cu")
		(net "CPU0_BP3")
	)
	(segment
		(start 302.777906 -162.176968)
		(end 302.776128 -162.17519)
		(width 0.11684)
		(layer "In11.Cu")
		(net "CPU0_BP3")
	)
	(segment
		(start 315.08446 -62.272926)
		(end 317.26251 -60.094876)
		(width 0.11684)
		(layer "In11.Cu")
		(net "CPU0_BP3")
	)
	(segment
		(start 310.66994 -122.09526)
		(end 310.66994 -104.93502)
		(width 0.11684)
		(layer "In11.Cu")
		(net "CPU0_BP3")
	)
	(segment
		(start 308.176422 -178.491388)
		(end 308.176422 -169.235628)
		(width 0.10668)
		(layer "F.Cu")
		(net "CPU0_BP2")
	)
	(segment
		(start 306.167282 -166.245286)
		(end 303.924462 -164.002466)
		(width 0.10668)
		(layer "F.Cu")
		(net "CPU0_BP2")
	)
	(segment
		(start 314.393834 -196.284342)
		(end 314.393834 -184.7088)
		(width 0.10668)
		(layer "F.Cu")
		(net "CPU0_BP2")
	)
	(segment
		(start 315.228478 -198.698612)
		(end 315.228478 -198.299578)
		(width 0.10668)
		(layer "F.Cu")
		(net "CPU0_BP2")
	)
	(segment
		(start 318.85001 -61.364876)
		(end 317.26251 -61.364876)
		(width 0.10668)
		(layer "F.Cu")
		(net "CPU0_BP2")
	)
	(segment
		(start 303.924462 -164.002466)
		(end 303.924462 -163.112704)
		(width 0.10668)
		(layer "F.Cu")
		(net "CPU0_BP2")
	)
	(segment
		(start 336.687922 -222.070168)
		(end 336.687922 -221.274894)
		(width 0.10668)
		(layer "F.Cu")
		(net "CPU0_BP2")
	)
	(segment
		(start 314.393834 -184.7088)
		(end 308.176422 -178.491388)
		(width 0.10668)
		(layer "F.Cu")
		(net "CPU0_BP2")
	)
	(segment
		(start 303.924462 -163.112704)
		(end 303.412906 -162.601148)
		(width 0.10668)
		(layer "F.Cu")
		(net "CPU0_BP2")
	)
	(segment
		(start 315.228478 -198.299578)
		(end 314.393834 -196.284342)
		(width 0.10668)
		(layer "F.Cu")
		(net "CPU0_BP2")
	)
	(segment
		(start 303.412906 -162.601148)
		(end 303.412906 -162.176968)
		(width 0.10668)
		(layer "F.Cu")
		(net "CPU0_BP2")
	)
	(segment
		(start 306.167282 -167.226488)
		(end 306.167282 -166.245286)
		(width 0.10668)
		(layer "F.Cu")
		(net "CPU0_BP2")
	)
	(segment
		(start 308.176422 -169.235628)
		(end 306.167282 -167.226488)
		(width 0.10668)
		(layer "F.Cu")
		(net "CPU0_BP2")
	)
	(via
		(at 317.26251 -61.364876)
		(size 0.508)
		(drill 0.254)
		(layers "F.Cu" "B.Cu")
		(net "CPU0_BP2")
	)
	(via
		(at 303.412906 -162.176968)
		(size 0.508)
		(drill 0.254)
		(layers "F.Cu" "B.Cu")
		(net "CPU0_BP2")
	)
	(via
		(at 336.687922 -221.274894)
		(size 0.508)
		(drill 0.254)
		(layers "F.Cu" "B.Cu")
		(net "CPU0_BP2")
	)
	(via
		(at 315.228478 -198.698612)
		(size 0.508)
		(drill 0.254)
		(layers "F.Cu" "B.Cu")
		(net "CPU0_BP2")
	)
	(segment
		(start 323.279008 -196.678296)
		(end 326.040242 -196.678296)
		(width 0.10668)
		(layer "B.Cu")
		(net "CPU0_BP2")
	)
	(segment
		(start 323.25564 -196.701664)
		(end 323.279008 -196.678296)
		(width 0.10668)
		(layer "B.Cu")
		(net "CPU0_BP2")
	)
	(segment
		(start 323.25564 -196.978016)
		(end 323.25564 -196.701664)
		(width 0.10668)
		(layer "B.Cu")
		(net "CPU0_BP2")
	)
	(segment
		(start 322.203826 -197.31482)
		(end 322.918836 -197.31482)
		(width 0.10668)
		(layer "B.Cu")
		(net "CPU0_BP2")
	)
	(segment
		(start 316.51829 -196.53504)
		(end 321.424046 -196.53504)
		(width 0.10668)
		(layer "B.Cu")
		(net "CPU0_BP2")
	)
	(segment
		(start 321.424046 -196.53504)
		(end 322.203826 -197.31482)
		(width 0.10668)
		(layer "B.Cu")
		(net "CPU0_BP2")
	)
	(segment
		(start 322.918836 -197.31482)
		(end 323.25564 -196.978016)
		(width 0.10668)
		(layer "B.Cu")
		(net "CPU0_BP2")
	)
	(segment
		(start 315.228478 -197.824852)
		(end 316.51829 -196.53504)
		(width 0.10668)
		(layer "B.Cu")
		(net "CPU0_BP2")
	)
	(segment
		(start 315.228478 -198.698612)
		(end 315.228478 -197.824852)
		(width 0.10668)
		(layer "B.Cu")
		(net "CPU0_BP2")
	)
	(segment
		(start 336.687922 -207.325976)
		(end 336.687922 -221.274894)
		(width 0.10668)
		(layer "B.Cu")
		(net "CPU0_BP2")
	)
	(segment
		(start 326.040242 -196.678296)
		(end 336.687922 -207.325976)
		(width 0.10668)
		(layer "B.Cu")
		(net "CPU0_BP2")
	)
	(segment
		(start 315.635132 -62.992254)
		(end 317.26251 -61.364876)
		(width 0.11684)
		(layer "In11.Cu")
		(net "CPU0_BP2")
	)
	(segment
		(start 315.635132 -72.130666)
		(end 315.635132 -62.992254)
		(width 0.11684)
		(layer "In11.Cu")
		(net "CPU0_BP2")
	)
	(segment
		(start 297.5991 -135.762492)
		(end 311.09158 -122.270012)
		(width 0.11684)
		(layer "In11.Cu")
		(net "CPU0_BP2")
	)
	(segment
		(start 303.411128 -160.227264)
		(end 297.5991 -154.415236)
		(width 0.11684)
		(layer "In11.Cu")
		(net "CPU0_BP2")
	)
	(segment
		(start 327.24852 -90.343228)
		(end 327.24852 -83.744054)
		(width 0.11684)
		(layer "In11.Cu")
		(net "CPU0_BP2")
	)
	(segment
		(start 303.412906 -162.176968)
		(end 303.411128 -162.17519)
		(width 0.11684)
		(layer "In11.Cu")
		(net "CPU0_BP2")
	)
	(segment
		(start 327.24852 -83.744054)
		(end 315.635132 -72.130666)
		(width 0.11684)
		(layer "In11.Cu")
		(net "CPU0_BP2")
	)
	(segment
		(start 303.411128 -162.17519)
		(end 303.411128 -160.227264)
		(width 0.11684)
		(layer "In11.Cu")
		(net "CPU0_BP2")
	)
	(segment
		(start 311.09158 -122.270012)
		(end 311.09158 -106.500168)
		(width 0.11684)
		(layer "In11.Cu")
		(net "CPU0_BP2")
	)
	(segment
		(start 297.5991 -154.415236)
		(end 297.5991 -135.762492)
		(width 0.11684)
		(layer "In11.Cu")
		(net "CPU0_BP2")
	)
	(segment
		(start 311.09158 -106.500168)
		(end 327.24852 -90.343228)
		(width 0.11684)
		(layer "In11.Cu")
		(net "CPU0_BP2")
	)
	(segment
		(start 308.549548 -169.209974)
		(end 308.549548 -178.336702)
		(width 0.10668)
		(layer "F.Cu")
		(net "CPU0_BP1")
	)
	(segment
		(start 304.047906 -162.601148)
		(end 304.297588 -162.85083)
		(width 0.10668)
		(layer "F.Cu")
		(net "CPU0_BP1")
	)
	(segment
		(start 314.734194 -184.521348)
		(end 314.734194 -196.16293)
		(width 0.10668)
		(layer "F.Cu")
		(net "CPU0_BP1")
	)
	(segment
		(start 318.85001 -62.634876)
		(end 317.26251 -62.634876)
		(width 0.10668)
		(layer "F.Cu")
		(net "CPU0_BP1")
	)
	(segment
		(start 308.549548 -178.336702)
		(end 314.734194 -184.521348)
		(width 0.10668)
		(layer "F.Cu")
		(net "CPU0_BP1")
	)
	(segment
		(start 314.734194 -196.16293)
		(end 315.279786 -197.47992)
		(width 0.10668)
		(layer "F.Cu")
		(net "CPU0_BP1")
	)
	(segment
		(start 304.047906 -162.176968)
		(end 304.047906 -162.601148)
		(width 0.10668)
		(layer "F.Cu")
		(net "CPU0_BP1")
	)
	(segment
		(start 315.279786 -197.47992)
		(end 315.774578 -197.974712)
		(width 0.10668)
		(layer "F.Cu")
		(net "CPU0_BP1")
	)
	(segment
		(start 304.297588 -162.85083)
		(end 304.297588 -163.84778)
		(width 0.10668)
		(layer "F.Cu")
		(net "CPU0_BP1")
	)
	(segment
		(start 337.627976 -223.69018)
		(end 337.161124 -223.424242)
		(width 0.10668)
		(layer "F.Cu")
		(net "CPU0_BP1")
	)
	(segment
		(start 306.540408 -166.0906)
		(end 306.540408 -167.200834)
		(width 0.10668)
		(layer "F.Cu")
		(net "CPU0_BP1")
	)
	(segment
		(start 304.297588 -163.84778)
		(end 306.540408 -166.0906)
		(width 0.10668)
		(layer "F.Cu")
		(net "CPU0_BP1")
	)
	(segment
		(start 306.540408 -167.200834)
		(end 308.549548 -169.209974)
		(width 0.10668)
		(layer "F.Cu")
		(net "CPU0_BP1")
	)
	(via
		(at 315.774578 -197.974712)
		(size 0.508)
		(drill 0.254)
		(layers "F.Cu" "B.Cu")
		(net "CPU0_BP1")
	)
	(via
		(at 337.161124 -223.424242)
		(size 0.4064)
		(drill 0.2032)
		(layers "F.Cu" "B.Cu")
		(net "CPU0_BP1")
	)
	(via
		(at 304.047906 -162.176968)
		(size 0.508)
		(drill 0.254)
		(layers "F.Cu" "B.Cu")
		(net "CPU0_BP1")
	)
	(via
		(at 317.26251 -62.634876)
		(size 0.508)
		(drill 0.254)
		(layers "F.Cu" "B.Cu")
		(net "CPU0_BP1")
	)
	(segment
		(start 320.973704 -196.973952)
		(end 321.247008 -197.247256)
		(width 0.10668)
		(layer "B.Cu")
		(net "CPU0_BP1")
	)
	(segment
		(start 336.109564 -207.146652)
		(end 336.109564 -221.453964)
		(width 0.10668)
		(layer "B.Cu")
		(net "CPU0_BP1")
	)
	(segment
		(start 321.247008 -197.567296)
		(end 321.360292 -197.68058)
		(width 0.10668)
		(layer "B.Cu")
		(net "CPU0_BP1")
	)
	(segment
		(start 336.109564 -221.453964)
		(end 337.161124 -222.505524)
		(width 0.10668)
		(layer "B.Cu")
		(net "CPU0_BP1")
	)
	(segment
		(start 337.161124 -222.505524)
		(end 337.161124 -223.424242)
		(width 0.10668)
		(layer "B.Cu")
		(net "CPU0_BP1")
	)
	(segment
		(start 326.643492 -197.68058)
		(end 336.109564 -207.146652)
		(width 0.10668)
		(layer "B.Cu")
		(net "CPU0_BP1")
	)
	(segment
		(start 321.247008 -197.247256)
		(end 321.247008 -197.567296)
		(width 0.10668)
		(layer "B.Cu")
		(net "CPU0_BP1")
	)
	(segment
		(start 315.774578 -197.974712)
		(end 316.775338 -196.973952)
		(width 0.10668)
		(layer "B.Cu")
		(net "CPU0_BP1")
	)
	(segment
		(start 316.775338 -196.973952)
		(end 320.973704 -196.973952)
		(width 0.10668)
		(layer "B.Cu")
		(net "CPU0_BP1")
	)
	(segment
		(start 321.360292 -197.68058)
		(end 326.643492 -197.68058)
		(width 0.10668)
		(layer "B.Cu")
		(net "CPU0_BP1")
	)
	(segment
		(start 304.046128 -159.96412)
		(end 298.02074 -153.938732)
		(width 0.11684)
		(layer "In11.Cu")
		(net "CPU0_BP1")
	)
	(segment
		(start 327.67016 -90.51798)
		(end 327.67016 -83.569302)
		(width 0.11684)
		(layer "In11.Cu")
		(net "CPU0_BP1")
	)
	(segment
		(start 298.02074 -153.938732)
		(end 298.02074 -135.937244)
		(width 0.11684)
		(layer "In11.Cu")
		(net "CPU0_BP1")
	)
	(segment
		(start 327.67016 -83.569302)
		(end 317.26251 -73.161652)
		(width 0.11684)
		(layer "In11.Cu")
		(net "CPU0_BP1")
	)
	(segment
		(start 304.046128 -162.17519)
		(end 304.046128 -159.96412)
		(width 0.11684)
		(layer "In11.Cu")
		(net "CPU0_BP1")
	)
	(segment
		(start 311.51322 -106.67492)
		(end 327.67016 -90.51798)
		(width 0.11684)
		(layer "In11.Cu")
		(net "CPU0_BP1")
	)
	(segment
		(start 298.02074 -135.937244)
		(end 311.51322 -122.444764)
		(width 0.11684)
		(layer "In11.Cu")
		(net "CPU0_BP1")
	)
	(segment
		(start 317.26251 -73.161652)
		(end 317.26251 -65.295272)
		(width 0.11684)
		(layer "In11.Cu")
		(net "CPU0_BP1")
	)
	(segment
		(start 316.472316 -64.505078)
		(end 316.472316 -63.42507)
		(width 0.11684)
		(layer "In11.Cu")
		(net "CPU0_BP1")
	)
	(segment
		(start 311.51322 -122.444764)
		(end 311.51322 -106.67492)
		(width 0.11684)
		(layer "In11.Cu")
		(net "CPU0_BP1")
	)
	(segment
		(start 316.472316 -63.42507)
		(end 317.26251 -62.634876)
		(width 0.11684)
		(layer "In11.Cu")
		(net "CPU0_BP1")
	)
	(segment
		(start 304.047906 -162.176968)
		(end 304.046128 -162.17519)
		(width 0.11684)
		(layer "In11.Cu")
		(net "CPU0_BP1")
	)
	(segment
		(start 317.26251 -65.295272)
		(end 316.472316 -64.505078)
		(width 0.11684)
		(layer "In11.Cu")
		(net "CPU0_BP1")
	)
	(segment
		(start 308.934866 -169.196512)
		(end 308.934866 -178.176936)
		(width 0.10668)
		(layer "F.Cu")
		(net "CPU0_BP0")
	)
	(segment
		(start 315.099954 -196.164454)
		(end 315.416438 -196.928486)
		(width 0.10668)
		(layer "F.Cu")
		(net "CPU0_BP0")
	)
	(segment
		(start 308.934866 -178.176936)
		(end 315.099954 -184.342024)
		(width 0.10668)
		(layer "F.Cu")
		(net "CPU0_BP0")
	)
	(segment
		(start 304.682906 -163.688014)
		(end 306.925726 -165.930834)
		(width 0.10668)
		(layer "F.Cu")
		(net "CPU0_BP0")
	)
	(segment
		(start 315.099954 -184.342024)
		(end 315.099954 -196.164454)
		(width 0.10668)
		(layer "F.Cu")
		(net "CPU0_BP0")
	)
	(segment
		(start 318.85001 -63.904876)
		(end 317.26251 -63.904876)
		(width 0.10668)
		(layer "F.Cu")
		(net "CPU0_BP0")
	)
	(segment
		(start 306.925726 -165.930834)
		(end 306.925726 -167.187372)
		(width 0.10668)
		(layer "F.Cu")
		(net "CPU0_BP0")
	)
	(segment
		(start 316.777878 -198.724774)
		(end 317.02502 -198.971916)
		(width 0.10668)
		(layer "F.Cu")
		(net "CPU0_BP0")
	)
	(segment
		(start 336.687922 -223.69018)
		(end 336.22107 -223.424242)
		(width 0.10668)
		(layer "F.Cu")
		(net "CPU0_BP0")
	)
	(segment
		(start 315.416438 -196.928486)
		(end 316.777878 -198.289926)
		(width 0.10668)
		(layer "F.Cu")
		(net "CPU0_BP0")
	)
	(segment
		(start 316.777878 -198.289926)
		(end 316.777878 -198.724774)
		(width 0.10668)
		(layer "F.Cu")
		(net "CPU0_BP0")
	)
	(segment
		(start 306.925726 -167.187372)
		(end 308.934866 -169.196512)
		(width 0.10668)
		(layer "F.Cu")
		(net "CPU0_BP0")
	)
	(segment
		(start 304.682906 -162.176968)
		(end 304.682906 -163.688014)
		(width 0.10668)
		(layer "F.Cu")
		(net "CPU0_BP0")
	)
	(via
		(at 317.26251 -63.904876)
		(size 0.508)
		(drill 0.254)
		(layers "F.Cu" "B.Cu")
		(net "CPU0_BP0")
	)
	(via
		(at 317.02502 -198.971916)
		(size 0.508)
		(drill 0.254)
		(layers "F.Cu" "B.Cu")
		(net "CPU0_BP0")
	)
	(via
		(at 336.22107 -223.424242)
		(size 0.4064)
		(drill 0.2032)
		(layers "F.Cu" "B.Cu")
		(net "CPU0_BP0")
	)
	(via
		(at 304.682906 -162.176968)
		(size 0.508)
		(drill 0.254)
		(layers "F.Cu" "B.Cu")
		(net "CPU0_BP0")
	)
	(segment
		(start 336.22107 -222.381064)
		(end 335.64957 -221.809564)
		(width 0.10668)
		(layer "B.Cu")
		(net "CPU0_BP0")
	)
	(segment
		(start 336.22107 -223.424242)
		(end 336.22107 -222.381064)
		(width 0.10668)
		(layer "B.Cu")
		(net "CPU0_BP0")
	)
	(segment
		(start 317.104014 -198.971916)
		(end 317.397638 -198.678292)
		(width 0.10668)
		(layer "B.Cu")
		(net "CPU0_BP0")
	)
	(segment
		(start 335.64957 -207.14462)
		(end 326.558656 -198.053706)
		(width 0.10668)
		(layer "B.Cu")
		(net "CPU0_BP0")
	)
	(segment
		(start 319.002664 -199.144636)
		(end 321.092576 -199.144636)
		(width 0.10668)
		(layer "B.Cu")
		(net "CPU0_BP0")
	)
	(segment
		(start 326.558656 -198.053706)
		(end 321.776598 -198.053706)
		(width 0.10668)
		(layer "B.Cu")
		(net "CPU0_BP0")
	)
	(segment
		(start 321.776598 -198.053706)
		(end 321.247008 -198.583296)
		(width 0.10668)
		(layer "B.Cu")
		(net "CPU0_BP0")
	)
	(segment
		(start 335.64957 -221.809564)
		(end 335.64957 -207.14462)
		(width 0.10668)
		(layer "B.Cu")
		(net "CPU0_BP0")
	)
	(segment
		(start 317.397638 -198.678292)
		(end 318.53632 -198.678292)
		(width 0.10668)
		(layer "B.Cu")
		(net "CPU0_BP0")
	)
	(segment
		(start 321.092576 -199.144636)
		(end 321.22364 -199.013572)
		(width 0.10668)
		(layer "B.Cu")
		(net "CPU0_BP0")
	)
	(segment
		(start 318.53632 -198.678292)
		(end 319.002664 -199.144636)
		(width 0.10668)
		(layer "B.Cu")
		(net "CPU0_BP0")
	)
	(segment
		(start 317.02502 -198.971916)
		(end 317.104014 -198.971916)
		(width 0.10668)
		(layer "B.Cu")
		(net "CPU0_BP0")
	)
	(segment
		(start 321.22364 -199.013572)
		(end 321.22364 -198.606664)
		(width 0.10668)
		(layer "B.Cu")
		(net "CPU0_BP0")
	)
	(segment
		(start 321.22364 -198.606664)
		(end 321.247008 -198.583296)
		(width 0.10668)
		(layer "B.Cu")
		(net "CPU0_BP0")
	)
	(segment
		(start 328.0918 -83.39455)
		(end 317.927482 -73.230232)
		(width 0.11684)
		(layer "In11.Cu")
		(net "CPU0_BP0")
	)
	(segment
		(start 311.93486 -122.619516)
		(end 311.93486 -108.792772)
		(width 0.11684)
		(layer "In11.Cu")
		(net "CPU0_BP0")
	)
	(segment
		(start 317.927482 -64.569848)
		(end 317.26251 -63.904876)
		(width 0.11684)
		(layer "In11.Cu")
		(net "CPU0_BP0")
	)
	(segment
		(start 298.44238 -153.462228)
		(end 298.44238 -136.111996)
		(width 0.11684)
		(layer "In11.Cu")
		(net "CPU0_BP0")
	)
	(segment
		(start 298.44238 -136.111996)
		(end 311.93486 -122.619516)
		(width 0.11684)
		(layer "In11.Cu")
		(net "CPU0_BP0")
	)
	(segment
		(start 328.0918 -92.635832)
		(end 328.0918 -83.39455)
		(width 0.11684)
		(layer "In11.Cu")
		(net "CPU0_BP0")
	)
	(segment
		(start 304.467768 -159.487616)
		(end 298.44238 -153.462228)
		(width 0.11684)
		(layer "In11.Cu")
		(net "CPU0_BP0")
	)
	(segment
		(start 304.467768 -161.96183)
		(end 304.467768 -159.487616)
		(width 0.11684)
		(layer "In11.Cu")
		(net "CPU0_BP0")
	)
	(segment
		(start 304.682906 -162.176968)
		(end 304.467768 -161.96183)
		(width 0.11684)
		(layer "In11.Cu")
		(net "CPU0_BP0")
	)
	(segment
		(start 311.93486 -108.792772)
		(end 328.0918 -92.635832)
		(width 0.11684)
		(layer "In11.Cu")
		(net "CPU0_BP0")
	)
	(segment
		(start 317.927482 -73.230232)
		(end 317.927482 -64.569848)
		(width 0.11684)
		(layer "In11.Cu")
		(net "CPU0_BP0")
	)
	(segment
		(start 167.53205 -121.580148)
		(end 167.907462 -121.580148)
		(width 0.10668)
		(layer "F.Cu")
		(net "CPLD_PROGRAMN")
	)
	(segment
		(start 167.53205 -120.360948)
		(end 167.53205 -121.580148)
		(width 0.10668)
		(layer "F.Cu")
		(net "CPLD_PROGRAMN")
	)
	(segment
		(start 167.907462 -121.580148)
		(end 168.148 -121.33961)
		(width 0.10668)
		(layer "F.Cu")
		(net "CPLD_PROGRAMN")
	)
	(segment
		(start 168.148 -121.33961)
		(end 168.148 -120.360948)
		(width 0.10668)
		(layer "F.Cu")
		(net "CPLD_PROGRAMN")
	)
	(segment
		(start 180.32222 -117.852952)
		(end 179.93233 -118.242842)
		(width 0.10668)
		(layer "F.Cu")
		(net "CPLD_PROGRAMN")
	)
	(via
		(at 179.93233 -118.242842)
		(size 0.4572)
		(drill 0.254)
		(layers "F.Cu" "B.Cu")
		(net "CPLD_PROGRAMN")
	)
	(via
		(at 167.53205 -121.580148)
		(size 0.762)
		(drill 0.381)
		(layers "F.Cu" "B.Cu")
		(net "CPLD_PROGRAMN")
	)
	(via
		(at 168.148 -120.360948)
		(size 0.508)
		(drill 0.254)
		(layers "F.Cu" "B.Cu")
		(net "CPLD_PROGRAMN")
	)
	(segment
		(start 180.327808 -117.288564)
		(end 180.070506 -117.031262)
		(width 0.11684)
		(layer "In6.Cu")
		(net "CPLD_PROGRAMN")
	)
	(segment
		(start 180.070506 -117.031262)
		(end 175.387762 -117.031262)
		(width 0.11684)
		(layer "In6.Cu")
		(net "CPLD_PROGRAMN")
	)
	(segment
		(start 179.977542 -118.242842)
		(end 180.327808 -117.892576)
		(width 0.11684)
		(layer "In6.Cu")
		(net "CPLD_PROGRAMN")
	)
	(segment
		(start 173.566328 -118.852696)
		(end 169.656252 -118.852696)
		(width 0.11684)
		(layer "In6.Cu")
		(net "CPLD_PROGRAMN")
	)
	(segment
		(start 175.387762 -117.031262)
		(end 173.566328 -118.852696)
		(width 0.11684)
		(layer "In6.Cu")
		(net "CPLD_PROGRAMN")
	)
	(segment
		(start 179.93233 -118.242842)
		(end 179.977542 -118.242842)
		(width 0.11684)
		(layer "In6.Cu")
		(net "CPLD_PROGRAMN")
	)
	(segment
		(start 180.327808 -117.892576)
		(end 180.327808 -117.288564)
		(width 0.11684)
		(layer "In6.Cu")
		(net "CPLD_PROGRAMN")
	)
	(segment
		(start 169.656252 -118.852696)
		(end 168.148 -120.360948)
		(width 0.11684)
		(layer "In6.Cu")
		(net "CPLD_PROGRAMN")
	)
	(segment
		(start 167.68953 -119.850916)
		(end 169.397426 -119.850916)
		(width 0.10668)
		(layer "F.Cu")
		(net "CPLD_JTAG_EN")
	)
	(segment
		(start 167.53205 -119.344948)
		(end 167.53205 -119.693436)
		(width 0.10668)
		(layer "F.Cu")
		(net "CPLD_JTAG_EN")
	)
	(segment
		(start 167.53205 -119.693436)
		(end 167.68953 -119.850916)
		(width 0.10668)
		(layer "F.Cu")
		(net "CPLD_JTAG_EN")
	)
	(segment
		(start 169.66438 -119.850916)
		(end 170.18 -119.335296)
		(width 0.10668)
		(layer "F.Cu")
		(net "CPLD_JTAG_EN")
	)
	(segment
		(start 180.32222 -117.052852)
		(end 179.93233 -117.442742)
		(width 0.10668)
		(layer "F.Cu")
		(net "CPLD_JTAG_EN")
	)
	(segment
		(start 169.397426 -119.850916)
		(end 169.66438 -119.850916)
		(width 0.10668)
		(layer "F.Cu")
		(net "CPLD_JTAG_EN")
	)
	(via
		(at 179.93233 -117.442742)
		(size 0.4572)
		(drill 0.254)
		(layers "F.Cu" "B.Cu")
		(net "CPLD_JTAG_EN")
	)
	(via
		(at 170.18 -119.335296)
		(size 0.508)
		(drill 0.254)
		(layers "F.Cu" "B.Cu")
		(net "CPLD_JTAG_EN")
	)
	(via
		(at 169.397426 -119.850916)
		(size 0.4064)
		(drill 0.2032)
		(layers "F.Cu" "B.Cu")
		(net "CPLD_JTAG_EN")
	)
	(segment
		(start 172.631608 -119.335296)
		(end 170.18 -119.335296)
		(width 0.11684)
		(layer "In6.Cu")
		(net "CPLD_JTAG_EN")
	)
	(segment
		(start 179.533296 -117.841776)
		(end 176.332388 -117.841776)
		(width 0.11684)
		(layer "In6.Cu")
		(net "CPLD_JTAG_EN")
	)
	(segment
		(start 173.721268 -119.340376)
		(end 172.636688 -119.340376)
		(width 0.11684)
		(layer "In6.Cu")
		(net "CPLD_JTAG_EN")
	)
	(segment
		(start 176.332388 -117.841776)
		(end 176.124108 -117.633496)
		(width 0.11684)
		(layer "In6.Cu")
		(net "CPLD_JTAG_EN")
	)
	(segment
		(start 179.93233 -117.442742)
		(end 179.533296 -117.841776)
		(width 0.11684)
		(layer "In6.Cu")
		(net "CPLD_JTAG_EN")
	)
	(segment
		(start 176.124108 -117.633496)
		(end 175.428148 -117.633496)
		(width 0.11684)
		(layer "In6.Cu")
		(net "CPLD_JTAG_EN")
	)
	(segment
		(start 172.636688 -119.340376)
		(end 172.631608 -119.335296)
		(width 0.11684)
		(layer "In6.Cu")
		(net "CPLD_JTAG_EN")
	)
	(segment
		(start 175.428148 -117.633496)
		(end 173.721268 -119.340376)
		(width 0.11684)
		(layer "In6.Cu")
		(net "CPLD_JTAG_EN")
	)
	(segment
		(start 303.653952 -20.958556)
		(end 302.66005 -19.964654)
		(width 0.10668)
		(layer "F.Cu")
		(net "CLR_CMOS_N")
	)
	(segment
		(start 302.66005 -19.964654)
		(end 302.194214 -19.964654)
		(width 0.10668)
		(layer "F.Cu")
		(net "CLR_CMOS_N")
	)
	(segment
		(start 301.871888 -19.642328)
		(end 301.871888 -19.09699)
		(width 0.10668)
		(layer "F.Cu")
		(net "CLR_CMOS_N")
	)
	(segment
		(start 302.194214 -19.964654)
		(end 301.871888 -19.642328)
		(width 0.10668)
		(layer "F.Cu")
		(net "CLR_CMOS_N")
	)
	(segment
		(start 303.653952 -21.12645)
		(end 303.653952 -22.34565)
		(width 0.10668)
		(layer "F.Cu")
		(net "CLR_CMOS_N")
	)
	(segment
		(start 303.653952 -21.12645)
		(end 303.653952 -20.958556)
		(width 0.10668)
		(layer "F.Cu")
		(net "CLR_CMOS_N")
	)
	(via
		(at 303.653952 -21.12645)
		(size 0.762)
		(drill 0.381)
		(layers "F.Cu" "B.Cu")
		(net "CLR_CMOS_N")
	)
	(segment
		(start 301.221902 -19.09699)
		(end 301.221902 -20.99691)
		(width 0.10668)
		(layer "F.Cu")
		(net "CLR_CMOS")
	)
	(segment
		(start 301.221902 -20.99691)
		(end 301.221902 -22.12975)
		(width 0.10668)
		(layer "F.Cu")
		(net "CLR_CMOS")
	)
	(segment
		(start 301.221902 -22.12975)
		(end 301.221902 -23.14575)
		(width 0.10668)
		(layer "F.Cu")
		(net "CLR_CMOS")
	)
	(segment
		(start 301.221902 -23.14575)
		(end 301.221902 -23.783036)
		(width 0.10668)
		(layer "F.Cu")
		(net "CLR_CMOS")
	)
	(via
		(at 240.12652 -59.426348)
		(size 0.508)
		(drill 0.254)
		(layers "F.Cu" "B.Cu")
		(net "CLR_CMOS")
	)
	(via
		(at 301.221902 -23.783036)
		(size 0.508)
		(drill 0.254)
		(layers "F.Cu" "B.Cu")
		(net "CLR_CMOS")
	)
	(via
		(at 238.744252 -98.151442)
		(size 0.508)
		(drill 0.254)
		(layers "F.Cu" "B.Cu")
		(net "CLR_CMOS")
	)
	(via
		(at 187.871608 -99.278948)
		(size 0.508)
		(drill 0.254)
		(layers "F.Cu" "B.Cu")
		(net "CLR_CMOS")
	)
	(segment
		(start 187.871608 -99.890326)
		(end 187.871608 -99.278948)
		(width 0.10668)
		(layer "B.Cu")
		(net "CLR_CMOS")
	)
	(segment
		(start 261.34314 -51.01717)
		(end 266.23391 -46.1264)
		(width 0.11684)
		(layer "In6.Cu")
		(net "CLR_CMOS")
	)
	(segment
		(start 261.34314 -57.275984)
		(end 261.34314 -51.01717)
		(width 0.11684)
		(layer "In6.Cu")
		(net "CLR_CMOS")
	)
	(segment
		(start 299.041566 -25.963372)
		(end 301.221902 -23.783036)
		(width 0.11684)
		(layer "In6.Cu")
		(net "CLR_CMOS")
	)
	(segment
		(start 252.58522 -59.1312)
		(end 255.1811 -59.1312)
		(width 0.11684)
		(layer "In6.Cu")
		(net "CLR_CMOS")
	)
	(segment
		(start 255.1811 -59.1312)
		(end 255.874266 -59.824366)
		(width 0.11684)
		(layer "In6.Cu")
		(net "CLR_CMOS")
	)
	(segment
		(start 258.794758 -59.824366)
		(end 261.34314 -57.275984)
		(width 0.11684)
		(layer "In6.Cu")
		(net "CLR_CMOS")
	)
	(segment
		(start 252.290072 -59.426348)
		(end 252.58522 -59.1312)
		(width 0.11684)
		(layer "In6.Cu")
		(net "CLR_CMOS")
	)
	(segment
		(start 293.439088 -25.963372)
		(end 299.041566 -25.963372)
		(width 0.11684)
		(layer "In6.Cu")
		(net "CLR_CMOS")
	)
	(segment
		(start 266.23391 -46.1264)
		(end 273.27606 -46.1264)
		(width 0.11684)
		(layer "In6.Cu")
		(net "CLR_CMOS")
	)
	(segment
		(start 255.874266 -59.824366)
		(end 258.794758 -59.824366)
		(width 0.11684)
		(layer "In6.Cu")
		(net "CLR_CMOS")
	)
	(segment
		(start 240.12652 -59.426348)
		(end 252.290072 -59.426348)
		(width 0.11684)
		(layer "In6.Cu")
		(net "CLR_CMOS")
	)
	(segment
		(start 273.27606 -46.1264)
		(end 293.439088 -25.963372)
		(width 0.11684)
		(layer "In6.Cu")
		(net "CLR_CMOS")
	)
	(segment
		(start 240.12652 -65.342516)
		(end 238.48568 -66.983356)
		(width 0.11684)
		(layer "In11.Cu")
		(net "CLR_CMOS")
	)
	(segment
		(start 242.43919 -94.456504)
		(end 238.744252 -98.151442)
		(width 0.11684)
		(layer "In11.Cu")
		(net "CLR_CMOS")
	)
	(segment
		(start 239.14608 -71.77532)
		(end 239.14608 -76.052934)
		(width 0.11684)
		(layer "In11.Cu")
		(net "CLR_CMOS")
	)
	(segment
		(start 242.43919 -79.346044)
		(end 242.43919 -94.456504)
		(width 0.11684)
		(layer "In11.Cu")
		(net "CLR_CMOS")
	)
	(segment
		(start 240.12652 -59.426348)
		(end 240.12652 -65.342516)
		(width 0.11684)
		(layer "In11.Cu")
		(net "CLR_CMOS")
	)
	(segment
		(start 239.14608 -76.052934)
		(end 242.43919 -79.346044)
		(width 0.11684)
		(layer "In11.Cu")
		(net "CLR_CMOS")
	)
	(segment
		(start 238.48568 -71.11492)
		(end 239.14608 -71.77532)
		(width 0.11684)
		(layer "In11.Cu")
		(net "CLR_CMOS")
	)
	(segment
		(start 238.48568 -66.983356)
		(end 238.48568 -71.11492)
		(width 0.11684)
		(layer "In11.Cu")
		(net "CLR_CMOS")
	)
	(segment
		(start 197.240906 -98.75647)
		(end 197.624954 -99.140518)
		(width 0.11684)
		(layer "In15.Cu")
		(net "CLR_CMOS")
	)
	(segment
		(start 210.443318 -104.174544)
		(end 211.188046 -103.429816)
		(width 0.11684)
		(layer "In15.Cu")
		(net "CLR_CMOS")
	)
	(segment
		(start 200.574656 -102.423214)
		(end 200.574656 -102.65791)
		(width 0.11684)
		(layer "In15.Cu")
		(net "CLR_CMOS")
	)
	(segment
		(start 213.61273 -103.607362)
		(end 233.288332 -103.607362)
		(width 0.11684)
		(layer "In15.Cu")
		(net "CLR_CMOS")
	)
	(segment
		(start 188.60897 -98.75647)
		(end 197.240906 -98.75647)
		(width 0.11684)
		(layer "In15.Cu")
		(net "CLR_CMOS")
	)
	(segment
		(start 202.09129 -104.174544)
		(end 210.443318 -104.174544)
		(width 0.11684)
		(layer "In15.Cu")
		(net "CLR_CMOS")
	)
	(segment
		(start 199.801734 -101.884988)
		(end 200.03643 -101.884988)
		(width 0.11684)
		(layer "In15.Cu")
		(net "CLR_CMOS")
	)
	(segment
		(start 233.288332 -103.607362)
		(end 238.744252 -98.151442)
		(width 0.11684)
		(layer "In15.Cu")
		(net "CLR_CMOS")
	)
	(segment
		(start 197.624954 -99.708208)
		(end 199.801734 -101.884988)
		(width 0.11684)
		(layer "In15.Cu")
		(net "CLR_CMOS")
	)
	(segment
		(start 200.574656 -102.65791)
		(end 202.09129 -104.174544)
		(width 0.11684)
		(layer "In15.Cu")
		(net "CLR_CMOS")
	)
	(segment
		(start 211.188046 -103.429816)
		(end 213.435184 -103.429816)
		(width 0.11684)
		(layer "In15.Cu")
		(net "CLR_CMOS")
	)
	(segment
		(start 213.435184 -103.429816)
		(end 213.61273 -103.607362)
		(width 0.11684)
		(layer "In15.Cu")
		(net "CLR_CMOS")
	)
	(segment
		(start 188.086492 -99.278948)
		(end 188.60897 -98.75647)
		(width 0.11684)
		(layer "In15.Cu")
		(net "CLR_CMOS")
	)
	(segment
		(start 187.871608 -99.278948)
		(end 188.086492 -99.278948)
		(width 0.11684)
		(layer "In15.Cu")
		(net "CLR_CMOS")
	)
	(segment
		(start 197.624954 -99.140518)
		(end 197.624954 -99.708208)
		(width 0.11684)
		(layer "In15.Cu")
		(net "CLR_CMOS")
	)
	(segment
		(start 200.03643 -101.884988)
		(end 200.574656 -102.423214)
		(width 0.11684)
		(layer "In15.Cu")
		(net "CLR_CMOS")
	)
	(segment
		(start 373.64797 -294.070024)
		(end 374.114822 -294.335962)
		(width 0.10668)
		(layer "F.Cu")
		(net "CLK_ESPI_CPU0_R_CLK1")
	)
	(via
		(at 374.114822 -294.335962)
		(size 0.4064)
		(drill 0.2032)
		(layers "F.Cu" "B.Cu")
		(net "CLK_ESPI_CPU0_R_CLK1")
	)
	(via
		(at 376.726958 -303.022254)
		(size 0.6604)
		(drill 0.3302)
		(layers "F.Cu" "B.Cu")
		(net "CLK_ESPI_CPU0_R_CLK1")
	)
	(segment
		(start 385.271518 -317.05042)
		(end 388.87527 -320.654172)
		(width 0.10668)
		(layer "B.Cu")
		(net "CLK_ESPI_CPU0_R_CLK1")
	)
	(segment
		(start 379.434344 -309.71363)
		(end 379.434344 -309.864506)
		(width 0.10668)
		(layer "B.Cu")
		(net "CLK_ESPI_CPU0_R_CLK1")
	)
	(segment
		(start 376.726958 -302.255936)
		(end 376.726958 -303.022254)
		(width 0.10668)
		(layer "B.Cu")
		(net "CLK_ESPI_CPU0_R_CLK1")
	)
	(segment
		(start 374.885458 -295.518332)
		(end 374.395238 -295.518332)
		(width 0.10668)
		(layer "B.Cu")
		(net "CLK_ESPI_CPU0_R_CLK1")
	)
	(segment
		(start 374.194578 -295.718992)
		(end 374.194578 -296.754296)
		(width 0.10668)
		(layer "B.Cu")
		(net "CLK_ESPI_CPU0_R_CLK1")
	)
	(segment
		(start 374.395238 -295.518332)
		(end 374.194578 -295.718992)
		(width 0.10668)
		(layer "B.Cu")
		(net "CLK_ESPI_CPU0_R_CLK1")
	)
	(segment
		(start 379.212856 -310.085994)
		(end 379.212856 -310.23687)
		(width 0.10668)
		(layer "B.Cu")
		(net "CLK_ESPI_CPU0_R_CLK1")
	)
	(segment
		(start 376.726958 -303.022254)
		(end 376.726958 -305.194208)
		(width 0.10668)
		(layer "B.Cu")
		(net "CLK_ESPI_CPU0_R_CLK1")
	)
	(segment
		(start 377.826016 -308.85003)
		(end 378.02185 -309.045864)
		(width 0.10668)
		(layer "B.Cu")
		(net "CLK_ESPI_CPU0_R_CLK1")
	)
	(segment
		(start 382.70561 -312.984896)
		(end 385.271518 -315.550804)
		(width 0.10668)
		(layer "B.Cu")
		(net "CLK_ESPI_CPU0_R_CLK1")
	)
	(segment
		(start 378.71527 -309.739284)
		(end 378.866146 -309.739284)
		(width 0.10668)
		(layer "B.Cu")
		(net "CLK_ESPI_CPU0_R_CLK1")
	)
	(segment
		(start 376.522742 -305.300888)
		(end 376.416062 -305.407568)
		(width 0.10668)
		(layer "B.Cu")
		(net "CLK_ESPI_CPU0_R_CLK1")
	)
	(segment
		(start 382.181354 -313.2074)
		(end 382.33223 -313.2074)
		(width 0.10668)
		(layer "B.Cu")
		(net "CLK_ESPI_CPU0_R_CLK1")
	)
	(segment
		(start 376.726958 -306.878228)
		(end 376.726958 -307.006244)
		(width 0.10668)
		(layer "B.Cu")
		(net "CLK_ESPI_CPU0_R_CLK1")
	)
	(segment
		(start 380.10211 -311.126124)
		(end 380.252986 -311.126124)
		(width 0.10668)
		(layer "B.Cu")
		(net "CLK_ESPI_CPU0_R_CLK1")
	)
	(segment
		(start 379.434344 -309.864506)
		(end 379.212856 -310.085994)
		(width 0.10668)
		(layer "B.Cu")
		(net "CLK_ESPI_CPU0_R_CLK1")
	)
	(segment
		(start 379.93193 -310.211216)
		(end 380.127764 -310.40705)
		(width 0.10668)
		(layer "B.Cu")
		(net "CLK_ESPI_CPU0_R_CLK1")
	)
	(segment
		(start 381.48895 -312.512964)
		(end 381.639826 -312.512964)
		(width 0.10668)
		(layer "B.Cu")
		(net "CLK_ESPI_CPU0_R_CLK1")
	)
	(segment
		(start 379.559566 -310.432704)
		(end 379.781054 -310.211216)
		(width 0.10668)
		(layer "B.Cu")
		(net "CLK_ESPI_CPU0_R_CLK1")
	)
	(segment
		(start 378.519436 -309.54345)
		(end 378.71527 -309.739284)
		(width 0.10668)
		(layer "B.Cu")
		(net "CLK_ESPI_CPU0_R_CLK1")
	)
	(segment
		(start 377.826016 -308.699154)
		(end 377.826016 -308.85003)
		(width 0.10668)
		(layer "B.Cu")
		(net "CLK_ESPI_CPU0_R_CLK1")
	)
	(segment
		(start 381.167894 -311.598056)
		(end 381.31877 -311.598056)
		(width 0.10668)
		(layer "B.Cu")
		(net "CLK_ESPI_CPU0_R_CLK1")
	)
	(segment
		(start 378.740924 -309.171086)
		(end 378.519436 -309.392574)
		(width 0.10668)
		(layer "B.Cu")
		(net "CLK_ESPI_CPU0_R_CLK1")
	)
	(segment
		(start 378.866146 -309.739284)
		(end 379.087634 -309.517796)
		(width 0.10668)
		(layer "B.Cu")
		(net "CLK_ESPI_CPU0_R_CLK1")
	)
	(segment
		(start 376.416062 -305.684428)
		(end 376.522742 -305.791108)
		(width 0.10668)
		(layer "B.Cu")
		(net "CLK_ESPI_CPU0_R_CLK1")
	)
	(segment
		(start 379.781054 -310.211216)
		(end 379.93193 -310.211216)
		(width 0.10668)
		(layer "B.Cu")
		(net "CLK_ESPI_CPU0_R_CLK1")
	)
	(segment
		(start 380.62535 -310.904636)
		(end 380.821184 -311.10047)
		(width 0.10668)
		(layer "B.Cu")
		(net "CLK_ESPI_CPU0_R_CLK1")
	)
	(segment
		(start 379.087634 -309.517796)
		(end 379.23851 -309.517796)
		(width 0.10668)
		(layer "B.Cu")
		(net "CLK_ESPI_CPU0_R_CLK1")
	)
	(segment
		(start 377.354084 -307.63337)
		(end 377.354084 -307.784246)
		(width 0.10668)
		(layer "B.Cu")
		(net "CLK_ESPI_CPU0_R_CLK1")
	)
	(segment
		(start 380.127764 -310.557926)
		(end 379.906276 -310.779414)
		(width 0.10668)
		(layer "B.Cu")
		(net "CLK_ESPI_CPU0_R_CLK1")
	)
	(segment
		(start 378.047504 -308.32679)
		(end 378.047504 -308.477666)
		(width 0.10668)
		(layer "B.Cu")
		(net "CLK_ESPI_CPU0_R_CLK1")
	)
	(segment
		(start 375.025158 -295.378632)
		(end 374.885458 -295.518332)
		(width 0.10668)
		(layer "B.Cu")
		(net "CLK_ESPI_CPU0_R_CLK1")
	)
	(segment
		(start 377.354084 -307.784246)
		(end 377.132596 -308.005734)
		(width 0.10668)
		(layer "B.Cu")
		(net "CLK_ESPI_CPU0_R_CLK1")
	)
	(segment
		(start 376.522742 -305.791108)
		(end 376.820938 -305.791108)
		(width 0.10668)
		(layer "B.Cu")
		(net "CLK_ESPI_CPU0_R_CLK1")
	)
	(segment
		(start 381.98552 -313.011566)
		(end 382.181354 -313.2074)
		(width 0.10668)
		(layer "B.Cu")
		(net "CLK_ESPI_CPU0_R_CLK1")
	)
	(segment
		(start 382.208024 -312.638186)
		(end 381.98552 -312.86069)
		(width 0.10668)
		(layer "B.Cu")
		(net "CLK_ESPI_CPU0_R_CLK1")
	)
	(segment
		(start 380.599696 -311.472834)
		(end 380.599696 -311.62371)
		(width 0.10668)
		(layer "B.Cu")
		(net "CLK_ESPI_CPU0_R_CLK1")
	)
	(segment
		(start 377.32843 -308.352444)
		(end 377.479306 -308.352444)
		(width 0.10668)
		(layer "B.Cu")
		(net "CLK_ESPI_CPU0_R_CLK1")
	)
	(segment
		(start 380.946406 -311.819544)
		(end 381.167894 -311.598056)
		(width 0.10668)
		(layer "B.Cu")
		(net "CLK_ESPI_CPU0_R_CLK1")
	)
	(segment
		(start 380.474474 -310.904636)
		(end 380.62535 -310.904636)
		(width 0.10668)
		(layer "B.Cu")
		(net "CLK_ESPI_CPU0_R_CLK1")
	)
	(segment
		(start 380.252986 -311.126124)
		(end 380.474474 -310.904636)
		(width 0.10668)
		(layer "B.Cu")
		(net "CLK_ESPI_CPU0_R_CLK1")
	)
	(segment
		(start 376.927618 -305.897788)
		(end 376.927618 -306.174648)
		(width 0.10668)
		(layer "B.Cu")
		(net "CLK_ESPI_CPU0_R_CLK1")
	)
	(segment
		(start 380.79553 -311.819544)
		(end 380.946406 -311.819544)
		(width 0.10668)
		(layer "B.Cu")
		(net "CLK_ESPI_CPU0_R_CLK1")
	)
	(segment
		(start 381.31877 -311.598056)
		(end 381.514604 -311.79389)
		(width 0.10668)
		(layer "B.Cu")
		(net "CLK_ESPI_CPU0_R_CLK1")
	)
	(segment
		(start 381.861314 -312.291476)
		(end 382.01219 -312.291476)
		(width 0.10668)
		(layer "B.Cu")
		(net "CLK_ESPI_CPU0_R_CLK1")
	)
	(segment
		(start 374.628156 -297.187874)
		(end 376.726958 -302.255936)
		(width 0.10668)
		(layer "B.Cu")
		(net "CLK_ESPI_CPU0_R_CLK1")
	)
	(segment
		(start 379.40869 -310.432704)
		(end 379.559566 -310.432704)
		(width 0.10668)
		(layer "B.Cu")
		(net "CLK_ESPI_CPU0_R_CLK1")
	)
	(segment
		(start 376.620278 -306.771548)
		(end 376.726958 -306.878228)
		(width 0.10668)
		(layer "B.Cu")
		(net "CLK_ESPI_CPU0_R_CLK1")
	)
	(segment
		(start 382.554734 -312.984896)
		(end 382.70561 -312.984896)
		(width 0.10668)
		(layer "B.Cu")
		(net "CLK_ESPI_CPU0_R_CLK1")
	)
	(segment
		(start 385.271518 -315.550804)
		(end 385.271518 -317.05042)
		(width 0.10668)
		(layer "B.Cu")
		(net "CLK_ESPI_CPU0_R_CLK1")
	)
	(segment
		(start 382.208024 -312.48731)
		(end 382.208024 -312.638186)
		(width 0.10668)
		(layer "B.Cu")
		(net "CLK_ESPI_CPU0_R_CLK1")
	)
	(segment
		(start 376.927618 -306.174648)
		(end 376.820938 -306.281328)
		(width 0.10668)
		(layer "B.Cu")
		(net "CLK_ESPI_CPU0_R_CLK1")
	)
	(segment
		(start 375.025158 -294.934132)
		(end 375.025158 -295.378632)
		(width 0.10668)
		(layer "B.Cu")
		(net "CLK_ESPI_CPU0_R_CLK1")
	)
	(segment
		(start 381.514604 -311.79389)
		(end 381.514604 -311.944766)
		(width 0.10668)
		(layer "B.Cu")
		(net "CLK_ESPI_CPU0_R_CLK1")
	)
	(segment
		(start 376.282458 -306.771548)
		(end 376.620278 -306.771548)
		(width 0.10668)
		(layer "B.Cu")
		(net "CLK_ESPI_CPU0_R_CLK1")
	)
	(segment
		(start 377.700794 -308.130956)
		(end 377.85167 -308.130956)
		(width 0.10668)
		(layer "B.Cu")
		(net "CLK_ESPI_CPU0_R_CLK1")
	)
	(segment
		(start 374.456452 -294.677592)
		(end 374.768618 -294.677592)
		(width 0.10668)
		(layer "B.Cu")
		(net "CLK_ESPI_CPU0_R_CLK1")
	)
	(segment
		(start 378.519436 -309.392574)
		(end 378.519436 -309.54345)
		(width 0.10668)
		(layer "B.Cu")
		(net "CLK_ESPI_CPU0_R_CLK1")
	)
	(segment
		(start 378.02185 -309.045864)
		(end 378.172726 -309.045864)
		(width 0.10668)
		(layer "B.Cu")
		(net "CLK_ESPI_CPU0_R_CLK1")
	)
	(segment
		(start 379.23851 -309.517796)
		(end 379.434344 -309.71363)
		(width 0.10668)
		(layer "B.Cu")
		(net "CLK_ESPI_CPU0_R_CLK1")
	)
	(segment
		(start 374.768618 -294.677592)
		(end 375.025158 -294.934132)
		(width 0.10668)
		(layer "B.Cu")
		(net "CLK_ESPI_CPU0_R_CLK1")
	)
	(segment
		(start 376.820938 -306.281328)
		(end 376.282458 -306.281328)
		(width 0.10668)
		(layer "B.Cu")
		(net "CLK_ESPI_CPU0_R_CLK1")
	)
	(segment
		(start 374.194578 -296.754296)
		(end 374.628156 -297.187874)
		(width 0.10668)
		(layer "B.Cu")
		(net "CLK_ESPI_CPU0_R_CLK1")
	)
	(segment
		(start 379.212856 -310.23687)
		(end 379.40869 -310.432704)
		(width 0.10668)
		(layer "B.Cu")
		(net "CLK_ESPI_CPU0_R_CLK1")
	)
	(segment
		(start 379.906276 -310.93029)
		(end 380.10211 -311.126124)
		(width 0.10668)
		(layer "B.Cu")
		(net "CLK_ESPI_CPU0_R_CLK1")
	)
	(segment
		(start 381.293116 -312.31713)
		(end 381.48895 -312.512964)
		(width 0.10668)
		(layer "B.Cu")
		(net "CLK_ESPI_CPU0_R_CLK1")
	)
	(segment
		(start 378.740924 -309.02021)
		(end 378.740924 -309.171086)
		(width 0.10668)
		(layer "B.Cu")
		(net "CLK_ESPI_CPU0_R_CLK1")
	)
	(segment
		(start 377.132596 -308.005734)
		(end 377.132596 -308.15661)
		(width 0.10668)
		(layer "B.Cu")
		(net "CLK_ESPI_CPU0_R_CLK1")
	)
	(segment
		(start 378.54509 -308.824376)
		(end 378.740924 -309.02021)
		(width 0.10668)
		(layer "B.Cu")
		(net "CLK_ESPI_CPU0_R_CLK1")
	)
	(segment
		(start 380.127764 -310.40705)
		(end 380.127764 -310.557926)
		(width 0.10668)
		(layer "B.Cu")
		(net "CLK_ESPI_CPU0_R_CLK1")
	)
	(segment
		(start 376.282458 -306.281328)
		(end 376.175778 -306.388008)
		(width 0.10668)
		(layer "B.Cu")
		(net "CLK_ESPI_CPU0_R_CLK1")
	)
	(segment
		(start 380.599696 -311.62371)
		(end 380.79553 -311.819544)
		(width 0.10668)
		(layer "B.Cu")
		(net "CLK_ESPI_CPU0_R_CLK1")
	)
	(segment
		(start 377.479306 -308.352444)
		(end 377.700794 -308.130956)
		(width 0.10668)
		(layer "B.Cu")
		(net "CLK_ESPI_CPU0_R_CLK1")
	)
	(segment
		(start 376.416062 -305.407568)
		(end 376.416062 -305.684428)
		(width 0.10668)
		(layer "B.Cu")
		(net "CLK_ESPI_CPU0_R_CLK1")
	)
	(segment
		(start 380.821184 -311.251346)
		(end 380.599696 -311.472834)
		(width 0.10668)
		(layer "B.Cu")
		(net "CLK_ESPI_CPU0_R_CLK1")
	)
	(segment
		(start 377.132596 -308.15661)
		(end 377.32843 -308.352444)
		(width 0.10668)
		(layer "B.Cu")
		(net "CLK_ESPI_CPU0_R_CLK1")
	)
	(segment
		(start 376.175778 -306.388008)
		(end 376.175778 -306.664868)
		(width 0.10668)
		(layer "B.Cu")
		(net "CLK_ESPI_CPU0_R_CLK1")
	)
	(segment
		(start 378.394214 -308.824376)
		(end 378.54509 -308.824376)
		(width 0.10668)
		(layer "B.Cu")
		(net "CLK_ESPI_CPU0_R_CLK1")
	)
	(segment
		(start 381.514604 -311.944766)
		(end 381.293116 -312.166254)
		(width 0.10668)
		(layer "B.Cu")
		(net "CLK_ESPI_CPU0_R_CLK1")
	)
	(segment
		(start 376.726958 -305.194208)
		(end 376.620278 -305.300888)
		(width 0.10668)
		(layer "B.Cu")
		(net "CLK_ESPI_CPU0_R_CLK1")
	)
	(segment
		(start 376.726958 -307.006244)
		(end 377.354084 -307.63337)
		(width 0.10668)
		(layer "B.Cu")
		(net "CLK_ESPI_CPU0_R_CLK1")
	)
	(segment
		(start 378.047504 -308.477666)
		(end 377.826016 -308.699154)
		(width 0.10668)
		(layer "B.Cu")
		(net "CLK_ESPI_CPU0_R_CLK1")
	)
	(segment
		(start 380.821184 -311.10047)
		(end 380.821184 -311.251346)
		(width 0.10668)
		(layer "B.Cu")
		(net "CLK_ESPI_CPU0_R_CLK1")
	)
	(segment
		(start 376.175778 -306.664868)
		(end 376.282458 -306.771548)
		(width 0.10668)
		(layer "B.Cu")
		(net "CLK_ESPI_CPU0_R_CLK1")
	)
	(segment
		(start 382.33223 -313.2074)
		(end 382.554734 -312.984896)
		(width 0.10668)
		(layer "B.Cu")
		(net "CLK_ESPI_CPU0_R_CLK1")
	)
	(segment
		(start 382.01219 -312.291476)
		(end 382.208024 -312.48731)
		(width 0.10668)
		(layer "B.Cu")
		(net "CLK_ESPI_CPU0_R_CLK1")
	)
	(segment
		(start 376.620278 -305.300888)
		(end 376.522742 -305.300888)
		(width 0.10668)
		(layer "B.Cu")
		(net "CLK_ESPI_CPU0_R_CLK1")
	)
	(segment
		(start 381.639826 -312.512964)
		(end 381.861314 -312.291476)
		(width 0.10668)
		(layer "B.Cu")
		(net "CLK_ESPI_CPU0_R_CLK1")
	)
	(segment
		(start 381.98552 -312.86069)
		(end 381.98552 -313.011566)
		(width 0.10668)
		(layer "B.Cu")
		(net "CLK_ESPI_CPU0_R_CLK1")
	)
	(segment
		(start 379.906276 -310.779414)
		(end 379.906276 -310.93029)
		(width 0.10668)
		(layer "B.Cu")
		(net "CLK_ESPI_CPU0_R_CLK1")
	)
	(segment
		(start 390.660128 -320.654172)
		(end 391.185908 -321.179952)
		(width 0.10668)
		(layer "B.Cu")
		(net "CLK_ESPI_CPU0_R_CLK1")
	)
	(segment
		(start 381.293116 -312.166254)
		(end 381.293116 -312.31713)
		(width 0.10668)
		(layer "B.Cu")
		(net "CLK_ESPI_CPU0_R_CLK1")
	)
	(segment
		(start 377.85167 -308.130956)
		(end 378.047504 -308.32679)
		(width 0.10668)
		(layer "B.Cu")
		(net "CLK_ESPI_CPU0_R_CLK1")
	)
	(segment
		(start 388.87527 -320.654172)
		(end 390.660128 -320.654172)
		(width 0.10668)
		(layer "B.Cu")
		(net "CLK_ESPI_CPU0_R_CLK1")
	)
	(segment
		(start 374.114822 -294.335962)
		(end 374.456452 -294.677592)
		(width 0.10668)
		(layer "B.Cu")
		(net "CLK_ESPI_CPU0_R_CLK1")
	)
	(segment
		(start 376.820938 -305.791108)
		(end 376.927618 -305.897788)
		(width 0.10668)
		(layer "B.Cu")
		(net "CLK_ESPI_CPU0_R_CLK1")
	)
	(segment
		(start 378.172726 -309.045864)
		(end 378.394214 -308.824376)
		(width 0.10668)
		(layer "B.Cu")
		(net "CLK_ESPI_CPU0_R_CLK1")
	)
	(segment
		(start 196.5706 -137.004298)
		(end 196.5706 -135.763)
		(width 0.10668)
		(layer "F.Cu")
		(net "CLK_ESPI_CPU0_R1_CLK1")
	)
	(segment
		(start 188.322204 -122.65279)
		(end 188.712094 -123.04268)
		(width 0.10668)
		(layer "F.Cu")
		(net "CLK_ESPI_CPU0_R1_CLK1")
	)
	(segment
		(start 196.5706 -135.763)
		(end 196.1134 -135.3058)
		(width 0.10668)
		(layer "F.Cu")
		(net "CLK_ESPI_CPU0_R1_CLK1")
	)
	(segment
		(start 196.342 -137.232898)
		(end 196.5706 -137.004298)
		(width 0.10668)
		(layer "F.Cu")
		(net "CLK_ESPI_CPU0_R1_CLK1")
	)
	(via
		(at 188.712094 -123.04268)
		(size 0.4572)
		(drill 0.254)
		(layers "F.Cu" "B.Cu")
		(net "CLK_ESPI_CPU0_R1_CLK1")
	)
	(via
		(at 196.1134 -135.3058)
		(size 0.508)
		(drill 0.254)
		(layers "F.Cu" "B.Cu")
		(net "CLK_ESPI_CPU0_R1_CLK1")
	)
	(segment
		(start 191.487044 -127.384556)
		(end 190.99276 -127.384556)
		(width 0.11684)
		(layer "In4.Cu")
		(net "CLK_ESPI_CPU0_R1_CLK1")
	)
	(segment
		(start 195.326 -131.699)
		(end 194.48018 -130.85318)
		(width 0.11684)
		(layer "In4.Cu")
		(net "CLK_ESPI_CPU0_R1_CLK1")
	)
	(segment
		(start 193.941192 -130.85318)
		(end 193.69405 -130.606038)
		(width 0.11684)
		(layer "In4.Cu")
		(net "CLK_ESPI_CPU0_R1_CLK1")
	)
	(segment
		(start 189.534292 -125.926088)
		(end 189.534292 -123.864878)
		(width 0.11684)
		(layer "In4.Cu")
		(net "CLK_ESPI_CPU0_R1_CLK1")
	)
	(segment
		(start 195.6308 -135.3058)
		(end 195.326 -135.001)
		(width 0.11684)
		(layer "In4.Cu")
		(net "CLK_ESPI_CPU0_R1_CLK1")
	)
	(segment
		(start 195.326 -135.001)
		(end 195.326 -131.699)
		(width 0.11684)
		(layer "In4.Cu")
		(net "CLK_ESPI_CPU0_R1_CLK1")
	)
	(segment
		(start 194.48018 -130.85318)
		(end 193.941192 -130.85318)
		(width 0.11684)
		(layer "In4.Cu")
		(net "CLK_ESPI_CPU0_R1_CLK1")
	)
	(segment
		(start 193.69405 -129.591562)
		(end 191.487044 -127.384556)
		(width 0.11684)
		(layer "In4.Cu")
		(net "CLK_ESPI_CPU0_R1_CLK1")
	)
	(segment
		(start 193.69405 -130.606038)
		(end 193.69405 -129.591562)
		(width 0.11684)
		(layer "In4.Cu")
		(net "CLK_ESPI_CPU0_R1_CLK1")
	)
	(segment
		(start 196.1134 -135.3058)
		(end 195.6308 -135.3058)
		(width 0.11684)
		(layer "In4.Cu")
		(net "CLK_ESPI_CPU0_R1_CLK1")
	)
	(segment
		(start 190.99276 -127.384556)
		(end 189.534292 -125.926088)
		(width 0.11684)
		(layer "In4.Cu")
		(net "CLK_ESPI_CPU0_R1_CLK1")
	)
	(segment
		(start 189.534292 -123.864878)
		(end 188.712094 -123.04268)
		(width 0.11684)
		(layer "In4.Cu")
		(net "CLK_ESPI_CPU0_R1_CLK1")
	)
	(segment
		(start 196.088 -138.648948)
		(end 196.088 -138.286998)
		(width 0.10668)
		(layer "F.Cu")
		(net "CLK_ESPI_CPU0_CLK1")
	)
	(segment
		(start 196.088 -138.286998)
		(end 196.342 -138.032998)
		(width 0.10668)
		(layer "F.Cu")
		(net "CLK_ESPI_CPU0_CLK1")
	)
	(segment
		(start 178.867054 -16.549878)
		(end 178.867054 -18.316448)
		(width 0.10668)
		(layer "F.Cu")
		(net "CLK_ESPI_CPU0_CLK1")
	)
	(via
		(at 178.867054 -18.316448)
		(size 0.508)
		(drill 0.254)
		(layers "F.Cu" "B.Cu")
		(net "CLK_ESPI_CPU0_CLK1")
	)
	(via
		(at 196.088 -138.648948)
		(size 0.508)
		(drill 0.254)
		(layers "F.Cu" "B.Cu")
		(net "CLK_ESPI_CPU0_CLK1")
	)
	(via
		(at 392.407394 -320.206116)
		(size 0.508)
		(drill 0.254)
		(layers "F.Cu" "B.Cu")
		(net "CLK_ESPI_CPU0_CLK1")
	)
	(segment
		(start 393.236958 -321.179952)
		(end 393.236958 -322.195952)
		(width 0.10668)
		(layer "B.Cu")
		(net "CLK_ESPI_CPU0_CLK1")
	)
	(segment
		(start 392.32713 -320.206116)
		(end 391.986008 -320.547238)
		(width 0.10668)
		(layer "B.Cu")
		(net "CLK_ESPI_CPU0_CLK1")
	)
	(segment
		(start 392.407394 -320.206116)
		(end 392.32713 -320.206116)
		(width 0.10668)
		(layer "B.Cu")
		(net "CLK_ESPI_CPU0_CLK1")
	)
	(segment
		(start 391.986008 -320.547238)
		(end 391.986008 -321.179952)
		(width 0.10668)
		(layer "B.Cu")
		(net "CLK_ESPI_CPU0_CLK1")
	)
	(segment
		(start 391.986008 -321.179952)
		(end 393.236958 -321.179952)
		(width 0.10668)
		(layer "B.Cu")
		(net "CLK_ESPI_CPU0_CLK1")
	)
	(segment
		(start 201.16038 -137.901426)
		(end 199.012556 -135.753602)
		(width 0.11684)
		(layer "In11.Cu")
		(net "CLK_ESPI_CPU0_CLK1")
	)
	(segment
		(start 199.012556 -135.588502)
		(end 199.165464 -135.435594)
		(width 0.11684)
		(layer "In11.Cu")
		(net "CLK_ESPI_CPU0_CLK1")
	)
	(segment
		(start 205.258924 -131.823714)
		(end 204.100684 -130.665474)
		(width 0.11684)
		(layer "In11.Cu")
		(net "CLK_ESPI_CPU0_CLK1")
	)
	(segment
		(start 197.422516 -137.343642)
		(end 199.526144 -139.44727)
		(width 0.11684)
		(layer "In11.Cu")
		(net "CLK_ESPI_CPU0_CLK1")
	)
	(segment
		(start 200.410572 -93.721174)
		(end 199.329294 -91.110816)
		(width 0.11684)
		(layer "In11.Cu")
		(net "CLK_ESPI_CPU0_CLK1")
	)
	(segment
		(start 197.740524 -137.025634)
		(end 197.740524 -136.860534)
		(width 0.11684)
		(layer "In11.Cu")
		(net "CLK_ESPI_CPU0_CLK1")
	)
	(segment
		(start 201.760836 -135.321802)
		(end 201.925936 -135.321802)
		(width 0.11684)
		(layer "In11.Cu")
		(net "CLK_ESPI_CPU0_CLK1")
	)
	(segment
		(start 201.394568 -94.920054)
		(end 200.410572 -93.721174)
		(width 0.11684)
		(layer "In11.Cu")
		(net "CLK_ESPI_CPU0_CLK1")
	)
	(segment
		(start 198.971916 -136.514078)
		(end 199.137016 -136.514078)
		(width 0.11684)
		(layer "In11.Cu")
		(net "CLK_ESPI_CPU0_CLK1")
	)
	(segment
		(start 201.124312 -136.593326)
		(end 199.648572 -135.117586)
		(width 0.11684)
		(layer "In11.Cu")
		(net "CLK_ESPI_CPU0_CLK1")
	)
	(segment
		(start 200.971404 -136.911334)
		(end 201.124312 -136.758426)
		(width 0.11684)
		(layer "In11.Cu")
		(net "CLK_ESPI_CPU0_CLK1")
	)
	(segment
		(start 201.709528 -132.89153)
		(end 201.874628 -132.89153)
		(width 0.11684)
		(layer "In11.Cu")
		(net "CLK_ESPI_CPU0_CLK1")
	)
	(segment
		(start 200.349358 -138.833352)
		(end 200.502266 -138.680444)
		(width 0.11684)
		(layer "In11.Cu")
		(net "CLK_ESPI_CPU0_CLK1")
	)
	(segment
		(start 202.192636 -132.408422)
		(end 202.345544 -132.255514)
		(width 0.11684)
		(layer "In11.Cu")
		(net "CLK_ESPI_CPU0_CLK1")
	)
	(segment
		(start 201.007472 -138.219434)
		(end 201.16038 -138.066526)
		(width 0.11684)
		(layer "In11.Cu")
		(net "CLK_ESPI_CPU0_CLK1")
	)
	(segment
		(start 200.806304 -136.911334)
		(end 200.971404 -136.911334)
		(width 0.11684)
		(layer "In11.Cu")
		(net "CLK_ESPI_CPU0_CLK1")
	)
	(segment
		(start 180.004974 -21.892006)
		(end 180.004974 -19.454368)
		(width 0.11684)
		(layer "In11.Cu")
		(net "CLK_ESPI_CPU0_CLK1")
	)
	(segment
		(start 202.086718 -98.10496)
		(end 202.086718 -96.090486)
		(width 0.11684)
		(layer "In11.Cu")
		(net "CLK_ESPI_CPU0_CLK1")
	)
	(segment
		(start 204.814424 -129.786634)
		(end 204.814424 -116.298726)
		(width 0.11684)
		(layer "In11.Cu")
		(net "CLK_ESPI_CPU0_CLK1")
	)
	(segment
		(start 203.14666 -131.619498)
		(end 204.3049 -132.777738)
		(width 0.11684)
		(layer "In11.Cu")
		(net "CLK_ESPI_CPU0_CLK1")
	)
	(segment
		(start 201.55662 -133.044438)
		(end 201.709528 -132.89153)
		(width 0.11684)
		(layer "In11.Cu")
		(net "CLK_ESPI_CPU0_CLK1")
	)
	(segment
		(start 205.258924 -131.988814)
		(end 205.258924 -131.823714)
		(width 0.11684)
		(layer "In11.Cu")
		(net "CLK_ESPI_CPU0_CLK1")
	)
	(segment
		(start 199.691244 -139.44727)
		(end 199.844152 -139.294362)
		(width 0.11684)
		(layer "In11.Cu")
		(net "CLK_ESPI_CPU0_CLK1")
	)
	(segment
		(start 204.622908 -132.62483)
		(end 204.622908 -132.45973)
		(width 0.11684)
		(layer "In11.Cu")
		(net "CLK_ESPI_CPU0_CLK1")
	)
	(segment
		(start 205.106016 -132.141722)
		(end 205.258924 -131.988814)
		(width 0.11684)
		(layer "In11.Cu")
		(net "CLK_ESPI_CPU0_CLK1")
	)
	(segment
		(start 183.804306 -28.131262)
		(end 183.804306 -25.691338)
		(width 0.11684)
		(layer "In11.Cu")
		(net "CLK_ESPI_CPU0_CLK1")
	)
	(segment
		(start 202.078844 -135.168894)
		(end 202.078844 -135.003794)
		(width 0.11684)
		(layer "In11.Cu")
		(net "CLK_ESPI_CPU0_CLK1")
	)
	(segment
		(start 202.71486 -134.367778)
		(end 201.55662 -133.209538)
		(width 0.11684)
		(layer "In11.Cu")
		(net "CLK_ESPI_CPU0_CLK1")
	)
	(segment
		(start 199.165464 -135.435594)
		(end 199.330564 -135.435594)
		(width 0.11684)
		(layer "In11.Cu")
		(net "CLK_ESPI_CPU0_CLK1")
	)
	(segment
		(start 201.55662 -133.209538)
		(end 201.55662 -133.044438)
		(width 0.11684)
		(layer "In11.Cu")
		(net "CLK_ESPI_CPU0_CLK1")
	)
	(segment
		(start 203.833984 -133.413754)
		(end 203.986892 -133.260846)
		(width 0.11684)
		(layer "In11.Cu")
		(net "CLK_ESPI_CPU0_CLK1")
	)
	(segment
		(start 202.946 -103.580184)
		(end 202.946 -99.771708)
		(width 0.11684)
		(layer "In11.Cu")
		(net "CLK_ESPI_CPU0_CLK1")
	)
	(segment
		(start 199.012556 -135.753602)
		(end 199.012556 -135.588502)
		(width 0.11684)
		(layer "In11.Cu")
		(net "CLK_ESPI_CPU0_CLK1")
	)
	(segment
		(start 201.238612 -133.527546)
		(end 202.396852 -134.685786)
		(width 0.11684)
		(layer "In11.Cu")
		(net "CLK_ESPI_CPU0_CLK1")
	)
	(segment
		(start 202.396852 -134.685786)
		(end 202.561952 -134.685786)
		(width 0.11684)
		(layer "In11.Cu")
		(net "CLK_ESPI_CPU0_CLK1")
	)
	(segment
		(start 199.526144 -139.44727)
		(end 199.691244 -139.44727)
		(width 0.11684)
		(layer "In11.Cu")
		(net "CLK_ESPI_CPU0_CLK1")
	)
	(segment
		(start 201.12482 -135.957818)
		(end 201.28992 -135.957818)
		(width 0.11684)
		(layer "In11.Cu")
		(net "CLK_ESPI_CPU0_CLK1")
	)
	(segment
		(start 203.464668 -131.13639)
		(end 203.617576 -130.983482)
		(width 0.11684)
		(layer "In11.Cu")
		(net "CLK_ESPI_CPU0_CLK1")
	)
	(segment
		(start 199.844152 -139.129262)
		(end 197.740524 -137.025634)
		(width 0.11684)
		(layer "In11.Cu")
		(net "CLK_ESPI_CPU0_CLK1")
	)
	(segment
		(start 187.756292 -73.724262)
		(end 187.756292 -32.083248)
		(width 0.11684)
		(layer "In11.Cu")
		(net "CLK_ESPI_CPU0_CLK1")
	)
	(segment
		(start 200.184258 -138.833352)
		(end 200.349358 -138.833352)
		(width 0.11684)
		(layer "In11.Cu")
		(net "CLK_ESPI_CPU0_CLK1")
	)
	(segment
		(start 203.986892 -133.260846)
		(end 203.986892 -133.095746)
		(width 0.11684)
		(layer "In11.Cu")
		(net "CLK_ESPI_CPU0_CLK1")
	)
	(segment
		(start 200.920604 -133.680454)
		(end 201.073512 -133.527546)
		(width 0.11684)
		(layer "In11.Cu")
		(net "CLK_ESPI_CPU0_CLK1")
	)
	(segment
		(start 203.668884 -133.413754)
		(end 203.833984 -133.413754)
		(width 0.11684)
		(layer "In11.Cu")
		(net "CLK_ESPI_CPU0_CLK1")
	)
	(segment
		(start 204.795374 -116.279676)
		(end 204.795374 -108.045504)
		(width 0.11684)
		(layer "In11.Cu")
		(net "CLK_ESPI_CPU0_CLK1")
	)
	(segment
		(start 201.925936 -135.321802)
		(end 202.078844 -135.168894)
		(width 0.11684)
		(layer "In11.Cu")
		(net "CLK_ESPI_CPU0_CLK1")
	)
	(segment
		(start 197.257416 -137.343642)
		(end 197.422516 -137.343642)
		(width 0.11684)
		(layer "In11.Cu")
		(net "CLK_ESPI_CPU0_CLK1")
	)
	(segment
		(start 204.3049 -132.777738)
		(end 204.47 -132.777738)
		(width 0.11684)
		(layer "In11.Cu")
		(net "CLK_ESPI_CPU0_CLK1")
	)
	(segment
		(start 203.350876 -133.731762)
		(end 202.192636 -132.573522)
		(width 0.11684)
		(layer "In11.Cu")
		(net "CLK_ESPI_CPU0_CLK1")
	)
	(segment
		(start 203.782676 -130.983482)
		(end 204.940916 -132.141722)
		(width 0.11684)
		(layer "In11.Cu")
		(net "CLK_ESPI_CPU0_CLK1")
	)
	(segment
		(start 199.648572 -135.117586)
		(end 199.648572 -134.952486)
		(width 0.11684)
		(layer "In11.Cu")
		(net "CLK_ESPI_CPU0_CLK1")
	)
	(segment
		(start 200.502266 -138.680444)
		(end 200.502266 -138.515344)
		(width 0.11684)
		(layer "In11.Cu")
		(net "CLK_ESPI_CPU0_CLK1")
	)
	(segment
		(start 200.98766 -134.713726)
		(end 201.15276 -134.713726)
		(width 0.11684)
		(layer "In11.Cu")
		(net "CLK_ESPI_CPU0_CLK1")
	)
	(segment
		(start 201.073512 -133.527546)
		(end 201.238612 -133.527546)
		(width 0.11684)
		(layer "In11.Cu")
		(net "CLK_ESPI_CPU0_CLK1")
	)
	(segment
		(start 202.828652 -131.937506)
		(end 202.828652 -131.772406)
		(width 0.11684)
		(layer "In11.Cu")
		(net "CLK_ESPI_CPU0_CLK1")
	)
	(segment
		(start 194.432174 -86.213696)
		(end 187.756292 -73.724262)
		(width 0.11684)
		(layer "In11.Cu")
		(net "CLK_ESPI_CPU0_CLK1")
	)
	(segment
		(start 204.100684 -130.500374)
		(end 204.814424 -129.786634)
		(width 0.11684)
		(layer "In11.Cu")
		(net "CLK_ESPI_CPU0_CLK1")
	)
	(segment
		(start 187.756292 -32.083248)
		(end 183.804306 -28.131262)
		(width 0.11684)
		(layer "In11.Cu")
		(net "CLK_ESPI_CPU0_CLK1")
	)
	(segment
		(start 201.442828 -135.63981)
		(end 200.834752 -135.031734)
		(width 0.11684)
		(layer "In11.Cu")
		(net "CLK_ESPI_CPU0_CLK1")
	)
	(segment
		(start 201.874628 -132.89153)
		(end 203.032868 -134.04977)
		(width 0.11684)
		(layer "In11.Cu")
		(net "CLK_ESPI_CPU0_CLK1")
	)
	(segment
		(start 201.74839 -95.273876)
		(end 201.394568 -94.920054)
		(width 0.11684)
		(layer "In11.Cu")
		(net "CLK_ESPI_CPU0_CLK1")
	)
	(segment
		(start 204.100684 -130.665474)
		(end 204.100684 -130.500374)
		(width 0.11684)
		(layer "In11.Cu")
		(net "CLK_ESPI_CPU0_CLK1")
	)
	(segment
		(start 199.053704 -139.758674)
		(end 197.03796 -137.74293)
		(width 0.11684)
		(layer "In11.Cu")
		(net "CLK_ESPI_CPU0_CLK1")
	)
	(segment
		(start 197.893432 -136.707626)
		(end 198.058532 -136.707626)
		(width 0.11684)
		(layer "In11.Cu")
		(net "CLK_ESPI_CPU0_CLK1")
	)
	(segment
		(start 202.510644 -132.255514)
		(end 203.668884 -133.413754)
		(width 0.11684)
		(layer "In11.Cu")
		(net "CLK_ESPI_CPU0_CLK1")
	)
	(segment
		(start 200.834752 -134.866634)
		(end 200.98766 -134.713726)
		(width 0.11684)
		(layer "In11.Cu")
		(net "CLK_ESPI_CPU0_CLK1")
	)
	(segment
		(start 200.920604 -133.845554)
		(end 200.920604 -133.680454)
		(width 0.11684)
		(layer "In11.Cu")
		(net "CLK_ESPI_CPU0_CLK1")
	)
	(segment
		(start 198.819008 -136.832086)
		(end 198.819008 -136.666986)
		(width 0.11684)
		(layer "In11.Cu")
		(net "CLK_ESPI_CPU0_CLK1")
	)
	(segment
		(start 201.15276 -134.713726)
		(end 201.760836 -135.321802)
		(width 0.11684)
		(layer "In11.Cu")
		(net "CLK_ESPI_CPU0_CLK1")
	)
	(segment
		(start 198.058532 -136.707626)
		(end 200.184258 -138.833352)
		(width 0.11684)
		(layer "In11.Cu")
		(net "CLK_ESPI_CPU0_CLK1")
	)
	(segment
		(start 202.946 -99.771708)
		(end 202.048872 -98.875596)
		(width 0.11684)
		(layer "In11.Cu")
		(net "CLK_ESPI_CPU0_CLK1")
	)
	(segment
		(start 201.16038 -138.066526)
		(end 201.16038 -137.901426)
		(width 0.11684)
		(layer "In11.Cu")
		(net "CLK_ESPI_CPU0_CLK1")
	)
	(segment
		(start 202.345544 -132.255514)
		(end 202.510644 -132.255514)
		(width 0.11684)
		(layer "In11.Cu")
		(net "CLK_ESPI_CPU0_CLK1")
	)
	(segment
		(start 180.004974 -19.454368)
		(end 178.867054 -18.316448)
		(width 0.11684)
		(layer "In11.Cu")
		(net "CLK_ESPI_CPU0_CLK1")
	)
	(segment
		(start 200.502266 -138.515344)
		(end 198.819008 -136.832086)
		(width 0.11684)
		(layer "In11.Cu")
		(net "CLK_ESPI_CPU0_CLK1")
	)
	(segment
		(start 203.617576 -130.983482)
		(end 203.782676 -130.983482)
		(width 0.11684)
		(layer "In11.Cu")
		(net "CLK_ESPI_CPU0_CLK1")
	)
	(segment
		(start 201.124312 -136.758426)
		(end 201.124312 -136.593326)
		(width 0.11684)
		(layer "In11.Cu")
		(net "CLK_ESPI_CPU0_CLK1")
	)
	(segment
		(start 202.71486 -134.532878)
		(end 202.71486 -134.367778)
		(width 0.11684)
		(layer "In11.Cu")
		(net "CLK_ESPI_CPU0_CLK1")
	)
	(segment
		(start 202.192636 -132.573522)
		(end 202.192636 -132.408422)
		(width 0.11684)
		(layer "In11.Cu")
		(net "CLK_ESPI_CPU0_CLK1")
	)
	(segment
		(start 199.330564 -135.435594)
		(end 200.806304 -136.911334)
		(width 0.11684)
		(layer "In11.Cu")
		(net "CLK_ESPI_CPU0_CLK1")
	)
	(segment
		(start 199.96658 -134.799578)
		(end 201.12482 -135.957818)
		(width 0.11684)
		(layer "In11.Cu")
		(net "CLK_ESPI_CPU0_CLK1")
	)
	(segment
		(start 202.048872 -98.875596)
		(end 202.086718 -98.10496)
		(width 0.11684)
		(layer "In11.Cu")
		(net "CLK_ESPI_CPU0_CLK1")
	)
	(segment
		(start 202.086718 -96.090486)
		(end 201.74839 -95.273876)
		(width 0.11684)
		(layer "In11.Cu")
		(net "CLK_ESPI_CPU0_CLK1")
	)
	(segment
		(start 198.064374 -140.625322)
		(end 198.352156 -140.625322)
		(width 0.11684)
		(layer "In11.Cu")
		(net "CLK_ESPI_CPU0_CLK1")
	)
	(segment
		(start 202.561952 -134.685786)
		(end 202.71486 -134.532878)
		(width 0.11684)
		(layer "In11.Cu")
		(net "CLK_ESPI_CPU0_CLK1")
	)
	(segment
		(start 203.350876 -133.896862)
		(end 203.350876 -133.731762)
		(width 0.11684)
		(layer "In11.Cu")
		(net "CLK_ESPI_CPU0_CLK1")
	)
	(segment
		(start 202.828652 -131.772406)
		(end 202.98156 -131.619498)
		(width 0.11684)
		(layer "In11.Cu")
		(net "CLK_ESPI_CPU0_CLK1")
	)
	(segment
		(start 199.844152 -139.294362)
		(end 199.844152 -139.129262)
		(width 0.11684)
		(layer "In11.Cu")
		(net "CLK_ESPI_CPU0_CLK1")
	)
	(segment
		(start 203.464668 -131.30149)
		(end 203.464668 -131.13639)
		(width 0.11684)
		(layer "In11.Cu")
		(net "CLK_ESPI_CPU0_CLK1")
	)
	(segment
		(start 198.819008 -136.666986)
		(end 198.971916 -136.514078)
		(width 0.11684)
		(layer "In11.Cu")
		(net "CLK_ESPI_CPU0_CLK1")
	)
	(segment
		(start 183.804306 -25.691338)
		(end 180.004974 -21.892006)
		(width 0.11684)
		(layer "In11.Cu")
		(net "CLK_ESPI_CPU0_CLK1")
	)
	(segment
		(start 198.352156 -140.625322)
		(end 199.053704 -139.923774)
		(width 0.11684)
		(layer "In11.Cu")
		(net "CLK_ESPI_CPU0_CLK1")
	)
	(segment
		(start 197.03796 -137.74293)
		(end 197.03796 -137.563098)
		(width 0.11684)
		(layer "In11.Cu")
		(net "CLK_ESPI_CPU0_CLK1")
	)
	(segment
		(start 199.137016 -136.514078)
		(end 200.842372 -138.219434)
		(width 0.11684)
		(layer "In11.Cu")
		(net "CLK_ESPI_CPU0_CLK1")
	)
	(segment
		(start 203.197968 -134.04977)
		(end 203.350876 -133.896862)
		(width 0.11684)
		(layer "In11.Cu")
		(net "CLK_ESPI_CPU0_CLK1")
	)
	(segment
		(start 196.088 -138.648948)
		(end 198.064374 -140.625322)
		(width 0.11684)
		(layer "In11.Cu")
		(net "CLK_ESPI_CPU0_CLK1")
	)
	(segment
		(start 204.940916 -132.141722)
		(end 205.106016 -132.141722)
		(width 0.11684)
		(layer "In11.Cu")
		(net "CLK_ESPI_CPU0_CLK1")
	)
	(segment
		(start 200.842372 -138.219434)
		(end 201.007472 -138.219434)
		(width 0.11684)
		(layer "In11.Cu")
		(net "CLK_ESPI_CPU0_CLK1")
	)
	(segment
		(start 199.648572 -134.952486)
		(end 199.80148 -134.799578)
		(width 0.11684)
		(layer "In11.Cu")
		(net "CLK_ESPI_CPU0_CLK1")
	)
	(segment
		(start 200.834752 -135.031734)
		(end 200.834752 -134.866634)
		(width 0.11684)
		(layer "In11.Cu")
		(net "CLK_ESPI_CPU0_CLK1")
	)
	(segment
		(start 203.986892 -133.095746)
		(end 202.828652 -131.937506)
		(width 0.11684)
		(layer "In11.Cu")
		(net "CLK_ESPI_CPU0_CLK1")
	)
	(segment
		(start 199.329294 -91.110816)
		(end 194.432174 -86.213696)
		(width 0.11684)
		(layer "In11.Cu")
		(net "CLK_ESPI_CPU0_CLK1")
	)
	(segment
		(start 201.28992 -135.957818)
		(end 201.442828 -135.80491)
		(width 0.11684)
		(layer "In11.Cu")
		(net "CLK_ESPI_CPU0_CLK1")
	)
	(segment
		(start 203.032868 -134.04977)
		(end 203.197968 -134.04977)
		(width 0.11684)
		(layer "In11.Cu")
		(net "CLK_ESPI_CPU0_CLK1")
	)
	(segment
		(start 202.078844 -135.003794)
		(end 200.920604 -133.845554)
		(width 0.11684)
		(layer "In11.Cu")
		(net "CLK_ESPI_CPU0_CLK1")
	)
	(segment
		(start 197.03796 -137.563098)
		(end 197.257416 -137.343642)
		(width 0.11684)
		(layer "In11.Cu")
		(net "CLK_ESPI_CPU0_CLK1")
	)
	(segment
		(start 197.740524 -136.860534)
		(end 197.893432 -136.707626)
		(width 0.11684)
		(layer "In11.Cu")
		(net "CLK_ESPI_CPU0_CLK1")
	)
	(segment
		(start 204.814424 -116.298726)
		(end 204.795374 -116.279676)
		(width 0.11684)
		(layer "In11.Cu")
		(net "CLK_ESPI_CPU0_CLK1")
	)
	(segment
		(start 201.442828 -135.80491)
		(end 201.442828 -135.63981)
		(width 0.11684)
		(layer "In11.Cu")
		(net "CLK_ESPI_CPU0_CLK1")
	)
	(segment
		(start 204.622908 -132.45973)
		(end 203.464668 -131.30149)
		(width 0.11684)
		(layer "In11.Cu")
		(net "CLK_ESPI_CPU0_CLK1")
	)
	(segment
		(start 204.47 -132.777738)
		(end 204.622908 -132.62483)
		(width 0.11684)
		(layer "In11.Cu")
		(net "CLK_ESPI_CPU0_CLK1")
	)
	(segment
		(start 199.80148 -134.799578)
		(end 199.96658 -134.799578)
		(width 0.11684)
		(layer "In11.Cu")
		(net "CLK_ESPI_CPU0_CLK1")
	)
	(segment
		(start 204.795374 -108.045504)
		(end 202.946 -103.580184)
		(width 0.11684)
		(layer "In11.Cu")
		(net "CLK_ESPI_CPU0_CLK1")
	)
	(segment
		(start 199.053704 -139.923774)
		(end 199.053704 -139.758674)
		(width 0.11684)
		(layer "In11.Cu")
		(net "CLK_ESPI_CPU0_CLK1")
	)
	(segment
		(start 202.98156 -131.619498)
		(end 203.14666 -131.619498)
		(width 0.11684)
		(layer "In11.Cu")
		(net "CLK_ESPI_CPU0_CLK1")
	)
	(segment
		(start 396.148814 -305.825652)
		(end 396.265654 -305.708812)
		(width 0.11684)
		(layer "In15.Cu")
		(net "CLK_ESPI_CPU0_CLK1")
	)
	(segment
		(start 396.265654 -308.190392)
		(end 396.148814 -308.073552)
		(width 0.11684)
		(layer "In15.Cu")
		(net "CLK_ESPI_CPU0_CLK1")
	)
	(segment
		(start 206.715868 -143.983456)
		(end 204.352652 -143.00454)
		(width 0.11684)
		(layer "In15.Cu")
		(net "CLK_ESPI_CPU0_CLK1")
	)
	(segment
		(start 394.472922 -307.740812)
		(end 394.589762 -307.623972)
		(width 0.11684)
		(layer "In15.Cu")
		(net "CLK_ESPI_CPU0_CLK1")
	)
	(segment
		(start 396.148814 -307.623972)
		(end 396.265654 -307.507132)
		(width 0.11684)
		(layer "In15.Cu")
		(net "CLK_ESPI_CPU0_CLK1")
	)
	(segment
		(start 222.688912 -145.89252)
		(end 210.06181 -144.648936)
		(width 0.11684)
		(layer "In15.Cu")
		(net "CLK_ESPI_CPU0_CLK1")
	)
	(segment
		(start 369.779804 -217.701368)
		(end 330.27112 -178.192684)
		(width 0.11684)
		(layer "In15.Cu")
		(net "CLK_ESPI_CPU0_CLK1")
	)
	(segment
		(start 396.265654 -221.216728)
		(end 394.915898 -219.866972)
		(width 0.11684)
		(layer "In15.Cu")
		(net "CLK_ESPI_CPU0_CLK1")
	)
	(segment
		(start 396.265654 -306.607972)
		(end 396.265654 -306.392072)
		(width 0.11684)
		(layer "In15.Cu")
		(net "CLK_ESPI_CPU0_CLK1")
	)
	(segment
		(start 389.64489 -317.76035)
		(end 389.64489 -314.558934)
		(width 0.11684)
		(layer "In15.Cu")
		(net "CLK_ESPI_CPU0_CLK1")
	)
	(segment
		(start 394.589762 -305.825652)
		(end 396.148814 -305.825652)
		(width 0.11684)
		(layer "In15.Cu")
		(net "CLK_ESPI_CPU0_CLK1")
	)
	(segment
		(start 392.352276 -320.237104)
		(end 391.423652 -320.237104)
		(width 0.11684)
		(layer "In15.Cu")
		(net "CLK_ESPI_CPU0_CLK1")
	)
	(segment
		(start 396.265654 -305.708812)
		(end 396.265654 -305.492912)
		(width 0.11684)
		(layer "In15.Cu")
		(net "CLK_ESPI_CPU0_CLK1")
	)
	(segment
		(start 391.01395 -313.189874)
		(end 391.852658 -313.189874)
		(width 0.11684)
		(layer "In15.Cu")
		(net "CLK_ESPI_CPU0_CLK1")
	)
	(segment
		(start 394.915898 -219.866972)
		(end 386.245608 -219.866972)
		(width 0.11684)
		(layer "In15.Cu")
		(net "CLK_ESPI_CPU0_CLK1")
	)
	(segment
		(start 384.080004 -217.701368)
		(end 369.779804 -217.701368)
		(width 0.11684)
		(layer "In15.Cu")
		(net "CLK_ESPI_CPU0_CLK1")
	)
	(segment
		(start 275.27377 -169.217848)
		(end 269.085314 -167.340534)
		(width 0.11684)
		(layer "In15.Cu")
		(net "CLK_ESPI_CPU0_CLK1")
	)
	(segment
		(start 396.148814 -304.926492)
		(end 396.265654 -304.809652)
		(width 0.11684)
		(layer "In15.Cu")
		(net "CLK_ESPI_CPU0_CLK1")
	)
	(segment
		(start 396.265654 -306.392072)
		(end 396.148814 -306.275232)
		(width 0.11684)
		(layer "In15.Cu")
		(net "CLK_ESPI_CPU0_CLK1")
	)
	(segment
		(start 396.148814 -306.275232)
		(end 394.589762 -306.275232)
		(width 0.11684)
		(layer "In15.Cu")
		(net "CLK_ESPI_CPU0_CLK1")
	)
	(segment
		(start 394.472922 -307.956712)
		(end 394.472922 -307.740812)
		(width 0.11684)
		(layer "In15.Cu")
		(net "CLK_ESPI_CPU0_CLK1")
	)
	(segment
		(start 392.383264 -320.206116)
		(end 392.352276 -320.237104)
		(width 0.11684)
		(layer "In15.Cu")
		(net "CLK_ESPI_CPU0_CLK1")
	)
	(segment
		(start 394.589762 -307.623972)
		(end 396.148814 -307.623972)
		(width 0.11684)
		(layer "In15.Cu")
		(net "CLK_ESPI_CPU0_CLK1")
	)
	(segment
		(start 390.84377 -319.657222)
		(end 390.84377 -318.95923)
		(width 0.11684)
		(layer "In15.Cu")
		(net "CLK_ESPI_CPU0_CLK1")
	)
	(segment
		(start 391.852658 -313.189874)
		(end 396.265654 -308.776878)
		(width 0.11684)
		(layer "In15.Cu")
		(net "CLK_ESPI_CPU0_CLK1")
	)
	(segment
		(start 394.472922 -307.057552)
		(end 394.472922 -306.841652)
		(width 0.11684)
		(layer "In15.Cu")
		(net "CLK_ESPI_CPU0_CLK1")
	)
	(segment
		(start 202.416918 -141.068806)
		(end 201.140314 -141.068806)
		(width 0.11684)
		(layer "In15.Cu")
		(net "CLK_ESPI_CPU0_CLK1")
	)
	(segment
		(start 394.472922 -305.043332)
		(end 394.589762 -304.926492)
		(width 0.11684)
		(layer "In15.Cu")
		(net "CLK_ESPI_CPU0_CLK1")
	)
	(segment
		(start 396.265654 -307.291232)
		(end 396.148814 -307.174392)
		(width 0.11684)
		(layer "In15.Cu")
		(net "CLK_ESPI_CPU0_CLK1")
	)
	(segment
		(start 394.472922 -305.259232)
		(end 394.472922 -305.043332)
		(width 0.11684)
		(layer "In15.Cu")
		(net "CLK_ESPI_CPU0_CLK1")
	)
	(segment
		(start 308.603904 -169.217848)
		(end 275.27377 -169.217848)
		(width 0.11684)
		(layer "In15.Cu")
		(net "CLK_ESPI_CPU0_CLK1")
	)
	(segment
		(start 196.687694 -139.248642)
		(end 196.088 -138.648948)
		(width 0.11684)
		(layer "In15.Cu")
		(net "CLK_ESPI_CPU0_CLK1")
	)
	(segment
		(start 199.32015 -139.248642)
		(end 196.687694 -139.248642)
		(width 0.11684)
		(layer "In15.Cu")
		(net "CLK_ESPI_CPU0_CLK1")
	)
	(segment
		(start 389.64489 -314.558934)
		(end 391.01395 -313.189874)
		(width 0.11684)
		(layer "In15.Cu")
		(net "CLK_ESPI_CPU0_CLK1")
	)
	(segment
		(start 330.27112 -178.192684)
		(end 308.603904 -169.217848)
		(width 0.11684)
		(layer "In15.Cu")
		(net "CLK_ESPI_CPU0_CLK1")
	)
	(segment
		(start 236.986064 -145.89252)
		(end 222.688912 -145.89252)
		(width 0.11684)
		(layer "In15.Cu")
		(net "CLK_ESPI_CPU0_CLK1")
	)
	(segment
		(start 386.245608 -219.866972)
		(end 384.080004 -217.701368)
		(width 0.11684)
		(layer "In15.Cu")
		(net "CLK_ESPI_CPU0_CLK1")
	)
	(segment
		(start 394.589762 -306.724812)
		(end 396.148814 -306.724812)
		(width 0.11684)
		(layer "In15.Cu")
		(net "CLK_ESPI_CPU0_CLK1")
	)
	(segment
		(start 201.140314 -141.068806)
		(end 199.32015 -139.248642)
		(width 0.11684)
		(layer "In15.Cu")
		(net "CLK_ESPI_CPU0_CLK1")
	)
	(segment
		(start 204.352652 -143.00454)
		(end 202.416918 -141.068806)
		(width 0.11684)
		(layer "In15.Cu")
		(net "CLK_ESPI_CPU0_CLK1")
	)
	(segment
		(start 394.589762 -307.174392)
		(end 394.472922 -307.057552)
		(width 0.11684)
		(layer "In15.Cu")
		(net "CLK_ESPI_CPU0_CLK1")
	)
	(segment
		(start 394.472922 -305.942492)
		(end 394.589762 -305.825652)
		(width 0.11684)
		(layer "In15.Cu")
		(net "CLK_ESPI_CPU0_CLK1")
	)
	(segment
		(start 390.84377 -318.95923)
		(end 389.64489 -317.76035)
		(width 0.11684)
		(layer "In15.Cu")
		(net "CLK_ESPI_CPU0_CLK1")
	)
	(segment
		(start 396.148814 -308.073552)
		(end 394.589762 -308.073552)
		(width 0.11684)
		(layer "In15.Cu")
		(net "CLK_ESPI_CPU0_CLK1")
	)
	(segment
		(start 394.589762 -308.073552)
		(end 394.472922 -307.956712)
		(width 0.11684)
		(layer "In15.Cu")
		(net "CLK_ESPI_CPU0_CLK1")
	)
	(segment
		(start 394.589762 -306.275232)
		(end 394.472922 -306.158392)
		(width 0.11684)
		(layer "In15.Cu")
		(net "CLK_ESPI_CPU0_CLK1")
	)
	(segment
		(start 396.148814 -306.724812)
		(end 396.265654 -306.607972)
		(width 0.11684)
		(layer "In15.Cu")
		(net "CLK_ESPI_CPU0_CLK1")
	)
	(segment
		(start 396.265654 -305.492912)
		(end 396.148814 -305.376072)
		(width 0.11684)
		(layer "In15.Cu")
		(net "CLK_ESPI_CPU0_CLK1")
	)
	(segment
		(start 396.265654 -308.776878)
		(end 396.265654 -308.190392)
		(width 0.11684)
		(layer "In15.Cu")
		(net "CLK_ESPI_CPU0_CLK1")
	)
	(segment
		(start 210.06181 -144.648936)
		(end 206.715868 -143.983456)
		(width 0.11684)
		(layer "In15.Cu")
		(net "CLK_ESPI_CPU0_CLK1")
	)
	(segment
		(start 396.265654 -307.507132)
		(end 396.265654 -307.291232)
		(width 0.11684)
		(layer "In15.Cu")
		(net "CLK_ESPI_CPU0_CLK1")
	)
	(segment
		(start 391.423652 -320.237104)
		(end 390.84377 -319.657222)
		(width 0.11684)
		(layer "In15.Cu")
		(net "CLK_ESPI_CPU0_CLK1")
	)
	(segment
		(start 269.085314 -167.340534)
		(end 236.986064 -145.89252)
		(width 0.11684)
		(layer "In15.Cu")
		(net "CLK_ESPI_CPU0_CLK1")
	)
	(segment
		(start 396.148814 -307.174392)
		(end 394.589762 -307.174392)
		(width 0.11684)
		(layer "In15.Cu")
		(net "CLK_ESPI_CPU0_CLK1")
	)
	(segment
		(start 394.589762 -305.376072)
		(end 394.472922 -305.259232)
		(width 0.11684)
		(layer "In15.Cu")
		(net "CLK_ESPI_CPU0_CLK1")
	)
	(segment
		(start 396.148814 -305.376072)
		(end 394.589762 -305.376072)
		(width 0.11684)
		(layer "In15.Cu")
		(net "CLK_ESPI_CPU0_CLK1")
	)
	(segment
		(start 394.589762 -304.926492)
		(end 396.148814 -304.926492)
		(width 0.11684)
		(layer "In15.Cu")
		(net "CLK_ESPI_CPU0_CLK1")
	)
	(segment
		(start 392.407394 -320.206116)
		(end 392.383264 -320.206116)
		(width 0.11684)
		(layer "In15.Cu")
		(net "CLK_ESPI_CPU0_CLK1")
	)
	(segment
		(start 394.472922 -306.158392)
		(end 394.472922 -305.942492)
		(width 0.11684)
		(layer "In15.Cu")
		(net "CLK_ESPI_CPU0_CLK1")
	)
	(segment
		(start 394.472922 -306.841652)
		(end 394.589762 -306.724812)
		(width 0.11684)
		(layer "In15.Cu")
		(net "CLK_ESPI_CPU0_CLK1")
	)
	(segment
		(start 396.265654 -304.809652)
		(end 396.265654 -221.216728)
		(width 0.11684)
		(layer "In15.Cu")
		(net "CLK_ESPI_CPU0_CLK1")
	)
	(segment
		(start 144.054068 -313.176158)
		(end 144.379696 -313.501786)
		(width 0.10668)
		(layer "F.Cu")
		(net "CLK_CPU1_RTCCLK")
	)
	(segment
		(start 144.379696 -317.052706)
		(end 144.050258 -317.382144)
		(width 0.10668)
		(layer "F.Cu")
		(net "CLK_CPU1_RTCCLK")
	)
	(segment
		(start 137.1473 -298.491148)
		(end 137.1473 -307.089302)
		(width 0.10668)
		(layer "F.Cu")
		(net "CLK_CPU1_RTCCLK")
	)
	(segment
		(start 140.4366 -310.378602)
		(end 142.596108 -310.378602)
		(width 0.10668)
		(layer "F.Cu")
		(net "CLK_CPU1_RTCCLK")
	)
	(segment
		(start 138.913362 -296.725086)
		(end 137.1473 -298.491148)
		(width 0.10668)
		(layer "F.Cu")
		(net "CLK_CPU1_RTCCLK")
	)
	(segment
		(start 142.596108 -310.378602)
		(end 144.054068 -311.836562)
		(width 0.10668)
		(layer "F.Cu")
		(net "CLK_CPU1_RTCCLK")
	)
	(segment
		(start 139.337796 -294.880284)
		(end 139.337796 -296.08399)
		(width 0.10668)
		(layer "F.Cu")
		(net "CLK_CPU1_RTCCLK")
	)
	(segment
		(start 137.1473 -307.089302)
		(end 140.4366 -310.378602)
		(width 0.10668)
		(layer "F.Cu")
		(net "CLK_CPU1_RTCCLK")
	)
	(segment
		(start 144.379696 -313.501786)
		(end 144.379696 -317.052706)
		(width 0.10668)
		(layer "F.Cu")
		(net "CLK_CPU1_RTCCLK")
	)
	(segment
		(start 138.913362 -296.508424)
		(end 138.913362 -296.725086)
		(width 0.10668)
		(layer "F.Cu")
		(net "CLK_CPU1_RTCCLK")
	)
	(segment
		(start 139.337796 -296.08399)
		(end 138.913362 -296.508424)
		(width 0.10668)
		(layer "F.Cu")
		(net "CLK_CPU1_RTCCLK")
	)
	(segment
		(start 144.054068 -311.836562)
		(end 144.054068 -313.176158)
		(width 0.10668)
		(layer "F.Cu")
		(net "CLK_CPU1_RTCCLK")
	)
	(via
		(at 146.2024 -319.3669)
		(size 0.6604)
		(drill 0.3302)
		(layers "F.Cu" "B.Cu")
		(net "CLK_CPU1_RTCCLK")
	)
	(via
		(at 144.050258 -317.382144)
		(size 0.508)
		(drill 0.254)
		(layers "F.Cu" "B.Cu")
		(net "CLK_CPU1_RTCCLK")
	)
	(segment
		(start 145.273268 -317.382144)
		(end 144.050258 -317.382144)
		(width 0.10668)
		(layer "B.Cu")
		(net "CLK_CPU1_RTCCLK")
	)
	(segment
		(start 146.410934 -319.575434)
		(end 146.410934 -320.525902)
		(width 0.10668)
		(layer "B.Cu")
		(net "CLK_CPU1_RTCCLK")
	)
	(segment
		(start 145.524728 -318.208152)
		(end 146.2024 -318.885824)
		(width 0.10668)
		(layer "B.Cu")
		(net "CLK_CPU1_RTCCLK")
	)
	(segment
		(start 145.524728 -317.633604)
		(end 145.273268 -317.382144)
		(width 0.10668)
		(layer "B.Cu")
		(net "CLK_CPU1_RTCCLK")
	)
	(segment
		(start 146.2024 -319.3669)
		(end 146.410934 -319.575434)
		(width 0.10668)
		(layer "B.Cu")
		(net "CLK_CPU1_RTCCLK")
	)
	(segment
		(start 145.524728 -318.208152)
		(end 145.524728 -317.633604)
		(width 0.10668)
		(layer "B.Cu")
		(net "CLK_CPU1_RTCCLK")
	)
	(segment
		(start 146.2024 -318.885824)
		(end 146.2024 -319.3669)
		(width 0.10668)
		(layer "B.Cu")
		(net "CLK_CPU1_RTCCLK")
	)
	(segment
		(start 387.026404 -312.95086)
		(end 383.033778 -308.958234)
		(width 0.10668)
		(layer "F.Cu")
		(net "CLK_CPU0_RTCCLK")
	)
	(segment
		(start 388.6581 -312.95086)
		(end 387.026404 -312.95086)
		(width 0.10668)
		(layer "F.Cu")
		(net "CLK_CPU0_RTCCLK")
	)
	(segment
		(start 387.323584 -298.055538)
		(end 387.323584 -296.046398)
		(width 0.10668)
		(layer "F.Cu")
		(net "CLK_CPU0_RTCCLK")
	)
	(segment
		(start 383.033778 -302.345344)
		(end 387.323584 -298.055538)
		(width 0.10668)
		(layer "F.Cu")
		(net "CLK_CPU0_RTCCLK")
	)
	(segment
		(start 387.277864 -296.000678)
		(end 387.277864 -294.88003)
		(width 0.10668)
		(layer "F.Cu")
		(net "CLK_CPU0_RTCCLK")
	)
	(segment
		(start 389.355584 -313.648344)
		(end 388.6581 -312.95086)
		(width 0.10668)
		(layer "F.Cu")
		(net "CLK_CPU0_RTCCLK")
	)
	(segment
		(start 383.033778 -308.958234)
		(end 383.033778 -302.345344)
		(width 0.10668)
		(layer "F.Cu")
		(net "CLK_CPU0_RTCCLK")
	)
	(segment
		(start 387.323584 -296.046398)
		(end 387.277864 -296.000678)
		(width 0.10668)
		(layer "F.Cu")
		(net "CLK_CPU0_RTCCLK")
	)
	(via
		(at 389.355584 -313.648344)
		(size 0.508)
		(drill 0.254)
		(layers "F.Cu" "B.Cu")
		(net "CLK_CPU0_RTCCLK")
	)
	(segment
		(start 389.487664 -313.780424)
		(end 389.355584 -313.648344)
		(width 0.10668)
		(layer "B.Cu")
		(net "CLK_CPU0_RTCCLK")
	)
	(segment
		(start 391.112248 -313.772804)
		(end 391.104628 -313.780424)
		(width 0.10668)
		(layer "B.Cu")
		(net "CLK_CPU0_RTCCLK")
	)
	(segment
		(start 391.104628 -313.780424)
		(end 390.020048 -313.780424)
		(width 0.10668)
		(layer "B.Cu")
		(net "CLK_CPU0_RTCCLK")
	)
	(segment
		(start 392.118088 -313.772804)
		(end 391.112248 -313.772804)
		(width 0.10668)
		(layer "B.Cu")
		(net "CLK_CPU0_RTCCLK")
	)
	(segment
		(start 390.020048 -313.780424)
		(end 389.487664 -313.780424)
		(width 0.10668)
		(layer "B.Cu")
		(net "CLK_CPU0_RTCCLK")
	)
	(segment
		(start 215.31961 -20.687792)
		(end 215.552528 -20.687792)
		(width 0.10668)
		(layer "F.Cu")
		(net "CLK_50M_RMII_R")
	)
	(segment
		(start 215.904064 -21.039328)
		(end 215.904064 -22.184614)
		(width 0.10668)
		(layer "F.Cu")
		(net "CLK_50M_RMII_R")
	)
	(segment
		(start 215.552528 -20.687792)
		(end 215.904064 -21.039328)
		(width 0.10668)
		(layer "F.Cu")
		(net "CLK_50M_RMII_R")
	)
	(segment
		(start 215.904064 -22.904704)
		(end 215.904064 -22.184614)
		(width 0.10668)
		(layer "F.Cu")
		(net "CLK_50M_RMII_R")
	)
	(via
		(at 215.904064 -22.184614)
		(size 0.508)
		(drill 0.254)
		(layers "F.Cu" "B.Cu")
		(net "CLK_50M_RMII_R")
	)
	(segment
		(start 168.666922 -16.549878)
		(end 168.666922 -17.99336)
		(width 0.10668)
		(layer "F.Cu")
		(net "CLK_50M_RMII_BMC_OCP")
	)
	(segment
		(start 168.666922 -17.99336)
		(end 168.25595 -18.983452)
		(width 0.10668)
		(layer "F.Cu")
		(net "CLK_50M_RMII_BMC_OCP")
	)
	(segment
		(start 212.661754 -22.974554)
		(end 212.661754 -23.678134)
		(width 0.10668)
		(layer "F.Cu")
		(net "CLK_50M_RMII_BMC_OCP")
	)
	(segment
		(start 168.25595 -18.983452)
		(end 168.046654 -19.192748)
		(width 0.10668)
		(layer "F.Cu")
		(net "CLK_50M_RMII_BMC_OCP")
	)
	(via
		(at 168.046654 -19.192748)
		(size 0.508)
		(drill 0.254)
		(layers "F.Cu" "B.Cu")
		(net "CLK_50M_RMII_BMC_OCP")
	)
	(via
		(at 212.661754 -23.678134)
		(size 0.508)
		(drill 0.254)
		(layers "F.Cu" "B.Cu")
		(net "CLK_50M_RMII_BMC_OCP")
	)
	(via
		(at 172.03547 -14.718538)
		(size 0.508)
		(drill 0.254)
		(layers "F.Cu" "B.Cu")
		(net "CLK_50M_RMII_BMC_OCP")
	)
	(segment
		(start 206.702406 -13.241274)
		(end 206.819246 -13.124434)
		(width 0.11684)
		(layer "In6.Cu")
		(net "CLK_50M_RMII_BMC_OCP")
	)
	(segment
		(start 173.047914 -14.037818)
		(end 173.164754 -14.154658)
		(width 0.11684)
		(layer "In6.Cu")
		(net "CLK_50M_RMII_BMC_OCP")
	)
	(segment
		(start 181.087014 -13.788644)
		(end 181.203854 -13.671804)
		(width 0.11684)
		(layer "In6.Cu")
		(net "CLK_50M_RMII_BMC_OCP")
	)
	(segment
		(start 198.750682 -19.059652)
		(end 199.144382 -19.059652)
		(width 0.11684)
		(layer "In6.Cu")
		(net "CLK_50M_RMII_BMC_OCP")
	)
	(segment
		(start 207.235552 -17.866868)
		(end 207.352392 -17.983708)
		(width 0.11684)
		(layer "In6.Cu")
		(net "CLK_50M_RMII_BMC_OCP")
	)
	(segment
		(start 209.172556 -24.448008)
		(end 209.566256 -24.448008)
		(width 0.11684)
		(layer "In6.Cu")
		(net "CLK_50M_RMII_BMC_OCP")
	)
	(segment
		(start 210.193636 -19.699224)
		(end 210.310476 -19.816064)
		(width 0.11684)
		(layer "In6.Cu")
		(net "CLK_50M_RMII_BMC_OCP")
	)
	(segment
		(start 178.694334 -15.502382)
		(end 178.694334 -13.048488)
		(width 0.11684)
		(layer "In6.Cu")
		(net "CLK_50M_RMII_BMC_OCP")
	)
	(segment
		(start 183.085994 -14.1478)
		(end 183.202834 -14.26464)
		(width 0.11684)
		(layer "In6.Cu")
		(net "CLK_50M_RMII_BMC_OCP")
	)
	(segment
		(start 203.682346 -15.010892)
		(end 204.076046 -15.010892)
		(width 0.11684)
		(layer "In6.Cu")
		(net "CLK_50M_RMII_BMC_OCP")
	)
	(segment
		(start 211.565236 -22.754082)
		(end 211.682076 -22.870922)
		(width 0.11684)
		(layer "In6.Cu")
		(net "CLK_50M_RMII_BMC_OCP")
	)
	(segment
		(start 205.564486 -13.124434)
		(end 205.958186 -13.124434)
		(width 0.11684)
		(layer "In6.Cu")
		(net "CLK_50M_RMII_BMC_OCP")
	)
	(segment
		(start 179.321714 -15.498572)
		(end 179.438554 -15.615412)
		(width 0.11684)
		(layer "In6.Cu")
		(net "CLK_50M_RMII_BMC_OCP")
	)
	(segment
		(start 186.222894 -14.015212)
		(end 186.222894 -13.048488)
		(width 0.11684)
		(layer "In6.Cu")
		(net "CLK_50M_RMII_BMC_OCP")
	)
	(segment
		(start 175.674274 -15.000478)
		(end 176.067974 -15.000478)
		(width 0.11684)
		(layer "In6.Cu")
		(net "CLK_50M_RMII_BMC_OCP")
	)
	(segment
		(start 178.577494 -15.619222)
		(end 178.694334 -15.502382)
		(width 0.11684)
		(layer "In6.Cu")
		(net "CLK_50M_RMII_BMC_OCP")
	)
	(segment
		(start 179.438554 -15.615412)
		(end 179.832254 -15.615412)
		(width 0.11684)
		(layer "In6.Cu")
		(net "CLK_50M_RMII_BMC_OCP")
	)
	(segment
		(start 202.310746 -14.894052)
		(end 202.427586 -15.010892)
		(width 0.11684)
		(layer "In6.Cu")
		(net "CLK_50M_RMII_BMC_OCP")
	)
	(segment
		(start 217.211656 -21.712174)
		(end 217.211656 -19.816064)
		(width 0.11684)
		(layer "In6.Cu")
		(net "CLK_50M_RMII_BMC_OCP")
	)
	(segment
		(start 210.382104 -17.356328)
		(end 207.979772 -17.356328)
		(width 0.11684)
		(layer "In6.Cu")
		(net "CLK_50M_RMII_BMC_OCP")
	)
	(segment
		(start 181.948074 -13.885672)
		(end 182.341774 -13.885672)
		(width 0.11684)
		(layer "In6.Cu")
		(net "CLK_50M_RMII_BMC_OCP")
	)
	(segment
		(start 174.185834 -12.560808)
		(end 174.302674 -12.677648)
		(width 0.11684)
		(layer "In6.Cu")
		(net "CLK_50M_RMII_BMC_OCP")
	)
	(segment
		(start 212.075776 -22.870922)
		(end 212.192616 -22.754082)
		(width 0.11684)
		(layer "In6.Cu")
		(net "CLK_50M_RMII_BMC_OCP")
	)
	(segment
		(start 193.68516 -12.027408)
		(end 194.782186 -13.124434)
		(width 0.11684)
		(layer "In6.Cu")
		(net "CLK_50M_RMII_BMC_OCP")
	)
	(segment
		(start 195.526406 -13.124434)
		(end 195.920106 -13.124434)
		(width 0.11684)
		(layer "In6.Cu")
		(net "CLK_50M_RMII_BMC_OCP")
	)
	(segment
		(start 183.830214 -12.931648)
		(end 184.223914 -12.931648)
		(width 0.11684)
		(layer "In6.Cu")
		(net "CLK_50M_RMII_BMC_OCP")
	)
	(segment
		(start 210.310476 -19.816064)
		(end 210.310476 -24.331168)
		(width 0.11684)
		(layer "In6.Cu")
		(net "CLK_50M_RMII_BMC_OCP")
	)
	(segment
		(start 214.074756 -19.816064)
		(end 214.074756 -21.544534)
		(width 0.11684)
		(layer "In6.Cu")
		(net "CLK_50M_RMII_BMC_OCP")
	)
	(segment
		(start 217.211656 -19.816064)
		(end 217.328496 -19.699224)
		(width 0.11684)
		(layer "In6.Cu")
		(net "CLK_50M_RMII_BMC_OCP")
	)
	(segment
		(start 212.192616 -22.754082)
		(end 212.192616 -19.816064)
		(width 0.11684)
		(layer "In6.Cu")
		(net "CLK_50M_RMII_BMC_OCP")
	)
	(segment
		(start 197.174866 -13.124434)
		(end 197.291706 -13.241274)
		(width 0.11684)
		(layer "In6.Cu")
		(net "CLK_50M_RMII_BMC_OCP")
	)
	(segment
		(start 210.937856 -24.331168)
		(end 210.937856 -19.816064)
		(width 0.11684)
		(layer "In6.Cu")
		(net "CLK_50M_RMII_BMC_OCP")
	)
	(segment
		(start 213.564216 -19.699224)
		(end 213.957916 -19.699224)
		(width 0.11684)
		(layer "In6.Cu")
		(net "CLK_50M_RMII_BMC_OCP")
	)
	(segment
		(start 207.979772 -17.356328)
		(end 207.862932 -17.239488)
		(width 0.11684)
		(layer "In6.Cu")
		(net "CLK_50M_RMII_BMC_OCP")
	)
	(segment
		(start 181.320694 -12.931648)
		(end 181.714394 -12.931648)
		(width 0.11684)
		(layer "In6.Cu")
		(net "CLK_50M_RMII_BMC_OCP")
	)
	(segment
		(start 207.118712 -16.728948)
		(end 207.235552 -16.845788)
		(width 0.11684)
		(layer "In6.Cu")
		(net "CLK_50M_RMII_BMC_OCP")
	)
	(segment
		(start 185.595514 -13.048488)
		(end 185.595514 -14.015212)
		(width 0.11684)
		(layer "In6.Cu")
		(net "CLK_50M_RMII_BMC_OCP")
	)
	(segment
		(start 195.920106 -13.124434)
		(end 196.036946 -13.241274)
		(width 0.11684)
		(layer "In6.Cu")
		(net "CLK_50M_RMII_BMC_OCP")
	)
	(segment
		(start 175.440594 -12.931648)
		(end 175.557434 -13.048488)
		(width 0.11684)
		(layer "In6.Cu")
		(net "CLK_50M_RMII_BMC_OCP")
	)
	(segment
		(start 201.172826 -15.010892)
		(end 201.566526 -15.010892)
		(width 0.11684)
		(layer "In6.Cu")
		(net "CLK_50M_RMII_BMC_OCP")
	)
	(segment
		(start 205.958186 -13.124434)
		(end 206.075026 -13.241274)
		(width 0.11684)
		(layer "In6.Cu")
		(net "CLK_50M_RMII_BMC_OCP")
	)
	(segment
		(start 198.546466 -14.894052)
		(end 198.663306 -15.010892)
		(width 0.11684)
		(layer "In6.Cu")
		(net "CLK_50M_RMII_BMC_OCP")
	)
	(segment
		(start 184.851294 -14.163548)
		(end 184.968134 -14.046708)
		(width 0.11684)
		(layer "In6.Cu")
		(net "CLK_50M_RMII_BMC_OCP")
	)
	(segment
		(start 183.596534 -14.26464)
		(end 183.713374 -14.1478)
		(width 0.11684)
		(layer "In6.Cu")
		(net "CLK_50M_RMII_BMC_OCP")
	)
	(segment
		(start 178.066954 -15.502382)
		(end 178.183794 -15.619222)
		(width 0.11684)
		(layer "In6.Cu")
		(net "CLK_50M_RMII_BMC_OCP")
	)
	(segment
		(start 174.302674 -14.065504)
		(end 174.419514 -14.182344)
		(width 0.11684)
		(layer "In6.Cu")
		(net "CLK_50M_RMII_BMC_OCP")
	)
	(segment
		(start 176.812194 -13.048488)
		(end 176.812194 -14.685518)
		(width 0.11684)
		(layer "In6.Cu")
		(net "CLK_50M_RMII_BMC_OCP")
	)
	(segment
		(start 172.03547 -13.202412)
		(end 172.306234 -12.931648)
		(width 0.11684)
		(layer "In6.Cu")
		(net "CLK_50M_RMII_BMC_OCP")
	)
	(segment
		(start 189.145926 -13.765276)
		(end 189.145926 -13.600176)
		(width 0.11684)
		(layer "In6.Cu")
		(net "CLK_50M_RMII_BMC_OCP")
	)
	(segment
		(start 176.812194 -14.685518)
		(end 176.929034 -14.802358)
		(width 0.11684)
		(layer "In6.Cu")
		(net "CLK_50M_RMII_BMC_OCP")
	)
	(segment
		(start 213.330536 -21.197824)
		(end 213.447376 -21.080984)
		(width 0.11684)
		(layer "In6.Cu")
		(net "CLK_50M_RMII_BMC_OCP")
	)
	(segment
		(start 176.184814 -13.048488)
		(end 176.301654 -12.931648)
		(width 0.11684)
		(layer "In6.Cu")
		(net "CLK_50M_RMII_BMC_OCP")
	)
	(segment
		(start 202.310746 -13.241274)
		(end 202.310746 -14.894052)
		(width 0.11684)
		(layer "In6.Cu")
		(net "CLK_50M_RMII_BMC_OCP")
	)
	(segment
		(start 199.173846 -14.894052)
		(end 199.173846 -13.241274)
		(width 0.11684)
		(layer "In6.Cu")
		(net "CLK_50M_RMII_BMC_OCP")
	)
	(segment
		(start 204.703426 -13.124434)
		(end 204.820266 -13.241274)
		(width 0.11684)
		(layer "In6.Cu")
		(net "CLK_50M_RMII_BMC_OCP")
	)
	(segment
		(start 214.818976 -19.699224)
		(end 215.212676 -19.699224)
		(width 0.11684)
		(layer "In6.Cu")
		(net "CLK_50M_RMII_BMC_OCP")
	)
	(segment
		(start 217.094816 -21.829014)
		(end 217.211656 -21.712174)
		(width 0.11684)
		(layer "In6.Cu")
		(net "CLK_50M_RMII_BMC_OCP")
	)
	(segment
		(start 173.164754 -14.154658)
		(end 173.558454 -14.154658)
		(width 0.11684)
		(layer "In6.Cu")
		(net "CLK_50M_RMII_BMC_OCP")
	)
	(segment
		(start 196.036946 -14.894052)
		(end 196.153786 -15.010892)
		(width 0.11684)
		(layer "In6.Cu")
		(net "CLK_50M_RMII_BMC_OCP")
	)
	(segment
		(start 194.782186 -13.124434)
		(end 194.782186 -14.894052)
		(width 0.11684)
		(layer "In6.Cu")
		(net "CLK_50M_RMII_BMC_OCP")
	)
	(segment
		(start 199.801226 -14.894052)
		(end 199.918066 -15.010892)
		(width 0.11684)
		(layer "In6.Cu")
		(net "CLK_50M_RMII_BMC_OCP")
	)
	(segment
		(start 209.055716 -19.188684)
		(end 209.055716 -24.331168)
		(width 0.11684)
		(layer "In6.Cu")
		(net "CLK_50M_RMII_BMC_OCP")
	)
	(segment
		(start 196.781166 -13.124434)
		(end 197.174866 -13.124434)
		(width 0.11684)
		(layer "In6.Cu")
		(net "CLK_50M_RMII_BMC_OCP")
	)
	(segment
		(start 200.428606 -14.894052)
		(end 200.428606 -13.241274)
		(width 0.11684)
		(layer "In6.Cu")
		(net "CLK_50M_RMII_BMC_OCP")
	)
	(segment
		(start 201.683366 -14.894052)
		(end 201.683366 -13.241274)
		(width 0.11684)
		(layer "In6.Cu")
		(net "CLK_50M_RMII_BMC_OCP")
	)
	(segment
		(start 216.21369 -25.021794)
		(end 213.575646 -25.021794)
		(width 0.11684)
		(layer "In6.Cu")
		(net "CLK_50M_RMII_BMC_OCP")
	)
	(segment
		(start 187.590938 -11.880342)
		(end 188.602112 -10.869168)
		(width 0.11684)
		(layer "In6.Cu")
		(net "CLK_50M_RMII_BMC_OCP")
	)
	(segment
		(start 209.683096 -19.816064)
		(end 209.799936 -19.699224)
		(width 0.11684)
		(layer "In6.Cu")
		(net "CLK_50M_RMII_BMC_OCP")
	)
	(segment
		(start 185.712354 -14.132052)
		(end 186.106054 -14.132052)
		(width 0.11684)
		(layer "In6.Cu")
		(net "CLK_50M_RMII_BMC_OCP")
	)
	(segment
		(start 215.956896 -19.816064)
		(end 216.073736 -19.699224)
		(width 0.11684)
		(layer "In6.Cu")
		(net "CLK_50M_RMII_BMC_OCP")
	)
	(segment
		(start 210.427316 -24.448008)
		(end 210.821016 -24.448008)
		(width 0.11684)
		(layer "In6.Cu")
		(net "CLK_50M_RMII_BMC_OCP")
	)
	(segment
		(start 196.868542 -16.728948)
		(end 197.262242 -16.728948)
		(width 0.11684)
		(layer "In6.Cu")
		(net "CLK_50M_RMII_BMC_OCP")
	)
	(segment
		(start 204.820266 -14.894052)
		(end 204.937106 -15.010892)
		(width 0.11684)
		(layer "In6.Cu")
		(net "CLK_50M_RMII_BMC_OCP")
	)
	(segment
		(start 176.184814 -14.883638)
		(end 176.184814 -13.048488)
		(width 0.11684)
		(layer "In6.Cu")
		(net "CLK_50M_RMII_BMC_OCP")
	)
	(segment
		(start 196.664326 -13.241274)
		(end 196.781166 -13.124434)
		(width 0.11684)
		(layer "In6.Cu")
		(net "CLK_50M_RMII_BMC_OCP")
	)
	(segment
		(start 180.576474 -13.671804)
		(end 180.693314 -13.788644)
		(width 0.11684)
		(layer "In6.Cu")
		(net "CLK_50M_RMII_BMC_OCP")
	)
	(segment
		(start 200.632822 -16.728948)
		(end 207.118712 -16.728948)
		(width 0.11684)
		(layer "In6.Cu")
		(net "CLK_50M_RMII_BMC_OCP")
	)
	(segment
		(start 182.575454 -12.931648)
		(end 182.969154 -12.931648)
		(width 0.11684)
		(layer "In6.Cu")
		(net "CLK_50M_RMII_BMC_OCP")
	)
	(segment
		(start 204.309726 -13.124434)
		(end 204.703426 -13.124434)
		(width 0.11684)
		(layer "In6.Cu")
		(net "CLK_50M_RMII_BMC_OCP")
	)
	(segment
		(start 196.664326 -14.894052)
		(end 196.664326 -13.241274)
		(width 0.11684)
		(layer "In6.Cu")
		(net "CLK_50M_RMII_BMC_OCP")
	)
	(segment
		(start 176.301654 -12.931648)
		(end 176.695354 -12.931648)
		(width 0.11684)
		(layer "In6.Cu")
		(net "CLK_50M_RMII_BMC_OCP")
	)
	(segment
		(start 188.602112 -10.869168)
		(end 189.79896 -10.869168)
		(width 0.11684)
		(layer "In6.Cu")
		(net "CLK_50M_RMII_BMC_OCP")
	)
	(segment
		(start 200.939146 -13.124434)
		(end 201.055986 -13.241274)
		(width 0.11684)
		(layer "In6.Cu")
		(net "CLK_50M_RMII_BMC_OCP")
	)
	(segment
		(start 197.379082 -16.845788)
		(end 197.379082 -20.83308)
		(width 0.11684)
		(layer "In6.Cu")
		(net "CLK_50M_RMII_BMC_OCP")
	)
	(segment
		(start 212.819996 -19.816064)
		(end 212.819996 -21.080984)
		(width 0.11684)
		(layer "In6.Cu")
		(net "CLK_50M_RMII_BMC_OCP")
	)
	(segment
		(start 204.820266 -13.241274)
		(end 204.820266 -14.894052)
		(width 0.11684)
		(layer "In6.Cu")
		(net "CLK_50M_RMII_BMC_OCP")
	)
	(segment
		(start 206.702406 -14.894052)
		(end 206.702406 -13.241274)
		(width 0.11684)
		(layer "In6.Cu")
		(net "CLK_50M_RMII_BMC_OCP")
	)
	(segment
		(start 196.036946 -13.241274)
		(end 196.036946 -14.894052)
		(width 0.11684)
		(layer "In6.Cu")
		(net "CLK_50M_RMII_BMC_OCP")
	)
	(segment
		(start 193.68516 -10.935716)
		(end 193.68516 -12.027408)
		(width 0.11684)
		(layer "In6.Cu")
		(net "CLK_50M_RMII_BMC_OCP")
	)
	(segment
		(start 194.899026 -15.010892)
		(end 195.292726 -15.010892)
		(width 0.11684)
		(layer "In6.Cu")
		(net "CLK_50M_RMII_BMC_OCP")
	)
	(segment
		(start 199.057006 -15.010892)
		(end 199.173846 -14.894052)
		(width 0.11684)
		(layer "In6.Cu")
		(net "CLK_50M_RMII_BMC_OCP")
	)
	(segment
		(start 173.047914 -13.048488)
		(end 173.047914 -14.037818)
		(width 0.11684)
		(layer "In6.Cu")
		(net "CLK_50M_RMII_BMC_OCP")
	)
	(segment
		(start 211.682076 -22.870922)
		(end 212.075776 -22.870922)
		(width 0.11684)
		(layer "In6.Cu")
		(net "CLK_50M_RMII_BMC_OCP")
	)
	(segment
		(start 198.429626 -13.124434)
		(end 198.546466 -13.241274)
		(width 0.11684)
		(layer "In6.Cu")
		(net "CLK_50M_RMII_BMC_OCP")
	)
	(segment
		(start 215.956896 -21.444458)
		(end 215.956896 -19.816064)
		(width 0.11684)
		(layer "In6.Cu")
		(net "CLK_50M_RMII_BMC_OCP")
	)
	(segment
		(start 197.919086 -13.241274)
		(end 198.035926 -13.124434)
		(width 0.11684)
		(layer "In6.Cu")
		(net "CLK_50M_RMII_BMC_OCP")
	)
	(segment
		(start 201.683366 -13.241274)
		(end 201.800206 -13.124434)
		(width 0.11684)
		(layer "In6.Cu")
		(net "CLK_50M_RMII_BMC_OCP")
	)
	(segment
		(start 194.9958 -16.601948)
		(end 195.1228 -16.728948)
		(width 0.11684)
		(layer "In6.Cu")
		(net "CLK_50M_RMII_BMC_OCP")
	)
	(segment
		(start 205.447646 -13.241274)
		(end 205.564486 -13.124434)
		(width 0.11684)
		(layer "In6.Cu")
		(net "CLK_50M_RMII_BMC_OCP")
	)
	(segment
		(start 186.9821 -12.48918)
		(end 187.1472 -12.48918)
		(width 0.11684)
		(layer "In6.Cu")
		(net "CLK_50M_RMII_BMC_OCP")
	)
	(segment
		(start 181.831234 -13.768832)
		(end 181.948074 -13.885672)
		(width 0.11684)
		(layer "In6.Cu")
		(net "CLK_50M_RMII_BMC_OCP")
	)
	(segment
		(start 209.799936 -19.699224)
		(end 210.193636 -19.699224)
		(width 0.11684)
		(layer "In6.Cu")
		(net "CLK_50M_RMII_BMC_OCP")
	)
	(segment
		(start 178.811174 -12.931648)
		(end 179.204874 -12.931648)
		(width 0.11684)
		(layer "In6.Cu")
		(net "CLK_50M_RMII_BMC_OCP")
	)
	(segment
		(start 195.292726 -15.010892)
		(end 195.409566 -14.894052)
		(width 0.11684)
		(layer "In6.Cu")
		(net "CLK_50M_RMII_BMC_OCP")
	)
	(segment
		(start 177.439574 -14.685518)
		(end 177.439574 -13.048488)
		(width 0.11684)
		(layer "In6.Cu")
		(net "CLK_50M_RMII_BMC_OCP")
	)
	(segment
		(start 186.339734 -12.931648)
		(end 186.539632 -12.931648)
		(width 0.11684)
		(layer "In6.Cu")
		(net "CLK_50M_RMII_BMC_OCP")
	)
	(segment
		(start 177.439574 -13.048488)
		(end 177.556414 -12.931648)
		(width 0.11684)
		(layer "In6.Cu")
		(net "CLK_50M_RMII_BMC_OCP")
	)
	(segment
		(start 200.515982 -17.75587)
		(end 200.515982 -16.845788)
		(width 0.11684)
		(layer "In6.Cu")
		(net "CLK_50M_RMII_BMC_OCP")
	)
	(segment
		(start 196.124322 -19.877024)
		(end 196.241162 -19.993864)
		(width 0.11684)
		(layer "In6.Cu")
		(net "CLK_50M_RMII_BMC_OCP")
	)
	(segment
		(start 172.931074 -12.931648)
		(end 173.047914 -13.048488)
		(width 0.11684)
		(layer "In6.Cu")
		(net "CLK_50M_RMII_BMC_OCP")
	)
	(segment
		(start 203.054966 -13.124434)
		(end 203.448666 -13.124434)
		(width 0.11684)
		(layer "In6.Cu")
		(net "CLK_50M_RMII_BMC_OCP")
	)
	(segment
		(start 179.321714 -13.048488)
		(end 179.321714 -15.498572)
		(width 0.11684)
		(layer "In6.Cu")
		(net "CLK_50M_RMII_BMC_OCP")
	)
	(segment
		(start 216.584276 -21.712174)
		(end 216.701116 -21.829014)
		(width 0.11684)
		(layer "In6.Cu")
		(net "CLK_50M_RMII_BMC_OCP")
	)
	(segment
		(start 195.409566 -14.894052)
		(end 195.409566 -13.241274)
		(width 0.11684)
		(layer "In6.Cu")
		(net "CLK_50M_RMII_BMC_OCP")
	)
	(segment
		(start 172.03547 -14.718538)
		(end 172.03547 -13.202412)
		(width 0.11684)
		(layer "In6.Cu")
		(net "CLK_50M_RMII_BMC_OCP")
	)
	(segment
		(start 180.459634 -12.931648)
		(end 180.576474 -13.048488)
		(width 0.11684)
		(layer "In6.Cu")
		(net "CLK_50M_RMII_BMC_OCP")
	)
	(segment
		(start 174.813214 -14.182344)
		(end 174.930054 -14.065504)
		(width 0.11684)
		(layer "In6.Cu")
		(net "CLK_50M_RMII_BMC_OCP")
	)
	(segment
		(start 181.203854 -13.048488)
		(end 181.320694 -12.931648)
		(width 0.11684)
		(layer "In6.Cu")
		(net "CLK_50M_RMII_BMC_OCP")
	)
	(segment
		(start 196.007482 -16.728948)
		(end 196.124322 -16.845788)
		(width 0.11684)
		(layer "In6.Cu")
		(net "CLK_50M_RMII_BMC_OCP")
	)
	(segment
		(start 199.261222 -18.942812)
		(end 199.261222 -16.845788)
		(width 0.11684)
		(layer "In6.Cu")
		(net "CLK_50M_RMII_BMC_OCP")
	)
	(segment
		(start 187.590938 -12.045188)
		(end 187.590938 -11.880342)
		(width 0.11684)
		(layer "In6.Cu")
		(net "CLK_50M_RMII_BMC_OCP")
	)
	(segment
		(start 206.075026 -14.894052)
		(end 206.191866 -15.010892)
		(width 0.11684)
		(layer "In6.Cu")
		(net "CLK_50M_RMII_BMC_OCP")
	)
	(segment
		(start 209.683096 -24.331168)
		(end 209.683096 -19.816064)
		(width 0.11684)
		(layer "In6.Cu")
		(net "CLK_50M_RMII_BMC_OCP")
	)
	(segment
		(start 200.428606 -13.241274)
		(end 200.545446 -13.124434)
		(width 0.11684)
		(layer "In6.Cu")
		(net "CLK_50M_RMII_BMC_OCP")
	)
	(segment
		(start 183.085994 -13.048488)
		(end 183.085994 -14.1478)
		(width 0.11684)
		(layer "In6.Cu")
		(net "CLK_50M_RMII_BMC_OCP")
	)
	(segment
		(start 206.819246 -13.124434)
		(end 207.212946 -13.124434)
		(width 0.11684)
		(layer "In6.Cu")
		(net "CLK_50M_RMII_BMC_OCP")
	)
	(segment
		(start 182.458614 -13.768832)
		(end 182.458614 -13.048488)
		(width 0.11684)
		(layer "In6.Cu")
		(net "CLK_50M_RMII_BMC_OCP")
	)
	(segment
		(start 199.888602 -16.845788)
		(end 199.888602 -17.75587)
		(width 0.11684)
		(layer "In6.Cu")
		(net "CLK_50M_RMII_BMC_OCP")
	)
	(segment
		(start 178.694334 -13.048488)
		(end 178.811174 -12.931648)
		(width 0.11684)
		(layer "In6.Cu")
		(net "CLK_50M_RMII_BMC_OCP")
	)
	(segment
		(start 212.936836 -21.197824)
		(end 213.330536 -21.197824)
		(width 0.11684)
		(layer "In6.Cu")
		(net "CLK_50M_RMII_BMC_OCP")
	)
	(segment
		(start 194.782186 -14.894052)
		(end 194.899026 -15.010892)
		(width 0.11684)
		(layer "In6.Cu")
		(net "CLK_50M_RMII_BMC_OCP")
	)
	(segment
		(start 198.517002 -16.728948)
		(end 198.633842 -16.845788)
		(width 0.11684)
		(layer "In6.Cu")
		(net "CLK_50M_RMII_BMC_OCP")
	)
	(segment
		(start 213.447376 -21.080984)
		(end 213.447376 -19.816064)
		(width 0.11684)
		(layer "In6.Cu")
		(net "CLK_50M_RMII_BMC_OCP")
	)
	(segment
		(start 201.055986 -13.241274)
		(end 201.055986 -14.894052)
		(width 0.11684)
		(layer "In6.Cu")
		(net "CLK_50M_RMII_BMC_OCP")
	)
	(segment
		(start 199.918066 -15.010892)
		(end 200.311766 -15.010892)
		(width 0.11684)
		(layer "In6.Cu")
		(net "CLK_50M_RMII_BMC_OCP")
	)
	(segment
		(start 214.585296 -21.661374)
		(end 214.702136 -21.544534)
		(width 0.11684)
		(layer "In6.Cu")
		(net "CLK_50M_RMII_BMC_OCP")
	)
	(segment
		(start 196.634862 -19.993864)
		(end 196.751702 -19.877024)
		(width 0.11684)
		(layer "In6.Cu")
		(net "CLK_50M_RMII_BMC_OCP")
	)
	(segment
		(start 173.558454 -14.154658)
		(end 173.675294 -14.037818)
		(width 0.11684)
		(layer "In6.Cu")
		(net "CLK_50M_RMII_BMC_OCP")
	)
	(segment
		(start 211.054696 -19.699224)
		(end 211.448396 -19.699224)
		(width 0.11684)
		(layer "In6.Cu")
		(net "CLK_50M_RMII_BMC_OCP")
	)
	(segment
		(start 173.675294 -14.037818)
		(end 173.675294 -12.677648)
		(width 0.11684)
		(layer "In6.Cu")
		(net "CLK_50M_RMII_BMC_OCP")
	)
	(segment
		(start 200.311766 -15.010892)
		(end 200.428606 -14.894052)
		(width 0.11684)
		(layer "In6.Cu")
		(net "CLK_50M_RMII_BMC_OCP")
	)
	(segment
		(start 216.467436 -19.699224)
		(end 216.584276 -19.816064)
		(width 0.11684)
		(layer "In6.Cu")
		(net "CLK_50M_RMII_BMC_OCP")
	)
	(segment
		(start 203.565506 -13.241274)
		(end 203.565506 -14.894052)
		(width 0.11684)
		(layer "In6.Cu")
		(net "CLK_50M_RMII_BMC_OCP")
	)
	(segment
		(start 186.539632 -12.931648)
		(end 186.9821 -12.48918)
		(width 0.11684)
		(layer "In6.Cu")
		(net "CLK_50M_RMII_BMC_OCP")
	)
	(segment
		(start 200.005442 -17.87271)
		(end 200.399142 -17.87271)
		(width 0.11684)
		(layer "In6.Cu")
		(net "CLK_50M_RMII_BMC_OCP")
	)
	(segment
		(start 195.1228 -16.728948)
		(end 196.007482 -16.728948)
		(width 0.11684)
		(layer "In6.Cu")
		(net "CLK_50M_RMII_BMC_OCP")
	)
	(segment
		(start 199.173846 -13.241274)
		(end 199.290686 -13.124434)
		(width 0.11684)
		(layer "In6.Cu")
		(net "CLK_50M_RMII_BMC_OCP")
	)
	(segment
		(start 182.341774 -13.885672)
		(end 182.458614 -13.768832)
		(width 0.11684)
		(layer "In6.Cu")
		(net "CLK_50M_RMII_BMC_OCP")
	)
	(segment
		(start 215.329516 -19.816064)
		(end 215.329516 -21.444458)
		(width 0.11684)
		(layer "In6.Cu")
		(net "CLK_50M_RMII_BMC_OCP")
	)
	(segment
		(start 212.495638 -18.100802)
		(end 217.609674 -18.100802)
		(width 0.11684)
		(layer "In6.Cu")
		(net "CLK_50M_RMII_BMC_OCP")
	)
	(segment
		(start 174.930054 -14.065504)
		(end 174.930054 -13.048488)
		(width 0.11684)
		(layer "In6.Cu")
		(net "CLK_50M_RMII_BMC_OCP")
	)
	(segment
		(start 199.144382 -19.059652)
		(end 199.261222 -18.942812)
		(width 0.11684)
		(layer "In6.Cu")
		(net "CLK_50M_RMII_BMC_OCP")
	)
	(segment
		(start 196.547486 -15.010892)
		(end 196.664326 -14.894052)
		(width 0.11684)
		(layer "In6.Cu")
		(net "CLK_50M_RMII_BMC_OCP")
	)
	(segment
		(start 173.675294 -12.677648)
		(end 173.792134 -12.560808)
		(width 0.11684)
		(layer "In6.Cu")
		(net "CLK_50M_RMII_BMC_OCP")
	)
	(segment
		(start 199.378062 -16.728948)
		(end 199.771762 -16.728948)
		(width 0.11684)
		(layer "In6.Cu")
		(net "CLK_50M_RMII_BMC_OCP")
	)
	(segment
		(start 201.566526 -15.010892)
		(end 201.683366 -14.894052)
		(width 0.11684)
		(layer "In6.Cu")
		(net "CLK_50M_RMII_BMC_OCP")
	)
	(segment
		(start 207.862932 -16.845788)
		(end 207.979772 -16.728948)
		(width 0.11684)
		(layer "In6.Cu")
		(net "CLK_50M_RMII_BMC_OCP")
	)
	(segment
		(start 188.867288 -14.043914)
		(end 189.145926 -13.765276)
		(width 0.11684)
		(layer "In6.Cu")
		(net "CLK_50M_RMII_BMC_OCP")
	)
	(segment
		(start 206.075026 -13.241274)
		(end 206.075026 -14.894052)
		(width 0.11684)
		(layer "In6.Cu")
		(net "CLK_50M_RMII_BMC_OCP")
	)
	(segment
		(start 180.693314 -13.788644)
		(end 181.087014 -13.788644)
		(width 0.11684)
		(layer "In6.Cu")
		(net "CLK_50M_RMII_BMC_OCP")
	)
	(segment
		(start 186.222894 -13.048488)
		(end 186.339734 -12.931648)
		(width 0.11684)
		(layer "In6.Cu")
		(net "CLK_50M_RMII_BMC_OCP")
	)
	(segment
		(start 198.546466 -13.241274)
		(end 198.546466 -14.894052)
		(width 0.11684)
		(layer "In6.Cu")
		(net "CLK_50M_RMII_BMC_OCP")
	)
	(segment
		(start 196.153786 -15.010892)
		(end 196.547486 -15.010892)
		(width 0.11684)
		(layer "In6.Cu")
		(net "CLK_50M_RMII_BMC_OCP")
	)
	(segment
		(start 210.937856 -19.816064)
		(end 211.054696 -19.699224)
		(width 0.11684)
		(layer "In6.Cu")
		(net "CLK_50M_RMII_BMC_OCP")
	)
	(segment
		(start 190.44158 -10.226548)
		(end 192.975992 -10.226548)
		(width 0.11684)
		(layer "In6.Cu")
		(net "CLK_50M_RMII_BMC_OCP")
	)
	(segment
		(start 209.172556 -19.071844)
		(end 209.055716 -19.188684)
		(width 0.11684)
		(layer "In6.Cu")
		(net "CLK_50M_RMII_BMC_OCP")
	)
	(segment
		(start 194.9958 -15.726918)
		(end 194.9958 -16.601948)
		(width 0.11684)
		(layer "In6.Cu")
		(net "CLK_50M_RMII_BMC_OCP")
	)
	(segment
		(start 203.565506 -14.894052)
		(end 203.682346 -15.010892)
		(width 0.11684)
		(layer "In6.Cu")
		(net "CLK_50M_RMII_BMC_OCP")
	)
	(segment
		(start 179.949094 -15.498572)
		(end 179.949094 -13.048488)
		(width 0.11684)
		(layer "In6.Cu")
		(net "CLK_50M_RMII_BMC_OCP")
	)
	(segment
		(start 210.310476 -24.331168)
		(end 210.427316 -24.448008)
		(width 0.11684)
		(layer "In6.Cu")
		(net "CLK_50M_RMII_BMC_OCP")
	)
	(segment
		(start 199.801226 -13.241274)
		(end 199.801226 -14.894052)
		(width 0.11684)
		(layer "In6.Cu")
		(net "CLK_50M_RMII_BMC_OCP")
	)
	(segment
		(start 196.241162 -19.993864)
		(end 196.634862 -19.993864)
		(width 0.11684)
		(layer "In6.Cu")
		(net "CLK_50M_RMII_BMC_OCP")
	)
	(segment
		(start 198.006462 -16.845788)
		(end 198.123302 -16.728948)
		(width 0.11684)
		(layer "In6.Cu")
		(net "CLK_50M_RMII_BMC_OCP")
	)
	(segment
		(start 205.447646 -14.894052)
		(end 205.447646 -13.241274)
		(width 0.11684)
		(layer "In6.Cu")
		(net "CLK_50M_RMII_BMC_OCP")
	)
	(segment
		(start 177.556414 -12.931648)
		(end 177.950114 -12.931648)
		(width 0.11684)
		(layer "In6.Cu")
		(net "CLK_50M_RMII_BMC_OCP")
	)
	(segment
		(start 197.379082 -20.83308)
		(end 197.495922 -20.94992)
		(width 0.11684)
		(layer "In6.Cu")
		(net "CLK_50M_RMII_BMC_OCP")
	)
	(segment
		(start 198.006462 -20.83308)
		(end 198.006462 -16.845788)
		(width 0.11684)
		(layer "In6.Cu")
		(net "CLK_50M_RMII_BMC_OCP")
	)
	(segment
		(start 202.821286 -15.010892)
		(end 202.938126 -14.894052)
		(width 0.11684)
		(layer "In6.Cu")
		(net "CLK_50M_RMII_BMC_OCP")
	)
	(segment
		(start 200.515982 -16.845788)
		(end 200.632822 -16.728948)
		(width 0.11684)
		(layer "In6.Cu")
		(net "CLK_50M_RMII_BMC_OCP")
	)
	(segment
		(start 204.192886 -13.241274)
		(end 204.309726 -13.124434)
		(width 0.11684)
		(layer "In6.Cu")
		(net "CLK_50M_RMII_BMC_OCP")
	)
	(segment
		(start 192.975992 -10.226548)
		(end 193.68516 -10.935716)
		(width 0.11684)
		(layer "In6.Cu")
		(net "CLK_50M_RMII_BMC_OCP")
	)
	(segment
		(start 207.979772 -16.728948)
		(end 211.123784 -16.728948)
		(width 0.11684)
		(layer "In6.Cu")
		(net "CLK_50M_RMII_BMC_OCP")
	)
	(segment
		(start 175.557434 -14.883638)
		(end 175.674274 -15.000478)
		(width 0.11684)
		(layer "In6.Cu")
		(net "CLK_50M_RMII_BMC_OCP")
	)
	(segment
		(start 198.123302 -16.728948)
		(end 198.517002 -16.728948)
		(width 0.11684)
		(layer "In6.Cu")
		(net "CLK_50M_RMII_BMC_OCP")
	)
	(segment
		(start 198.663306 -15.010892)
		(end 199.057006 -15.010892)
		(width 0.11684)
		(layer "In6.Cu")
		(net "CLK_50M_RMII_BMC_OCP")
	)
	(segment
		(start 176.929034 -14.802358)
		(end 177.322734 -14.802358)
		(width 0.11684)
		(layer "In6.Cu")
		(net "CLK_50M_RMII_BMC_OCP")
	)
	(segment
		(start 204.192886 -14.894052)
		(end 204.192886 -13.241274)
		(width 0.11684)
		(layer "In6.Cu")
		(net "CLK_50M_RMII_BMC_OCP")
	)
	(segment
		(start 172.306234 -12.931648)
		(end 172.931074 -12.931648)
		(width 0.11684)
		(layer "In6.Cu")
		(net "CLK_50M_RMII_BMC_OCP")
	)
	(segment
		(start 212.819996 -21.080984)
		(end 212.936836 -21.197824)
		(width 0.11684)
		(layer "In6.Cu")
		(net "CLK_50M_RMII_BMC_OCP")
	)
	(segment
		(start 209.055716 -24.331168)
		(end 209.172556 -24.448008)
		(width 0.11684)
		(layer "In6.Cu")
		(net "CLK_50M_RMII_BMC_OCP")
	)
	(segment
		(start 207.235552 -16.845788)
		(end 207.235552 -17.866868)
		(width 0.11684)
		(layer "In6.Cu")
		(net "CLK_50M_RMII_BMC_OCP")
	)
	(segment
		(start 207.212946 -15.638272)
		(end 195.084446 -15.638272)
		(width 0.11684)
		(layer "In6.Cu")
		(net "CLK_50M_RMII_BMC_OCP")
	)
	(segment
		(start 181.203854 -13.671804)
		(end 181.203854 -13.048488)
		(width 0.11684)
		(layer "In6.Cu")
		(net "CLK_50M_RMII_BMC_OCP")
	)
	(segment
		(start 180.065934 -12.931648)
		(end 180.459634 -12.931648)
		(width 0.11684)
		(layer "In6.Cu")
		(net "CLK_50M_RMII_BMC_OCP")
	)
	(segment
		(start 182.969154 -12.931648)
		(end 183.085994 -13.048488)
		(width 0.11684)
		(layer "In6.Cu")
		(net "CLK_50M_RMII_BMC_OCP")
	)
	(segment
		(start 217.609674 -18.100802)
		(end 217.839036 -18.330164)
		(width 0.11684)
		(layer "In6.Cu")
		(net "CLK_50M_RMII_BMC_OCP")
	)
	(segment
		(start 199.261222 -16.845788)
		(end 199.378062 -16.728948)
		(width 0.11684)
		(layer "In6.Cu")
		(net "CLK_50M_RMII_BMC_OCP")
	)
	(segment
		(start 196.124322 -16.845788)
		(end 196.124322 -19.877024)
		(width 0.11684)
		(layer "In6.Cu")
		(net "CLK_50M_RMII_BMC_OCP")
	)
	(segment
		(start 199.771762 -16.728948)
		(end 199.888602 -16.845788)
		(width 0.11684)
		(layer "In6.Cu")
		(net "CLK_50M_RMII_BMC_OCP")
	)
	(segment
		(start 214.702136 -21.544534)
		(end 214.702136 -19.816064)
		(width 0.11684)
		(layer "In6.Cu")
		(net "CLK_50M_RMII_BMC_OCP")
	)
	(segment
		(start 183.202834 -14.26464)
		(end 183.596534 -14.26464)
		(width 0.11684)
		(layer "In6.Cu")
		(net "CLK_50M_RMII_BMC_OCP")
	)
	(segment
		(start 175.046894 -12.931648)
		(end 175.440594 -12.931648)
		(width 0.11684)
		(layer "In6.Cu")
		(net "CLK_50M_RMII_BMC_OCP")
	)
	(segment
		(start 197.802246 -15.010892)
		(end 197.919086 -14.894052)
		(width 0.11684)
		(layer "In6.Cu")
		(net "CLK_50M_RMII_BMC_OCP")
	)
	(segment
		(start 174.930054 -13.048488)
		(end 175.046894 -12.931648)
		(width 0.11684)
		(layer "In6.Cu")
		(net "CLK_50M_RMII_BMC_OCP")
	)
	(segment
		(start 189.79896 -10.869168)
		(end 190.44158 -10.226548)
		(width 0.11684)
		(layer "In6.Cu")
		(net "CLK_50M_RMII_BMC_OCP")
	)
	(segment
		(start 177.322734 -14.802358)
		(end 177.439574 -14.685518)
		(width 0.11684)
		(layer "In6.Cu")
		(net "CLK_50M_RMII_BMC_OCP")
	)
	(segment
		(start 210.498944 -17.473168)
		(end 210.382104 -17.356328)
		(width 0.11684)
		(layer "In6.Cu")
		(net "CLK_50M_RMII_BMC_OCP")
	)
	(segment
		(start 209.566256 -24.448008)
		(end 209.683096 -24.331168)
		(width 0.11684)
		(layer "In6.Cu")
		(net "CLK_50M_RMII_BMC_OCP")
	)
	(segment
		(start 175.557434 -13.048488)
		(end 175.557434 -14.883638)
		(width 0.11684)
		(layer "In6.Cu")
		(net "CLK_50M_RMII_BMC_OCP")
	)
	(segment
		(start 174.302674 -12.677648)
		(end 174.302674 -14.065504)
		(width 0.11684)
		(layer "In6.Cu")
		(net "CLK_50M_RMII_BMC_OCP")
	)
	(segment
		(start 181.714394 -12.931648)
		(end 181.831234 -13.048488)
		(width 0.11684)
		(layer "In6.Cu")
		(net "CLK_50M_RMII_BMC_OCP")
	)
	(segment
		(start 213.575646 -25.021794)
		(end 212.661754 -24.107902)
		(width 0.11684)
		(layer "In6.Cu")
		(net "CLK_50M_RMII_BMC_OCP")
	)
	(segment
		(start 215.446356 -21.561298)
		(end 215.840056 -21.561298)
		(width 0.11684)
		(layer "In6.Cu")
		(net "CLK_50M_RMII_BMC_OCP")
	)
	(segment
		(start 195.409566 -13.241274)
		(end 195.526406 -13.124434)
		(width 0.11684)
		(layer "In6.Cu")
		(net "CLK_50M_RMII_BMC_OCP")
	)
	(segment
		(start 188.701934 -14.043914)
		(end 188.867288 -14.043914)
		(width 0.11684)
		(layer "In6.Cu")
		(net "CLK_50M_RMII_BMC_OCP")
	)
	(segment
		(start 213.447376 -19.816064)
		(end 213.564216 -19.699224)
		(width 0.11684)
		(layer "In6.Cu")
		(net "CLK_50M_RMII_BMC_OCP")
	)
	(segment
		(start 217.722196 -19.071844)
		(end 209.172556 -19.071844)
		(width 0.11684)
		(layer "In6.Cu")
		(net "CLK_50M_RMII_BMC_OCP")
	)
	(segment
		(start 187.1472 -12.48918)
		(end 188.701934 -14.043914)
		(width 0.11684)
		(layer "In6.Cu")
		(net "CLK_50M_RMII_BMC_OCP")
	)
	(segment
		(start 202.427586 -15.010892)
		(end 202.821286 -15.010892)
		(width 0.11684)
		(layer "In6.Cu")
		(net "CLK_50M_RMII_BMC_OCP")
	)
	(segment
		(start 197.889622 -20.94992)
		(end 198.006462 -20.83308)
		(width 0.11684)
		(layer "In6.Cu")
		(net "CLK_50M_RMII_BMC_OCP")
	)
	(segment
		(start 182.458614 -13.048488)
		(end 182.575454 -12.931648)
		(width 0.11684)
		(layer "In6.Cu")
		(net "CLK_50M_RMII_BMC_OCP")
	)
	(segment
		(start 196.751702 -19.877024)
		(end 196.751702 -16.845788)
		(width 0.11684)
		(layer "In6.Cu")
		(net "CLK_50M_RMII_BMC_OCP")
	)
	(segment
		(start 210.382104 -17.983708)
		(end 210.498944 -17.866868)
		(width 0.11684)
		(layer "In6.Cu")
		(net "CLK_50M_RMII_BMC_OCP")
	)
	(segment
		(start 195.084446 -15.638272)
		(end 194.9958 -15.726918)
		(width 0.11684)
		(layer "In6.Cu")
		(net "CLK_50M_RMII_BMC_OCP")
	)
	(segment
		(start 210.498944 -17.866868)
		(end 210.498944 -17.473168)
		(width 0.11684)
		(layer "In6.Cu")
		(net "CLK_50M_RMII_BMC_OCP")
	)
	(segment
		(start 212.192616 -19.816064)
		(end 212.309456 -19.699224)
		(width 0.11684)
		(layer "In6.Cu")
		(net "CLK_50M_RMII_BMC_OCP")
	)
	(segment
		(start 183.713374 -13.048488)
		(end 183.830214 -12.931648)
		(width 0.11684)
		(layer "In6.Cu")
		(net "CLK_50M_RMII_BMC_OCP")
	)
	(segment
		(start 214.702136 -19.816064)
		(end 214.818976 -19.699224)
		(width 0.11684)
		(layer "In6.Cu")
		(net "CLK_50M_RMII_BMC_OCP")
	)
	(segment
		(start 179.949094 -13.048488)
		(end 180.065934 -12.931648)
		(width 0.11684)
		(layer "In6.Cu")
		(net "CLK_50M_RMII_BMC_OCP")
	)
	(segment
		(start 204.937106 -15.010892)
		(end 205.330806 -15.010892)
		(width 0.11684)
		(layer "In6.Cu")
		(net "CLK_50M_RMII_BMC_OCP")
	)
	(segment
		(start 207.352392 -17.983708)
		(end 210.382104 -17.983708)
		(width 0.11684)
		(layer "In6.Cu")
		(net "CLK_50M_RMII_BMC_OCP")
	)
	(segment
		(start 216.073736 -19.699224)
		(end 216.467436 -19.699224)
		(width 0.11684)
		(layer "In6.Cu")
		(net "CLK_50M_RMII_BMC_OCP")
	)
	(segment
		(start 207.329786 -15.521432)
		(end 207.212946 -15.638272)
		(width 0.11684)
		(layer "In6.Cu")
		(net "CLK_50M_RMII_BMC_OCP")
	)
	(segment
		(start 181.831234 -13.048488)
		(end 181.831234 -13.768832)
		(width 0.11684)
		(layer "In6.Cu")
		(net "CLK_50M_RMII_BMC_OCP")
	)
	(segment
		(start 210.821016 -24.448008)
		(end 210.937856 -24.331168)
		(width 0.11684)
		(layer "In6.Cu")
		(net "CLK_50M_RMII_BMC_OCP")
	)
	(segment
		(start 178.183794 -15.619222)
		(end 178.577494 -15.619222)
		(width 0.11684)
		(layer "In6.Cu")
		(net "CLK_50M_RMII_BMC_OCP")
	)
	(segment
		(start 199.290686 -13.124434)
		(end 199.684386 -13.124434)
		(width 0.11684)
		(layer "In6.Cu")
		(net "CLK_50M_RMII_BMC_OCP")
	)
	(segment
		(start 203.448666 -13.124434)
		(end 203.565506 -13.241274)
		(width 0.11684)
		(layer "In6.Cu")
		(net "CLK_50M_RMII_BMC_OCP")
	)
	(segment
		(start 217.839036 -18.330164)
		(end 217.839036 -18.955004)
		(width 0.11684)
		(layer "In6.Cu")
		(net "CLK_50M_RMII_BMC_OCP")
	)
	(segment
		(start 198.633842 -18.942812)
		(end 198.750682 -19.059652)
		(width 0.11684)
		(layer "In6.Cu")
		(net "CLK_50M_RMII_BMC_OCP")
	)
	(segment
		(start 216.701116 -21.829014)
		(end 217.094816 -21.829014)
		(width 0.11684)
		(layer "In6.Cu")
		(net "CLK_50M_RMII_BMC_OCP")
	)
	(segment
		(start 197.408546 -15.010892)
		(end 197.802246 -15.010892)
		(width 0.11684)
		(layer "In6.Cu")
		(net "CLK_50M_RMII_BMC_OCP")
	)
	(segment
		(start 184.223914 -12.931648)
		(end 184.340754 -13.048488)
		(width 0.11684)
		(layer "In6.Cu")
		(net "CLK_50M_RMII_BMC_OCP")
	)
	(segment
		(start 185.084974 -12.931648)
		(end 185.478674 -12.931648)
		(width 0.11684)
		(layer "In6.Cu")
		(net "CLK_50M_RMII_BMC_OCP")
	)
	(segment
		(start 178.066954 -13.048488)
		(end 178.066954 -15.502382)
		(width 0.11684)
		(layer "In6.Cu")
		(net "CLK_50M_RMII_BMC_OCP")
	)
	(segment
		(start 186.106054 -14.132052)
		(end 186.222894 -14.015212)
		(width 0.11684)
		(layer "In6.Cu")
		(net "CLK_50M_RMII_BMC_OCP")
	)
	(segment
		(start 199.888602 -17.75587)
		(end 200.005442 -17.87271)
		(width 0.11684)
		(layer "In6.Cu")
		(net "CLK_50M_RMII_BMC_OCP")
	)
	(segment
		(start 212.703156 -19.699224)
		(end 212.819996 -19.816064)
		(width 0.11684)
		(layer "In6.Cu")
		(net "CLK_50M_RMII_BMC_OCP")
	)
	(segment
		(start 176.067974 -15.000478)
		(end 176.184814 -14.883638)
		(width 0.11684)
		(layer "In6.Cu")
		(net "CLK_50M_RMII_BMC_OCP")
	)
	(segment
		(start 217.328496 -19.699224)
		(end 217.722196 -19.699224)
		(width 0.11684)
		(layer "In6.Cu")
		(net "CLK_50M_RMII_BMC_OCP")
	)
	(segment
		(start 207.329786 -13.241274)
		(end 207.329786 -15.521432)
		(width 0.11684)
		(layer "In6.Cu")
		(net "CLK_50M_RMII_BMC_OCP")
	)
	(segment
		(start 201.055986 -14.894052)
		(end 201.172826 -15.010892)
		(width 0.11684)
		(layer "In6.Cu")
		(net "CLK_50M_RMII_BMC_OCP")
	)
	(segment
		(start 212.661754 -24.107902)
		(end 212.661754 -23.678134)
		(width 0.11684)
		(layer "In6.Cu")
		(net "CLK_50M_RMII_BMC_OCP")
	)
	(segment
		(start 211.448396 -19.699224)
		(end 211.565236 -19.816064)
		(width 0.11684)
		(layer "In6.Cu")
		(net "CLK_50M_RMII_BMC_OCP")
	)
	(segment
		(start 185.478674 -12.931648)
		(end 185.595514 -13.048488)
		(width 0.11684)
		(layer "In6.Cu")
		(net "CLK_50M_RMII_BMC_OCP")
	)
	(segment
		(start 214.074756 -21.544534)
		(end 214.191596 -21.661374)
		(width 0.11684)
		(layer "In6.Cu")
		(net "CLK_50M_RMII_BMC_OCP")
	)
	(segment
		(start 211.123784 -16.728948)
		(end 212.495638 -18.100802)
		(width 0.11684)
		(layer "In6.Cu")
		(net "CLK_50M_RMII_BMC_OCP")
	)
	(segment
		(start 202.938126 -13.241274)
		(end 203.054966 -13.124434)
		(width 0.11684)
		(layer "In6.Cu")
		(net "CLK_50M_RMII_BMC_OCP")
	)
	(segment
		(start 184.340754 -14.046708)
		(end 184.457594 -14.163548)
		(width 0.11684)
		(layer "In6.Cu")
		(net "CLK_50M_RMII_BMC_OCP")
	)
	(segment
		(start 184.340754 -13.048488)
		(end 184.340754 -14.046708)
		(width 0.11684)
		(layer "In6.Cu")
		(net "CLK_50M_RMII_BMC_OCP")
	)
	(segment
		(start 196.751702 -16.845788)
		(end 196.868542 -16.728948)
		(width 0.11684)
		(layer "In6.Cu")
		(net "CLK_50M_RMII_BMC_OCP")
	)
	(segment
		(start 177.950114 -12.931648)
		(end 178.066954 -13.048488)
		(width 0.11684)
		(layer "In6.Cu")
		(net "CLK_50M_RMII_BMC_OCP")
	)
	(segment
		(start 215.840056 -21.561298)
		(end 215.956896 -21.444458)
		(width 0.11684)
		(layer "In6.Cu")
		(net "CLK_50M_RMII_BMC_OCP")
	)
	(segment
		(start 213.957916 -19.699224)
		(end 214.074756 -19.816064)
		(width 0.11684)
		(layer "In6.Cu")
		(net "CLK_50M_RMII_BMC_OCP")
	)
	(segment
		(start 184.968134 -13.048488)
		(end 185.084974 -12.931648)
		(width 0.11684)
		(layer "In6.Cu")
		(net "CLK_50M_RMII_BMC_OCP")
	)
	(segment
		(start 217.722196 -19.699224)
		(end 217.839036 -19.816064)
		(width 0.11684)
		(layer "In6.Cu")
		(net "CLK_50M_RMII_BMC_OCP")
	)
	(segment
		(start 179.204874 -12.931648)
		(end 179.321714 -13.048488)
		(width 0.11684)
		(layer "In6.Cu")
		(net "CLK_50M_RMII_BMC_OCP")
	)
	(segment
		(start 197.291706 -14.894052)
		(end 197.408546 -15.010892)
		(width 0.11684)
		(layer "In6.Cu")
		(net "CLK_50M_RMII_BMC_OCP")
	)
	(segment
		(start 176.695354 -12.931648)
		(end 176.812194 -13.048488)
		(width 0.11684)
		(layer "In6.Cu")
		(net "CLK_50M_RMII_BMC_OCP")
	)
	(segment
		(start 207.862932 -17.239488)
		(end 207.862932 -16.845788)
		(width 0.11684)
		(layer "In6.Cu")
		(net "CLK_50M_RMII_BMC_OCP")
	)
	(segment
		(start 174.419514 -14.182344)
		(end 174.813214 -14.182344)
		(width 0.11684)
		(layer "In6.Cu")
		(net "CLK_50M_RMII_BMC_OCP")
	)
	(segment
		(start 216.584276 -19.816064)
		(end 216.584276 -21.712174)
		(width 0.11684)
		(layer "In6.Cu")
		(net "CLK_50M_RMII_BMC_OCP")
	)
	(segment
		(start 215.212676 -19.699224)
		(end 215.329516 -19.816064)
		(width 0.11684)
		(layer "In6.Cu")
		(net "CLK_50M_RMII_BMC_OCP")
	)
	(segment
		(start 211.565236 -19.816064)
		(end 211.565236 -22.754082)
		(width 0.11684)
		(layer "In6.Cu")
		(net "CLK_50M_RMII_BMC_OCP")
	)
	(segment
		(start 217.839036 -23.396448)
		(end 216.21369 -25.021794)
		(width 0.11684)
		(layer "In6.Cu")
		(net "CLK_50M_RMII_BMC_OCP")
	)
	(segment
		(start 217.839036 -18.955004)
		(end 217.722196 -19.071844)
		(width 0.11684)
		(layer "In6.Cu")
		(net "CLK_50M_RMII_BMC_OCP")
	)
	(segment
		(start 189.145926 -13.600176)
		(end 187.590938 -12.045188)
		(width 0.11684)
		(layer "In6.Cu")
		(net "CLK_50M_RMII_BMC_OCP")
	)
	(segment
		(start 173.792134 -12.560808)
		(end 174.185834 -12.560808)
		(width 0.11684)
		(layer "In6.Cu")
		(net "CLK_50M_RMII_BMC_OCP")
	)
	(segment
		(start 197.919086 -14.894052)
		(end 197.919086 -13.241274)
		(width 0.11684)
		(layer "In6.Cu")
		(net "CLK_50M_RMII_BMC_OCP")
	)
	(segment
		(start 206.585566 -15.010892)
		(end 206.702406 -14.894052)
		(width 0.11684)
		(layer "In6.Cu")
		(net "CLK_50M_RMII_BMC_OCP")
	)
	(segment
		(start 204.076046 -15.010892)
		(end 204.192886 -14.894052)
		(width 0.11684)
		(layer "In6.Cu")
		(net "CLK_50M_RMII_BMC_OCP")
	)
	(segment
		(start 197.291706 -13.241274)
		(end 197.291706 -14.894052)
		(width 0.11684)
		(layer "In6.Cu")
		(net "CLK_50M_RMII_BMC_OCP")
	)
	(segment
		(start 179.832254 -15.615412)
		(end 179.949094 -15.498572)
		(width 0.11684)
		(layer "In6.Cu")
		(net "CLK_50M_RMII_BMC_OCP")
	)
	(segment
		(start 207.212946 -13.124434)
		(end 207.329786 -13.241274)
		(width 0.11684)
		(layer "In6.Cu")
		(net "CLK_50M_RMII_BMC_OCP")
	)
	(segment
		(start 185.595514 -14.015212)
		(end 185.712354 -14.132052)
		(width 0.11684)
		(layer "In6.Cu")
		(net "CLK_50M_RMII_BMC_OCP")
	)
	(segment
		(start 214.191596 -21.661374)
		(end 214.585296 -21.661374)
		(width 0.11684)
		(layer "In6.Cu")
		(net "CLK_50M_RMII_BMC_OCP")
	)
	(segment
		(start 197.262242 -16.728948)
		(end 197.379082 -16.845788)
		(width 0.11684)
		(layer "In6.Cu")
		(net "CLK_50M_RMII_BMC_OCP")
	)
	(segment
		(start 215.329516 -21.444458)
		(end 215.446356 -21.561298)
		(width 0.11684)
		(layer "In6.Cu")
		(net "CLK_50M_RMII_BMC_OCP")
	)
	(segment
		(start 217.839036 -19.816064)
		(end 217.839036 -23.396448)
		(width 0.11684)
		(layer "In6.Cu")
		(net "CLK_50M_RMII_BMC_OCP")
	)
	(segment
		(start 205.330806 -15.010892)
		(end 205.447646 -14.894052)
		(width 0.11684)
		(layer "In6.Cu")
		(net "CLK_50M_RMII_BMC_OCP")
	)
	(segment
		(start 201.800206 -13.124434)
		(end 202.193906 -13.124434)
		(width 0.11684)
		(layer "In6.Cu")
		(net "CLK_50M_RMII_BMC_OCP")
	)
	(segment
		(start 200.399142 -17.87271)
		(end 200.515982 -17.75587)
		(width 0.11684)
		(layer "In6.Cu")
		(net "CLK_50M_RMII_BMC_OCP")
	)
	(segment
		(start 202.193906 -13.124434)
		(end 202.310746 -13.241274)
		(width 0.11684)
		(layer "In6.Cu")
		(net "CLK_50M_RMII_BMC_OCP")
	)
	(segment
		(start 212.309456 -19.699224)
		(end 212.703156 -19.699224)
		(width 0.11684)
		(layer "In6.Cu")
		(net "CLK_50M_RMII_BMC_OCP")
	)
	(segment
		(start 198.035926 -13.124434)
		(end 198.429626 -13.124434)
		(width 0.11684)
		(layer "In6.Cu")
		(net "CLK_50M_RMII_BMC_OCP")
	)
	(segment
		(start 202.938126 -14.894052)
		(end 202.938126 -13.241274)
		(width 0.11684)
		(layer "In6.Cu")
		(net "CLK_50M_RMII_BMC_OCP")
	)
	(segment
		(start 184.457594 -14.163548)
		(end 184.851294 -14.163548)
		(width 0.11684)
		(layer "In6.Cu")
		(net "CLK_50M_RMII_BMC_OCP")
	)
	(segment
		(start 197.495922 -20.94992)
		(end 197.889622 -20.94992)
		(width 0.11684)
		(layer "In6.Cu")
		(net "CLK_50M_RMII_BMC_OCP")
	)
	(segment
		(start 184.968134 -14.046708)
		(end 184.968134 -13.048488)
		(width 0.11684)
		(layer "In6.Cu")
		(net "CLK_50M_RMII_BMC_OCP")
	)
	(segment
		(start 198.633842 -16.845788)
		(end 198.633842 -18.942812)
		(width 0.11684)
		(layer "In6.Cu")
		(net "CLK_50M_RMII_BMC_OCP")
	)
	(segment
		(start 206.191866 -15.010892)
		(end 206.585566 -15.010892)
		(width 0.11684)
		(layer "In6.Cu")
		(net "CLK_50M_RMII_BMC_OCP")
	)
	(segment
		(start 180.576474 -13.048488)
		(end 180.576474 -13.671804)
		(width 0.11684)
		(layer "In6.Cu")
		(net "CLK_50M_RMII_BMC_OCP")
	)
	(segment
		(start 183.713374 -14.1478)
		(end 183.713374 -13.048488)
		(width 0.11684)
		(layer "In6.Cu")
		(net "CLK_50M_RMII_BMC_OCP")
	)
	(segment
		(start 200.545446 -13.124434)
		(end 200.939146 -13.124434)
		(width 0.11684)
		(layer "In6.Cu")
		(net "CLK_50M_RMII_BMC_OCP")
	)
	(segment
		(start 199.684386 -13.124434)
		(end 199.801226 -13.241274)
		(width 0.11684)
		(layer "In6.Cu")
		(net "CLK_50M_RMII_BMC_OCP")
	)
	(segment
		(start 170.840654 -14.835378)
		(end 170.840654 -18.09877)
		(width 0.11684)
		(layer "In11.Cu")
		(net "CLK_50M_RMII_BMC_OCP")
	)
	(segment
		(start 172.839634 -16.424148)
		(end 172.722794 -16.307308)
		(width 0.11684)
		(layer "In11.Cu")
		(net "CLK_50M_RMII_BMC_OCP")
	)
	(segment
		(start 173.977554 -15.577058)
		(end 173.860714 -15.460218)
		(width 0.11684)
		(layer "In11.Cu")
		(net "CLK_50M_RMII_BMC_OCP")
	)
	(segment
		(start 173.350174 -15.577058)
		(end 173.350174 -16.307308)
		(width 0.11684)
		(layer "In11.Cu")
		(net "CLK_50M_RMII_BMC_OCP")
	)
	(segment
		(start 173.233334 -16.424148)
		(end 172.839634 -16.424148)
		(width 0.11684)
		(layer "In11.Cu")
		(net "CLK_50M_RMII_BMC_OCP")
	)
	(segment
		(start 171.468034 -17.168368)
		(end 171.584874 -17.051528)
		(width 0.11684)
		(layer "In11.Cu")
		(net "CLK_50M_RMII_BMC_OCP")
	)
	(segment
		(start 173.860714 -15.460218)
		(end 173.467014 -15.460218)
		(width 0.11684)
		(layer "In11.Cu")
		(net "CLK_50M_RMII_BMC_OCP")
	)
	(segment
		(start 175.115474 -17.051528)
		(end 175.232314 -16.934688)
		(width 0.11684)
		(layer "In11.Cu")
		(net "CLK_50M_RMII_BMC_OCP")
	)
	(segment
		(start 174.721774 -15.460218)
		(end 174.604934 -15.577058)
		(width 0.11684)
		(layer "In11.Cu")
		(net "CLK_50M_RMII_BMC_OCP")
	)
	(segment
		(start 172.605954 -15.460218)
		(end 172.212254 -15.460218)
		(width 0.11684)
		(layer "In11.Cu")
		(net "CLK_50M_RMII_BMC_OCP")
	)
	(segment
		(start 173.977554 -16.307308)
		(end 173.977554 -15.577058)
		(width 0.11684)
		(layer "In11.Cu")
		(net "CLK_50M_RMII_BMC_OCP")
	)
	(segment
		(start 175.232314 -16.934688)
		(end 175.232314 -15.577058)
		(width 0.11684)
		(layer "In11.Cu")
		(net "CLK_50M_RMII_BMC_OCP")
	)
	(segment
		(start 174.488094 -16.424148)
		(end 174.094394 -16.424148)
		(width 0.11684)
		(layer "In11.Cu")
		(net "CLK_50M_RMII_BMC_OCP")
	)
	(segment
		(start 172.095414 -15.577058)
		(end 172.095414 -16.307308)
		(width 0.11684)
		(layer "In11.Cu")
		(net "CLK_50M_RMII_BMC_OCP")
	)
	(segment
		(start 171.584874 -17.051528)
		(end 175.115474 -17.051528)
		(width 0.11684)
		(layer "In11.Cu")
		(net "CLK_50M_RMII_BMC_OCP")
	)
	(segment
		(start 172.212254 -15.460218)
		(end 172.095414 -15.577058)
		(width 0.11684)
		(layer "In11.Cu")
		(net "CLK_50M_RMII_BMC_OCP")
	)
	(segment
		(start 172.722794 -16.307308)
		(end 172.722794 -15.577058)
		(width 0.11684)
		(layer "In11.Cu")
		(net "CLK_50M_RMII_BMC_OCP")
	)
	(segment
		(start 170.098974 -14.718538)
		(end 170.723814 -14.718538)
		(width 0.11684)
		(layer "In11.Cu")
		(net "CLK_50M_RMII_BMC_OCP")
	)
	(segment
		(start 171.468034 -16.307308)
		(end 171.468034 -14.835378)
		(width 0.11684)
		(layer "In11.Cu")
		(net "CLK_50M_RMII_BMC_OCP")
	)
	(segment
		(start 174.604934 -16.307308)
		(end 174.488094 -16.424148)
		(width 0.11684)
		(layer "In11.Cu")
		(net "CLK_50M_RMII_BMC_OCP")
	)
	(segment
		(start 175.115474 -15.460218)
		(end 174.721774 -15.460218)
		(width 0.11684)
		(layer "In11.Cu")
		(net "CLK_50M_RMII_BMC_OCP")
	)
	(segment
		(start 170.957494 -18.21561)
		(end 171.351194 -18.21561)
		(width 0.11684)
		(layer "In11.Cu")
		(net "CLK_50M_RMII_BMC_OCP")
	)
	(segment
		(start 168.666668 -16.150844)
		(end 170.098974 -14.718538)
		(width 0.11684)
		(layer "In11.Cu")
		(net "CLK_50M_RMII_BMC_OCP")
	)
	(segment
		(start 174.094394 -16.424148)
		(end 173.977554 -16.307308)
		(width 0.11684)
		(layer "In11.Cu")
		(net "CLK_50M_RMII_BMC_OCP")
	)
	(segment
		(start 170.840654 -18.09877)
		(end 170.957494 -18.21561)
		(width 0.11684)
		(layer "In11.Cu")
		(net "CLK_50M_RMII_BMC_OCP")
	)
	(segment
		(start 172.722794 -15.577058)
		(end 172.605954 -15.460218)
		(width 0.11684)
		(layer "In11.Cu")
		(net "CLK_50M_RMII_BMC_OCP")
	)
	(segment
		(start 171.978574 -16.424148)
		(end 171.584874 -16.424148)
		(width 0.11684)
		(layer "In11.Cu")
		(net "CLK_50M_RMII_BMC_OCP")
	)
	(segment
		(start 171.584874 -16.424148)
		(end 171.468034 -16.307308)
		(width 0.11684)
		(layer "In11.Cu")
		(net "CLK_50M_RMII_BMC_OCP")
	)
	(segment
		(start 171.584874 -14.718538)
		(end 172.03547 -14.718538)
		(width 0.11684)
		(layer "In11.Cu")
		(net "CLK_50M_RMII_BMC_OCP")
	)
	(segment
		(start 171.468034 -14.835378)
		(end 171.584874 -14.718538)
		(width 0.11684)
		(layer "In11.Cu")
		(net "CLK_50M_RMII_BMC_OCP")
	)
	(segment
		(start 172.095414 -16.307308)
		(end 171.978574 -16.424148)
		(width 0.11684)
		(layer "In11.Cu")
		(net "CLK_50M_RMII_BMC_OCP")
	)
	(segment
		(start 175.232314 -15.577058)
		(end 175.115474 -15.460218)
		(width 0.11684)
		(layer "In11.Cu")
		(net "CLK_50M_RMII_BMC_OCP")
	)
	(segment
		(start 168.046654 -19.192748)
		(end 168.666668 -18.572734)
		(width 0.11684)
		(layer "In11.Cu")
		(net "CLK_50M_RMII_BMC_OCP")
	)
	(segment
		(start 171.351194 -18.21561)
		(end 171.468034 -18.09877)
		(width 0.11684)
		(layer "In11.Cu")
		(net "CLK_50M_RMII_BMC_OCP")
	)
	(segment
		(start 173.350174 -16.307308)
		(end 173.233334 -16.424148)
		(width 0.11684)
		(layer "In11.Cu")
		(net "CLK_50M_RMII_BMC_OCP")
	)
	(segment
		(start 174.604934 -15.577058)
		(end 174.604934 -16.307308)
		(width 0.11684)
		(layer "In11.Cu")
		(net "CLK_50M_RMII_BMC_OCP")
	)
	(segment
		(start 173.467014 -15.460218)
		(end 173.350174 -15.577058)
		(width 0.11684)
		(layer "In11.Cu")
		(net "CLK_50M_RMII_BMC_OCP")
	)
	(segment
		(start 171.468034 -18.09877)
		(end 171.468034 -17.168368)
		(width 0.11684)
		(layer "In11.Cu")
		(net "CLK_50M_RMII_BMC_OCP")
	)
	(segment
		(start 168.666668 -18.572734)
		(end 168.666668 -16.150844)
		(width 0.11684)
		(layer "In11.Cu")
		(net "CLK_50M_RMII_BMC_OCP")
	)
	(segment
		(start 170.723814 -14.718538)
		(end 170.840654 -14.835378)
		(width 0.11684)
		(layer "In11.Cu")
		(net "CLK_50M_RMII_BMC_OCP")
	)
	(segment
		(start 215.624664 -26.911554)
		(end 214.824564 -26.111454)
		(width 0.10668)
		(layer "F.Cu")
		(net "CLK_50M_RMII")
	)
	(segment
		(start 215.620854 -23.704804)
		(end 215.904064 -23.704804)
		(width 0.10668)
		(layer "F.Cu")
		(net "CLK_50M_RMII")
	)
	(segment
		(start 215.258142 -24.067516)
		(end 215.620854 -23.704804)
		(width 0.10668)
		(layer "F.Cu")
		(net "CLK_50M_RMII")
	)
	(segment
		(start 214.824564 -26.111454)
		(end 214.824564 -24.501094)
		(width 0.10668)
		(layer "F.Cu")
		(net "CLK_50M_RMII")
	)
	(segment
		(start 214.824564 -24.501094)
		(end 215.258142 -24.067516)
		(width 0.10668)
		(layer "F.Cu")
		(net "CLK_50M_RMII")
	)
	(segment
		(start 215.922352 -26.911554)
		(end 215.624664 -26.911554)
		(width 0.10668)
		(layer "F.Cu")
		(net "CLK_50M_RMII")
	)
	(via
		(at 215.258142 -24.067516)
		(size 0.508)
		(drill 0.254)
		(layers "F.Cu" "B.Cu")
		(net "CLK_50M_RMII")
	)
	(segment
		(start 86.311994 -33.287208)
		(end 86.311994 -32.068008)
		(width 0.10668)
		(layer "F.Cu")
		(net "CLK_50M_NCSI_OCP_V3_2_ISO_R")
	)
	(segment
		(start 88.308942 -32.07131)
		(end 87.527892 -32.07131)
		(width 0.10668)
		(layer "F.Cu")
		(net "CLK_50M_NCSI_OCP_V3_2_ISO_R")
	)
	(segment
		(start 87.527892 -32.07131)
		(end 86.311994 -33.287208)
		(width 0.10668)
		(layer "F.Cu")
		(net "CLK_50M_NCSI_OCP_V3_2_ISO_R")
	)
	(via
		(at 86.311994 -33.287208)
		(size 0.762)
		(drill 0.381)
		(layers "F.Cu" "B.Cu")
		(net "CLK_50M_NCSI_OCP_V3_2_ISO_R")
	)
	(segment
		(start 70.261988 -8.320024)
		(end 70.261988 -7.638034)
		(width 0.10668)
		(layer "F.Cu")
		(net "CLK_50M_NCSI_OCP_V3_2_ISO")
	)
	(segment
		(start 86.311994 -30.77972)
		(end 86.470744 -30.62097)
		(width 0.10668)
		(layer "F.Cu")
		(net "CLK_50M_NCSI_OCP_V3_2_ISO")
	)
	(segment
		(start 86.311994 -31.267908)
		(end 86.311994 -30.77972)
		(width 0.10668)
		(layer "F.Cu")
		(net "CLK_50M_NCSI_OCP_V3_2_ISO")
	)
	(segment
		(start 70.261988 -7.638034)
		(end 69.879464 -7.25551)
		(width 0.10668)
		(layer "F.Cu")
		(net "CLK_50M_NCSI_OCP_V3_2_ISO")
	)
	(via
		(at 86.470744 -30.62097)
		(size 0.508)
		(drill 0.254)
		(layers "F.Cu" "B.Cu")
		(net "CLK_50M_NCSI_OCP_V3_2_ISO")
	)
	(via
		(at 69.879464 -7.25551)
		(size 0.508)
		(drill 0.254)
		(layers "F.Cu" "B.Cu")
		(net "CLK_50M_NCSI_OCP_V3_2_ISO")
	)
	(segment
		(start 85.78215 -17.306798)
		(end 85.78215 -29.932376)
		(width 0.11684)
		(layer "In4.Cu")
		(net "CLK_50M_NCSI_OCP_V3_2_ISO")
	)
	(segment
		(start 85.78215 -29.932376)
		(end 86.470744 -30.62097)
		(width 0.11684)
		(layer "In4.Cu")
		(net "CLK_50M_NCSI_OCP_V3_2_ISO")
	)
	(segment
		(start 79.725012 -11.24966)
		(end 85.78215 -17.306798)
		(width 0.11684)
		(layer "In4.Cu")
		(net "CLK_50M_NCSI_OCP_V3_2_ISO")
	)
	(segment
		(start 70.958202 -8.334248)
		(end 70.958202 -10.614914)
		(width 0.11684)
		(layer "In4.Cu")
		(net "CLK_50M_NCSI_OCP_V3_2_ISO")
	)
	(segment
		(start 70.958202 -10.614914)
		(end 71.592948 -11.24966)
		(width 0.11684)
		(layer "In4.Cu")
		(net "CLK_50M_NCSI_OCP_V3_2_ISO")
	)
	(segment
		(start 69.879464 -7.25551)
		(end 70.958202 -8.334248)
		(width 0.11684)
		(layer "In4.Cu")
		(net "CLK_50M_NCSI_OCP_V3_2_ISO")
	)
	(segment
		(start 71.592948 -11.24966)
		(end 79.725012 -11.24966)
		(width 0.11684)
		(layer "In4.Cu")
		(net "CLK_50M_NCSI_OCP_V3_2_ISO")
	)
	(segment
		(start 217.58402 -15.822422)
		(end 217.58402 -15.981172)
		(width 0.10668)
		(layer "F.Cu")
		(net "CLK_50M_NCSI_OCP_V3_2")
	)
	(segment
		(start 87.531194 -33.02127)
		(end 87.235284 -33.31718)
		(width 0.10668)
		(layer "F.Cu")
		(net "CLK_50M_NCSI_OCP_V3_2")
	)
	(segment
		(start 218.09202 -15.314422)
		(end 217.58402 -15.822422)
		(width 0.10668)
		(layer "F.Cu")
		(net "CLK_50M_NCSI_OCP_V3_2")
	)
	(segment
		(start 88.308942 -33.02127)
		(end 87.531194 -33.02127)
		(width 0.10668)
		(layer "F.Cu")
		(net "CLK_50M_NCSI_OCP_V3_2")
	)
	(via
		(at 218.09202 -15.314422)
		(size 0.508)
		(drill 0.254)
		(layers "F.Cu" "B.Cu")
		(net "CLK_50M_NCSI_OCP_V3_2")
	)
	(via
		(at 87.235284 -33.31718)
		(size 0.508)
		(drill 0.254)
		(layers "F.Cu" "B.Cu")
		(net "CLK_50M_NCSI_OCP_V3_2")
	)
	(segment
		(start 100.482908 -17.670526)
		(end 100.599748 -17.553686)
		(width 0.11684)
		(layer "In2.Cu")
		(net "CLK_50M_NCSI_OCP_V3_2")
	)
	(segment
		(start 100.599748 -17.553686)
		(end 100.599748 -15.002764)
		(width 0.11684)
		(layer "In2.Cu")
		(net "CLK_50M_NCSI_OCP_V3_2")
	)
	(segment
		(start 96.835468 -16.12265)
		(end 96.835468 -15.002764)
		(width 0.11684)
		(layer "In2.Cu")
		(net "CLK_50M_NCSI_OCP_V3_2")
	)
	(segment
		(start 87.04326 -27.253438)
		(end 87.1601 -27.136598)
		(width 0.11684)
		(layer "In2.Cu")
		(net "CLK_50M_NCSI_OCP_V3_2")
	)
	(segment
		(start 88.569038 -22.117558)
		(end 88.685878 -22.000718)
		(width 0.11684)
		(layer "In2.Cu")
		(net "CLK_50M_NCSI_OCP_V3_2")
	)
	(segment
		(start 104.874568 -14.885924)
		(end 104.991408 -15.002764)
		(width 0.11684)
		(layer "In2.Cu")
		(net "CLK_50M_NCSI_OCP_V3_2")
	)
	(segment
		(start 101.737668 -17.670526)
		(end 101.854508 -17.553686)
		(width 0.11684)
		(layer "In2.Cu")
		(net "CLK_50M_NCSI_OCP_V3_2")
	)
	(segment
		(start 87.1601 -27.763978)
		(end 87.04326 -27.647138)
		(width 0.11684)
		(layer "In2.Cu")
		(net "CLK_50M_NCSI_OCP_V3_2")
	)
	(segment
		(start 103.853488 -17.555972)
		(end 104.247188 -17.555972)
		(width 0.11684)
		(layer "In2.Cu")
		(net "CLK_50M_NCSI_OCP_V3_2")
	)
	(segment
		(start 88.569038 -29.018738)
		(end 87.1601 -29.018738)
		(width 0.11684)
		(layer "In2.Cu")
		(net "CLK_50M_NCSI_OCP_V3_2")
	)
	(segment
		(start 88.569038 -26.509218)
		(end 87.1601 -26.509218)
		(width 0.11684)
		(layer "In2.Cu")
		(net "CLK_50M_NCSI_OCP_V3_2")
	)
	(segment
		(start 105.108248 -16.23949)
		(end 105.501948 -16.23949)
		(width 0.11684)
		(layer "In2.Cu")
		(net "CLK_50M_NCSI_OCP_V3_2")
	)
	(segment
		(start 96.208088 -16.12265)
		(end 96.324928 -16.23949)
		(width 0.11684)
		(layer "In2.Cu")
		(net "CLK_50M_NCSI_OCP_V3_2")
	)
	(segment
		(start 120.282716 -13.20673)
		(end 120.399556 -13.32357)
		(width 0.11684)
		(layer "In2.Cu")
		(net "CLK_50M_NCSI_OCP_V3_2")
	)
	(segment
		(start 182.310532 -10.047732)
		(end 183.578246 -8.780018)
		(width 0.11684)
		(layer "In2.Cu")
		(net "CLK_50M_NCSI_OCP_V3_2")
	)
	(segment
		(start 88.685878 -28.274518)
		(end 88.685878 -27.880818)
		(width 0.11684)
		(layer "In2.Cu")
		(net "CLK_50M_NCSI_OCP_V3_2")
	)
	(segment
		(start 88.569038 -28.391358)
		(end 88.685878 -28.274518)
		(width 0.11684)
		(layer "In2.Cu")
		(net "CLK_50M_NCSI_OCP_V3_2")
	)
	(segment
		(start 87.04326 -25.998678)
		(end 87.1601 -25.881838)
		(width 0.11684)
		(layer "In2.Cu")
		(net "CLK_50M_NCSI_OCP_V3_2")
	)
	(segment
		(start 158.197296 -8.377428)
		(end 159.489394 -9.669526)
		(width 0.11684)
		(layer "In2.Cu")
		(net "CLK_50M_NCSI_OCP_V3_2")
	)
	(segment
		(start 117.701314 -13.134848)
		(end 117.890036 -13.32357)
		(width 0.11684)
		(layer "In2.Cu")
		(net "CLK_50M_NCSI_OCP_V3_2")
	)
	(segment
		(start 97.346008 -14.885924)
		(end 97.462848 -15.002764)
		(width 0.11684)
		(layer "In2.Cu")
		(net "CLK_50M_NCSI_OCP_V3_2")
	)
	(segment
		(start 144.412462 -7.384288)
		(end 144.412462 -9.361678)
		(width 0.11684)
		(layer "In2.Cu")
		(net "CLK_50M_NCSI_OCP_V3_2")
	)
	(segment
		(start 133.089142 -7.267448)
		(end 141.786102 -7.267448)
		(width 0.11684)
		(layer "In2.Cu")
		(net "CLK_50M_NCSI_OCP_V3_2")
	)
	(segment
		(start 106.246168 -16.12265)
		(end 106.363008 -16.23949)
		(width 0.11684)
		(layer "In2.Cu")
		(net "CLK_50M_NCSI_OCP_V3_2")
	)
	(segment
		(start 168.848278 -7.250176)
		(end 177.066194 -7.250176)
		(width 0.11684)
		(layer "In2.Cu")
		(net "CLK_50M_NCSI_OCP_V3_2")
	)
	(segment
		(start 101.227128 -17.553686)
		(end 101.343968 -17.670526)
		(width 0.11684)
		(layer "In2.Cu")
		(net "CLK_50M_NCSI_OCP_V3_2")
	)
	(segment
		(start 144.529302 -9.478518)
		(end 144.923002 -9.478518)
		(width 0.11684)
		(layer "In2.Cu")
		(net "CLK_50M_NCSI_OCP_V3_2")
	)
	(segment
		(start 87.1601 -23.999698)
		(end 87.04326 -23.882858)
		(width 0.11684)
		(layer "In2.Cu")
		(net "CLK_50M_NCSI_OCP_V3_2")
	)
	(segment
		(start 106.246168 -15.002764)
		(end 106.246168 -16.12265)
		(width 0.11684)
		(layer "In2.Cu")
		(net "CLK_50M_NCSI_OCP_V3_2")
	)
	(segment
		(start 212.108796 -13.800328)
		(end 212.225636 -13.917168)
		(width 0.11684)
		(layer "In2.Cu")
		(net "CLK_50M_NCSI_OCP_V3_2")
	)
	(segment
		(start 100.716588 -14.885924)
		(end 101.110288 -14.885924)
		(width 0.11684)
		(layer "In2.Cu")
		(net "CLK_50M_NCSI_OCP_V3_2")
	)
	(segment
		(start 97.462848 -15.002764)
		(end 97.462848 -16.15821)
		(width 0.11684)
		(layer "In2.Cu")
		(net "CLK_50M_NCSI_OCP_V3_2")
	)
	(segment
		(start 212.969856 -13.800328)
		(end 213.363556 -13.800328)
		(width 0.11684)
		(layer "In2.Cu")
		(net "CLK_50M_NCSI_OCP_V3_2")
	)
	(segment
		(start 88.685878 -20.344384)
		(end 94.144338 -14.885924)
		(width 0.11684)
		(layer "In2.Cu")
		(net "CLK_50M_NCSI_OCP_V3_2")
	)
	(segment
		(start 99.855528 -14.885924)
		(end 99.972368 -15.002764)
		(width 0.11684)
		(layer "In2.Cu")
		(net "CLK_50M_NCSI_OCP_V3_2")
	)
	(segment
		(start 210.343496 -14.950948)
		(end 210.343496 -13.917168)
		(width 0.11684)
		(layer "In2.Cu")
		(net "CLK_50M_NCSI_OCP_V3_2")
	)
	(segment
		(start 215.362536 -14.950948)
		(end 215.362536 -13.917168)
		(width 0.11684)
		(layer "In2.Cu")
		(net "CLK_50M_NCSI_OCP_V3_2")
	)
	(segment
		(start 214.851996 -15.067788)
		(end 215.245696 -15.067788)
		(width 0.11684)
		(layer "In2.Cu")
		(net "CLK_50M_NCSI_OCP_V3_2")
	)
	(segment
		(start 98.090228 -15.002764)
		(end 98.207068 -14.885924)
		(width 0.11684)
		(layer "In2.Cu")
		(net "CLK_50M_NCSI_OCP_V3_2")
	)
	(segment
		(start 104.247188 -17.555972)
		(end 104.364028 -17.439132)
		(width 0.11684)
		(layer "In2.Cu")
		(net "CLK_50M_NCSI_OCP_V3_2")
	)
	(segment
		(start 213.597236 -15.067788)
		(end 213.990936 -15.067788)
		(width 0.11684)
		(layer "In2.Cu")
		(net "CLK_50M_NCSI_OCP_V3_2")
	)
	(segment
		(start 143.157702 -7.384288)
		(end 143.157702 -9.361678)
		(width 0.11684)
		(layer "In2.Cu")
		(net "CLK_50M_NCSI_OCP_V3_2")
	)
	(segment
		(start 127.356616 -9.691624)
		(end 128.31572 -9.294114)
		(width 0.11684)
		(layer "In2.Cu")
		(net "CLK_50M_NCSI_OCP_V3_2")
	)
	(segment
		(start 118.634256 -13.20673)
		(end 119.027956 -13.20673)
		(width 0.11684)
		(layer "In2.Cu")
		(net "CLK_50M_NCSI_OCP_V3_2")
	)
	(segment
		(start 87.04326 -25.137618)
		(end 87.04326 -24.743918)
		(width 0.11684)
		(layer "In2.Cu")
		(net "CLK_50M_NCSI_OCP_V3_2")
	)
	(segment
		(start 96.718628 -16.23949)
		(end 96.835468 -16.12265)
		(width 0.11684)
		(layer "In2.Cu")
		(net "CLK_50M_NCSI_OCP_V3_2")
	)
	(segment
		(start 120.399556 -13.32357)
		(end 120.399556 -16.760444)
		(width 0.11684)
		(layer "In2.Cu")
		(net "CLK_50M_NCSI_OCP_V3_2")
	)
	(segment
		(start 121.026936 -13.32357)
		(end 121.143776 -13.20673)
		(width 0.11684)
		(layer "In2.Cu")
		(net "CLK_50M_NCSI_OCP_V3_2")
	)
	(segment
		(start 144.923002 -9.478518)
		(end 145.039842 -9.361678)
		(width 0.11684)
		(layer "In2.Cu")
		(net "CLK_50M_NCSI_OCP_V3_2")
	)
	(segment
		(start 88.569038 -29.646118)
		(end 88.685878 -29.529278)
		(width 0.11684)
		(layer "In2.Cu")
		(net "CLK_50M_NCSI_OCP_V3_2")
	)
	(segment
		(start 97.973388 -16.27505)
		(end 98.090228 -16.15821)
		(width 0.11684)
		(layer "In2.Cu")
		(net "CLK_50M_NCSI_OCP_V3_2")
	)
	(segment
		(start 100.599748 -15.002764)
		(end 100.716588 -14.885924)
		(width 0.11684)
		(layer "In2.Cu")
		(net "CLK_50M_NCSI_OCP_V3_2")
	)
	(segment
		(start 87.1601 -28.391358)
		(end 88.569038 -28.391358)
		(width 0.11684)
		(layer "In2.Cu")
		(net "CLK_50M_NCSI_OCP_V3_2")
	)
	(segment
		(start 213.480396 -14.950948)
		(end 213.597236 -15.067788)
		(width 0.11684)
		(layer "In2.Cu")
		(net "CLK_50M_NCSI_OCP_V3_2")
	)
	(segment
		(start 127.217424 -9.830816)
		(end 127.356616 -9.691624)
		(width 0.11684)
		(layer "In2.Cu")
		(net "CLK_50M_NCSI_OCP_V3_2")
	)
	(segment
		(start 212.736176 -15.067788)
		(end 212.853016 -14.950948)
		(width 0.11684)
		(layer "In2.Cu")
		(net "CLK_50M_NCSI_OCP_V3_2")
	)
	(segment
		(start 163.138612 -8.490712)
		(end 167.607742 -8.490712)
		(width 0.11684)
		(layer "In2.Cu")
		(net "CLK_50M_NCSI_OCP_V3_2")
	)
	(segment
		(start 102.598728 -17.661128)
		(end 102.992428 -17.661128)
		(width 0.11684)
		(layer "In2.Cu")
		(net "CLK_50M_NCSI_OCP_V3_2")
	)
	(segment
		(start 143.785082 -9.361678)
		(end 143.785082 -7.384288)
		(width 0.11684)
		(layer "In2.Cu")
		(net "CLK_50M_NCSI_OCP_V3_2")
	)
	(segment
		(start 106.756708 -16.23949)
		(end 106.873548 -16.12265)
		(width 0.11684)
		(layer "In2.Cu")
		(net "CLK_50M_NCSI_OCP_V3_2")
	)
	(segment
		(start 213.990936 -15.067788)
		(end 214.107776 -14.950948)
		(width 0.11684)
		(layer "In2.Cu")
		(net "CLK_50M_NCSI_OCP_V3_2")
	)
	(segment
		(start 119.655336 -16.877284)
		(end 119.772176 -16.760444)
		(width 0.11684)
		(layer "In2.Cu")
		(net "CLK_50M_NCSI_OCP_V3_2")
	)
	(segment
		(start 118.517416 -16.760444)
		(end 118.517416 -13.32357)
		(width 0.11684)
		(layer "In2.Cu")
		(net "CLK_50M_NCSI_OCP_V3_2")
	)
	(segment
		(start 105.735628 -14.885924)
		(end 106.129328 -14.885924)
		(width 0.11684)
		(layer "In2.Cu")
		(net "CLK_50M_NCSI_OCP_V3_2")
	)
	(segment
		(start 145.039842 -9.361678)
		(end 145.039842 -7.384288)
		(width 0.11684)
		(layer "In2.Cu")
		(net "CLK_50M_NCSI_OCP_V3_2")
	)
	(segment
		(start 98.207068 -14.885924)
		(end 98.600768 -14.885924)
		(width 0.11684)
		(layer "In2.Cu")
		(net "CLK_50M_NCSI_OCP_V3_2")
	)
	(segment
		(start 211.715096 -13.800328)
		(end 212.108796 -13.800328)
		(width 0.11684)
		(layer "In2.Cu")
		(net "CLK_50M_NCSI_OCP_V3_2")
	)
	(segment
		(start 98.600768 -14.885924)
		(end 98.717608 -15.002764)
		(width 0.11684)
		(layer "In2.Cu")
		(net "CLK_50M_NCSI_OCP_V3_2")
	)
	(segment
		(start 141.902942 -7.384288)
		(end 141.902942 -9.361678)
		(width 0.11684)
		(layer "In2.Cu")
		(net "CLK_50M_NCSI_OCP_V3_2")
	)
	(segment
		(start 98.717608 -16.483076)
		(end 98.834448 -16.599916)
		(width 0.11684)
		(layer "In2.Cu")
		(net "CLK_50M_NCSI_OCP_V3_2")
	)
	(segment
		(start 214.224616 -13.800328)
		(end 214.618316 -13.800328)
		(width 0.11684)
		(layer "In2.Cu")
		(net "CLK_50M_NCSI_OCP_V3_2")
	)
	(segment
		(start 119.144796 -16.760444)
		(end 119.261636 -16.877284)
		(width 0.11684)
		(layer "In2.Cu")
		(net "CLK_50M_NCSI_OCP_V3_2")
	)
	(segment
		(start 167.607742 -8.490712)
		(end 168.848278 -7.250176)
		(width 0.11684)
		(layer "In2.Cu")
		(net "CLK_50M_NCSI_OCP_V3_2")
	)
	(segment
		(start 87.04326 -29.762958)
		(end 87.1601 -29.646118)
		(width 0.11684)
		(layer "In2.Cu")
		(net "CLK_50M_NCSI_OCP_V3_2")
	)
	(segment
		(start 194.692016 -12.449302)
		(end 196.043042 -13.800328)
		(width 0.11684)
		(layer "In2.Cu")
		(net "CLK_50M_NCSI_OCP_V3_2")
	)
	(segment
		(start 88.569038 -22.744938)
		(end 87.1601 -22.744938)
		(width 0.11684)
		(layer "In2.Cu")
		(net "CLK_50M_NCSI_OCP_V3_2")
	)
	(segment
		(start 142.530322 -9.361678)
		(end 142.530322 -7.384288)
		(width 0.11684)
		(layer "In2.Cu")
		(net "CLK_50M_NCSI_OCP_V3_2")
	)
	(segment
		(start 143.901922 -7.267448)
		(end 144.295622 -7.267448)
		(width 0.11684)
		(layer "In2.Cu")
		(net "CLK_50M_NCSI_OCP_V3_2")
	)
	(segment
		(start 194.29984 -11.50239)
		(end 194.692016 -12.449302)
		(width 0.11684)
		(layer "In2.Cu")
		(net "CLK_50M_NCSI_OCP_V3_2")
	)
	(segment
		(start 142.647162 -7.267448)
		(end 143.040862 -7.267448)
		(width 0.11684)
		(layer "In2.Cu")
		(net "CLK_50M_NCSI_OCP_V3_2")
	)
	(segment
		(start 88.685878 -23.255478)
		(end 88.685878 -22.861778)
		(width 0.11684)
		(layer "In2.Cu")
		(net "CLK_50M_NCSI_OCP_V3_2")
	)
	(segment
		(start 211.598256 -13.917168)
		(end 211.715096 -13.800328)
		(width 0.11684)
		(layer "In2.Cu")
		(net "CLK_50M_NCSI_OCP_V3_2")
	)
	(segment
		(start 119.027956 -13.20673)
		(end 119.144796 -13.32357)
		(width 0.11684)
		(layer "In2.Cu")
		(net "CLK_50M_NCSI_OCP_V3_2")
	)
	(segment
		(start 88.569038 -23.999698)
		(end 87.1601 -23.999698)
		(width 0.11684)
		(layer "In2.Cu")
		(net "CLK_50M_NCSI_OCP_V3_2")
	)
	(segment
		(start 94.144338 -14.885924)
		(end 96.091248 -14.885924)
		(width 0.11684)
		(layer "In2.Cu")
		(net "CLK_50M_NCSI_OCP_V3_2")
	)
	(segment
		(start 159.489394 -9.669526)
		(end 161.959798 -9.669526)
		(width 0.11684)
		(layer "In2.Cu")
		(net "CLK_50M_NCSI_OCP_V3_2")
	)
	(segment
		(start 88.569038 -30.273498)
		(end 87.1601 -30.273498)
		(width 0.11684)
		(layer "In2.Cu")
		(net "CLK_50M_NCSI_OCP_V3_2")
	)
	(segment
		(start 87.04326 -22.234398)
		(end 87.1601 -22.117558)
		(width 0.11684)
		(layer "In2.Cu")
		(net "CLK_50M_NCSI_OCP_V3_2")
	)
	(segment
		(start 216.577926 -13.800328)
		(end 218.09202 -15.314422)
		(width 0.11684)
		(layer "In2.Cu")
		(net "CLK_50M_NCSI_OCP_V3_2")
	)
	(segment
		(start 119.772176 -13.32357)
		(end 119.889016 -13.20673)
		(width 0.11684)
		(layer "In2.Cu")
		(net "CLK_50M_NCSI_OCP_V3_2")
	)
	(segment
		(start 105.618788 -16.12265)
		(end 105.618788 -15.002764)
		(width 0.11684)
		(layer "In2.Cu")
		(net "CLK_50M_NCSI_OCP_V3_2")
	)
	(segment
		(start 88.685878 -25.764998)
		(end 88.685878 -25.371298)
		(width 0.11684)
		(layer "In2.Cu")
		(net "CLK_50M_NCSI_OCP_V3_2")
	)
	(segment
		(start 212.853016 -13.917168)
		(end 212.969856 -13.800328)
		(width 0.11684)
		(layer "In2.Cu")
		(net "CLK_50M_NCSI_OCP_V3_2")
	)
	(segment
		(start 87.1601 -22.117558)
		(end 88.569038 -22.117558)
		(width 0.11684)
		(layer "In2.Cu")
		(net "CLK_50M_NCSI_OCP_V3_2")
	)
	(segment
		(start 87.04326 -23.489158)
		(end 87.1601 -23.372318)
		(width 0.11684)
		(layer "In2.Cu")
		(net "CLK_50M_NCSI_OCP_V3_2")
	)
	(segment
		(start 210.970876 -14.950948)
		(end 211.087716 -15.067788)
		(width 0.11684)
		(layer "In2.Cu")
		(net "CLK_50M_NCSI_OCP_V3_2")
	)
	(segment
		(start 126.789688 -11.8491)
		(end 127.217424 -11.421364)
		(width 0.11684)
		(layer "In2.Cu")
		(net "CLK_50M_NCSI_OCP_V3_2")
	)
	(segment
		(start 119.144796 -13.32357)
		(end 119.144796 -16.760444)
		(width 0.11684)
		(layer "In2.Cu")
		(net "CLK_50M_NCSI_OCP_V3_2")
	)
	(segment
		(start 104.991408 -16.12265)
		(end 105.108248 -16.23949)
		(width 0.11684)
		(layer "In2.Cu")
		(net "CLK_50M_NCSI_OCP_V3_2")
	)
	(segment
		(start 87.04326 -23.882858)
		(end 87.04326 -23.489158)
		(width 0.11684)
		(layer "In2.Cu")
		(net "CLK_50M_NCSI_OCP_V3_2")
	)
	(segment
		(start 193.692018 -10.009378)
		(end 194.020186 -10.337546)
		(width 0.11684)
		(layer "In2.Cu")
		(net "CLK_50M_NCSI_OCP_V3_2")
	)
	(segment
		(start 96.324928 -16.23949)
		(end 96.718628 -16.23949)
		(width 0.11684)
		(layer "In2.Cu")
		(net "CLK_50M_NCSI_OCP_V3_2")
	)
	(segment
		(start 88.569038 -24.627078)
		(end 88.685878 -24.510238)
		(width 0.11684)
		(layer "In2.Cu")
		(net "CLK_50M_NCSI_OCP_V3_2")
	)
	(segment
		(start 118.517416 -13.32357)
		(end 118.634256 -13.20673)
		(width 0.11684)
		(layer "In2.Cu")
		(net "CLK_50M_NCSI_OCP_V3_2")
	)
	(segment
		(start 212.225636 -14.950948)
		(end 212.342476 -15.067788)
		(width 0.11684)
		(layer "In2.Cu")
		(net "CLK_50M_NCSI_OCP_V3_2")
	)
	(segment
		(start 117.890036 -16.760444)
		(end 118.006876 -16.877284)
		(width 0.11684)
		(layer "In2.Cu")
		(net "CLK_50M_NCSI_OCP_V3_2")
	)
	(segment
		(start 121.143776 -13.20673)
		(end 125.41504 -13.20673)
		(width 0.11684)
		(layer "In2.Cu")
		(net "CLK_50M_NCSI_OCP_V3_2")
	)
	(segment
		(start 118.006876 -16.877284)
		(end 118.400576 -16.877284)
		(width 0.11684)
		(layer "In2.Cu")
		(net "CLK_50M_NCSI_OCP_V3_2")
	)
	(segment
		(start 106.129328 -14.885924)
		(end 106.246168 -15.002764)
		(width 0.11684)
		(layer "In2.Cu")
		(net "CLK_50M_NCSI_OCP_V3_2")
	)
	(segment
		(start 88.685878 -27.880818)
		(end 88.569038 -27.763978)
		(width 0.11684)
		(layer "In2.Cu")
		(net "CLK_50M_NCSI_OCP_V3_2")
	)
	(segment
		(start 98.717608 -15.002764)
		(end 98.717608 -16.483076)
		(width 0.11684)
		(layer "In2.Cu")
		(net "CLK_50M_NCSI_OCP_V3_2")
	)
	(segment
		(start 99.972368 -15.002764)
		(end 99.972368 -17.553686)
		(width 0.11684)
		(layer "In2.Cu")
		(net "CLK_50M_NCSI_OCP_V3_2")
	)
	(segment
		(start 143.785082 -7.384288)
		(end 143.901922 -7.267448)
		(width 0.11684)
		(layer "In2.Cu")
		(net "CLK_50M_NCSI_OCP_V3_2")
	)
	(segment
		(start 196.043042 -13.800328)
		(end 209.599276 -13.800328)
		(width 0.11684)
		(layer "In2.Cu")
		(net "CLK_50M_NCSI_OCP_V3_2")
	)
	(segment
		(start 87.235284 -33.31718)
		(end 88.685878 -31.866586)
		(width 0.11684)
		(layer "In2.Cu")
		(net "CLK_50M_NCSI_OCP_V3_2")
	)
	(segment
		(start 102.481888 -15.002764)
		(end 102.481888 -17.544288)
		(width 0.11684)
		(layer "In2.Cu")
		(net "CLK_50M_NCSI_OCP_V3_2")
	)
	(segment
		(start 177.066194 -7.250176)
		(end 179.86375 -10.047732)
		(width 0.11684)
		(layer "In2.Cu")
		(net "CLK_50M_NCSI_OCP_V3_2")
	)
	(segment
		(start 214.735156 -14.950948)
		(end 214.851996 -15.067788)
		(width 0.11684)
		(layer "In2.Cu")
		(net "CLK_50M_NCSI_OCP_V3_2")
	)
	(segment
		(start 87.1601 -30.273498)
		(end 87.04326 -30.156658)
		(width 0.11684)
		(layer "In2.Cu")
		(net "CLK_50M_NCSI_OCP_V3_2")
	)
	(segment
		(start 142.530322 -7.384288)
		(end 142.647162 -7.267448)
		(width 0.11684)
		(layer "In2.Cu")
		(net "CLK_50M_NCSI_OCP_V3_2")
	)
	(segment
		(start 142.019782 -9.478518)
		(end 142.413482 -9.478518)
		(width 0.11684)
		(layer "In2.Cu")
		(net "CLK_50M_NCSI_OCP_V3_2")
	)
	(segment
		(start 103.109268 -15.002764)
		(end 103.226108 -14.885924)
		(width 0.11684)
		(layer "In2.Cu")
		(net "CLK_50M_NCSI_OCP_V3_2")
	)
	(segment
		(start 88.685878 -26.626058)
		(end 88.569038 -26.509218)
		(width 0.11684)
		(layer "In2.Cu")
		(net "CLK_50M_NCSI_OCP_V3_2")
	)
	(segment
		(start 87.04326 -30.156658)
		(end 87.04326 -29.762958)
		(width 0.11684)
		(layer "In2.Cu")
		(net "CLK_50M_NCSI_OCP_V3_2")
	)
	(segment
		(start 96.835468 -15.002764)
		(end 96.952308 -14.885924)
		(width 0.11684)
		(layer "In2.Cu")
		(net "CLK_50M_NCSI_OCP_V3_2")
	)
	(segment
		(start 212.342476 -15.067788)
		(end 212.736176 -15.067788)
		(width 0.11684)
		(layer "In2.Cu")
		(net "CLK_50M_NCSI_OCP_V3_2")
	)
	(segment
		(start 213.363556 -13.800328)
		(end 213.480396 -13.917168)
		(width 0.11684)
		(layer "In2.Cu")
		(net "CLK_50M_NCSI_OCP_V3_2")
	)
	(segment
		(start 119.889016 -13.20673)
		(end 120.282716 -13.20673)
		(width 0.11684)
		(layer "In2.Cu")
		(net "CLK_50M_NCSI_OCP_V3_2")
	)
	(segment
		(start 155.239466 -8.377428)
		(end 158.197296 -8.377428)
		(width 0.11684)
		(layer "In2.Cu")
		(net "CLK_50M_NCSI_OCP_V3_2")
	)
	(segment
		(start 106.873548 -15.002764)
		(end 106.990388 -14.885924)
		(width 0.11684)
		(layer "In2.Cu")
		(net "CLK_50M_NCSI_OCP_V3_2")
	)
	(segment
		(start 99.344988 -15.002764)
		(end 99.461828 -14.885924)
		(width 0.11684)
		(layer "In2.Cu")
		(net "CLK_50M_NCSI_OCP_V3_2")
	)
	(segment
		(start 213.480396 -13.917168)
		(end 213.480396 -14.950948)
		(width 0.11684)
		(layer "In2.Cu")
		(net "CLK_50M_NCSI_OCP_V3_2")
	)
	(segment
		(start 88.685878 -22.861778)
		(end 88.569038 -22.744938)
		(width 0.11684)
		(layer "In2.Cu")
		(net "CLK_50M_NCSI_OCP_V3_2")
	)
	(segment
		(start 87.1601 -23.372318)
		(end 88.569038 -23.372318)
		(width 0.11684)
		(layer "In2.Cu")
		(net "CLK_50M_NCSI_OCP_V3_2")
	)
	(segment
		(start 98.834448 -16.599916)
		(end 99.228148 -16.599916)
		(width 0.11684)
		(layer "In2.Cu")
		(net "CLK_50M_NCSI_OCP_V3_2")
	)
	(segment
		(start 87.04326 -28.901898)
		(end 87.04326 -28.508198)
		(width 0.11684)
		(layer "In2.Cu")
		(net "CLK_50M_NCSI_OCP_V3_2")
	)
	(segment
		(start 211.598256 -14.950948)
		(end 211.598256 -13.917168)
		(width 0.11684)
		(layer "In2.Cu")
		(net "CLK_50M_NCSI_OCP_V3_2")
	)
	(segment
		(start 87.04326 -24.743918)
		(end 87.1601 -24.627078)
		(width 0.11684)
		(layer "In2.Cu")
		(net "CLK_50M_NCSI_OCP_V3_2")
	)
	(segment
		(start 194.29984 -11.012932)
		(end 194.29984 -11.50239)
		(width 0.11684)
		(layer "In2.Cu")
		(net "CLK_50M_NCSI_OCP_V3_2")
	)
	(segment
		(start 88.685878 -29.529278)
		(end 88.685878 -29.135578)
		(width 0.11684)
		(layer "In2.Cu")
		(net "CLK_50M_NCSI_OCP_V3_2")
	)
	(segment
		(start 179.86375 -10.047732)
		(end 182.310532 -10.047732)
		(width 0.11684)
		(layer "In2.Cu")
		(net "CLK_50M_NCSI_OCP_V3_2")
	)
	(segment
		(start 88.685878 -29.135578)
		(end 88.569038 -29.018738)
		(width 0.11684)
		(layer "In2.Cu")
		(net "CLK_50M_NCSI_OCP_V3_2")
	)
	(segment
		(start 103.736648 -15.002764)
		(end 103.736648 -17.439132)
		(width 0.11684)
		(layer "In2.Cu")
		(net "CLK_50M_NCSI_OCP_V3_2")
	)
	(segment
		(start 120.910096 -16.877284)
		(end 121.026936 -16.760444)
		(width 0.11684)
		(layer "In2.Cu")
		(net "CLK_50M_NCSI_OCP_V3_2")
	)
	(segment
		(start 87.04326 -26.392378)
		(end 87.04326 -25.998678)
		(width 0.11684)
		(layer "In2.Cu")
		(net "CLK_50M_NCSI_OCP_V3_2")
	)
	(segment
		(start 101.854508 -17.553686)
		(end 101.854508 -15.002764)
		(width 0.11684)
		(layer "In2.Cu")
		(net "CLK_50M_NCSI_OCP_V3_2")
	)
	(segment
		(start 126.77267 -11.8491)
		(end 126.789688 -11.8491)
		(width 0.11684)
		(layer "In2.Cu")
		(net "CLK_50M_NCSI_OCP_V3_2")
	)
	(segment
		(start 121.026936 -16.760444)
		(end 121.026936 -13.32357)
		(width 0.11684)
		(layer "In2.Cu")
		(net "CLK_50M_NCSI_OCP_V3_2")
	)
	(segment
		(start 98.090228 -16.15821)
		(end 98.090228 -15.002764)
		(width 0.11684)
		(layer "In2.Cu")
		(net "CLK_50M_NCSI_OCP_V3_2")
	)
	(segment
		(start 88.685878 -22.000718)
		(end 88.685878 -20.344384)
		(width 0.11684)
		(layer "In2.Cu")
		(net "CLK_50M_NCSI_OCP_V3_2")
	)
	(segment
		(start 87.1601 -25.881838)
		(end 88.569038 -25.881838)
		(width 0.11684)
		(layer "In2.Cu")
		(net "CLK_50M_NCSI_OCP_V3_2")
	)
	(segment
		(start 88.569038 -27.763978)
		(end 87.1601 -27.763978)
		(width 0.11684)
		(layer "In2.Cu")
		(net "CLK_50M_NCSI_OCP_V3_2")
	)
	(segment
		(start 87.04326 -28.508198)
		(end 87.1601 -28.391358)
		(width 0.11684)
		(layer "In2.Cu")
		(net "CLK_50M_NCSI_OCP_V3_2")
	)
	(segment
		(start 101.971348 -14.885924)
		(end 102.365048 -14.885924)
		(width 0.11684)
		(layer "In2.Cu")
		(net "CLK_50M_NCSI_OCP_V3_2")
	)
	(segment
		(start 161.959798 -9.669526)
		(end 163.138612 -8.490712)
		(width 0.11684)
		(layer "In2.Cu")
		(net "CLK_50M_NCSI_OCP_V3_2")
	)
	(segment
		(start 214.618316 -13.800328)
		(end 214.735156 -13.917168)
		(width 0.11684)
		(layer "In2.Cu")
		(net "CLK_50M_NCSI_OCP_V3_2")
	)
	(segment
		(start 87.1601 -24.627078)
		(end 88.569038 -24.627078)
		(width 0.11684)
		(layer "In2.Cu")
		(net "CLK_50M_NCSI_OCP_V3_2")
	)
	(segment
		(start 104.364028 -17.439132)
		(end 104.364028 -15.002764)
		(width 0.11684)
		(layer "In2.Cu")
		(net "CLK_50M_NCSI_OCP_V3_2")
	)
	(segment
		(start 210.343496 -13.917168)
		(end 210.460336 -13.800328)
		(width 0.11684)
		(layer "In2.Cu")
		(net "CLK_50M_NCSI_OCP_V3_2")
	)
	(segment
		(start 87.1601 -29.646118)
		(end 88.569038 -29.646118)
		(width 0.11684)
		(layer "In2.Cu")
		(net "CLK_50M_NCSI_OCP_V3_2")
	)
	(segment
		(start 209.716116 -13.917168)
		(end 209.716116 -14.950948)
		(width 0.11684)
		(layer "In2.Cu")
		(net "CLK_50M_NCSI_OCP_V3_2")
	)
	(segment
		(start 103.619808 -14.885924)
		(end 103.736648 -15.002764)
		(width 0.11684)
		(layer "In2.Cu")
		(net "CLK_50M_NCSI_OCP_V3_2")
	)
	(segment
		(start 97.579688 -16.27505)
		(end 97.973388 -16.27505)
		(width 0.11684)
		(layer "In2.Cu")
		(net "CLK_50M_NCSI_OCP_V3_2")
	)
	(segment
		(start 88.685878 -27.019758)
		(end 88.685878 -26.626058)
		(width 0.11684)
		(layer "In2.Cu")
		(net "CLK_50M_NCSI_OCP_V3_2")
	)
	(segment
		(start 102.481888 -17.544288)
		(end 102.598728 -17.661128)
		(width 0.11684)
		(layer "In2.Cu")
		(net "CLK_50M_NCSI_OCP_V3_2")
	)
	(segment
		(start 100.089208 -17.670526)
		(end 100.482908 -17.670526)
		(width 0.11684)
		(layer "In2.Cu")
		(net "CLK_50M_NCSI_OCP_V3_2")
	)
	(segment
		(start 210.970876 -13.917168)
		(end 210.970876 -14.950948)
		(width 0.11684)
		(layer "In2.Cu")
		(net "CLK_50M_NCSI_OCP_V3_2")
	)
	(segment
		(start 87.04326 -27.647138)
		(end 87.04326 -27.253438)
		(width 0.11684)
		(layer "In2.Cu")
		(net "CLK_50M_NCSI_OCP_V3_2")
	)
	(segment
		(start 101.343968 -17.670526)
		(end 101.737668 -17.670526)
		(width 0.11684)
		(layer "In2.Cu")
		(net "CLK_50M_NCSI_OCP_V3_2")
	)
	(segment
		(start 214.107776 -13.917168)
		(end 214.224616 -13.800328)
		(width 0.11684)
		(layer "In2.Cu")
		(net "CLK_50M_NCSI_OCP_V3_2")
	)
	(segment
		(start 141.786102 -7.267448)
		(end 141.902942 -7.384288)
		(width 0.11684)
		(layer "In2.Cu")
		(net "CLK_50M_NCSI_OCP_V3_2")
	)
	(segment
		(start 120.399556 -16.760444)
		(end 120.516396 -16.877284)
		(width 0.11684)
		(layer "In2.Cu")
		(net "CLK_50M_NCSI_OCP_V3_2")
	)
	(segment
		(start 101.110288 -14.885924)
		(end 101.227128 -15.002764)
		(width 0.11684)
		(layer "In2.Cu")
		(net "CLK_50M_NCSI_OCP_V3_2")
	)
	(segment
		(start 210.460336 -13.800328)
		(end 210.854036 -13.800328)
		(width 0.11684)
		(layer "In2.Cu")
		(net "CLK_50M_NCSI_OCP_V3_2")
	)
	(segment
		(start 214.735156 -13.917168)
		(end 214.735156 -14.950948)
		(width 0.11684)
		(layer "In2.Cu")
		(net "CLK_50M_NCSI_OCP_V3_2")
	)
	(segment
		(start 143.668242 -9.478518)
		(end 143.785082 -9.361678)
		(width 0.11684)
		(layer "In2.Cu")
		(net "CLK_50M_NCSI_OCP_V3_2")
	)
	(segment
		(start 143.040862 -7.267448)
		(end 143.157702 -7.384288)
		(width 0.11684)
		(layer "In2.Cu")
		(net "CLK_50M_NCSI_OCP_V3_2")
	)
	(segment
		(start 104.480868 -14.885924)
		(end 104.874568 -14.885924)
		(width 0.11684)
		(layer "In2.Cu")
		(net "CLK_50M_NCSI_OCP_V3_2")
	)
	(segment
		(start 119.261636 -16.877284)
		(end 119.655336 -16.877284)
		(width 0.11684)
		(layer "In2.Cu")
		(net "CLK_50M_NCSI_OCP_V3_2")
	)
	(segment
		(start 88.685878 -24.510238)
		(end 88.685878 -24.116538)
		(width 0.11684)
		(layer "In2.Cu")
		(net "CLK_50M_NCSI_OCP_V3_2")
	)
	(segment
		(start 215.362536 -13.917168)
		(end 215.479376 -13.800328)
		(width 0.11684)
		(layer "In2.Cu")
		(net "CLK_50M_NCSI_OCP_V3_2")
	)
	(segment
		(start 88.569038 -27.136598)
		(end 88.685878 -27.019758)
		(width 0.11684)
		(layer "In2.Cu")
		(net "CLK_50M_NCSI_OCP_V3_2")
	)
	(segment
		(start 87.1601 -27.136598)
		(end 88.569038 -27.136598)
		(width 0.11684)
		(layer "In2.Cu")
		(net "CLK_50M_NCSI_OCP_V3_2")
	)
	(segment
		(start 99.972368 -17.553686)
		(end 100.089208 -17.670526)
		(width 0.11684)
		(layer "In2.Cu")
		(net "CLK_50M_NCSI_OCP_V3_2")
	)
	(segment
		(start 88.569038 -25.254458)
		(end 87.1601 -25.254458)
		(width 0.11684)
		(layer "In2.Cu")
		(net "CLK_50M_NCSI_OCP_V3_2")
	)
	(segment
		(start 141.902942 -9.361678)
		(end 142.019782 -9.478518)
		(width 0.11684)
		(layer "In2.Cu")
		(net "CLK_50M_NCSI_OCP_V3_2")
	)
	(segment
		(start 215.479376 -13.800328)
		(end 216.577926 -13.800328)
		(width 0.11684)
		(layer "In2.Cu")
		(net "CLK_50M_NCSI_OCP_V3_2")
	)
	(segment
		(start 88.569038 -25.881838)
		(end 88.685878 -25.764998)
		(width 0.11684)
		(layer "In2.Cu")
		(net "CLK_50M_NCSI_OCP_V3_2")
	)
	(segment
		(start 145.156682 -7.267448)
		(end 154.129486 -7.267448)
		(width 0.11684)
		(layer "In2.Cu")
		(net "CLK_50M_NCSI_OCP_V3_2")
	)
	(segment
		(start 209.716116 -14.950948)
		(end 209.832956 -15.067788)
		(width 0.11684)
		(layer "In2.Cu")
		(net "CLK_50M_NCSI_OCP_V3_2")
	)
	(segment
		(start 88.569038 -23.372318)
		(end 88.685878 -23.255478)
		(width 0.11684)
		(layer "In2.Cu")
		(net "CLK_50M_NCSI_OCP_V3_2")
	)
	(segment
		(start 87.1601 -25.254458)
		(end 87.04326 -25.137618)
		(width 0.11684)
		(layer "In2.Cu")
		(net "CLK_50M_NCSI_OCP_V3_2")
	)
	(segment
		(start 183.578246 -8.780018)
		(end 190.723774 -8.780018)
		(width 0.11684)
		(layer "In2.Cu")
		(net "CLK_50M_NCSI_OCP_V3_2")
	)
	(segment
		(start 87.1601 -26.509218)
		(end 87.04326 -26.392378)
		(width 0.11684)
		(layer "In2.Cu")
		(net "CLK_50M_NCSI_OCP_V3_2")
	)
	(segment
		(start 106.363008 -16.23949)
		(end 106.756708 -16.23949)
		(width 0.11684)
		(layer "In2.Cu")
		(net "CLK_50M_NCSI_OCP_V3_2")
	)
	(segment
		(start 97.462848 -16.15821)
		(end 97.579688 -16.27505)
		(width 0.11684)
		(layer "In2.Cu")
		(net "CLK_50M_NCSI_OCP_V3_2")
	)
	(segment
		(start 99.461828 -14.885924)
		(end 99.855528 -14.885924)
		(width 0.11684)
		(layer "In2.Cu")
		(net "CLK_50M_NCSI_OCP_V3_2")
	)
	(segment
		(start 96.091248 -14.885924)
		(end 96.208088 -15.002764)
		(width 0.11684)
		(layer "In2.Cu")
		(net "CLK_50M_NCSI_OCP_V3_2")
	)
	(segment
		(start 105.501948 -16.23949)
		(end 105.618788 -16.12265)
		(width 0.11684)
		(layer "In2.Cu")
		(net "CLK_50M_NCSI_OCP_V3_2")
	)
	(segment
		(start 209.599276 -13.800328)
		(end 209.716116 -13.917168)
		(width 0.11684)
		(layer "In2.Cu")
		(net "CLK_50M_NCSI_OCP_V3_2")
	)
	(segment
		(start 101.854508 -15.002764)
		(end 101.971348 -14.885924)
		(width 0.11684)
		(layer "In2.Cu")
		(net "CLK_50M_NCSI_OCP_V3_2")
	)
	(segment
		(start 211.087716 -15.067788)
		(end 211.481416 -15.067788)
		(width 0.11684)
		(layer "In2.Cu")
		(net "CLK_50M_NCSI_OCP_V3_2")
	)
	(segment
		(start 96.208088 -15.002764)
		(end 96.208088 -16.12265)
		(width 0.11684)
		(layer "In2.Cu")
		(net "CLK_50M_NCSI_OCP_V3_2")
	)
	(segment
		(start 120.516396 -16.877284)
		(end 120.910096 -16.877284)
		(width 0.11684)
		(layer "In2.Cu")
		(net "CLK_50M_NCSI_OCP_V3_2")
	)
	(segment
		(start 101.227128 -15.002764)
		(end 101.227128 -17.553686)
		(width 0.11684)
		(layer "In2.Cu")
		(net "CLK_50M_NCSI_OCP_V3_2")
	)
	(segment
		(start 194.020186 -10.337546)
		(end 194.29984 -11.012932)
		(width 0.11684)
		(layer "In2.Cu")
		(net "CLK_50M_NCSI_OCP_V3_2")
	)
	(segment
		(start 87.04326 -22.628098)
		(end 87.04326 -22.234398)
		(width 0.11684)
		(layer "In2.Cu")
		(net "CLK_50M_NCSI_OCP_V3_2")
	)
	(segment
		(start 142.413482 -9.478518)
		(end 142.530322 -9.361678)
		(width 0.11684)
		(layer "In2.Cu")
		(net "CLK_50M_NCSI_OCP_V3_2")
	)
	(segment
		(start 103.736648 -17.439132)
		(end 103.853488 -17.555972)
		(width 0.11684)
		(layer "In2.Cu")
		(net "CLK_50M_NCSI_OCP_V3_2")
	)
	(segment
		(start 103.109268 -17.544288)
		(end 103.109268 -15.002764)
		(width 0.11684)
		(layer "In2.Cu")
		(net "CLK_50M_NCSI_OCP_V3_2")
	)
	(segment
		(start 144.412462 -9.361678)
		(end 144.529302 -9.478518)
		(width 0.11684)
		(layer "In2.Cu")
		(net "CLK_50M_NCSI_OCP_V3_2")
	)
	(segment
		(start 127.217424 -11.421364)
		(end 127.217424 -9.830816)
		(width 0.11684)
		(layer "In2.Cu")
		(net "CLK_50M_NCSI_OCP_V3_2")
	)
	(segment
		(start 102.365048 -14.885924)
		(end 102.481888 -15.002764)
		(width 0.11684)
		(layer "In2.Cu")
		(net "CLK_50M_NCSI_OCP_V3_2")
	)
	(segment
		(start 125.41504 -13.20673)
		(end 126.77267 -11.8491)
		(width 0.11684)
		(layer "In2.Cu")
		(net "CLK_50M_NCSI_OCP_V3_2")
	)
	(segment
		(start 107.840272 -14.885924)
		(end 109.591348 -13.134848)
		(width 0.11684)
		(layer "In2.Cu")
		(net "CLK_50M_NCSI_OCP_V3_2")
	)
	(segment
		(start 103.226108 -14.885924)
		(end 103.619808 -14.885924)
		(width 0.11684)
		(layer "In2.Cu")
		(net "CLK_50M_NCSI_OCP_V3_2")
	)
	(segment
		(start 99.228148 -16.599916)
		(end 99.344988 -16.483076)
		(width 0.11684)
		(layer "In2.Cu")
		(net "CLK_50M_NCSI_OCP_V3_2")
	)
	(segment
		(start 215.245696 -15.067788)
		(end 215.362536 -14.950948)
		(width 0.11684)
		(layer "In2.Cu")
		(net "CLK_50M_NCSI_OCP_V3_2")
	)
	(segment
		(start 105.618788 -15.002764)
		(end 105.735628 -14.885924)
		(width 0.11684)
		(layer "In2.Cu")
		(net "CLK_50M_NCSI_OCP_V3_2")
	)
	(segment
		(start 104.991408 -15.002764)
		(end 104.991408 -16.12265)
		(width 0.11684)
		(layer "In2.Cu")
		(net "CLK_50M_NCSI_OCP_V3_2")
	)
	(segment
		(start 117.890036 -13.32357)
		(end 117.890036 -16.760444)
		(width 0.11684)
		(layer "In2.Cu")
		(net "CLK_50M_NCSI_OCP_V3_2")
	)
	(segment
		(start 211.481416 -15.067788)
		(end 211.598256 -14.950948)
		(width 0.11684)
		(layer "In2.Cu")
		(net "CLK_50M_NCSI_OCP_V3_2")
	)
	(segment
		(start 144.295622 -7.267448)
		(end 144.412462 -7.384288)
		(width 0.11684)
		(layer "In2.Cu")
		(net "CLK_50M_NCSI_OCP_V3_2")
	)
	(segment
		(start 212.225636 -13.917168)
		(end 212.225636 -14.950948)
		(width 0.11684)
		(layer "In2.Cu")
		(net "CLK_50M_NCSI_OCP_V3_2")
	)
	(segment
		(start 88.685878 -31.866586)
		(end 88.685878 -30.390338)
		(width 0.11684)
		(layer "In2.Cu")
		(net "CLK_50M_NCSI_OCP_V3_2")
	)
	(segment
		(start 109.591348 -13.134848)
		(end 117.701314 -13.134848)
		(width 0.11684)
		(layer "In2.Cu")
		(net "CLK_50M_NCSI_OCP_V3_2")
	)
	(segment
		(start 106.873548 -16.12265)
		(end 106.873548 -15.002764)
		(width 0.11684)
		(layer "In2.Cu")
		(net "CLK_50M_NCSI_OCP_V3_2")
	)
	(segment
		(start 190.723774 -8.780018)
		(end 193.692018 -10.009378)
		(width 0.11684)
		(layer "In2.Cu")
		(net "CLK_50M_NCSI_OCP_V3_2")
	)
	(segment
		(start 96.952308 -14.885924)
		(end 97.346008 -14.885924)
		(width 0.11684)
		(layer "In2.Cu")
		(net "CLK_50M_NCSI_OCP_V3_2")
	)
	(segment
		(start 87.1601 -29.018738)
		(end 87.04326 -28.901898)
		(width 0.11684)
		(layer "In2.Cu")
		(net "CLK_50M_NCSI_OCP_V3_2")
	)
	(segment
		(start 143.274542 -9.478518)
		(end 143.668242 -9.478518)
		(width 0.11684)
		(layer "In2.Cu")
		(net "CLK_50M_NCSI_OCP_V3_2")
	)
	(segment
		(start 88.685878 -24.116538)
		(end 88.569038 -23.999698)
		(width 0.11684)
		(layer "In2.Cu")
		(net "CLK_50M_NCSI_OCP_V3_2")
	)
	(segment
		(start 214.107776 -14.950948)
		(end 214.107776 -13.917168)
		(width 0.11684)
		(layer "In2.Cu")
		(net "CLK_50M_NCSI_OCP_V3_2")
	)
	(segment
		(start 210.854036 -13.800328)
		(end 210.970876 -13.917168)
		(width 0.11684)
		(layer "In2.Cu")
		(net "CLK_50M_NCSI_OCP_V3_2")
	)
	(segment
		(start 210.226656 -15.067788)
		(end 210.343496 -14.950948)
		(width 0.11684)
		(layer "In2.Cu")
		(net "CLK_50M_NCSI_OCP_V3_2")
	)
	(segment
		(start 99.344988 -16.483076)
		(end 99.344988 -15.002764)
		(width 0.11684)
		(layer "In2.Cu")
		(net "CLK_50M_NCSI_OCP_V3_2")
	)
	(segment
		(start 87.1601 -22.744938)
		(end 87.04326 -22.628098)
		(width 0.11684)
		(layer "In2.Cu")
		(net "CLK_50M_NCSI_OCP_V3_2")
	)
	(segment
		(start 88.685878 -25.371298)
		(end 88.569038 -25.254458)
		(width 0.11684)
		(layer "In2.Cu")
		(net "CLK_50M_NCSI_OCP_V3_2")
	)
	(segment
		(start 154.129486 -7.267448)
		(end 155.239466 -8.377428)
		(width 0.11684)
		(layer "In2.Cu")
		(net "CLK_50M_NCSI_OCP_V3_2")
	)
	(segment
		(start 129.202434 -8.4074)
		(end 131.94919 -8.4074)
		(width 0.11684)
		(layer "In2.Cu")
		(net "CLK_50M_NCSI_OCP_V3_2")
	)
	(segment
		(start 143.157702 -9.361678)
		(end 143.274542 -9.478518)
		(width 0.11684)
		(layer "In2.Cu")
		(net "CLK_50M_NCSI_OCP_V3_2")
	)
	(segment
		(start 128.31572 -9.294114)
		(end 129.202434 -8.4074)
		(width 0.11684)
		(layer "In2.Cu")
		(net "CLK_50M_NCSI_OCP_V3_2")
	)
	(segment
		(start 88.685878 -30.390338)
		(end 88.569038 -30.273498)
		(width 0.11684)
		(layer "In2.Cu")
		(net "CLK_50M_NCSI_OCP_V3_2")
	)
	(segment
		(start 119.772176 -16.760444)
		(end 119.772176 -13.32357)
		(width 0.11684)
		(layer "In2.Cu")
		(net "CLK_50M_NCSI_OCP_V3_2")
	)
	(segment
		(start 102.992428 -17.661128)
		(end 103.109268 -17.544288)
		(width 0.11684)
		(layer "In2.Cu")
		(net "CLK_50M_NCSI_OCP_V3_2")
	)
	(segment
		(start 131.94919 -8.4074)
		(end 133.089142 -7.267448)
		(width 0.11684)
		(layer "In2.Cu")
		(net "CLK_50M_NCSI_OCP_V3_2")
	)
	(segment
		(start 106.990388 -14.885924)
		(end 107.840272 -14.885924)
		(width 0.11684)
		(layer "In2.Cu")
		(net "CLK_50M_NCSI_OCP_V3_2")
	)
	(segment
		(start 145.039842 -7.384288)
		(end 145.156682 -7.267448)
		(width 0.11684)
		(layer "In2.Cu")
		(net "CLK_50M_NCSI_OCP_V3_2")
	)
	(segment
		(start 118.400576 -16.877284)
		(end 118.517416 -16.760444)
		(width 0.11684)
		(layer "In2.Cu")
		(net "CLK_50M_NCSI_OCP_V3_2")
	)
	(segment
		(start 104.364028 -15.002764)
		(end 104.480868 -14.885924)
		(width 0.11684)
		(layer "In2.Cu")
		(net "CLK_50M_NCSI_OCP_V3_2")
	)
	(segment
		(start 212.853016 -14.950948)
		(end 212.853016 -13.917168)
		(width 0.11684)
		(layer "In2.Cu")
		(net "CLK_50M_NCSI_OCP_V3_2")
	)
	(segment
		(start 209.832956 -15.067788)
		(end 210.226656 -15.067788)
		(width 0.11684)
		(layer "In2.Cu")
		(net "CLK_50M_NCSI_OCP_V3_2")
	)
	(segment
		(start 383.407666 -33.228788)
		(end 384.646932 -33.228788)
		(width 0.10668)
		(layer "F.Cu")
		(net "CLK_50M_NCSI_OCP_SFF_ISO_R")
	)
	(segment
		(start 384.646932 -33.228788)
		(end 384.649218 -33.226502)
		(width 0.10668)
		(layer "F.Cu")
		(net "CLK_50M_NCSI_OCP_SFF_ISO_R")
	)
	(segment
		(start 381.620522 -33.228788)
		(end 383.407666 -33.228788)
		(width 0.10668)
		(layer "F.Cu")
		(net "CLK_50M_NCSI_OCP_SFF_ISO_R")
	)
	(via
		(at 383.407666 -33.228788)
		(size 0.762)
		(drill 0.381)
		(layers "F.Cu" "B.Cu")
		(net "CLK_50M_NCSI_OCP_SFF_ISO_R")
	)
	(segment
		(start 444.761874 -7.356856)
		(end 444.171832 -6.766814)
		(width 0.10668)
		(layer "F.Cu")
		(net "CLK_50M_NCSI_OCP_SFF_ISO")
	)
	(segment
		(start 385.449318 -30.854142)
		(end 385.026916 -30.43174)
		(width 0.10668)
		(layer "F.Cu")
		(net "CLK_50M_NCSI_OCP_SFF_ISO")
	)
	(segment
		(start 385.449318 -33.226502)
		(end 385.449318 -30.854142)
		(width 0.10668)
		(layer "F.Cu")
		(net "CLK_50M_NCSI_OCP_SFF_ISO")
	)
	(segment
		(start 444.761874 -8.320024)
		(end 444.761874 -7.356856)
		(width 0.10668)
		(layer "F.Cu")
		(net "CLK_50M_NCSI_OCP_SFF_ISO")
	)
	(via
		(at 385.026916 -30.43174)
		(size 0.508)
		(drill 0.254)
		(layers "F.Cu" "B.Cu")
		(net "CLK_50M_NCSI_OCP_SFF_ISO")
	)
	(via
		(at 444.171832 -6.766814)
		(size 0.508)
		(drill 0.254)
		(layers "F.Cu" "B.Cu")
		(net "CLK_50M_NCSI_OCP_SFF_ISO")
	)
	(segment
		(start 440.383168 -2.97815)
		(end 444.171832 -6.766814)
		(width 0.11684)
		(layer "In2.Cu")
		(net "CLK_50M_NCSI_OCP_SFF_ISO")
	)
	(segment
		(start 421.236648 -4.454398)
		(end 423.421048 -4.454398)
		(width 0.11684)
		(layer "In2.Cu")
		(net "CLK_50M_NCSI_OCP_SFF_ISO")
	)
	(segment
		(start 391.356088 -7.430516)
		(end 395.595348 -3.191256)
		(width 0.11684)
		(layer "In2.Cu")
		(net "CLK_50M_NCSI_OCP_SFF_ISO")
	)
	(segment
		(start 424.897296 -2.97815)
		(end 440.383168 -2.97815)
		(width 0.11684)
		(layer "In2.Cu")
		(net "CLK_50M_NCSI_OCP_SFF_ISO")
	)
	(segment
		(start 423.421048 -4.454398)
		(end 424.897296 -2.97815)
		(width 0.11684)
		(layer "In2.Cu")
		(net "CLK_50M_NCSI_OCP_SFF_ISO")
	)
	(segment
		(start 411.863794 -3.412998)
		(end 420.195248 -3.412998)
		(width 0.11684)
		(layer "In2.Cu")
		(net "CLK_50M_NCSI_OCP_SFF_ISO")
	)
	(segment
		(start 407.033476 -3.191256)
		(end 408.606752 -4.764532)
		(width 0.11684)
		(layer "In2.Cu")
		(net "CLK_50M_NCSI_OCP_SFF_ISO")
	)
	(segment
		(start 395.595348 -3.191256)
		(end 407.033476 -3.191256)
		(width 0.11684)
		(layer "In2.Cu")
		(net "CLK_50M_NCSI_OCP_SFF_ISO")
	)
	(segment
		(start 408.606752 -4.764532)
		(end 410.51226 -4.764532)
		(width 0.11684)
		(layer "In2.Cu")
		(net "CLK_50M_NCSI_OCP_SFF_ISO")
	)
	(segment
		(start 420.195248 -3.412998)
		(end 421.236648 -4.454398)
		(width 0.11684)
		(layer "In2.Cu")
		(net "CLK_50M_NCSI_OCP_SFF_ISO")
	)
	(segment
		(start 387.54812 -27.910536)
		(end 387.54812 -14.168628)
		(width 0.11684)
		(layer "In2.Cu")
		(net "CLK_50M_NCSI_OCP_SFF_ISO")
	)
	(segment
		(start 387.54812 -14.168628)
		(end 391.356088 -10.36066)
		(width 0.11684)
		(layer "In2.Cu")
		(net "CLK_50M_NCSI_OCP_SFF_ISO")
	)
	(segment
		(start 410.51226 -4.764532)
		(end 411.863794 -3.412998)
		(width 0.11684)
		(layer "In2.Cu")
		(net "CLK_50M_NCSI_OCP_SFF_ISO")
	)
	(segment
		(start 391.356088 -10.36066)
		(end 391.356088 -7.430516)
		(width 0.11684)
		(layer "In2.Cu")
		(net "CLK_50M_NCSI_OCP_SFF_ISO")
	)
	(segment
		(start 385.026916 -30.43174)
		(end 387.54812 -27.910536)
		(width 0.11684)
		(layer "In2.Cu")
		(net "CLK_50M_NCSI_OCP_SFF_ISO")
	)
	(segment
		(start 211.21116 -15.943072)
		(end 212.54212 -17.274032)
		(width 0.10668)
		(layer "F.Cu")
		(net "CLK_50M_NCSI_OCP_SFF")
	)
	(segment
		(start 381.620522 -32.278828)
		(end 381.203708 -32.278828)
		(width 0.10668)
		(layer "F.Cu")
		(net "CLK_50M_NCSI_OCP_SFF")
	)
	(segment
		(start 381.203708 -32.278828)
		(end 379.702314 -30.777434)
		(width 0.10668)
		(layer "F.Cu")
		(net "CLK_50M_NCSI_OCP_SFF")
	)
	(via
		(at 212.54212 -17.274032)
		(size 0.508)
		(drill 0.254)
		(layers "F.Cu" "B.Cu")
		(net "CLK_50M_NCSI_OCP_SFF")
	)
	(via
		(at 379.702314 -30.777434)
		(size 0.508)
		(drill 0.254)
		(layers "F.Cu" "B.Cu")
		(net "CLK_50M_NCSI_OCP_SFF")
	)
	(segment
		(start 379.702314 -30.777434)
		(end 373.433086 -24.508206)
		(width 0.11684)
		(layer "In2.Cu")
		(net "CLK_50M_NCSI_OCP_SFF")
	)
	(segment
		(start 242.597432 -41.111932)
		(end 241.146076 -42.563288)
		(width 0.11684)
		(layer "In2.Cu")
		(net "CLK_50M_NCSI_OCP_SFF")
	)
	(segment
		(start 312.902346 -17.46377)
		(end 309.219092 -21.147024)
		(width 0.11684)
		(layer "In2.Cu")
		(net "CLK_50M_NCSI_OCP_SFF")
	)
	(segment
		(start 235.383578 -42.563288)
		(end 234.05465 -41.23436)
		(width 0.11684)
		(layer "In2.Cu")
		(net "CLK_50M_NCSI_OCP_SFF")
	)
	(segment
		(start 220.558868 -22.41423)
		(end 215.41867 -17.274032)
		(width 0.11684)
		(layer "In2.Cu")
		(net "CLK_50M_NCSI_OCP_SFF")
	)
	(segment
		(start 234.05465 -41.23436)
		(end 232.179622 -41.23436)
		(width 0.11684)
		(layer "In2.Cu")
		(net "CLK_50M_NCSI_OCP_SFF")
	)
	(segment
		(start 241.146076 -42.563288)
		(end 235.383578 -42.563288)
		(width 0.11684)
		(layer "In2.Cu")
		(net "CLK_50M_NCSI_OCP_SFF")
	)
	(segment
		(start 220.558868 -35.804348)
		(end 220.558868 -22.41423)
		(width 0.11684)
		(layer "In2.Cu")
		(net "CLK_50M_NCSI_OCP_SFF")
	)
	(segment
		(start 349.951548 -25.566116)
		(end 336.981546 -25.566116)
		(width 0.11684)
		(layer "In2.Cu")
		(net "CLK_50M_NCSI_OCP_SFF")
	)
	(segment
		(start 223.88068 -39.12616)
		(end 220.558868 -35.804348)
		(width 0.11684)
		(layer "In2.Cu")
		(net "CLK_50M_NCSI_OCP_SFF")
	)
	(segment
		(start 215.41867 -17.274032)
		(end 212.54212 -17.274032)
		(width 0.11684)
		(layer "In2.Cu")
		(net "CLK_50M_NCSI_OCP_SFF")
	)
	(segment
		(start 282.422854 -21.147024)
		(end 265.294618 -38.27526)
		(width 0.11684)
		(layer "In2.Cu")
		(net "CLK_50M_NCSI_OCP_SFF")
	)
	(segment
		(start 336.981546 -25.566116)
		(end 332.258416 -20.842986)
		(width 0.11684)
		(layer "In2.Cu")
		(net "CLK_50M_NCSI_OCP_SFF")
	)
	(segment
		(start 332.258416 -20.842986)
		(end 329.602084 -20.842986)
		(width 0.11684)
		(layer "In2.Cu")
		(net "CLK_50M_NCSI_OCP_SFF")
	)
	(segment
		(start 230.071422 -39.12616)
		(end 223.88068 -39.12616)
		(width 0.11684)
		(layer "In2.Cu")
		(net "CLK_50M_NCSI_OCP_SFF")
	)
	(segment
		(start 309.219092 -21.147024)
		(end 282.422854 -21.147024)
		(width 0.11684)
		(layer "In2.Cu")
		(net "CLK_50M_NCSI_OCP_SFF")
	)
	(segment
		(start 244.288818 -41.111932)
		(end 242.597432 -41.111932)
		(width 0.11684)
		(layer "In2.Cu")
		(net "CLK_50M_NCSI_OCP_SFF")
	)
	(segment
		(start 373.433086 -24.508206)
		(end 351.009458 -24.508206)
		(width 0.11684)
		(layer "In2.Cu")
		(net "CLK_50M_NCSI_OCP_SFF")
	)
	(segment
		(start 232.179622 -41.23436)
		(end 230.071422 -39.12616)
		(width 0.11684)
		(layer "In2.Cu")
		(net "CLK_50M_NCSI_OCP_SFF")
	)
	(segment
		(start 265.294618 -38.27526)
		(end 247.12549 -38.27526)
		(width 0.11684)
		(layer "In2.Cu")
		(net "CLK_50M_NCSI_OCP_SFF")
	)
	(segment
		(start 351.009458 -24.508206)
		(end 349.951548 -25.566116)
		(width 0.11684)
		(layer "In2.Cu")
		(net "CLK_50M_NCSI_OCP_SFF")
	)
	(segment
		(start 326.222868 -17.46377)
		(end 312.902346 -17.46377)
		(width 0.11684)
		(layer "In2.Cu")
		(net "CLK_50M_NCSI_OCP_SFF")
	)
	(segment
		(start 247.12549 -38.27526)
		(end 244.288818 -41.111932)
		(width 0.11684)
		(layer "In2.Cu")
		(net "CLK_50M_NCSI_OCP_SFF")
	)
	(segment
		(start 329.602084 -20.842986)
		(end 326.222868 -17.46377)
		(width 0.11684)
		(layer "In2.Cu")
		(net "CLK_50M_NCSI_OCP_SFF")
	)
	(segment
		(start 214.669878 -14.845792)
		(end 214.669624 -14.845792)
		(width 0.10668)
		(layer "F.Cu")
		(net "CLK_50M_NCSI_OCP_2")
	)
	(segment
		(start 216.741248 -17.981422)
		(end 214.669878 -15.910052)
		(width 0.10668)
		(layer "F.Cu")
		(net "CLK_50M_NCSI_OCP_2")
	)
	(segment
		(start 217.58402 -16.781272)
		(end 217.58402 -17.981422)
		(width 0.10668)
		(layer "F.Cu")
		(net "CLK_50M_NCSI_OCP_2")
	)
	(segment
		(start 217.58402 -17.981422)
		(end 216.741248 -17.981422)
		(width 0.10668)
		(layer "F.Cu")
		(net "CLK_50M_NCSI_OCP_2")
	)
	(segment
		(start 214.669878 -15.910052)
		(end 214.669878 -14.845792)
		(width 0.10668)
		(layer "F.Cu")
		(net "CLK_50M_NCSI_OCP_2")
	)
	(via
		(at 217.58402 -17.981422)
		(size 0.762)
		(drill 0.381)
		(layers "F.Cu" "B.Cu")
		(net "CLK_50M_NCSI_OCP_2")
	)
	(segment
		(start 213.369652 -17.40916)
		(end 212.733128 -18.045684)
		(width 0.10668)
		(layer "F.Cu")
		(net "CLK_50M_NCSI_OCP_1")
	)
	(segment
		(start 213.369398 -14.845792)
		(end 213.369652 -14.845792)
		(width 0.10668)
		(layer "F.Cu")
		(net "CLK_50M_NCSI_OCP_1")
	)
	(segment
		(start 211.313522 -18.045684)
		(end 211.21116 -17.943322)
		(width 0.10668)
		(layer "F.Cu")
		(net "CLK_50M_NCSI_OCP_1")
	)
	(segment
		(start 211.21116 -16.743172)
		(end 211.21116 -17.943322)
		(width 0.10668)
		(layer "F.Cu")
		(net "CLK_50M_NCSI_OCP_1")
	)
	(segment
		(start 212.733128 -18.045684)
		(end 211.313522 -18.045684)
		(width 0.10668)
		(layer "F.Cu")
		(net "CLK_50M_NCSI_OCP_1")
	)
	(segment
		(start 213.369652 -14.845792)
		(end 213.369652 -17.40916)
		(width 0.10668)
		(layer "F.Cu")
		(net "CLK_50M_NCSI_OCP_1")
	)
	(via
		(at 211.21116 -17.943322)
		(size 0.762)
		(drill 0.381)
		(layers "F.Cu" "B.Cu")
		(net "CLK_50M_NCSI_OCP_1")
	)
	(segment
		(start 215.111584 -22.103334)
		(end 215.111584 -23.206964)
		(width 0.10668)
		(layer "F.Cu")
		(net "CLK_50M_EN")
	)
	(segment
		(start 213.802468 -25.201626)
		(end 213.762336 -25.161494)
		(width 0.10668)
		(layer "F.Cu")
		(net "CLK_50M_EN")
	)
	(segment
		(start 215.111584 -23.206964)
		(end 214.613744 -23.704804)
		(width 0.10668)
		(layer "F.Cu")
		(net "CLK_50M_EN")
	)
	(segment
		(start 213.762336 -25.161494)
		(end 213.762336 -23.922228)
		(width 0.10668)
		(layer "F.Cu")
		(net "CLK_50M_EN")
	)
	(segment
		(start 213.97976 -23.704804)
		(end 213.76259 -23.921974)
		(width 0.10668)
		(layer "F.Cu")
		(net "CLK_50M_EN")
	)
	(segment
		(start 214.669624 -20.687792)
		(end 214.669624 -21.661374)
		(width 0.10668)
		(layer "F.Cu")
		(net "CLK_50M_EN")
	)
	(segment
		(start 214.669624 -21.661374)
		(end 215.111584 -22.103334)
		(width 0.10668)
		(layer "F.Cu")
		(net "CLK_50M_EN")
	)
	(segment
		(start 214.613744 -23.704804)
		(end 213.97976 -23.704804)
		(width 0.10668)
		(layer "F.Cu")
		(net "CLK_50M_EN")
	)
	(segment
		(start 213.802468 -25.311354)
		(end 213.802468 -25.201626)
		(width 0.10668)
		(layer "F.Cu")
		(net "CLK_50M_EN")
	)
	(segment
		(start 213.762336 -23.922228)
		(end 213.76259 -23.921974)
		(width 0.10668)
		(layer "F.Cu")
		(net "CLK_50M_EN")
	)
	(via
		(at 213.76259 -23.921974)
		(size 0.508)
		(drill 0.254)
		(layers "F.Cu" "B.Cu")
		(net "CLK_50M_EN")
	)
	(segment
		(start 213.334346 -22.847046)
		(end 213.461854 -22.974554)
		(width 0.10668)
		(layer "F.Cu")
		(net "CLK_50M_BMC_MAC_R")
	)
	(segment
		(start 213.334346 -22.160992)
		(end 214.019384 -21.475954)
		(width 0.10668)
		(layer "F.Cu")
		(net "CLK_50M_BMC_MAC_R")
	)
	(segment
		(start 213.334346 -22.160992)
		(end 213.334346 -22.847046)
		(width 0.10668)
		(layer "F.Cu")
		(net "CLK_50M_BMC_MAC_R")
	)
	(segment
		(start 214.019384 -21.475954)
		(end 214.019384 -20.687792)
		(width 0.10668)
		(layer "F.Cu")
		(net "CLK_50M_BMC_MAC_R")
	)
	(via
		(at 213.334346 -22.160992)
		(size 0.508)
		(drill 0.254)
		(layers "F.Cu" "B.Cu")
		(net "CLK_50M_BMC_MAC_R")
	)
	(segment
		(start 347.71965 -219.463366)
		(end 339.503766 -218.654122)
		(width 0.12954)
		(layer "F.Cu")
		(net "CLK_100M_REF_OUT_DP")
	)
	(segment
		(start 376.799348 -221.126304)
		(end 376.202702 -220.529658)
		(width 0.12954)
		(layer "F.Cu")
		(net "CLK_100M_REF_OUT_DP")
	)
	(segment
		(start 376.799348 -221.761558)
		(end 376.799348 -221.126304)
		(width 0.12954)
		(layer "F.Cu")
		(net "CLK_100M_REF_OUT_DP")
	)
	(segment
		(start 377.107958 -222.070168)
		(end 376.799348 -221.761558)
		(width 0.12954)
		(layer "F.Cu")
		(net "CLK_100M_REF_OUT_DP")
	)
	(segment
		(start 339.203538 -218.353894)
		(end 339.203538 -217.867992)
		(width 0.12954)
		(layer "F.Cu")
		(net "CLK_100M_REF_OUT_DP")
	)
	(segment
		(start 339.503766 -218.654122)
		(end 339.203538 -218.353894)
		(width 0.12954)
		(layer "F.Cu")
		(net "CLK_100M_REF_OUT_DP")
	)
	(segment
		(start 365.375444 -219.463366)
		(end 347.71965 -219.463366)
		(width 0.12954)
		(layer "F.Cu")
		(net "CLK_100M_REF_OUT_DP")
	)
	(segment
		(start 339.203538 -217.867992)
		(end 339.550248 -217.521282)
		(width 0.12954)
		(layer "F.Cu")
		(net "CLK_100M_REF_OUT_DP")
	)
	(segment
		(start 376.202702 -220.529658)
		(end 365.375444 -219.463366)
		(width 0.12954)
		(layer "F.Cu")
		(net "CLK_100M_REF_OUT_DP")
	)
	(via
		(at 339.550248 -217.521282)
		(size 0.508)
		(drill 0.254)
		(layers "F.Cu" "B.Cu")
		(net "CLK_100M_REF_OUT_DP")
	)
	(segment
		(start 339.220048 -217.191082)
		(end 339.550248 -217.521282)
		(width 0.12954)
		(layer "B.Cu")
		(net "CLK_100M_REF_OUT_DP")
	)
	(segment
		(start 339.220048 -215.627712)
		(end 339.220048 -217.191082)
		(width 0.12954)
		(layer "B.Cu")
		(net "CLK_100M_REF_OUT_DP")
	)
	(segment
		(start 339.566758 -215.281002)
		(end 339.220048 -215.627712)
		(width 0.12954)
		(layer "B.Cu")
		(net "CLK_100M_REF_OUT_DP")
	)
	(segment
		(start 376.167904 -222.070168)
		(end 376.476768 -221.761304)
		(width 0.12954)
		(layer "F.Cu")
		(net "CLK_100M_REF_OUT_DN")
	)
	(segment
		(start 376.056144 -220.839538)
		(end 365.359442 -219.785946)
		(width 0.12954)
		(layer "F.Cu")
		(net "CLK_100M_REF_OUT_DN")
	)
	(segment
		(start 339.357208 -218.964002)
		(end 338.880958 -218.487752)
		(width 0.12954)
		(layer "F.Cu")
		(net "CLK_100M_REF_OUT_DN")
	)
	(segment
		(start 376.476768 -221.761304)
		(end 376.476768 -221.260162)
		(width 0.12954)
		(layer "F.Cu")
		(net "CLK_100M_REF_OUT_DN")
	)
	(segment
		(start 338.880958 -218.487752)
		(end 338.880958 -217.867992)
		(width 0.12954)
		(layer "F.Cu")
		(net "CLK_100M_REF_OUT_DN")
	)
	(segment
		(start 338.880958 -217.867992)
		(end 338.534248 -217.521282)
		(width 0.12954)
		(layer "F.Cu")
		(net "CLK_100M_REF_OUT_DN")
	)
	(segment
		(start 376.476768 -221.260162)
		(end 376.056144 -220.839538)
		(width 0.12954)
		(layer "F.Cu")
		(net "CLK_100M_REF_OUT_DN")
	)
	(segment
		(start 347.703648 -219.785946)
		(end 339.357208 -218.964002)
		(width 0.12954)
		(layer "F.Cu")
		(net "CLK_100M_REF_OUT_DN")
	)
	(segment
		(start 365.359442 -219.785946)
		(end 347.703648 -219.785946)
		(width 0.12954)
		(layer "F.Cu")
		(net "CLK_100M_REF_OUT_DN")
	)
	(via
		(at 338.534248 -217.521282)
		(size 0.508)
		(drill 0.254)
		(layers "F.Cu" "B.Cu")
		(net "CLK_100M_REF_OUT_DN")
	)
	(segment
		(start 338.897468 -215.627712)
		(end 338.897468 -217.158062)
		(width 0.12954)
		(layer "B.Cu")
		(net "CLK_100M_REF_OUT_DN")
	)
	(segment
		(start 338.550758 -215.281002)
		(end 338.897468 -215.627712)
		(width 0.12954)
		(layer "B.Cu")
		(net "CLK_100M_REF_OUT_DN")
	)
	(segment
		(start 338.897468 -217.158062)
		(end 338.534248 -217.521282)
		(width 0.12954)
		(layer "B.Cu")
		(net "CLK_100M_REF_OUT_DN")
	)
	(segment
		(start 129.07518 -221.19971)
		(end 129.866644 -220.871796)
		(width 0.12954)
		(layer "F.Cu")
		(net "CLK_100M_REF_IN_DP")
	)
	(segment
		(start 130.100578 -220.139768)
		(end 130.447288 -219.793058)
		(width 0.12954)
		(layer "F.Cu")
		(net "CLK_100M_REF_IN_DP")
	)
	(segment
		(start 128.85928 -221.761812)
		(end 128.85928 -221.41561)
		(width 0.12954)
		(layer "F.Cu")
		(net "CLK_100M_REF_IN_DP")
	)
	(segment
		(start 130.100578 -220.637862)
		(end 130.100578 -220.139768)
		(width 0.12954)
		(layer "F.Cu")
		(net "CLK_100M_REF_IN_DP")
	)
	(segment
		(start 129.16789 -222.070422)
		(end 128.85928 -221.761812)
		(width 0.12954)
		(layer "F.Cu")
		(net "CLK_100M_REF_IN_DP")
	)
	(segment
		(start 128.85928 -221.41561)
		(end 129.07518 -221.19971)
		(width 0.12954)
		(layer "F.Cu")
		(net "CLK_100M_REF_IN_DP")
	)
	(segment
		(start 129.866644 -220.871796)
		(end 130.100578 -220.637862)
		(width 0.12954)
		(layer "F.Cu")
		(net "CLK_100M_REF_IN_DP")
	)
	(via
		(at 130.447288 -219.793058)
		(size 0.508)
		(drill 0.254)
		(layers "F.Cu" "B.Cu")
		(net "CLK_100M_REF_IN_DP")
	)
	(segment
		(start 339.566758 -214.480902)
		(end 339.220048 -214.134192)
		(width 0.12954)
		(layer "B.Cu")
		(net "CLK_100M_REF_IN_DP")
	)
	(segment
		(start 128.338072 -220.778832)
		(end 129.77876 -220.778832)
		(width 0.12954)
		(layer "B.Cu")
		(net "CLK_100M_REF_IN_DP")
	)
	(segment
		(start 127.61976 -212.040978)
		(end 127.61976 -220.06052)
		(width 0.12954)
		(layer "B.Cu")
		(net "CLK_100M_REF_IN_DP")
	)
	(segment
		(start 147.833842 -191.826896)
		(end 127.61976 -212.040978)
		(width 0.12954)
		(layer "B.Cu")
		(net "CLK_100M_REF_IN_DP")
	)
	(segment
		(start 130.100578 -220.139768)
		(end 130.447288 -219.793058)
		(width 0.12954)
		(layer "B.Cu")
		(net "CLK_100M_REF_IN_DP")
	)
	(segment
		(start 149.92477 -191.826896)
		(end 147.833842 -191.826896)
		(width 0.12954)
		(layer "B.Cu")
		(net "CLK_100M_REF_IN_DP")
	)
	(segment
		(start 127.61976 -220.06052)
		(end 128.338072 -220.778832)
		(width 0.12954)
		(layer "B.Cu")
		(net "CLK_100M_REF_IN_DP")
	)
	(segment
		(start 208.35747 -181.054756)
		(end 188.167264 -180.691282)
		(width 0.12954)
		(layer "B.Cu")
		(net "CLK_100M_REF_IN_DP")
	)
	(segment
		(start 167.982646 -180.327808)
		(end 164.19068 -180.327808)
		(width 0.12954)
		(layer "B.Cu")
		(net "CLK_100M_REF_IN_DP")
	)
	(segment
		(start 308.145942 -185.36031)
		(end 301.915322 -183.966866)
		(width 0.12954)
		(layer "B.Cu")
		(net "CLK_100M_REF_IN_DP")
	)
	(segment
		(start 129.77876 -220.778832)
		(end 130.100578 -220.457014)
		(width 0.12954)
		(layer "B.Cu")
		(net "CLK_100M_REF_IN_DP")
	)
	(segment
		(start 301.915322 -183.966866)
		(end 233.284522 -182.730648)
		(width 0.12954)
		(layer "B.Cu")
		(net "CLK_100M_REF_IN_DP")
	)
	(segment
		(start 188.167264 -180.691282)
		(end 188.167264 -180.691028)
		(width 0.12954)
		(layer "B.Cu")
		(net "CLK_100M_REF_IN_DP")
	)
	(segment
		(start 164.19068 -180.327808)
		(end 159.467296 -182.28437)
		(width 0.12954)
		(layer "B.Cu")
		(net "CLK_100M_REF_IN_DP")
	)
	(segment
		(start 130.100578 -220.457014)
		(end 130.100578 -220.139768)
		(width 0.12954)
		(layer "B.Cu")
		(net "CLK_100M_REF_IN_DP")
	)
	(segment
		(start 339.220048 -207.936084)
		(end 323.5706 -192.286382)
		(width 0.12954)
		(layer "B.Cu")
		(net "CLK_100M_REF_IN_DP")
	)
	(segment
		(start 159.467296 -182.28437)
		(end 149.92477 -191.826896)
		(width 0.12954)
		(layer "B.Cu")
		(net "CLK_100M_REF_IN_DP")
	)
	(segment
		(start 339.220048 -214.134192)
		(end 339.220048 -207.936084)
		(width 0.12954)
		(layer "B.Cu")
		(net "CLK_100M_REF_IN_DP")
	)
	(segment
		(start 233.284522 -182.730648)
		(end 208.35747 -181.054756)
		(width 0.12954)
		(layer "B.Cu")
		(net "CLK_100M_REF_IN_DP")
	)
	(segment
		(start 318.898016 -190.188596)
		(end 308.145942 -185.36031)
		(width 0.12954)
		(layer "B.Cu")
		(net "CLK_100M_REF_IN_DP")
	)
	(segment
		(start 323.5706 -192.286382)
		(end 318.898016 -190.188596)
		(width 0.12954)
		(layer "B.Cu")
		(net "CLK_100M_REF_IN_DP")
	)
	(segment
		(start 188.167264 -180.691028)
		(end 167.982646 -180.327808)
		(width 0.12954)
		(layer "B.Cu")
		(net "CLK_100M_REF_IN_DP")
	)
	(segment
		(start 129.777998 -220.504004)
		(end 129.777998 -220.139768)
		(width 0.12954)
		(layer "F.Cu")
		(net "CLK_100M_REF_IN_DN")
	)
	(segment
		(start 129.683764 -220.598238)
		(end 129.777998 -220.504004)
		(width 0.12954)
		(layer "F.Cu")
		(net "CLK_100M_REF_IN_DN")
	)
	(segment
		(start 129.777998 -220.139768)
		(end 129.431288 -219.793058)
		(width 0.12954)
		(layer "F.Cu")
		(net "CLK_100M_REF_IN_DN")
	)
	(segment
		(start 128.5367 -221.761558)
		(end 128.5367 -221.281752)
		(width 0.12954)
		(layer "F.Cu")
		(net "CLK_100M_REF_IN_DN")
	)
	(segment
		(start 128.227836 -222.070422)
		(end 128.5367 -221.761558)
		(width 0.12954)
		(layer "F.Cu")
		(net "CLK_100M_REF_IN_DN")
	)
	(segment
		(start 128.8923 -220.926152)
		(end 129.683764 -220.598238)
		(width 0.12954)
		(layer "F.Cu")
		(net "CLK_100M_REF_IN_DN")
	)
	(segment
		(start 128.5367 -221.281752)
		(end 128.8923 -220.926152)
		(width 0.12954)
		(layer "F.Cu")
		(net "CLK_100M_REF_IN_DN")
	)
	(via
		(at 129.431288 -219.793058)
		(size 0.508)
		(drill 0.254)
		(layers "F.Cu" "B.Cu")
		(net "CLK_100M_REF_IN_DN")
	)
	(segment
		(start 318.159384 -190.419482)
		(end 318.063626 -190.167514)
		(width 0.12954)
		(layer "B.Cu")
		(net "CLK_100M_REF_IN_DN")
	)
	(segment
		(start 318.063626 -190.167514)
		(end 308.04358 -185.668158)
		(width 0.12954)
		(layer "B.Cu")
		(net "CLK_100M_REF_IN_DN")
	)
	(segment
		(start 318.765936 -190.482982)
		(end 318.514222 -190.57874)
		(width 0.12954)
		(layer "B.Cu")
		(net "CLK_100M_REF_IN_DN")
	)
	(segment
		(start 319.216024 -190.894208)
		(end 319.120266 -190.641986)
		(width 0.12954)
		(layer "B.Cu")
		(net "CLK_100M_REF_IN_DN")
	)
	(segment
		(start 233.270806 -183.053228)
		(end 208.343754 -181.377336)
		(width 0.12954)
		(layer "B.Cu")
		(net "CLK_100M_REF_IN_DN")
	)
	(segment
		(start 127.94234 -215.134698)
		(end 127.94234 -215.527128)
		(width 0.12954)
		(layer "B.Cu")
		(net "CLK_100M_REF_IN_DN")
	)
	(segment
		(start 338.706968 -210.186016)
		(end 338.706968 -209.799936)
		(width 0.12954)
		(layer "B.Cu")
		(net "CLK_100M_REF_IN_DN")
	)
	(segment
		(start 127.94234 -217.833448)
		(end 128.13284 -218.023948)
		(width 0.12954)
		(layer "B.Cu")
		(net "CLK_100M_REF_IN_DN")
	)
	(segment
		(start 128.47193 -220.456252)
		(end 129.644902 -220.456252)
		(width 0.12954)
		(layer "B.Cu")
		(net "CLK_100M_REF_IN_DN")
	)
	(segment
		(start 129.189226 -210.92795)
		(end 128.91643 -211.200746)
		(width 0.12954)
		(layer "B.Cu")
		(net "CLK_100M_REF_IN_DN")
	)
	(segment
		(start 127.94234 -217.447368)
		(end 127.94234 -217.833448)
		(width 0.12954)
		(layer "B.Cu")
		(net "CLK_100M_REF_IN_DN")
	)
	(segment
		(start 129.777998 -220.139768)
		(end 129.431288 -219.793058)
		(width 0.12954)
		(layer "B.Cu")
		(net "CLK_100M_REF_IN_DN")
	)
	(segment
		(start 128.13284 -213.285324)
		(end 128.13284 -213.671404)
		(width 0.12954)
		(layer "B.Cu")
		(net "CLK_100M_REF_IN_DN")
	)
	(segment
		(start 338.897468 -209.223356)
		(end 338.706968 -209.032856)
		(width 0.12954)
		(layer "B.Cu")
		(net "CLK_100M_REF_IN_DN")
	)
	(segment
		(start 127.94234 -214.367618)
		(end 128.13284 -214.558118)
		(width 0.12954)
		(layer "B.Cu")
		(net "CLK_100M_REF_IN_DN")
	)
	(segment
		(start 127.94234 -218.600528)
		(end 127.94234 -219.926662)
		(width 0.12954)
		(layer "B.Cu")
		(net "CLK_100M_REF_IN_DN")
	)
	(segment
		(start 323.384164 -192.556638)
		(end 319.822576 -190.957454)
		(width 0.12954)
		(layer "B.Cu")
		(net "CLK_100M_REF_IN_DN")
	)
	(segment
		(start 128.91643 -211.200746)
		(end 128.91643 -211.469986)
		(width 0.12954)
		(layer "B.Cu")
		(net "CLK_100M_REF_IN_DN")
	)
	(segment
		(start 128.91643 -211.469986)
		(end 128.643126 -211.74329)
		(width 0.12954)
		(layer "B.Cu")
		(net "CLK_100M_REF_IN_DN")
	)
	(segment
		(start 129.644902 -220.456252)
		(end 129.777998 -220.323156)
		(width 0.12954)
		(layer "B.Cu")
		(net "CLK_100M_REF_IN_DN")
	)
	(segment
		(start 319.822576 -190.957454)
		(end 319.570862 -191.053212)
		(width 0.12954)
		(layer "B.Cu")
		(net "CLK_100M_REF_IN_DN")
	)
	(segment
		(start 128.13284 -216.103708)
		(end 127.94234 -216.294208)
		(width 0.12954)
		(layer "B.Cu")
		(net "CLK_100M_REF_IN_DN")
	)
	(segment
		(start 127.94234 -212.174836)
		(end 127.94234 -213.094824)
		(width 0.12954)
		(layer "B.Cu")
		(net "CLK_100M_REF_IN_DN")
	)
	(segment
		(start 150.058628 -192.149476)
		(end 147.9677 -192.149476)
		(width 0.12954)
		(layer "B.Cu")
		(net "CLK_100M_REF_IN_DN")
	)
	(segment
		(start 319.120266 -190.641986)
		(end 318.765936 -190.482982)
		(width 0.12954)
		(layer "B.Cu")
		(net "CLK_100M_REF_IN_DN")
	)
	(segment
		(start 128.13284 -216.870788)
		(end 128.13284 -217.256868)
		(width 0.12954)
		(layer "B.Cu")
		(net "CLK_100M_REF_IN_DN")
	)
	(segment
		(start 338.897468 -214.134192)
		(end 338.897468 -212.682836)
		(width 0.12954)
		(layer "B.Cu")
		(net "CLK_100M_REF_IN_DN")
	)
	(segment
		(start 128.13284 -213.671404)
		(end 127.94234 -213.861904)
		(width 0.12954)
		(layer "B.Cu")
		(net "CLK_100M_REF_IN_DN")
	)
	(segment
		(start 338.897468 -210.376516)
		(end 338.706968 -210.186016)
		(width 0.12954)
		(layer "B.Cu")
		(net "CLK_100M_REF_IN_DN")
	)
	(segment
		(start 129.732024 -210.654646)
		(end 129.45872 -210.92795)
		(width 0.12954)
		(layer "B.Cu")
		(net "CLK_100M_REF_IN_DN")
	)
	(segment
		(start 338.897468 -209.609436)
		(end 338.897468 -209.223356)
		(width 0.12954)
		(layer "B.Cu")
		(net "CLK_100M_REF_IN_DN")
	)
	(segment
		(start 167.979598 -180.650388)
		(end 164.254942 -180.650388)
		(width 0.12954)
		(layer "B.Cu")
		(net "CLK_100M_REF_IN_DN")
	)
	(segment
		(start 128.373886 -211.74329)
		(end 127.94234 -212.174836)
		(width 0.12954)
		(layer "B.Cu")
		(net "CLK_100M_REF_IN_DN")
	)
	(segment
		(start 128.13284 -214.944198)
		(end 127.94234 -215.134698)
		(width 0.12954)
		(layer "B.Cu")
		(net "CLK_100M_REF_IN_DN")
	)
	(segment
		(start 127.94234 -216.294208)
		(end 127.94234 -216.680288)
		(width 0.12954)
		(layer "B.Cu")
		(net "CLK_100M_REF_IN_DN")
	)
	(segment
		(start 128.13284 -215.717628)
		(end 128.13284 -216.103708)
		(width 0.12954)
		(layer "B.Cu")
		(net "CLK_100M_REF_IN_DN")
	)
	(segment
		(start 127.94234 -213.094824)
		(end 128.13284 -213.285324)
		(width 0.12954)
		(layer "B.Cu")
		(net "CLK_100M_REF_IN_DN")
	)
	(segment
		(start 128.13284 -214.558118)
		(end 128.13284 -214.944198)
		(width 0.12954)
		(layer "B.Cu")
		(net "CLK_100M_REF_IN_DN")
	)
	(segment
		(start 127.94234 -215.527128)
		(end 128.13284 -215.717628)
		(width 0.12954)
		(layer "B.Cu")
		(net "CLK_100M_REF_IN_DN")
	)
	(segment
		(start 338.706968 -211.339176)
		(end 338.706968 -210.953096)
		(width 0.12954)
		(layer "B.Cu")
		(net "CLK_100M_REF_IN_DN")
	)
	(segment
		(start 159.650176 -182.557928)
		(end 150.058628 -192.149476)
		(width 0.12954)
		(layer "B.Cu")
		(net "CLK_100M_REF_IN_DN")
	)
	(segment
		(start 338.706968 -212.106256)
		(end 338.897468 -211.915756)
		(width 0.12954)
		(layer "B.Cu")
		(net "CLK_100M_REF_IN_DN")
	)
	(segment
		(start 164.254942 -180.650388)
		(end 159.650176 -182.557928)
		(width 0.12954)
		(layer "B.Cu")
		(net "CLK_100M_REF_IN_DN")
	)
	(segment
		(start 338.706968 -212.492336)
		(end 338.706968 -212.106256)
		(width 0.12954)
		(layer "B.Cu")
		(net "CLK_100M_REF_IN_DN")
	)
	(segment
		(start 147.9677 -192.149476)
		(end 129.732024 -210.385152)
		(width 0.12954)
		(layer "B.Cu")
		(net "CLK_100M_REF_IN_DN")
	)
	(segment
		(start 129.45872 -210.92795)
		(end 129.189226 -210.92795)
		(width 0.12954)
		(layer "B.Cu")
		(net "CLK_100M_REF_IN_DN")
	)
	(segment
		(start 129.777998 -220.323156)
		(end 129.777998 -220.139768)
		(width 0.12954)
		(layer "B.Cu")
		(net "CLK_100M_REF_IN_DN")
	)
	(segment
		(start 338.706968 -208.646776)
		(end 338.897468 -208.456276)
		(width 0.12954)
		(layer "B.Cu")
		(net "CLK_100M_REF_IN_DN")
	)
	(segment
		(start 318.514222 -190.57874)
		(end 318.159384 -190.419482)
		(width 0.12954)
		(layer "B.Cu")
		(net "CLK_100M_REF_IN_DN")
	)
	(segment
		(start 129.732024 -210.385152)
		(end 129.732024 -210.654646)
		(width 0.12954)
		(layer "B.Cu")
		(net "CLK_100M_REF_IN_DN")
	)
	(segment
		(start 338.706968 -210.953096)
		(end 338.897468 -210.762596)
		(width 0.12954)
		(layer "B.Cu")
		(net "CLK_100M_REF_IN_DN")
	)
	(segment
		(start 319.570862 -191.053212)
		(end 319.216024 -190.894208)
		(width 0.12954)
		(layer "B.Cu")
		(net "CLK_100M_REF_IN_DN")
	)
	(segment
		(start 338.897468 -212.682836)
		(end 338.706968 -212.492336)
		(width 0.12954)
		(layer "B.Cu")
		(net "CLK_100M_REF_IN_DN")
	)
	(segment
		(start 128.13284 -218.023948)
		(end 128.13284 -218.410028)
		(width 0.12954)
		(layer "B.Cu")
		(net "CLK_100M_REF_IN_DN")
	)
	(segment
		(start 338.706968 -209.799936)
		(end 338.897468 -209.609436)
		(width 0.12954)
		(layer "B.Cu")
		(net "CLK_100M_REF_IN_DN")
	)
	(segment
		(start 338.897468 -208.456276)
		(end 338.897468 -208.070196)
		(width 0.12954)
		(layer "B.Cu")
		(net "CLK_100M_REF_IN_DN")
	)
	(segment
		(start 127.94234 -213.861904)
		(end 127.94234 -214.367618)
		(width 0.12954)
		(layer "B.Cu")
		(net "CLK_100M_REF_IN_DN")
	)
	(segment
		(start 338.706968 -209.032856)
		(end 338.706968 -208.646776)
		(width 0.12954)
		(layer "B.Cu")
		(net "CLK_100M_REF_IN_DN")
	)
	(segment
		(start 127.94234 -219.926662)
		(end 128.47193 -220.456252)
		(width 0.12954)
		(layer "B.Cu")
		(net "CLK_100M_REF_IN_DN")
	)
	(segment
		(start 338.897468 -210.762596)
		(end 338.897468 -210.376516)
		(width 0.12954)
		(layer "B.Cu")
		(net "CLK_100M_REF_IN_DN")
	)
	(segment
		(start 128.13284 -218.410028)
		(end 127.94234 -218.600528)
		(width 0.12954)
		(layer "B.Cu")
		(net "CLK_100M_REF_IN_DN")
	)
	(segment
		(start 208.343754 -181.377336)
		(end 167.979598 -180.650388)
		(width 0.12954)
		(layer "B.Cu")
		(net "CLK_100M_REF_IN_DN")
	)
	(segment
		(start 301.876714 -184.288938)
		(end 233.270806 -183.053228)
		(width 0.12954)
		(layer "B.Cu")
		(net "CLK_100M_REF_IN_DN")
	)
	(segment
		(start 128.13284 -217.256868)
		(end 127.94234 -217.447368)
		(width 0.12954)
		(layer "B.Cu")
		(net "CLK_100M_REF_IN_DN")
	)
	(segment
		(start 338.550758 -214.480902)
		(end 338.897468 -214.134192)
		(width 0.12954)
		(layer "B.Cu")
		(net "CLK_100M_REF_IN_DN")
	)
	(segment
		(start 338.897468 -211.915756)
		(end 338.897468 -211.529676)
		(width 0.12954)
		(layer "B.Cu")
		(net "CLK_100M_REF_IN_DN")
	)
	(segment
		(start 127.94234 -216.680288)
		(end 128.13284 -216.870788)
		(width 0.12954)
		(layer "B.Cu")
		(net "CLK_100M_REF_IN_DN")
	)
	(segment
		(start 338.897468 -208.070196)
		(end 323.384164 -192.556638)
		(width 0.12954)
		(layer "B.Cu")
		(net "CLK_100M_REF_IN_DN")
	)
	(segment
		(start 128.643126 -211.74329)
		(end 128.373886 -211.74329)
		(width 0.12954)
		(layer "B.Cu")
		(net "CLK_100M_REF_IN_DN")
	)
	(segment
		(start 338.897468 -211.529676)
		(end 338.706968 -211.339176)
		(width 0.12954)
		(layer "B.Cu")
		(net "CLK_100M_REF_IN_DN")
	)
	(segment
		(start 308.04358 -185.668158)
		(end 301.876714 -184.288938)
		(width 0.12954)
		(layer "B.Cu")
		(net "CLK_100M_REF_IN_DN")
	)
	(segment
		(start 20.092162 -137.319512)
		(end 19.436842 -137.319512)
		(width 0.12954)
		(layer "F.Cu")
		(net "CLK_100M_GPU_FPGA_DP")
	)
	(segment
		(start 19.436842 -137.319512)
		(end 19.102832 -136.985502)
		(width 0.12954)
		(layer "F.Cu")
		(net "CLK_100M_GPU_FPGA_DP")
	)
	(segment
		(start 20.400772 -137.010902)
		(end 20.092162 -137.319512)
		(width 0.12954)
		(layer "F.Cu")
		(net "CLK_100M_GPU_FPGA_DP")
	)
	(segment
		(start 60.190888 -420.348918)
		(end 60.649866 -419.88994)
		(width 0.14224)
		(layer "In2.Cu")
		(net "CLK_100M_GPU_FPGA_DP")
	)
	(segment
		(start 59.98972 -420.348918)
		(end 60.190888 -420.348918)
		(width 0.14224)
		(layer "In2.Cu")
		(net "CLK_100M_GPU_FPGA_DP")
	)
	(segment
		(start 49.485296 -416.864038)
		(end 57.574688 -416.864038)
		(width 0.14224)
		(layer "In2.Cu")
		(net "CLK_100M_GPU_FPGA_DP")
	)
	(segment
		(start 57.687718 -416.751008)
		(end 59.196224 -416.751008)
		(width 0.14224)
		(layer "In2.Cu")
		(net "CLK_100M_GPU_FPGA_DP")
	)
	(segment
		(start 59.84748 -417.402264)
		(end 59.84748 -420.206678)
		(width 0.14224)
		(layer "In2.Cu")
		(net "CLK_100M_GPU_FPGA_DP")
	)
	(segment
		(start 57.574688 -416.864038)
		(end 57.687718 -416.751008)
		(width 0.14224)
		(layer "In2.Cu")
		(net "CLK_100M_GPU_FPGA_DP")
	)
	(segment
		(start 59.84748 -420.206678)
		(end 59.98972 -420.348918)
		(width 0.14224)
		(layer "In2.Cu")
		(net "CLK_100M_GPU_FPGA_DP")
	)
	(segment
		(start 59.196224 -416.751008)
		(end 59.84748 -417.402264)
		(width 0.14224)
		(layer "In2.Cu")
		(net "CLK_100M_GPU_FPGA_DP")
	)
	(segment
		(start 49.194466 -416.573208)
		(end 49.485296 -416.864038)
		(width 0.14224)
		(layer "In2.Cu")
		(net "CLK_100M_GPU_FPGA_DP")
	)
	(segment
		(start 14.097 -167.894)
		(end 8.382 -167.894)
		(width 0.14224)
		(layer "In15.Cu")
		(net "CLK_100M_GPU_FPGA_DP")
	)
	(segment
		(start 17.68094 -164.31006)
		(end 14.097 -167.894)
		(width 0.14224)
		(layer "In15.Cu")
		(net "CLK_100M_GPU_FPGA_DP")
	)
	(segment
		(start 37.082476 -395.397736)
		(end 37.082476 -407.450798)
		(width 0.14224)
		(layer "In15.Cu")
		(net "CLK_100M_GPU_FPGA_DP")
	)
	(segment
		(start 23.885398 -349.350838)
		(end 18.74266 -355.617018)
		(width 0.14224)
		(layer "In15.Cu")
		(net "CLK_100M_GPU_FPGA_DP")
	)
	(segment
		(start 21.377656 -139.390628)
		(end 17.68094 -164.31006)
		(width 0.14224)
		(layer "In15.Cu")
		(net "CLK_100M_GPU_FPGA_DP")
	)
	(segment
		(start 20.973034 -137.365232)
		(end 21.377656 -137.769854)
		(width 0.14224)
		(layer "In15.Cu")
		(net "CLK_100M_GPU_FPGA_DP")
	)
	(segment
		(start 38.735508 -391.406634)
		(end 37.082476 -395.397736)
		(width 0.14224)
		(layer "In15.Cu")
		(net "CLK_100M_GPU_FPGA_DP")
	)
	(segment
		(start 30.635702 -379.268482)
		(end 38.735508 -387.368288)
		(width 0.14224)
		(layer "In15.Cu")
		(net "CLK_100M_GPU_FPGA_DP")
	)
	(segment
		(start 12.530328 -330.263754)
		(end 17.636998 -342.5952)
		(width 0.14224)
		(layer "In15.Cu")
		(net "CLK_100M_GPU_FPGA_DP")
	)
	(segment
		(start 23.885398 -346.288106)
		(end 23.885398 -349.350838)
		(width 0.14224)
		(layer "In15.Cu")
		(net "CLK_100M_GPU_FPGA_DP")
	)
	(segment
		(start 18.74266 -363.303058)
		(end 20.766532 -368.189256)
		(width 0.14224)
		(layer "In15.Cu")
		(net "CLK_100M_GPU_FPGA_DP")
	)
	(segment
		(start 18.74266 -355.617018)
		(end 18.74266 -363.303058)
		(width 0.14224)
		(layer "In15.Cu")
		(net "CLK_100M_GPU_FPGA_DP")
	)
	(segment
		(start 38.735508 -387.368288)
		(end 38.735508 -391.406634)
		(width 0.14224)
		(layer "In15.Cu")
		(net "CLK_100M_GPU_FPGA_DP")
	)
	(segment
		(start 21.377656 -137.769854)
		(end 21.377656 -139.390628)
		(width 0.14224)
		(layer "In15.Cu")
		(net "CLK_100M_GPU_FPGA_DP")
	)
	(segment
		(start 23.494238 -368.710464)
		(end 30.635702 -375.851928)
		(width 0.14224)
		(layer "In15.Cu")
		(net "CLK_100M_GPU_FPGA_DP")
	)
	(segment
		(start 48.903636 -416.864038)
		(end 49.194466 -416.573208)
		(width 0.14224)
		(layer "In15.Cu")
		(net "CLK_100M_GPU_FPGA_DP")
	)
	(segment
		(start 6.985 -169.291)
		(end 6.985 -240.83772)
		(width 0.14224)
		(layer "In15.Cu")
		(net "CLK_100M_GPU_FPGA_DP")
	)
	(segment
		(start 21.999956 -344.402664)
		(end 23.885398 -346.288106)
		(width 0.14224)
		(layer "In15.Cu")
		(net "CLK_100M_GPU_FPGA_DP")
	)
	(segment
		(start 20.766532 -368.189256)
		(end 21.28774 -368.710464)
		(width 0.14224)
		(layer "In15.Cu")
		(net "CLK_100M_GPU_FPGA_DP")
	)
	(segment
		(start 21.28774 -368.710464)
		(end 23.494238 -368.710464)
		(width 0.14224)
		(layer "In15.Cu")
		(net "CLK_100M_GPU_FPGA_DP")
	)
	(segment
		(start 20.400772 -137.010902)
		(end 20.400772 -137.222992)
		(width 0.14224)
		(layer "In15.Cu")
		(net "CLK_100M_GPU_FPGA_DP")
	)
	(segment
		(start 20.400772 -137.222992)
		(end 20.543012 -137.365232)
		(width 0.14224)
		(layer "In15.Cu")
		(net "CLK_100M_GPU_FPGA_DP")
	)
	(segment
		(start 10.61593 -314.745116)
		(end 12.530328 -330.263754)
		(width 0.14224)
		(layer "In15.Cu")
		(net "CLK_100M_GPU_FPGA_DP")
	)
	(segment
		(start 45.436282 -415.804604)
		(end 47.993554 -416.864038)
		(width 0.14224)
		(layer "In15.Cu")
		(net "CLK_100M_GPU_FPGA_DP")
	)
	(segment
		(start 6.985 -240.83772)
		(end 10.61593 -314.745116)
		(width 0.14224)
		(layer "In15.Cu")
		(net "CLK_100M_GPU_FPGA_DP")
	)
	(segment
		(start 20.543012 -137.365232)
		(end 20.973034 -137.365232)
		(width 0.14224)
		(layer "In15.Cu")
		(net "CLK_100M_GPU_FPGA_DP")
	)
	(segment
		(start 8.382 -167.894)
		(end 6.985 -169.291)
		(width 0.14224)
		(layer "In15.Cu")
		(net "CLK_100M_GPU_FPGA_DP")
	)
	(segment
		(start 47.993554 -416.864038)
		(end 48.903636 -416.864038)
		(width 0.14224)
		(layer "In15.Cu")
		(net "CLK_100M_GPU_FPGA_DP")
	)
	(segment
		(start 17.636998 -342.5952)
		(end 21.999956 -344.402664)
		(width 0.14224)
		(layer "In15.Cu")
		(net "CLK_100M_GPU_FPGA_DP")
	)
	(segment
		(start 37.082476 -407.450798)
		(end 45.436282 -415.804604)
		(width 0.14224)
		(layer "In15.Cu")
		(net "CLK_100M_GPU_FPGA_DP")
	)
	(segment
		(start 30.635702 -375.851928)
		(end 30.635702 -379.268482)
		(width 0.14224)
		(layer "In15.Cu")
		(net "CLK_100M_GPU_FPGA_DP")
	)
	(segment
		(start 19.436842 -137.642092)
		(end 19.102832 -137.976102)
		(width 0.12954)
		(layer "F.Cu")
		(net "CLK_100M_GPU_FPGA_DN")
	)
	(segment
		(start 20.041362 -137.642092)
		(end 19.436842 -137.642092)
		(width 0.12954)
		(layer "F.Cu")
		(net "CLK_100M_GPU_FPGA_DN")
	)
	(segment
		(start 20.400772 -138.001502)
		(end 20.041362 -137.642092)
		(width 0.12954)
		(layer "F.Cu")
		(net "CLK_100M_GPU_FPGA_DN")
	)
	(segment
		(start 55.07355 -417.145978)
		(end 57.691528 -417.145978)
		(width 0.14224)
		(layer "In2.Cu")
		(net "CLK_100M_GPU_FPGA_DN")
	)
	(segment
		(start 60.190888 -420.630858)
		(end 60.649866 -421.089836)
		(width 0.14224)
		(layer "In2.Cu")
		(net "CLK_100M_GPU_FPGA_DN")
	)
	(segment
		(start 54.50967 -417.283138)
		(end 54.93639 -417.283138)
		(width 0.14224)
		(layer "In2.Cu")
		(net "CLK_100M_GPU_FPGA_DN")
	)
	(segment
		(start 49.194466 -417.436808)
		(end 49.485296 -417.145978)
		(width 0.14224)
		(layer "In2.Cu")
		(net "CLK_100M_GPU_FPGA_DN")
	)
	(segment
		(start 59.56554 -417.519104)
		(end 59.56554 -420.323518)
		(width 0.14224)
		(layer "In2.Cu")
		(net "CLK_100M_GPU_FPGA_DN")
	)
	(segment
		(start 49.485296 -417.145978)
		(end 54.37251 -417.145978)
		(width 0.14224)
		(layer "In2.Cu")
		(net "CLK_100M_GPU_FPGA_DN")
	)
	(segment
		(start 59.079384 -417.032948)
		(end 59.56554 -417.519104)
		(width 0.14224)
		(layer "In2.Cu")
		(net "CLK_100M_GPU_FPGA_DN")
	)
	(segment
		(start 59.87288 -420.630858)
		(end 60.190888 -420.630858)
		(width 0.14224)
		(layer "In2.Cu")
		(net "CLK_100M_GPU_FPGA_DN")
	)
	(segment
		(start 57.804558 -417.032948)
		(end 59.079384 -417.032948)
		(width 0.14224)
		(layer "In2.Cu")
		(net "CLK_100M_GPU_FPGA_DN")
	)
	(segment
		(start 57.691528 -417.145978)
		(end 57.804558 -417.032948)
		(width 0.14224)
		(layer "In2.Cu")
		(net "CLK_100M_GPU_FPGA_DN")
	)
	(segment
		(start 54.93639 -417.283138)
		(end 55.07355 -417.145978)
		(width 0.14224)
		(layer "In2.Cu")
		(net "CLK_100M_GPU_FPGA_DN")
	)
	(segment
		(start 59.56554 -420.323518)
		(end 59.87288 -420.630858)
		(width 0.14224)
		(layer "In2.Cu")
		(net "CLK_100M_GPU_FPGA_DN")
	)
	(segment
		(start 54.37251 -417.145978)
		(end 54.50967 -417.283138)
		(width 0.14224)
		(layer "In2.Cu")
		(net "CLK_100M_GPU_FPGA_DN")
	)
	(segment
		(start 23.603458 -349.249746)
		(end 18.46072 -355.515926)
		(width 0.14224)
		(layer "In15.Cu")
		(net "CLK_100M_GPU_FPGA_DN")
	)
	(segment
		(start 23.377398 -368.992404)
		(end 30.353762 -375.968768)
		(width 0.14224)
		(layer "In15.Cu")
		(net "CLK_100M_GPU_FPGA_DN")
	)
	(segment
		(start 36.800536 -395.341602)
		(end 36.800536 -407.567638)
		(width 0.14224)
		(layer "In15.Cu")
		(net "CLK_100M_GPU_FPGA_DN")
	)
	(segment
		(start 20.527518 -368.349022)
		(end 21.1709 -368.992404)
		(width 0.14224)
		(layer "In15.Cu")
		(net "CLK_100M_GPU_FPGA_DN")
	)
	(segment
		(start 17.41551 -164.176456)
		(end 13.98016 -167.61206)
		(width 0.14224)
		(layer "In15.Cu")
		(net "CLK_100M_GPU_FPGA_DN")
	)
	(segment
		(start 13.98016 -167.61206)
		(end 8.26516 -167.61206)
		(width 0.14224)
		(layer "In15.Cu")
		(net "CLK_100M_GPU_FPGA_DN")
	)
	(segment
		(start 6.70306 -240.844832)
		(end 10.334752 -314.769246)
		(width 0.14224)
		(layer "In15.Cu")
		(net "CLK_100M_GPU_FPGA_DN")
	)
	(segment
		(start 23.603458 -346.404946)
		(end 23.603458 -349.249746)
		(width 0.14224)
		(layer "In15.Cu")
		(net "CLK_100M_GPU_FPGA_DN")
	)
	(segment
		(start 36.800536 -407.567638)
		(end 45.276516 -416.043618)
		(width 0.14224)
		(layer "In15.Cu")
		(net "CLK_100M_GPU_FPGA_DN")
	)
	(segment
		(start 21.095716 -137.886694)
		(end 21.095716 -139.3698)
		(width 0.14224)
		(layer "In15.Cu")
		(net "CLK_100M_GPU_FPGA_DN")
	)
	(segment
		(start 12.254992 -330.336398)
		(end 17.421098 -342.8111)
		(width 0.14224)
		(layer "In15.Cu")
		(net "CLK_100M_GPU_FPGA_DN")
	)
	(segment
		(start 30.353762 -375.968768)
		(end 30.353762 -379.385322)
		(width 0.14224)
		(layer "In15.Cu")
		(net "CLK_100M_GPU_FPGA_DN")
	)
	(segment
		(start 45.276516 -416.043618)
		(end 47.93742 -417.145978)
		(width 0.14224)
		(layer "In15.Cu")
		(net "CLK_100M_GPU_FPGA_DN")
	)
	(segment
		(start 18.46072 -363.359192)
		(end 20.527518 -368.349022)
		(width 0.14224)
		(layer "In15.Cu")
		(net "CLK_100M_GPU_FPGA_DN")
	)
	(segment
		(start 30.353762 -379.385322)
		(end 38.453568 -387.485128)
		(width 0.14224)
		(layer "In15.Cu")
		(net "CLK_100M_GPU_FPGA_DN")
	)
	(segment
		(start 21.1709 -368.992404)
		(end 23.377398 -368.992404)
		(width 0.14224)
		(layer "In15.Cu")
		(net "CLK_100M_GPU_FPGA_DN")
	)
	(segment
		(start 20.400772 -138.001502)
		(end 20.400772 -137.789412)
		(width 0.14224)
		(layer "In15.Cu")
		(net "CLK_100M_GPU_FPGA_DN")
	)
	(segment
		(start 38.453568 -391.3505)
		(end 36.800536 -395.341602)
		(width 0.14224)
		(layer "In15.Cu")
		(net "CLK_100M_GPU_FPGA_DN")
	)
	(segment
		(start 20.543012 -137.647172)
		(end 20.856194 -137.647172)
		(width 0.14224)
		(layer "In15.Cu")
		(net "CLK_100M_GPU_FPGA_DN")
	)
	(segment
		(start 48.903636 -417.145978)
		(end 49.194466 -417.436808)
		(width 0.14224)
		(layer "In15.Cu")
		(net "CLK_100M_GPU_FPGA_DN")
	)
	(segment
		(start 38.453568 -387.485128)
		(end 38.453568 -391.3505)
		(width 0.14224)
		(layer "In15.Cu")
		(net "CLK_100M_GPU_FPGA_DN")
	)
	(segment
		(start 8.26516 -167.61206)
		(end 6.70306 -169.17416)
		(width 0.14224)
		(layer "In15.Cu")
		(net "CLK_100M_GPU_FPGA_DN")
	)
	(segment
		(start 47.93742 -417.145978)
		(end 48.903636 -417.145978)
		(width 0.14224)
		(layer "In15.Cu")
		(net "CLK_100M_GPU_FPGA_DN")
	)
	(segment
		(start 21.095716 -139.3698)
		(end 17.41551 -164.176456)
		(width 0.14224)
		(layer "In15.Cu")
		(net "CLK_100M_GPU_FPGA_DN")
	)
	(segment
		(start 20.400772 -137.789412)
		(end 20.543012 -137.647172)
		(width 0.14224)
		(layer "In15.Cu")
		(net "CLK_100M_GPU_FPGA_DN")
	)
	(segment
		(start 17.421098 -342.8111)
		(end 21.84019 -344.641678)
		(width 0.14224)
		(layer "In15.Cu")
		(net "CLK_100M_GPU_FPGA_DN")
	)
	(segment
		(start 18.46072 -355.515926)
		(end 18.46072 -363.359192)
		(width 0.14224)
		(layer "In15.Cu")
		(net "CLK_100M_GPU_FPGA_DN")
	)
	(segment
		(start 10.334752 -314.769246)
		(end 12.254992 -330.336398)
		(width 0.14224)
		(layer "In15.Cu")
		(net "CLK_100M_GPU_FPGA_DN")
	)
	(segment
		(start 21.84019 -344.641678)
		(end 23.603458 -346.404946)
		(width 0.14224)
		(layer "In15.Cu")
		(net "CLK_100M_GPU_FPGA_DN")
	)
	(segment
		(start 20.856194 -137.647172)
		(end 21.095716 -137.886694)
		(width 0.14224)
		(layer "In15.Cu")
		(net "CLK_100M_GPU_FPGA_DN")
	)
	(segment
		(start 6.70306 -169.17416)
		(end 6.70306 -240.844832)
		(width 0.14224)
		(layer "In15.Cu")
		(net "CLK_100M_GPU_FPGA_DN")
	)
	(segment
		(start 125.76429 -320.909188)
		(end 126.111 -321.255898)
		(width 0.12954)
		(layer "F.Cu")
		(net "CLK_100M_CPU1_CLK11_R_DP")
	)
	(segment
		(start 109.41939 -295.9989)
		(end 109.41939 -301.574454)
		(width 0.12954)
		(layer "F.Cu")
		(net "CLK_100M_CPU1_CLK11_R_DP")
	)
	(segment
		(start 109.728 -295.69029)
		(end 109.41939 -295.9989)
		(width 0.12954)
		(layer "F.Cu")
		(net "CLK_100M_CPU1_CLK11_R_DP")
	)
	(segment
		(start 109.41939 -301.574454)
		(end 125.76429 -317.919354)
		(width 0.12954)
		(layer "F.Cu")
		(net "CLK_100M_CPU1_CLK11_R_DP")
	)
	(segment
		(start 125.76429 -317.919354)
		(end 125.76429 -320.909188)
		(width 0.12954)
		(layer "F.Cu")
		(net "CLK_100M_CPU1_CLK11_R_DP")
	)
	(segment
		(start 109.09681 -295.999154)
		(end 109.09681 -301.708312)
		(width 0.12954)
		(layer "F.Cu")
		(net "CLK_100M_CPU1_CLK11_R_DN")
	)
	(segment
		(start 125.44171 -318.053212)
		(end 125.44171 -320.909188)
		(width 0.12954)
		(layer "F.Cu")
		(net "CLK_100M_CPU1_CLK11_R_DN")
	)
	(segment
		(start 109.09681 -301.708312)
		(end 125.44171 -318.053212)
		(width 0.12954)
		(layer "F.Cu")
		(net "CLK_100M_CPU1_CLK11_R_DN")
	)
	(segment
		(start 108.787946 -295.69029)
		(end 109.09681 -295.999154)
		(width 0.12954)
		(layer "F.Cu")
		(net "CLK_100M_CPU1_CLK11_R_DN")
	)
	(segment
		(start 125.44171 -320.909188)
		(end 125.095 -321.255898)
		(width 0.12954)
		(layer "F.Cu")
		(net "CLK_100M_CPU1_CLK11_R_DN")
	)
	(segment
		(start 127.188976 -326.403208)
		(end 127.45847 -326.403208)
		(width 0.12954)
		(layer "F.Cu")
		(net "CLK_100M_CPU1_CLK11_DP")
	)
	(segment
		(start 126.369826 -325.584058)
		(end 126.63932 -325.584058)
		(width 0.12954)
		(layer "F.Cu")
		(net "CLK_100M_CPU1_CLK11_DP")
	)
	(segment
		(start 127.733552 -326.947784)
		(end 128.008126 -327.222358)
		(width 0.12954)
		(layer "F.Cu")
		(net "CLK_100M_CPU1_CLK11_DP")
	)
	(segment
		(start 126.914402 -326.128634)
		(end 127.188976 -326.403208)
		(width 0.12954)
		(layer "F.Cu")
		(net "CLK_100M_CPU1_CLK11_DP")
	)
	(segment
		(start 126.63932 -325.584058)
		(end 126.914402 -325.85914)
		(width 0.12954)
		(layer "F.Cu")
		(net "CLK_100M_CPU1_CLK11_DP")
	)
	(segment
		(start 126.111 -322.055998)
		(end 125.76429 -322.402708)
		(width 0.12954)
		(layer "F.Cu")
		(net "CLK_100M_CPU1_CLK11_DP")
	)
	(segment
		(start 125.76429 -322.402708)
		(end 125.76429 -324.978522)
		(width 0.12954)
		(layer "F.Cu")
		(net "CLK_100M_CPU1_CLK11_DP")
	)
	(segment
		(start 162.588702 -361.803188)
		(end 165.845236 -361.803188)
		(width 0.12954)
		(layer "F.Cu")
		(net "CLK_100M_CPU1_CLK11_DP")
	)
	(segment
		(start 127.45847 -326.403208)
		(end 127.733552 -326.67829)
		(width 0.12954)
		(layer "F.Cu")
		(net "CLK_100M_CPU1_CLK11_DP")
	)
	(segment
		(start 128.552702 -327.49744)
		(end 128.552702 -327.766934)
		(width 0.12954)
		(layer "F.Cu")
		(net "CLK_100M_CPU1_CLK11_DP")
	)
	(segment
		(start 161.911284 -361.12577)
		(end 162.588702 -361.803188)
		(width 0.12954)
		(layer "F.Cu")
		(net "CLK_100M_CPU1_CLK11_DP")
	)
	(segment
		(start 128.27762 -327.222358)
		(end 128.552702 -327.49744)
		(width 0.12954)
		(layer "F.Cu")
		(net "CLK_100M_CPU1_CLK11_DP")
	)
	(segment
		(start 128.008126 -327.222358)
		(end 128.27762 -327.222358)
		(width 0.12954)
		(layer "F.Cu")
		(net "CLK_100M_CPU1_CLK11_DP")
	)
	(segment
		(start 128.552702 -327.766934)
		(end 161.911538 -361.12577)
		(width 0.12954)
		(layer "F.Cu")
		(net "CLK_100M_CPU1_CLK11_DP")
	)
	(segment
		(start 161.911538 -361.12577)
		(end 161.911284 -361.12577)
		(width 0.12954)
		(layer "F.Cu")
		(net "CLK_100M_CPU1_CLK11_DP")
	)
	(segment
		(start 127.733552 -326.67829)
		(end 127.733552 -326.947784)
		(width 0.12954)
		(layer "F.Cu")
		(net "CLK_100M_CPU1_CLK11_DP")
	)
	(segment
		(start 126.914402 -325.85914)
		(end 126.914402 -326.128634)
		(width 0.12954)
		(layer "F.Cu")
		(net "CLK_100M_CPU1_CLK11_DP")
	)
	(segment
		(start 165.845236 -361.803188)
		(end 166.115746 -361.532678)
		(width 0.12954)
		(layer "F.Cu")
		(net "CLK_100M_CPU1_CLK11_DP")
	)
	(segment
		(start 125.76429 -324.978522)
		(end 126.369826 -325.584058)
		(width 0.12954)
		(layer "F.Cu")
		(net "CLK_100M_CPU1_CLK11_DP")
	)
	(via
		(at 161.911538 -361.12577)
		(size 0.4064)
		(drill 0.2032)
		(layers "F.Cu" "B.Cu")
		(net "CLK_100M_CPU1_CLK11_DP")
	)
	(segment
		(start 149.734524 -373.50446)
		(end 149.17928 -372.949216)
		(width 0.14224)
		(layer "In4.Cu")
		(net "CLK_100M_CPU1_CLK11_DP")
	)
	(segment
		(start 103.494078 -404.454614)
		(end 106.309922 -401.63877)
		(width 0.14224)
		(layer "In4.Cu")
		(net "CLK_100M_CPU1_CLK11_DP")
	)
	(segment
		(start 132.958332 -394.481558)
		(end 133.3881 -394.027406)
		(width 0.14224)
		(layer "In4.Cu")
		(net "CLK_100M_CPU1_CLK11_DP")
	)
	(segment
		(start 100.220272 -410.291534)
		(end 100.220272 -407.668984)
		(width 0.14224)
		(layer "In4.Cu")
		(net "CLK_100M_CPU1_CLK11_DP")
	)
	(segment
		(start 100.761292 -410.832554)
		(end 100.220272 -410.291534)
		(width 0.14224)
		(layer "In4.Cu")
		(net "CLK_100M_CPU1_CLK11_DP")
	)
	(segment
		(start 106.309922 -401.63877)
		(end 109.980984 -400.118072)
		(width 0.14224)
		(layer "In4.Cu")
		(net "CLK_100M_CPU1_CLK11_DP")
	)
	(segment
		(start 137.308082 -389.470138)
		(end 138.234674 -388.543546)
		(width 0.14224)
		(layer "In4.Cu")
		(net "CLK_100M_CPU1_CLK11_DP")
	)
	(segment
		(start 135.831072 -390.082278)
		(end 136.443212 -389.470138)
		(width 0.14224)
		(layer "In4.Cu")
		(net "CLK_100M_CPU1_CLK11_DP")
	)
	(segment
		(start 136.443212 -389.470138)
		(end 137.308082 -389.470138)
		(width 0.14224)
		(layer "In4.Cu")
		(net "CLK_100M_CPU1_CLK11_DP")
	)
	(segment
		(start 133.523736 -393.02563)
		(end 135.831072 -390.487662)
		(width 0.14224)
		(layer "In4.Cu")
		(net "CLK_100M_CPU1_CLK11_DP")
	)
	(segment
		(start 63.452248 -422.806622)
		(end 63.452248 -415.605214)
		(width 0.14224)
		(layer "In4.Cu")
		(net "CLK_100M_CPU1_CLK11_DP")
	)
	(segment
		(start 109.980984 -400.118072)
		(end 112.721644 -398.350232)
		(width 0.14224)
		(layer "In4.Cu")
		(net "CLK_100M_CPU1_CLK11_DP")
	)
	(segment
		(start 135.831072 -390.487662)
		(end 135.831072 -390.082278)
		(width 0.14224)
		(layer "In4.Cu")
		(net "CLK_100M_CPU1_CLK11_DP")
	)
	(segment
		(start 149.551898 -374.782334)
		(end 149.734524 -374.278652)
		(width 0.14224)
		(layer "In4.Cu")
		(net "CLK_100M_CPU1_CLK11_DP")
	)
	(segment
		(start 149.757384 -369.47602)
		(end 149.757384 -368.3762)
		(width 0.14224)
		(layer "In4.Cu")
		(net "CLK_100M_CPU1_CLK11_DP")
	)
	(segment
		(start 64.932814 -411.731968)
		(end 65.471294 -411.193488)
		(width 0.14224)
		(layer "In4.Cu")
		(net "CLK_100M_CPU1_CLK11_DP")
	)
	(segment
		(start 149.734524 -374.278652)
		(end 149.734524 -373.50446)
		(width 0.14224)
		(layer "In4.Cu")
		(net "CLK_100M_CPU1_CLK11_DP")
	)
	(segment
		(start 149.17928 -372.949216)
		(end 148.739352 -372.766844)
		(width 0.14224)
		(layer "In4.Cu")
		(net "CLK_100M_CPU1_CLK11_DP")
	)
	(segment
		(start 148.031962 -372.059454)
		(end 148.031962 -370.931694)
		(width 0.14224)
		(layer "In4.Cu")
		(net "CLK_100M_CPU1_CLK11_DP")
	)
	(segment
		(start 133.3881 -394.027406)
		(end 133.523736 -393.02563)
		(width 0.14224)
		(layer "In4.Cu")
		(net "CLK_100M_CPU1_CLK11_DP")
	)
	(segment
		(start 141.858746 -384.655568)
		(end 143.31315 -382.884172)
		(width 0.14224)
		(layer "In4.Cu")
		(net "CLK_100M_CPU1_CLK11_DP")
	)
	(segment
		(start 103.494078 -405.361394)
		(end 103.494078 -404.454614)
		(width 0.14224)
		(layer "In4.Cu")
		(net "CLK_100M_CPU1_CLK11_DP")
	)
	(segment
		(start 145.41881 -379.732794)
		(end 145.464784 -379.686566)
		(width 0.14224)
		(layer "In4.Cu")
		(net "CLK_100M_CPU1_CLK11_DP")
	)
	(segment
		(start 148.73605 -370.227606)
		(end 149.196552 -370.036852)
		(width 0.14224)
		(layer "In4.Cu")
		(net "CLK_100M_CPU1_CLK11_DP")
	)
	(segment
		(start 65.471294 -411.193488)
		(end 95.846392 -411.193488)
		(width 0.14224)
		(layer "In4.Cu")
		(net "CLK_100M_CPU1_CLK11_DP")
	)
	(segment
		(start 63.10884 -422.948862)
		(end 63.310008 -422.948862)
		(width 0.14224)
		(layer "In4.Cu")
		(net "CLK_100M_CPU1_CLK11_DP")
	)
	(segment
		(start 100.761292 -412.27629)
		(end 100.761292 -410.832554)
		(width 0.14224)
		(layer "In4.Cu")
		(net "CLK_100M_CPU1_CLK11_DP")
	)
	(segment
		(start 112.721644 -398.350232)
		(end 132.958332 -394.481558)
		(width 0.14224)
		(layer "In4.Cu")
		(net "CLK_100M_CPU1_CLK11_DP")
	)
	(segment
		(start 149.196552 -370.036852)
		(end 149.757384 -369.47602)
		(width 0.14224)
		(layer "In4.Cu")
		(net "CLK_100M_CPU1_CLK11_DP")
	)
	(segment
		(start 148.031962 -370.931694)
		(end 148.73605 -370.227606)
		(width 0.14224)
		(layer "In4.Cu")
		(net "CLK_100M_CPU1_CLK11_DP")
	)
	(segment
		(start 138.234674 -388.543546)
		(end 138.661648 -387.85292)
		(width 0.14224)
		(layer "In4.Cu")
		(net "CLK_100M_CPU1_CLK11_DP")
	)
	(segment
		(start 100.501958 -412.535624)
		(end 100.761292 -412.27629)
		(width 0.14224)
		(layer "In4.Cu")
		(net "CLK_100M_CPU1_CLK11_DP")
	)
	(segment
		(start 101.221286 -406.66797)
		(end 102.187502 -406.66797)
		(width 0.14224)
		(layer "In4.Cu")
		(net "CLK_100M_CPU1_CLK11_DP")
	)
	(segment
		(start 97.188528 -412.535624)
		(end 100.501958 -412.535624)
		(width 0.14224)
		(layer "In4.Cu")
		(net "CLK_100M_CPU1_CLK11_DP")
	)
	(segment
		(start 62.649862 -422.489884)
		(end 63.10884 -422.948862)
		(width 0.14224)
		(layer "In4.Cu")
		(net "CLK_100M_CPU1_CLK11_DP")
	)
	(segment
		(start 64.932814 -414.124648)
		(end 64.932814 -411.731968)
		(width 0.14224)
		(layer "In4.Cu")
		(net "CLK_100M_CPU1_CLK11_DP")
	)
	(segment
		(start 156.310076 -361.823508)
		(end 165.824916 -361.823508)
		(width 0.14224)
		(layer "In4.Cu")
		(net "CLK_100M_CPU1_CLK11_DP")
	)
	(segment
		(start 143.31315 -382.884172)
		(end 145.41881 -379.732794)
		(width 0.14224)
		(layer "In4.Cu")
		(net "CLK_100M_CPU1_CLK11_DP")
	)
	(segment
		(start 145.464784 -379.686566)
		(end 149.551898 -374.782334)
		(width 0.14224)
		(layer "In4.Cu")
		(net "CLK_100M_CPU1_CLK11_DP")
	)
	(segment
		(start 165.824916 -361.823508)
		(end 166.115746 -361.532678)
		(width 0.14224)
		(layer "In4.Cu")
		(net "CLK_100M_CPU1_CLK11_DP")
	)
	(segment
		(start 138.661648 -387.85292)
		(end 141.858746 -384.655568)
		(width 0.14224)
		(layer "In4.Cu")
		(net "CLK_100M_CPU1_CLK11_DP")
	)
	(segment
		(start 63.310008 -422.948862)
		(end 63.452248 -422.806622)
		(width 0.14224)
		(layer "In4.Cu")
		(net "CLK_100M_CPU1_CLK11_DP")
	)
	(segment
		(start 102.187502 -406.66797)
		(end 103.494078 -405.361394)
		(width 0.14224)
		(layer "In4.Cu")
		(net "CLK_100M_CPU1_CLK11_DP")
	)
	(segment
		(start 63.452248 -415.605214)
		(end 64.932814 -414.124648)
		(width 0.14224)
		(layer "In4.Cu")
		(net "CLK_100M_CPU1_CLK11_DP")
	)
	(segment
		(start 100.220272 -407.668984)
		(end 101.221286 -406.66797)
		(width 0.14224)
		(layer "In4.Cu")
		(net "CLK_100M_CPU1_CLK11_DP")
	)
	(segment
		(start 95.846392 -411.193488)
		(end 97.188528 -412.535624)
		(width 0.14224)
		(layer "In4.Cu")
		(net "CLK_100M_CPU1_CLK11_DP")
	)
	(segment
		(start 148.739352 -372.766844)
		(end 148.031962 -372.059454)
		(width 0.14224)
		(layer "In4.Cu")
		(net "CLK_100M_CPU1_CLK11_DP")
	)
	(segment
		(start 149.757384 -368.3762)
		(end 156.310076 -361.823508)
		(width 0.14224)
		(layer "In4.Cu")
		(net "CLK_100M_CPU1_CLK11_DP")
	)
	(segment
		(start 125.095 -322.055998)
		(end 125.44171 -322.402708)
		(width 0.12954)
		(layer "F.Cu")
		(net "CLK_100M_CPU1_CLK11_DN")
	)
	(segment
		(start 159.762952 -359.433876)
		(end 162.454844 -362.125768)
		(width 0.12954)
		(layer "F.Cu")
		(net "CLK_100M_CPU1_CLK11_DN")
	)
	(segment
		(start 125.44171 -325.112634)
		(end 159.762952 -359.433876)
		(width 0.12954)
		(layer "F.Cu")
		(net "CLK_100M_CPU1_CLK11_DN")
	)
	(segment
		(start 165.845236 -362.125768)
		(end 166.115746 -362.396278)
		(width 0.12954)
		(layer "F.Cu")
		(net "CLK_100M_CPU1_CLK11_DN")
	)
	(segment
		(start 162.454844 -362.125768)
		(end 165.845236 -362.125768)
		(width 0.12954)
		(layer "F.Cu")
		(net "CLK_100M_CPU1_CLK11_DN")
	)
	(segment
		(start 125.44171 -322.402708)
		(end 125.44171 -325.112634)
		(width 0.12954)
		(layer "F.Cu")
		(net "CLK_100M_CPU1_CLK11_DN")
	)
	(via
		(at 159.762952 -359.433876)
		(size 0.4064)
		(drill 0.2032)
		(layers "F.Cu" "B.Cu")
		(net "CLK_100M_CPU1_CLK11_DN")
	)
	(segment
		(start 145.638012 -379.912372)
		(end 145.673318 -379.877066)
		(width 0.14224)
		(layer "In4.Cu")
		(net "CLK_100M_CPU1_CLK11_DN")
	)
	(segment
		(start 148.313902 -371.048534)
		(end 148.895816 -370.46662)
		(width 0.14224)
		(layer "In4.Cu")
		(net "CLK_100M_CPU1_CLK11_DN")
	)
	(segment
		(start 63.426848 -423.230802)
		(end 63.734188 -422.923462)
		(width 0.14224)
		(layer "In4.Cu")
		(net "CLK_100M_CPU1_CLK11_DN")
	)
	(segment
		(start 101.338126 -406.94991)
		(end 102.304342 -406.94991)
		(width 0.14224)
		(layer "In4.Cu")
		(net "CLK_100M_CPU1_CLK11_DN")
	)
	(segment
		(start 150.016464 -373.38762)
		(end 149.339046 -372.710202)
		(width 0.14224)
		(layer "In4.Cu")
		(net "CLK_100M_CPU1_CLK11_DN")
	)
	(segment
		(start 165.824916 -362.105448)
		(end 166.115746 -362.396278)
		(width 0.14224)
		(layer "In4.Cu")
		(net "CLK_100M_CPU1_CLK11_DN")
	)
	(segment
		(start 150.039324 -369.59286)
		(end 150.039324 -368.49304)
		(width 0.14224)
		(layer "In4.Cu")
		(net "CLK_100M_CPU1_CLK11_DN")
	)
	(segment
		(start 149.356318 -370.275866)
		(end 150.039324 -369.59286)
		(width 0.14224)
		(layer "In4.Cu")
		(net "CLK_100M_CPU1_CLK11_DN")
	)
	(segment
		(start 102.304342 -406.94991)
		(end 103.776018 -405.478234)
		(width 0.14224)
		(layer "In4.Cu")
		(net "CLK_100M_CPU1_CLK11_DN")
	)
	(segment
		(start 148.313902 -371.942614)
		(end 148.313902 -371.048534)
		(width 0.14224)
		(layer "In4.Cu")
		(net "CLK_100M_CPU1_CLK11_DN")
	)
	(segment
		(start 63.734188 -415.722054)
		(end 65.214754 -414.241488)
		(width 0.14224)
		(layer "In4.Cu")
		(net "CLK_100M_CPU1_CLK11_DN")
	)
	(segment
		(start 101.043232 -412.39313)
		(end 101.043232 -410.715714)
		(width 0.14224)
		(layer "In4.Cu")
		(net "CLK_100M_CPU1_CLK11_DN")
	)
	(segment
		(start 148.895816 -370.46662)
		(end 149.356318 -370.275866)
		(width 0.14224)
		(layer "In4.Cu")
		(net "CLK_100M_CPU1_CLK11_DN")
	)
	(segment
		(start 136.014206 -390.705848)
		(end 136.113012 -390.596882)
		(width 0.14224)
		(layer "In4.Cu")
		(net "CLK_100M_CPU1_CLK11_DN")
	)
	(segment
		(start 97.071688 -412.817564)
		(end 100.618798 -412.817564)
		(width 0.14224)
		(layer "In4.Cu")
		(net "CLK_100M_CPU1_CLK11_DN")
	)
	(segment
		(start 150.016464 -374.328182)
		(end 150.016464 -373.38762)
		(width 0.14224)
		(layer "In4.Cu")
		(net "CLK_100M_CPU1_CLK11_DN")
	)
	(segment
		(start 136.560052 -389.752078)
		(end 137.424922 -389.752078)
		(width 0.14224)
		(layer "In4.Cu")
		(net "CLK_100M_CPU1_CLK11_DN")
	)
	(segment
		(start 133.100572 -394.741654)
		(end 133.655562 -394.155422)
		(width 0.14224)
		(layer "In4.Cu")
		(net "CLK_100M_CPU1_CLK11_DN")
	)
	(segment
		(start 145.673318 -379.877066)
		(end 149.80031 -374.925082)
		(width 0.14224)
		(layer "In4.Cu")
		(net "CLK_100M_CPU1_CLK11_DN")
	)
	(segment
		(start 148.899118 -372.52783)
		(end 148.313902 -371.942614)
		(width 0.14224)
		(layer "In4.Cu")
		(net "CLK_100M_CPU1_CLK11_DN")
	)
	(segment
		(start 103.776018 -404.571454)
		(end 106.469688 -401.877784)
		(width 0.14224)
		(layer "In4.Cu")
		(net "CLK_100M_CPU1_CLK11_DN")
	)
	(segment
		(start 65.588134 -411.475428)
		(end 95.729552 -411.475428)
		(width 0.14224)
		(layer "In4.Cu")
		(net "CLK_100M_CPU1_CLK11_DN")
	)
	(segment
		(start 112.828324 -398.616932)
		(end 133.100572 -394.741654)
		(width 0.14224)
		(layer "In4.Cu")
		(net "CLK_100M_CPU1_CLK11_DN")
	)
	(segment
		(start 63.734188 -422.923462)
		(end 63.734188 -415.722054)
		(width 0.14224)
		(layer "In4.Cu")
		(net "CLK_100M_CPU1_CLK11_DN")
	)
	(segment
		(start 95.729552 -411.475428)
		(end 97.071688 -412.817564)
		(width 0.14224)
		(layer "In4.Cu")
		(net "CLK_100M_CPU1_CLK11_DN")
	)
	(segment
		(start 149.80031 -374.925082)
		(end 150.016464 -374.328182)
		(width 0.14224)
		(layer "In4.Cu")
		(net "CLK_100M_CPU1_CLK11_DN")
	)
	(segment
		(start 63.10884 -423.230802)
		(end 63.426848 -423.230802)
		(width 0.14224)
		(layer "In4.Cu")
		(net "CLK_100M_CPU1_CLK11_DN")
	)
	(segment
		(start 65.214754 -411.848808)
		(end 65.588134 -411.475428)
		(width 0.14224)
		(layer "In4.Cu")
		(net "CLK_100M_CPU1_CLK11_DN")
	)
	(segment
		(start 143.539972 -383.05232)
		(end 145.638012 -379.912372)
		(width 0.14224)
		(layer "In4.Cu")
		(net "CLK_100M_CPU1_CLK11_DN")
	)
	(segment
		(start 156.426916 -362.105448)
		(end 165.824916 -362.105448)
		(width 0.14224)
		(layer "In4.Cu")
		(net "CLK_100M_CPU1_CLK11_DN")
	)
	(segment
		(start 103.776018 -405.478234)
		(end 103.776018 -404.571454)
		(width 0.14224)
		(layer "In4.Cu")
		(net "CLK_100M_CPU1_CLK11_DN")
	)
	(segment
		(start 138.884152 -388.029196)
		(end 142.068042 -384.845306)
		(width 0.14224)
		(layer "In4.Cu")
		(net "CLK_100M_CPU1_CLK11_DN")
	)
	(segment
		(start 133.655562 -394.155422)
		(end 133.791452 -393.150344)
		(width 0.14224)
		(layer "In4.Cu")
		(net "CLK_100M_CPU1_CLK11_DN")
	)
	(segment
		(start 101.043232 -410.715714)
		(end 100.502212 -410.174694)
		(width 0.14224)
		(layer "In4.Cu")
		(net "CLK_100M_CPU1_CLK11_DN")
	)
	(segment
		(start 100.618798 -412.817564)
		(end 101.043232 -412.39313)
		(width 0.14224)
		(layer "In4.Cu")
		(net "CLK_100M_CPU1_CLK11_DN")
	)
	(segment
		(start 150.039324 -368.49304)
		(end 156.426916 -362.105448)
		(width 0.14224)
		(layer "In4.Cu")
		(net "CLK_100M_CPU1_CLK11_DN")
	)
	(segment
		(start 137.424922 -389.752078)
		(end 138.457178 -388.719822)
		(width 0.14224)
		(layer "In4.Cu")
		(net "CLK_100M_CPU1_CLK11_DN")
	)
	(segment
		(start 100.502212 -410.174694)
		(end 100.502212 -407.785824)
		(width 0.14224)
		(layer "In4.Cu")
		(net "CLK_100M_CPU1_CLK11_DN")
	)
	(segment
		(start 62.649862 -423.68978)
		(end 63.10884 -423.230802)
		(width 0.14224)
		(layer "In4.Cu")
		(net "CLK_100M_CPU1_CLK11_DN")
	)
	(segment
		(start 138.457178 -388.719822)
		(end 138.884152 -388.029196)
		(width 0.14224)
		(layer "In4.Cu")
		(net "CLK_100M_CPU1_CLK11_DN")
	)
	(segment
		(start 136.113012 -390.596882)
		(end 136.113012 -390.199118)
		(width 0.14224)
		(layer "In4.Cu")
		(net "CLK_100M_CPU1_CLK11_DN")
	)
	(segment
		(start 142.068042 -384.845306)
		(end 143.539972 -383.05232)
		(width 0.14224)
		(layer "In4.Cu")
		(net "CLK_100M_CPU1_CLK11_DN")
	)
	(segment
		(start 65.214754 -414.241488)
		(end 65.214754 -411.848808)
		(width 0.14224)
		(layer "In4.Cu")
		(net "CLK_100M_CPU1_CLK11_DN")
	)
	(segment
		(start 133.791452 -393.150344)
		(end 136.014206 -390.705848)
		(width 0.14224)
		(layer "In4.Cu")
		(net "CLK_100M_CPU1_CLK11_DN")
	)
	(segment
		(start 136.113012 -390.199118)
		(end 136.560052 -389.752078)
		(width 0.14224)
		(layer "In4.Cu")
		(net "CLK_100M_CPU1_CLK11_DN")
	)
	(segment
		(start 149.339046 -372.710202)
		(end 148.899118 -372.52783)
		(width 0.14224)
		(layer "In4.Cu")
		(net "CLK_100M_CPU1_CLK11_DN")
	)
	(segment
		(start 106.469688 -401.877784)
		(end 110.112556 -400.369024)
		(width 0.14224)
		(layer "In4.Cu")
		(net "CLK_100M_CPU1_CLK11_DN")
	)
	(segment
		(start 100.502212 -407.785824)
		(end 101.338126 -406.94991)
		(width 0.14224)
		(layer "In4.Cu")
		(net "CLK_100M_CPU1_CLK11_DN")
	)
	(segment
		(start 110.112556 -400.369024)
		(end 112.828324 -398.616932)
		(width 0.14224)
		(layer "In4.Cu")
		(net "CLK_100M_CPU1_CLK11_DN")
	)
	(segment
		(start 341.939118 -306.305966)
		(end 345.080844 -309.447692)
		(width 0.12954)
		(layer "F.Cu")
		(net "CLK_100M_CPU0_CLK11_R_DP")
	)
	(segment
		(start 354.965762 -309.447692)
		(end 366.056418 -320.538348)
		(width 0.12954)
		(layer "F.Cu")
		(net "CLK_100M_CPU0_CLK11_R_DP")
	)
	(segment
		(start 343.140284 -303.966118)
		(end 341.939118 -305.167284)
		(width 0.12954)
		(layer "F.Cu")
		(net "CLK_100M_CPU0_CLK11_R_DP")
	)
	(segment
		(start 341.939118 -305.167284)
		(end 341.939118 -306.305966)
		(width 0.12954)
		(layer "F.Cu")
		(net "CLK_100M_CPU0_CLK11_R_DP")
	)
	(segment
		(start 357.359458 -296.739056)
		(end 355.07676 -299.021754)
		(width 0.12954)
		(layer "F.Cu")
		(net "CLK_100M_CPU0_CLK11_R_DP")
	)
	(segment
		(start 345.080844 -309.447692)
		(end 354.965762 -309.447692)
		(width 0.12954)
		(layer "F.Cu")
		(net "CLK_100M_CPU0_CLK11_R_DP")
	)
	(segment
		(start 357.668068 -295.690036)
		(end 357.359458 -295.998646)
		(width 0.12954)
		(layer "F.Cu")
		(net "CLK_100M_CPU0_CLK11_R_DP")
	)
	(segment
		(start 355.07676 -299.021754)
		(end 343.140284 -303.966118)
		(width 0.12954)
		(layer "F.Cu")
		(net "CLK_100M_CPU0_CLK11_R_DP")
	)
	(segment
		(start 357.359458 -295.998646)
		(end 357.359458 -296.739056)
		(width 0.12954)
		(layer "F.Cu")
		(net "CLK_100M_CPU0_CLK11_R_DP")
	)
	(segment
		(start 366.056418 -320.538348)
		(end 366.056418 -323.55028)
		(width 0.12954)
		(layer "F.Cu")
		(net "CLK_100M_CPU0_CLK11_R_DP")
	)
	(segment
		(start 366.056418 -323.55028)
		(end 366.403128 -323.89699)
		(width 0.12954)
		(layer "F.Cu")
		(net "CLK_100M_CPU0_CLK11_R_DP")
	)
	(segment
		(start 341.616538 -305.033426)
		(end 341.616538 -306.439824)
		(width 0.12954)
		(layer "F.Cu")
		(net "CLK_100M_CPU0_CLK11_R_DN")
	)
	(segment
		(start 365.733838 -323.55028)
		(end 365.387128 -323.89699)
		(width 0.12954)
		(layer "F.Cu")
		(net "CLK_100M_CPU0_CLK11_R_DN")
	)
	(segment
		(start 342.957404 -303.69256)
		(end 341.616538 -305.033426)
		(width 0.12954)
		(layer "F.Cu")
		(net "CLK_100M_CPU0_CLK11_R_DN")
	)
	(segment
		(start 341.616538 -306.439824)
		(end 344.946986 -309.770272)
		(width 0.12954)
		(layer "F.Cu")
		(net "CLK_100M_CPU0_CLK11_R_DN")
	)
	(segment
		(start 356.728014 -295.690036)
		(end 357.036878 -295.9989)
		(width 0.12954)
		(layer "F.Cu")
		(net "CLK_100M_CPU0_CLK11_R_DN")
	)
	(segment
		(start 354.89388 -298.748196)
		(end 342.957404 -303.69256)
		(width 0.12954)
		(layer "F.Cu")
		(net "CLK_100M_CPU0_CLK11_R_DN")
	)
	(segment
		(start 344.946986 -309.770272)
		(end 354.831904 -309.770272)
		(width 0.12954)
		(layer "F.Cu")
		(net "CLK_100M_CPU0_CLK11_R_DN")
	)
	(segment
		(start 357.036878 -295.9989)
		(end 357.036878 -296.605198)
		(width 0.12954)
		(layer "F.Cu")
		(net "CLK_100M_CPU0_CLK11_R_DN")
	)
	(segment
		(start 357.036878 -296.605198)
		(end 354.89388 -298.748196)
		(width 0.12954)
		(layer "F.Cu")
		(net "CLK_100M_CPU0_CLK11_R_DN")
	)
	(segment
		(start 354.831904 -309.770272)
		(end 365.733838 -320.672206)
		(width 0.12954)
		(layer "F.Cu")
		(net "CLK_100M_CPU0_CLK11_R_DN")
	)
	(segment
		(start 365.733838 -320.672206)
		(end 365.733838 -323.55028)
		(width 0.12954)
		(layer "F.Cu")
		(net "CLK_100M_CPU0_CLK11_R_DN")
	)
	(segment
		(start 368.617754 -353.391978)
		(end 348.414086 -373.595646)
		(width 0.12954)
		(layer "F.Cu")
		(net "CLK_100M_CPU0_CLK11_DP")
	)
	(segment
		(start 176.7078 -371.360446)
		(end 184.19191 -371.360446)
		(width 0.12954)
		(layer "F.Cu")
		(net "CLK_100M_CPU0_CLK11_DP")
	)
	(segment
		(start 220.942916 -371.081046)
		(end 219.239846 -372.784116)
		(width 0.12954)
		(layer "F.Cu")
		(net "CLK_100M_CPU0_CLK11_DP")
	)
	(segment
		(start 233.790744 -366.778032)
		(end 233.37647 -367.192306)
		(width 0.12954)
		(layer "F.Cu")
		(net "CLK_100M_CPU0_CLK11_DP")
	)
	(segment
		(start 283.108908 -375.476262)
		(end 278.836374 -371.203728)
		(width 0.12954)
		(layer "F.Cu")
		(net "CLK_100M_CPU0_CLK11_DP")
	)
	(segment
		(start 278.836374 -371.203728)
		(end 252.635512 -371.203728)
		(width 0.12954)
		(layer "F.Cu")
		(net "CLK_100M_CPU0_CLK11_DP")
	)
	(segment
		(start 366.403128 -324.69709)
		(end 366.056418 -325.0438)
		(width 0.12954)
		(layer "F.Cu")
		(net "CLK_100M_CPU0_CLK11_DP")
	)
	(segment
		(start 298.115228 -373.595646)
		(end 296.234612 -375.476262)
		(width 0.12954)
		(layer "F.Cu")
		(net "CLK_100M_CPU0_CLK11_DP")
	)
	(segment
		(start 252.635512 -371.203728)
		(end 248.209816 -366.778032)
		(width 0.12954)
		(layer "F.Cu")
		(net "CLK_100M_CPU0_CLK11_DP")
	)
	(segment
		(start 368.617754 -327.890886)
		(end 368.617754 -353.391978)
		(width 0.12954)
		(layer "F.Cu")
		(net "CLK_100M_CPU0_CLK11_DP")
	)
	(segment
		(start 175.584104 -369.598448)
		(end 175.854614 -369.868958)
		(width 0.12954)
		(layer "F.Cu")
		(net "CLK_100M_CPU0_CLK11_DP")
	)
	(segment
		(start 348.414086 -373.595646)
		(end 298.115228 -373.595646)
		(width 0.12954)
		(layer "F.Cu")
		(net "CLK_100M_CPU0_CLK11_DP")
	)
	(segment
		(start 175.854614 -369.868958)
		(end 175.854614 -370.50726)
		(width 0.12954)
		(layer "F.Cu")
		(net "CLK_100M_CPU0_CLK11_DP")
	)
	(segment
		(start 193.059812 -372.129304)
		(end 193.714624 -372.784116)
		(width 0.12954)
		(layer "F.Cu")
		(net "CLK_100M_CPU0_CLK11_DP")
	)
	(segment
		(start 226.236022 -371.081046)
		(end 220.942916 -371.081046)
		(width 0.12954)
		(layer "F.Cu")
		(net "CLK_100M_CPU0_CLK11_DP")
	)
	(segment
		(start 175.854614 -370.50726)
		(end 176.7078 -371.360446)
		(width 0.12954)
		(layer "F.Cu")
		(net "CLK_100M_CPU0_CLK11_DP")
	)
	(segment
		(start 248.209816 -366.778032)
		(end 233.790744 -366.778032)
		(width 0.12954)
		(layer "F.Cu")
		(net "CLK_100M_CPU0_CLK11_DP")
	)
	(segment
		(start 184.960768 -372.129304)
		(end 193.059812 -372.129304)
		(width 0.12954)
		(layer "F.Cu")
		(net "CLK_100M_CPU0_CLK11_DP")
	)
	(segment
		(start 233.37647 -367.192306)
		(end 230.124762 -367.192306)
		(width 0.12954)
		(layer "F.Cu")
		(net "CLK_100M_CPU0_CLK11_DP")
	)
	(segment
		(start 296.234612 -375.476262)
		(end 283.108908 -375.476262)
		(width 0.12954)
		(layer "F.Cu")
		(net "CLK_100M_CPU0_CLK11_DP")
	)
	(segment
		(start 230.124762 -367.192306)
		(end 226.236022 -371.081046)
		(width 0.12954)
		(layer "F.Cu")
		(net "CLK_100M_CPU0_CLK11_DP")
	)
	(segment
		(start 184.19191 -371.360446)
		(end 184.960768 -372.129304)
		(width 0.12954)
		(layer "F.Cu")
		(net "CLK_100M_CPU0_CLK11_DP")
	)
	(segment
		(start 366.056418 -325.0438)
		(end 366.056418 -325.32955)
		(width 0.12954)
		(layer "F.Cu")
		(net "CLK_100M_CPU0_CLK11_DP")
	)
	(segment
		(start 193.714624 -372.784116)
		(end 207.99679 -372.784116)
		(width 0.12954)
		(layer "F.Cu")
		(net "CLK_100M_CPU0_CLK11_DP")
	)
	(segment
		(start 219.239846 -372.784116)
		(end 207.99679 -372.784116)
		(width 0.12954)
		(layer "F.Cu")
		(net "CLK_100M_CPU0_CLK11_DP")
	)
	(segment
		(start 366.056418 -325.32955)
		(end 368.617754 -327.890886)
		(width 0.12954)
		(layer "F.Cu")
		(net "CLK_100M_CPU0_CLK11_DP")
	)
	(via
		(at 207.99679 -372.784116)
		(size 0.4064)
		(drill 0.2032)
		(layers "F.Cu" "B.Cu")
		(net "CLK_100M_CPU0_CLK11_DP")
	)
	(segment
		(start 65.310004 -423.94886)
		(end 65.494916 -423.763948)
		(width 0.14224)
		(layer "In4.Cu")
		(net "CLK_100M_CPU0_CLK11_DP")
	)
	(segment
		(start 108.088938 -411.960822)
		(end 109.236764 -410.812996)
		(width 0.14224)
		(layer "In4.Cu")
		(net "CLK_100M_CPU0_CLK11_DP")
	)
	(segment
		(start 65.494916 -417.280852)
		(end 66.43624 -416.339528)
		(width 0.14224)
		(layer "In4.Cu")
		(net "CLK_100M_CPU0_CLK11_DP")
	)
	(segment
		(start 85.573616 -415.06394)
		(end 93.27261 -422.762934)
		(width 0.14224)
		(layer "In4.Cu")
		(net "CLK_100M_CPU0_CLK11_DP")
	)
	(segment
		(start 153.709624 -379.941836)
		(end 154.136344 -379.941836)
		(width 0.14224)
		(layer "In4.Cu")
		(net "CLK_100M_CPU0_CLK11_DP")
	)
	(segment
		(start 145.298414 -388.519162)
		(end 145.678144 -386.851144)
		(width 0.14224)
		(layer "In4.Cu")
		(net "CLK_100M_CPU0_CLK11_DP")
	)
	(segment
		(start 161.857944 -380.078996)
		(end 171.71924 -370.2177)
		(width 0.14224)
		(layer "In4.Cu")
		(net "CLK_100M_CPU0_CLK11_DP")
	)
	(segment
		(start 175.874934 -370.0907)
		(end 175.874934 -369.889278)
		(width 0.14224)
		(layer "In4.Cu")
		(net "CLK_100M_CPU0_CLK11_DP")
	)
	(segment
		(start 113.471198 -402.806916)
		(end 113.829084 -402.44903)
		(width 0.14224)
		(layer "In4.Cu")
		(net "CLK_100M_CPU0_CLK11_DP")
	)
	(segment
		(start 113.829084 -402.44903)
		(end 118.58371 -399.919698)
		(width 0.14224)
		(layer "In4.Cu")
		(net "CLK_100M_CPU0_CLK11_DP")
	)
	(segment
		(start 128.201166 -396.511018)
		(end 133.767322 -395.426946)
		(width 0.14224)
		(layer "In4.Cu")
		(net "CLK_100M_CPU0_CLK11_DP")
	)
	(segment
		(start 143.934942 -389.336788)
		(end 145.298414 -388.519162)
		(width 0.14224)
		(layer "In4.Cu")
		(net "CLK_100M_CPU0_CLK11_DP")
	)
	(segment
		(start 71.488808 -415.06394)
		(end 85.573616 -415.06394)
		(width 0.14224)
		(layer "In4.Cu")
		(net "CLK_100M_CPU0_CLK11_DP")
	)
	(segment
		(start 155.264104 -379.941836)
		(end 155.401264 -380.078996)
		(width 0.14224)
		(layer "In4.Cu")
		(net "CLK_100M_CPU0_CLK11_DP")
	)
	(segment
		(start 143.405606 -389.4836)
		(end 143.934942 -389.336788)
		(width 0.14224)
		(layer "In4.Cu")
		(net "CLK_100M_CPU0_CLK11_DP")
	)
	(segment
		(start 146.547332 -383.330196)
		(end 146.547332 -381.566674)
		(width 0.14224)
		(layer "In4.Cu")
		(net "CLK_100M_CPU0_CLK11_DP")
	)
	(segment
		(start 113.471198 -409.587954)
		(end 113.471198 -402.806916)
		(width 0.14224)
		(layer "In4.Cu")
		(net "CLK_100M_CPU0_CLK11_DP")
	)
	(segment
		(start 154.837384 -379.941836)
		(end 155.264104 -379.941836)
		(width 0.14224)
		(layer "In4.Cu")
		(net "CLK_100M_CPU0_CLK11_DP")
	)
	(segment
		(start 138.554714 -390.61644)
		(end 139.433554 -389.382)
		(width 0.14224)
		(layer "In4.Cu")
		(net "CLK_100M_CPU0_CLK11_DP")
	)
	(segment
		(start 109.236764 -410.812996)
		(end 112.246156 -410.812996)
		(width 0.14224)
		(layer "In4.Cu")
		(net "CLK_100M_CPU0_CLK11_DP")
	)
	(segment
		(start 135.844534 -393.13485)
		(end 135.94334 -392.637264)
		(width 0.14224)
		(layer "In4.Cu")
		(net "CLK_100M_CPU0_CLK11_DP")
	)
	(segment
		(start 112.246156 -410.812996)
		(end 113.471198 -409.587954)
		(width 0.14224)
		(layer "In4.Cu")
		(net "CLK_100M_CPU0_CLK11_DP")
	)
	(segment
		(start 137.38225 -391.023348)
		(end 137.9728 -391.023348)
		(width 0.14224)
		(layer "In4.Cu")
		(net "CLK_100M_CPU0_CLK11_DP")
	)
	(segment
		(start 153.145744 -380.078996)
		(end 153.572464 -380.078996)
		(width 0.14224)
		(layer "In4.Cu")
		(net "CLK_100M_CPU0_CLK11_DP")
	)
	(segment
		(start 118.58371 -399.919698)
		(end 128.201166 -396.511018)
		(width 0.14224)
		(layer "In4.Cu")
		(net "CLK_100M_CPU0_CLK11_DP")
	)
	(segment
		(start 93.27261 -422.762934)
		(end 97.323402 -422.762934)
		(width 0.14224)
		(layer "In4.Cu")
		(net "CLK_100M_CPU0_CLK11_DP")
	)
	(segment
		(start 148.03501 -380.078996)
		(end 151.316944 -380.078996)
		(width 0.14224)
		(layer "In4.Cu")
		(net "CLK_100M_CPU0_CLK11_DP")
	)
	(segment
		(start 140.49756 -389.382)
		(end 140.59916 -389.4836)
		(width 0.14224)
		(layer "In4.Cu")
		(net "CLK_100M_CPU0_CLK11_DP")
	)
	(segment
		(start 97.323402 -422.762934)
		(end 97.939098 -422.147238)
		(width 0.14224)
		(layer "In4.Cu")
		(net "CLK_100M_CPU0_CLK11_DP")
	)
	(segment
		(start 152.444704 -380.078996)
		(end 152.581864 -379.941836)
		(width 0.14224)
		(layer "In4.Cu")
		(net "CLK_100M_CPU0_CLK11_DP")
	)
	(segment
		(start 139.433554 -389.382)
		(end 140.49756 -389.382)
		(width 0.14224)
		(layer "In4.Cu")
		(net "CLK_100M_CPU0_CLK11_DP")
	)
	(segment
		(start 154.136344 -379.941836)
		(end 154.273504 -380.078996)
		(width 0.14224)
		(layer "In4.Cu")
		(net "CLK_100M_CPU0_CLK11_DP")
	)
	(segment
		(start 108.088938 -415.341562)
		(end 108.088938 -411.960822)
		(width 0.14224)
		(layer "In4.Cu")
		(net "CLK_100M_CPU0_CLK11_DP")
	)
	(segment
		(start 146.547332 -381.566674)
		(end 148.03501 -380.078996)
		(width 0.14224)
		(layer "In4.Cu")
		(net "CLK_100M_CPU0_CLK11_DP")
	)
	(segment
		(start 97.939098 -422.147238)
		(end 104.329738 -422.147238)
		(width 0.14224)
		(layer "In4.Cu")
		(net "CLK_100M_CPU0_CLK11_DP")
	)
	(segment
		(start 145.678144 -386.851144)
		(end 145.678144 -384.199384)
		(width 0.14224)
		(layer "In4.Cu")
		(net "CLK_100M_CPU0_CLK11_DP")
	)
	(segment
		(start 145.678144 -384.199384)
		(end 146.547332 -383.330196)
		(width 0.14224)
		(layer "In4.Cu")
		(net "CLK_100M_CPU0_CLK11_DP")
	)
	(segment
		(start 133.767322 -395.426946)
		(end 135.844534 -393.13485)
		(width 0.14224)
		(layer "In4.Cu")
		(net "CLK_100M_CPU0_CLK11_DP")
	)
	(segment
		(start 154.700224 -380.078996)
		(end 154.837384 -379.941836)
		(width 0.14224)
		(layer "In4.Cu")
		(net "CLK_100M_CPU0_CLK11_DP")
	)
	(segment
		(start 140.59916 -389.4836)
		(end 143.405606 -389.4836)
		(width 0.14224)
		(layer "In4.Cu")
		(net "CLK_100M_CPU0_CLK11_DP")
	)
	(segment
		(start 175.747934 -370.2177)
		(end 175.874934 -370.0907)
		(width 0.14224)
		(layer "In4.Cu")
		(net "CLK_100M_CPU0_CLK11_DP")
	)
	(segment
		(start 152.017984 -380.078996)
		(end 152.444704 -380.078996)
		(width 0.14224)
		(layer "In4.Cu")
		(net "CLK_100M_CPU0_CLK11_DP")
	)
	(segment
		(start 151.454104 -379.941836)
		(end 151.880824 -379.941836)
		(width 0.14224)
		(layer "In4.Cu")
		(net "CLK_100M_CPU0_CLK11_DP")
	)
	(segment
		(start 136.067038 -392.338306)
		(end 137.38225 -391.023348)
		(width 0.14224)
		(layer "In4.Cu")
		(net "CLK_100M_CPU0_CLK11_DP")
	)
	(segment
		(start 66.43624 -416.339528)
		(end 70.21322 -416.339528)
		(width 0.14224)
		(layer "In4.Cu")
		(net "CLK_100M_CPU0_CLK11_DP")
	)
	(segment
		(start 105.93451 -420.542466)
		(end 108.088938 -415.341562)
		(width 0.14224)
		(layer "In4.Cu")
		(net "CLK_100M_CPU0_CLK11_DP")
	)
	(segment
		(start 70.21322 -416.339528)
		(end 71.488808 -415.06394)
		(width 0.14224)
		(layer "In4.Cu")
		(net "CLK_100M_CPU0_CLK11_DP")
	)
	(segment
		(start 171.71924 -370.2177)
		(end 175.747934 -370.2177)
		(width 0.14224)
		(layer "In4.Cu")
		(net "CLK_100M_CPU0_CLK11_DP")
	)
	(segment
		(start 65.494916 -423.763948)
		(end 65.494916 -417.280852)
		(width 0.14224)
		(layer "In4.Cu")
		(net "CLK_100M_CPU0_CLK11_DP")
	)
	(segment
		(start 175.874934 -369.889278)
		(end 175.584104 -369.598448)
		(width 0.14224)
		(layer "In4.Cu")
		(net "CLK_100M_CPU0_CLK11_DP")
	)
	(segment
		(start 155.401264 -380.078996)
		(end 161.857944 -380.078996)
		(width 0.14224)
		(layer "In4.Cu")
		(net "CLK_100M_CPU0_CLK11_DP")
	)
	(segment
		(start 104.329738 -422.147238)
		(end 105.93451 -420.542466)
		(width 0.14224)
		(layer "In4.Cu")
		(net "CLK_100M_CPU0_CLK11_DP")
	)
	(segment
		(start 64.649858 -423.489882)
		(end 65.108836 -423.94886)
		(width 0.14224)
		(layer "In4.Cu")
		(net "CLK_100M_CPU0_CLK11_DP")
	)
	(segment
		(start 151.880824 -379.941836)
		(end 152.017984 -380.078996)
		(width 0.14224)
		(layer "In4.Cu")
		(net "CLK_100M_CPU0_CLK11_DP")
	)
	(segment
		(start 65.108836 -423.94886)
		(end 65.310004 -423.94886)
		(width 0.14224)
		(layer "In4.Cu")
		(net "CLK_100M_CPU0_CLK11_DP")
	)
	(segment
		(start 151.316944 -380.078996)
		(end 151.454104 -379.941836)
		(width 0.14224)
		(layer "In4.Cu")
		(net "CLK_100M_CPU0_CLK11_DP")
	)
	(segment
		(start 152.581864 -379.941836)
		(end 153.008584 -379.941836)
		(width 0.14224)
		(layer "In4.Cu")
		(net "CLK_100M_CPU0_CLK11_DP")
	)
	(segment
		(start 153.572464 -380.078996)
		(end 153.709624 -379.941836)
		(width 0.14224)
		(layer "In4.Cu")
		(net "CLK_100M_CPU0_CLK11_DP")
	)
	(segment
		(start 137.9728 -391.023348)
		(end 138.554714 -390.61644)
		(width 0.14224)
		(layer "In4.Cu")
		(net "CLK_100M_CPU0_CLK11_DP")
	)
	(segment
		(start 154.273504 -380.078996)
		(end 154.700224 -380.078996)
		(width 0.14224)
		(layer "In4.Cu")
		(net "CLK_100M_CPU0_CLK11_DP")
	)
	(segment
		(start 135.94334 -392.637264)
		(end 136.067038 -392.338306)
		(width 0.14224)
		(layer "In4.Cu")
		(net "CLK_100M_CPU0_CLK11_DP")
	)
	(segment
		(start 153.008584 -379.941836)
		(end 153.145744 -380.078996)
		(width 0.14224)
		(layer "In4.Cu")
		(net "CLK_100M_CPU0_CLK11_DP")
	)
	(segment
		(start 351.623122 -369.660678)
		(end 351.623122 -369.930172)
		(width 0.12954)
		(layer "F.Cu")
		(net "CLK_100M_CPU0_CLK11_DN")
	)
	(segment
		(start 296.100754 -375.153682)
		(end 283.242766 -375.153682)
		(width 0.12954)
		(layer "F.Cu")
		(net "CLK_100M_CPU0_CLK11_DN")
	)
	(segment
		(start 357.06812 -364.485174)
		(end 356.802436 -364.485174)
		(width 0.12954)
		(layer "F.Cu")
		(net "CLK_100M_CPU0_CLK11_DN")
	)
	(segment
		(start 352.442272 -368.841528)
		(end 352.442272 -369.111022)
		(width 0.12954)
		(layer "F.Cu")
		(net "CLK_100M_CPU0_CLK11_DN")
	)
	(segment
		(start 220.809058 -370.758466)
		(end 219.105988 -372.461536)
		(width 0.12954)
		(layer "F.Cu")
		(net "CLK_100M_CPU0_CLK11_DN")
	)
	(segment
		(start 219.105988 -372.461536)
		(end 210.66506 -372.461536)
		(width 0.12954)
		(layer "F.Cu")
		(net "CLK_100M_CPU0_CLK11_DN")
	)
	(segment
		(start 355.71176 -365.841534)
		(end 355.437186 -366.116108)
		(width 0.12954)
		(layer "F.Cu")
		(net "CLK_100M_CPU0_CLK11_DN")
	)
	(segment
		(start 226.102164 -370.758466)
		(end 220.809058 -370.758466)
		(width 0.12954)
		(layer "F.Cu")
		(net "CLK_100M_CPU0_CLK11_DN")
	)
	(segment
		(start 354.896166 -366.39119)
		(end 354.896166 -366.657128)
		(width 0.12954)
		(layer "F.Cu")
		(net "CLK_100M_CPU0_CLK11_DN")
	)
	(segment
		(start 348.280228 -373.273066)
		(end 297.98137 -373.273066)
		(width 0.12954)
		(layer "F.Cu")
		(net "CLK_100M_CPU0_CLK11_DN")
	)
	(segment
		(start 351.623122 -369.930172)
		(end 348.280228 -373.273066)
		(width 0.12954)
		(layer "F.Cu")
		(net "CLK_100M_CPU0_CLK11_DN")
	)
	(segment
		(start 353.261422 -368.291872)
		(end 352.986848 -368.566446)
		(width 0.12954)
		(layer "F.Cu")
		(net "CLK_100M_CPU0_CLK11_DN")
	)
	(segment
		(start 283.242766 -375.153682)
		(end 278.970232 -370.881148)
		(width 0.12954)
		(layer "F.Cu")
		(net "CLK_100M_CPU0_CLK11_DN")
	)
	(segment
		(start 193.848482 -372.461536)
		(end 210.66506 -372.461536)
		(width 0.12954)
		(layer "F.Cu")
		(net "CLK_100M_CPU0_CLK11_DN")
	)
	(segment
		(start 356.25278 -365.300514)
		(end 355.986842 -365.300514)
		(width 0.12954)
		(layer "F.Cu")
		(net "CLK_100M_CPU0_CLK11_DN")
	)
	(segment
		(start 297.98137 -373.273066)
		(end 296.100754 -375.153682)
		(width 0.12954)
		(layer "F.Cu")
		(net "CLK_100M_CPU0_CLK11_DN")
	)
	(segment
		(start 356.527354 -365.02594)
		(end 356.25278 -365.300514)
		(width 0.12954)
		(layer "F.Cu")
		(net "CLK_100M_CPU0_CLK11_DN")
	)
	(segment
		(start 355.437186 -366.116108)
		(end 355.171248 -366.116108)
		(width 0.12954)
		(layer "F.Cu")
		(net "CLK_100M_CPU0_CLK11_DN")
	)
	(segment
		(start 353.261422 -368.022378)
		(end 353.261422 -368.291872)
		(width 0.12954)
		(layer "F.Cu")
		(net "CLK_100M_CPU0_CLK11_DN")
	)
	(segment
		(start 351.898204 -369.385596)
		(end 351.623122 -369.660678)
		(width 0.12954)
		(layer "F.Cu")
		(net "CLK_100M_CPU0_CLK11_DN")
	)
	(segment
		(start 252.76937 -370.881148)
		(end 248.343674 -366.455452)
		(width 0.12954)
		(layer "F.Cu")
		(net "CLK_100M_CPU0_CLK11_DN")
	)
	(segment
		(start 352.986848 -368.566446)
		(end 352.717354 -368.566446)
		(width 0.12954)
		(layer "F.Cu")
		(net "CLK_100M_CPU0_CLK11_DN")
	)
	(segment
		(start 185.094626 -371.806724)
		(end 193.19367 -371.806724)
		(width 0.12954)
		(layer "F.Cu")
		(net "CLK_100M_CPU0_CLK11_DN")
	)
	(segment
		(start 354.080572 -367.206784)
		(end 354.080572 -367.472722)
		(width 0.12954)
		(layer "F.Cu")
		(net "CLK_100M_CPU0_CLK11_DN")
	)
	(segment
		(start 176.177194 -370.373402)
		(end 176.841658 -371.037866)
		(width 0.12954)
		(layer "F.Cu")
		(net "CLK_100M_CPU0_CLK11_DN")
	)
	(segment
		(start 233.242612 -366.869726)
		(end 229.990904 -366.869726)
		(width 0.12954)
		(layer "F.Cu")
		(net "CLK_100M_CPU0_CLK11_DN")
	)
	(segment
		(start 368.295174 -328.024744)
		(end 368.295174 -353.25812)
		(width 0.12954)
		(layer "F.Cu")
		(net "CLK_100M_CPU0_CLK11_DN")
	)
	(segment
		(start 176.447704 -369.598448)
		(end 176.177194 -369.868958)
		(width 0.12954)
		(layer "F.Cu")
		(net "CLK_100M_CPU0_CLK11_DN")
	)
	(segment
		(start 353.805998 -367.747296)
		(end 353.536504 -367.747296)
		(width 0.12954)
		(layer "F.Cu")
		(net "CLK_100M_CPU0_CLK11_DN")
	)
	(segment
		(start 354.621592 -366.931702)
		(end 354.355654 -366.931702)
		(width 0.12954)
		(layer "F.Cu")
		(net "CLK_100M_CPU0_CLK11_DN")
	)
	(segment
		(start 352.717354 -368.566446)
		(end 352.442272 -368.841528)
		(width 0.12954)
		(layer "F.Cu")
		(net "CLK_100M_CPU0_CLK11_DN")
	)
	(segment
		(start 229.990904 -366.869726)
		(end 226.102164 -370.758466)
		(width 0.12954)
		(layer "F.Cu")
		(net "CLK_100M_CPU0_CLK11_DN")
	)
	(segment
		(start 248.343674 -366.455452)
		(end 233.656886 -366.455452)
		(width 0.12954)
		(layer "F.Cu")
		(net "CLK_100M_CPU0_CLK11_DN")
	)
	(segment
		(start 365.733838 -325.463408)
		(end 368.295174 -328.024744)
		(width 0.12954)
		(layer "F.Cu")
		(net "CLK_100M_CPU0_CLK11_DN")
	)
	(segment
		(start 278.970232 -370.881148)
		(end 252.76937 -370.881148)
		(width 0.12954)
		(layer "F.Cu")
		(net "CLK_100M_CPU0_CLK11_DN")
	)
	(segment
		(start 193.19367 -371.806724)
		(end 193.848482 -372.461536)
		(width 0.12954)
		(layer "F.Cu")
		(net "CLK_100M_CPU0_CLK11_DN")
	)
	(segment
		(start 356.802436 -364.485174)
		(end 356.527354 -364.760256)
		(width 0.12954)
		(layer "F.Cu")
		(net "CLK_100M_CPU0_CLK11_DN")
	)
	(segment
		(start 353.536504 -367.747296)
		(end 353.261422 -368.022378)
		(width 0.12954)
		(layer "F.Cu")
		(net "CLK_100M_CPU0_CLK11_DN")
	)
	(segment
		(start 354.896166 -366.657128)
		(end 354.621592 -366.931702)
		(width 0.12954)
		(layer "F.Cu")
		(net "CLK_100M_CPU0_CLK11_DN")
	)
	(segment
		(start 355.171248 -366.116108)
		(end 354.896166 -366.39119)
		(width 0.12954)
		(layer "F.Cu")
		(net "CLK_100M_CPU0_CLK11_DN")
	)
	(segment
		(start 233.656886 -366.455452)
		(end 233.242612 -366.869726)
		(width 0.12954)
		(layer "F.Cu")
		(net "CLK_100M_CPU0_CLK11_DN")
	)
	(segment
		(start 365.387128 -324.69709)
		(end 365.733838 -325.0438)
		(width 0.12954)
		(layer "F.Cu")
		(net "CLK_100M_CPU0_CLK11_DN")
	)
	(segment
		(start 176.841658 -371.037866)
		(end 184.325768 -371.037866)
		(width 0.12954)
		(layer "F.Cu")
		(net "CLK_100M_CPU0_CLK11_DN")
	)
	(segment
		(start 356.527354 -364.760256)
		(end 356.527354 -365.02594)
		(width 0.12954)
		(layer "F.Cu")
		(net "CLK_100M_CPU0_CLK11_DN")
	)
	(segment
		(start 184.325768 -371.037866)
		(end 185.094626 -371.806724)
		(width 0.12954)
		(layer "F.Cu")
		(net "CLK_100M_CPU0_CLK11_DN")
	)
	(segment
		(start 365.733838 -325.0438)
		(end 365.733838 -325.463408)
		(width 0.12954)
		(layer "F.Cu")
		(net "CLK_100M_CPU0_CLK11_DN")
	)
	(segment
		(start 354.355654 -366.931702)
		(end 354.080572 -367.206784)
		(width 0.12954)
		(layer "F.Cu")
		(net "CLK_100M_CPU0_CLK11_DN")
	)
	(segment
		(start 354.080572 -367.472722)
		(end 353.805998 -367.747296)
		(width 0.12954)
		(layer "F.Cu")
		(net "CLK_100M_CPU0_CLK11_DN")
	)
	(segment
		(start 352.167698 -369.385596)
		(end 351.898204 -369.385596)
		(width 0.12954)
		(layer "F.Cu")
		(net "CLK_100M_CPU0_CLK11_DN")
	)
	(segment
		(start 368.295174 -353.25812)
		(end 357.06812 -364.485174)
		(width 0.12954)
		(layer "F.Cu")
		(net "CLK_100M_CPU0_CLK11_DN")
	)
	(segment
		(start 176.177194 -369.868958)
		(end 176.177194 -370.373402)
		(width 0.12954)
		(layer "F.Cu")
		(net "CLK_100M_CPU0_CLK11_DN")
	)
	(segment
		(start 352.442272 -369.111022)
		(end 352.167698 -369.385596)
		(width 0.12954)
		(layer "F.Cu")
		(net "CLK_100M_CPU0_CLK11_DN")
	)
	(segment
		(start 355.986842 -365.300514)
		(end 355.71176 -365.575596)
		(width 0.12954)
		(layer "F.Cu")
		(net "CLK_100M_CPU0_CLK11_DN")
	)
	(segment
		(start 355.71176 -365.575596)
		(end 355.71176 -365.841534)
		(width 0.12954)
		(layer "F.Cu")
		(net "CLK_100M_CPU0_CLK11_DN")
	)
	(via
		(at 210.66506 -372.461536)
		(size 0.4064)
		(drill 0.2032)
		(layers "F.Cu" "B.Cu")
		(net "CLK_100M_CPU0_CLK11_DN")
	)
	(segment
		(start 144.04721 -389.598408)
		(end 145.546826 -388.699248)
		(width 0.14224)
		(layer "In4.Cu")
		(net "CLK_100M_CPU0_CLK11_DN")
	)
	(segment
		(start 136.306306 -392.498072)
		(end 137.49909 -391.305288)
		(width 0.14224)
		(layer "In4.Cu")
		(net "CLK_100M_CPU0_CLK11_DN")
	)
	(segment
		(start 138.0617 -391.305288)
		(end 138.756136 -390.81964)
		(width 0.14224)
		(layer "In4.Cu")
		(net "CLK_100M_CPU0_CLK11_DN")
	)
	(segment
		(start 113.998756 -402.678138)
		(end 118.697756 -400.178524)
		(width 0.14224)
		(layer "In4.Cu")
		(net "CLK_100M_CPU0_CLK11_DN")
	)
	(segment
		(start 108.370878 -412.077662)
		(end 109.353604 -411.094936)
		(width 0.14224)
		(layer "In4.Cu")
		(net "CLK_100M_CPU0_CLK11_DN")
	)
	(segment
		(start 176.156874 -370.20754)
		(end 176.156874 -369.889278)
		(width 0.14224)
		(layer "In4.Cu")
		(net "CLK_100M_CPU0_CLK11_DN")
	)
	(segment
		(start 145.960084 -386.882894)
		(end 145.960084 -384.316224)
		(width 0.14224)
		(layer "In4.Cu")
		(net "CLK_100M_CPU0_CLK11_DN")
	)
	(segment
		(start 118.697756 -400.178524)
		(end 128.275588 -396.783814)
		(width 0.14224)
		(layer "In4.Cu")
		(net "CLK_100M_CPU0_CLK11_DN")
	)
	(segment
		(start 138.756136 -390.81964)
		(end 139.579096 -389.66394)
		(width 0.14224)
		(layer "In4.Cu")
		(net "CLK_100M_CPU0_CLK11_DN")
	)
	(segment
		(start 70.33006 -416.621468)
		(end 71.605648 -415.34588)
		(width 0.14224)
		(layer "In4.Cu")
		(net "CLK_100M_CPU0_CLK11_DN")
	)
	(segment
		(start 148.15185 -380.360936)
		(end 161.974784 -380.360936)
		(width 0.14224)
		(layer "In4.Cu")
		(net "CLK_100M_CPU0_CLK11_DN")
	)
	(segment
		(start 106.173524 -420.702232)
		(end 108.370878 -415.397696)
		(width 0.14224)
		(layer "In4.Cu")
		(net "CLK_100M_CPU0_CLK11_DN")
	)
	(segment
		(start 65.776856 -417.397692)
		(end 66.55308 -416.621468)
		(width 0.14224)
		(layer "In4.Cu")
		(net "CLK_100M_CPU0_CLK11_DN")
	)
	(segment
		(start 146.829272 -381.683514)
		(end 148.15185 -380.360936)
		(width 0.14224)
		(layer "In4.Cu")
		(net "CLK_100M_CPU0_CLK11_DN")
	)
	(segment
		(start 145.960084 -384.316224)
		(end 146.829272 -383.447036)
		(width 0.14224)
		(layer "In4.Cu")
		(net "CLK_100M_CPU0_CLK11_DN")
	)
	(segment
		(start 65.108836 -424.2308)
		(end 65.426844 -424.2308)
		(width 0.14224)
		(layer "In4.Cu")
		(net "CLK_100M_CPU0_CLK11_DN")
	)
	(segment
		(start 136.1059 -393.266422)
		(end 136.214612 -392.71956)
		(width 0.14224)
		(layer "In4.Cu")
		(net "CLK_100M_CPU0_CLK11_DN")
	)
	(segment
		(start 104.446578 -422.429178)
		(end 106.173524 -420.702232)
		(width 0.14224)
		(layer "In4.Cu")
		(net "CLK_100M_CPU0_CLK11_DN")
	)
	(segment
		(start 98.055938 -422.429178)
		(end 104.446578 -422.429178)
		(width 0.14224)
		(layer "In4.Cu")
		(net "CLK_100M_CPU0_CLK11_DN")
	)
	(segment
		(start 176.156874 -369.889278)
		(end 176.447704 -369.598448)
		(width 0.14224)
		(layer "In4.Cu")
		(net "CLK_100M_CPU0_CLK11_DN")
	)
	(segment
		(start 93.15577 -423.044874)
		(end 97.440242 -423.044874)
		(width 0.14224)
		(layer "In4.Cu")
		(net "CLK_100M_CPU0_CLK11_DN")
	)
	(segment
		(start 113.753138 -402.923756)
		(end 113.998756 -402.678138)
		(width 0.14224)
		(layer "In4.Cu")
		(net "CLK_100M_CPU0_CLK11_DN")
	)
	(segment
		(start 108.370878 -415.397696)
		(end 108.370878 -412.077662)
		(width 0.14224)
		(layer "In4.Cu")
		(net "CLK_100M_CPU0_CLK11_DN")
	)
	(segment
		(start 65.776856 -423.880788)
		(end 65.776856 -417.397692)
		(width 0.14224)
		(layer "In4.Cu")
		(net "CLK_100M_CPU0_CLK11_DN")
	)
	(segment
		(start 71.605648 -415.34588)
		(end 85.456776 -415.34588)
		(width 0.14224)
		(layer "In4.Cu")
		(net "CLK_100M_CPU0_CLK11_DN")
	)
	(segment
		(start 66.55308 -416.621468)
		(end 70.33006 -416.621468)
		(width 0.14224)
		(layer "In4.Cu")
		(net "CLK_100M_CPU0_CLK11_DN")
	)
	(segment
		(start 65.426844 -424.2308)
		(end 65.776856 -423.880788)
		(width 0.14224)
		(layer "In4.Cu")
		(net "CLK_100M_CPU0_CLK11_DN")
	)
	(segment
		(start 128.275588 -396.783814)
		(end 133.913372 -395.685772)
		(width 0.14224)
		(layer "In4.Cu")
		(net "CLK_100M_CPU0_CLK11_DN")
	)
	(segment
		(start 140.38072 -389.66394)
		(end 140.48232 -389.76554)
		(width 0.14224)
		(layer "In4.Cu")
		(net "CLK_100M_CPU0_CLK11_DN")
	)
	(segment
		(start 85.456776 -415.34588)
		(end 93.15577 -423.044874)
		(width 0.14224)
		(layer "In4.Cu")
		(net "CLK_100M_CPU0_CLK11_DN")
	)
	(segment
		(start 140.48232 -389.76554)
		(end 143.444214 -389.76554)
		(width 0.14224)
		(layer "In4.Cu")
		(net "CLK_100M_CPU0_CLK11_DN")
	)
	(segment
		(start 139.579096 -389.66394)
		(end 140.38072 -389.66394)
		(width 0.14224)
		(layer "In4.Cu")
		(net "CLK_100M_CPU0_CLK11_DN")
	)
	(segment
		(start 109.353604 -411.094936)
		(end 112.362996 -411.094936)
		(width 0.14224)
		(layer "In4.Cu")
		(net "CLK_100M_CPU0_CLK11_DN")
	)
	(segment
		(start 64.649858 -424.689778)
		(end 65.108836 -424.2308)
		(width 0.14224)
		(layer "In4.Cu")
		(net "CLK_100M_CPU0_CLK11_DN")
	)
	(segment
		(start 175.864774 -370.49964)
		(end 176.156874 -370.20754)
		(width 0.14224)
		(layer "In4.Cu")
		(net "CLK_100M_CPU0_CLK11_DN")
	)
	(segment
		(start 97.440242 -423.044874)
		(end 98.055938 -422.429178)
		(width 0.14224)
		(layer "In4.Cu")
		(net "CLK_100M_CPU0_CLK11_DN")
	)
	(segment
		(start 171.83608 -370.49964)
		(end 175.864774 -370.49964)
		(width 0.14224)
		(layer "In4.Cu")
		(net "CLK_100M_CPU0_CLK11_DN")
	)
	(segment
		(start 113.753138 -409.704794)
		(end 113.753138 -402.923756)
		(width 0.14224)
		(layer "In4.Cu")
		(net "CLK_100M_CPU0_CLK11_DN")
	)
	(segment
		(start 133.913372 -395.685772)
		(end 136.1059 -393.266422)
		(width 0.14224)
		(layer "In4.Cu")
		(net "CLK_100M_CPU0_CLK11_DN")
	)
	(segment
		(start 137.49909 -391.305288)
		(end 138.0617 -391.305288)
		(width 0.14224)
		(layer "In4.Cu")
		(net "CLK_100M_CPU0_CLK11_DN")
	)
	(segment
		(start 146.829272 -383.447036)
		(end 146.829272 -381.683514)
		(width 0.14224)
		(layer "In4.Cu")
		(net "CLK_100M_CPU0_CLK11_DN")
	)
	(segment
		(start 112.362996 -411.094936)
		(end 113.753138 -409.704794)
		(width 0.14224)
		(layer "In4.Cu")
		(net "CLK_100M_CPU0_CLK11_DN")
	)
	(segment
		(start 145.546826 -388.699248)
		(end 145.960084 -386.882894)
		(width 0.14224)
		(layer "In4.Cu")
		(net "CLK_100M_CPU0_CLK11_DN")
	)
	(segment
		(start 136.214612 -392.71956)
		(end 136.306306 -392.498072)
		(width 0.14224)
		(layer "In4.Cu")
		(net "CLK_100M_CPU0_CLK11_DN")
	)
	(segment
		(start 143.444214 -389.76554)
		(end 144.04721 -389.598408)
		(width 0.14224)
		(layer "In4.Cu")
		(net "CLK_100M_CPU0_CLK11_DN")
	)
	(segment
		(start 161.974784 -380.360936)
		(end 171.83608 -370.49964)
		(width 0.14224)
		(layer "In4.Cu")
		(net "CLK_100M_CPU0_CLK11_DN")
	)
	(segment
		(start 130.808222 -12.88034)
		(end 130.808222 -12.110212)
		(width 0.12954)
		(layer "F.Cu")
		(net "CLK_100M_BMC_RC_DP")
	)
	(segment
		(start 130.808222 -12.110212)
		(end 131.078732 -11.839702)
		(width 0.12954)
		(layer "F.Cu")
		(net "CLK_100M_BMC_RC_DP")
	)
	(segment
		(start 130.946906 -13.599922)
		(end 130.946906 -13.019024)
		(width 0.12954)
		(layer "F.Cu")
		(net "CLK_100M_BMC_RC_DP")
	)
	(segment
		(start 130.946906 -13.019024)
		(end 130.808222 -12.88034)
		(width 0.12954)
		(layer "F.Cu")
		(net "CLK_100M_BMC_RC_DP")
	)
	(segment
		(start 19.436842 -132.823712)
		(end 20.226782 -132.823712)
		(width 0.12954)
		(layer "F.Cu")
		(net "CLK_100M_BMC_RC_DP")
	)
	(segment
		(start 20.226782 -132.823712)
		(end 20.560792 -132.489702)
		(width 0.12954)
		(layer "F.Cu")
		(net "CLK_100M_BMC_RC_DP")
	)
	(segment
		(start 19.102832 -132.489702)
		(end 19.436842 -132.823712)
		(width 0.12954)
		(layer "F.Cu")
		(net "CLK_100M_BMC_RC_DP")
	)
	(via
		(at 131.078732 -11.839702)
		(size 0.508)
		(drill 0.254)
		(layers "F.Cu" "B.Cu")
		(net "CLK_100M_BMC_RC_DP")
	)
	(via
		(at 20.560792 -132.489702)
		(size 0.508)
		(drill 0.254)
		(layers "F.Cu" "B.Cu")
		(net "CLK_100M_BMC_RC_DP")
	)
	(segment
		(start 74.78649 -46.191932)
		(end 81.559654 -36.519358)
		(width 0.14224)
		(layer "In2.Cu")
		(net "CLK_100M_BMC_RC_DP")
	)
	(segment
		(start 112.681004 -19.947636)
		(end 117.177566 -19.947636)
		(width 0.14224)
		(layer "In2.Cu")
		(net "CLK_100M_BMC_RC_DP")
	)
	(segment
		(start 126.374144 -16.125952)
		(end 127.668528 -13.001752)
		(width 0.14224)
		(layer "In2.Cu")
		(net "CLK_100M_BMC_RC_DP")
	)
	(segment
		(start 112.27562 -20.35302)
		(end 112.681004 -19.947636)
		(width 0.14224)
		(layer "In2.Cu")
		(net "CLK_100M_BMC_RC_DP")
	)
	(segment
		(start 20.560792 -132.489702)
		(end 20.915122 -132.844032)
		(width 0.14224)
		(layer "In2.Cu")
		(net "CLK_100M_BMC_RC_DP")
	)
	(segment
		(start 104.281732 -20.06981)
		(end 105.211118 -19.418808)
		(width 0.14224)
		(layer "In2.Cu")
		(net "CLK_100M_BMC_RC_DP")
	)
	(segment
		(start 105.211118 -19.418808)
		(end 106.661712 -19.163284)
		(width 0.14224)
		(layer "In2.Cu")
		(net "CLK_100M_BMC_RC_DP")
	)
	(segment
		(start 98.387916 -27.030172)
		(end 98.836988 -26.5811)
		(width 0.14224)
		(layer "In2.Cu")
		(net "CLK_100M_BMC_RC_DP")
	)
	(segment
		(start 98.836988 -26.5811)
		(end 102.544626 -21.286724)
		(width 0.14224)
		(layer "In2.Cu")
		(net "CLK_100M_BMC_RC_DP")
	)
	(segment
		(start 130.787902 -11.548872)
		(end 131.078732 -11.839702)
		(width 0.14224)
		(layer "In2.Cu")
		(net "CLK_100M_BMC_RC_DP")
	)
	(segment
		(start 127.668528 -13.001752)
		(end 129.727198 -10.943082)
		(width 0.14224)
		(layer "In2.Cu")
		(net "CLK_100M_BMC_RC_DP")
	)
	(segment
		(start 89.583514 -33.195006)
		(end 98.387916 -27.030172)
		(width 0.14224)
		(layer "In2.Cu")
		(net "CLK_100M_BMC_RC_DP")
	)
	(segment
		(start 102.544626 -21.286724)
		(end 104.281732 -20.06981)
		(width 0.14224)
		(layer "In2.Cu")
		(net "CLK_100M_BMC_RC_DP")
	)
	(segment
		(start 106.661712 -19.163284)
		(end 108.33608 -19.458432)
		(width 0.14224)
		(layer "In2.Cu")
		(net "CLK_100M_BMC_RC_DP")
	)
	(segment
		(start 122.81408 -18.953734)
		(end 125.25629 -17.243806)
		(width 0.14224)
		(layer "In2.Cu")
		(net "CLK_100M_BMC_RC_DP")
	)
	(segment
		(start 130.480562 -10.943082)
		(end 130.787902 -11.250422)
		(width 0.14224)
		(layer "In2.Cu")
		(net "CLK_100M_BMC_RC_DP")
	)
	(segment
		(start 108.33608 -19.458432)
		(end 110.495842 -20.35302)
		(width 0.14224)
		(layer "In2.Cu")
		(net "CLK_100M_BMC_RC_DP")
	)
	(segment
		(start 110.495842 -20.35302)
		(end 112.27562 -20.35302)
		(width 0.14224)
		(layer "In2.Cu")
		(net "CLK_100M_BMC_RC_DP")
	)
	(segment
		(start 125.25629 -17.243806)
		(end 126.374144 -16.125952)
		(width 0.14224)
		(layer "In2.Cu")
		(net "CLK_100M_BMC_RC_DP")
	)
	(segment
		(start 81.559654 -36.519358)
		(end 89.583514 -33.195006)
		(width 0.14224)
		(layer "In2.Cu")
		(net "CLK_100M_BMC_RC_DP")
	)
	(segment
		(start 30.902656 -112.835944)
		(end 74.157078 -49.761394)
		(width 0.14224)
		(layer "In2.Cu")
		(net "CLK_100M_BMC_RC_DP")
	)
	(segment
		(start 130.787902 -11.250422)
		(end 130.787902 -11.548872)
		(width 0.14224)
		(layer "In2.Cu")
		(net "CLK_100M_BMC_RC_DP")
	)
	(segment
		(start 74.157078 -49.761394)
		(end 74.78649 -46.191932)
		(width 0.14224)
		(layer "In2.Cu")
		(net "CLK_100M_BMC_RC_DP")
	)
	(segment
		(start 129.727198 -10.943082)
		(end 130.480562 -10.943082)
		(width 0.14224)
		(layer "In2.Cu")
		(net "CLK_100M_BMC_RC_DP")
	)
	(segment
		(start 117.177566 -19.947636)
		(end 122.81408 -18.953734)
		(width 0.14224)
		(layer "In2.Cu")
		(net "CLK_100M_BMC_RC_DP")
	)
	(segment
		(start 20.915122 -132.844032)
		(end 21.702268 -132.844032)
		(width 0.14224)
		(layer "In2.Cu")
		(net "CLK_100M_BMC_RC_DP")
	)
	(segment
		(start 21.702268 -132.844032)
		(end 22.871684 -131.674616)
		(width 0.14224)
		(layer "In2.Cu")
		(net "CLK_100M_BMC_RC_DP")
	)
	(segment
		(start 22.871684 -131.674616)
		(end 30.902656 -112.835944)
		(width 0.14224)
		(layer "In2.Cu")
		(net "CLK_100M_BMC_RC_DP")
	)
	(segment
		(start 19.436842 -133.146292)
		(end 20.226782 -133.146292)
		(width 0.12954)
		(layer "F.Cu")
		(net "CLK_100M_BMC_RC_DN")
	)
	(segment
		(start 19.102832 -133.480302)
		(end 19.436842 -133.146292)
		(width 0.12954)
		(layer "F.Cu")
		(net "CLK_100M_BMC_RC_DN")
	)
	(segment
		(start 130.485642 -12.110212)
		(end 130.215132 -11.839702)
		(width 0.12954)
		(layer "F.Cu")
		(net "CLK_100M_BMC_RC_DN")
	)
	(segment
		(start 130.485642 -12.886436)
		(end 130.485642 -12.110212)
		(width 0.12954)
		(layer "F.Cu")
		(net "CLK_100M_BMC_RC_DN")
	)
	(segment
		(start 20.226782 -133.146292)
		(end 20.560792 -133.480302)
		(width 0.12954)
		(layer "F.Cu")
		(net "CLK_100M_BMC_RC_DN")
	)
	(segment
		(start 130.346958 -13.599922)
		(end 130.346958 -13.02512)
		(width 0.12954)
		(layer "F.Cu")
		(net "CLK_100M_BMC_RC_DN")
	)
	(segment
		(start 130.346958 -13.02512)
		(end 130.485642 -12.886436)
		(width 0.12954)
		(layer "F.Cu")
		(net "CLK_100M_BMC_RC_DN")
	)
	(via
		(at 130.215132 -11.839702)
		(size 0.508)
		(drill 0.254)
		(layers "F.Cu" "B.Cu")
		(net "CLK_100M_BMC_RC_DN")
	)
	(via
		(at 20.560792 -133.480302)
		(size 0.508)
		(drill 0.254)
		(layers "F.Cu" "B.Cu")
		(net "CLK_100M_BMC_RC_DN")
	)
	(segment
		(start 104.205024 -20.635468)
		(end 104.55275 -20.391882)
		(width 0.14224)
		(layer "In2.Cu")
		(net "CLK_100M_BMC_RC_DN")
	)
	(segment
		(start 21.819108 -133.125972)
		(end 23.109682 -131.835398)
		(width 0.14224)
		(layer "In2.Cu")
		(net "CLK_100M_BMC_RC_DN")
	)
	(segment
		(start 110.439708 -20.63496)
		(end 112.39246 -20.63496)
		(width 0.14224)
		(layer "In2.Cu")
		(net "CLK_100M_BMC_RC_DN")
	)
	(segment
		(start 102.503986 -21.83638)
		(end 102.747064 -21.489162)
		(width 0.14224)
		(layer "In2.Cu")
		(net "CLK_100M_BMC_RC_DN")
	)
	(segment
		(start 101.649784 -23.294848)
		(end 101.89337 -22.947376)
		(width 0.14224)
		(layer "In2.Cu")
		(net "CLK_100M_BMC_RC_DN")
	)
	(segment
		(start 125.438154 -17.460722)
		(end 126.613158 -16.285718)
		(width 0.14224)
		(layer "In2.Cu")
		(net "CLK_100M_BMC_RC_DN")
	)
	(segment
		(start 108.256578 -19.730974)
		(end 110.439708 -20.63496)
		(width 0.14224)
		(layer "In2.Cu")
		(net "CLK_100M_BMC_RC_DN")
	)
	(segment
		(start 104.014016 -20.601686)
		(end 104.205024 -20.635468)
		(width 0.14224)
		(layer "In2.Cu")
		(net "CLK_100M_BMC_RC_DN")
	)
	(segment
		(start 126.613158 -16.285718)
		(end 127.907542 -13.161518)
		(width 0.14224)
		(layer "In2.Cu")
		(net "CLK_100M_BMC_RC_DN")
	)
	(segment
		(start 105.321862 -19.685762)
		(end 106.661712 -19.449796)
		(width 0.14224)
		(layer "In2.Cu")
		(net "CLK_100M_BMC_RC_DN")
	)
	(segment
		(start 130.505962 -11.548872)
		(end 130.215132 -11.839702)
		(width 0.14224)
		(layer "In2.Cu")
		(net "CLK_100M_BMC_RC_DN")
	)
	(segment
		(start 101.859842 -22.756114)
		(end 102.10292 -22.408896)
		(width 0.14224)
		(layer "In2.Cu")
		(net "CLK_100M_BMC_RC_DN")
	)
	(segment
		(start 98.56978 -27.247088)
		(end 99.053904 -26.762964)
		(width 0.14224)
		(layer "In2.Cu")
		(net "CLK_100M_BMC_RC_DN")
	)
	(segment
		(start 102.293928 -22.375114)
		(end 102.537514 -22.027642)
		(width 0.14224)
		(layer "In2.Cu")
		(net "CLK_100M_BMC_RC_DN")
	)
	(segment
		(start 31.151068 -112.972342)
		(end 74.424286 -49.870614)
		(width 0.14224)
		(layer "In2.Cu")
		(net "CLK_100M_BMC_RC_DN")
	)
	(segment
		(start 74.424286 -49.870614)
		(end 75.053444 -46.302422)
		(width 0.14224)
		(layer "In2.Cu")
		(net "CLK_100M_BMC_RC_DN")
	)
	(segment
		(start 101.89337 -22.947376)
		(end 101.859842 -22.756114)
		(width 0.14224)
		(layer "In2.Cu")
		(net "CLK_100M_BMC_RC_DN")
	)
	(segment
		(start 130.505962 -11.367262)
		(end 130.505962 -11.548872)
		(width 0.14224)
		(layer "In2.Cu")
		(net "CLK_100M_BMC_RC_DN")
	)
	(segment
		(start 75.053444 -46.302422)
		(end 81.74355 -36.748466)
		(width 0.14224)
		(layer "In2.Cu")
		(net "CLK_100M_BMC_RC_DN")
	)
	(segment
		(start 130.363722 -11.225022)
		(end 130.505962 -11.367262)
		(width 0.14224)
		(layer "In2.Cu")
		(net "CLK_100M_BMC_RC_DN")
	)
	(segment
		(start 99.053904 -26.762964)
		(end 101.458776 -23.328884)
		(width 0.14224)
		(layer "In2.Cu")
		(net "CLK_100M_BMC_RC_DN")
	)
	(segment
		(start 104.55275 -20.391882)
		(end 104.586532 -20.200874)
		(width 0.14224)
		(layer "In2.Cu")
		(net "CLK_100M_BMC_RC_DN")
	)
	(segment
		(start 129.844038 -11.225022)
		(end 130.363722 -11.225022)
		(width 0.14224)
		(layer "In2.Cu")
		(net "CLK_100M_BMC_RC_DN")
	)
	(segment
		(start 106.661712 -19.449796)
		(end 108.256578 -19.730974)
		(width 0.14224)
		(layer "In2.Cu")
		(net "CLK_100M_BMC_RC_DN")
	)
	(segment
		(start 20.915122 -133.125972)
		(end 21.819108 -133.125972)
		(width 0.14224)
		(layer "In2.Cu")
		(net "CLK_100M_BMC_RC_DN")
	)
	(segment
		(start 101.458776 -23.328884)
		(end 101.458776 -23.32863)
		(width 0.14224)
		(layer "In2.Cu")
		(net "CLK_100M_BMC_RC_DN")
	)
	(segment
		(start 112.797844 -20.229576)
		(end 117.202458 -20.229576)
		(width 0.14224)
		(layer "In2.Cu")
		(net "CLK_100M_BMC_RC_DN")
	)
	(segment
		(start 81.74355 -36.748466)
		(end 89.720166 -33.443926)
		(width 0.14224)
		(layer "In2.Cu")
		(net "CLK_100M_BMC_RC_DN")
	)
	(segment
		(start 103.633016 -21.036026)
		(end 103.666798 -20.845018)
		(width 0.14224)
		(layer "In2.Cu")
		(net "CLK_100M_BMC_RC_DN")
	)
	(segment
		(start 102.747064 -21.489162)
		(end 103.094282 -21.24583)
		(width 0.14224)
		(layer "In2.Cu")
		(net "CLK_100M_BMC_RC_DN")
	)
	(segment
		(start 122.92457 -19.220688)
		(end 125.438154 -17.460722)
		(width 0.14224)
		(layer "In2.Cu")
		(net "CLK_100M_BMC_RC_DN")
	)
	(segment
		(start 89.720166 -33.443926)
		(end 98.56978 -27.247088)
		(width 0.14224)
		(layer "In2.Cu")
		(net "CLK_100M_BMC_RC_DN")
	)
	(segment
		(start 20.560792 -133.480302)
		(end 20.915122 -133.125972)
		(width 0.14224)
		(layer "In2.Cu")
		(net "CLK_100M_BMC_RC_DN")
	)
	(segment
		(start 101.458776 -23.32863)
		(end 101.649784 -23.294848)
		(width 0.14224)
		(layer "In2.Cu")
		(net "CLK_100M_BMC_RC_DN")
	)
	(segment
		(start 127.907542 -13.161518)
		(end 129.844038 -11.225022)
		(width 0.14224)
		(layer "In2.Cu")
		(net "CLK_100M_BMC_RC_DN")
	)
	(segment
		(start 104.586532 -20.200874)
		(end 105.321862 -19.685762)
		(width 0.14224)
		(layer "In2.Cu")
		(net "CLK_100M_BMC_RC_DN")
	)
	(segment
		(start 23.109682 -131.835398)
		(end 31.151068 -112.972342)
		(width 0.14224)
		(layer "In2.Cu")
		(net "CLK_100M_BMC_RC_DN")
	)
	(segment
		(start 103.666798 -20.845018)
		(end 104.014016 -20.601686)
		(width 0.14224)
		(layer "In2.Cu")
		(net "CLK_100M_BMC_RC_DN")
	)
	(segment
		(start 103.28529 -21.279612)
		(end 103.633016 -21.036026)
		(width 0.14224)
		(layer "In2.Cu")
		(net "CLK_100M_BMC_RC_DN")
	)
	(segment
		(start 103.094282 -21.24583)
		(end 103.28529 -21.279612)
		(width 0.14224)
		(layer "In2.Cu")
		(net "CLK_100M_BMC_RC_DN")
	)
	(segment
		(start 102.537514 -22.027642)
		(end 102.503986 -21.83638)
		(width 0.14224)
		(layer "In2.Cu")
		(net "CLK_100M_BMC_RC_DN")
	)
	(segment
		(start 112.39246 -20.63496)
		(end 112.797844 -20.229576)
		(width 0.14224)
		(layer "In2.Cu")
		(net "CLK_100M_BMC_RC_DN")
	)
	(segment
		(start 117.202458 -20.229576)
		(end 122.92457 -19.220688)
		(width 0.14224)
		(layer "In2.Cu")
		(net "CLK_100M_BMC_RC_DN")
	)
	(segment
		(start 102.10292 -22.408896)
		(end 102.293928 -22.375114)
		(width 0.14224)
		(layer "In2.Cu")
		(net "CLK_100M_BMC_RC_DN")
	)
	(segment
		(start 171.066968 -13.599922)
		(end 171.066968 -13.064236)
		(width 0.12954)
		(layer "F.Cu")
		(net "CLK_100M_CPU0_CLK01_DP")
	)
	(segment
		(start 171.066968 -13.064236)
		(end 170.928284 -12.925552)
		(width 0.12954)
		(layer "F.Cu")
		(net "CLK_100M_CPU0_CLK01_DP")
	)
	(segment
		(start 170.928284 -11.056874)
		(end 171.199302 -10.785856)
		(width 0.12954)
		(layer "F.Cu")
		(net "CLK_100M_CPU0_CLK01_DP")
	)
	(segment
		(start 170.928284 -12.925552)
		(end 170.928284 -11.056874)
		(width 0.12954)
		(layer "F.Cu")
		(net "CLK_100M_CPU0_CLK01_DP")
	)
	(via
		(at 171.199302 -10.785856)
		(size 0.508)
		(drill 0.254)
		(layers "F.Cu" "B.Cu")
		(net "CLK_100M_CPU0_CLK01_DP")
	)
	(segment
		(start 170.86961 -15.112746)
		(end 171.207684 -15.45082)
		(width 0.12954)
		(layer "B.Cu")
		(net "CLK_100M_CPU0_CLK01_DP")
	)
	(segment
		(start 184.47512 -16.37538)
		(end 189.215776 -16.37538)
		(width 0.12954)
		(layer "B.Cu")
		(net "CLK_100M_CPU0_CLK01_DP")
	)
	(segment
		(start 217.730324 -51.391566)
		(end 229.449376 -63.110618)
		(width 0.12954)
		(layer "B.Cu")
		(net "CLK_100M_CPU0_CLK01_DP")
	)
	(segment
		(start 248.384314 -123.60656)
		(end 253.005336 -128.227582)
		(width 0.12954)
		(layer "B.Cu")
		(net "CLK_100M_CPU0_CLK01_DP")
	)
	(segment
		(start 314.950094 -167.530526)
		(end 331.76972 -184.350152)
		(width 0.12954)
		(layer "B.Cu")
		(net "CLK_100M_CPU0_CLK01_DP")
	)
	(segment
		(start 189.7761 -16.607536)
		(end 193.957194 -19.401282)
		(width 0.12954)
		(layer "B.Cu")
		(net "CLK_100M_CPU0_CLK01_DP")
	)
	(segment
		(start 179.948586 -15.677134)
		(end 183.776874 -15.677134)
		(width 0.12954)
		(layer "B.Cu")
		(net "CLK_100M_CPU0_CLK01_DP")
	)
	(segment
		(start 253.005336 -128.227582)
		(end 264.376408 -128.227582)
		(width 0.12954)
		(layer "B.Cu")
		(net "CLK_100M_CPU0_CLK01_DP")
	)
	(segment
		(start 174.118778 -15.45082)
		(end 175.534066 -16.037052)
		(width 0.12954)
		(layer "B.Cu")
		(net "CLK_100M_CPU0_CLK01_DP")
	)
	(segment
		(start 201.340974 -28.688538)
		(end 210.127342 -32.328104)
		(width 0.12954)
		(layer "B.Cu")
		(net "CLK_100M_CPU0_CLK01_DP")
	)
	(segment
		(start 179.588668 -16.037052)
		(end 179.948586 -15.677134)
		(width 0.12954)
		(layer "B.Cu")
		(net "CLK_100M_CPU0_CLK01_DP")
	)
	(segment
		(start 171.199302 -10.785856)
		(end 170.86961 -11.115548)
		(width 0.12954)
		(layer "B.Cu")
		(net "CLK_100M_CPU0_CLK01_DP")
	)
	(segment
		(start 171.207684 -15.45082)
		(end 174.118778 -15.45082)
		(width 0.12954)
		(layer "B.Cu")
		(net "CLK_100M_CPU0_CLK01_DP")
	)
	(segment
		(start 358.125522 -212.154516)
		(end 370.56695 -212.154516)
		(width 0.12954)
		(layer "B.Cu")
		(net "CLK_100M_CPU0_CLK01_DP")
	)
	(segment
		(start 292.357302 -167.530526)
		(end 314.950094 -167.530526)
		(width 0.12954)
		(layer "B.Cu")
		(net "CLK_100M_CPU0_CLK01_DP")
	)
	(segment
		(start 170.86961 -11.115548)
		(end 170.86961 -15.112746)
		(width 0.12954)
		(layer "B.Cu")
		(net "CLK_100M_CPU0_CLK01_DP")
	)
	(segment
		(start 331.76972 -185.798714)
		(end 358.125522 -212.154516)
		(width 0.12954)
		(layer "B.Cu")
		(net "CLK_100M_CPU0_CLK01_DP")
	)
	(segment
		(start 216.497662 -45.899832)
		(end 216.497662 -48.415702)
		(width 0.12954)
		(layer "B.Cu")
		(net "CLK_100M_CPU0_CLK01_DP")
	)
	(segment
		(start 248.384314 -80.612234)
		(end 248.384314 -123.60656)
		(width 0.12954)
		(layer "B.Cu")
		(net "CLK_100M_CPU0_CLK01_DP")
	)
	(segment
		(start 370.56695 -212.154516)
		(end 371.837966 -213.425532)
		(width 0.12954)
		(layer "B.Cu")
		(net "CLK_100M_CPU0_CLK01_DP")
	)
	(segment
		(start 267.027406 -131.174998)
		(end 271.13484 -155.73629)
		(width 0.12954)
		(layer "B.Cu")
		(net "CLK_100M_CPU0_CLK01_DP")
	)
	(segment
		(start 175.534066 -16.037052)
		(end 179.588668 -16.037052)
		(width 0.12954)
		(layer "B.Cu")
		(net "CLK_100M_CPU0_CLK01_DP")
	)
	(segment
		(start 216.497662 -48.415702)
		(end 217.730324 -51.391566)
		(width 0.12954)
		(layer "B.Cu")
		(net "CLK_100M_CPU0_CLK01_DP")
	)
	(segment
		(start 211.405216 -33.605978)
		(end 216.497662 -45.899832)
		(width 0.12954)
		(layer "B.Cu")
		(net "CLK_100M_CPU0_CLK01_DP")
	)
	(segment
		(start 196.84111 -22.285198)
		(end 198.18731 -25.534874)
		(width 0.12954)
		(layer "B.Cu")
		(net "CLK_100M_CPU0_CLK01_DP")
	)
	(segment
		(start 183.776874 -15.677134)
		(end 184.47512 -16.37538)
		(width 0.12954)
		(layer "B.Cu")
		(net "CLK_100M_CPU0_CLK01_DP")
	)
	(segment
		(start 189.215776 -16.37538)
		(end 189.7761 -16.607536)
		(width 0.12954)
		(layer "B.Cu")
		(net "CLK_100M_CPU0_CLK01_DP")
	)
	(segment
		(start 193.957194 -19.401282)
		(end 196.84111 -22.285198)
		(width 0.12954)
		(layer "B.Cu")
		(net "CLK_100M_CPU0_CLK01_DP")
	)
	(segment
		(start 238.582962 -66.893694)
		(end 245.614698 -73.92543)
		(width 0.12954)
		(layer "B.Cu")
		(net "CLK_100M_CPU0_CLK01_DP")
	)
	(segment
		(start 331.76972 -184.350152)
		(end 331.76972 -185.798714)
		(width 0.12954)
		(layer "B.Cu")
		(net "CLK_100M_CPU0_CLK01_DP")
	)
	(segment
		(start 264.376408 -128.227582)
		(end 266.712954 -130.564128)
		(width 0.12954)
		(layer "B.Cu")
		(net "CLK_100M_CPU0_CLK01_DP")
	)
	(segment
		(start 272.586704 -158.555436)
		(end 273.928332 -159.897064)
		(width 0.12954)
		(layer "B.Cu")
		(net "CLK_100M_CPU0_CLK01_DP")
	)
	(segment
		(start 371.837966 -213.709758)
		(end 372.251986 -214.123778)
		(width 0.12954)
		(layer "B.Cu")
		(net "CLK_100M_CPU0_CLK01_DP")
	)
	(segment
		(start 271.13484 -155.73629)
		(end 272.586704 -158.555436)
		(width 0.12954)
		(layer "B.Cu")
		(net "CLK_100M_CPU0_CLK01_DP")
	)
	(segment
		(start 229.449376 -63.110618)
		(end 238.582962 -66.893694)
		(width 0.12954)
		(layer "B.Cu")
		(net "CLK_100M_CPU0_CLK01_DP")
	)
	(segment
		(start 210.127342 -32.328104)
		(end 211.405216 -33.605978)
		(width 0.12954)
		(layer "B.Cu")
		(net "CLK_100M_CPU0_CLK01_DP")
	)
	(segment
		(start 245.614698 -73.92543)
		(end 248.384314 -80.612234)
		(width 0.12954)
		(layer "B.Cu")
		(net "CLK_100M_CPU0_CLK01_DP")
	)
	(segment
		(start 371.837966 -213.425532)
		(end 371.837966 -213.709758)
		(width 0.12954)
		(layer "B.Cu")
		(net "CLK_100M_CPU0_CLK01_DP")
	)
	(segment
		(start 266.712954 -130.564128)
		(end 267.027406 -131.174998)
		(width 0.12954)
		(layer "B.Cu")
		(net "CLK_100M_CPU0_CLK01_DP")
	)
	(segment
		(start 273.928332 -159.897064)
		(end 292.357302 -167.530526)
		(width 0.12954)
		(layer "B.Cu")
		(net "CLK_100M_CPU0_CLK01_DP")
	)
	(segment
		(start 198.18731 -25.534874)
		(end 201.340974 -28.688538)
		(width 0.12954)
		(layer "B.Cu")
		(net "CLK_100M_CPU0_CLK01_DP")
	)
	(segment
		(start 170.605704 -12.8778)
		(end 170.605704 -11.055858)
		(width 0.12954)
		(layer "F.Cu")
		(net "CLK_100M_CPU0_CLK01_DN")
	)
	(segment
		(start 170.46702 -13.599922)
		(end 170.46702 -13.016484)
		(width 0.12954)
		(layer "F.Cu")
		(net "CLK_100M_CPU0_CLK01_DN")
	)
	(segment
		(start 170.605704 -11.055858)
		(end 170.335702 -10.785856)
		(width 0.12954)
		(layer "F.Cu")
		(net "CLK_100M_CPU0_CLK01_DN")
	)
	(segment
		(start 170.46702 -13.016484)
		(end 170.605704 -12.8778)
		(width 0.12954)
		(layer "F.Cu")
		(net "CLK_100M_CPU0_CLK01_DN")
	)
	(via
		(at 170.335702 -10.785856)
		(size 0.508)
		(drill 0.254)
		(layers "F.Cu" "B.Cu")
		(net "CLK_100M_CPU0_CLK01_DN")
	)
	(segment
		(start 170.335702 -10.785856)
		(end 170.54703 -10.997184)
		(width 0.12954)
		(layer "B.Cu")
		(net "CLK_100M_CPU0_CLK01_DN")
	)
	(segment
		(start 216.175082 -45.964094)
		(end 216.175082 -48.479964)
		(width 0.12954)
		(layer "B.Cu")
		(net "CLK_100M_CPU0_CLK01_DN")
	)
	(segment
		(start 331.44714 -184.48401)
		(end 331.44714 -185.932572)
		(width 0.12954)
		(layer "B.Cu")
		(net "CLK_100M_CPU0_CLK01_DN")
	)
	(segment
		(start 184.341262 -16.69796)
		(end 189.151514 -16.69796)
		(width 0.12954)
		(layer "B.Cu")
		(net "CLK_100M_CPU0_CLK01_DN")
	)
	(segment
		(start 217.456766 -51.574446)
		(end 229.266242 -63.383922)
		(width 0.12954)
		(layer "B.Cu")
		(net "CLK_100M_CPU0_CLK01_DN")
	)
	(segment
		(start 175.469804 -16.359632)
		(end 179.722526 -16.359632)
		(width 0.12954)
		(layer "B.Cu")
		(net "CLK_100M_CPU0_CLK01_DN")
	)
	(segment
		(start 174.054516 -15.7734)
		(end 175.469804 -16.359632)
		(width 0.12954)
		(layer "B.Cu")
		(net "CLK_100M_CPU0_CLK01_DN")
	)
	(segment
		(start 196.567552 -22.468078)
		(end 197.889368 -25.658572)
		(width 0.12954)
		(layer "B.Cu")
		(net "CLK_100M_CPU0_CLK01_DN")
	)
	(segment
		(start 357.991664 -212.477096)
		(end 370.433092 -212.477096)
		(width 0.12954)
		(layer "B.Cu")
		(net "CLK_100M_CPU0_CLK01_DN")
	)
	(segment
		(start 371.515386 -213.742778)
		(end 371.134386 -214.123778)
		(width 0.12954)
		(layer "B.Cu")
		(net "CLK_100M_CPU0_CLK01_DN")
	)
	(segment
		(start 238.400082 -67.167252)
		(end 245.34114 -74.10831)
		(width 0.12954)
		(layer "B.Cu")
		(net "CLK_100M_CPU0_CLK01_DN")
	)
	(segment
		(start 371.515386 -213.55939)
		(end 371.515386 -213.742778)
		(width 0.12954)
		(layer "B.Cu")
		(net "CLK_100M_CPU0_CLK01_DN")
	)
	(segment
		(start 314.816236 -167.853106)
		(end 331.44714 -184.48401)
		(width 0.12954)
		(layer "B.Cu")
		(net "CLK_100M_CPU0_CLK01_DN")
	)
	(segment
		(start 193.751454 -19.65198)
		(end 196.567552 -22.468078)
		(width 0.12954)
		(layer "B.Cu")
		(net "CLK_100M_CPU0_CLK01_DN")
	)
	(segment
		(start 189.623192 -16.89354)
		(end 193.751454 -19.65198)
		(width 0.12954)
		(layer "B.Cu")
		(net "CLK_100M_CPU0_CLK01_DN")
	)
	(segment
		(start 245.34114 -74.10831)
		(end 248.061734 -80.676496)
		(width 0.12954)
		(layer "B.Cu")
		(net "CLK_100M_CPU0_CLK01_DN")
	)
	(segment
		(start 170.54703 -15.246604)
		(end 171.073826 -15.7734)
		(width 0.12954)
		(layer "B.Cu")
		(net "CLK_100M_CPU0_CLK01_DN")
	)
	(segment
		(start 331.44714 -185.932572)
		(end 357.991664 -212.477096)
		(width 0.12954)
		(layer "B.Cu")
		(net "CLK_100M_CPU0_CLK01_DN")
	)
	(segment
		(start 252.871478 -128.550162)
		(end 264.24255 -128.550162)
		(width 0.12954)
		(layer "B.Cu")
		(net "CLK_100M_CPU0_CLK01_DN")
	)
	(segment
		(start 248.061734 -123.740418)
		(end 252.871478 -128.550162)
		(width 0.12954)
		(layer "B.Cu")
		(net "CLK_100M_CPU0_CLK01_DN")
	)
	(segment
		(start 292.29304 -167.853106)
		(end 314.816236 -167.853106)
		(width 0.12954)
		(layer "B.Cu")
		(net "CLK_100M_CPU0_CLK01_DN")
	)
	(segment
		(start 209.944462 -32.601662)
		(end 211.131658 -33.788858)
		(width 0.12954)
		(layer "B.Cu")
		(net "CLK_100M_CPU0_CLK01_DN")
	)
	(segment
		(start 229.266242 -63.383922)
		(end 238.400082 -67.167252)
		(width 0.12954)
		(layer "B.Cu")
		(net "CLK_100M_CPU0_CLK01_DN")
	)
	(segment
		(start 273.745452 -160.170622)
		(end 292.29304 -167.853106)
		(width 0.12954)
		(layer "B.Cu")
		(net "CLK_100M_CPU0_CLK01_DN")
	)
	(segment
		(start 270.82496 -155.83916)
		(end 272.322798 -158.747968)
		(width 0.12954)
		(layer "B.Cu")
		(net "CLK_100M_CPU0_CLK01_DN")
	)
	(segment
		(start 197.889368 -25.69337)
		(end 201.158094 -28.962096)
		(width 0.12954)
		(layer "B.Cu")
		(net "CLK_100M_CPU0_CLK01_DN")
	)
	(segment
		(start 248.061734 -80.676496)
		(end 248.061734 -123.740418)
		(width 0.12954)
		(layer "B.Cu")
		(net "CLK_100M_CPU0_CLK01_DN")
	)
	(segment
		(start 170.54703 -10.997184)
		(end 170.54703 -15.246604)
		(width 0.12954)
		(layer "B.Cu")
		(net "CLK_100M_CPU0_CLK01_DN")
	)
	(segment
		(start 197.889368 -25.658572)
		(end 197.889368 -25.69337)
		(width 0.12954)
		(layer "B.Cu")
		(net "CLK_100M_CPU0_CLK01_DN")
	)
	(segment
		(start 216.175082 -48.479964)
		(end 217.456766 -51.574446)
		(width 0.12954)
		(layer "B.Cu")
		(net "CLK_100M_CPU0_CLK01_DN")
	)
	(segment
		(start 201.158094 -28.962096)
		(end 209.944462 -32.601662)
		(width 0.12954)
		(layer "B.Cu")
		(net "CLK_100M_CPU0_CLK01_DN")
	)
	(segment
		(start 189.151514 -16.69796)
		(end 189.623192 -16.89354)
		(width 0.12954)
		(layer "B.Cu")
		(net "CLK_100M_CPU0_CLK01_DN")
	)
	(segment
		(start 266.449048 -130.75666)
		(end 266.717526 -131.277868)
		(width 0.12954)
		(layer "B.Cu")
		(net "CLK_100M_CPU0_CLK01_DN")
	)
	(segment
		(start 171.073826 -15.7734)
		(end 174.054516 -15.7734)
		(width 0.12954)
		(layer "B.Cu")
		(net "CLK_100M_CPU0_CLK01_DN")
	)
	(segment
		(start 180.082444 -15.999714)
		(end 183.643016 -15.999714)
		(width 0.12954)
		(layer "B.Cu")
		(net "CLK_100M_CPU0_CLK01_DN")
	)
	(segment
		(start 264.24255 -128.550162)
		(end 266.449048 -130.75666)
		(width 0.12954)
		(layer "B.Cu")
		(net "CLK_100M_CPU0_CLK01_DN")
	)
	(segment
		(start 266.717526 -131.277868)
		(end 270.82496 -155.83916)
		(width 0.12954)
		(layer "B.Cu")
		(net "CLK_100M_CPU0_CLK01_DN")
	)
	(segment
		(start 272.322798 -158.747968)
		(end 273.745452 -160.170622)
		(width 0.12954)
		(layer "B.Cu")
		(net "CLK_100M_CPU0_CLK01_DN")
	)
	(segment
		(start 370.433092 -212.477096)
		(end 371.515386 -213.55939)
		(width 0.12954)
		(layer "B.Cu")
		(net "CLK_100M_CPU0_CLK01_DN")
	)
	(segment
		(start 183.643016 -15.999714)
		(end 184.341262 -16.69796)
		(width 0.12954)
		(layer "B.Cu")
		(net "CLK_100M_CPU0_CLK01_DN")
	)
	(segment
		(start 211.131658 -33.788858)
		(end 216.175082 -45.964094)
		(width 0.12954)
		(layer "B.Cu")
		(net "CLK_100M_CPU0_CLK01_DN")
	)
	(segment
		(start 179.722526 -16.359632)
		(end 180.082444 -15.999714)
		(width 0.12954)
		(layer "B.Cu")
		(net "CLK_100M_CPU0_CLK01_DN")
	)
	(segment
		(start 401.751038 -332.031594)
		(end 401.751038 -330.778612)
		(width 0.10668)
		(layer "F.Cu")
		(net "BOOT_RDY_R_H")
	)
	(segment
		(start 367.538 -295.19753)
		(end 366.9792 -295.75633)
		(width 0.10668)
		(layer "F.Cu")
		(net "BOOT_RDY_R_H")
	)
	(segment
		(start 366.9792 -295.75633)
		(end 366.9792 -310.643778)
		(width 0.10668)
		(layer "F.Cu")
		(net "BOOT_RDY_R_H")
	)
	(segment
		(start 399.408904 -334.373728)
		(end 401.751038 -332.031594)
		(width 0.10668)
		(layer "F.Cu")
		(net "BOOT_RDY_R_H")
	)
	(segment
		(start 390.70915 -334.373728)
		(end 399.408904 -334.373728)
		(width 0.10668)
		(layer "F.Cu")
		(net "BOOT_RDY_R_H")
	)
	(segment
		(start 385.592574 -329.257152)
		(end 390.70915 -334.373728)
		(width 0.10668)
		(layer "F.Cu")
		(net "BOOT_RDY_R_H")
	)
	(segment
		(start 367.538 -294.88003)
		(end 367.538 -295.19753)
		(width 0.10668)
		(layer "F.Cu")
		(net "BOOT_RDY_R_H")
	)
	(segment
		(start 366.9792 -310.643778)
		(end 385.592574 -329.257152)
		(width 0.10668)
		(layer "F.Cu")
		(net "BOOT_RDY_R_H")
	)
	(via
		(at 385.592574 -329.257152)
		(size 0.762)
		(drill 0.381)
		(layers "F.Cu" "B.Cu")
		(net "BOOT_RDY_R_H")
	)
	(via
		(at 400.444716 -340.047326)
		(size 0.6604)
		(drill 0.3302)
		(layers "F.Cu" "B.Cu")
		(net "BOOT_RDY_R1_N")
	)
	(segment
		(start 399.522696 -340.772242)
		(end 399.522696 -340.425786)
		(width 0.10668)
		(layer "B.Cu")
		(net "BOOT_RDY_R1_N")
	)
	(segment
		(start 401.985734 -340.047326)
		(end 402.56079 -340.622382)
		(width 0.10668)
		(layer "B.Cu")
		(net "BOOT_RDY_R1_N")
	)
	(segment
		(start 399.901156 -340.047326)
		(end 400.444716 -340.047326)
		(width 0.10668)
		(layer "B.Cu")
		(net "BOOT_RDY_R1_N")
	)
	(segment
		(start 399.522696 -340.425786)
		(end 399.901156 -340.047326)
		(width 0.10668)
		(layer "B.Cu")
		(net "BOOT_RDY_R1_N")
	)
	(segment
		(start 400.444716 -340.047326)
		(end 401.985734 -340.047326)
		(width 0.10668)
		(layer "B.Cu")
		(net "BOOT_RDY_R1_N")
	)
	(segment
		(start 402.56079 -340.622382)
		(end 405.700738 -340.622382)
		(width 0.10668)
		(layer "B.Cu")
		(net "BOOT_RDY_R1_N")
	)
	(segment
		(start 399.522696 -340.772242)
		(end 398.563592 -340.772242)
		(width 0.10668)
		(layer "B.Cu")
		(net "BOOT_RDY_R1_N")
	)
	(segment
		(start 340.31936 -20.606512)
		(end 340.31936 -21.043646)
		(width 0.10668)
		(layer "F.Cu")
		(net "BOOT_RDY_LED_N")
	)
	(segment
		(start 339.70849 -19.995642)
		(end 340.31936 -20.606512)
		(width 0.10668)
		(layer "F.Cu")
		(net "BOOT_RDY_LED_N")
	)
	(segment
		(start 339.70849 -16.400526)
		(end 339.70849 -17.894808)
		(width 0.10668)
		(layer "F.Cu")
		(net "BOOT_RDY_LED_N")
	)
	(segment
		(start 339.70849 -17.894808)
		(end 339.70849 -19.995642)
		(width 0.10668)
		(layer "F.Cu")
		(net "BOOT_RDY_LED_N")
	)
	(segment
		(start 339.70976 -16.399256)
		(end 339.70849 -16.400526)
		(width 0.10668)
		(layer "F.Cu")
		(net "BOOT_RDY_LED_N")
	)
	(via
		(at 339.70849 -17.894808)
		(size 0.762)
		(drill 0.381)
		(layers "F.Cu" "B.Cu")
		(net "BOOT_RDY_LED_N")
	)
	(segment
		(start 341.619332 -18.710656)
		(end 341.619332 -19.143726)
		(width 0.10668)
		(layer "F.Cu")
		(net "BOOT_RDY_LED")
	)
	(segment
		(start 342.442546 -22.278086)
		(end 342.442546 -23.497286)
		(width 0.10668)
		(layer "F.Cu")
		(net "BOOT_RDY_LED")
	)
	(segment
		(start 342.442546 -20.389342)
		(end 342.442546 -22.278086)
		(width 0.10668)
		(layer "F.Cu")
		(net "BOOT_RDY_LED")
	)
	(segment
		(start 341.619332 -19.143726)
		(end 341.619332 -19.566128)
		(width 0.10668)
		(layer "F.Cu")
		(net "BOOT_RDY_LED")
	)
	(segment
		(start 341.484966 -18.57629)
		(end 341.619332 -18.710656)
		(width 0.10668)
		(layer "F.Cu")
		(net "BOOT_RDY_LED")
	)
	(segment
		(start 341.103712 -18.57629)
		(end 341.484966 -18.57629)
		(width 0.10668)
		(layer "F.Cu")
		(net "BOOT_RDY_LED")
	)
	(segment
		(start 340.969346 -18.710656)
		(end 341.103712 -18.57629)
		(width 0.10668)
		(layer "F.Cu")
		(net "BOOT_RDY_LED")
	)
	(segment
		(start 340.969346 -19.143726)
		(end 340.969346 -18.710656)
		(width 0.10668)
		(layer "F.Cu")
		(net "BOOT_RDY_LED")
	)
	(segment
		(start 341.619332 -19.566128)
		(end 342.442546 -20.389342)
		(width 0.10668)
		(layer "F.Cu")
		(net "BOOT_RDY_LED")
	)
	(via
		(at 342.442546 -22.278086)
		(size 0.762)
		(drill 0.381)
		(layers "F.Cu" "B.Cu")
		(net "BOOT_RDY_LED")
	)
	(segment
		(start 402.551138 -329.762612)
		(end 402.551138 -330.778612)
		(width 0.10668)
		(layer "F.Cu")
		(net "BOOT_RDY_H")
	)
	(segment
		(start 399.372074 -334.992218)
		(end 402.16963 -332.194662)
		(width 0.10668)
		(layer "F.Cu")
		(net "BOOT_RDY_H")
	)
	(segment
		(start 399.372074 -342.44407)
		(end 399.372074 -334.992218)
		(width 0.10668)
		(layer "F.Cu")
		(net "BOOT_RDY_H")
	)
	(segment
		(start 402.16963 -331.16012)
		(end 402.551138 -330.778612)
		(width 0.10668)
		(layer "F.Cu")
		(net "BOOT_RDY_H")
	)
	(segment
		(start 402.16963 -332.194662)
		(end 402.16963 -331.16012)
		(width 0.10668)
		(layer "F.Cu")
		(net "BOOT_RDY_H")
	)
	(via
		(at 399.372074 -342.44407)
		(size 0.508)
		(drill 0.254)
		(layers "F.Cu" "B.Cu")
		(net "BOOT_RDY_H")
	)
	(segment
		(start 399.522696 -341.572342)
		(end 399.522696 -342.293448)
		(width 0.10668)
		(layer "B.Cu")
		(net "BOOT_RDY_H")
	)
	(segment
		(start 399.522696 -342.293448)
		(end 399.372074 -342.44407)
		(width 0.10668)
		(layer "B.Cu")
		(net "BOOT_RDY_H")
	)
	(segment
		(start 339.699346 -24.297386)
		(end 339.699346 -24.913336)
		(width 0.10668)
		(layer "F.Cu")
		(net "BOOT_RDY_BUF_R_LED")
	)
	(via
		(at 392.98753 -375.45391)
		(size 0.508)
		(drill 0.254)
		(layers "F.Cu" "B.Cu")
		(net "BOOT_RDY_BUF_R_LED")
	)
	(via
		(at 397.448532 -347.429836)
		(size 0.508)
		(drill 0.254)
		(layers "F.Cu" "B.Cu")
		(net "BOOT_RDY_BUF_R_LED")
	)
	(via
		(at 312.948574 -116.98732)
		(size 0.508)
		(drill 0.254)
		(layers "F.Cu" "B.Cu")
		(net "BOOT_RDY_BUF_R_LED")
	)
	(via
		(at 339.699346 -24.913336)
		(size 0.508)
		(drill 0.254)
		(layers "F.Cu" "B.Cu")
		(net "BOOT_RDY_BUF_R_LED")
	)
	(segment
		(start 400.718782 -339.31606)
		(end 401.075144 -339.672422)
		(width 0.10668)
		(layer "B.Cu")
		(net "BOOT_RDY_BUF_R_LED")
	)
	(segment
		(start 401.075144 -339.672422)
		(end 403.250654 -339.672422)
		(width 0.10668)
		(layer "B.Cu")
		(net "BOOT_RDY_BUF_R_LED")
	)
	(segment
		(start 396.09014 -339.79866)
		(end 396.57274 -339.31606)
		(width 0.10668)
		(layer "B.Cu")
		(net "BOOT_RDY_BUF_R_LED")
	)
	(segment
		(start 396.09014 -346.071444)
		(end 396.09014 -339.79866)
		(width 0.10668)
		(layer "B.Cu")
		(net "BOOT_RDY_BUF_R_LED")
	)
	(segment
		(start 396.57274 -339.31606)
		(end 400.718782 -339.31606)
		(width 0.10668)
		(layer "B.Cu")
		(net "BOOT_RDY_BUF_R_LED")
	)
	(segment
		(start 397.448532 -347.429836)
		(end 396.09014 -346.071444)
		(width 0.10668)
		(layer "B.Cu")
		(net "BOOT_RDY_BUF_R_LED")
	)
	(segment
		(start 426.09897 -124.219716)
		(end 402.070824 -124.219716)
		(width 0.11684)
		(layer "In2.Cu")
		(net "BOOT_RDY_BUF_R_LED")
	)
	(segment
		(start 427.426882 -370.086382)
		(end 429.37557 -370.086382)
		(width 0.11684)
		(layer "In2.Cu")
		(net "BOOT_RDY_BUF_R_LED")
	)
	(segment
		(start 445.355472 -365.143542)
		(end 448.51574 -361.983274)
		(width 0.11684)
		(layer "In2.Cu")
		(net "BOOT_RDY_BUF_R_LED")
	)
	(segment
		(start 402.070824 -124.219716)
		(end 400.353022 -125.937518)
		(width 0.11684)
		(layer "In2.Cu")
		(net "BOOT_RDY_BUF_R_LED")
	)
	(segment
		(start 432.066446 -367.395506)
		(end 435.191916 -367.395506)
		(width 0.11684)
		(layer "In2.Cu")
		(net "BOOT_RDY_BUF_R_LED")
	)
	(segment
		(start 429.37557 -370.086382)
		(end 432.066446 -367.395506)
		(width 0.11684)
		(layer "In2.Cu")
		(net "BOOT_RDY_BUF_R_LED")
	)
	(segment
		(start 393.995656 -374.445784)
		(end 423.06748 -374.445784)
		(width 0.11684)
		(layer "In2.Cu")
		(net "BOOT_RDY_BUF_R_LED")
	)
	(segment
		(start 371.994176 -124.81306)
		(end 319.783206 -124.81306)
		(width 0.11684)
		(layer "In2.Cu")
		(net "BOOT_RDY_BUF_R_LED")
	)
	(segment
		(start 448.51574 -334.881982)
		(end 461.327246 -322.070476)
		(width 0.11684)
		(layer "In2.Cu")
		(net "BOOT_RDY_BUF_R_LED")
	)
	(segment
		(start 461.327246 -322.070476)
		(end 461.327246 -176.5935)
		(width 0.11684)
		(layer "In2.Cu")
		(net "BOOT_RDY_BUF_R_LED")
	)
	(segment
		(start 398.076166 -125.937518)
		(end 397.640556 -126.373128)
		(width 0.11684)
		(layer "In2.Cu")
		(net "BOOT_RDY_BUF_R_LED")
	)
	(segment
		(start 423.06748 -374.445784)
		(end 427.426882 -370.086382)
		(width 0.11684)
		(layer "In2.Cu")
		(net "BOOT_RDY_BUF_R_LED")
	)
	(segment
		(start 397.640556 -126.373128)
		(end 373.554244 -126.373128)
		(width 0.11684)
		(layer "In2.Cu")
		(net "BOOT_RDY_BUF_R_LED")
	)
	(segment
		(start 461.327246 -176.5935)
		(end 449.757038 -165.023292)
		(width 0.11684)
		(layer "In2.Cu")
		(net "BOOT_RDY_BUF_R_LED")
	)
	(segment
		(start 400.353022 -125.937518)
		(end 398.076166 -125.937518)
		(width 0.11684)
		(layer "In2.Cu")
		(net "BOOT_RDY_BUF_R_LED")
	)
	(segment
		(start 312.948574 -117.978428)
		(end 312.948574 -116.98732)
		(width 0.11684)
		(layer "In2.Cu")
		(net "BOOT_RDY_BUF_R_LED")
	)
	(segment
		(start 449.757038 -147.877784)
		(end 426.09897 -124.219716)
		(width 0.11684)
		(layer "In2.Cu")
		(net "BOOT_RDY_BUF_R_LED")
	)
	(segment
		(start 449.757038 -165.023292)
		(end 449.757038 -147.877784)
		(width 0.11684)
		(layer "In2.Cu")
		(net "BOOT_RDY_BUF_R_LED")
	)
	(segment
		(start 435.191916 -367.395506)
		(end 437.44388 -365.143542)
		(width 0.11684)
		(layer "In2.Cu")
		(net "BOOT_RDY_BUF_R_LED")
	)
	(segment
		(start 437.44388 -365.143542)
		(end 445.355472 -365.143542)
		(width 0.11684)
		(layer "In2.Cu")
		(net "BOOT_RDY_BUF_R_LED")
	)
	(segment
		(start 448.51574 -361.983274)
		(end 448.51574 -334.881982)
		(width 0.11684)
		(layer "In2.Cu")
		(net "BOOT_RDY_BUF_R_LED")
	)
	(segment
		(start 319.783206 -124.81306)
		(end 312.948574 -117.978428)
		(width 0.11684)
		(layer "In2.Cu")
		(net "BOOT_RDY_BUF_R_LED")
	)
	(segment
		(start 373.554244 -126.373128)
		(end 371.994176 -124.81306)
		(width 0.11684)
		(layer "In2.Cu")
		(net "BOOT_RDY_BUF_R_LED")
	)
	(segment
		(start 392.98753 -375.45391)
		(end 393.995656 -374.445784)
		(width 0.11684)
		(layer "In2.Cu")
		(net "BOOT_RDY_BUF_R_LED")
	)
	(segment
		(start 337.92795 -59.98972)
		(end 339.699346 -58.218324)
		(width 0.11684)
		(layer "In4.Cu")
		(net "BOOT_RDY_BUF_R_LED")
	)
	(segment
		(start 312.54192 -116.580666)
		(end 312.54192 -108.483654)
		(width 0.11684)
		(layer "In4.Cu")
		(net "BOOT_RDY_BUF_R_LED")
	)
	(segment
		(start 337.92795 -80.26019)
		(end 337.92795 -59.98972)
		(width 0.11684)
		(layer "In4.Cu")
		(net "BOOT_RDY_BUF_R_LED")
	)
	(segment
		(start 312.948574 -116.98732)
		(end 312.54192 -116.580666)
		(width 0.11684)
		(layer "In4.Cu")
		(net "BOOT_RDY_BUF_R_LED")
	)
	(segment
		(start 316.587378 -104.438196)
		(end 316.587378 -101.600762)
		(width 0.11684)
		(layer "In4.Cu")
		(net "BOOT_RDY_BUF_R_LED")
	)
	(segment
		(start 312.54192 -108.483654)
		(end 316.587378 -104.438196)
		(width 0.11684)
		(layer "In4.Cu")
		(net "BOOT_RDY_BUF_R_LED")
	)
	(segment
		(start 339.699346 -58.218324)
		(end 339.699346 -24.913336)
		(width 0.11684)
		(layer "In4.Cu")
		(net "BOOT_RDY_BUF_R_LED")
	)
	(segment
		(start 316.587378 -101.600762)
		(end 337.92795 -80.26019)
		(width 0.11684)
		(layer "In4.Cu")
		(net "BOOT_RDY_BUF_R_LED")
	)
	(segment
		(start 392.98753 -375.45391)
		(end 398.704562 -375.45391)
		(width 0.11684)
		(layer "In15.Cu")
		(net "BOOT_RDY_BUF_R_LED")
	)
	(segment
		(start 401.957286 -351.93859)
		(end 397.448532 -347.429836)
		(width 0.11684)
		(layer "In15.Cu")
		(net "BOOT_RDY_BUF_R_LED")
	)
	(segment
		(start 402.880322 -353.637088)
		(end 401.957286 -352.714052)
		(width 0.11684)
		(layer "In15.Cu")
		(net "BOOT_RDY_BUF_R_LED")
	)
	(segment
		(start 401.957286 -352.714052)
		(end 401.957286 -351.93859)
		(width 0.11684)
		(layer "In15.Cu")
		(net "BOOT_RDY_BUF_R_LED")
	)
	(segment
		(start 398.704562 -375.45391)
		(end 402.880322 -371.27815)
		(width 0.11684)
		(layer "In15.Cu")
		(net "BOOT_RDY_BUF_R_LED")
	)
	(segment
		(start 402.880322 -371.27815)
		(end 402.880322 -353.637088)
		(width 0.11684)
		(layer "In15.Cu")
		(net "BOOT_RDY_BUF_R_LED")
	)
	(segment
		(start 339.699346 -23.497286)
		(end 340.715346 -23.497286)
		(width 0.10668)
		(layer "F.Cu")
		(net "BOOT_RDY_BUF_LED")
	)
	(segment
		(start 340.969346 -22.024086)
		(end 340.715346 -22.278086)
		(width 0.10668)
		(layer "F.Cu")
		(net "BOOT_RDY_BUF_LED")
	)
	(segment
		(start 340.715346 -22.278086)
		(end 340.715346 -23.497286)
		(width 0.10668)
		(layer "F.Cu")
		(net "BOOT_RDY_BUF_LED")
	)
	(segment
		(start 340.969346 -21.043646)
		(end 340.969346 -22.024086)
		(width 0.10668)
		(layer "F.Cu")
		(net "BOOT_RDY_BUF_LED")
	)
	(via
		(at 340.715346 -22.278086)
		(size 0.762)
		(drill 0.381)
		(layers "F.Cu" "B.Cu")
		(net "BOOT_RDY_BUF_LED")
	)
	(segment
		(start 208.38795 -184.750202)
		(end 210.293712 -189.350904)
		(width 0.10668)
		(layer "F.Cu")
		(net "BMC_MONITER_R")
	)
	(segment
		(start 199.425306 -180.489098)
		(end 204.126846 -180.489098)
		(width 0.10668)
		(layer "F.Cu")
		(net "BMC_MONITER_R")
	)
	(segment
		(start 210.293712 -194.202558)
		(end 209.548476 -194.947794)
		(width 0.10668)
		(layer "F.Cu")
		(net "BMC_MONITER_R")
	)
	(segment
		(start 204.126846 -180.489098)
		(end 208.38795 -184.750202)
		(width 0.10668)
		(layer "F.Cu")
		(net "BMC_MONITER_R")
	)
	(segment
		(start 191.320674 -172.384466)
		(end 199.425306 -180.489098)
		(width 0.10668)
		(layer "F.Cu")
		(net "BMC_MONITER_R")
	)
	(segment
		(start 209.294476 -110.649512)
		(end 209.85226 -110.649512)
		(width 0.10668)
		(layer "F.Cu")
		(net "BMC_MONITER_R")
	)
	(segment
		(start 209.548476 -194.947794)
		(end 208.989676 -194.947794)
		(width 0.10668)
		(layer "F.Cu")
		(net "BMC_MONITER_R")
	)
	(segment
		(start 209.85226 -110.649512)
		(end 209.924396 -110.577376)
		(width 0.10668)
		(layer "F.Cu")
		(net "BMC_MONITER_R")
	)
	(segment
		(start 210.293712 -189.350904)
		(end 210.293712 -194.202558)
		(width 0.10668)
		(layer "F.Cu")
		(net "BMC_MONITER_R")
	)
	(via
		(at 209.924396 -110.577376)
		(size 0.508)
		(drill 0.254)
		(layers "F.Cu" "B.Cu")
		(net "BMC_MONITER_R")
	)
	(via
		(at 174.496476 -413.785558)
		(size 0.508)
		(drill 0.254)
		(layers "F.Cu" "B.Cu")
		(net "BMC_MONITER_R")
	)
	(via
		(at 208.989676 -194.947794)
		(size 0.508)
		(drill 0.254)
		(layers "F.Cu" "B.Cu")
		(net "BMC_MONITER_R")
	)
	(via
		(at 202.762104 -134.968488)
		(size 0.6604)
		(drill 0.3302)
		(layers "F.Cu" "B.Cu")
		(net "BMC_MONITER_R")
	)
	(via
		(at 191.320674 -172.384466)
		(size 0.508)
		(drill 0.254)
		(layers "F.Cu" "B.Cu")
		(net "BMC_MONITER_R")
	)
	(segment
		(start 201.815954 -134.022338)
		(end 202.762104 -134.968488)
		(width 0.10668)
		(layer "B.Cu")
		(net "BMC_MONITER_R")
	)
	(segment
		(start 220.733366 -122.966734)
		(end 219.044266 -124.655834)
		(width 0.10668)
		(layer "B.Cu")
		(net "BMC_MONITER_R")
	)
	(segment
		(start 219.338652 -109.780832)
		(end 220.733366 -111.175546)
		(width 0.10668)
		(layer "B.Cu")
		(net "BMC_MONITER_R")
	)
	(segment
		(start 208.27873 -127.093472)
		(end 204.93101 -127.093472)
		(width 0.10668)
		(layer "B.Cu")
		(net "BMC_MONITER_R")
	)
	(segment
		(start 202.762104 -135.76808)
		(end 202.762104 -134.968488)
		(width 0.10668)
		(layer "B.Cu")
		(net "BMC_MONITER_R")
	)
	(segment
		(start 191.320674 -172.384466)
		(end 193.007488 -174.07128)
		(width 0.10668)
		(layer "B.Cu")
		(net "BMC_MONITER_R")
	)
	(segment
		(start 219.044266 -124.655834)
		(end 219.044266 -125.01626)
		(width 0.10668)
		(layer "B.Cu")
		(net "BMC_MONITER_R")
	)
	(segment
		(start 217.880184 -126.180342)
		(end 209.19186 -126.180342)
		(width 0.10668)
		(layer "B.Cu")
		(net "BMC_MONITER_R")
	)
	(segment
		(start 209.924396 -110.577376)
		(end 210.72094 -109.780832)
		(width 0.10668)
		(layer "B.Cu")
		(net "BMC_MONITER_R")
	)
	(segment
		(start 210.72094 -109.780832)
		(end 219.338652 -109.780832)
		(width 0.10668)
		(layer "B.Cu")
		(net "BMC_MONITER_R")
	)
	(segment
		(start 197.636892 -174.07128)
		(end 203.890626 -167.817546)
		(width 0.10668)
		(layer "B.Cu")
		(net "BMC_MONITER_R")
	)
	(segment
		(start 203.523342 -126.63678)
		(end 201.815954 -128.344168)
		(width 0.10668)
		(layer "B.Cu")
		(net "BMC_MONITER_R")
	)
	(segment
		(start 203.890626 -167.817546)
		(end 203.890626 -136.896602)
		(width 0.10668)
		(layer "B.Cu")
		(net "BMC_MONITER_R")
	)
	(segment
		(start 209.19186 -126.180342)
		(end 208.27873 -127.093472)
		(width 0.10668)
		(layer "B.Cu")
		(net "BMC_MONITER_R")
	)
	(segment
		(start 172.856144 -413.776668)
		(end 172.856144 -414.792668)
		(width 0.10668)
		(layer "B.Cu")
		(net "BMC_MONITER_R")
	)
	(segment
		(start 173.489366 -414.792668)
		(end 174.496476 -413.785558)
		(width 0.10668)
		(layer "B.Cu")
		(net "BMC_MONITER_R")
	)
	(segment
		(start 172.856144 -414.792668)
		(end 173.489366 -414.792668)
		(width 0.10668)
		(layer "B.Cu")
		(net "BMC_MONITER_R")
	)
	(segment
		(start 201.815954 -128.344168)
		(end 201.815954 -134.022338)
		(width 0.10668)
		(layer "B.Cu")
		(net "BMC_MONITER_R")
	)
	(segment
		(start 174.496476 -413.785558)
		(end 175.483012 -413.785558)
		(width 0.10668)
		(layer "B.Cu")
		(net "BMC_MONITER_R")
	)
	(segment
		(start 220.733366 -111.175546)
		(end 220.733366 -122.966734)
		(width 0.10668)
		(layer "B.Cu")
		(net "BMC_MONITER_R")
	)
	(segment
		(start 193.007488 -174.07128)
		(end 197.636892 -174.07128)
		(width 0.10668)
		(layer "B.Cu")
		(net "BMC_MONITER_R")
	)
	(segment
		(start 204.93101 -127.093472)
		(end 204.474318 -126.63678)
		(width 0.10668)
		(layer "B.Cu")
		(net "BMC_MONITER_R")
	)
	(segment
		(start 204.474318 -126.63678)
		(end 203.523342 -126.63678)
		(width 0.10668)
		(layer "B.Cu")
		(net "BMC_MONITER_R")
	)
	(segment
		(start 203.890626 -136.896602)
		(end 202.762104 -135.76808)
		(width 0.10668)
		(layer "B.Cu")
		(net "BMC_MONITER_R")
	)
	(segment
		(start 219.044266 -125.01626)
		(end 217.880184 -126.180342)
		(width 0.10668)
		(layer "B.Cu")
		(net "BMC_MONITER_R")
	)
	(segment
		(start 179.092352 -389.68934)
		(end 176.78654 -391.995152)
		(width 0.11684)
		(layer "In6.Cu")
		(net "BMC_MONITER_R")
	)
	(segment
		(start 216.684098 -319.799462)
		(end 228.513386 -331.62875)
		(width 0.11684)
		(layer "In6.Cu")
		(net "BMC_MONITER_R")
	)
	(segment
		(start 177.414682 -400.929348)
		(end 178.066192 -400.929348)
		(width 0.11684)
		(layer "In6.Cu")
		(net "BMC_MONITER_R")
	)
	(segment
		(start 178.612546 -406.296622)
		(end 178.612546 -407.705052)
		(width 0.11684)
		(layer "In6.Cu")
		(net "BMC_MONITER_R")
	)
	(segment
		(start 182.292752 -383.545588)
		(end 182.292752 -387.196076)
		(width 0.11684)
		(layer "In6.Cu")
		(net "BMC_MONITER_R")
	)
	(segment
		(start 174.605188 -411.640782)
		(end 174.605188 -412.205678)
		(width 0.11684)
		(layer "In6.Cu")
		(net "BMC_MONITER_R")
	)
	(segment
		(start 179.799488 -389.68934)
		(end 179.092352 -389.68934)
		(width 0.11684)
		(layer "In6.Cu")
		(net "BMC_MONITER_R")
	)
	(segment
		(start 178.612546 -407.705052)
		(end 178.764438 -407.856944)
		(width 0.11684)
		(layer "In6.Cu")
		(net "BMC_MONITER_R")
	)
	(segment
		(start 191.797686 -375.617232)
		(end 190.221108 -375.617232)
		(width 0.11684)
		(layer "In6.Cu")
		(net "BMC_MONITER_R")
	)
	(segment
		(start 174.973488 -412.573978)
		(end 174.973488 -413.308546)
		(width 0.11684)
		(layer "In6.Cu")
		(net "BMC_MONITER_R")
	)
	(segment
		(start 178.28895 -401.152106)
		(end 178.28895 -405.973026)
		(width 0.11684)
		(layer "In6.Cu")
		(net "BMC_MONITER_R")
	)
	(segment
		(start 209.986372 -194.947794)
		(end 216.684098 -201.64552)
		(width 0.11684)
		(layer "In6.Cu")
		(net "BMC_MONITER_R")
	)
	(segment
		(start 193.464434 -373.950484)
		(end 191.797686 -375.617232)
		(width 0.11684)
		(layer "In6.Cu")
		(net "BMC_MONITER_R")
	)
	(segment
		(start 178.066192 -400.929348)
		(end 178.28895 -401.152106)
		(width 0.11684)
		(layer "In6.Cu")
		(net "BMC_MONITER_R")
	)
	(segment
		(start 221.200726 -373.950484)
		(end 193.464434 -373.950484)
		(width 0.11684)
		(layer "In6.Cu")
		(net "BMC_MONITER_R")
	)
	(segment
		(start 216.684098 -201.64552)
		(end 216.684098 -319.799462)
		(width 0.11684)
		(layer "In6.Cu")
		(net "BMC_MONITER_R")
	)
	(segment
		(start 177.887884 -409.789376)
		(end 176.456594 -409.789376)
		(width 0.11684)
		(layer "In6.Cu")
		(net "BMC_MONITER_R")
	)
	(segment
		(start 176.456594 -409.789376)
		(end 174.605188 -411.640782)
		(width 0.11684)
		(layer "In6.Cu")
		(net "BMC_MONITER_R")
	)
	(segment
		(start 176.78654 -400.301206)
		(end 177.414682 -400.929348)
		(width 0.11684)
		(layer "In6.Cu")
		(net "BMC_MONITER_R")
	)
	(segment
		(start 174.605188 -412.205678)
		(end 174.973488 -412.573978)
		(width 0.11684)
		(layer "In6.Cu")
		(net "BMC_MONITER_R")
	)
	(segment
		(start 208.989676 -194.947794)
		(end 209.986372 -194.947794)
		(width 0.11684)
		(layer "In6.Cu")
		(net "BMC_MONITER_R")
	)
	(segment
		(start 178.764438 -408.912822)
		(end 177.887884 -409.789376)
		(width 0.11684)
		(layer "In6.Cu")
		(net "BMC_MONITER_R")
	)
	(segment
		(start 227.474526 -367.676684)
		(end 221.200726 -373.950484)
		(width 0.11684)
		(layer "In6.Cu")
		(net "BMC_MONITER_R")
	)
	(segment
		(start 228.513386 -363.44733)
		(end 227.474526 -364.48619)
		(width 0.11684)
		(layer "In6.Cu")
		(net "BMC_MONITER_R")
	)
	(segment
		(start 178.28895 -405.973026)
		(end 178.612546 -406.296622)
		(width 0.11684)
		(layer "In6.Cu")
		(net "BMC_MONITER_R")
	)
	(segment
		(start 176.78654 -391.995152)
		(end 176.78654 -400.301206)
		(width 0.11684)
		(layer "In6.Cu")
		(net "BMC_MONITER_R")
	)
	(segment
		(start 174.973488 -413.308546)
		(end 174.496476 -413.785558)
		(width 0.11684)
		(layer "In6.Cu")
		(net "BMC_MONITER_R")
	)
	(segment
		(start 227.474526 -364.48619)
		(end 227.474526 -367.676684)
		(width 0.11684)
		(layer "In6.Cu")
		(net "BMC_MONITER_R")
	)
	(segment
		(start 190.221108 -375.617232)
		(end 182.292752 -383.545588)
		(width 0.11684)
		(layer "In6.Cu")
		(net "BMC_MONITER_R")
	)
	(segment
		(start 228.513386 -331.62875)
		(end 228.513386 -363.44733)
		(width 0.11684)
		(layer "In6.Cu")
		(net "BMC_MONITER_R")
	)
	(segment
		(start 178.764438 -407.856944)
		(end 178.764438 -408.912822)
		(width 0.11684)
		(layer "In6.Cu")
		(net "BMC_MONITER_R")
	)
	(segment
		(start 182.292752 -387.196076)
		(end 179.799488 -389.68934)
		(width 0.11684)
		(layer "In6.Cu")
		(net "BMC_MONITER_R")
	)
	(via
		(at 178.411632 -412.756858)
		(size 0.6604)
		(drill 0.3302)
		(layers "F.Cu" "B.Cu")
		(net "BMC_MONITER_BUF_R")
	)
	(segment
		(start 182.401718 -413.631634)
		(end 182.401718 -413.743394)
		(width 0.10668)
		(layer "B.Cu")
		(net "BMC_MONITER_BUF_R")
	)
	(segment
		(start 181.319678 -412.549594)
		(end 182.401718 -413.631634)
		(width 0.10668)
		(layer "B.Cu")
		(net "BMC_MONITER_BUF_R")
	)
	(segment
		(start 181.182518 -412.549594)
		(end 181.319678 -412.549594)
		(width 0.10668)
		(layer "B.Cu")
		(net "BMC_MONITER_BUF_R")
	)
	(segment
		(start 178.411632 -412.756858)
		(end 178.618896 -412.549594)
		(width 0.10668)
		(layer "B.Cu")
		(net "BMC_MONITER_BUF_R")
	)
	(segment
		(start 178.618896 -412.549594)
		(end 180.166518 -412.549594)
		(width 0.10668)
		(layer "B.Cu")
		(net "BMC_MONITER_BUF_R")
	)
	(segment
		(start 177.382932 -413.785558)
		(end 178.411632 -412.756858)
		(width 0.10668)
		(layer "B.Cu")
		(net "BMC_MONITER_BUF_R")
	)
	(segment
		(start 180.166518 -412.549594)
		(end 181.182518 -412.549594)
		(width 0.10668)
		(layer "B.Cu")
		(net "BMC_MONITER_BUF_R")
	)
	(segment
		(start 168.364916 -414.081976)
		(end 164.80663 -417.640262)
		(width 0.10668)
		(layer "F.Cu")
		(net "BMC_MONITER_BUF")
	)
	(segment
		(start 170.269154 -414.081976)
		(end 168.364916 -414.081976)
		(width 0.10668)
		(layer "F.Cu")
		(net "BMC_MONITER_BUF")
	)
	(segment
		(start 181.029102 -411.503368)
		(end 179.683918 -412.848552)
		(width 0.10668)
		(layer "F.Cu")
		(net "BMC_MONITER_BUF")
	)
	(segment
		(start 179.683918 -412.848552)
		(end 176.187862 -412.848552)
		(width 0.10668)
		(layer "F.Cu")
		(net "BMC_MONITER_BUF")
	)
	(segment
		(start 182.404766 -412.57982)
		(end 182.404766 -411.866588)
		(width 0.10668)
		(layer "F.Cu")
		(net "BMC_MONITER_BUF")
	)
	(segment
		(start 175.6918 -413.344614)
		(end 174.835312 -413.344614)
		(width 0.10668)
		(layer "F.Cu")
		(net "BMC_MONITER_BUF")
	)
	(segment
		(start 162.271202 -417.640262)
		(end 161.014918 -418.896546)
		(width 0.10668)
		(layer "F.Cu")
		(net "BMC_MONITER_BUF")
	)
	(segment
		(start 171.40174 -412.94939)
		(end 170.269154 -414.081976)
		(width 0.10668)
		(layer "F.Cu")
		(net "BMC_MONITER_BUF")
	)
	(segment
		(start 174.835312 -413.344614)
		(end 174.769272 -413.278574)
		(width 0.10668)
		(layer "F.Cu")
		(net "BMC_MONITER_BUF")
	)
	(segment
		(start 173.476666 -412.94939)
		(end 171.40174 -412.94939)
		(width 0.10668)
		(layer "F.Cu")
		(net "BMC_MONITER_BUF")
	)
	(segment
		(start 173.80585 -413.278574)
		(end 173.476666 -412.94939)
		(width 0.10668)
		(layer "F.Cu")
		(net "BMC_MONITER_BUF")
	)
	(segment
		(start 164.80663 -417.640262)
		(end 162.271202 -417.640262)
		(width 0.10668)
		(layer "F.Cu")
		(net "BMC_MONITER_BUF")
	)
	(segment
		(start 161.014918 -418.896546)
		(end 161.014918 -422.847516)
		(width 0.10668)
		(layer "F.Cu")
		(net "BMC_MONITER_BUF")
	)
	(segment
		(start 182.404766 -411.866588)
		(end 182.041546 -411.503368)
		(width 0.10668)
		(layer "F.Cu")
		(net "BMC_MONITER_BUF")
	)
	(segment
		(start 174.769272 -413.278574)
		(end 173.80585 -413.278574)
		(width 0.10668)
		(layer "F.Cu")
		(net "BMC_MONITER_BUF")
	)
	(segment
		(start 182.041546 -411.503368)
		(end 181.029102 -411.503368)
		(width 0.10668)
		(layer "F.Cu")
		(net "BMC_MONITER_BUF")
	)
	(segment
		(start 176.187862 -412.848552)
		(end 175.6918 -413.344614)
		(width 0.10668)
		(layer "F.Cu")
		(net "BMC_MONITER_BUF")
	)
	(segment
		(start 161.014918 -422.847516)
		(end 159.971232 -423.891202)
		(width 0.10668)
		(layer "F.Cu")
		(net "BMC_MONITER_BUF")
	)
	(via
		(at 182.404766 -412.57982)
		(size 0.508)
		(drill 0.254)
		(layers "F.Cu" "B.Cu")
		(net "BMC_MONITER_BUF")
	)
	(via
		(at 159.971232 -423.891202)
		(size 0.508)
		(drill 0.254)
		(layers "F.Cu" "B.Cu")
		(net "BMC_MONITER_BUF")
	)
	(segment
		(start 182.404766 -412.946342)
		(end 182.404766 -412.57982)
		(width 0.10668)
		(layer "B.Cu")
		(net "BMC_MONITER_BUF")
	)
	(segment
		(start 183.201818 -413.743394)
		(end 182.404766 -412.946342)
		(width 0.10668)
		(layer "B.Cu")
		(net "BMC_MONITER_BUF")
	)
	(segment
		(start 145.165318 -422.990772)
		(end 159.070802 -422.990772)
		(width 0.11684)
		(layer "In2.Cu")
		(net "BMC_MONITER_BUF")
	)
	(segment
		(start 143.902684 -439.337196)
		(end 143.902684 -424.253406)
		(width 0.11684)
		(layer "In2.Cu")
		(net "BMC_MONITER_BUF")
	)
	(segment
		(start 143.902684 -424.253406)
		(end 145.165318 -422.990772)
		(width 0.11684)
		(layer "In2.Cu")
		(net "BMC_MONITER_BUF")
	)
	(segment
		(start 142.750032 -440.489848)
		(end 143.902684 -439.337196)
		(width 0.11684)
		(layer "In2.Cu")
		(net "BMC_MONITER_BUF")
	)
	(segment
		(start 159.070802 -422.990772)
		(end 159.971232 -423.891202)
		(width 0.11684)
		(layer "In2.Cu")
		(net "BMC_MONITER_BUF")
	)
	(segment
		(start 191.135 -128.977898)
		(end 191.785748 -128.32715)
		(width 0.10668)
		(layer "F.Cu")
		(net "BMC_JTAG_SEL_R")
	)
	(segment
		(start 191.785748 -128.32715)
		(end 191.785748 -127.654304)
		(width 0.10668)
		(layer "F.Cu")
		(net "BMC_JTAG_SEL_R")
	)
	(segment
		(start 191.135 -127.003556)
		(end 191.135 -125.980444)
		(width 0.10668)
		(layer "F.Cu")
		(net "BMC_JTAG_SEL_R")
	)
	(segment
		(start 189.92215 -121.852944)
		(end 190.31204 -122.242834)
		(width 0.10668)
		(layer "F.Cu")
		(net "BMC_JTAG_SEL_R")
	)
	(segment
		(start 191.135 -125.980444)
		(end 191.326008 -125.789436)
		(width 0.10668)
		(layer "F.Cu")
		(net "BMC_JTAG_SEL_R")
	)
	(segment
		(start 191.785748 -127.654304)
		(end 191.135 -127.003556)
		(width 0.10668)
		(layer "F.Cu")
		(net "BMC_JTAG_SEL_R")
	)
	(via
		(at 191.135 -127.003556)
		(size 0.762)
		(drill 0.381)
		(layers "F.Cu" "B.Cu")
		(net "BMC_JTAG_SEL_R")
	)
	(via
		(at 191.326008 -125.789436)
		(size 0.508)
		(drill 0.254)
		(layers "F.Cu" "B.Cu")
		(net "BMC_JTAG_SEL_R")
	)
	(via
		(at 190.31204 -122.242834)
		(size 0.4572)
		(drill 0.254)
		(layers "F.Cu" "B.Cu")
		(net "BMC_JTAG_SEL_R")
	)
	(segment
		(start 190.706248 -122.637042)
		(end 190.706248 -124.113036)
		(width 0.11684)
		(layer "In11.Cu")
		(net "BMC_JTAG_SEL_R")
	)
	(segment
		(start 190.706248 -124.113036)
		(end 191.326008 -124.732796)
		(width 0.11684)
		(layer "In11.Cu")
		(net "BMC_JTAG_SEL_R")
	)
	(segment
		(start 190.31204 -122.242834)
		(end 190.706248 -122.637042)
		(width 0.11684)
		(layer "In11.Cu")
		(net "BMC_JTAG_SEL_R")
	)
	(segment
		(start 191.326008 -124.732796)
		(end 191.326008 -125.789436)
		(width 0.11684)
		(layer "In11.Cu")
		(net "BMC_JTAG_SEL_R")
	)
	(segment
		(start 191.135 -131.409948)
		(end 191.135 -131.1529)
		(width 0.10668)
		(layer "F.Cu")
		(net "BMC_JTAG_SEL")
	)
	(segment
		(start 191.643 -130.6449)
		(end 191.643 -130.05054)
		(width 0.10668)
		(layer "F.Cu")
		(net "BMC_JTAG_SEL")
	)
	(segment
		(start 431.5714 -39.817548)
		(end 430.5554 -39.817548)
		(width 0.10668)
		(layer "F.Cu")
		(net "BMC_JTAG_SEL")
	)
	(segment
		(start 191.643 -130.05054)
		(end 191.370458 -129.777998)
		(width 0.10668)
		(layer "F.Cu")
		(net "BMC_JTAG_SEL")
	)
	(segment
		(start 191.370458 -129.777998)
		(end 191.135 -129.777998)
		(width 0.10668)
		(layer "F.Cu")
		(net "BMC_JTAG_SEL")
	)
	(segment
		(start 191.135 -131.1529)
		(end 191.643 -130.6449)
		(width 0.10668)
		(layer "F.Cu")
		(net "BMC_JTAG_SEL")
	)
	(via
		(at 430.5554 -39.817548)
		(size 0.508)
		(drill 0.254)
		(layers "F.Cu" "B.Cu")
		(net "BMC_JTAG_SEL")
	)
	(via
		(at 191.135 -131.409948)
		(size 0.508)
		(drill 0.254)
		(layers "F.Cu" "B.Cu")
		(net "BMC_JTAG_SEL")
	)
	(via
		(at 264.17524 -79.636112)
		(size 0.508)
		(drill 0.254)
		(layers "F.Cu" "B.Cu")
		(net "BMC_JTAG_SEL")
	)
	(via
		(at 263.10844 -123.437904)
		(size 0.508)
		(drill 0.254)
		(layers "F.Cu" "B.Cu")
		(net "BMC_JTAG_SEL")
	)
	(segment
		(start 430.3014 -40.071548)
		(end 430.5554 -39.817548)
		(width 0.10668)
		(layer "B.Cu")
		(net "BMC_JTAG_SEL")
	)
	(segment
		(start 429.387 -40.071548)
		(end 430.3014 -40.071548)
		(width 0.10668)
		(layer "B.Cu")
		(net "BMC_JTAG_SEL")
	)
	(segment
		(start 190.693802 -131.851146)
		(end 191.135 -131.409948)
		(width 0.11684)
		(layer "In2.Cu")
		(net "BMC_JTAG_SEL")
	)
	(segment
		(start 202.70597 -133.36397)
		(end 190.820802 -133.36397)
		(width 0.11684)
		(layer "In2.Cu")
		(net "BMC_JTAG_SEL")
	)
	(segment
		(start 250.95454 -126.827534)
		(end 245.041166 -132.740908)
		(width 0.11684)
		(layer "In2.Cu")
		(net "BMC_JTAG_SEL")
	)
	(segment
		(start 203.329032 -132.740908)
		(end 202.70597 -133.36397)
		(width 0.11684)
		(layer "In2.Cu")
		(net "BMC_JTAG_SEL")
	)
	(segment
		(start 190.820802 -133.36397)
		(end 190.693802 -133.23697)
		(width 0.11684)
		(layer "In2.Cu")
		(net "BMC_JTAG_SEL")
	)
	(segment
		(start 262.567166 -123.979178)
		(end 259.161534 -123.979178)
		(width 0.11684)
		(layer "In2.Cu")
		(net "BMC_JTAG_SEL")
	)
	(segment
		(start 252.438662 -126.212854)
		(end 250.95454 -126.827534)
		(width 0.11684)
		(layer "In2.Cu")
		(net "BMC_JTAG_SEL")
	)
	(segment
		(start 256.927858 -126.212854)
		(end 252.438662 -126.212854)
		(width 0.11684)
		(layer "In2.Cu")
		(net "BMC_JTAG_SEL")
	)
	(segment
		(start 259.161534 -123.979178)
		(end 256.927858 -126.212854)
		(width 0.11684)
		(layer "In2.Cu")
		(net "BMC_JTAG_SEL")
	)
	(segment
		(start 263.10844 -123.437904)
		(end 262.567166 -123.979178)
		(width 0.11684)
		(layer "In2.Cu")
		(net "BMC_JTAG_SEL")
	)
	(segment
		(start 245.041166 -132.740908)
		(end 203.329032 -132.740908)
		(width 0.11684)
		(layer "In2.Cu")
		(net "BMC_JTAG_SEL")
	)
	(segment
		(start 190.693802 -133.23697)
		(end 190.693802 -131.851146)
		(width 0.11684)
		(layer "In2.Cu")
		(net "BMC_JTAG_SEL")
	)
	(segment
		(start 263.438894 -103.83012)
		(end 263.438894 -80.372458)
		(width 0.11684)
		(layer "In4.Cu")
		(net "BMC_JTAG_SEL")
	)
	(segment
		(start 263.10844 -123.437904)
		(end 263.10844 -115.56492)
		(width 0.11684)
		(layer "In4.Cu")
		(net "BMC_JTAG_SEL")
	)
	(segment
		(start 266.0142 -113.86566)
		(end 266.94384 -112.93602)
		(width 0.11684)
		(layer "In4.Cu")
		(net "BMC_JTAG_SEL")
	)
	(segment
		(start 266.94384 -107.335066)
		(end 263.438894 -103.83012)
		(width 0.11684)
		(layer "In4.Cu")
		(net "BMC_JTAG_SEL")
	)
	(segment
		(start 266.94384 -112.93602)
		(end 266.94384 -107.335066)
		(width 0.11684)
		(layer "In4.Cu")
		(net "BMC_JTAG_SEL")
	)
	(segment
		(start 263.438894 -80.372458)
		(end 264.17524 -79.636112)
		(width 0.11684)
		(layer "In4.Cu")
		(net "BMC_JTAG_SEL")
	)
	(segment
		(start 264.8077 -113.86566)
		(end 266.0142 -113.86566)
		(width 0.11684)
		(layer "In4.Cu")
		(net "BMC_JTAG_SEL")
	)
	(segment
		(start 263.10844 -115.56492)
		(end 264.8077 -113.86566)
		(width 0.11684)
		(layer "In4.Cu")
		(net "BMC_JTAG_SEL")
	)
	(segment
		(start 288.101278 -57.35701)
		(end 280.096214 -65.362074)
		(width 0.11684)
		(layer "In6.Cu")
		(net "BMC_JTAG_SEL")
	)
	(segment
		(start 395.583156 -40.29964)
		(end 380.693168 -55.189628)
		(width 0.11684)
		(layer "In6.Cu")
		(net "BMC_JTAG_SEL")
	)
	(segment
		(start 280.096214 -65.362074)
		(end 280.096214 -69.895466)
		(width 0.11684)
		(layer "In6.Cu")
		(net "BMC_JTAG_SEL")
	)
	(segment
		(start 308.279292 -54.478428)
		(end 305.40071 -57.35701)
		(width 0.11684)
		(layer "In6.Cu")
		(net "BMC_JTAG_SEL")
	)
	(segment
		(start 280.096214 -69.895466)
		(end 276.488144 -73.503536)
		(width 0.11684)
		(layer "In6.Cu")
		(net "BMC_JTAG_SEL")
	)
	(segment
		(start 426.05452 -38.5445)
		(end 424.29938 -40.29964)
		(width 0.11684)
		(layer "In6.Cu")
		(net "BMC_JTAG_SEL")
	)
	(segment
		(start 430.5554 -39.817548)
		(end 429.282352 -38.5445)
		(width 0.11684)
		(layer "In6.Cu")
		(net "BMC_JTAG_SEL")
	)
	(segment
		(start 324.1675 -55.17642)
		(end 323.469508 -54.478428)
		(width 0.11684)
		(layer "In6.Cu")
		(net "BMC_JTAG_SEL")
	)
	(segment
		(start 305.40071 -57.35701)
		(end 288.101278 -57.35701)
		(width 0.11684)
		(layer "In6.Cu")
		(net "BMC_JTAG_SEL")
	)
	(segment
		(start 429.282352 -38.5445)
		(end 426.05452 -38.5445)
		(width 0.11684)
		(layer "In6.Cu")
		(net "BMC_JTAG_SEL")
	)
	(segment
		(start 270.307816 -73.503536)
		(end 264.17524 -79.636112)
		(width 0.11684)
		(layer "In6.Cu")
		(net "BMC_JTAG_SEL")
	)
	(segment
		(start 329.837796 -55.17642)
		(end 324.1675 -55.17642)
		(width 0.11684)
		(layer "In6.Cu")
		(net "BMC_JTAG_SEL")
	)
	(segment
		(start 424.29938 -40.29964)
		(end 395.583156 -40.29964)
		(width 0.11684)
		(layer "In6.Cu")
		(net "BMC_JTAG_SEL")
	)
	(segment
		(start 323.469508 -54.478428)
		(end 308.279292 -54.478428)
		(width 0.11684)
		(layer "In6.Cu")
		(net "BMC_JTAG_SEL")
	)
	(segment
		(start 329.851004 -55.189628)
		(end 329.837796 -55.17642)
		(width 0.11684)
		(layer "In6.Cu")
		(net "BMC_JTAG_SEL")
	)
	(segment
		(start 380.693168 -55.189628)
		(end 329.851004 -55.189628)
		(width 0.11684)
		(layer "In6.Cu")
		(net "BMC_JTAG_SEL")
	)
	(segment
		(start 276.488144 -73.503536)
		(end 270.307816 -73.503536)
		(width 0.11684)
		(layer "In6.Cu")
		(net "BMC_JTAG_SEL")
	)
	(segment
		(start 330.036678 -14.360144)
		(end 329.2348 -14.360144)
		(width 0.10668)
		(layer "F.Cu")
		(net "BMC_FPGA_LED2_R_N")
	)
	(segment
		(start 329.2348 -15.579344)
		(end 329.2348 -14.360144)
		(width 0.10668)
		(layer "F.Cu")
		(net "BMC_FPGA_LED2_R_N")
	)
	(segment
		(start 330.63434 -15.428214)
		(end 330.63434 -14.957806)
		(width 0.10668)
		(layer "F.Cu")
		(net "BMC_FPGA_LED2_R_N")
	)
	(segment
		(start 330.63434 -14.957806)
		(end 330.036678 -14.360144)
		(width 0.10668)
		(layer "F.Cu")
		(net "BMC_FPGA_LED2_R_N")
	)
	(via
		(at 329.2348 -14.360144)
		(size 0.762)
		(drill 0.381)
		(layers "F.Cu" "B.Cu")
		(net "BMC_FPGA_LED2_R_N")
	)
	(segment
		(start 330.63307 -16.929608)
		(end 330.63434 -16.928338)
		(width 0.10668)
		(layer "F.Cu")
		(net "BMC_FPGA_LED2_N")
	)
	(segment
		(start 330.63307 -19.747992)
		(end 330.63307 -18.374868)
		(width 0.10668)
		(layer "F.Cu")
		(net "BMC_FPGA_LED2_N")
	)
	(segment
		(start 330.63307 -18.374868)
		(end 330.63307 -16.929608)
		(width 0.10668)
		(layer "F.Cu")
		(net "BMC_FPGA_LED2_N")
	)
	(via
		(at 330.63307 -18.374868)
		(size 0.762)
		(drill 0.381)
		(layers "F.Cu" "B.Cu")
		(net "BMC_FPGA_LED2_N")
	)
	(segment
		(start 332.293976 -20.397978)
		(end 331.64399 -19.747992)
		(width 0.10668)
		(layer "F.Cu")
		(net "BMC_FPGA_LED2")
	)
	(segment
		(start 192.322196 -113.85296)
		(end 192.712086 -113.46307)
		(width 0.10668)
		(layer "F.Cu")
		(net "BMC_FPGA_LED2")
	)
	(segment
		(start 332.53299 -20.397978)
		(end 332.293976 -20.397978)
		(width 0.10668)
		(layer "F.Cu")
		(net "BMC_FPGA_LED2")
	)
	(segment
		(start 331.64399 -19.747992)
		(end 331.64399 -18.985992)
		(width 0.10668)
		(layer "F.Cu")
		(net "BMC_FPGA_LED2")
	)
	(via
		(at 258.258056 -88.920828)
		(size 0.508)
		(drill 0.254)
		(layers "F.Cu" "B.Cu")
		(net "BMC_FPGA_LED2")
	)
	(via
		(at 331.64399 -18.985992)
		(size 0.508)
		(drill 0.254)
		(layers "F.Cu" "B.Cu")
		(net "BMC_FPGA_LED2")
	)
	(via
		(at 192.712086 -113.46307)
		(size 0.4572)
		(drill 0.254)
		(layers "F.Cu" "B.Cu")
		(net "BMC_FPGA_LED2")
	)
	(segment
		(start 297.738292 -20.149312)
		(end 294.520366 -20.149312)
		(width 0.11684)
		(layer "In11.Cu")
		(net "BMC_FPGA_LED2")
	)
	(segment
		(start 260.00202 -49.583086)
		(end 260.00202 -56.039258)
		(width 0.11684)
		(layer "In11.Cu")
		(net "BMC_FPGA_LED2")
	)
	(segment
		(start 294.145716 -19.774662)
		(end 291.535104 -19.774662)
		(width 0.11684)
		(layer "In11.Cu")
		(net "BMC_FPGA_LED2")
	)
	(segment
		(start 289.431476 -13.485368)
		(end 285.973012 -13.485368)
		(width 0.11684)
		(layer "In11.Cu")
		(net "BMC_FPGA_LED2")
	)
	(segment
		(start 308.130194 -19.16684)
		(end 307.547772 -18.584418)
		(width 0.11684)
		(layer "In11.Cu")
		(net "BMC_FPGA_LED2")
	)
	(segment
		(start 271.925542 -44.528486)
		(end 265.05662 -44.528486)
		(width 0.11684)
		(layer "In11.Cu")
		(net "BMC_FPGA_LED2")
	)
	(segment
		(start 291.535104 -19.774662)
		(end 291.248592 -19.48815)
		(width 0.11684)
		(layer "In11.Cu")
		(net "BMC_FPGA_LED2")
	)
	(segment
		(start 260.00202 -56.039258)
		(end 261.730998 -57.768236)
		(width 0.11684)
		(layer "In11.Cu")
		(net "BMC_FPGA_LED2")
	)
	(segment
		(start 307.547772 -18.584418)
		(end 299.303186 -18.584418)
		(width 0.11684)
		(layer "In11.Cu")
		(net "BMC_FPGA_LED2")
	)
	(segment
		(start 299.303186 -18.584418)
		(end 297.738292 -20.149312)
		(width 0.11684)
		(layer "In11.Cu")
		(net "BMC_FPGA_LED2")
	)
	(segment
		(start 329.539346 -17.643348)
		(end 313.64174 -17.643348)
		(width 0.11684)
		(layer "In11.Cu")
		(net "BMC_FPGA_LED2")
	)
	(segment
		(start 265.05662 -44.528486)
		(end 260.00202 -49.583086)
		(width 0.11684)
		(layer "In11.Cu")
		(net "BMC_FPGA_LED2")
	)
	(segment
		(start 330.88199 -18.985992)
		(end 329.539346 -17.643348)
		(width 0.11684)
		(layer "In11.Cu")
		(net "BMC_FPGA_LED2")
	)
	(segment
		(start 331.64399 -18.985992)
		(end 330.88199 -18.985992)
		(width 0.11684)
		(layer "In11.Cu")
		(net "BMC_FPGA_LED2")
	)
	(segment
		(start 260.789928 -74.907902)
		(end 260.789928 -76.162662)
		(width 0.11684)
		(layer "In11.Cu")
		(net "BMC_FPGA_LED2")
	)
	(segment
		(start 289.431476 -16.845026)
		(end 289.431476 -13.485368)
		(width 0.11684)
		(layer "In11.Cu")
		(net "BMC_FPGA_LED2")
	)
	(segment
		(start 258.258056 -78.694534)
		(end 258.258056 -88.920828)
		(width 0.11684)
		(layer "In11.Cu")
		(net "BMC_FPGA_LED2")
	)
	(segment
		(start 294.520366 -20.149312)
		(end 294.145716 -19.774662)
		(width 0.11684)
		(layer "In11.Cu")
		(net "BMC_FPGA_LED2")
	)
	(segment
		(start 277.668482 -20.45716)
		(end 277.668482 -38.785546)
		(width 0.11684)
		(layer "In11.Cu")
		(net "BMC_FPGA_LED2")
	)
	(segment
		(start 285.973012 -13.485368)
		(end 284.638496 -14.819884)
		(width 0.11684)
		(layer "In11.Cu")
		(net "BMC_FPGA_LED2")
	)
	(segment
		(start 284.638496 -14.819884)
		(end 283.305758 -14.819884)
		(width 0.11684)
		(layer "In11.Cu")
		(net "BMC_FPGA_LED2")
	)
	(segment
		(start 261.730998 -57.768236)
		(end 261.730998 -73.966832)
		(width 0.11684)
		(layer "In11.Cu")
		(net "BMC_FPGA_LED2")
	)
	(segment
		(start 313.64174 -17.643348)
		(end 312.118248 -19.16684)
		(width 0.11684)
		(layer "In11.Cu")
		(net "BMC_FPGA_LED2")
	)
	(segment
		(start 283.305758 -14.819884)
		(end 277.668482 -20.45716)
		(width 0.11684)
		(layer "In11.Cu")
		(net "BMC_FPGA_LED2")
	)
	(segment
		(start 312.118248 -19.16684)
		(end 308.130194 -19.16684)
		(width 0.11684)
		(layer "In11.Cu")
		(net "BMC_FPGA_LED2")
	)
	(segment
		(start 291.248592 -19.48815)
		(end 291.248592 -18.662142)
		(width 0.11684)
		(layer "In11.Cu")
		(net "BMC_FPGA_LED2")
	)
	(segment
		(start 260.789928 -76.162662)
		(end 258.258056 -78.694534)
		(width 0.11684)
		(layer "In11.Cu")
		(net "BMC_FPGA_LED2")
	)
	(segment
		(start 277.668482 -38.785546)
		(end 271.925542 -44.528486)
		(width 0.11684)
		(layer "In11.Cu")
		(net "BMC_FPGA_LED2")
	)
	(segment
		(start 261.730998 -73.966832)
		(end 260.789928 -74.907902)
		(width 0.11684)
		(layer "In11.Cu")
		(net "BMC_FPGA_LED2")
	)
	(segment
		(start 291.248592 -18.662142)
		(end 289.431476 -16.845026)
		(width 0.11684)
		(layer "In11.Cu")
		(net "BMC_FPGA_LED2")
	)
	(segment
		(start 254.248158 -91.530932)
		(end 253.553468 -92.225622)
		(width 0.11684)
		(layer "In15.Cu")
		(net "BMC_FPGA_LED2")
	)
	(segment
		(start 220.327982 -108.56341)
		(end 209.380074 -108.56341)
		(width 0.11684)
		(layer "In15.Cu")
		(net "BMC_FPGA_LED2")
	)
	(segment
		(start 220.719904 -108.171488)
		(end 220.327982 -108.56341)
		(width 0.11684)
		(layer "In15.Cu")
		(net "BMC_FPGA_LED2")
	)
	(segment
		(start 233.011218 -108.171488)
		(end 220.719904 -108.171488)
		(width 0.11684)
		(layer "In15.Cu")
		(net "BMC_FPGA_LED2")
	)
	(segment
		(start 248.957084 -92.225622)
		(end 233.011218 -108.171488)
		(width 0.11684)
		(layer "In15.Cu")
		(net "BMC_FPGA_LED2")
	)
	(segment
		(start 255.637284 -88.920828)
		(end 254.248158 -90.309954)
		(width 0.11684)
		(layer "In15.Cu")
		(net "BMC_FPGA_LED2")
	)
	(segment
		(start 204.030326 -109.010196)
		(end 198.141336 -109.010196)
		(width 0.11684)
		(layer "In15.Cu")
		(net "BMC_FPGA_LED2")
	)
	(segment
		(start 197.4088 -111.66856)
		(end 196.21754 -112.85982)
		(width 0.11684)
		(layer "In15.Cu")
		(net "BMC_FPGA_LED2")
	)
	(segment
		(start 197.4088 -109.742732)
		(end 197.4088 -111.66856)
		(width 0.11684)
		(layer "In15.Cu")
		(net "BMC_FPGA_LED2")
	)
	(segment
		(start 192.712086 -113.420652)
		(end 192.712086 -113.46307)
		(width 0.11684)
		(layer "In15.Cu")
		(net "BMC_FPGA_LED2")
	)
	(segment
		(start 208.747614 -107.93095)
		(end 205.109572 -107.93095)
		(width 0.11684)
		(layer "In15.Cu")
		(net "BMC_FPGA_LED2")
	)
	(segment
		(start 258.258056 -88.920828)
		(end 255.637284 -88.920828)
		(width 0.11684)
		(layer "In15.Cu")
		(net "BMC_FPGA_LED2")
	)
	(segment
		(start 196.21754 -112.85982)
		(end 193.272918 -112.85982)
		(width 0.11684)
		(layer "In15.Cu")
		(net "BMC_FPGA_LED2")
	)
	(segment
		(start 205.109572 -107.93095)
		(end 204.030326 -109.010196)
		(width 0.11684)
		(layer "In15.Cu")
		(net "BMC_FPGA_LED2")
	)
	(segment
		(start 198.141336 -109.010196)
		(end 197.4088 -109.742732)
		(width 0.11684)
		(layer "In15.Cu")
		(net "BMC_FPGA_LED2")
	)
	(segment
		(start 254.248158 -90.309954)
		(end 254.248158 -91.530932)
		(width 0.11684)
		(layer "In15.Cu")
		(net "BMC_FPGA_LED2")
	)
	(segment
		(start 209.380074 -108.56341)
		(end 208.747614 -107.93095)
		(width 0.11684)
		(layer "In15.Cu")
		(net "BMC_FPGA_LED2")
	)
	(segment
		(start 253.553468 -92.225622)
		(end 248.957084 -92.225622)
		(width 0.11684)
		(layer "In15.Cu")
		(net "BMC_FPGA_LED2")
	)
	(segment
		(start 193.272918 -112.85982)
		(end 192.712086 -113.420652)
		(width 0.11684)
		(layer "In15.Cu")
		(net "BMC_FPGA_LED2")
	)
	(segment
		(start 333.061818 -14.360144)
		(end 332.25994 -14.360144)
		(width 0.10668)
		(layer "F.Cu")
		(net "BMC_FPGA_LED1_R_N")
	)
	(segment
		(start 332.25994 -15.579344)
		(end 332.25994 -14.360144)
		(width 0.10668)
		(layer "F.Cu")
		(net "BMC_FPGA_LED1_R_N")
	)
	(segment
		(start 333.65948 -14.957806)
		(end 333.061818 -14.360144)
		(width 0.10668)
		(layer "F.Cu")
		(net "BMC_FPGA_LED1_R_N")
	)
	(segment
		(start 333.65948 -15.428214)
		(end 333.65948 -14.957806)
		(width 0.10668)
		(layer "F.Cu")
		(net "BMC_FPGA_LED1_R_N")
	)
	(via
		(at 332.25994 -14.360144)
		(size 0.762)
		(drill 0.381)
		(layers "F.Cu" "B.Cu")
		(net "BMC_FPGA_LED1_R_N")
	)
	(segment
		(start 333.65821 -16.929608)
		(end 333.65948 -16.928338)
		(width 0.10668)
		(layer "F.Cu")
		(net "BMC_FPGA_LED1_N")
	)
	(segment
		(start 332.53299 -21.047964)
		(end 333.162656 -21.047964)
		(width 0.10668)
		(layer "F.Cu")
		(net "BMC_FPGA_LED1_N")
	)
	(segment
		(start 333.65821 -18.374868)
		(end 333.65821 -16.929608)
		(width 0.10668)
		(layer "F.Cu")
		(net "BMC_FPGA_LED1_N")
	)
	(segment
		(start 333.162656 -21.047964)
		(end 333.65821 -20.55241)
		(width 0.10668)
		(layer "F.Cu")
		(net "BMC_FPGA_LED1_N")
	)
	(segment
		(start 333.65821 -20.55241)
		(end 333.65821 -18.374868)
		(width 0.10668)
		(layer "F.Cu")
		(net "BMC_FPGA_LED1_N")
	)
	(via
		(at 333.65821 -18.374868)
		(size 0.762)
		(drill 0.381)
		(layers "F.Cu" "B.Cu")
		(net "BMC_FPGA_LED1_N")
	)
	(segment
		(start 329.995784 -20.169124)
		(end 329.995784 -19.357086)
		(width 0.10668)
		(layer "F.Cu")
		(net "BMC_FPGA_LED1")
	)
	(segment
		(start 330.63307 -20.397978)
		(end 330.224638 -20.397978)
		(width 0.10668)
		(layer "F.Cu")
		(net "BMC_FPGA_LED1")
	)
	(segment
		(start 330.224638 -20.397978)
		(end 329.995784 -20.169124)
		(width 0.10668)
		(layer "F.Cu")
		(net "BMC_FPGA_LED1")
	)
	(segment
		(start 193.922142 -113.85296)
		(end 194.312032 -113.46307)
		(width 0.10668)
		(layer "F.Cu")
		(net "BMC_FPGA_LED1")
	)
	(via
		(at 198.808848 -66.158364)
		(size 0.508)
		(drill 0.254)
		(layers "F.Cu" "B.Cu")
		(net "BMC_FPGA_LED1")
	)
	(via
		(at 194.312032 -113.46307)
		(size 0.4572)
		(drill 0.254)
		(layers "F.Cu" "B.Cu")
		(net "BMC_FPGA_LED1")
	)
	(via
		(at 197.513448 -102.49027)
		(size 0.508)
		(drill 0.254)
		(layers "F.Cu" "B.Cu")
		(net "BMC_FPGA_LED1")
	)
	(via
		(at 329.995784 -19.357086)
		(size 0.508)
		(drill 0.254)
		(layers "F.Cu" "B.Cu")
		(net "BMC_FPGA_LED1")
	)
	(via
		(at 238.39678 -59.220608)
		(size 0.508)
		(drill 0.254)
		(layers "F.Cu" "B.Cu")
		(net "BMC_FPGA_LED1")
	)
	(segment
		(start 197.41642 -85.44687)
		(end 197.568058 -85.295232)
		(width 0.11684)
		(layer "In4.Cu")
		(net "BMC_FPGA_LED1")
	)
	(segment
		(start 200.983596 -72.520556)
		(end 198.808848 -70.345808)
		(width 0.11684)
		(layer "In4.Cu")
		(net "BMC_FPGA_LED1")
	)
	(segment
		(start 198.191882 -99.997768)
		(end 198.191882 -91.90863)
		(width 0.11684)
		(layer "In4.Cu")
		(net "BMC_FPGA_LED1")
	)
	(segment
		(start 197.568058 -83.048348)
		(end 200.983596 -79.63281)
		(width 0.11684)
		(layer "In4.Cu")
		(net "BMC_FPGA_LED1")
	)
	(segment
		(start 198.808848 -70.345808)
		(end 198.808848 -66.158364)
		(width 0.11684)
		(layer "In4.Cu")
		(net "BMC_FPGA_LED1")
	)
	(segment
		(start 197.513448 -102.49027)
		(end 197.513448 -100.676202)
		(width 0.11684)
		(layer "In4.Cu")
		(net "BMC_FPGA_LED1")
	)
	(segment
		(start 197.513448 -100.676202)
		(end 198.191882 -99.997768)
		(width 0.11684)
		(layer "In4.Cu")
		(net "BMC_FPGA_LED1")
	)
	(segment
		(start 200.983596 -79.63281)
		(end 200.983596 -72.520556)
		(width 0.11684)
		(layer "In4.Cu")
		(net "BMC_FPGA_LED1")
	)
	(segment
		(start 197.568058 -85.295232)
		(end 197.568058 -83.048348)
		(width 0.11684)
		(layer "In4.Cu")
		(net "BMC_FPGA_LED1")
	)
	(segment
		(start 198.191882 -91.90863)
		(end 197.41642 -91.133168)
		(width 0.11684)
		(layer "In4.Cu")
		(net "BMC_FPGA_LED1")
	)
	(segment
		(start 197.41642 -91.133168)
		(end 197.41642 -85.44687)
		(width 0.11684)
		(layer "In4.Cu")
		(net "BMC_FPGA_LED1")
	)
	(segment
		(start 285.961328 -35.244278)
		(end 294.398954 -26.806652)
		(width 0.11684)
		(layer "In6.Cu")
		(net "BMC_FPGA_LED1")
	)
	(segment
		(start 238.39678 -59.220608)
		(end 238.39678 -60.0075)
		(width 0.11684)
		(layer "In6.Cu")
		(net "BMC_FPGA_LED1")
	)
	(segment
		(start 322.200016 -21.768308)
		(end 324.611238 -19.357086)
		(width 0.11684)
		(layer "In6.Cu")
		(net "BMC_FPGA_LED1")
	)
	(segment
		(start 324.611238 -19.357086)
		(end 329.995784 -19.357086)
		(width 0.11684)
		(layer "In6.Cu")
		(net "BMC_FPGA_LED1")
	)
	(segment
		(start 318.895476 -24.411686)
		(end 320.878708 -24.411686)
		(width 0.11684)
		(layer "In6.Cu")
		(net "BMC_FPGA_LED1")
	)
	(segment
		(start 261.624572 -60.891928)
		(end 264.776458 -57.740042)
		(width 0.11684)
		(layer "In6.Cu")
		(net "BMC_FPGA_LED1")
	)
	(segment
		(start 320.878708 -24.411686)
		(end 322.200016 -23.090378)
		(width 0.11684)
		(layer "In6.Cu")
		(net "BMC_FPGA_LED1")
	)
	(segment
		(start 294.398954 -26.806652)
		(end 316.50051 -26.806652)
		(width 0.11684)
		(layer "In6.Cu")
		(net "BMC_FPGA_LED1")
	)
	(segment
		(start 285.961328 -42.497756)
		(end 285.961328 -35.244278)
		(width 0.11684)
		(layer "In6.Cu")
		(net "BMC_FPGA_LED1")
	)
	(segment
		(start 264.776458 -57.740042)
		(end 270.719042 -57.740042)
		(width 0.11684)
		(layer "In6.Cu")
		(net "BMC_FPGA_LED1")
	)
	(segment
		(start 238.39678 -60.0075)
		(end 239.281208 -60.891928)
		(width 0.11684)
		(layer "In6.Cu")
		(net "BMC_FPGA_LED1")
	)
	(segment
		(start 316.50051 -26.806652)
		(end 318.895476 -24.411686)
		(width 0.11684)
		(layer "In6.Cu")
		(net "BMC_FPGA_LED1")
	)
	(segment
		(start 322.200016 -23.090378)
		(end 322.200016 -21.768308)
		(width 0.11684)
		(layer "In6.Cu")
		(net "BMC_FPGA_LED1")
	)
	(segment
		(start 239.281208 -60.891928)
		(end 261.624572 -60.891928)
		(width 0.11684)
		(layer "In6.Cu")
		(net "BMC_FPGA_LED1")
	)
	(segment
		(start 270.719042 -57.740042)
		(end 285.961328 -42.497756)
		(width 0.11684)
		(layer "In6.Cu")
		(net "BMC_FPGA_LED1")
	)
	(segment
		(start 194.99453 -112.90046)
		(end 194.43192 -113.46307)
		(width 0.11684)
		(layer "In11.Cu")
		(net "BMC_FPGA_LED1")
	)
	(segment
		(start 196.80428 -112.46104)
		(end 196.36486 -112.90046)
		(width 0.11684)
		(layer "In11.Cu")
		(net "BMC_FPGA_LED1")
	)
	(segment
		(start 197.147434 -105.572306)
		(end 196.80428 -105.91546)
		(width 0.11684)
		(layer "In11.Cu")
		(net "BMC_FPGA_LED1")
	)
	(segment
		(start 194.43192 -113.46307)
		(end 194.312032 -113.46307)
		(width 0.11684)
		(layer "In11.Cu")
		(net "BMC_FPGA_LED1")
	)
	(segment
		(start 197.147434 -102.856284)
		(end 197.147434 -105.572306)
		(width 0.11684)
		(layer "In11.Cu")
		(net "BMC_FPGA_LED1")
	)
	(segment
		(start 196.80428 -105.91546)
		(end 196.80428 -112.46104)
		(width 0.11684)
		(layer "In11.Cu")
		(net "BMC_FPGA_LED1")
	)
	(segment
		(start 196.36486 -112.90046)
		(end 194.99453 -112.90046)
		(width 0.11684)
		(layer "In11.Cu")
		(net "BMC_FPGA_LED1")
	)
	(segment
		(start 197.513448 -102.49027)
		(end 197.147434 -102.856284)
		(width 0.11684)
		(layer "In11.Cu")
		(net "BMC_FPGA_LED1")
	)
	(segment
		(start 237.63605 -61.936884)
		(end 237.63605 -59.981338)
		(width 0.11684)
		(layer "In15.Cu")
		(net "BMC_FPGA_LED1")
	)
	(segment
		(start 235.479336 -64.093598)
		(end 237.63605 -61.936884)
		(width 0.11684)
		(layer "In15.Cu")
		(net "BMC_FPGA_LED1")
	)
	(segment
		(start 198.808848 -66.158364)
		(end 200.873614 -64.093598)
		(width 0.11684)
		(layer "In15.Cu")
		(net "BMC_FPGA_LED1")
	)
	(segment
		(start 237.63605 -59.981338)
		(end 238.39678 -59.220608)
		(width 0.11684)
		(layer "In15.Cu")
		(net "BMC_FPGA_LED1")
	)
	(segment
		(start 200.873614 -64.093598)
		(end 235.479336 -64.093598)
		(width 0.11684)
		(layer "In15.Cu")
		(net "BMC_FPGA_LED1")
	)
	(segment
		(start 187.071 -127.003556)
		(end 187.071 -128.977898)
		(width 0.10668)
		(layer "F.Cu")
		(net "BIOS_DEBUG_MODE_R")
	)
	(segment
		(start 186.543188 -126.475744)
		(end 186.543188 -123.631706)
		(width 0.10668)
		(layer "F.Cu")
		(net "BIOS_DEBUG_MODE_R")
	)
	(segment
		(start 187.071 -127.003556)
		(end 186.543188 -126.475744)
		(width 0.10668)
		(layer "F.Cu")
		(net "BIOS_DEBUG_MODE_R")
	)
	(segment
		(start 186.543188 -123.631706)
		(end 186.722004 -123.45289)
		(width 0.10668)
		(layer "F.Cu")
		(net "BIOS_DEBUG_MODE_R")
	)
	(via
		(at 187.071 -127.003556)
		(size 0.762)
		(drill 0.381)
		(layers "F.Cu" "B.Cu")
		(net "BIOS_DEBUG_MODE_R")
	)
	(segment
		(start 187.071 -123.883674)
		(end 187.111894 -123.84278)
		(width 0.10668)
		(layer "F.Cu")
		(net "BIOS_DEBUG_MODE")
	)
	(segment
		(start 367.067846 -292.450012)
		(end 367.534698 -292.71595)
		(width 0.10668)
		(layer "F.Cu")
		(net "BIOS_DEBUG_MODE")
	)
	(segment
		(start 187.305696 -129.777998)
		(end 187.52185 -129.561844)
		(width 0.10668)
		(layer "F.Cu")
		(net "BIOS_DEBUG_MODE")
	)
	(segment
		(start 187.667392 -126.635256)
		(end 187.071 -126.038864)
		(width 0.10668)
		(layer "F.Cu")
		(net "BIOS_DEBUG_MODE")
	)
	(segment
		(start 187.667392 -127.397256)
		(end 187.667392 -126.635256)
		(width 0.10668)
		(layer "F.Cu")
		(net "BIOS_DEBUG_MODE")
	)
	(segment
		(start 337.195414 -25.737058)
		(end 337.195414 -26.727658)
		(width 0.10668)
		(layer "F.Cu")
		(net "BIOS_DEBUG_MODE")
	)
	(segment
		(start 187.071 -126.038864)
		(end 187.071 -123.883674)
		(width 0.10668)
		(layer "F.Cu")
		(net "BIOS_DEBUG_MODE")
	)
	(segment
		(start 187.52185 -129.561844)
		(end 187.52185 -127.542798)
		(width 0.10668)
		(layer "F.Cu")
		(net "BIOS_DEBUG_MODE")
	)
	(segment
		(start 187.52185 -127.542798)
		(end 187.667392 -127.397256)
		(width 0.10668)
		(layer "F.Cu")
		(net "BIOS_DEBUG_MODE")
	)
	(segment
		(start 187.071 -129.777998)
		(end 187.305696 -129.777998)
		(width 0.10668)
		(layer "F.Cu")
		(net "BIOS_DEBUG_MODE")
	)
	(segment
		(start 431.5714 -36.007548)
		(end 430.5554 -36.007548)
		(width 0.10668)
		(layer "F.Cu")
		(net "BIOS_DEBUG_MODE")
	)
	(via
		(at 396.95628 -332.57744)
		(size 0.508)
		(drill 0.254)
		(layers "F.Cu" "B.Cu")
		(net "BIOS_DEBUG_MODE")
	)
	(via
		(at 367.534698 -292.71595)
		(size 0.4064)
		(drill 0.2032)
		(layers "F.Cu" "B.Cu")
		(net "BIOS_DEBUG_MODE")
	)
	(via
		(at 430.5554 -36.007548)
		(size 0.508)
		(drill 0.254)
		(layers "F.Cu" "B.Cu")
		(net "BIOS_DEBUG_MODE")
	)
	(via
		(at 290.744402 -127.081026)
		(size 0.508)
		(drill 0.254)
		(layers "F.Cu" "B.Cu")
		(net "BIOS_DEBUG_MODE")
	)
	(via
		(at 337.195414 -26.727658)
		(size 0.508)
		(drill 0.254)
		(layers "F.Cu" "B.Cu")
		(net "BIOS_DEBUG_MODE")
	)
	(via
		(at 187.111894 -123.84278)
		(size 0.4572)
		(drill 0.254)
		(layers "F.Cu" "B.Cu")
		(net "BIOS_DEBUG_MODE")
	)
	(segment
		(start 392.07821 -332.57744)
		(end 372.970298 -313.469528)
		(width 0.10668)
		(layer "B.Cu")
		(net "BIOS_DEBUG_MODE")
	)
	(segment
		(start 367.085118 -294.548052)
		(end 367.085118 -294.116252)
		(width 0.10668)
		(layer "B.Cu")
		(net "BIOS_DEBUG_MODE")
	)
	(segment
		(start 396.95628 -332.57744)
		(end 392.07821 -332.57744)
		(width 0.10668)
		(layer "B.Cu")
		(net "BIOS_DEBUG_MODE")
	)
	(segment
		(start 367.07191 -306.17795)
		(end 367.07191 -296.615358)
		(width 0.10668)
		(layer "B.Cu")
		(net "BIOS_DEBUG_MODE")
	)
	(segment
		(start 429.387 -37.023548)
		(end 429.387 -36.007548)
		(width 0.10668)
		(layer "B.Cu")
		(net "BIOS_DEBUG_MODE")
	)
	(segment
		(start 367.534698 -293.666672)
		(end 367.534698 -292.71595)
		(width 0.10668)
		(layer "B.Cu")
		(net "BIOS_DEBUG_MODE")
	)
	(segment
		(start 367.07191 -296.615358)
		(end 367.549938 -296.13733)
		(width 0.10668)
		(layer "B.Cu")
		(net "BIOS_DEBUG_MODE")
	)
	(segment
		(start 367.549938 -296.13733)
		(end 367.549938 -295.012872)
		(width 0.10668)
		(layer "B.Cu")
		(net "BIOS_DEBUG_MODE")
	)
	(segment
		(start 367.085118 -294.116252)
		(end 367.534698 -293.666672)
		(width 0.10668)
		(layer "B.Cu")
		(net "BIOS_DEBUG_MODE")
	)
	(segment
		(start 372.970298 -312.076338)
		(end 367.07191 -306.17795)
		(width 0.10668)
		(layer "B.Cu")
		(net "BIOS_DEBUG_MODE")
	)
	(segment
		(start 367.549938 -295.012872)
		(end 367.085118 -294.548052)
		(width 0.10668)
		(layer "B.Cu")
		(net "BIOS_DEBUG_MODE")
	)
	(segment
		(start 430.5554 -36.007548)
		(end 429.387 -36.007548)
		(width 0.10668)
		(layer "B.Cu")
		(net "BIOS_DEBUG_MODE")
	)
	(segment
		(start 372.970298 -313.469528)
		(end 372.970298 -312.076338)
		(width 0.10668)
		(layer "B.Cu")
		(net "BIOS_DEBUG_MODE")
	)
	(segment
		(start 337.195414 -57.594246)
		(end 337.195414 -26.727658)
		(width 0.11684)
		(layer "In4.Cu")
		(net "BIOS_DEBUG_MODE")
	)
	(segment
		(start 316.119764 -101.347524)
		(end 335.576672 -81.890616)
		(width 0.11684)
		(layer "In4.Cu")
		(net "BIOS_DEBUG_MODE")
	)
	(segment
		(start 316.119764 -102.817422)
		(end 316.119764 -101.347524)
		(width 0.11684)
		(layer "In4.Cu")
		(net "BIOS_DEBUG_MODE")
	)
	(segment
		(start 312.0771 -106.860086)
		(end 316.119764 -102.817422)
		(width 0.11684)
		(layer "In4.Cu")
		(net "BIOS_DEBUG_MODE")
	)
	(segment
		(start 335.576672 -59.212988)
		(end 337.195414 -57.594246)
		(width 0.11684)
		(layer "In4.Cu")
		(net "BIOS_DEBUG_MODE")
	)
	(segment
		(start 306.057554 -127.952754)
		(end 312.0771 -121.933208)
		(width 0.11684)
		(layer "In4.Cu")
		(net "BIOS_DEBUG_MODE")
	)
	(segment
		(start 290.744402 -127.081026)
		(end 291.61613 -127.952754)
		(width 0.11684)
		(layer "In4.Cu")
		(net "BIOS_DEBUG_MODE")
	)
	(segment
		(start 312.0771 -121.933208)
		(end 312.0771 -106.860086)
		(width 0.11684)
		(layer "In4.Cu")
		(net "BIOS_DEBUG_MODE")
	)
	(segment
		(start 335.576672 -81.890616)
		(end 335.576672 -59.212988)
		(width 0.11684)
		(layer "In4.Cu")
		(net "BIOS_DEBUG_MODE")
	)
	(segment
		(start 291.61613 -127.952754)
		(end 306.057554 -127.952754)
		(width 0.11684)
		(layer "In4.Cu")
		(net "BIOS_DEBUG_MODE")
	)
	(segment
		(start 217.28303 -119.031004)
		(end 217.964004 -119.711978)
		(width 0.11684)
		(layer "In6.Cu")
		(net "BIOS_DEBUG_MODE")
	)
	(segment
		(start 288.072576 -127.035052)
		(end 289.334194 -128.29667)
		(width 0.11684)
		(layer "In6.Cu")
		(net "BIOS_DEBUG_MODE")
	)
	(segment
		(start 198.274686 -123.664726)
		(end 200.681336 -123.664726)
		(width 0.11684)
		(layer "In6.Cu")
		(net "BIOS_DEBUG_MODE")
	)
	(segment
		(start 290.061142 -128.29667)
		(end 290.744402 -127.61341)
		(width 0.11684)
		(layer "In6.Cu")
		(net "BIOS_DEBUG_MODE")
	)
	(segment
		(start 197.619874 -128.626108)
		(end 197.978268 -128.267714)
		(width 0.11684)
		(layer "In6.Cu")
		(net "BIOS_DEBUG_MODE")
	)
	(segment
		(start 220.132656 -120.453404)
		(end 233.149648 -120.453404)
		(width 0.11684)
		(layer "In6.Cu")
		(net "BIOS_DEBUG_MODE")
	)
	(segment
		(start 196.32168 -128.626108)
		(end 197.619874 -128.626108)
		(width 0.11684)
		(layer "In6.Cu")
		(net "BIOS_DEBUG_MODE")
	)
	(segment
		(start 191.51092 -122.757946)
		(end 191.51092 -123.815348)
		(width 0.11684)
		(layer "In6.Cu")
		(net "BIOS_DEBUG_MODE")
	)
	(segment
		(start 187.120784 -123.84278)
		(end 188.330332 -122.633232)
		(width 0.11684)
		(layer "In6.Cu")
		(net "BIOS_DEBUG_MODE")
	)
	(segment
		(start 290.744402 -127.61341)
		(end 290.744402 -127.081026)
		(width 0.11684)
		(layer "In6.Cu")
		(net "BIOS_DEBUG_MODE")
	)
	(segment
		(start 260.779006 -126.350522)
		(end 261.463536 -127.035052)
		(width 0.11684)
		(layer "In6.Cu")
		(net "BIOS_DEBUG_MODE")
	)
	(segment
		(start 191.51092 -123.815348)
		(end 196.32168 -128.626108)
		(width 0.11684)
		(layer "In6.Cu")
		(net "BIOS_DEBUG_MODE")
	)
	(segment
		(start 212.844634 -119.711978)
		(end 213.220046 -119.711978)
		(width 0.11684)
		(layer "In6.Cu")
		(net "BIOS_DEBUG_MODE")
	)
	(segment
		(start 217.964004 -119.711978)
		(end 219.39123 -119.711978)
		(width 0.11684)
		(layer "In6.Cu")
		(net "BIOS_DEBUG_MODE")
	)
	(segment
		(start 233.149648 -120.453404)
		(end 237.122462 -124.426218)
		(width 0.11684)
		(layer "In6.Cu")
		(net "BIOS_DEBUG_MODE")
	)
	(segment
		(start 197.978268 -123.961144)
		(end 198.274686 -123.664726)
		(width 0.11684)
		(layer "In6.Cu")
		(net "BIOS_DEBUG_MODE")
	)
	(segment
		(start 289.334194 -128.29667)
		(end 290.061142 -128.29667)
		(width 0.11684)
		(layer "In6.Cu")
		(net "BIOS_DEBUG_MODE")
	)
	(segment
		(start 237.122462 -124.426218)
		(end 254.385064 -124.426218)
		(width 0.11684)
		(layer "In6.Cu")
		(net "BIOS_DEBUG_MODE")
	)
	(segment
		(start 219.39123 -119.711978)
		(end 220.132656 -120.453404)
		(width 0.11684)
		(layer "In6.Cu")
		(net "BIOS_DEBUG_MODE")
	)
	(segment
		(start 197.978268 -128.267714)
		(end 197.978268 -123.961144)
		(width 0.11684)
		(layer "In6.Cu")
		(net "BIOS_DEBUG_MODE")
	)
	(segment
		(start 187.111894 -123.84278)
		(end 187.120784 -123.84278)
		(width 0.11684)
		(layer "In6.Cu")
		(net "BIOS_DEBUG_MODE")
	)
	(segment
		(start 202.791822 -122.300746)
		(end 203.610464 -121.482104)
		(width 0.11684)
		(layer "In6.Cu")
		(net "BIOS_DEBUG_MODE")
	)
	(segment
		(start 261.463536 -127.035052)
		(end 288.072576 -127.035052)
		(width 0.11684)
		(layer "In6.Cu")
		(net "BIOS_DEBUG_MODE")
	)
	(segment
		(start 191.386206 -122.633232)
		(end 191.51092 -122.757946)
		(width 0.11684)
		(layer "In6.Cu")
		(net "BIOS_DEBUG_MODE")
	)
	(segment
		(start 188.330332 -122.633232)
		(end 191.386206 -122.633232)
		(width 0.11684)
		(layer "In6.Cu")
		(net "BIOS_DEBUG_MODE")
	)
	(segment
		(start 213.220046 -119.711978)
		(end 213.90102 -119.031004)
		(width 0.11684)
		(layer "In6.Cu")
		(net "BIOS_DEBUG_MODE")
	)
	(segment
		(start 256.309368 -126.350522)
		(end 260.779006 -126.350522)
		(width 0.11684)
		(layer "In6.Cu")
		(net "BIOS_DEBUG_MODE")
	)
	(segment
		(start 203.610464 -121.482104)
		(end 211.074508 -121.482104)
		(width 0.11684)
		(layer "In6.Cu")
		(net "BIOS_DEBUG_MODE")
	)
	(segment
		(start 213.90102 -119.031004)
		(end 217.28303 -119.031004)
		(width 0.11684)
		(layer "In6.Cu")
		(net "BIOS_DEBUG_MODE")
	)
	(segment
		(start 211.074508 -121.482104)
		(end 212.844634 -119.711978)
		(width 0.11684)
		(layer "In6.Cu")
		(net "BIOS_DEBUG_MODE")
	)
	(segment
		(start 254.385064 -124.426218)
		(end 256.309368 -126.350522)
		(width 0.11684)
		(layer "In6.Cu")
		(net "BIOS_DEBUG_MODE")
	)
	(segment
		(start 202.045316 -122.300746)
		(end 202.791822 -122.300746)
		(width 0.11684)
		(layer "In6.Cu")
		(net "BIOS_DEBUG_MODE")
	)
	(segment
		(start 200.681336 -123.664726)
		(end 202.045316 -122.300746)
		(width 0.11684)
		(layer "In6.Cu")
		(net "BIOS_DEBUG_MODE")
	)
	(segment
		(start 451.884034 -91.031568)
		(end 448.977766 -88.1253)
		(width 0.11684)
		(layer "In15.Cu")
		(net "BIOS_DEBUG_MODE")
	)
	(segment
		(start 456.131168 -163.066476)
		(end 456.131168 -153.087832)
		(width 0.11684)
		(layer "In15.Cu")
		(net "BIOS_DEBUG_MODE")
	)
	(segment
		(start 430.5554 -35.395408)
		(end 430.5554 -36.007548)
		(width 0.11684)
		(layer "In15.Cu")
		(net "BIOS_DEBUG_MODE")
	)
	(segment
		(start 451.884034 -130.828034)
		(end 451.884034 -91.031568)
		(width 0.11684)
		(layer "In15.Cu")
		(net "BIOS_DEBUG_MODE")
	)
	(segment
		(start 456.131168 -153.087832)
		(end 457.02982 -152.18918)
		(width 0.11684)
		(layer "In15.Cu")
		(net "BIOS_DEBUG_MODE")
	)
	(segment
		(start 434.528214 -82.829654)
		(end 434.528214 -60.743084)
		(width 0.11684)
		(layer "In15.Cu")
		(net "BIOS_DEBUG_MODE")
	)
	(segment
		(start 429.739806 -30.204664)
		(end 429.739806 -34.579814)
		(width 0.11684)
		(layer "In15.Cu")
		(net "BIOS_DEBUG_MODE")
	)
	(segment
		(start 429.23587 -29.700728)
		(end 429.739806 -30.204664)
		(width 0.11684)
		(layer "In15.Cu")
		(net "BIOS_DEBUG_MODE")
	)
	(segment
		(start 399.311876 -335.77784)
		(end 408.390598 -335.77784)
		(width 0.11684)
		(layer "In15.Cu")
		(net "BIOS_DEBUG_MODE")
	)
	(segment
		(start 466.35416 -173.289468)
		(end 456.131168 -163.066476)
		(width 0.11684)
		(layer "In15.Cu")
		(net "BIOS_DEBUG_MODE")
	)
	(segment
		(start 415.94278 -328.225658)
		(end 460.698342 -328.225658)
		(width 0.11684)
		(layer "In15.Cu")
		(net "BIOS_DEBUG_MODE")
	)
	(segment
		(start 341.064342 -32.025336)
		(end 367.972848 -32.025336)
		(width 0.11684)
		(layer "In15.Cu")
		(net "BIOS_DEBUG_MODE")
	)
	(segment
		(start 429.205898 -55.420768)
		(end 429.205898 -37.35705)
		(width 0.11684)
		(layer "In15.Cu")
		(net "BIOS_DEBUG_MODE")
	)
	(segment
		(start 337.195414 -26.727658)
		(end 337.195414 -28.156408)
		(width 0.11684)
		(layer "In15.Cu")
		(net "BIOS_DEBUG_MODE")
	)
	(segment
		(start 457.02982 -152.18918)
		(end 457.02982 -135.97382)
		(width 0.11684)
		(layer "In15.Cu")
		(net "BIOS_DEBUG_MODE")
	)
	(segment
		(start 434.528214 -60.743084)
		(end 429.205898 -55.420768)
		(width 0.11684)
		(layer "In15.Cu")
		(net "BIOS_DEBUG_MODE")
	)
	(segment
		(start 367.972848 -32.025336)
		(end 370.297456 -29.700728)
		(width 0.11684)
		(layer "In15.Cu")
		(net "BIOS_DEBUG_MODE")
	)
	(segment
		(start 337.195414 -28.156408)
		(end 341.064342 -32.025336)
		(width 0.11684)
		(layer "In15.Cu")
		(net "BIOS_DEBUG_MODE")
	)
	(segment
		(start 370.297456 -29.700728)
		(end 429.23587 -29.700728)
		(width 0.11684)
		(layer "In15.Cu")
		(net "BIOS_DEBUG_MODE")
	)
	(segment
		(start 439.82386 -88.1253)
		(end 434.528214 -82.829654)
		(width 0.11684)
		(layer "In15.Cu")
		(net "BIOS_DEBUG_MODE")
	)
	(segment
		(start 457.02982 -135.97382)
		(end 451.884034 -130.828034)
		(width 0.11684)
		(layer "In15.Cu")
		(net "BIOS_DEBUG_MODE")
	)
	(segment
		(start 396.95628 -333.422244)
		(end 399.311876 -335.77784)
		(width 0.11684)
		(layer "In15.Cu")
		(net "BIOS_DEBUG_MODE")
	)
	(segment
		(start 408.390598 -335.77784)
		(end 415.94278 -328.225658)
		(width 0.11684)
		(layer "In15.Cu")
		(net "BIOS_DEBUG_MODE")
	)
	(segment
		(start 448.977766 -88.1253)
		(end 439.82386 -88.1253)
		(width 0.11684)
		(layer "In15.Cu")
		(net "BIOS_DEBUG_MODE")
	)
	(segment
		(start 429.205898 -37.35705)
		(end 430.5554 -36.007548)
		(width 0.11684)
		(layer "In15.Cu")
		(net "BIOS_DEBUG_MODE")
	)
	(segment
		(start 429.739806 -34.579814)
		(end 430.5554 -35.395408)
		(width 0.11684)
		(layer "In15.Cu")
		(net "BIOS_DEBUG_MODE")
	)
	(segment
		(start 460.698342 -328.225658)
		(end 466.35416 -322.56984)
		(width 0.11684)
		(layer "In15.Cu")
		(net "BIOS_DEBUG_MODE")
	)
	(segment
		(start 396.95628 -332.57744)
		(end 396.95628 -333.422244)
		(width 0.11684)
		(layer "In15.Cu")
		(net "BIOS_DEBUG_MODE")
	)
	(segment
		(start 466.35416 -322.56984)
		(end 466.35416 -173.289468)
		(width 0.11684)
		(layer "In15.Cu")
		(net "BIOS_DEBUG_MODE")
	)
	(segment
		(start 168.821862 -439.490358)
		(end 168.821862 -440.140344)
		(width 0.10668)
		(layer "F.Cu")
		(net "BIC_MONITER_N")
	)
	(segment
		(start 170.056302 -440.140344)
		(end 170.970702 -440.140344)
		(width 0.10668)
		(layer "F.Cu")
		(net "BIC_MONITER_N")
	)
	(segment
		(start 168.821862 -440.140344)
		(end 170.056302 -440.140344)
		(width 0.10668)
		(layer "F.Cu")
		(net "BIC_MONITER_N")
	)
	(via
		(at 170.056302 -440.140344)
		(size 0.762)
		(drill 0.381)
		(layers "F.Cu" "B.Cu")
		(net "BIC_MONITER_N")
	)
	(segment
		(start 163.82365 -438.209944)
		(end 163.82365 -438.912)
		(width 0.10668)
		(layer "F.Cu")
		(net "BIC_MONITER_ISO")
	)
	(segment
		(start 163.82365 -438.912)
		(end 164.80155 -438.912)
		(width 0.10668)
		(layer "F.Cu")
		(net "BIC_MONITER_ISO")
	)
	(segment
		(start 193.485516 -170.914822)
		(end 196.882004 -170.914822)
		(width 0.10668)
		(layer "F.Cu")
		(net "BIC_MONITER_ISO")
	)
	(segment
		(start 196.882004 -170.914822)
		(end 209.727546 -183.760364)
		(width 0.10668)
		(layer "F.Cu")
		(net "BIC_MONITER_ISO")
	)
	(segment
		(start 166.921942 -438.840372)
		(end 166.392098 -438.310528)
		(width 0.10668)
		(layer "F.Cu")
		(net "BIC_MONITER_ISO")
	)
	(segment
		(start 211.909406 -196.313552)
		(end 209.27441 -198.948548)
		(width 0.10668)
		(layer "F.Cu")
		(net "BIC_MONITER_ISO")
	)
	(segment
		(start 166.392098 -438.310528)
		(end 165.403022 -438.310528)
		(width 0.10668)
		(layer "F.Cu")
		(net "BIC_MONITER_ISO")
	)
	(segment
		(start 165.403022 -438.310528)
		(end 164.80155 -438.912)
		(width 0.10668)
		(layer "F.Cu")
		(net "BIC_MONITER_ISO")
	)
	(segment
		(start 191.96431 -169.393616)
		(end 193.485516 -170.914822)
		(width 0.10668)
		(layer "F.Cu")
		(net "BIC_MONITER_ISO")
	)
	(segment
		(start 209.727546 -183.760364)
		(end 211.909406 -189.027816)
		(width 0.10668)
		(layer "F.Cu")
		(net "BIC_MONITER_ISO")
	)
	(segment
		(start 209.27441 -198.948548)
		(end 209.007456 -198.948548)
		(width 0.10668)
		(layer "F.Cu")
		(net "BIC_MONITER_ISO")
	)
	(segment
		(start 211.909406 -189.027816)
		(end 211.909406 -196.313552)
		(width 0.10668)
		(layer "F.Cu")
		(net "BIC_MONITER_ISO")
	)
	(via
		(at 191.96431 -169.393616)
		(size 0.508)
		(drill 0.254)
		(layers "F.Cu" "B.Cu")
		(net "BIC_MONITER_ISO")
	)
	(via
		(at 163.82365 -438.209944)
		(size 0.508)
		(drill 0.254)
		(layers "F.Cu" "B.Cu")
		(net "BIC_MONITER_ISO")
	)
	(via
		(at 209.007456 -198.948548)
		(size 0.508)
		(drill 0.254)
		(layers "F.Cu" "B.Cu")
		(net "BIC_MONITER_ISO")
	)
	(segment
		(start 191.96431 -169.393616)
		(end 190.020956 -167.450262)
		(width 0.10668)
		(layer "B.Cu")
		(net "BIC_MONITER_ISO")
	)
	(segment
		(start 186.551316 -151.322532)
		(end 192.672208 -145.20164)
		(width 0.10668)
		(layer "B.Cu")
		(net "BIC_MONITER_ISO")
	)
	(segment
		(start 185.727848 -161.753296)
		(end 185.727848 -154.024584)
		(width 0.10668)
		(layer "B.Cu")
		(net "BIC_MONITER_ISO")
	)
	(segment
		(start 200.779888 -126.653036)
		(end 200.779888 -124.208794)
		(width 0.10668)
		(layer "B.Cu")
		(net "BIC_MONITER_ISO")
	)
	(segment
		(start 200.779888 -124.208794)
		(end 200.423272 -123.852178)
		(width 0.10668)
		(layer "B.Cu")
		(net "BIC_MONITER_ISO")
	)
	(segment
		(start 192.672208 -145.20164)
		(end 192.672208 -143.844518)
		(width 0.10668)
		(layer "B.Cu")
		(net "BIC_MONITER_ISO")
	)
	(segment
		(start 186.551316 -153.201116)
		(end 186.551316 -151.322532)
		(width 0.10668)
		(layer "B.Cu")
		(net "BIC_MONITER_ISO")
	)
	(segment
		(start 197.934072 -129.498852)
		(end 200.779888 -126.653036)
		(width 0.10668)
		(layer "B.Cu")
		(net "BIC_MONITER_ISO")
	)
	(segment
		(start 197.934072 -138.582654)
		(end 197.934072 -129.498852)
		(width 0.10668)
		(layer "B.Cu")
		(net "BIC_MONITER_ISO")
	)
	(segment
		(start 190.020956 -167.450262)
		(end 190.020956 -166.046404)
		(width 0.10668)
		(layer "B.Cu")
		(net "BIC_MONITER_ISO")
	)
	(segment
		(start 192.672208 -143.844518)
		(end 197.934072 -138.582654)
		(width 0.10668)
		(layer "B.Cu")
		(net "BIC_MONITER_ISO")
	)
	(segment
		(start 185.727848 -154.024584)
		(end 186.551316 -153.201116)
		(width 0.10668)
		(layer "B.Cu")
		(net "BIC_MONITER_ISO")
	)
	(segment
		(start 200.423272 -123.852178)
		(end 200.423272 -123.831096)
		(width 0.10668)
		(layer "B.Cu")
		(net "BIC_MONITER_ISO")
	)
	(segment
		(start 190.020956 -166.046404)
		(end 185.727848 -161.753296)
		(width 0.10668)
		(layer "B.Cu")
		(net "BIC_MONITER_ISO")
	)
	(segment
		(start 224.955354 -362.010706)
		(end 223.397826 -363.568234)
		(width 0.11684)
		(layer "In6.Cu")
		(net "BIC_MONITER_ISO")
	)
	(segment
		(start 168.170352 -418.344604)
		(end 168.170352 -419.03142)
		(width 0.11684)
		(layer "In6.Cu")
		(net "BIC_MONITER_ISO")
	)
	(segment
		(start 168.170352 -419.03142)
		(end 167.273986 -419.927786)
		(width 0.11684)
		(layer "In6.Cu")
		(net "BIC_MONITER_ISO")
	)
	(segment
		(start 166.349934 -406.977596)
		(end 169.17416 -409.801822)
		(width 0.11684)
		(layer "In6.Cu")
		(net "BIC_MONITER_ISO")
	)
	(segment
		(start 168.046654 -418.220906)
		(end 168.170352 -418.344604)
		(width 0.11684)
		(layer "In6.Cu")
		(net "BIC_MONITER_ISO")
	)
	(segment
		(start 179.097178 -382.99771)
		(end 179.097178 -385.129024)
		(width 0.11684)
		(layer "In6.Cu")
		(net "BIC_MONITER_ISO")
	)
	(segment
		(start 179.097178 -385.129024)
		(end 173.849284 -390.376918)
		(width 0.11684)
		(layer "In6.Cu")
		(net "BIC_MONITER_ISO")
	)
	(segment
		(start 214.12962 -320.33718)
		(end 224.955354 -331.162914)
		(width 0.11684)
		(layer "In6.Cu")
		(net "BIC_MONITER_ISO")
	)
	(segment
		(start 170.659044 -397.54556)
		(end 169.585894 -397.54556)
		(width 0.11684)
		(layer "In6.Cu")
		(net "BIC_MONITER_ISO")
	)
	(segment
		(start 173.849284 -390.376918)
		(end 173.849284 -394.35532)
		(width 0.11684)
		(layer "In6.Cu")
		(net "BIC_MONITER_ISO")
	)
	(segment
		(start 191.676528 -370.41836)
		(end 179.097178 -382.99771)
		(width 0.11684)
		(layer "In6.Cu")
		(net "BIC_MONITER_ISO")
	)
	(segment
		(start 214.12962 -203.631292)
		(end 214.12962 -320.33718)
		(width 0.11684)
		(layer "In6.Cu")
		(net "BIC_MONITER_ISO")
	)
	(segment
		(start 167.273986 -421.065452)
		(end 168.25722 -422.048686)
		(width 0.11684)
		(layer "In6.Cu")
		(net "BIC_MONITER_ISO")
	)
	(segment
		(start 168.656254 -417.114228)
		(end 168.046654 -417.723828)
		(width 0.11684)
		(layer "In6.Cu")
		(net "BIC_MONITER_ISO")
	)
	(segment
		(start 173.849284 -394.35532)
		(end 170.659044 -397.54556)
		(width 0.11684)
		(layer "In6.Cu")
		(net "BIC_MONITER_ISO")
	)
	(segment
		(start 219.67952 -370.41836)
		(end 191.676528 -370.41836)
		(width 0.11684)
		(layer "In6.Cu")
		(net "BIC_MONITER_ISO")
	)
	(segment
		(start 224.955354 -332.597252)
		(end 224.955354 -362.010706)
		(width 0.11684)
		(layer "In6.Cu")
		(net "BIC_MONITER_ISO")
	)
	(segment
		(start 169.17416 -409.801822)
		(end 169.17416 -412.3817)
		(width 0.11684)
		(layer "In6.Cu")
		(net "BIC_MONITER_ISO")
	)
	(segment
		(start 223.397826 -364.352586)
		(end 222.050356 -365.700056)
		(width 0.11684)
		(layer "In6.Cu")
		(net "BIC_MONITER_ISO")
	)
	(segment
		(start 168.920922 -412.634938)
		(end 168.920922 -414.547304)
		(width 0.11684)
		(layer "In6.Cu")
		(net "BIC_MONITER_ISO")
	)
	(segment
		(start 164.22751 -429.0441)
		(end 161.620454 -431.651156)
		(width 0.11684)
		(layer "In6.Cu")
		(net "BIC_MONITER_ISO")
	)
	(segment
		(start 168.656254 -414.811972)
		(end 168.656254 -417.114228)
		(width 0.11684)
		(layer "In6.Cu")
		(net "BIC_MONITER_ISO")
	)
	(segment
		(start 222.050356 -368.047524)
		(end 219.67952 -370.41836)
		(width 0.11684)
		(layer "In6.Cu")
		(net "BIC_MONITER_ISO")
	)
	(segment
		(start 168.920922 -414.547304)
		(end 168.656254 -414.811972)
		(width 0.11684)
		(layer "In6.Cu")
		(net "BIC_MONITER_ISO")
	)
	(segment
		(start 168.25722 -423.918126)
		(end 166.703502 -425.471844)
		(width 0.11684)
		(layer "In6.Cu")
		(net "BIC_MONITER_ISO")
	)
	(segment
		(start 167.273986 -419.927786)
		(end 167.273986 -421.065452)
		(width 0.11684)
		(layer "In6.Cu")
		(net "BIC_MONITER_ISO")
	)
	(segment
		(start 222.050356 -365.700056)
		(end 222.050356 -368.047524)
		(width 0.11684)
		(layer "In6.Cu")
		(net "BIC_MONITER_ISO")
	)
	(segment
		(start 209.446876 -198.948548)
		(end 214.12962 -203.631292)
		(width 0.11684)
		(layer "In6.Cu")
		(net "BIC_MONITER_ISO")
	)
	(segment
		(start 165.299644 -429.0441)
		(end 164.22751 -429.0441)
		(width 0.11684)
		(layer "In6.Cu")
		(net "BIC_MONITER_ISO")
	)
	(segment
		(start 168.25722 -422.048686)
		(end 168.25722 -423.918126)
		(width 0.11684)
		(layer "In6.Cu")
		(net "BIC_MONITER_ISO")
	)
	(segment
		(start 161.620454 -433.964588)
		(end 163.82365 -436.167784)
		(width 0.11684)
		(layer "In6.Cu")
		(net "BIC_MONITER_ISO")
	)
	(segment
		(start 225.25482 -331.912214)
		(end 225.25482 -332.297786)
		(width 0.11684)
		(layer "In6.Cu")
		(net "BIC_MONITER_ISO")
	)
	(segment
		(start 161.620454 -431.651156)
		(end 161.620454 -433.964588)
		(width 0.11684)
		(layer "In6.Cu")
		(net "BIC_MONITER_ISO")
	)
	(segment
		(start 224.955354 -331.612748)
		(end 225.25482 -331.912214)
		(width 0.11684)
		(layer "In6.Cu")
		(net "BIC_MONITER_ISO")
	)
	(segment
		(start 168.046654 -417.723828)
		(end 168.046654 -418.220906)
		(width 0.11684)
		(layer "In6.Cu")
		(net "BIC_MONITER_ISO")
	)
	(segment
		(start 166.349934 -400.78152)
		(end 166.349934 -406.977596)
		(width 0.11684)
		(layer "In6.Cu")
		(net "BIC_MONITER_ISO")
	)
	(segment
		(start 225.25482 -332.297786)
		(end 224.955354 -332.597252)
		(width 0.11684)
		(layer "In6.Cu")
		(net "BIC_MONITER_ISO")
	)
	(segment
		(start 169.585894 -397.54556)
		(end 166.349934 -400.78152)
		(width 0.11684)
		(layer "In6.Cu")
		(net "BIC_MONITER_ISO")
	)
	(segment
		(start 224.955354 -331.162914)
		(end 224.955354 -331.612748)
		(width 0.11684)
		(layer "In6.Cu")
		(net "BIC_MONITER_ISO")
	)
	(segment
		(start 169.17416 -412.3817)
		(end 168.920922 -412.634938)
		(width 0.11684)
		(layer "In6.Cu")
		(net "BIC_MONITER_ISO")
	)
	(segment
		(start 166.703502 -427.640242)
		(end 165.299644 -429.0441)
		(width 0.11684)
		(layer "In6.Cu")
		(net "BIC_MONITER_ISO")
	)
	(segment
		(start 209.007456 -198.948548)
		(end 209.446876 -198.948548)
		(width 0.11684)
		(layer "In6.Cu")
		(net "BIC_MONITER_ISO")
	)
	(segment
		(start 166.703502 -425.471844)
		(end 166.703502 -427.640242)
		(width 0.11684)
		(layer "In6.Cu")
		(net "BIC_MONITER_ISO")
	)
	(segment
		(start 163.82365 -436.167784)
		(end 163.82365 -438.209944)
		(width 0.11684)
		(layer "In6.Cu")
		(net "BIC_MONITER_ISO")
	)
	(segment
		(start 223.397826 -363.568234)
		(end 223.397826 -364.352586)
		(width 0.11684)
		(layer "In6.Cu")
		(net "BIC_MONITER_ISO")
	)
	(segment
		(start 166.447724 -439.702194)
		(end 166.65956 -439.490358)
		(width 0.10668)
		(layer "F.Cu")
		(net "BIC_MONITER")
	)
	(segment
		(start 166.65956 -439.490358)
		(end 166.921942 -439.490358)
		(width 0.10668)
		(layer "F.Cu")
		(net "BIC_MONITER")
	)
	(segment
		(start 164.80155 -440.182)
		(end 165.281356 -439.702194)
		(width 0.10668)
		(layer "F.Cu")
		(net "BIC_MONITER")
	)
	(segment
		(start 163.82365 -440.182)
		(end 164.80155 -440.182)
		(width 0.10668)
		(layer "F.Cu")
		(net "BIC_MONITER")
	)
	(segment
		(start 166.921942 -439.490358)
		(end 167.87622 -439.490358)
		(width 0.10668)
		(layer "F.Cu")
		(net "BIC_MONITER")
	)
	(segment
		(start 165.281356 -439.702194)
		(end 166.447724 -439.702194)
		(width 0.10668)
		(layer "F.Cu")
		(net "BIC_MONITER")
	)
	(via
		(at 167.87622 -439.490358)
		(size 0.508)
		(drill 0.254)
		(layers "F.Cu" "B.Cu")
		(net "BIC_MONITER")
	)
	(segment
		(start 168.68902 -434.96992)
		(end 170.090592 -433.568348)
		(width 0.11684)
		(layer "In2.Cu")
		(net "BIC_MONITER")
	)
	(segment
		(start 161.125916 -427.239684)
		(end 161.125916 -426.912278)
		(width 0.11684)
		(layer "In2.Cu")
		(net "BIC_MONITER")
	)
	(segment
		(start 167.342566 -434.96992)
		(end 168.68902 -434.96992)
		(width 0.11684)
		(layer "In2.Cu")
		(net "BIC_MONITER")
	)
	(segment
		(start 170.090592 -433.568348)
		(end 170.090592 -431.513234)
		(width 0.11684)
		(layer "In2.Cu")
		(net "BIC_MONITER")
	)
	(segment
		(start 166.992808 -438.606946)
		(end 166.992808 -435.319678)
		(width 0.11684)
		(layer "In2.Cu")
		(net "BIC_MONITER")
	)
	(segment
		(start 163.964112 -430.07788)
		(end 161.125916 -427.239684)
		(width 0.11684)
		(layer "In2.Cu")
		(net "BIC_MONITER")
	)
	(segment
		(start 165.345618 -429.96485)
		(end 165.232588 -430.07788)
		(width 0.11684)
		(layer "In2.Cu")
		(net "BIC_MONITER")
	)
	(segment
		(start 157.66923 -423.455592)
		(end 146.601942 -423.455592)
		(width 0.11684)
		(layer "In2.Cu")
		(net "BIC_MONITER")
	)
	(segment
		(start 146.601942 -423.455592)
		(end 145.890234 -424.1673)
		(width 0.11684)
		(layer "In2.Cu")
		(net "BIC_MONITER")
	)
	(segment
		(start 145.890234 -424.1673)
		(end 145.890234 -439.630058)
		(width 0.11684)
		(layer "In2.Cu")
		(net "BIC_MONITER")
	)
	(segment
		(start 170.090592 -431.513234)
		(end 168.542208 -429.96485)
		(width 0.11684)
		(layer "In2.Cu")
		(net "BIC_MONITER")
	)
	(segment
		(start 161.125916 -426.912278)
		(end 157.66923 -423.455592)
		(width 0.11684)
		(layer "In2.Cu")
		(net "BIC_MONITER")
	)
	(segment
		(start 145.890234 -439.630058)
		(end 146.750024 -440.489848)
		(width 0.11684)
		(layer "In2.Cu")
		(net "BIC_MONITER")
	)
	(segment
		(start 166.992808 -435.319678)
		(end 167.342566 -434.96992)
		(width 0.11684)
		(layer "In2.Cu")
		(net "BIC_MONITER")
	)
	(segment
		(start 165.232588 -430.07788)
		(end 163.964112 -430.07788)
		(width 0.11684)
		(layer "In2.Cu")
		(net "BIC_MONITER")
	)
	(segment
		(start 167.87622 -439.490358)
		(end 166.992808 -438.606946)
		(width 0.11684)
		(layer "In2.Cu")
		(net "BIC_MONITER")
	)
	(segment
		(start 168.542208 -429.96485)
		(end 165.345618 -429.96485)
		(width 0.11684)
		(layer "In2.Cu")
		(net "BIC_MONITER")
	)
	(segment
		(start 300.571916 -20.99691)
		(end 300.571916 -20.632928)
		(width 0.10668)
		(layer "F.Cu")
		(net "BAT_LDO_EN")
	)
	(segment
		(start 302.466756 -24.349456)
		(end 300.422564 -24.349456)
		(width 0.10668)
		(layer "F.Cu")
		(net "BAT_LDO_EN")
	)
	(segment
		(start 300.23181 -20.292822)
		(end 299.477938 -20.292822)
		(width 0.10668)
		(layer "F.Cu")
		(net "BAT_LDO_EN")
	)
	(segment
		(start 300.571916 -22.303232)
		(end 300.571916 -20.99691)
		(width 0.10668)
		(layer "F.Cu")
		(net "BAT_LDO_EN")
	)
	(segment
		(start 300.422564 -24.349456)
		(end 300.422564 -23.462996)
		(width 0.10668)
		(layer "F.Cu")
		(net "BAT_LDO_EN")
	)
	(segment
		(start 299.477938 -20.292822)
		(end 298.950888 -19.765772)
		(width 0.10668)
		(layer "F.Cu")
		(net "BAT_LDO_EN")
	)
	(segment
		(start 299.917358 -22.95779)
		(end 300.571916 -22.303232)
		(width 0.10668)
		(layer "F.Cu")
		(net "BAT_LDO_EN")
	)
	(segment
		(start 300.422564 -23.462996)
		(end 299.917358 -22.95779)
		(width 0.10668)
		(layer "F.Cu")
		(net "BAT_LDO_EN")
	)
	(segment
		(start 298.950888 -19.765772)
		(end 298.950888 -19.306032)
		(width 0.10668)
		(layer "F.Cu")
		(net "BAT_LDO_EN")
	)
	(segment
		(start 303.089564 -24.972264)
		(end 302.466756 -24.349456)
		(width 0.10668)
		(layer "F.Cu")
		(net "BAT_LDO_EN")
	)
	(segment
		(start 300.571916 -20.632928)
		(end 300.23181 -20.292822)
		(width 0.10668)
		(layer "F.Cu")
		(net "BAT_LDO_EN")
	)
	(segment
		(start 303.831498 -24.972264)
		(end 303.089564 -24.972264)
		(width 0.10668)
		(layer "F.Cu")
		(net "BAT_LDO_EN")
	)
	(via
		(at 299.917358 -22.95779)
		(size 0.762)
		(drill 0.381)
		(layers "F.Cu" "B.Cu")
		(net "BAT_LDO_EN")
	)
	(segment
		(start 152.905968 -119.41302)
		(end 152.260808 -119.41302)
		(width 0.10668)
		(layer "F.Cu")
		(net "A_P12V_STBY_FP_TRIGGER")
	)
	(segment
		(start 154.15006 -119.082312)
		(end 153.236676 -119.082312)
		(width 0.10668)
		(layer "F.Cu")
		(net "A_P12V_STBY_FP_TRIGGER")
	)
	(segment
		(start 152.260808 -119.41302)
		(end 151.576786 -119.41302)
		(width 0.10668)
		(layer "F.Cu")
		(net "A_P12V_STBY_FP_TRIGGER")
	)
	(segment
		(start 151.262588 -119.098822)
		(end 150.768812 -119.098822)
		(width 0.10668)
		(layer "F.Cu")
		(net "A_P12V_STBY_FP_TRIGGER")
	)
	(segment
		(start 151.576786 -119.41302)
		(end 151.262588 -119.098822)
		(width 0.10668)
		(layer "F.Cu")
		(net "A_P12V_STBY_FP_TRIGGER")
	)
	(segment
		(start 150.768812 -119.098822)
		(end 150.768812 -120.485662)
		(width 0.10668)
		(layer "F.Cu")
		(net "A_P12V_STBY_FP_TRIGGER")
	)
	(segment
		(start 153.236676 -119.082312)
		(end 152.905968 -119.41302)
		(width 0.10668)
		(layer "F.Cu")
		(net "A_P12V_STBY_FP_TRIGGER")
	)
	(via
		(at 152.260808 -119.41302)
		(size 0.762)
		(drill 0.381)
		(layers "F.Cu" "B.Cu")
		(net "A_P12V_STBY_FP_TRIGGER")
	)
	(segment
		(start 152.282652 -116.449094)
		(end 150.800308 -116.449094)
		(width 0.10668)
		(layer "F.Cu")
		(net "A_P12V_STBY_FPH_GATE")
	)
	(segment
		(start 155.682188 -120.869964)
		(end 155.419552 -120.607328)
		(width 0.10668)
		(layer "F.Cu")
		(net "A_P12V_STBY_FPH_GATE")
	)
	(segment
		(start 153.627328 -117.182392)
		(end 152.87244 -116.427504)
		(width 0.10668)
		(layer "F.Cu")
		(net "A_P12V_STBY_FPH_GATE")
	)
	(segment
		(start 156.519626 -120.869964)
		(end 155.682188 -120.869964)
		(width 0.10668)
		(layer "F.Cu")
		(net "A_P12V_STBY_FPH_GATE")
	)
	(segment
		(start 154.15006 -117.182392)
		(end 153.627328 -117.182392)
		(width 0.10668)
		(layer "F.Cu")
		(net "A_P12V_STBY_FPH_GATE")
	)
	(segment
		(start 152.87244 -116.427504)
		(end 152.304242 -116.427504)
		(width 0.10668)
		(layer "F.Cu")
		(net "A_P12V_STBY_FPH_GATE")
	)
	(segment
		(start 152.304242 -116.427504)
		(end 152.282652 -116.449094)
		(width 0.10668)
		(layer "F.Cu")
		(net "A_P12V_STBY_FPH_GATE")
	)
	(segment
		(start 155.419552 -120.607328)
		(end 155.419552 -117.446552)
		(width 0.10668)
		(layer "F.Cu")
		(net "A_P12V_STBY_FPH_GATE")
	)
	(segment
		(start 155.419552 -117.446552)
		(end 155.155392 -117.182392)
		(width 0.10668)
		(layer "F.Cu")
		(net "A_P12V_STBY_FPH_GATE")
	)
	(segment
		(start 155.155392 -117.182392)
		(end 154.15006 -117.182392)
		(width 0.10668)
		(layer "F.Cu")
		(net "A_P12V_STBY_FPH_GATE")
	)
	(via
		(at 152.304242 -116.427504)
		(size 0.762)
		(drill 0.381)
		(layers "F.Cu" "B.Cu")
		(net "A_P12V_STBY_FPH_GATE")
	)
	(segment
		(start 156.769816 -119.082312)
		(end 158.650686 -119.082312)
		(width 0.10668)
		(layer "F.Cu")
		(net "A_P12V_STBY_ADR_TRIGGER")
	)
	(segment
		(start 159.970724 -119.082312)
		(end 159.977836 -119.089424)
		(width 0.10668)
		(layer "F.Cu")
		(net "A_P12V_STBY_ADR_TRIGGER")
	)
	(segment
		(start 158.650686 -119.082312)
		(end 159.970724 -119.082312)
		(width 0.10668)
		(layer "F.Cu")
		(net "A_P12V_STBY_ADR_TRIGGER")
	)
	(segment
		(start 159.980884 -119.092472)
		(end 159.977836 -119.089424)
		(width 0.10668)
		(layer "F.Cu")
		(net "A_P12V_STBY_ADR_TRIGGER")
	)
	(segment
		(start 159.980884 -120.40108)
		(end 159.980884 -119.092472)
		(width 0.10668)
		(layer "F.Cu")
		(net "A_P12V_STBY_ADR_TRIGGER")
	)
	(via
		(at 158.650686 -119.082312)
		(size 0.762)
		(drill 0.381)
		(layers "F.Cu" "B.Cu")
		(net "A_P12V_STBY_ADR_TRIGGER")
	)
	(segment
		(start 184.322212 -118.652798)
		(end 183.932322 -119.042688)
		(width 0.10668)
		(layer "F.Cu")
		(net "APML_CPU1_ALERT_R_N")
	)
	(via
		(at 185.150252 -131.45008)
		(size 0.762)
		(drill 0.254)
		(layers "F.Cu" "B.Cu")
		(net "APML_CPU1_ALERT_R_N")
	)
	(via
		(at 183.932322 -119.042688)
		(size 0.4572)
		(drill 0.254)
		(layers "F.Cu" "B.Cu")
		(net "APML_CPU1_ALERT_R_N")
	)
	(segment
		(start 185.51398 -132.498338)
		(end 185.390282 -132.199126)
		(width 0.10668)
		(layer "B.Cu")
		(net "APML_CPU1_ALERT_R_N")
	)
	(segment
		(start 185.51398 -132.987542)
		(end 185.51398 -132.498338)
		(width 0.10668)
		(layer "B.Cu")
		(net "APML_CPU1_ALERT_R_N")
	)
	(segment
		(start 185.324496 -133.177026)
		(end 185.51398 -132.987542)
		(width 0.10668)
		(layer "B.Cu")
		(net "APML_CPU1_ALERT_R_N")
	)
	(segment
		(start 185.390282 -132.199126)
		(end 185.150252 -131.959096)
		(width 0.10668)
		(layer "B.Cu")
		(net "APML_CPU1_ALERT_R_N")
	)
	(segment
		(start 185.150252 -131.959096)
		(end 185.150252 -131.45008)
		(width 0.10668)
		(layer "B.Cu")
		(net "APML_CPU1_ALERT_R_N")
	)
	(segment
		(start 183.932322 -119.293132)
		(end 183.932322 -119.042688)
		(width 0.11684)
		(layer "In4.Cu")
		(net "APML_CPU1_ALERT_R_N")
	)
	(segment
		(start 184.3405 -127.874268)
		(end 184.3405 -119.70131)
		(width 0.11684)
		(layer "In4.Cu")
		(net "APML_CPU1_ALERT_R_N")
	)
	(segment
		(start 185.150252 -131.298696)
		(end 185.560716 -130.888232)
		(width 0.11684)
		(layer "In4.Cu")
		(net "APML_CPU1_ALERT_R_N")
	)
	(segment
		(start 184.3405 -119.70131)
		(end 183.932322 -119.293132)
		(width 0.11684)
		(layer "In4.Cu")
		(net "APML_CPU1_ALERT_R_N")
	)
	(segment
		(start 185.150252 -131.45008)
		(end 185.150252 -131.298696)
		(width 0.11684)
		(layer "In4.Cu")
		(net "APML_CPU1_ALERT_R_N")
	)
	(segment
		(start 185.560716 -130.888232)
		(end 185.560716 -129.094484)
		(width 0.11684)
		(layer "In4.Cu")
		(net "APML_CPU1_ALERT_R_N")
	)
	(segment
		(start 185.560716 -129.094484)
		(end 184.3405 -127.874268)
		(width 0.11684)
		(layer "In4.Cu")
		(net "APML_CPU1_ALERT_R_N")
	)
	(segment
		(start 84.216748 -205.164436)
		(end 88.762586 -209.710274)
		(width 0.10668)
		(layer "F.Cu")
		(net "APML_CPU1_ALERT_N")
	)
	(segment
		(start 76.809346 -205.164436)
		(end 84.216748 -205.164436)
		(width 0.10668)
		(layer "F.Cu")
		(net "APML_CPU1_ALERT_N")
	)
	(segment
		(start 76.808584 -205.164182)
		(end 76.809346 -205.164436)
		(width 0.10668)
		(layer "F.Cu")
		(net "APML_CPU1_ALERT_N")
	)
	(segment
		(start 72.14489 -202.3999)
		(end 72.69353 -202.3999)
		(width 0.10668)
		(layer "F.Cu")
		(net "APML_CPU1_ALERT_N")
	)
	(segment
		(start 84.047838 -220.978222)
		(end 84.047838 -222.070422)
		(width 0.10668)
		(layer "F.Cu")
		(net "APML_CPU1_ALERT_N")
	)
	(segment
		(start 72.69353 -202.3999)
		(end 75.457812 -205.164182)
		(width 0.10668)
		(layer "F.Cu")
		(net "APML_CPU1_ALERT_N")
	)
	(segment
		(start 75.457812 -205.164182)
		(end 76.808584 -205.164182)
		(width 0.10668)
		(layer "F.Cu")
		(net "APML_CPU1_ALERT_N")
	)
	(segment
		(start 88.762586 -216.263474)
		(end 84.047838 -220.978222)
		(width 0.10668)
		(layer "F.Cu")
		(net "APML_CPU1_ALERT_N")
	)
	(segment
		(start 88.762586 -209.710274)
		(end 88.762586 -216.263474)
		(width 0.10668)
		(layer "F.Cu")
		(net "APML_CPU1_ALERT_N")
	)
	(via
		(at 112.289336 -130.01498)
		(size 0.508)
		(drill 0.254)
		(layers "F.Cu" "B.Cu")
		(net "APML_CPU1_ALERT_N")
	)
	(via
		(at 72.14489 -202.3999)
		(size 0.508)
		(drill 0.254)
		(layers "F.Cu" "B.Cu")
		(net "APML_CPU1_ALERT_N")
	)
	(via
		(at 185.077608 -138.648948)
		(size 0.508)
		(drill 0.254)
		(layers "F.Cu" "B.Cu")
		(net "APML_CPU1_ALERT_N")
	)
	(segment
		(start 185.077608 -138.648948)
		(end 185.077608 -137.372598)
		(width 0.10668)
		(layer "B.Cu")
		(net "APML_CPU1_ALERT_N")
	)
	(segment
		(start 185.59526 -134.24789)
		(end 185.324496 -133.977126)
		(width 0.10668)
		(layer "B.Cu")
		(net "APML_CPU1_ALERT_N")
	)
	(segment
		(start 71.485506 -202.688952)
		(end 71.774558 -202.3999)
		(width 0.10668)
		(layer "B.Cu")
		(net "APML_CPU1_ALERT_N")
	)
	(segment
		(start 71.774558 -202.3999)
		(end 72.14489 -202.3999)
		(width 0.10668)
		(layer "B.Cu")
		(net "APML_CPU1_ALERT_N")
	)
	(segment
		(start 185.59526 -136.854946)
		(end 185.59526 -134.24789)
		(width 0.10668)
		(layer "B.Cu")
		(net "APML_CPU1_ALERT_N")
	)
	(segment
		(start 185.077608 -137.372598)
		(end 185.59526 -136.854946)
		(width 0.10668)
		(layer "B.Cu")
		(net "APML_CPU1_ALERT_N")
	)
	(segment
		(start 70.572884 -202.688952)
		(end 71.485506 -202.688952)
		(width 0.10668)
		(layer "B.Cu")
		(net "APML_CPU1_ALERT_N")
	)
	(segment
		(start 180.287422 -138.117326)
		(end 179.774596 -137.6045)
		(width 0.11684)
		(layer "In6.Cu")
		(net "APML_CPU1_ALERT_N")
	)
	(segment
		(start 113.814098 -131.539742)
		(end 112.289336 -130.01498)
		(width 0.11684)
		(layer "In6.Cu")
		(net "APML_CPU1_ALERT_N")
	)
	(segment
		(start 163.525708 -134.73938)
		(end 162.1409 -133.354572)
		(width 0.11684)
		(layer "In6.Cu")
		(net "APML_CPU1_ALERT_N")
	)
	(segment
		(start 154.610816 -131.539742)
		(end 113.814098 -131.539742)
		(width 0.11684)
		(layer "In6.Cu")
		(net "APML_CPU1_ALERT_N")
	)
	(segment
		(start 184.545986 -138.117326)
		(end 180.287422 -138.117326)
		(width 0.11684)
		(layer "In6.Cu")
		(net "APML_CPU1_ALERT_N")
	)
	(segment
		(start 179.774596 -137.6045)
		(end 172.367194 -137.6045)
		(width 0.11684)
		(layer "In6.Cu")
		(net "APML_CPU1_ALERT_N")
	)
	(segment
		(start 156.425646 -133.354572)
		(end 154.610816 -131.539742)
		(width 0.11684)
		(layer "In6.Cu")
		(net "APML_CPU1_ALERT_N")
	)
	(segment
		(start 172.367194 -137.6045)
		(end 169.502074 -134.73938)
		(width 0.11684)
		(layer "In6.Cu")
		(net "APML_CPU1_ALERT_N")
	)
	(segment
		(start 162.1409 -133.354572)
		(end 156.425646 -133.354572)
		(width 0.11684)
		(layer "In6.Cu")
		(net "APML_CPU1_ALERT_N")
	)
	(segment
		(start 169.502074 -134.73938)
		(end 163.525708 -134.73938)
		(width 0.11684)
		(layer "In6.Cu")
		(net "APML_CPU1_ALERT_N")
	)
	(segment
		(start 185.077608 -138.648948)
		(end 184.545986 -138.117326)
		(width 0.11684)
		(layer "In6.Cu")
		(net "APML_CPU1_ALERT_N")
	)
	(segment
		(start 64.221614 -197.395338)
		(end 67.282568 -200.456292)
		(width 0.11684)
		(layer "In11.Cu")
		(net "APML_CPU1_ALERT_N")
	)
	(segment
		(start 107.699302 -134.605014)
		(end 52.45227 -134.605014)
		(width 0.11684)
		(layer "In11.Cu")
		(net "APML_CPU1_ALERT_N")
	)
	(segment
		(start 37.651182 -187.884816)
		(end 40.467788 -190.701422)
		(width 0.11684)
		(layer "In11.Cu")
		(net "APML_CPU1_ALERT_N")
	)
	(segment
		(start 39.983156 -155.208478)
		(end 31.735268 -163.456366)
		(width 0.11684)
		(layer "In11.Cu")
		(net "APML_CPU1_ALERT_N")
	)
	(segment
		(start 31.735268 -163.456366)
		(end 31.735268 -177.65776)
		(width 0.11684)
		(layer "In11.Cu")
		(net "APML_CPU1_ALERT_N")
	)
	(segment
		(start 70.927722 -200.456292)
		(end 72.174862 -201.703432)
		(width 0.11684)
		(layer "In11.Cu")
		(net "APML_CPU1_ALERT_N")
	)
	(segment
		(start 112.289336 -130.01498)
		(end 107.699302 -134.605014)
		(width 0.11684)
		(layer "In11.Cu")
		(net "APML_CPU1_ALERT_N")
	)
	(segment
		(start 72.174862 -202.369928)
		(end 72.14489 -202.3999)
		(width 0.11684)
		(layer "In11.Cu")
		(net "APML_CPU1_ALERT_N")
	)
	(segment
		(start 37.651182 -183.573674)
		(end 37.651182 -187.884816)
		(width 0.11684)
		(layer "In11.Cu")
		(net "APML_CPU1_ALERT_N")
	)
	(segment
		(start 64.221614 -195.318126)
		(end 64.221614 -197.395338)
		(width 0.11684)
		(layer "In11.Cu")
		(net "APML_CPU1_ALERT_N")
	)
	(segment
		(start 72.174862 -201.703432)
		(end 72.174862 -202.369928)
		(width 0.11684)
		(layer "In11.Cu")
		(net "APML_CPU1_ALERT_N")
	)
	(segment
		(start 39.983156 -147.074128)
		(end 39.983156 -155.208478)
		(width 0.11684)
		(layer "In11.Cu")
		(net "APML_CPU1_ALERT_N")
	)
	(segment
		(start 31.735268 -177.65776)
		(end 37.651182 -183.573674)
		(width 0.11684)
		(layer "In11.Cu")
		(net "APML_CPU1_ALERT_N")
	)
	(segment
		(start 59.60491 -190.701422)
		(end 64.221614 -195.318126)
		(width 0.11684)
		(layer "In11.Cu")
		(net "APML_CPU1_ALERT_N")
	)
	(segment
		(start 67.282568 -200.456292)
		(end 70.927722 -200.456292)
		(width 0.11684)
		(layer "In11.Cu")
		(net "APML_CPU1_ALERT_N")
	)
	(segment
		(start 40.467788 -190.701422)
		(end 59.60491 -190.701422)
		(width 0.11684)
		(layer "In11.Cu")
		(net "APML_CPU1_ALERT_N")
	)
	(segment
		(start 52.45227 -134.605014)
		(end 39.983156 -147.074128)
		(width 0.11684)
		(layer "In11.Cu")
		(net "APML_CPU1_ALERT_N")
	)
	(segment
		(start 325.545958 -192.173352)
		(end 325.545958 -171.481242)
		(width 0.10668)
		(layer "F.Cu")
		(net "APML_CPU0_ALERT_R_N")
	)
	(segment
		(start 325.545958 -171.481242)
		(end 329.692 -167.3352)
		(width 0.10668)
		(layer "F.Cu")
		(net "APML_CPU0_ALERT_R_N")
	)
	(segment
		(start 325.545958 -193.525902)
		(end 325.545958 -192.173352)
		(width 0.10668)
		(layer "F.Cu")
		(net "APML_CPU0_ALERT_R_N")
	)
	(segment
		(start 329.692 -167.3352)
		(end 329.692 -167.005)
		(width 0.10668)
		(layer "F.Cu")
		(net "APML_CPU0_ALERT_R_N")
	)
	(segment
		(start 185.122058 -119.452898)
		(end 184.732168 -119.842788)
		(width 0.10668)
		(layer "F.Cu")
		(net "APML_CPU0_ALERT_R_N")
	)
	(via
		(at 187.035948 -161.760916)
		(size 0.508)
		(drill 0.254)
		(layers "F.Cu" "B.Cu")
		(net "APML_CPU0_ALERT_R_N")
	)
	(via
		(at 184.732168 -119.842788)
		(size 0.4572)
		(drill 0.254)
		(layers "F.Cu" "B.Cu")
		(net "APML_CPU0_ALERT_R_N")
	)
	(via
		(at 325.545958 -192.173352)
		(size 0.762)
		(drill 0.381)
		(layers "F.Cu" "B.Cu")
		(net "APML_CPU0_ALERT_R_N")
	)
	(via
		(at 303.557432 -169.709592)
		(size 0.508)
		(drill 0.254)
		(layers "F.Cu" "B.Cu")
		(net "APML_CPU0_ALERT_R_N")
	)
	(via
		(at 329.692 -167.005)
		(size 0.508)
		(drill 0.254)
		(layers "F.Cu" "B.Cu")
		(net "APML_CPU0_ALERT_R_N")
	)
	(segment
		(start 303.557432 -169.709592)
		(end 303.557432 -169.79011)
		(width 0.11684)
		(layer "In2.Cu")
		(net "APML_CPU0_ALERT_R_N")
	)
	(segment
		(start 326.48144 -170.21556)
		(end 329.692 -167.005)
		(width 0.11684)
		(layer "In2.Cu")
		(net "APML_CPU0_ALERT_R_N")
	)
	(segment
		(start 303.982882 -170.21556)
		(end 326.48144 -170.21556)
		(width 0.11684)
		(layer "In2.Cu")
		(net "APML_CPU0_ALERT_R_N")
	)
	(segment
		(start 303.557432 -169.79011)
		(end 303.982882 -170.21556)
		(width 0.11684)
		(layer "In2.Cu")
		(net "APML_CPU0_ALERT_R_N")
	)
	(segment
		(start 185.751724 -131.384802)
		(end 185.751724 -133.617208)
		(width 0.11684)
		(layer "In4.Cu")
		(net "APML_CPU0_ALERT_R_N")
	)
	(segment
		(start 186.573414 -129.262632)
		(end 186.573414 -130.563112)
		(width 0.11684)
		(layer "In4.Cu")
		(net "APML_CPU0_ALERT_R_N")
	)
	(segment
		(start 184.732168 -119.842788)
		(end 185.003694 -119.842788)
		(width 0.11684)
		(layer "In4.Cu")
		(net "APML_CPU0_ALERT_R_N")
	)
	(segment
		(start 185.214514 -120.053608)
		(end 185.214514 -127.903732)
		(width 0.11684)
		(layer "In4.Cu")
		(net "APML_CPU0_ALERT_R_N")
	)
	(segment
		(start 185.59018 -137.442448)
		(end 186.573414 -138.425682)
		(width 0.11684)
		(layer "In4.Cu")
		(net "APML_CPU0_ALERT_R_N")
	)
	(segment
		(start 187.035948 -160.87979)
		(end 187.035948 -161.760916)
		(width 0.11684)
		(layer "In4.Cu")
		(net "APML_CPU0_ALERT_R_N")
	)
	(segment
		(start 186.573414 -160.417256)
		(end 187.035948 -160.87979)
		(width 0.11684)
		(layer "In4.Cu")
		(net "APML_CPU0_ALERT_R_N")
	)
	(segment
		(start 185.751724 -133.617208)
		(end 185.59018 -133.778752)
		(width 0.11684)
		(layer "In4.Cu")
		(net "APML_CPU0_ALERT_R_N")
	)
	(segment
		(start 185.59018 -133.778752)
		(end 185.59018 -137.442448)
		(width 0.11684)
		(layer "In4.Cu")
		(net "APML_CPU0_ALERT_R_N")
	)
	(segment
		(start 186.573414 -138.425682)
		(end 186.573414 -160.417256)
		(width 0.11684)
		(layer "In4.Cu")
		(net "APML_CPU0_ALERT_R_N")
	)
	(segment
		(start 185.003694 -119.842788)
		(end 185.214514 -120.053608)
		(width 0.11684)
		(layer "In4.Cu")
		(net "APML_CPU0_ALERT_R_N")
	)
	(segment
		(start 186.573414 -130.563112)
		(end 185.751724 -131.384802)
		(width 0.11684)
		(layer "In4.Cu")
		(net "APML_CPU0_ALERT_R_N")
	)
	(segment
		(start 185.214514 -127.903732)
		(end 186.573414 -129.262632)
		(width 0.11684)
		(layer "In4.Cu")
		(net "APML_CPU0_ALERT_R_N")
	)
	(segment
		(start 303.520348 -169.709592)
		(end 302.675544 -170.554396)
		(width 0.11684)
		(layer "In15.Cu")
		(net "APML_CPU0_ALERT_R_N")
	)
	(segment
		(start 303.557432 -169.709592)
		(end 303.520348 -169.709592)
		(width 0.11684)
		(layer "In15.Cu")
		(net "APML_CPU0_ALERT_R_N")
	)
	(segment
		(start 236.953806 -167.367966)
		(end 236.52226 -166.93642)
		(width 0.11684)
		(layer "In15.Cu")
		(net "APML_CPU0_ALERT_R_N")
	)
	(segment
		(start 216.486994 -166.93642)
		(end 216.128346 -166.577772)
		(width 0.11684)
		(layer "In15.Cu")
		(net "APML_CPU0_ALERT_R_N")
	)
	(segment
		(start 266.094464 -166.100506)
		(end 240.370868 -166.100506)
		(width 0.11684)
		(layer "In15.Cu")
		(net "APML_CPU0_ALERT_R_N")
	)
	(segment
		(start 240.370868 -166.100506)
		(end 239.103408 -167.367966)
		(width 0.11684)
		(layer "In15.Cu")
		(net "APML_CPU0_ALERT_R_N")
	)
	(segment
		(start 192.30213 -163.327334)
		(end 188.602366 -163.327334)
		(width 0.11684)
		(layer "In15.Cu")
		(net "APML_CPU0_ALERT_R_N")
	)
	(segment
		(start 239.103408 -167.367966)
		(end 236.953806 -167.367966)
		(width 0.11684)
		(layer "In15.Cu")
		(net "APML_CPU0_ALERT_R_N")
	)
	(segment
		(start 270.27378 -170.279822)
		(end 266.094464 -166.100506)
		(width 0.11684)
		(layer "In15.Cu")
		(net "APML_CPU0_ALERT_R_N")
	)
	(segment
		(start 216.128346 -166.577772)
		(end 212.074506 -166.577772)
		(width 0.11684)
		(layer "In15.Cu")
		(net "APML_CPU0_ALERT_R_N")
	)
	(segment
		(start 188.602366 -163.327334)
		(end 187.035948 -161.760916)
		(width 0.11684)
		(layer "In15.Cu")
		(net "APML_CPU0_ALERT_R_N")
	)
	(segment
		(start 195.911216 -166.93642)
		(end 192.30213 -163.327334)
		(width 0.11684)
		(layer "In15.Cu")
		(net "APML_CPU0_ALERT_R_N")
	)
	(segment
		(start 302.675544 -170.554396)
		(end 295.399714 -170.554396)
		(width 0.11684)
		(layer "In15.Cu")
		(net "APML_CPU0_ALERT_R_N")
	)
	(segment
		(start 236.52226 -166.93642)
		(end 216.486994 -166.93642)
		(width 0.11684)
		(layer "In15.Cu")
		(net "APML_CPU0_ALERT_R_N")
	)
	(segment
		(start 295.399714 -170.554396)
		(end 295.12514 -170.279822)
		(width 0.11684)
		(layer "In15.Cu")
		(net "APML_CPU0_ALERT_R_N")
	)
	(segment
		(start 211.715858 -166.93642)
		(end 195.911216 -166.93642)
		(width 0.11684)
		(layer "In15.Cu")
		(net "APML_CPU0_ALERT_R_N")
	)
	(segment
		(start 295.12514 -170.279822)
		(end 270.27378 -170.279822)
		(width 0.11684)
		(layer "In15.Cu")
		(net "APML_CPU0_ALERT_R_N")
	)
	(segment
		(start 212.074506 -166.577772)
		(end 211.715858 -166.93642)
		(width 0.11684)
		(layer "In15.Cu")
		(net "APML_CPU0_ALERT_R_N")
	)
	(segment
		(start 324.529958 -195.678552)
		(end 324.529958 -194.326002)
		(width 0.10668)
		(layer "F.Cu")
		(net "APML_CPU0_ALERT_N")
	)
	(segment
		(start 325.545958 -198.06412)
		(end 325.545958 -196.694552)
		(width 0.10668)
		(layer "F.Cu")
		(net "APML_CPU0_ALERT_N")
	)
	(segment
		(start 336.726022 -209.244184)
		(end 325.545958 -198.06412)
		(width 0.10668)
		(layer "F.Cu")
		(net "APML_CPU0_ALERT_N")
	)
	(segment
		(start 331.987906 -220.84665)
		(end 336.726022 -216.108534)
		(width 0.10668)
		(layer "F.Cu")
		(net "APML_CPU0_ALERT_N")
	)
	(segment
		(start 331.987906 -222.070168)
		(end 331.987906 -220.84665)
		(width 0.10668)
		(layer "F.Cu")
		(net "APML_CPU0_ALERT_N")
	)
	(segment
		(start 336.726022 -216.108534)
		(end 336.726022 -209.244184)
		(width 0.10668)
		(layer "F.Cu")
		(net "APML_CPU0_ALERT_N")
	)
	(segment
		(start 325.545958 -194.326002)
		(end 324.529958 -194.326002)
		(width 0.10668)
		(layer "F.Cu")
		(net "APML_CPU0_ALERT_N")
	)
	(segment
		(start 325.545958 -196.694552)
		(end 324.529958 -195.678552)
		(width 0.10668)
		(layer "F.Cu")
		(net "APML_CPU0_ALERT_N")
	)
	(via
		(at 324.529958 -195.678552)
		(size 0.762)
		(drill 0.381)
		(layers "F.Cu" "B.Cu")
		(net "APML_CPU0_ALERT_N")
	)
	(segment
		(start 178.31689 -399.420842)
		(end 177.70094 -399.420842)
		(width 0.3556)
		(layer "F.Cu")
		(net "AGND_HSC")
	)
	(segment
		(start 181.38394 -401.69465)
		(end 182.041038 -401.69465)
		(width 0.254)
		(layer "F.Cu")
		(net "AGND_HSC")
	)
	(segment
		(start 195.887594 -402.170138)
		(end 195.6943 -402.363432)
		(width 0.254)
		(layer "F.Cu")
		(net "AGND_HSC")
	)
	(segment
		(start 178.28895 -405.511)
		(end 178.28895 -404.528782)
		(width 0.381)
		(layer "F.Cu")
		(net "AGND_HSC")
	)
	(segment
		(start 205.16215 -404.020782)
		(end 205.7781 -404.020782)
		(width 0.254)
		(layer "F.Cu")
		(net "AGND_HSC")
	)
	(segment
		(start 193.82105 -399.982182)
		(end 193.2051 -399.982182)
		(width 0.254)
		(layer "F.Cu")
		(net "AGND_HSC")
	)
	(segment
		(start 215.03005 -400.972782)
		(end 214.4141 -400.972782)
		(width 0.3556)
		(layer "F.Cu")
		(net "AGND_HSC")
	)
	(segment
		(start 178.28895 -407.543)
		(end 177.546 -407.543)
		(width 0.381)
		(layer "F.Cu")
		(net "AGND_HSC")
	)
	(segment
		(start 191.81699 -403.611842)
		(end 192.43294 -403.611842)
		(width 0.3556)
		(layer "F.Cu")
		(net "AGND_HSC")
	)
	(segment
		(start 178.32451 -396.385542)
		(end 178.32451 -397.381222)
		(width 0.3556)
		(layer "F.Cu")
		(net "AGND_HSC")
	)
	(segment
		(start 193.817748 -398.940782)
		(end 193.2051 -398.940782)
		(width 0.254)
		(layer "F.Cu")
		(net "AGND_HSC")
	)
	(segment
		(start 204.36205 -405.036782)
		(end 203.7461 -405.036782)
		(width 0.254)
		(layer "F.Cu")
		(net "AGND_HSC")
	)
	(segment
		(start 181.476396 -397.848582)
		(end 182.16245 -397.848582)
		(width 0.3556)
		(layer "F.Cu")
		(net "AGND_HSC")
	)
	(segment
		(start 205.16215 -407.068782)
		(end 205.7781 -407.068782)
		(width 0.254)
		(layer "F.Cu")
		(net "AGND_HSC")
	)
	(segment
		(start 183.745632 -408.617674)
		(end 183.745632 -408.61996)
		(width 0.3556)
		(layer "F.Cu")
		(net "AGND_HSC")
	)
	(segment
		(start 178.31689 -397.388842)
		(end 178.31689 -398.404842)
		(width 0.3556)
		(layer "F.Cu")
		(net "AGND_HSC")
	)
	(segment
		(start 205.9559 -403.284182)
		(end 205.9559 -403.074632)
		(width 0.3556)
		(layer "F.Cu")
		(net "AGND_HSC")
	)
	(segment
		(start 225.69805 -398.940782)
		(end 225.0821 -398.940782)
		(width 0.254)
		(layer "F.Cu")
		(net "AGND_HSC")
	)
	(segment
		(start 183.425084 -408.297126)
		(end 183.745632 -408.617674)
		(width 0.3556)
		(layer "F.Cu")
		(net "AGND_HSC")
	)
	(segment
		(start 227.2919 -403.284182)
		(end 227.2919 -403.074632)
		(width 0.3556)
		(layer "F.Cu")
		(net "AGND_HSC")
	)
	(segment
		(start 227.2919 -403.074632)
		(end 227.7745 -402.592032)
		(width 0.3556)
		(layer "F.Cu")
		(net "AGND_HSC")
	)
	(segment
		(start 193.82105 -403.284182)
		(end 193.2051 -403.284182)
		(width 0.254)
		(layer "F.Cu")
		(net "AGND_HSC")
	)
	(segment
		(start 179.418996 -401.452842)
		(end 179.718716 -401.153122)
		(width 0.3556)
		(layer "F.Cu")
		(net "AGND_HSC")
	)
	(segment
		(start 178.31689 -400.436842)
		(end 177.70094 -400.436842)
		(width 0.3556)
		(layer "F.Cu")
		(net "AGND_HSC")
	)
	(segment
		(start 205.9559 -403.074632)
		(end 206.4385 -402.592032)
		(width 0.3556)
		(layer "F.Cu")
		(net "AGND_HSC")
	)
	(segment
		(start 228.35489 -402.170138)
		(end 229.303072 -402.170138)
		(width 0.254)
		(layer "F.Cu")
		(net "AGND_HSC")
	)
	(segment
		(start 178.32451 -397.381222)
		(end 178.31689 -397.388842)
		(width 0.3556)
		(layer "F.Cu")
		(net "AGND_HSC")
	)
	(segment
		(start 225.69805 -405.036782)
		(end 225.0821 -405.036782)
		(width 0.254)
		(layer "F.Cu")
		(net "AGND_HSC")
	)
	(segment
		(start 178.28895 -405.511)
		(end 177.673 -405.511)
		(width 0.381)
		(layer "F.Cu")
		(net "AGND_HSC")
	)
	(segment
		(start 217.264996 -402.592032)
		(end 217.1065 -402.592032)
		(width 0.254)
		(layer "F.Cu")
		(net "AGND_HSC")
	)
	(segment
		(start 178.31689 -398.404842)
		(end 177.70094 -398.404842)
		(width 0.3556)
		(layer "F.Cu")
		(net "AGND_HSC")
	)
	(segment
		(start 207.967072 -402.170138)
		(end 207.01889 -402.170138)
		(width 0.254)
		(layer "F.Cu")
		(net "AGND_HSC")
	)
	(segment
		(start 215.83015 -407.068782)
		(end 216.4461 -407.068782)
		(width 0.254)
		(layer "F.Cu")
		(net "AGND_HSC")
	)
	(segment
		(start 237.16615 -403.919182)
		(end 237.7821 -403.919182)
		(width 0.254)
		(layer "F.Cu")
		(net "AGND_HSC")
	)
	(segment
		(start 183.425084 -407.266648)
		(end 183.425084 -408.297126)
		(width 0.3556)
		(layer "F.Cu")
		(net "AGND_HSC")
	)
	(segment
		(start 237.16615 -401.887182)
		(end 237.7821 -401.887182)
		(width 0.254)
		(layer "F.Cu")
		(net "AGND_HSC")
	)
	(segment
		(start 206.596996 -402.592032)
		(end 206.4385 -402.592032)
		(width 0.254)
		(layer "F.Cu")
		(net "AGND_HSC")
	)
	(segment
		(start 217.68689 -402.170138)
		(end 217.264996 -402.592032)
		(width 0.254)
		(layer "F.Cu")
		(net "AGND_HSC")
	)
	(segment
		(start 197.299072 -402.170138)
		(end 195.887594 -402.170138)
		(width 0.254)
		(layer "F.Cu")
		(net "AGND_HSC")
	)
	(segment
		(start 178.31689 -402.468842)
		(end 177.70094 -402.468842)
		(width 0.254)
		(layer "F.Cu")
		(net "AGND_HSC")
	)
	(segment
		(start 179.11699 -401.452842)
		(end 179.418996 -401.452842)
		(width 0.3556)
		(layer "F.Cu")
		(net "AGND_HSC")
	)
	(segment
		(start 179.718716 -401.153122)
		(end 180.842412 -401.153122)
		(width 0.3556)
		(layer "F.Cu")
		(net "AGND_HSC")
	)
	(segment
		(start 215.03005 -405.036782)
		(end 214.4141 -405.036782)
		(width 0.254)
		(layer "F.Cu")
		(net "AGND_HSC")
	)
	(segment
		(start 183.6547 -407.037032)
		(end 183.425084 -407.266648)
		(width 0.3556)
		(layer "F.Cu")
		(net "AGND_HSC")
	)
	(segment
		(start 226.49815 -407.068782)
		(end 227.1141 -407.068782)
		(width 0.254)
		(layer "F.Cu")
		(net "AGND_HSC")
	)
	(segment
		(start 214.4141 -402.039582)
		(end 214.97925 -402.039582)
		(width 0.254)
		(layer "F.Cu")
		(net "AGND_HSC")
	)
	(segment
		(start 216.6239 -403.284182)
		(end 216.6239 -403.074632)
		(width 0.3556)
		(layer "F.Cu")
		(net "AGND_HSC")
	)
	(segment
		(start 225.69805 -400.972782)
		(end 225.0821 -400.972782)
		(width 0.3556)
		(layer "F.Cu")
		(net "AGND_HSC")
	)
	(segment
		(start 215.83015 -404.020782)
		(end 216.4461 -404.020782)
		(width 0.254)
		(layer "F.Cu")
		(net "AGND_HSC")
	)
	(segment
		(start 177.673 -405.511)
		(end 177.419 -405.257)
		(width 0.381)
		(layer "F.Cu")
		(net "AGND_HSC")
	)
	(segment
		(start 204.36205 -398.940782)
		(end 203.7461 -398.940782)
		(width 0.254)
		(layer "F.Cu")
		(net "AGND_HSC")
	)
	(segment
		(start 207.01889 -402.170138)
		(end 206.596996 -402.592032)
		(width 0.254)
		(layer "F.Cu")
		(net "AGND_HSC")
	)
	(segment
		(start 218.635072 -402.170138)
		(end 217.68689 -402.170138)
		(width 0.254)
		(layer "F.Cu")
		(net "AGND_HSC")
	)
	(segment
		(start 180.842412 -401.153122)
		(end 181.38394 -401.69465)
		(width 0.3556)
		(layer "F.Cu")
		(net "AGND_HSC")
	)
	(segment
		(start 226.49815 -404.020782)
		(end 227.1141 -404.020782)
		(width 0.254)
		(layer "F.Cu")
		(net "AGND_HSC")
	)
	(segment
		(start 216.6239 -403.074632)
		(end 217.1065 -402.592032)
		(width 0.3556)
		(layer "F.Cu")
		(net "AGND_HSC")
	)
	(segment
		(start 225.0821 -402.039582)
		(end 225.64725 -402.039582)
		(width 0.254)
		(layer "F.Cu")
		(net "AGND_HSC")
	)
	(segment
		(start 215.03005 -398.940782)
		(end 214.4141 -398.940782)
		(width 0.254)
		(layer "F.Cu")
		(net "AGND_HSC")
	)
	(segment
		(start 195.6943 -402.363432)
		(end 195.0085 -402.363432)
		(width 0.3556)
		(layer "F.Cu")
		(net "AGND_HSC")
	)
	(segment
		(start 227.7745 -402.592032)
		(end 227.932996 -402.592032)
		(width 0.254)
		(layer "F.Cu")
		(net "AGND_HSC")
	)
	(segment
		(start 193.82105 -400.998182)
		(end 193.2051 -400.998182)
		(width 0.254)
		(layer "F.Cu")
		(net "AGND_HSC")
	)
	(segment
		(start 227.932996 -402.592032)
		(end 228.35489 -402.170138)
		(width 0.254)
		(layer "F.Cu")
		(net "AGND_HSC")
	)
	(segment
		(start 204.31125 -402.039582)
		(end 204.36205 -401.988782)
		(width 0.254)
		(layer "F.Cu")
		(net "AGND_HSC")
	)
	(segment
		(start 225.64725 -402.039582)
		(end 225.69805 -401.988782)
		(width 0.254)
		(layer "F.Cu")
		(net "AGND_HSC")
	)
	(segment
		(start 203.7461 -402.039582)
		(end 204.31125 -402.039582)
		(width 0.254)
		(layer "F.Cu")
		(net "AGND_HSC")
	)
	(segment
		(start 178.28895 -404.528782)
		(end 178.31689 -404.500842)
		(width 0.381)
		(layer "F.Cu")
		(net "AGND_HSC")
	)
	(segment
		(start 177.419 -405.257)
		(end 177.419 -404.89505)
		(width 0.381)
		(layer "F.Cu")
		(net "AGND_HSC")
	)
	(segment
		(start 204.36205 -400.972782)
		(end 203.7461 -400.972782)
		(width 0.3556)
		(layer "F.Cu")
		(net "AGND_HSC")
	)
	(segment
		(start 214.97925 -402.039582)
		(end 215.03005 -401.988782)
		(width 0.254)
		(layer "F.Cu")
		(net "AGND_HSC")
	)
	(via
		(at 214.4141 -398.940782)
		(size 0.508)
		(drill 0.254)
		(layers "F.Cu" "B.Cu")
		(net "AGND_HSC")
	)
	(via
		(at 225.0821 -400.972782)
		(size 0.508)
		(drill 0.254)
		(layers "F.Cu" "B.Cu")
		(net "AGND_HSC")
	)
	(via
		(at 203.7461 -400.972782)
		(size 0.508)
		(drill 0.254)
		(layers "F.Cu" "B.Cu")
		(net "AGND_HSC")
	)
	(via
		(at 227.1141 -404.020782)
		(size 0.508)
		(drill 0.254)
		(layers "F.Cu" "B.Cu")
		(net "AGND_HSC")
	)
	(via
		(at 216.4461 -404.020782)
		(size 0.508)
		(drill 0.254)
		(layers "F.Cu" "B.Cu")
		(net "AGND_HSC")
	)
	(via
		(at 205.9559 -403.284182)
		(size 0.508)
		(drill 0.254)
		(layers "F.Cu" "B.Cu")
		(net "AGND_HSC")
	)
	(via
		(at 203.7461 -398.940782)
		(size 0.508)
		(drill 0.254)
		(layers "F.Cu" "B.Cu")
		(net "AGND_HSC")
	)
	(via
		(at 177.70094 -400.436842)
		(size 0.508)
		(drill 0.254)
		(layers "F.Cu" "B.Cu")
		(net "AGND_HSC")
	)
	(via
		(at 193.2051 -398.940782)
		(size 0.508)
		(drill 0.254)
		(layers "F.Cu" "B.Cu")
		(net "AGND_HSC")
	)
	(via
		(at 225.0821 -402.039582)
		(size 0.508)
		(drill 0.254)
		(layers "F.Cu" "B.Cu")
		(net "AGND_HSC")
	)
	(via
		(at 203.7461 -402.039582)
		(size 0.508)
		(drill 0.254)
		(layers "F.Cu" "B.Cu")
		(net "AGND_HSC")
	)
	(via
		(at 195.0085 -402.363432)
		(size 0.508)
		(drill 0.254)
		(layers "F.Cu" "B.Cu")
		(net "AGND_HSC")
	)
	(via
		(at 216.6239 -403.284182)
		(size 0.508)
		(drill 0.254)
		(layers "F.Cu" "B.Cu")
		(net "AGND_HSC")
	)
	(via
		(at 193.2051 -403.284182)
		(size 0.508)
		(drill 0.254)
		(layers "F.Cu" "B.Cu")
		(net "AGND_HSC")
	)
	(via
		(at 216.4461 -407.068782)
		(size 0.508)
		(drill 0.254)
		(layers "F.Cu" "B.Cu")
		(net "AGND_HSC")
	)
	(via
		(at 177.673 -405.511)
		(size 0.508)
		(drill 0.254)
		(layers "F.Cu" "B.Cu")
		(net "AGND_HSC")
	)
	(via
		(at 205.7781 -404.020782)
		(size 0.508)
		(drill 0.254)
		(layers "F.Cu" "B.Cu")
		(net "AGND_HSC")
	)
	(via
		(at 214.4141 -402.039582)
		(size 0.508)
		(drill 0.254)
		(layers "F.Cu" "B.Cu")
		(net "AGND_HSC")
	)
	(via
		(at 227.2919 -403.284182)
		(size 0.508)
		(drill 0.254)
		(layers "F.Cu" "B.Cu")
		(net "AGND_HSC")
	)
	(via
		(at 193.2051 -400.998182)
		(size 0.508)
		(drill 0.254)
		(layers "F.Cu" "B.Cu")
		(net "AGND_HSC")
	)
	(via
		(at 203.7461 -405.036782)
		(size 0.508)
		(drill 0.254)
		(layers "F.Cu" "B.Cu")
		(net "AGND_HSC")
	)
	(via
		(at 227.1141 -407.068782)
		(size 0.508)
		(drill 0.254)
		(layers "F.Cu" "B.Cu")
		(net "AGND_HSC")
	)
	(via
		(at 237.7821 -401.887182)
		(size 0.508)
		(drill 0.254)
		(layers "F.Cu" "B.Cu")
		(net "AGND_HSC")
	)
	(via
		(at 177.70094 -402.468842)
		(size 0.508)
		(drill 0.254)
		(layers "F.Cu" "B.Cu")
		(net "AGND_HSC")
	)
	(via
		(at 192.43294 -403.611842)
		(size 0.508)
		(drill 0.254)
		(layers "F.Cu" "B.Cu")
		(net "AGND_HSC")
	)
	(via
		(at 183.745632 -408.61996)
		(size 0.508)
		(drill 0.254)
		(layers "F.Cu" "B.Cu")
		(net "AGND_HSC")
	)
	(via
		(at 182.870602 -402.79066)
		(size 0.508)
		(drill 0.254)
		(layers "F.Cu" "B.Cu")
		(net "AGND_HSC")
	)
	(via
		(at 214.4141 -400.972782)
		(size 0.508)
		(drill 0.254)
		(layers "F.Cu" "B.Cu")
		(net "AGND_HSC")
	)
	(via
		(at 183.378602 -403.29866)
		(size 0.508)
		(drill 0.254)
		(layers "F.Cu" "B.Cu")
		(net "AGND_HSC")
	)
	(via
		(at 177.546 -407.543)
		(size 0.508)
		(drill 0.254)
		(layers "F.Cu" "B.Cu")
		(net "AGND_HSC")
	)
	(via
		(at 225.0821 -405.036782)
		(size 0.508)
		(drill 0.254)
		(layers "F.Cu" "B.Cu")
		(net "AGND_HSC")
	)
	(via
		(at 237.7821 -403.919182)
		(size 0.508)
		(drill 0.254)
		(layers "F.Cu" "B.Cu")
		(net "AGND_HSC")
	)
	(via
		(at 214.4141 -405.036782)
		(size 0.508)
		(drill 0.254)
		(layers "F.Cu" "B.Cu")
		(net "AGND_HSC")
	)
	(via
		(at 193.2051 -399.982182)
		(size 0.508)
		(drill 0.254)
		(layers "F.Cu" "B.Cu")
		(net "AGND_HSC")
	)
	(via
		(at 177.70094 -398.404842)
		(size 0.508)
		(drill 0.254)
		(layers "F.Cu" "B.Cu")
		(net "AGND_HSC")
	)
	(via
		(at 177.70094 -399.420842)
		(size 0.508)
		(drill 0.254)
		(layers "F.Cu" "B.Cu")
		(net "AGND_HSC")
	)
	(via
		(at 205.7781 -407.068782)
		(size 0.508)
		(drill 0.254)
		(layers "F.Cu" "B.Cu")
		(net "AGND_HSC")
	)
	(via
		(at 181.38394 -401.69465)
		(size 0.508)
		(drill 0.254)
		(layers "F.Cu" "B.Cu")
		(net "AGND_HSC")
	)
	(via
		(at 225.0821 -398.940782)
		(size 0.508)
		(drill 0.254)
		(layers "F.Cu" "B.Cu")
		(net "AGND_HSC")
	)
	(via
		(at 181.476396 -397.848582)
		(size 0.508)
		(drill 0.254)
		(layers "F.Cu" "B.Cu")
		(net "AGND_HSC")
	)
	(via
		(at 183.886602 -402.79066)
		(size 0.508)
		(drill 0.254)
		(layers "F.Cu" "B.Cu")
		(net "AGND_HSC")
	)
	(segment
		(start 182.382922 -399.48612)
		(end 182.764684 -399.867882)
		(width 0.3556)
		(layer "B.Cu")
		(net "AGND_HSC")
	)
	(segment
		(start 183.36006 -407.77414)
		(end 183.36006 -407.622248)
		(width 0.254)
		(layer "B.Cu")
		(net "AGND_HSC")
	)
	(segment
		(start 183.745632 -408.61996)
		(end 183.745632 -408.159712)
		(width 0.254)
		(layer "B.Cu")
		(net "AGND_HSC")
	)
	(segment
		(start 181.476396 -397.848582)
		(end 182.382922 -398.755108)
		(width 0.3556)
		(layer "B.Cu")
		(net "AGND_HSC")
	)
	(segment
		(start 182.382922 -399.370804)
		(end 182.382922 -399.48612)
		(width 0.3556)
		(layer "B.Cu")
		(net "AGND_HSC")
	)
	(segment
		(start 182.382922 -398.755108)
		(end 182.382922 -399.370804)
		(width 0.3556)
		(layer "B.Cu")
		(net "AGND_HSC")
	)
	(segment
		(start 183.3753 -402.318982)
		(end 183.34228 -402.318982)
		(width 0.4572)
		(layer "B.Cu")
		(net "AGND_HSC")
	)
	(segment
		(start 183.745632 -408.159712)
		(end 183.36006 -407.77414)
		(width 0.254)
		(layer "B.Cu")
		(net "AGND_HSC")
	)
	(segment
		(start 183.34228 -402.318982)
		(end 182.870602 -402.79066)
		(width 0.4572)
		(layer "B.Cu")
		(net "AGND_HSC")
	)
	(zone
		(layer "F.Cu")
		(hatch none 0.5)
		(connect_pads
			(clearance 0)
		)
		(min_thickness 0.25)
		(keepout
			(tracks not_allowed)
			(vias allowed)
			(pads allowed)
			(copperpour not_allowed)
			(footprints allowed)
		)
		(placement
			(enabled no)
			(sheetname "")
		)
		(fill
			(thermal_gap 0.5)
			(thermal_bridge_width 0.5)
			(island_removal_mode 0)
		)
		(polygon
			(pts
				(xy 298.31919 -347.417136) (xy 298.31919 -348.378018) (xy 298.561506 -348.378018) (xy 298.561506 -347.417136)
			)
		)
	)
	(zone
		(layer "F.Cu")
		(hatch none 0.5)
		(connect_pads
			(clearance 0)
		)
		(min_thickness 0.25)
		(keepout
			(tracks allowed)
			(vias allowed)
			(pads allowed)
			(copperpour allowed)
			(footprints not_allowed)
		)
		(placement
			(enabled no)
			(sheetname "")
		)
		(fill
			(thermal_gap 0.5)
			(thermal_bridge_width 0.5)
			(island_removal_mode 0)
		)
		(polygon
			(pts
				(arc
					(start 78.529942 -304.790094)
					(mid 81.330038 -301.989998)
					(end 84.12988 -304.790094)
				)
				(arc
					(start 84.12988 -304.790094)
					(mid 81.330038 -307.589936)
					(end 78.529942 -304.790094)
				)
			)
		)
	)
	(zone
		(layer "F.Cu")
		(hatch none 0.5)
		(connect_pads
			(clearance 0)
		)
		(min_thickness 0.25)
		(keepout
			(tracks allowed)
			(vias allowed)
			(pads allowed)
			(copperpour allowed)
			(footprints allowed)
		)
		(placement
			(enabled no)
			(sheetname "")
		)
		(fill
			(thermal_gap 0.5)
			(thermal_bridge_width 0.5)
			(island_removal_mode 0)
		)
		(polygon
			(pts
				(xy 147.467828 -376.024902) (xy 147.467828 -375.02084) (xy 148.86432 -375.02084) (xy 148.86432 -376.024902)
			)
		)
	)
	(zone
		(layer "F.Cu")
		(hatch none 0.5)
		(connect_pads
			(clearance 0)
		)
		(min_thickness 0.25)
		(keepout
			(tracks allowed)
			(vias allowed)
			(pads allowed)
			(copperpour allowed)
			(footprints allowed)
		)
		(placement
			(enabled no)
			(sheetname "")
		)
		(fill
			(thermal_gap 0.5)
			(thermal_bridge_width 0.5)
			(island_removal_mode 0)
		)
		(polygon
			(pts
				(xy 142.362428 -373.561102) (xy 142.362428 -372.55704) (xy 143.75892 -372.55704) (xy 143.75892 -373.561102)
			)
		)
	)
	(zone
		(layer "F.Cu")
		(hatch none 0.5)
		(connect_pads
			(clearance 0)
		)
		(min_thickness 0.25)
		(keepout
			(tracks allowed)
			(vias allowed)
			(pads allowed)
			(copperpour allowed)
			(footprints allowed)
		)
		(placement
			(enabled no)
			(sheetname "")
		)
		(fill
			(thermal_gap 0.5)
			(thermal_bridge_width 0.5)
			(island_removal_mode 0)
		)
		(polygon
			(pts
				(xy 308.66588 -308.092348) (xy 308.66588 -308.422548) (xy 306.12588 -308.422548) (xy 306.12588 -308.092348)
			)
		)
	)
	(zone
		(layer "F.Cu")
		(hatch none 0.5)
		(connect_pads
			(clearance 0)
		)
		(min_thickness 0.25)
		(keepout
			(tracks allowed)
			(vias allowed)
			(pads allowed)
			(copperpour allowed)
			(footprints allowed)
		)
		(placement
			(enabled no)
			(sheetname "")
		)
		(fill
			(thermal_gap 0.5)
			(thermal_bridge_width 0.5)
			(island_removal_mode 0)
		)
		(polygon
			(pts
				(xy 458.51826 -50.007266) (xy 458.51826 -48.52924) (xy 460.84998 -48.52924) (xy 460.84998 -50.007266)
			)
		)
	)
	(zone
		(layer "F.Cu")
		(hatch none 0.5)
		(connect_pads
			(clearance 0)
		)
		(min_thickness 0.25)
		(keepout
			(tracks allowed)
			(vias allowed)
			(pads allowed)
			(copperpour allowed)
			(footprints not_allowed)
		)
		(placement
			(enabled no)
			(sheetname "")
		)
		(fill
			(thermal_gap 0.5)
			(thermal_bridge_width 0.5)
			(island_removal_mode 0)
		)
		(polygon
			(pts
				(arc
					(start 92.099892 -22.29993)
					(mid 94.899988 -19.499834)
					(end 97.700084 -22.29993)
				)
				(arc
					(start 97.700084 -22.29993)
					(mid 94.899988 -25.100026)
					(end 92.099892 -22.29993)
				)
			)
		)
	)
	(zone
		(layer "F.Cu")
		(hatch none 0.5)
		(connect_pads
			(clearance 0)
		)
		(min_thickness 0.25)
		(keepout
			(tracks allowed)
			(vias allowed)
			(pads allowed)
			(copperpour allowed)
			(footprints allowed)
		)
		(placement
			(enabled no)
			(sheetname "")
		)
		(fill
			(thermal_gap 0.5)
			(thermal_bridge_width 0.5)
			(island_removal_mode 0)
		)
		(polygon
			(pts
				(xy 239.84331 -293.764716) (xy 241.404648 -293.764716) (xy 242.18138 -292.987984) (xy 242.18138 -289.928046)
				(xy 241.851688 -289.598354) (xy 240.603786 -289.598354) (xy 238.009176 -289.598354) (xy 237.794546 -289.812984)
				(xy 237.794546 -290.836858) (xy 238.043212 -291.085524) (xy 239.670336 -291.085524) (xy 239.670336 -293.591742)
			)
		)
	)
	(zone
		(layer "F.Cu")
		(hatch none 0.5)
		(connect_pads
			(clearance 0)
		)
		(min_thickness 0.25)
		(keepout
			(tracks allowed)
			(vias allowed)
			(pads allowed)
			(copperpour allowed)
			(footprints not_allowed)
		)
		(placement
			(enabled no)
			(sheetname "")
		)
		(fill
			(thermal_gap 0.5)
			(thermal_bridge_width 0.5)
			(island_removal_mode 0)
		)
		(polygon
			(pts
				(xy 307.384958 -48.410114) (xy 294.014906 -48.410114) (xy 294.014906 -59.390026) (xy 307.384958 -59.390026)
			)
		)
	)
	(zone
		(layer "F.Cu")
		(hatch none 0.5)
		(connect_pads
			(clearance 0)
		)
		(min_thickness 0.25)
		(keepout
			(tracks allowed)
			(vias allowed)
			(pads allowed)
			(copperpour allowed)
			(footprints not_allowed)
		)
		(placement
			(enabled no)
			(sheetname "")
		)
		(fill
			(thermal_gap 0.5)
			(thermal_bridge_width 0.5)
			(island_removal_mode 0)
		)
		(polygon
			(pts
				(arc
					(start 139.729972 -212.989922)
					(mid 142.530068 -210.189826)
					(end 145.32991 -212.989922)
				)
				(arc
					(start 145.32991 -212.989922)
					(mid 142.530068 -215.789764)
					(end 139.729972 -212.989922)
				)
			)
		)
	)
	(zone
		(layer "F.Cu")
		(hatch none 0.5)
		(connect_pads
			(clearance 0)
		)
		(min_thickness 0.25)
		(keepout
			(tracks allowed)
			(vias allowed)
			(pads allowed)
			(copperpour allowed)
			(footprints allowed)
		)
		(placement
			(enabled no)
			(sheetname "")
		)
		(fill
			(thermal_gap 0.5)
			(thermal_bridge_width 0.5)
			(island_removal_mode 0)
		)
		(polygon
			(pts
				(xy 411.317694 -273.578066) (xy 411.317694 -273.247866) (xy 413.236664 -273.247866) (xy 413.236664 -273.578066)
			)
		)
	)
	(zone
		(layer "F.Cu")
		(hatch none 0.5)
		(connect_pads
			(clearance 0)
		)
		(min_thickness 0.25)
		(keepout
			(tracks allowed)
			(vias allowed)
			(pads allowed)
			(copperpour allowed)
			(footprints allowed)
		)
		(placement
			(enabled no)
			(sheetname "")
		)
		(fill
			(thermal_gap 0.5)
			(thermal_bridge_width 0.5)
			(island_removal_mode 0)
		)
		(polygon
			(pts
				(xy 168.843452 -375.812812) (xy 169.847514 -375.812812) (xy 169.847514 -377.209304) (xy 168.843452 -377.209304)
			)
		)
	)
	(zone
		(layer "F.Cu")
		(hatch none 0.5)
		(connect_pads
			(clearance 0)
		)
		(min_thickness 0.25)
		(keepout
			(tracks not_allowed)
			(vias allowed)
			(pads allowed)
			(copperpour not_allowed)
			(footprints allowed)
		)
		(placement
			(enabled no)
			(sheetname "")
		)
		(fill
			(thermal_gap 0.5)
			(thermal_bridge_width 0.5)
			(island_removal_mode 0)
		)
		(polygon
			(pts
				(arc
					(start 135.986012 -146.84502)
					(mid 132.886196 -149.944836)
					(end 129.786126 -146.84502)
				)
				(arc
					(start 129.786126 -146.84502)
					(mid 132.886196 -143.74495)
					(end 135.986012 -146.84502)
				)
			)
		)
	)
	(zone
		(layer "F.Cu")
		(hatch none 0.5)
		(connect_pads
			(clearance 0)
		)
		(min_thickness 0.25)
		(keepout
			(tracks allowed)
			(vias allowed)
			(pads allowed)
			(copperpour allowed)
			(footprints allowed)
		)
		(placement
			(enabled no)
			(sheetname "")
		)
		(fill
			(thermal_gap 0.5)
			(thermal_bridge_width 0.5)
			(island_removal_mode 0)
		)
		(polygon
			(pts
				(xy 81.209388 -409.042616) (xy 81.209388 -408.038554) (xy 82.60588 -408.038554) (xy 82.60588 -409.042616)
			)
		)
	)
	(zone
		(layer "F.Cu")
		(hatch none 0.5)
		(connect_pads
			(clearance 0)
		)
		(min_thickness 0.25)
		(keepout
			(tracks allowed)
			(vias allowed)
			(pads allowed)
			(copperpour allowed)
			(footprints allowed)
		)
		(placement
			(enabled no)
			(sheetname "")
		)
		(fill
			(thermal_gap 0.5)
			(thermal_bridge_width 0.5)
			(island_removal_mode 0)
		)
		(polygon
			(pts
				(xy 58.13044 -261.677912) (xy 58.13044 -261.347712) (xy 60.67044 -261.347712) (xy 60.67044 -261.677912)
			)
		)
	)
	(zone
		(layer "F.Cu")
		(hatch none 0.5)
		(connect_pads
			(clearance 0)
		)
		(min_thickness 0.25)
		(keepout
			(tracks allowed)
			(vias allowed)
			(pads allowed)
			(copperpour allowed)
			(footprints not_allowed)
		)
		(placement
			(enabled no)
			(sheetname "")
		)
		(fill
			(thermal_gap 0.5)
			(thermal_bridge_width 0.5)
			(island_removal_mode 0)
		)
		(polygon
			(pts
				(arc
					(start 176.186084 -351.825052)
					(mid 173.086014 -354.925122)
					(end 169.985944 -351.825052)
				)
				(arc
					(start 169.985944 -351.825052)
					(mid 173.086014 -348.724982)
					(end 176.186084 -351.825052)
				)
			)
		)
	)
	(zone
		(layer "F.Cu")
		(hatch none 0.5)
		(connect_pads
			(clearance 0)
		)
		(min_thickness 0.25)
		(keepout
			(tracks not_allowed)
			(vias allowed)
			(pads allowed)
			(copperpour not_allowed)
			(footprints allowed)
		)
		(placement
			(enabled no)
			(sheetname "")
		)
		(fill
			(thermal_gap 0.5)
			(thermal_bridge_width 0.5)
			(island_removal_mode 0)
		)
		(polygon
			(pts
				(xy 76.461112 -178.375056) (xy 76.461112 -177.918364) (xy 75.765406 -177.918364) (xy 75.765406 -178.078892)
				(xy 75.206606 -178.078892) (xy 75.206606 -177.672492) (xy 75.765406 -177.672492) (xy 75.765406 -177.892964)
				(xy 76.461112 -177.892964) (xy 76.461112 -177.765964) (xy 76.005436 -177.765964) (xy 76.005436 -177.379376)
				(xy 75.76312 -177.379376) (xy 75.231244 -177.379376) (xy 74.911712 -177.698908) (xy 74.911712 -178.375056)
			)
		)
	)
	(zone
		(layer "F.Cu")
		(hatch none 0.5)
		(connect_pads
			(clearance 0)
		)
		(min_thickness 0.25)
		(keepout
			(tracks allowed)
			(vias allowed)
			(pads allowed)
			(copperpour allowed)
			(footprints not_allowed)
		)
		(placement
			(enabled no)
			(sheetname "")
		)
		(fill
			(thermal_gap 0.5)
			(thermal_bridge_width 0.5)
			(island_removal_mode 0)
		)
		(polygon
			(pts
				(xy 245.124986 -350.813878)
				(arc
					(start 244.470428 -350.813878)
					(mid 236.650022 -360.500025)
					(end 228.829616 -350.813878)
				)
				(xy 227.434902 -350.813878) (xy 227.434902 -370.701824) (xy 245.124986 -370.701824)
			)
		)
	)
	(zone
		(layer "F.Cu")
		(hatch none 0.5)
		(connect_pads
			(clearance 0)
		)
		(min_thickness 0.25)
		(keepout
			(tracks allowed)
			(vias allowed)
			(pads allowed)
			(copperpour allowed)
			(footprints allowed)
		)
		(placement
			(enabled no)
			(sheetname "")
		)
		(fill
			(thermal_gap 0.5)
			(thermal_bridge_width 0.5)
			(island_removal_mode 0)
		)
		(polygon
			(pts
				(xy 163.377626 -288.54273) (xy 163.377626 -288.87293) (xy 165.296596 -288.87293) (xy 165.296596 -288.54273)
			)
		)
	)
	(zone
		(layer "F.Cu")
		(hatch none 0.5)
		(connect_pads
			(clearance 0)
		)
		(min_thickness 0.25)
		(keepout
			(tracks allowed)
			(vias allowed)
			(pads allowed)
			(copperpour allowed)
			(footprints not_allowed)
		)
		(placement
			(enabled no)
			(sheetname "")
		)
		(fill
			(thermal_gap 0.5)
			(thermal_bridge_width 0.5)
			(island_removal_mode 0)
		)
		(polygon
			(pts
				(arc
					(start 49.110392 -51.012852)
					(mid 54.484298 -58.950251)
					(end 63.56731 -62.01283)
				)
				(xy 168.283128 -62.01283) (xy 168.283128 -32.01289)
				(arc
					(start 63.56731 -32.01289)
					(mid 54.484365 -35.075557)
					(end 49.110392 -43.012868)
				)
				(xy 40.583104 -43.012868) (xy 40.583104 -51.012852)
			)
		)
	)
	(zone
		(layer "F.Cu")
		(hatch none 0.5)
		(connect_pads
			(clearance 0)
		)
		(min_thickness 0.25)
		(keepout
			(tracks allowed)
			(vias allowed)
			(pads allowed)
			(copperpour allowed)
			(footprints allowed)
		)
		(placement
			(enabled no)
			(sheetname "")
		)
		(fill
			(thermal_gap 0.5)
			(thermal_bridge_width 0.5)
			(island_removal_mode 0)
		)
		(polygon
			(pts
				(xy 414.947354 -333.517748) (xy 414.947354 -332.963774) (xy 415.491676 -332.963774) (xy 415.491676 -333.517748)
			)
		)
	)
	(zone
		(layer "F.Cu")
		(hatch none 0.5)
		(connect_pads
			(clearance 0)
		)
		(min_thickness 0.25)
		(keepout
			(tracks allowed)
			(vias allowed)
			(pads allowed)
			(copperpour allowed)
			(footprints allowed)
		)
		(placement
			(enabled no)
			(sheetname "")
		)
		(fill
			(thermal_gap 0.5)
			(thermal_bridge_width 0.5)
			(island_removal_mode 0)
		)
		(polygon
			(pts
				(xy 411.317694 -316.592458) (xy 411.317694 -316.922658) (xy 413.236664 -316.922658) (xy 413.236664 -316.592458)
			)
		)
	)
	(zone
		(layer "F.Cu")
		(hatch none 0.5)
		(connect_pads
			(clearance 0)
		)
		(min_thickness 0.25)
		(keepout
			(tracks allowed)
			(vias allowed)
			(pads allowed)
			(copperpour allowed)
			(footprints allowed)
		)
		(placement
			(enabled no)
			(sheetname "")
		)
		(fill
			(thermal_gap 0.5)
			(thermal_bridge_width 0.5)
			(island_removal_mode 0)
		)
		(polygon
			(pts
				(xy 168.843452 -379.216412) (xy 169.847514 -379.216412) (xy 169.847514 -380.612904) (xy 168.843452 -380.612904)
			)
		)
	)
	(zone
		(layer "F.Cu")
		(hatch none 0.5)
		(connect_pads
			(clearance 0)
		)
		(min_thickness 0.25)
		(keepout
			(tracks allowed)
			(vias allowed)
			(pads allowed)
			(copperpour allowed)
			(footprints allowed)
		)
		(placement
			(enabled no)
			(sheetname "")
		)
		(fill
			(thermal_gap 0.5)
			(thermal_bridge_width 0.5)
			(island_removal_mode 0)
		)
		(polygon
			(pts
				(xy 259.41274 4.45262) (xy 259.41274 6.2992) (xy 261.50316 6.2992) (xy 261.50316 4.45262)
			)
		)
	)
	(zone
		(layer "F.Cu")
		(hatch none 0.5)
		(connect_pads
			(clearance 0)
		)
		(min_thickness 0.25)
		(keepout
			(tracks not_allowed)
			(vias allowed)
			(pads allowed)
			(copperpour not_allowed)
			(footprints allowed)
		)
		(placement
			(enabled no)
			(sheetname "")
		)
		(fill
			(thermal_gap 0.5)
			(thermal_bridge_width 0.5)
			(island_removal_mode 0)
		)
		(polygon
			(pts
				(arc
					(start 50.062892 -74.76109)
					(mid 45.062902 -79.76108)
					(end 40.062912 -74.76109)
				)
				(arc
					(start 40.062912 -66.061082)
					(mid 45.062902 -61.061092)
					(end 50.062892 -66.061082)
				)
			)
		)
	)
	(zone
		(layer "F.Cu")
		(hatch none 0.5)
		(connect_pads
			(clearance 0)
		)
		(min_thickness 0.25)
		(keepout
			(tracks allowed)
			(vias allowed)
			(pads allowed)
			(copperpour allowed)
			(footprints allowed)
		)
		(placement
			(enabled no)
			(sheetname "")
		)
		(fill
			(thermal_gap 0.5)
			(thermal_bridge_width 0.5)
			(island_removal_mode 0)
		)
		(polygon
			(pts
				(xy 411.317694 -253.177802) (xy 411.317694 -252.847602) (xy 413.236664 -252.847602) (xy 413.236664 -253.177802)
			)
		)
	)
	(zone
		(layer "F.Cu")
		(hatch none 0.5)
		(connect_pads
			(clearance 0)
		)
		(min_thickness 0.25)
		(keepout
			(tracks allowed)
			(vias allowed)
			(pads allowed)
			(copperpour allowed)
			(footprints allowed)
		)
		(placement
			(enabled no)
			(sheetname "")
		)
		(fill
			(thermal_gap 0.5)
			(thermal_bridge_width 0.5)
			(island_removal_mode 0)
		)
		(polygon
			(pts
				(xy 430.90846 -103.999284) (xy 430.90846 -103.712772) (xy 431.199798 -103.712772) (xy 431.199798 -103.999284)
			)
		)
	)
	(zone
		(layer "F.Cu")
		(hatch none 0.5)
		(connect_pads
			(clearance 0)
		)
		(min_thickness 0.25)
		(keepout
			(tracks allowed)
			(vias allowed)
			(pads allowed)
			(copperpour allowed)
			(footprints allowed)
		)
		(placement
			(enabled no)
			(sheetname "")
		)
		(fill
			(thermal_gap 0.5)
			(thermal_bridge_width 0.5)
			(island_removal_mode 0)
		)
		(polygon
			(pts
				(xy 136.05637 -409.042616) (xy 136.05637 -408.038554) (xy 137.452862 -408.038554) (xy 137.452862 -409.042616)
			)
		)
	)
	(zone
		(layer "F.Cu")
		(hatch none 0.5)
		(connect_pads
			(clearance 0)
		)
		(min_thickness 0.25)
		(keepout
			(tracks not_allowed)
			(vias allowed)
			(pads allowed)
			(copperpour not_allowed)
			(footprints allowed)
		)
		(placement
			(enabled no)
			(sheetname "")
		)
		(fill
			(thermal_gap 0.5)
			(thermal_bridge_width 0.5)
			(island_removal_mode 0)
		)
		(polygon
			(pts
				(arc
					(start 11.970258 -114.706908)
					(mid 11.302238 -114.706908)
					(end 11.970258 -114.706908)
				)
			)
		)
	)
	(zone
		(layer "F.Cu")
		(hatch none 0.5)
		(connect_pads
			(clearance 0)
		)
		(min_thickness 0.25)
		(keepout
			(tracks allowed)
			(vias allowed)
			(pads allowed)
			(copperpour allowed)
			(footprints allowed)
		)
		(placement
			(enabled no)
			(sheetname "")
		)
		(fill
			(thermal_gap 0.5)
			(thermal_bridge_width 0.5)
			(island_removal_mode 0)
		)
		(polygon
			(pts
				(xy 115.037362 -169.86885) (xy 113.233962 -169.86885) (xy 113.233962 -171.41825) (xy 115.037362 -171.41825)
			)
		)
	)
	(zone
		(layer "F.Cu")
		(hatch none 0.5)
		(connect_pads
			(clearance 0)
		)
		(min_thickness 0.25)
		(keepout
			(tracks allowed)
			(vias allowed)
			(pads allowed)
			(copperpour allowed)
			(footprints allowed)
		)
		(placement
			(enabled no)
			(sheetname "")
		)
		(fill
			(thermal_gap 0.5)
			(thermal_bridge_width 0.5)
			(island_removal_mode 0)
		)
		(polygon
			(pts
				(xy 180.0352 -48.377348) (xy 180.0352 -46.853348) (xy 181.0258 -46.853348) (xy 181.0258 -48.377348)
			)
		)
	)
	(zone
		(layer "F.Cu")
		(hatch none 0.5)
		(connect_pads
			(clearance 0)
		)
		(min_thickness 0.25)
		(keepout
			(tracks allowed)
			(vias allowed)
			(pads allowed)
			(copperpour allowed)
			(footprints allowed)
		)
		(placement
			(enabled no)
			(sheetname "")
		)
		(fill
			(thermal_gap 0.5)
			(thermal_bridge_width 0.5)
			(island_removal_mode 0)
		)
		(polygon
			(pts
				(xy 102.75824 -129.23012) (xy 102.75824 -127.8001) (xy 103.51516 -127.8001) (xy 103.51516 -129.23012)
			)
		)
	)
	(zone
		(layer "F.Cu")
		(hatch none 0.5)
		(connect_pads
			(clearance 0)
		)
		(min_thickness 0.25)
		(keepout
			(tracks allowed)
			(vias allowed)
			(pads allowed)
			(copperpour allowed)
			(footprints allowed)
		)
		(placement
			(enabled no)
			(sheetname "")
		)
		(fill
			(thermal_gap 0.5)
			(thermal_bridge_width 0.5)
			(island_removal_mode 0)
		)
		(polygon
			(pts
				(xy 167.889428 -371.097302) (xy 167.889428 -370.09324) (xy 169.28592 -370.09324) (xy 169.28592 -371.097302)
			)
		)
	)
	(zone
		(layer "F.Cu")
		(hatch none 0.5)
		(connect_pads
			(clearance 0)
		)
		(min_thickness 0.25)
		(keepout
			(tracks allowed)
			(vias allowed)
			(pads allowed)
			(copperpour allowed)
			(footprints not_allowed)
		)
		(placement
			(enabled no)
			(sheetname "")
		)
		(fill
			(thermal_gap 0.5)
			(thermal_bridge_width 0.5)
			(island_removal_mode 0)
		)
		(polygon
			(pts
				(xy 34.649918 -57.53989) (xy 34.649918 -46.459902) (xy 23.150068 -46.459902) (xy 23.150068 -57.53989)
			)
		)
	)
	(zone
		(layer "F.Cu")
		(hatch none 0.5)
		(connect_pads
			(clearance 0)
		)
		(min_thickness 0.25)
		(keepout
			(tracks allowed)
			(vias allowed)
			(pads allowed)
			(copperpour allowed)
			(footprints allowed)
		)
		(placement
			(enabled no)
			(sheetname "")
		)
		(fill
			(thermal_gap 0.5)
			(thermal_bridge_width 0.5)
			(island_removal_mode 0)
		)
		(polygon
			(pts
				(xy 136.77646 -151.525224) (xy 136.77646 -150.961598) (xy 137.292334 -150.961598) (xy 137.292334 -151.525224)
			)
		)
	)
	(zone
		(layer "F.Cu")
		(hatch none 0.5)
		(connect_pads
			(clearance 0)
		)
		(min_thickness 0.25)
		(keepout
			(tracks allowed)
			(vias allowed)
			(pads allowed)
			(copperpour allowed)
			(footprints allowed)
		)
		(placement
			(enabled no)
			(sheetname "")
		)
		(fill
			(thermal_gap 0.5)
			(thermal_bridge_width 0.5)
			(island_removal_mode 0)
		)
		(polygon
			(pts
				(xy 130.589528 -53.685948) (xy 129.370328 -53.685948) (xy 129.370328 -52.582572) (xy 130.589528 -52.582572)
			)
		)
	)
	(zone
		(layer "F.Cu")
		(hatch none 0.5)
		(connect_pads
			(clearance 0)
		)
		(min_thickness 0.25)
		(keepout
			(tracks allowed)
			(vias allowed)
			(pads allowed)
			(copperpour allowed)
			(footprints not_allowed)
		)
		(placement
			(enabled no)
			(sheetname "")
		)
		(fill
			(thermal_gap 0.5)
			(thermal_bridge_width 0.5)
			(island_removal_mode 0)
		)
		(polygon
			(pts
				(xy 350.499934 -440.989974) (xy 350.499934 -417.889944) (xy 310.20004 -417.889944) (xy 310.20004 -440.989974)
				(xy 313.30011 -440.989974) (xy 313.30011 -420.990014) (xy 347.400118 -420.990014) (xy 347.400118 -440.989974)
			)
		)
	)
	(zone
		(layer "F.Cu")
		(hatch none 0.5)
		(connect_pads
			(clearance 0)
		)
		(min_thickness 0.25)
		(keepout
			(tracks allowed)
			(vias allowed)
			(pads allowed)
			(copperpour allowed)
			(footprints allowed)
		)
		(placement
			(enabled no)
			(sheetname "")
		)
		(fill
			(thermal_gap 0.5)
			(thermal_bridge_width 0.5)
			(island_removal_mode 0)
		)
		(polygon
			(pts
				(xy 411.317694 -242.97767) (xy 411.317694 -242.64747) (xy 413.236664 -242.64747) (xy 413.236664 -242.97767)
			)
		)
	)
	(zone
		(layer "F.Cu")
		(hatch none 0.5)
		(connect_pads
			(clearance 0)
		)
		(min_thickness 0.25)
		(keepout
			(tracks not_allowed)
			(vias allowed)
			(pads allowed)
			(copperpour not_allowed)
			(footprints allowed)
		)
		(placement
			(enabled no)
			(sheetname "")
		)
		(fill
			(thermal_gap 0.5)
			(thermal_bridge_width 0.5)
			(island_removal_mode 0)
		)
		(polygon
			(pts
				(arc
					(start 32.820102 -376.489976)
					(mid 35.070034 -374.240044)
					(end 37.319966 -376.489976)
				)
				(arc
					(start 37.319966 -376.489976)
					(mid 35.070034 -378.739908)
					(end 32.820102 -376.489976)
				)
			)
		)
	)
	(zone
		(layer "F.Cu")
		(hatch none 0.5)
		(connect_pads
			(clearance 0)
		)
		(min_thickness 0.25)
		(keepout
			(tracks not_allowed)
			(vias allowed)
			(pads allowed)
			(copperpour not_allowed)
			(footprints allowed)
		)
		(placement
			(enabled no)
			(sheetname "")
		)
		(fill
			(thermal_gap 0.5)
			(thermal_bridge_width 0.5)
			(island_removal_mode 0)
		)
		(polygon
			(pts
				(xy 117.730016 -171.223432) (xy 117.730016 -170.26255) (xy 117.4877 -170.26255) (xy 117.4877 -171.223432)
			)
		)
	)
	(zone
		(layer "F.Cu")
		(hatch none 0.5)
		(connect_pads
			(clearance 0)
		)
		(min_thickness 0.25)
		(keepout
			(tracks allowed)
			(vias allowed)
			(pads allowed)
			(copperpour allowed)
			(footprints allowed)
		)
		(placement
			(enabled no)
			(sheetname "")
		)
		(fill
			(thermal_gap 0.5)
			(thermal_bridge_width 0.5)
			(island_removal_mode 0)
		)
		(polygon
			(pts
				(xy 193.698114 -351.826068) (xy 191.894714 -351.826068) (xy 191.894714 -353.375468) (xy 193.698114 -353.375468)
			)
		)
	)
	(zone
		(layer "F.Cu")
		(hatch none 0.5)
		(connect_pads
			(clearance 0)
		)
		(min_thickness 0.25)
		(keepout
			(tracks allowed)
			(vias allowed)
			(pads allowed)
			(copperpour allowed)
			(footprints allowed)
		)
		(placement
			(enabled no)
			(sheetname "")
		)
		(fill
			(thermal_gap 0.5)
			(thermal_bridge_width 0.5)
			(island_removal_mode 0)
		)
		(polygon
			(pts
				(xy 411.317694 -307.242464) (xy 411.317694 -307.572664) (xy 413.236664 -307.572664) (xy 413.236664 -307.242464)
			)
		)
	)
	(zone
		(layer "F.Cu")
		(hatch none 0.5)
		(connect_pads
			(clearance 0)
		)
		(min_thickness 0.25)
		(keepout
			(tracks allowed)
			(vias allowed)
			(pads allowed)
			(copperpour allowed)
			(footprints allowed)
		)
		(placement
			(enabled no)
			(sheetname "")
		)
		(fill
			(thermal_gap 0.5)
			(thermal_bridge_width 0.5)
			(island_removal_mode 0)
		)
		(polygon
			(pts
				(xy 263.37514 -194.76466) (xy 263.37514 -190.48984) (xy 310.12384 -190.48984) (xy 310.12384 -194.76466)
			)
		)
	)
	(zone
		(layer "F.Cu")
		(hatch none 0.5)
		(connect_pads
			(clearance 0)
		)
		(min_thickness 0.25)
		(keepout
			(tracks allowed)
			(vias allowed)
			(pads allowed)
			(copperpour allowed)
			(footprints not_allowed)
		)
		(placement
			(enabled no)
			(sheetname "")
		)
		(fill
			(thermal_gap 0.5)
			(thermal_bridge_width 0.5)
			(island_removal_mode 0)
		)
		(polygon
			(pts
				(xy 24.099012 -183.50992) (xy 24.099012 -327.609962) (xy 30.298898 -327.609962) (xy 30.298898 -183.50992)
			)
		)
	)
	(zone
		(layer "F.Cu")
		(hatch none 0.5)
		(connect_pads
			(clearance 0)
		)
		(min_thickness 0.25)
		(keepout
			(tracks allowed)
			(vias allowed)
			(pads allowed)
			(copperpour allowed)
			(footprints allowed)
		)
		(placement
			(enabled no)
			(sheetname "")
		)
		(fill
			(thermal_gap 0.5)
			(thermal_bridge_width 0.5)
			(island_removal_mode 0)
		)
		(polygon
			(pts
				(xy 392.315446 -384.194812) (xy 393.319508 -384.194812) (xy 393.319508 -385.591304) (xy 392.315446 -385.591304)
			)
		)
	)
	(zone
		(layer "F.Cu")
		(hatch none 0.5)
		(connect_pads
			(clearance 0)
		)
		(min_thickness 0.25)
		(keepout
			(tracks allowed)
			(vias allowed)
			(pads allowed)
			(copperpour allowed)
			(footprints allowed)
		)
		(placement
			(enabled no)
			(sheetname "")
		)
		(fill
			(thermal_gap 0.5)
			(thermal_bridge_width 0.5)
			(island_removal_mode 0)
		)
		(polygon
			(pts
				(xy 163.377626 -291.42817) (xy 163.377626 -291.09797) (xy 165.296596 -291.09797) (xy 165.296596 -291.42817)
			)
		)
	)
	(zone
		(layer "F.Cu")
		(hatch none 0.5)
		(connect_pads
			(clearance 0)
		)
		(min_thickness 0.25)
		(keepout
			(tracks allowed)
			(vias allowed)
			(pads allowed)
			(copperpour allowed)
			(footprints allowed)
		)
		(placement
			(enabled no)
			(sheetname "")
		)
		(fill
			(thermal_gap 0.5)
			(thermal_bridge_width 0.5)
			(island_removal_mode 0)
		)
		(polygon
			(pts
				(xy 98.425762 -180.63845) (xy 96.622362 -180.63845) (xy 96.622362 -182.18785) (xy 98.425762 -182.18785)
			)
		)
	)
	(zone
		(layer "F.Cu")
		(hatch none 0.5)
		(connect_pads
			(clearance 0)
		)
		(min_thickness 0.25)
		(keepout
			(tracks allowed)
			(vias allowed)
			(pads allowed)
			(copperpour allowed)
			(footprints not_allowed)
		)
		(placement
			(enabled no)
			(sheetname "")
		)
		(fill
			(thermal_gap 0.5)
			(thermal_bridge_width 0.5)
			(island_removal_mode 0)
		)
		(polygon
			(pts
				(arc
					(start 450.54012 -40.420036)
					(mid 447.44005 -43.520106)
					(end 444.33998 -40.420036)
				)
				(arc
					(start 444.33998 -40.420036)
					(mid 447.44005 -37.319966)
					(end 450.54012 -40.420036)
				)
			)
		)
	)
	(zone
		(layer "F.Cu")
		(hatch none 0.5)
		(connect_pads
			(clearance 0)
		)
		(min_thickness 0.25)
		(keepout
			(tracks allowed)
			(vias allowed)
			(pads allowed)
			(copperpour allowed)
			(footprints allowed)
		)
		(placement
			(enabled no)
			(sheetname "")
		)
		(fill
			(thermal_gap 0.5)
			(thermal_bridge_width 0.5)
			(island_removal_mode 0)
		)
		(polygon
			(pts
				(xy 340.27237 -417.424616) (xy 340.27237 -416.420554) (xy 341.668862 -416.420554) (xy 341.668862 -417.424616)
			)
		)
	)
	(zone
		(layer "F.Cu")
		(hatch none 0.5)
		(connect_pads
			(clearance 0)
		)
		(min_thickness 0.25)
		(keepout
			(tracks allowed)
			(vias allowed)
			(pads allowed)
			(copperpour allowed)
			(footprints allowed)
		)
		(placement
			(enabled no)
			(sheetname "")
		)
		(fill
			(thermal_gap 0.5)
			(thermal_bridge_width 0.5)
			(island_removal_mode 0)
		)
		(polygon
			(pts
				(xy 386.256022 -381.943102) (xy 386.256022 -380.93904) (xy 387.652514 -380.93904) (xy 387.652514 -381.943102)
			)
		)
	)
	(zone
		(layer "F.Cu")
		(hatch none 0.5)
		(connect_pads
			(clearance 0)
		)
		(min_thickness 0.25)
		(keepout
			(tracks not_allowed)
			(vias allowed)
			(pads allowed)
			(copperpour not_allowed)
			(footprints allowed)
		)
		(placement
			(enabled no)
			(sheetname "")
		)
		(fill
			(thermal_gap 0.5)
			(thermal_bridge_width 0.5)
			(island_removal_mode 0)
		)
		(polygon
			(pts
				(arc
					(start 105.500424 -435.600094)
					(mid 100.500434 -440.600084)
					(end 95.500444 -435.600094)
				)
				(arc
					(start 95.500444 -435.600094)
					(mid 100.500434 -430.600104)
					(end 105.500424 -435.600094)
				)
			)
		)
	)
	(zone
		(layer "F.Cu")
		(hatch none 0.5)
		(connect_pads
			(clearance 0)
		)
		(min_thickness 0.25)
		(keepout
			(tracks not_allowed)
			(vias allowed)
			(pads allowed)
			(copperpour not_allowed)
			(footprints allowed)
		)
		(placement
			(enabled no)
			(sheetname "")
		)
		(fill
			(thermal_gap 0.5)
			(thermal_bridge_width 0.5)
			(island_removal_mode 0)
		)
		(polygon
			(pts
				(xy 34.562034 -87.286084) (xy 55.557928 -87.286084) (xy 55.557928 -59.967114) (xy 34.562034 -59.965082)
			)
		)
	)
	(zone
		(layer "F.Cu")
		(hatch none 0.5)
		(connect_pads
			(clearance 0)
		)
		(min_thickness 0.25)
		(keepout
			(tracks allowed)
			(vias allowed)
			(pads allowed)
			(copperpour allowed)
			(footprints allowed)
		)
		(placement
			(enabled no)
			(sheetname "")
		)
		(fill
			(thermal_gap 0.5)
			(thermal_bridge_width 0.5)
			(island_removal_mode 0)
		)
		(polygon
			(pts
				(xy 163.377626 -301.628302) (xy 163.377626 -301.298102) (xy 165.296596 -301.298102) (xy 165.296596 -301.628302)
			)
		)
	)
	(zone
		(layer "F.Cu")
		(hatch none 0.5)
		(connect_pads
			(clearance 0)
		)
		(min_thickness 0.25)
		(keepout
			(tracks allowed)
			(vias allowed)
			(pads allowed)
			(copperpour allowed)
			(footprints allowed)
		)
		(placement
			(enabled no)
			(sheetname "")
		)
		(fill
			(thermal_gap 0.5)
			(thermal_bridge_width 0.5)
			(island_removal_mode 0)
		)
		(polygon
			(pts
				(xy 87.175086 -376.024902) (xy 87.175086 -375.02084) (xy 88.571578 -375.02084) (xy 88.571578 -376.024902)
			)
		)
	)
	(zone
		(layer "F.Cu")
		(hatch none 0.5)
		(connect_pads
			(clearance 0)
		)
		(min_thickness 0.25)
		(keepout
			(tracks allowed)
			(vias allowed)
			(pads allowed)
			(copperpour allowed)
			(footprints allowed)
		)
		(placement
			(enabled no)
			(sheetname "")
		)
		(fill
			(thermal_gap 0.5)
			(thermal_bridge_width 0.5)
			(island_removal_mode 0)
		)
		(polygon
			(pts
				(xy 314.05068 -379.479302) (xy 314.05068 -378.47524) (xy 315.447172 -378.47524) (xy 315.447172 -379.479302)
			)
		)
	)
	(zone
		(layer "F.Cu")
		(hatch none 0.5)
		(connect_pads
			(clearance 0)
		)
		(min_thickness 0.25)
		(keepout
			(tracks allowed)
			(vias allowed)
			(pads allowed)
			(copperpour allowed)
			(footprints allowed)
		)
		(placement
			(enabled no)
			(sheetname "")
		)
		(fill
			(thermal_gap 0.5)
			(thermal_bridge_width 0.5)
			(island_removal_mode 0)
		)
		(polygon
			(pts
				(xy 391.361422 -379.479302) (xy 391.361422 -378.47524) (xy 392.757914 -378.47524) (xy 392.757914 -379.479302)
			)
		)
	)
	(zone
		(layer "F.Cu")
		(hatch none 0.5)
		(connect_pads
			(clearance 0)
		)
		(min_thickness 0.25)
		(keepout
			(tracks allowed)
			(vias allowed)
			(pads allowed)
			(copperpour allowed)
			(footprints allowed)
		)
		(placement
			(enabled no)
			(sheetname "")
		)
		(fill
			(thermal_gap 0.5)
			(thermal_bridge_width 0.5)
			(island_removal_mode 0)
		)
		(polygon
			(pts
				(xy 60.725812 -300.44263) (xy 60.725812 -300.77283) (xy 58.185812 -300.77283) (xy 58.185812 -300.44263)
			)
		)
	)
	(zone
		(layer "F.Cu")
		(hatch none 0.5)
		(connect_pads
			(clearance 0)
		)
		(min_thickness 0.25)
		(keepout
			(tracks allowed)
			(vias allowed)
			(pads allowed)
			(copperpour allowed)
			(footprints allowed)
		)
		(placement
			(enabled no)
			(sheetname "")
		)
		(fill
			(thermal_gap 0.5)
			(thermal_bridge_width 0.5)
			(island_removal_mode 0)
		)
		(polygon
			(pts
				(xy 136.315704 -379.216412) (xy 137.319766 -379.216412) (xy 137.319766 -380.612904) (xy 136.315704 -380.612904)
			)
		)
	)
	(zone
		(layer "F.Cu")
		(hatch none 0.5)
		(connect_pads
			(clearance 0)
		)
		(min_thickness 0.25)
		(keepout
			(tracks allowed)
			(vias allowed)
			(pads allowed)
			(copperpour allowed)
			(footprints allowed)
		)
		(placement
			(enabled no)
			(sheetname "")
		)
		(fill
			(thermal_gap 0.5)
			(thermal_bridge_width 0.5)
			(island_removal_mode 0)
		)
		(polygon
			(pts
				(xy 411.789118 -164.107368) (xy 418.139118 -164.107368) (xy 418.774118 -163.472368) (xy 418.774118 -158.900368)
				(xy 418.139118 -158.265368) (xy 412.170118 -158.265368) (xy 411.662118 -158.773368) (xy 411.662118 -163.980368)
			)
		)
	)
	(zone
		(layer "F.Cu")
		(hatch none 0.5)
		(connect_pads
			(clearance 0)
		)
		(min_thickness 0.25)
		(keepout
			(tracks allowed)
			(vias allowed)
			(pads allowed)
			(copperpour allowed)
			(footprints not_allowed)
		)
		(placement
			(enabled no)
			(sheetname "")
		)
		(fill
			(thermal_gap 0.5)
			(thermal_bridge_width 0.5)
			(island_removal_mode 0)
		)
		(polygon
			(pts
				(xy 227.772976 -162.572954) (xy 242.384072 -162.572954) (xy 242.384072 -139.195048) (xy 227.772976 -139.195048)
			)
		)
	)
	(zone
		(layer "F.Cu")
		(hatch none 0.5)
		(connect_pads
			(clearance 0)
		)
		(min_thickness 0.25)
		(keepout
			(tracks allowed)
			(vias allowed)
			(pads allowed)
			(copperpour allowed)
			(footprints not_allowed)
		)
		(placement
			(enabled no)
			(sheetname "")
		)
		(fill
			(thermal_gap 0.5)
			(thermal_bridge_width 0.5)
			(island_removal_mode 0)
		)
		(polygon
			(pts
				(arc
					(start 157.530038 -258.890008)
					(mid 154.030172 -262.389874)
					(end 150.530052 -258.890008)
				)
				(arc
					(start 150.530052 -258.890008)
					(mid 154.030172 -255.389888)
					(end 157.530038 -258.890008)
				)
			)
		)
	)
	(zone
		(layer "F.Cu")
		(hatch none 0.5)
		(connect_pads
			(clearance 0)
		)
		(min_thickness 0.25)
		(keepout
			(tracks allowed)
			(vias allowed)
			(pads allowed)
			(copperpour allowed)
			(footprints not_allowed)
		)
		(placement
			(enabled no)
			(sheetname "")
		)
		(fill
			(thermal_gap 0.5)
			(thermal_bridge_width 0.5)
			(island_removal_mode 0)
		)
		(polygon
			(pts
				(xy 69.071236 -410.29001) (xy 35.571176 -410.29001) (xy 35.571176 -399.290032) (xy 39.285164 -399.290032)
				(xy 39.285164 -394.759942) (xy 39.880032 -394.759942) (xy 39.880032 -398.560036) (xy 44.669964 -398.560036)
				(xy 44.669964 -393.530074) (xy 39.990014 -393.530074) (xy 39.990014 -385.160012) (xy 39.285164 -385.160012)
				(xy 39.285164 -381.989838) (xy 29.471112 -381.989838) (xy 29.471112 -370.98986) (xy 39.285164 -370.98986)
				(xy 39.285164 -367.789968) (xy 173.284896 -367.789968) (xy 173.284896 -370.98986) (xy 183.498744 -370.98986)
				(xy 183.498744 -381.989838) (xy 173.284896 -381.989838) (xy 173.284896 -399.290032) (xy 176.998884 -399.290032)
				(xy 176.998884 -410.29001) (xy 140.550392 -410.29001) (xy 140.550392 -406.78989) (xy 69.071236 -406.78989)
			)
		)
	)
	(zone
		(layer "F.Cu")
		(hatch none 0.5)
		(connect_pads
			(clearance 0)
		)
		(min_thickness 0.25)
		(keepout
			(tracks allowed)
			(vias allowed)
			(pads allowed)
			(copperpour allowed)
			(footprints allowed)
		)
		(placement
			(enabled no)
			(sheetname "")
		)
		(fill
			(thermal_gap 0.5)
			(thermal_bridge_width 0.5)
			(island_removal_mode 0)
		)
		(polygon
			(pts
				(xy 11.662664 -136.45896) (xy 11.662664 -135.50392) (xy 13.428218 -135.50392) (xy 13.428218 -136.45896)
			)
		)
	)
	(zone
		(layer "F.Cu")
		(hatch none 0.5)
		(connect_pads
			(clearance 0)
		)
		(min_thickness 0.25)
		(keepout
			(tracks allowed)
			(vias allowed)
			(pads allowed)
			(copperpour allowed)
			(footprints allowed)
		)
		(placement
			(enabled no)
			(sheetname "")
		)
		(fill
			(thermal_gap 0.5)
			(thermal_bridge_width 0.5)
			(island_removal_mode 0)
		)
		(polygon
			(pts
				(xy 306.070508 -198.77786) (xy 306.070508 -198.44766) (xy 308.610508 -198.44766) (xy 308.610508 -198.77786)
			)
		)
	)
	(zone
		(layer "F.Cu")
		(hatch none 0.5)
		(connect_pads
			(clearance 0)
		)
		(min_thickness 0.25)
		(keepout
			(tracks allowed)
			(vias allowed)
			(pads allowed)
			(copperpour allowed)
			(footprints not_allowed)
		)
		(placement
			(enabled no)
			(sheetname "")
		)
		(fill
			(thermal_gap 0.5)
			(thermal_bridge_width 0.5)
			(island_removal_mode 0)
		)
		(polygon
			(pts
				(xy 108.915962 -344.914982) (xy 117.606064 -344.914982) (xy 117.606064 -336.12455) (xy 108.915962 -336.12455)
			)
		)
	)
	(zone
		(layer "F.Cu")
		(hatch none 0.5)
		(connect_pads
			(clearance 0)
		)
		(min_thickness 0.25)
		(keepout
			(tracks allowed)
			(vias allowed)
			(pads allowed)
			(copperpour allowed)
			(footprints allowed)
		)
		(placement
			(enabled no)
			(sheetname "")
		)
		(fill
			(thermal_gap 0.5)
			(thermal_bridge_width 0.5)
			(island_removal_mode 0)
		)
		(polygon
			(pts
				(xy 411.562042 -229.377748) (xy 411.562042 -229.047548) (xy 413.236664 -229.047548) (xy 413.236664 -229.377748)
			)
		)
	)
	(zone
		(layer "F.Cu")
		(hatch none 0.5)
		(connect_pads
			(clearance 0)
		)
		(min_thickness 0.25)
		(keepout
			(tracks allowed)
			(vias allowed)
			(pads allowed)
			(copperpour allowed)
			(footprints not_allowed)
		)
		(placement
			(enabled no)
			(sheetname "")
		)
		(fill
			(thermal_gap 0.5)
			(thermal_bridge_width 0.5)
			(island_removal_mode 0)
		)
		(polygon
			(pts
				(arc
					(start 172.900086 -160.50006)
					(mid 167.900096 -165.50005)
					(end 162.900106 -160.50006)
				)
				(arc
					(start 162.900106 -160.50006)
					(mid 167.900096 -155.50007)
					(end 172.900086 -160.50006)
				)
			)
		)
	)
	(zone
		(layer "F.Cu")
		(hatch none 0.5)
		(connect_pads
			(clearance 0)
		)
		(min_thickness 0.25)
		(keepout
			(tracks allowed)
			(vias allowed)
			(pads allowed)
			(copperpour allowed)
			(footprints not_allowed)
		)
		(placement
			(enabled no)
			(sheetname "")
		)
		(fill
			(thermal_gap 0.5)
			(thermal_bridge_width 0.5)
			(island_removal_mode 0)
		)
		(polygon
			(pts
				(arc
					(start 15.340076 -160.50006)
					(mid 10.340086 -165.50005)
					(end 5.340096 -160.50006)
				)
				(arc
					(start 5.340096 -160.50006)
					(mid 10.340086 -155.50007)
					(end 15.340076 -160.50006)
				)
			)
		)
	)
	(zone
		(layer "F.Cu")
		(hatch none 0.5)
		(connect_pads
			(clearance 0)
		)
		(min_thickness 0.25)
		(keepout
			(tracks allowed)
			(vias allowed)
			(pads allowed)
			(copperpour allowed)
			(footprints allowed)
		)
		(placement
			(enabled no)
			(sheetname "")
		)
		(fill
			(thermal_gap 0.5)
			(thermal_bridge_width 0.5)
			(island_removal_mode 0)
		)
		(polygon
			(pts
				(xy 395.859254 -224.740978) (xy 392.597386 -224.740978) (xy 391.439654 -225.89871) (xy 391.439654 -259.78231)
				(xy 392.735054 -261.07771) (xy 392.735054 -261.23011) (xy 392.557254 -261.40791) (xy 392.404854 -261.40791)
				(xy 391.744454 -262.06831) (xy 391.744454 -292.19271) (xy 393.090654 -293.53891) (xy 395.572234 -293.53891)
				(xy 395.859254 -293.25189)
			)
		)
	)
	(zone
		(layer "F.Cu")
		(hatch none 0.5)
		(connect_pads
			(clearance 0)
		)
		(min_thickness 0.25)
		(keepout
			(tracks allowed)
			(vias allowed)
			(pads allowed)
			(copperpour allowed)
			(footprints not_allowed)
		)
		(placement
			(enabled no)
			(sheetname "")
		)
		(fill
			(thermal_gap 0.5)
			(thermal_bridge_width 0.5)
			(island_removal_mode 0)
		)
		(polygon
			(pts
				(xy 231.199944 -38.34511) (xy 231.199944 -62.989968) (xy 237.400084 -62.989968) (xy 237.400084 -38.34511)
			)
		)
	)
	(zone
		(layer "F.Cu")
		(hatch none 0.5)
		(connect_pads
			(clearance 0)
		)
		(min_thickness 0.25)
		(keepout
			(tracks allowed)
			(vias allowed)
			(pads allowed)
			(copperpour allowed)
			(footprints allowed)
		)
		(placement
			(enabled no)
			(sheetname "")
		)
		(fill
			(thermal_gap 0.5)
			(thermal_bridge_width 0.5)
			(island_removal_mode 0)
		)
		(polygon
			(pts
				(xy 423.780712 -13.208508) (xy 423.780712 -10.3378) (xy 433.876196 -10.3378) (xy 433.876196 -13.208508)
			)
		)
	)
	(zone
		(layer "F.Cu")
		(hatch none 0.5)
		(connect_pads
			(clearance 0)
		)
		(min_thickness 0.25)
		(keepout
			(tracks allowed)
			(vias allowed)
			(pads allowed)
			(copperpour allowed)
			(footprints not_allowed)
		)
		(placement
			(enabled no)
			(sheetname "")
		)
		(fill
			(thermal_gap 0.5)
			(thermal_bridge_width 0.5)
			(island_removal_mode 0)
		)
		(polygon
			(pts
				(arc
					(start 387.67004 -212.989922)
					(mid 390.470136 -210.189826)
					(end 393.269978 -212.989922)
				)
				(arc
					(start 393.269978 -212.989922)
					(mid 390.470136 -215.789764)
					(end 387.67004 -212.989922)
				)
			)
		)
	)
	(zone
		(layer "F.Cu")
		(hatch none 0.5)
		(connect_pads
			(clearance 0)
		)
		(min_thickness 0.25)
		(keepout
			(tracks allowed)
			(vias allowed)
			(pads allowed)
			(copperpour allowed)
			(footprints not_allowed)
		)
		(placement
			(enabled no)
			(sheetname "")
		)
		(fill
			(thermal_gap 0.5)
			(thermal_bridge_width 0.5)
			(island_removal_mode 0)
		)
		(polygon
			(pts
				(xy 111.716058 -161.275014) (xy 102.20706 -161.275014) (xy 102.20706 -170.835066) (xy 111.716058 -170.835066)
			)
		)
	)
	(zone
		(layer "F.Cu")
		(hatch none 0.5)
		(connect_pads
			(clearance 0)
		)
		(min_thickness 0.25)
		(keepout
			(tracks allowed)
			(vias allowed)
			(pads allowed)
			(copperpour allowed)
			(footprints allowed)
		)
		(placement
			(enabled no)
			(sheetname "")
		)
		(fill
			(thermal_gap 0.5)
			(thermal_bridge_width 0.5)
			(island_removal_mode 0)
		)
		(polygon
			(pts
				(xy 152.521666 -196.54012) (xy 152.521666 -196.03212) (xy 152.717246 -196.03212) (xy 152.717246 -196.54012)
			)
		)
	)
	(zone
		(layer "F.Cu")
		(hatch none 0.5)
		(connect_pads
			(clearance 0)
		)
		(min_thickness 0.25)
		(keepout
			(tracks allowed)
			(vias allowed)
			(pads allowed)
			(copperpour allowed)
			(footprints not_allowed)
		)
		(placement
			(enabled no)
			(sheetname "")
		)
		(fill
			(thermal_gap 0.5)
			(thermal_bridge_width 0.5)
			(island_removal_mode 0)
		)
		(polygon
			(pts
				(arc
					(start 431.25009 -384.869944)
					(mid 433.500022 -382.620012)
					(end 435.749954 -384.869944)
				)
				(arc
					(start 435.749954 -384.869944)
					(mid 433.500022 -387.119876)
					(end 431.25009 -384.869944)
				)
			)
		)
	)
	(zone
		(layer "F.Cu")
		(hatch none 0.5)
		(connect_pads
			(clearance 0)
		)
		(min_thickness 0.25)
		(keepout
			(tracks allowed)
			(vias allowed)
			(pads allowed)
			(copperpour allowed)
			(footprints not_allowed)
		)
		(placement
			(enabled no)
			(sheetname "")
		)
		(fill
			(thermal_gap 0.5)
			(thermal_bridge_width 0.5)
			(island_removal_mode 0)
		)
		(polygon
			(pts
				(arc
					(start 195.399914 -22.29993)
					(mid 203.399898 -14.299946)
					(end 211.399882 -22.29993)
				)
				(arc
					(start 211.399882 -22.29993)
					(mid 203.399898 -30.299914)
					(end 195.399914 -22.29993)
				)
			)
		)
	)
	(zone
		(layer "F.Cu")
		(hatch none 0.5)
		(connect_pads
			(clearance 0)
		)
		(min_thickness 0.25)
		(keepout
			(tracks allowed)
			(vias allowed)
			(pads allowed)
			(copperpour allowed)
			(footprints not_allowed)
		)
		(placement
			(enabled no)
			(sheetname "")
		)
		(fill
			(thermal_gap 0.5)
			(thermal_bridge_width 0.5)
			(island_removal_mode 0)
		)
		(polygon
			(pts
				(arc
					(start 290.74999 -435.600094)
					(mid 293.550086 -432.799998)
					(end 296.349928 -435.600094)
				)
				(arc
					(start 296.349928 -435.600094)
					(mid 293.550086 -438.399936)
					(end 290.74999 -435.600094)
				)
			)
		)
	)
	(zone
		(layer "F.Cu")
		(hatch none 0.5)
		(connect_pads
			(clearance 0)
		)
		(min_thickness 0.25)
		(keepout
			(tracks allowed)
			(vias allowed)
			(pads allowed)
			(copperpour allowed)
			(footprints not_allowed)
		)
		(placement
			(enabled no)
			(sheetname "")
		)
		(fill
			(thermal_gap 0.5)
			(thermal_bridge_width 0.5)
			(island_removal_mode 0)
		)
		(polygon
			(pts
				(xy 65.227962 -319.030096) (xy 111.87811 -319.030096) (xy 111.87811 -262.880094) (xy 104.878124 -262.880094)
				(xy 104.878124 -254.88011) (xy 118.977918 -254.88011) (xy 118.977918 -262.880094) (xy 111.977932 -262.880094)
				(xy 111.977932 -319.030096) (xy 158.62808 -319.030096) (xy 158.62808 -198.579994) (xy 65.227962 -198.579994)
			)
		)
	)
	(zone
		(layer "F.Cu")
		(hatch none 0.5)
		(connect_pads
			(clearance 0)
		)
		(min_thickness 0.25)
		(keepout
			(tracks not_allowed)
			(vias allowed)
			(pads allowed)
			(copperpour not_allowed)
			(footprints allowed)
		)
		(placement
			(enabled no)
			(sheetname "")
		)
		(fill
			(thermal_gap 0.5)
			(thermal_bridge_width 0.5)
			(island_removal_mode 0)
		)
		(polygon
			(pts
				(xy 63.108332 -9.094724) (xy 63.22568 -9.094724) (xy 63.27648 -9.043924) (xy 63.27648 -7.596124)
				(xy 63.22568 -7.545324) (xy 63.108332 -7.545324) (xy 63.057532 -7.596124) (xy 63.057532 -9.043924)
			)
		)
	)
	(zone
		(layer "F.Cu")
		(hatch none 0.5)
		(connect_pads
			(clearance 0)
		)
		(min_thickness 0.25)
		(keepout
			(tracks allowed)
			(vias allowed)
			(pads allowed)
			(copperpour allowed)
			(footprints allowed)
		)
		(placement
			(enabled no)
			(sheetname "")
		)
		(fill
			(thermal_gap 0.5)
			(thermal_bridge_width 0.5)
			(island_removal_mode 0)
		)
		(polygon
			(pts
				(xy 82.069686 -373.561102) (xy 82.069686 -372.55704) (xy 83.466178 -372.55704) (xy 83.466178 -373.561102)
			)
		)
	)
	(zone
		(layer "F.Cu")
		(hatch none 0.5)
		(connect_pads
			(clearance 0)
		)
		(min_thickness 0.25)
		(keepout
			(tracks not_allowed)
			(vias allowed)
			(pads allowed)
			(copperpour not_allowed)
			(footprints allowed)
		)
		(placement
			(enabled no)
			(sheetname "")
		)
		(fill
			(thermal_gap 0.5)
			(thermal_bridge_width 0.5)
			(island_removal_mode 0)
		)
		(polygon
			(pts
				(arc
					(start 33.005014 -389.439912)
					(mid 34.870136 -387.57479)
					(end 36.735004 -389.439912)
				)
				(arc
					(start 36.735004 -389.439912)
					(mid 34.870136 -391.30478)
					(end 33.005014 -389.439912)
				)
			)
		)
	)
	(zone
		(layer "F.Cu")
		(hatch none 0.5)
		(connect_pads
			(clearance 0)
		)
		(min_thickness 0.25)
		(keepout
			(tracks allowed)
			(vias allowed)
			(pads allowed)
			(copperpour allowed)
			(footprints not_allowed)
		)
		(placement
			(enabled no)
			(sheetname "")
		)
		(fill
			(thermal_gap 0.5)
			(thermal_bridge_width 0.5)
			(island_removal_mode 0)
		)
		(polygon
			(pts
				(arc
					(start 222.360998 -92.700094)
					(mid 222.007535 -92.846503)
					(end 221.861126 -93.199966)
				)
				(xy 221.861126 -139.195048) (xy 227.772976 -139.195048) (xy 242.384072 -139.195048) (xy 242.384072 -162.572954)
				(xy 227.772976 -162.572954) (xy 227.772976 -139.295124) (xy 221.861126 -139.295124)
				(arc
					(start 221.861126 -148.999956)
					(mid 221.568144 -149.707151)
					(end 220.860874 -149.999954)
				)
				(arc
					(start 209.447892 -149.999954)
					(mid 208.740787 -150.292847)
					(end 208.447894 -150.999952)
				)
				(xy 208.447894 -319.550034) (xy 215.650064 -319.550034) (xy 215.650064 -267.1699)
				(arc
					(start 230.68407 -267.1699)
					(mid 236.649937 -264.499786)
					(end 242.61572 -267.1699)
				)
				(xy 256.15011 -267.1699) (xy 256.15011 -319.65011) (xy 208.447894 -319.65011) (xy 208.447894 -347.544898)
				(xy 205.705964 -347.544898) (xy 205.705964 -350.813878)
				(arc
					(start 228.829616 -350.813878)
					(mid 236.650022 -344.499835)
					(end 244.470428 -350.813878)
				)
				(xy 263.151874 -350.813878) (xy 263.151874 -342.914986) (xy 263.347962 -342.914986)
				(arc
					(start 263.347962 -150.999952)
					(mid 263.055069 -150.292847)
					(end 262.347964 -149.999954)
				)
				(arc
					(start 250.934982 -149.999954)
					(mid 250.227877 -149.707061)
					(end 249.934984 -148.999956)
				)
				(arc
					(start 249.934984 -93.199966)
					(mid 249.788575 -92.846503)
					(end 249.435112 -92.700094)
				)
			)
		)
	)
	(zone
		(layer "F.Cu")
		(hatch none 0.5)
		(connect_pads
			(clearance 0)
		)
		(min_thickness 0.25)
		(keepout
			(tracks allowed)
			(vias allowed)
			(pads allowed)
			(copperpour allowed)
			(footprints allowed)
		)
		(placement
			(enabled no)
			(sheetname "")
		)
		(fill
			(thermal_gap 0.5)
			(thermal_bridge_width 0.5)
			(island_removal_mode 0)
		)
		(polygon
			(pts
				(xy 420.48557 -379.479302) (xy 420.48557 -378.47524) (xy 421.882062 -378.47524) (xy 421.882062 -379.479302)
			)
		)
	)
	(zone
		(layer "F.Cu")
		(hatch none 0.5)
		(connect_pads
			(clearance 0)
		)
		(min_thickness 0.25)
		(keepout
			(tracks allowed)
			(vias allowed)
			(pads allowed)
			(copperpour allowed)
			(footprints allowed)
		)
		(placement
			(enabled no)
			(sheetname "")
		)
		(fill
			(thermal_gap 0.5)
			(thermal_bridge_width 0.5)
			(island_removal_mode 0)
		)
		(polygon
			(pts
				(xy 20.302474 -333.293212) (xy 16.870934 -333.293212) (xy 15.745714 -332.167992) (xy 15.745714 -323.453252)
				(xy 17.229074 -321.969892) (xy 53.022754 -321.969892) (xy 55.250334 -319.742312) (xy 61.818774 -319.742312)
				(xy 72.580754 -308.980332) (xy 84.622894 -308.980332) (xy 86.809834 -306.793392) (xy 86.809834 -299.353732)
				(xy 86.469474 -299.013372) (xy 86.469474 -298.594272) (xy 86.611714 -298.452032) (xy 87.792814 -298.452032)
				(xy 87.914734 -298.573952) (xy 87.914734 -298.962572) (xy 87.602314 -299.274992) (xy 87.602314 -307.237892)
				(xy 85.006434 -309.833772) (xy 72.829674 -309.833772) (xy 62.138814 -320.524632) (xy 55.613554 -320.524632)
				(xy 53.294534 -322.843652) (xy 17.681194 -322.843652) (xy 16.578834 -323.946012) (xy 16.578834 -331.154532)
				(xy 16.949674 -331.525372) (xy 20.101814 -331.525372) (xy 20.411694 -331.835252) (xy 20.411694 -333.183992)
			)
		)
	)
	(zone
		(layer "F.Cu")
		(hatch none 0.5)
		(connect_pads
			(clearance 0)
		)
		(min_thickness 0.25)
		(keepout
			(tracks allowed)
			(vias allowed)
			(pads allowed)
			(copperpour allowed)
			(footprints allowed)
		)
		(placement
			(enabled no)
			(sheetname "")
		)
		(fill
			(thermal_gap 0.5)
			(thermal_bridge_width 0.5)
			(island_removal_mode 0)
		)
		(polygon
			(pts
				(xy 173.303692 -29.719778) (xy 173.303692 -29.141928) (xy 175.720502 -29.141928) (xy 175.720502 -29.719778)
			)
		)
	)
	(zone
		(layer "F.Cu")
		(hatch none 0.5)
		(connect_pads
			(clearance 0)
		)
		(min_thickness 0.25)
		(keepout
			(tracks allowed)
			(vias allowed)
			(pads allowed)
			(copperpour allowed)
			(footprints allowed)
		)
		(placement
			(enabled no)
			(sheetname "")
		)
		(fill
			(thermal_gap 0.5)
			(thermal_bridge_width 0.5)
			(island_removal_mode 0)
		)
		(polygon
			(pts
				(xy 434.711348 -350.80067) (xy 428.361348 -350.80067) (xy 427.726348 -351.43567) (xy 427.726348 -356.00767)
				(xy 428.361348 -356.64267) (xy 434.330348 -356.64267) (xy 434.838348 -356.13467) (xy 434.838348 -350.92767)
			)
		)
	)
	(zone
		(layer "F.Cu")
		(hatch none 0.5)
		(connect_pads
			(clearance 0)
		)
		(min_thickness 0.25)
		(keepout
			(tracks allowed)
			(vias allowed)
			(pads allowed)
			(copperpour allowed)
			(footprints allowed)
		)
		(placement
			(enabled no)
			(sheetname "")
		)
		(fill
			(thermal_gap 0.5)
			(thermal_bridge_width 0.5)
			(island_removal_mode 0)
		)
		(polygon
			(pts
				(xy 63.156338 -373.561102) (xy 63.156338 -372.55704) (xy 64.55283 -372.55704) (xy 64.55283 -373.561102)
			)
		)
	)
	(zone
		(layer "F.Cu")
		(hatch none 0.5)
		(connect_pads
			(clearance 0)
		)
		(min_thickness 0.25)
		(keepout
			(tracks allowed)
			(vias allowed)
			(pads allowed)
			(copperpour allowed)
			(footprints allowed)
		)
		(placement
			(enabled no)
			(sheetname "")
		)
		(fill
			(thermal_gap 0.5)
			(thermal_bridge_width 0.5)
			(island_removal_mode 0)
		)
		(polygon
			(pts
				(xy 189.493144 -12.29614) (xy 189.493144 -13.824458) (xy 188.552328 -13.824458) (xy 188.552328 -12.29614)
			)
		)
	)
	(zone
		(layer "F.Cu")
		(hatch none 0.5)
		(connect_pads
			(clearance 0)
		)
		(min_thickness 0.25)
		(keepout
			(tracks allowed)
			(vias allowed)
			(pads allowed)
			(copperpour allowed)
			(footprints allowed)
		)
		(placement
			(enabled no)
			(sheetname "")
		)
		(fill
			(thermal_gap 0.5)
			(thermal_bridge_width 0.5)
			(island_removal_mode 0)
		)
		(polygon
			(pts
				(xy 302.217074 -346.376752) (xy 295.867074 -346.376752) (xy 295.232074 -347.011752) (xy 295.232074 -351.583752)
				(xy 295.867074 -352.218752) (xy 301.836074 -352.218752) (xy 302.344074 -351.710752) (xy 302.344074 -346.503752)
			)
		)
	)
	(zone
		(layer "F.Cu")
		(hatch none 0.5)
		(connect_pads
			(clearance 0)
		)
		(min_thickness 0.25)
		(keepout
			(tracks allowed)
			(vias allowed)
			(pads allowed)
			(copperpour allowed)
			(footprints allowed)
		)
		(placement
			(enabled no)
			(sheetname "")
		)
		(fill
			(thermal_gap 0.5)
			(thermal_bridge_width 0.5)
			(island_removal_mode 0)
		)
		(polygon
			(pts
				(xy 306.57673 -417.424616) (xy 306.57673 -416.420554) (xy 307.973222 -416.420554) (xy 307.973222 -417.424616)
			)
		)
	)
	(zone
		(layer "F.Cu")
		(hatch none 0.5)
		(connect_pads
			(clearance 0)
		)
		(min_thickness 0.25)
		(keepout
			(tracks allowed)
			(vias allowed)
			(pads allowed)
			(copperpour allowed)
			(footprints allowed)
		)
		(placement
			(enabled no)
			(sheetname "")
		)
		(fill
			(thermal_gap 0.5)
			(thermal_bridge_width 0.5)
			(island_removal_mode 0)
		)
		(polygon
			(pts
				(xy 60.725812 -283.442664) (xy 60.725812 -283.772864) (xy 58.185812 -283.772864) (xy 58.185812 -283.442664)
			)
		)
	)
	(zone
		(layer "F.Cu")
		(hatch none 0.5)
		(connect_pads
			(clearance 0)
		)
		(min_thickness 0.25)
		(keepout
			(tracks not_allowed)
			(vias allowed)
			(pads allowed)
			(copperpour not_allowed)
			(footprints allowed)
		)
		(placement
			(enabled no)
			(sheetname "")
		)
		(fill
			(thermal_gap 0.5)
			(thermal_bridge_width 0.5)
			(island_removal_mode 0)
		)
		(polygon
			(pts
				(xy 332.56093 -334.223868) (xy 332.56093 -334.68056) (xy 333.256636 -334.68056) (xy 333.256636 -334.520032)
				(xy 333.815436 -334.520032) (xy 333.815436 -334.926432) (xy 333.256636 -334.926432) (xy 333.256636 -334.70596)
				(xy 332.56093 -334.70596) (xy 332.56093 -334.83296) (xy 333.016606 -334.83296) (xy 333.016606 -335.219548)
				(xy 333.258922 -335.219548) (xy 333.790798 -335.219548) (xy 334.11033 -334.900016) (xy 334.11033 -334.223868)
			)
		)
	)
	(zone
		(layer "F.Cu")
		(hatch none 0.5)
		(connect_pads
			(clearance 0)
		)
		(min_thickness 0.25)
		(keepout
			(tracks allowed)
			(vias allowed)
			(pads allowed)
			(copperpour allowed)
			(footprints not_allowed)
		)
		(placement
			(enabled no)
			(sheetname "")
		)
		(fill
			(thermal_gap 0.5)
			(thermal_bridge_width 0.5)
			(island_removal_mode 0)
		)
		(polygon
			(pts
				(arc
					(start 55.5625 -59.698636)
					(mid 51.526018 -55.957762)
					(end 49.110392 -51.012852)
				)
				(arc
					(start 45.5676 -51.012852)
					(mid 45.144853 -55.66738)
					(end 43.310048 -59.965844)
				)
				(xy 55.5625 -59.967114)
			)
		)
	)
	(zone
		(layer "F.Cu")
		(hatch none 0.5)
		(connect_pads
			(clearance 0)
		)
		(min_thickness 0.25)
		(keepout
			(tracks allowed)
			(vias allowed)
			(pads allowed)
			(copperpour allowed)
			(footprints allowed)
		)
		(placement
			(enabled no)
			(sheetname "")
		)
		(fill
			(thermal_gap 0.5)
			(thermal_bridge_width 0.5)
			(island_removal_mode 0)
		)
		(polygon
			(pts
				(xy 308.28488 -200.142602) (xy 308.28488 -200.472802) (xy 305.74488 -200.472802) (xy 305.74488 -200.142602)
			)
		)
	)
	(zone
		(layer "F.Cu")
		(hatch none 0.5)
		(connect_pads
			(clearance 0)
		)
		(min_thickness 0.25)
		(keepout
			(tracks allowed)
			(vias allowed)
			(pads allowed)
			(copperpour allowed)
			(footprints allowed)
		)
		(placement
			(enabled no)
			(sheetname "")
		)
		(fill
			(thermal_gap 0.5)
			(thermal_bridge_width 0.5)
			(island_removal_mode 0)
		)
		(polygon
			(pts
				(xy 411.317694 -310.978042) (xy 411.317694 -310.647842) (xy 413.236664 -310.647842) (xy 413.236664 -310.978042)
			)
		)
	)
	(zone
		(layer "F.Cu")
		(hatch none 0.5)
		(connect_pads
			(clearance 0)
		)
		(min_thickness 0.25)
		(keepout
			(tracks allowed)
			(vias allowed)
			(pads allowed)
			(copperpour allowed)
			(footprints not_allowed)
		)
		(placement
			(enabled no)
			(sheetname "")
		)
		(fill
			(thermal_gap 0.5)
			(thermal_bridge_width 0.5)
			(island_removal_mode 0)
		)
		(polygon
			(pts
				(arc
					(start 244.650006 -272.50009)
					(mid 236.650022 -280.500074)
					(end 228.650038 -272.50009)
				)
				(arc
					(start 228.650038 -272.50009)
					(mid 236.650022 -264.500106)
					(end 244.650006 -272.50009)
				)
			)
		)
	)
	(zone
		(layer "F.Cu")
		(hatch none 0.5)
		(connect_pads
			(clearance 0)
		)
		(min_thickness 0.25)
		(keepout
			(tracks allowed)
			(vias allowed)
			(pads allowed)
			(copperpour allowed)
			(footprints allowed)
		)
		(placement
			(enabled no)
			(sheetname "")
		)
		(fill
			(thermal_gap 0.5)
			(thermal_bridge_width 0.5)
			(island_removal_mode 0)
		)
		(polygon
			(pts
				(xy 81.216246 -335.498186) (xy 79.412846 -335.498186) (xy 79.412846 -337.047586) (xy 81.216246 -337.047586)
			)
		)
	)
	(zone
		(layer "F.Cu")
		(hatch none 0.5)
		(connect_pads
			(clearance 0)
		)
		(min_thickness 0.25)
		(keepout
			(tracks allowed)
			(vias allowed)
			(pads allowed)
			(copperpour allowed)
			(footprints allowed)
		)
		(placement
			(enabled no)
			(sheetname "")
		)
		(fill
			(thermal_gap 0.5)
			(thermal_bridge_width 0.5)
			(island_removal_mode 0)
		)
		(polygon
			(pts
				(xy 58.13044 -223.428052) (xy 58.13044 -223.097852) (xy 60.67044 -223.097852) (xy 60.67044 -223.428052)
			)
		)
	)
	(zone
		(layer "F.Cu")
		(hatch none 0.5)
		(connect_pads
			(clearance 0)
		)
		(min_thickness 0.25)
		(keepout
			(tracks allowed)
			(vias allowed)
			(pads allowed)
			(copperpour allowed)
			(footprints allowed)
		)
		(placement
			(enabled no)
			(sheetname "")
		)
		(fill
			(thermal_gap 0.5)
			(thermal_bridge_width 0.5)
			(island_removal_mode 0)
		)
		(polygon
			(pts
				(xy 143.83766 -77.9526) (xy 143.83766 -77.60716) (xy 144.84858 -77.60716) (xy 145.334736 -78.093316)
				(xy 145.334736 -78.371192) (xy 145.15592 -78.550008) (xy 143.9291 -78.550008) (xy 143.878046 -78.498954)
				(xy 143.878046 -77.98435) (xy 143.846296 -77.9526)
			)
		)
	)
	(zone
		(layer "F.Cu")
		(hatch none 0.5)
		(connect_pads
			(clearance 0)
		)
		(min_thickness 0.25)
		(keepout
			(tracks allowed)
			(vias allowed)
			(pads allowed)
			(copperpour allowed)
			(footprints not_allowed)
		)
		(placement
			(enabled no)
			(sheetname "")
		)
		(fill
			(thermal_gap 0.5)
			(thermal_bridge_width 0.5)
			(island_removal_mode 0)
		)
		(polygon
			(pts
				(xy 364.842044 -336.125058) (xy 356.151942 -336.125058) (xy 356.151942 -339.194902) (xy 356.792022 -339.194902)
				(xy 356.792022 -340.965028) (xy 356.151942 -340.965028) (xy 356.151942 -344.914982) (xy 364.842044 -344.914982)
			)
		)
	)
	(zone
		(layer "F.Cu")
		(hatch none 0.5)
		(connect_pads
			(clearance 0)
		)
		(min_thickness 0.25)
		(keepout
			(tracks not_allowed)
			(vias allowed)
			(pads allowed)
			(copperpour not_allowed)
			(footprints allowed)
		)
		(placement
			(enabled no)
			(sheetname "")
		)
		(fill
			(thermal_gap 0.5)
			(thermal_bridge_width 0.5)
			(island_removal_mode 0)
		)
		(polygon
			(pts
				(xy 34.380932 -345.971876) (xy 34.380932 -346.428568) (xy 35.076638 -346.428568) (xy 35.076638 -346.26804)
				(xy 35.635438 -346.26804) (xy 35.635438 -346.67444) (xy 35.076638 -346.67444) (xy 35.076638 -346.453968)
				(xy 34.380932 -346.453968) (xy 34.380932 -346.580968) (xy 34.836608 -346.580968) (xy 34.836608 -346.967556)
				(xy 35.078924 -346.967556) (xy 35.6108 -346.967556) (xy 35.930332 -346.648024) (xy 35.930332 -345.971876)
			)
		)
	)
	(zone
		(layer "F.Cu")
		(hatch none 0.5)
		(connect_pads
			(clearance 0)
		)
		(min_thickness 0.25)
		(keepout
			(tracks allowed)
			(vias allowed)
			(pads allowed)
			(copperpour allowed)
			(footprints allowed)
		)
		(placement
			(enabled no)
			(sheetname "")
		)
		(fill
			(thermal_gap 0.5)
			(thermal_bridge_width 0.5)
			(island_removal_mode 0)
		)
		(polygon
			(pts
				(xy 111.53648 -371.097302) (xy 111.53648 -370.09324) (xy 112.932972 -370.09324) (xy 112.932972 -371.097302)
			)
		)
	)
	(zone
		(layer "F.Cu")
		(hatch none 0.5)
		(connect_pads
			(clearance 0)
		)
		(min_thickness 0.25)
		(keepout
			(tracks allowed)
			(vias allowed)
			(pads allowed)
			(copperpour allowed)
			(footprints not_allowed)
		)
		(placement
			(enabled no)
			(sheetname "")
		)
		(fill
			(thermal_gap 0.5)
			(thermal_bridge_width 0.5)
			(island_removal_mode 0)
		)
		(polygon
			(pts
				(arc
					(start 241.650012 -352.49993)
					(mid 236.650022 -357.49992)
					(end 231.650032 -352.49993)
				)
				(arc
					(start 231.650032 -352.49993)
					(mid 236.650022 -347.49994)
					(end 241.650012 -352.49993)
				)
			)
		)
	)
	(zone
		(layer "F.Cu")
		(hatch none 0.5)
		(connect_pads
			(clearance 0)
		)
		(min_thickness 0.25)
		(keepout
			(tracks allowed)
			(vias allowed)
			(pads allowed)
			(copperpour allowed)
			(footprints not_allowed)
		)
		(placement
			(enabled no)
			(sheetname "")
		)
		(fill
			(thermal_gap 0.5)
			(thermal_bridge_width 0.5)
			(island_removal_mode 0)
		)
		(polygon
			(pts
				(xy 82.147156 -42.049954) (xy 50.917094 -42.049954) (xy 50.917094 -52.049934) (xy 123.916948 -52.049934)
				(xy 123.916948 -42.049954) (xy 86.397084 -42.049954) (xy 86.397084 -47.118016) (xy 82.147156 -47.118016)
			)
		)
	)
	(zone
		(layer "F.Cu")
		(hatch none 0.5)
		(connect_pads
			(clearance 0)
		)
		(min_thickness 0.25)
		(keepout
			(tracks allowed)
			(vias allowed)
			(pads allowed)
			(copperpour allowed)
			(footprints allowed)
		)
		(placement
			(enabled no)
			(sheetname "")
		)
		(fill
			(thermal_gap 0.5)
			(thermal_bridge_width 0.5)
			(island_removal_mode 0)
		)
		(polygon
			(pts
				(xy 229.040944 -59.127136) (xy 229.040944 -51.129692) (xy 232.770172 -51.129692) (xy 232.770172 -59.127136)
			)
		)
	)
	(zone
		(layer "F.Cu")
		(hatch none 0.5)
		(connect_pads
			(clearance 0)
		)
		(min_thickness 0.25)
		(keepout
			(tracks not_allowed)
			(vias allowed)
			(pads allowed)
			(copperpour not_allowed)
			(footprints allowed)
		)
		(placement
			(enabled no)
			(sheetname "")
		)
		(fill
			(thermal_gap 0.5)
			(thermal_bridge_width 0.5)
			(island_removal_mode 0)
		)
		(polygon
			(pts
				(xy 391.453624 -182.043832) (xy 391.453624 -181.08295) (xy 391.211308 -181.08295) (xy 391.211308 -182.043832)
			)
		)
	)
	(zone
		(layer "F.Cu")
		(hatch none 0.5)
		(connect_pads
			(clearance 0)
		)
		(min_thickness 0.25)
		(keepout
			(tracks allowed)
			(vias allowed)
			(pads allowed)
			(copperpour allowed)
			(footprints allowed)
		)
		(placement
			(enabled no)
			(sheetname "")
		)
		(fill
			(thermal_gap 0.5)
			(thermal_bridge_width 0.5)
			(island_removal_mode 0)
		)
		(polygon
			(pts
				(xy 306.070508 -232.777792) (xy 306.070508 -232.447592) (xy 308.610508 -232.447592) (xy 308.610508 -232.777792)
			)
		)
	)
	(zone
		(layer "F.Cu")
		(hatch none 0.5)
		(connect_pads
			(clearance 0)
		)
		(min_thickness 0.25)
		(keepout
			(tracks allowed)
			(vias allowed)
			(pads allowed)
			(copperpour allowed)
			(footprints allowed)
		)
		(placement
			(enabled no)
			(sheetname "")
		)
		(fill
			(thermal_gap 0.5)
			(thermal_bridge_width 0.5)
			(island_removal_mode 0)
		)
		(polygon
			(pts
				(xy 376.740166 -417.424616) (xy 376.740166 -416.420554) (xy 378.136658 -416.420554) (xy 378.136658 -417.424616)
			)
		)
	)
	(zone
		(layer "F.Cu")
		(hatch none 0.5)
		(connect_pads
			(clearance 0)
		)
		(min_thickness 0.25)
		(keepout
			(tracks not_allowed)
			(vias allowed)
			(pads allowed)
			(copperpour not_allowed)
			(footprints allowed)
		)
		(placement
			(enabled no)
			(sheetname "")
		)
		(fill
			(thermal_gap 0.5)
			(thermal_bridge_width 0.5)
			(island_removal_mode 0)
		)
		(polygon
			(pts
				(xy 176.308258 -38.66007) (xy 177.908458 -38.66007) (xy 177.959258 -38.60927) (xy 177.959258 -38.490144)
				(xy 177.908458 -38.439344) (xy 176.308258 -38.439344) (xy 176.257458 -38.490144) (xy 176.257458 -38.60927)
			)
		)
	)
	(zone
		(layer "F.Cu")
		(hatch none 0.5)
		(connect_pads
			(clearance 0)
		)
		(min_thickness 0.25)
		(keepout
			(tracks allowed)
			(vias allowed)
			(pads allowed)
			(copperpour allowed)
			(footprints allowed)
		)
		(placement
			(enabled no)
			(sheetname "")
		)
		(fill
			(thermal_gap 0.5)
			(thermal_bridge_width 0.5)
			(island_removal_mode 0)
		)
		(polygon
			(pts
				(xy 320.730626 -335.715864) (xy 318.927226 -335.715864) (xy 318.927226 -337.265264) (xy 320.730626 -337.265264)
			)
		)
	)
	(zone
		(layer "F.Cu")
		(hatch none 0.5)
		(connect_pads
			(clearance 0)
		)
		(min_thickness 0.25)
		(keepout
			(tracks allowed)
			(vias allowed)
			(pads allowed)
			(copperpour allowed)
			(footprints allowed)
		)
		(placement
			(enabled no)
			(sheetname "")
		)
		(fill
			(thermal_gap 0.5)
			(thermal_bridge_width 0.5)
			(island_removal_mode 0)
		)
		(polygon
			(pts
				(xy 380.42977 -180.731922) (xy 378.62637 -180.731922) (xy 378.62637 -182.281322) (xy 380.42977 -182.281322)
			)
		)
	)
	(zone
		(layer "F.Cu")
		(hatch none 0.5)
		(connect_pads
			(clearance 0)
		)
		(min_thickness 0.25)
		(keepout
			(tracks allowed)
			(vias allowed)
			(pads allowed)
			(copperpour allowed)
			(footprints allowed)
		)
		(placement
			(enabled no)
			(sheetname "")
		)
		(fill
			(thermal_gap 0.5)
			(thermal_bridge_width 0.5)
			(island_removal_mode 0)
		)
		(polygon
			(pts
				(xy 114.94008 -376.024902) (xy 114.94008 -375.02084) (xy 116.336572 -375.02084) (xy 116.336572 -376.024902)
			)
		)
	)
	(zone
		(layer "F.Cu")
		(hatch none 0.5)
		(connect_pads
			(clearance 0)
		)
		(min_thickness 0.25)
		(keepout
			(tracks allowed)
			(vias allowed)
			(pads allowed)
			(copperpour allowed)
			(footprints not_allowed)
		)
		(placement
			(enabled no)
			(sheetname "")
		)
		(fill
			(thermal_gap 0.5)
			(thermal_bridge_width 0.5)
			(island_removal_mode 0)
		)
		(polygon
			(pts
				(xy 357.006906 -350.415098) (xy 357.006906 -344.914982) (xy 344.602054 -344.914982) (xy 340.80704 -341.23503)
				(xy 321.567048 -341.23503) (xy 321.567048 -346.734892) (xy 340.80704 -346.734892) (xy 340.80704 -350.415098)
			)
		)
	)
	(zone
		(layer "F.Cu")
		(hatch none 0.5)
		(connect_pads
			(clearance 0)
		)
		(min_thickness 0.25)
		(keepout
			(tracks allowed)
			(vias allowed)
			(pads allowed)
			(copperpour allowed)
			(footprints allowed)
		)
		(placement
			(enabled no)
			(sheetname "")
		)
		(fill
			(thermal_gap 0.5)
			(thermal_bridge_width 0.5)
			(island_removal_mode 0)
		)
		(polygon
			(pts
				(xy 306.070508 -242.97767) (xy 306.070508 -242.64747) (xy 308.610508 -242.64747) (xy 308.610508 -242.97767)
			)
		)
	)
	(zone
		(layer "F.Cu")
		(hatch none 0.5)
		(connect_pads
			(clearance 0)
		)
		(min_thickness 0.25)
		(keepout
			(tracks allowed)
			(vias allowed)
			(pads allowed)
			(copperpour allowed)
			(footprints allowed)
		)
		(placement
			(enabled no)
			(sheetname "")
		)
		(fill
			(thermal_gap 0.5)
			(thermal_bridge_width 0.5)
			(island_removal_mode 0)
		)
		(polygon
			(pts
				(xy 112.94491 -172.263054) (xy 118.73484 -172.263054) (xy 119.01678 -172.544994) (xy 119.01678 -174.84598)
				(xy 119.56796 -175.39716) (xy 120.05564 -175.39716) (xy 120.27662 -175.17618) (xy 120.27662 -174.08906)
				(xy 119.92991 -173.74235) (xy 119.92991 -171.628054) (xy 119.92991 -167.056054) (xy 119.29491 -166.421054)
				(xy 113.32591 -166.421054) (xy 112.81791 -166.929054) (xy 112.81791 -172.136054)
			)
		)
	)
	(zone
		(layer "F.Cu")
		(hatch none 0.5)
		(connect_pads
			(clearance 0)
		)
		(min_thickness 0.25)
		(keepout
			(tracks not_allowed)
			(vias allowed)
			(pads allowed)
			(copperpour not_allowed)
			(footprints allowed)
		)
		(placement
			(enabled no)
			(sheetname "")
		)
		(fill
			(thermal_gap 0.5)
			(thermal_bridge_width 0.5)
			(island_removal_mode 0)
		)
		(polygon
			(pts
				(xy 315.84773 -334.245458) (xy 315.84773 -334.70215) (xy 316.543436 -334.70215) (xy 316.543436 -334.541622)
				(xy 317.102236 -334.541622) (xy 317.102236 -334.948022) (xy 316.543436 -334.948022) (xy 316.543436 -334.72755)
				(xy 315.84773 -334.72755) (xy 315.84773 -334.85455) (xy 316.303406 -334.85455) (xy 316.303406 -335.241138)
				(xy 316.545722 -335.241138) (xy 317.077598 -335.241138) (xy 317.39713 -334.921606) (xy 317.39713 -334.245458)
			)
		)
	)
	(zone
		(layer "F.Cu")
		(hatch none 0.5)
		(connect_pads
			(clearance 0)
		)
		(min_thickness 0.25)
		(keepout
			(tracks allowed)
			(vias allowed)
			(pads allowed)
			(copperpour allowed)
			(footprints allowed)
		)
		(placement
			(enabled no)
			(sheetname "")
		)
		(fill
			(thermal_gap 0.5)
			(thermal_bridge_width 0.5)
			(island_removal_mode 0)
		)
		(polygon
			(pts
				(xy 259.52196 -5.83184) (xy 259.52196 -3.85064) (xy 261.61492 -3.85064) (xy 261.61492 -5.83184)
			)
		)
	)
	(zone
		(layer "F.Cu")
		(hatch none 0.5)
		(connect_pads
			(clearance 0)
		)
		(min_thickness 0.25)
		(keepout
			(tracks allowed)
			(vias allowed)
			(pads allowed)
			(copperpour allowed)
			(footprints allowed)
		)
		(placement
			(enabled no)
			(sheetname "")
		)
		(fill
			(thermal_gap 0.5)
			(thermal_bridge_width 0.5)
			(island_removal_mode 0)
		)
		(polygon
			(pts
				(xy 170.14698 -333.727044) (xy 170.14698 -333.083408) (xy 170.762422 -333.083408) (xy 170.762422 -333.727044)
			)
		)
	)
	(zone
		(layer "F.Cu")
		(hatch none 0.5)
		(connect_pads
			(clearance 0)
		)
		(min_thickness 0.25)
		(keepout
			(tracks allowed)
			(vias allowed)
			(pads allowed)
			(copperpour allowed)
			(footprints allowed)
		)
		(placement
			(enabled no)
			(sheetname "")
		)
		(fill
			(thermal_gap 0.5)
			(thermal_bridge_width 0.5)
			(island_removal_mode 0)
		)
		(polygon
			(pts
				(xy 88.557354 -195.33616) (xy 88.557354 -197.24116) (xy 92.570554 -197.24116) (xy 92.570554 -195.33616)
			)
		)
	)
	(zone
		(layer "F.Cu")
		(hatch none 0.5)
		(connect_pads
			(clearance 0)
		)
		(min_thickness 0.25)
		(keepout
			(tracks allowed)
			(vias allowed)
			(pads allowed)
			(copperpour allowed)
			(footprints allowed)
		)
		(placement
			(enabled no)
			(sheetname "")
		)
		(fill
			(thermal_gap 0.5)
			(thermal_bridge_width 0.5)
			(island_removal_mode 0)
		)
		(polygon
			(pts
				(xy 248.52884 -58.80354) (xy 256.92354 -58.80354) (xy 257.31724 -58.40984) (xy 257.31724 -51.02606)
				(xy 257.81 -50.5333) (xy 259.3721 -50.5333) (xy 259.99694 -49.90846) (xy 259.99694 -40.2082) (xy 258.15036 -38.36162)
				(xy 248.89206 -38.36162) (xy 247.64238 -39.6113) (xy 247.64238 -41.5163) (xy 247.26392 -41.89476)
				(xy 235.72978 -41.89476) (xy 235.54436 -42.08018) (xy 235.54436 -45.71238) (xy 235.71454 -45.88256)
				(xy 240.85296 -45.88256) (xy 242.32108 -47.35068) (xy 242.32108 -47.8155) (xy 242.29822 -47.83836)
				(xy 242.29822 -50.61712) (xy 242.76304 -51.08194) (xy 244.53342 -51.08194) (xy 245.1354 -51.68392)
				(xy 245.1354 -53.56606) (xy 245.4275 -53.85816) (xy 246.46382 -53.85816) (xy 246.70766 -54.102)
				(xy 246.70766 -56.98236)
			)
		)
	)
	(zone
		(layer "F.Cu")
		(hatch none 0.5)
		(connect_pads
			(clearance 0)
		)
		(min_thickness 0.25)
		(keepout
			(tracks allowed)
			(vias allowed)
			(pads allowed)
			(copperpour allowed)
			(footprints allowed)
		)
		(placement
			(enabled no)
			(sheetname "")
		)
		(fill
			(thermal_gap 0.5)
			(thermal_bridge_width 0.5)
			(island_removal_mode 0)
		)
		(polygon
			(pts
				(xy 331.262228 -381.943102) (xy 331.262228 -380.93904) (xy 332.65872 -380.93904) (xy 332.65872 -381.943102)
			)
		)
	)
	(zone
		(layer "F.Cu")
		(hatch none 0.5)
		(connect_pads
			(clearance 0)
		)
		(min_thickness 0.25)
		(keepout
			(tracks allowed)
			(vias allowed)
			(pads allowed)
			(copperpour allowed)
			(footprints allowed)
		)
		(placement
			(enabled no)
			(sheetname "")
		)
		(fill
			(thermal_gap 0.5)
			(thermal_bridge_width 0.5)
			(island_removal_mode 0)
		)
		(polygon
			(pts
				(xy 249.7963 4.25196) (xy 249.7963 6.477) (xy 252.222 6.477) (xy 252.222 4.25196)
			)
		)
	)
	(zone
		(layer "F.Cu")
		(hatch none 0.5)
		(connect_pads
			(clearance 0)
		)
		(min_thickness 0.25)
		(keepout
			(tracks not_allowed)
			(vias allowed)
			(pads allowed)
			(copperpour not_allowed)
			(footprints allowed)
		)
		(placement
			(enabled no)
			(sheetname "")
		)
		(fill
			(thermal_gap 0.5)
			(thermal_bridge_width 0.5)
			(island_removal_mode 0)
		)
		(polygon
			(pts
				(xy 416.885882 -360.44632) (xy 416.885882 -360.86034) (xy 417.038282 -360.86034) (xy 417.038282 -360.44632)
			)
		)
	)
	(zone
		(layer "F.Cu")
		(hatch none 0.5)
		(connect_pads
			(clearance 0)
		)
		(min_thickness 0.25)
		(keepout
			(tracks not_allowed)
			(vias allowed)
			(pads allowed)
			(copperpour not_allowed)
			(footprints allowed)
		)
		(placement
			(enabled no)
			(sheetname "")
		)
		(fill
			(thermal_gap 0.5)
			(thermal_bridge_width 0.5)
			(island_removal_mode 0)
		)
		(polygon
			(pts
				(arc
					(start 241.650012 -272.50009)
					(mid 236.650022 -277.50008)
					(end 231.650032 -272.50009)
				)
				(arc
					(start 231.650032 -272.50009)
					(mid 236.650022 -267.5001)
					(end 241.650012 -272.50009)
				)
			)
		)
	)
	(zone
		(layer "F.Cu")
		(hatch none 0.5)
		(connect_pads
			(clearance 0)
		)
		(min_thickness 0.25)
		(keepout
			(tracks allowed)
			(vias allowed)
			(pads allowed)
			(copperpour allowed)
			(footprints allowed)
		)
		(placement
			(enabled no)
			(sheetname "")
		)
		(fill
			(thermal_gap 0.5)
			(thermal_bridge_width 0.5)
			(island_removal_mode 0)
		)
		(polygon
			(pts
				(xy 289.24504 -419.647878) (xy 288.12109 -419.647878) (xy 288.12109 -418.91331) (xy 288.12109 -417.577778)
				(xy 289.24504 -417.577778)
			)
		)
	)
	(zone
		(layer "F.Cu")
		(hatch none 0.5)
		(connect_pads
			(clearance 0)
		)
		(min_thickness 0.25)
		(keepout
			(tracks allowed)
			(vias allowed)
			(pads allowed)
			(copperpour allowed)
			(footprints allowed)
		)
		(placement
			(enabled no)
			(sheetname "")
		)
		(fill
			(thermal_gap 0.5)
			(thermal_bridge_width 0.5)
			(island_removal_mode 0)
		)
		(polygon
			(pts
				(xy 411.317694 -244.677692) (xy 411.317694 -244.347492) (xy 413.236664 -244.347492) (xy 413.236664 -244.677692)
			)
		)
	)
	(zone
		(layer "F.Cu")
		(hatch none 0.5)
		(connect_pads
			(clearance 0)
		)
		(min_thickness 0.25)
		(keepout
			(tracks allowed)
			(vias allowed)
			(pads allowed)
			(copperpour allowed)
			(footprints allowed)
		)
		(placement
			(enabled no)
			(sheetname "")
		)
		(fill
			(thermal_gap 0.5)
			(thermal_bridge_width 0.5)
			(island_removal_mode 0)
		)
		(polygon
			(pts
				(xy 308.66588 -281.742388) (xy 308.66588 -282.072588) (xy 306.12588 -282.072588) (xy 306.12588 -281.742388)
			)
		)
	)
	(zone
		(layer "F.Cu")
		(hatch none 0.5)
		(connect_pads
			(clearance 0)
		)
		(min_thickness 0.25)
		(keepout
			(tracks allowed)
			(vias allowed)
			(pads allowed)
			(copperpour allowed)
			(footprints not_allowed)
		)
		(placement
			(enabled no)
			(sheetname "")
		)
		(fill
			(thermal_gap 0.5)
			(thermal_bridge_width 0.5)
			(island_removal_mode 0)
		)
		(polygon
			(pts
				(xy 288.393886 -161.291524) (xy 288.396426 -139.291568) (xy 267.396214 -139.289282) (xy 267.393928 -161.289492)
			)
		)
	)
	(zone
		(layer "F.Cu")
		(hatch none 0.5)
		(connect_pads
			(clearance 0)
		)
		(min_thickness 0.25)
		(keepout
			(tracks allowed)
			(vias allowed)
			(pads allowed)
			(copperpour allowed)
			(footprints not_allowed)
		)
		(placement
			(enabled no)
			(sheetname "")
		)
		(fill
			(thermal_gap 0.5)
			(thermal_bridge_width 0.5)
			(island_removal_mode 0)
		)
		(polygon
			(pts
				(arc
					(start 467.300056 -353.167696)
					(mid 453.460093 -347.700092)
					(end 467.300056 -342.232488)
				)
			)
		)
	)
	(zone
		(layer "F.Cu")
		(hatch none 0.5)
		(connect_pads
			(clearance 0)
		)
		(min_thickness 0.25)
		(keepout
			(tracks allowed)
			(vias allowed)
			(pads allowed)
			(copperpour allowed)
			(footprints allowed)
		)
		(placement
			(enabled no)
			(sheetname "")
		)
		(fill
			(thermal_gap 0.5)
			(thermal_bridge_width 0.5)
			(island_removal_mode 0)
		)
		(polygon
			(pts
				(xy 58.050938 -371.097302) (xy 58.050938 -370.09324) (xy 59.44743 -370.09324) (xy 59.44743 -371.097302)
			)
		)
	)
	(zone
		(layer "F.Cu")
		(hatch none 0.5)
		(connect_pads
			(clearance 0)
		)
		(min_thickness 0.25)
		(keepout
			(tracks allowed)
			(vias allowed)
			(pads allowed)
			(copperpour allowed)
			(footprints allowed)
		)
		(placement
			(enabled no)
			(sheetname "")
		)
		(fill
			(thermal_gap 0.5)
			(thermal_bridge_width 0.5)
			(island_removal_mode 0)
		)
		(polygon
			(pts
				(xy 411.317694 -267.627862) (xy 411.317694 -267.297662) (xy 413.236664 -267.297662) (xy 413.236664 -267.627862)
			)
		)
	)
	(zone
		(layer "F.Cu")
		(hatch none 0.5)
		(connect_pads
			(clearance 0)
		)
		(min_thickness 0.25)
		(keepout
			(tracks not_allowed)
			(vias allowed)
			(pads allowed)
			(copperpour not_allowed)
			(footprints allowed)
		)
		(placement
			(enabled no)
			(sheetname "")
		)
		(fill
			(thermal_gap 0.5)
			(thermal_bridge_width 0.5)
			(island_removal_mode 0)
		)
		(polygon
			(pts
				(arc
					(start 241.650012 -192.499996)
					(mid 236.650022 -197.499986)
					(end 231.650032 -192.499996)
				)
				(arc
					(start 231.650032 -192.499996)
					(mid 236.650022 -187.500006)
					(end 241.650012 -192.499996)
				)
			)
		)
	)
	(zone
		(layer "F.Cu")
		(hatch none 0.5)
		(connect_pads
			(clearance 0)
		)
		(min_thickness 0.25)
		(keepout
			(tracks allowed)
			(vias allowed)
			(pads allowed)
			(copperpour allowed)
			(footprints allowed)
		)
		(placement
			(enabled no)
			(sheetname "")
		)
		(fill
			(thermal_gap 0.5)
			(thermal_bridge_width 0.5)
			(island_removal_mode 0)
		)
		(polygon
			(pts
				(xy 238.431324 -53.173884) (xy 238.431324 -51.556412) (xy 239.868964 -51.556412) (xy 239.868964 -53.173884)
			)
		)
	)
	(zone
		(layer "F.Cu")
		(hatch none 0.5)
		(connect_pads
			(clearance 0)
		)
		(min_thickness 0.25)
		(keepout
			(tracks allowed)
			(vias allowed)
			(pads allowed)
			(copperpour allowed)
			(footprints allowed)
		)
		(placement
			(enabled no)
			(sheetname "")
		)
		(fill
			(thermal_gap 0.5)
			(thermal_bridge_width 0.5)
			(island_removal_mode 0)
		)
		(polygon
			(pts
				(xy 411.317694 -269.327884) (xy 411.317694 -268.997684) (xy 413.236664 -268.997684) (xy 413.236664 -269.327884)
			)
		)
	)
	(zone
		(layer "F.Cu")
		(hatch none 0.5)
		(connect_pads
			(clearance 0)
		)
		(min_thickness 0.25)
		(keepout
			(tracks allowed)
			(vias allowed)
			(pads allowed)
			(copperpour allowed)
			(footprints allowed)
		)
		(placement
			(enabled no)
			(sheetname "")
		)
		(fill
			(thermal_gap 0.5)
			(thermal_bridge_width 0.5)
			(island_removal_mode 0)
		)
		(polygon
			(pts
				(xy 204.944472 -343.63152) (xy 204.944472 -343.19718) (xy 206.054452 -343.19718) (xy 206.054452 -343.63152)
			)
		)
	)
	(zone
		(layer "F.Cu")
		(hatch none 0.5)
		(connect_pads
			(clearance 0)
		)
		(min_thickness 0.25)
		(keepout
			(tracks allowed)
			(vias allowed)
			(pads allowed)
			(copperpour allowed)
			(footprints not_allowed)
		)
		(placement
			(enabled no)
			(sheetname "")
		)
		(fill
			(thermal_gap 0.5)
			(thermal_bridge_width 0.5)
			(island_removal_mode 0)
		)
		(polygon
			(pts
				(arc
					(start 466.460078 -347.700092)
					(mid 461.460088 -352.700082)
					(end 456.460098 -347.700092)
				)
				(arc
					(start 456.460098 -347.700092)
					(mid 461.460088 -342.700102)
					(end 466.460078 -347.700092)
				)
			)
		)
	)
	(zone
		(layer "F.Cu")
		(hatch none 0.5)
		(connect_pads
			(clearance 0)
		)
		(min_thickness 0.25)
		(keepout
			(tracks allowed)
			(vias allowed)
			(pads allowed)
			(copperpour allowed)
			(footprints not_allowed)
		)
		(placement
			(enabled no)
			(sheetname "")
		)
		(fill
			(thermal_gap 0.5)
			(thermal_bridge_width 0.5)
			(island_removal_mode 0)
		)
		(polygon
			(pts
				(arc
					(start 11.726672 -28.754324)
					(mid 12.400909 -27.358704)
					(end 13.749528 -26.594816)
				)
				(arc
					(start 13.749528 -26.594816)
					(mid 11.807805 -15.905617)
					(end 0.999998 -17.008602)
				)
				(arc
					(start 0.999998 -27.591512)
					(mid 6.137804 -30.253378)
					(end 11.726672 -28.754324)
				)
			)
		)
	)
	(zone
		(layer "F.Cu")
		(hatch none 0.5)
		(connect_pads
			(clearance 0)
		)
		(min_thickness 0.25)
		(keepout
			(tracks allowed)
			(vias allowed)
			(pads allowed)
			(copperpour allowed)
			(footprints allowed)
		)
		(placement
			(enabled no)
			(sheetname "")
		)
		(fill
			(thermal_gap 0.5)
			(thermal_bridge_width 0.5)
			(island_removal_mode 0)
		)
		(polygon
			(pts
				(xy 60.725812 -287.692592) (xy 60.725812 -288.022792) (xy 58.185812 -288.022792) (xy 58.185812 -287.692592)
			)
		)
	)
	(zone
		(layer "F.Cu")
		(hatch none 0.5)
		(connect_pads
			(clearance 0)
		)
		(min_thickness 0.25)
		(keepout
			(tracks allowed)
			(vias allowed)
			(pads allowed)
			(copperpour allowed)
			(footprints not_allowed)
		)
		(placement
			(enabled no)
			(sheetname "")
		)
		(fill
			(thermal_gap 0.5)
			(thermal_bridge_width 0.5)
			(island_removal_mode 0)
		)
		(polygon
			(pts
				(arc
					(start 456.000104 -435.600094)
					(mid 458.8002 -432.799998)
					(end 461.600042 -435.600094)
				)
				(arc
					(start 461.600042 -435.600094)
					(mid 458.8002 -438.399936)
					(end 456.000104 -435.600094)
				)
			)
		)
	)
	(zone
		(layer "F.Cu")
		(hatch none 0.5)
		(connect_pads
			(clearance 0)
		)
		(min_thickness 0.25)
		(keepout
			(tracks allowed)
			(vias allowed)
			(pads allowed)
			(copperpour allowed)
			(footprints allowed)
		)
		(placement
			(enabled no)
			(sheetname "")
		)
		(fill
			(thermal_gap 0.5)
			(thermal_bridge_width 0.5)
			(island_removal_mode 0)
		)
		(polygon
			(pts
				(xy 58.13044 -252.327918) (xy 58.13044 -251.997718) (xy 60.67044 -251.997718) (xy 60.67044 -252.327918)
			)
		)
	)
	(zone
		(layer "F.Cu")
		(hatch none 0.5)
		(connect_pads
			(clearance 0)
		)
		(min_thickness 0.25)
		(keepout
			(tracks allowed)
			(vias allowed)
			(pads allowed)
			(copperpour allowed)
			(footprints allowed)
		)
		(placement
			(enabled no)
			(sheetname "")
		)
		(fill
			(thermal_gap 0.5)
			(thermal_bridge_width 0.5)
			(island_removal_mode 0)
		)
		(polygon
			(pts
				(xy 411.317694 -208.977738) (xy 411.317694 -208.647538) (xy 413.236664 -208.647538) (xy 413.236664 -208.977738)
			)
		)
	)
	(zone
		(layer "F.Cu")
		(hatch none 0.5)
		(connect_pads
			(clearance 0)
		)
		(min_thickness 0.25)
		(keepout
			(tracks not_allowed)
			(vias allowed)
			(pads allowed)
			(copperpour not_allowed)
			(footprints allowed)
		)
		(placement
			(enabled no)
			(sheetname "")
		)
		(fill
			(thermal_gap 0.5)
			(thermal_bridge_width 0.5)
			(island_removal_mode 0)
		)
		(polygon
			(pts
				(xy 391.9093 -183.493156) (xy 391.9093 -183.036464) (xy 391.213594 -183.036464) (xy 391.213594 -183.196992)
				(xy 390.654794 -183.196992) (xy 390.654794 -182.790592) (xy 391.213594 -182.790592) (xy 391.213594 -183.011064)
				(xy 391.9093 -183.011064) (xy 391.9093 -182.884064) (xy 391.453624 -182.884064) (xy 391.453624 -182.497476)
				(xy 391.211308 -182.497476) (xy 390.679432 -182.497476) (xy 390.3599 -182.817008) (xy 390.3599 -183.493156)
			)
		)
	)
	(zone
		(layer "F.Cu")
		(hatch none 0.5)
		(connect_pads
			(clearance 0)
		)
		(min_thickness 0.25)
		(keepout
			(tracks allowed)
			(vias allowed)
			(pads allowed)
			(copperpour allowed)
			(footprints allowed)
		)
		(placement
			(enabled no)
			(sheetname "")
		)
		(fill
			(thermal_gap 0.5)
			(thermal_bridge_width 0.5)
			(island_removal_mode 0)
		)
		(polygon
			(pts
				(xy 58.13044 -267.628116) (xy 58.13044 -267.297916) (xy 60.67044 -267.297916) (xy 60.67044 -267.628116)
			)
		)
	)
	(zone
		(layer "F.Cu")
		(hatch none 0.5)
		(connect_pads
			(clearance 0)
		)
		(min_thickness 0.25)
		(keepout
			(tracks allowed)
			(vias allowed)
			(pads allowed)
			(copperpour allowed)
			(footprints allowed)
		)
		(placement
			(enabled no)
			(sheetname "")
		)
		(fill
			(thermal_gap 0.5)
			(thermal_bridge_width 0.5)
			(island_removal_mode 0)
		)
		(polygon
			(pts
				(xy 60.725812 -311.492646) (xy 60.725812 -311.822846) (xy 58.185812 -311.822846) (xy 58.185812 -311.492646)
			)
		)
	)
	(zone
		(layer "F.Cu")
		(hatch none 0.5)
		(connect_pads
			(clearance 0)
		)
		(min_thickness 0.25)
		(keepout
			(tracks allowed)
			(vias allowed)
			(pads allowed)
			(copperpour allowed)
			(footprints allowed)
		)
		(placement
			(enabled no)
			(sheetname "")
		)
		(fill
			(thermal_gap 0.5)
			(thermal_bridge_width 0.5)
			(island_removal_mode 0)
		)
		(polygon
			(pts
				(xy 185.371486 -351.800668) (xy 183.568086 -351.800668) (xy 183.568086 -353.350068) (xy 185.371486 -353.350068)
			)
		)
	)
	(zone
		(layer "F.Cu")
		(hatch none 0.5)
		(connect_pads
			(clearance 0)
		)
		(min_thickness 0.25)
		(keepout
			(tracks allowed)
			(vias allowed)
			(pads allowed)
			(copperpour allowed)
			(footprints not_allowed)
		)
		(placement
			(enabled no)
			(sheetname "")
		)
		(fill
			(thermal_gap 0.5)
			(thermal_bridge_width 0.5)
			(island_removal_mode 0)
		)
		(polygon
			(pts
				(xy 183.45404 -161.280602) (xy 204.453998 -161.282888) (xy 204.455776 -144.808448) (xy 221.861126 -144.808448)
				(arc
					(start 221.861126 -148.999956)
					(mid 221.568144 -149.707151)
					(end 220.860874 -149.999954)
				)
				(arc
					(start 209.447892 -149.999954)
					(mid 208.740787 -150.292847)
					(end 208.447894 -150.999952)
				)
				(xy 208.447894 -165.596062)
				(arc
					(start 174.066962 -165.596062)
					(mid 167.531827 -152.508574)
					(end 162.228022 -166.141654)
				)
				(xy 162.228022 -347.544898) (xy 168.706038 -347.544898) (xy 168.706038 -351.605088) (xy 74.331068 -351.605088)
				(xy 74.331068 -346.734892) (xy 93.57106 -346.734892) (xy 93.57106 -350.415098) (xy 109.770926 -350.415098)
				(xy 109.770926 -344.914982) (xy 117.606064 -344.914982) (xy 117.606064 -336.12455) (xy 100.215954 -336.12455)
				(xy 100.215954 -331.185012) (xy 65.715896 -331.185012) (xy 65.715896 -342.914986) (xy 61.62802 -342.914986)
				(xy 61.62802 -258.990084) (xy 65.227962 -258.990084) (xy 65.227962 -319.030096) (xy 158.62808 -319.030096)
				(xy 158.62808 -198.579994) (xy 65.227962 -198.579994) (xy 65.227962 -258.890008) (xy 61.62802 -258.890008)
				(xy 61.62802 -172.315124) (xy 69.656706 -172.315124) (xy 69.656706 -181.315106) (xy 78.016608 -181.315106)
				(xy 78.016608 -186.37504) (xy 104.206802 -186.37504) (xy 104.206802 -181.805072) (xy 112.436656 -181.805072)
				(xy 112.436656 -175.554894) (xy 120.28678 -175.554894) (xy 120.28678 -168.90492) (xy 128.839468 -168.90492)
				(xy 128.839468 -160.245044) (xy 137.196068 -160.245044) (xy 137.196068 -150.80488) (xy 137.196068 -144.808448)
				(xy 183.455818 -144.808448)
			)
		)
	)
	(zone
		(layer "F.Cu")
		(hatch none 0.5)
		(connect_pads
			(clearance 0)
		)
		(min_thickness 0.25)
		(keepout
			(tracks allowed)
			(vias allowed)
			(pads allowed)
			(copperpour allowed)
			(footprints allowed)
		)
		(placement
			(enabled no)
			(sheetname "")
		)
		(fill
			(thermal_gap 0.5)
			(thermal_bridge_width 0.5)
			(island_removal_mode 0)
		)
		(polygon
			(pts
				(xy 121.135648 -348.619826) (xy 121.135648 -348.197932) (xy 121.25071 -348.197932) (xy 121.25071 -348.619826)
			)
		)
	)
	(zone
		(layer "F.Cu")
		(hatch none 0.5)
		(connect_pads
			(clearance 0)
		)
		(min_thickness 0.25)
		(keepout
			(tracks allowed)
			(vias allowed)
			(pads allowed)
			(copperpour allowed)
			(footprints not_allowed)
		)
		(placement
			(enabled no)
			(sheetname "")
		)
		(fill
			(thermal_gap 0.5)
			(thermal_bridge_width 0.5)
			(island_removal_mode 0)
		)
		(polygon
			(pts
				(arc
					(start 314.969906 -258.890008)
					(mid 317.770002 -256.089912)
					(end 320.570098 -258.890008)
				)
				(arc
					(start 320.570098 -258.890008)
					(mid 317.770002 -261.690104)
					(end 314.969906 -258.890008)
				)
			)
		)
	)
	(zone
		(layer "F.Cu")
		(hatch none 0.5)
		(connect_pads
			(clearance 0)
		)
		(min_thickness 0.25)
		(keepout
			(tracks allowed)
			(vias allowed)
			(pads allowed)
			(copperpour allowed)
			(footprints allowed)
		)
		(placement
			(enabled no)
			(sheetname "")
		)
		(fill
			(thermal_gap 0.5)
			(thermal_bridge_width 0.5)
			(island_removal_mode 0)
		)
		(polygon
			(pts
				(xy 111.932212 -391.360406) (xy 113.73866 -391.360406) (xy 114.027458 -391.071608) (xy 114.027458 -388.252462)
				(xy 114.152426 -388.127494) (xy 133.538468 -388.127494) (xy 133.538468 -390.775952) (xy 133.188964 -391.125456)
				(xy 133.188964 -392.40206) (xy 133.35381 -392.566906) (xy 133.943598 -392.566906) (xy 135.42391 -391.086594)
				(xy 135.42391 -388.176008) (xy 133.196584 -385.948682) (xy 114.013742 -385.948682) (xy 113.399062 -385.334002)
				(xy 113.399062 -384.995166) (xy 113.24844 -384.844544) (xy 112.23244 -384.844544) (xy 111.856012 -385.220972)
				(xy 111.856012 -387.315964) (xy 110.97768 -388.194296) (xy 110.97768 -389.260842) (xy 111.868458 -390.15162)
				(xy 111.868458 -391.296652)
			)
		)
	)
	(zone
		(layer "F.Cu")
		(hatch none 0.5)
		(connect_pads
			(clearance 0)
		)
		(min_thickness 0.25)
		(keepout
			(tracks allowed)
			(vias allowed)
			(pads allowed)
			(copperpour allowed)
			(footprints allowed)
		)
		(placement
			(enabled no)
			(sheetname "")
		)
		(fill
			(thermal_gap 0.5)
			(thermal_bridge_width 0.5)
			(island_removal_mode 0)
		)
		(polygon
			(pts
				(xy 163.634928 -312.678064) (xy 163.634928 -312.347864) (xy 165.296596 -312.347864) (xy 165.296596 -312.678064)
			)
		)
	)
	(zone
		(layer "F.Cu")
		(hatch none 0.5)
		(connect_pads
			(clearance 0)
		)
		(min_thickness 0.25)
		(keepout
			(tracks allowed)
			(vias allowed)
			(pads allowed)
			(copperpour allowed)
			(footprints allowed)
		)
		(placement
			(enabled no)
			(sheetname "")
		)
		(fill
			(thermal_gap 0.5)
			(thermal_bridge_width 0.5)
			(island_removal_mode 0)
		)
		(polygon
			(pts
				(xy 131.064 -33.7058) (xy 133.1214 -33.7058) (xy 133.3754 -33.4518) (xy 133.3754 -31.6992) (xy 133.2992 -31.623)
				(xy 132.5118 -31.623) (xy 132.2578 -31.369) (xy 132.2578 -31.1404) (xy 132.2578 -30.9118) (xy 132.0546 -30.7086)
				(xy 131.718812 -30.372812) (xy 129.170684 -30.372812) (xy 128.416812 -31.126684) (xy 128.416812 -32.391604)
				(xy 129.731008 -33.7058)
			)
		)
	)
	(zone
		(layer "F.Cu")
		(hatch none 0.5)
		(connect_pads
			(clearance 0)
		)
		(min_thickness 0.25)
		(keepout
			(tracks allowed)
			(vias allowed)
			(pads allowed)
			(copperpour allowed)
			(footprints allowed)
		)
		(placement
			(enabled no)
			(sheetname "")
		)
		(fill
			(thermal_gap 0.5)
			(thermal_bridge_width 0.5)
			(island_removal_mode 0)
		)
		(polygon
			(pts
				(xy 69.939408 -13.186918) (xy 69.939408 -9.853676) (xy 73.021952 -9.853676) (xy 73.021952 -13.186918)
			)
		)
	)
	(zone
		(layer "F.Cu")
		(hatch none 0.5)
		(connect_pads
			(clearance 0)
		)
		(min_thickness 0.25)
		(keepout
			(tracks not_allowed)
			(vias allowed)
			(pads allowed)
			(copperpour not_allowed)
			(footprints allowed)
		)
		(placement
			(enabled no)
			(sheetname "")
		)
		(fill
			(thermal_gap 0.5)
			(thermal_bridge_width 0.5)
			(island_removal_mode 0)
		)
		(polygon
			(pts
				(arc
					(start 165.1 -160.50006)
					(mid 167.900096 -157.699964)
					(end 170.699938 -160.50006)
				)
				(arc
					(start 170.699938 -160.50006)
					(mid 167.900096 -163.299902)
					(end 165.1 -160.50006)
				)
			)
		)
	)
	(zone
		(layer "F.Cu")
		(hatch none 0.5)
		(connect_pads
			(clearance 0)
		)
		(min_thickness 0.25)
		(keepout
			(tracks not_allowed)
			(vias allowed)
			(pads allowed)
			(copperpour not_allowed)
			(footprints allowed)
		)
		(placement
			(enabled no)
			(sheetname "")
		)
		(fill
			(thermal_gap 0.5)
			(thermal_bridge_width 0.5)
			(island_removal_mode 0)
		)
		(polygon
			(pts
				(xy 101.574092 -183.442356) (xy 101.574092 -182.985664) (xy 100.878386 -182.985664) (xy 100.878386 -183.146192)
				(xy 100.319586 -183.146192) (xy 100.319586 -182.739792) (xy 100.878386 -182.739792) (xy 100.878386 -182.960264)
				(xy 101.574092 -182.960264) (xy 101.574092 -182.833264) (xy 101.118416 -182.833264) (xy 101.118416 -182.446676)
				(xy 100.8761 -182.446676) (xy 100.344224 -182.446676) (xy 100.024692 -182.766208) (xy 100.024692 -183.442356)
			)
		)
	)
	(zone
		(layer "F.Cu")
		(hatch none 0.5)
		(connect_pads
			(clearance 0)
		)
		(min_thickness 0.25)
		(keepout
			(tracks allowed)
			(vias allowed)
			(pads allowed)
			(copperpour allowed)
			(footprints allowed)
		)
		(placement
			(enabled no)
			(sheetname "")
		)
		(fill
			(thermal_gap 0.5)
			(thermal_bridge_width 0.5)
			(island_removal_mode 0)
		)
		(polygon
			(pts
				(xy 315.046868 -364.768892) (xy 319.315084 -364.768892) (xy 319.581784 -364.502192) (xy 319.581784 -362.854748)
				(xy 318.765428 -362.038392) (xy 316.553088 -362.038392) (xy 315.768736 -361.25404) (xy 315.768736 -358.900222)
				(xy 315.407802 -358.539288) (xy 313.587638 -358.539288) (xy 312.803032 -359.323894) (xy 312.803032 -362.525056)
			)
		)
	)
	(zone
		(layer "F.Cu")
		(hatch none 0.5)
		(connect_pads
			(clearance 0)
		)
		(min_thickness 0.25)
		(keepout
			(tracks not_allowed)
			(vias allowed)
			(pads allowed)
			(copperpour not_allowed)
			(footprints allowed)
		)
		(placement
			(enabled no)
			(sheetname "")
		)
		(fill
			(thermal_gap 0.5)
			(thermal_bridge_width 0.5)
			(island_removal_mode 0)
		)
		(polygon
			(pts
				(arc
					(start 36.548314 -417.465002)
					(mid 35.880294 -417.465002)
					(end 36.548314 -417.465002)
				)
			)
		)
	)
	(zone
		(layer "F.Cu")
		(hatch none 0.5)
		(connect_pads
			(clearance 0)
		)
		(min_thickness 0.25)
		(keepout
			(tracks not_allowed)
			(vias allowed)
			(pads allowed)
			(copperpour not_allowed)
			(footprints allowed)
		)
		(placement
			(enabled no)
			(sheetname "")
		)
		(fill
			(thermal_gap 0.5)
			(thermal_bridge_width 0.5)
			(island_removal_mode 0)
		)
		(polygon
			(pts
				(xy 289.96259 -347.417136) (xy 289.96259 -348.378018) (xy 290.204906 -348.378018) (xy 290.204906 -347.417136)
			)
		)
	)
	(zone
		(layer "F.Cu")
		(hatch none 0.5)
		(connect_pads
			(clearance 0)
		)
		(min_thickness 0.25)
		(keepout
			(tracks allowed)
			(vias allowed)
			(pads allowed)
			(copperpour allowed)
			(footprints allowed)
		)
		(placement
			(enabled no)
			(sheetname "")
		)
		(fill
			(thermal_gap 0.5)
			(thermal_bridge_width 0.5)
			(island_removal_mode 0)
		)
		(polygon
			(pts
				(xy 58.13044 -204.728064) (xy 58.13044 -204.397864) (xy 60.67044 -204.397864) (xy 60.67044 -204.728064)
			)
		)
	)
	(zone
		(layer "F.Cu")
		(hatch none 0.5)
		(connect_pads
			(clearance 0)
		)
		(min_thickness 0.25)
		(keepout
			(tracks allowed)
			(vias allowed)
			(pads allowed)
			(copperpour allowed)
			(footprints allowed)
		)
		(placement
			(enabled no)
			(sheetname "")
		)
		(fill
			(thermal_gap 0.5)
			(thermal_bridge_width 0.5)
			(island_removal_mode 0)
		)
		(polygon
			(pts
				(xy 163.377626 -241.277902) (xy 163.377626 -240.947702) (xy 165.296596 -240.947702) (xy 165.296596 -241.277902)
			)
		)
	)
	(zone
		(layer "F.Cu")
		(hatch none 0.5)
		(connect_pads
			(clearance 0)
		)
		(min_thickness 0.25)
		(keepout
			(tracks allowed)
			(vias allowed)
			(pads allowed)
			(copperpour allowed)
			(footprints not_allowed)
		)
		(placement
			(enabled no)
			(sheetname "")
		)
		(fill
			(thermal_gap 0.5)
			(thermal_bridge_width 0.5)
			(island_removal_mode 0)
		)
		(polygon
			(pts
				(xy 361.313984 -24.109934) (xy 371.714014 -24.109934) (xy 371.714014 -19.010122) (xy 361.313984 -19.010122)
			)
		)
	)
	(zone
		(layer "F.Cu")
		(hatch none 0.5)
		(connect_pads
			(clearance 0)
		)
		(min_thickness 0.25)
		(keepout
			(tracks allowed)
			(vias allowed)
			(pads allowed)
			(copperpour allowed)
			(footprints not_allowed)
		)
		(placement
			(enabled no)
			(sheetname "")
		)
		(fill
			(thermal_gap 0.5)
			(thermal_bridge_width 0.5)
			(island_removal_mode 0)
		)
		(polygon
			(pts
				(arc
					(start 466.460078 -160.50006)
					(mid 461.460088 -165.50005)
					(end 456.460098 -160.50006)
				)
				(arc
					(start 456.460098 -160.50006)
					(mid 461.460088 -155.50007)
					(end 466.460078 -160.50006)
				)
			)
		)
	)
	(zone
		(layer "F.Cu")
		(hatch none 0.5)
		(connect_pads
			(clearance 0)
		)
		(min_thickness 0.25)
		(keepout
			(tracks allowed)
			(vias allowed)
			(pads allowed)
			(copperpour allowed)
			(footprints allowed)
		)
		(placement
			(enabled no)
			(sheetname "")
		)
		(fill
			(thermal_gap 0.5)
			(thermal_bridge_width 0.5)
			(island_removal_mode 0)
		)
		(polygon
			(pts
				(xy 71.22033 -177.965354) (xy 76.96962 -177.965354) (xy 77.1906 -178.186334) (xy 77.1906 -180.53558)
				(xy 77.76464 -181.10962) (xy 78.4606 -181.10962) (xy 78.60792 -180.9623) (xy 78.60792 -179.72786)
				(xy 78.20533 -179.32527) (xy 78.20533 -177.330354) (xy 78.20533 -172.758354) (xy 77.57033 -172.123354)
				(xy 71.60133 -172.123354) (xy 71.09333 -172.631354) (xy 71.09333 -177.838354)
			)
		)
	)
	(zone
		(layer "F.Cu")
		(hatch none 0.5)
		(connect_pads
			(clearance 0)
		)
		(min_thickness 0.25)
		(keepout
			(tracks allowed)
			(vias allowed)
			(pads allowed)
			(copperpour allowed)
			(footprints not_allowed)
		)
		(placement
			(enabled no)
			(sheetname "")
		)
		(fill
			(thermal_gap 0.5)
			(thermal_bridge_width 0.5)
			(island_removal_mode 0)
		)
		(polygon
			(pts
				(arc
					(start 458.659992 -160.50006)
					(mid 461.460088 -157.699964)
					(end 464.25993 -160.50006)
				)
				(arc
					(start 464.25993 -160.50006)
					(mid 461.460088 -163.299902)
					(end 458.659992 -160.50006)
				)
			)
		)
	)
	(zone
		(layer "F.Cu")
		(hatch none 0.5)
		(connect_pads
			(clearance 0)
		)
		(min_thickness 0.25)
		(keepout
			(tracks allowed)
			(vias allowed)
			(pads allowed)
			(copperpour allowed)
			(footprints allowed)
		)
		(placement
			(enabled no)
			(sheetname "")
		)
		(fill
			(thermal_gap 0.5)
			(thermal_bridge_width 0.5)
			(island_removal_mode 0)
		)
		(polygon
			(pts
				(xy 163.377626 -271.02816) (xy 163.377626 -270.69796) (xy 165.296596 -270.69796) (xy 165.296596 -271.02816)
			)
		)
	)
	(zone
		(layer "F.Cu")
		(hatch none 0.5)
		(connect_pads
			(clearance 0)
		)
		(min_thickness 0.25)
		(keepout
			(tracks allowed)
			(vias allowed)
			(pads allowed)
			(copperpour allowed)
			(footprints not_allowed)
		)
		(placement
			(enabled no)
			(sheetname "")
		)
		(fill
			(thermal_gap 0.5)
			(thermal_bridge_width 0.5)
			(island_removal_mode 0)
		)
		(polygon
			(pts
				(xy 225.320098 -296.720006) (xy 246.720106 -296.720006) (xy 246.720106 -288.120074) (xy 227.320094 -288.120074)
				(xy 227.320094 -286.120078) (xy 225.320098 -286.120078)
			)
		)
	)
	(zone
		(layer "F.Cu")
		(hatch none 0.5)
		(connect_pads
			(clearance 0)
		)
		(min_thickness 0.25)
		(keepout
			(tracks allowed)
			(vias allowed)
			(pads allowed)
			(copperpour allowed)
			(footprints allowed)
		)
		(placement
			(enabled no)
			(sheetname "")
		)
		(fill
			(thermal_gap 0.5)
			(thermal_bridge_width 0.5)
			(island_removal_mode 0)
		)
		(polygon
			(pts
				(xy 21.873464 -332.400402) (xy 21.873464 -331.81163) (xy 22.438106 -331.81163) (xy 22.438106 -332.400402)
			)
		)
	)
	(zone
		(layer "F.Cu")
		(hatch none 0.5)
		(connect_pads
			(clearance 0)
		)
		(min_thickness 0.25)
		(keepout
			(tracks allowed)
			(vias allowed)
			(pads allowed)
			(copperpour allowed)
			(footprints allowed)
		)
		(placement
			(enabled no)
			(sheetname "")
		)
		(fill
			(thermal_gap 0.5)
			(thermal_bridge_width 0.5)
			(island_removal_mode 0)
		)
		(polygon
			(pts
				(xy 65.53327 -30.17266) (xy 65.53327 -28.87345) (xy 66.321178 -28.87345) (xy 66.321178 -30.17266)
			)
		)
	)
	(zone
		(layer "F.Cu")
		(hatch none 0.5)
		(connect_pads
			(clearance 0)
		)
		(min_thickness 0.25)
		(keepout
			(tracks allowed)
			(vias allowed)
			(pads allowed)
			(copperpour allowed)
			(footprints allowed)
		)
		(placement
			(enabled no)
			(sheetname "")
		)
		(fill
			(thermal_gap 0.5)
			(thermal_bridge_width 0.5)
			(island_removal_mode 0)
		)
		(polygon
			(pts
				(xy 332.964028 -379.479302) (xy 332.964028 -378.47524) (xy 334.36052 -378.47524) (xy 334.36052 -379.479302)
			)
		)
	)
	(zone
		(layer "F.Cu")
		(hatch none 0.5)
		(connect_pads
			(clearance 0)
		)
		(min_thickness 0.25)
		(keepout
			(tracks allowed)
			(vias allowed)
			(pads allowed)
			(copperpour allowed)
			(footprints allowed)
		)
		(placement
			(enabled no)
			(sheetname "")
		)
		(fill
			(thermal_gap 0.5)
			(thermal_bridge_width 0.5)
			(island_removal_mode 0)
		)
		(polygon
			(pts
				(xy 306.070508 -223.427798) (xy 306.070508 -223.097598) (xy 308.610508 -223.097598) (xy 308.610508 -223.427798)
			)
		)
	)
	(zone
		(layer "F.Cu")
		(hatch none 0.5)
		(connect_pads
			(clearance 0)
		)
		(min_thickness 0.25)
		(keepout
			(tracks allowed)
			(vias allowed)
			(pads allowed)
			(copperpour allowed)
			(footprints allowed)
		)
		(placement
			(enabled no)
			(sheetname "")
		)
		(fill
			(thermal_gap 0.5)
			(thermal_bridge_width 0.5)
			(island_removal_mode 0)
		)
		(polygon
			(pts
				(xy 115.212876 -75.294236) (xy 115.212876 -72.124316) (xy 116.968016 -72.124316) (xy 116.968016 -75.294236)
			)
		)
	)
	(zone
		(layer "F.Cu")
		(hatch none 0.5)
		(connect_pads
			(clearance 0)
		)
		(min_thickness 0.25)
		(keepout
			(tracks allowed)
			(vias allowed)
			(pads allowed)
			(copperpour allowed)
			(footprints not_allowed)
		)
		(placement
			(enabled no)
			(sheetname "")
		)
		(fill
			(thermal_gap 0.5)
			(thermal_bridge_width 0.5)
			(island_removal_mode 0)
		)
		(polygon
			(pts
				(arc
					(start 86.900004 -22.29993)
					(mid 94.899988 -14.299946)
					(end 102.899972 -22.29993)
				)
				(arc
					(start 102.899972 -22.29993)
					(mid 94.899988 -30.299914)
					(end 86.900004 -22.29993)
				)
			)
		)
	)
	(zone
		(layer "F.Cu")
		(hatch none 0.5)
		(connect_pads
			(clearance 0)
		)
		(min_thickness 0.25)
		(keepout
			(tracks allowed)
			(vias allowed)
			(pads allowed)
			(copperpour allowed)
			(footprints allowed)
		)
		(placement
			(enabled no)
			(sheetname "")
		)
		(fill
			(thermal_gap 0.5)
			(thermal_bridge_width 0.5)
			(island_removal_mode 0)
		)
		(polygon
			(pts
				(xy 337.90382 6.85546) (xy 337.90382 8.92556) (xy 340.24316 8.92556) (xy 340.24316 6.85546)
			)
		)
	)
	(zone
		(layer "F.Cu")
		(hatch none 0.5)
		(connect_pads
			(clearance 0)
		)
		(min_thickness 0.25)
		(keepout
			(tracks allowed)
			(vias allowed)
			(pads allowed)
			(copperpour allowed)
			(footprints allowed)
		)
		(placement
			(enabled no)
			(sheetname "")
		)
		(fill
			(thermal_gap 0.5)
			(thermal_bridge_width 0.5)
			(island_removal_mode 0)
		)
		(polygon
			(pts
				(xy 397.17599 -175.11649) (xy 395.37259 -175.11649) (xy 395.37259 -176.66589) (xy 397.17599 -176.66589)
			)
		)
	)
	(zone
		(layer "F.Cu")
		(hatch none 0.5)
		(connect_pads
			(clearance 0)
		)
		(min_thickness 0.25)
		(keepout
			(tracks allowed)
			(vias allowed)
			(pads allowed)
			(copperpour allowed)
			(footprints not_allowed)
		)
		(placement
			(enabled no)
			(sheetname "")
		)
		(fill
			(thermal_gap 0.5)
			(thermal_bridge_width 0.5)
			(island_removal_mode 0)
		)
		(polygon
			(pts
				(arc
					(start 208.399888 -22.29993)
					(mid 203.399898 -27.29992)
					(end 198.399908 -22.29993)
				)
				(arc
					(start 198.399908 -22.29993)
					(mid 203.399898 -17.29994)
					(end 208.399888 -22.29993)
				)
			)
		)
	)
	(zone
		(layer "F.Cu")
		(hatch none 0.5)
		(connect_pads
			(clearance 0)
		)
		(min_thickness 0.25)
		(keepout
			(tracks not_allowed)
			(vias allowed)
			(pads allowed)
			(copperpour not_allowed)
			(footprints allowed)
		)
		(placement
			(enabled no)
			(sheetname "")
		)
		(fill
			(thermal_gap 0.5)
			(thermal_bridge_width 0.5)
			(island_removal_mode 0)
		)
		(polygon
			(pts
				(arc
					(start 209.650076 -51.999896)
					(mid 204.650086 -56.999886)
					(end 199.650096 -51.999896)
				)
				(arc
					(start 199.650096 -51.999896)
					(mid 204.650086 -46.999906)
					(end 209.650076 -51.999896)
				)
			)
		)
	)
	(zone
		(layer "F.Cu")
		(hatch none 0.5)
		(connect_pads
			(clearance 0)
		)
		(min_thickness 0.25)
		(keepout
			(tracks allowed)
			(vias allowed)
			(pads allowed)
			(copperpour allowed)
			(footprints not_allowed)
		)
		(placement
			(enabled no)
			(sheetname "")
		)
		(fill
			(thermal_gap 0.5)
			(thermal_bridge_width 0.5)
			(island_removal_mode 0)
		)
		(polygon
			(pts
				(arc
					(start 72.633078 -47.049944)
					(mid 70.383146 -49.299876)
					(end 68.13296 -47.049944)
				)
				(arc
					(start 68.13296 -47.049944)
					(mid 70.383146 -44.799758)
					(end 72.633078 -47.049944)
				)
			)
		)
	)
	(zone
		(layer "F.Cu")
		(hatch none 0.5)
		(connect_pads
			(clearance 0)
		)
		(min_thickness 0.25)
		(keepout
			(tracks allowed)
			(vias allowed)
			(pads allowed)
			(copperpour allowed)
			(footprints not_allowed)
		)
		(placement
			(enabled no)
			(sheetname "")
		)
		(fill
			(thermal_gap 0.5)
			(thermal_bridge_width 0.5)
			(island_removal_mode 0)
		)
		(polygon
			(pts
				(xy 192.814194 -375.409968) (xy 192.814194 -390.910064) (xy 198.96582 -390.910064) (xy 198.96582 -375.409968)
			)
		)
	)
	(zone
		(layer "F.Cu")
		(hatch none 0.5)
		(connect_pads
			(clearance 0)
		)
		(min_thickness 0.25)
		(keepout
			(tracks allowed)
			(vias allowed)
			(pads allowed)
			(copperpour allowed)
			(footprints allowed)
		)
		(placement
			(enabled no)
			(sheetname "")
		)
		(fill
			(thermal_gap 0.5)
			(thermal_bridge_width 0.5)
			(island_removal_mode 0)
		)
		(polygon
			(pts
				(xy 14.472158 -391.21334) (xy 16.590518 -391.21334) (xy 16.590518 -394.08862) (xy 14.472158 -394.08862)
				(xy 13.422884 -394.08862) (xy 13.179552 -393.845288) (xy 13.179552 -392.505946) (xy 12.745212 -392.505946)
				(xy 12.637262 -392.397996) (xy 12.637262 -388.64159) (xy 13.186918 -388.091934) (xy 13.774674 -388.091934)
				(xy 14.273022 -388.590282) (xy 14.273022 -391.030714) (xy 14.463776 -391.221468)
			)
		)
	)
	(zone
		(layer "F.Cu")
		(hatch none 0.5)
		(connect_pads
			(clearance 0)
		)
		(min_thickness 0.25)
		(keepout
			(tracks not_allowed)
			(vias allowed)
			(pads allowed)
			(copperpour not_allowed)
			(footprints allowed)
		)
		(placement
			(enabled no)
			(sheetname "")
		)
		(fill
			(thermal_gap 0.5)
			(thermal_bridge_width 0.5)
			(island_removal_mode 0)
		)
		(polygon
			(pts
				(arc
					(start 139.729972 -304.790094)
					(mid 142.530068 -301.989998)
					(end 145.32991 -304.790094)
				)
				(arc
					(start 145.32991 -304.790094)
					(mid 142.530068 -307.589936)
					(end 139.729972 -304.790094)
				)
			)
		)
	)
	(zone
		(layer "F.Cu")
		(hatch none 0.5)
		(connect_pads
			(clearance 0)
		)
		(min_thickness 0.25)
		(keepout
			(tracks allowed)
			(vias allowed)
			(pads allowed)
			(copperpour allowed)
			(footprints allowed)
		)
		(placement
			(enabled no)
			(sheetname "")
		)
		(fill
			(thermal_gap 0.5)
			(thermal_bridge_width 0.5)
			(island_removal_mode 0)
		)
		(polygon
			(pts
				(xy 163.377626 -305.542696) (xy 163.377626 -305.872896) (xy 165.296596 -305.872896) (xy 165.296596 -305.542696)
			)
		)
	)
	(zone
		(layer "F.Cu")
		(hatch none 0.5)
		(connect_pads
			(clearance 0)
		)
		(min_thickness 0.25)
		(keepout
			(tracks not_allowed)
			(vias allowed)
			(pads allowed)
			(copperpour not_allowed)
			(footprints allowed)
		)
		(placement
			(enabled no)
			(sheetname "")
		)
		(fill
			(thermal_gap 0.5)
			(thermal_bridge_width 0.5)
			(island_removal_mode 0)
		)
		(polygon
			(pts
				(arc
					(start 223.330516 -388.161784)
					(mid 225.430588 -386.061712)
					(end 227.530406 -388.161784)
				)
				(arc
					(start 227.530406 -388.161784)
					(mid 225.430588 -390.261602)
					(end 223.330516 -388.161784)
				)
			)
		)
	)
	(zone
		(layer "F.Cu")
		(hatch none 0.5)
		(connect_pads
			(clearance 0)
		)
		(min_thickness 0.25)
		(keepout
			(tracks allowed)
			(vias allowed)
			(pads allowed)
			(copperpour allowed)
			(footprints not_allowed)
		)
		(placement
			(enabled no)
			(sheetname "")
		)
		(fill
			(thermal_gap 0.5)
			(thermal_bridge_width 0.5)
			(island_removal_mode 0)
		)
		(polygon
			(pts
				(arc
					(start 146.029934 -212.989922)
					(mid 142.530068 -216.489788)
					(end 139.029948 -212.989922)
				)
				(arc
					(start 139.029948 -212.989922)
					(mid 142.530068 -209.489802)
					(end 146.029934 -212.989922)
				)
			)
		)
	)
	(zone
		(layer "F.Cu")
		(hatch none 0.5)
		(connect_pads
			(clearance 0)
		)
		(min_thickness 0.25)
		(keepout
			(tracks allowed)
			(vias allowed)
			(pads allowed)
			(copperpour allowed)
			(footprints allowed)
		)
		(placement
			(enabled no)
			(sheetname "")
		)
		(fill
			(thermal_gap 0.5)
			(thermal_bridge_width 0.5)
			(island_removal_mode 0)
		)
		(polygon
			(pts
				(xy 411.317694 -218.327732) (xy 411.317694 -217.997532) (xy 413.236664 -217.997532) (xy 413.236664 -218.327732)
			)
		)
	)
	(zone
		(layer "F.Cu")
		(hatch none 0.5)
		(connect_pads
			(clearance 0)
		)
		(min_thickness 0.25)
		(keepout
			(tracks allowed)
			(vias allowed)
			(pads allowed)
			(copperpour allowed)
			(footprints allowed)
		)
		(placement
			(enabled no)
			(sheetname "")
		)
		(fill
			(thermal_gap 0.5)
			(thermal_bridge_width 0.5)
			(island_removal_mode 0)
		)
		(polygon
			(pts
				(xy 163.377626 -307.242718) (xy 163.377626 -307.572918) (xy 165.296596 -307.572918) (xy 165.296596 -307.242718)
			)
		)
	)
	(zone
		(layer "F.Cu")
		(hatch none 0.5)
		(connect_pads
			(clearance 0)
		)
		(min_thickness 0.25)
		(keepout
			(tracks allowed)
			(vias allowed)
			(pads allowed)
			(copperpour allowed)
			(footprints allowed)
		)
		(placement
			(enabled no)
			(sheetname "")
		)
		(fill
			(thermal_gap 0.5)
			(thermal_bridge_width 0.5)
			(island_removal_mode 0)
		)
		(polygon
			(pts
				(xy 330.96962 -389.607044) (xy 331.973682 -389.607044) (xy 331.973682 -391.003536) (xy 330.96962 -391.003536)
			)
		)
	)
	(zone
		(layer "F.Cu")
		(hatch none 0.5)
		(connect_pads
			(clearance 0)
		)
		(min_thickness 0.25)
		(keepout
			(tracks allowed)
			(vias allowed)
			(pads allowed)
			(copperpour allowed)
			(footprints allowed)
		)
		(placement
			(enabled no)
			(sheetname "")
		)
		(fill
			(thermal_gap 0.5)
			(thermal_bridge_width 0.5)
			(island_removal_mode 0)
		)
		(polygon
			(pts
				(xy 83.771486 -371.097302) (xy 83.771486 -370.09324) (xy 85.167978 -370.09324) (xy 85.167978 -371.097302)
			)
		)
	)
	(zone
		(layer "F.Cu")
		(hatch none 0.5)
		(connect_pads
			(clearance 0)
		)
		(min_thickness 0.25)
		(keepout
			(tracks allowed)
			(vias allowed)
			(pads allowed)
			(copperpour allowed)
			(footprints allowed)
		)
		(placement
			(enabled no)
			(sheetname "")
		)
		(fill
			(thermal_gap 0.5)
			(thermal_bridge_width 0.5)
			(island_removal_mode 0)
		)
		(polygon
			(pts
				(xy 259.38988 -0.77978) (xy 259.38988 1.37922) (xy 261.63778 1.37922) (xy 261.63778 -0.77978)
			)
		)
	)
	(zone
		(layer "F.Cu")
		(hatch none 0.5)
		(connect_pads
			(clearance 0)
		)
		(min_thickness 0.25)
		(keepout
			(tracks allowed)
			(vias allowed)
			(pads allowed)
			(copperpour allowed)
			(footprints allowed)
		)
		(placement
			(enabled no)
			(sheetname "")
		)
		(fill
			(thermal_gap 0.5)
			(thermal_bridge_width 0.5)
			(island_removal_mode 0)
		)
		(polygon
			(pts
				(xy 411.562042 -294.827706) (xy 411.562042 -294.497506) (xy 413.236664 -294.497506) (xy 413.236664 -294.827706)
			)
		)
	)
	(zone
		(layer "F.Cu")
		(hatch none 0.5)
		(connect_pads
			(clearance 0)
		)
		(min_thickness 0.25)
		(keepout
			(tracks allowed)
			(vias allowed)
			(pads allowed)
			(copperpour allowed)
			(footprints allowed)
		)
		(placement
			(enabled no)
			(sheetname "")
		)
		(fill
			(thermal_gap 0.5)
			(thermal_bridge_width 0.5)
			(island_removal_mode 0)
		)
		(polygon
			(pts
				(xy 163.377626 -282.078176) (xy 163.377626 -281.747976) (xy 165.296596 -281.747976) (xy 165.296596 -282.078176)
			)
		)
	)
	(zone
		(layer "F.Cu")
		(hatch none 0.5)
		(connect_pads
			(clearance 0)
		)
		(min_thickness 0.25)
		(keepout
			(tracks allowed)
			(vias allowed)
			(pads allowed)
			(copperpour allowed)
			(footprints not_allowed)
		)
		(placement
			(enabled no)
			(sheetname "")
		)
		(fill
			(thermal_gap 0.5)
			(thermal_bridge_width 0.5)
			(island_removal_mode 0)
		)
		(polygon
			(pts
				(xy 263.347962 -329.060048) (xy 309.568088 -329.060048) (xy 309.568088 -182.060088) (xy 263.347962 -182.060088)
			)
		)
	)
	(zone
		(layer "F.Cu")
		(hatch none 0.5)
		(connect_pads
			(clearance 0)
		)
		(min_thickness 0.25)
		(keepout
			(tracks allowed)
			(vias allowed)
			(pads allowed)
			(copperpour allowed)
			(footprints allowed)
		)
		(placement
			(enabled no)
			(sheetname "")
		)
		(fill
			(thermal_gap 0.5)
			(thermal_bridge_width 0.5)
			(island_removal_mode 0)
		)
		(polygon
			(pts
				(xy 163.377626 -225.977958) (xy 163.377626 -225.647758) (xy 165.296596 -225.647758) (xy 165.296596 -225.977958)
			)
		)
	)
	(zone
		(layer "F.Cu")
		(hatch none 0.5)
		(connect_pads
			(clearance 0)
		)
		(min_thickness 0.25)
		(keepout
			(tracks allowed)
			(vias allowed)
			(pads allowed)
			(copperpour allowed)
			(footprints allowed)
		)
		(placement
			(enabled no)
			(sheetname "")
		)
		(fill
			(thermal_gap 0.5)
			(thermal_bridge_width 0.5)
			(island_removal_mode 0)
		)
		(polygon
			(pts
				(xy 163.621974 -201.32802) (xy 163.621974 -200.99782) (xy 165.296596 -200.99782) (xy 165.296596 -201.32802)
			)
		)
	)
	(zone
		(layer "F.Cu")
		(hatch none 0.5)
		(connect_pads
			(clearance 0)
		)
		(min_thickness 0.25)
		(keepout
			(tracks allowed)
			(vias allowed)
			(pads allowed)
			(copperpour allowed)
			(footprints allowed)
		)
		(placement
			(enabled no)
			(sheetname "")
		)
		(fill
			(thermal_gap 0.5)
			(thermal_bridge_width 0.5)
			(island_removal_mode 0)
		)
		(polygon
			(pts
				(xy 430.116488 -337.610196) (xy 430.116488 -340.404196) (xy 433.824888 -340.404196) (xy 433.824888 -337.610196)
			)
		)
	)
	(zone
		(layer "F.Cu")
		(hatch none 0.5)
		(connect_pads
			(clearance 0)
		)
		(min_thickness 0.25)
		(keepout
			(tracks allowed)
			(vias allowed)
			(pads allowed)
			(copperpour allowed)
			(footprints not_allowed)
		)
		(placement
			(enabled no)
			(sheetname "")
		)
		(fill
			(thermal_gap 0.5)
			(thermal_bridge_width 0.5)
			(island_removal_mode 0)
		)
		(polygon
			(pts
				(arc
					(start 211.399882 -22.29993)
					(mid 203.399898 -30.299914)
					(end 195.399914 -22.29993)
				)
				(arc
					(start 195.399914 -22.29993)
					(mid 203.399898 -14.299946)
					(end 211.399882 -22.29993)
				)
			)
		)
	)
	(zone
		(layer "F.Cu")
		(hatch none 0.5)
		(connect_pads
			(clearance 0)
		)
		(min_thickness 0.25)
		(keepout
			(tracks allowed)
			(vias allowed)
			(pads allowed)
			(copperpour allowed)
			(footprints allowed)
		)
		(placement
			(enabled no)
			(sheetname "")
		)
		(fill
			(thermal_gap 0.5)
			(thermal_bridge_width 0.5)
			(island_removal_mode 0)
		)
		(polygon
			(pts
				(xy 411.562042 -313.527694) (xy 411.562042 -313.197494) (xy 413.236664 -313.197494) (xy 413.236664 -313.527694)
			)
		)
	)
	(zone
		(layer "F.Cu")
		(hatch none 0.5)
		(connect_pads
			(clearance 0)
		)
		(min_thickness 0.25)
		(keepout
			(tracks not_allowed)
			(vias allowed)
			(pads allowed)
			(copperpour not_allowed)
			(footprints allowed)
		)
		(placement
			(enabled no)
			(sheetname "")
		)
		(fill
			(thermal_gap 0.5)
			(thermal_bridge_width 0.5)
			(island_removal_mode 0)
		)
		(polygon
			(pts
				(xy 429.470566 -350.390968) (xy 429.470566 -350.84766) (xy 430.166272 -350.84766) (xy 430.166272 -350.687132)
				(xy 430.725072 -350.687132) (xy 430.725072 -351.093532) (xy 430.166272 -351.093532) (xy 430.166272 -350.87306)
				(xy 429.470566 -350.87306) (xy 429.470566 -351.00006) (xy 429.926242 -351.00006) (xy 429.926242 -351.386648)
				(xy 430.168558 -351.386648) (xy 430.700434 -351.386648) (xy 431.019966 -351.067116) (xy 431.019966 -350.390968)
			)
		)
	)
	(zone
		(layer "F.Cu")
		(hatch none 0.5)
		(connect_pads
			(clearance 0)
		)
		(min_thickness 0.25)
		(keepout
			(tracks allowed)
			(vias allowed)
			(pads allowed)
			(copperpour allowed)
			(footprints allowed)
		)
		(placement
			(enabled no)
			(sheetname "")
		)
		(fill
			(thermal_gap 0.5)
			(thermal_bridge_width 0.5)
			(island_removal_mode 0)
		)
		(polygon
			(pts
				(xy 74.969878 -381.225044) (xy 75.97394 -381.225044) (xy 75.97394 -382.621536) (xy 74.969878 -382.621536)
			)
		)
	)
	(zone
		(layer "F.Cu")
		(hatch none 0.5)
		(connect_pads
			(clearance 0)
		)
		(min_thickness 0.25)
		(keepout
			(tracks not_allowed)
			(vias allowed)
			(pads allowed)
			(copperpour not_allowed)
			(footprints allowed)
		)
		(placement
			(enabled no)
			(sheetname "")
		)
		(fill
			(thermal_gap 0.5)
			(thermal_bridge_width 0.5)
			(island_removal_mode 0)
		)
		(polygon
			(pts
				(arc
					(start 176.950116 -435.600094)
					(mid 179.750212 -432.799998)
					(end 182.550054 -435.600094)
				)
				(arc
					(start 182.550054 -435.600094)
					(mid 179.750212 -438.399936)
					(end 176.950116 -435.600094)
				)
			)
		)
	)
	(zone
		(layer "F.Cu")
		(hatch none 0.5)
		(connect_pads
			(clearance 0)
		)
		(min_thickness 0.25)
		(keepout
			(tracks allowed)
			(vias allowed)
			(pads allowed)
			(copperpour allowed)
			(footprints allowed)
		)
		(placement
			(enabled no)
			(sheetname "")
		)
		(fill
			(thermal_gap 0.5)
			(thermal_bridge_width 0.5)
			(island_removal_mode 0)
		)
		(polygon
			(pts
				(xy 100.789486 -371.097302) (xy 100.789486 -370.09324) (xy 102.185978 -370.09324) (xy 102.185978 -371.097302)
			)
		)
	)
	(zone
		(layer "F.Cu")
		(hatch none 0.5)
		(connect_pads
			(clearance 0)
		)
		(min_thickness 0.25)
		(keepout
			(tracks allowed)
			(vias allowed)
			(pads allowed)
			(copperpour allowed)
			(footprints not_allowed)
		)
		(placement
			(enabled no)
			(sheetname "")
		)
		(fill
			(thermal_gap 0.5)
			(thermal_bridge_width 0.5)
			(island_removal_mode 0)
		)
		(polygon
			(pts
				(arc
					(start 9.970008 -389.439912)
					(mid 6.870192 -392.539728)
					(end 3.770122 -389.439912)
				)
				(arc
					(start 3.770122 -389.439912)
					(mid 6.870192 -386.339842)
					(end 9.970008 -389.439912)
				)
			)
		)
	)
	(zone
		(layer "F.Cu")
		(hatch none 0.5)
		(connect_pads
			(clearance 0)
		)
		(min_thickness 0.25)
		(keepout
			(tracks not_allowed)
			(vias allowed)
			(pads allowed)
			(copperpour not_allowed)
			(footprints allowed)
		)
		(placement
			(enabled no)
			(sheetname "")
		)
		(fill
			(thermal_gap 0.5)
			(thermal_bridge_width 0.5)
			(island_removal_mode 0)
		)
		(polygon
			(pts
				(arc
					(start 72.633078 -47.049944)
					(mid 70.383146 -49.299876)
					(end 68.13296 -47.049944)
				)
				(arc
					(start 68.13296 -47.049944)
					(mid 70.383146 -44.799758)
					(end 72.633078 -47.049944)
				)
			)
		)
	)
	(zone
		(layer "F.Cu")
		(hatch none 0.5)
		(connect_pads
			(clearance 0)
		)
		(min_thickness 0.25)
		(keepout
			(tracks allowed)
			(vias allowed)
			(pads allowed)
			(copperpour allowed)
			(footprints allowed)
		)
		(placement
			(enabled no)
			(sheetname "")
		)
		(fill
			(thermal_gap 0.5)
			(thermal_bridge_width 0.5)
			(island_removal_mode 0)
		)
		(polygon
			(pts
				(xy 319.15608 -381.943102) (xy 319.15608 -380.93904) (xy 320.552572 -380.93904) (xy 320.552572 -381.943102)
			)
		)
	)
	(zone
		(layer "F.Cu")
		(hatch none 0.5)
		(connect_pads
			(clearance 0)
		)
		(min_thickness 0.25)
		(keepout
			(tracks not_allowed)
			(vias allowed)
			(pads allowed)
			(copperpour not_allowed)
			(footprints allowed)
		)
		(placement
			(enabled no)
			(sheetname "")
		)
		(fill
			(thermal_gap 0.5)
			(thermal_bridge_width 0.5)
			(island_removal_mode 0)
		)
		(polygon
			(pts
				(xy 341.347806 -335.723992) (xy 341.347806 -336.684874) (xy 341.590122 -336.684874) (xy 341.590122 -335.723992)
			)
		)
	)
	(zone
		(layer "F.Cu")
		(hatch none 0.5)
		(connect_pads
			(clearance 0)
		)
		(min_thickness 0.25)
		(keepout
			(tracks allowed)
			(vias allowed)
			(pads allowed)
			(copperpour allowed)
			(footprints not_allowed)
		)
		(placement
			(enabled no)
			(sheetname "")
		)
		(fill
			(thermal_gap 0.5)
			(thermal_bridge_width 0.5)
			(island_removal_mode 0)
		)
		(polygon
			(pts
				(arc
					(start 33.005014 -389.439912)
					(mid 34.870136 -387.57479)
					(end 36.735004 -389.439912)
				)
				(arc
					(start 36.735004 -389.439912)
					(mid 34.870136 -391.30478)
					(end 33.005014 -389.439912)
				)
			)
		)
	)
	(zone
		(layer "F.Cu")
		(hatch none 0.5)
		(connect_pads
			(clearance 0)
		)
		(min_thickness 0.25)
		(keepout
			(tracks allowed)
			(vias allowed)
			(pads allowed)
			(copperpour allowed)
			(footprints allowed)
		)
		(placement
			(enabled no)
			(sheetname "")
		)
		(fill
			(thermal_gap 0.5)
			(thermal_bridge_width 0.5)
			(island_removal_mode 0)
		)
		(polygon
			(pts
				(xy 163.377626 -248.928128) (xy 163.377626 -248.597928) (xy 165.296596 -248.597928) (xy 165.296596 -248.928128)
			)
		)
	)
	(zone
		(layer "F.Cu")
		(hatch none 0.5)
		(connect_pads
			(clearance 0)
		)
		(min_thickness 0.25)
		(keepout
			(tracks not_allowed)
			(vias allowed)
			(pads allowed)
			(copperpour not_allowed)
			(footprints allowed)
		)
		(placement
			(enabled no)
			(sheetname "")
		)
		(fill
			(thermal_gap 0.5)
			(thermal_bridge_width 0.5)
			(island_removal_mode 0)
		)
		(polygon
			(pts
				(arc
					(start 327.90003 -160.50006)
					(mid 322.90004 -165.50005)
					(end 317.90005 -160.50006)
				)
				(arc
					(start 317.90005 -160.50006)
					(mid 322.90004 -155.50007)
					(end 327.90003 -160.50006)
				)
			)
		)
	)
	(zone
		(layer "F.Cu")
		(hatch none 0.5)
		(connect_pads
			(clearance 0)
		)
		(min_thickness 0.25)
		(keepout
			(tracks allowed)
			(vias allowed)
			(pads allowed)
			(copperpour allowed)
			(footprints allowed)
		)
		(placement
			(enabled no)
			(sheetname "")
		)
		(fill
			(thermal_gap 0.5)
			(thermal_bridge_width 0.5)
			(island_removal_mode 0)
		)
		(polygon
			(pts
				(xy 365.541814 -384.069844) (xy 366.545876 -384.069844) (xy 366.545876 -385.466336) (xy 365.541814 -385.466336)
			)
		)
	)
	(zone
		(layer "F.Cu")
		(hatch none 0.5)
		(connect_pads
			(clearance 0)
		)
		(min_thickness 0.25)
		(keepout
			(tracks allowed)
			(vias allowed)
			(pads allowed)
			(copperpour allowed)
			(footprints not_allowed)
		)
		(placement
			(enabled no)
			(sheetname "")
		)
		(fill
			(thermal_gap 0.5)
			(thermal_bridge_width 0.5)
			(island_removal_mode 0)
		)
		(polygon
			(pts
				(xy 410.16809 -347.134942) (xy 410.16809 -329.060048) (xy 458.300074 -329.060048)
				(arc
					(start 458.300074 -340.350602)
					(mid 454.938322 -343.066631)
					(end 453.479916 -347.134942)
				)
			)
		)
	)
	(zone
		(layer "F.Cu")
		(hatch none 0.5)
		(connect_pads
			(clearance 0)
		)
		(min_thickness 0.25)
		(keepout
			(tracks not_allowed)
			(vias allowed)
			(pads allowed)
			(copperpour not_allowed)
			(footprints allowed)
		)
		(placement
			(enabled no)
			(sheetname "")
		)
		(fill
			(thermal_gap 0.5)
			(thermal_bridge_width 0.5)
			(island_removal_mode 0)
		)
		(polygon
			(pts
				(xy 349.623634 -340.634066) (xy 349.623634 -341.594948) (xy 349.86595 -341.594948) (xy 349.86595 -340.634066)
			)
		)
	)
	(zone
		(layer "F.Cu")
		(hatch none 0.5)
		(connect_pads
			(clearance 0)
		)
		(min_thickness 0.25)
		(keepout
			(tracks allowed)
			(vias allowed)
			(pads allowed)
			(copperpour allowed)
			(footprints allowed)
		)
		(placement
			(enabled no)
			(sheetname "")
		)
		(fill
			(thermal_gap 0.5)
			(thermal_bridge_width 0.5)
			(island_removal_mode 0)
		)
		(polygon
			(pts
				(xy 361.573318 -178.110896) (xy 367.10112 -178.110896) (xy 367.52784 -178.537616) (xy 367.52784 -180.94706)
				(xy 367.87074 -181.28996) (xy 368.65306 -181.28996) (xy 368.82324 -181.11978) (xy 368.82324 -179.75072)
				(xy 368.558318 -179.485798) (xy 368.558318 -177.475896) (xy 368.558318 -172.903896) (xy 367.923318 -172.268896)
				(xy 361.954318 -172.268896) (xy 361.446318 -172.776896) (xy 361.446318 -177.983896)
			)
		)
	)
	(zone
		(layer "F.Cu")
		(hatch none 0.5)
		(connect_pads
			(clearance 0)
		)
		(min_thickness 0.25)
		(keepout
			(tracks allowed)
			(vias allowed)
			(pads allowed)
			(copperpour allowed)
			(footprints allowed)
		)
		(placement
			(enabled no)
			(sheetname "")
		)
		(fill
			(thermal_gap 0.5)
			(thermal_bridge_width 0.5)
			(island_removal_mode 0)
		)
		(polygon
			(pts
				(xy 56.703468 -409.042616) (xy 56.703468 -408.038554) (xy 58.09996 -408.038554) (xy 58.09996 -409.042616)
			)
		)
	)
	(zone
		(layer "F.Cu")
		(hatch none 0.5)
		(connect_pads
			(clearance 0)
		)
		(min_thickness 0.25)
		(keepout
			(tracks allowed)
			(vias allowed)
			(pads allowed)
			(copperpour allowed)
			(footprints not_allowed)
		)
		(placement
			(enabled no)
			(sheetname "")
		)
		(fill
			(thermal_gap 0.5)
			(thermal_bridge_width 0.5)
			(island_removal_mode 0)
		)
		(polygon
			(pts
				(xy 455.235056 -183.50992) (xy 449.034916 -183.50992) (xy 449.034916 -327.609962) (xy 455.235056 -327.609962)
			)
		)
	)
	(zone
		(layer "F.Cu")
		(hatch none 0.5)
		(connect_pads
			(clearance 0)
		)
		(min_thickness 0.25)
		(keepout
			(tracks allowed)
			(vias allowed)
			(pads allowed)
			(copperpour allowed)
			(footprints allowed)
		)
		(placement
			(enabled no)
			(sheetname "")
		)
		(fill
			(thermal_gap 0.5)
			(thermal_bridge_width 0.5)
			(island_removal_mode 0)
		)
		(polygon
			(pts
				(xy 184.076594 -408.940254) (xy 185.080656 -408.940254) (xy 185.080656 -410.336746) (xy 184.076594 -410.336746)
			)
		)
	)
	(zone
		(layer "F.Cu")
		(hatch none 0.5)
		(connect_pads
			(clearance 0)
		)
		(min_thickness 0.25)
		(keepout
			(tracks allowed)
			(vias allowed)
			(pads allowed)
			(copperpour allowed)
			(footprints not_allowed)
		)
		(placement
			(enabled no)
			(sheetname "")
		)
		(fill
			(thermal_gap 0.5)
			(thermal_bridge_width 0.5)
			(island_removal_mode 0)
		)
		(polygon
			(pts
				(xy 162.228022 -347.544898) (xy 162.228022 -329.060048) (xy 208.447894 -329.060048) (xy 208.447894 -347.544898)
			)
		)
	)
	(zone
		(layer "F.Cu")
		(hatch none 0.5)
		(connect_pads
			(clearance 0)
		)
		(min_thickness 0.25)
		(keepout
			(tracks allowed)
			(vias allowed)
			(pads allowed)
			(copperpour allowed)
			(footprints allowed)
		)
		(placement
			(enabled no)
			(sheetname "")
		)
		(fill
			(thermal_gap 0.5)
			(thermal_bridge_width 0.5)
			(island_removal_mode 0)
		)
		(polygon
			(pts
				(xy 193.987166 -350.981264) (xy 187.637166 -350.981264) (xy 187.002166 -351.616264) (xy 187.002166 -356.188264)
				(xy 187.637166 -356.823264) (xy 193.606166 -356.823264) (xy 194.114166 -356.315264) (xy 194.114166 -351.108264)
			)
		)
	)
	(zone
		(layer "F.Cu")
		(hatch none 0.5)
		(connect_pads
			(clearance 0)
		)
		(min_thickness 0.25)
		(keepout
			(tracks allowed)
			(vias allowed)
			(pads allowed)
			(copperpour allowed)
			(footprints allowed)
		)
		(placement
			(enabled no)
			(sheetname "")
		)
		(fill
			(thermal_gap 0.5)
			(thermal_bridge_width 0.5)
			(island_removal_mode 0)
		)
		(polygon
			(pts
				(xy 378.953522 -195.358512) (xy 378.953522 -197.263512) (xy 382.966722 -197.263512) (xy 382.966722 -195.358512)
			)
		)
	)
	(zone
		(layer "F.Cu")
		(hatch none 0.5)
		(connect_pads
			(clearance 0)
		)
		(min_thickness 0.25)
		(keepout
			(tracks allowed)
			(vias allowed)
			(pads allowed)
			(copperpour allowed)
			(footprints not_allowed)
		)
		(placement
			(enabled no)
			(sheetname "")
		)
		(fill
			(thermal_gap 0.5)
			(thermal_bridge_width 0.5)
			(island_removal_mode 0)
		)
		(polygon
			(pts
				(arc
					(start 447.250058 -435.600094)
					(mid 448.799966 -434.050186)
					(end 450.349874 -435.600094)
				)
				(arc
					(start 450.349874 -435.600094)
					(mid 448.799966 -437.150002)
					(end 447.250058 -435.600094)
				)
			)
		)
	)
	(zone
		(layer "F.Cu")
		(hatch none 0.5)
		(connect_pads
			(clearance 0)
		)
		(min_thickness 0.25)
		(keepout
			(tracks allowed)
			(vias allowed)
			(pads allowed)
			(copperpour allowed)
			(footprints allowed)
		)
		(placement
			(enabled no)
			(sheetname "")
		)
		(fill
			(thermal_gap 0.5)
			(thermal_bridge_width 0.5)
			(island_removal_mode 0)
		)
		(polygon
			(pts
				(xy 59.80811 -332.20152) (xy 59.80811 -334.10652) (xy 63.82131 -334.10652) (xy 63.82131 -332.20152)
			)
		)
	)
	(zone
		(layer "F.Cu")
		(hatch none 0.5)
		(connect_pads
			(clearance 0)
		)
		(min_thickness 0.25)
		(keepout
			(tracks allowed)
			(vias allowed)
			(pads allowed)
			(copperpour allowed)
			(footprints allowed)
		)
		(placement
			(enabled no)
			(sheetname "")
		)
		(fill
			(thermal_gap 0.5)
			(thermal_bridge_width 0.5)
			(island_removal_mode 0)
		)
		(polygon
			(pts
				(xy 163.377626 -265.928094) (xy 163.377626 -265.597894) (xy 165.296596 -265.597894) (xy 165.296596 -265.928094)
			)
		)
	)
	(zone
		(layer "F.Cu")
		(hatch none 0.5)
		(connect_pads
			(clearance 0)
		)
		(min_thickness 0.25)
		(keepout
			(tracks not_allowed)
			(vias allowed)
			(pads allowed)
			(copperpour not_allowed)
			(footprints allowed)
		)
		(placement
			(enabled no)
			(sheetname "")
		)
		(fill
			(thermal_gap 0.5)
			(thermal_bridge_width 0.5)
			(island_removal_mode 0)
		)
		(polygon
			(pts
				(arc
					(start 361.362498 -431.360072)
					(mid 359.774998 -432.947572)
					(end 358.187498 -431.360072)
				)
				(arc
					(start 358.187498 -431.360072)
					(mid 359.774998 -429.772572)
					(end 361.362498 -431.360072)
				)
			)
		)
	)
	(zone
		(layer "F.Cu")
		(hatch none 0.5)
		(connect_pads
			(clearance 0)
		)
		(min_thickness 0.25)
		(keepout
			(tracks allowed)
			(vias allowed)
			(pads allowed)
			(copperpour allowed)
			(footprints allowed)
		)
		(placement
			(enabled no)
			(sheetname "")
		)
		(fill
			(thermal_gap 0.5)
			(thermal_bridge_width 0.5)
			(island_removal_mode 0)
		)
		(polygon
			(pts
				(xy 109.542072 -375.687844) (xy 110.546134 -375.687844) (xy 110.546134 -377.084336) (xy 109.542072 -377.084336)
			)
		)
	)
	(zone
		(layer "F.Cu")
		(hatch none 0.5)
		(connect_pads
			(clearance 0)
		)
		(min_thickness 0.25)
		(keepout
			(tracks allowed)
			(vias allowed)
			(pads allowed)
			(copperpour allowed)
			(footprints allowed)
		)
		(placement
			(enabled no)
			(sheetname "")
		)
		(fill
			(thermal_gap 0.5)
			(thermal_bridge_width 0.5)
			(island_removal_mode 0)
		)
		(polygon
			(pts
				(xy 411.317694 -266.777978) (xy 411.317694 -266.447778) (xy 413.236664 -266.447778) (xy 413.236664 -266.777978)
			)
		)
	)
	(zone
		(layer "F.Cu")
		(hatch none 0.5)
		(connect_pads
			(clearance 0)
		)
		(min_thickness 0.25)
		(keepout
			(tracks allowed)
			(vias allowed)
			(pads allowed)
			(copperpour allowed)
			(footprints allowed)
		)
		(placement
			(enabled no)
			(sheetname "")
		)
		(fill
			(thermal_gap 0.5)
			(thermal_bridge_width 0.5)
			(island_removal_mode 0)
		)
		(polygon
			(pts
				(xy 64.999362 -166.873936) (xy 63.195962 -166.873936) (xy 63.195962 -168.423336) (xy 64.999362 -168.423336)
			)
		)
	)
	(zone
		(layer "F.Cu")
		(hatch none 0.5)
		(connect_pads
			(clearance 0)
		)
		(min_thickness 0.25)
		(keepout
			(tracks allowed)
			(vias allowed)
			(pads allowed)
			(copperpour allowed)
			(footprints allowed)
		)
		(placement
			(enabled no)
			(sheetname "")
		)
		(fill
			(thermal_gap 0.5)
			(thermal_bridge_width 0.5)
			(island_removal_mode 0)
		)
		(polygon
			(pts
				(xy 411.317694 -277.49246) (xy 411.317694 -277.82266) (xy 413.236664 -277.82266) (xy 413.236664 -277.49246)
			)
		)
	)
	(zone
		(layer "F.Cu")
		(hatch none 0.5)
		(connect_pads
			(clearance 0)
		)
		(min_thickness 0.25)
		(keepout
			(tracks allowed)
			(vias allowed)
			(pads allowed)
			(copperpour allowed)
			(footprints not_allowed)
		)
		(placement
			(enabled no)
			(sheetname "")
		)
		(fill
			(thermal_gap 0.5)
			(thermal_bridge_width 0.5)
			(island_removal_mode 0)
		)
		(polygon
			(pts
				(arc
					(start 363.024928 -431.360072)
					(mid 359.774998 -434.610002)
					(end 356.525068 -431.360072)
				)
				(arc
					(start 356.525068 -431.360072)
					(mid 359.774998 -428.110142)
					(end 363.024928 -431.360072)
				)
			)
		)
	)
	(zone
		(layer "F.Cu")
		(hatch none 0.5)
		(connect_pads
			(clearance 0)
		)
		(min_thickness 0.25)
		(keepout
			(tracks allowed)
			(vias allowed)
			(pads allowed)
			(copperpour allowed)
			(footprints not_allowed)
		)
		(placement
			(enabled no)
			(sheetname "")
		)
		(fill
			(thermal_gap 0.5)
			(thermal_bridge_width 0.5)
			(island_removal_mode 0)
		)
		(polygon
			(pts
				(arc
					(start 45.569886 -404.789894)
					(mid 41.569894 -408.789886)
					(end 37.569902 -404.789894)
				)
				(arc
					(start 37.569902 -404.789894)
					(mid 41.569894 -400.789902)
					(end 45.569886 -404.789894)
				)
			)
		)
	)
	(zone
		(layer "F.Cu")
		(hatch none 0.5)
		(connect_pads
			(clearance 0)
		)
		(min_thickness 0.25)
		(keepout
			(tracks not_allowed)
			(vias allowed)
			(pads allowed)
			(copperpour not_allowed)
			(footprints allowed)
		)
		(placement
			(enabled no)
			(sheetname "")
		)
		(fill
			(thermal_gap 0.5)
			(thermal_bridge_width 0.5)
			(island_removal_mode 0)
		)
		(polygon
			(pts
				(xy 134.468616 -155.831032) (xy 134.468616 -154.87015) (xy 134.2263 -154.87015) (xy 134.2263 -155.831032)
			)
		)
	)
	(zone
		(layer "F.Cu")
		(hatch none 0.5)
		(connect_pads
			(clearance 0)
		)
		(min_thickness 0.25)
		(keepout
			(tracks allowed)
			(vias allowed)
			(pads allowed)
			(copperpour allowed)
			(footprints not_allowed)
		)
		(placement
			(enabled no)
			(sheetname "")
		)
		(fill
			(thermal_gap 0.5)
			(thermal_bridge_width 0.5)
			(island_removal_mode 0)
		)
		(polygon
			(pts
				(xy 468.342726 -91.764104) (xy 468.342726 -81.77403) (xy 437.30164 -81.77403) (xy 437.30164 -87.286084)
				(xy 416.301682 -87.286084) (xy 416.301682 -81.77403) (xy 303.500028 -81.77403) (xy 303.500028 -87.286084)
				(xy 282.50007 -87.286084) (xy 282.50007 -81.77403) (xy 250.001024 -81.77403) (xy 250.001024 -91.764104)
			)
		)
	)
	(zone
		(layer "F.Cu")
		(hatch none 0.5)
		(connect_pads
			(clearance 0)
		)
		(min_thickness 0.25)
		(keepout
			(tracks not_allowed)
			(vias allowed)
			(pads allowed)
			(copperpour not_allowed)
			(footprints allowed)
		)
		(placement
			(enabled no)
			(sheetname "")
		)
		(fill
			(thermal_gap 0.5)
			(thermal_bridge_width 0.5)
			(island_removal_mode 0)
		)
		(polygon
			(pts
				(arc
					(start 220.03512 -290.900104)
					(mid 221.900242 -289.034982)
					(end 223.76511 -290.900104)
				)
				(arc
					(start 223.76511 -290.900104)
					(mid 221.900242 -292.764972)
					(end 220.03512 -290.900104)
				)
			)
		)
	)
	(zone
		(layer "F.Cu")
		(hatch none 0.5)
		(connect_pads
			(clearance 0)
		)
		(min_thickness 0.25)
		(keepout
			(tracks allowed)
			(vias allowed)
			(pads allowed)
			(copperpour allowed)
			(footprints allowed)
		)
		(placement
			(enabled no)
			(sheetname "")
		)
		(fill
			(thermal_gap 0.5)
			(thermal_bridge_width 0.5)
			(island_removal_mode 0)
		)
		(polygon
			(pts
				(xy 163.621974 -238.727996) (xy 163.621974 -238.397796) (xy 165.296596 -238.397796) (xy 165.296596 -238.727996)
			)
		)
	)
	(zone
		(layer "F.Cu")
		(hatch none 0.5)
		(connect_pads
			(clearance 0)
		)
		(min_thickness 0.25)
		(keepout
			(tracks allowed)
			(vias allowed)
			(pads allowed)
			(copperpour allowed)
			(footprints allowed)
		)
		(placement
			(enabled no)
			(sheetname "")
		)
		(fill
			(thermal_gap 0.5)
			(thermal_bridge_width 0.5)
			(island_removal_mode 0)
		)
		(polygon
			(pts
				(xy 75.082908 -409.042616) (xy 75.082908 -408.038554) (xy 76.4794 -408.038554) (xy 76.4794 -409.042616)
			)
		)
	)
	(zone
		(layer "F.Cu")
		(hatch none 0.5)
		(connect_pads
			(clearance 0)
		)
		(min_thickness 0.25)
		(keepout
			(tracks not_allowed)
			(vias allowed)
			(pads allowed)
			(copperpour not_allowed)
			(footprints allowed)
		)
		(placement
			(enabled no)
			(sheetname "")
		)
		(fill
			(thermal_gap 0.5)
			(thermal_bridge_width 0.5)
			(island_removal_mode 0)
		)
		(polygon
			(pts
				(arc
					(start 67.030092 -258.890008)
					(mid 69.830188 -256.089912)
					(end 72.63003 -258.890008)
				)
				(arc
					(start 72.63003 -258.890008)
					(mid 69.830188 -261.68985)
					(end 67.030092 -258.890008)
				)
			)
		)
	)
	(zone
		(layer "F.Cu")
		(hatch none 0.5)
		(connect_pads
			(clearance 0)
		)
		(min_thickness 0.25)
		(keepout
			(tracks allowed)
			(vias allowed)
			(pads allowed)
			(copperpour allowed)
			(footprints allowed)
		)
		(placement
			(enabled no)
			(sheetname "")
		)
		(fill
			(thermal_gap 0.5)
			(thermal_bridge_width 0.5)
			(island_removal_mode 0)
		)
		(polygon
			(pts
				(xy 23.834344 -41.436798) (xy 23.834344 -38.75151) (xy 26.507186 -38.75151) (xy 26.507186 -41.436798)
			)
		)
	)
	(zone
		(layer "F.Cu")
		(hatch none 0.5)
		(connect_pads
			(clearance 0)
		)
		(min_thickness 0.25)
		(keepout
			(tracks allowed)
			(vias allowed)
			(pads allowed)
			(copperpour allowed)
			(footprints not_allowed)
		)
		(placement
			(enabled no)
			(sheetname "")
		)
		(fill
			(thermal_gap 0.5)
			(thermal_bridge_width 0.5)
			(island_removal_mode 0)
		)
		(polygon
			(pts
				(arc
					(start 204.186028 -351.825052)
					(mid 201.085958 -354.925122)
					(end 197.985888 -351.825052)
				)
				(arc
					(start 197.985888 -351.825052)
					(mid 201.085958 -348.724982)
					(end 204.186028 -351.825052)
				)
			)
		)
	)
	(zone
		(layer "F.Cu")
		(hatch none 0.5)
		(connect_pads
			(clearance 0)
		)
		(min_thickness 0.25)
		(keepout
			(tracks not_allowed)
			(vias allowed)
			(pads allowed)
			(copperpour not_allowed)
			(footprints allowed)
		)
		(placement
			(enabled no)
			(sheetname "")
		)
		(fill
			(thermal_gap 0.5)
			(thermal_bridge_width 0.5)
			(island_removal_mode 0)
		)
		(polygon
			(pts
				(xy 168.758108 -53.410104) (xy 170.358308 -53.410104) (xy 170.409108 -53.359304) (xy 170.409108 -53.240178)
				(xy 170.358308 -53.189378) (xy 168.758108 -53.189378) (xy 168.707308 -53.240178) (xy 168.707308 -53.359304)
			)
		)
	)
	(zone
		(layer "F.Cu")
		(hatch none 0.5)
		(connect_pads
			(clearance 0)
		)
		(min_thickness 0.25)
		(keepout
			(tracks not_allowed)
			(vias allowed)
			(pads allowed)
			(copperpour not_allowed)
			(footprints allowed)
		)
		(placement
			(enabled no)
			(sheetname "")
		)
		(fill
			(thermal_gap 0.5)
			(thermal_bridge_width 0.5)
			(island_removal_mode 0)
		)
		(polygon
			(pts
				(arc
					(start 184.75198 -66.06794)
					(mid 178.86299 -60.17895)
					(end 172.974 -66.06794)
				)
				(arc
					(start 172.974 -74.767948)
					(mid 178.86299 -80.656938)
					(end 184.75198 -74.767948)
				)
			)
		)
	)
	(zone
		(layer "F.Cu")
		(hatch none 0.5)
		(connect_pads
			(clearance 0)
		)
		(min_thickness 0.25)
		(keepout
			(tracks not_allowed)
			(vias allowed)
			(pads allowed)
			(copperpour not_allowed)
			(footprints allowed)
		)
		(placement
			(enabled no)
			(sheetname "")
		)
		(fill
			(thermal_gap 0.5)
			(thermal_bridge_width 0.5)
			(island_removal_mode 0)
		)
		(polygon
			(pts
				(xy 189.20206 -352.020886) (xy 189.20206 -352.981768) (xy 189.444376 -352.981768) (xy 189.444376 -352.020886)
			)
		)
	)
	(zone
		(layer "F.Cu")
		(hatch none 0.5)
		(connect_pads
			(clearance 0)
		)
		(min_thickness 0.25)
		(keepout
			(tracks allowed)
			(vias allowed)
			(pads allowed)
			(copperpour allowed)
			(footprints allowed)
		)
		(placement
			(enabled no)
			(sheetname "")
		)
		(fill
			(thermal_gap 0.5)
			(thermal_bridge_width 0.5)
			(island_removal_mode 0)
		)
		(polygon
			(pts
				(xy 310.64708 -384.406902) (xy 310.64708 -383.40284) (xy 312.043572 -383.40284) (xy 312.043572 -384.406902)
			)
		)
	)
	(zone
		(layer "F.Cu")
		(hatch none 0.5)
		(connect_pads
			(clearance 0)
		)
		(min_thickness 0.25)
		(keepout
			(tracks allowed)
			(vias allowed)
			(pads allowed)
			(copperpour allowed)
			(footprints allowed)
		)
		(placement
			(enabled no)
			(sheetname "")
		)
		(fill
			(thermal_gap 0.5)
			(thermal_bridge_width 0.5)
			(island_removal_mode 0)
		)
		(polygon
			(pts
				(xy 306.070508 -269.327884) (xy 306.070508 -268.997684) (xy 308.610508 -268.997684) (xy 308.610508 -269.327884)
			)
		)
	)
	(zone
		(layer "F.Cu")
		(hatch none 0.5)
		(connect_pads
			(clearance 0)
		)
		(min_thickness 0.25)
		(keepout
			(tracks not_allowed)
			(vias allowed)
			(pads allowed)
			(copperpour not_allowed)
			(footprints allowed)
		)
		(placement
			(enabled no)
			(sheetname "")
		)
		(fill
			(thermal_gap 0.5)
			(thermal_bridge_width 0.5)
			(island_removal_mode 0)
		)
		(polygon
			(pts
				(xy 316.303406 -335.694782) (xy 316.303406 -336.655664) (xy 316.545722 -336.655664) (xy 316.545722 -335.694782)
			)
		)
	)
	(zone
		(layer "F.Cu")
		(hatch none 0.5)
		(connect_pads
			(clearance 0)
		)
		(min_thickness 0.25)
		(keepout
			(tracks not_allowed)
			(vias allowed)
			(pads allowed)
			(copperpour not_allowed)
			(footprints allowed)
		)
		(placement
			(enabled no)
			(sheetname "")
		)
		(fill
			(thermal_gap 0.5)
			(thermal_bridge_width 0.5)
			(island_removal_mode 0)
		)
		(polygon
			(pts
				(arc
					(start 115.816126 -340.315042)
					(mid 112.716056 -343.415112)
					(end 109.615986 -340.315042)
				)
				(arc
					(start 109.615986 -340.315042)
					(mid 112.716056 -337.214972)
					(end 115.816126 -340.315042)
				)
			)
		)
	)
	(zone
		(layer "F.Cu")
		(hatch none 0.5)
		(connect_pads
			(clearance 0)
		)
		(min_thickness 0.25)
		(keepout
			(tracks allowed)
			(vias allowed)
			(pads allowed)
			(copperpour allowed)
			(footprints not_allowed)
		)
		(placement
			(enabled no)
			(sheetname "")
		)
		(fill
			(thermal_gap 0.5)
			(thermal_bridge_width 0.5)
			(island_removal_mode 0)
		)
		(polygon
			(pts
				(arc
					(start 217.674952 -360.764074)
					(mid 213.67496 -364.764066)
					(end 209.674968 -360.764074)
				)
				(arc
					(start 209.674968 -360.764074)
					(mid 213.67496 -356.764082)
					(end 217.674952 -360.764074)
				)
			)
		)
	)
	(zone
		(layer "F.Cu")
		(hatch none 0.5)
		(connect_pads
			(clearance 0)
		)
		(min_thickness 0.25)
		(keepout
			(tracks allowed)
			(vias allowed)
			(pads allowed)
			(copperpour allowed)
			(footprints allowed)
		)
		(placement
			(enabled no)
			(sheetname "")
		)
		(fill
			(thermal_gap 0.5)
			(thermal_bridge_width 0.5)
			(island_removal_mode 0)
		)
		(polygon
			(pts
				(xy 337.99526 -0.66802) (xy 337.99526 1.40208) (xy 340.3092 1.40208) (xy 340.3092 -0.66802)
			)
		)
	)
	(zone
		(layer "F.Cu")
		(hatch none 0.5)
		(connect_pads
			(clearance 0)
		)
		(min_thickness 0.25)
		(keepout
			(tracks allowed)
			(vias allowed)
			(pads allowed)
			(copperpour allowed)
			(footprints not_allowed)
		)
		(placement
			(enabled no)
			(sheetname "")
		)
		(fill
			(thermal_gap 0.5)
			(thermal_bridge_width 0.5)
			(island_removal_mode 0)
		)
		(polygon
			(pts
				(xy 55.559198 -81.77403) (xy 55.562246 -62.01283) (xy 168.364408 -62.01283) (xy 168.362376 -81.77403)
			)
		)
	)
	(zone
		(layer "F.Cu")
		(hatch none 0.5)
		(connect_pads
			(clearance 0)
		)
		(min_thickness 0.25)
		(keepout
			(tracks allowed)
			(vias allowed)
			(pads allowed)
			(copperpour allowed)
			(footprints not_allowed)
		)
		(placement
			(enabled no)
			(sheetname "")
		)
		(fill
			(thermal_gap 0.5)
			(thermal_bridge_width 0.5)
			(island_removal_mode 0)
		)
		(polygon
			(pts
				(xy 54.274974 -183.50992) (xy 54.274974 -327.609962) (xy 60.475114 -327.609962) (xy 60.475114 -183.50992)
			)
		)
	)
	(zone
		(layer "F.Cu")
		(hatch none 0.5)
		(connect_pads
			(clearance 0)
		)
		(min_thickness 0.25)
		(keepout
			(tracks allowed)
			(vias allowed)
			(pads allowed)
			(copperpour allowed)
			(footprints allowed)
		)
		(placement
			(enabled no)
			(sheetname "")
		)
		(fill
			(thermal_gap 0.5)
			(thermal_bridge_width 0.5)
			(island_removal_mode 0)
		)
		(polygon
			(pts
				(xy 126.86665 -409.042616) (xy 126.86665 -408.038554) (xy 128.263142 -408.038554) (xy 128.263142 -409.042616)
			)
		)
	)
	(zone
		(layer "F.Cu")
		(hatch none 0.5)
		(connect_pads
			(clearance 0)
		)
		(min_thickness 0.25)
		(keepout
			(tracks allowed)
			(vias allowed)
			(pads allowed)
			(copperpour allowed)
			(footprints allowed)
		)
		(placement
			(enabled no)
			(sheetname "")
		)
		(fill
			(thermal_gap 0.5)
			(thermal_bridge_width 0.5)
			(island_removal_mode 0)
		)
		(polygon
			(pts
				(xy 438.924192 -169.636186) (xy 438.924192 -168.203372) (xy 439.745628 -168.203372) (xy 439.745628 -169.636186)
			)
		)
	)
	(zone
		(layer "F.Cu")
		(hatch none 0.5)
		(connect_pads
			(clearance 0)
		)
		(min_thickness 0.25)
		(keepout
			(tracks not_allowed)
			(vias allowed)
			(pads allowed)
			(copperpour not_allowed)
			(footprints allowed)
		)
		(placement
			(enabled no)
			(sheetname "")
		)
		(fill
			(thermal_gap 0.5)
			(thermal_bridge_width 0.5)
			(island_removal_mode 0)
		)
		(polygon
			(pts
				(arc
					(start 399.16989 -258.890008)
					(mid 401.969986 -256.089912)
					(end 404.770082 -258.890008)
				)
				(arc
					(start 404.770082 -258.890008)
					(mid 401.969986 -261.690104)
					(end 399.16989 -258.890008)
				)
			)
		)
	)
	(zone
		(layer "F.Cu")
		(hatch none 0.5)
		(connect_pads
			(clearance 0)
		)
		(min_thickness 0.25)
		(keepout
			(tracks allowed)
			(vias allowed)
			(pads allowed)
			(copperpour allowed)
			(footprints not_allowed)
		)
		(placement
			(enabled no)
			(sheetname "")
		)
		(fill
			(thermal_gap 0.5)
			(thermal_bridge_width 0.5)
			(island_removal_mode 0)
		)
		(polygon
			(pts
				(xy 440.146948 -183.50992) (xy 433.947062 -183.50992) (xy 433.947062 -327.609962) (xy 440.146948 -327.609962)
			)
		)
	)
	(zone
		(layer "F.Cu")
		(hatch none 0.5)
		(connect_pads
			(clearance 0)
		)
		(min_thickness 0.25)
		(keepout
			(tracks not_allowed)
			(vias allowed)
			(pads allowed)
			(copperpour not_allowed)
			(footprints allowed)
		)
		(placement
			(enabled no)
			(sheetname "")
		)
		(fill
			(thermal_gap 0.5)
			(thermal_bridge_width 0.5)
			(island_removal_mode 0)
		)
		(polygon
			(pts
				(xy 76.264516 -334.24368) (xy 76.264516 -334.700372) (xy 76.960222 -334.700372) (xy 76.960222 -334.539844)
				(xy 77.519022 -334.539844) (xy 77.519022 -334.946244) (xy 76.960222 -334.946244) (xy 76.960222 -334.725772)
				(xy 76.264516 -334.725772) (xy 76.264516 -334.852772) (xy 76.720192 -334.852772) (xy 76.720192 -335.23936)
				(xy 76.962508 -335.23936) (xy 77.494384 -335.23936) (xy 77.813916 -334.919828) (xy 77.813916 -334.24368)
			)
		)
	)
	(zone
		(layer "F.Cu")
		(hatch none 0.5)
		(connect_pads
			(clearance 0)
		)
		(min_thickness 0.25)
		(keepout
			(tracks allowed)
			(vias allowed)
			(pads allowed)
			(copperpour allowed)
			(footprints not_allowed)
		)
		(placement
			(enabled no)
			(sheetname "")
		)
		(fill
			(thermal_gap 0.5)
			(thermal_bridge_width 0.5)
			(island_removal_mode 0)
		)
		(polygon
			(pts
				(xy 2.999994 -394.759942) (xy 10.290048 -394.759942) (xy 10.290048 -385.160012) (xy 2.999994 -385.160012)
			)
		)
	)
	(zone
		(layer "F.Cu")
		(hatch none 0.5)
		(connect_pads
			(clearance 0)
		)
		(min_thickness 0.25)
		(keepout
			(tracks allowed)
			(vias allowed)
			(pads allowed)
			(copperpour allowed)
			(footprints allowed)
		)
		(placement
			(enabled no)
			(sheetname "")
		)
		(fill
			(thermal_gap 0.5)
			(thermal_bridge_width 0.5)
			(island_removal_mode 0)
		)
		(polygon
			(pts
				(xy 331.16647 -320.45402) (xy 331.16647 -322.35902) (xy 335.17967 -322.35902) (xy 335.17967 -320.45402)
			)
		)
	)
	(zone
		(layer "F.Cu")
		(hatch none 0.5)
		(connect_pads
			(clearance 0)
		)
		(min_thickness 0.25)
		(keepout
			(tracks allowed)
			(vias allowed)
			(pads allowed)
			(copperpour allowed)
			(footprints allowed)
		)
		(placement
			(enabled no)
			(sheetname "")
		)
		(fill
			(thermal_gap 0.5)
			(thermal_bridge_width 0.5)
			(island_removal_mode 0)
		)
		(polygon
			(pts
				(xy 377.747022 -384.406902) (xy 377.747022 -383.40284) (xy 379.143514 -383.40284) (xy 379.143514 -384.406902)
			)
		)
	)
	(zone
		(layer "F.Cu")
		(hatch none 0.5)
		(connect_pads
			(clearance 0)
		)
		(min_thickness 0.25)
		(keepout
			(tracks allowed)
			(vias allowed)
			(pads allowed)
			(copperpour allowed)
			(footprints allowed)
		)
		(placement
			(enabled no)
			(sheetname "")
		)
		(fill
			(thermal_gap 0.5)
			(thermal_bridge_width 0.5)
			(island_removal_mode 0)
		)
		(polygon
			(pts
				(xy 351.683828 -381.943102) (xy 351.683828 -380.93904) (xy 353.08032 -380.93904) (xy 353.08032 -381.943102)
			)
		)
	)
	(zone
		(layer "F.Cu")
		(hatch none 0.5)
		(connect_pads
			(clearance 0)
		)
		(min_thickness 0.25)
		(keepout
			(tracks allowed)
			(vias allowed)
			(pads allowed)
			(copperpour allowed)
			(footprints allowed)
		)
		(placement
			(enabled no)
			(sheetname "")
		)
		(fill
			(thermal_gap 0.5)
			(thermal_bridge_width 0.5)
			(island_removal_mode 0)
		)
		(polygon
			(pts
				(xy 124.731272 -55.537862) (xy 123.558808 -55.537862) (xy 123.558808 -54.105048) (xy 124.731272 -54.105048)
			)
		)
	)
	(zone
		(layer "F.Cu")
		(hatch none 0.5)
		(connect_pads
			(clearance 0)
		)
		(min_thickness 0.25)
		(keepout
			(tracks allowed)
			(vias allowed)
			(pads allowed)
			(copperpour allowed)
			(footprints not_allowed)
		)
		(placement
			(enabled no)
			(sheetname "")
		)
		(fill
			(thermal_gap 0.5)
			(thermal_bridge_width 0.5)
			(island_removal_mode 0)
		)
		(polygon
			(pts
				(xy 294.971978 -45.2501) (xy 294.971978 -22.750018) (xy 270.771874 -22.750018) (xy 270.771874 -45.2501)
			)
		)
	)
	(zone
		(layer "F.Cu")
		(hatch none 0.5)
		(connect_pads
			(clearance 0)
		)
		(min_thickness 0.25)
		(keepout
			(tracks not_allowed)
			(vias allowed)
			(pads allowed)
			(copperpour not_allowed)
			(footprints allowed)
		)
		(placement
			(enabled no)
			(sheetname "")
		)
		(fill
			(thermal_gap 0.5)
			(thermal_bridge_width 0.5)
			(island_removal_mode 0)
		)
		(polygon
			(pts
				(xy 190.7032 -17.324578) (xy 190.820548 -17.324578) (xy 190.871348 -17.273778) (xy 190.871348 -15.825978)
				(xy 190.820548 -15.775178) (xy 190.7032 -15.775178) (xy 190.6524 -15.825978) (xy 190.6524 -17.273778)
			)
		)
	)
	(zone
		(layer "F.Cu")
		(hatch none 0.5)
		(connect_pads
			(clearance 0)
		)
		(min_thickness 0.25)
		(keepout
			(tracks not_allowed)
			(vias allowed)
			(pads allowed)
			(copperpour not_allowed)
			(footprints allowed)
		)
		(placement
			(enabled no)
			(sheetname "")
		)
		(fill
			(thermal_gap 0.5)
			(thermal_bridge_width 0.5)
			(island_removal_mode 0)
		)
		(polygon
			(pts
				(xy 440.008264 -9.094724) (xy 440.125612 -9.094724) (xy 440.176412 -9.043924) (xy 440.176412 -7.596124)
				(xy 440.125612 -7.545324) (xy 440.008264 -7.545324) (xy 439.957464 -7.596124) (xy 439.957464 -9.043924)
			)
		)
	)
	(zone
		(layer "F.Cu")
		(hatch none 0.5)
		(connect_pads
			(clearance 0)
		)
		(min_thickness 0.25)
		(keepout
			(tracks allowed)
			(vias allowed)
			(pads allowed)
			(copperpour allowed)
			(footprints allowed)
		)
		(placement
			(enabled no)
			(sheetname "")
		)
		(fill
			(thermal_gap 0.5)
			(thermal_bridge_width 0.5)
			(island_removal_mode 0)
		)
		(polygon
			(pts
				(xy 163.377626 -199.627998) (xy 163.377626 -199.297798) (xy 165.296596 -199.297798) (xy 165.296596 -199.627998)
			)
		)
	)
	(zone
		(layer "F.Cu")
		(hatch none 0.5)
		(connect_pads
			(clearance 0)
		)
		(min_thickness 0.25)
		(keepout
			(tracks not_allowed)
			(vias allowed)
			(pads allowed)
			(copperpour not_allowed)
			(footprints allowed)
		)
		(placement
			(enabled no)
			(sheetname "")
		)
		(fill
			(thermal_gap 0.5)
			(thermal_bridge_width 0.5)
			(island_removal_mode 0)
		)
		(polygon
			(pts
				(arc
					(start 217.674952 -360.764074)
					(mid 213.67496 -364.764066)
					(end 209.674968 -360.764074)
				)
				(arc
					(start 209.674968 -360.764074)
					(mid 213.67496 -356.764082)
					(end 217.674952 -360.764074)
				)
			)
		)
	)
	(zone
		(layer "F.Cu")
		(hatch none 0.5)
		(connect_pads
			(clearance 0)
		)
		(min_thickness 0.25)
		(keepout
			(tracks allowed)
			(vias allowed)
			(pads allowed)
			(copperpour allowed)
			(footprints allowed)
		)
		(placement
			(enabled no)
			(sheetname "")
		)
		(fill
			(thermal_gap 0.5)
			(thermal_bridge_width 0.5)
			(island_removal_mode 0)
		)
		(polygon
			(pts
				(xy 104.71531 -178.511454) (xy 111.06531 -178.511454) (xy 111.70031 -177.876454) (xy 111.70031 -173.304454)
				(xy 111.06531 -172.669454) (xy 105.09631 -172.669454) (xy 104.58831 -173.177454) (xy 104.58831 -178.384454)
			)
		)
	)
	(zone
		(layer "F.Cu")
		(hatch none 0.5)
		(connect_pads
			(clearance 0)
		)
		(min_thickness 0.25)
		(keepout
			(tracks allowed)
			(vias allowed)
			(pads allowed)
			(copperpour allowed)
			(footprints allowed)
		)
		(placement
			(enabled no)
			(sheetname "")
		)
		(fill
			(thermal_gap 0.5)
			(thermal_bridge_width 0.5)
			(island_removal_mode 0)
		)
		(polygon
			(pts
				(xy 209.6135 -5.98932) (xy 209.6135 -3.7846) (xy 211.8614 -3.7846) (xy 211.8614 -5.98932)
			)
		)
	)
	(zone
		(layer "F.Cu")
		(hatch none 0.5)
		(connect_pads
			(clearance 0)
		)
		(min_thickness 0.25)
		(keepout
			(tracks allowed)
			(vias allowed)
			(pads allowed)
			(copperpour allowed)
			(footprints not_allowed)
		)
		(placement
			(enabled no)
			(sheetname "")
		)
		(fill
			(thermal_gap 0.5)
			(thermal_bridge_width 0.5)
			(island_removal_mode 0)
		)
		(polygon
			(pts
				(arc
					(start 433.574952 -399.029936)
					(mid 435.440074 -397.164814)
					(end 437.304942 -399.029936)
				)
				(arc
					(start 437.304942 -399.029936)
					(mid 435.440074 -400.894804)
					(end 433.574952 -399.029936)
				)
			)
		)
	)
	(zone
		(layer "F.Cu")
		(hatch none 0.5)
		(connect_pads
			(clearance 0)
		)
		(min_thickness 0.25)
		(keepout
			(tracks not_allowed)
			(vias allowed)
			(pads allowed)
			(copperpour not_allowed)
			(footprints allowed)
		)
		(placement
			(enabled no)
			(sheetname "")
		)
		(fill
			(thermal_gap 0.5)
			(thermal_bridge_width 0.5)
			(island_removal_mode 0)
		)
		(polygon
			(pts
				(xy 340.89213 -334.274668) (xy 340.89213 -334.73136) (xy 341.587836 -334.73136) (xy 341.587836 -334.570832)
				(xy 342.146636 -334.570832) (xy 342.146636 -334.977232) (xy 341.587836 -334.977232) (xy 341.587836 -334.75676)
				(xy 340.89213 -334.75676) (xy 340.89213 -334.88376) (xy 341.347806 -334.88376) (xy 341.347806 -335.270348)
				(xy 341.590122 -335.270348) (xy 342.121998 -335.270348) (xy 342.44153 -334.950816) (xy 342.44153 -334.274668)
			)
		)
	)
	(zone
		(layer "F.Cu")
		(hatch none 0.5)
		(connect_pads
			(clearance 0)
		)
		(min_thickness 0.25)
		(keepout
			(tracks allowed)
			(vias allowed)
			(pads allowed)
			(copperpour allowed)
			(footprints not_allowed)
		)
		(placement
			(enabled no)
			(sheetname "")
		)
		(fill
			(thermal_gap 0.5)
			(thermal_bridge_width 0.5)
			(island_removal_mode 0)
		)
		(polygon
			(pts
				(xy 393.759944 -403.260052) (xy 398.789906 -403.260052) (xy 398.789906 -398.560036) (xy 393.759944 -398.560036)
			)
		)
	)
	(zone
		(layer "F.Cu")
		(hatch none 0.5)
		(connect_pads
			(clearance 0)
		)
		(min_thickness 0.25)
		(keepout
			(tracks allowed)
			(vias allowed)
			(pads allowed)
			(copperpour allowed)
			(footprints allowed)
		)
		(placement
			(enabled no)
			(sheetname "")
		)
		(fill
			(thermal_gap 0.5)
			(thermal_bridge_width 0.5)
			(island_removal_mode 0)
		)
		(polygon
			(pts
				(xy 308.28488 -218.84259) (xy 308.28488 -219.17279) (xy 305.74488 -219.17279) (xy 305.74488 -218.84259)
			)
		)
	)
	(zone
		(layer "F.Cu")
		(hatch none 0.5)
		(connect_pads
			(clearance 0)
		)
		(min_thickness 0.25)
		(keepout
			(tracks not_allowed)
			(vias allowed)
			(pads allowed)
			(copperpour not_allowed)
			(footprints allowed)
		)
		(placement
			(enabled no)
			(sheetname "")
		)
		(fill
			(thermal_gap 0.5)
			(thermal_bridge_width 0.5)
			(island_removal_mode 0)
		)
		(polygon
			(pts
				(arc
					(start 433.574952 -399.029936)
					(mid 435.440074 -397.164814)
					(end 437.304942 -399.029936)
				)
				(arc
					(start 437.304942 -399.029936)
					(mid 435.440074 -400.894804)
					(end 433.574952 -399.029936)
				)
			)
		)
	)
	(zone
		(layer "F.Cu")
		(hatch none 0.5)
		(connect_pads
			(clearance 0)
		)
		(min_thickness 0.25)
		(keepout
			(tracks allowed)
			(vias allowed)
			(pads allowed)
			(copperpour allowed)
			(footprints allowed)
		)
		(placement
			(enabled no)
			(sheetname "")
		)
		(fill
			(thermal_gap 0.5)
			(thermal_bridge_width 0.5)
			(island_removal_mode 0)
		)
		(polygon
			(pts
				(xy 276.985222 -347.221556) (xy 275.181822 -347.221556) (xy 275.181822 -348.770956) (xy 276.985222 -348.770956)
			)
		)
	)
	(zone
		(layer "F.Cu")
		(hatch none 0.5)
		(connect_pads
			(clearance 0)
		)
		(min_thickness 0.25)
		(keepout
			(tracks not_allowed)
			(vias allowed)
			(pads allowed)
			(copperpour not_allowed)
			(footprints allowed)
		)
		(placement
			(enabled no)
			(sheetname "")
		)
		(fill
			(thermal_gap 0.5)
			(thermal_bridge_width 0.5)
			(island_removal_mode 0)
		)
		(polygon
			(pts
				(arc
					(start 97.700338 -435.600094)
					(mid 100.500434 -432.799998)
					(end 103.300276 -435.600094)
				)
				(arc
					(start 103.300276 -435.600094)
					(mid 100.500434 -438.399936)
					(end 97.700338 -435.600094)
				)
			)
		)
	)
	(zone
		(layer "F.Cu")
		(hatch none 0.5)
		(connect_pads
			(clearance 0)
		)
		(min_thickness 0.25)
		(keepout
			(tracks allowed)
			(vias allowed)
			(pads allowed)
			(copperpour allowed)
			(footprints allowed)
		)
		(placement
			(enabled no)
			(sheetname "")
		)
		(fill
			(thermal_gap 0.5)
			(thermal_bridge_width 0.5)
			(island_removal_mode 0)
		)
		(polygon
			(pts
				(xy 60.725812 -297.042586) (xy 60.725812 -297.372786) (xy 58.185812 -297.372786) (xy 58.185812 -297.042586)
			)
		)
	)
	(zone
		(layer "F.Cu")
		(hatch none 0.5)
		(connect_pads
			(clearance 0)
		)
		(min_thickness 0.25)
		(keepout
			(tracks allowed)
			(vias allowed)
			(pads allowed)
			(copperpour allowed)
			(footprints allowed)
		)
		(placement
			(enabled no)
			(sheetname "")
		)
		(fill
			(thermal_gap 0.5)
			(thermal_bridge_width 0.5)
			(island_removal_mode 0)
		)
		(polygon
			(pts
				(xy 164.485828 -371.097302) (xy 164.485828 -370.09324) (xy 165.88232 -370.09324) (xy 165.88232 -371.097302)
			)
		)
	)
	(zone
		(layer "F.Cu")
		(hatch none 0.5)
		(connect_pads
			(clearance 0)
		)
		(min_thickness 0.25)
		(keepout
			(tracks not_allowed)
			(vias allowed)
			(pads allowed)
			(copperpour not_allowed)
			(footprints allowed)
		)
		(placement
			(enabled no)
			(sheetname "")
		)
		(fill
			(thermal_gap 0.5)
			(thermal_bridge_width 0.5)
			(island_removal_mode 0)
		)
		(polygon
			(pts
				(arc
					(start 94.383098 -45.449998)
					(mid 95.983044 -47.049944)
					(end 94.383098 -48.64989)
				)
				(arc
					(start 92.782898 -48.64989)
					(mid 91.182952 -47.049944)
					(end 92.782898 -45.449998)
				)
			)
		)
	)
	(zone
		(layer "F.Cu")
		(hatch none 0.5)
		(connect_pads
			(clearance 0)
		)
		(min_thickness 0.25)
		(keepout
			(tracks allowed)
			(vias allowed)
			(pads allowed)
			(copperpour allowed)
			(footprints allowed)
		)
		(placement
			(enabled no)
			(sheetname "")
		)
		(fill
			(thermal_gap 0.5)
			(thermal_bridge_width 0.5)
			(island_removal_mode 0)
		)
		(polygon
			(pts
				(xy 101.74351 -375.812812) (xy 102.747572 -375.812812) (xy 102.747572 -377.209304) (xy 101.74351 -377.209304)
			)
		)
	)
	(zone
		(layer "F.Cu")
		(hatch none 0.5)
		(connect_pads
			(clearance 0)
		)
		(min_thickness 0.25)
		(keepout
			(tracks allowed)
			(vias allowed)
			(pads allowed)
			(copperpour allowed)
			(footprints allowed)
		)
		(placement
			(enabled no)
			(sheetname "")
		)
		(fill
			(thermal_gap 0.5)
			(thermal_bridge_width 0.5)
			(island_removal_mode 0)
		)
		(polygon
			(pts
				(xy 16.38173 -191.385444) (xy 16.38173 -319.663064) (xy 60.725812 -319.663064) (xy 60.725812 -191.385444)
			)
		)
	)
	(zone
		(layer "F.Cu")
		(hatch none 0.5)
		(connect_pads
			(clearance 0)
		)
		(min_thickness 0.25)
		(keepout
			(tracks allowed)
			(vias allowed)
			(pads allowed)
			(copperpour allowed)
			(footprints not_allowed)
		)
		(placement
			(enabled no)
			(sheetname "")
		)
		(fill
			(thermal_gap 0.5)
			(thermal_bridge_width 0.5)
			(island_removal_mode 0)
		)
		(polygon
			(pts
				(arc
					(start 8.01624 -435.550056)
					(mid 13.01623 -430.550066)
					(end 18.01622 -435.550056)
				)
				(arc
					(start 18.01622 -435.550056)
					(mid 13.01623 -440.550046)
					(end 8.01624 -435.550056)
				)
			)
		)
	)
	(zone
		(layer "F.Cu")
		(hatch none 0.5)
		(connect_pads
			(clearance 0)
		)
		(min_thickness 0.25)
		(keepout
			(tracks allowed)
			(vias allowed)
			(pads allowed)
			(copperpour allowed)
			(footprints allowed)
		)
		(placement
			(enabled no)
			(sheetname "")
		)
		(fill
			(thermal_gap 0.5)
			(thermal_bridge_width 0.5)
			(island_removal_mode 0)
		)
		(polygon
			(pts
				(xy 154.275028 -376.024902) (xy 154.275028 -375.02084) (xy 155.67152 -375.02084) (xy 155.67152 -376.024902)
			)
		)
	)
	(zone
		(layer "F.Cu")
		(hatch none 0.5)
		(connect_pads
			(clearance 0)
		)
		(min_thickness 0.25)
		(keepout
			(tracks allowed)
			(vias allowed)
			(pads allowed)
			(copperpour allowed)
			(footprints allowed)
		)
		(placement
			(enabled no)
			(sheetname "")
		)
		(fill
			(thermal_gap 0.5)
			(thermal_bridge_width 0.5)
			(island_removal_mode 0)
		)
		(polygon
			(pts
				(xy 367.536222 -379.479302) (xy 367.536222 -378.47524) (xy 368.932714 -378.47524) (xy 368.932714 -379.479302)
			)
		)
	)
	(zone
		(layer "F.Cu")
		(hatch none 0.5)
		(connect_pads
			(clearance 0)
		)
		(min_thickness 0.25)
		(keepout
			(tracks allowed)
			(vias allowed)
			(pads allowed)
			(copperpour allowed)
			(footprints allowed)
		)
		(placement
			(enabled no)
			(sheetname "")
		)
		(fill
			(thermal_gap 0.5)
			(thermal_bridge_width 0.5)
			(island_removal_mode 0)
		)
		(polygon
			(pts
				(xy 325.700136 -104.920034) (xy 325.700136 -102.234746) (xy 328.372978 -102.234746) (xy 328.372978 -104.920034)
			)
		)
	)
	(zone
		(layer "F.Cu")
		(hatch none 0.5)
		(connect_pads
			(clearance 0)
		)
		(min_thickness 0.25)
		(keepout
			(tracks allowed)
			(vias allowed)
			(pads allowed)
			(copperpour allowed)
			(footprints allowed)
		)
		(placement
			(enabled no)
			(sheetname "")
		)
		(fill
			(thermal_gap 0.5)
			(thermal_bridge_width 0.5)
			(island_removal_mode 0)
		)
		(polygon
			(pts
				(xy 18.21942 -405.694642) (xy 18.21942 -407.123392) (xy 18.962878 -407.86685) (xy 18.962878 -409.170124)
				(xy 18.209006 -409.923996) (xy 17.646904 -409.923996) (xy 17.519142 -409.796234) (xy 17.519142 -408.036776)
				(xy 15.694406 -408.036776) (xy 15.56639 -407.90876) (xy 15.56639 -407.496264) (xy 15.219172 -407.149046)
				(xy 15.219172 -406.026874) (xy 15.551404 -405.694642) (xy 15.879318 -405.694642)
			)
		)
	)
	(zone
		(layer "F.Cu")
		(hatch none 0.5)
		(connect_pads
			(clearance 0)
		)
		(min_thickness 0.25)
		(keepout
			(tracks allowed)
			(vias allowed)
			(pads allowed)
			(copperpour allowed)
			(footprints not_allowed)
		)
		(placement
			(enabled no)
			(sheetname "")
		)
		(fill
			(thermal_gap 0.5)
			(thermal_bridge_width 0.5)
			(island_removal_mode 0)
		)
		(polygon
			(pts
				(xy 300.870874 -183.50992) (xy 294.670988 -183.50992) (xy 294.670988 -327.609962) (xy 300.870874 -327.609962)
			)
		)
	)
	(zone
		(layer "F.Cu")
		(hatch none 0.5)
		(connect_pads
			(clearance 0)
		)
		(min_thickness 0.25)
		(keepout
			(tracks not_allowed)
			(vias allowed)
			(pads allowed)
			(copperpour not_allowed)
			(footprints allowed)
		)
		(placement
			(enabled no)
			(sheetname "")
		)
		(fill
			(thermal_gap 0.5)
			(thermal_bridge_width 0.5)
			(island_removal_mode 0)
		)
		(polygon
			(pts
				(arc
					(start 172.900086 -160.50006)
					(mid 167.900096 -165.50005)
					(end 162.900106 -160.50006)
				)
				(arc
					(start 162.900106 -160.50006)
					(mid 167.900096 -155.50007)
					(end 172.900086 -160.50006)
				)
			)
		)
	)
	(zone
		(layer "F.Cu")
		(hatch none 0.5)
		(connect_pads
			(clearance 0)
		)
		(min_thickness 0.25)
		(keepout
			(tracks allowed)
			(vias allowed)
			(pads allowed)
			(copperpour allowed)
			(footprints not_allowed)
		)
		(placement
			(enabled no)
			(sheetname "")
		)
		(fill
			(thermal_gap 0.5)
			(thermal_bridge_width 0.5)
			(island_removal_mode 0)
		)
		(polygon
			(pts
				(xy 221.861126 -91.764104) (xy 221.861126 -144.808448) (xy 204.455776 -144.808448) (xy 204.456284 -139.282678)
				(xy 183.456326 -139.280646) (xy 183.455818 -144.808448) (xy 137.196068 -144.808448) (xy 137.196068 -141.865096)
				(xy 129.09677 -141.865096) (xy 129.09677 -144.808448) (xy 40.45585 -144.808448) (xy 40.456358 -139.26566)
				(xy 19.4564 -139.284964) (xy 19.455638 -144.808448) (xy 2.999994 -144.808448) (xy 2.999994 -91.764104)
			)
		)
	)
	(zone
		(layer "F.Cu")
		(hatch none 0.5)
		(connect_pads
			(clearance 0)
		)
		(min_thickness 0.25)
		(keepout
			(tracks allowed)
			(vias allowed)
			(pads allowed)
			(copperpour allowed)
			(footprints allowed)
		)
		(placement
			(enabled no)
			(sheetname "")
		)
		(fill
			(thermal_gap 0.5)
			(thermal_bridge_width 0.5)
			(island_removal_mode 0)
		)
		(polygon
			(pts
				(xy 220.9292 -191.5414) (xy 220.9292 -189.9666) (xy 221.7928 -189.9666) (xy 221.7928 -191.5414)
			)
		)
	)
	(zone
		(layer "F.Cu")
		(hatch none 0.5)
		(connect_pads
			(clearance 0)
		)
		(min_thickness 0.25)
		(keepout
			(tracks allowed)
			(vias allowed)
			(pads allowed)
			(copperpour allowed)
			(footprints allowed)
		)
		(placement
			(enabled no)
			(sheetname "")
		)
		(fill
			(thermal_gap 0.5)
			(thermal_bridge_width 0.5)
			(island_removal_mode 0)
		)
		(polygon
			(pts
				(xy 286.498792 -425.188126) (xy 287.67405 -425.188126) (xy 287.67405 -426.15231) (xy 286.498792 -426.15231)
			)
		)
	)
	(zone
		(layer "F.Cu")
		(hatch none 0.5)
		(connect_pads
			(clearance 0)
		)
		(min_thickness 0.25)
		(keepout
			(tracks allowed)
			(vias allowed)
			(pads allowed)
			(copperpour allowed)
			(footprints allowed)
		)
		(placement
			(enabled no)
			(sheetname "")
		)
		(fill
			(thermal_gap 0.5)
			(thermal_bridge_width 0.5)
			(island_removal_mode 0)
		)
		(polygon
			(pts
				(xy 61.41466 -30.52318) (xy 63.44158 -30.52318) (xy 64.2874 -29.67736) (xy 69.81444 -29.67736) (xy 69.99732 -29.49448)
				(xy 69.99732 -25.4) (xy 69.2023 -24.60498) (xy 66.82232 -24.60498) (xy 66.82232 -22.95398) (xy 67.23888 -22.53742)
				(xy 67.23888 -21.56206) (xy 66.78422 -21.1074) (xy 64.01562 -21.1074) (xy 60.26912 -24.8539) (xy 60.26912 -29.37764)
			)
		)
	)
	(zone
		(layer "F.Cu")
		(hatch none 0.5)
		(connect_pads
			(clearance 0)
		)
		(min_thickness 0.25)
		(keepout
			(tracks allowed)
			(vias allowed)
			(pads allowed)
			(copperpour allowed)
			(footprints allowed)
		)
		(placement
			(enabled no)
			(sheetname "")
		)
		(fill
			(thermal_gap 0.5)
			(thermal_bridge_width 0.5)
			(island_removal_mode 0)
		)
		(polygon
			(pts
				(xy 372.641622 -381.943102) (xy 372.641622 -380.93904) (xy 374.038114 -380.93904) (xy 374.038114 -381.943102)
			)
		)
	)
	(zone
		(layer "F.Cu")
		(hatch none 0.5)
		(connect_pads
			(clearance 0)
		)
		(min_thickness 0.25)
		(keepout
			(tracks not_allowed)
			(vias allowed)
			(pads allowed)
			(copperpour not_allowed)
			(footprints allowed)
		)
		(placement
			(enabled no)
			(sheetname "")
		)
		(fill
			(thermal_gap 0.5)
			(thermal_bridge_width 0.5)
			(island_removal_mode 0)
		)
		(polygon
			(pts
				(xy 408.192224 -167.893746) (xy 408.192224 -166.932864) (xy 407.949908 -166.932864) (xy 407.949908 -167.893746)
			)
		)
	)
	(zone
		(layer "F.Cu")
		(hatch none 0.5)
		(connect_pads
			(clearance 0)
		)
		(min_thickness 0.25)
		(keepout
			(tracks allowed)
			(vias allowed)
			(pads allowed)
			(copperpour allowed)
			(footprints allowed)
		)
		(placement
			(enabled no)
			(sheetname "")
		)
		(fill
			(thermal_gap 0.5)
			(thermal_bridge_width 0.5)
			(island_removal_mode 0)
		)
		(polygon
			(pts
				(xy 97.385886 -371.097302) (xy 97.385886 -370.09324) (xy 98.782378 -370.09324) (xy 98.782378 -371.097302)
			)
		)
	)
	(zone
		(layer "F.Cu")
		(hatch none 0.5)
		(connect_pads
			(clearance 0)
		)
		(min_thickness 0.25)
		(keepout
			(tracks allowed)
			(vias allowed)
			(pads allowed)
			(copperpour allowed)
			(footprints allowed)
		)
		(placement
			(enabled no)
			(sheetname "")
		)
		(fill
			(thermal_gap 0.5)
			(thermal_bridge_width 0.5)
			(island_removal_mode 0)
		)
		(polygon
			(pts
				(xy 102.753922 -33.267904) (xy 102.753922 -31.769304) (xy 103.388922 -31.769304) (xy 103.388922 -33.267904)
			)
		)
	)
	(zone
		(layer "F.Cu")
		(hatch none 0.5)
		(connect_pads
			(clearance 0)
		)
		(min_thickness 0.25)
		(keepout
			(tracks allowed)
			(vias allowed)
			(pads allowed)
			(copperpour allowed)
			(footprints allowed)
		)
		(placement
			(enabled no)
			(sheetname "")
		)
		(fill
			(thermal_gap 0.5)
			(thermal_bridge_width 0.5)
			(island_removal_mode 0)
		)
		(polygon
			(pts
				(xy 411.317694 -241.277648) (xy 411.317694 -240.947448) (xy 413.236664 -240.947448) (xy 413.236664 -241.277648)
			)
		)
	)
	(zone
		(layer "F.Cu")
		(hatch none 0.5)
		(connect_pads
			(clearance 0)
		)
		(min_thickness 0.25)
		(keepout
			(tracks not_allowed)
			(vias allowed)
			(pads allowed)
			(copperpour not_allowed)
			(footprints allowed)
		)
		(placement
			(enabled no)
			(sheetname "")
		)
		(fill
			(thermal_gap 0.5)
			(thermal_bridge_width 0.5)
			(island_removal_mode 0)
		)
		(polygon
			(pts
				(arc
					(start 131.021074 -146.84502)
					(mid 132.886196 -144.979898)
					(end 134.751064 -146.84502)
				)
				(arc
					(start 134.751064 -146.84502)
					(mid 132.886196 -148.709888)
					(end 131.021074 -146.84502)
				)
			)
		)
	)
	(zone
		(layer "F.Cu")
		(hatch none 0.5)
		(connect_pads
			(clearance 0)
		)
		(min_thickness 0.25)
		(keepout
			(tracks allowed)
			(vias allowed)
			(pads allowed)
			(copperpour allowed)
			(footprints not_allowed)
		)
		(placement
			(enabled no)
			(sheetname "")
		)
		(fill
			(thermal_gap 0.5)
			(thermal_bridge_width 0.5)
			(island_removal_mode 0)
		)
		(polygon
			(pts
				(arc
					(start 173.500034 -376.489976)
					(mid 177.500026 -372.489984)
					(end 181.500018 -376.489976)
				)
				(arc
					(start 181.500018 -376.489976)
					(mid 177.500026 -380.489968)
					(end 173.500034 -376.489976)
				)
			)
		)
	)
	(zone
		(layer "F.Cu")
		(hatch none 0.5)
		(connect_pads
			(clearance 0)
		)
		(min_thickness 0.25)
		(keepout
			(tracks allowed)
			(vias allowed)
			(pads allowed)
			(copperpour allowed)
			(footprints not_allowed)
		)
		(placement
			(enabled no)
			(sheetname "")
		)
		(fill
			(thermal_gap 0.5)
			(thermal_bridge_width 0.5)
			(island_removal_mode 0)
		)
		(polygon
			(pts
				(arc
					(start 469.799924 -22.29993)
					(mid 464.799934 -27.29992)
					(end 459.799944 -22.29993)
				)
				(arc
					(start 459.799944 -22.29993)
					(mid 464.799934 -17.29994)
					(end 469.799924 -22.29993)
				)
			)
		)
	)
	(zone
		(layer "F.Cu")
		(hatch none 0.5)
		(connect_pads
			(clearance 0)
		)
		(min_thickness 0.25)
		(keepout
			(tracks not_allowed)
			(vias allowed)
			(pads allowed)
			(copperpour not_allowed)
			(footprints allowed)
		)
		(placement
			(enabled no)
			(sheetname "")
		)
		(fill
			(thermal_gap 0.5)
			(thermal_bridge_width 0.5)
			(island_removal_mode 0)
		)
		(polygon
			(pts
				(arc
					(start 139.729972 -212.989922)
					(mid 142.530068 -210.189826)
					(end 145.32991 -212.989922)
				)
				(arc
					(start 145.32991 -212.989922)
					(mid 142.530068 -215.789764)
					(end 139.729972 -212.989922)
				)
			)
		)
	)
	(zone
		(layer "F.Cu")
		(hatch none 0.5)
		(connect_pads
			(clearance 0)
		)
		(min_thickness 0.25)
		(keepout
			(tracks allowed)
			(vias allowed)
			(pads allowed)
			(copperpour allowed)
			(footprints not_allowed)
		)
		(placement
			(enabled no)
			(sheetname "")
		)
		(fill
			(thermal_gap 0.5)
			(thermal_bridge_width 0.5)
			(island_removal_mode 0)
		)
		(polygon
			(pts
				(xy 31.690056 -394.759942) (xy 39.990014 -394.759942) (xy 39.990014 -385.160012) (xy 31.690056 -385.160012)
			)
		)
	)
	(zone
		(layer "F.Cu")
		(hatch none 0.5)
		(connect_pads
			(clearance 0)
		)
		(min_thickness 0.25)
		(keepout
			(tracks allowed)
			(vias allowed)
			(pads allowed)
			(copperpour allowed)
			(footprints allowed)
		)
		(placement
			(enabled no)
			(sheetname "")
		)
		(fill
			(thermal_gap 0.5)
			(thermal_bridge_width 0.5)
			(island_removal_mode 0)
		)
		(polygon
			(pts
				(xy 163.377626 -197.927976) (xy 163.377626 -197.597776) (xy 165.296596 -197.597776) (xy 165.296596 -197.927976)
			)
		)
	)
	(zone
		(layer "F.Cu")
		(hatch none 0.5)
		(connect_pads
			(clearance 0)
		)
		(min_thickness 0.25)
		(keepout
			(tracks allowed)
			(vias allowed)
			(pads allowed)
			(copperpour allowed)
			(footprints not_allowed)
		)
		(placement
			(enabled no)
			(sheetname "")
		)
		(fill
			(thermal_gap 0.5)
			(thermal_bridge_width 0.5)
			(island_removal_mode 0)
		)
		(polygon
			(pts
				(xy 409.571952 -356.735126) (xy 417.24199 -356.735126) (xy 417.24199 -347.134942) (xy 409.571952 -347.134942)
			)
		)
	)
	(zone
		(layer "F.Cu")
		(hatch none 0.5)
		(connect_pads
			(clearance 0)
		)
		(min_thickness 0.25)
		(keepout
			(tracks allowed)
			(vias allowed)
			(pads allowed)
			(copperpour allowed)
			(footprints allowed)
		)
		(placement
			(enabled no)
			(sheetname "")
		)
		(fill
			(thermal_gap 0.5)
			(thermal_bridge_width 0.5)
			(island_removal_mode 0)
		)
		(polygon
			(pts
				(xy 95.684086 -373.561102) (xy 95.684086 -372.55704) (xy 97.080578 -372.55704) (xy 97.080578 -373.561102)
			)
		)
	)
	(zone
		(layer "F.Cu")
		(hatch none 0.5)
		(connect_pads
			(clearance 0)
		)
		(min_thickness 0.25)
		(keepout
			(tracks allowed)
			(vias allowed)
			(pads allowed)
			(copperpour allowed)
			(footprints allowed)
		)
		(placement
			(enabled no)
			(sheetname "")
		)
		(fill
			(thermal_gap 0.5)
			(thermal_bridge_width 0.5)
			(island_removal_mode 0)
		)
		(polygon
			(pts
				(xy 411.574996 -209.827876) (xy 411.574996 -209.497676) (xy 413.236664 -209.497676) (xy 413.236664 -209.827876)
			)
		)
	)
	(zone
		(layer "F.Cu")
		(hatch none 0.5)
		(connect_pads
			(clearance 0)
		)
		(min_thickness 0.25)
		(keepout
			(tracks allowed)
			(vias allowed)
			(pads allowed)
			(copperpour allowed)
			(footprints allowed)
		)
		(placement
			(enabled no)
			(sheetname "")
		)
		(fill
			(thermal_gap 0.5)
			(thermal_bridge_width 0.5)
			(island_removal_mode 0)
		)
		(polygon
			(pts
				(xy 421.78986 -337.584796) (xy 421.78986 -340.378796) (xy 425.49826 -340.378796) (xy 425.49826 -337.584796)
			)
		)
	)
	(zone
		(layer "F.Cu")
		(hatch none 0.5)
		(connect_pads
			(clearance 0)
		)
		(min_thickness 0.25)
		(keepout
			(tracks allowed)
			(vias allowed)
			(pads allowed)
			(copperpour allowed)
			(footprints allowed)
		)
		(placement
			(enabled no)
			(sheetname "")
		)
		(fill
			(thermal_gap 0.5)
			(thermal_bridge_width 0.5)
			(island_removal_mode 0)
		)
		(polygon
			(pts
				(xy 50.576988 -409.042616) (xy 50.576988 -408.038554) (xy 51.97348 -408.038554) (xy 51.97348 -409.042616)
			)
		)
	)
	(zone
		(layer "F.Cu")
		(hatch none 0.5)
		(connect_pads
			(clearance 0)
		)
		(min_thickness 0.25)
		(keepout
			(tracks allowed)
			(vias allowed)
			(pads allowed)
			(copperpour allowed)
			(footprints allowed)
		)
		(placement
			(enabled no)
			(sheetname "")
		)
		(fill
			(thermal_gap 0.5)
			(thermal_bridge_width 0.5)
			(island_removal_mode 0)
		)
		(polygon
			(pts
				(xy 334.6958 -145.79092) (xy 334.6958 -139.69238) (xy 332.84414 -137.84072) (xy 332.84414 -133.8961)
				(xy 332.592172 -133.8961) (xy 331.813662 -133.11759) (xy 331.813662 -131.571492) (xy 332.184248 -131.200906)
				(xy 333.500222 -131.200906) (xy 333.883762 -131.584446) (xy 333.883762 -133.155944) (xy 334.057498 -133.32968)
				(xy 334.6958 -133.32968) (xy 336.84718 -133.32968) (xy 336.84718 -145.79092)
			)
		)
	)
	(zone
		(layer "F.Cu")
		(hatch none 0.5)
		(connect_pads
			(clearance 0)
		)
		(min_thickness 0.25)
		(keepout
			(tracks allowed)
			(vias allowed)
			(pads allowed)
			(copperpour allowed)
			(footprints allowed)
		)
		(placement
			(enabled no)
			(sheetname "")
		)
		(fill
			(thermal_gap 0.5)
			(thermal_bridge_width 0.5)
			(island_removal_mode 0)
		)
		(polygon
			(pts
				(xy 163.377626 -252.327918) (xy 163.377626 -251.997718) (xy 165.296596 -251.997718) (xy 165.296596 -252.327918)
			)
		)
	)
	(zone
		(layer "F.Cu")
		(hatch none 0.5)
		(connect_pads
			(clearance 0)
		)
		(min_thickness 0.25)
		(keepout
			(tracks allowed)
			(vias allowed)
			(pads allowed)
			(copperpour allowed)
			(footprints allowed)
		)
		(placement
			(enabled no)
			(sheetname "")
		)
		(fill
			(thermal_gap 0.5)
			(thermal_bridge_width 0.5)
			(island_removal_mode 0)
		)
		(polygon
			(pts
				(xy 405.49957 -166.539164) (xy 403.69617 -166.539164) (xy 403.69617 -168.088564) (xy 405.49957 -168.088564)
			)
		)
	)
	(zone
		(layer "F.Cu")
		(hatch none 0.5)
		(connect_pads
			(clearance 0)
		)
		(min_thickness 0.25)
		(keepout
			(tracks allowed)
			(vias allowed)
			(pads allowed)
			(copperpour allowed)
			(footprints not_allowed)
		)
		(placement
			(enabled no)
			(sheetname "")
		)
		(fill
			(thermal_gap 0.5)
			(thermal_bridge_width 0.5)
			(island_removal_mode 0)
		)
		(polygon
			(pts
				(xy 70.63994 -390.180068) (xy 70.63994 -394.880084) (xy 75.669902 -394.880084) (xy 75.669902 -390.180068)
			)
		)
	)
	(zone
		(layer "F.Cu")
		(hatch none 0.5)
		(connect_pads
			(clearance 0)
		)
		(min_thickness 0.25)
		(keepout
			(tracks allowed)
			(vias allowed)
			(pads allowed)
			(copperpour allowed)
			(footprints allowed)
		)
		(placement
			(enabled no)
			(sheetname "")
		)
		(fill
			(thermal_gap 0.5)
			(thermal_bridge_width 0.5)
			(island_removal_mode 0)
		)
		(polygon
			(pts
				(xy 379.448822 -381.943102) (xy 379.448822 -380.93904) (xy 380.845314 -380.93904) (xy 380.845314 -381.943102)
			)
		)
	)
	(zone
		(layer "F.Cu")
		(hatch none 0.5)
		(connect_pads
			(clearance 0)
		)
		(min_thickness 0.25)
		(keepout
			(tracks allowed)
			(vias allowed)
			(pads allowed)
			(copperpour allowed)
			(footprints allowed)
		)
		(placement
			(enabled no)
			(sheetname "")
		)
		(fill
			(thermal_gap 0.5)
			(thermal_bridge_width 0.5)
			(island_removal_mode 0)
		)
		(polygon
			(pts
				(xy 185.660538 -350.955864) (xy 179.310538 -350.955864) (xy 178.675538 -351.590864) (xy 178.675538 -356.162864)
				(xy 179.310538 -356.797864) (xy 185.279538 -356.797864) (xy 185.787538 -356.289864) (xy 185.787538 -351.082864)
			)
		)
	)
	(zone
		(layer "F.Cu")
		(hatch none 0.5)
		(connect_pads
			(clearance 0)
		)
		(min_thickness 0.25)
		(keepout
			(tracks allowed)
			(vias allowed)
			(pads allowed)
			(copperpour allowed)
			(footprints not_allowed)
		)
		(placement
			(enabled no)
			(sheetname "")
		)
		(fill
			(thermal_gap 0.5)
			(thermal_bridge_width 0.5)
			(island_removal_mode 0)
		)
		(polygon
			(pts
				(xy 296.515028 -50.909982) (xy 296.515028 -56.889904) (xy 304.88509 -56.889904) (xy 304.88509 -50.909982)
			)
		)
	)
	(zone
		(layer "F.Cu")
		(hatch none 0.5)
		(connect_pads
			(clearance 0)
		)
		(min_thickness 0.25)
		(keepout
			(tracks allowed)
			(vias allowed)
			(pads allowed)
			(copperpour allowed)
			(footprints allowed)
		)
		(placement
			(enabled no)
			(sheetname "")
		)
		(fill
			(thermal_gap 0.5)
			(thermal_bridge_width 0.5)
			(island_removal_mode 0)
		)
		(polygon
			(pts
				(xy 180.71846 4.27482) (xy 180.71846 6.32206) (xy 183.18988 6.32206) (xy 183.18988 4.27482)
			)
		)
	)
	(zone
		(layer "F.Cu")
		(hatch none 0.5)
		(connect_pads
			(clearance 0)
		)
		(min_thickness 0.25)
		(keepout
			(tracks allowed)
			(vias allowed)
			(pads allowed)
			(copperpour allowed)
			(footprints allowed)
		)
		(placement
			(enabled no)
			(sheetname "")
		)
		(fill
			(thermal_gap 0.5)
			(thermal_bridge_width 0.5)
			(island_removal_mode 0)
		)
		(polygon
			(pts
				(xy 236.22635 -305.23307) (xy 236.22635 -303.648364) (xy 236.602778 -303.648364) (xy 236.602778 -305.23307)
			)
		)
	)
	(zone
		(layer "F.Cu")
		(hatch none 0.5)
		(connect_pads
			(clearance 0)
		)
		(min_thickness 0.25)
		(keepout
			(tracks allowed)
			(vias allowed)
			(pads allowed)
			(copperpour allowed)
			(footprints allowed)
		)
		(placement
			(enabled no)
			(sheetname "")
		)
		(fill
			(thermal_gap 0.5)
			(thermal_bridge_width 0.5)
			(island_removal_mode 0)
		)
		(polygon
			(pts
				(xy 9.64692 -405.576532) (xy 9.64692 -406.52827) (xy 8.642858 -406.52827) (xy 8.642858 -405.576532)
			)
		)
	)
	(zone
		(layer "F.Cu")
		(hatch none 0.5)
		(connect_pads
			(clearance 0)
		)
		(min_thickness 0.25)
		(keepout
			(tracks allowed)
			(vias allowed)
			(pads allowed)
			(copperpour allowed)
			(footprints not_allowed)
		)
		(placement
			(enabled no)
			(sheetname "")
		)
		(fill
			(thermal_gap 0.5)
			(thermal_bridge_width 0.5)
			(island_removal_mode 0)
		)
		(polygon
			(pts
				(xy 341.449914 -39.980108) (xy 341.449914 -45.980096) (xy 355.149912 -45.980096) (xy 355.149912 -39.980108)
			)
		)
	)
	(zone
		(layer "F.Cu")
		(hatch none 0.5)
		(connect_pads
			(clearance 0)
		)
		(min_thickness 0.25)
		(keepout
			(tracks allowed)
			(vias allowed)
			(pads allowed)
			(copperpour allowed)
			(footprints allowed)
		)
		(placement
			(enabled no)
			(sheetname "")
		)
		(fill
			(thermal_gap 0.5)
			(thermal_bridge_width 0.5)
			(island_removal_mode 0)
		)
		(polygon
			(pts
				(xy 349.982028 -384.406902) (xy 349.982028 -383.40284) (xy 351.37852 -383.40284) (xy 351.37852 -384.406902)
			)
		)
	)
	(zone
		(layer "F.Cu")
		(hatch none 0.5)
		(connect_pads
			(clearance 0)
		)
		(min_thickness 0.25)
		(keepout
			(tracks not_allowed)
			(vias allowed)
			(pads allowed)
			(copperpour not_allowed)
			(footprints allowed)
		)
		(placement
			(enabled no)
			(sheetname "")
		)
		(fill
			(thermal_gap 0.5)
			(thermal_bridge_width 0.5)
			(island_removal_mode 0)
		)
		(polygon
			(pts
				(arc
					(start 183.86298 -74.767948)
					(mid 178.86299 -79.767938)
					(end 173.863 -74.767948)
				)
				(arc
					(start 173.863 -66.06794)
					(mid 178.86299 -61.06795)
					(end 183.86298 -66.06794)
				)
			)
		)
	)
	(zone
		(layer "F.Cu")
		(hatch none 0.5)
		(connect_pads
			(clearance 0)
		)
		(min_thickness 0.25)
		(keepout
			(tracks allowed)
			(vias allowed)
			(pads allowed)
			(copperpour allowed)
			(footprints allowed)
		)
		(placement
			(enabled no)
			(sheetname "")
		)
		(fill
			(thermal_gap 0.5)
			(thermal_bridge_width 0.5)
			(island_removal_mode 0)
		)
		(polygon
			(pts
				(xy 76.964286 -371.097302) (xy 76.964286 -370.09324) (xy 78.360778 -370.09324) (xy 78.360778 -371.097302)
			)
		)
	)
	(zone
		(layer "F.Cu")
		(hatch none 0.5)
		(connect_pads
			(clearance 0)
		)
		(min_thickness 0.25)
		(keepout
			(tracks allowed)
			(vias allowed)
			(pads allowed)
			(copperpour allowed)
			(footprints allowed)
		)
		(placement
			(enabled no)
			(sheetname "")
		)
		(fill
			(thermal_gap 0.5)
			(thermal_bridge_width 0.5)
			(island_removal_mode 0)
		)
		(polygon
			(pts
				(xy 280.92527 -332.196694) (xy 280.92527 -334.101694) (xy 284.93847 -334.101694) (xy 284.93847 -332.196694)
			)
		)
	)
	(zone
		(layer "F.Cu")
		(hatch none 0.5)
		(connect_pads
			(clearance 0)
		)
		(min_thickness 0.25)
		(keepout
			(tracks not_allowed)
			(vias allowed)
			(pads allowed)
			(copperpour not_allowed)
			(footprints allowed)
		)
		(placement
			(enabled no)
			(sheetname "")
		)
		(fill
			(thermal_gap 0.5)
			(thermal_bridge_width 0.5)
			(island_removal_mode 0)
		)
		(polygon
			(pts
				(xy 358.5337 -170.245278) (xy 358.5337 -169.788586) (xy 357.837994 -169.788586) (xy 357.837994 -169.949114)
				(xy 357.279194 -169.949114) (xy 357.279194 -169.542714) (xy 357.837994 -169.542714) (xy 357.837994 -169.763186)
				(xy 358.5337 -169.763186) (xy 358.5337 -169.636186) (xy 358.078024 -169.636186) (xy 358.078024 -169.249598)
				(xy 357.835708 -169.249598) (xy 357.303832 -169.249598) (xy 356.9843 -169.56913) (xy 356.9843 -170.245278)
			)
		)
	)
	(zone
		(layer "F.Cu")
		(hatch none 0.5)
		(connect_pads
			(clearance 0)
		)
		(min_thickness 0.25)
		(keepout
			(tracks not_allowed)
			(vias allowed)
			(pads allowed)
			(copperpour not_allowed)
			(footprints allowed)
		)
		(placement
			(enabled no)
			(sheetname "")
		)
		(fill
			(thermal_gap 0.5)
			(thermal_bridge_width 0.5)
			(island_removal_mode 0)
		)
		(polygon
			(pts
				(xy 51.043332 -345.971876) (xy 51.043332 -346.428568) (xy 51.739038 -346.428568) (xy 51.739038 -346.26804)
				(xy 52.297838 -346.26804) (xy 52.297838 -346.67444) (xy 51.739038 -346.67444) (xy 51.739038 -346.453968)
				(xy 51.043332 -346.453968) (xy 51.043332 -346.580968) (xy 51.499008 -346.580968) (xy 51.499008 -346.967556)
				(xy 51.741324 -346.967556) (xy 52.2732 -346.967556) (xy 52.592732 -346.648024) (xy 52.592732 -345.971876)
			)
		)
	)
	(zone
		(layer "F.Cu")
		(hatch none 0.5)
		(connect_pads
			(clearance 0)
		)
		(min_thickness 0.25)
		(keepout
			(tracks not_allowed)
			(vias allowed)
			(pads allowed)
			(copperpour not_allowed)
			(footprints allowed)
		)
		(placement
			(enabled no)
			(sheetname "")
		)
		(fill
			(thermal_gap 0.5)
			(thermal_bridge_width 0.5)
			(island_removal_mode 0)
		)
		(polygon
			(pts
				(xy 59.374532 -345.971876) (xy 59.374532 -346.428568) (xy 60.070238 -346.428568) (xy 60.070238 -346.26804)
				(xy 60.629038 -346.26804) (xy 60.629038 -346.67444) (xy 60.070238 -346.67444) (xy 60.070238 -346.453968)
				(xy 59.374532 -346.453968) (xy 59.374532 -346.580968) (xy 59.830208 -346.580968) (xy 59.830208 -346.967556)
				(xy 60.072524 -346.967556) (xy 60.6044 -346.967556) (xy 60.923932 -346.648024) (xy 60.923932 -345.971876)
			)
		)
	)
	(zone
		(layer "F.Cu")
		(hatch none 0.5)
		(connect_pads
			(clearance 0)
		)
		(min_thickness 0.25)
		(keepout
			(tracks allowed)
			(vias allowed)
			(pads allowed)
			(copperpour allowed)
			(footprints allowed)
		)
		(placement
			(enabled no)
			(sheetname "")
		)
		(fill
			(thermal_gap 0.5)
			(thermal_bridge_width 0.5)
			(island_removal_mode 0)
		)
		(polygon
			(pts
				(xy 353.385628 -379.479302) (xy 353.385628 -378.47524) (xy 354.78212 -378.47524) (xy 354.78212 -379.479302)
			)
		)
	)
	(zone
		(layer "F.Cu")
		(hatch none 0.5)
		(connect_pads
			(clearance 0)
		)
		(min_thickness 0.25)
		(keepout
			(tracks allowed)
			(vias allowed)
			(pads allowed)
			(copperpour allowed)
			(footprints allowed)
		)
		(placement
			(enabled no)
			(sheetname "")
		)
		(fill
			(thermal_gap 0.5)
			(thermal_bridge_width 0.5)
			(island_removal_mode 0)
		)
		(polygon
			(pts
				(xy 411.317694 -197.927722) (xy 411.317694 -197.597522) (xy 413.236664 -197.597522) (xy 413.236664 -197.927722)
			)
		)
	)
	(zone
		(layer "F.Cu")
		(hatch none 0.5)
		(connect_pads
			(clearance 0)
		)
		(min_thickness 0.25)
		(keepout
			(tracks allowed)
			(vias allowed)
			(pads allowed)
			(copperpour allowed)
			(footprints allowed)
		)
		(placement
			(enabled no)
			(sheetname "")
		)
		(fill
			(thermal_gap 0.5)
			(thermal_bridge_width 0.5)
			(island_removal_mode 0)
		)
		(polygon
			(pts
				(xy 306.070508 -267.627862) (xy 306.070508 -267.297662) (xy 308.610508 -267.297662) (xy 308.610508 -267.627862)
			)
		)
	)
	(zone
		(layer "F.Cu")
		(hatch none 0.5)
		(connect_pads
			(clearance 0)
		)
		(min_thickness 0.25)
		(keepout
			(tracks allowed)
			(vias allowed)
			(pads allowed)
			(copperpour allowed)
			(footprints allowed)
		)
		(placement
			(enabled no)
			(sheetname "")
		)
		(fill
			(thermal_gap 0.5)
			(thermal_bridge_width 0.5)
			(island_removal_mode 0)
		)
		(polygon
			(pts
				(xy 163.377626 -216.627964) (xy 163.377626 -216.297764) (xy 165.296596 -216.297764) (xy 165.296596 -216.627964)
			)
		)
	)
	(zone
		(layer "F.Cu")
		(hatch none 0.5)
		(connect_pads
			(clearance 0)
		)
		(min_thickness 0.25)
		(keepout
			(tracks allowed)
			(vias allowed)
			(pads allowed)
			(copperpour allowed)
			(footprints allowed)
		)
		(placement
			(enabled no)
			(sheetname "")
		)
		(fill
			(thermal_gap 0.5)
			(thermal_bridge_width 0.5)
			(island_removal_mode 0)
		)
		(polygon
			(pts
				(xy 146.343878 -58.488834) (xy 146.343878 -57.797954) (xy 146.63801 -57.797954) (xy 146.63801 -58.488834)
			)
		)
	)
	(zone
		(layer "F.Cu")
		(hatch none 0.5)
		(connect_pads
			(clearance 0)
		)
		(min_thickness 0.25)
		(keepout
			(tracks allowed)
			(vias allowed)
			(pads allowed)
			(copperpour allowed)
			(footprints allowed)
		)
		(placement
			(enabled no)
			(sheetname "")
		)
		(fill
			(thermal_gap 0.5)
			(thermal_bridge_width 0.5)
			(island_removal_mode 0)
		)
		(polygon
			(pts
				(xy 308.66588 -298.742354) (xy 308.66588 -299.072554) (xy 306.12588 -299.072554) (xy 306.12588 -298.742354)
			)
		)
	)
	(zone
		(layer "F.Cu")
		(hatch none 0.5)
		(connect_pads
			(clearance 0)
		)
		(min_thickness 0.25)
		(keepout
			(tracks allowed)
			(vias allowed)
			(pads allowed)
			(copperpour allowed)
			(footprints not_allowed)
		)
		(placement
			(enabled no)
			(sheetname "")
		)
		(fill
			(thermal_gap 0.5)
			(thermal_bridge_width 0.5)
			(island_removal_mode 0)
		)
		(polygon
			(pts
				(arc
					(start 2.999994 -157.318202)
					(mid 18.339672 -160.50006)
					(end 2.999994 -163.681918)
				)
			)
		)
	)
	(zone
		(layer "F.Cu")
		(hatch none 0.5)
		(connect_pads
			(clearance 0)
		)
		(min_thickness 0.25)
		(keepout
			(tracks not_allowed)
			(vias allowed)
			(pads allowed)
			(copperpour not_allowed)
			(footprints allowed)
		)
		(placement
			(enabled no)
			(sheetname "")
		)
		(fill
			(thermal_gap 0.5)
			(thermal_bridge_width 0.5)
			(island_removal_mode 0)
		)
		(polygon
			(pts
				(arc
					(start 466.460078 -347.700092)
					(mid 461.460088 -352.700082)
					(end 456.460098 -347.700092)
				)
				(arc
					(start 456.460098 -347.700092)
					(mid 461.460088 -342.700102)
					(end 466.460078 -347.700092)
				)
			)
		)
	)
	(zone
		(layer "F.Cu")
		(hatch none 0.5)
		(connect_pads
			(clearance 0)
		)
		(min_thickness 0.25)
		(keepout
			(tracks not_allowed)
			(vias allowed)
			(pads allowed)
			(copperpour not_allowed)
			(footprints allowed)
		)
		(placement
			(enabled no)
			(sheetname "")
		)
		(fill
			(thermal_gap 0.5)
			(thermal_bridge_width 0.5)
			(island_removal_mode 0)
		)
		(polygon
			(pts
				(arc
					(start 445.574928 -40.420036)
					(mid 447.44005 -38.554914)
					(end 449.304918 -40.420036)
				)
				(arc
					(start 449.304918 -40.420036)
					(mid 447.44005 -42.284904)
					(end 445.574928 -40.420036)
				)
			)
		)
	)
	(zone
		(layer "F.Cu")
		(hatch none 0.5)
		(connect_pads
			(clearance 0)
		)
		(min_thickness 0.25)
		(keepout
			(tracks allowed)
			(vias allowed)
			(pads allowed)
			(copperpour allowed)
			(footprints allowed)
		)
		(placement
			(enabled no)
			(sheetname "")
		)
		(fill
			(thermal_gap 0.5)
			(thermal_bridge_width 0.5)
			(island_removal_mode 0)
		)
		(polygon
			(pts
				(xy 121.74728 -376.024902) (xy 121.74728 -375.02084) (xy 123.143772 -375.02084) (xy 123.143772 -376.024902)
			)
		)
	)
	(zone
		(layer "F.Cu")
		(hatch none 0.5)
		(connect_pads
			(clearance 0)
		)
		(min_thickness 0.25)
		(keepout
			(tracks allowed)
			(vias allowed)
			(pads allowed)
			(copperpour allowed)
			(footprints allowed)
		)
		(placement
			(enabled no)
			(sheetname "")
		)
		(fill
			(thermal_gap 0.5)
			(thermal_bridge_width 0.5)
			(island_removal_mode 0)
		)
		(polygon
			(pts
				(xy 201.605388 -342.581992) (xy 201.605388 -338.828126) (xy 203.974446 -338.828126) (xy 203.974446 -342.581992)
			)
		)
	)
	(zone
		(layer "F.Cu")
		(hatch none 0.5)
		(connect_pads
			(clearance 0)
		)
		(min_thickness 0.25)
		(keepout
			(tracks allowed)
			(vias allowed)
			(pads allowed)
			(copperpour allowed)
			(footprints not_allowed)
		)
		(placement
			(enabled no)
			(sheetname "")
		)
		(fill
			(thermal_gap 0.5)
			(thermal_bridge_width 0.5)
			(island_removal_mode 0)
		)
		(polygon
			(pts
				(xy 66.216022 -351.605088) (xy 74.331068 -351.605088) (xy 74.331068 -341.514938) (xy 66.216022 -341.514938)
				(xy 66.216022 -345.876626) (xy 66.805556 -345.876626) (xy 66.805556 -347.646498) (xy 66.216022 -347.646498)
			)
		)
	)
	(zone
		(layer "F.Cu")
		(hatch none 0.5)
		(connect_pads
			(clearance 0)
		)
		(min_thickness 0.25)
		(keepout
			(tracks allowed)
			(vias allowed)
			(pads allowed)
			(copperpour allowed)
			(footprints not_allowed)
		)
		(placement
			(enabled no)
			(sheetname "")
		)
		(fill
			(thermal_gap 0.5)
			(thermal_bridge_width 0.5)
			(island_removal_mode 0)
		)
		(polygon
			(pts
				(arc
					(start 233.849926 -192.499996)
					(mid 236.650022 -189.6999)
					(end 239.450118 -192.499996)
				)
				(arc
					(start 239.450118 -192.499996)
					(mid 236.650022 -195.300092)
					(end 233.849926 -192.499996)
				)
			)
		)
	)
	(zone
		(layer "F.Cu")
		(hatch none 0.5)
		(connect_pads
			(clearance 0)
		)
		(min_thickness 0.25)
		(keepout
			(tracks not_allowed)
			(vias allowed)
			(pads allowed)
			(copperpour not_allowed)
			(footprints allowed)
		)
		(placement
			(enabled no)
			(sheetname "")
		)
		(fill
			(thermal_gap 0.5)
			(thermal_bridge_width 0.5)
			(island_removal_mode 0)
		)
		(polygon
			(pts
				(arc
					(start 84.829904 -304.790094)
					(mid 81.330038 -308.28996)
					(end 77.829918 -304.790094)
				)
				(arc
					(start 77.829918 -304.790094)
					(mid 81.330038 -301.289974)
					(end 84.829904 -304.790094)
				)
			)
		)
	)
	(zone
		(layer "F.Cu")
		(hatch none 0.5)
		(connect_pads
			(clearance 0)
		)
		(min_thickness 0.25)
		(keepout
			(tracks allowed)
			(vias allowed)
			(pads allowed)
			(copperpour allowed)
			(footprints not_allowed)
		)
		(placement
			(enabled no)
			(sheetname "")
		)
		(fill
			(thermal_gap 0.5)
			(thermal_bridge_width 0.5)
			(island_removal_mode 0)
		)
		(polygon
			(pts
				(arc
					(start 97.700338 -435.600094)
					(mid 100.500434 -432.799998)
					(end 103.300276 -435.600094)
				)
				(arc
					(start 103.300276 -435.600094)
					(mid 100.500434 -438.399936)
					(end 97.700338 -435.600094)
				)
			)
		)
	)
	(zone
		(layer "F.Cu")
		(hatch none 0.5)
		(connect_pads
			(clearance 0)
		)
		(min_thickness 0.25)
		(keepout
			(tracks allowed)
			(vias allowed)
			(pads allowed)
			(copperpour allowed)
			(footprints not_allowed)
		)
		(placement
			(enabled no)
			(sheetname "")
		)
		(fill
			(thermal_gap 0.5)
			(thermal_bridge_width 0.5)
			(island_removal_mode 0)
		)
		(polygon
			(pts
				(arc
					(start 430.9999 -413.170116)
					(mid 426.999908 -417.170108)
					(end 422.999916 -413.170116)
				)
				(arc
					(start 422.999916 -413.170116)
					(mid 426.999908 -409.170124)
					(end 430.9999 -413.170116)
				)
			)
		)
	)
	(zone
		(layer "F.Cu")
		(hatch none 0.5)
		(connect_pads
			(clearance 0)
		)
		(min_thickness 0.25)
		(keepout
			(tracks not_allowed)
			(vias allowed)
			(pads allowed)
			(copperpour not_allowed)
			(footprints allowed)
		)
		(placement
			(enabled no)
			(sheetname "")
		)
		(fill
			(thermal_gap 0.5)
			(thermal_bridge_width 0.5)
			(island_removal_mode 0)
		)
		(polygon
			(pts
				(xy 289.506914 -345.967812) (xy 289.506914 -346.424504) (xy 290.20262 -346.424504) (xy 290.20262 -346.263976)
				(xy 290.76142 -346.263976) (xy 290.76142 -346.670376) (xy 290.20262 -346.670376) (xy 290.20262 -346.449904)
				(xy 289.506914 -346.449904) (xy 289.506914 -346.576904) (xy 289.96259 -346.576904) (xy 289.96259 -346.963492)
				(xy 290.204906 -346.963492) (xy 290.736782 -346.963492) (xy 291.056314 -346.64396) (xy 291.056314 -345.967812)
			)
		)
	)
	(zone
		(layer "F.Cu")
		(hatch none 0.5)
		(connect_pads
			(clearance 0)
		)
		(min_thickness 0.25)
		(keepout
			(tracks allowed)
			(vias allowed)
			(pads allowed)
			(copperpour allowed)
			(footprints not_allowed)
		)
		(placement
			(enabled no)
			(sheetname "")
		)
		(fill
			(thermal_gap 0.5)
			(thermal_bridge_width 0.5)
			(island_removal_mode 0)
		)
		(polygon
			(pts
				(arc
					(start 320.099944 -160.50006)
					(mid 322.90004 -157.699964)
					(end 325.699882 -160.50006)
				)
				(arc
					(start 325.699882 -160.50006)
					(mid 322.90004 -163.299902)
					(end 320.099944 -160.50006)
				)
			)
		)
	)
	(zone
		(layer "F.Cu")
		(hatch none 0.5)
		(connect_pads
			(clearance 0)
		)
		(min_thickness 0.25)
		(keepout
			(tracks allowed)
			(vias allowed)
			(pads allowed)
			(copperpour allowed)
			(footprints allowed)
		)
		(placement
			(enabled no)
			(sheetname "")
		)
		(fill
			(thermal_gap 0.5)
			(thermal_bridge_width 0.5)
			(island_removal_mode 0)
		)
		(polygon
			(pts
				(xy 356.013258 -327.940924) (xy 356.013258 -327.195942) (xy 356.624382 -327.195942) (xy 356.624382 -327.940924)
			)
		)
	)
	(zone
		(layer "F.Cu")
		(hatch none 0.5)
		(connect_pads
			(clearance 0)
		)
		(min_thickness 0.25)
		(keepout
			(tracks allowed)
			(vias allowed)
			(pads allowed)
			(copperpour allowed)
			(footprints not_allowed)
		)
		(placement
			(enabled no)
			(sheetname "")
		)
		(fill
			(thermal_gap 0.5)
			(thermal_bridge_width 0.5)
			(island_removal_mode 0)
		)
		(polygon
			(pts
				(xy 227.320094 -288.120074) (xy 245.869968 -288.120074) (xy 245.869968 -286.120078) (xy 227.320094 -286.120078)
			)
		)
	)
	(zone
		(layer "F.Cu")
		(hatch none 0.5)
		(connect_pads
			(clearance 0)
		)
		(min_thickness 0.25)
		(keepout
			(tracks allowed)
			(vias allowed)
			(pads allowed)
			(copperpour allowed)
			(footprints allowed)
		)
		(placement
			(enabled no)
			(sheetname "")
		)
		(fill
			(thermal_gap 0.5)
			(thermal_bridge_width 0.5)
			(island_removal_mode 0)
		)
		(polygon
			(pts
				(xy 163.377626 -271.878298) (xy 163.377626 -271.548098) (xy 165.296596 -271.548098) (xy 165.296596 -271.878298)
			)
		)
	)
	(zone
		(layer "F.Cu")
		(hatch none 0.5)
		(connect_pads
			(clearance 0)
		)
		(min_thickness 0.25)
		(keepout
			(tracks allowed)
			(vias allowed)
			(pads allowed)
			(copperpour allowed)
			(footprints not_allowed)
		)
		(placement
			(enabled no)
			(sheetname "")
		)
		(fill
			(thermal_gap 0.5)
			(thermal_bridge_width 0.5)
			(island_removal_mode 0)
		)
		(polygon
			(pts
				(xy 168.283128 -58.97499) (xy 168.283128 -35.124898) (xy 178.433222 -35.124898) (xy 178.433222 -58.97499)
			)
		)
	)
	(zone
		(layer "F.Cu")
		(hatch none 0.5)
		(connect_pads
			(clearance 0)
		)
		(min_thickness 0.25)
		(keepout
			(tracks allowed)
			(vias allowed)
			(pads allowed)
			(copperpour allowed)
			(footprints allowed)
		)
		(placement
			(enabled no)
			(sheetname "")
		)
		(fill
			(thermal_gap 0.5)
			(thermal_bridge_width 0.5)
			(island_removal_mode 0)
		)
		(polygon
			(pts
				(xy 181.065678 -337.76539) (xy 181.065678 -340.55939) (xy 184.774078 -340.55939) (xy 184.774078 -337.76539)
			)
		)
	)
	(zone
		(layer "F.Cu")
		(hatch none 0.5)
		(connect_pads
			(clearance 0)
		)
		(min_thickness 0.25)
		(keepout
			(tracks allowed)
			(vias allowed)
			(pads allowed)
			(copperpour allowed)
			(footprints allowed)
		)
		(placement
			(enabled no)
			(sheetname "")
		)
		(fill
			(thermal_gap 0.5)
			(thermal_bridge_width 0.5)
			(island_removal_mode 0)
		)
		(polygon
			(pts
				(xy 89.513156 -335.01838) (xy 83.163156 -335.01838) (xy 82.528156 -335.65338) (xy 82.528156 -340.22538)
				(xy 83.163156 -340.86038) (xy 89.132156 -340.86038) (xy 89.640156 -340.35238) (xy 89.640156 -335.14538)
			)
		)
	)
	(zone
		(layer "F.Cu")
		(hatch none 0.5)
		(connect_pads
			(clearance 0)
		)
		(min_thickness 0.25)
		(keepout
			(tracks allowed)
			(vias allowed)
			(pads allowed)
			(copperpour allowed)
			(footprints allowed)
		)
		(placement
			(enabled no)
			(sheetname "")
		)
		(fill
			(thermal_gap 0.5)
			(thermal_bridge_width 0.5)
			(island_removal_mode 0)
		)
		(polygon
			(pts
				(xy 306.070508 -226.827842) (xy 306.070508 -226.497642) (xy 308.610508 -226.497642) (xy 308.610508 -226.827842)
			)
		)
	)
	(zone
		(layer "F.Cu")
		(hatch none 0.5)
		(connect_pads
			(clearance 0)
		)
		(min_thickness 0.25)
		(keepout
			(tracks allowed)
			(vias allowed)
			(pads allowed)
			(copperpour allowed)
			(footprints allowed)
		)
		(placement
			(enabled no)
			(sheetname "")
		)
		(fill
			(thermal_gap 0.5)
			(thermal_bridge_width 0.5)
			(island_removal_mode 0)
		)
		(polygon
			(pts
				(xy 149.805644 -193.1416) (xy 149.805644 -192.6336) (xy 150.001224 -192.6336) (xy 150.001224 -193.1416)
			)
		)
	)
	(zone
		(layer "F.Cu")
		(hatch none 0.5)
		(connect_pads
			(clearance 0)
		)
		(min_thickness 0.25)
		(keepout
			(tracks allowed)
			(vias allowed)
			(pads allowed)
			(copperpour allowed)
			(footprints not_allowed)
		)
		(placement
			(enabled no)
			(sheetname "")
		)
		(fill
			(thermal_gap 0.5)
			(thermal_bridge_width 0.5)
			(island_removal_mode 0)
		)
		(polygon
			(pts
				(xy 217.019886 -296.720006) (xy 225.320098 -296.720006) (xy 225.320098 -286.120078) (xy 217.019886 -286.120078)
			)
		)
	)
	(zone
		(layer "F.Cu")
		(hatch none 0.5)
		(connect_pads
			(clearance 0)
		)
		(min_thickness 0.25)
		(keepout
			(tracks not_allowed)
			(vias allowed)
			(pads allowed)
			(copperpour not_allowed)
			(footprints allowed)
		)
		(placement
			(enabled no)
			(sheetname "")
		)
		(fill
			(thermal_gap 0.5)
			(thermal_bridge_width 0.5)
			(island_removal_mode 0)
		)
		(polygon
			(pts
				(arc
					(start 9.970008 -389.439912)
					(mid 6.870192 -392.539728)
					(end 3.770122 -389.439912)
				)
				(arc
					(start 3.770122 -389.439912)
					(mid 6.870192 -386.339842)
					(end 9.970008 -389.439912)
				)
			)
		)
	)
	(zone
		(layer "F.Cu")
		(hatch none 0.5)
		(connect_pads
			(clearance 0)
		)
		(min_thickness 0.25)
		(keepout
			(tracks allowed)
			(vias allowed)
			(pads allowed)
			(copperpour allowed)
			(footprints allowed)
		)
		(placement
			(enabled no)
			(sheetname "")
		)
		(fill
			(thermal_gap 0.5)
			(thermal_bridge_width 0.5)
			(island_removal_mode 0)
		)
		(polygon
			(pts
				(xy 15.47114 -194.4751) (xy 15.47114 -191.75984) (xy 61.10732 -191.75984) (xy 61.10732 -194.4751)
			)
		)
	)
	(zone
		(layer "F.Cu")
		(hatch none 0.5)
		(connect_pads
			(clearance 0)
		)
		(min_thickness 0.25)
		(keepout
			(tracks not_allowed)
			(vias allowed)
			(pads allowed)
			(copperpour not_allowed)
			(footprints allowed)
		)
		(placement
			(enabled no)
			(sheetname "")
		)
		(fill
			(thermal_gap 0.5)
			(thermal_bridge_width 0.5)
			(island_removal_mode 0)
		)
		(polygon
			(pts
				(xy 26.556208 -346.967556) (xy 27.290776 -346.967556) (xy 27.649932 -346.6084) (xy 27.649932 -345.971876)
				(xy 26.100532 -345.971876) (xy 26.100532 -346.428568) (xy 26.796238 -346.428568) (xy 26.796238 -346.26804)
				(xy 27.355038 -346.26804) (xy 27.355038 -346.67444) (xy 26.796238 -346.67444) (xy 26.796238 -346.453968)
				(xy 26.100532 -346.453968) (xy 26.100532 -346.580968) (xy 26.556208 -346.580968)
			)
		)
	)
	(zone
		(layer "F.Cu")
		(hatch none 0.5)
		(connect_pads
			(clearance 0)
		)
		(min_thickness 0.25)
		(keepout
			(tracks not_allowed)
			(vias allowed)
			(pads allowed)
			(copperpour not_allowed)
			(footprints allowed)
		)
		(placement
			(enabled no)
			(sheetname "")
		)
		(fill
			(thermal_gap 0.5)
			(thermal_bridge_width 0.5)
			(island_removal_mode 0)
		)
		(polygon
			(pts
				(xy 437.302656 -87.300054) (xy 437.302656 -60.000134) (xy 416.30473 -59.997848) (xy 416.301936 -87.297768)
			)
		)
	)
	(zone
		(layer "F.Cu")
		(hatch none 0.5)
		(connect_pads
			(clearance 0)
		)
		(min_thickness 0.25)
		(keepout
			(tracks allowed)
			(vias allowed)
			(pads allowed)
			(copperpour allowed)
			(footprints allowed)
		)
		(placement
			(enabled no)
			(sheetname "")
		)
		(fill
			(thermal_gap 0.5)
			(thermal_bridge_width 0.5)
			(island_removal_mode 0)
		)
		(polygon
			(pts
				(xy 308.28488 -237.542578) (xy 308.28488 -237.872778) (xy 305.74488 -237.872778) (xy 305.74488 -237.542578)
			)
		)
	)
	(zone
		(layer "F.Cu")
		(hatch none 0.5)
		(connect_pads
			(clearance 0)
		)
		(min_thickness 0.25)
		(keepout
			(tracks allowed)
			(vias allowed)
			(pads allowed)
			(copperpour allowed)
			(footprints not_allowed)
		)
		(placement
			(enabled no)
			(sheetname "")
		)
		(fill
			(thermal_gap 0.5)
			(thermal_bridge_width 0.5)
			(island_removal_mode 0)
		)
		(polygon
			(pts
				(arc
					(start 174.999904 -404.789894)
					(mid 170.999912 -408.789886)
					(end 166.99992 -404.789894)
				)
				(arc
					(start 166.99992 -404.789894)
					(mid 170.999912 -400.789902)
					(end 174.999904 -404.789894)
				)
			)
		)
	)
	(zone
		(layer "F.Cu")
		(hatch none 0.5)
		(connect_pads
			(clearance 0)
		)
		(min_thickness 0.25)
		(keepout
			(tracks allowed)
			(vias allowed)
			(pads allowed)
			(copperpour allowed)
			(footprints allowed)
		)
		(placement
			(enabled no)
			(sheetname "")
		)
		(fill
			(thermal_gap 0.5)
			(thermal_bridge_width 0.5)
			(island_removal_mode 0)
		)
		(polygon
			(pts
				(xy 12.36472 -198.18096) (xy 12.36472 -195.10756) (xy 13.60424 -195.10756) (xy 13.60424 -198.18096)
			)
		)
	)
	(zone
		(layer "F.Cu")
		(hatch none 0.5)
		(connect_pads
			(clearance 0)
		)
		(min_thickness 0.25)
		(keepout
			(tracks allowed)
			(vias allowed)
			(pads allowed)
			(copperpour allowed)
			(footprints allowed)
		)
		(placement
			(enabled no)
			(sheetname "")
		)
		(fill
			(thermal_gap 0.5)
			(thermal_bridge_width 0.5)
			(island_removal_mode 0)
		)
		(polygon
			(pts
				(xy 60.725812 -281.742642) (xy 60.725812 -282.072842) (xy 58.185812 -282.072842) (xy 58.185812 -281.742642)
			)
		)
	)
	(zone
		(layer "F.Cu")
		(hatch none 0.5)
		(connect_pads
			(clearance 0)
		)
		(min_thickness 0.25)
		(keepout
			(tracks not_allowed)
			(vias allowed)
			(pads allowed)
			(copperpour not_allowed)
			(footprints allowed)
		)
		(placement
			(enabled no)
			(sheetname "")
		)
		(fill
			(thermal_gap 0.5)
			(thermal_bridge_width 0.5)
			(island_removal_mode 0)
		)
		(polygon
			(pts
				(arc
					(start 110.437422 -431.360072)
					(mid 112.024922 -429.772572)
					(end 113.612422 -431.360072)
				)
				(arc
					(start 113.612422 -431.360072)
					(mid 112.024922 -432.947572)
					(end 110.437422 -431.360072)
				)
			)
		)
	)
	(zone
		(layer "F.Cu")
		(hatch none 0.5)
		(connect_pads
			(clearance 0)
		)
		(min_thickness 0.25)
		(keepout
			(tracks allowed)
			(vias allowed)
			(pads allowed)
			(copperpour allowed)
			(footprints allowed)
		)
		(placement
			(enabled no)
			(sheetname "")
		)
		(fill
			(thermal_gap 0.5)
			(thermal_bridge_width 0.5)
			(island_removal_mode 0)
		)
		(polygon
			(pts
				(xy 321.019678 -334.87106) (xy 314.669678 -334.87106) (xy 314.034678 -335.50606) (xy 314.034678 -340.07806)
				(xy 314.669678 -340.71306) (xy 320.638678 -340.71306) (xy 321.146678 -340.20506) (xy 321.146678 -334.99806)
			)
		)
	)
	(zone
		(layer "F.Cu")
		(hatch none 0.5)
		(connect_pads
			(clearance 0)
		)
		(min_thickness 0.25)
		(keepout
			(tracks allowed)
			(vias allowed)
			(pads allowed)
			(copperpour allowed)
			(footprints not_allowed)
		)
		(placement
			(enabled no)
			(sheetname "")
		)
		(fill
			(thermal_gap 0.5)
			(thermal_bridge_width 0.5)
			(island_removal_mode 0)
		)
		(polygon
			(pts
				(arc
					(start 445.051942 -351.415096)
					(mid 441.952126 -354.514912)
					(end 438.852056 -351.415096)
				)
				(arc
					(start 438.852056 -351.415096)
					(mid 441.952126 -348.315026)
					(end 445.051942 -351.415096)
				)
			)
		)
	)
	(zone
		(layer "F.Cu")
		(hatch none 0.5)
		(connect_pads
			(clearance 0)
		)
		(min_thickness 0.25)
		(keepout
			(tracks allowed)
			(vias allowed)
			(pads allowed)
			(copperpour allowed)
			(footprints allowed)
		)
		(placement
			(enabled no)
			(sheetname "")
		)
		(fill
			(thermal_gap 0.5)
			(thermal_bridge_width 0.5)
			(island_removal_mode 0)
		)
		(polygon
			(pts
				(xy 60.344812 -200.142856) (xy 60.344812 -200.473056) (xy 57.804812 -200.473056) (xy 57.804812 -200.142856)
			)
		)
	)
	(zone
		(layer "F.Cu")
		(hatch none 0.5)
		(connect_pads
			(clearance 0)
		)
		(min_thickness 0.25)
		(keepout
			(tracks allowed)
			(vias allowed)
			(pads allowed)
			(copperpour allowed)
			(footprints allowed)
		)
		(placement
			(enabled no)
			(sheetname "")
		)
		(fill
			(thermal_gap 0.5)
			(thermal_bridge_width 0.5)
			(island_removal_mode 0)
		)
		(polygon
			(pts
				(xy 58.13044 -247.227852) (xy 58.13044 -246.897652) (xy 60.67044 -246.897652) (xy 60.67044 -247.227852)
			)
		)
	)
	(zone
		(layer "F.Cu")
		(hatch none 0.5)
		(connect_pads
			(clearance 0)
		)
		(min_thickness 0.25)
		(keepout
			(tracks allowed)
			(vias allowed)
			(pads allowed)
			(copperpour allowed)
			(footprints not_allowed)
		)
		(placement
			(enabled no)
			(sheetname "")
		)
		(fill
			(thermal_gap 0.5)
			(thermal_bridge_width 0.5)
			(island_removal_mode 0)
		)
		(polygon
			(pts
				(xy 452.394066 -161.308542) (xy 452.394066 -139.308586) (xy 431.396394 -139.309856) (xy 431.394108 -161.306256)
			)
		)
	)
	(zone
		(layer "F.Cu")
		(hatch none 0.5)
		(connect_pads
			(clearance 0)
		)
		(min_thickness 0.25)
		(keepout
			(tracks allowed)
			(vias allowed)
			(pads allowed)
			(copperpour allowed)
			(footprints allowed)
		)
		(placement
			(enabled no)
			(sheetname "")
		)
		(fill
			(thermal_gap 0.5)
			(thermal_bridge_width 0.5)
			(island_removal_mode 0)
		)
		(polygon
			(pts
				(xy 338.553298 -354.137468) (xy 338.553298 -352.97491) (xy 340.690708 -352.97491) (xy 340.690708 -354.137468)
			)
		)
	)
	(zone
		(layer "F.Cu")
		(hatch none 0.5)
		(connect_pads
			(clearance 0)
		)
		(min_thickness 0.25)
		(keepout
			(tracks allowed)
			(vias allowed)
			(pads allowed)
			(copperpour allowed)
			(footprints allowed)
		)
		(placement
			(enabled no)
			(sheetname "")
		)
		(fill
			(thermal_gap 0.5)
			(thermal_bridge_width 0.5)
			(island_removal_mode 0)
		)
		(polygon
			(pts
				(xy 81.636362 -180.68925) (xy 79.832962 -180.68925) (xy 79.832962 -182.23865) (xy 81.636362 -182.23865)
			)
		)
	)
	(zone
		(layer "F.Cu")
		(hatch none 0.5)
		(connect_pads
			(clearance 0)
		)
		(min_thickness 0.25)
		(keepout
			(tracks allowed)
			(vias allowed)
			(pads allowed)
			(copperpour allowed)
			(footprints not_allowed)
		)
		(placement
			(enabled no)
			(sheetname "")
		)
		(fill
			(thermal_gap 0.5)
			(thermal_bridge_width 0.5)
			(island_removal_mode 0)
		)
		(polygon
			(pts
				(arc
					(start 262.124952 -360.764074)
					(mid 258.12496 -364.764066)
					(end 254.124968 -360.764074)
				)
				(arc
					(start 254.124968 -360.764074)
					(mid 258.12496 -356.764082)
					(end 262.124952 -360.764074)
				)
			)
		)
	)
	(zone
		(layer "F.Cu")
		(hatch none 0.5)
		(connect_pads
			(clearance 0)
		)
		(min_thickness 0.25)
		(keepout
			(tracks allowed)
			(vias allowed)
			(pads allowed)
			(copperpour allowed)
			(footprints allowed)
		)
		(placement
			(enabled no)
			(sheetname "")
		)
		(fill
			(thermal_gap 0.5)
			(thermal_bridge_width 0.5)
			(island_removal_mode 0)
		)
		(polygon
			(pts
				(xy 163.377626 -270.178276) (xy 163.377626 -269.848076) (xy 165.296596 -269.848076) (xy 165.296596 -270.178276)
			)
		)
	)
	(zone
		(layer "F.Cu")
		(hatch none 0.5)
		(connect_pads
			(clearance 0)
		)
		(min_thickness 0.25)
		(keepout
			(tracks allowed)
			(vias allowed)
			(pads allowed)
			(copperpour allowed)
			(footprints allowed)
		)
		(placement
			(enabled no)
			(sheetname "")
		)
		(fill
			(thermal_gap 0.5)
			(thermal_bridge_width 0.5)
			(island_removal_mode 0)
		)
		(polygon
			(pts
				(xy 15.10284 -109.837728) (xy 15.10284 -108.829348) (xy 16.76908 -108.829348) (xy 16.76908 -109.837728)
			)
		)
	)
	(zone
		(layer "F.Cu")
		(hatch none 0.5)
		(connect_pads
			(clearance 0)
		)
		(min_thickness 0.25)
		(keepout
			(tracks allowed)
			(vias allowed)
			(pads allowed)
			(copperpour allowed)
			(footprints not_allowed)
		)
		(placement
			(enabled no)
			(sheetname "")
		)
		(fill
			(thermal_gap 0.5)
			(thermal_bridge_width 0.5)
			(island_removal_mode 0)
		)
		(polygon
			(pts
				(arc
					(start 131.021074 -146.84502)
					(mid 132.886196 -144.979898)
					(end 134.751064 -146.84502)
				)
				(arc
					(start 134.751064 -146.84502)
					(mid 132.886196 -148.709888)
					(end 131.021074 -146.84502)
				)
			)
		)
	)
	(zone
		(layer "F.Cu")
		(hatch none 0.5)
		(connect_pads
			(clearance 0)
		)
		(min_thickness 0.25)
		(keepout
			(tracks allowed)
			(vias allowed)
			(pads allowed)
			(copperpour allowed)
			(footprints not_allowed)
		)
		(placement
			(enabled no)
			(sheetname "")
		)
		(fill
			(thermal_gap 0.5)
			(thermal_bridge_width 0.5)
			(island_removal_mode 0)
		)
		(polygon
			(pts
				(xy 201.959972 -386.409946) (xy 199.959976 -386.409946) (xy 199.959976 -389.40994) (xy 201.959972 -389.40994)
			)
		)
	)
	(zone
		(layer "F.Cu")
		(hatch none 0.5)
		(connect_pads
			(clearance 0)
		)
		(min_thickness 0.25)
		(keepout
			(tracks allowed)
			(vias allowed)
			(pads allowed)
			(copperpour allowed)
			(footprints not_allowed)
		)
		(placement
			(enabled no)
			(sheetname "")
		)
		(fill
			(thermal_gap 0.5)
			(thermal_bridge_width 0.5)
			(island_removal_mode 0)
		)
		(polygon
			(pts
				(arc
					(start 270.649954 -22.29993)
					(mid 270.451511 -23.694616)
					(end 269.871952 -24.978614)
				)
				(xy 269.871952 -46.459902) (xy 295.8719 -46.459902) (xy 295.8719 -21.860002)
				(arc
					(start 270.63065 -21.860002)
					(mid 270.645148 -22.079753)
					(end 270.649954 -22.29993)
				)
			)
		)
	)
	(zone
		(layer "F.Cu")
		(hatch none 0.5)
		(connect_pads
			(clearance 0)
		)
		(min_thickness 0.25)
		(keepout
			(tracks allowed)
			(vias allowed)
			(pads allowed)
			(copperpour allowed)
			(footprints allowed)
		)
		(placement
			(enabled no)
			(sheetname "")
		)
		(fill
			(thermal_gap 0.5)
			(thermal_bridge_width 0.5)
			(island_removal_mode 0)
		)
		(polygon
			(pts
				(xy 163.377626 -207.27797) (xy 163.377626 -206.94777) (xy 165.296596 -206.94777) (xy 165.296596 -207.27797)
			)
		)
	)
	(zone
		(layer "F.Cu")
		(hatch none 0.5)
		(connect_pads
			(clearance 0)
		)
		(min_thickness 0.25)
		(keepout
			(tracks allowed)
			(vias allowed)
			(pads allowed)
			(copperpour allowed)
			(footprints allowed)
		)
		(placement
			(enabled no)
			(sheetname "")
		)
		(fill
			(thermal_gap 0.5)
			(thermal_bridge_width 0.5)
			(island_removal_mode 0)
		)
		(polygon
			(pts
				(xy 109.542072 -381.225044) (xy 110.546134 -381.225044) (xy 110.546134 -382.621536) (xy 109.542072 -382.621536)
			)
		)
	)
	(zone
		(layer "F.Cu")
		(hatch none 0.5)
		(connect_pads
			(clearance 0)
		)
		(min_thickness 0.25)
		(keepout
			(tracks allowed)
			(vias allowed)
			(pads allowed)
			(copperpour allowed)
			(footprints allowed)
		)
		(placement
			(enabled no)
			(sheetname "")
		)
		(fill
			(thermal_gap 0.5)
			(thermal_bridge_width 0.5)
			(island_removal_mode 0)
		)
		(polygon
			(pts
				(xy 129.68351 -156.870654) (xy 136.03351 -156.870654) (xy 136.66851 -156.235654) (xy 136.66851 -151.663654)
				(xy 136.03351 -151.028654) (xy 130.06451 -151.028654) (xy 129.55651 -151.536654) (xy 129.55651 -156.743654)
			)
		)
	)
	(zone
		(layer "F.Cu")
		(hatch none 0.5)
		(connect_pads
			(clearance 0)
		)
		(min_thickness 0.25)
		(keepout
			(tracks allowed)
			(vias allowed)
			(pads allowed)
			(copperpour allowed)
			(footprints not_allowed)
		)
		(placement
			(enabled no)
			(sheetname "")
		)
		(fill
			(thermal_gap 0.5)
			(thermal_bridge_width 0.5)
			(island_removal_mode 0)
		)
		(polygon
			(pts
				(xy 34.562034 -81.77403) (xy 2.999994 -81.77403) (xy 2.999994 -91.764104) (xy 221.861126 -91.764104)
				(xy 221.861126 -81.77403) (xy 189.36208 -81.77403) (xy 189.36208 -87.286084) (xy 168.362122 -87.286084)
				(xy 168.362122 -81.77403) (xy 55.557928 -81.77403) (xy 55.557928 -87.286084) (xy 34.562034 -87.286084)
			)
		)
	)
	(zone
		(layer "F.Cu")
		(hatch none 0.5)
		(connect_pads
			(clearance 0)
		)
		(min_thickness 0.25)
		(keepout
			(tracks allowed)
			(vias allowed)
			(pads allowed)
			(copperpour allowed)
			(footprints allowed)
		)
		(placement
			(enabled no)
			(sheetname "")
		)
		(fill
			(thermal_gap 0.5)
			(thermal_bridge_width 0.5)
			(island_removal_mode 0)
		)
		(polygon
			(pts
				(xy 303.83988 -384.406902) (xy 303.83988 -383.40284) (xy 305.236372 -383.40284) (xy 305.236372 -384.406902)
			)
		)
	)
	(zone
		(layer "F.Cu")
		(hatch none 0.5)
		(connect_pads
			(clearance 0)
		)
		(min_thickness 0.25)
		(keepout
			(tracks allowed)
			(vias allowed)
			(pads allowed)
			(copperpour allowed)
			(footprints not_allowed)
		)
		(placement
			(enabled no)
			(sheetname "")
		)
		(fill
			(thermal_gap 0.5)
			(thermal_bridge_width 0.5)
			(island_removal_mode 0)
		)
		(polygon
			(pts
				(arc
					(start 223.330516 -388.161784)
					(mid 225.430588 -386.061712)
					(end 227.530406 -388.161784)
				)
				(arc
					(start 227.530406 -388.161784)
					(mid 225.430588 -390.261602)
					(end 223.330516 -388.161784)
				)
			)
		)
	)
	(zone
		(layer "F.Cu")
		(hatch none 0.5)
		(connect_pads
			(clearance 0)
		)
		(min_thickness 0.25)
		(keepout
			(tracks not_allowed)
			(vias allowed)
			(pads allowed)
			(copperpour not_allowed)
			(footprints allowed)
		)
		(placement
			(enabled no)
			(sheetname "")
		)
		(fill
			(thermal_gap 0.5)
			(thermal_bridge_width 0.5)
			(island_removal_mode 0)
		)
		(polygon
			(pts
				(xy 55.5625 -87.293196) (xy 55.5625 -59.993276) (xy 34.564574 -59.99099) (xy 34.56178 -87.29091)
			)
		)
	)
	(zone
		(layer "F.Cu")
		(hatch none 0.5)
		(connect_pads
			(clearance 0)
		)
		(min_thickness 0.25)
		(keepout
			(tracks allowed)
			(vias allowed)
			(pads allowed)
			(copperpour allowed)
			(footprints not_allowed)
		)
		(placement
			(enabled no)
			(sheetname "")
		)
		(fill
			(thermal_gap 0.5)
			(thermal_bridge_width 0.5)
			(island_removal_mode 0)
		)
		(polygon
			(pts
				(arc
					(start 102.633018 -47.049944)
					(mid 100.383086 -49.299876)
					(end 98.1329 -47.049944)
				)
				(arc
					(start 98.1329 -47.049944)
					(mid 100.383086 -44.799758)
					(end 102.633018 -47.049944)
				)
			)
		)
	)
	(zone
		(layer "F.Cu")
		(hatch none 0.5)
		(connect_pads
			(clearance 0)
		)
		(min_thickness 0.25)
		(keepout
			(tracks allowed)
			(vias allowed)
			(pads allowed)
			(copperpour allowed)
			(footprints allowed)
		)
		(placement
			(enabled no)
			(sheetname "")
		)
		(fill
			(thermal_gap 0.5)
			(thermal_bridge_width 0.5)
			(island_removal_mode 0)
		)
		(polygon
			(pts
				(xy 63.259716 -28.677616) (xy 63.259716 -28.11399) (xy 65.695576 -28.11399) (xy 65.695576 -28.677616)
			)
		)
	)
	(zone
		(layer "F.Cu")
		(hatch none 0.5)
		(connect_pads
			(clearance 0)
		)
		(min_thickness 0.25)
		(keepout
			(tracks allowed)
			(vias allowed)
			(pads allowed)
			(copperpour allowed)
			(footprints not_allowed)
		)
		(placement
			(enabled no)
			(sheetname "")
		)
		(fill
			(thermal_gap 0.5)
			(thermal_bridge_width 0.5)
			(island_removal_mode 0)
		)
		(polygon
			(pts
				(xy 295.980104 -406.940004) (xy 300.68012 -406.940004) (xy 300.68012 -401.910042) (xy 295.980104 -401.910042)
			)
		)
	)
	(zone
		(layer "F.Cu")
		(hatch none 0.5)
		(connect_pads
			(clearance 0)
		)
		(min_thickness 0.25)
		(keepout
			(tracks not_allowed)
			(vias allowed)
			(pads allowed)
			(copperpour not_allowed)
			(footprints allowed)
		)
		(placement
			(enabled no)
			(sheetname "")
		)
		(fill
			(thermal_gap 0.5)
			(thermal_bridge_width 0.5)
			(island_removal_mode 0)
		)
		(polygon
			(pts
				(arc
					(start 431.25009 -384.869944)
					(mid 433.500022 -382.620012)
					(end 435.749954 -384.869944)
				)
				(arc
					(start 435.749954 -384.869944)
					(mid 433.500022 -387.119876)
					(end 431.25009 -384.869944)
				)
			)
		)
	)
	(zone
		(layer "F.Cu")
		(hatch none 0.5)
		(connect_pads
			(clearance 0)
		)
		(min_thickness 0.25)
		(keepout
			(tracks not_allowed)
			(vias allowed)
			(pads allowed)
			(copperpour not_allowed)
			(footprints allowed)
		)
		(placement
			(enabled no)
			(sheetname "")
		)
		(fill
			(thermal_gap 0.5)
			(thermal_bridge_width 0.5)
			(island_removal_mode 0)
		)
		(polygon
			(pts
				(arc
					(start 182.553102 -244.085364)
					(mid 181.885082 -244.085364)
					(end 182.553102 -244.085364)
				)
			)
		)
	)
	(zone
		(layer "F.Cu")
		(hatch none 0.5)
		(connect_pads
			(clearance 0)
		)
		(min_thickness 0.25)
		(keepout
			(tracks allowed)
			(vias allowed)
			(pads allowed)
			(copperpour allowed)
			(footprints allowed)
		)
		(placement
			(enabled no)
			(sheetname "")
		)
		(fill
			(thermal_gap 0.5)
			(thermal_bridge_width 0.5)
			(island_removal_mode 0)
		)
		(polygon
			(pts
				(xy 411.317694 -246.377714) (xy 411.317694 -246.047514) (xy 413.236664 -246.047514) (xy 413.236664 -246.377714)
			)
		)
	)
	(zone
		(layer "F.Cu")
		(hatch none 0.5)
		(connect_pads
			(clearance 0)
		)
		(min_thickness 0.25)
		(keepout
			(tracks allowed)
			(vias allowed)
			(pads allowed)
			(copperpour allowed)
			(footprints allowed)
		)
		(placement
			(enabled no)
			(sheetname "")
		)
		(fill
			(thermal_gap 0.5)
			(thermal_bridge_width 0.5)
			(island_removal_mode 0)
		)
		(polygon
			(pts
				(xy 411.574996 -275.277834) (xy 411.574996 -274.947634) (xy 413.236664 -274.947634) (xy 413.236664 -275.277834)
			)
		)
	)
	(zone
		(layer "F.Cu")
		(hatch none 0.5)
		(connect_pads
			(clearance 0)
		)
		(min_thickness 0.25)
		(keepout
			(tracks not_allowed)
			(vias allowed)
			(pads allowed)
			(copperpour not_allowed)
			(footprints allowed)
		)
		(placement
			(enabled no)
			(sheetname "")
		)
		(fill
			(thermal_gap 0.5)
			(thermal_bridge_width 0.5)
			(island_removal_mode 0)
		)
		(polygon
			(pts
				(arc
					(start 15.340076 -160.50006)
					(mid 10.340086 -165.50005)
					(end 5.340096 -160.50006)
				)
				(arc
					(start 5.340096 -160.50006)
					(mid 10.340086 -155.50007)
					(end 15.340076 -160.50006)
				)
			)
		)
	)
	(zone
		(layer "F.Cu")
		(hatch none 0.5)
		(connect_pads
			(clearance 0)
		)
		(min_thickness 0.25)
		(keepout
			(tracks not_allowed)
			(vias allowed)
			(pads allowed)
			(copperpour not_allowed)
			(footprints allowed)
		)
		(placement
			(enabled no)
			(sheetname "")
		)
		(fill
			(thermal_gap 0.5)
			(thermal_bridge_width 0.5)
			(island_removal_mode 0)
		)
		(polygon
			(pts
				(arc
					(start 39.319962 -404.789894)
					(mid 41.570148 -402.539708)
					(end 43.82008 -404.789894)
				)
				(arc
					(start 43.82008 -404.789894)
					(mid 41.570148 -407.039826)
					(end 39.319962 -404.789894)
				)
			)
		)
	)
	(zone
		(layer "F.Cu")
		(hatch none 0.5)
		(connect_pads
			(clearance 0)
		)
		(min_thickness 0.25)
		(keepout
			(tracks allowed)
			(vias allowed)
			(pads allowed)
			(copperpour allowed)
			(footprints allowed)
		)
		(placement
			(enabled no)
			(sheetname "")
		)
		(fill
			(thermal_gap 0.5)
			(thermal_bridge_width 0.5)
			(island_removal_mode 0)
		)
		(polygon
			(pts
				(xy 163.621974 -304.177954) (xy 163.621974 -303.847754) (xy 165.296596 -303.847754) (xy 165.296596 -304.177954)
			)
		)
	)
	(zone
		(layer "F.Cu")
		(hatch none 0.5)
		(connect_pads
			(clearance 0)
		)
		(min_thickness 0.25)
		(keepout
			(tracks allowed)
			(vias allowed)
			(pads allowed)
			(copperpour allowed)
			(footprints allowed)
		)
		(placement
			(enabled no)
			(sheetname "")
		)
		(fill
			(thermal_gap 0.5)
			(thermal_bridge_width 0.5)
			(island_removal_mode 0)
		)
		(polygon
			(pts
				(xy 75.2221 -25.59304) (xy 82.97418 -25.59304) (xy 84.53374 -24.03348) (xy 84.53374 -16.62176) (xy 83.28406 -15.37208)
				(xy 79.12354 -15.37208) (xy 76.70546 -12.954) (xy 73.68794 -12.954) (xy 72.77862 -13.86332) (xy 72.77862 -15.52956)
				(xy 74.33818 -17.08912) (xy 74.33818 -24.70912)
			)
		)
	)
	(zone
		(layer "F.Cu")
		(hatch none 0.5)
		(connect_pads
			(clearance 0)
		)
		(min_thickness 0.25)
		(keepout
			(tracks allowed)
			(vias allowed)
			(pads allowed)
			(copperpour allowed)
			(footprints not_allowed)
		)
		(placement
			(enabled no)
			(sheetname "")
		)
		(fill
			(thermal_gap 0.5)
			(thermal_bridge_width 0.5)
			(island_removal_mode 0)
		)
		(polygon
			(pts
				(xy 432.809904 -44.60494) (xy 432.809904 -28.675076) (xy 422.710102 -28.675076) (xy 422.710102 -44.60494)
			)
		)
	)
	(zone
		(layer "F.Cu")
		(hatch none 0.5)
		(connect_pads
			(clearance 0)
		)
		(min_thickness 0.25)
		(keepout
			(tracks allowed)
			(vias allowed)
			(pads allowed)
			(copperpour allowed)
			(footprints not_allowed)
		)
		(placement
			(enabled no)
			(sheetname "")
		)
		(fill
			(thermal_gap 0.5)
			(thermal_bridge_width 0.5)
			(island_removal_mode 0)
		)
		(polygon
			(pts
				(xy 356.151942 -344.914982) (xy 356.151942 -340.965028) (xy 356.792022 -340.965028) (xy 356.792022 -339.194902)
				(xy 356.151942 -339.194902) (xy 356.151942 -336.12455) (xy 347.451934 -336.12455) (xy 347.451934 -331.185012)
				(xy 312.951876 -331.185012) (xy 312.951876 -342.914986) (xy 270.542258 -342.914986) (xy 270.542258 -344.41511)
				(xy 271.132046 -344.41511) (xy 271.132046 -350.665034) (xy 269.352014 -350.665034) (xy 269.352014 -351.605088)
				(xy 313.452002 -351.605088) (xy 313.452002 -347.646498) (xy 314.332112 -347.646498) (xy 314.332112 -345.876626)
				(xy 313.452002 -345.876626) (xy 313.452002 -340.814914) (xy 319.651888 -340.814914) (xy 319.651888 -341.644986)
				(xy 321.567048 -341.644986) (xy 321.567048 -341.23503) (xy 340.80704 -341.23503) (xy 344.602054 -344.914982)
			)
		)
	)
	(zone
		(layer "F.Cu")
		(hatch none 0.5)
		(connect_pads
			(clearance 0)
		)
		(min_thickness 0.25)
		(keepout
			(tracks allowed)
			(vias allowed)
			(pads allowed)
			(copperpour allowed)
			(footprints allowed)
		)
		(placement
			(enabled no)
			(sheetname "")
		)
		(fill
			(thermal_gap 0.5)
			(thermal_bridge_width 0.5)
			(island_removal_mode 0)
		)
		(polygon
			(pts
				(xy 87.94115 -183.015382) (xy 94.29115 -183.015382) (xy 94.92615 -182.380382) (xy 94.92615 -177.808382)
				(xy 94.29115 -177.173382) (xy 88.32215 -177.173382) (xy 87.81415 -177.681382) (xy 87.81415 -182.888382)
			)
		)
	)
	(zone
		(layer "F.Cu")
		(hatch none 0.5)
		(connect_pads
			(clearance 0)
		)
		(min_thickness 0.25)
		(keepout
			(tracks allowed)
			(vias allowed)
			(pads allowed)
			(copperpour allowed)
			(footprints allowed)
		)
		(placement
			(enabled no)
			(sheetname "")
		)
		(fill
			(thermal_gap 0.5)
			(thermal_bridge_width 0.5)
			(island_removal_mode 0)
		)
		(polygon
			(pts
				(xy 58.13044 -266.777978) (xy 58.13044 -266.447778) (xy 60.67044 -266.447778) (xy 60.67044 -266.777978)
			)
		)
	)
	(zone
		(layer "F.Cu")
		(hatch none 0.5)
		(connect_pads
			(clearance 0)
		)
		(min_thickness 0.25)
		(keepout
			(tracks allowed)
			(vias allowed)
			(pads allowed)
			(copperpour allowed)
			(footprints allowed)
		)
		(placement
			(enabled no)
			(sheetname "")
		)
		(fill
			(thermal_gap 0.5)
			(thermal_bridge_width 0.5)
			(island_removal_mode 0)
		)
		(polygon
			(pts
				(xy 105.8164 -225.6282) (xy 111.0234 -225.6282) (xy 112.1664 -224.4852) (xy 112.1664 -221.6912)
				(xy 111.5568 -221.0816) (xy 102.9462 -221.0816) (xy 102.9462 -221.3864) (xy 103.0986 -221.5388)
				(xy 103.0986 -222.6564) (xy 104.0384 -223.5962) (xy 104.0384 -223.8502)
			)
		)
	)
	(zone
		(layer "F.Cu")
		(hatch none 0.5)
		(connect_pads
			(clearance 0)
		)
		(min_thickness 0.25)
		(keepout
			(tracks allowed)
			(vias allowed)
			(pads allowed)
			(copperpour allowed)
			(footprints allowed)
		)
		(placement
			(enabled no)
			(sheetname "")
		)
		(fill
			(thermal_gap 0.5)
			(thermal_bridge_width 0.5)
			(island_removal_mode 0)
		)
		(polygon
			(pts
				(xy 163.377626 -208.977992) (xy 163.377626 -208.647792) (xy 165.296596 -208.647792) (xy 165.296596 -208.977992)
			)
		)
	)
	(zone
		(layer "F.Cu")
		(hatch none 0.5)
		(connect_pads
			(clearance 0)
		)
		(min_thickness 0.25)
		(keepout
			(tracks allowed)
			(vias allowed)
			(pads allowed)
			(copperpour allowed)
			(footprints allowed)
		)
		(placement
			(enabled no)
			(sheetname "")
		)
		(fill
			(thermal_gap 0.5)
			(thermal_bridge_width 0.5)
			(island_removal_mode 0)
		)
		(polygon
			(pts
				(xy 163.621974 -220.028008) (xy 163.621974 -219.697808) (xy 165.296596 -219.697808) (xy 165.296596 -220.028008)
			)
		)
	)
	(zone
		(layer "F.Cu")
		(hatch none 0.5)
		(connect_pads
			(clearance 0)
		)
		(min_thickness 0.25)
		(keepout
			(tracks allowed)
			(vias allowed)
			(pads allowed)
			(copperpour allowed)
			(footprints allowed)
		)
		(placement
			(enabled no)
			(sheetname "")
		)
		(fill
			(thermal_gap 0.5)
			(thermal_bridge_width 0.5)
			(island_removal_mode 0)
		)
		(polygon
			(pts
				(xy 21.09597 -405.118062) (xy 21.09597 -406.514554) (xy 20.091908 -406.514554) (xy 20.091908 -405.118062)
				(xy 20.091908 -404.591266) (xy 20.253452 -404.429722) (xy 20.930616 -404.429722) (xy 21.09597 -404.595076)
			)
		)
	)
	(zone
		(layer "F.Cu")
		(hatch none 0.5)
		(connect_pads
			(clearance 0)
		)
		(min_thickness 0.25)
		(keepout
			(tracks allowed)
			(vias allowed)
			(pads allowed)
			(copperpour allowed)
			(footprints allowed)
		)
		(placement
			(enabled no)
			(sheetname "")
		)
		(fill
			(thermal_gap 0.5)
			(thermal_bridge_width 0.5)
			(island_removal_mode 0)
		)
		(polygon
			(pts
				(xy 416.562286 -417.424616) (xy 416.562286 -416.420554) (xy 417.958778 -416.420554) (xy 417.958778 -417.424616)
			)
		)
	)
	(zone
		(layer "F.Cu")
		(hatch none 0.5)
		(connect_pads
			(clearance 0)
		)
		(min_thickness 0.25)
		(keepout
			(tracks allowed)
			(vias allowed)
			(pads allowed)
			(copperpour allowed)
			(footprints not_allowed)
		)
		(placement
			(enabled no)
			(sheetname "")
		)
		(fill
			(thermal_gap 0.5)
			(thermal_bridge_width 0.5)
			(island_removal_mode 0)
		)
		(polygon
			(pts
				(arc
					(start 233.849926 -272.50009)
					(mid 236.650022 -269.699994)
					(end 239.450118 -272.50009)
				)
				(arc
					(start 239.450118 -272.50009)
					(mid 236.650022 -275.300186)
					(end 233.849926 -272.50009)
				)
			)
		)
	)
	(zone
		(layer "F.Cu")
		(hatch none 0.5)
		(connect_pads
			(clearance 0)
		)
		(min_thickness 0.25)
		(keepout
			(tracks not_allowed)
			(vias allowed)
			(pads allowed)
			(copperpour not_allowed)
			(footprints allowed)
		)
		(placement
			(enabled no)
			(sheetname "")
		)
		(fill
			(thermal_gap 0.5)
			(thermal_bridge_width 0.5)
			(island_removal_mode 0)
		)
		(polygon
			(pts
				(arc
					(start 68.350892 -344.814906)
					(mid 70.216014 -342.949784)
					(end 72.080882 -344.814906)
				)
				(arc
					(start 72.080882 -344.814906)
					(mid 70.216014 -346.679774)
					(end 68.350892 -344.814906)
				)
			)
		)
	)
	(zone
		(layer "F.Cu")
		(hatch none 0.5)
		(connect_pads
			(clearance 0)
		)
		(min_thickness 0.25)
		(keepout
			(tracks allowed)
			(vias allowed)
			(pads allowed)
			(copperpour allowed)
			(footprints allowed)
		)
		(placement
			(enabled no)
			(sheetname "")
		)
		(fill
			(thermal_gap 0.5)
			(thermal_bridge_width 0.5)
			(island_removal_mode 0)
		)
		(polygon
			(pts
				(xy 63.523114 -181.543198) (xy 63.523114 -183.448198) (xy 67.536314 -183.448198) (xy 67.536314 -181.543198)
			)
		)
	)
	(zone
		(layer "F.Cu")
		(hatch none 0.5)
		(connect_pads
			(clearance 0)
		)
		(min_thickness 0.25)
		(keepout
			(tracks allowed)
			(vias allowed)
			(pads allowed)
			(copperpour allowed)
			(footprints allowed)
		)
		(placement
			(enabled no)
			(sheetname "")
		)
		(fill
			(thermal_gap 0.5)
			(thermal_bridge_width 0.5)
			(island_removal_mode 0)
		)
		(polygon
			(pts
				(xy 395.884146 -77.917548) (xy 395.884146 -75.23226) (xy 398.556988 -75.23226) (xy 398.556988 -77.917548)
			)
		)
	)
	(zone
		(layer "F.Cu")
		(hatch none 0.5)
		(connect_pads
			(clearance 0)
		)
		(min_thickness 0.25)
		(keepout
			(tracks allowed)
			(vias allowed)
			(pads allowed)
			(copperpour allowed)
			(footprints allowed)
		)
		(placement
			(enabled no)
			(sheetname "")
		)
		(fill
			(thermal_gap 0.5)
			(thermal_bridge_width 0.5)
			(island_removal_mode 0)
		)
		(polygon
			(pts
				(xy 8.6741 -100.162868) (xy 8.6741 -97.968308) (xy 12.065 -97.968308) (xy 12.065 -100.162868)
			)
		)
	)
	(zone
		(layer "F.Cu")
		(hatch none 0.5)
		(connect_pads
			(clearance 0)
		)
		(min_thickness 0.25)
		(keepout
			(tracks allowed)
			(vias allowed)
			(pads allowed)
			(copperpour allowed)
			(footprints allowed)
		)
		(placement
			(enabled no)
			(sheetname "")
		)
		(fill
			(thermal_gap 0.5)
			(thermal_bridge_width 0.5)
			(island_removal_mode 0)
		)
		(polygon
			(pts
				(xy 136.315704 -375.812812) (xy 137.319766 -375.812812) (xy 137.319766 -377.209304) (xy 136.315704 -377.209304)
			)
		)
	)
	(zone
		(layer "F.Cu")
		(hatch none 0.5)
		(connect_pads
			(clearance 0)
		)
		(min_thickness 0.25)
		(keepout
			(tracks allowed)
			(vias allowed)
			(pads allowed)
			(copperpour allowed)
			(footprints allowed)
		)
		(placement
			(enabled no)
			(sheetname "")
		)
		(fill
			(thermal_gap 0.5)
			(thermal_bridge_width 0.5)
			(island_removal_mode 0)
		)
		(polygon
			(pts
				(xy 122.684032 -56.069738) (xy 121.999502 -56.069738) (xy 121.999502 -55.318914) (xy 122.684032 -55.318914)
			)
		)
	)
	(zone
		(layer "F.Cu")
		(hatch none 0.5)
		(connect_pads
			(clearance 0)
		)
		(min_thickness 0.25)
		(keepout
			(tracks allowed)
			(vias allowed)
			(pads allowed)
			(copperpour allowed)
			(footprints allowed)
		)
		(placement
			(enabled no)
			(sheetname "")
		)
		(fill
			(thermal_gap 0.5)
			(thermal_bridge_width 0.5)
			(island_removal_mode 0)
		)
		(polygon
			(pts
				(xy 19.24304 -137.78992) (xy 20.71624 -137.78992) (xy 20.71624 -138.67892) (xy 19.24304 -138.67892)
			)
		)
	)
	(zone
		(layer "F.Cu")
		(hatch none 0.5)
		(connect_pads
			(clearance 0)
		)
		(min_thickness 0.25)
		(keepout
			(tracks allowed)
			(vias allowed)
			(pads allowed)
			(copperpour allowed)
			(footprints not_allowed)
		)
		(placement
			(enabled no)
			(sheetname "")
		)
		(fill
			(thermal_gap 0.5)
			(thermal_bridge_width 0.5)
			(island_removal_mode 0)
		)
		(polygon
			(pts
				(arc
					(start 241.650012 -272.50009)
					(mid 236.650022 -277.50008)
					(end 231.650032 -272.50009)
				)
				(arc
					(start 231.650032 -272.50009)
					(mid 236.650022 -267.5001)
					(end 241.650012 -272.50009)
				)
			)
		)
	)
	(zone
		(layer "F.Cu")
		(hatch none 0.5)
		(connect_pads
			(clearance 0)
		)
		(min_thickness 0.25)
		(keepout
			(tracks not_allowed)
			(vias allowed)
			(pads allowed)
			(copperpour not_allowed)
			(footprints allowed)
		)
		(placement
			(enabled no)
			(sheetname "")
		)
		(fill
			(thermal_gap 0.5)
			(thermal_bridge_width 0.5)
			(island_removal_mode 0)
		)
		(polygon
			(pts
				(xy 109.500416 -177.471832) (xy 109.500416 -176.51095) (xy 109.2581 -176.51095) (xy 109.2581 -177.471832)
			)
		)
	)
	(zone
		(layer "F.Cu")
		(hatch none 0.5)
		(connect_pads
			(clearance 0)
		)
		(min_thickness 0.25)
		(keepout
			(tracks allowed)
			(vias allowed)
			(pads allowed)
			(copperpour allowed)
			(footprints not_allowed)
		)
		(placement
			(enabled no)
			(sheetname "")
		)
		(fill
			(thermal_gap 0.5)
			(thermal_bridge_width 0.5)
			(island_removal_mode 0)
		)
		(polygon
			(pts
				(xy 339.350096 -59.159902) (xy 339.350096 -64.840104) (xy 346.250006 -64.840104) (xy 346.250006 -59.159902)
			)
		)
	)
	(zone
		(layer "F.Cu")
		(hatch none 0.5)
		(connect_pads
			(clearance 0)
		)
		(min_thickness 0.25)
		(keepout
			(tracks allowed)
			(vias allowed)
			(pads allowed)
			(copperpour allowed)
			(footprints allowed)
		)
		(placement
			(enabled no)
			(sheetname "")
		)
		(fill
			(thermal_gap 0.5)
			(thermal_bridge_width 0.5)
			(island_removal_mode 0)
		)
		(polygon
			(pts
				(xy 14.783816 -422.69283) (xy 14.783816 -424.089322) (xy 13.779754 -424.089322) (xy 13.779754 -422.69283)
				(xy 13.779754 -422.166034) (xy 13.941298 -422.00449) (xy 14.618462 -422.00449) (xy 14.783816 -422.169844)
			)
		)
	)
	(zone
		(layer "F.Cu")
		(hatch none 0.5)
		(connect_pads
			(clearance 0)
		)
		(min_thickness 0.25)
		(keepout
			(tracks allowed)
			(vias allowed)
			(pads allowed)
			(copperpour allowed)
			(footprints allowed)
		)
		(placement
			(enabled no)
			(sheetname "")
		)
		(fill
			(thermal_gap 0.5)
			(thermal_bridge_width 0.5)
			(island_removal_mode 0)
		)
		(polygon
			(pts
				(xy 411.574996 -312.67781) (xy 411.574996 -312.34761) (xy 413.236664 -312.34761) (xy 413.236664 -312.67781)
			)
		)
	)
	(zone
		(layer "F.Cu")
		(hatch none 0.5)
		(connect_pads
			(clearance 0)
		)
		(min_thickness 0.25)
		(keepout
			(tracks not_allowed)
			(vias allowed)
			(pads allowed)
			(copperpour not_allowed)
			(footprints allowed)
		)
		(placement
			(enabled no)
			(sheetname "")
		)
		(fill
			(thermal_gap 0.5)
			(thermal_bridge_width 0.5)
			(island_removal_mode 0)
		)
		(polygon
			(pts
				(arc
					(start 92.099892 -22.29993)
					(mid 94.899988 -19.499834)
					(end 97.700084 -22.29993)
				)
				(arc
					(start 97.700084 -22.29993)
					(mid 94.899988 -25.100026)
					(end 92.099892 -22.29993)
				)
			)
		)
	)
	(zone
		(layer "F.Cu")
		(hatch none 0.5)
		(connect_pads
			(clearance 0)
		)
		(min_thickness 0.25)
		(keepout
			(tracks not_allowed)
			(vias allowed)
			(pads allowed)
			(copperpour not_allowed)
			(footprints allowed)
		)
		(placement
			(enabled no)
			(sheetname "")
		)
		(fill
			(thermal_gap 0.5)
			(thermal_bridge_width 0.5)
			(island_removal_mode 0)
		)
		(polygon
			(pts
				(xy 101.22916 -339.190076) (xy 101.22916 -339.646768) (xy 101.924866 -339.646768) (xy 101.924866 -339.48624)
				(xy 102.483666 -339.48624) (xy 102.483666 -339.89264) (xy 101.924866 -339.89264) (xy 101.924866 -339.672168)
				(xy 101.22916 -339.672168) (xy 101.22916 -339.799168) (xy 101.684836 -339.799168) (xy 101.684836 -340.185756)
				(xy 101.927152 -340.185756) (xy 102.459028 -340.185756) (xy 102.77856 -339.866224) (xy 102.77856 -339.190076)
			)
		)
	)
	(zone
		(layer "F.Cu")
		(hatch none 0.5)
		(connect_pads
			(clearance 0)
		)
		(min_thickness 0.25)
		(keepout
			(tracks allowed)
			(vias allowed)
			(pads allowed)
			(copperpour allowed)
			(footprints allowed)
		)
		(placement
			(enabled no)
			(sheetname "")
		)
		(fill
			(thermal_gap 0.5)
			(thermal_bridge_width 0.5)
			(island_removal_mode 0)
		)
		(polygon
			(pts
				(xy 58.13044 -263.377934) (xy 58.13044 -263.047734) (xy 60.67044 -263.047734) (xy 60.67044 -263.377934)
			)
		)
	)
	(zone
		(layer "F.Cu")
		(hatch none 0.5)
		(connect_pads
			(clearance 0)
		)
		(min_thickness 0.25)
		(keepout
			(tracks allowed)
			(vias allowed)
			(pads allowed)
			(copperpour allowed)
			(footprints allowed)
		)
		(placement
			(enabled no)
			(sheetname "")
		)
		(fill
			(thermal_gap 0.5)
			(thermal_bridge_width 0.5)
			(island_removal_mode 0)
		)
		(polygon
			(pts
				(xy 181.929278 -164.498528) (xy 181.929278 -163.123118) (xy 183.944768 -163.123118) (xy 183.944768 -164.498528)
			)
		)
	)
	(zone
		(layer "F.Cu")
		(hatch none 0.5)
		(connect_pads
			(clearance 0)
		)
		(min_thickness 0.25)
		(keepout
			(tracks allowed)
			(vias allowed)
			(pads allowed)
			(copperpour allowed)
			(footprints allowed)
		)
		(placement
			(enabled no)
			(sheetname "")
		)
		(fill
			(thermal_gap 0.5)
			(thermal_bridge_width 0.5)
			(island_removal_mode 0)
		)
		(polygon
			(pts
				(xy 162.37458 -194.52082) (xy 162.37458 -191.38138) (xy 208.58988 -191.38138) (xy 208.58988 -194.52082)
			)
		)
	)
	(zone
		(layer "F.Cu")
		(hatch none 0.5)
		(connect_pads
			(clearance 0)
		)
		(min_thickness 0.25)
		(keepout
			(tracks allowed)
			(vias allowed)
			(pads allowed)
			(copperpour allowed)
			(footprints allowed)
		)
		(placement
			(enabled no)
			(sheetname "")
		)
		(fill
			(thermal_gap 0.5)
			(thermal_bridge_width 0.5)
			(island_removal_mode 0)
		)
		(polygon
			(pts
				(xy 205.101952 -136.146286) (xy 205.101952 -135.437626) (xy 206.374492 -135.437626) (xy 206.374492 -136.146286)
			)
		)
	)
	(zone
		(layer "F.Cu")
		(hatch none 0.5)
		(connect_pads
			(clearance 0)
		)
		(min_thickness 0.25)
		(keepout
			(tracks allowed)
			(vias allowed)
			(pads allowed)
			(copperpour allowed)
			(footprints allowed)
		)
		(placement
			(enabled no)
			(sheetname "")
		)
		(fill
			(thermal_gap 0.5)
			(thermal_bridge_width 0.5)
			(island_removal_mode 0)
		)
		(polygon
			(pts
				(xy 306.070508 -214.927688) (xy 306.070508 -214.597488) (xy 308.610508 -214.597488) (xy 308.610508 -214.927688)
			)
		)
	)
	(zone
		(layer "F.Cu")
		(hatch none 0.5)
		(connect_pads
			(clearance 0)
		)
		(min_thickness 0.25)
		(keepout
			(tracks allowed)
			(vias allowed)
			(pads allowed)
			(copperpour allowed)
			(footprints not_allowed)
		)
		(placement
			(enabled no)
			(sheetname "")
		)
		(fill
			(thermal_gap 0.5)
			(thermal_bridge_width 0.5)
			(island_removal_mode 0)
		)
		(polygon
			(pts
				(arc
					(start 57.815988 -167.135048)
					(mid 54.716172 -170.234864)
					(end 51.616102 -167.135048)
				)
				(arc
					(start 51.616102 -167.135048)
					(mid 54.716172 -164.034978)
					(end 57.815988 -167.135048)
				)
			)
		)
	)
	(zone
		(layer "F.Cu")
		(hatch none 0.5)
		(connect_pads
			(clearance 0)
		)
		(min_thickness 0.25)
		(keepout
			(tracks allowed)
			(vias allowed)
			(pads allowed)
			(copperpour allowed)
			(footprints allowed)
		)
		(placement
			(enabled no)
			(sheetname "")
		)
		(fill
			(thermal_gap 0.5)
			(thermal_bridge_width 0.5)
			(island_removal_mode 0)
		)
		(polygon
			(pts
				(xy 272.64487 -332.196694) (xy 272.64487 -334.101694) (xy 276.65807 -334.101694) (xy 276.65807 -332.196694)
			)
		)
	)
	(zone
		(layer "F.Cu")
		(hatch none 0.5)
		(connect_pads
			(clearance 0)
		)
		(min_thickness 0.25)
		(keepout
			(tracks allowed)
			(vias allowed)
			(pads allowed)
			(copperpour allowed)
			(footprints allowed)
		)
		(placement
			(enabled no)
			(sheetname "")
		)
		(fill
			(thermal_gap 0.5)
			(thermal_bridge_width 0.5)
			(island_removal_mode 0)
		)
		(polygon
			(pts
				(xy 329.08621 -335.708752) (xy 327.28281 -335.708752) (xy 327.28281 -337.258152) (xy 329.08621 -337.258152)
			)
		)
	)
	(zone
		(layer "F.Cu")
		(hatch none 0.5)
		(connect_pads
			(clearance 0)
		)
		(min_thickness 0.25)
		(keepout
			(tracks allowed)
			(vias allowed)
			(pads allowed)
			(copperpour allowed)
			(footprints allowed)
		)
		(placement
			(enabled no)
			(sheetname "")
		)
		(fill
			(thermal_gap 0.5)
			(thermal_bridge_width 0.5)
			(island_removal_mode 0)
		)
		(polygon
			(pts
				(xy 370.939822 -384.406902) (xy 370.939822 -383.40284) (xy 372.336314 -383.40284) (xy 372.336314 -384.406902)
			)
		)
	)
	(zone
		(layer "F.Cu")
		(hatch none 0.5)
		(connect_pads
			(clearance 0)
		)
		(min_thickness 0.25)
		(keepout
			(tracks allowed)
			(vias allowed)
			(pads allowed)
			(copperpour allowed)
			(footprints not_allowed)
		)
		(placement
			(enabled no)
			(sheetname "")
		)
		(fill
			(thermal_gap 0.5)
			(thermal_bridge_width 0.5)
			(island_removal_mode 0)
		)
		(polygon
			(pts
				(xy 137.196068 -141.865096) (xy 129.09677 -141.865096) (xy 129.09677 -150.80488) (xy 137.196068 -150.80488)
			)
		)
	)
	(zone
		(layer "F.Cu")
		(hatch none 0.5)
		(connect_pads
			(clearance 0)
		)
		(min_thickness 0.25)
		(keepout
			(tracks allowed)
			(vias allowed)
			(pads allowed)
			(copperpour allowed)
			(footprints not_allowed)
		)
		(placement
			(enabled no)
			(sheetname "")
		)
		(fill
			(thermal_gap 0.5)
			(thermal_bridge_width 0.5)
			(island_removal_mode 0)
		)
		(polygon
			(pts
				(arc
					(start 151.230076 -258.890008)
					(mid 154.030172 -256.089912)
					(end 156.830014 -258.890008)
				)
				(arc
					(start 156.830014 -258.890008)
					(mid 154.030172 -261.68985)
					(end 151.230076 -258.890008)
				)
			)
		)
	)
	(zone
		(layer "F.Cu")
		(hatch none 0.5)
		(connect_pads
			(clearance 0)
		)
		(min_thickness 0.25)
		(keepout
			(tracks not_allowed)
			(vias allowed)
			(pads allowed)
			(copperpour not_allowed)
			(footprints allowed)
		)
		(placement
			(enabled no)
			(sheetname "")
		)
		(fill
			(thermal_gap 0.5)
			(thermal_bridge_width 0.5)
			(island_removal_mode 0)
		)
		(polygon
			(pts
				(arc
					(start 458.659992 -347.700092)
					(mid 461.460088 -344.899996)
					(end 464.25993 -347.700092)
				)
				(arc
					(start 464.25993 -347.700092)
					(mid 461.460088 -350.499934)
					(end 458.659992 -347.700092)
				)
			)
		)
	)
	(zone
		(layer "F.Cu")
		(hatch none 0.5)
		(connect_pads
			(clearance 0)
		)
		(min_thickness 0.25)
		(keepout
			(tracks allowed)
			(vias allowed)
			(pads allowed)
			(copperpour allowed)
			(footprints not_allowed)
		)
		(placement
			(enabled no)
			(sheetname "")
		)
		(fill
			(thermal_gap 0.5)
			(thermal_bridge_width 0.5)
			(island_removal_mode 0)
		)
		(polygon
			(pts
				(xy 447.691002 -327.609962) (xy 447.691002 -183.50992) (xy 441.491116 -183.50992) (xy 441.491116 -327.609962)
			)
		)
	)
	(zone
		(layer "F.Cu")
		(hatch none 0.5)
		(connect_pads
			(clearance 0)
		)
		(min_thickness 0.25)
		(keepout
			(tracks not_allowed)
			(vias allowed)
			(pads allowed)
			(copperpour not_allowed)
			(footprints allowed)
		)
		(placement
			(enabled no)
			(sheetname "")
		)
		(fill
			(thermal_gap 0.5)
			(thermal_bridge_width 0.5)
			(island_removal_mode 0)
		)
		(polygon
			(pts
				(arc
					(start 405.470106 -258.890008)
					(mid 401.97024 -262.389874)
					(end 398.47012 -258.890008)
				)
				(arc
					(start 398.47012 -258.890008)
					(mid 401.97024 -255.389888)
					(end 405.470106 -258.890008)
				)
			)
		)
	)
	(zone
		(layer "F.Cu")
		(hatch none 0.5)
		(connect_pads
			(clearance 0)
		)
		(min_thickness 0.25)
		(keepout
			(tracks allowed)
			(vias allowed)
			(pads allowed)
			(copperpour allowed)
			(footprints allowed)
		)
		(placement
			(enabled no)
			(sheetname "")
		)
		(fill
			(thermal_gap 0.5)
			(thermal_bridge_width 0.5)
			(island_removal_mode 0)
		)
		(polygon
			(pts
				(xy 411.317694 -314.892436) (xy 411.317694 -315.222636) (xy 413.236664 -315.222636) (xy 413.236664 -314.892436)
			)
		)
	)
	(zone
		(layer "F.Cu")
		(hatch none 0.5)
		(connect_pads
			(clearance 0)
		)
		(min_thickness 0.25)
		(keepout
			(tracks allowed)
			(vias allowed)
			(pads allowed)
			(copperpour allowed)
			(footprints allowed)
		)
		(placement
			(enabled no)
			(sheetname "")
		)
		(fill
			(thermal_gap 0.5)
			(thermal_bridge_width 0.5)
			(island_removal_mode 0)
		)
		(polygon
			(pts
				(xy 151.829516 -193.167) (xy 151.829516 -192.659) (xy 152.025096 -192.659) (xy 152.025096 -193.167)
			)
		)
	)
	(zone
		(layer "F.Cu")
		(hatch none 0.5)
		(connect_pads
			(clearance 0)
		)
		(min_thickness 0.25)
		(keepout
			(tracks allowed)
			(vias allowed)
			(pads allowed)
			(copperpour allowed)
			(footprints not_allowed)
		)
		(placement
			(enabled no)
			(sheetname "")
		)
		(fill
			(thermal_gap 0.5)
			(thermal_bridge_width 0.5)
			(island_removal_mode 0)
		)
		(polygon
			(pts
				(xy 438.85993 -404.850092) (xy 460.259938 -404.850092) (xy 460.259938 -394.24991) (xy 438.85993 -394.24991)
			)
		)
	)
	(zone
		(layer "F.Cu")
		(hatch none 0.5)
		(connect_pads
			(clearance 0)
		)
		(min_thickness 0.25)
		(keepout
			(tracks allowed)
			(vias allowed)
			(pads allowed)
			(copperpour allowed)
			(footprints allowed)
		)
		(placement
			(enabled no)
			(sheetname "")
		)
		(fill
			(thermal_gap 0.5)
			(thermal_bridge_width 0.5)
			(island_removal_mode 0)
		)
		(polygon
			(pts
				(xy 39.584376 -346.61729) (xy 33.234376 -346.61729) (xy 32.599376 -347.25229) (xy 32.599376 -351.82429)
				(xy 33.234376 -352.45929) (xy 39.203376 -352.45929) (xy 39.711376 -351.95129) (xy 39.711376 -346.74429)
			)
		)
	)
	(zone
		(layer "F.Cu")
		(hatch none 0.5)
		(connect_pads
			(clearance 0)
		)
		(min_thickness 0.25)
		(keepout
			(tracks allowed)
			(vias allowed)
			(pads allowed)
			(copperpour allowed)
			(footprints allowed)
		)
		(placement
			(enabled no)
			(sheetname "")
		)
		(fill
			(thermal_gap 0.5)
			(thermal_bridge_width 0.5)
			(island_removal_mode 0)
		)
		(polygon
			(pts
				(xy 89.690956 -59.239912) (xy 89.690956 -58.91022) (xy 90.12555 -58.91022) (xy 90.12555 -59.239912)
			)
		)
	)
	(zone
		(layer "F.Cu")
		(hatch none 0.5)
		(connect_pads
			(clearance 0)
		)
		(min_thickness 0.25)
		(keepout
			(tracks allowed)
			(vias allowed)
			(pads allowed)
			(copperpour allowed)
			(footprints allowed)
		)
		(placement
			(enabled no)
			(sheetname "")
		)
		(fill
			(thermal_gap 0.5)
			(thermal_bridge_width 0.5)
			(island_removal_mode 0)
		)
		(polygon
			(pts
				(xy 345.684094 -173.754542) (xy 345.684094 -175.659542) (xy 349.697294 -175.659542) (xy 349.697294 -173.754542)
			)
		)
	)
	(zone
		(layer "F.Cu")
		(hatch none 0.5)
		(connect_pads
			(clearance 0)
		)
		(min_thickness 0.25)
		(keepout
			(tracks allowed)
			(vias allowed)
			(pads allowed)
			(copperpour allowed)
			(footprints allowed)
		)
		(placement
			(enabled no)
			(sheetname "")
		)
		(fill
			(thermal_gap 0.5)
			(thermal_bridge_width 0.5)
			(island_removal_mode 0)
		)
		(polygon
			(pts
				(xy 163.377626 -310.128158) (xy 163.377626 -309.797958) (xy 165.296596 -309.797958) (xy 165.296596 -310.128158)
			)
		)
	)
	(zone
		(layer "F.Cu")
		(hatch none 0.5)
		(connect_pads
			(clearance 0)
		)
		(min_thickness 0.25)
		(keepout
			(tracks not_allowed)
			(vias allowed)
			(pads allowed)
			(copperpour not_allowed)
			(footprints allowed)
		)
		(placement
			(enabled no)
			(sheetname "")
		)
		(fill
			(thermal_gap 0.5)
			(thermal_bridge_width 0.5)
			(island_removal_mode 0)
		)
		(polygon
			(pts
				(arc
					(start 393.970002 -212.989922)
					(mid 390.470136 -216.489788)
					(end 386.970016 -212.989922)
				)
				(arc
					(start 386.970016 -212.989922)
					(mid 390.470136 -209.489802)
					(end 393.970002 -212.989922)
				)
			)
		)
	)
	(zone
		(layer "F.Cu")
		(hatch none 0.5)
		(connect_pads
			(clearance 0)
		)
		(min_thickness 0.25)
		(keepout
			(tracks allowed)
			(vias allowed)
			(pads allowed)
			(copperpour allowed)
			(footprints allowed)
		)
		(placement
			(enabled no)
			(sheetname "")
		)
		(fill
			(thermal_gap 0.5)
			(thermal_bridge_width 0.5)
			(island_removal_mode 0)
		)
		(polygon
			(pts
				(xy 411.317694 -237.02772) (xy 411.317694 -236.69752) (xy 413.236664 -236.69752) (xy 413.236664 -237.02772)
			)
		)
	)
	(zone
		(layer "F.Cu")
		(hatch none 0.5)
		(connect_pads
			(clearance 0)
		)
		(min_thickness 0.25)
		(keepout
			(tracks allowed)
			(vias allowed)
			(pads allowed)
			(copperpour allowed)
			(footprints not_allowed)
		)
		(placement
			(enabled no)
			(sheetname "")
		)
		(fill
			(thermal_gap 0.5)
			(thermal_bridge_width 0.5)
			(island_removal_mode 0)
		)
		(polygon
			(pts
				(arc
					(start 262.347964 -149.999954)
					(mid 263.055069 -150.292847)
					(end 263.347962 -150.999952)
				)
				(xy 263.347962 -165.596062) (xy 309.568088 -165.596062) (xy 309.568088 -342.914986) (xy 312.951876 -342.914986)
				(xy 312.951876 -331.185012) (xy 347.451934 -331.185012) (xy 347.451934 -336.12455) (xy 364.842044 -336.125058)
				(xy 364.842044 -344.914982) (xy 357.006906 -344.914982) (xy 357.006906 -350.415098) (xy 340.80704 -350.415098)
				(xy 340.80704 -346.734892) (xy 321.567048 -346.734892) (xy 321.567048 -351.605088) (xy 409.571952 -351.605088)
				(xy 409.571952 -347.134942) (xy 410.16809 -347.134942) (xy 410.16809 -258.990084) (xy 406.567894 -258.990084)
				(xy 406.567894 -319.030096) (xy 313.16803 -319.030096) (xy 313.16803 -198.579994) (xy 406.567894 -198.579994)
				(xy 406.567894 -258.890008) (xy 410.16809 -258.890008) (xy 410.16809 -172.235114) (xy 402.592032 -172.235114)
				(xy 402.592032 -180.865018) (xy 394.30198 -180.865018) (xy 394.30198 -186.485022) (xy 367.95202 -186.485022)
				(xy 367.95202 -181.464966) (xy 360.352848 -181.464966) (xy 360.352848 -173.185074) (xy 351.553018 -173.185074)
				(xy 351.553018 -164.885116) (xy 343.462102 -164.885116) (xy 343.462102 -154.617928) (xy 343.462102 -144.808448)
				(xy 288.395664 -144.808448) (xy 288.393886 -161.291524) (xy 267.393928 -161.289492) (xy 267.395706 -144.808448)
				(xy 249.934984 -144.808448)
				(arc
					(start 249.934984 -148.999956)
					(mid 250.227877 -149.707061)
					(end 250.934982 -149.999954)
				)
			)
		)
	)
	(zone
		(layer "F.Cu")
		(hatch none 0.5)
		(connect_pads
			(clearance 0)
		)
		(min_thickness 0.25)
		(keepout
			(tracks allowed)
			(vias allowed)
			(pads allowed)
			(copperpour allowed)
			(footprints not_allowed)
		)
		(placement
			(enabled no)
			(sheetname "")
		)
		(fill
			(thermal_gap 0.5)
			(thermal_bridge_width 0.5)
			(island_removal_mode 0)
		)
		(polygon
			(pts
				(arc
					(start 209.650076 -51.999896)
					(mid 204.650086 -56.999886)
					(end 199.650096 -51.999896)
				)
				(arc
					(start 199.650096 -51.999896)
					(mid 204.650086 -46.999906)
					(end 209.650076 -51.999896)
				)
			)
		)
	)
	(zone
		(layer "F.Cu")
		(hatch none 0.5)
		(connect_pads
			(clearance 0)
		)
		(min_thickness 0.25)
		(keepout
			(tracks allowed)
			(vias allowed)
			(pads allowed)
			(copperpour allowed)
			(footprints allowed)
		)
		(placement
			(enabled no)
			(sheetname "")
		)
		(fill
			(thermal_gap 0.5)
			(thermal_bridge_width 0.5)
			(island_removal_mode 0)
		)
		(polygon
			(pts
				(xy 235.802932 -59.239404) (xy 235.802932 -49.399952) (xy 237.93704 -49.399952) (xy 237.93704 -59.239404)
			)
		)
	)
	(zone
		(layer "F.Cu")
		(hatch none 0.5)
		(connect_pads
			(clearance 0)
		)
		(min_thickness 0.25)
		(keepout
			(tracks not_allowed)
			(vias allowed)
			(pads allowed)
			(copperpour not_allowed)
			(footprints allowed)
		)
		(placement
			(enabled no)
			(sheetname "")
		)
		(fill
			(thermal_gap 0.5)
			(thermal_bridge_width 0.5)
			(island_removal_mode 0)
		)
		(polygon
			(pts
				(arc
					(start 110.850934 -340.315042)
					(mid 112.716056 -338.44992)
					(end 114.580924 -340.315042)
				)
				(arc
					(start 114.580924 -340.315042)
					(mid 112.716056 -342.17991)
					(end 110.850934 -340.315042)
				)
			)
		)
	)
	(zone
		(layer "F.Cu")
		(hatch none 0.5)
		(connect_pads
			(clearance 0)
		)
		(min_thickness 0.25)
		(keepout
			(tracks allowed)
			(vias allowed)
			(pads allowed)
			(copperpour allowed)
			(footprints allowed)
		)
		(placement
			(enabled no)
			(sheetname "")
		)
		(fill
			(thermal_gap 0.5)
			(thermal_bridge_width 0.5)
			(island_removal_mode 0)
		)
		(polygon
			(pts
				(xy 411.317694 -262.527796) (xy 411.317694 -262.197596) (xy 413.236664 -262.197596) (xy 413.236664 -262.527796)
			)
		)
	)
	(zone
		(layer "F.Cu")
		(hatch none 0.5)
		(connect_pads
			(clearance 0)
		)
		(min_thickness 0.25)
		(keepout
			(tracks allowed)
			(vias allowed)
			(pads allowed)
			(copperpour allowed)
			(footprints allowed)
		)
		(placement
			(enabled no)
			(sheetname "")
		)
		(fill
			(thermal_gap 0.5)
			(thermal_bridge_width 0.5)
			(island_removal_mode 0)
		)
		(polygon
			(pts
				(xy 337.732878 -334.84947) (xy 331.382878 -334.84947) (xy 330.747878 -335.48447) (xy 330.747878 -340.05647)
				(xy 331.382878 -340.69147) (xy 337.351878 -340.69147) (xy 337.859878 -340.18347) (xy 337.859878 -334.97647)
			)
		)
	)
	(zone
		(layer "F.Cu")
		(hatch none 0.5)
		(connect_pads
			(clearance 0)
		)
		(min_thickness 0.25)
		(keepout
			(tracks allowed)
			(vias allowed)
			(pads allowed)
			(copperpour allowed)
			(footprints allowed)
		)
		(placement
			(enabled no)
			(sheetname "")
		)
		(fill
			(thermal_gap 0.5)
			(thermal_bridge_width 0.5)
			(island_removal_mode 0)
		)
		(polygon
			(pts
				(xy 236.605318 -307.438806) (xy 236.605318 -306.60086) (xy 237.00613 -306.60086) (xy 237.00613 -307.438806)
			)
		)
	)
	(zone
		(layer "F.Cu")
		(hatch none 0.5)
		(connect_pads
			(clearance 0)
		)
		(min_thickness 0.25)
		(keepout
			(tracks not_allowed)
			(vias allowed)
			(pads allowed)
			(copperpour not_allowed)
			(footprints allowed)
		)
		(placement
			(enabled no)
			(sheetname "")
		)
		(fill
			(thermal_gap 0.5)
			(thermal_bridge_width 0.5)
			(island_removal_mode 0)
		)
		(polygon
			(pts
				(xy 306.194714 -345.967812) (xy 306.194714 -346.424504) (xy 306.89042 -346.424504) (xy 306.89042 -346.263976)
				(xy 307.44922 -346.263976) (xy 307.44922 -346.670376) (xy 306.89042 -346.670376) (xy 306.89042 -346.449904)
				(xy 306.194714 -346.449904) (xy 306.194714 -346.576904) (xy 306.65039 -346.576904) (xy 306.65039 -346.963492)
				(xy 306.892706 -346.963492) (xy 307.424582 -346.963492) (xy 307.744114 -346.64396) (xy 307.744114 -345.967812)
			)
		)
	)
	(zone
		(layer "F.Cu")
		(hatch none 0.5)
		(connect_pads
			(clearance 0)
		)
		(min_thickness 0.25)
		(keepout
			(tracks allowed)
			(vias allowed)
			(pads allowed)
			(copperpour allowed)
			(footprints allowed)
		)
		(placement
			(enabled no)
			(sheetname "")
		)
		(fill
			(thermal_gap 0.5)
			(thermal_bridge_width 0.5)
			(island_removal_mode 0)
		)
		(polygon
			(pts
				(xy 90.94343 -146.188176) (xy 90.94343 -145.623534) (xy 91.501976 -145.623534) (xy 91.501976 -146.188176)
			)
		)
	)
	(zone
		(layer "F.Cu")
		(hatch none 0.5)
		(connect_pads
			(clearance 0)
		)
		(min_thickness 0.25)
		(keepout
			(tracks allowed)
			(vias allowed)
			(pads allowed)
			(copperpour allowed)
			(footprints allowed)
		)
		(placement
			(enabled no)
			(sheetname "")
		)
		(fill
			(thermal_gap 0.5)
			(thermal_bridge_width 0.5)
			(island_removal_mode 0)
		)
		(polygon
			(pts
				(xy 72.860662 -335.505298) (xy 71.057262 -335.505298) (xy 71.057262 -337.054698) (xy 72.860662 -337.054698)
			)
		)
	)
	(zone
		(layer "F.Cu")
		(hatch none 0.5)
		(connect_pads
			(clearance 0)
		)
		(min_thickness 0.25)
		(keepout
			(tracks allowed)
			(vias allowed)
			(pads allowed)
			(copperpour allowed)
			(footprints allowed)
		)
		(placement
			(enabled no)
			(sheetname "")
		)
		(fill
			(thermal_gap 0.5)
			(thermal_bridge_width 0.5)
			(island_removal_mode 0)
		)
		(polygon
			(pts
				(xy 308.66588 -309.79237) (xy 308.66588 -310.12257) (xy 306.12588 -310.12257) (xy 306.12588 -309.79237)
			)
		)
	)
	(zone
		(layer "F.Cu")
		(hatch none 0.5)
		(connect_pads
			(clearance 0)
		)
		(min_thickness 0.25)
		(keepout
			(tracks not_allowed)
			(vias allowed)
			(pads allowed)
			(copperpour not_allowed)
			(footprints allowed)
		)
		(placement
			(enabled no)
			(sheetname "")
		)
		(fill
			(thermal_gap 0.5)
			(thermal_bridge_width 0.5)
			(island_removal_mode 0)
		)
		(polygon
			(pts
				(arc
					(start 46.071028 -244.085364)
					(mid 45.403008 -244.085364)
					(end 46.071028 -244.085364)
				)
			)
		)
	)
	(zone
		(layer "F.Cu")
		(hatch none 0.5)
		(connect_pads
			(clearance 0)
		)
		(min_thickness 0.25)
		(keepout
			(tracks not_allowed)
			(vias allowed)
			(pads allowed)
			(copperpour not_allowed)
			(footprints allowed)
		)
		(placement
			(enabled no)
			(sheetname "")
		)
		(fill
			(thermal_gap 0.5)
			(thermal_bridge_width 0.5)
			(island_removal_mode 0)
		)
		(polygon
			(pts
				(xy 176.308258 -38.160198) (xy 177.908458 -38.160198) (xy 177.959258 -38.109398) (xy 177.959258 -37.990272)
				(xy 177.908458 -37.939472) (xy 176.308258 -37.939472) (xy 176.257458 -37.990272) (xy 176.257458 -38.109398)
			)
		)
	)
	(zone
		(layer "F.Cu")
		(hatch none 0.5)
		(connect_pads
			(clearance 0)
		)
		(min_thickness 0.25)
		(keepout
			(tracks allowed)
			(vias allowed)
			(pads allowed)
			(copperpour allowed)
			(footprints allowed)
		)
		(placement
			(enabled no)
			(sheetname "")
		)
		(fill
			(thermal_gap 0.5)
			(thermal_bridge_width 0.5)
			(island_removal_mode 0)
		)
		(polygon
			(pts
				(xy 384.21056 -139.54506) (xy 384.21056 -138.84656) (xy 385.48564 -138.84656) (xy 385.48564 -139.54506)
			)
		)
	)
	(zone
		(layer "F.Cu")
		(hatch none 0.5)
		(connect_pads
			(clearance 0)
		)
		(min_thickness 0.25)
		(keepout
			(tracks not_allowed)
			(vias allowed)
			(pads allowed)
			(copperpour not_allowed)
			(footprints allowed)
		)
		(placement
			(enabled no)
			(sheetname "")
		)
		(fill
			(thermal_gap 0.5)
			(thermal_bridge_width 0.5)
			(island_removal_mode 0)
		)
		(polygon
			(pts
				(xy 168.758108 -38.910006) (xy 170.358308 -38.910006) (xy 170.409108 -38.859206) (xy 170.409108 -38.74008)
				(xy 170.358308 -38.68928) (xy 168.758108 -38.68928) (xy 168.707308 -38.74008) (xy 168.707308 -38.859206)
			)
		)
	)
	(zone
		(layer "F.Cu")
		(hatch none 0.5)
		(connect_pads
			(clearance 0)
		)
		(min_thickness 0.25)
		(keepout
			(tracks not_allowed)
			(vias allowed)
			(pads allowed)
			(copperpour not_allowed)
			(footprints allowed)
		)
		(placement
			(enabled no)
			(sheetname "")
		)
		(fill
			(thermal_gap 0.5)
			(thermal_bridge_width 0.5)
			(island_removal_mode 0)
		)
		(polygon
			(pts
				(xy 101.118416 -181.993032) (xy 101.118416 -181.03215) (xy 100.8761 -181.03215) (xy 100.8761 -181.993032)
			)
		)
	)
	(zone
		(layer "F.Cu")
		(hatch none 0.5)
		(connect_pads
			(clearance 0)
		)
		(min_thickness 0.25)
		(keepout
			(tracks not_allowed)
			(vias allowed)
			(pads allowed)
			(copperpour not_allowed)
			(footprints allowed)
		)
		(placement
			(enabled no)
			(sheetname "")
		)
		(fill
			(thermal_gap 0.5)
			(thermal_bridge_width 0.5)
			(island_removal_mode 0)
		)
		(polygon
			(pts
				(xy 426.11421 -401.903184) (xy 428.203106 -401.903184) (xy 428.203106 -400.84502) (xy 428.060358 -400.84502)
				(xy 428.060358 -401.760436) (xy 426.256958 -401.760436) (xy 426.256958 -400.884136) (xy 426.11421 -400.884136)
			)
		)
	)
	(zone
		(layer "F.Cu")
		(hatch none 0.5)
		(connect_pads
			(clearance 0)
		)
		(min_thickness 0.25)
		(keepout
			(tracks allowed)
			(vias allowed)
			(pads allowed)
			(copperpour allowed)
			(footprints not_allowed)
		)
		(placement
			(enabled no)
			(sheetname "")
		)
		(fill
			(thermal_gap 0.5)
			(thermal_bridge_width 0.5)
			(island_removal_mode 0)
		)
		(polygon
			(pts
				(xy 2.999994 -338.15909) (xy 11.66495 -338.15909) (xy 11.66495 -320.36004) (xy 2.999994 -320.36004)
			)
		)
	)
	(zone
		(layer "F.Cu")
		(hatch none 0.5)
		(connect_pads
			(clearance 0)
		)
		(min_thickness 0.25)
		(keepout
			(tracks not_allowed)
			(vias allowed)
			(pads allowed)
			(copperpour not_allowed)
			(footprints allowed)
		)
		(placement
			(enabled no)
			(sheetname "")
		)
		(fill
			(thermal_gap 0.5)
			(thermal_bridge_width 0.5)
			(island_removal_mode 0)
		)
		(polygon
			(pts
				(arc
					(start 233.849926 -192.499996)
					(mid 236.650022 -189.6999)
					(end 239.450118 -192.499996)
				)
				(arc
					(start 239.450118 -192.499996)
					(mid 236.650022 -195.300092)
					(end 233.849926 -192.499996)
				)
			)
		)
	)
	(zone
		(layer "F.Cu")
		(hatch none 0.5)
		(connect_pads
			(clearance 0)
		)
		(min_thickness 0.25)
		(keepout
			(tracks allowed)
			(vias allowed)
			(pads allowed)
			(copperpour allowed)
			(footprints allowed)
		)
		(placement
			(enabled no)
			(sheetname "")
		)
		(fill
			(thermal_gap 0.5)
			(thermal_bridge_width 0.5)
			(island_removal_mode 0)
		)
		(polygon
			(pts
				(xy 163.634928 -219.178124) (xy 163.634928 -218.847924) (xy 165.296596 -218.847924) (xy 165.296596 -219.178124)
			)
		)
	)
	(zone
		(layer "F.Cu")
		(hatch none 0.5)
		(connect_pads
			(clearance 0)
		)
		(min_thickness 0.25)
		(keepout
			(tracks not_allowed)
			(vias allowed)
			(pads allowed)
			(copperpour not_allowed)
			(footprints allowed)
		)
		(placement
			(enabled no)
			(sheetname "")
		)
		(fill
			(thermal_gap 0.5)
			(thermal_bridge_width 0.5)
			(island_removal_mode 0)
		)
		(polygon
			(pts
				(xy 168.758108 -38.410134) (xy 170.358308 -38.410134) (xy 170.409108 -38.359334) (xy 170.409108 -38.240208)
				(xy 170.358308 -38.189408) (xy 168.758108 -38.189408) (xy 168.707308 -38.240208) (xy 168.707308 -38.359334)
			)
		)
	)
	(zone
		(layer "F.Cu")
		(hatch none 0.5)
		(connect_pads
			(clearance 0)
		)
		(min_thickness 0.25)
		(keepout
			(tracks not_allowed)
			(vias allowed)
			(pads allowed)
			(copperpour not_allowed)
			(footprints allowed)
		)
		(placement
			(enabled no)
			(sheetname "")
		)
		(fill
			(thermal_gap 0.5)
			(thermal_bridge_width 0.5)
			(island_removal_mode 0)
		)
		(polygon
			(pts
				(arc
					(start 447.250058 -435.600094)
					(mid 448.799966 -434.050186)
					(end 450.349874 -435.600094)
				)
				(arc
					(start 450.349874 -435.600094)
					(mid 448.799966 -437.150002)
					(end 447.250058 -435.600094)
				)
			)
		)
	)
	(zone
		(layer "F.Cu")
		(hatch none 0.5)
		(connect_pads
			(clearance 0)
		)
		(min_thickness 0.25)
		(keepout
			(tracks allowed)
			(vias allowed)
			(pads allowed)
			(copperpour allowed)
			(footprints not_allowed)
		)
		(placement
			(enabled no)
			(sheetname "")
		)
		(fill
			(thermal_gap 0.5)
			(thermal_bridge_width 0.5)
			(island_removal_mode 0)
		)
		(polygon
			(pts
				(arc
					(start 225.000058 -290.900104)
					(mid 221.899988 -294.000174)
					(end 218.799918 -290.900104)
				)
				(arc
					(start 218.799918 -290.900104)
					(mid 221.899988 -287.800034)
					(end 225.000058 -290.900104)
				)
			)
		)
	)
	(zone
		(layer "F.Cu")
		(hatch none 0.5)
		(connect_pads
			(clearance 0)
		)
		(min_thickness 0.25)
		(keepout
			(tracks allowed)
			(vias allowed)
			(pads allowed)
			(copperpour allowed)
			(footprints allowed)
		)
		(placement
			(enabled no)
			(sheetname "")
		)
		(fill
			(thermal_gap 0.5)
			(thermal_bridge_width 0.5)
			(island_removal_mode 0)
		)
		(polygon
			(pts
				(xy 411.562042 -210.67776) (xy 411.562042 -210.34756) (xy 413.236664 -210.34756) (xy 413.236664 -210.67776)
			)
		)
	)
	(zone
		(layer "F.Cu")
		(hatch none 0.5)
		(connect_pads
			(clearance 0)
		)
		(min_thickness 0.25)
		(keepout
			(tracks allowed)
			(vias allowed)
			(pads allowed)
			(copperpour allowed)
			(footprints not_allowed)
		)
		(placement
			(enabled no)
			(sheetname "")
		)
		(fill
			(thermal_gap 0.5)
			(thermal_bridge_width 0.5)
			(island_removal_mode 0)
		)
		(polygon
			(pts
				(arc
					(start 94.383098 -45.449998)
					(mid 95.983044 -47.049944)
					(end 94.383098 -48.64989)
				)
				(arc
					(start 92.782898 -48.64989)
					(mid 91.182952 -47.049944)
					(end 92.782898 -45.449998)
				)
			)
		)
	)
	(zone
		(layer "F.Cu")
		(hatch none 0.5)
		(connect_pads
			(clearance 0)
		)
		(min_thickness 0.25)
		(keepout
			(tracks allowed)
			(vias allowed)
			(pads allowed)
			(copperpour allowed)
			(footprints allowed)
		)
		(placement
			(enabled no)
			(sheetname "")
		)
		(fill
			(thermal_gap 0.5)
			(thermal_bridge_width 0.5)
			(island_removal_mode 0)
		)
		(polygon
			(pts
				(xy 325.215504 -384.194812) (xy 326.219566 -384.194812) (xy 326.219566 -385.591304) (xy 325.215504 -385.591304)
			)
		)
	)
	(zone
		(layer "F.Cu")
		(hatch none 0.5)
		(connect_pads
			(clearance 0)
		)
		(min_thickness 0.25)
		(keepout
			(tracks allowed)
			(vias allowed)
			(pads allowed)
			(copperpour allowed)
			(footprints allowed)
		)
		(placement
			(enabled no)
			(sheetname "")
		)
		(fill
			(thermal_gap 0.5)
			(thermal_bridge_width 0.5)
			(island_removal_mode 0)
		)
		(polygon
			(pts
				(xy 338.069428 -381.943102) (xy 338.069428 -380.93904) (xy 339.46592 -380.93904) (xy 339.46592 -381.943102)
			)
		)
	)
	(zone
		(layer "F.Cu")
		(hatch none 0.5)
		(connect_pads
			(clearance 0)
		)
		(min_thickness 0.25)
		(keepout
			(tracks allowed)
			(vias allowed)
			(pads allowed)
			(copperpour allowed)
			(footprints not_allowed)
		)
		(placement
			(enabled no)
			(sheetname "")
		)
		(fill
			(thermal_gap 0.5)
			(thermal_bridge_width 0.5)
			(island_removal_mode 0)
		)
		(polygon
			(pts
				(arc
					(start 466.540088 -399.029936)
					(mid 463.440018 -402.130006)
					(end 460.339948 -399.029936)
				)
				(arc
					(start 460.339948 -399.029936)
					(mid 463.440018 -395.929866)
					(end 466.540088 -399.029936)
				)
			)
		)
	)
	(zone
		(layer "F.Cu")
		(hatch none 0.5)
		(connect_pads
			(clearance 0)
		)
		(min_thickness 0.25)
		(keepout
			(tracks allowed)
			(vias allowed)
			(pads allowed)
			(copperpour allowed)
			(footprints allowed)
		)
		(placement
			(enabled no)
			(sheetname "")
		)
		(fill
			(thermal_gap 0.5)
			(thermal_bridge_width 0.5)
			(island_removal_mode 0)
		)
		(polygon
			(pts
				(xy 310.259222 -347.221556) (xy 308.455822 -347.221556) (xy 308.455822 -348.770956) (xy 310.259222 -348.770956)
			)
		)
	)
	(zone
		(layer "F.Cu")
		(hatch none 0.5)
		(connect_pads
			(clearance 0)
		)
		(min_thickness 0.25)
		(keepout
			(tracks not_allowed)
			(vias allowed)
			(pads allowed)
			(copperpour not_allowed)
			(footprints allowed)
		)
		(placement
			(enabled no)
			(sheetname "")
		)
		(fill
			(thermal_gap 0.5)
			(thermal_bridge_width 0.5)
			(island_removal_mode 0)
		)
		(polygon
			(pts
				(xy 64.908176 -9.094724) (xy 65.025524 -9.094724) (xy 65.076324 -9.043924) (xy 65.076324 -7.596124)
				(xy 65.025524 -7.545324) (xy 64.908176 -7.545324) (xy 64.857376 -7.596124) (xy 64.857376 -9.043924)
			)
		)
	)
	(zone
		(layer "F.Cu")
		(hatch none 0.5)
		(connect_pads
			(clearance 0)
		)
		(min_thickness 0.25)
		(keepout
			(tracks allowed)
			(vias allowed)
			(pads allowed)
			(copperpour allowed)
			(footprints allowed)
		)
		(placement
			(enabled no)
			(sheetname "")
		)
		(fill
			(thermal_gap 0.5)
			(thermal_bridge_width 0.5)
			(island_removal_mode 0)
		)
		(polygon
			(pts
				(xy 47.890176 -346.61729) (xy 41.540176 -346.61729) (xy 40.905176 -347.25229) (xy 40.905176 -351.82429)
				(xy 41.540176 -352.45929) (xy 47.509176 -352.45929) (xy 48.017176 -351.95129) (xy 48.017176 -346.74429)
			)
		)
	)
	(zone
		(layer "F.Cu")
		(hatch none 0.5)
		(connect_pads
			(clearance 0)
		)
		(min_thickness 0.25)
		(keepout
			(tracks not_allowed)
			(vias allowed)
			(pads allowed)
			(copperpour not_allowed)
			(footprints allowed)
		)
		(placement
			(enabled no)
			(sheetname "")
		)
		(fill
			(thermal_gap 0.5)
			(thermal_bridge_width 0.5)
			(island_removal_mode 0)
		)
		(polygon
			(pts
				(arc
					(start 378.100082 -22.29993)
					(mid 380.900178 -19.499834)
					(end 383.70002 -22.29993)
				)
				(arc
					(start 383.70002 -22.29993)
					(mid 380.900178 -25.099772)
					(end 378.100082 -22.29993)
				)
			)
		)
	)
	(zone
		(layer "F.Cu")
		(hatch none 0.5)
		(connect_pads
			(clearance 0)
		)
		(min_thickness 0.25)
		(keepout
			(tracks allowed)
			(vias allowed)
			(pads allowed)
			(copperpour allowed)
			(footprints allowed)
		)
		(placement
			(enabled no)
			(sheetname "")
		)
		(fill
			(thermal_gap 0.5)
			(thermal_bridge_width 0.5)
			(island_removal_mode 0)
		)
		(polygon
			(pts
				(xy 411.317694 -216.62771) (xy 411.317694 -216.29751) (xy 413.236664 -216.29751) (xy 413.236664 -216.62771)
			)
		)
	)
	(zone
		(layer "F.Cu")
		(hatch none 0.5)
		(connect_pads
			(clearance 0)
		)
		(min_thickness 0.25)
		(keepout
			(tracks allowed)
			(vias allowed)
			(pads allowed)
			(copperpour allowed)
			(footprints allowed)
		)
		(placement
			(enabled no)
			(sheetname "")
		)
		(fill
			(thermal_gap 0.5)
			(thermal_bridge_width 0.5)
			(island_removal_mode 0)
		)
		(polygon
			(pts
				(xy 149.169628 -373.561102) (xy 149.169628 -372.55704) (xy 150.56612 -372.55704) (xy 150.56612 -373.561102)
			)
		)
	)
	(zone
		(layer "F.Cu")
		(hatch none 0.5)
		(connect_pads
			(clearance 0)
		)
		(min_thickness 0.25)
		(keepout
			(tracks allowed)
			(vias allowed)
			(pads allowed)
			(copperpour allowed)
			(footprints allowed)
		)
		(placement
			(enabled no)
			(sheetname "")
		)
		(fill
			(thermal_gap 0.5)
			(thermal_bridge_width 0.5)
			(island_removal_mode 0)
		)
		(polygon
			(pts
				(xy 308.28488 -228.192584) (xy 308.28488 -228.522784) (xy 305.74488 -228.522784) (xy 305.74488 -228.192584)
			)
		)
	)
	(zone
		(layer "F.Cu")
		(hatch none 0.5)
		(connect_pads
			(clearance 0)
		)
		(min_thickness 0.25)
		(keepout
			(tracks not_allowed)
			(vias allowed)
			(pads allowed)
			(copperpour not_allowed)
			(footprints allowed)
		)
		(placement
			(enabled no)
			(sheetname "")
		)
		(fill
			(thermal_gap 0.5)
			(thermal_bridge_width 0.5)
			(island_removal_mode 0)
		)
		(polygon
			(pts
				(arc
					(start 146.029934 -304.790094)
					(mid 142.530068 -308.28996)
					(end 139.029948 -304.790094)
				)
				(arc
					(start 139.029948 -304.790094)
					(mid 142.530068 -301.289974)
					(end 146.029934 -304.790094)
				)
			)
		)
	)
	(zone
		(layer "F.Cu")
		(hatch none 0.5)
		(connect_pads
			(clearance 0)
		)
		(min_thickness 0.25)
		(keepout
			(tracks allowed)
			(vias allowed)
			(pads allowed)
			(copperpour allowed)
			(footprints not_allowed)
		)
		(placement
			(enabled no)
			(sheetname "")
		)
		(fill
			(thermal_gap 0.5)
			(thermal_bridge_width 0.5)
			(island_removal_mode 0)
		)
		(polygon
			(pts
				(xy 343.462102 -154.617928) (xy 343.462102 -143.215106) (xy 352.222054 -143.215106) (xy 352.222054 -154.617928)
			)
		)
	)
	(zone
		(layer "F.Cu")
		(hatch none 0.5)
		(connect_pads
			(clearance 0)
		)
		(min_thickness 0.25)
		(keepout
			(tracks not_allowed)
			(vias allowed)
			(pads allowed)
			(copperpour not_allowed)
			(footprints allowed)
		)
		(placement
			(enabled no)
			(sheetname "")
		)
		(fill
			(thermal_gap 0.5)
			(thermal_bridge_width 0.5)
			(island_removal_mode 0)
		)
		(polygon
			(pts
				(arc
					(start 45.569886 -404.789894)
					(mid 41.569894 -408.789886)
					(end 37.569902 -404.789894)
				)
				(arc
					(start 37.569902 -404.789894)
					(mid 41.569894 -400.789902)
					(end 45.569886 -404.789894)
				)
			)
		)
	)
	(zone
		(layer "F.Cu")
		(hatch none 0.5)
		(connect_pads
			(clearance 0)
		)
		(min_thickness 0.25)
		(keepout
			(tracks allowed)
			(vias allowed)
			(pads allowed)
			(copperpour allowed)
			(footprints allowed)
		)
		(placement
			(enabled no)
			(sheetname "")
		)
		(fill
			(thermal_gap 0.5)
			(thermal_bridge_width 0.5)
			(island_removal_mode 0)
		)
		(polygon
			(pts
				(xy 172.62475 -18.103596) (xy 172.62475 -16.393922) (xy 173.752002 -16.393922) (xy 173.752002 -18.103596)
			)
		)
	)
	(zone
		(layer "F.Cu")
		(hatch none 0.5)
		(connect_pads
			(clearance 0)
		)
		(min_thickness 0.25)
		(keepout
			(tracks allowed)
			(vias allowed)
			(pads allowed)
			(copperpour allowed)
			(footprints not_allowed)
		)
		(placement
			(enabled no)
			(sheetname "")
		)
		(fill
			(thermal_gap 0.5)
			(thermal_bridge_width 0.5)
			(island_removal_mode 0)
		)
		(polygon
			(pts
				(arc
					(start 84.829904 -304.790094)
					(mid 81.330038 -308.28996)
					(end 77.829918 -304.790094)
				)
				(arc
					(start 77.829918 -304.790094)
					(mid 81.330038 -301.289974)
					(end 84.829904 -304.790094)
				)
			)
		)
	)
	(zone
		(layer "F.Cu")
		(hatch none 0.5)
		(connect_pads
			(clearance 0)
		)
		(min_thickness 0.25)
		(keepout
			(tracks allowed)
			(vias allowed)
			(pads allowed)
			(copperpour allowed)
			(footprints allowed)
		)
		(placement
			(enabled no)
			(sheetname "")
		)
		(fill
			(thermal_gap 0.5)
			(thermal_bridge_width 0.5)
			(island_removal_mode 0)
		)
		(polygon
			(pts
				(xy 238.520986 -59.10453) (xy 238.520986 -56.700928) (xy 239.913922 -56.700928) (xy 239.913922 -59.10453)
			)
		)
	)
	(zone
		(layer "F.Cu")
		(hatch none 0.5)
		(connect_pads
			(clearance 0)
		)
		(min_thickness 0.25)
		(keepout
			(tracks allowed)
			(vias allowed)
			(pads allowed)
			(copperpour allowed)
			(footprints allowed)
		)
		(placement
			(enabled no)
			(sheetname "")
		)
		(fill
			(thermal_gap 0.5)
			(thermal_bridge_width 0.5)
			(island_removal_mode 0)
		)
		(polygon
			(pts
				(xy 411.317694 -282.92806) (xy 411.317694 -282.59786) (xy 413.236664 -282.59786) (xy 413.236664 -282.92806)
			)
		)
	)
	(zone
		(layer "F.Cu")
		(hatch none 0.5)
		(connect_pads
			(clearance 0)
		)
		(min_thickness 0.25)
		(keepout
			(tracks allowed)
			(vias allowed)
			(pads allowed)
			(copperpour allowed)
			(footprints allowed)
		)
		(placement
			(enabled no)
			(sheetname "")
		)
		(fill
			(thermal_gap 0.5)
			(thermal_bridge_width 0.5)
			(island_removal_mode 0)
		)
		(polygon
			(pts
				(xy 308.66588 -280.042366) (xy 308.66588 -280.372566) (xy 306.12588 -280.372566) (xy 306.12588 -280.042366)
			)
		)
	)
	(zone
		(layer "F.Cu")
		(hatch none 0.5)
		(connect_pads
			(clearance 0)
		)
		(min_thickness 0.25)
		(keepout
			(tracks allowed)
			(vias allowed)
			(pads allowed)
			(copperpour allowed)
			(footprints allowed)
		)
		(placement
			(enabled no)
			(sheetname "")
		)
		(fill
			(thermal_gap 0.5)
			(thermal_bridge_width 0.5)
			(island_removal_mode 0)
		)
		(polygon
			(pts
				(xy 411.97657 -381.943102) (xy 411.97657 -380.93904) (xy 413.373062 -380.93904) (xy 413.373062 -381.943102)
			)
		)
	)
	(zone
		(layer "F.Cu")
		(hatch none 0.5)
		(connect_pads
			(clearance 0)
		)
		(min_thickness 0.25)
		(keepout
			(tracks allowed)
			(vias allowed)
			(pads allowed)
			(copperpour allowed)
			(footprints allowed)
		)
		(placement
			(enabled no)
			(sheetname "")
		)
		(fill
			(thermal_gap 0.5)
			(thermal_bridge_width 0.5)
			(island_removal_mode 0)
		)
		(polygon
			(pts
				(xy 163.377626 -235.327952) (xy 163.377626 -234.997752) (xy 165.296596 -234.997752) (xy 165.296596 -235.327952)
			)
		)
	)
	(zone
		(layer "F.Cu")
		(hatch none 0.5)
		(connect_pads
			(clearance 0)
		)
		(min_thickness 0.25)
		(keepout
			(tracks allowed)
			(vias allowed)
			(pads allowed)
			(copperpour allowed)
			(footprints not_allowed)
		)
		(placement
			(enabled no)
			(sheetname "")
		)
		(fill
			(thermal_gap 0.5)
			(thermal_bridge_width 0.5)
			(island_removal_mode 0)
		)
		(polygon
			(pts
				(arc
					(start 199.22109 -351.825052)
					(mid 201.086212 -349.95993)
					(end 202.95108 -351.825052)
				)
				(arc
					(start 202.95108 -351.825052)
					(mid 201.086212 -353.68992)
					(end 199.22109 -351.825052)
				)
			)
		)
	)
	(zone
		(layer "F.Cu")
		(hatch none 0.5)
		(connect_pads
			(clearance 0)
		)
		(min_thickness 0.25)
		(keepout
			(tracks allowed)
			(vias allowed)
			(pads allowed)
			(copperpour allowed)
			(footprints not_allowed)
		)
		(placement
			(enabled no)
			(sheetname "")
		)
		(fill
			(thermal_gap 0.5)
			(thermal_bridge_width 0.5)
			(island_removal_mode 0)
		)
		(polygon
			(pts
				(arc
					(start 286.13862 -59.991244)
					(mid 285.810014 -58.203949)
					(end 285.699962 -56.390032)
				)
				(xy 294.014906 -56.390032) (xy 294.014906 -59.390026)
				(arc
					(start 304.428906 -59.390026)
					(mid 304.50091 -64.989214)
					(end 306.621434 -70.171818)
				)
				(arc
					(start 306.621434 -70.171818)
					(mid 305.088005 -70.733839)
					(end 303.502568 -71.125842)
				)
				(xy 303.502568 -59.993276)
			)
		)
	)
	(zone
		(layer "F.Cu")
		(hatch none 0.5)
		(connect_pads
			(clearance 0)
		)
		(min_thickness 0.25)
		(keepout
			(tracks not_allowed)
			(vias allowed)
			(pads allowed)
			(copperpour not_allowed)
			(footprints allowed)
		)
		(placement
			(enabled no)
			(sheetname "")
		)
		(fill
			(thermal_gap 0.5)
			(thermal_bridge_width 0.5)
			(island_removal_mode 0)
		)
		(polygon
			(pts
				(arc
					(start 432.311048 -66.06794)
					(mid 426.803058 -60.55995)
					(end 421.295068 -66.06794)
				)
				(arc
					(start 421.295068 -74.767948)
					(mid 426.803058 -80.275938)
					(end 432.311048 -74.767948)
				)
			)
		)
	)
	(zone
		(layer "F.Cu")
		(hatch none 0.5)
		(connect_pads
			(clearance 0)
		)
		(min_thickness 0.25)
		(keepout
			(tracks allowed)
			(vias allowed)
			(pads allowed)
			(copperpour allowed)
			(footprints allowed)
		)
		(placement
			(enabled no)
			(sheetname "")
		)
		(fill
			(thermal_gap 0.5)
			(thermal_bridge_width 0.5)
			(island_removal_mode 0)
		)
		(polygon
			(pts
				(xy 306.070508 -245.52783) (xy 306.070508 -245.19763) (xy 308.610508 -245.19763) (xy 308.610508 -245.52783)
			)
		)
	)
	(zone
		(layer "F.Cu")
		(hatch none 0.5)
		(connect_pads
			(clearance 0)
		)
		(min_thickness 0.25)
		(keepout
			(tracks allowed)
			(vias allowed)
			(pads allowed)
			(copperpour allowed)
			(footprints not_allowed)
		)
		(placement
			(enabled no)
			(sheetname "")
		)
		(fill
			(thermal_gap 0.5)
			(thermal_bridge_width 0.5)
			(island_removal_mode 0)
		)
		(polygon
			(pts
				(arc
					(start 78.529942 -212.989922)
					(mid 81.330038 -210.189826)
					(end 84.12988 -212.989922)
				)
				(arc
					(start 84.12988 -212.989922)
					(mid 81.330038 -215.789764)
					(end 78.529942 -212.989922)
				)
			)
		)
	)
	(zone
		(layer "F.Cu")
		(hatch none 0.5)
		(connect_pads
			(clearance 0)
		)
		(min_thickness 0.25)
		(keepout
			(tracks allowed)
			(vias allowed)
			(pads allowed)
			(copperpour allowed)
			(footprints not_allowed)
		)
		(placement
			(enabled no)
			(sheetname "")
		)
		(fill
			(thermal_gap 0.5)
			(thermal_bridge_width 0.5)
			(island_removal_mode 0)
		)
		(polygon
			(pts
				(arc
					(start 0.999998 -66.069718)
					(mid 3.558661 -66.765642)
					(end 6.199886 -67.00012)
				)
				(xy 6.199886 -57.53989) (xy 2.15011 -57.53989) (xy 2.15011 -46.459902) (xy 6.199886 -46.459902)
				(arc
					(start 6.199886 -36.999926)
					(mid 3.558674 -37.234295)
					(end 0.999998 -37.930074)
				)
			)
		)
	)
	(zone
		(layer "F.Cu")
		(hatch none 0.5)
		(connect_pads
			(clearance 0)
		)
		(min_thickness 0.25)
		(keepout
			(tracks allowed)
			(vias allowed)
			(pads allowed)
			(copperpour allowed)
			(footprints allowed)
		)
		(placement
			(enabled no)
			(sheetname "")
		)
		(fill
			(thermal_gap 0.5)
			(thermal_bridge_width 0.5)
			(island_removal_mode 0)
		)
		(polygon
			(pts
				(xy 142.06982 -375.687844) (xy 143.073882 -375.687844) (xy 143.073882 -377.084336) (xy 142.06982 -377.084336)
			)
		)
	)
	(zone
		(layer "F.Cu")
		(hatch none 0.5)
		(connect_pads
			(clearance 0)
		)
		(min_thickness 0.25)
		(keepout
			(tracks allowed)
			(vias allowed)
			(pads allowed)
			(copperpour allowed)
			(footprints not_allowed)
		)
		(placement
			(enabled no)
			(sheetname "")
		)
		(fill
			(thermal_gap 0.5)
			(thermal_bridge_width 0.5)
			(island_removal_mode 0)
		)
		(polygon
			(pts
				(arc
					(start 7.500112 -429.755808)
					(mid 18.636089 -429.85637)
					(end 18.881852 -440.989974)
				)
				(arc
					(start 8.50011 -440.989974)
					(mid 7.793005 -440.697081)
					(end 7.500112 -439.989976)
				)
			)
		)
	)
	(zone
		(layer "F.Cu")
		(hatch none 0.5)
		(connect_pads
			(clearance 0)
		)
		(min_thickness 0.25)
		(keepout
			(tracks allowed)
			(vias allowed)
			(pads allowed)
			(copperpour allowed)
			(footprints allowed)
		)
		(placement
			(enabled no)
			(sheetname "")
		)
		(fill
			(thermal_gap 0.5)
			(thermal_bridge_width 0.5)
			(island_removal_mode 0)
		)
		(polygon
			(pts
				(xy 267.446506 -332.26629) (xy 267.446506 -331.807566) (xy 268.029182 -331.807566) (xy 268.029182 -332.26629)
			)
		)
	)
	(zone
		(layer "F.Cu")
		(hatch none 0.5)
		(connect_pads
			(clearance 0)
		)
		(min_thickness 0.25)
		(keepout
			(tracks allowed)
			(vias allowed)
			(pads allowed)
			(copperpour allowed)
			(footprints allowed)
		)
		(placement
			(enabled no)
			(sheetname "")
		)
		(fill
			(thermal_gap 0.5)
			(thermal_bridge_width 0.5)
			(island_removal_mode 0)
		)
		(polygon
			(pts
				(xy 58.13044 -265.077956) (xy 58.13044 -264.747756) (xy 60.67044 -264.747756) (xy 60.67044 -265.077956)
			)
		)
	)
	(zone
		(layer "F.Cu")
		(hatch none 0.5)
		(connect_pads
			(clearance 0)
		)
		(min_thickness 0.25)
		(keepout
			(tracks not_allowed)
			(vias allowed)
			(pads allowed)
			(copperpour not_allowed)
			(footprints allowed)
		)
		(placement
			(enabled no)
			(sheetname "")
		)
		(fill
			(thermal_gap 0.5)
			(thermal_bridge_width 0.5)
			(island_removal_mode 0)
		)
		(polygon
			(pts
				(arc
					(start 412.08706 -351.415096)
					(mid 413.952182 -349.549974)
					(end 415.81705 -351.415096)
				)
				(arc
					(start 415.81705 -351.415096)
					(mid 413.952182 -353.279964)
					(end 412.08706 -351.415096)
				)
			)
		)
	)
	(zone
		(layer "F.Cu")
		(hatch none 0.5)
		(connect_pads
			(clearance 0)
		)
		(min_thickness 0.25)
		(keepout
			(tracks allowed)
			(vias allowed)
			(pads allowed)
			(copperpour allowed)
			(footprints not_allowed)
		)
		(placement
			(enabled no)
			(sheetname "")
		)
		(fill
			(thermal_gap 0.5)
			(thermal_bridge_width 0.5)
			(island_removal_mode 0)
		)
		(polygon
			(pts
				(arc
					(start 240.89995 -81.700116)
					(mid 235.89996 -86.700106)
					(end 230.89997 -81.700116)
				)
				(arc
					(start 230.89997 -81.700116)
					(mid 235.89996 -76.700126)
					(end 240.89995 -81.700116)
				)
			)
		)
	)
	(zone
		(layer "F.Cu")
		(hatch none 0.5)
		(connect_pads
			(clearance 0)
		)
		(min_thickness 0.25)
		(keepout
			(tracks allowed)
			(vias allowed)
			(pads allowed)
			(copperpour allowed)
			(footprints not_allowed)
		)
		(placement
			(enabled no)
			(sheetname "")
		)
		(fill
			(thermal_gap 0.5)
			(thermal_bridge_width 0.5)
			(island_removal_mode 0)
		)
		(polygon
			(pts
				(arc
					(start 11.999976 -168.3258)
					(mid 6.671559 -167.609354)
					(end 2.999994 -163.681918)
				)
				(xy 2.999994 -182.060088) (xy 11.999976 -182.060088)
			)
		)
	)
	(zone
		(layer "F.Cu")
		(hatch none 0.5)
		(connect_pads
			(clearance 0)
		)
		(min_thickness 0.25)
		(keepout
			(tracks allowed)
			(vias allowed)
			(pads allowed)
			(copperpour allowed)
			(footprints not_allowed)
		)
		(placement
			(enabled no)
			(sheetname "")
		)
		(fill
			(thermal_gap 0.5)
			(thermal_bridge_width 0.5)
			(island_removal_mode 0)
		)
		(polygon
			(pts
				(arc
					(start 238.949992 -39.425118)
					(mid 239.94999 -38.42512)
					(end 240.949988 -39.425118)
				)
				(arc
					(start 240.949988 -39.425118)
					(mid 239.94999 -40.425116)
					(end 238.949992 -39.425118)
				)
			)
		)
	)
	(zone
		(layer "F.Cu")
		(hatch none 0.5)
		(connect_pads
			(clearance 0)
		)
		(min_thickness 0.25)
		(keepout
			(tracks allowed)
			(vias allowed)
			(pads allowed)
			(copperpour allowed)
			(footprints not_allowed)
		)
		(placement
			(enabled no)
			(sheetname "")
		)
		(fill
			(thermal_gap 0.5)
			(thermal_bridge_width 0.5)
			(island_removal_mode 0)
		)
		(polygon
			(pts
				(arc
					(start 176.950116 -435.600094)
					(mid 179.750212 -432.799998)
					(end 182.550054 -435.600094)
				)
				(arc
					(start 182.550054 -435.600094)
					(mid 179.750212 -438.399936)
					(end 176.950116 -435.600094)
				)
			)
		)
	)
	(zone
		(layer "F.Cu")
		(hatch none 0.5)
		(connect_pads
			(clearance 0)
		)
		(min_thickness 0.25)
		(keepout
			(tracks allowed)
			(vias allowed)
			(pads allowed)
			(copperpour allowed)
			(footprints not_allowed)
		)
		(placement
			(enabled no)
			(sheetname "")
		)
		(fill
			(thermal_gap 0.5)
			(thermal_bridge_width 0.5)
			(island_removal_mode 0)
		)
		(polygon
			(pts
				(arc
					(start 23.31593 -347.8149)
					(mid 20.216114 -350.914716)
					(end 17.116044 -347.8149)
				)
				(arc
					(start 17.116044 -347.8149)
					(mid 20.216114 -344.71483)
					(end 23.31593 -347.8149)
				)
			)
		)
	)
	(zone
		(layer "F.Cu")
		(hatch none 0.5)
		(connect_pads
			(clearance 0)
		)
		(min_thickness 0.25)
		(keepout
			(tracks allowed)
			(vias allowed)
			(pads allowed)
			(copperpour allowed)
			(footprints allowed)
		)
		(placement
			(enabled no)
			(sheetname "")
		)
		(fill
			(thermal_gap 0.5)
			(thermal_bridge_width 0.5)
			(island_removal_mode 0)
		)
		(polygon
			(pts
				(xy 12.15136 -100.983288) (xy 12.15136 -97.318068) (xy 15.91564 -97.318068) (xy 15.91564 -100.983288)
			)
		)
	)
	(zone
		(layer "F.Cu")
		(hatch none 0.5)
		(connect_pads
			(clearance 0)
		)
		(min_thickness 0.25)
		(keepout
			(tracks allowed)
			(vias allowed)
			(pads allowed)
			(copperpour allowed)
			(footprints not_allowed)
		)
		(placement
			(enabled no)
			(sheetname "")
		)
		(fill
			(thermal_gap 0.5)
			(thermal_bridge_width 0.5)
			(island_removal_mode 0)
		)
		(polygon
			(pts
				(arc
					(start 269.871952 -43.949874)
					(mid 260.872136 -34.000173)
					(end 269.871952 -24.050244)
				)
			)
		)
	)
	(zone
		(layer "F.Cu")
		(hatch none 0.5)
		(connect_pads
			(clearance 0)
		)
		(min_thickness 0.25)
		(keepout
			(tracks allowed)
			(vias allowed)
			(pads allowed)
			(copperpour allowed)
			(footprints not_allowed)
		)
		(placement
			(enabled no)
			(sheetname "")
		)
		(fill
			(thermal_gap 0.5)
			(thermal_bridge_width 0.5)
			(island_removal_mode 0)
		)
		(polygon
			(pts
				(arc
					(start 451.300088 -435.600094)
					(mid 448.80022 -438.099962)
					(end 446.300098 -435.600094)
				)
				(arc
					(start 446.300098 -435.600094)
					(mid 448.80022 -433.099972)
					(end 451.300088 -435.600094)
				)
			)
		)
	)
	(zone
		(layer "F.Cu")
		(hatch none 0.5)
		(connect_pads
			(clearance 0)
		)
		(min_thickness 0.25)
		(keepout
			(tracks allowed)
			(vias allowed)
			(pads allowed)
			(copperpour allowed)
			(footprints not_allowed)
		)
		(placement
			(enabled no)
			(sheetname "")
		)
		(fill
			(thermal_gap 0.5)
			(thermal_bridge_width 0.5)
			(island_removal_mode 0)
		)
		(polygon
			(pts
				(arc
					(start 181.500018 -376.489976)
					(mid 177.500026 -380.489968)
					(end 173.500034 -376.489976)
				)
				(arc
					(start 173.500034 -376.489976)
					(mid 177.500026 -372.489984)
					(end 181.500018 -376.489976)
				)
			)
		)
	)
	(zone
		(layer "F.Cu")
		(hatch none 0.5)
		(connect_pads
			(clearance 0)
		)
		(min_thickness 0.25)
		(keepout
			(tracks allowed)
			(vias allowed)
			(pads allowed)
			(copperpour allowed)
			(footprints not_allowed)
		)
		(placement
			(enabled no)
			(sheetname "")
		)
		(fill
			(thermal_gap 0.5)
			(thermal_bridge_width 0.5)
			(island_removal_mode 0)
		)
		(polygon
			(pts
				(arc
					(start 244.650006 -352.49993)
					(mid 236.650022 -360.499914)
					(end 228.650038 -352.49993)
				)
				(arc
					(start 228.650038 -352.49993)
					(mid 236.650022 -344.499946)
					(end 244.650006 -352.49993)
				)
			)
		)
	)
	(zone
		(layer "F.Cu")
		(hatch none 0.5)
		(connect_pads
			(clearance 0)
		)
		(min_thickness 0.25)
		(keepout
			(tracks allowed)
			(vias allowed)
			(pads allowed)
			(copperpour allowed)
			(footprints allowed)
		)
		(placement
			(enabled no)
			(sheetname "")
		)
		(fill
			(thermal_gap 0.5)
			(thermal_bridge_width 0.5)
			(island_removal_mode 0)
		)
		(polygon
			(pts
				(xy 205.037944 -137.807446) (xy 205.037944 -137.098786) (xy 206.310484 -137.098786) (xy 206.310484 -137.807446)
			)
		)
	)
	(zone
		(layer "F.Cu")
		(hatch none 0.5)
		(connect_pads
			(clearance 0)
		)
		(min_thickness 0.25)
		(keepout
			(tracks not_allowed)
			(vias allowed)
			(pads allowed)
			(copperpour not_allowed)
			(footprints allowed)
		)
		(placement
			(enabled no)
			(sheetname "")
		)
		(fill
			(thermal_gap 0.5)
			(thermal_bridge_width 0.5)
			(island_removal_mode 0)
		)
		(polygon
			(pts
				(arc
					(start 265.586972 -347.8149)
					(mid 267.452094 -345.949778)
					(end 269.316962 -347.8149)
				)
				(arc
					(start 269.316962 -347.8149)
					(mid 267.452094 -349.679768)
					(end 265.586972 -347.8149)
				)
			)
		)
	)
	(zone
		(layer "F.Cu")
		(hatch none 0.5)
		(connect_pads
			(clearance 0)
		)
		(min_thickness 0.25)
		(keepout
			(tracks allowed)
			(vias allowed)
			(pads allowed)
			(copperpour allowed)
			(footprints allowed)
		)
		(placement
			(enabled no)
			(sheetname "")
		)
		(fill
			(thermal_gap 0.5)
			(thermal_bridge_width 0.5)
			(island_removal_mode 0)
		)
		(polygon
			(pts
				(xy 347.07957 -159.084772) (xy 345.27617 -159.084772) (xy 345.27617 -160.634172) (xy 347.07957 -160.634172)
			)
		)
	)
	(zone
		(layer "F.Cu")
		(hatch none 0.5)
		(connect_pads
			(clearance 0)
		)
		(min_thickness 0.25)
		(keepout
			(tracks allowed)
			(vias allowed)
			(pads allowed)
			(copperpour allowed)
			(footprints allowed)
		)
		(placement
			(enabled no)
			(sheetname "")
		)
		(fill
			(thermal_gap 0.5)
			(thermal_bridge_width 0.5)
			(island_removal_mode 0)
		)
		(polygon
			(pts
				(xy 163.377626 -297.892724) (xy 163.377626 -298.222924) (xy 165.296596 -298.222924) (xy 165.296596 -297.892724)
			)
		)
	)
	(zone
		(layer "F.Cu")
		(hatch none 0.5)
		(connect_pads
			(clearance 0)
		)
		(min_thickness 0.25)
		(keepout
			(tracks allowed)
			(vias allowed)
			(pads allowed)
			(copperpour allowed)
			(footprints allowed)
		)
		(placement
			(enabled no)
			(sheetname "")
		)
		(fill
			(thermal_gap 0.5)
			(thermal_bridge_width 0.5)
			(island_removal_mode 0)
		)
		(polygon
			(pts
				(xy 147.67306 -193.2178) (xy 147.67306 -192.7098) (xy 147.86864 -192.7098) (xy 147.86864 -193.2178)
			)
		)
	)
	(zone
		(layer "F.Cu")
		(hatch none 0.5)
		(connect_pads
			(clearance 0)
		)
		(min_thickness 0.25)
		(keepout
			(tracks allowed)
			(vias allowed)
			(pads allowed)
			(copperpour allowed)
			(footprints allowed)
		)
		(placement
			(enabled no)
			(sheetname "")
		)
		(fill
			(thermal_gap 0.5)
			(thermal_bridge_width 0.5)
			(island_removal_mode 0)
		)
		(polygon
			(pts
				(xy 411.317694 -279.192482) (xy 411.317694 -279.522682) (xy 413.236664 -279.522682) (xy 413.236664 -279.192482)
			)
		)
	)
	(zone
		(layer "F.Cu")
		(hatch none 0.5)
		(connect_pads
			(clearance 0)
		)
		(min_thickness 0.25)
		(keepout
			(tracks allowed)
			(vias allowed)
			(pads allowed)
			(copperpour allowed)
			(footprints allowed)
		)
		(placement
			(enabled no)
			(sheetname "")
		)
		(fill
			(thermal_gap 0.5)
			(thermal_bridge_width 0.5)
			(island_removal_mode 0)
		)
		(polygon
			(pts
				(xy 163.377626 -316.592712) (xy 163.377626 -316.922912) (xy 165.296596 -316.922912) (xy 165.296596 -316.592712)
			)
		)
	)
	(zone
		(layer "F.Cu")
		(hatch none 0.5)
		(connect_pads
			(clearance 0)
		)
		(min_thickness 0.25)
		(keepout
			(tracks allowed)
			(vias allowed)
			(pads allowed)
			(copperpour allowed)
			(footprints allowed)
		)
		(placement
			(enabled no)
			(sheetname "")
		)
		(fill
			(thermal_gap 0.5)
			(thermal_bridge_width 0.5)
			(island_removal_mode 0)
		)
		(polygon
			(pts
				(xy 12.8143 -102.568248) (xy 12.8143 -101.265228) (xy 14.15288 -101.265228) (xy 14.15288 -102.568248)
			)
		)
	)
	(zone
		(layer "F.Cu")
		(hatch none 0.5)
		(connect_pads
			(clearance 0)
		)
		(min_thickness 0.25)
		(keepout
			(tracks allowed)
			(vias allowed)
			(pads allowed)
			(copperpour allowed)
			(footprints allowed)
		)
		(placement
			(enabled no)
			(sheetname "")
		)
		(fill
			(thermal_gap 0.5)
			(thermal_bridge_width 0.5)
			(island_removal_mode 0)
		)
		(polygon
			(pts
				(xy 384.554222 -384.406902) (xy 384.554222 -383.40284) (xy 385.950714 -383.40284) (xy 385.950714 -384.406902)
			)
		)
	)
	(zone
		(layer "F.Cu")
		(hatch none 0.5)
		(connect_pads
			(clearance 0)
		)
		(min_thickness 0.25)
		(keepout
			(tracks allowed)
			(vias allowed)
			(pads allowed)
			(copperpour allowed)
			(footprints not_allowed)
		)
		(placement
			(enabled no)
			(sheetname "")
		)
		(fill
			(thermal_gap 0.5)
			(thermal_bridge_width 0.5)
			(island_removal_mode 0)
		)
		(polygon
			(pts
				(xy 16.554958 -183.50992) (xy 16.554958 -327.609962) (xy 22.755098 -327.609962) (xy 22.755098 -183.50992)
			)
		)
	)
	(zone
		(layer "F.Cu")
		(hatch none 0.5)
		(connect_pads
			(clearance 0)
		)
		(min_thickness 0.25)
		(keepout
			(tracks allowed)
			(vias allowed)
			(pads allowed)
			(copperpour allowed)
			(footprints not_allowed)
		)
		(placement
			(enabled no)
			(sheetname "")
		)
		(fill
			(thermal_gap 0.5)
			(thermal_bridge_width 0.5)
			(island_removal_mode 0)
		)
		(polygon
			(pts
				(arc
					(start 405.470106 -258.890008)
					(mid 401.97024 -262.389874)
					(end 398.47012 -258.890008)
				)
				(arc
					(start 398.47012 -258.890008)
					(mid 401.97024 -255.389888)
					(end 405.470106 -258.890008)
				)
			)
		)
	)
	(zone
		(layer "F.Cu")
		(hatch none 0.5)
		(connect_pads
			(clearance 0)
		)
		(min_thickness 0.25)
		(keepout
			(tracks allowed)
			(vias allowed)
			(pads allowed)
			(copperpour allowed)
			(footprints not_allowed)
		)
		(placement
			(enabled no)
			(sheetname "")
		)
		(fill
			(thermal_gap 0.5)
			(thermal_bridge_width 0.5)
			(island_removal_mode 0)
		)
		(polygon
			(pts
				(arc
					(start 363.052106 -340.315042)
					(mid 359.952036 -343.415112)
					(end 356.851966 -340.315042)
				)
				(arc
					(start 356.851966 -340.315042)
					(mid 359.952036 -337.214972)
					(end 363.052106 -340.315042)
				)
			)
		)
	)
	(zone
		(layer "F.Cu")
		(hatch none 0.5)
		(connect_pads
			(clearance 0)
		)
		(min_thickness 0.25)
		(keepout
			(tracks allowed)
			(vias allowed)
			(pads allowed)
			(copperpour allowed)
			(footprints allowed)
		)
		(placement
			(enabled no)
			(sheetname "")
		)
		(fill
			(thermal_gap 0.5)
			(thermal_bridge_width 0.5)
			(island_removal_mode 0)
		)
		(polygon
			(pts
				(xy 163.377626 -267.628116) (xy 163.377626 -267.297916) (xy 165.296596 -267.297916) (xy 165.296596 -267.628116)
			)
		)
	)
	(zone
		(layer "F.Cu")
		(hatch none 0.5)
		(connect_pads
			(clearance 0)
		)
		(min_thickness 0.25)
		(keepout
			(tracks allowed)
			(vias allowed)
			(pads allowed)
			(copperpour allowed)
			(footprints not_allowed)
		)
		(placement
			(enabled no)
			(sheetname "")
		)
		(fill
			(thermal_gap 0.5)
			(thermal_bridge_width 0.5)
			(island_removal_mode 0)
		)
		(polygon
			(pts
				(arc
					(start 399.16989 -258.890008)
					(mid 401.969986 -256.089912)
					(end 404.770082 -258.890008)
				)
				(arc
					(start 404.770082 -258.890008)
					(mid 401.969986 -261.690104)
					(end 399.16989 -258.890008)
				)
			)
		)
	)
	(zone
		(layer "F.Cu")
		(hatch none 0.5)
		(connect_pads
			(clearance 0)
		)
		(min_thickness 0.25)
		(keepout
			(tracks allowed)
			(vias allowed)
			(pads allowed)
			(copperpour allowed)
			(footprints allowed)
		)
		(placement
			(enabled no)
			(sheetname "")
		)
		(fill
			(thermal_gap 0.5)
			(thermal_bridge_width 0.5)
			(island_removal_mode 0)
		)
		(polygon
			(pts
				(xy 411.317694 -297.89247) (xy 411.317694 -298.22267) (xy 413.236664 -298.22267) (xy 413.236664 -297.89247)
			)
		)
	)
	(zone
		(layer "F.Cu")
		(hatch none 0.5)
		(connect_pads
			(clearance 0)
		)
		(min_thickness 0.25)
		(keepout
			(tracks allowed)
			(vias allowed)
			(pads allowed)
			(copperpour allowed)
			(footprints allowed)
		)
		(placement
			(enabled no)
			(sheetname "")
		)
		(fill
			(thermal_gap 0.5)
			(thermal_bridge_width 0.5)
			(island_removal_mode 0)
		)
		(polygon
			(pts
				(xy 388.993126 -417.424616) (xy 388.993126 -416.420554) (xy 390.389618 -416.420554) (xy 390.389618 -417.424616)
			)
		)
	)
	(zone
		(layer "F.Cu")
		(hatch none 0.5)
		(connect_pads
			(clearance 0)
		)
		(min_thickness 0.25)
		(keepout
			(tracks allowed)
			(vias allowed)
			(pads allowed)
			(copperpour allowed)
			(footprints allowed)
		)
		(placement
			(enabled no)
			(sheetname "")
		)
		(fill
			(thermal_gap 0.5)
			(thermal_bridge_width 0.5)
			(island_removal_mode 0)
		)
		(polygon
			(pts
				(xy 27.620976 -363.0041) (xy 27.620976 -364.10138) (xy 26.450036 -364.10138) (xy 25.106122 -364.10138)
				(xy 24.832564 -363.827822) (xy 24.832564 -359.75544) (xy 25.22474 -359.363264) (xy 25.852374 -359.363264)
				(xy 27.620976 -361.131866)
			)
		)
	)
	(zone
		(layer "F.Cu")
		(hatch none 0.5)
		(connect_pads
			(clearance 0)
		)
		(min_thickness 0.25)
		(keepout
			(tracks allowed)
			(vias allowed)
			(pads allowed)
			(copperpour allowed)
			(footprints allowed)
		)
		(placement
			(enabled no)
			(sheetname "")
		)
		(fill
			(thermal_gap 0.5)
			(thermal_bridge_width 0.5)
			(island_removal_mode 0)
		)
		(polygon
			(pts
				(xy 15.10284 -109.050328) (xy 15.10284 -108.041948) (xy 16.76908 -108.041948) (xy 16.76908 -109.050328)
			)
		)
	)
	(zone
		(layer "F.Cu")
		(hatch none 0.5)
		(connect_pads
			(clearance 0)
		)
		(min_thickness 0.25)
		(keepout
			(tracks allowed)
			(vias allowed)
			(pads allowed)
			(copperpour allowed)
			(footprints allowed)
		)
		(placement
			(enabled no)
			(sheetname "")
		)
		(fill
			(thermal_gap 0.5)
			(thermal_bridge_width 0.5)
			(island_removal_mode 0)
		)
		(polygon
			(pts
				(xy 461.28686 -40.91432) (xy 461.28686 -40.36568) (xy 462.48574 -40.36568) (xy 462.48574 -40.91432)
			)
		)
	)
	(zone
		(layer "F.Cu")
		(hatch none 0.5)
		(connect_pads
			(clearance 0)
		)
		(min_thickness 0.25)
		(keepout
			(tracks allowed)
			(vias allowed)
			(pads allowed)
			(copperpour allowed)
			(footprints allowed)
		)
		(placement
			(enabled no)
			(sheetname "")
		)
		(fill
			(thermal_gap 0.5)
			(thermal_bridge_width 0.5)
			(island_removal_mode 0)
		)
		(polygon
			(pts
				(xy 120.74017 -409.042616) (xy 120.74017 -408.038554) (xy 122.136662 -408.038554) (xy 122.136662 -409.042616)
			)
		)
	)
	(zone
		(layer "F.Cu")
		(hatch none 0.5)
		(connect_pads
			(clearance 0)
		)
		(min_thickness 0.25)
		(keepout
			(tracks not_allowed)
			(vias allowed)
			(pads allowed)
			(copperpour not_allowed)
			(footprints allowed)
		)
		(placement
			(enabled no)
			(sheetname "")
		)
		(fill
			(thermal_gap 0.5)
			(thermal_bridge_width 0.5)
			(island_removal_mode 0)
		)
		(polygon
			(pts
				(arc
					(start 64.382904 -43.850052)
					(mid 67.58305 -47.050198)
					(end 64.382904 -50.25009)
				)
				(arc
					(start 62.782958 -50.25009)
					(mid 59.583066 -47.050198)
					(end 62.782958 -43.850052)
				)
			)
		)
	)
	(zone
		(layer "F.Cu")
		(hatch none 0.5)
		(connect_pads
			(clearance 0)
		)
		(min_thickness 0.25)
		(keepout
			(tracks allowed)
			(vias allowed)
			(pads allowed)
			(copperpour allowed)
			(footprints allowed)
		)
		(placement
			(enabled no)
			(sheetname "")
		)
		(fill
			(thermal_gap 0.5)
			(thermal_bridge_width 0.5)
			(island_removal_mode 0)
		)
		(polygon
			(pts
				(xy 60.725812 -306.39258) (xy 60.725812 -306.72278) (xy 58.185812 -306.72278) (xy 58.185812 -306.39258)
			)
		)
	)
	(zone
		(layer "F.Cu")
		(hatch none 0.5)
		(connect_pads
			(clearance 0)
		)
		(min_thickness 0.25)
		(keepout
			(tracks allowed)
			(vias allowed)
			(pads allowed)
			(copperpour allowed)
			(footprints not_allowed)
		)
		(placement
			(enabled no)
			(sheetname "")
		)
		(fill
			(thermal_gap 0.5)
			(thermal_bridge_width 0.5)
			(island_removal_mode 0)
		)
		(polygon
			(pts
				(xy 55.558436 -87.267288) (xy 55.5625 -59.967114) (xy 34.564574 -59.965082) (xy 34.56178 -87.265002)
			)
		)
	)
	(zone
		(layer "F.Cu")
		(hatch none 0.5)
		(connect_pads
			(clearance 0)
		)
		(min_thickness 0.25)
		(keepout
			(tracks allowed)
			(vias allowed)
			(pads allowed)
			(copperpour allowed)
			(footprints not_allowed)
		)
		(placement
			(enabled no)
			(sheetname "")
		)
		(fill
			(thermal_gap 0.5)
			(thermal_bridge_width 0.5)
			(island_removal_mode 0)
		)
		(polygon
			(pts
				(xy 384.552952 -175.565054) (xy 384.552952 -168.654984) (xy 393.462002 -168.654984) (xy 393.462002 -175.565054)
				(arc
					(start 391.654538 -175.565054)
					(mid 389.522116 -176.414965)
					(end 387.389624 -175.565054)
				)
			)
		)
	)
	(zone
		(layer "F.Cu")
		(hatch none 0.5)
		(connect_pads
			(clearance 0)
		)
		(min_thickness 0.25)
		(keepout
			(tracks allowed)
			(vias allowed)
			(pads allowed)
			(copperpour allowed)
			(footprints allowed)
		)
		(placement
			(enabled no)
			(sheetname "")
		)
		(fill
			(thermal_gap 0.5)
			(thermal_bridge_width 0.5)
			(island_removal_mode 0)
		)
		(polygon
			(pts
				(xy 307.24348 -379.479302) (xy 307.24348 -378.47524) (xy 308.639972 -378.47524) (xy 308.639972 -379.479302)
			)
		)
	)
	(zone
		(layer "F.Cu")
		(hatch none 0.5)
		(connect_pads
			(clearance 0)
		)
		(min_thickness 0.25)
		(keepout
			(tracks not_allowed)
			(vias allowed)
			(pads allowed)
			(copperpour not_allowed)
			(footprints allowed)
		)
		(placement
			(enabled no)
			(sheetname "")
		)
		(fill
			(thermal_gap 0.5)
			(thermal_bridge_width 0.5)
			(island_removal_mode 0)
		)
		(polygon
			(pts
				(xy 333.016606 -335.673192) (xy 333.016606 -336.634074) (xy 333.258922 -336.634074) (xy 333.258922 -335.673192)
			)
		)
	)
	(zone
		(layer "F.Cu")
		(hatch none 0.5)
		(connect_pads
			(clearance 0)
		)
		(min_thickness 0.25)
		(keepout
			(tracks allowed)
			(vias allowed)
			(pads allowed)
			(copperpour allowed)
			(footprints allowed)
		)
		(placement
			(enabled no)
			(sheetname "")
		)
		(fill
			(thermal_gap 0.5)
			(thermal_bridge_width 0.5)
			(island_removal_mode 0)
		)
		(polygon
			(pts
				(xy 423.88917 -379.479302) (xy 423.88917 -378.47524) (xy 425.285662 -378.47524) (xy 425.285662 -379.479302)
			)
		)
	)
	(zone
		(layer "F.Cu")
		(hatch none 0.5)
		(connect_pads
			(clearance 0)
		)
		(min_thickness 0.25)
		(keepout
			(tracks allowed)
			(vias allowed)
			(pads allowed)
			(copperpour allowed)
			(footprints allowed)
		)
		(placement
			(enabled no)
			(sheetname "")
		)
		(fill
			(thermal_gap 0.5)
			(thermal_bridge_width 0.5)
			(island_removal_mode 0)
		)
		(polygon
			(pts
				(xy 12.052808 -16.200882) (xy 12.052808 -14.351508) (xy 14.364462 -14.351508) (xy 14.364462 -16.200882)
			)
		)
	)
	(zone
		(layer "F.Cu")
		(hatch none 0.5)
		(connect_pads
			(clearance 0)
		)
		(min_thickness 0.25)
		(keepout
			(tracks not_allowed)
			(vias allowed)
			(pads allowed)
			(copperpour not_allowed)
			(footprints allowed)
		)
		(placement
			(enabled no)
			(sheetname "")
		)
		(fill
			(thermal_gap 0.5)
			(thermal_bridge_width 0.5)
			(island_removal_mode 0)
		)
		(polygon
			(pts
				(arc
					(start 240.89995 -81.700116)
					(mid 235.89996 -86.700106)
					(end 230.89997 -81.700116)
				)
				(arc
					(start 230.89997 -81.700116)
					(mid 235.89996 -76.700126)
					(end 240.89995 -81.700116)
				)
			)
		)
	)
	(zone
		(layer "F.Cu")
		(hatch none 0.5)
		(connect_pads
			(clearance 0)
		)
		(min_thickness 0.25)
		(keepout
			(tracks allowed)
			(vias allowed)
			(pads allowed)
			(copperpour allowed)
			(footprints allowed)
		)
		(placement
			(enabled no)
			(sheetname "")
		)
		(fill
			(thermal_gap 0.5)
			(thermal_bridge_width 0.5)
			(island_removal_mode 0)
		)
		(polygon
			(pts
				(xy 58.13044 -245.528084) (xy 58.13044 -245.197884) (xy 60.67044 -245.197884) (xy 60.67044 -245.528084)
			)
		)
	)
	(zone
		(layer "F.Cu")
		(hatch none 0.5)
		(connect_pads
			(clearance 0)
		)
		(min_thickness 0.25)
		(keepout
			(tracks allowed)
			(vias allowed)
			(pads allowed)
			(copperpour allowed)
			(footprints not_allowed)
		)
		(placement
			(enabled no)
			(sheetname "")
		)
		(fill
			(thermal_gap 0.5)
			(thermal_bridge_width 0.5)
			(island_removal_mode 0)
		)
		(polygon
			(pts
				(xy 137.750042 -394.880084) (xy 142.780004 -394.880084) (xy 142.780004 -390.180068) (xy 137.750042 -390.180068)
			)
		)
	)
	(zone
		(layer "F.Cu")
		(hatch none 0.5)
		(connect_pads
			(clearance 0)
		)
		(min_thickness 0.25)
		(keepout
			(tracks allowed)
			(vias allowed)
			(pads allowed)
			(copperpour allowed)
			(footprints allowed)
		)
		(placement
			(enabled no)
			(sheetname "")
		)
		(fill
			(thermal_gap 0.5)
			(thermal_bridge_width 0.5)
			(island_removal_mode 0)
		)
		(polygon
			(pts
				(xy 306.070508 -271.027652) (xy 306.070508 -270.697452) (xy 308.610508 -270.697452) (xy 308.610508 -271.027652)
			)
		)
	)
	(zone
		(layer "F.Cu")
		(hatch none 0.5)
		(connect_pads
			(clearance 0)
		)
		(min_thickness 0.25)
		(keepout
			(tracks allowed)
			(vias allowed)
			(pads allowed)
			(copperpour allowed)
			(footprints allowed)
		)
		(placement
			(enabled no)
			(sheetname "")
		)
		(fill
			(thermal_gap 0.5)
			(thermal_bridge_width 0.5)
			(island_removal_mode 0)
		)
		(polygon
			(pts
				(xy 453.694292 -49.534318) (xy 453.694292 -48.617378) (xy 454.534778 -48.617378) (xy 454.534778 -49.534318)
			)
		)
	)
	(zone
		(layer "F.Cu")
		(hatch none 0.5)
		(connect_pads
			(clearance 0)
		)
		(min_thickness 0.25)
		(keepout
			(tracks allowed)
			(vias allowed)
			(pads allowed)
			(copperpour allowed)
			(footprints not_allowed)
		)
		(placement
			(enabled no)
			(sheetname "")
		)
		(fill
			(thermal_gap 0.5)
			(thermal_bridge_width 0.5)
			(island_removal_mode 0)
		)
		(polygon
			(pts
				(xy 313.237118 -356.605078) (xy 313.237118 -351.605088) (xy 409.571952 -351.605088) (xy 409.571952 -356.735126)
				(xy 443.986158 -356.735126) (xy 446.571878 -354.145088) (xy 446.571878 -347.134942)
				(arc
					(start 453.479916 -347.134942)
					(mid 458.259485 -355.032123)
					(end 467.300056 -353.167696)
				)
				(xy 467.300056 -394.24991) (xy 430.559972 -394.24991) (xy 430.559972 -404.850092) (xy 464.300062 -404.850092)
				(arc
					(start 464.300062 -429.790606)
					(mid 456.265069 -428.01222)
					(end 450.912484 -434.263038)
				)
				(arc
					(start 450.912484 -434.263038)
					(mid 446.299876 -435.600201)
					(end 450.912484 -436.936896)
				)
				(arc
					(start 450.912484 -436.936896)
					(mid 451.608975 -439.105509)
					(end 452.88835 -440.989974)
				)
				(xy 417.599876 -440.989974) (xy 417.599876 -418.669978) (xy 432.99888 -418.669978) (xy 432.99888 -407.67)
				(xy 429.284892 -407.67) (xy 429.284892 -390.369806) (xy 439.498994 -390.369806) (xy 439.498994 -379.369828)
				(xy 429.284892 -379.369828) (xy 429.284892 -376.169936) (xy 295.28516 -376.169936) (xy 295.28516 -379.369828)
				(xy 285.471108 -379.369828) (xy 285.471108 -390.369806) (xy 295.28516 -390.369806) (xy 295.28516 -407.67)
				(xy 291.571172 -407.67) (xy 291.571172 -418.669978) (xy 310.20004 -418.669978) (xy 310.20004 -440.989974)
				(arc
					(start 299.461682 -440.989974)
					(mid 293.550172 -427.599808)
					(end 287.638236 -440.989974)
				)
				(arc
					(start 277.804118 -440.989974)
					(mid 277.309907 -440.047498)
					(end 276.314916 -439.669936)
				)
				(xy 275.815044 -439.669936) (xy 275.815044 -424.126914) (xy 196.004942 -424.126914) (xy 196.004942 -439.669936)
				(arc
					(start 195.50507 -439.669936)
					(mid 194.51003 -440.047443)
					(end 194.015868 -440.989974)
				)
				(arc
					(start 185.661554 -440.989974)
					(mid 179.749958 -427.600233)
					(end 173.838362 -440.989974)
				)
				(xy 161.59988 -440.989974) (xy 161.59988 -417.889944) (xy 121.299986 -417.889944) (xy 121.299986 -440.989974)
				(xy 117.54993 -440.989974) (xy 117.54993 -418.869876) (xy 106.499914 -418.869876)
				(arc
					(start 106.499914 -430.308004)
					(mid 100.499726 -427.599819)
					(end 94.499938 -430.308766)
				)
				(xy 94.499938 -417.889944) (xy 77.499972 -417.889944) (xy 77.499972 -410.69006) (xy 54.200044 -410.69006)
				(xy 54.200044 -440.989974)
				(arc
					(start 18.91157 -440.989974)
					(mid 18.603422 -429.890528)
					(end 7.500112 -429.790606)
				)
				(arc
					(start 7.500112 -409.528518)
					(mid 7.271649 -408.380426)
					(end 6.621272 -407.40711)
				)
				(arc
					(start 3.292856 -404.078694)
					(mid 3.076074 -403.754257)
					(end 2.999994 -403.371558)
				)
				(xy 2.999994 -394.759942) (xy 39.285164 -394.759942) (xy 39.285164 -399.290032) (xy 35.571176 -399.290032)
				(xy 35.571176 -410.29001) (xy 69.071236 -410.29001) (xy 69.071236 -406.78989) (xy 140.550392 -406.78989)
				(xy 140.550392 -410.29001) (xy 176.998884 -410.29001) (xy 176.998884 -399.290032) (xy 173.284896 -399.290032)
				(xy 173.284896 -381.989838) (xy 183.498744 -381.989838) (xy 183.498744 -370.98986) (xy 173.284896 -370.98986)
				(xy 173.284896 -367.789968) (xy 39.285164 -367.789968) (xy 39.285164 -370.98986) (xy 29.471112 -370.98986)
				(xy 29.471112 -381.989838) (xy 39.285164 -381.989838) (xy 39.285164 -385.160012) (xy 2.999994 -385.160012)
				(arc
					(start 2.999994 -350.88195)
					(mid 9.936658 -355.689987)
					(end 17.322292 -351.605088)
				)
				(xy 23.846028 -351.605088) (xy 23.846028 -356.605078) (xy 66.000884 -356.605078) (xy 66.000884 -351.605088)
				(xy 168.706038 -351.605088) (xy 168.706038 -357.145082) (xy 207.21828 -357.145082) (xy 207.21828 -370.701824)
				(xy 187.330334 -370.701824) (xy 187.330334 -395.691868) (xy 238.430308 -395.691868) (xy 238.430308 -370.701824)
				(xy 271.124934 -370.701824) (xy 271.124934 -356.605078)
			)
		)
	)
	(zone
		(layer "F.Cu")
		(hatch none 0.5)
		(connect_pads
			(clearance 0)
		)
		(min_thickness 0.25)
		(keepout
			(tracks allowed)
			(vias allowed)
			(pads allowed)
			(copperpour allowed)
			(footprints allowed)
		)
		(placement
			(enabled no)
			(sheetname "")
		)
		(fill
			(thermal_gap 0.5)
			(thermal_bridge_width 0.5)
			(island_removal_mode 0)
		)
		(polygon
			(pts
				(xy 163.377626 -245.528084) (xy 163.377626 -245.197884) (xy 165.296596 -245.197884) (xy 165.296596 -245.528084)
			)
		)
	)
	(zone
		(layer "F.Cu")
		(hatch none 0.5)
		(connect_pads
			(clearance 0)
		)
		(min_thickness 0.25)
		(keepout
			(tracks allowed)
			(vias allowed)
			(pads allowed)
			(copperpour allowed)
			(footprints allowed)
		)
		(placement
			(enabled no)
			(sheetname "")
		)
		(fill
			(thermal_gap 0.5)
			(thermal_bridge_width 0.5)
			(island_removal_mode 0)
		)
		(polygon
			(pts
				(xy 411.562042 -285.477712) (xy 411.562042 -285.147512) (xy 413.236664 -285.147512) (xy 413.236664 -285.477712)
			)
		)
	)
	(zone
		(layer "F.Cu")
		(hatch none 0.5)
		(connect_pads
			(clearance 0)
		)
		(min_thickness 0.25)
		(keepout
			(tracks allowed)
			(vias allowed)
			(pads allowed)
			(copperpour allowed)
			(footprints allowed)
		)
		(placement
			(enabled no)
			(sheetname "")
		)
		(fill
			(thermal_gap 0.5)
			(thermal_bridge_width 0.5)
			(island_removal_mode 0)
		)
		(polygon
			(pts
				(xy 109.83468 -373.561102) (xy 109.83468 -372.55704) (xy 111.231172 -372.55704) (xy 111.231172 -373.561102)
			)
		)
	)
	(zone
		(layer "F.Cu")
		(hatch none 0.5)
		(connect_pads
			(clearance 0)
		)
		(min_thickness 0.25)
		(keepout
			(tracks allowed)
			(vias allowed)
			(pads allowed)
			(copperpour allowed)
			(footprints not_allowed)
		)
		(placement
			(enabled no)
			(sheetname "")
		)
		(fill
			(thermal_gap 0.5)
			(thermal_bridge_width 0.5)
			(island_removal_mode 0)
		)
		(polygon
			(pts
				(arc
					(start 327.90003 -160.50006)
					(mid 322.90004 -165.50005)
					(end 317.90005 -160.50006)
				)
				(arc
					(start 317.90005 -160.50006)
					(mid 322.90004 -155.50007)
					(end 327.90003 -160.50006)
				)
			)
		)
	)
	(zone
		(layer "F.Cu")
		(hatch none 0.5)
		(connect_pads
			(clearance 0)
		)
		(min_thickness 0.25)
		(keepout
			(tracks allowed)
			(vias allowed)
			(pads allowed)
			(copperpour allowed)
			(footprints not_allowed)
		)
		(placement
			(enabled no)
			(sheetname "")
		)
		(fill
			(thermal_gap 0.5)
			(thermal_bridge_width 0.5)
			(island_removal_mode 0)
		)
		(polygon
			(pts
				(xy 25.450038 -49.159922) (xy 25.450038 -54.840124) (xy 32.349948 -54.840124) (xy 32.349948 -49.159922)
			)
		)
	)
	(zone
		(layer "F.Cu")
		(hatch none 0.5)
		(connect_pads
			(clearance 0)
		)
		(min_thickness 0.25)
		(keepout
			(tracks allowed)
			(vias allowed)
			(pads allowed)
			(copperpour allowed)
			(footprints not_allowed)
		)
		(placement
			(enabled no)
			(sheetname "")
		)
		(fill
			(thermal_gap 0.5)
			(thermal_bridge_width 0.5)
			(island_removal_mode 0)
		)
		(polygon
			(pts
				(xy 438.742074 -347.134942) (xy 417.24199 -347.134942) (xy 417.24199 -356.735126) (xy 438.742074 -356.735126)
			)
		)
	)
	(zone
		(layer "F.Cu")
		(hatch none 0.5)
		(connect_pads
			(clearance 0)
		)
		(min_thickness 0.25)
		(keepout
			(tracks allowed)
			(vias allowed)
			(pads allowed)
			(copperpour allowed)
			(footprints allowed)
		)
		(placement
			(enabled no)
			(sheetname "")
		)
		(fill
			(thermal_gap 0.5)
			(thermal_bridge_width 0.5)
			(island_removal_mode 0)
		)
		(polygon
			(pts
				(xy 163.377626 -253.178056) (xy 163.377626 -252.847856) (xy 165.296596 -252.847856) (xy 165.296596 -253.178056)
			)
		)
	)
	(zone
		(layer "F.Cu")
		(hatch none 0.5)
		(connect_pads
			(clearance 0)
		)
		(min_thickness 0.25)
		(keepout
			(tracks allowed)
			(vias allowed)
			(pads allowed)
			(copperpour allowed)
			(footprints allowed)
		)
		(placement
			(enabled no)
			(sheetname "")
		)
		(fill
			(thermal_gap 0.5)
			(thermal_bridge_width 0.5)
			(island_removal_mode 0)
		)
		(polygon
			(pts
				(xy 31.052262 -347.226382) (xy 29.248862 -347.226382) (xy 29.248862 -348.775782) (xy 31.052262 -348.775782)
			)
		)
	)
	(zone
		(layer "F.Cu")
		(hatch none 0.5)
		(connect_pads
			(clearance 0)
		)
		(min_thickness 0.25)
		(keepout
			(tracks allowed)
			(vias allowed)
			(pads allowed)
			(copperpour allowed)
			(footprints not_allowed)
		)
		(placement
			(enabled no)
			(sheetname "")
		)
		(fill
			(thermal_gap 0.5)
			(thermal_bridge_width 0.5)
			(island_removal_mode 0)
		)
		(polygon
			(pts
				(arc
					(start 265.586972 -347.8149)
					(mid 267.452094 -345.949778)
					(end 269.316962 -347.8149)
				)
				(arc
					(start 269.316962 -347.8149)
					(mid 267.452094 -349.679768)
					(end 265.586972 -347.8149)
				)
			)
		)
	)
	(zone
		(layer "F.Cu")
		(hatch none 0.5)
		(connect_pads
			(clearance 0)
		)
		(min_thickness 0.25)
		(keepout
			(tracks allowed)
			(vias allowed)
			(pads allowed)
			(copperpour allowed)
			(footprints allowed)
		)
		(placement
			(enabled no)
			(sheetname "")
		)
		(fill
			(thermal_gap 0.5)
			(thermal_bridge_width 0.5)
			(island_removal_mode 0)
		)
		(polygon
			(pts
				(xy 400.06397 -379.479302) (xy 400.06397 -378.47524) (xy 401.460462 -378.47524) (xy 401.460462 -379.479302)
			)
		)
	)
	(zone
		(layer "F.Cu")
		(hatch none 0.5)
		(connect_pads
			(clearance 0)
		)
		(min_thickness 0.25)
		(keepout
			(tracks allowed)
			(vias allowed)
			(pads allowed)
			(copperpour allowed)
			(footprints allowed)
		)
		(placement
			(enabled no)
			(sheetname "")
		)
		(fill
			(thermal_gap 0.5)
			(thermal_bridge_width 0.5)
			(island_removal_mode 0)
		)
		(polygon
			(pts
				(xy 10.47496 -107.259628) (xy 10.47496 -104.737408) (xy 11.189716 -104.022652) (xy 12.846304 -104.022652)
				(xy 13.56106 -104.737408) (xy 13.56106 -107.259628) (xy 13.194538 -107.62615) (xy 10.841482 -107.62615)
			)
		)
	)
	(zone
		(layer "F.Cu")
		(hatch none 0.5)
		(connect_pads
			(clearance 0)
		)
		(min_thickness 0.25)
		(keepout
			(tracks allowed)
			(vias allowed)
			(pads allowed)
			(copperpour allowed)
			(footprints not_allowed)
		)
		(placement
			(enabled no)
			(sheetname "")
		)
		(fill
			(thermal_gap 0.5)
			(thermal_bridge_width 0.5)
			(island_removal_mode 0)
		)
		(polygon
			(pts
				(arc
					(start 455.292968 -165.596062)
					(mid 456.662323 -166.901887)
					(end 458.300074 -167.84955)
				)
				(xy 458.300074 -182.060088) (xy 410.16809 -182.060088) (xy 410.16809 -172.235114) (xy 411.031944 -172.235114)
				(xy 411.031944 -167.40505) (xy 429.681894 -167.40505) (xy 429.681894 -165.596062)
			)
		)
	)
	(zone
		(layer "F.Cu")
		(hatch none 0.5)
		(connect_pads
			(clearance 0)
		)
		(min_thickness 0.25)
		(keepout
			(tracks allowed)
			(vias allowed)
			(pads allowed)
			(copperpour allowed)
			(footprints allowed)
		)
		(placement
			(enabled no)
			(sheetname "")
		)
		(fill
			(thermal_gap 0.5)
			(thermal_bridge_width 0.5)
			(island_removal_mode 0)
		)
		(polygon
			(pts
				(xy 413.499046 -417.424616) (xy 413.499046 -416.420554) (xy 414.895538 -416.420554) (xy 414.895538 -417.424616)
			)
		)
	)
	(zone
		(layer "F.Cu")
		(hatch none 0.5)
		(connect_pads
			(clearance 0)
		)
		(min_thickness 0.25)
		(keepout
			(tracks allowed)
			(vias allowed)
			(pads allowed)
			(copperpour allowed)
			(footprints allowed)
		)
		(placement
			(enabled no)
			(sheetname "")
		)
		(fill
			(thermal_gap 0.5)
			(thermal_bridge_width 0.5)
			(island_removal_mode 0)
		)
		(polygon
			(pts
				(xy 74.969878 -375.687844) (xy 75.97394 -375.687844) (xy 75.97394 -377.084336) (xy 74.969878 -377.084336)
			)
		)
	)
	(zone
		(layer "F.Cu")
		(hatch none 0.5)
		(connect_pads
			(clearance 0)
		)
		(min_thickness 0.25)
		(keepout
			(tracks allowed)
			(vias allowed)
			(pads allowed)
			(copperpour allowed)
			(footprints allowed)
		)
		(placement
			(enabled no)
			(sheetname "")
		)
		(fill
			(thermal_gap 0.5)
			(thermal_bridge_width 0.5)
			(island_removal_mode 0)
		)
		(polygon
			(pts
				(xy 312.70321 -417.424616) (xy 312.70321 -416.420554) (xy 314.099702 -416.420554) (xy 314.099702 -417.424616)
			)
		)
	)
	(zone
		(layer "F.Cu")
		(hatch none 0.5)
		(connect_pads
			(clearance 0)
		)
		(min_thickness 0.25)
		(keepout
			(tracks allowed)
			(vias allowed)
			(pads allowed)
			(copperpour allowed)
			(footprints allowed)
		)
		(placement
			(enabled no)
			(sheetname "")
		)
		(fill
			(thermal_gap 0.5)
			(thermal_bridge_width 0.5)
			(island_removal_mode 0)
		)
		(polygon
			(pts
				(xy 19.453098 -422.775888) (xy 19.453098 -423.252646) (xy 19.66595 -423.465498) (xy 19.764756 -423.564304)
				(xy 19.764756 -424.12666) (xy 19.614642 -424.276774) (xy 18.55343 -424.276774) (xy 18.449036 -424.17238)
				(xy 18.449036 -422.775888) (xy 18.449036 -422.249092) (xy 18.61058 -422.087548) (xy 19.287744 -422.087548)
				(xy 19.453098 -422.252902)
			)
		)
	)
	(zone
		(layer "F.Cu")
		(hatch none 0.5)
		(connect_pads
			(clearance 0)
		)
		(min_thickness 0.25)
		(keepout
			(tracks allowed)
			(vias allowed)
			(pads allowed)
			(copperpour allowed)
			(footprints not_allowed)
		)
		(placement
			(enabled no)
			(sheetname "")
		)
		(fill
			(thermal_gap 0.5)
			(thermal_bridge_width 0.5)
			(island_removal_mode 0)
		)
		(polygon
			(pts
				(xy 246.720106 -296.720006) (xy 254.999998 -296.720006) (xy 254.999998 -286.120078) (xy 245.869968 -286.120078)
				(xy 245.869968 -288.120074) (xy 246.720106 -288.120074)
			)
		)
	)
	(zone
		(layer "F.Cu")
		(hatch none 0.5)
		(connect_pads
			(clearance 0)
		)
		(min_thickness 0.25)
		(keepout
			(tracks allowed)
			(vias allowed)
			(pads allowed)
			(copperpour allowed)
			(footprints not_allowed)
		)
		(placement
			(enabled no)
			(sheetname "")
		)
		(fill
			(thermal_gap 0.5)
			(thermal_bridge_width 0.5)
			(island_removal_mode 0)
		)
		(polygon
			(pts
				(xy 467.300056 -182.060088) (xy 455.666602 -182.060088) (xy 455.666602 -192.321688) (xy 467.300056 -192.321688)
			)
		)
	)
	(zone
		(layer "F.Cu")
		(hatch none 0.5)
		(connect_pads
			(clearance 0)
		)
		(min_thickness 0.25)
		(keepout
			(tracks not_allowed)
			(vias allowed)
			(pads allowed)
			(copperpour not_allowed)
			(footprints allowed)
		)
		(placement
			(enabled no)
			(sheetname "")
		)
		(fill
			(thermal_gap 0.5)
			(thermal_bridge_width 0.5)
			(island_removal_mode 0)
		)
		(polygon
			(pts
				(xy 438.808114 -9.094724) (xy 438.925462 -9.094724) (xy 438.976262 -9.043924) (xy 438.976262 -7.596124)
				(xy 438.925462 -7.545324) (xy 438.808114 -7.545324) (xy 438.757314 -7.596124) (xy 438.757314 -9.043924)
			)
		)
	)
	(zone
		(layer "F.Cu")
		(hatch none 0.5)
		(connect_pads
			(clearance 0)
		)
		(min_thickness 0.25)
		(keepout
			(tracks allowed)
			(vias allowed)
			(pads allowed)
			(copperpour allowed)
			(footprints allowed)
		)
		(placement
			(enabled no)
			(sheetname "")
		)
		(fill
			(thermal_gap 0.5)
			(thermal_bridge_width 0.5)
			(island_removal_mode 0)
		)
		(polygon
			(pts
				(xy 106.807762 -176.11725) (xy 105.004362 -176.11725) (xy 105.004362 -177.66665) (xy 106.807762 -177.66665)
			)
		)
	)
	(zone
		(layer "F.Cu")
		(hatch none 0.5)
		(connect_pads
			(clearance 0)
		)
		(min_thickness 0.25)
		(keepout
			(tracks allowed)
			(vias allowed)
			(pads allowed)
			(copperpour allowed)
			(footprints allowed)
		)
		(placement
			(enabled no)
			(sheetname "")
		)
		(fill
			(thermal_gap 0.5)
			(thermal_bridge_width 0.5)
			(island_removal_mode 0)
		)
		(polygon
			(pts
				(xy 454.530206 -48.527462) (xy 454.530206 -46.48327) (xy 455.72426 -46.48327) (xy 455.72426 -48.527462)
			)
		)
	)
	(zone
		(layer "F.Cu")
		(hatch none 0.5)
		(connect_pads
			(clearance 0)
		)
		(min_thickness 0.25)
		(keepout
			(tracks allowed)
			(vias allowed)
			(pads allowed)
			(copperpour allowed)
			(footprints not_allowed)
		)
		(placement
			(enabled no)
			(sheetname "")
		)
		(fill
			(thermal_gap 0.5)
			(thermal_bridge_width 0.5)
			(island_removal_mode 0)
		)
		(polygon
			(pts
				(arc
					(start 269.871952 -29.095192)
					(mid 264.596261 -30.230318)
					(end 259.80009 -27.756866)
				)
				(arc
					(start 259.80009 -16.842994)
					(mid 268.376748 -14.779037)
					(end 273.63801 -21.860002)
				)
				(arc
					(start 270.63065 -21.860002)
					(mid 265.424711 -17.304929)
					(end 260.649974 -22.31009)
				)
				(arc
					(start 260.649974 -22.31009)
					(mid 264.260141 -27.10314)
					(end 269.871952 -24.978614)
				)
			)
		)
	)
	(zone
		(layer "F.Cu")
		(hatch none 0.5)
		(connect_pads
			(clearance 0)
		)
		(min_thickness 0.25)
		(keepout
			(tracks not_allowed)
			(vias allowed)
			(pads allowed)
			(copperpour not_allowed)
			(footprints allowed)
		)
		(placement
			(enabled no)
			(sheetname "")
		)
		(fill
			(thermal_gap 0.5)
			(thermal_bridge_width 0.5)
			(island_removal_mode 0)
		)
		(polygon
			(pts
				(xy 14.46403 -135.58393) (xy 15.09141 -135.58393) (xy 15.09141 -134.203948) (xy 14.822424 -134.203948)
				(xy 14.822424 -135.314944) (xy 14.46403 -135.314944)
			)
		)
	)
	(zone
		(layer "F.Cu")
		(hatch none 0.5)
		(connect_pads
			(clearance 0)
		)
		(min_thickness 0.25)
		(keepout
			(tracks allowed)
			(vias allowed)
			(pads allowed)
			(copperpour allowed)
			(footprints allowed)
		)
		(placement
			(enabled no)
			(sheetname "")
		)
		(fill
			(thermal_gap 0.5)
			(thermal_bridge_width 0.5)
			(island_removal_mode 0)
		)
		(polygon
			(pts
				(xy 58.13044 -232.778046) (xy 58.13044 -232.447846) (xy 60.67044 -232.447846) (xy 60.67044 -232.778046)
			)
		)
	)
	(zone
		(layer "F.Cu")
		(hatch none 0.5)
		(connect_pads
			(clearance 0)
		)
		(min_thickness 0.25)
		(keepout
			(tracks allowed)
			(vias allowed)
			(pads allowed)
			(copperpour allowed)
			(footprints not_allowed)
		)
		(placement
			(enabled no)
			(sheetname "")
		)
		(fill
			(thermal_gap 0.5)
			(thermal_bridge_width 0.5)
			(island_removal_mode 0)
		)
		(polygon
			(pts
				(arc
					(start 421.016938 -163.314888)
					(mid 422.88206 -161.449766)
					(end 424.746928 -163.314888)
				)
				(arc
					(start 424.746928 -163.314888)
					(mid 422.88206 -165.179756)
					(end 421.016938 -163.314888)
				)
			)
		)
	)
	(zone
		(layer "F.Cu")
		(hatch none 0.5)
		(connect_pads
			(clearance 0)
		)
		(min_thickness 0.25)
		(keepout
			(tracks allowed)
			(vias allowed)
			(pads allowed)
			(copperpour allowed)
			(footprints allowed)
		)
		(placement
			(enabled no)
			(sheetname "")
		)
		(fill
			(thermal_gap 0.5)
			(thermal_bridge_width 0.5)
			(island_removal_mode 0)
		)
		(polygon
			(pts
				(xy 298.441872 -389.607044) (xy 299.445934 -389.607044) (xy 299.445934 -391.003536) (xy 298.441872 -391.003536)
			)
		)
	)
	(zone
		(layer "F.Cu")
		(hatch none 0.5)
		(connect_pads
			(clearance 0)
		)
		(min_thickness 0.25)
		(keepout
			(tracks allowed)
			(vias allowed)
			(pads allowed)
			(copperpour allowed)
			(footprints allowed)
		)
		(placement
			(enabled no)
			(sheetname "")
		)
		(fill
			(thermal_gap 0.5)
			(thermal_bridge_width 0.5)
			(island_removal_mode 0)
		)
		(polygon
			(pts
				(xy 12.845796 -410.504386) (xy 12.845796 -412.622746) (xy 10.77214 -412.622746) (xy 10.28192 -412.132526)
				(xy 10.28192 -410.097732) (xy 10.28192 -407.744168) (xy 11.162538 -406.86355) (xy 11.878056 -406.86355)
				(xy 12.845796 -407.83129)
			)
		)
	)
	(zone
		(layer "F.Cu")
		(hatch none 0.5)
		(connect_pads
			(clearance 0)
		)
		(min_thickness 0.25)
		(keepout
			(tracks not_allowed)
			(vias allowed)
			(pads allowed)
			(copperpour not_allowed)
			(footprints allowed)
		)
		(placement
			(enabled no)
			(sheetname "")
		)
		(fill
			(thermal_gap 0.5)
			(thermal_bridge_width 0.5)
			(island_removal_mode 0)
		)
		(polygon
			(pts
				(xy 439.408062 -12.04468) (xy 439.52541 -12.04468) (xy 439.57621 -11.99388) (xy 439.57621 -10.54608)
				(xy 439.52541 -10.49528) (xy 439.408062 -10.49528) (xy 439.357262 -10.54608) (xy 439.357262 -11.99388)
			)
		)
	)
	(zone
		(layer "F.Cu")
		(hatch none 0.5)
		(connect_pads
			(clearance 0)
		)
		(min_thickness 0.25)
		(keepout
			(tracks allowed)
			(vias allowed)
			(pads allowed)
			(copperpour allowed)
			(footprints not_allowed)
		)
		(placement
			(enabled no)
			(sheetname "")
		)
		(fill
			(thermal_gap 0.5)
			(thermal_bridge_width 0.5)
			(island_removal_mode 0)
		)
		(polygon
			(pts
				(xy 230.300022 -64.52489) (xy 238.300006 -64.52489) (xy 238.300006 -40.450008) (xy 237.89005 -40.450008)
				(xy 237.89005 -37.120068) (xy 230.300022 -37.120068) (xy 230.300022 -41.999916) (xy 230.709978 -41.999916)
				(xy 230.709978 -46.999906) (xy 230.300022 -46.999906)
			)
		)
	)
	(zone
		(layer "F.Cu")
		(hatch none 0.5)
		(connect_pads
			(clearance 0)
		)
		(min_thickness 0.25)
		(keepout
			(tracks allowed)
			(vias allowed)
			(pads allowed)
			(copperpour allowed)
			(footprints allowed)
		)
		(placement
			(enabled no)
			(sheetname "")
		)
		(fill
			(thermal_gap 0.5)
			(thermal_bridge_width 0.5)
			(island_removal_mode 0)
		)
		(polygon
			(pts
				(xy 47.840138 -376.024902) (xy 47.840138 -375.02084) (xy 49.23663 -375.02084) (xy 49.23663 -376.024902)
			)
		)
	)
	(zone
		(layer "F.Cu")
		(hatch none 0.5)
		(connect_pads
			(clearance 0)
		)
		(min_thickness 0.25)
		(keepout
			(tracks allowed)
			(vias allowed)
			(pads allowed)
			(copperpour allowed)
			(footprints allowed)
		)
		(placement
			(enabled no)
			(sheetname "")
		)
		(fill
			(thermal_gap 0.5)
			(thermal_bridge_width 0.5)
			(island_removal_mode 0)
		)
		(polygon
			(pts
				(xy 163.634928 -200.478136) (xy 163.634928 -200.147936) (xy 165.296596 -200.147936) (xy 165.296596 -200.478136)
			)
		)
	)
	(zone
		(layer "F.Cu")
		(hatch none 0.5)
		(connect_pads
			(clearance 0)
		)
		(min_thickness 0.25)
		(keepout
			(tracks not_allowed)
			(vias allowed)
			(pads allowed)
			(copperpour not_allowed)
			(footprints allowed)
		)
		(placement
			(enabled no)
			(sheetname "")
		)
		(fill
			(thermal_gap 0.5)
			(thermal_bridge_width 0.5)
			(island_removal_mode 0)
		)
		(polygon
			(pts
				(xy 439.408062 -9.094724) (xy 439.52541 -9.094724) (xy 439.57621 -9.043924) (xy 439.57621 -7.596124)
				(xy 439.52541 -7.545324) (xy 439.408062 -7.545324) (xy 439.357262 -7.596124) (xy 439.357262 -9.043924)
			)
		)
	)
	(zone
		(layer "F.Cu")
		(hatch none 0.5)
		(connect_pads
			(clearance 0)
		)
		(min_thickness 0.25)
		(keepout
			(tracks allowed)
			(vias allowed)
			(pads allowed)
			(copperpour allowed)
			(footprints allowed)
		)
		(placement
			(enabled no)
			(sheetname "")
		)
		(fill
			(thermal_gap 0.5)
			(thermal_bridge_width 0.5)
			(island_removal_mode 0)
		)
		(polygon
			(pts
				(xy 411.317694 -270.178022) (xy 411.317694 -269.847822) (xy 413.236664 -269.847822) (xy 413.236664 -270.178022)
			)
		)
	)
	(zone
		(layer "F.Cu")
		(hatch none 0.5)
		(connect_pads
			(clearance 0)
		)
		(min_thickness 0.25)
		(keepout
			(tracks allowed)
			(vias allowed)
			(pads allowed)
			(copperpour allowed)
			(footprints not_allowed)
		)
		(placement
			(enabled no)
			(sheetname "")
		)
		(fill
			(thermal_gap 0.5)
			(thermal_bridge_width 0.5)
			(island_removal_mode 0)
		)
		(polygon
			(pts
				(xy 11.999976 -329.060048) (xy 2.999994 -329.060048)
				(arc
					(start 2.999994 -344.518234)
					(mid 6.671551 -340.59073)
					(end 11.999976 -339.874098)
				)
			)
		)
	)
	(zone
		(layer "F.Cu")
		(hatch none 0.5)
		(connect_pads
			(clearance 0)
		)
		(min_thickness 0.25)
		(keepout
			(tracks allowed)
			(vias allowed)
			(pads allowed)
			(copperpour allowed)
			(footprints allowed)
		)
		(placement
			(enabled no)
			(sheetname "")
		)
		(fill
			(thermal_gap 0.5)
			(thermal_bridge_width 0.5)
			(island_removal_mode 0)
		)
		(polygon
			(pts
				(xy 300.43628 -379.479302) (xy 300.43628 -378.47524) (xy 301.832772 -378.47524) (xy 301.832772 -379.479302)
			)
		)
	)
	(zone
		(layer "F.Cu")
		(hatch none 0.5)
		(connect_pads
			(clearance 0)
		)
		(min_thickness 0.25)
		(keepout
			(tracks not_allowed)
			(vias allowed)
			(pads allowed)
			(copperpour not_allowed)
			(footprints allowed)
		)
		(placement
			(enabled no)
			(sheetname "")
		)
		(fill
			(thermal_gap 0.5)
			(thermal_bridge_width 0.5)
			(island_removal_mode 0)
		)
		(polygon
			(pts
				(arc
					(start 50.570892 -66.060828)
					(mid 45.062902 -60.552838)
					(end 39.554912 -66.060828)
				)
				(arc
					(start 39.554912 -74.760836)
					(mid 45.062902 -80.268826)
					(end 50.570892 -74.760836)
				)
			)
		)
	)
	(zone
		(layer "F.Cu")
		(hatch none 0.5)
		(connect_pads
			(clearance 0)
		)
		(min_thickness 0.25)
		(keepout
			(tracks allowed)
			(vias allowed)
			(pads allowed)
			(copperpour allowed)
			(footprints allowed)
		)
		(placement
			(enabled no)
			(sheetname "")
		)
		(fill
			(thermal_gap 0.5)
			(thermal_bridge_width 0.5)
			(island_removal_mode 0)
		)
		(polygon
			(pts
				(xy 187.1726 -408.832304) (xy 279.00376 -408.832304) (xy 281.26182 -406.574244) (xy 281.26182 -392.891264)
				(xy 279.65146 -391.280904) (xy 238.77016 -391.280904) (xy 231.95788 -398.093184) (xy 189.56274 -398.093184)
				(xy 186.91098 -395.441424) (xy 182.12816 -395.441424) (xy 178.64328 -398.926304) (xy 178.64328 -406.023064)
				(xy 178.64328 -408.488642) (xy 178.92268 -408.768042) (xy 179.05603 -408.768042) (xy 179.613052 -408.21102)
				(xy 179.613052 -407.669492) (xy 179.926742 -407.355802) (xy 182.53964 -407.355802) (xy 184.016142 -408.832304)
			)
		)
	)
	(zone
		(layer "F.Cu")
		(hatch none 0.5)
		(connect_pads
			(clearance 0)
		)
		(min_thickness 0.25)
		(keepout
			(tracks not_allowed)
			(vias allowed)
			(pads allowed)
			(copperpour not_allowed)
			(footprints allowed)
		)
		(placement
			(enabled no)
			(sheetname "")
		)
		(fill
			(thermal_gap 0.5)
			(thermal_bridge_width 0.5)
			(island_removal_mode 0)
		)
		(polygon
			(pts
				(xy 92.726256 -181.97576) (xy 92.726256 -181.014878) (xy 92.48394 -181.014878) (xy 92.48394 -181.97576)
			)
		)
	)
	(zone
		(layer "F.Cu")
		(hatch none 0.5)
		(connect_pads
			(clearance 0)
		)
		(min_thickness 0.25)
		(keepout
			(tracks not_allowed)
			(vias allowed)
			(pads allowed)
			(copperpour not_allowed)
			(footprints allowed)
		)
		(placement
			(enabled no)
			(sheetname "")
		)
		(fill
			(thermal_gap 0.5)
			(thermal_bridge_width 0.5)
			(island_removal_mode 0)
		)
		(polygon
			(pts
				(arc
					(start 229.430326 -388.161784)
					(mid 225.430334 -392.161776)
					(end 221.430342 -388.161784)
				)
				(arc
					(start 221.430342 -388.161784)
					(mid 225.430334 -384.161792)
					(end 229.430326 -388.161784)
				)
			)
		)
	)
	(zone
		(layer "F.Cu")
		(hatch none 0.5)
		(connect_pads
			(clearance 0)
		)
		(min_thickness 0.25)
		(keepout
			(tracks not_allowed)
			(vias allowed)
			(pads allowed)
			(copperpour not_allowed)
			(footprints allowed)
		)
		(placement
			(enabled no)
			(sheetname "")
		)
		(fill
			(thermal_gap 0.5)
			(thermal_bridge_width 0.5)
			(island_removal_mode 0)
		)
		(polygon
			(pts
				(xy 416.574224 -163.067746) (xy 416.574224 -162.106864) (xy 416.331908 -162.106864) (xy 416.331908 -163.067746)
			)
		)
	)
	(zone
		(layer "F.Cu")
		(hatch none 0.5)
		(connect_pads
			(clearance 0)
		)
		(min_thickness 0.25)
		(keepout
			(tracks not_allowed)
			(vias allowed)
			(pads allowed)
			(copperpour not_allowed)
			(footprints allowed)
		)
		(placement
			(enabled no)
			(sheetname "")
		)
		(fill
			(thermal_gap 0.5)
			(thermal_bridge_width 0.5)
			(island_removal_mode 0)
		)
		(polygon
			(pts
				(arc
					(start 7.53999 -160.50006)
					(mid 10.340086 -157.699964)
					(end 13.139928 -160.50006)
				)
				(arc
					(start 13.139928 -160.50006)
					(mid 10.340086 -163.299902)
					(end 7.53999 -160.50006)
				)
			)
		)
	)
	(zone
		(layer "F.Cu")
		(hatch none 0.5)
		(connect_pads
			(clearance 0)
		)
		(min_thickness 0.25)
		(keepout
			(tracks allowed)
			(vias allowed)
			(pads allowed)
			(copperpour allowed)
			(footprints allowed)
		)
		(placement
			(enabled no)
			(sheetname "")
		)
		(fill
			(thermal_gap 0.5)
			(thermal_bridge_width 0.5)
			(island_removal_mode 0)
		)
		(polygon
			(pts
				(xy 163.377626 -272.728182) (xy 163.377626 -272.397982) (xy 165.296596 -272.397982) (xy 165.296596 -272.728182)
			)
		)
	)
	(zone
		(layer "F.Cu")
		(hatch none 0.5)
		(connect_pads
			(clearance 0)
		)
		(min_thickness 0.25)
		(keepout
			(tracks allowed)
			(vias allowed)
			(pads allowed)
			(copperpour allowed)
			(footprints allowed)
		)
		(placement
			(enabled no)
			(sheetname "")
		)
		(fill
			(thermal_gap 0.5)
			(thermal_bridge_width 0.5)
			(island_removal_mode 0)
		)
		(polygon
			(pts
				(xy 330.96962 -384.069844) (xy 331.973682 -384.069844) (xy 331.973682 -385.466336) (xy 330.96962 -385.466336)
			)
		)
	)
	(zone
		(layer "F.Cu")
		(hatch none 0.5)
		(connect_pads
			(clearance 0)
		)
		(min_thickness 0.25)
		(keepout
			(tracks allowed)
			(vias allowed)
			(pads allowed)
			(copperpour allowed)
			(footprints allowed)
		)
		(placement
			(enabled no)
			(sheetname "")
		)
		(fill
			(thermal_gap 0.5)
			(thermal_bridge_width 0.5)
			(island_removal_mode 0)
		)
		(polygon
			(pts
				(xy 58.13044 -198.778114) (xy 58.13044 -198.447914) (xy 60.67044 -198.447914) (xy 60.67044 -198.778114)
			)
		)
	)
	(zone
		(layer "F.Cu")
		(hatch none 0.5)
		(connect_pads
			(clearance 0)
		)
		(min_thickness 0.25)
		(keepout
			(tracks allowed)
			(vias allowed)
			(pads allowed)
			(copperpour allowed)
			(footprints not_allowed)
		)
		(placement
			(enabled no)
			(sheetname "")
		)
		(fill
			(thermal_gap 0.5)
			(thermal_bridge_width 0.5)
			(island_removal_mode 0)
		)
		(polygon
			(pts
				(arc
					(start 34.563812 -66.46672)
					(mid 32.599707 -66.86612)
					(end 30.599888 -67.00012)
				)
				(xy 30.599888 -57.53989) (xy 27.200098 -57.53989)
				(arc
					(start 27.200098 -67.00012)
					(mid 22.574634 -66.269157)
					(end 18.400014 -64.147446)
				)
				(arc
					(start 18.400014 -64.147446)
					(mid 14.22537 -66.269085)
					(end 9.59993 -67.00012)
				)
				(xy 9.59993 -57.53989) (xy 6.199886 -57.53989)
				(arc
					(start 6.199886 -67.00012)
					(mid 3.558666 -66.765613)
					(end 0.999998 -66.069718)
				)
				(arc
					(start 0.999998 -77.671676)
					(mid 1.076099 -78.054261)
					(end 1.29286 -78.378558)
				)
				(arc
					(start 2.121408 -79.207106)
					(mid 2.77167 -80.180431)
					(end 2.999994 -81.328514)
				)
				(xy 2.999994 -81.77403) (xy 34.562288 -81.77403)
			)
		)
	)
	(zone
		(layer "F.Cu")
		(hatch none 0.5)
		(connect_pads
			(clearance 0)
		)
		(min_thickness 0.25)
		(keepout
			(tracks allowed)
			(vias allowed)
			(pads allowed)
			(copperpour allowed)
			(footprints allowed)
		)
		(placement
			(enabled no)
			(sheetname "")
		)
		(fill
			(thermal_gap 0.5)
			(thermal_bridge_width 0.5)
			(island_removal_mode 0)
		)
		(polygon
			(pts
				(xy 130.348228 -110.140496) (xy 129.639568 -110.140496) (xy 129.639568 -108.867956) (xy 130.348228 -108.867956)
			)
		)
	)
	(zone
		(layer "F.Cu")
		(hatch none 0.5)
		(connect_pads
			(clearance 0)
		)
		(min_thickness 0.25)
		(keepout
			(tracks allowed)
			(vias allowed)
			(pads allowed)
			(copperpour allowed)
			(footprints allowed)
		)
		(placement
			(enabled no)
			(sheetname "")
		)
		(fill
			(thermal_gap 0.5)
			(thermal_bridge_width 0.5)
			(island_removal_mode 0)
		)
		(polygon
			(pts
				(xy 163.377626 -231.927908) (xy 163.377626 -231.597708) (xy 165.296596 -231.597708) (xy 165.296596 -231.927908)
			)
		)
	)
	(zone
		(layer "F.Cu")
		(hatch none 0.5)
		(connect_pads
			(clearance 0)
		)
		(min_thickness 0.25)
		(keepout
			(tracks not_allowed)
			(vias allowed)
			(pads allowed)
			(copperpour not_allowed)
			(footprints allowed)
		)
		(placement
			(enabled no)
			(sheetname "")
		)
		(fill
			(thermal_gap 0.5)
			(thermal_bridge_width 0.5)
			(island_removal_mode 0)
		)
		(polygon
			(pts
				(arc
					(start 12.833858 -114.706908)
					(mid 12.165838 -114.706908)
					(end 12.833858 -114.706908)
				)
			)
		)
	)
	(zone
		(layer "F.Cu")
		(hatch none 0.5)
		(connect_pads
			(clearance 0)
		)
		(min_thickness 0.25)
		(keepout
			(tracks allowed)
			(vias allowed)
			(pads allowed)
			(copperpour allowed)
			(footprints allowed)
		)
		(placement
			(enabled no)
			(sheetname "")
		)
		(fill
			(thermal_gap 0.5)
			(thermal_bridge_width 0.5)
			(island_removal_mode 0)
		)
		(polygon
			(pts
				(xy 411.317694 -251.47778) (xy 411.317694 -251.14758) (xy 413.236664 -251.14758) (xy 413.236664 -251.47778)
			)
		)
	)
	(zone
		(layer "F.Cu")
		(hatch none 0.5)
		(connect_pads
			(clearance 0)
		)
		(min_thickness 0.25)
		(keepout
			(tracks allowed)
			(vias allowed)
			(pads allowed)
			(copperpour allowed)
			(footprints allowed)
		)
		(placement
			(enabled no)
			(sheetname "")
		)
		(fill
			(thermal_gap 0.5)
			(thermal_bridge_width 0.5)
			(island_removal_mode 0)
		)
		(polygon
			(pts
				(xy 163.377626 -269.328138) (xy 163.377626 -268.997938) (xy 165.296596 -268.997938) (xy 165.296596 -269.328138)
			)
		)
	)
	(zone
		(layer "F.Cu")
		(hatch none 0.5)
		(connect_pads
			(clearance 0)
		)
		(min_thickness 0.25)
		(keepout
			(tracks allowed)
			(vias allowed)
			(pads allowed)
			(copperpour allowed)
			(footprints allowed)
		)
		(placement
			(enabled no)
			(sheetname "")
		)
		(fill
			(thermal_gap 0.5)
			(thermal_bridge_width 0.5)
			(island_removal_mode 0)
		)
		(polygon
			(pts
				(xy 363.66577 -175.716692) (xy 361.86237 -175.716692) (xy 361.86237 -177.266092) (xy 363.66577 -177.266092)
			)
		)
	)
	(zone
		(layer "F.Cu")
		(hatch none 0.5)
		(connect_pads
			(clearance 0)
		)
		(min_thickness 0.25)
		(keepout
			(tracks allowed)
			(vias allowed)
			(pads allowed)
			(copperpour allowed)
			(footprints not_allowed)
		)
		(placement
			(enabled no)
			(sheetname "")
		)
		(fill
			(thermal_gap 0.5)
			(thermal_bridge_width 0.5)
			(island_removal_mode 0)
		)
		(polygon
			(pts
				(arc
					(start 299.09897 -12.783566)
					(mid 299.065424 -13.224112)
					(end 299.044868 -13.665454)
				)
				(xy 306.28463 -13.665454) (xy 306.28463 -12.783566)
			)
		)
	)
	(zone
		(layer "F.Cu")
		(hatch none 0.5)
		(connect_pads
			(clearance 0)
		)
		(min_thickness 0.25)
		(keepout
			(tracks allowed)
			(vias allowed)
			(pads allowed)
			(copperpour allowed)
			(footprints allowed)
		)
		(placement
			(enabled no)
			(sheetname "")
		)
		(fill
			(thermal_gap 0.5)
			(thermal_bridge_width 0.5)
			(island_removal_mode 0)
		)
		(polygon
			(pts
				(xy 180.0352 -51.247548) (xy 180.0352 -49.774348) (xy 181.0766 -49.774348) (xy 181.0766 -51.247548)
			)
		)
	)
	(zone
		(layer "F.Cu")
		(hatch none 0.5)
		(connect_pads
			(clearance 0)
		)
		(min_thickness 0.25)
		(keepout
			(tracks allowed)
			(vias allowed)
			(pads allowed)
			(copperpour allowed)
			(footprints allowed)
		)
		(placement
			(enabled no)
			(sheetname "")
		)
		(fill
			(thermal_gap 0.5)
			(thermal_bridge_width 0.5)
			(island_removal_mode 0)
		)
		(polygon
			(pts
				(xy 154.43581 -409.042616) (xy 154.43581 -408.038554) (xy 155.832302 -408.038554) (xy 155.832302 -409.042616)
			)
		)
	)
	(zone
		(layer "F.Cu")
		(hatch none 0.5)
		(connect_pads
			(clearance 0)
		)
		(min_thickness 0.25)
		(keepout
			(tracks not_allowed)
			(vias allowed)
			(pads allowed)
			(copperpour not_allowed)
			(footprints allowed)
		)
		(placement
			(enabled no)
			(sheetname "")
		)
		(fill
			(thermal_gap 0.5)
			(thermal_bridge_width 0.5)
			(island_removal_mode 0)
		)
		(polygon
			(pts
				(xy 366.8141 -178.520598) (xy 366.8141 -178.063906) (xy 366.118394 -178.063906) (xy 366.118394 -178.224434)
				(xy 365.559594 -178.224434) (xy 365.559594 -177.818034) (xy 366.118394 -177.818034) (xy 366.118394 -178.038506)
				(xy 366.8141 -178.038506) (xy 366.8141 -177.911506) (xy 366.358424 -177.911506) (xy 366.358424 -177.524918)
				(xy 366.116108 -177.524918) (xy 365.584232 -177.524918) (xy 365.2647 -177.84445) (xy 365.2647 -178.520598)
			)
		)
	)
	(zone
		(layer "F.Cu")
		(hatch none 0.5)
		(connect_pads
			(clearance 0)
		)
		(min_thickness 0.25)
		(keepout
			(tracks allowed)
			(vias allowed)
			(pads allowed)
			(copperpour allowed)
			(footprints allowed)
		)
		(placement
			(enabled no)
			(sheetname "")
		)
		(fill
			(thermal_gap 0.5)
			(thermal_bridge_width 0.5)
			(island_removal_mode 0)
		)
		(polygon
			(pts
				(xy 51.52771 -332.20152) (xy 51.52771 -334.10652) (xy 55.54091 -334.10652) (xy 55.54091 -332.20152)
			)
		)
	)
	(zone
		(layer "F.Cu")
		(hatch none 0.5)
		(connect_pads
			(clearance 0)
		)
		(min_thickness 0.25)
		(keepout
			(tracks allowed)
			(vias allowed)
			(pads allowed)
			(copperpour allowed)
			(footprints allowed)
		)
		(placement
			(enabled no)
			(sheetname "")
		)
		(fill
			(thermal_gap 0.5)
			(thermal_bridge_width 0.5)
			(island_removal_mode 0)
		)
		(polygon
			(pts
				(xy 306.070508 -272.727674) (xy 306.070508 -272.397474) (xy 308.573932 -272.397474) (xy 308.573932 -272.727674)
			)
		)
	)
	(zone
		(layer "F.Cu")
		(hatch none 0.5)
		(connect_pads
			(clearance 0)
		)
		(min_thickness 0.25)
		(keepout
			(tracks not_allowed)
			(vias allowed)
			(pads allowed)
			(copperpour not_allowed)
			(footprints allowed)
		)
		(placement
			(enabled no)
			(sheetname "")
		)
		(fill
			(thermal_gap 0.5)
			(thermal_bridge_width 0.5)
			(island_removal_mode 0)
		)
		(polygon
			(pts
				(arc
					(start 461.574896 -399.029936)
					(mid 463.440018 -397.164814)
					(end 465.304886 -399.029936)
				)
				(arc
					(start 465.304886 -399.029936)
					(mid 463.440018 -400.894804)
					(end 461.574896 -399.029936)
				)
			)
		)
	)
	(zone
		(layer "F.Cu")
		(hatch none 0.5)
		(connect_pads
			(clearance 0)
		)
		(min_thickness 0.25)
		(keepout
			(tracks allowed)
			(vias allowed)
			(pads allowed)
			(copperpour allowed)
			(footprints allowed)
		)
		(placement
			(enabled no)
			(sheetname "")
		)
		(fill
			(thermal_gap 0.5)
			(thermal_bridge_width 0.5)
			(island_removal_mode 0)
		)
		(polygon
			(pts
				(xy 398.069562 -389.607044) (xy 399.073624 -389.607044) (xy 399.073624 -391.003536) (xy 398.069562 -391.003536)
			)
		)
	)
	(zone
		(layer "F.Cu")
		(hatch none 0.5)
		(connect_pads
			(clearance 0)
		)
		(min_thickness 0.25)
		(keepout
			(tracks allowed)
			(vias allowed)
			(pads allowed)
			(copperpour allowed)
			(footprints allowed)
		)
		(placement
			(enabled no)
			(sheetname "")
		)
		(fill
			(thermal_gap 0.5)
			(thermal_bridge_width 0.5)
			(island_removal_mode 0)
		)
		(polygon
			(pts
				(xy 324.26148 -379.479302) (xy 324.26148 -378.47524) (xy 325.657972 -378.47524) (xy 325.657972 -379.479302)
			)
		)
	)
	(zone
		(layer "F.Cu")
		(hatch none 0.5)
		(connect_pads
			(clearance 0)
		)
		(min_thickness 0.25)
		(keepout
			(tracks allowed)
			(vias allowed)
			(pads allowed)
			(copperpour allowed)
			(footprints allowed)
		)
		(placement
			(enabled no)
			(sheetname "")
		)
		(fill
			(thermal_gap 0.5)
			(thermal_bridge_width 0.5)
			(island_removal_mode 0)
		)
		(polygon
			(pts
				(xy 36.242498 -425.323254) (xy 36.242498 -426.719746) (xy 35.374834 -426.719746) (xy 35.374834 -424.66006)
				(xy 35.374834 -422.834816) (xy 35.643058 -422.566592) (xy 36.064952 -422.566592) (xy 36.242498 -422.744138)
				(xy 36.242498 -424.800268)
			)
		)
	)
	(zone
		(layer "F.Cu")
		(hatch none 0.5)
		(connect_pads
			(clearance 0)
		)
		(min_thickness 0.25)
		(keepout
			(tracks allowed)
			(vias allowed)
			(pads allowed)
			(copperpour allowed)
			(footprints allowed)
		)
		(placement
			(enabled no)
			(sheetname "")
		)
		(fill
			(thermal_gap 0.5)
			(thermal_bridge_width 0.5)
			(island_removal_mode 0)
		)
		(polygon
			(pts
				(xy 144.352518 -58.2295) (xy 144.352518 -56.955944) (xy 145.756122 -56.955944) (xy 145.756122 -58.2295)
			)
		)
	)
	(zone
		(layer "F.Cu")
		(hatch none 0.5)
		(connect_pads
			(clearance 0)
		)
		(min_thickness 0.25)
		(keepout
			(tracks not_allowed)
			(vias allowed)
			(pads allowed)
			(copperpour not_allowed)
			(footprints allowed)
		)
		(placement
			(enabled no)
			(sheetname "")
		)
		(fill
			(thermal_gap 0.5)
			(thermal_bridge_width 0.5)
			(island_removal_mode 0)
		)
		(polygon
			(pts
				(xy 76.005436 -176.925732) (xy 76.005436 -175.96485) (xy 75.76312 -175.96485) (xy 75.76312 -176.925732)
			)
		)
	)
	(zone
		(layer "F.Cu")
		(hatch none 0.5)
		(connect_pads
			(clearance 0)
		)
		(min_thickness 0.25)
		(keepout
			(tracks not_allowed)
			(vias allowed)
			(pads allowed)
			(copperpour not_allowed)
			(footprints allowed)
		)
		(placement
			(enabled no)
			(sheetname "")
		)
		(fill
			(thermal_gap 0.5)
			(thermal_bridge_width 0.5)
			(island_removal_mode 0)
		)
		(polygon
			(pts
				(arc
					(start 78.529942 -212.989922)
					(mid 81.330038 -210.189826)
					(end 84.12988 -212.989922)
				)
				(arc
					(start 84.12988 -212.989922)
					(mid 81.330038 -215.789764)
					(end 78.529942 -212.989922)
				)
			)
		)
	)
	(zone
		(layer "F.Cu")
		(hatch none 0.5)
		(connect_pads
			(clearance 0)
		)
		(min_thickness 0.25)
		(keepout
			(tracks allowed)
			(vias allowed)
			(pads allowed)
			(copperpour allowed)
			(footprints not_allowed)
		)
		(placement
			(enabled no)
			(sheetname "")
		)
		(fill
			(thermal_gap 0.5)
			(thermal_bridge_width 0.5)
			(island_removal_mode 0)
		)
		(polygon
			(pts
				(xy 135.56488 -71.099934) (xy 156.034994 -71.099934) (xy 156.034994 -68.229988) (xy 135.56488 -68.229988)
			)
		)
	)
	(zone
		(layer "F.Cu")
		(hatch none 0.5)
		(connect_pads
			(clearance 0)
		)
		(min_thickness 0.25)
		(keepout
			(tracks allowed)
			(vias allowed)
			(pads allowed)
			(copperpour allowed)
			(footprints allowed)
		)
		(placement
			(enabled no)
			(sheetname "")
		)
		(fill
			(thermal_gap 0.5)
			(thermal_bridge_width 0.5)
			(island_removal_mode 0)
		)
		(polygon
			(pts
				(xy 385.929886 -417.424616) (xy 385.929886 -416.420554) (xy 387.326378 -416.420554) (xy 387.326378 -417.424616)
			)
		)
	)
	(zone
		(layer "F.Cu")
		(hatch none 0.5)
		(connect_pads
			(clearance 0)
		)
		(min_thickness 0.25)
		(keepout
			(tracks allowed)
			(vias allowed)
			(pads allowed)
			(copperpour allowed)
			(footprints allowed)
		)
		(placement
			(enabled no)
			(sheetname "")
		)
		(fill
			(thermal_gap 0.5)
			(thermal_bridge_width 0.5)
			(island_removal_mode 0)
		)
		(polygon
			(pts
				(xy 163.621974 -294.82796) (xy 163.621974 -294.49776) (xy 165.296596 -294.49776) (xy 165.296596 -294.82796)
			)
		)
	)
	(zone
		(layer "F.Cu")
		(hatch none 0.5)
		(connect_pads
			(clearance 0)
		)
		(min_thickness 0.25)
		(keepout
			(tracks allowed)
			(vias allowed)
			(pads allowed)
			(copperpour allowed)
			(footprints allowed)
		)
		(placement
			(enabled no)
			(sheetname "")
		)
		(fill
			(thermal_gap 0.5)
			(thermal_bridge_width 0.5)
			(island_removal_mode 0)
		)
		(polygon
			(pts
				(xy 411.317694 -245.52783) (xy 411.317694 -245.19763) (xy 413.236664 -245.19763) (xy 413.236664 -245.52783)
			)
		)
	)
	(zone
		(layer "F.Cu")
		(hatch none 0.5)
		(connect_pads
			(clearance 0)
		)
		(min_thickness 0.25)
		(keepout
			(tracks allowed)
			(vias allowed)
			(pads allowed)
			(copperpour allowed)
			(footprints allowed)
		)
		(placement
			(enabled no)
			(sheetname "")
		)
		(fill
			(thermal_gap 0.5)
			(thermal_bridge_width 0.5)
			(island_removal_mode 0)
		)
		(polygon
			(pts
				(xy 163.377626 -265.07821) (xy 163.377626 -264.74801) (xy 165.296596 -264.74801) (xy 165.296596 -265.07821)
			)
		)
	)
	(zone
		(layer "F.Cu")
		(hatch none 0.5)
		(connect_pads
			(clearance 0)
		)
		(min_thickness 0.25)
		(keepout
			(tracks allowed)
			(vias allowed)
			(pads allowed)
			(copperpour allowed)
			(footprints not_allowed)
		)
		(placement
			(enabled no)
			(sheetname "")
		)
		(fill
			(thermal_gap 0.5)
			(thermal_bridge_width 0.5)
			(island_removal_mode 0)
		)
		(polygon
			(pts
				(xy 31.643066 -183.50992) (xy 31.643066 -327.609962) (xy 37.842952 -327.609962) (xy 37.842952 -183.50992)
			)
		)
	)
	(zone
		(layer "F.Cu")
		(hatch none 0.5)
		(connect_pads
			(clearance 0)
		)
		(min_thickness 0.25)
		(keepout
			(tracks allowed)
			(vias allowed)
			(pads allowed)
			(copperpour allowed)
			(footprints not_allowed)
		)
		(placement
			(enabled no)
			(sheetname "")
		)
		(fill
			(thermal_gap 0.5)
			(thermal_bridge_width 0.5)
			(island_removal_mode 0)
		)
		(polygon
			(pts
				(xy 267.395706 -144.808448) (xy 249.934984 -144.808448) (xy 249.934984 -91.764104) (xy 467.300056 -91.764104)
				(xy 467.300056 -144.808448) (xy 452.394066 -144.808448) (xy 452.394066 -139.308586) (xy 431.396394 -139.309856)
				(xy 431.395632 -144.808448) (xy 352.222054 -144.808448) (xy 352.222054 -143.215106) (xy 343.462102 -143.215106)
				(xy 343.462102 -144.808448) (xy 288.395664 -144.808448) (xy 288.396426 -139.291568) (xy 267.396214 -139.289282)
			)
		)
	)
	(zone
		(layer "F.Cu")
		(hatch none 0.5)
		(connect_pads
			(clearance 0)
		)
		(min_thickness 0.25)
		(keepout
			(tracks not_allowed)
			(vias allowed)
			(pads allowed)
			(copperpour not_allowed)
			(footprints allowed)
		)
		(placement
			(enabled no)
			(sheetname "")
		)
		(fill
			(thermal_gap 0.5)
			(thermal_bridge_width 0.5)
			(island_removal_mode 0)
		)
		(polygon
			(pts
				(arc
					(start 363.052106 -340.315042)
					(mid 359.952036 -343.415112)
					(end 356.851966 -340.315042)
				)
				(arc
					(start 356.851966 -340.315042)
					(mid 359.952036 -337.214972)
					(end 363.052106 -340.315042)
				)
			)
		)
	)
	(zone
		(layer "F.Cu")
		(hatch none 0.5)
		(connect_pads
			(clearance 0)
		)
		(min_thickness 0.25)
		(keepout
			(tracks allowed)
			(vias allowed)
			(pads allowed)
			(copperpour allowed)
			(footprints allowed)
		)
		(placement
			(enabled no)
			(sheetname "")
		)
		(fill
			(thermal_gap 0.5)
			(thermal_bridge_width 0.5)
			(island_removal_mode 0)
		)
		(polygon
			(pts
				(xy 87.335868 -409.042616) (xy 87.335868 -408.038554) (xy 88.73236 -408.038554) (xy 88.73236 -409.042616)
			)
		)
	)
	(zone
		(layer "F.Cu")
		(hatch none 0.5)
		(connect_pads
			(clearance 0)
		)
		(min_thickness 0.25)
		(keepout
			(tracks allowed)
			(vias allowed)
			(pads allowed)
			(copperpour allowed)
			(footprints not_allowed)
		)
		(placement
			(enabled no)
			(sheetname "")
		)
		(fill
			(thermal_gap 0.5)
			(thermal_bridge_width 0.5)
			(island_removal_mode 0)
		)
		(polygon
			(pts
				(arc
					(start 387.657086 -173.315122)
					(mid 389.522208 -171.45)
					(end 391.387076 -173.315122)
				)
				(arc
					(start 391.387076 -173.315122)
					(mid 389.522208 -175.17999)
					(end 387.657086 -173.315122)
				)
			)
		)
	)
	(zone
		(layer "F.Cu")
		(hatch none 0.5)
		(connect_pads
			(clearance 0)
		)
		(min_thickness 0.25)
		(keepout
			(tracks allowed)
			(vias allowed)
			(pads allowed)
			(copperpour allowed)
			(footprints allowed)
		)
		(placement
			(enabled no)
			(sheetname "")
		)
		(fill
			(thermal_gap 0.5)
			(thermal_bridge_width 0.5)
			(island_removal_mode 0)
		)
		(polygon
			(pts
				(xy 130.3528 -25.0698) (xy 130.3528 -24.4094) (xy 131.699 -24.4094) (xy 131.699 -25.0698)
			)
		)
	)
	(zone
		(layer "F.Cu")
		(hatch none 0.5)
		(connect_pads
			(clearance 0)
		)
		(min_thickness 0.25)
		(keepout
			(tracks allowed)
			(vias allowed)
			(pads allowed)
			(copperpour allowed)
			(footprints allowed)
		)
		(placement
			(enabled no)
			(sheetname "")
		)
		(fill
			(thermal_gap 0.5)
			(thermal_bridge_width 0.5)
			(island_removal_mode 0)
		)
		(polygon
			(pts
				(xy 373.676926 -417.424616) (xy 373.676926 -416.420554) (xy 375.073418 -416.420554) (xy 375.073418 -417.424616)
			)
		)
	)
	(zone
		(layer "F.Cu")
		(hatch none 0.5)
		(connect_pads
			(clearance 0)
		)
		(min_thickness 0.25)
		(keepout
			(tracks not_allowed)
			(vias allowed)
			(pads allowed)
			(copperpour not_allowed)
			(footprints allowed)
		)
		(placement
			(enabled no)
			(sheetname "")
		)
		(fill
			(thermal_gap 0.5)
			(thermal_bridge_width 0.5)
			(island_removal_mode 0)
		)
		(polygon
			(pts
				(arc
					(start 466.460078 -160.50006)
					(mid 461.460088 -165.50005)
					(end 456.460098 -160.50006)
				)
				(arc
					(start 456.460098 -160.50006)
					(mid 461.460088 -155.50007)
					(end 466.460078 -160.50006)
				)
			)
		)
	)
	(zone
		(layer "F.Cu")
		(hatch none 0.5)
		(connect_pads
			(clearance 0)
		)
		(min_thickness 0.25)
		(keepout
			(tracks not_allowed)
			(vias allowed)
			(pads allowed)
			(copperpour not_allowed)
			(footprints allowed)
		)
		(placement
			(enabled no)
			(sheetname "")
		)
		(fill
			(thermal_gap 0.5)
			(thermal_bridge_width 0.5)
			(island_removal_mode 0)
		)
		(polygon
			(pts
				(arc
					(start 440.087004 -351.415096)
					(mid 441.952126 -349.549974)
					(end 443.816994 -351.415096)
				)
				(arc
					(start 443.816994 -351.415096)
					(mid 441.952126 -353.279964)
					(end 440.087004 -351.415096)
				)
			)
		)
	)
	(zone
		(layer "F.Cu")
		(hatch none 0.5)
		(connect_pads
			(clearance 0)
		)
		(min_thickness 0.25)
		(keepout
			(tracks allowed)
			(vias allowed)
			(pads allowed)
			(copperpour allowed)
			(footprints allowed)
		)
		(placement
			(enabled no)
			(sheetname "")
		)
		(fill
			(thermal_gap 0.5)
			(thermal_bridge_width 0.5)
			(island_removal_mode 0)
		)
		(polygon
			(pts
				(xy 411.562042 -201.327766) (xy 411.562042 -200.997566) (xy 413.236664 -200.997566) (xy 413.236664 -201.327766)
			)
		)
	)
	(zone
		(layer "F.Cu")
		(hatch none 0.5)
		(connect_pads
			(clearance 0)
		)
		(min_thickness 0.25)
		(keepout
			(tracks allowed)
			(vias allowed)
			(pads allowed)
			(copperpour allowed)
			(footprints allowed)
		)
		(placement
			(enabled no)
			(sheetname "")
		)
		(fill
			(thermal_gap 0.5)
			(thermal_bridge_width 0.5)
			(island_removal_mode 0)
		)
		(polygon
			(pts
				(xy 179.9082 -45.329348) (xy 179.9082 -43.754548) (xy 181.0512 -43.754548) (xy 181.0512 -45.329348)
			)
		)
	)
	(zone
		(layer "F.Cu")
		(hatch none 0.5)
		(connect_pads
			(clearance 0)
		)
		(min_thickness 0.25)
		(keepout
			(tracks allowed)
			(vias allowed)
			(pads allowed)
			(copperpour allowed)
			(footprints allowed)
		)
		(placement
			(enabled no)
			(sheetname "")
		)
		(fill
			(thermal_gap 0.5)
			(thermal_bridge_width 0.5)
			(island_removal_mode 0)
		)
		(polygon
			(pts
				(xy 163.377626 -248.07799) (xy 163.377626 -247.74779) (xy 165.296596 -247.74779) (xy 165.296596 -248.07799)
			)
		)
	)
	(zone
		(layer "F.Cu")
		(hatch none 0.5)
		(connect_pads
			(clearance 0)
		)
		(min_thickness 0.25)
		(keepout
			(tracks not_allowed)
			(vias allowed)
			(pads allowed)
			(copperpour not_allowed)
			(footprints allowed)
		)
		(placement
			(enabled no)
			(sheetname "")
		)
		(fill
			(thermal_gap 0.5)
			(thermal_bridge_width 0.5)
			(island_removal_mode 0)
		)
		(polygon
			(pts
				(xy 118.185692 -172.672756) (xy 118.185692 -172.216064) (xy 117.489986 -172.216064) (xy 117.489986 -172.376592)
				(xy 116.931186 -172.376592) (xy 116.931186 -171.970192) (xy 117.489986 -171.970192) (xy 117.489986 -172.190664)
				(xy 118.185692 -172.190664) (xy 118.185692 -172.063664) (xy 117.730016 -172.063664) (xy 117.730016 -171.677076)
				(xy 117.4877 -171.677076) (xy 116.955824 -171.677076) (xy 116.636292 -171.996608) (xy 116.636292 -172.672756)
			)
		)
	)
	(zone
		(layer "F.Cu")
		(hatch none 0.5)
		(connect_pads
			(clearance 0)
		)
		(min_thickness 0.25)
		(keepout
			(tracks allowed)
			(vias allowed)
			(pads allowed)
			(copperpour allowed)
			(footprints allowed)
		)
		(placement
			(enabled no)
			(sheetname "")
		)
		(fill
			(thermal_gap 0.5)
			(thermal_bridge_width 0.5)
			(island_removal_mode 0)
		)
		(polygon
			(pts
				(xy 62.90691 -169.26814) (xy 68.53428 -169.26814) (xy 68.83908 -169.57294) (xy 68.83908 -171.88688)
				(xy 69.44106 -172.48886) (xy 69.99986 -172.48886) (xy 70.11162 -172.3771) (xy 70.11162 -170.92422)
				(xy 69.89191 -170.70451) (xy 69.89191 -168.63314) (xy 69.89191 -164.06114) (xy 69.25691 -163.42614)
				(xy 63.28791 -163.42614) (xy 62.77991 -163.93414) (xy 62.77991 -169.14114)
			)
		)
	)
	(zone
		(layer "F.Cu")
		(hatch none 0.5)
		(connect_pads
			(clearance 0)
		)
		(min_thickness 0.25)
		(keepout
			(tracks allowed)
			(vias allowed)
			(pads allowed)
			(copperpour allowed)
			(footprints not_allowed)
		)
		(placement
			(enabled no)
			(sheetname "")
		)
		(fill
			(thermal_gap 0.5)
			(thermal_bridge_width 0.5)
			(island_removal_mode 0)
		)
		(polygon
			(pts
				(xy 437.30164 -87.307166) (xy 437.304688 -60.007246) (xy 416.30473 -60.00496) (xy 416.301682 -87.30488)
			)
		)
	)
	(zone
		(layer "F.Cu")
		(hatch none 0.5)
		(connect_pads
			(clearance 0)
		)
		(min_thickness 0.25)
		(keepout
			(tracks allowed)
			(vias allowed)
			(pads allowed)
			(copperpour allowed)
			(footprints not_allowed)
		)
		(placement
			(enabled no)
			(sheetname "")
		)
		(fill
			(thermal_gap 0.5)
			(thermal_bridge_width 0.5)
			(island_removal_mode 0)
		)
		(polygon
			(pts
				(arc
					(start 175.250094 -376.489976)
					(mid 177.500026 -374.240044)
					(end 179.749958 -376.489976)
				)
				(arc
					(start 179.749958 -376.489976)
					(mid 177.500026 -378.739908)
					(end 175.250094 -376.489976)
				)
			)
		)
	)
	(zone
		(layer "F.Cu")
		(hatch none 0.5)
		(connect_pads
			(clearance 0)
		)
		(min_thickness 0.25)
		(keepout
			(tracks allowed)
			(vias allowed)
			(pads allowed)
			(copperpour allowed)
			(footprints not_allowed)
		)
		(placement
			(enabled no)
			(sheetname "")
		)
		(fill
			(thermal_gap 0.5)
			(thermal_bridge_width 0.5)
			(island_removal_mode 0)
		)
		(polygon
			(pts
				(xy 432.602894 -183.50992) (xy 426.403008 -183.50992) (xy 426.403008 -327.609962) (xy 432.602894 -327.609962)
			)
		)
	)
	(zone
		(layer "F.Cu")
		(hatch none 0.5)
		(connect_pads
			(clearance 0)
		)
		(min_thickness 0.25)
		(keepout
			(tracks allowed)
			(vias allowed)
			(pads allowed)
			(copperpour allowed)
			(footprints not_allowed)
		)
		(placement
			(enabled no)
			(sheetname "")
		)
		(fill
			(thermal_gap 0.5)
			(thermal_bridge_width 0.5)
			(island_removal_mode 0)
		)
		(polygon
			(pts
				(arc
					(start 469.989916 -51.289966)
					(mid 466.8901 -54.389782)
					(end 463.79003 -51.289966)
				)
				(arc
					(start 463.79003 -51.289966)
					(mid 466.8901 -48.189896)
					(end 469.989916 -51.289966)
				)
			)
		)
	)
	(zone
		(layer "F.Cu")
		(hatch none 0.5)
		(connect_pads
			(clearance 0)
		)
		(min_thickness 0.25)
		(keepout
			(tracks allowed)
			(vias allowed)
			(pads allowed)
			(copperpour allowed)
			(footprints allowed)
		)
		(placement
			(enabled no)
			(sheetname "")
		)
		(fill
			(thermal_gap 0.5)
			(thermal_bridge_width 0.5)
			(island_removal_mode 0)
		)
		(polygon
			(pts
				(xy 210.787488 -129.85242) (xy 210.787488 -128.906778) (xy 211.389214 -128.906778) (xy 211.389214 -129.85242)
			)
		)
	)
	(zone
		(layer "F.Cu")
		(hatch none 0.5)
		(connect_pads
			(clearance 0)
		)
		(min_thickness 0.25)
		(keepout
			(tracks allowed)
			(vias allowed)
			(pads allowed)
			(copperpour allowed)
			(footprints allowed)
		)
		(placement
			(enabled no)
			(sheetname "")
		)
		(fill
			(thermal_gap 0.5)
			(thermal_bridge_width 0.5)
			(island_removal_mode 0)
		)
		(polygon
			(pts
				(xy 11.08964 -108.991908) (xy 11.08964 -107.889548) (xy 13.02512 -107.889548) (xy 13.02512 -108.991908)
			)
		)
	)
	(zone
		(layer "F.Cu")
		(hatch none 0.5)
		(connect_pads
			(clearance 0)
		)
		(min_thickness 0.25)
		(keepout
			(tracks allowed)
			(vias allowed)
			(pads allowed)
			(copperpour allowed)
			(footprints allowed)
		)
		(placement
			(enabled no)
			(sheetname "")
		)
		(fill
			(thermal_gap 0.5)
			(thermal_bridge_width 0.5)
			(island_removal_mode 0)
		)
		(polygon
			(pts
				(xy 444.184278 -13.280136) (xy 444.184278 -6.26745) (xy 447.594482 -6.26745) (xy 447.594482 -13.280136)
			)
		)
	)
	(zone
		(layer "F.Cu")
		(hatch none 0.5)
		(connect_pads
			(clearance 0)
		)
		(min_thickness 0.25)
		(keepout
			(tracks allowed)
			(vias allowed)
			(pads allowed)
			(copperpour allowed)
			(footprints allowed)
		)
		(placement
			(enabled no)
			(sheetname "")
		)
		(fill
			(thermal_gap 0.5)
			(thermal_bridge_width 0.5)
			(island_removal_mode 0)
		)
		(polygon
			(pts
				(xy 306.070508 -247.227598) (xy 306.070508 -246.897398) (xy 308.610508 -246.897398) (xy 308.610508 -247.227598)
			)
		)
	)
	(zone
		(layer "F.Cu")
		(hatch none 0.5)
		(connect_pads
			(clearance 0)
		)
		(min_thickness 0.25)
		(keepout
			(tracks allowed)
			(vias allowed)
			(pads allowed)
			(copperpour allowed)
			(footprints not_allowed)
		)
		(placement
			(enabled no)
			(sheetname "")
		)
		(fill
			(thermal_gap 0.5)
			(thermal_bridge_width 0.5)
			(island_removal_mode 0)
		)
		(polygon
			(pts
				(arc
					(start 368.498628 -435.600094)
					(mid 371.298724 -432.799998)
					(end 374.098566 -435.600094)
				)
				(arc
					(start 374.098566 -435.600094)
					(mid 371.298724 -438.399936)
					(end 368.498628 -435.600094)
				)
			)
		)
	)
	(zone
		(layer "F.Cu")
		(hatch none 0.5)
		(connect_pads
			(clearance 0)
		)
		(min_thickness 0.25)
		(keepout
			(tracks not_allowed)
			(vias allowed)
			(pads allowed)
			(copperpour not_allowed)
			(footprints allowed)
		)
		(placement
			(enabled no)
			(sheetname "")
		)
		(fill
			(thermal_gap 0.5)
			(thermal_bridge_width 0.5)
			(island_removal_mode 0)
		)
		(polygon
			(pts
				(xy 109.956092 -178.921156) (xy 109.956092 -178.464464) (xy 109.260386 -178.464464) (xy 109.260386 -178.624992)
				(xy 108.701586 -178.624992) (xy 108.701586 -178.218592) (xy 109.260386 -178.218592) (xy 109.260386 -178.439064)
				(xy 109.956092 -178.439064) (xy 109.956092 -178.312064) (xy 109.500416 -178.312064) (xy 109.500416 -177.925476)
				(xy 109.2581 -177.925476) (xy 108.726224 -177.925476) (xy 108.406692 -178.245008) (xy 108.406692 -178.921156)
			)
		)
	)
	(zone
		(layer "F.Cu")
		(hatch none 0.5)
		(connect_pads
			(clearance 0)
		)
		(min_thickness 0.25)
		(keepout
			(tracks allowed)
			(vias allowed)
			(pads allowed)
			(copperpour allowed)
			(footprints allowed)
		)
		(placement
			(enabled no)
			(sheetname "")
		)
		(fill
			(thermal_gap 0.5)
			(thermal_bridge_width 0.5)
			(island_removal_mode 0)
		)
		(polygon
			(pts
				(xy 154.008836 -196.130926) (xy 154.203146 -195.661534) (xy 154.38374 -195.73621) (xy 154.18943 -196.205602)
			)
		)
	)
	(zone
		(layer "F.Cu")
		(hatch none 0.5)
		(connect_pads
			(clearance 0)
		)
		(min_thickness 0.25)
		(keepout
			(tracks not_allowed)
			(vias allowed)
			(pads allowed)
			(copperpour not_allowed)
			(footprints allowed)
		)
		(placement
			(enabled no)
			(sheetname "")
		)
		(fill
			(thermal_gap 0.5)
			(thermal_bridge_width 0.5)
			(island_removal_mode 0)
		)
		(polygon
			(pts
				(xy 440.008264 -12.04468) (xy 440.125612 -12.04468) (xy 440.176412 -11.99388) (xy 440.176412 -10.54608)
				(xy 440.125612 -10.49528) (xy 440.008264 -10.49528) (xy 439.957464 -10.54608) (xy 439.957464 -11.99388)
			)
		)
	)
	(zone
		(layer "F.Cu")
		(hatch none 0.5)
		(connect_pads
			(clearance 0)
		)
		(min_thickness 0.25)
		(keepout
			(tracks not_allowed)
			(vias allowed)
			(pads allowed)
			(copperpour not_allowed)
			(footprints allowed)
		)
		(placement
			(enabled no)
			(sheetname "")
		)
		(fill
			(thermal_gap 0.5)
			(thermal_bridge_width 0.5)
			(island_removal_mode 0)
		)
		(polygon
			(pts
				(arc
					(start 458.659992 -160.50006)
					(mid 461.460088 -157.699964)
					(end 464.25993 -160.50006)
				)
				(arc
					(start 464.25993 -160.50006)
					(mid 461.460088 -163.299902)
					(end 458.659992 -160.50006)
				)
			)
		)
	)
	(zone
		(layer "F.Cu")
		(hatch none 0.5)
		(connect_pads
			(clearance 0)
		)
		(min_thickness 0.25)
		(keepout
			(tracks allowed)
			(vias allowed)
			(pads allowed)
			(copperpour allowed)
			(footprints not_allowed)
		)
		(placement
			(enabled no)
			(sheetname "")
		)
		(fill
			(thermal_gap 0.5)
			(thermal_bridge_width 0.5)
			(island_removal_mode 0)
		)
		(polygon
			(pts
				(arc
					(start 15.340076 -347.700092)
					(mid 10.340086 -352.700082)
					(end 5.340096 -347.700092)
				)
				(arc
					(start 5.340096 -347.700092)
					(mid 10.340086 -342.700102)
					(end 15.340076 -347.700092)
				)
			)
		)
	)
	(zone
		(layer "F.Cu")
		(hatch none 0.5)
		(connect_pads
			(clearance 0)
		)
		(min_thickness 0.25)
		(keepout
			(tracks allowed)
			(vias allowed)
			(pads allowed)
			(copperpour allowed)
			(footprints allowed)
		)
		(placement
			(enabled no)
			(sheetname "")
		)
		(fill
			(thermal_gap 0.5)
			(thermal_bridge_width 0.5)
			(island_removal_mode 0)
		)
		(polygon
			(pts
				(xy 58.13044 -270.178022) (xy 58.13044 -269.847822) (xy 60.67044 -269.847822) (xy 60.67044 -270.178022)
			)
		)
	)
	(zone
		(layer "F.Cu")
		(hatch none 0.5)
		(connect_pads
			(clearance 0)
		)
		(min_thickness 0.25)
		(keepout
			(tracks not_allowed)
			(vias allowed)
			(pads allowed)
			(copperpour not_allowed)
			(footprints allowed)
		)
		(placement
			(enabled no)
			(sheetname "")
		)
		(fill
			(thermal_gap 0.5)
			(thermal_bridge_width 0.5)
			(island_removal_mode 0)
		)
		(polygon
			(pts
				(arc
					(start 73.316084 -344.814906)
					(mid 70.216014 -347.914976)
					(end 67.115944 -344.814906)
				)
				(arc
					(start 67.115944 -344.814906)
					(mid 70.216014 -341.714836)
					(end 73.316084 -344.814906)
				)
			)
		)
	)
	(zone
		(layer "F.Cu")
		(hatch none 0.5)
		(connect_pads
			(clearance 0)
		)
		(min_thickness 0.25)
		(keepout
			(tracks allowed)
			(vias allowed)
			(pads allowed)
			(copperpour allowed)
			(footprints allowed)
		)
		(placement
			(enabled no)
			(sheetname "")
		)
		(fill
			(thermal_gap 0.5)
			(thermal_bridge_width 0.5)
			(island_removal_mode 0)
		)
		(polygon
			(pts
				(xy 365.541814 -389.607044) (xy 366.545876 -389.607044) (xy 366.545876 -391.003536) (xy 365.541814 -391.003536)
			)
		)
	)
	(zone
		(layer "F.Cu")
		(hatch none 0.5)
		(connect_pads
			(clearance 0)
		)
		(min_thickness 0.25)
		(keepout
			(tracks allowed)
			(vias allowed)
			(pads allowed)
			(copperpour allowed)
			(footprints allowed)
		)
		(placement
			(enabled no)
			(sheetname "")
		)
		(fill
			(thermal_gap 0.5)
			(thermal_bridge_width 0.5)
			(island_removal_mode 0)
		)
		(polygon
			(pts
				(xy 369.77828 -183.083454) (xy 376.28449 -183.083454) (xy 376.91949 -182.448454) (xy 376.91949 -177.876454)
				(xy 376.28449 -177.241454) (xy 369.999006 -177.241454) (xy 369.5827 -177.65776) (xy 369.5827 -182.887874)
			)
		)
	)
	(zone
		(layer "F.Cu")
		(hatch none 0.5)
		(connect_pads
			(clearance 0)
		)
		(min_thickness 0.25)
		(keepout
			(tracks allowed)
			(vias allowed)
			(pads allowed)
			(copperpour allowed)
			(footprints allowed)
		)
		(placement
			(enabled no)
			(sheetname "")
		)
		(fill
			(thermal_gap 0.5)
			(thermal_bridge_width 0.5)
			(island_removal_mode 0)
		)
		(polygon
			(pts
				(xy 334.14589 -417.424616) (xy 334.14589 -416.420554) (xy 335.542382 -416.420554) (xy 335.542382 -417.424616)
			)
		)
	)
	(zone
		(layer "F.Cu")
		(hatch none 0.5)
		(connect_pads
			(clearance 0)
		)
		(min_thickness 0.25)
		(keepout
			(tracks not_allowed)
			(vias allowed)
			(pads allowed)
			(copperpour not_allowed)
			(footprints allowed)
		)
		(placement
			(enabled no)
			(sheetname "")
		)
		(fill
			(thermal_gap 0.5)
			(thermal_bridge_width 0.5)
			(island_removal_mode 0)
		)
		(polygon
			(pts
				(arc
					(start 200.600056 -22.29993)
					(mid 203.400152 -19.499834)
					(end 206.199994 -22.29993)
				)
				(arc
					(start 206.199994 -22.29993)
					(mid 203.400152 -25.099772)
					(end 200.600056 -22.29993)
				)
			)
		)
	)
	(zone
		(layer "F.Cu")
		(hatch none 0.5)
		(connect_pads
			(clearance 0)
		)
		(min_thickness 0.25)
		(keepout
			(tracks allowed)
			(vias allowed)
			(pads allowed)
			(copperpour allowed)
			(footprints allowed)
		)
		(placement
			(enabled no)
			(sheetname "")
		)
		(fill
			(thermal_gap 0.5)
			(thermal_bridge_width 0.5)
			(island_removal_mode 0)
		)
		(polygon
			(pts
				(xy 69.862192 -151.068278) (xy 66.166492 -151.068278) (xy 65.993772 -150.895558) (xy 65.993772 -149.356318)
				(xy 66.252852 -149.097238) (xy 66.252852 -148.601684) (xy 66.745866 -148.10867) (xy 68.891404 -148.10867)
				(xy 69.879972 -149.097238) (xy 70.100952 -149.318218) (xy 70.100952 -150.829518)
			)
		)
	)
	(zone
		(layer "F.Cu")
		(hatch none 0.5)
		(connect_pads
			(clearance 0)
		)
		(min_thickness 0.25)
		(keepout
			(tracks not_allowed)
			(vias allowed)
			(pads allowed)
			(copperpour not_allowed)
			(footprints allowed)
		)
		(placement
			(enabled no)
			(sheetname "")
		)
		(fill
			(thermal_gap 0.5)
			(thermal_bridge_width 0.5)
			(island_removal_mode 0)
		)
		(polygon
			(pts
				(xy 438.208166 -12.04468) (xy 438.325514 -12.04468) (xy 438.376314 -11.99388) (xy 438.376314 -10.54608)
				(xy 438.325514 -10.49528) (xy 438.208166 -10.49528) (xy 438.157366 -10.54608) (xy 438.157366 -11.99388)
			)
		)
	)
	(zone
		(layer "F.Cu")
		(hatch none 0.5)
		(connect_pads
			(clearance 0)
		)
		(min_thickness 0.25)
		(keepout
			(tracks allowed)
			(vias allowed)
			(pads allowed)
			(copperpour allowed)
			(footprints allowed)
		)
		(placement
			(enabled no)
			(sheetname "")
		)
		(fill
			(thermal_gap 0.5)
			(thermal_bridge_width 0.5)
			(island_removal_mode 0)
		)
		(polygon
			(pts
				(xy 211.56422 -145.2118) (xy 211.56422 -144.2085) (xy 212.45576 -144.2085) (xy 212.45576 -145.2118)
			)
		)
	)
	(zone
		(layer "F.Cu")
		(hatch none 0.5)
		(connect_pads
			(clearance 0)
		)
		(min_thickness 0.25)
		(keepout
			(tracks allowed)
			(vias allowed)
			(pads allowed)
			(copperpour allowed)
			(footprints allowed)
		)
		(placement
			(enabled no)
			(sheetname "")
		)
		(fill
			(thermal_gap 0.5)
			(thermal_bridge_width 0.5)
			(island_removal_mode 0)
		)
		(polygon
			(pts
				(xy 411.317694 -271.027906) (xy 411.317694 -270.697706) (xy 413.236664 -270.697706) (xy 413.236664 -271.027906)
			)
		)
	)
	(zone
		(layer "F.Cu")
		(hatch none 0.5)
		(connect_pads
			(clearance 0)
		)
		(min_thickness 0.25)
		(keepout
			(tracks allowed)
			(vias allowed)
			(pads allowed)
			(copperpour allowed)
			(footprints allowed)
		)
		(placement
			(enabled no)
			(sheetname "")
		)
		(fill
			(thermal_gap 0.5)
			(thermal_bridge_width 0.5)
			(island_removal_mode 0)
		)
		(polygon
			(pts
				(xy 163.377626 -279.192736) (xy 163.377626 -279.522936) (xy 165.296596 -279.522936) (xy 165.296596 -279.192736)
			)
		)
	)
	(zone
		(layer "F.Cu")
		(hatch none 0.5)
		(connect_pads
			(clearance 0)
		)
		(min_thickness 0.25)
		(keepout
			(tracks allowed)
			(vias allowed)
			(pads allowed)
			(copperpour allowed)
			(footprints allowed)
		)
		(placement
			(enabled no)
			(sheetname "")
		)
		(fill
			(thermal_gap 0.5)
			(thermal_bridge_width 0.5)
			(island_removal_mode 0)
		)
		(polygon
			(pts
				(xy 405.16937 -381.943102) (xy 405.16937 -380.93904) (xy 406.565862 -380.93904) (xy 406.565862 -381.943102)
			)
		)
	)
	(zone
		(layer "F.Cu")
		(hatch none 0.5)
		(connect_pads
			(clearance 0)
		)
		(min_thickness 0.25)
		(keepout
			(tracks allowed)
			(vias allowed)
			(pads allowed)
			(copperpour allowed)
			(footprints not_allowed)
		)
		(placement
			(enabled no)
			(sheetname "")
		)
		(fill
			(thermal_gap 0.5)
			(thermal_bridge_width 0.5)
			(island_removal_mode 0)
		)
		(polygon
			(pts
				(arc
					(start 244.650006 -192.499996)
					(mid 236.650022 -200.49998)
					(end 228.650038 -192.499996)
				)
				(arc
					(start 228.650038 -192.499996)
					(mid 236.650022 -184.500012)
					(end 244.650006 -192.499996)
				)
			)
		)
	)
	(zone
		(layer "F.Cu")
		(hatch none 0.5)
		(connect_pads
			(clearance 0)
		)
		(min_thickness 0.25)
		(keepout
			(tracks not_allowed)
			(vias allowed)
			(pads allowed)
			(copperpour not_allowed)
			(footprints allowed)
		)
		(placement
			(enabled no)
			(sheetname "")
		)
		(fill
			(thermal_gap 0.5)
			(thermal_bridge_width 0.5)
			(island_removal_mode 0)
		)
		(polygon
			(pts
				(arc
					(start 469.989916 -51.289966)
					(mid 466.8901 -54.389782)
					(end 463.79003 -51.289966)
				)
				(arc
					(start 463.79003 -51.289966)
					(mid 466.8901 -48.189896)
					(end 469.989916 -51.289966)
				)
			)
		)
	)
	(zone
		(layer "F.Cu")
		(hatch none 0.5)
		(connect_pads
			(clearance 0)
		)
		(min_thickness 0.25)
		(keepout
			(tracks allowed)
			(vias allowed)
			(pads allowed)
			(copperpour allowed)
			(footprints not_allowed)
		)
		(placement
			(enabled no)
			(sheetname "")
		)
		(fill
			(thermal_gap 0.5)
			(thermal_bridge_width 0.5)
			(island_removal_mode 0)
		)
		(polygon
			(pts
				(xy 46.73092 -183.50992) (xy 46.73092 -327.609962) (xy 52.93106 -327.609962) (xy 52.93106 -183.50992)
			)
		)
	)
	(zone
		(layer "F.Cu")
		(hatch none 0.5)
		(connect_pads
			(clearance 0)
		)
		(min_thickness 0.25)
		(keepout
			(tracks allowed)
			(vias allowed)
			(pads allowed)
			(copperpour allowed)
			(footprints not_allowed)
		)
		(placement
			(enabled no)
			(sheetname "")
		)
		(fill
			(thermal_gap 0.5)
			(thermal_bridge_width 0.5)
			(island_removal_mode 0)
		)
		(polygon
			(pts
				(arc
					(start 304.428906 -59.390026)
					(mid 307.707634 -71.639816)
					(end 319.200022 -77.0001)
				)
				(xy 319.200022 -67.540124) (xy 315.149992 -67.540124) (xy 315.149992 -56.459882) (xy 319.200022 -56.459882)
				(arc
					(start 319.200022 -46.999906)
					(mid 312.628179 -48.516278)
					(end 307.384958 -52.758594)
				)
				(xy 307.384958 -59.390026)
			)
		)
	)
	(zone
		(layer "F.Cu")
		(hatch none 0.5)
		(connect_pads
			(clearance 0)
		)
		(min_thickness 0.25)
		(keepout
			(tracks allowed)
			(vias allowed)
			(pads allowed)
			(copperpour allowed)
			(footprints not_allowed)
		)
		(placement
			(enabled no)
			(sheetname "")
		)
		(fill
			(thermal_gap 0.5)
			(thermal_bridge_width 0.5)
			(island_removal_mode 0)
		)
		(polygon
			(pts
				(arc
					(start 463.320384 -30.161992)
					(mid 464.799934 -29.700001)
					(end 466.279484 -30.161992)
				)
				(arc
					(start 466.279484 -30.161992)
					(mid 468.754375 -29.254283)
					(end 470.799922 -27.591512)
				)
				(arc
					(start 470.799922 -17.008602)
					(mid 457.845774 -18.345481)
					(end 463.320384 -30.161992)
				)
			)
		)
	)
	(zone
		(layer "F.Cu")
		(hatch none 0.5)
		(connect_pads
			(clearance 0)
		)
		(min_thickness 0.25)
		(keepout
			(tracks allowed)
			(vias allowed)
			(pads allowed)
			(copperpour allowed)
			(footprints allowed)
		)
		(placement
			(enabled no)
			(sheetname "")
		)
		(fill
			(thermal_gap 0.5)
			(thermal_bridge_width 0.5)
			(island_removal_mode 0)
		)
		(polygon
			(pts
				(xy 104.01173 -409.339542) (xy 104.01173 -410.073094) (xy 102.954836 -410.073094) (xy 102.954836 -409.339542)
			)
		)
	)
	(zone
		(layer "F.Cu")
		(hatch none 0.5)
		(connect_pads
			(clearance 0)
		)
		(min_thickness 0.25)
		(keepout
			(tracks not_allowed)
			(vias allowed)
			(pads allowed)
			(copperpour not_allowed)
			(footprints allowed)
		)
		(placement
			(enabled no)
			(sheetname "")
		)
		(fill
			(thermal_gap 0.5)
			(thermal_bridge_width 0.5)
			(island_removal_mode 0)
		)
		(polygon
			(pts
				(xy 68.364608 -335.700116) (xy 68.364608 -336.660998) (xy 68.606924 -336.660998) (xy 68.606924 -335.700116)
			)
		)
	)
	(zone
		(layer "F.Cu")
		(hatch none 0.5)
		(connect_pads
			(clearance 0)
		)
		(min_thickness 0.25)
		(keepout
			(tracks not_allowed)
			(vias allowed)
			(pads allowed)
			(copperpour not_allowed)
			(footprints allowed)
		)
		(placement
			(enabled no)
			(sheetname "")
		)
		(fill
			(thermal_gap 0.5)
			(thermal_bridge_width 0.5)
			(island_removal_mode 0)
		)
		(polygon
			(pts
				(xy 324.65899 -335.68767) (xy 324.65899 -336.648552) (xy 324.901306 -336.648552) (xy 324.901306 -335.68767)
			)
		)
	)
	(zone
		(layer "F.Cu")
		(hatch none 0.5)
		(connect_pads
			(clearance 0)
		)
		(min_thickness 0.25)
		(keepout
			(tracks allowed)
			(vias allowed)
			(pads allowed)
			(copperpour allowed)
			(footprints allowed)
		)
		(placement
			(enabled no)
			(sheetname "")
		)
		(fill
			(thermal_gap 0.5)
			(thermal_bridge_width 0.5)
			(island_removal_mode 0)
		)
		(polygon
			(pts
				(xy 285.297372 -421.723312) (xy 285.297372 -420.548054) (xy 286.261556 -420.548054) (xy 286.261556 -421.723312)
			)
		)
	)
	(zone
		(layer "F.Cu")
		(hatch none 0.5)
		(connect_pads
			(clearance 0)
		)
		(min_thickness 0.25)
		(keepout
			(tracks allowed)
			(vias allowed)
			(pads allowed)
			(copperpour allowed)
			(footprints allowed)
		)
		(placement
			(enabled no)
			(sheetname "")
		)
		(fill
			(thermal_gap 0.5)
			(thermal_bridge_width 0.5)
			(island_removal_mode 0)
		)
		(polygon
			(pts
				(xy 43.24731 -332.20152) (xy 43.24731 -334.10652) (xy 47.26051 -334.10652) (xy 47.26051 -332.20152)
			)
		)
	)
	(zone
		(layer "F.Cu")
		(hatch none 0.5)
		(connect_pads
			(clearance 0)
		)
		(min_thickness 0.25)
		(keepout
			(tracks allowed)
			(vias allowed)
			(pads allowed)
			(copperpour allowed)
			(footprints not_allowed)
		)
		(placement
			(enabled no)
			(sheetname "")
		)
		(fill
			(thermal_gap 0.5)
			(thermal_bridge_width 0.5)
			(island_removal_mode 0)
		)
		(polygon
			(pts
				(arc
					(start 13.53693 -11.532362)
					(mid 12.471941 -12.448952)
					(end 11.106404 -12.78001)
				)
				(arc
					(start 83.697572 -12.78001)
					(mid 82.339599 -12.45274)
					(end 81.276952 -11.546078)
				)
				(xy 81.276952 -11.949938) (xy 13.53693 -11.949938)
			)
		)
	)
	(zone
		(layer "F.Cu")
		(hatch none 0.5)
		(connect_pads
			(clearance 0)
		)
		(min_thickness 0.25)
		(keepout
			(tracks allowed)
			(vias allowed)
			(pads allowed)
			(copperpour allowed)
			(footprints allowed)
		)
		(placement
			(enabled no)
			(sheetname "")
		)
		(fill
			(thermal_gap 0.5)
			(thermal_bridge_width 0.5)
			(island_removal_mode 0)
		)
		(polygon
			(pts
				(xy 345.775026 -335.745074) (xy 343.971626 -335.745074) (xy 343.971626 -337.294474) (xy 345.775026 -337.294474)
			)
		)
	)
	(zone
		(layer "F.Cu")
		(hatch none 0.5)
		(connect_pads
			(clearance 0)
		)
		(min_thickness 0.25)
		(keepout
			(tracks not_allowed)
			(vias allowed)
			(pads allowed)
			(copperpour not_allowed)
			(footprints allowed)
		)
		(placement
			(enabled no)
			(sheetname "")
		)
		(fill
			(thermal_gap 0.5)
			(thermal_bridge_width 0.5)
			(island_removal_mode 0)
		)
		(polygon
			(pts
				(arc
					(start 104.850946 -166.61511)
					(mid 106.716068 -164.749988)
					(end 108.580936 -166.61511)
				)
				(arc
					(start 108.580936 -166.61511)
					(mid 106.716068 -168.479978)
					(end 104.850946 -166.61511)
				)
			)
		)
	)
	(zone
		(layer "F.Cu")
		(hatch none 0.5)
		(connect_pads
			(clearance 0)
		)
		(min_thickness 0.25)
		(keepout
			(tracks allowed)
			(vias allowed)
			(pads allowed)
			(copperpour allowed)
			(footprints not_allowed)
		)
		(placement
			(enabled no)
			(sheetname "")
		)
		(fill
			(thermal_gap 0.5)
			(thermal_bridge_width 0.5)
			(island_removal_mode 0)
		)
		(polygon
			(pts
				(arc
					(start 146.029934 -304.790094)
					(mid 142.530068 -308.28996)
					(end 139.029948 -304.790094)
				)
				(arc
					(start 139.029948 -304.790094)
					(mid 142.530068 -301.289974)
					(end 146.029934 -304.790094)
				)
			)
		)
	)
	(zone
		(layer "F.Cu")
		(hatch none 0.5)
		(connect_pads
			(clearance 0)
		)
		(min_thickness 0.25)
		(keepout
			(tracks allowed)
			(vias allowed)
			(pads allowed)
			(copperpour allowed)
			(footprints allowed)
		)
		(placement
			(enabled no)
			(sheetname "")
		)
		(fill
			(thermal_gap 0.5)
			(thermal_bridge_width 0.5)
			(island_removal_mode 0)
		)
		(polygon
			(pts
				(xy 289.23107 -332.196694) (xy 289.23107 -334.101694) (xy 293.24427 -334.101694) (xy 293.24427 -332.196694)
			)
		)
	)
	(zone
		(layer "F.Cu")
		(hatch none 0.5)
		(connect_pads
			(clearance 0)
		)
		(min_thickness 0.25)
		(keepout
			(tracks allowed)
			(vias allowed)
			(pads allowed)
			(copperpour allowed)
			(footprints not_allowed)
		)
		(placement
			(enabled no)
			(sheetname "")
		)
		(fill
			(thermal_gap 0.5)
			(thermal_bridge_width 0.5)
			(island_removal_mode 0)
		)
		(polygon
			(pts
				(arc
					(start 456.46086 -160.50006)
					(mid 461.46085 -155.50007)
					(end 466.46084 -160.50006)
				)
				(arc
					(start 466.46084 -160.50006)
					(mid 461.46085 -165.50005)
					(end 456.46086 -160.50006)
				)
			)
		)
	)
	(zone
		(layer "F.Cu")
		(hatch none 0.5)
		(connect_pads
			(clearance 0)
		)
		(min_thickness 0.25)
		(keepout
			(tracks allowed)
			(vias allowed)
			(pads allowed)
			(copperpour allowed)
			(footprints not_allowed)
		)
		(placement
			(enabled no)
			(sheetname "")
		)
		(fill
			(thermal_gap 0.5)
			(thermal_bridge_width 0.5)
			(island_removal_mode 0)
		)
		(polygon
			(pts
				(xy 74.331068 -346.734892) (xy 93.57106 -346.734892) (xy 93.57106 -350.415098) (xy 109.770926 -350.415098)
				(xy 109.770926 -344.914982) (xy 97.865946 -344.914982) (xy 94.070932 -341.23503) (xy 74.331068 -341.23503)
			)
		)
	)
	(zone
		(layer "F.Cu")
		(hatch none 0.5)
		(connect_pads
			(clearance 0)
		)
		(min_thickness 0.25)
		(keepout
			(tracks allowed)
			(vias allowed)
			(pads allowed)
			(copperpour allowed)
			(footprints allowed)
		)
		(placement
			(enabled no)
			(sheetname "")
		)
		(fill
			(thermal_gap 0.5)
			(thermal_bridge_width 0.5)
			(island_removal_mode 0)
		)
		(polygon
			(pts
				(xy 114.61369 -409.042616) (xy 114.61369 -408.038554) (xy 116.010182 -408.038554) (xy 116.010182 -409.042616)
			)
		)
	)
	(zone
		(layer "F.Cu")
		(hatch none 0.5)
		(connect_pads
			(clearance 0)
		)
		(min_thickness 0.25)
		(keepout
			(tracks allowed)
			(vias allowed)
			(pads allowed)
			(copperpour allowed)
			(footprints not_allowed)
		)
		(placement
			(enabled no)
			(sheetname "")
		)
		(fill
			(thermal_gap 0.5)
			(thermal_bridge_width 0.5)
			(island_removal_mode 0)
		)
		(polygon
			(pts
				(arc
					(start 253.000002 -290.900104)
					(mid 249.900186 -293.99992)
					(end 246.800116 -290.900104)
				)
				(arc
					(start 246.800116 -290.900104)
					(mid 249.900186 -287.800034)
					(end 253.000002 -290.900104)
				)
			)
		)
	)
	(zone
		(layer "F.Cu")
		(hatch none 0.5)
		(connect_pads
			(clearance 0)
		)
		(min_thickness 0.25)
		(keepout
			(tracks not_allowed)
			(vias allowed)
			(pads allowed)
			(copperpour not_allowed)
			(footprints allowed)
		)
		(placement
			(enabled no)
			(sheetname "")
		)
		(fill
			(thermal_gap 0.5)
			(thermal_bridge_width 0.5)
			(island_removal_mode 0)
		)
		(polygon
			(pts
				(arc
					(start 5.00507 -389.439912)
					(mid 6.870192 -387.57479)
					(end 8.73506 -389.439912)
				)
				(arc
					(start 8.73506 -389.439912)
					(mid 6.870192 -391.30478)
					(end 5.00507 -389.439912)
				)
			)
		)
	)
	(zone
		(layer "F.Cu")
		(hatch none 0.5)
		(connect_pads
			(clearance 0)
		)
		(min_thickness 0.25)
		(keepout
			(tracks allowed)
			(vias allowed)
			(pads allowed)
			(copperpour allowed)
			(footprints allowed)
		)
		(placement
			(enabled no)
			(sheetname "")
		)
		(fill
			(thermal_gap 0.5)
			(thermal_bridge_width 0.5)
			(island_removal_mode 0)
		)
		(polygon
			(pts
				(xy 176.2252 -56.073548) (xy 176.2252 -42.103548) (xy 179.5272 -42.103548) (xy 179.5272 -56.073548)
			)
		)
	)
	(zone
		(layer "F.Cu")
		(hatch none 0.5)
		(connect_pads
			(clearance 0)
		)
		(min_thickness 0.25)
		(keepout
			(tracks not_allowed)
			(vias allowed)
			(pads allowed)
			(copperpour not_allowed)
			(footprints allowed)
		)
		(placement
			(enabled no)
			(sheetname "")
		)
		(fill
			(thermal_gap 0.5)
			(thermal_bridge_width 0.5)
			(island_removal_mode 0)
		)
		(polygon
			(pts
				(arc
					(start 430.49317 -244.08511)
					(mid 429.82515 -244.08511)
					(end 430.49317 -244.08511)
				)
			)
		)
	)
	(zone
		(layer "F.Cu")
		(hatch none 0.5)
		(connect_pads
			(clearance 0)
		)
		(min_thickness 0.25)
		(keepout
			(tracks allowed)
			(vias allowed)
			(pads allowed)
			(copperpour allowed)
			(footprints not_allowed)
		)
		(placement
			(enabled no)
			(sheetname "")
		)
		(fill
			(thermal_gap 0.5)
			(thermal_bridge_width 0.5)
			(island_removal_mode 0)
		)
		(polygon
			(pts
				(arc
					(start 64.382904 -45.449998)
					(mid 65.98285 -47.049944)
					(end 64.382904 -48.64989)
				)
				(arc
					(start 62.782958 -48.64989)
					(mid 61.183012 -47.049944)
					(end 62.782958 -45.449998)
				)
			)
		)
	)
	(zone
		(layer "F.Cu")
		(hatch none 0.5)
		(connect_pads
			(clearance 0)
		)
		(min_thickness 0.25)
		(keepout
			(tracks not_allowed)
			(vias allowed)
			(pads allowed)
			(copperpour not_allowed)
			(footprints allowed)
		)
		(placement
			(enabled no)
			(sheetname "")
		)
		(fill
			(thermal_gap 0.5)
			(thermal_bridge_width 0.5)
			(island_removal_mode 0)
		)
		(polygon
			(pts
				(arc
					(start 151.230076 -258.890008)
					(mid 154.030172 -256.089912)
					(end 156.830014 -258.890008)
				)
				(arc
					(start 156.830014 -258.890008)
					(mid 154.030172 -261.68985)
					(end 151.230076 -258.890008)
				)
			)
		)
	)
	(zone
		(layer "F.Cu")
		(hatch none 0.5)
		(connect_pads
			(clearance 0)
		)
		(min_thickness 0.25)
		(keepout
			(tracks not_allowed)
			(vias allowed)
			(pads allowed)
			(copperpour not_allowed)
			(footprints allowed)
		)
		(placement
			(enabled no)
			(sheetname "")
		)
		(fill
			(thermal_gap 0.5)
			(thermal_bridge_width 0.5)
			(island_removal_mode 0)
		)
		(polygon
			(pts
				(arc
					(start 320.099944 -160.50006)
					(mid 322.90004 -157.699964)
					(end 325.699882 -160.50006)
				)
				(arc
					(start 325.699882 -160.50006)
					(mid 322.90004 -163.299902)
					(end 320.099944 -160.50006)
				)
			)
		)
	)
	(zone
		(layer "F.Cu")
		(hatch none 0.5)
		(connect_pads
			(clearance 0)
		)
		(min_thickness 0.25)
		(keepout
			(tracks allowed)
			(vias allowed)
			(pads allowed)
			(copperpour allowed)
			(footprints allowed)
		)
		(placement
			(enabled no)
			(sheetname "")
		)
		(fill
			(thermal_gap 0.5)
			(thermal_bridge_width 0.5)
			(island_removal_mode 0)
		)
		(polygon
			(pts
				(xy 391.083546 -315.788802) (xy 391.083546 -314.991242) (xy 392.881612 -314.991242) (xy 392.881612 -315.788802)
			)
		)
	)
	(zone
		(layer "F.Cu")
		(hatch none 0.5)
		(connect_pads
			(clearance 0)
		)
		(min_thickness 0.25)
		(keepout
			(tracks allowed)
			(vias allowed)
			(pads allowed)
			(copperpour allowed)
			(footprints not_allowed)
		)
		(placement
			(enabled no)
			(sheetname "")
		)
		(fill
			(thermal_gap 0.5)
			(thermal_bridge_width 0.5)
			(island_removal_mode 0)
		)
		(polygon
			(pts
				(arc
					(start 98.482912 -47.049944)
					(mid 100.383086 -45.14977)
					(end 102.283006 -47.049944)
				)
				(arc
					(start 102.283006 -47.049944)
					(mid 100.383086 -48.949864)
					(end 98.482912 -47.049944)
				)
			)
		)
	)
	(zone
		(layer "F.Cu")
		(hatch none 0.5)
		(connect_pads
			(clearance 0)
		)
		(min_thickness 0.25)
		(keepout
			(tracks allowed)
			(vias allowed)
			(pads allowed)
			(copperpour allowed)
			(footprints allowed)
		)
		(placement
			(enabled no)
			(sheetname "")
		)
		(fill
			(thermal_gap 0.5)
			(thermal_bridge_width 0.5)
			(island_removal_mode 0)
		)
		(polygon
			(pts
				(xy 309.63997 -417.424616) (xy 309.63997 -416.420554) (xy 311.036462 -416.420554) (xy 311.036462 -417.424616)
			)
		)
	)
	(zone
		(layer "F.Cu")
		(hatch none 0.5)
		(connect_pads
			(clearance 0)
		)
		(min_thickness 0.25)
		(keepout
			(tracks allowed)
			(vias allowed)
			(pads allowed)
			(copperpour allowed)
			(footprints not_allowed)
		)
		(placement
			(enabled no)
			(sheetname "")
		)
		(fill
			(thermal_gap 0.5)
			(thermal_bridge_width 0.5)
			(island_removal_mode 0)
		)
		(polygon
			(pts
				(arc
					(start 73.080118 -258.890008)
					(mid 69.830188 -262.139938)
					(end 66.580004 -258.890008)
				)
				(arc
					(start 66.580004 -258.890008)
					(mid 69.830188 -255.639824)
					(end 73.080118 -258.890008)
				)
			)
		)
	)
	(zone
		(layer "F.Cu")
		(hatch none 0.5)
		(connect_pads
			(clearance 0)
		)
		(min_thickness 0.25)
		(keepout
			(tracks allowed)
			(vias allowed)
			(pads allowed)
			(copperpour allowed)
			(footprints allowed)
		)
		(placement
			(enabled no)
			(sheetname "")
		)
		(fill
			(thermal_gap 0.5)
			(thermal_bridge_width 0.5)
			(island_removal_mode 0)
		)
		(polygon
			(pts
				(xy 49.541938 -373.561102) (xy 49.541938 -372.55704) (xy 50.93843 -372.55704) (xy 50.93843 -373.561102)
			)
		)
	)
	(zone
		(layer "F.Cu")
		(hatch none 0.5)
		(connect_pads
			(clearance 0)
		)
		(min_thickness 0.25)
		(keepout
			(tracks allowed)
			(vias allowed)
			(pads allowed)
			(copperpour allowed)
			(footprints allowed)
		)
		(placement
			(enabled no)
			(sheetname "")
		)
		(fill
			(thermal_gap 0.5)
			(thermal_bridge_width 0.5)
			(island_removal_mode 0)
		)
		(polygon
			(pts
				(xy 163.621974 -229.378002) (xy 163.621974 -229.047802) (xy 165.296596 -229.047802) (xy 165.296596 -229.378002)
			)
		)
	)
	(zone
		(layer "F.Cu")
		(hatch none 0.5)
		(connect_pads
			(clearance 0)
		)
		(min_thickness 0.25)
		(keepout
			(tracks not_allowed)
			(vias allowed)
			(pads allowed)
			(copperpour not_allowed)
			(footprints allowed)
		)
		(placement
			(enabled no)
			(sheetname "")
		)
		(fill
			(thermal_gap 0.5)
			(thermal_bridge_width 0.5)
			(island_removal_mode 0)
		)
		(polygon
			(pts
				(xy 383.122424 -182.086504) (xy 383.122424 -181.125622) (xy 382.880108 -181.125622) (xy 382.880108 -182.086504)
			)
		)
	)
	(zone
		(layer "F.Cu")
		(hatch none 0.5)
		(connect_pads
			(clearance 0)
		)
		(min_thickness 0.25)
		(keepout
			(tracks not_allowed)
			(vias allowed)
			(pads allowed)
			(copperpour not_allowed)
			(footprints allowed)
		)
		(placement
			(enabled no)
			(sheetname "")
		)
		(fill
			(thermal_gap 0.5)
			(thermal_bridge_width 0.5)
			(island_removal_mode 0)
		)
		(polygon
			(pts
				(arc
					(start 294.011096 -244.08511)
					(mid 293.343076 -244.08511)
					(end 294.011096 -244.08511)
				)
			)
		)
	)
	(zone
		(layer "F.Cu")
		(hatch none 0.5)
		(connect_pads
			(clearance 0)
		)
		(min_thickness 0.25)
		(keepout
			(tracks not_allowed)
			(vias allowed)
			(pads allowed)
			(copperpour not_allowed)
			(footprints allowed)
		)
		(placement
			(enabled no)
			(sheetname "")
		)
		(fill
			(thermal_gap 0.5)
			(thermal_bridge_width 0.5)
			(island_removal_mode 0)
		)
		(polygon
			(pts
				(arc
					(start 288.820098 -384.869944)
					(mid 291.07003 -382.620012)
					(end 293.319962 -384.869944)
				)
				(arc
					(start 293.319962 -384.869944)
					(mid 291.07003 -387.119876)
					(end 288.820098 -384.869944)
				)
			)
		)
	)
	(zone
		(layer "F.Cu")
		(hatch none 0.5)
		(connect_pads
			(clearance 0)
		)
		(min_thickness 0.25)
		(keepout
			(tracks allowed)
			(vias allowed)
			(pads allowed)
			(copperpour allowed)
			(footprints allowed)
		)
		(placement
			(enabled no)
			(sheetname "")
		)
		(fill
			(thermal_gap 0.5)
			(thermal_bridge_width 0.5)
			(island_removal_mode 0)
		)
		(polygon
			(pts
				(xy 81.15554 -335.032858) (xy 74.80554 -335.032858) (xy 74.17054 -335.667858) (xy 74.17054 -340.239858)
				(xy 74.80554 -340.874858) (xy 80.77454 -340.874858) (xy 81.28254 -340.366858) (xy 81.28254 -335.159858)
			)
		)
	)
	(zone
		(layer "F.Cu")
		(hatch none 0.5)
		(connect_pads
			(clearance 0)
		)
		(min_thickness 0.25)
		(keepout
			(tracks not_allowed)
			(vias allowed)
			(pads allowed)
			(copperpour not_allowed)
			(footprints allowed)
		)
		(placement
			(enabled no)
			(sheetname "")
		)
		(fill
			(thermal_gap 0.5)
			(thermal_bridge_width 0.5)
			(island_removal_mode 0)
		)
		(polygon
			(pts
				(arc
					(start 52.85105 -167.135048)
					(mid 54.716172 -165.269926)
					(end 56.58104 -167.135048)
				)
				(arc
					(start 56.58104 -167.135048)
					(mid 54.716172 -168.999916)
					(end 52.85105 -167.135048)
				)
			)
		)
	)
	(zone
		(layer "F.Cu")
		(hatch none 0.5)
		(connect_pads
			(clearance 0)
		)
		(min_thickness 0.25)
		(keepout
			(tracks allowed)
			(vias allowed)
			(pads allowed)
			(copperpour allowed)
			(footprints allowed)
		)
		(placement
			(enabled no)
			(sheetname "")
		)
		(fill
			(thermal_gap 0.5)
			(thermal_bridge_width 0.5)
			(island_removal_mode 0)
		)
		(polygon
			(pts
				(xy 411.317694 -207.277716) (xy 411.317694 -206.947516) (xy 413.236664 -206.947516) (xy 413.236664 -207.277716)
			)
		)
	)
	(zone
		(layer "F.Cu")
		(hatch none 0.5)
		(connect_pads
			(clearance 0)
		)
		(min_thickness 0.25)
		(keepout
			(tracks allowed)
			(vias allowed)
			(pads allowed)
			(copperpour allowed)
			(footprints not_allowed)
		)
		(placement
			(enabled no)
			(sheetname "")
		)
		(fill
			(thermal_gap 0.5)
			(thermal_bridge_width 0.5)
			(island_removal_mode 0)
		)
		(polygon
			(pts
				(xy 387.08711 -12.850114) (xy 456.727052 -12.850114)
				(arc
					(start 456.727052 -12.392406)
					(mid 456.209779 -12.023006)
					(end 455.781918 -11.552936)
				)
				(xy 455.781918 -11.949938) (xy 388.03707 -11.949938)
				(arc
					(start 388.03707 -11.532362)
					(mid 387.6081 -12.010633)
					(end 387.08711 -12.386564)
				)
			)
		)
	)
	(zone
		(layer "F.Cu")
		(hatch none 0.5)
		(connect_pads
			(clearance 0)
		)
		(min_thickness 0.25)
		(keepout
			(tracks allowed)
			(vias allowed)
			(pads allowed)
			(copperpour allowed)
			(footprints allowed)
		)
		(placement
			(enabled no)
			(sheetname "")
		)
		(fill
			(thermal_gap 0.5)
			(thermal_bridge_width 0.5)
			(island_removal_mode 0)
		)
		(polygon
			(pts
				(xy 56.246776 -346.61729) (xy 49.896776 -346.61729) (xy 49.261776 -347.25229) (xy 49.261776 -351.82429)
				(xy 49.896776 -352.45929) (xy 55.865776 -352.45929) (xy 56.373776 -351.95129) (xy 56.373776 -346.74429)
			)
		)
	)
	(zone
		(layer "F.Cu")
		(hatch none 0.5)
		(connect_pads
			(clearance 0)
		)
		(min_thickness 0.25)
		(keepout
			(tracks allowed)
			(vias allowed)
			(pads allowed)
			(copperpour allowed)
			(footprints allowed)
		)
		(placement
			(enabled no)
			(sheetname "")
		)
		(fill
			(thermal_gap 0.5)
			(thermal_bridge_width 0.5)
			(island_removal_mode 0)
		)
		(polygon
			(pts
				(xy 370.512086 -415.16173) (xy 370.512086 -414.157668) (xy 371.908578 -414.157668) (xy 371.908578 -415.16173)
			)
		)
	)
	(zone
		(layer "F.Cu")
		(hatch none 0.5)
		(connect_pads
			(clearance 0)
		)
		(min_thickness 0.25)
		(keepout
			(tracks allowed)
			(vias allowed)
			(pads allowed)
			(copperpour allowed)
			(footprints not_allowed)
		)
		(placement
			(enabled no)
			(sheetname "")
		)
		(fill
			(thermal_gap 0.5)
			(thermal_bridge_width 0.5)
			(island_removal_mode 0)
		)
		(polygon
			(pts
				(arc
					(start 346.187014 -147.904962)
					(mid 348.052136 -146.03984)
					(end 349.917004 -147.904962)
				)
				(arc
					(start 349.917004 -147.904962)
					(mid 348.052136 -149.76983)
					(end 346.187014 -147.904962)
				)
			)
		)
	)
	(zone
		(layer "F.Cu")
		(hatch none 0.5)
		(connect_pads
			(clearance 0)
		)
		(min_thickness 0.25)
		(keepout
			(tracks allowed)
			(vias allowed)
			(pads allowed)
			(copperpour allowed)
			(footprints allowed)
		)
		(placement
			(enabled no)
			(sheetname "")
		)
		(fill
			(thermal_gap 0.5)
			(thermal_bridge_width 0.5)
			(island_removal_mode 0)
		)
		(polygon
			(pts
				(xy 80.702658 -20.079208) (xy 80.702658 -19.797268) (xy 81.027524 -19.797268) (xy 81.027524 -20.079208)
			)
		)
	)
	(zone
		(layer "F.Cu")
		(hatch none 0.5)
		(connect_pads
			(clearance 0)
		)
		(min_thickness 0.25)
		(keepout
			(tracks allowed)
			(vias allowed)
			(pads allowed)
			(copperpour allowed)
			(footprints not_allowed)
		)
		(placement
			(enabled no)
			(sheetname "")
		)
		(fill
			(thermal_gap 0.5)
			(thermal_bridge_width 0.5)
			(island_removal_mode 0)
		)
		(polygon
			(pts
				(xy 184.66308 -327.609962) (xy 184.66308 -183.50992) (xy 178.46294 -183.50992) (xy 178.46294 -327.609962)
			)
		)
	)
	(zone
		(layer "F.Cu")
		(hatch none 0.5)
		(connect_pads
			(clearance 0)
		)
		(min_thickness 0.25)
		(keepout
			(tracks allowed)
			(vias allowed)
			(pads allowed)
			(copperpour allowed)
			(footprints not_allowed)
		)
		(placement
			(enabled no)
			(sheetname "")
		)
		(fill
			(thermal_gap 0.5)
			(thermal_bridge_width 0.5)
			(island_removal_mode 0)
		)
		(polygon
			(pts
				(arc
					(start 94.383098 -43.850052)
					(mid 97.583244 -47.050198)
					(end 94.383098 -50.25009)
				)
				(arc
					(start 92.782898 -50.25009)
					(mid 89.583006 -47.050198)
					(end 92.782898 -43.850052)
				)
			)
		)
	)
	(zone
		(layer "F.Cu")
		(hatch none 0.5)
		(connect_pads
			(clearance 0)
		)
		(min_thickness 0.25)
		(keepout
			(tracks allowed)
			(vias allowed)
			(pads allowed)
			(copperpour allowed)
			(footprints allowed)
		)
		(placement
			(enabled no)
			(sheetname "")
		)
		(fill
			(thermal_gap 0.5)
			(thermal_bridge_width 0.5)
			(island_removal_mode 0)
		)
		(polygon
			(pts
				(xy 337.20913 -417.424616) (xy 337.20913 -416.420554) (xy 338.605622 -416.420554) (xy 338.605622 -417.424616)
			)
		)
	)
	(zone
		(layer "F.Cu")
		(hatch none 0.5)
		(connect_pads
			(clearance 0)
		)
		(min_thickness 0.25)
		(keepout
			(tracks allowed)
			(vias allowed)
			(pads allowed)
			(copperpour allowed)
			(footprints allowed)
		)
		(placement
			(enabled no)
			(sheetname "")
		)
		(fill
			(thermal_gap 0.5)
			(thermal_bridge_width 0.5)
			(island_removal_mode 0)
		)
		(polygon
			(pts
				(xy 60.344812 -209.49285) (xy 60.344812 -209.82305) (xy 57.804812 -209.82305) (xy 57.804812 -209.49285)
			)
		)
	)
	(zone
		(layer "F.Cu")
		(hatch none 0.5)
		(connect_pads
			(clearance 0)
		)
		(min_thickness 0.25)
		(keepout
			(tracks allowed)
			(vias allowed)
			(pads allowed)
			(copperpour allowed)
			(footprints not_allowed)
		)
		(placement
			(enabled no)
			(sheetname "")
		)
		(fill
			(thermal_gap 0.5)
			(thermal_bridge_width 0.5)
			(island_removal_mode 0)
		)
		(polygon
			(pts
				(arc
					(start 273.649948 -51.999896)
					(mid 268.649958 -56.999886)
					(end 263.649968 -51.999896)
				)
				(arc
					(start 263.649968 -51.999896)
					(mid 268.649958 -46.999906)
					(end 273.649948 -51.999896)
				)
			)
		)
	)
	(zone
		(layer "F.Cu")
		(hatch none 0.5)
		(connect_pads
			(clearance 0)
		)
		(min_thickness 0.25)
		(keepout
			(tracks allowed)
			(vias allowed)
			(pads allowed)
			(copperpour allowed)
			(footprints allowed)
		)
		(placement
			(enabled no)
			(sheetname "")
		)
		(fill
			(thermal_gap 0.5)
			(thermal_bridge_width 0.5)
			(island_removal_mode 0)
		)
		(polygon
			(pts
				(xy 306.070508 -250.627642) (xy 306.070508 -250.297442) (xy 308.610508 -250.297442) (xy 308.610508 -250.627642)
			)
		)
	)
	(zone
		(layer "F.Cu")
		(hatch none 0.5)
		(connect_pads
			(clearance 0)
		)
		(min_thickness 0.25)
		(keepout
			(tracks allowed)
			(vias allowed)
			(pads allowed)
			(copperpour allowed)
			(footprints not_allowed)
		)
		(placement
			(enabled no)
			(sheetname "")
		)
		(fill
			(thermal_gap 0.5)
			(thermal_bridge_width 0.5)
			(island_removal_mode 0)
		)
		(polygon
			(pts
				(xy 217.019886 -286.120078) (xy 217.019886 -296.720006) (xy 254.999998 -296.720006) (xy 254.999998 -286.120078)
			)
		)
	)
	(zone
		(layer "F.Cu")
		(hatch none 0.5)
		(connect_pads
			(clearance 0)
		)
		(min_thickness 0.25)
		(keepout
			(tracks allowed)
			(vias allowed)
			(pads allowed)
			(copperpour allowed)
			(footprints allowed)
		)
		(placement
			(enabled no)
			(sheetname "")
		)
		(fill
			(thermal_gap 0.5)
			(thermal_bridge_width 0.5)
			(island_removal_mode 0)
		)
		(polygon
			(pts
				(xy 411.317694 -247.227852) (xy 411.317694 -246.897652) (xy 413.236664 -246.897652) (xy 413.236664 -247.227852)
			)
		)
	)
	(zone
		(layer "F.Cu")
		(hatch none 0.5)
		(connect_pads
			(clearance 0)
		)
		(min_thickness 0.25)
		(keepout
			(tracks allowed)
			(vias allowed)
			(pads allowed)
			(copperpour allowed)
			(footprints not_allowed)
		)
		(placement
			(enabled no)
			(sheetname "")
		)
		(fill
			(thermal_gap 0.5)
			(thermal_bridge_width 0.5)
			(island_removal_mode 0)
		)
		(polygon
			(pts
				(xy 123.916948 -52.049934) (xy 123.916948 -42.049954) (xy 86.397084 -42.049954) (xy 86.397084 -47.118016)
				(xy 82.147156 -47.118016) (xy 82.147156 -42.049954) (xy 50.917094 -42.049954) (xy 50.917094 -52.049934)
			)
		)
	)
	(zone
		(layer "F.Cu")
		(hatch none 0.5)
		(connect_pads
			(clearance 0)
		)
		(min_thickness 0.25)
		(keepout
			(tracks allowed)
			(vias allowed)
			(pads allowed)
			(copperpour allowed)
			(footprints not_allowed)
		)
		(placement
			(enabled no)
			(sheetname "")
		)
		(fill
			(thermal_gap 0.5)
			(thermal_bridge_width 0.5)
			(island_removal_mode 0)
		)
		(polygon
			(pts
				(arc
					(start 461.574896 -399.029936)
					(mid 463.440018 -397.164814)
					(end 465.304886 -399.029936)
				)
				(arc
					(start 465.304886 -399.029936)
					(mid 463.440018 -400.894804)
					(end 461.574896 -399.029936)
				)
			)
		)
	)
	(zone
		(layer "F.Cu")
		(hatch none 0.5)
		(connect_pads
			(clearance 0)
		)
		(min_thickness 0.25)
		(keepout
			(tracks allowed)
			(vias allowed)
			(pads allowed)
			(copperpour allowed)
			(footprints allowed)
		)
		(placement
			(enabled no)
			(sheetname "")
		)
		(fill
			(thermal_gap 0.5)
			(thermal_bridge_width 0.5)
			(island_removal_mode 0)
		)
		(polygon
			(pts
				(xy 39.332662 -347.226382) (xy 37.529262 -347.226382) (xy 37.529262 -348.775782) (xy 39.332662 -348.775782)
			)
		)
	)
	(zone
		(layer "F.Cu")
		(hatch none 0.5)
		(connect_pads
			(clearance 0)
		)
		(min_thickness 0.25)
		(keepout
			(tracks allowed)
			(vias allowed)
			(pads allowed)
			(copperpour allowed)
			(footprints allowed)
		)
		(placement
			(enabled no)
			(sheetname "")
		)
		(fill
			(thermal_gap 0.5)
			(thermal_bridge_width 0.5)
			(island_removal_mode 0)
		)
		(polygon
			(pts
				(xy 23.586948 -391.21334) (xy 25.66924 -391.21334) (xy 25.66924 -394.08862) (xy 23.55088 -394.08862)
				(xy 22.501606 -394.08862) (xy 22.258274 -393.845288) (xy 22.258274 -392.505946) (xy 21.772626 -392.020298)
				(xy 21.772626 -388.688326) (xy 21.951442 -388.50951) (xy 22.667214 -388.50951) (xy 23.586948 -389.429244)
			)
		)
	)
	(zone
		(layer "F.Cu")
		(hatch none 0.5)
		(connect_pads
			(clearance 0)
		)
		(min_thickness 0.25)
		(keepout
			(tracks allowed)
			(vias allowed)
			(pads allowed)
			(copperpour allowed)
			(footprints allowed)
		)
		(placement
			(enabled no)
			(sheetname "")
		)
		(fill
			(thermal_gap 0.5)
			(thermal_bridge_width 0.5)
			(island_removal_mode 0)
		)
		(polygon
			(pts
				(xy 328.422 -0.84582) (xy 328.422 1.29032) (xy 330.62672 1.29032) (xy 330.62672 -0.84582)
			)
		)
	)
	(zone
		(layer "F.Cu")
		(hatch none 0.5)
		(connect_pads
			(clearance 0)
		)
		(min_thickness 0.25)
		(keepout
			(tracks allowed)
			(vias allowed)
			(pads allowed)
			(copperpour allowed)
			(footprints not_allowed)
		)
		(placement
			(enabled no)
			(sheetname "")
		)
		(fill
			(thermal_gap 0.5)
			(thermal_bridge_width 0.5)
			(island_removal_mode 0)
		)
		(polygon
			(pts
				(arc
					(start 230.89997 -81.700116)
					(mid 235.89996 -76.700126)
					(end 240.89995 -81.700116)
				)
				(arc
					(start 240.89995 -81.700116)
					(mid 235.89996 -86.700106)
					(end 230.89997 -81.700116)
				)
			)
		)
	)
	(zone
		(layer "F.Cu")
		(hatch none 0.5)
		(connect_pads
			(clearance 0)
		)
		(min_thickness 0.25)
		(keepout
			(tracks allowed)
			(vias allowed)
			(pads allowed)
			(copperpour allowed)
			(footprints not_allowed)
		)
		(placement
			(enabled no)
			(sheetname "")
		)
		(fill
			(thermal_gap 0.5)
			(thermal_bridge_width 0.5)
			(island_removal_mode 0)
		)
		(polygon
			(pts
				(xy 319.651888 -341.644986) (xy 321.567048 -341.644986) (xy 321.567048 -351.605088) (xy 313.452002 -351.605088)
				(xy 313.452002 -347.646498) (xy 314.332112 -347.646498) (xy 314.332112 -345.876626) (xy 313.452002 -345.876626)
				(xy 313.452002 -340.814914) (xy 319.651888 -340.814914)
			)
		)
	)
	(zone
		(layer "F.Cu")
		(hatch none 0.5)
		(connect_pads
			(clearance 0)
		)
		(min_thickness 0.25)
		(keepout
			(tracks allowed)
			(vias allowed)
			(pads allowed)
			(copperpour allowed)
			(footprints not_allowed)
		)
		(placement
			(enabled no)
			(sheetname "")
		)
		(fill
			(thermal_gap 0.5)
			(thermal_bridge_width 0.5)
			(island_removal_mode 0)
		)
		(polygon
			(pts
				(arc
					(start 467.300056 -165.967664)
					(mid 453.460093 -160.50006)
					(end 467.300056 -155.032456)
				)
			)
		)
	)
	(zone
		(layer "F.Cu")
		(hatch none 0.5)
		(connect_pads
			(clearance 0)
		)
		(min_thickness 0.25)
		(keepout
			(tracks allowed)
			(vias allowed)
			(pads allowed)
			(copperpour allowed)
			(footprints allowed)
		)
		(placement
			(enabled no)
			(sheetname "")
		)
		(fill
			(thermal_gap 0.5)
			(thermal_bridge_width 0.5)
			(island_removal_mode 0)
		)
		(polygon
			(pts
				(xy 336.367628 -384.406902) (xy 336.367628 -383.40284) (xy 337.76412 -383.40284) (xy 337.76412 -384.406902)
			)
		)
	)
	(zone
		(layer "F.Cu")
		(hatch none 0.5)
		(connect_pads
			(clearance 0)
		)
		(min_thickness 0.25)
		(keepout
			(tracks not_allowed)
			(vias allowed)
			(pads allowed)
			(copperpour not_allowed)
			(footprints allowed)
		)
		(placement
			(enabled no)
			(sheetname "")
		)
		(fill
			(thermal_gap 0.5)
			(thermal_bridge_width 0.5)
			(island_removal_mode 0)
		)
		(polygon
			(pts
				(xy 76.720192 -335.693004) (xy 76.720192 -336.653886) (xy 76.962508 -336.653886) (xy 76.962508 -335.693004)
			)
		)
	)
	(zone
		(layer "F.Cu")
		(hatch none 0.5)
		(connect_pads
			(clearance 0)
		)
		(min_thickness 0.25)
		(keepout
			(tracks allowed)
			(vias allowed)
			(pads allowed)
			(copperpour allowed)
			(footprints not_allowed)
		)
		(placement
			(enabled no)
			(sheetname "")
		)
		(fill
			(thermal_gap 0.5)
			(thermal_bridge_width 0.5)
			(island_removal_mode 0)
		)
		(polygon
			(pts
				(arc
					(start 287.070038 -384.869944)
					(mid 291.07003 -380.869952)
					(end 295.070022 -384.869944)
				)
				(arc
					(start 295.070022 -384.869944)
					(mid 291.07003 -388.869936)
					(end 287.070038 -384.869944)
				)
			)
		)
	)
	(zone
		(layer "F.Cu")
		(hatch none 0.5)
		(connect_pads
			(clearance 0)
		)
		(min_thickness 0.25)
		(keepout
			(tracks not_allowed)
			(vias allowed)
			(pads allowed)
			(copperpour not_allowed)
			(footprints allowed)
		)
		(placement
			(enabled no)
			(sheetname "")
		)
		(fill
			(thermal_gap 0.5)
			(thermal_bridge_width 0.5)
			(island_removal_mode 0)
		)
		(polygon
			(pts
				(arc
					(start 346.187014 -147.904962)
					(mid 348.052136 -146.03984)
					(end 349.917004 -147.904962)
				)
				(arc
					(start 349.917004 -147.904962)
					(mid 348.052136 -149.76983)
					(end 346.187014 -147.904962)
				)
			)
		)
	)
	(zone
		(layer "F.Cu")
		(hatch none 0.5)
		(connect_pads
			(clearance 0)
		)
		(min_thickness 0.25)
		(keepout
			(tracks allowed)
			(vias allowed)
			(pads allowed)
			(copperpour allowed)
			(footprints allowed)
		)
		(placement
			(enabled no)
			(sheetname "")
		)
		(fill
			(thermal_gap 0.5)
			(thermal_bridge_width 0.5)
			(island_removal_mode 0)
		)
		(polygon
			(pts
				(xy 19.3802 -136.26338) (xy 20.8534 -136.26338) (xy 20.8534 -137.15238) (xy 19.3802 -137.15238)
			)
		)
	)
	(zone
		(layer "F.Cu")
		(hatch none 0.5)
		(connect_pads
			(clearance 0)
		)
		(min_thickness 0.25)
		(keepout
			(tracks allowed)
			(vias allowed)
			(pads allowed)
			(copperpour allowed)
			(footprints allowed)
		)
		(placement
			(enabled no)
			(sheetname "")
		)
		(fill
			(thermal_gap 0.5)
			(thermal_bridge_width 0.5)
			(island_removal_mode 0)
		)
		(polygon
			(pts
				(xy 307.274976 -359.5751) (xy 307.274976 -360.67238) (xy 306.104036 -360.67238) (xy 304.760122 -360.67238)
				(xy 304.486564 -360.398822) (xy 304.486564 -356.32644) (xy 304.87874 -355.934264) (xy 305.506374 -355.934264)
				(xy 307.274976 -357.702866)
			)
		)
	)
	(zone
		(layer "F.Cu")
		(hatch none 0.5)
		(connect_pads
			(clearance 0)
		)
		(min_thickness 0.25)
		(keepout
			(tracks allowed)
			(vias allowed)
			(pads allowed)
			(copperpour allowed)
			(footprints allowed)
		)
		(placement
			(enabled no)
			(sheetname "")
		)
		(fill
			(thermal_gap 0.5)
			(thermal_bridge_width 0.5)
			(island_removal_mode 0)
		)
		(polygon
			(pts
				(xy 93.462348 -409.042616) (xy 93.462348 -408.038554) (xy 94.85884 -408.038554) (xy 94.85884 -409.042616)
			)
		)
	)
	(zone
		(layer "F.Cu")
		(hatch none 0.5)
		(connect_pads
			(clearance 0)
		)
		(min_thickness 0.25)
		(keepout
			(tracks allowed)
			(vias allowed)
			(pads allowed)
			(copperpour allowed)
			(footprints not_allowed)
		)
		(placement
			(enabled no)
			(sheetname "")
		)
		(fill
			(thermal_gap 0.5)
			(thermal_bridge_width 0.5)
			(island_removal_mode 0)
		)
		(polygon
			(pts
				(arc
					(start 331.849984 -73.808336)
					(mid 327.492608 -76.179691)
					(end 322.600066 -77.0001)
				)
				(xy 322.600066 -67.540124) (xy 326.650096 -67.540124) (xy 326.650096 -56.459882) (xy 322.600066 -56.459882)
				(arc
					(start 322.600066 -46.999906)
					(mid 327.552821 -47.841246)
					(end 331.95006 -50.270664)
				)
				(xy 331.95006 -55.47995) (xy 341.099902 -55.47995) (xy 341.099902 -56.459882) (xy 337.050126 -56.459882)
				(xy 337.050126 -67.540124) (xy 341.099902 -67.540124)
				(arc
					(start 341.099902 -77.0001)
					(mid 336.207364 -76.179682)
					(end 331.849984 -73.808336)
				)
			)
		)
	)
	(zone
		(layer "F.Cu")
		(hatch none 0.5)
		(connect_pads
			(clearance 0)
		)
		(min_thickness 0.25)
		(keepout
			(tracks allowed)
			(vias allowed)
			(pads allowed)
			(copperpour allowed)
			(footprints allowed)
		)
		(placement
			(enabled no)
			(sheetname "")
		)
		(fill
			(thermal_gap 0.5)
			(thermal_bridge_width 0.5)
			(island_removal_mode 0)
		)
		(polygon
			(pts
				(xy 306.070508 -242.127786) (xy 306.070508 -241.797586) (xy 308.610508 -241.797586) (xy 308.610508 -242.127786)
			)
		)
	)
	(zone
		(layer "F.Cu")
		(hatch none 0.5)
		(connect_pads
			(clearance 0)
		)
		(min_thickness 0.25)
		(keepout
			(tracks allowed)
			(vias allowed)
			(pads allowed)
			(copperpour allowed)
			(footprints allowed)
		)
		(placement
			(enabled no)
			(sheetname "")
		)
		(fill
			(thermal_gap 0.5)
			(thermal_bridge_width 0.5)
			(island_removal_mode 0)
		)
		(polygon
			(pts
				(xy 236.493558 -48.149256) (xy 236.493558 -47.638208) (xy 239.063022 -47.638208) (xy 239.063022 -48.149256)
			)
		)
	)
	(zone
		(layer "F.Cu")
		(hatch none 0.5)
		(connect_pads
			(clearance 0)
		)
		(min_thickness 0.25)
		(keepout
			(tracks not_allowed)
			(vias allowed)
			(pads allowed)
			(copperpour not_allowed)
			(footprints allowed)
		)
		(placement
			(enabled no)
			(sheetname "")
		)
		(fill
			(thermal_gap 0.5)
			(thermal_bridge_width 0.5)
			(island_removal_mode 0)
		)
		(polygon
			(pts
				(arc
					(start 451.300088 -435.600094)
					(mid 448.80022 -438.099962)
					(end 446.300098 -435.600094)
				)
				(arc
					(start 446.300098 -435.600094)
					(mid 448.80022 -433.099972)
					(end 451.300088 -435.600094)
				)
			)
		)
	)
	(zone
		(layer "F.Cu")
		(hatch none 0.5)
		(connect_pads
			(clearance 0)
		)
		(min_thickness 0.25)
		(keepout
			(tracks allowed)
			(vias allowed)
			(pads allowed)
			(copperpour allowed)
			(footprints not_allowed)
		)
		(placement
			(enabled no)
			(sheetname "")
		)
		(fill
			(thermal_gap 0.5)
			(thermal_bridge_width 0.5)
			(island_removal_mode 0)
		)
		(polygon
			(pts
				(arc
					(start 135.986012 -146.84502)
					(mid 132.886196 -149.944836)
					(end 129.786126 -146.84502)
				)
				(arc
					(start 129.786126 -146.84502)
					(mid 132.886196 -143.74495)
					(end 135.986012 -146.84502)
				)
			)
		)
	)
	(zone
		(layer "F.Cu")
		(hatch none 0.5)
		(connect_pads
			(clearance 0)
		)
		(min_thickness 0.25)
		(keepout
			(tracks allowed)
			(vias allowed)
			(pads allowed)
			(copperpour allowed)
			(footprints allowed)
		)
		(placement
			(enabled no)
			(sheetname "")
		)
		(fill
			(thermal_gap 0.5)
			(thermal_bridge_width 0.5)
			(island_removal_mode 0)
		)
		(polygon
			(pts
				(xy 372.026942 -180.68925) (xy 370.223542 -180.68925) (xy 370.223542 -182.23865) (xy 372.026942 -182.23865)
			)
		)
	)
	(zone
		(layer "F.Cu")
		(hatch none 0.5)
		(connect_pads
			(clearance 0)
		)
		(min_thickness 0.25)
		(keepout
			(tracks allowed)
			(vias allowed)
			(pads allowed)
			(copperpour allowed)
			(footprints allowed)
		)
		(placement
			(enabled no)
			(sheetname "")
		)
		(fill
			(thermal_gap 0.5)
			(thermal_bridge_width 0.5)
			(island_removal_mode 0)
		)
		(polygon
			(pts
				(xy 458.608938 -47.829216) (xy 458.608938 -46.181518) (xy 460.122778 -46.181518) (xy 460.122778 -47.829216)
			)
		)
	)
	(zone
		(layer "F.Cu")
		(hatch none 0.5)
		(connect_pads
			(clearance 0)
		)
		(min_thickness 0.25)
		(keepout
			(tracks allowed)
			(vias allowed)
			(pads allowed)
			(copperpour allowed)
			(footprints allowed)
		)
		(placement
			(enabled no)
			(sheetname "")
		)
		(fill
			(thermal_gap 0.5)
			(thermal_bridge_width 0.5)
			(island_removal_mode 0)
		)
		(polygon
			(pts
				(xy 432.008026 -164.00018) (xy 432.008026 -163.436554) (xy 433.382166 -163.436554) (xy 433.382166 -164.00018)
			)
		)
	)
	(zone
		(layer "F.Cu")
		(hatch none 0.5)
		(connect_pads
			(clearance 0)
		)
		(min_thickness 0.25)
		(keepout
			(tracks allowed)
			(vias allowed)
			(pads allowed)
			(copperpour allowed)
			(footprints allowed)
		)
		(placement
			(enabled no)
			(sheetname "")
		)
		(fill
			(thermal_gap 0.5)
			(thermal_bridge_width 0.5)
			(island_removal_mode 0)
		)
		(polygon
			(pts
				(xy 389.816848 -3.862324) (xy 389.816848 -20.04822) (xy 439.439812 -20.04822) (xy 439.439812 -3.862324)
			)
		)
	)
	(zone
		(layer "F.Cu")
		(hatch none 0.5)
		(connect_pads
			(clearance 0)
		)
		(min_thickness 0.25)
		(keepout
			(tracks allowed)
			(vias allowed)
			(pads allowed)
			(copperpour allowed)
			(footprints allowed)
		)
		(placement
			(enabled no)
			(sheetname "")
		)
		(fill
			(thermal_gap 0.5)
			(thermal_bridge_width 0.5)
			(island_removal_mode 0)
		)
		(polygon
			(pts
				(xy 163.377626 -262.52805) (xy 163.377626 -262.19785) (xy 165.296596 -262.19785) (xy 165.296596 -262.52805)
			)
		)
	)
	(zone
		(layer "F.Cu")
		(hatch none 0.5)
		(connect_pads
			(clearance 0)
		)
		(min_thickness 0.25)
		(keepout
			(tracks allowed)
			(vias allowed)
			(pads allowed)
			(copperpour allowed)
			(footprints allowed)
		)
		(placement
			(enabled no)
			(sheetname "")
		)
		(fill
			(thermal_gap 0.5)
			(thermal_bridge_width 0.5)
			(island_removal_mode 0)
		)
		(polygon
			(pts
				(xy 210.453224 -372.404894) (xy 210.875118 -372.404894) (xy 210.875118 -372.519956) (xy 210.453224 -372.519956)
			)
		)
	)
	(zone
		(layer "F.Cu")
		(hatch none 0.5)
		(connect_pads
			(clearance 0)
		)
		(min_thickness 0.25)
		(keepout
			(tracks allowed)
			(vias allowed)
			(pads allowed)
			(copperpour allowed)
			(footprints allowed)
		)
		(placement
			(enabled no)
			(sheetname "")
		)
		(fill
			(thermal_gap 0.5)
			(thermal_bridge_width 0.5)
			(island_removal_mode 0)
		)
		(polygon
			(pts
				(xy 306.070508 -244.677692) (xy 306.070508 -244.347492) (xy 308.610508 -244.347492) (xy 308.610508 -244.677692)
			)
		)
	)
	(zone
		(layer "F.Cu")
		(hatch none 0.5)
		(connect_pads
			(clearance 0)
		)
		(min_thickness 0.25)
		(keepout
			(tracks allowed)
			(vias allowed)
			(pads allowed)
			(copperpour allowed)
			(footprints allowed)
		)
		(placement
			(enabled no)
			(sheetname "")
		)
		(fill
			(thermal_gap 0.5)
			(thermal_bridge_width 0.5)
			(island_removal_mode 0)
		)
		(polygon
			(pts
				(xy 161.002726 -351.884996) (xy 161.002726 -350.739202) (xy 162.19805 -350.739202) (xy 162.19805 -351.884996)
			)
		)
	)
	(zone
		(layer "F.Cu")
		(hatch none 0.5)
		(connect_pads
			(clearance 0)
		)
		(min_thickness 0.25)
		(keepout
			(tracks allowed)
			(vias allowed)
			(pads allowed)
			(copperpour allowed)
			(footprints allowed)
		)
		(placement
			(enabled no)
			(sheetname "")
		)
		(fill
			(thermal_gap 0.5)
			(thermal_bridge_width 0.5)
			(island_removal_mode 0)
		)
		(polygon
			(pts
				(xy 413.88157 -161.713164) (xy 412.07817 -161.713164) (xy 412.07817 -163.262564) (xy 413.88157 -163.262564)
			)
		)
	)
	(zone
		(layer "F.Cu")
		(hatch none 0.5)
		(connect_pads
			(clearance 0)
		)
		(min_thickness 0.25)
		(keepout
			(tracks allowed)
			(vias allowed)
			(pads allowed)
			(copperpour allowed)
			(footprints allowed)
		)
		(placement
			(enabled no)
			(sheetname "")
		)
		(fill
			(thermal_gap 0.5)
			(thermal_bridge_width 0.5)
			(island_removal_mode 0)
		)
		(polygon
			(pts
				(xy 411.317694 -288.542476) (xy 411.317694 -288.872676) (xy 413.236664 -288.872676) (xy 413.236664 -288.542476)
			)
		)
	)
	(zone
		(layer "F.Cu")
		(hatch none 0.5)
		(connect_pads
			(clearance 0)
		)
		(min_thickness 0.25)
		(keepout
			(tracks allowed)
			(vias allowed)
			(pads allowed)
			(copperpour allowed)
			(footprints allowed)
		)
		(placement
			(enabled no)
			(sheetname "")
		)
		(fill
			(thermal_gap 0.5)
			(thermal_bridge_width 0.5)
			(island_removal_mode 0)
		)
		(polygon
			(pts
				(xy 308.66588 -315.74232) (xy 308.66588 -316.07252) (xy 306.12588 -316.07252) (xy 306.12588 -315.74232)
			)
		)
	)
	(zone
		(layer "F.Cu")
		(hatch none 0.5)
		(connect_pads
			(clearance 0)
		)
		(min_thickness 0.25)
		(keepout
			(tracks allowed)
			(vias allowed)
			(pads allowed)
			(copperpour allowed)
			(footprints allowed)
		)
		(placement
			(enabled no)
			(sheetname "")
		)
		(fill
			(thermal_gap 0.5)
			(thermal_bridge_width 0.5)
			(island_removal_mode 0)
		)
		(polygon
			(pts
				(xy 411.317694 -282.077922) (xy 411.317694 -281.747722) (xy 413.236664 -281.747722) (xy 413.236664 -282.077922)
			)
		)
	)
	(zone
		(layer "F.Cu")
		(hatch none 0.5)
		(connect_pads
			(clearance 0)
		)
		(min_thickness 0.25)
		(keepout
			(tracks allowed)
			(vias allowed)
			(pads allowed)
			(copperpour allowed)
			(footprints allowed)
		)
		(placement
			(enabled no)
			(sheetname "")
		)
		(fill
			(thermal_gap 0.5)
			(thermal_bridge_width 0.5)
			(island_removal_mode 0)
		)
		(polygon
			(pts
				(xy 31.303976 -346.61729) (xy 24.953976 -346.61729) (xy 24.318976 -347.25229) (xy 24.318976 -351.82429)
				(xy 24.953976 -352.45929) (xy 30.922976 -352.45929) (xy 31.430976 -351.95129) (xy 31.430976 -346.74429)
			)
		)
	)
	(zone
		(layer "F.Cu")
		(hatch none 0.5)
		(connect_pads
			(clearance 0)
		)
		(min_thickness 0.25)
		(keepout
			(tracks not_allowed)
			(vias allowed)
			(pads allowed)
			(copperpour not_allowed)
			(footprints allowed)
		)
		(placement
			(enabled no)
			(sheetname "")
		)
		(fill
			(thermal_gap 0.5)
			(thermal_bridge_width 0.5)
			(island_removal_mode 0)
		)
		(polygon
			(pts
				(xy 93.409008 -335.729326) (xy 93.409008 -336.690208) (xy 93.651324 -336.690208) (xy 93.651324 -335.729326)
			)
		)
	)
	(zone
		(layer "F.Cu")
		(hatch none 0.5)
		(connect_pads
			(clearance 0)
		)
		(min_thickness 0.25)
		(keepout
			(tracks allowed)
			(vias allowed)
			(pads allowed)
			(copperpour allowed)
			(footprints allowed)
		)
		(placement
			(enabled no)
			(sheetname "")
		)
		(fill
			(thermal_gap 0.5)
			(thermal_bridge_width 0.5)
			(island_removal_mode 0)
		)
		(polygon
			(pts
				(xy 14.11732 -106.388408) (xy 14.11732 -103.866188) (xy 14.804136 -103.179372) (xy 16.516604 -103.179372)
				(xy 17.20342 -103.866188) (xy 17.20342 -106.388408)
			)
		)
	)
	(zone
		(layer "F.Cu")
		(hatch none 0.5)
		(connect_pads
			(clearance 0)
		)
		(min_thickness 0.25)
		(keepout
			(tracks not_allowed)
			(vias allowed)
			(pads allowed)
			(copperpour not_allowed)
			(footprints allowed)
		)
		(placement
			(enabled no)
			(sheetname "")
		)
		(fill
			(thermal_gap 0.5)
			(thermal_bridge_width 0.5)
			(island_removal_mode 0)
		)
		(polygon
			(pts
				(arc
					(start 4.19989 -22.29993)
					(mid 6.999986 -19.499834)
					(end 9.800082 -22.29993)
				)
				(arc
					(start 9.800082 -22.29993)
					(mid 6.999986 -25.100026)
					(end 4.19989 -22.29993)
				)
			)
		)
	)
	(zone
		(layer "F.Cu")
		(hatch none 0.5)
		(connect_pads
			(clearance 0)
		)
		(min_thickness 0.25)
		(keepout
			(tracks allowed)
			(vias allowed)
			(pads allowed)
			(copperpour allowed)
			(footprints not_allowed)
		)
		(placement
			(enabled no)
			(sheetname "")
		)
		(fill
			(thermal_gap 0.5)
			(thermal_bridge_width 0.5)
			(island_removal_mode 0)
		)
		(polygon
			(pts
				(arc
					(start 241.650012 -192.499996)
					(mid 236.650022 -197.499986)
					(end 231.650032 -192.499996)
				)
				(arc
					(start 231.650032 -192.499996)
					(mid 236.650022 -187.500006)
					(end 241.650012 -192.499996)
				)
			)
		)
	)
	(zone
		(layer "F.Cu")
		(hatch none 0.5)
		(connect_pads
			(clearance 0)
		)
		(min_thickness 0.25)
		(keepout
			(tracks allowed)
			(vias allowed)
			(pads allowed)
			(copperpour allowed)
			(footprints not_allowed)
		)
		(placement
			(enabled no)
			(sheetname "")
		)
		(fill
			(thermal_gap 0.5)
			(thermal_bridge_width 0.5)
			(island_removal_mode 0)
		)
		(polygon
			(pts
				(xy 425.059094 -183.50992) (xy 418.858954 -183.50992) (xy 418.858954 -327.609962) (xy 425.059094 -327.609962)
			)
		)
	)
	(zone
		(layer "F.Cu")
		(hatch none 0.5)
		(connect_pads
			(clearance 0)
		)
		(min_thickness 0.25)
		(keepout
			(tracks not_allowed)
			(vias allowed)
			(pads allowed)
			(copperpour not_allowed)
			(footprints allowed)
		)
		(placement
			(enabled no)
			(sheetname "")
		)
		(fill
			(thermal_gap 0.5)
			(thermal_bridge_width 0.5)
			(island_removal_mode 0)
		)
		(polygon
			(pts
				(arc
					(start 326.47001 -212.989922)
					(mid 329.270106 -210.189826)
					(end 332.069948 -212.989922)
				)
				(arc
					(start 332.069948 -212.989922)
					(mid 329.270106 -215.789764)
					(end 326.47001 -212.989922)
				)
			)
		)
	)
	(zone
		(layer "F.Cu")
		(hatch none 0.5)
		(connect_pads
			(clearance 0)
		)
		(min_thickness 0.25)
		(keepout
			(tracks allowed)
			(vias allowed)
			(pads allowed)
			(copperpour allowed)
			(footprints allowed)
		)
		(placement
			(enabled no)
			(sheetname "")
		)
		(fill
			(thermal_gap 0.5)
			(thermal_bridge_width 0.5)
			(island_removal_mode 0)
		)
		(polygon
			(pts
				(xy 189.62116 -43.63212) (xy 189.62116 -42.15892) (xy 190.41618 -42.15892) (xy 190.41618 -43.63212)
			)
		)
	)
	(zone
		(layer "F.Cu")
		(hatch none 0.5)
		(connect_pads
			(clearance 0)
		)
		(min_thickness 0.25)
		(keepout
			(tracks not_allowed)
			(vias allowed)
			(pads allowed)
			(copperpour not_allowed)
			(footprints allowed)
		)
		(placement
			(enabled no)
			(sheetname "")
		)
		(fill
			(thermal_gap 0.5)
			(thermal_bridge_width 0.5)
			(island_removal_mode 0)
		)
		(polygon
			(pts
				(xy 84.329016 -182.043832) (xy 84.329016 -181.08295) (xy 84.0867 -181.08295) (xy 84.0867 -182.043832)
			)
		)
	)
	(zone
		(layer "F.Cu")
		(hatch none 0.5)
		(connect_pads
			(clearance 0)
		)
		(min_thickness 0.25)
		(keepout
			(tracks allowed)
			(vias allowed)
			(pads allowed)
			(copperpour allowed)
			(footprints allowed)
		)
		(placement
			(enabled no)
			(sheetname "")
		)
		(fill
			(thermal_gap 0.5)
			(thermal_bridge_width 0.5)
			(island_removal_mode 0)
		)
		(polygon
			(pts
				(xy 374.343422 -379.479302) (xy 374.343422 -378.47524) (xy 375.739914 -378.47524) (xy 375.739914 -379.479302)
			)
		)
	)
	(zone
		(layer "F.Cu")
		(hatch none 0.5)
		(connect_pads
			(clearance 0)
		)
		(min_thickness 0.25)
		(keepout
			(tracks not_allowed)
			(vias allowed)
			(pads allowed)
			(copperpour not_allowed)
			(footprints allowed)
		)
		(placement
			(enabled no)
			(sheetname "")
		)
		(fill
			(thermal_gap 0.5)
			(thermal_bridge_width 0.5)
			(island_removal_mode 0)
		)
		(polygon
			(pts
				(arc
					(start 298.89196 -66.060828)
					(mid 293.00297 -60.171838)
					(end 287.11398 -66.060828)
				)
				(arc
					(start 287.11398 -74.760836)
					(mid 293.00297 -80.649826)
					(end 298.89196 -74.760836)
				)
			)
		)
	)
	(zone
		(layer "F.Cu")
		(hatch none 0.5)
		(connect_pads
			(clearance 0)
		)
		(min_thickness 0.25)
		(keepout
			(tracks allowed)
			(vias allowed)
			(pads allowed)
			(copperpour allowed)
			(footprints not_allowed)
		)
		(placement
			(enabled no)
			(sheetname "")
		)
		(fill
			(thermal_gap 0.5)
			(thermal_bridge_width 0.5)
			(island_removal_mode 0)
		)
		(polygon
			(pts
				(arc
					(start 321.270122 -258.890008)
					(mid 317.770002 -262.390128)
					(end 314.269882 -258.890008)
				)
				(arc
					(start 314.269882 -258.890008)
					(mid 317.770002 -255.389888)
					(end 321.270122 -258.890008)
				)
			)
		)
	)
	(zone
		(layer "F.Cu")
		(hatch none 0.5)
		(connect_pads
			(clearance 0)
		)
		(min_thickness 0.25)
		(keepout
			(tracks allowed)
			(vias allowed)
			(pads allowed)
			(copperpour allowed)
			(footprints allowed)
		)
		(placement
			(enabled no)
			(sheetname "")
		)
		(fill
			(thermal_gap 0.5)
			(thermal_bridge_width 0.5)
			(island_removal_mode 0)
		)
		(polygon
			(pts
				(xy 378.10948 6.86816) (xy 378.10948 8.89254) (xy 380.33452 8.89254) (xy 380.33452 6.86816)
			)
		)
	)
	(zone
		(layer "F.Cu")
		(hatch none 0.5)
		(connect_pads
			(clearance 0)
		)
		(min_thickness 0.25)
		(keepout
			(tracks allowed)
			(vias allowed)
			(pads allowed)
			(copperpour allowed)
			(footprints allowed)
		)
		(placement
			(enabled no)
			(sheetname "")
		)
		(fill
			(thermal_gap 0.5)
			(thermal_bridge_width 0.5)
			(island_removal_mode 0)
		)
		(polygon
			(pts
				(xy 339.420454 -320.468498) (xy 339.420454 -322.373498) (xy 343.433654 -322.373498) (xy 343.433654 -320.468498)
			)
		)
	)
	(zone
		(layer "F.Cu")
		(hatch none 0.5)
		(connect_pads
			(clearance 0)
		)
		(min_thickness 0.25)
		(keepout
			(tracks allowed)
			(vias allowed)
			(pads allowed)
			(copperpour allowed)
			(footprints allowed)
		)
		(placement
			(enabled no)
			(sheetname "")
		)
		(fill
			(thermal_gap 0.5)
			(thermal_bridge_width 0.5)
			(island_removal_mode 0)
		)
		(polygon
			(pts
				(xy 78.958186 -221.174564) (xy 102.6668 -221.174564) (xy 103.0986 -221.606364) (xy 103.0986 -222.6564)
				(xy 104.0384 -223.5962) (xy 104.0384 -223.8502) (xy 105.8418 -225.6536) (xy 111.0742 -225.6536)
				(xy 112.2426 -224.4852) (xy 112.2426 -221.631764) (xy 112.6998 -221.174564) (xy 135.56742 -221.174564)
				(xy 135.69442 -221.301564) (xy 135.69442 -222.14332) (xy 136.017 -222.4659) (xy 136.017 -222.6818)
				(xy 135.48868 -223.21012) (xy 135.48868 -223.87052) (xy 135.61568 -223.99752) (xy 141.72438 -223.99752)
				(xy 142.57782 -223.14408) (xy 142.57782 -222.25254) (xy 142.3797 -222.05442) (xy 142.3797 -221.33306)
				(xy 142.538196 -221.174564) (xy 144.921986 -221.174564) (xy 146.877786 -223.130364) (xy 146.877786 -224.292922)
				(xy 146.429476 -224.741232) (xy 144.657318 -224.741232) (xy 143.499586 -225.898964) (xy 143.499586 -259.782564)
				(xy 144.794986 -261.077964) (xy 144.794986 -261.230364) (xy 144.617186 -261.408164) (xy 144.464786 -261.408164)
				(xy 143.804386 -262.068564) (xy 143.804386 -292.192964) (xy 145.150586 -293.539164) (xy 147.632166 -293.539164)
				(xy 147.632166 -296.223944) (xy 147.243546 -296.612564) (xy 76.716636 -296.612564) (xy 76.309474 -296.205402)
				(xy 76.309474 -293.666164) (xy 78.958186 -293.666164) (xy 80.405986 -292.218364) (xy 80.405986 -261.992364)
				(xy 79.821786 -261.408164) (xy 79.593186 -261.408164) (xy 79.440786 -261.255764) (xy 79.440786 -260.950964)
				(xy 80.075786 -260.315964) (xy 80.075786 -225.924364) (xy 77.484986 -223.333564) (xy 77.484986 -222.647764)
			)
		)
	)
	(zone
		(layer "F.Cu")
		(hatch none 0.5)
		(connect_pads
			(clearance 0)
		)
		(min_thickness 0.25)
		(keepout
			(tracks allowed)
			(vias allowed)
			(pads allowed)
			(copperpour allowed)
			(footprints not_allowed)
		)
		(placement
			(enabled no)
			(sheetname "")
		)
		(fill
			(thermal_gap 0.5)
			(thermal_bridge_width 0.5)
			(island_removal_mode 0)
		)
		(polygon
			(pts
				(arc
					(start 287.638236 -440.989974)
					(mid 293.550172 -427.59962)
					(end 299.461682 -440.989974)
				)
			)
		)
	)
	(zone
		(layer "F.Cu")
		(hatch none 0.5)
		(connect_pads
			(clearance 0)
		)
		(min_thickness 0.25)
		(keepout
			(tracks not_allowed)
			(vias allowed)
			(pads allowed)
			(copperpour not_allowed)
			(footprints allowed)
		)
		(placement
			(enabled no)
			(sheetname "")
		)
		(fill
			(thermal_gap 0.5)
			(thermal_bridge_width 0.5)
			(island_removal_mode 0)
		)
		(polygon
			(pts
				(arc
					(start 465.024978 -51.289966)
					(mid 466.8901 -49.424844)
					(end 468.754968 -51.289966)
				)
				(arc
					(start 468.754968 -51.289966)
					(mid 466.8901 -53.154834)
					(end 465.024978 -51.289966)
				)
			)
		)
	)
	(zone
		(layer "F.Cu")
		(hatch none 0.5)
		(connect_pads
			(clearance 0)
		)
		(min_thickness 0.25)
		(keepout
			(tracks not_allowed)
			(vias allowed)
			(pads allowed)
			(copperpour not_allowed)
			(footprints allowed)
		)
		(placement
			(enabled no)
			(sheetname "")
		)
		(fill
			(thermal_gap 0.5)
			(thermal_bridge_width 0.5)
			(island_removal_mode 0)
		)
		(polygon
			(pts
				(xy 93.181932 -183.425084) (xy 93.181932 -182.968392) (xy 92.486226 -182.968392) (xy 92.486226 -183.12892)
				(xy 91.927426 -183.12892) (xy 91.927426 -182.72252) (xy 92.486226 -182.72252) (xy 92.486226 -182.942992)
				(xy 93.181932 -182.942992) (xy 93.181932 -182.815992) (xy 92.726256 -182.815992) (xy 92.726256 -182.429404)
				(xy 92.48394 -182.429404) (xy 91.952064 -182.429404) (xy 91.632532 -182.748936) (xy 91.632532 -183.425084)
			)
		)
	)
	(zone
		(layer "F.Cu")
		(hatch none 0.5)
		(connect_pads
			(clearance 0)
		)
		(min_thickness 0.25)
		(keepout
			(tracks allowed)
			(vias allowed)
			(pads allowed)
			(copperpour allowed)
			(footprints allowed)
		)
		(placement
			(enabled no)
			(sheetname "")
		)
		(fill
			(thermal_gap 0.5)
			(thermal_bridge_width 0.5)
			(island_removal_mode 0)
		)
		(polygon
			(pts
				(xy 58.13044 -272.727928) (xy 58.13044 -272.397728) (xy 60.633864 -272.397728) (xy 60.633864 -272.727928)
			)
		)
	)
	(zone
		(layer "F.Cu")
		(hatch none 0.5)
		(connect_pads
			(clearance 0)
		)
		(min_thickness 0.25)
		(keepout
			(tracks not_allowed)
			(vias allowed)
			(pads allowed)
			(copperpour not_allowed)
			(footprints allowed)
		)
		(placement
			(enabled no)
			(sheetname "")
		)
		(fill
			(thermal_gap 0.5)
			(thermal_bridge_width 0.5)
			(island_removal_mode 0)
		)
		(polygon
			(pts
				(xy 350.2279 -161.888678) (xy 350.2279 -161.431986) (xy 349.532194 -161.431986) (xy 349.532194 -161.592514)
				(xy 348.973394 -161.592514) (xy 348.973394 -161.186114) (xy 349.532194 -161.186114) (xy 349.532194 -161.406586)
				(xy 350.2279 -161.406586) (xy 350.2279 -161.279586) (xy 349.772224 -161.279586) (xy 349.772224 -160.892998)
				(xy 349.529908 -160.892998) (xy 348.998032 -160.892998) (xy 348.6785 -161.21253) (xy 348.6785 -161.888678)
			)
		)
	)
	(zone
		(layer "F.Cu")
		(hatch none 0.5)
		(connect_pads
			(clearance 0)
		)
		(min_thickness 0.25)
		(keepout
			(tracks allowed)
			(vias allowed)
			(pads allowed)
			(copperpour allowed)
			(footprints allowed)
		)
		(placement
			(enabled no)
			(sheetname "")
		)
		(fill
			(thermal_gap 0.5)
			(thermal_bridge_width 0.5)
			(island_removal_mode 0)
		)
		(polygon
			(pts
				(xy 398.182846 -417.424616) (xy 398.182846 -416.420554) (xy 399.579338 -416.420554) (xy 399.579338 -417.424616)
			)
		)
	)
	(zone
		(layer "F.Cu")
		(hatch none 0.5)
		(connect_pads
			(clearance 0)
		)
		(min_thickness 0.25)
		(keepout
			(tracks allowed)
			(vias allowed)
			(pads allowed)
			(copperpour allowed)
			(footprints allowed)
		)
		(placement
			(enabled no)
			(sheetname "")
		)
		(fill
			(thermal_gap 0.5)
			(thermal_bridge_width 0.5)
			(island_removal_mode 0)
		)
		(polygon
			(pts
				(xy 333.35976 -399.742406) (xy 335.166208 -399.742406) (xy 335.455006 -399.453608) (xy 335.455006 -396.634462)
				(xy 335.579974 -396.509494) (xy 354.966016 -396.509494) (xy 354.966016 -399.157952) (xy 354.616512 -399.507456)
				(xy 354.616512 -400.78406) (xy 354.781358 -400.948906) (xy 355.371146 -400.948906) (xy 356.851458 -399.468594)
				(xy 356.851458 -396.558008) (xy 354.624132 -394.330682) (xy 335.44129 -394.330682) (xy 334.82661 -393.716002)
				(xy 334.82661 -393.377166) (xy 334.675988 -393.226544) (xy 333.659988 -393.226544) (xy 333.28356 -393.602972)
				(xy 333.28356 -395.697964) (xy 332.405228 -396.576296) (xy 332.405228 -397.642842) (xy 333.296006 -398.53362)
				(xy 333.296006 -399.678652)
			)
		)
	)
	(zone
		(layer "F.Cu")
		(hatch none 0.5)
		(connect_pads
			(clearance 0)
		)
		(min_thickness 0.25)
		(keepout
			(tracks not_allowed)
			(vias allowed)
			(pads allowed)
			(copperpour not_allowed)
			(footprints allowed)
		)
		(placement
			(enabled no)
			(sheetname "")
		)
		(fill
			(thermal_gap 0.5)
			(thermal_bridge_width 0.5)
			(island_removal_mode 0)
		)
		(polygon
			(pts
				(arc
					(start 301.569882 -413.170116)
					(mid 297.56989 -417.170108)
					(end 293.569898 -413.170116)
				)
				(arc
					(start 293.569898 -413.170116)
					(mid 297.56989 -409.170124)
					(end 301.569882 -413.170116)
				)
			)
		)
	)
	(zone
		(layer "F.Cu")
		(hatch none 0.5)
		(connect_pads
			(clearance 0)
		)
		(min_thickness 0.25)
		(keepout
			(tracks allowed)
			(vias allowed)
			(pads allowed)
			(copperpour allowed)
			(footprints not_allowed)
		)
		(placement
			(enabled no)
			(sheetname "")
		)
		(fill
			(thermal_gap 0.5)
			(thermal_bridge_width 0.5)
			(island_removal_mode 0)
		)
		(polygon
			(pts
				(xy 57.954926 -172.315124) (xy 69.656706 -172.315124) (xy 69.656706 -181.315106) (xy 78.016608 -181.315106)
				(xy 78.016608 -186.37504) (xy 104.206802 -186.37504) (xy 104.206802 -181.805072) (xy 112.436656 -181.805072)
				(xy 112.436656 -175.554894) (xy 120.28678 -175.554894) (xy 120.28678 -168.90492) (xy 128.839468 -168.90492)
				(xy 128.839468 -160.245044) (xy 137.196068 -160.245044) (xy 137.196068 -150.80488) (xy 129.09677 -150.80488)
				(xy 129.09677 -151.545036) (xy 120.026684 -151.545036) (xy 120.026684 -161.275014) (xy 111.716058 -161.275014)
				(xy 111.716058 -170.835066) (xy 97.726754 -170.835066) (xy 97.726754 -176.224946) (xy 84.162138 -176.224946)
				(xy 84.162138 -172.995082) (xy 77.252068 -172.995082) (xy 77.252068 -167.239188) (xy 73.078086 -163.314888)
				(xy 57.954926 -163.314888)
			)
		)
	)
	(zone
		(layer "F.Cu")
		(hatch none 0.5)
		(connect_pads
			(clearance 0)
		)
		(min_thickness 0.25)
		(keepout
			(tracks allowed)
			(vias allowed)
			(pads allowed)
			(copperpour allowed)
			(footprints allowed)
		)
		(placement
			(enabled no)
			(sheetname "")
		)
		(fill
			(thermal_gap 0.5)
			(thermal_bridge_width 0.5)
			(island_removal_mode 0)
		)
		(polygon
			(pts
				(xy 120.813068 -345.951556) (xy 120.813068 -345.529662) (xy 120.92813 -345.529662) (xy 120.92813 -345.951556)
			)
		)
	)
	(zone
		(layer "F.Cu")
		(hatch none 0.5)
		(connect_pads
			(clearance 0)
		)
		(min_thickness 0.25)
		(keepout
			(tracks not_allowed)
			(vias allowed)
			(pads allowed)
			(copperpour not_allowed)
			(footprints allowed)
		)
		(placement
			(enabled no)
			(sheetname "")
		)
		(fill
			(thermal_gap 0.5)
			(thermal_bridge_width 0.5)
			(island_removal_mode 0)
		)
		(polygon
			(pts
				(arc
					(start 184.749948 -435.600094)
					(mid 179.749958 -440.600084)
					(end 174.749968 -435.600094)
				)
				(arc
					(start 174.749968 -435.600094)
					(mid 179.749958 -430.600104)
					(end 184.749948 -435.600094)
				)
			)
		)
	)
	(zone
		(layer "F.Cu")
		(hatch none 0.5)
		(connect_pads
			(clearance 0)
		)
		(min_thickness 0.25)
		(keepout
			(tracks allowed)
			(vias allowed)
			(pads allowed)
			(copperpour allowed)
			(footprints allowed)
		)
		(placement
			(enabled no)
			(sheetname "")
		)
		(fill
			(thermal_gap 0.5)
			(thermal_bridge_width 0.5)
			(island_removal_mode 0)
		)
		(polygon
			(pts
				(xy 378.885958 -137.283952) (xy 378.885958 -138.680952) (xy 375.964958 -138.680952) (xy 375.964958 -137.283952)
			)
		)
	)
	(zone
		(layer "F.Cu")
		(hatch none 0.5)
		(connect_pads
			(clearance 0)
		)
		(min_thickness 0.25)
		(keepout
			(tracks allowed)
			(vias allowed)
			(pads allowed)
			(copperpour allowed)
			(footprints allowed)
		)
		(placement
			(enabled no)
			(sheetname "")
		)
		(fill
			(thermal_gap 0.5)
			(thermal_bridge_width 0.5)
			(island_removal_mode 0)
		)
		(polygon
			(pts
				(xy 355.38537 -167.441372) (xy 353.58197 -167.441372) (xy 353.58197 -168.990772) (xy 355.38537 -168.990772)
			)
		)
	)
	(zone
		(layer "F.Cu")
		(hatch none 0.5)
		(connect_pads
			(clearance 0)
		)
		(min_thickness 0.25)
		(keepout
			(tracks not_allowed)
			(vias allowed)
			(pads allowed)
			(copperpour not_allowed)
			(footprints allowed)
		)
		(placement
			(enabled no)
			(sheetname "")
		)
		(fill
			(thermal_gap 0.5)
			(thermal_bridge_width 0.5)
			(island_removal_mode 0)
		)
		(polygon
			(pts
				(xy 358.078024 -168.795954) (xy 358.078024 -167.835072) (xy 357.835708 -167.835072) (xy 357.835708 -168.795954)
			)
		)
	)
	(zone
		(layer "F.Cu")
		(hatch none 0.5)
		(connect_pads
			(clearance 0)
		)
		(min_thickness 0.25)
		(keepout
			(tracks allowed)
			(vias allowed)
			(pads allowed)
			(copperpour allowed)
			(footprints allowed)
		)
		(placement
			(enabled no)
			(sheetname "")
		)
		(fill
			(thermal_gap 0.5)
			(thermal_bridge_width 0.5)
			(island_removal_mode 0)
		)
		(polygon
			(pts
				(xy 411.317694 -214.927688) (xy 411.317694 -214.597488) (xy 413.236664 -214.597488) (xy 413.236664 -214.927688)
			)
		)
	)
	(zone
		(layer "F.Cu")
		(hatch none 0.5)
		(connect_pads
			(clearance 0)
		)
		(min_thickness 0.25)
		(keepout
			(tracks allowed)
			(vias allowed)
			(pads allowed)
			(copperpour allowed)
			(footprints allowed)
		)
		(placement
			(enabled no)
			(sheetname "")
		)
		(fill
			(thermal_gap 0.5)
			(thermal_bridge_width 0.5)
			(island_removal_mode 0)
		)
		(polygon
			(pts
				(xy 68.956428 -409.042616) (xy 68.956428 -408.038554) (xy 70.35292 -408.038554) (xy 70.35292 -409.042616)
			)
		)
	)
	(zone
		(layer "F.Cu")
		(hatch none 0.5)
		(connect_pads
			(clearance 0)
		)
		(min_thickness 0.25)
		(keepout
			(tracks allowed)
			(vias allowed)
			(pads allowed)
			(copperpour allowed)
			(footprints not_allowed)
		)
		(placement
			(enabled no)
			(sheetname "")
		)
		(fill
			(thermal_gap 0.5)
			(thermal_bridge_width 0.5)
			(island_removal_mode 0)
		)
		(polygon
			(pts
				(xy 39.18712 -183.50992) (xy 39.18712 -327.609962) (xy 45.387006 -327.609962) (xy 45.387006 -183.50992)
			)
		)
	)
	(zone
		(layer "F.Cu")
		(hatch none 0.5)
		(connect_pads
			(clearance 0)
		)
		(min_thickness 0.25)
		(keepout
			(tracks allowed)
			(vias allowed)
			(pads allowed)
			(copperpour allowed)
			(footprints allowed)
		)
		(placement
			(enabled no)
			(sheetname "")
		)
		(fill
			(thermal_gap 0.5)
			(thermal_bridge_width 0.5)
			(island_removal_mode 0)
		)
		(polygon
			(pts
				(xy 407.226516 -133.443218) (xy 407.226516 -134.824216) (xy 408.144472 -135.742172) (xy 410.41193 -135.742172)
				(xy 411.062932 -135.09117) (xy 411.062932 -133.655054) (xy 410.655262 -133.247384) (xy 407.42235 -133.247384)
			)
		)
	)
	(zone
		(layer "F.Cu")
		(hatch none 0.5)
		(connect_pads
			(clearance 0)
		)
		(min_thickness 0.25)
		(keepout
			(tracks allowed)
			(vias allowed)
			(pads allowed)
			(copperpour allowed)
			(footprints allowed)
		)
		(placement
			(enabled no)
			(sheetname "")
		)
		(fill
			(thermal_gap 0.5)
			(thermal_bridge_width 0.5)
			(island_removal_mode 0)
		)
		(polygon
			(pts
				(xy 257.36804 -69.18198) (xy 257.36804 -67.87896) (xy 258.14274 -67.87896) (xy 258.14274 -69.18198)
			)
		)
	)
	(zone
		(layer "F.Cu")
		(hatch none 0.5)
		(connect_pads
			(clearance 0)
		)
		(min_thickness 0.25)
		(keepout
			(tracks allowed)
			(vias allowed)
			(pads allowed)
			(copperpour allowed)
			(footprints not_allowed)
		)
		(placement
			(enabled no)
			(sheetname "")
		)
		(fill
			(thermal_gap 0.5)
			(thermal_bridge_width 0.5)
			(island_removal_mode 0)
		)
		(polygon
			(pts
				(arc
					(start 332.769972 -304.790094)
					(mid 329.270106 -308.28996)
					(end 325.769986 -304.790094)
				)
				(arc
					(start 325.769986 -304.790094)
					(mid 329.270106 -301.289974)
					(end 332.769972 -304.790094)
				)
			)
		)
	)
	(zone
		(layer "F.Cu")
		(hatch none 0.5)
		(connect_pads
			(clearance 0)
		)
		(min_thickness 0.25)
		(keepout
			(tracks allowed)
			(vias allowed)
			(pads allowed)
			(copperpour allowed)
			(footprints allowed)
		)
		(placement
			(enabled no)
			(sheetname "")
		)
		(fill
			(thermal_gap 0.5)
			(thermal_bridge_width 0.5)
			(island_removal_mode 0)
		)
		(polygon
			(pts
				(xy 379.803406 -417.424616) (xy 379.803406 -416.420554) (xy 381.199898 -416.420554) (xy 381.199898 -417.424616)
			)
		)
	)
	(zone
		(layer "F.Cu")
		(hatch none 0.5)
		(connect_pads
			(clearance 0)
		)
		(min_thickness 0.25)
		(keepout
			(tracks allowed)
			(vias allowed)
			(pads allowed)
			(copperpour allowed)
			(footprints allowed)
		)
		(placement
			(enabled no)
			(sheetname "")
		)
		(fill
			(thermal_gap 0.5)
			(thermal_bridge_width 0.5)
			(island_removal_mode 0)
		)
		(polygon
			(pts
				(xy 189.392306 -337.79079) (xy 189.392306 -340.58479) (xy 193.100706 -340.58479) (xy 193.100706 -337.79079)
			)
		)
	)
	(zone
		(layer "F.Cu")
		(hatch none 0.5)
		(connect_pads
			(clearance 0)
		)
		(min_thickness 0.25)
		(keepout
			(tracks allowed)
			(vias allowed)
			(pads allowed)
			(copperpour allowed)
			(footprints allowed)
		)
		(placement
			(enabled no)
			(sheetname "")
		)
		(fill
			(thermal_gap 0.5)
			(thermal_bridge_width 0.5)
			(island_removal_mode 0)
		)
		(polygon
			(pts
				(xy 148.8567 -119.52478) (xy 148.8567 -118.7323) (xy 150.27148 -118.7323) (xy 150.27148 -119.52478)
			)
		)
	)
	(zone
		(layer "F.Cu")
		(hatch none 0.5)
		(connect_pads
			(clearance 0)
		)
		(min_thickness 0.25)
		(keepout
			(tracks allowed)
			(vias allowed)
			(pads allowed)
			(copperpour allowed)
			(footprints not_allowed)
		)
		(placement
			(enabled no)
			(sheetname "")
		)
		(fill
			(thermal_gap 0.5)
			(thermal_bridge_width 0.5)
			(island_removal_mode 0)
		)
		(polygon
			(pts
				(xy 177.119026 -327.609962) (xy 177.119026 -183.50992) (xy 170.918886 -183.50992) (xy 170.918886 -327.609962)
			)
		)
	)
	(zone
		(layer "F.Cu")
		(hatch none 0.5)
		(connect_pads
			(clearance 0)
		)
		(min_thickness 0.25)
		(keepout
			(tracks allowed)
			(vias allowed)
			(pads allowed)
			(copperpour allowed)
			(footprints allowed)
		)
		(placement
			(enabled no)
			(sheetname "")
		)
		(fill
			(thermal_gap 0.5)
			(thermal_bridge_width 0.5)
			(island_removal_mode 0)
		)
		(polygon
			(pts
				(xy 189.655958 -44.054776) (xy 191.129158 -44.054776) (xy 191.129158 -44.849796) (xy 189.655958 -44.849796)
			)
		)
	)
	(zone
		(layer "F.Cu")
		(hatch none 0.5)
		(connect_pads
			(clearance 0)
		)
		(min_thickness 0.25)
		(keepout
			(tracks allowed)
			(vias allowed)
			(pads allowed)
			(copperpour allowed)
			(footprints not_allowed)
		)
		(placement
			(enabled no)
			(sheetname "")
		)
		(fill
			(thermal_gap 0.5)
			(thermal_bridge_width 0.5)
			(island_removal_mode 0)
		)
		(polygon
			(pts
				(xy 105.220008 -394.880084) (xy 110.24997 -394.880084) (xy 110.24997 -390.180068) (xy 105.220008 -390.180068)
			)
		)
	)
	(zone
		(layer "F.Cu")
		(hatch none 0.5)
		(connect_pads
			(clearance 0)
		)
		(min_thickness 0.25)
		(keepout
			(tracks not_allowed)
			(vias allowed)
			(pads allowed)
			(copperpour not_allowed)
			(footprints allowed)
		)
		(placement
			(enabled no)
			(sheetname "")
		)
		(fill
			(thermal_gap 0.5)
			(thermal_bridge_width 0.5)
			(island_removal_mode 0)
		)
		(polygon
			(pts
				(arc
					(start 425.981876 -163.314888)
					(mid 422.88206 -166.414704)
					(end 419.78199 -163.314888)
				)
				(arc
					(start 419.78199 -163.314888)
					(mid 422.88206 -160.214818)
					(end 425.981876 -163.314888)
				)
			)
		)
	)
	(zone
		(layer "F.Cu")
		(hatch none 0.5)
		(connect_pads
			(clearance 0)
		)
		(min_thickness 0.25)
		(keepout
			(tracks allowed)
			(vias allowed)
			(pads allowed)
			(copperpour allowed)
			(footprints not_allowed)
		)
		(placement
			(enabled no)
			(sheetname "")
		)
		(fill
			(thermal_gap 0.5)
			(thermal_bridge_width 0.5)
			(island_removal_mode 0)
		)
		(polygon
			(pts
				(xy 163.375086 -183.50992) (xy 163.375086 -327.609962) (xy 169.574972 -327.609962) (xy 169.574972 -183.50992)
			)
		)
	)
	(zone
		(layer "F.Cu")
		(hatch none 0.5)
		(connect_pads
			(clearance 0)
		)
		(min_thickness 0.25)
		(keepout
			(tracks allowed)
			(vias allowed)
			(pads allowed)
			(copperpour allowed)
			(footprints allowed)
		)
		(placement
			(enabled no)
			(sheetname "")
		)
		(fill
			(thermal_gap 0.5)
			(thermal_bridge_width 0.5)
			(island_removal_mode 0)
		)
		(polygon
			(pts
				(xy 60.725812 -298.742608) (xy 60.725812 -299.072808) (xy 58.185812 -299.072808) (xy 58.185812 -298.742608)
			)
		)
	)
	(zone
		(layer "F.Cu")
		(hatch none 0.5)
		(connect_pads
			(clearance 0)
		)
		(min_thickness 0.25)
		(keepout
			(tracks allowed)
			(vias allowed)
			(pads allowed)
			(copperpour allowed)
			(footprints allowed)
		)
		(placement
			(enabled no)
			(sheetname "")
		)
		(fill
			(thermal_gap 0.5)
			(thermal_bridge_width 0.5)
			(island_removal_mode 0)
		)
		(polygon
			(pts
				(xy 401.246086 -417.424616) (xy 401.246086 -416.420554) (xy 402.642578 -416.420554) (xy 402.642578 -417.424616)
			)
		)
	)
	(zone
		(layer "F.Cu")
		(hatch none 0.5)
		(connect_pads
			(clearance 0)
		)
		(min_thickness 0.25)
		(keepout
			(tracks allowed)
			(vias allowed)
			(pads allowed)
			(copperpour allowed)
			(footprints not_allowed)
		)
		(placement
			(enabled no)
			(sheetname "")
		)
		(fill
			(thermal_gap 0.5)
			(thermal_bridge_width 0.5)
			(island_removal_mode 0)
		)
		(polygon
			(pts
				(xy 306.28463 -21.352002) (xy 322.284598 -21.352002) (xy 322.284598 -12.78001) (xy 306.28463 -12.78001)
			)
		)
	)
	(zone
		(layer "F.Cu")
		(hatch none 0.5)
		(connect_pads
			(clearance 0)
		)
		(min_thickness 0.25)
		(keepout
			(tracks allowed)
			(vias allowed)
			(pads allowed)
			(copperpour allowed)
			(footprints allowed)
		)
		(placement
			(enabled no)
			(sheetname "")
		)
		(fill
			(thermal_gap 0.5)
			(thermal_bridge_width 0.5)
			(island_removal_mode 0)
		)
		(polygon
			(pts
				(xy 411.317694 -203.877672) (xy 411.317694 -203.547472) (xy 413.236664 -203.547472) (xy 413.236664 -203.877672)
			)
		)
	)
	(zone
		(layer "F.Cu")
		(hatch none 0.5)
		(connect_pads
			(clearance 0)
		)
		(min_thickness 0.25)
		(keepout
			(tracks not_allowed)
			(vias allowed)
			(pads allowed)
			(copperpour not_allowed)
			(footprints allowed)
		)
		(placement
			(enabled no)
			(sheetname "")
		)
		(fill
			(thermal_gap 0.5)
			(thermal_bridge_width 0.5)
			(island_removal_mode 0)
		)
		(polygon
			(pts
				(arc
					(start 431.803048 -74.767948)
					(mid 426.803058 -79.767938)
					(end 421.803068 -74.767948)
				)
				(arc
					(start 421.803068 -66.06794)
					(mid 426.803058 -61.06795)
					(end 431.803048 -66.06794)
				)
			)
		)
	)
	(zone
		(layer "F.Cu")
		(hatch none 0.5)
		(connect_pads
			(clearance 0)
		)
		(min_thickness 0.25)
		(keepout
			(tracks allowed)
			(vias allowed)
			(pads allowed)
			(copperpour allowed)
			(footprints allowed)
		)
		(placement
			(enabled no)
			(sheetname "")
		)
		(fill
			(thermal_gap 0.5)
			(thermal_bridge_width 0.5)
			(island_removal_mode 0)
		)
		(polygon
			(pts
				(xy 411.317694 -296.192448) (xy 411.317694 -296.522648) (xy 413.236664 -296.522648) (xy 413.236664 -296.192448)
			)
		)
	)
	(zone
		(layer "F.Cu")
		(hatch none 0.5)
		(connect_pads
			(clearance 0)
		)
		(min_thickness 0.25)
		(keepout
			(tracks not_allowed)
			(vias allowed)
			(pads allowed)
			(copperpour not_allowed)
			(footprints allowed)
		)
		(placement
			(enabled no)
			(sheetname "")
		)
		(fill
			(thermal_gap 0.5)
			(thermal_bridge_width 0.5)
			(island_removal_mode 0)
		)
		(polygon
			(pts
				(arc
					(start 225.000058 -290.900104)
					(mid 221.899988 -294.000174)
					(end 218.799918 -290.900104)
				)
				(arc
					(start 218.799918 -290.900104)
					(mid 221.899988 -287.800034)
					(end 225.000058 -290.900104)
				)
			)
		)
	)
	(zone
		(layer "F.Cu")
		(hatch none 0.5)
		(connect_pads
			(clearance 0)
		)
		(min_thickness 0.25)
		(keepout
			(tracks allowed)
			(vias allowed)
			(pads allowed)
			(copperpour allowed)
			(footprints allowed)
		)
		(placement
			(enabled no)
			(sheetname "")
		)
		(fill
			(thermal_gap 0.5)
			(thermal_bridge_width 0.5)
			(island_removal_mode 0)
		)
		(polygon
			(pts
				(xy 378.22124 -0.635) (xy 378.22124 1.17856) (xy 380.17958 1.17856) (xy 380.17958 -0.635)
			)
		)
	)
	(zone
		(layer "F.Cu")
		(hatch none 0.5)
		(connect_pads
			(clearance 0)
		)
		(min_thickness 0.25)
		(keepout
			(tracks allowed)
			(vias allowed)
			(pads allowed)
			(copperpour allowed)
			(footprints allowed)
		)
		(placement
			(enabled no)
			(sheetname "")
		)
		(fill
			(thermal_gap 0.5)
			(thermal_bridge_width 0.5)
			(island_removal_mode 0)
		)
		(polygon
			(pts
				(xy 137.16 -77.75448) (xy 137.16 -74.5236) (xy 139.08786 -74.5236) (xy 139.08786 -77.75448)
			)
		)
	)
	(zone
		(layer "F.Cu")
		(hatch none 0.5)
		(connect_pads
			(clearance 0)
		)
		(min_thickness 0.25)
		(keepout
			(tracks allowed)
			(vias allowed)
			(pads allowed)
			(copperpour allowed)
			(footprints allowed)
		)
		(placement
			(enabled no)
			(sheetname "")
		)
		(fill
			(thermal_gap 0.5)
			(thermal_bridge_width 0.5)
			(island_removal_mode 0)
		)
		(polygon
			(pts
				(xy 417.08197 -384.406902) (xy 417.08197 -383.40284) (xy 418.478462 -383.40284) (xy 418.478462 -384.406902)
			)
		)
	)
	(zone
		(layer "F.Cu")
		(hatch none 0.5)
		(connect_pads
			(clearance 0)
		)
		(min_thickness 0.25)
		(keepout
			(tracks allowed)
			(vias allowed)
			(pads allowed)
			(copperpour allowed)
			(footprints allowed)
		)
		(placement
			(enabled no)
			(sheetname "")
		)
		(fill
			(thermal_gap 0.5)
			(thermal_bridge_width 0.5)
			(island_removal_mode 0)
		)
		(polygon
			(pts
				(xy 306.070508 -214.077804) (xy 306.070508 -213.747604) (xy 308.610508 -213.747604) (xy 308.610508 -214.077804)
			)
		)
	)
	(zone
		(layer "F.Cu")
		(hatch none 0.5)
		(connect_pads
			(clearance 0)
		)
		(min_thickness 0.25)
		(keepout
			(tracks not_allowed)
			(vias allowed)
			(pads allowed)
			(copperpour not_allowed)
			(footprints allowed)
		)
		(placement
			(enabled no)
			(sheetname "")
		)
		(fill
			(thermal_gap 0.5)
			(thermal_bridge_width 0.5)
			(island_removal_mode 0)
		)
		(polygon
			(pts
				(arc
					(start 208.399888 -22.29993)
					(mid 203.399898 -27.29992)
					(end 198.399908 -22.29993)
				)
				(arc
					(start 198.399908 -22.29993)
					(mid 203.399898 -17.29994)
					(end 208.399888 -22.29993)
				)
			)
		)
	)
	(zone
		(layer "F.Cu")
		(hatch none 0.5)
		(connect_pads
			(clearance 0)
		)
		(min_thickness 0.25)
		(keepout
			(tracks allowed)
			(vias allowed)
			(pads allowed)
			(copperpour allowed)
			(footprints allowed)
		)
		(placement
			(enabled no)
			(sheetname "")
		)
		(fill
			(thermal_gap 0.5)
			(thermal_bridge_width 0.5)
			(island_removal_mode 0)
		)
		(polygon
			(pts
				(xy 308.66588 -278.342344) (xy 308.66588 -278.672544) (xy 306.12588 -278.672544) (xy 306.12588 -278.342344)
			)
		)
	)
	(zone
		(layer "F.Cu")
		(hatch none 0.5)
		(connect_pads
			(clearance 0)
		)
		(min_thickness 0.25)
		(keepout
			(tracks not_allowed)
			(vias allowed)
			(pads allowed)
			(copperpour not_allowed)
			(footprints allowed)
		)
		(placement
			(enabled no)
			(sheetname "")
		)
		(fill
			(thermal_gap 0.5)
			(thermal_bridge_width 0.5)
			(island_removal_mode 0)
		)
		(polygon
			(pts
				(arc
					(start 438.53989 -399.029936)
					(mid 435.440074 -402.129752)
					(end 432.340004 -399.029936)
				)
				(arc
					(start 432.340004 -399.029936)
					(mid 435.440074 -395.929866)
					(end 438.53989 -399.029936)
				)
			)
		)
	)
	(zone
		(layer "F.Cu")
		(hatch none 0.5)
		(connect_pads
			(clearance 0)
		)
		(min_thickness 0.25)
		(keepout
			(tracks allowed)
			(vias allowed)
			(pads allowed)
			(copperpour allowed)
			(footprints allowed)
		)
		(placement
			(enabled no)
			(sheetname "")
		)
		(fill
			(thermal_gap 0.5)
			(thermal_bridge_width 0.5)
			(island_removal_mode 0)
		)
		(polygon
			(pts
				(xy 147.35048 -195.6054) (xy 147.35048 -195.0974) (xy 147.54606 -195.0974) (xy 147.54606 -195.6054)
			)
		)
	)
	(zone
		(layer "F.Cu")
		(hatch none 0.5)
		(connect_pads
			(clearance 0)
		)
		(min_thickness 0.25)
		(keepout
			(tracks allowed)
			(vias allowed)
			(pads allowed)
			(copperpour allowed)
			(footprints allowed)
		)
		(placement
			(enabled no)
			(sheetname "")
		)
		(fill
			(thermal_gap 0.5)
			(thermal_bridge_width 0.5)
			(island_removal_mode 0)
		)
		(polygon
			(pts
				(xy 422.827958 -358.136952) (xy 416.731958 -358.136952) (xy 415.588958 -359.279952) (xy 415.588958 -363.724952)
				(xy 417.366958 -365.502952) (xy 421.557958 -365.502952) (xy 422.162732 -364.897924) (xy 422.895268 -364.897924)
				(xy 424.683936 -364.897924) (xy 426.779436 -366.993424) (xy 427.725078 -366.993424) (xy 427.954948 -366.763554)
				(xy 427.954948 -366.009428) (xy 425.74464 -363.79912) (xy 423.081958 -363.79912) (xy 423.081958 -358.390952)
			)
		)
	)
	(zone
		(layer "F.Cu")
		(hatch none 0.5)
		(connect_pads
			(clearance 0)
		)
		(min_thickness 0.25)
		(keepout
			(tracks not_allowed)
			(vias allowed)
			(pads allowed)
			(copperpour not_allowed)
			(footprints allowed)
		)
		(placement
			(enabled no)
			(sheetname "")
		)
		(fill
			(thermal_gap 0.5)
			(thermal_bridge_width 0.5)
			(island_removal_mode 0)
		)
		(polygon
			(pts
				(arc
					(start 175.250094 -376.489976)
					(mid 177.500026 -374.240044)
					(end 179.749958 -376.489976)
				)
				(arc
					(start 179.749958 -376.489976)
					(mid 177.500026 -378.739908)
					(end 175.250094 -376.489976)
				)
			)
		)
	)
	(zone
		(layer "F.Cu")
		(hatch none 0.5)
		(connect_pads
			(clearance 0)
		)
		(min_thickness 0.25)
		(keepout
			(tracks not_allowed)
			(vias allowed)
			(pads allowed)
			(copperpour not_allowed)
			(footprints allowed)
		)
		(placement
			(enabled no)
			(sheetname "")
		)
		(fill
			(thermal_gap 0.5)
			(thermal_bridge_width 0.5)
			(island_removal_mode 0)
		)
		(polygon
			(pts
				(xy 437.608218 -12.04468) (xy 437.725566 -12.04468) (xy 437.776366 -11.99388) (xy 437.776366 -10.54608)
				(xy 437.725566 -10.49528) (xy 437.608218 -10.49528) (xy 437.557418 -10.54608) (xy 437.557418 -11.99388)
			)
		)
	)
	(zone
		(layer "F.Cu")
		(hatch none 0.5)
		(connect_pads
			(clearance 0)
		)
		(min_thickness 0.25)
		(keepout
			(tracks not_allowed)
			(vias allowed)
			(pads allowed)
			(copperpour not_allowed)
			(footprints allowed)
		)
		(placement
			(enabled no)
			(sheetname "")
		)
		(fill
			(thermal_gap 0.5)
			(thermal_bridge_width 0.5)
			(island_removal_mode 0)
		)
		(polygon
			(pts
				(arc
					(start 199.22109 -351.825052)
					(mid 201.086212 -349.95993)
					(end 202.95108 -351.825052)
				)
				(arc
					(start 202.95108 -351.825052)
					(mid 201.086212 -353.68992)
					(end 199.22109 -351.825052)
				)
			)
		)
	)
	(zone
		(layer "F.Cu")
		(hatch none 0.5)
		(connect_pads
			(clearance 0)
		)
		(min_thickness 0.25)
		(keepout
			(tracks not_allowed)
			(vias allowed)
			(pads allowed)
			(copperpour not_allowed)
			(footprints allowed)
		)
		(placement
			(enabled no)
			(sheetname "")
		)
		(fill
			(thermal_gap 0.5)
			(thermal_bridge_width 0.5)
			(island_removal_mode 0)
		)
		(polygon
			(pts
				(xy 190.7032 -14.374622) (xy 190.820548 -14.374622) (xy 190.871348 -14.323822) (xy 190.871348 -12.876022)
				(xy 190.820548 -12.825222) (xy 190.7032 -12.825222) (xy 190.6524 -12.876022) (xy 190.6524 -14.323822)
			)
		)
	)
	(zone
		(layer "F.Cu")
		(hatch none 0.5)
		(connect_pads
			(clearance 0)
		)
		(min_thickness 0.25)
		(keepout
			(tracks allowed)
			(vias allowed)
			(pads allowed)
			(copperpour allowed)
			(footprints allowed)
		)
		(placement
			(enabled no)
			(sheetname "")
		)
		(fill
			(thermal_gap 0.5)
			(thermal_bridge_width 0.5)
			(island_removal_mode 0)
		)
		(polygon
			(pts
				(xy 163.377626 -203.877926) (xy 163.377626 -203.547726) (xy 165.296596 -203.547726) (xy 165.296596 -203.877926)
			)
		)
	)
	(zone
		(layer "F.Cu")
		(hatch none 0.5)
		(connect_pads
			(clearance 0)
		)
		(min_thickness 0.25)
		(keepout
			(tracks allowed)
			(vias allowed)
			(pads allowed)
			(copperpour allowed)
			(footprints allowed)
		)
		(placement
			(enabled no)
			(sheetname "")
		)
		(fill
			(thermal_gap 0.5)
			(thermal_bridge_width 0.5)
			(island_removal_mode 0)
		)
		(polygon
			(pts
				(xy 155.7274 -193.09842) (xy 155.7274 -192.59042) (xy 155.92298 -192.59042) (xy 155.92298 -193.09842)
			)
		)
	)
	(zone
		(layer "F.Cu")
		(hatch none 0.5)
		(connect_pads
			(clearance 0)
		)
		(min_thickness 0.25)
		(keepout
			(tracks not_allowed)
			(vias allowed)
			(pads allowed)
			(copperpour not_allowed)
			(footprints allowed)
		)
		(placement
			(enabled no)
			(sheetname "")
		)
		(fill
			(thermal_gap 0.5)
			(thermal_bridge_width 0.5)
			(island_removal_mode 0)
		)
		(polygon
			(pts
				(xy 416.301682 -87.286084) (xy 437.30164 -87.286084) (xy 437.30164 -60.007246) (xy 416.301682 -60.007246)
			)
		)
	)
	(zone
		(layer "F.Cu")
		(hatch none 0.5)
		(connect_pads
			(clearance 0)
		)
		(min_thickness 0.25)
		(keepout
			(tracks not_allowed)
			(vias allowed)
			(pads allowed)
			(copperpour not_allowed)
			(footprints allowed)
		)
		(placement
			(enabled no)
			(sheetname "")
		)
		(fill
			(thermal_gap 0.5)
			(thermal_bridge_width 0.5)
			(island_removal_mode 0)
		)
		(polygon
			(pts
				(arc
					(start 387.657086 -173.315122)
					(mid 389.522208 -171.45)
					(end 391.387076 -173.315122)
				)
				(arc
					(start 391.387076 -173.315122)
					(mid 389.522208 -175.17999)
					(end 387.657086 -173.315122)
				)
			)
		)
	)
	(zone
		(layer "F.Cu")
		(hatch none 0.5)
		(connect_pads
			(clearance 0)
		)
		(min_thickness 0.25)
		(keepout
			(tracks not_allowed)
			(vias allowed)
			(pads allowed)
			(copperpour not_allowed)
			(footprints allowed)
		)
		(placement
			(enabled no)
			(sheetname "")
		)
		(fill
			(thermal_gap 0.5)
			(thermal_bridge_width 0.5)
			(island_removal_mode 0)
		)
		(polygon
			(pts
				(arc
					(start 64.382904 -45.449998)
					(mid 65.98285 -47.049944)
					(end 64.382904 -48.64989)
				)
				(arc
					(start 62.782958 -48.64989)
					(mid 61.183012 -47.049944)
					(end 62.782958 -45.449998)
				)
			)
		)
	)
	(zone
		(layer "F.Cu")
		(hatch none 0.5)
		(connect_pads
			(clearance 0)
		)
		(min_thickness 0.25)
		(keepout
			(tracks allowed)
			(vias allowed)
			(pads allowed)
			(copperpour allowed)
			(footprints allowed)
		)
		(placement
			(enabled no)
			(sheetname "")
		)
		(fill
			(thermal_gap 0.5)
			(thermal_bridge_width 0.5)
			(island_removal_mode 0)
		)
		(polygon
			(pts
				(xy 97.905062 -335.534508) (xy 96.101662 -335.534508) (xy 96.101662 -337.083908) (xy 97.905062 -337.083908)
			)
		)
	)
	(zone
		(layer "F.Cu")
		(hatch none 0.5)
		(connect_pads
			(clearance 0)
		)
		(min_thickness 0.25)
		(keepout
			(tracks not_allowed)
			(vias allowed)
			(pads allowed)
			(copperpour not_allowed)
			(footprints allowed)
		)
		(placement
			(enabled no)
			(sheetname "")
		)
		(fill
			(thermal_gap 0.5)
			(thermal_bridge_width 0.5)
			(island_removal_mode 0)
		)
		(polygon
			(pts
				(arc
					(start 295.195498 -384.869944)
					(mid 286.944562 -384.869944)
					(end 295.195498 -384.869944)
				)
			)
		)
	)
	(zone
		(layer "F.Cu")
		(hatch none 0.5)
		(connect_pads
			(clearance 0)
		)
		(min_thickness 0.25)
		(keepout
			(tracks not_allowed)
			(vias allowed)
			(pads allowed)
			(copperpour not_allowed)
			(footprints allowed)
		)
		(placement
			(enabled no)
			(sheetname "")
		)
		(fill
			(thermal_gap 0.5)
			(thermal_bridge_width 0.5)
			(island_removal_mode 0)
		)
		(polygon
			(pts
				(arc
					(start 73.080118 -258.890008)
					(mid 69.830188 -262.139938)
					(end 66.580004 -258.890008)
				)
				(arc
					(start 66.580004 -258.890008)
					(mid 69.830188 -255.639824)
					(end 73.080118 -258.890008)
				)
			)
		)
	)
	(zone
		(layer "F.Cu")
		(hatch none 0.5)
		(connect_pads
			(clearance 0)
		)
		(min_thickness 0.25)
		(keepout
			(tracks allowed)
			(vias allowed)
			(pads allowed)
			(copperpour allowed)
			(footprints not_allowed)
		)
		(placement
			(enabled no)
			(sheetname "")
		)
		(fill
			(thermal_gap 0.5)
			(thermal_bridge_width 0.5)
			(island_removal_mode 0)
		)
		(polygon
			(pts
				(xy 460.259938 -404.850092) (xy 467.300056 -404.850092) (xy 467.300056 -394.24991) (xy 460.259938 -394.24991)
			)
		)
	)
	(zone
		(layer "F.Cu")
		(hatch none 0.5)
		(connect_pads
			(clearance 0)
		)
		(min_thickness 0.25)
		(keepout
			(tracks allowed)
			(vias allowed)
			(pads allowed)
			(copperpour allowed)
			(footprints allowed)
		)
		(placement
			(enabled no)
			(sheetname "")
		)
		(fill
			(thermal_gap 0.5)
			(thermal_bridge_width 0.5)
			(island_removal_mode 0)
		)
		(polygon
			(pts
				(xy 55.995062 -347.226382) (xy 54.191662 -347.226382) (xy 54.191662 -348.775782) (xy 55.995062 -348.775782)
			)
		)
	)
	(zone
		(layer "F.Cu")
		(hatch none 0.5)
		(connect_pads
			(clearance 0)
		)
		(min_thickness 0.25)
		(keepout
			(tracks allowed)
			(vias allowed)
			(pads allowed)
			(copperpour allowed)
			(footprints allowed)
		)
		(placement
			(enabled no)
			(sheetname "")
		)
		(fill
			(thermal_gap 0.5)
			(thermal_bridge_width 0.5)
			(island_removal_mode 0)
		)
		(polygon
			(pts
				(xy 306.070508 -270.177768) (xy 306.070508 -269.847568) (xy 308.610508 -269.847568) (xy 308.610508 -270.177768)
			)
		)
	)
	(zone
		(layer "F.Cu")
		(hatch none 0.5)
		(connect_pads
			(clearance 0)
		)
		(min_thickness 0.25)
		(keepout
			(tracks allowed)
			(vias allowed)
			(pads allowed)
			(copperpour allowed)
			(footprints not_allowed)
		)
		(placement
			(enabled no)
			(sheetname "")
		)
		(fill
			(thermal_gap 0.5)
			(thermal_bridge_width 0.5)
			(island_removal_mode 0)
		)
		(polygon
			(pts
				(arc
					(start 195.22694 -12.392406)
					(mid 194.737934 -12.047721)
					(end 194.327018 -11.61288)
				)
				(xy 194.327018 -17.23009) (xy 126.455932 -17.23009)
				(arc
					(start 126.455932 -11.640058)
					(mid 126.057429 -12.055173)
					(end 125.586998 -12.386564)
				)
				(xy 125.586998 -18.130012) (xy 195.22694 -18.130012)
			)
		)
	)
	(zone
		(layer "F.Cu")
		(hatch none 0.5)
		(connect_pads
			(clearance 0)
		)
		(min_thickness 0.25)
		(keepout
			(tracks not_allowed)
			(vias allowed)
			(pads allowed)
			(copperpour not_allowed)
			(footprints allowed)
		)
		(placement
			(enabled no)
			(sheetname "")
		)
		(fill
			(thermal_gap 0.5)
			(thermal_bridge_width 0.5)
			(island_removal_mode 0)
		)
		(polygon
			(pts
				(arc
					(start 102.633018 -47.049944)
					(mid 100.383086 -49.299876)
					(end 98.1329 -47.049944)
				)
				(arc
					(start 98.1329 -47.049944)
					(mid 100.383086 -44.799758)
					(end 102.633018 -47.049944)
				)
			)
		)
	)
	(zone
		(layer "F.Cu")
		(hatch none 0.5)
		(connect_pads
			(clearance 0)
		)
		(min_thickness 0.25)
		(keepout
			(tracks allowed)
			(vias allowed)
			(pads allowed)
			(copperpour allowed)
			(footprints allowed)
		)
		(placement
			(enabled no)
			(sheetname "")
		)
		(fill
			(thermal_gap 0.5)
			(thermal_bridge_width 0.5)
			(island_removal_mode 0)
		)
		(polygon
			(pts
				(xy 163.377626 -246.377968) (xy 163.377626 -246.047768) (xy 165.296596 -246.047768) (xy 165.296596 -246.377968)
			)
		)
	)
	(zone
		(layer "F.Cu")
		(hatch none 0.5)
		(connect_pads
			(clearance 0)
		)
		(min_thickness 0.25)
		(keepout
			(tracks not_allowed)
			(vias allowed)
			(pads allowed)
			(copperpour not_allowed)
			(footprints allowed)
		)
		(placement
			(enabled no)
			(sheetname "")
		)
		(fill
			(thermal_gap 0.5)
			(thermal_bridge_width 0.5)
			(island_removal_mode 0)
		)
		(polygon
			(pts
				(xy 168.362122 -87.286084) (xy 189.36208 -87.286084) (xy 189.36208 -59.981084) (xy 168.362122 -59.979052)
			)
		)
	)
	(zone
		(layer "F.Cu")
		(hatch none 0.5)
		(connect_pads
			(clearance 0)
		)
		(min_thickness 0.25)
		(keepout
			(tracks allowed)
			(vias allowed)
			(pads allowed)
			(copperpour allowed)
			(footprints allowed)
		)
		(placement
			(enabled no)
			(sheetname "")
		)
		(fill
			(thermal_gap 0.5)
			(thermal_bridge_width 0.5)
			(island_removal_mode 0)
		)
		(polygon
			(pts
				(xy 308.66588 -297.042332) (xy 308.66588 -297.372532) (xy 306.12588 -297.372532) (xy 306.12588 -297.042332)
			)
		)
	)
	(zone
		(layer "F.Cu")
		(hatch none 0.5)
		(connect_pads
			(clearance 0)
		)
		(min_thickness 0.25)
		(keepout
			(tracks not_allowed)
			(vias allowed)
			(pads allowed)
			(copperpour not_allowed)
			(footprints allowed)
		)
		(placement
			(enabled no)
			(sheetname "")
		)
		(fill
			(thermal_gap 0.5)
			(thermal_bridge_width 0.5)
			(island_removal_mode 0)
		)
		(polygon
			(pts
				(arc
					(start 176.186084 -351.825052)
					(mid 173.086014 -354.925122)
					(end 169.985944 -351.825052)
				)
				(arc
					(start 169.985944 -351.825052)
					(mid 173.086014 -348.724982)
					(end 176.186084 -351.825052)
				)
			)
		)
	)
	(zone
		(layer "F.Cu")
		(hatch none 0.5)
		(connect_pads
			(clearance 0)
		)
		(min_thickness 0.25)
		(keepout
			(tracks allowed)
			(vias allowed)
			(pads allowed)
			(copperpour allowed)
			(footprints allowed)
		)
		(placement
			(enabled no)
			(sheetname "")
		)
		(fill
			(thermal_gap 0.5)
			(thermal_bridge_width 0.5)
			(island_removal_mode 0)
		)
		(polygon
			(pts
				(xy 58.766202 -182.149242) (xy 58.766202 -181.509162) (xy 59.41568 -181.509162) (xy 59.41568 -182.149242)
			)
		)
	)
	(zone
		(layer "F.Cu")
		(hatch none 0.5)
		(connect_pads
			(clearance 0)
		)
		(min_thickness 0.25)
		(keepout
			(tracks allowed)
			(vias allowed)
			(pads allowed)
			(copperpour allowed)
			(footprints not_allowed)
		)
		(placement
			(enabled no)
			(sheetname "")
		)
		(fill
			(thermal_gap 0.5)
			(thermal_bridge_width 0.5)
			(island_removal_mode 0)
		)
		(polygon
			(pts
				(xy 446.571878 -347.134942) (xy 438.742074 -347.134942) (xy 438.742074 -356.735126) (xy 443.986158 -356.735126)
				(xy 446.571878 -354.145088)
			)
		)
	)
	(zone
		(layer "F.Cu")
		(hatch none 0.5)
		(connect_pads
			(clearance 0)
		)
		(min_thickness 0.25)
		(keepout
			(tracks allowed)
			(vias allowed)
			(pads allowed)
			(copperpour allowed)
			(footprints allowed)
		)
		(placement
			(enabled no)
			(sheetname "")
		)
		(fill
			(thermal_gap 0.5)
			(thermal_bridge_width 0.5)
			(island_removal_mode 0)
		)
		(polygon
			(pts
				(xy 411.317694 -310.127904) (xy 411.317694 -309.797704) (xy 413.236664 -309.797704) (xy 413.236664 -310.127904)
			)
		)
	)
	(zone
		(layer "F.Cu")
		(hatch none 0.5)
		(connect_pads
			(clearance 0)
		)
		(min_thickness 0.25)
		(keepout
			(tracks allowed)
			(vias allowed)
			(pads allowed)
			(copperpour allowed)
			(footprints not_allowed)
		)
		(placement
			(enabled no)
			(sheetname "")
		)
		(fill
			(thermal_gap 0.5)
			(thermal_bridge_width 0.5)
			(island_removal_mode 0)
		)
		(polygon
			(pts
				(xy 199.959976 -389.40994) (xy 201.959972 -389.40994) (xy 201.959972 -386.409946) (xy 199.959976 -386.409946)
			)
		)
	)
	(zone
		(layer "F.Cu")
		(hatch none 0.5)
		(connect_pads
			(clearance 0)
		)
		(min_thickness 0.25)
		(keepout
			(tracks allowed)
			(vias allowed)
			(pads allowed)
			(copperpour allowed)
			(footprints allowed)
		)
		(placement
			(enabled no)
			(sheetname "")
		)
		(fill
			(thermal_gap 0.5)
			(thermal_bridge_width 0.5)
			(island_removal_mode 0)
		)
		(polygon
			(pts
				(xy 337.443826 -335.694274) (xy 335.640426 -335.694274) (xy 335.640426 -337.243674) (xy 337.443826 -337.243674)
			)
		)
	)
	(zone
		(layer "F.Cu")
		(hatch none 0.5)
		(connect_pads
			(clearance 0)
		)
		(min_thickness 0.25)
		(keepout
			(tracks allowed)
			(vias allowed)
			(pads allowed)
			(copperpour allowed)
			(footprints not_allowed)
		)
		(placement
			(enabled no)
			(sheetname "")
		)
		(fill
			(thermal_gap 0.5)
			(thermal_bridge_width 0.5)
			(island_removal_mode 0)
		)
		(polygon
			(pts
				(arc
					(start 392.700002 -73.859898)
					(mid 377.700032 -58.859928)
					(end 392.700002 -43.859958)
				)
				(xy 392.700002 -49.509934) (xy 397.20012 -49.509934)
				(arc
					(start 397.20012 -43.859958)
					(mid 412.20009 -58.859928)
					(end 397.20012 -73.859898)
				)
				(xy 397.20012 -68.209922) (xy 392.700002 -68.209922)
			)
		)
	)
	(zone
		(layer "F.Cu")
		(hatch none 0.5)
		(connect_pads
			(clearance 0)
		)
		(min_thickness 0.25)
		(keepout
			(tracks allowed)
			(vias allowed)
			(pads allowed)
			(copperpour allowed)
			(footprints not_allowed)
		)
		(placement
			(enabled no)
			(sheetname "")
		)
		(fill
			(thermal_gap 0.5)
			(thermal_bridge_width 0.5)
			(island_removal_mode 0)
		)
		(polygon
			(pts
				(arc
					(start 326.47001 -304.790094)
					(mid 329.270106 -301.989998)
					(end 332.069948 -304.790094)
				)
				(arc
					(start 332.069948 -304.790094)
					(mid 329.270106 -307.589936)
					(end 326.47001 -304.790094)
				)
			)
		)
	)
	(zone
		(layer "F.Cu")
		(hatch none 0.5)
		(connect_pads
			(clearance 0)
		)
		(min_thickness 0.25)
		(keepout
			(tracks allowed)
			(vias allowed)
			(pads allowed)
			(copperpour allowed)
			(footprints not_allowed)
		)
		(placement
			(enabled no)
			(sheetname "")
		)
		(fill
			(thermal_gap 0.5)
			(thermal_bridge_width 0.5)
			(island_removal_mode 0)
		)
		(polygon
			(pts
				(xy 416.301682 -81.77403) (xy 303.502568 -81.77403)
				(arc
					(start 303.502568 -71.125842)
					(mid 305.088012 -70.733861)
					(end 306.621434 -70.171818)
				)
				(arc
					(start 306.621434 -70.171818)
					(mid 312.043809 -75.182921)
					(end 319.200022 -77.0001)
				)
				(xy 319.200022 -67.540124) (xy 322.600066 -67.540124)
				(arc
					(start 322.600066 -77.0001)
					(mid 327.492604 -76.179682)
					(end 331.849984 -73.808336)
				)
				(arc
					(start 331.849984 -73.808336)
					(mid 336.20736 -76.179691)
					(end 341.099902 -77.0001)
				)
				(xy 341.099902 -67.540124) (xy 344.499946 -67.540124)
				(arc
					(start 344.499946 -77.0001)
					(mid 357.204434 -69.975006)
					(end 358.008936 -55.47995)
				)
				(xy 364.65002 -55.47995)
				(arc
					(start 364.65002 -38.312598)
					(mid 373.682835 -36.771196)
					(end 380.133606 -30.263084)
				)
				(arc
					(start 380.133606 -30.263084)
					(mid 388.893788 -22.611713)
					(end 380.75616 -14.301216)
				)
				(arc
					(start 380.75616 -14.301216)
					(mid 380.434586 -13.532876)
					(end 380.070868 -12.783566)
				)
				(arc
					(start 469.799924 -12.78001)
					(mid 470.507029 -13.072903)
					(end 470.799922 -13.780008)
				)
				(arc
					(start 470.799922 -17.008602)
					(mid 457.845774 -18.345481)
					(end 463.320384 -30.161992)
				)
				(arc
					(start 463.320384 -30.161992)
					(mid 462.497053 -31.093055)
					(end 462.19999 -32.29991)
				)
				(arc
					(start 462.19999 -33.90011)
					(mid 464.799934 -36.500054)
					(end 467.399878 -33.90011)
				)
				(arc
					(start 467.399878 -32.29991)
					(mid 467.102806 -31.093059)
					(end 466.279484 -30.161992)
				)
				(arc
					(start 466.279484 -30.161992)
					(mid 468.754375 -29.254283)
					(end 470.799922 -27.591512)
				)
				(arc
					(start 470.799922 -77.671676)
					(mid 470.723821 -78.054261)
					(end 470.50706 -78.378558)
				)
				(arc
					(start 468.178642 -80.70723)
					(mid 467.777931 -81.203873)
					(end 467.491318 -81.77403)
				)
				(xy 437.302402 -81.77403) (xy 437.304688 -60.007246) (xy 416.30473 -60.00496)
			)
		)
	)
	(zone
		(layer "F.Cu")
		(hatch none 0.5)
		(connect_pads
			(clearance 0)
		)
		(min_thickness 0.25)
		(keepout
			(tracks allowed)
			(vias allowed)
			(pads allowed)
			(copperpour allowed)
			(footprints allowed)
		)
		(placement
			(enabled no)
			(sheetname "")
		)
		(fill
			(thermal_gap 0.5)
			(thermal_bridge_width 0.5)
			(island_removal_mode 0)
		)
		(polygon
			(pts
				(xy 302.14062 -148.89988) (xy 302.14062 -146.970496) (xy 302.809148 -146.970496) (xy 302.809148 -148.89988)
			)
		)
	)
	(zone
		(layer "F.Cu")
		(hatch none 0.5)
		(connect_pads
			(clearance 0)
		)
		(min_thickness 0.25)
		(keepout
			(tracks allowed)
			(vias allowed)
			(pads allowed)
			(copperpour allowed)
			(footprints allowed)
		)
		(placement
			(enabled no)
			(sheetname "")
		)
		(fill
			(thermal_gap 0.5)
			(thermal_bridge_width 0.5)
			(island_removal_mode 0)
		)
		(polygon
			(pts
				(xy 42.44213 -375.687844) (xy 43.446192 -375.687844) (xy 43.446192 -377.084336) (xy 42.44213 -377.084336)
			)
		)
	)
	(zone
		(layer "F.Cu")
		(hatch none 0.5)
		(connect_pads
			(clearance 0)
		)
		(min_thickness 0.25)
		(keepout
			(tracks allowed)
			(vias allowed)
			(pads allowed)
			(copperpour allowed)
			(footprints allowed)
		)
		(placement
			(enabled no)
			(sheetname "")
		)
		(fill
			(thermal_gap 0.5)
			(thermal_bridge_width 0.5)
			(island_removal_mode 0)
		)
		(polygon
			(pts
				(xy 450.889116 -403.156674) (xy 450.889116 -399.908014) (xy 454.137776 -399.908014) (xy 454.137776 -403.156674)
			)
		)
	)
	(zone
		(layer "F.Cu")
		(hatch none 0.5)
		(connect_pads
			(clearance 0)
		)
		(min_thickness 0.25)
		(keepout
			(tracks not_allowed)
			(vias allowed)
			(pads allowed)
			(copperpour not_allowed)
			(footprints allowed)
		)
		(placement
			(enabled no)
			(sheetname "")
		)
		(fill
			(thermal_gap 0.5)
			(thermal_bridge_width 0.5)
			(island_removal_mode 0)
		)
		(polygon
			(pts
				(xy 67.908932 -334.250792) (xy 67.908932 -334.707484) (xy 68.604638 -334.707484) (xy 68.604638 -334.546956)
				(xy 69.163438 -334.546956) (xy 69.163438 -334.953356) (xy 68.604638 -334.953356) (xy 68.604638 -334.732884)
				(xy 67.908932 -334.732884) (xy 67.908932 -334.859884) (xy 68.364608 -334.859884) (xy 68.364608 -335.246472)
				(xy 68.606924 -335.246472) (xy 69.1388 -335.246472) (xy 69.458332 -334.92694) (xy 69.458332 -334.250792)
			)
		)
	)
	(zone
		(layer "F.Cu")
		(hatch none 0.5)
		(connect_pads
			(clearance 0)
		)
		(min_thickness 0.25)
		(keepout
			(tracks allowed)
			(vias allowed)
			(pads allowed)
			(copperpour allowed)
			(footprints not_allowed)
		)
		(placement
			(enabled no)
			(sheetname "")
		)
		(fill
			(thermal_gap 0.5)
			(thermal_bridge_width 0.5)
			(island_removal_mode 0)
		)
		(polygon
			(pts
				(arc
					(start 467.300056 -165.967664)
					(mid 463.097432 -168.330706)
					(end 458.300074 -167.84955)
				)
				(xy 458.300074 -182.060088) (xy 467.300056 -182.060088)
			)
		)
	)
	(zone
		(layer "F.Cu")
		(hatch none 0.5)
		(connect_pads
			(clearance 0)
		)
		(min_thickness 0.25)
		(keepout
			(tracks allowed)
			(vias allowed)
			(pads allowed)
			(copperpour allowed)
			(footprints allowed)
		)
		(placement
			(enabled no)
			(sheetname "")
		)
		(fill
			(thermal_gap 0.5)
			(thermal_bridge_width 0.5)
			(island_removal_mode 0)
		)
		(polygon
			(pts
				(xy 396.040356 -189.785752) (xy 396.040356 -191.690752) (xy 400.053556 -191.690752) (xy 400.053556 -189.785752)
			)
		)
	)
	(zone
		(layer "F.Cu")
		(hatch none 0.5)
		(connect_pads
			(clearance 0)
		)
		(min_thickness 0.25)
		(keepout
			(tracks allowed)
			(vias allowed)
			(pads allowed)
			(copperpour allowed)
			(footprints allowed)
		)
		(placement
			(enabled no)
			(sheetname "")
		)
		(fill
			(thermal_gap 0.5)
			(thermal_bridge_width 0.5)
			(island_removal_mode 0)
		)
		(polygon
			(pts
				(xy 197.792086 -339.221826) (xy 197.792086 -338.681568) (xy 199.788526 -338.681568) (xy 199.788526 -339.221826)
			)
		)
	)
	(zone
		(layer "F.Cu")
		(hatch none 0.5)
		(connect_pads
			(clearance 0)
		)
		(min_thickness 0.25)
		(keepout
			(tracks allowed)
			(vias allowed)
			(pads allowed)
			(copperpour allowed)
			(footprints allowed)
		)
		(placement
			(enabled no)
			(sheetname "")
		)
		(fill
			(thermal_gap 0.5)
			(thermal_bridge_width 0.5)
			(island_removal_mode 0)
		)
		(polygon
			(pts
				(xy 58.13044 -271.027906) (xy 58.13044 -270.697706) (xy 60.67044 -270.697706) (xy 60.67044 -271.027906)
			)
		)
	)
	(zone
		(layer "F.Cu")
		(hatch none 0.5)
		(connect_pads
			(clearance 0)
		)
		(min_thickness 0.25)
		(keepout
			(tracks allowed)
			(vias allowed)
			(pads allowed)
			(copperpour allowed)
			(footprints allowed)
		)
		(placement
			(enabled no)
			(sheetname "")
		)
		(fill
			(thermal_gap 0.5)
			(thermal_bridge_width 0.5)
			(island_removal_mode 0)
		)
		(polygon
			(pts
				(xy 69.215762 -379.216412) (xy 70.219824 -379.216412) (xy 70.219824 -380.612904) (xy 69.215762 -380.612904)
			)
		)
	)
	(zone
		(layer "F.Cu")
		(hatch none 0.5)
		(connect_pads
			(clearance 0)
		)
		(min_thickness 0.25)
		(keepout
			(tracks allowed)
			(vias allowed)
			(pads allowed)
			(copperpour allowed)
			(footprints allowed)
		)
		(placement
			(enabled no)
			(sheetname "")
		)
		(fill
			(thermal_gap 0.5)
			(thermal_bridge_width 0.5)
			(island_removal_mode 0)
		)
		(polygon
			(pts
				(xy 15.730728 -412.589472) (xy 17.849088 -412.589472) (xy 17.849088 -414.663128) (xy 17.358868 -415.153348)
				(xy 15.324074 -415.153348) (xy 15.196058 -415.025332) (xy 15.196058 -413.124142)
			)
		)
	)
	(zone
		(layer "F.Cu")
		(hatch none 0.5)
		(connect_pads
			(clearance 0)
		)
		(min_thickness 0.25)
		(keepout
			(tracks allowed)
			(vias allowed)
			(pads allowed)
			(copperpour allowed)
			(footprints allowed)
		)
		(placement
			(enabled no)
			(sheetname "")
		)
		(fill
			(thermal_gap 0.5)
			(thermal_bridge_width 0.5)
			(island_removal_mode 0)
		)
		(polygon
			(pts
				(xy 349.46209 -417.424616) (xy 349.46209 -416.420554) (xy 350.858582 -416.420554) (xy 350.858582 -417.424616)
			)
		)
	)
	(zone
		(layer "F.Cu")
		(hatch none 0.5)
		(connect_pads
			(clearance 0)
		)
		(min_thickness 0.25)
		(keepout
			(tracks allowed)
			(vias allowed)
			(pads allowed)
			(copperpour allowed)
			(footprints not_allowed)
		)
		(placement
			(enabled no)
			(sheetname "")
		)
		(fill
			(thermal_gap 0.5)
			(thermal_bridge_width 0.5)
			(island_removal_mode 0)
		)
		(polygon
			(pts
				(xy 178.08321 -35.924998) (xy 178.08321 -58.17489) (xy 168.63314 -58.17489) (xy 168.63314 -35.924998)
			)
		)
	)
	(zone
		(layer "F.Cu")
		(hatch none 0.5)
		(connect_pads
			(clearance 0)
		)
		(min_thickness 0.25)
		(keepout
			(tracks not_allowed)
			(vias allowed)
			(pads allowed)
			(copperpour not_allowed)
			(footprints allowed)
		)
		(placement
			(enabled no)
			(sheetname "")
		)
		(fill
			(thermal_gap 0.5)
			(thermal_bridge_width 0.5)
			(island_removal_mode 0)
		)
		(polygon
			(pts
				(xy 168.758108 -55.910226) (xy 170.358308 -55.910226) (xy 170.409108 -55.859426) (xy 170.409108 -55.7403)
				(xy 170.358308 -55.6895) (xy 168.758108 -55.6895) (xy 168.707308 -55.7403) (xy 168.707308 -55.859426)
			)
		)
	)
	(zone
		(layer "F.Cu")
		(hatch none 0.5)
		(connect_pads
			(clearance 0)
		)
		(min_thickness 0.25)
		(keepout
			(tracks allowed)
			(vias allowed)
			(pads allowed)
			(copperpour allowed)
			(footprints allowed)
		)
		(placement
			(enabled no)
			(sheetname "")
		)
		(fill
			(thermal_gap 0.5)
			(thermal_bridge_width 0.5)
			(island_removal_mode 0)
		)
		(polygon
			(pts
				(xy 60.725812 -308.092602) (xy 60.725812 -308.422802) (xy 58.185812 -308.422802) (xy 58.185812 -308.092602)
			)
		)
	)
	(zone
		(layer "F.Cu")
		(hatch none 0.5)
		(connect_pads
			(clearance 0)
		)
		(min_thickness 0.25)
		(keepout
			(tracks allowed)
			(vias allowed)
			(pads allowed)
			(copperpour allowed)
			(footprints allowed)
		)
		(placement
			(enabled no)
			(sheetname "")
		)
		(fill
			(thermal_gap 0.5)
			(thermal_bridge_width 0.5)
			(island_removal_mode 0)
		)
		(polygon
			(pts
				(xy 93.982286 -376.024902) (xy 93.982286 -375.02084) (xy 95.378778 -375.02084) (xy 95.378778 -376.024902)
			)
		)
	)
	(zone
		(layer "F.Cu")
		(hatch none 0.5)
		(connect_pads
			(clearance 0)
		)
		(min_thickness 0.25)
		(keepout
			(tracks allowed)
			(vias allowed)
			(pads allowed)
			(copperpour allowed)
			(footprints allowed)
		)
		(placement
			(enabled no)
			(sheetname "")
		)
		(fill
			(thermal_gap 0.5)
			(thermal_bridge_width 0.5)
			(island_removal_mode 0)
		)
		(polygon
			(pts
				(xy 413.67837 -379.479302) (xy 413.67837 -378.47524) (xy 415.074862 -378.47524) (xy 415.074862 -379.479302)
			)
		)
	)
	(zone
		(layer "F.Cu")
		(hatch none 0.5)
		(connect_pads
			(clearance 0)
		)
		(min_thickness 0.25)
		(keepout
			(tracks allowed)
			(vias allowed)
			(pads allowed)
			(copperpour allowed)
			(footprints allowed)
		)
		(placement
			(enabled no)
			(sheetname "")
		)
		(fill
			(thermal_gap 0.5)
			(thermal_bridge_width 0.5)
			(island_removal_mode 0)
		)
		(polygon
			(pts
				(xy 411.574996 -284.627828) (xy 411.574996 -284.297628) (xy 413.236664 -284.297628) (xy 413.236664 -284.627828)
			)
		)
	)
	(zone
		(layer "F.Cu")
		(hatch none 0.5)
		(connect_pads
			(clearance 0)
		)
		(min_thickness 0.25)
		(keepout
			(tracks allowed)
			(vias allowed)
			(pads allowed)
			(copperpour allowed)
			(footprints not_allowed)
		)
		(placement
			(enabled no)
			(sheetname "")
		)
		(fill
			(thermal_gap 0.5)
			(thermal_bridge_width 0.5)
			(island_removal_mode 0)
		)
		(polygon
			(pts
				(xy 377.312428 -440.8805)
				(arc
					(start 377.312428 -430.28743)
					(mid 371.320852 -427.560222)
					(end 365.312452 -430.250092)
				)
				(arc
					(start 365.312452 -440.850528)
					(mid 365.375034 -440.920621)
					(end 365.438436 -440.989974)
				)
				(xy 377.213114 -440.989974)
			)
		)
	)
	(zone
		(layer "F.Cu")
		(hatch none 0.5)
		(connect_pads
			(clearance 0)
		)
		(min_thickness 0.25)
		(keepout
			(tracks not_allowed)
			(vias allowed)
			(pads allowed)
			(copperpour not_allowed)
			(footprints allowed)
		)
		(placement
			(enabled no)
			(sheetname "")
		)
		(fill
			(thermal_gap 0.5)
			(thermal_bridge_width 0.5)
			(island_removal_mode 0)
		)
		(polygon
			(pts
				(arc
					(start 171.220892 -351.825052)
					(mid 173.086014 -349.95993)
					(end 174.950882 -351.825052)
				)
				(arc
					(start 174.950882 -351.825052)
					(mid 173.086014 -353.68992)
					(end 171.220892 -351.825052)
				)
			)
		)
	)
	(zone
		(layer "F.Cu")
		(hatch none 0.5)
		(connect_pads
			(clearance 0)
		)
		(min_thickness 0.25)
		(keepout
			(tracks allowed)
			(vias allowed)
			(pads allowed)
			(copperpour allowed)
			(footprints allowed)
		)
		(placement
			(enabled no)
			(sheetname "")
		)
		(fill
			(thermal_gap 0.5)
			(thermal_bridge_width 0.5)
			(island_removal_mode 0)
		)
		(polygon
			(pts
				(xy 153.853134 -193.167) (xy 153.853134 -192.659) (xy 154.048714 -192.659) (xy 154.048714 -193.167)
			)
		)
	)
	(zone
		(layer "F.Cu")
		(hatch none 0.5)
		(connect_pads
			(clearance 0)
		)
		(min_thickness 0.25)
		(keepout
			(tracks not_allowed)
			(vias allowed)
			(pads allowed)
			(copperpour not_allowed)
			(footprints allowed)
		)
		(placement
			(enabled no)
			(sheetname "")
		)
		(fill
			(thermal_gap 0.5)
			(thermal_bridge_width 0.5)
			(island_removal_mode 0)
		)
		(polygon
			(pts
				(arc
					(start 321.270122 -258.890008)
					(mid 317.770002 -262.390128)
					(end 314.269882 -258.890008)
				)
				(arc
					(start 314.269882 -258.890008)
					(mid 317.770002 -255.389888)
					(end 321.270122 -258.890008)
				)
			)
		)
	)
	(zone
		(layer "F.Cu")
		(hatch none 0.5)
		(connect_pads
			(clearance 0)
		)
		(min_thickness 0.25)
		(keepout
			(tracks allowed)
			(vias allowed)
			(pads allowed)
			(copperpour allowed)
			(footprints not_allowed)
		)
		(placement
			(enabled no)
			(sheetname "")
		)
		(fill
			(thermal_gap 0.5)
			(thermal_bridge_width 0.5)
			(island_removal_mode 0)
		)
		(polygon
			(pts
				(arc
					(start 110.850934 -340.315042)
					(mid 112.716056 -338.44992)
					(end 114.580924 -340.315042)
				)
				(arc
					(start 114.580924 -340.315042)
					(mid 112.716056 -342.17991)
					(end 110.850934 -340.315042)
				)
			)
		)
	)
	(zone
		(layer "F.Cu")
		(hatch none 0.5)
		(connect_pads
			(clearance 0)
		)
		(min_thickness 0.25)
		(keepout
			(tracks not_allowed)
			(vias allowed)
			(pads allowed)
			(copperpour not_allowed)
			(footprints allowed)
		)
		(placement
			(enabled no)
			(sheetname "")
		)
		(fill
			(thermal_gap 0.5)
			(thermal_bridge_width 0.5)
			(island_removal_mode 0)
		)
		(polygon
			(pts
				(xy 297.863514 -345.967812) (xy 297.863514 -346.424504) (xy 298.55922 -346.424504) (xy 298.55922 -346.263976)
				(xy 299.11802 -346.263976) (xy 299.11802 -346.670376) (xy 298.55922 -346.670376) (xy 298.55922 -346.449904)
				(xy 297.863514 -346.449904) (xy 297.863514 -346.576904) (xy 298.31919 -346.576904) (xy 298.31919 -346.963492)
				(xy 298.561506 -346.963492) (xy 299.093382 -346.963492) (xy 299.412914 -346.64396) (xy 299.412914 -345.967812)
			)
		)
	)
	(zone
		(layer "F.Cu")
		(hatch none 0.5)
		(connect_pads
			(clearance 0)
		)
		(min_thickness 0.25)
		(keepout
			(tracks allowed)
			(vias allowed)
			(pads allowed)
			(copperpour allowed)
			(footprints allowed)
		)
		(placement
			(enabled no)
			(sheetname "")
		)
		(fill
			(thermal_gap 0.5)
			(thermal_bridge_width 0.5)
			(island_removal_mode 0)
		)
		(polygon
			(pts
				(xy 60.725812 -274.09267) (xy 60.725812 -274.42287) (xy 58.185812 -274.42287) (xy 58.185812 -274.09267)
			)
		)
	)
	(zone
		(layer "F.Cu")
		(hatch none 0.5)
		(connect_pads
			(clearance 0)
		)
		(min_thickness 0.25)
		(keepout
			(tracks allowed)
			(vias allowed)
			(pads allowed)
			(copperpour allowed)
			(footprints allowed)
		)
		(placement
			(enabled no)
			(sheetname "")
		)
		(fill
			(thermal_gap 0.5)
			(thermal_bridge_width 0.5)
			(island_removal_mode 0)
		)
		(polygon
			(pts
				(xy 293.571422 -347.221556) (xy 291.768022 -347.221556) (xy 291.768022 -348.770956) (xy 293.571422 -348.770956)
			)
		)
	)
	(zone
		(layer "F.Cu")
		(hatch none 0.5)
		(connect_pads
			(clearance 0)
		)
		(min_thickness 0.25)
		(keepout
			(tracks allowed)
			(vias allowed)
			(pads allowed)
			(copperpour allowed)
			(footprints allowed)
		)
		(placement
			(enabled no)
			(sheetname "")
		)
		(fill
			(thermal_gap 0.5)
			(thermal_bridge_width 0.5)
			(island_removal_mode 0)
		)
		(polygon
			(pts
				(xy 387.957822 -379.479302) (xy 387.957822 -378.47524) (xy 389.354314 -378.47524) (xy 389.354314 -379.479302)
			)
		)
	)
	(zone
		(layer "F.Cu")
		(hatch none 0.5)
		(connect_pads
			(clearance 0)
		)
		(min_thickness 0.25)
		(keepout
			(tracks allowed)
			(vias allowed)
			(pads allowed)
			(copperpour allowed)
			(footprints allowed)
		)
		(placement
			(enabled no)
			(sheetname "")
		)
		(fill
			(thermal_gap 0.5)
			(thermal_bridge_width 0.5)
			(island_removal_mode 0)
		)
		(polygon
			(pts
				(xy 163.634928 -284.628082) (xy 163.634928 -284.297882) (xy 165.296596 -284.297882) (xy 165.296596 -284.628082)
			)
		)
	)
	(zone
		(layer "F.Cu")
		(hatch none 0.5)
		(connect_pads
			(clearance 0)
		)
		(min_thickness 0.25)
		(keepout
			(tracks allowed)
			(vias allowed)
			(pads allowed)
			(copperpour allowed)
			(footprints allowed)
		)
		(placement
			(enabled no)
			(sheetname "")
		)
		(fill
			(thermal_gap 0.5)
			(thermal_bridge_width 0.5)
			(island_removal_mode 0)
		)
		(polygon
			(pts
				(xy 76.494386 -223.333564) (xy 77.484986 -223.333564) (xy 80.075786 -225.924364) (xy 80.075786 -260.315964)
				(xy 79.440786 -260.950964) (xy 79.440786 -261.255764) (xy 79.593186 -261.408164) (xy 79.821786 -261.408164)
				(xy 80.405986 -261.992364) (xy 80.405986 -292.218364) (xy 78.958186 -293.666164) (xy 76.309474 -293.666164)
				(xy 75.955906 -293.312596) (xy 75.955906 -226.666044) (xy 76.494386 -226.127564)
			)
		)
	)
	(zone
		(layer "F.Cu")
		(hatch none 0.5)
		(connect_pads
			(clearance 0)
		)
		(min_thickness 0.25)
		(keepout
			(tracks allowed)
			(vias allowed)
			(pads allowed)
			(copperpour allowed)
			(footprints allowed)
		)
		(placement
			(enabled no)
			(sheetname "")
		)
		(fill
			(thermal_gap 0.5)
			(thermal_bridge_width 0.5)
			(island_removal_mode 0)
		)
		(polygon
			(pts
				(xy 314.45327 -320.47561) (xy 314.45327 -322.38061) (xy 318.46647 -322.38061) (xy 318.46647 -320.47561)
			)
		)
	)
	(zone
		(layer "F.Cu")
		(hatch none 0.5)
		(connect_pads
			(clearance 0)
		)
		(min_thickness 0.25)
		(keepout
			(tracks allowed)
			(vias allowed)
			(pads allowed)
			(copperpour allowed)
			(footprints allowed)
		)
		(placement
			(enabled no)
			(sheetname "")
		)
		(fill
			(thermal_gap 0.5)
			(thermal_bridge_width 0.5)
			(island_removal_mode 0)
		)
		(polygon
			(pts
				(xy 404.309326 -417.424616) (xy 404.309326 -416.420554) (xy 405.705818 -416.420554) (xy 405.705818 -417.424616)
			)
		)
	)
	(zone
		(layer "F.Cu")
		(hatch none 0.5)
		(connect_pads
			(clearance 0)
		)
		(min_thickness 0.25)
		(keepout
			(tracks allowed)
			(vias allowed)
			(pads allowed)
			(copperpour allowed)
			(footprints allowed)
		)
		(placement
			(enabled no)
			(sheetname "")
		)
		(fill
			(thermal_gap 0.5)
			(thermal_bridge_width 0.5)
			(island_removal_mode 0)
		)
		(polygon
			(pts
				(xy 285.265622 -347.221556) (xy 283.462222 -347.221556) (xy 283.462222 -348.770956) (xy 285.265622 -348.770956)
			)
		)
	)
	(zone
		(layer "F.Cu")
		(hatch none 0.5)
		(connect_pads
			(clearance 0)
		)
		(min_thickness 0.25)
		(keepout
			(tracks not_allowed)
			(vias allowed)
			(pads allowed)
			(copperpour not_allowed)
			(footprints allowed)
		)
		(placement
			(enabled no)
			(sheetname "")
		)
		(fill
			(thermal_gap 0.5)
			(thermal_bridge_width 0.5)
			(island_removal_mode 0)
		)
		(polygon
			(pts
				(arc
					(start 7.53999 -347.700092)
					(mid 10.340086 -344.899996)
					(end 13.139928 -347.700092)
				)
				(arc
					(start 13.139928 -347.700092)
					(mid 10.340086 -350.499934)
					(end 7.53999 -347.700092)
				)
			)
		)
	)
	(zone
		(layer "F.Cu")
		(hatch none 0.5)
		(connect_pads
			(clearance 0)
		)
		(min_thickness 0.25)
		(keepout
			(tracks not_allowed)
			(vias allowed)
			(pads allowed)
			(copperpour not_allowed)
			(footprints allowed)
		)
		(placement
			(enabled no)
			(sheetname "")
		)
		(fill
			(thermal_gap 0.5)
			(thermal_bridge_width 0.5)
			(island_removal_mode 0)
		)
		(polygon
			(pts
				(arc
					(start 52.525676 -418.77742)
					(mid 51.857656 -418.77742)
					(end 52.525676 -418.77742)
				)
			)
		)
	)
	(zone
		(layer "F.Cu")
		(hatch none 0.5)
		(connect_pads
			(clearance 0)
		)
		(min_thickness 0.25)
		(keepout
			(tracks allowed)
			(vias allowed)
			(pads allowed)
			(copperpour allowed)
			(footprints not_allowed)
		)
		(placement
			(enabled no)
			(sheetname "")
		)
		(fill
			(thermal_gap 0.5)
			(thermal_bridge_width 0.5)
			(island_removal_mode 0)
		)
		(polygon
			(pts
				(xy 326.650096 -403.260052) (xy 331.680058 -403.260052) (xy 331.680058 -398.560036) (xy 326.650096 -398.560036)
			)
		)
	)
	(zone
		(layer "F.Cu")
		(hatch none 0.5)
		(connect_pads
			(clearance 0)
		)
		(min_thickness 0.25)
		(keepout
			(tracks allowed)
			(vias allowed)
			(pads allowed)
			(copperpour allowed)
			(footprints not_allowed)
		)
		(placement
			(enabled no)
			(sheetname "")
		)
		(fill
			(thermal_gap 0.5)
			(thermal_bridge_width 0.5)
			(island_removal_mode 0)
		)
		(polygon
			(pts
				(xy 70.63994 -394.880084) (xy 75.669902 -394.880084) (xy 75.669902 -390.180068) (xy 70.63994 -390.180068)
			)
		)
	)
	(zone
		(layer "F.Cu")
		(hatch none 0.5)
		(connect_pads
			(clearance 0)
		)
		(min_thickness 0.25)
		(keepout
			(tracks not_allowed)
			(vias allowed)
			(pads allowed)
			(copperpour not_allowed)
			(footprints allowed)
		)
		(placement
			(enabled no)
			(sheetname "")
		)
		(fill
			(thermal_gap 0.5)
			(thermal_bridge_width 0.5)
			(island_removal_mode 0)
		)
		(polygon
			(pts
				(xy 92.953332 -334.280002) (xy 92.953332 -334.736694) (xy 93.649038 -334.736694) (xy 93.649038 -334.576166)
				(xy 94.207838 -334.576166) (xy 94.207838 -334.982566) (xy 93.649038 -334.982566) (xy 93.649038 -334.762094)
				(xy 92.953332 -334.762094) (xy 92.953332 -334.889094) (xy 93.409008 -334.889094) (xy 93.409008 -335.275682)
				(xy 93.651324 -335.275682) (xy 94.1832 -335.275682) (xy 94.502732 -334.95615) (xy 94.502732 -334.280002)
			)
		)
	)
	(zone
		(layer "F.Cu")
		(hatch none 0.5)
		(connect_pads
			(clearance 0)
		)
		(min_thickness 0.25)
		(keepout
			(tracks allowed)
			(vias allowed)
			(pads allowed)
			(copperpour allowed)
			(footprints not_allowed)
		)
		(placement
			(enabled no)
			(sheetname "")
		)
		(fill
			(thermal_gap 0.5)
			(thermal_bridge_width 0.5)
			(island_removal_mode 0)
		)
		(polygon
			(pts
				(arc
					(start 201.900028 -51.999896)
					(mid 204.650086 -49.249838)
					(end 207.39989 -51.999896)
				)
				(arc
					(start 207.39989 -51.999896)
					(mid 204.650086 -54.7497)
					(end 201.900028 -51.999896)
				)
			)
		)
	)
	(zone
		(layer "F.Cu")
		(hatch none 0.5)
		(connect_pads
			(clearance 0)
		)
		(min_thickness 0.25)
		(keepout
			(tracks allowed)
			(vias allowed)
			(pads allowed)
			(copperpour allowed)
			(footprints allowed)
		)
		(placement
			(enabled no)
			(sheetname "")
		)
		(fill
			(thermal_gap 0.5)
			(thermal_bridge_width 0.5)
			(island_removal_mode 0)
		)
		(polygon
			(pts
				(xy 411.317694 -205.577694) (xy 411.317694 -205.247494) (xy 413.236664 -205.247494) (xy 413.236664 -205.577694)
			)
		)
	)
	(zone
		(layer "F.Cu")
		(hatch none 0.5)
		(connect_pads
			(clearance 0)
		)
		(min_thickness 0.25)
		(keepout
			(tracks allowed)
			(vias allowed)
			(pads allowed)
			(copperpour allowed)
			(footprints allowed)
		)
		(placement
			(enabled no)
			(sheetname "")
		)
		(fill
			(thermal_gap 0.5)
			(thermal_bridge_width 0.5)
			(island_removal_mode 0)
		)
		(polygon
			(pts
				(xy 93.487494 -320.473324) (xy 93.487494 -322.378324) (xy 97.500694 -322.378324) (xy 97.500694 -320.473324)
			)
		)
	)
	(zone
		(layer "F.Cu")
		(hatch none 0.5)
		(connect_pads
			(clearance 0)
		)
		(min_thickness 0.25)
		(keepout
			(tracks allowed)
			(vias allowed)
			(pads allowed)
			(copperpour allowed)
			(footprints not_allowed)
		)
		(placement
			(enabled no)
			(sheetname "")
		)
		(fill
			(thermal_gap 0.5)
			(thermal_bridge_width 0.5)
			(island_removal_mode 0)
		)
		(polygon
			(pts
				(arc
					(start 30.599888 -36.999926)
					(mid 37.315393 -38.587145)
					(end 42.60977 -43.012868)
				)
				(arc
					(start 49.110392 -43.012868)
					(mid 54.484298 -35.075469)
					(end 63.56731 -32.01289)
				)
				(xy 168.283128 -32.01289) (xy 168.283128 -35.012884) (xy 178.283108 -35.012884) (xy 178.283108 -59.980068)
				(xy 189.36462 -59.981084) (xy 189.362334 -81.77403) (xy 222.861124 -81.77403) (xy 222.861124 -92.700094)
				(xy 249.001026 -92.700094) (xy 249.001026 -81.77403) (xy 282.502356 -81.77403) (xy 282.504642 -59.99099)
				(arc
					(start 286.13862 -59.991244)
					(mid 285.810014 -58.203949)
					(end 285.699962 -56.390032)
				)
				(xy 294.014906 -56.390032) (xy 294.014906 -51.410108)
				(arc
					(start 289.184842 -51.410108)
					(mid 281.399996 -55.139737)
					(end 273.61515 -51.410108)
				)
				(arc
					(start 273.61515 -51.410108)
					(mid 264.24991 -54.375199)
					(end 271.867884 -48.173132)
				)
				(arc
					(start 271.867884 -48.173132)
					(mid 271.606587 -47.172395)
					(end 271.450054 -46.150022)
				)
				(xy 269.871952 -46.150022)
				(arc
					(start 269.871952 -43.949874)
					(mid 262.081691 -38.767813)
					(end 261.986522 -29.41193)
				)
				(arc
					(start 261.986522 -29.41193)
					(mid 260.821865 -28.678777)
					(end 259.80009 -27.756866)
				)
				(arc
					(start 259.80009 -34.120074)
					(mid 258.921412 -36.24139)
					(end 256.800096 -37.120068)
				)
				(xy 242.149884 -37.120068) (xy 242.149884 -41.924986) (xy 238.300006 -41.924986) (xy 238.300006 -64.52489)
				(xy 230.300022 -64.52489) (xy 230.300022 -46.999906) (xy 226.44989 -46.999906) (xy 226.44989 -41.999916)
				(xy 230.300022 -41.999916) (xy 230.300022 -37.120068)
				(arc
					(start 225.300032 -37.120068)
					(mid 223.178716 -36.24139)
					(end 222.300038 -34.120074)
				)
				(arc
					(start 222.300038 -13.780008)
					(mid 222.007145 -13.072903)
					(end 221.30004 -12.78001)
				)
				(arc
					(start 196.701918 -12.78001)
					(mid 195.939394 -12.681485)
					(end 195.22694 -12.392406)
				)
				(xy 195.22694 -18.130012) (xy 125.586998 -18.130012)
				(arc
					(start 125.586998 -12.386564)
					(mid 124.870167 -12.679944)
					(end 124.102114 -12.78001)
				)
				(arc
					(start 1.999996 -12.78001)
					(mid 1.292891 -13.072903)
					(end 0.999998 -13.780008)
				)
				(arc
					(start 0.999998 -17.008602)
					(mid 11.804633 -15.903618)
					(end 13.753592 -26.588212)
				)
				(arc
					(start 13.753592 -26.588212)
					(mid 14.985714 -26.62545)
					(end 16.062198 -27.226006)
				)
				(arc
					(start 17.234916 -28.314396)
					(mid 17.37169 -31.988628)
					(end 13.697458 -32.125666)
				)
				(arc
					(start 12.52474 -31.037276)
					(mid 11.841868 -29.997326)
					(end 11.720322 -28.75915)
				)
				(arc
					(start 11.720322 -28.75915)
					(mid 6.133824 -30.253097)
					(end 0.999998 -27.591512)
				)
				(arc
					(start 0.999998 -37.930074)
					(mid 3.558673 -37.234292)
					(end 6.199886 -36.999926)
				)
				(xy 6.199886 -46.459902) (xy 9.59993 -46.459902)
				(arc
					(start 9.59993 -36.999926)
					(mid 14.225394 -37.730889)
					(end 18.400014 -39.8526)
				)
				(arc
					(start 18.400014 -39.8526)
					(mid 22.574658 -37.730961)
					(end 27.200098 -36.999926)
				)
				(xy 27.200098 -46.459902) (xy 30.599888 -46.459902)
			)
		)
	)
	(zone
		(layer "F.Cu")
		(hatch none 0.5)
		(connect_pads
			(clearance 0)
		)
		(min_thickness 0.25)
		(keepout
			(tracks allowed)
			(vias allowed)
			(pads allowed)
			(copperpour allowed)
			(footprints allowed)
		)
		(placement
			(enabled no)
			(sheetname "")
		)
		(fill
			(thermal_gap 0.5)
			(thermal_bridge_width 0.5)
			(island_removal_mode 0)
		)
		(polygon
			(pts
				(xy 207.784954 -372.727474) (xy 208.206848 -372.727474) (xy 208.206848 -372.842536) (xy 207.784954 -372.842536)
			)
		)
	)
	(zone
		(layer "F.Cu")
		(hatch none 0.5)
		(connect_pads
			(clearance 0)
		)
		(min_thickness 0.25)
		(keepout
			(tracks not_allowed)
			(vias allowed)
			(pads allowed)
			(copperpour not_allowed)
			(footprints allowed)
		)
		(placement
			(enabled no)
			(sheetname "")
		)
		(fill
			(thermal_gap 0.5)
			(thermal_bridge_width 0.5)
			(island_removal_mode 0)
		)
		(polygon
			(pts
				(xy 273.37639 -347.417136) (xy 273.37639 -348.378018) (xy 273.618706 -348.378018) (xy 273.618706 -347.417136)
			)
		)
	)
	(zone
		(layer "F.Cu")
		(hatch none 0.5)
		(connect_pads
			(clearance 0)
		)
		(min_thickness 0.25)
		(keepout
			(tracks allowed)
			(vias allowed)
			(pads allowed)
			(copperpour allowed)
			(footprints allowed)
		)
		(placement
			(enabled no)
			(sheetname "")
		)
		(fill
			(thermal_gap 0.5)
			(thermal_bridge_width 0.5)
			(island_removal_mode 0)
		)
		(polygon
			(pts
				(xy 163.377626 -224.277936) (xy 163.377626 -223.947736) (xy 165.296596 -223.947736) (xy 165.296596 -224.277936)
			)
		)
	)
	(zone
		(layer "F.Cu")
		(hatch none 0.5)
		(connect_pads
			(clearance 0)
		)
		(min_thickness 0.25)
		(keepout
			(tracks not_allowed)
			(vias allowed)
			(pads allowed)
			(copperpour not_allowed)
			(footprints allowed)
		)
		(placement
			(enabled no)
			(sheetname "")
		)
		(fill
			(thermal_gap 0.5)
			(thermal_bridge_width 0.5)
			(island_removal_mode 0)
		)
		(polygon
			(pts
				(arc
					(start 298.51096 -66.060828)
					(mid 293.00297 -60.552838)
					(end 287.49498 -66.060828)
				)
				(arc
					(start 287.49498 -74.760836)
					(mid 293.00297 -80.268826)
					(end 298.51096 -74.760836)
				)
			)
		)
	)
	(zone
		(layer "F.Cu")
		(hatch none 0.5)
		(connect_pads
			(clearance 0)
		)
		(min_thickness 0.25)
		(keepout
			(tracks allowed)
			(vias allowed)
			(pads allowed)
			(copperpour allowed)
			(footprints allowed)
		)
		(placement
			(enabled no)
			(sheetname "")
		)
		(fill
			(thermal_gap 0.5)
			(thermal_bridge_width 0.5)
			(island_removal_mode 0)
		)
		(polygon
			(pts
				(xy 138.736578 -168.855136) (xy 138.736578 -168.308782) (xy 139.253214 -168.308782) (xy 139.253214 -168.855136)
			)
		)
	)
	(zone
		(layer "F.Cu")
		(hatch none 0.5)
		(connect_pads
			(clearance 0)
		)
		(min_thickness 0.25)
		(keepout
			(tracks allowed)
			(vias allowed)
			(pads allowed)
			(copperpour allowed)
			(footprints allowed)
		)
		(placement
			(enabled no)
			(sheetname "")
		)
		(fill
			(thermal_gap 0.5)
			(thermal_bridge_width 0.5)
			(island_removal_mode 0)
		)
		(polygon
			(pts
				(xy 136.6774 -28.0416) (xy 136.6774 -29.4894) (xy 136.645904 -29.4894) (xy 136.645904 -30.600904)
				(xy 135.96874 -31.278068) (xy 133.808978 -31.278068) (xy 133.5024 -30.97149) (xy 133.5024 -29.6672)
				(xy 134.652512 -28.517088) (xy 134.652512 -27.559762) (xy 135.278622 -26.933652) (xy 136.377426 -26.933652)
				(xy 136.6774 -27.233626)
			)
		)
	)
	(zone
		(layer "F.Cu")
		(hatch none 0.5)
		(connect_pads
			(clearance 0)
		)
		(min_thickness 0.25)
		(keepout
			(tracks allowed)
			(vias allowed)
			(pads allowed)
			(copperpour allowed)
			(footprints allowed)
		)
		(placement
			(enabled no)
			(sheetname "")
		)
		(fill
			(thermal_gap 0.5)
			(thermal_bridge_width 0.5)
			(island_removal_mode 0)
		)
		(polygon
			(pts
				(xy 411.317694 -286.842454) (xy 411.317694 -287.172654) (xy 413.236664 -287.172654) (xy 413.236664 -286.842454)
			)
		)
	)
	(zone
		(layer "F.Cu")
		(hatch none 0.5)
		(connect_pads
			(clearance 0)
		)
		(min_thickness 0.25)
		(keepout
			(tracks allowed)
			(vias allowed)
			(pads allowed)
			(copperpour allowed)
			(footprints not_allowed)
		)
		(placement
			(enabled no)
			(sheetname "")
		)
		(fill
			(thermal_gap 0.5)
			(thermal_bridge_width 0.5)
			(island_removal_mode 0)
		)
		(polygon
			(pts
				(arc
					(start 429.50003 -384.869944)
					(mid 433.500022 -380.869952)
					(end 437.500014 -384.869944)
				)
				(arc
					(start 437.500014 -384.869944)
					(mid 433.500022 -388.869936)
					(end 429.50003 -384.869944)
				)
			)
		)
	)
	(zone
		(layer "F.Cu")
		(hatch none 0.5)
		(connect_pads
			(clearance 0)
		)
		(min_thickness 0.25)
		(keepout
			(tracks allowed)
			(vias allowed)
			(pads allowed)
			(copperpour allowed)
			(footprints allowed)
		)
		(placement
			(enabled no)
			(sheetname "")
		)
		(fill
			(thermal_gap 0.5)
			(thermal_bridge_width 0.5)
			(island_removal_mode 0)
		)
		(polygon
			(pts
				(xy 157.49905 -409.042616) (xy 157.49905 -408.038554) (xy 158.895542 -408.038554) (xy 158.895542 -409.042616)
			)
		)
	)
	(zone
		(layer "F.Cu")
		(hatch none 0.5)
		(connect_pads
			(clearance 0)
		)
		(min_thickness 0.25)
		(keepout
			(tracks allowed)
			(vias allowed)
			(pads allowed)
			(copperpour allowed)
			(footprints allowed)
		)
		(placement
			(enabled no)
			(sheetname "")
		)
		(fill
			(thermal_gap 0.5)
			(thermal_bridge_width 0.5)
			(island_removal_mode 0)
		)
		(polygon
			(pts
				(xy 64.858138 -371.097302) (xy 64.858138 -370.09324) (xy 66.25463 -370.09324) (xy 66.25463 -371.097302)
			)
		)
	)
	(zone
		(layer "F.Cu")
		(hatch none 0.5)
		(connect_pads
			(clearance 0)
		)
		(min_thickness 0.25)
		(keepout
			(tracks allowed)
			(vias allowed)
			(pads allowed)
			(copperpour allowed)
			(footprints allowed)
		)
		(placement
			(enabled no)
			(sheetname "")
		)
		(fill
			(thermal_gap 0.5)
			(thermal_bridge_width 0.5)
			(island_removal_mode 0)
		)
		(polygon
			(pts
				(xy 424.011852 -9.605772) (xy 424.011852 -6.003036) (xy 433.741322 -6.003036) (xy 433.741322 -9.605772)
			)
		)
	)
	(zone
		(layer "F.Cu")
		(hatch none 0.5)
		(connect_pads
			(clearance 0)
		)
		(min_thickness 0.25)
		(keepout
			(tracks allowed)
			(vias allowed)
			(pads allowed)
			(copperpour allowed)
			(footprints allowed)
		)
		(placement
			(enabled no)
			(sheetname "")
		)
		(fill
			(thermal_gap 0.5)
			(thermal_bridge_width 0.5)
			(island_removal_mode 0)
		)
		(polygon
			(pts
				(xy 58.13044 -205.577948) (xy 58.13044 -205.247748) (xy 60.67044 -205.247748) (xy 60.67044 -205.577948)
			)
		)
	)
	(zone
		(layer "F.Cu")
		(hatch none 0.5)
		(connect_pads
			(clearance 0)
		)
		(min_thickness 0.25)
		(keepout
			(tracks allowed)
			(vias allowed)
			(pads allowed)
			(copperpour allowed)
			(footprints allowed)
		)
		(placement
			(enabled no)
			(sheetname "")
		)
		(fill
			(thermal_gap 0.5)
			(thermal_bridge_width 0.5)
			(island_removal_mode 0)
		)
		(polygon
			(pts
				(xy 450.13499 -427.606968) (xy 450.910706 -427.606968) (xy 450.910706 -428.346108) (xy 450.13499 -428.346108)
			)
		)
	)
	(zone
		(layer "F.Cu")
		(hatch none 0.5)
		(connect_pads
			(clearance 0)
		)
		(min_thickness 0.25)
		(keepout
			(tracks allowed)
			(vias allowed)
			(pads allowed)
			(copperpour allowed)
			(footprints allowed)
		)
		(placement
			(enabled no)
			(sheetname "")
		)
		(fill
			(thermal_gap 0.5)
			(thermal_bridge_width 0.5)
			(island_removal_mode 0)
		)
		(polygon
			(pts
				(xy 297.58767 -332.196694) (xy 297.58767 -334.101694) (xy 301.60087 -334.101694) (xy 301.60087 -332.196694)
			)
		)
	)
	(zone
		(layer "F.Cu")
		(hatch none 0.5)
		(connect_pads
			(clearance 0)
		)
		(min_thickness 0.25)
		(keepout
			(tracks allowed)
			(vias allowed)
			(pads allowed)
			(copperpour allowed)
			(footprints allowed)
		)
		(placement
			(enabled no)
			(sheetname "")
		)
		(fill
			(thermal_gap 0.5)
			(thermal_bridge_width 0.5)
			(island_removal_mode 0)
		)
		(polygon
			(pts
				(xy 106.120184 -339.979254) (xy 100.72878 -339.979254) (xy 100.5205 -339.770974) (xy 100.5205 -337.7184)
				(xy 100.04298 -337.24088) (xy 100.04298 -336.66938) (xy 99.93884 -336.56524) (xy 99.31146 -336.56524)
				(xy 99.135184 -336.741516) (xy 99.135184 -340.614254) (xy 99.135184 -345.186254) (xy 99.770184 -345.821254)
				(xy 105.739184 -345.821254) (xy 106.247184 -345.313254) (xy 106.247184 -340.106254)
			)
		)
	)
	(zone
		(layer "F.Cu")
		(hatch none 0.5)
		(connect_pads
			(clearance 0)
		)
		(min_thickness 0.25)
		(keepout
			(tracks allowed)
			(vias allowed)
			(pads allowed)
			(copperpour allowed)
			(footprints allowed)
		)
		(placement
			(enabled no)
			(sheetname "")
		)
		(fill
			(thermal_gap 0.5)
			(thermal_bridge_width 0.5)
			(island_removal_mode 0)
		)
		(polygon
			(pts
				(xy 60.725812 -302.142652) (xy 60.725812 -302.472852) (xy 58.185812 -302.472852) (xy 58.185812 -302.142652)
			)
		)
	)
	(zone
		(layer "F.Cu")
		(hatch none 0.5)
		(connect_pads
			(clearance 0)
		)
		(min_thickness 0.25)
		(keepout
			(tracks allowed)
			(vias allowed)
			(pads allowed)
			(copperpour allowed)
			(footprints allowed)
		)
		(placement
			(enabled no)
			(sheetname "")
		)
		(fill
			(thermal_gap 0.5)
			(thermal_bridge_width 0.5)
			(island_removal_mode 0)
		)
		(polygon
			(pts
				(xy 382.866646 -417.424616) (xy 382.866646 -416.420554) (xy 384.263138 -416.420554) (xy 384.263138 -417.424616)
			)
		)
	)
	(zone
		(layer "F.Cu")
		(hatch none 0.5)
		(connect_pads
			(clearance 0)
		)
		(min_thickness 0.25)
		(keepout
			(tracks allowed)
			(vias allowed)
			(pads allowed)
			(copperpour allowed)
			(footprints allowed)
		)
		(placement
			(enabled no)
			(sheetname "")
		)
		(fill
			(thermal_gap 0.5)
			(thermal_bridge_width 0.5)
			(island_removal_mode 0)
		)
		(polygon
			(pts
				(xy 58.13044 -250.627896) (xy 58.13044 -250.297696) (xy 60.67044 -250.297696) (xy 60.67044 -250.627896)
			)
		)
	)
	(zone
		(layer "F.Cu")
		(hatch none 0.5)
		(connect_pads
			(clearance 0)
		)
		(min_thickness 0.25)
		(keepout
			(tracks allowed)
			(vias allowed)
			(pads allowed)
			(copperpour allowed)
			(footprints allowed)
		)
		(placement
			(enabled no)
			(sheetname "")
		)
		(fill
			(thermal_gap 0.5)
			(thermal_bridge_width 0.5)
			(island_removal_mode 0)
		)
		(polygon
			(pts
				(xy 326.898254 -221.17431) (xy 392.862054 -221.17431) (xy 394.817854 -223.13011) (xy 394.817854 -224.292668)
				(xy 394.369544 -224.740978) (xy 392.597386 -224.740978) (xy 391.439654 -225.89871) (xy 391.439654 -259.78231)
				(xy 392.735054 -261.07771) (xy 392.735054 -261.23011) (xy 392.557254 -261.40791) (xy 392.404854 -261.40791)
				(xy 391.744454 -262.06831) (xy 391.744454 -292.19271) (xy 393.090654 -293.53891) (xy 395.572234 -293.53891)
				(xy 395.572234 -296.22369) (xy 395.183614 -296.61231) (xy 324.656704 -296.61231) (xy 324.249542 -296.205148)
				(xy 324.249542 -293.66591) (xy 326.898254 -293.66591) (xy 328.346054 -292.21811) (xy 328.346054 -261.99211)
				(xy 327.761854 -261.40791) (xy 327.533254 -261.40791) (xy 327.380854 -261.25551) (xy 327.380854 -260.95071)
				(xy 328.015854 -260.31571) (xy 328.015854 -225.92411) (xy 325.425054 -223.33331) (xy 325.425054 -222.64751)
			)
		)
	)
	(zone
		(layer "F.Cu")
		(hatch none 0.5)
		(connect_pads
			(clearance 0)
		)
		(min_thickness 0.25)
		(keepout
			(tracks not_allowed)
			(vias allowed)
			(pads allowed)
			(copperpour not_allowed)
			(footprints allowed)
		)
		(placement
			(enabled no)
			(sheetname "")
		)
		(fill
			(thermal_gap 0.5)
			(thermal_bridge_width 0.5)
			(island_removal_mode 0)
		)
		(polygon
			(pts
				(xy 84.622132 -334.229202) (xy 84.622132 -334.685894) (xy 85.317838 -334.685894) (xy 85.317838 -334.525366)
				(xy 85.876638 -334.525366) (xy 85.876638 -334.931766) (xy 85.317838 -334.931766) (xy 85.317838 -334.711294)
				(xy 84.622132 -334.711294) (xy 84.622132 -334.838294) (xy 85.077808 -334.838294) (xy 85.077808 -335.224882)
				(xy 85.320124 -335.224882) (xy 85.852 -335.224882) (xy 86.171532 -334.90535) (xy 86.171532 -334.229202)
			)
		)
	)
	(zone
		(layer "F.Cu")
		(hatch none 0.5)
		(connect_pads
			(clearance 0)
		)
		(min_thickness 0.25)
		(keepout
			(tracks not_allowed)
			(vias allowed)
			(pads allowed)
			(copperpour not_allowed)
			(footprints allowed)
		)
		(placement
			(enabled no)
			(sheetname "")
		)
		(fill
			(thermal_gap 0.5)
			(thermal_bridge_width 0.5)
			(island_removal_mode 0)
		)
		(polygon
			(pts
				(arc
					(start 273.649948 -51.999896)
					(mid 268.649958 -56.999886)
					(end 263.649968 -51.999896)
				)
				(arc
					(start 263.649968 -51.999896)
					(mid 268.649958 -46.999906)
					(end 273.649948 -51.999896)
				)
			)
		)
	)
	(zone
		(layer "F.Cu")
		(hatch none 0.5)
		(connect_pads
			(clearance 0)
		)
		(min_thickness 0.25)
		(keepout
			(tracks allowed)
			(vias allowed)
			(pads allowed)
			(copperpour allowed)
			(footprints not_allowed)
		)
		(placement
			(enabled no)
			(sheetname "")
		)
		(fill
			(thermal_gap 0.5)
			(thermal_bridge_width 0.5)
			(island_removal_mode 0)
		)
		(polygon
			(pts
				(arc
					(start 317.731394 -160.50006)
					(mid 322.731384 -155.50007)
					(end 327.731374 -160.50006)
				)
				(arc
					(start 327.731374 -160.50006)
					(mid 322.731384 -165.50005)
					(end 317.731394 -160.50006)
				)
			)
		)
	)
	(zone
		(layer "F.Cu")
		(hatch none 0.5)
		(connect_pads
			(clearance 0)
		)
		(min_thickness 0.25)
		(keepout
			(tracks allowed)
			(vias allowed)
			(pads allowed)
			(copperpour allowed)
			(footprints allowed)
		)
		(placement
			(enabled no)
			(sheetname "")
		)
		(fill
			(thermal_gap 0.5)
			(thermal_bridge_width 0.5)
			(island_removal_mode 0)
		)
		(polygon
			(pts
				(xy 400.459956 -399.742406) (xy 402.266404 -399.742406) (xy 402.555202 -399.453608) (xy 402.555202 -396.634462)
				(xy 402.68017 -396.509494) (xy 422.066212 -396.509494) (xy 422.066212 -399.157952) (xy 421.716708 -399.507456)
				(xy 421.716708 -400.78406) (xy 421.881554 -400.948906) (xy 422.471342 -400.948906) (xy 423.951654 -399.468594)
				(xy 423.951654 -396.558008) (xy 421.724328 -394.330682) (xy 402.541486 -394.330682) (xy 401.926806 -393.716002)
				(xy 401.926806 -393.377166) (xy 401.776184 -393.226544) (xy 400.760184 -393.226544) (xy 400.383756 -393.602972)
				(xy 400.383756 -395.697964) (xy 399.505424 -396.576296) (xy 399.505424 -397.642842) (xy 400.396202 -398.53362)
				(xy 400.396202 -399.678652)
			)
		)
	)
	(zone
		(layer "F.Cu")
		(hatch none 0.5)
		(connect_pads
			(clearance 0)
		)
		(min_thickness 0.25)
		(keepout
			(tracks allowed)
			(vias allowed)
			(pads allowed)
			(copperpour allowed)
			(footprints allowed)
		)
		(placement
			(enabled no)
			(sheetname "")
		)
		(fill
			(thermal_gap 0.5)
			(thermal_bridge_width 0.5)
			(island_removal_mode 0)
		)
		(polygon
			(pts
				(xy 339.771228 -379.479302) (xy 339.771228 -378.47524) (xy 341.16772 -378.47524) (xy 341.16772 -379.479302)
			)
		)
	)
	(zone
		(layer "F.Cu")
		(hatch none 0.5)
		(connect_pads
			(clearance 0)
		)
		(min_thickness 0.25)
		(keepout
			(tracks allowed)
			(vias allowed)
			(pads allowed)
			(copperpour allowed)
			(footprints not_allowed)
		)
		(placement
			(enabled no)
			(sheetname "")
		)
		(fill
			(thermal_gap 0.5)
			(thermal_bridge_width 0.5)
			(island_removal_mode 0)
		)
		(polygon
			(pts
				(arc
					(start 358.086914 -340.315042)
					(mid 359.952036 -338.44992)
					(end 361.816904 -340.315042)
				)
				(arc
					(start 361.816904 -340.315042)
					(mid 359.952036 -342.17991)
					(end 358.086914 -340.315042)
				)
			)
		)
	)
	(zone
		(layer "F.Cu")
		(hatch none 0.5)
		(connect_pads
			(clearance 0)
		)
		(min_thickness 0.25)
		(keepout
			(tracks not_allowed)
			(vias allowed)
			(pads allowed)
			(copperpour not_allowed)
			(footprints allowed)
		)
		(placement
			(enabled no)
			(sheetname "")
		)
		(fill
			(thermal_gap 0.5)
			(thermal_bridge_width 0.5)
			(island_removal_mode 0)
		)
		(polygon
			(pts
				(xy 42.686732 -345.971876) (xy 42.686732 -346.428568) (xy 43.382438 -346.428568) (xy 43.382438 -346.26804)
				(xy 43.941238 -346.26804) (xy 43.941238 -346.67444) (xy 43.382438 -346.67444) (xy 43.382438 -346.453968)
				(xy 42.686732 -346.453968) (xy 42.686732 -346.580968) (xy 43.142408 -346.580968) (xy 43.142408 -346.967556)
				(xy 43.384724 -346.967556) (xy 43.9166 -346.967556) (xy 44.236132 -346.648024) (xy 44.236132 -345.971876)
			)
		)
	)
	(zone
		(layer "F.Cu")
		(hatch none 0.5)
		(connect_pads
			(clearance 0)
		)
		(min_thickness 0.25)
		(keepout
			(tracks allowed)
			(vias allowed)
			(pads allowed)
			(copperpour allowed)
			(footprints not_allowed)
		)
		(placement
			(enabled no)
			(sheetname "")
		)
		(fill
			(thermal_gap 0.5)
			(thermal_bridge_width 0.5)
			(island_removal_mode 0)
		)
		(polygon
			(pts
				(xy 2.999994 -199.053958) (xy 16.199104 -199.053958) (xy 16.199104 -190.215012) (xy 2.999994 -190.215012)
			)
		)
	)
	(zone
		(layer "F.Cu")
		(hatch none 0.5)
		(connect_pads
			(clearance 0)
		)
		(min_thickness 0.25)
		(keepout
			(tracks allowed)
			(vias allowed)
			(pads allowed)
			(copperpour allowed)
			(footprints not_allowed)
		)
		(placement
			(enabled no)
			(sheetname "")
		)
		(fill
			(thermal_gap 0.5)
			(thermal_bridge_width 0.5)
			(island_removal_mode 0)
		)
		(polygon
			(pts
				(arc
					(start 5.00507 -389.439912)
					(mid 6.870192 -387.57479)
					(end 8.73506 -389.439912)
				)
				(arc
					(start 8.73506 -389.439912)
					(mid 6.870192 -391.30478)
					(end 5.00507 -389.439912)
				)
			)
		)
	)
	(zone
		(layer "F.Cu")
		(hatch none 0.5)
		(connect_pads
			(clearance 0)
		)
		(min_thickness 0.25)
		(keepout
			(tracks not_allowed)
			(vias allowed)
			(pads allowed)
			(copperpour not_allowed)
			(footprints allowed)
		)
		(placement
			(enabled no)
			(sheetname "")
		)
		(fill
			(thermal_gap 0.5)
			(thermal_bridge_width 0.5)
			(island_removal_mode 0)
		)
		(polygon
			(pts
				(arc
					(start 326.47001 -304.790094)
					(mid 329.270106 -301.989998)
					(end 332.069948 -304.790094)
				)
				(arc
					(start 332.069948 -304.790094)
					(mid 329.270106 -307.589936)
					(end 326.47001 -304.790094)
				)
			)
		)
	)
	(zone
		(layer "F.Cu")
		(hatch none 0.5)
		(connect_pads
			(clearance 0)
		)
		(min_thickness 0.25)
		(keepout
			(tracks allowed)
			(vias allowed)
			(pads allowed)
			(copperpour allowed)
			(footprints not_allowed)
		)
		(placement
			(enabled no)
			(sheetname "")
		)
		(fill
			(thermal_gap 0.5)
			(thermal_bridge_width 0.5)
			(island_removal_mode 0)
		)
		(polygon
			(pts
				(arc
					(start 445.574928 -40.420036)
					(mid 447.44005 -38.554914)
					(end 449.304918 -40.420036)
				)
				(arc
					(start 449.304918 -40.420036)
					(mid 447.44005 -42.284904)
					(end 445.574928 -40.420036)
				)
			)
		)
	)
	(zone
		(layer "F.Cu")
		(hatch none 0.5)
		(connect_pads
			(clearance 0)
		)
		(min_thickness 0.25)
		(keepout
			(tracks allowed)
			(vias allowed)
			(pads allowed)
			(copperpour allowed)
			(footprints allowed)
		)
		(placement
			(enabled no)
			(sheetname "")
		)
		(fill
			(thermal_gap 0.5)
			(thermal_bridge_width 0.5)
			(island_removal_mode 0)
		)
		(polygon
			(pts
				(xy 96.949514 -195.307712) (xy 96.949514 -197.212712) (xy 100.962714 -197.212712) (xy 100.962714 -195.307712)
			)
		)
	)
	(zone
		(layer "F.Cu")
		(hatch none 0.5)
		(connect_pads
			(clearance 0)
		)
		(min_thickness 0.25)
		(keepout
			(tracks allowed)
			(vias allowed)
			(pads allowed)
			(copperpour allowed)
			(footprints allowed)
		)
		(placement
			(enabled no)
			(sheetname "")
		)
		(fill
			(thermal_gap 0.5)
			(thermal_bridge_width 0.5)
			(island_removal_mode 0)
		)
		(polygon
			(pts
				(xy 328.28738 -5.78866) (xy 328.28738 -3.80746) (xy 330.62672 -3.80746) (xy 330.62672 -5.78866)
			)
		)
	)
	(zone
		(layer "F.Cu")
		(hatch none 0.5)
		(connect_pads
			(clearance 0)
		)
		(min_thickness 0.25)
		(keepout
			(tracks allowed)
			(vias allowed)
			(pads allowed)
			(copperpour allowed)
			(footprints allowed)
		)
		(placement
			(enabled no)
			(sheetname "")
		)
		(fill
			(thermal_gap 0.5)
			(thermal_bridge_width 0.5)
			(island_removal_mode 0)
		)
		(polygon
			(pts
				(xy 123.80341 -409.042616) (xy 123.80341 -408.038554) (xy 125.199902 -408.038554) (xy 125.199902 -409.042616)
			)
		)
	)
	(zone
		(layer "F.Cu")
		(hatch none 0.5)
		(connect_pads
			(clearance 0)
		)
		(min_thickness 0.25)
		(keepout
			(tracks allowed)
			(vias allowed)
			(pads allowed)
			(copperpour allowed)
			(footprints not_allowed)
		)
		(placement
			(enabled no)
			(sheetname "")
		)
		(fill
			(thermal_gap 0.5)
			(thermal_bridge_width 0.5)
			(island_removal_mode 0)
		)
		(polygon
			(pts
				(arc
					(start 84.829904 -212.989922)
					(mid 81.330038 -216.489788)
					(end 77.829918 -212.989922)
				)
				(arc
					(start 77.829918 -212.989922)
					(mid 81.330038 -209.489802)
					(end 84.829904 -212.989922)
				)
			)
		)
	)
	(zone
		(layer "F.Cu")
		(hatch none 0.5)
		(connect_pads
			(clearance 0)
		)
		(min_thickness 0.25)
		(keepout
			(tracks allowed)
			(vias allowed)
			(pads allowed)
			(copperpour allowed)
			(footprints allowed)
		)
		(placement
			(enabled no)
			(sheetname "")
		)
		(fill
			(thermal_gap 0.5)
			(thermal_bridge_width 0.5)
			(island_removal_mode 0)
		)
		(polygon
			(pts
				(xy 150.871428 -371.097302) (xy 150.871428 -370.09324) (xy 152.26792 -370.09324) (xy 152.26792 -371.097302)
			)
		)
	)
	(zone
		(layer "F.Cu")
		(hatch none 0.5)
		(connect_pads
			(clearance 0)
		)
		(min_thickness 0.25)
		(keepout
			(tracks allowed)
			(vias allowed)
			(pads allowed)
			(copperpour allowed)
			(footprints allowed)
		)
		(placement
			(enabled no)
			(sheetname "")
		)
		(fill
			(thermal_gap 0.5)
			(thermal_bridge_width 0.5)
			(island_removal_mode 0)
		)
		(polygon
			(pts
				(xy 395.119606 -417.424616) (xy 395.119606 -416.420554) (xy 396.516098 -416.420554) (xy 396.516098 -417.424616)
			)
		)
	)
	(zone
		(layer "F.Cu")
		(hatch none 0.5)
		(connect_pads
			(clearance 0)
		)
		(min_thickness 0.25)
		(keepout
			(tracks allowed)
			(vias allowed)
			(pads allowed)
			(copperpour allowed)
			(footprints not_allowed)
		)
		(placement
			(enabled no)
			(sheetname "")
		)
		(fill
			(thermal_gap 0.5)
			(thermal_bridge_width 0.5)
			(island_removal_mode 0)
		)
		(polygon
			(pts
				(arc
					(start 298.550076 -435.600094)
					(mid 293.550086 -440.600084)
					(end 288.550096 -435.600094)
				)
				(arc
					(start 288.550096 -435.600094)
					(mid 293.550086 -430.600104)
					(end 298.550076 -435.600094)
				)
			)
		)
	)
	(zone
		(layer "F.Cu")
		(hatch none 0.5)
		(connect_pads
			(clearance 0)
		)
		(min_thickness 0.25)
		(keepout
			(tracks allowed)
			(vias allowed)
			(pads allowed)
			(copperpour allowed)
			(footprints allowed)
		)
		(placement
			(enabled no)
			(sheetname "")
		)
		(fill
			(thermal_gap 0.5)
			(thermal_bridge_width 0.5)
			(island_removal_mode 0)
		)
		(polygon
			(pts
				(xy 56.349138 -373.561102) (xy 56.349138 -372.55704) (xy 57.74563 -372.55704) (xy 57.74563 -373.561102)
			)
		)
	)
	(zone
		(layer "F.Cu")
		(hatch none 0.5)
		(connect_pads
			(clearance 0)
		)
		(min_thickness 0.25)
		(keepout
			(tracks allowed)
			(vias allowed)
			(pads allowed)
			(copperpour allowed)
			(footprints not_allowed)
		)
		(placement
			(enabled no)
			(sheetname "")
		)
		(fill
			(thermal_gap 0.5)
			(thermal_bridge_width 0.5)
			(island_removal_mode 0)
		)
		(polygon
			(pts
				(arc
					(start 7.53999 -160.50006)
					(mid 10.340086 -157.699964)
					(end 13.139928 -160.50006)
				)
				(arc
					(start 13.139928 -160.50006)
					(mid 10.340086 -163.299902)
					(end 7.53999 -160.50006)
				)
			)
		)
	)
	(zone
		(layer "F.Cu")
		(hatch none 0.5)
		(connect_pads
			(clearance 0)
		)
		(min_thickness 0.25)
		(keepout
			(tracks not_allowed)
			(vias allowed)
			(pads allowed)
			(copperpour not_allowed)
			(footprints allowed)
		)
		(placement
			(enabled no)
			(sheetname "")
		)
		(fill
			(thermal_gap 0.5)
			(thermal_bridge_width 0.5)
			(island_removal_mode 0)
		)
		(polygon
			(pts
				(arc
					(start 332.769972 -212.989922)
					(mid 329.270106 -216.489788)
					(end 325.769986 -212.989922)
				)
				(arc
					(start 325.769986 -212.989922)
					(mid 329.270106 -209.489802)
					(end 332.769972 -212.989922)
				)
			)
		)
	)
	(zone
		(layer "F.Cu")
		(hatch none 0.5)
		(connect_pads
			(clearance 0)
		)
		(min_thickness 0.25)
		(keepout
			(tracks allowed)
			(vias allowed)
			(pads allowed)
			(copperpour allowed)
			(footprints allowed)
		)
		(placement
			(enabled no)
			(sheetname "")
		)
		(fill
			(thermal_gap 0.5)
			(thermal_bridge_width 0.5)
			(island_removal_mode 0)
		)
		(polygon
			(pts
				(xy 163.377626 -286.842708) (xy 163.377626 -287.172908) (xy 165.296596 -287.172908) (xy 165.296596 -286.842708)
			)
		)
	)
	(zone
		(layer "F.Cu")
		(hatch none 0.5)
		(connect_pads
			(clearance 0)
		)
		(min_thickness 0.25)
		(keepout
			(tracks allowed)
			(vias allowed)
			(pads allowed)
			(copperpour allowed)
			(footprints not_allowed)
		)
		(placement
			(enabled no)
			(sheetname "")
		)
		(fill
			(thermal_gap 0.5)
			(thermal_bridge_width 0.5)
			(island_removal_mode 0)
		)
		(polygon
			(pts
				(arc
					(start 11.999976 -22.29993)
					(mid 6.999986 -27.29992)
					(end 1.999996 -22.29993)
				)
				(arc
					(start 1.999996 -22.29993)
					(mid 6.999986 -17.29994)
					(end 11.999976 -22.29993)
				)
			)
		)
	)
	(zone
		(layer "F.Cu")
		(hatch none 0.5)
		(connect_pads
			(clearance 0)
		)
		(min_thickness 0.25)
		(keepout
			(tracks allowed)
			(vias allowed)
			(pads allowed)
			(copperpour allowed)
			(footprints allowed)
		)
		(placement
			(enabled no)
			(sheetname "")
		)
		(fill
			(thermal_gap 0.5)
			(thermal_bridge_width 0.5)
			(island_removal_mode 0)
		)
		(polygon
			(pts
				(xy 79.54391 -183.083454) (xy 85.89391 -183.083454) (xy 86.52891 -182.448454) (xy 86.52891 -177.876454)
				(xy 85.89391 -177.241454) (xy 79.92491 -177.241454) (xy 79.41691 -177.749454) (xy 79.41691 -182.956454)
			)
		)
	)
	(zone
		(layer "F.Cu")
		(hatch none 0.5)
		(connect_pads
			(clearance 0)
		)
		(min_thickness 0.25)
		(keepout
			(tracks not_allowed)
			(vias allowed)
			(pads allowed)
			(copperpour not_allowed)
			(footprints allowed)
		)
		(placement
			(enabled no)
			(sheetname "")
		)
		(fill
			(thermal_gap 0.5)
			(thermal_bridge_width 0.5)
			(island_removal_mode 0)
		)
		(polygon
			(pts
				(xy 16.046196 -98.196654) (xy 15.893796 -98.196654) (xy 15.893796 -100.965254) (xy 12.236196 -100.965254)
				(xy 12.236196 -97.307654) (xy 15.893796 -97.307654) (xy 15.893796 -98.171254) (xy 16.046196 -98.171254)
				(xy 16.046196 -97.155254) (xy 12.083796 -97.155254) (xy 12.083796 -101.117654) (xy 16.046196 -101.117654)
			)
		)
	)
	(zone
		(layer "F.Cu")
		(hatch none 0.5)
		(connect_pads
			(clearance 0)
		)
		(min_thickness 0.25)
		(keepout
			(tracks allowed)
			(vias allowed)
			(pads allowed)
			(copperpour allowed)
			(footprints not_allowed)
		)
		(placement
			(enabled no)
			(sheetname "")
		)
		(fill
			(thermal_gap 0.5)
			(thermal_bridge_width 0.5)
			(island_removal_mode 0)
		)
		(polygon
			(pts
				(xy 39.880032 -394.759942) (xy 39.880032 -398.560036) (xy 44.669964 -398.560036) (xy 44.669964 -393.530074)
				(xy 39.990014 -393.530074) (xy 39.990014 -394.759942)
			)
		)
	)
	(zone
		(layer "F.Cu")
		(hatch none 0.5)
		(connect_pads
			(clearance 0)
		)
		(min_thickness 0.25)
		(keepout
			(tracks allowed)
			(vias allowed)
			(pads allowed)
			(copperpour allowed)
			(footprints allowed)
		)
		(placement
			(enabled no)
			(sheetname "")
		)
		(fill
			(thermal_gap 0.5)
			(thermal_bridge_width 0.5)
			(island_removal_mode 0)
		)
		(polygon
			(pts
				(xy 109.534452 -409.295092) (xy 109.534452 -410.028644) (xy 108.477558 -410.028644) (xy 108.477558 -409.295092)
			)
		)
	)
	(zone
		(layer "F.Cu")
		(hatch none 0.5)
		(connect_pads
			(clearance 0)
		)
		(min_thickness 0.25)
		(keepout
			(tracks not_allowed)
			(vias allowed)
			(pads allowed)
			(copperpour not_allowed)
			(footprints allowed)
		)
		(placement
			(enabled no)
			(sheetname "")
		)
		(fill
			(thermal_gap 0.5)
			(thermal_bridge_width 0.5)
			(island_removal_mode 0)
		)
		(polygon
			(pts
				(arc
					(start 146.029934 -212.989922)
					(mid 142.530068 -216.489788)
					(end 139.029948 -212.989922)
				)
				(arc
					(start 139.029948 -212.989922)
					(mid 142.530068 -209.489802)
					(end 146.029934 -212.989922)
				)
			)
		)
	)
	(zone
		(layer "F.Cu")
		(hatch none 0.5)
		(connect_pads
			(clearance 0)
		)
		(min_thickness 0.25)
		(keepout
			(tracks allowed)
			(vias allowed)
			(pads allowed)
			(copperpour allowed)
			(footprints allowed)
		)
		(placement
			(enabled no)
			(sheetname "")
		)
		(fill
			(thermal_gap 0.5)
			(thermal_bridge_width 0.5)
			(island_removal_mode 0)
		)
		(polygon
			(pts
				(xy 51.243738 -371.097302) (xy 51.243738 -370.09324) (xy 52.64023 -370.09324) (xy 52.64023 -371.097302)
			)
		)
	)
	(zone
		(layer "F.Cu")
		(hatch none 0.5)
		(connect_pads
			(clearance 0)
		)
		(min_thickness 0.25)
		(keepout
			(tracks not_allowed)
			(vias allowed)
			(pads allowed)
			(copperpour not_allowed)
			(footprints allowed)
		)
		(placement
			(enabled no)
			(sheetname "")
		)
		(fill
			(thermal_gap 0.5)
			(thermal_bridge_width 0.5)
			(island_removal_mode 0)
		)
		(polygon
			(pts
				(xy 134.924292 -157.280356) (xy 134.924292 -156.823664) (xy 134.228586 -156.823664) (xy 134.228586 -156.984192)
				(xy 133.669786 -156.984192) (xy 133.669786 -156.577792) (xy 134.228586 -156.577792) (xy 134.228586 -156.798264)
				(xy 134.924292 -156.798264) (xy 134.924292 -156.671264) (xy 134.468616 -156.671264) (xy 134.468616 -156.284676)
				(xy 134.2263 -156.284676) (xy 133.694424 -156.284676) (xy 133.374892 -156.604208) (xy 133.374892 -157.280356)
			)
		)
	)
	(zone
		(layer "F.Cu")
		(hatch none 0.5)
		(connect_pads
			(clearance 0)
		)
		(min_thickness 0.25)
		(keepout
			(tracks not_allowed)
			(vias allowed)
			(pads allowed)
			(copperpour not_allowed)
			(footprints allowed)
		)
		(placement
			(enabled no)
			(sheetname "")
		)
		(fill
			(thermal_gap 0.5)
			(thermal_bridge_width 0.5)
			(island_removal_mode 0)
		)
		(polygon
			(pts
				(arc
					(start 270.649954 -22.29993)
					(mid 265.649964 -27.29992)
					(end 260.649974 -22.29993)
				)
				(arc
					(start 260.649974 -22.29993)
					(mid 265.649964 -17.29994)
					(end 270.649954 -22.29993)
				)
			)
		)
	)
	(zone
		(layer "F.Cu")
		(hatch none 0.5)
		(connect_pads
			(clearance 0)
		)
		(min_thickness 0.25)
		(keepout
			(tracks allowed)
			(vias allowed)
			(pads allowed)
			(copperpour allowed)
			(footprints not_allowed)
		)
		(placement
			(enabled no)
			(sheetname "")
		)
		(fill
			(thermal_gap 0.5)
			(thermal_bridge_width 0.5)
			(island_removal_mode 0)
		)
		(polygon
			(pts
				(xy 278.238966 -327.609962) (xy 278.238966 -183.50992) (xy 272.03908 -183.50992) (xy 272.03908 -327.609962)
			)
		)
	)
	(zone
		(layer "F.Cu")
		(hatch none 0.5)
		(connect_pads
			(clearance 0)
		)
		(min_thickness 0.25)
		(keepout
			(tracks allowed)
			(vias allowed)
			(pads allowed)
			(copperpour allowed)
			(footprints allowed)
		)
		(placement
			(enabled no)
			(sheetname "")
		)
		(fill
			(thermal_gap 0.5)
			(thermal_bridge_width 0.5)
			(island_removal_mode 0)
		)
		(polygon
			(pts
				(xy 56.254396 -147.08378) (xy 56.254396 -146.472402) (xy 56.856122 -146.472402) (xy 56.856122 -147.08378)
			)
		)
	)
	(zone
		(layer "F.Cu")
		(hatch none 0.5)
		(connect_pads
			(clearance 0)
		)
		(min_thickness 0.25)
		(keepout
			(tracks allowed)
			(vias allowed)
			(pads allowed)
			(copperpour allowed)
			(footprints allowed)
		)
		(placement
			(enabled no)
			(sheetname "")
		)
		(fill
			(thermal_gap 0.5)
			(thermal_bridge_width 0.5)
			(island_removal_mode 0)
		)
		(polygon
			(pts
				(xy 300.832012 -399.742406) (xy 302.63846 -399.742406) (xy 302.927258 -399.453608) (xy 302.927258 -396.634462)
				(xy 303.052226 -396.509494) (xy 322.438268 -396.509494) (xy 322.438268 -399.157952) (xy 322.088764 -399.507456)
				(xy 322.088764 -400.78406) (xy 322.25361 -400.948906) (xy 322.843398 -400.948906) (xy 324.32371 -399.468594)
				(xy 324.32371 -396.558008) (xy 322.096384 -394.330682) (xy 302.913542 -394.330682) (xy 302.298862 -393.716002)
				(xy 302.298862 -393.377166) (xy 302.14824 -393.226544) (xy 301.13224 -393.226544) (xy 300.755812 -393.602972)
				(xy 300.755812 -395.697964) (xy 299.87748 -396.576296) (xy 299.87748 -397.642842) (xy 300.768258 -398.53362)
				(xy 300.768258 -399.678652)
			)
		)
	)
	(zone
		(layer "F.Cu")
		(hatch none 0.5)
		(connect_pads
			(clearance 0)
		)
		(min_thickness 0.25)
		(keepout
			(tracks allowed)
			(vias allowed)
			(pads allowed)
			(copperpour allowed)
			(footprints allowed)
		)
		(placement
			(enabled no)
			(sheetname "")
		)
		(fill
			(thermal_gap 0.5)
			(thermal_bridge_width 0.5)
			(island_removal_mode 0)
		)
		(polygon
			(pts
				(xy 306.070508 -252.327664) (xy 306.070508 -251.997464) (xy 308.610508 -251.997464) (xy 308.610508 -252.327664)
			)
		)
	)
	(zone
		(layer "F.Cu")
		(hatch none 0.5)
		(connect_pads
			(clearance 0)
		)
		(min_thickness 0.25)
		(keepout
			(tracks allowed)
			(vias allowed)
			(pads allowed)
			(copperpour allowed)
			(footprints not_allowed)
		)
		(placement
			(enabled no)
			(sheetname "")
		)
		(fill
			(thermal_gap 0.5)
			(thermal_bridge_width 0.5)
			(island_removal_mode 0)
		)
		(polygon
			(pts
				(xy 13.64996 -46.459902) (xy 2.15011 -46.459902) (xy 2.15011 -57.53989) (xy 13.64996 -57.53989)
			)
		)
	)
	(zone
		(layer "F.Cu")
		(hatch none 0.5)
		(connect_pads
			(clearance 0)
		)
		(min_thickness 0.25)
		(keepout
			(tracks allowed)
			(vias allowed)
			(pads allowed)
			(copperpour allowed)
			(footprints allowed)
		)
		(placement
			(enabled no)
			(sheetname "")
		)
		(fill
			(thermal_gap 0.5)
			(thermal_bridge_width 0.5)
			(island_removal_mode 0)
		)
		(polygon
			(pts
				(xy 129.260092 -14.410182) (xy 129.260092 -11.597386) (xy 137.236454 -11.597386) (xy 137.236454 -14.410182)
			)
		)
	)
	(zone
		(layer "F.Cu")
		(hatch none 0.5)
		(connect_pads
			(clearance 0)
		)
		(min_thickness 0.25)
		(keepout
			(tracks not_allowed)
			(vias allowed)
			(pads allowed)
			(copperpour not_allowed)
			(footprints allowed)
		)
		(placement
			(enabled no)
			(sheetname "")
		)
		(fill
			(thermal_gap 0.5)
			(thermal_bridge_width 0.5)
			(island_removal_mode 0)
		)
		(polygon
			(pts
				(xy 349.772224 -160.439354) (xy 349.772224 -159.478472) (xy 349.529908 -159.478472) (xy 349.529908 -160.439354)
			)
		)
	)
	(zone
		(layer "F.Cu")
		(hatch none 0.5)
		(connect_pads
			(clearance 0)
		)
		(min_thickness 0.25)
		(keepout
			(tracks allowed)
			(vias allowed)
			(pads allowed)
			(copperpour allowed)
			(footprints allowed)
		)
		(placement
			(enabled no)
			(sheetname "")
		)
		(fill
			(thermal_gap 0.5)
			(thermal_bridge_width 0.5)
			(island_removal_mode 0)
		)
		(polygon
			(pts
				(xy 159.653224 -359.244138) (xy 159.95142 -359.542334) (xy 159.87014 -359.623614) (xy 159.571944 -359.325418)
			)
		)
	)
	(zone
		(layer "F.Cu")
		(hatch none 0.5)
		(connect_pads
			(clearance 0)
		)
		(min_thickness 0.25)
		(keepout
			(tracks allowed)
			(vias allowed)
			(pads allowed)
			(copperpour allowed)
			(footprints allowed)
		)
		(placement
			(enabled no)
			(sheetname "")
		)
		(fill
			(thermal_gap 0.5)
			(thermal_bridge_width 0.5)
			(island_removal_mode 0)
		)
		(polygon
			(pts
				(xy 135.36168 -371.097302) (xy 135.36168 -370.09324) (xy 136.758172 -370.09324) (xy 136.758172 -371.097302)
			)
		)
	)
	(zone
		(layer "F.Cu")
		(hatch none 0.5)
		(connect_pads
			(clearance 0)
		)
		(min_thickness 0.25)
		(keepout
			(tracks allowed)
			(vias allowed)
			(pads allowed)
			(copperpour allowed)
			(footprints allowed)
		)
		(placement
			(enabled no)
			(sheetname "")
		)
		(fill
			(thermal_gap 0.5)
			(thermal_bridge_width 0.5)
			(island_removal_mode 0)
		)
		(polygon
			(pts
				(xy 163.634928 -275.278088) (xy 163.634928 -274.947888) (xy 165.296596 -274.947888) (xy 165.296596 -275.278088)
			)
		)
	)
	(zone
		(layer "F.Cu")
		(hatch none 0.5)
		(connect_pads
			(clearance 0)
		)
		(min_thickness 0.25)
		(keepout
			(tracks allowed)
			(vias allowed)
			(pads allowed)
			(copperpour allowed)
			(footprints allowed)
		)
		(placement
			(enabled no)
			(sheetname "")
		)
		(fill
			(thermal_gap 0.5)
			(thermal_bridge_width 0.5)
			(island_removal_mode 0)
		)
		(polygon
			(pts
				(xy 315.76645 -417.424616) (xy 315.76645 -416.420554) (xy 317.162942 -416.420554) (xy 317.162942 -417.424616)
			)
		)
	)
	(zone
		(layer "F.Cu")
		(hatch none 0.5)
		(connect_pads
			(clearance 0)
		)
		(min_thickness 0.25)
		(keepout
			(tracks allowed)
			(vias allowed)
			(pads allowed)
			(copperpour allowed)
			(footprints not_allowed)
		)
		(placement
			(enabled no)
			(sheetname "")
		)
		(fill
			(thermal_gap 0.5)
			(thermal_bridge_width 0.5)
			(island_removal_mode 0)
		)
		(polygon
			(pts
				(xy 326.650096 -398.560036) (xy 326.650096 -403.260052) (xy 331.680058 -403.260052) (xy 331.680058 -398.560036)
			)
		)
	)
	(zone
		(layer "F.Cu")
		(hatch none 0.5)
		(connect_pads
			(clearance 0)
		)
		(min_thickness 0.25)
		(keepout
			(tracks allowed)
			(vias allowed)
			(pads allowed)
			(copperpour allowed)
			(footprints allowed)
		)
		(placement
			(enabled no)
			(sheetname "")
		)
		(fill
			(thermal_gap 0.5)
			(thermal_bridge_width 0.5)
			(island_removal_mode 0)
		)
		(polygon
			(pts
				(xy 308.28488 -209.492596) (xy 308.28488 -209.822796) (xy 305.74488 -209.822796) (xy 305.74488 -209.492596)
			)
		)
	)
	(zone
		(layer "F.Cu")
		(hatch none 0.5)
		(connect_pads
			(clearance 0)
		)
		(min_thickness 0.25)
		(keepout
			(tracks allowed)
			(vias allowed)
			(pads allowed)
			(copperpour allowed)
			(footprints allowed)
		)
		(placement
			(enabled no)
			(sheetname "")
		)
		(fill
			(thermal_gap 0.5)
			(thermal_bridge_width 0.5)
			(island_removal_mode 0)
		)
		(polygon
			(pts
				(xy 411.317694 -224.277682) (xy 411.317694 -223.947482) (xy 413.236664 -223.947482) (xy 413.236664 -224.277682)
			)
		)
	)
	(zone
		(layer "F.Cu")
		(hatch none 0.5)
		(connect_pads
			(clearance 0)
		)
		(min_thickness 0.25)
		(keepout
			(tracks allowed)
			(vias allowed)
			(pads allowed)
			(copperpour allowed)
			(footprints not_allowed)
		)
		(placement
			(enabled no)
			(sheetname "")
		)
		(fill
			(thermal_gap 0.5)
			(thermal_bridge_width 0.5)
			(island_removal_mode 0)
		)
		(polygon
			(pts
				(xy 23.846028 -351.605088) (xy 23.846028 -356.605078) (xy 66.000884 -356.605078) (xy 66.000884 -351.605088)
			)
		)
	)
	(zone
		(layer "F.Cu")
		(hatch none 0.5)
		(connect_pads
			(clearance 0)
		)
		(min_thickness 0.25)
		(keepout
			(tracks allowed)
			(vias allowed)
			(pads allowed)
			(copperpour allowed)
			(footprints not_allowed)
		)
		(placement
			(enabled no)
			(sheetname "")
		)
		(fill
			(thermal_gap 0.5)
			(thermal_bridge_width 0.5)
			(island_removal_mode 0)
		)
		(polygon
			(pts
				(arc
					(start 7.53999 -347.700092)
					(mid 10.340086 -344.899996)
					(end 13.139928 -347.700092)
				)
				(arc
					(start 13.139928 -347.700092)
					(mid 10.340086 -350.499934)
					(end 7.53999 -347.700092)
				)
			)
		)
	)
	(zone
		(layer "F.Cu")
		(hatch none 0.5)
		(connect_pads
			(clearance 0)
		)
		(min_thickness 0.25)
		(keepout
			(tracks allowed)
			(vias allowed)
			(pads allowed)
			(copperpour allowed)
			(footprints not_allowed)
		)
		(placement
			(enabled no)
			(sheetname "")
		)
		(fill
			(thermal_gap 0.5)
			(thermal_bridge_width 0.5)
			(island_removal_mode 0)
		)
		(polygon
			(pts
				(arc
					(start 463.300064 -440.989974)
					(mid 464.007169 -440.697081)
					(end 464.300062 -439.989976)
				)
				(arc
					(start 464.300062 -429.790606)
					(mid 456.265069 -428.01222)
					(end 450.912484 -434.263038)
				)
				(arc
					(start 450.912484 -434.263038)
					(mid 451.300056 -435.599987)
					(end 450.912484 -436.936896)
				)
				(arc
					(start 450.912484 -436.936896)
					(mid 451.608975 -439.105509)
					(end 452.88835 -440.989974)
				)
			)
		)
	)
	(zone
		(layer "F.Cu")
		(hatch none 0.5)
		(connect_pads
			(clearance 0)
		)
		(min_thickness 0.25)
		(keepout
			(tracks allowed)
			(vias allowed)
			(pads allowed)
			(copperpour allowed)
			(footprints allowed)
		)
		(placement
			(enabled no)
			(sheetname "")
		)
		(fill
			(thermal_gap 0.5)
			(thermal_bridge_width 0.5)
			(island_removal_mode 0)
		)
		(polygon
			(pts
				(xy 58.13044 -248.927874) (xy 58.13044 -248.597674) (xy 60.67044 -248.597674) (xy 60.67044 -248.927874)
			)
		)
	)
	(zone
		(layer "F.Cu")
		(hatch none 0.5)
		(connect_pads
			(clearance 0)
		)
		(min_thickness 0.25)
		(keepout
			(tracks allowed)
			(vias allowed)
			(pads allowed)
			(copperpour allowed)
			(footprints allowed)
		)
		(placement
			(enabled no)
			(sheetname "")
		)
		(fill
			(thermal_gap 0.5)
			(thermal_bridge_width 0.5)
			(island_removal_mode 0)
		)
		(polygon
			(pts
				(xy 441.994544 -424.10634) (xy 441.994544 -425.822618) (xy 443.448694 -425.822618) (xy 444.688468 -427.062392)
				(xy 444.688468 -428.224696) (xy 444.381636 -428.531528) (xy 442.227716 -428.531528) (xy 439.920888 -426.2247)
				(xy 439.430668 -425.73448) (xy 439.430668 -423.699686) (xy 439.430668 -421.346122) (xy 440.311286 -420.465504)
				(xy 441.026804 -420.465504) (xy 441.994544 -421.433244)
			)
		)
	)
	(zone
		(layer "F.Cu")
		(hatch none 0.5)
		(connect_pads
			(clearance 0)
		)
		(min_thickness 0.25)
		(keepout
			(tracks not_allowed)
			(vias allowed)
			(pads allowed)
			(copperpour not_allowed)
			(footprints allowed)
		)
		(placement
			(enabled no)
			(sheetname "")
		)
		(fill
			(thermal_gap 0.5)
			(thermal_bridge_width 0.5)
			(island_removal_mode 0)
		)
		(polygon
			(pts
				(arc
					(start 99.899978 -22.29993)
					(mid 94.899988 -27.29992)
					(end 89.899998 -22.29993)
				)
				(arc
					(start 89.899998 -22.29993)
					(mid 94.899988 -17.29994)
					(end 99.899978 -22.29993)
				)
			)
		)
	)
	(zone
		(layer "F.Cu")
		(hatch none 0.5)
		(connect_pads
			(clearance 0)
		)
		(min_thickness 0.25)
		(keepout
			(tracks not_allowed)
			(vias allowed)
			(pads allowed)
			(copperpour not_allowed)
			(footprints allowed)
		)
		(placement
			(enabled no)
			(sheetname "")
		)
		(fill
			(thermal_gap 0.5)
			(thermal_bridge_width 0.5)
			(island_removal_mode 0)
		)
		(polygon
			(pts
				(xy 68.147692 -169.677842) (xy 68.147692 -169.22115) (xy 67.451986 -169.22115) (xy 67.451986 -169.381678)
				(xy 66.893186 -169.381678) (xy 66.893186 -168.975278) (xy 67.451986 -168.975278) (xy 67.451986 -169.19575)
				(xy 68.147692 -169.19575) (xy 68.147692 -169.06875) (xy 67.692016 -169.06875) (xy 67.692016 -168.682162)
				(xy 67.4497 -168.682162) (xy 66.917824 -168.682162) (xy 66.598292 -169.001694) (xy 66.598292 -169.677842)
			)
		)
	)
	(zone
		(layer "F.Cu")
		(hatch none 0.5)
		(connect_pads
			(clearance 0)
		)
		(min_thickness 0.25)
		(keepout
			(tracks allowed)
			(vias allowed)
			(pads allowed)
			(copperpour allowed)
			(footprints not_allowed)
		)
		(placement
			(enabled no)
			(sheetname "")
		)
		(fill
			(thermal_gap 0.5)
			(thermal_bridge_width 0.5)
			(island_removal_mode 0)
		)
		(polygon
			(pts
				(arc
					(start 301.569882 -413.170116)
					(mid 297.56989 -417.170108)
					(end 293.569898 -413.170116)
				)
				(arc
					(start 293.569898 -413.170116)
					(mid 297.56989 -409.170124)
					(end 301.569882 -413.170116)
				)
			)
		)
	)
	(zone
		(layer "F.Cu")
		(hatch none 0.5)
		(connect_pads
			(clearance 0)
		)
		(min_thickness 0.25)
		(keepout
			(tracks allowed)
			(vias allowed)
			(pads allowed)
			(copperpour allowed)
			(footprints allowed)
		)
		(placement
			(enabled no)
			(sheetname "")
		)
		(fill
			(thermal_gap 0.5)
			(thermal_bridge_width 0.5)
			(island_removal_mode 0)
		)
		(polygon
			(pts
				(xy 60.00242 -36.4617) (xy 60.00242 -35.78352) (xy 61.30544 -35.78352) (xy 61.30544 -36.4617)
			)
		)
	)
	(zone
		(layer "F.Cu")
		(hatch none 0.5)
		(connect_pads
			(clearance 0)
		)
		(min_thickness 0.25)
		(keepout
			(tracks not_allowed)
			(vias allowed)
			(pads allowed)
			(copperpour not_allowed)
			(footprints allowed)
		)
		(placement
			(enabled no)
			(sheetname "")
		)
		(fill
			(thermal_gap 0.5)
			(thermal_bridge_width 0.5)
			(island_removal_mode 0)
		)
		(polygon
			(pts
				(arc
					(start 52.525676 -419.64102)
					(mid 51.857656 -419.64102)
					(end 52.525676 -419.64102)
				)
			)
		)
	)
	(zone
		(layer "F.Cu")
		(hatch none 0.5)
		(connect_pads
			(clearance 0)
		)
		(min_thickness 0.25)
		(keepout
			(tracks allowed)
			(vias allowed)
			(pads allowed)
			(copperpour allowed)
			(footprints allowed)
		)
		(placement
			(enabled no)
			(sheetname "")
		)
		(fill
			(thermal_gap 0.5)
			(thermal_bridge_width 0.5)
			(island_removal_mode 0)
		)
		(polygon
			(pts
				(xy 367.932208 -399.742406) (xy 369.738656 -399.742406) (xy 370.027454 -399.453608) (xy 370.027454 -396.634462)
				(xy 370.152422 -396.509494) (xy 389.538464 -396.509494) (xy 389.538464 -399.157952) (xy 389.18896 -399.507456)
				(xy 389.18896 -400.78406) (xy 389.353806 -400.948906) (xy 389.943594 -400.948906) (xy 391.423906 -399.468594)
				(xy 391.423906 -396.558008) (xy 389.19658 -394.330682) (xy 370.013738 -394.330682) (xy 369.399058 -393.716002)
				(xy 369.399058 -393.377166) (xy 369.248436 -393.226544) (xy 368.232436 -393.226544) (xy 367.856008 -393.602972)
				(xy 367.856008 -395.697964) (xy 366.977676 -396.576296) (xy 366.977676 -397.642842) (xy 367.868454 -398.53362)
				(xy 367.868454 -399.678652)
			)
		)
	)
	(zone
		(layer "F.Cu")
		(hatch none 0.5)
		(connect_pads
			(clearance 0)
		)
		(min_thickness 0.25)
		(keepout
			(tracks allowed)
			(vias allowed)
			(pads allowed)
			(copperpour allowed)
			(footprints allowed)
		)
		(placement
			(enabled no)
			(sheetname "")
		)
		(fill
			(thermal_gap 0.5)
			(thermal_bridge_width 0.5)
			(island_removal_mode 0)
		)
		(polygon
			(pts
				(xy 123.099068 -340.806532) (xy 123.099068 -340.384638) (xy 123.21413 -340.384638) (xy 123.21413 -340.806532)
			)
		)
	)
	(zone
		(layer "F.Cu")
		(hatch none 0.5)
		(connect_pads
			(clearance 0)
		)
		(min_thickness 0.25)
		(keepout
			(tracks allowed)
			(vias allowed)
			(pads allowed)
			(copperpour allowed)
			(footprints not_allowed)
		)
		(placement
			(enabled no)
			(sheetname "")
		)
		(fill
			(thermal_gap 0.5)
			(thermal_bridge_width 0.5)
			(island_removal_mode 0)
		)
		(polygon
			(pts
				(arc
					(start 165.1 -160.50006)
					(mid 167.900096 -157.699964)
					(end 170.699938 -160.50006)
				)
				(arc
					(start 170.699938 -160.50006)
					(mid 167.900096 -163.299902)
					(end 165.1 -160.50006)
				)
			)
		)
	)
	(zone
		(layer "F.Cu")
		(hatch none 0.5)
		(connect_pads
			(clearance 0)
		)
		(min_thickness 0.25)
		(keepout
			(tracks allowed)
			(vias allowed)
			(pads allowed)
			(copperpour allowed)
			(footprints not_allowed)
		)
		(placement
			(enabled no)
			(sheetname "")
		)
		(fill
			(thermal_gap 0.5)
			(thermal_bridge_width 0.5)
			(island_removal_mode 0)
		)
		(polygon
			(pts
				(arc
					(start 463.799936 -435.600094)
					(mid 458.799946 -440.600084)
					(end 453.799956 -435.600094)
				)
				(arc
					(start 453.799956 -435.600094)
					(mid 458.799946 -430.600104)
					(end 463.799936 -435.600094)
				)
			)
		)
	)
	(zone
		(layer "F.Cu")
		(hatch none 0.5)
		(connect_pads
			(clearance 0)
		)
		(min_thickness 0.25)
		(keepout
			(tracks allowed)
			(vias allowed)
			(pads allowed)
			(copperpour allowed)
			(footprints allowed)
		)
		(placement
			(enabled no)
			(sheetname "")
		)
		(fill
			(thermal_gap 0.5)
			(thermal_bridge_width 0.5)
			(island_removal_mode 0)
		)
		(polygon
			(pts
				(xy 353.292918 -169.835576) (xy 359.01884 -169.835576) (xy 359.24998 -170.066716) (xy 359.24998 -172.3771)
				(xy 359.94594 -173.07306) (xy 360.4133 -173.07306) (xy 360.58348 -172.90288) (xy 360.58348 -171.54652)
				(xy 360.277918 -171.240958) (xy 360.277918 -169.200576) (xy 360.277918 -164.628576) (xy 359.642918 -163.993576)
				(xy 353.673918 -163.993576) (xy 353.165918 -164.501576) (xy 353.165918 -169.708576)
			)
		)
	)
	(zone
		(layer "F.Cu")
		(hatch none 0.5)
		(connect_pads
			(clearance 0)
		)
		(min_thickness 0.25)
		(keepout
			(tracks allowed)
			(vias allowed)
			(pads allowed)
			(copperpour allowed)
			(footprints not_allowed)
		)
		(placement
			(enabled no)
			(sheetname "")
		)
		(fill
			(thermal_gap 0.5)
			(thermal_bridge_width 0.5)
			(island_removal_mode 0)
		)
		(polygon
			(pts
				(xy 365.300006 -418.869876) (xy 354.24999 -418.869876) (xy 354.24999 -440.989974) (xy 365.300006 -440.989974)
			)
		)
	)
	(zone
		(layer "F.Cu")
		(hatch none 0.5)
		(connect_pads
			(clearance 0)
		)
		(min_thickness 0.25)
		(keepout
			(tracks allowed)
			(vias allowed)
			(pads allowed)
			(copperpour allowed)
			(footprints allowed)
		)
		(placement
			(enabled no)
			(sheetname "")
		)
		(fill
			(thermal_gap 0.5)
			(thermal_bridge_width 0.5)
			(island_removal_mode 0)
		)
		(polygon
			(pts
				(xy 15.316962 -5.169916) (xy 15.316962 -20.04822) (xy 64.939926 -20.04822) (xy 64.939926 -5.169916)
			)
		)
	)
	(zone
		(layer "F.Cu")
		(hatch none 0.5)
		(connect_pads
			(clearance 0)
		)
		(min_thickness 0.25)
		(keepout
			(tracks allowed)
			(vias allowed)
			(pads allowed)
			(copperpour allowed)
			(footprints allowed)
		)
		(placement
			(enabled no)
			(sheetname "")
		)
		(fill
			(thermal_gap 0.5)
			(thermal_bridge_width 0.5)
			(island_removal_mode 0)
		)
		(polygon
			(pts
				(xy 407.372566 -417.424616) (xy 407.372566 -416.420554) (xy 408.769058 -416.420554) (xy 408.769058 -417.424616)
			)
		)
	)
	(zone
		(layer "F.Cu")
		(hatch none 0.5)
		(connect_pads
			(clearance 0)
		)
		(min_thickness 0.25)
		(keepout
			(tracks allowed)
			(vias allowed)
			(pads allowed)
			(copperpour allowed)
			(footprints allowed)
		)
		(placement
			(enabled no)
			(sheetname "")
		)
		(fill
			(thermal_gap 0.5)
			(thermal_bridge_width 0.5)
			(island_removal_mode 0)
		)
		(polygon
			(pts
				(xy 58.13044 -246.377968) (xy 58.13044 -246.047768) (xy 60.67044 -246.047768) (xy 60.67044 -246.377968)
			)
		)
	)
	(zone
		(layer "F.Cu")
		(hatch none 0.5)
		(connect_pads
			(clearance 0)
		)
		(min_thickness 0.25)
		(keepout
			(tracks allowed)
			(vias allowed)
			(pads allowed)
			(copperpour allowed)
			(footprints not_allowed)
		)
		(placement
			(enabled no)
			(sheetname "")
		)
		(fill
			(thermal_gap 0.5)
			(thermal_bridge_width 0.5)
			(island_removal_mode 0)
		)
		(polygon
			(pts
				(arc
					(start 2.999994 -344.518234)
					(mid 18.339672 -347.700092)
					(end 2.999994 -350.88195)
				)
			)
		)
	)
	(zone
		(layer "F.Cu")
		(hatch none 0.5)
		(connect_pads
			(clearance 0)
		)
		(min_thickness 0.25)
		(keepout
			(tracks allowed)
			(vias allowed)
			(pads allowed)
			(copperpour allowed)
			(footprints not_allowed)
		)
		(placement
			(enabled no)
			(sheetname "")
		)
		(fill
			(thermal_gap 0.5)
			(thermal_bridge_width 0.5)
			(island_removal_mode 0)
		)
		(polygon
			(pts
				(arc
					(start 31.070042 -376.489976)
					(mid 35.070034 -372.489984)
					(end 39.070026 -376.489976)
				)
				(arc
					(start 39.070026 -376.489976)
					(mid 35.070034 -380.489968)
					(end 31.070042 -376.489976)
				)
			)
		)
	)
	(zone
		(layer "F.Cu")
		(hatch none 0.5)
		(connect_pads
			(clearance 0)
		)
		(min_thickness 0.25)
		(keepout
			(tracks not_allowed)
			(vias allowed)
			(pads allowed)
			(copperpour not_allowed)
			(footprints allowed)
		)
		(placement
			(enabled no)
			(sheetname "")
		)
		(fill
			(thermal_gap 0.5)
			(thermal_bridge_width 0.5)
			(island_removal_mode 0)
		)
		(polygon
			(pts
				(arc
					(start 184.37098 -66.06794)
					(mid 178.86299 -60.55995)
					(end 173.355 -66.06794)
				)
				(arc
					(start 173.355 -74.767948)
					(mid 178.86299 -80.275938)
					(end 184.37098 -74.767948)
				)
			)
		)
	)
	(zone
		(layer "F.Cu")
		(hatch none 0.5)
		(connect_pads
			(clearance 0)
		)
		(min_thickness 0.25)
		(keepout
			(tracks allowed)
			(vias allowed)
			(pads allowed)
			(copperpour allowed)
			(footprints allowed)
		)
		(placement
			(enabled no)
			(sheetname "")
		)
		(fill
			(thermal_gap 0.5)
			(thermal_bridge_width 0.5)
			(island_removal_mode 0)
		)
		(polygon
			(pts
				(xy 146.30273 -115.186206) (xy 146.30273 -115.894866) (xy 145.784316 -116.41328) (xy 145.08099 -116.41328)
				(xy 145.03019 -116.36248) (xy 145.03019 -115.894866) (xy 145.03019 -115.186206)
			)
		)
	)
	(zone
		(layer "F.Cu")
		(hatch none 0.5)
		(connect_pads
			(clearance 0)
		)
		(min_thickness 0.25)
		(keepout
			(tracks not_allowed)
			(vias allowed)
			(pads allowed)
			(copperpour not_allowed)
			(footprints allowed)
		)
		(placement
			(enabled no)
			(sheetname "")
		)
		(fill
			(thermal_gap 0.5)
			(thermal_bridge_width 0.5)
			(island_removal_mode 0)
		)
		(polygon
			(pts
				(xy 64.308228 -9.094724) (xy 64.425576 -9.094724) (xy 64.476376 -9.043924) (xy 64.476376 -7.596124)
				(xy 64.425576 -7.545324) (xy 64.308228 -7.545324) (xy 64.257428 -7.596124) (xy 64.257428 -9.043924)
			)
		)
	)
	(zone
		(layer "F.Cu")
		(hatch none 0.5)
		(connect_pads
			(clearance 0)
		)
		(min_thickness 0.25)
		(keepout
			(tracks allowed)
			(vias allowed)
			(pads allowed)
			(copperpour allowed)
			(footprints allowed)
		)
		(placement
			(enabled no)
			(sheetname "")
		)
		(fill
			(thermal_gap 0.5)
			(thermal_bridge_width 0.5)
			(island_removal_mode 0)
		)
		(polygon
			(pts
				(xy 306.070508 -208.127854) (xy 306.070508 -207.797654) (xy 308.610508 -207.797654) (xy 308.610508 -208.127854)
			)
		)
	)
	(zone
		(layer "F.Cu")
		(hatch none 0.5)
		(connect_pads
			(clearance 0)
		)
		(min_thickness 0.25)
		(keepout
			(tracks allowed)
			(vias allowed)
			(pads allowed)
			(copperpour allowed)
			(footprints allowed)
		)
		(placement
			(enabled no)
			(sheetname "")
		)
		(fill
			(thermal_gap 0.5)
			(thermal_bridge_width 0.5)
			(island_removal_mode 0)
		)
		(polygon
			(pts
				(xy 171.40682 -31.21152) (xy 177.47996 -31.21152) (xy 181.22392 -34.95548) (xy 181.77002 -34.95548)
				(xy 182.4101 -34.3154) (xy 182.4101 -23.60422) (xy 183.26862 -22.7457) (xy 183.26862 -18.87474)
				(xy 182.49646 -18.10258) (xy 175.68418 -18.10258) (xy 170.96486 -22.8219) (xy 170.96486 -30.76956)
			)
		)
	)
	(zone
		(layer "F.Cu")
		(hatch none 0.5)
		(connect_pads
			(clearance 0)
		)
		(min_thickness 0.25)
		(keepout
			(tracks allowed)
			(vias allowed)
			(pads allowed)
			(copperpour allowed)
			(footprints allowed)
		)
		(placement
			(enabled no)
			(sheetname "")
		)
		(fill
			(thermal_gap 0.5)
			(thermal_bridge_width 0.5)
			(island_removal_mode 0)
		)
		(polygon
			(pts
				(xy 293.860474 -346.376752) (xy 287.510474 -346.376752) (xy 286.875474 -347.011752) (xy 286.875474 -351.583752)
				(xy 287.510474 -352.218752) (xy 293.479474 -352.218752) (xy 293.987474 -351.710752) (xy 293.987474 -346.503752)
			)
		)
	)
	(zone
		(layer "F.Cu")
		(hatch none 0.5)
		(connect_pads
			(clearance 0)
		)
		(min_thickness 0.25)
		(keepout
			(tracks allowed)
			(vias allowed)
			(pads allowed)
			(copperpour allowed)
			(footprints allowed)
		)
		(placement
			(enabled no)
			(sheetname "")
		)
		(fill
			(thermal_gap 0.5)
			(thermal_bridge_width 0.5)
			(island_removal_mode 0)
		)
		(polygon
			(pts
				(xy 151.506936 -194.691) (xy 151.506936 -194.183) (xy 151.702516 -194.183) (xy 151.702516 -194.691)
			)
		)
	)
	(zone
		(layer "F.Cu")
		(hatch none 0.5)
		(connect_pads
			(clearance 0)
		)
		(min_thickness 0.25)
		(keepout
			(tracks allowed)
			(vias allowed)
			(pads allowed)
			(copperpour allowed)
			(footprints allowed)
		)
		(placement
			(enabled no)
			(sheetname "")
		)
		(fill
			(thermal_gap 0.5)
			(thermal_bridge_width 0.5)
			(island_removal_mode 0)
		)
		(polygon
			(pts
				(xy 387.284722 -195.358512) (xy 387.284722 -197.263512) (xy 391.297922 -197.263512) (xy 391.297922 -195.358512)
			)
		)
	)
	(zone
		(layer "F.Cu")
		(hatch none 0.5)
		(connect_pads
			(clearance 0)
		)
		(min_thickness 0.25)
		(keepout
			(tracks allowed)
			(vias allowed)
			(pads allowed)
			(copperpour allowed)
			(footprints not_allowed)
		)
		(placement
			(enabled no)
			(sheetname "")
		)
		(fill
			(thermal_gap 0.5)
			(thermal_bridge_width 0.5)
			(island_removal_mode 0)
		)
		(polygon
			(pts
				(arc
					(start 95.540322 -435.550056)
					(mid 100.540312 -430.550066)
					(end 105.540302 -435.550056)
				)
				(arc
					(start 105.540302 -435.550056)
					(mid 100.540312 -440.550046)
					(end 95.540322 -435.550056)
				)
			)
		)
	)
	(zone
		(layer "F.Cu")
		(hatch none 0.5)
		(connect_pads
			(clearance 0)
		)
		(min_thickness 0.25)
		(keepout
			(tracks allowed)
			(vias allowed)
			(pads allowed)
			(copperpour allowed)
			(footprints not_allowed)
		)
		(placement
			(enabled no)
			(sheetname "")
		)
		(fill
			(thermal_gap 0.5)
			(thermal_bridge_width 0.5)
			(island_removal_mode 0)
		)
		(polygon
			(pts
				(arc
					(start 388.469886 -304.790094)
					(mid 390.469882 -302.790098)
					(end 392.469878 -304.790094)
				)
				(arc
					(start 392.469878 -304.790094)
					(mid 390.469882 -306.79009)
					(end 388.469886 -304.790094)
				)
			)
		)
	)
	(zone
		(layer "F.Cu")
		(hatch none 0.5)
		(connect_pads
			(clearance 0)
		)
		(min_thickness 0.25)
		(keepout
			(tracks allowed)
			(vias allowed)
			(pads allowed)
			(copperpour allowed)
			(footprints not_allowed)
		)
		(placement
			(enabled no)
			(sheetname "")
		)
		(fill
			(thermal_gap 0.5)
			(thermal_bridge_width 0.5)
			(island_removal_mode 0)
		)
		(polygon
			(pts
				(xy 204.453998 -161.282888) (xy 204.456284 -139.282678) (xy 183.456326 -139.280646) (xy 183.45404 -161.280602)
			)
		)
	)
	(zone
		(layer "F.Cu")
		(hatch none 0.5)
		(connect_pads
			(clearance 0)
		)
		(min_thickness 0.25)
		(keepout
			(tracks allowed)
			(vias allowed)
			(pads allowed)
			(copperpour allowed)
			(footprints allowed)
		)
		(placement
			(enabled no)
			(sheetname "")
		)
		(fill
			(thermal_gap 0.5)
			(thermal_bridge_width 0.5)
			(island_removal_mode 0)
		)
		(polygon
			(pts
				(xy 163.621974 -285.477966) (xy 163.621974 -285.147766) (xy 165.296596 -285.147766) (xy 165.296596 -285.477966)
			)
		)
	)
	(zone
		(layer "F.Cu")
		(hatch none 0.5)
		(connect_pads
			(clearance 0)
		)
		(min_thickness 0.25)
		(keepout
			(tracks allowed)
			(vias allowed)
			(pads allowed)
			(copperpour allowed)
			(footprints not_allowed)
		)
		(placement
			(enabled no)
			(sheetname "")
		)
		(fill
			(thermal_gap 0.5)
			(thermal_bridge_width 0.5)
			(island_removal_mode 0)
		)
		(polygon
			(pts
				(xy 423.209974 -29.474922) (xy 423.209974 -43.805094) (xy 432.310032 -43.805094) (xy 432.310032 -29.474922)
			)
		)
	)
	(zone
		(layer "F.Cu")
		(hatch none 0.5)
		(connect_pads
			(clearance 0)
		)
		(min_thickness 0.25)
		(keepout
			(tracks allowed)
			(vias allowed)
			(pads allowed)
			(copperpour allowed)
			(footprints allowed)
		)
		(placement
			(enabled no)
			(sheetname "")
		)
		(fill
			(thermal_gap 0.5)
			(thermal_bridge_width 0.5)
			(island_removal_mode 0)
		)
		(polygon
			(pts
				(xy 114.09426 -184.538112) (xy 114.09426 -186.443112) (xy 118.10746 -186.443112) (xy 118.10746 -184.538112)
			)
		)
	)
	(zone
		(layer "F.Cu")
		(hatch none 0.5)
		(connect_pads
			(clearance 0)
		)
		(min_thickness 0.25)
		(keepout
			(tracks allowed)
			(vias allowed)
			(pads allowed)
			(copperpour allowed)
			(footprints allowed)
		)
		(placement
			(enabled no)
			(sheetname "")
		)
		(fill
			(thermal_gap 0.5)
			(thermal_bridge_width 0.5)
			(island_removal_mode 0)
		)
		(polygon
			(pts
				(xy 54.647338 -376.024902) (xy 54.647338 -375.02084) (xy 56.04383 -375.02084) (xy 56.04383 -376.024902)
			)
		)
	)
	(zone
		(layer "F.Cu")
		(hatch none 0.5)
		(connect_pads
			(clearance 0)
		)
		(min_thickness 0.25)
		(keepout
			(tracks allowed)
			(vias allowed)
			(pads allowed)
			(copperpour allowed)
			(footprints allowed)
		)
		(placement
			(enabled no)
			(sheetname "")
		)
		(fill
			(thermal_gap 0.5)
			(thermal_bridge_width 0.5)
			(island_removal_mode 0)
		)
		(polygon
			(pts
				(xy 306.070508 -268.477746) (xy 306.070508 -268.147546) (xy 308.610508 -268.147546) (xy 308.610508 -268.477746)
			)
		)
	)
	(zone
		(layer "F.Cu")
		(hatch none 0.5)
		(connect_pads
			(clearance 0)
		)
		(min_thickness 0.25)
		(keepout
			(tracks allowed)
			(vias allowed)
			(pads allowed)
			(copperpour allowed)
			(footprints allowed)
		)
		(placement
			(enabled no)
			(sheetname "")
		)
		(fill
			(thermal_gap 0.5)
			(thermal_bridge_width 0.5)
			(island_removal_mode 0)
		)
		(polygon
			(pts
				(xy 130.25628 -373.561102) (xy 130.25628 -372.55704) (xy 131.652772 -372.55704) (xy 131.652772 -373.561102)
			)
		)
	)
	(zone
		(layer "F.Cu")
		(hatch none 0.5)
		(connect_pads
			(clearance 0)
		)
		(min_thickness 0.25)
		(keepout
			(tracks allowed)
			(vias allowed)
			(pads allowed)
			(copperpour allowed)
			(footprints allowed)
		)
		(placement
			(enabled no)
			(sheetname "")
		)
		(fill
			(thermal_gap 0.5)
			(thermal_bridge_width 0.5)
			(island_removal_mode 0)
		)
		(polygon
			(pts
				(xy 146.834352 -57.79516) (xy 146.834352 -56.45658) (xy 147.861782 -56.45658) (xy 147.861782 -57.79516)
			)
		)
	)
	(zone
		(layer "F.Cu")
		(hatch none 0.5)
		(connect_pads
			(clearance 0)
		)
		(min_thickness 0.25)
		(keepout
			(tracks allowed)
			(vias allowed)
			(pads allowed)
			(copperpour allowed)
			(footprints not_allowed)
		)
		(placement
			(enabled no)
			(sheetname "")
		)
		(fill
			(thermal_gap 0.5)
			(thermal_bridge_width 0.5)
			(island_removal_mode 0)
		)
		(polygon
			(pts
				(xy 40.454072 -161.265616) (xy 40.456358 -139.26566) (xy 19.4564 -139.284964) (xy 19.454114 -161.26333)
			)
		)
	)
	(zone
		(layer "F.Cu")
		(hatch none 0.5)
		(connect_pads
			(clearance 0)
		)
		(min_thickness 0.25)
		(keepout
			(tracks allowed)
			(vias allowed)
			(pads allowed)
			(copperpour allowed)
			(footprints not_allowed)
		)
		(placement
			(enabled no)
			(sheetname "")
		)
		(fill
			(thermal_gap 0.5)
			(thermal_bridge_width 0.5)
			(island_removal_mode 0)
		)
		(polygon
			(pts
				(xy 134.765034 -67.429888) (xy 134.765034 -71.900034) (xy 156.835094 -71.900034) (xy 156.835094 -67.429888)
			)
		)
	)
	(zone
		(layer "F.Cu")
		(hatch none 0.5)
		(connect_pads
			(clearance 0)
		)
		(min_thickness 0.25)
		(keepout
			(tracks allowed)
			(vias allowed)
			(pads allowed)
			(copperpour allowed)
			(footprints not_allowed)
		)
		(placement
			(enabled no)
			(sheetname "")
		)
		(fill
			(thermal_gap 0.5)
			(thermal_bridge_width 0.5)
			(island_removal_mode 0)
		)
		(polygon
			(pts
				(xy 417.599876 -440.989974) (xy 417.599876 -417.889944) (xy 377.299982 -417.889944) (xy 377.299982 -440.989974)
				(xy 380.400052 -440.989974) (xy 380.400052 -420.990014) (xy 414.50006 -420.990014) (xy 414.50006 -440.989974)
			)
		)
	)
	(zone
		(layer "F.Cu")
		(hatch none 0.5)
		(connect_pads
			(clearance 0)
		)
		(min_thickness 0.25)
		(keepout
			(tracks allowed)
			(vias allowed)
			(pads allowed)
			(copperpour allowed)
			(footprints not_allowed)
		)
		(placement
			(enabled no)
			(sheetname "")
		)
		(fill
			(thermal_gap 0.5)
			(thermal_bridge_width 0.5)
			(island_removal_mode 0)
		)
		(polygon
			(pts
				(xy 207.294988 -183.50992) (xy 201.095102 -183.50992) (xy 201.095102 -327.609962) (xy 207.294988 -327.609962)
			)
		)
	)
	(zone
		(layer "F.Cu")
		(hatch none 0.5)
		(connect_pads
			(clearance 0)
		)
		(min_thickness 0.25)
		(keepout
			(tracks allowed)
			(vias allowed)
			(pads allowed)
			(copperpour allowed)
			(footprints allowed)
		)
		(placement
			(enabled no)
			(sheetname "")
		)
		(fill
			(thermal_gap 0.5)
			(thermal_bridge_width 0.5)
			(island_removal_mode 0)
		)
		(polygon
			(pts
				(xy 299.187362 -372.40845) (xy 299.609256 -372.40845) (xy 299.609256 -372.523512) (xy 299.187362 -372.523512)
			)
		)
	)
	(zone
		(layer "F.Cu")
		(hatch none 0.5)
		(connect_pads
			(clearance 0)
		)
		(min_thickness 0.25)
		(keepout
			(tracks not_allowed)
			(vias allowed)
			(pads allowed)
			(copperpour not_allowed)
			(footprints allowed)
		)
		(placement
			(enabled no)
			(sheetname "")
		)
		(fill
			(thermal_gap 0.5)
			(thermal_bridge_width 0.5)
			(island_removal_mode 0)
		)
		(polygon
			(pts
				(arc
					(start 432.692048 -66.06794)
					(mid 426.803058 -60.17895)
					(end 420.914068 -66.06794)
				)
				(arc
					(start 420.914068 -74.767948)
					(mid 426.803058 -80.656938)
					(end 432.692048 -74.767948)
				)
			)
		)
	)
	(zone
		(layer "F.Cu")
		(hatch none 0.5)
		(connect_pads
			(clearance 0)
		)
		(min_thickness 0.25)
		(keepout
			(tracks allowed)
			(vias allowed)
			(pads allowed)
			(copperpour allowed)
			(footprints not_allowed)
		)
		(placement
			(enabled no)
			(sheetname "")
		)
		(fill
			(thermal_gap 0.5)
			(thermal_bridge_width 0.5)
			(island_removal_mode 0)
		)
		(polygon
			(pts
				(xy 322.284598 -21.352002) (xy 322.284598 -18.352008)
				(arc
					(start 329.027282 -18.352008)
					(mid 314.036198 -32.839767)
					(end 299.044868 -18.352008)
				)
				(xy 306.28463 -18.352008) (xy 306.28463 -21.352002)
			)
		)
	)
	(zone
		(layer "F.Cu")
		(hatch none 0.5)
		(connect_pads
			(clearance 0)
		)
		(min_thickness 0.25)
		(keepout
			(tracks allowed)
			(vias allowed)
			(pads allowed)
			(copperpour allowed)
			(footprints not_allowed)
		)
		(placement
			(enabled no)
			(sheetname "")
		)
		(fill
			(thermal_gap 0.5)
			(thermal_bridge_width 0.5)
			(island_removal_mode 0)
		)
		(polygon
			(pts
				(xy 419.643052 -158.90494) (xy 429.681894 -158.90494) (xy 429.681894 -167.40505) (xy 419.643052 -167.40505)
			)
		)
	)
	(zone
		(layer "F.Cu")
		(hatch none 0.5)
		(connect_pads
			(clearance 0)
		)
		(min_thickness 0.25)
		(keepout
			(tracks not_allowed)
			(vias allowed)
			(pads allowed)
			(copperpour not_allowed)
			(footprints allowed)
		)
		(placement
			(enabled no)
			(sheetname "")
		)
		(fill
			(thermal_gap 0.5)
			(thermal_bridge_width 0.5)
			(island_removal_mode 0)
		)
		(polygon
			(pts
				(xy 417.0299 -164.51707) (xy 417.0299 -164.060378) (xy 416.334194 -164.060378) (xy 416.334194 -164.220906)
				(xy 415.775394 -164.220906) (xy 415.775394 -163.814506) (xy 416.334194 -163.814506) (xy 416.334194 -164.034978)
				(xy 417.0299 -164.034978) (xy 417.0299 -163.907978) (xy 416.574224 -163.907978) (xy 416.574224 -163.52139)
				(xy 416.331908 -163.52139) (xy 415.800032 -163.52139) (xy 415.4805 -163.840922) (xy 415.4805 -164.51707)
			)
		)
	)
	(zone
		(layer "F.Cu")
		(hatch none 0.5)
		(connect_pads
			(clearance 0)
		)
		(min_thickness 0.25)
		(keepout
			(tracks allowed)
			(vias allowed)
			(pads allowed)
			(copperpour allowed)
			(footprints allowed)
		)
		(placement
			(enabled no)
			(sheetname "")
		)
		(fill
			(thermal_gap 0.5)
			(thermal_bridge_width 0.5)
			(island_removal_mode 0)
		)
		(polygon
			(pts
				(xy 88.916764 -145.161762) (xy 88.916764 -144.59712) (xy 89.47531 -144.59712) (xy 89.47531 -145.161762)
			)
		)
	)
	(zone
		(layer "F.Cu")
		(hatch none 0.5)
		(connect_pads
			(clearance 0)
		)
		(min_thickness 0.25)
		(keepout
			(tracks allowed)
			(vias allowed)
			(pads allowed)
			(copperpour allowed)
			(footprints allowed)
		)
		(placement
			(enabled no)
			(sheetname "")
		)
		(fill
			(thermal_gap 0.5)
			(thermal_bridge_width 0.5)
			(island_removal_mode 0)
		)
		(polygon
			(pts
				(xy 163.377626 -242.977924) (xy 163.377626 -242.647724) (xy 165.296596 -242.647724) (xy 165.296596 -242.977924)
			)
		)
	)
	(zone
		(layer "F.Cu")
		(hatch none 0.5)
		(connect_pads
			(clearance 0)
		)
		(min_thickness 0.25)
		(keepout
			(tracks allowed)
			(vias allowed)
			(pads allowed)
			(copperpour allowed)
			(footprints allowed)
		)
		(placement
			(enabled no)
			(sheetname "")
		)
		(fill
			(thermal_gap 0.5)
			(thermal_bridge_width 0.5)
			(island_removal_mode 0)
		)
		(polygon
			(pts
				(xy 265.878056 -419.16858) (xy 265.878056 -419.903148) (xy 264.240772 -419.903148) (xy 264.240772 -419.16858)
				(xy 264.240772 -417.833048) (xy 265.876278 -417.833048) (xy 265.876278 -419.16858)
			)
		)
	)
	(zone
		(layer "F.Cu")
		(hatch none 0.5)
		(connect_pads
			(clearance 0)
		)
		(min_thickness 0.25)
		(keepout
			(tracks allowed)
			(vias allowed)
			(pads allowed)
			(copperpour allowed)
			(footprints not_allowed)
		)
		(placement
			(enabled no)
			(sheetname "")
		)
		(fill
			(thermal_gap 0.5)
			(thermal_bridge_width 0.5)
			(island_removal_mode 0)
		)
		(polygon
			(pts
				(xy 275.815044 -424.126914) (xy 196.004942 -424.126914) (xy 196.004942 -439.958226) (xy 199.105012 -439.958226)
				(xy 199.105012 -427.232064) (xy 272.714974 -427.232064) (xy 272.714974 -439.958226) (xy 275.815044 -439.958226)
			)
		)
	)
	(zone
		(layer "F.Cu")
		(hatch none 0.5)
		(connect_pads
			(clearance 0)
		)
		(min_thickness 0.25)
		(keepout
			(tracks allowed)
			(vias allowed)
			(pads allowed)
			(copperpour allowed)
			(footprints allowed)
		)
		(placement
			(enabled no)
			(sheetname "")
		)
		(fill
			(thermal_gap 0.5)
			(thermal_bridge_width 0.5)
			(island_removal_mode 0)
		)
		(polygon
			(pts
				(xy 411.574996 -228.527864) (xy 411.574996 -228.197664) (xy 413.236664 -228.197664) (xy 413.236664 -228.527864)
			)
		)
	)
	(zone
		(layer "F.Cu")
		(hatch none 0.5)
		(connect_pads
			(clearance 0)
		)
		(min_thickness 0.25)
		(keepout
			(tracks not_allowed)
			(vias allowed)
			(pads allowed)
			(copperpour not_allowed)
			(footprints allowed)
		)
		(placement
			(enabled no)
			(sheetname "")
		)
		(fill
			(thermal_gap 0.5)
			(thermal_bridge_width 0.5)
			(island_removal_mode 0)
		)
		(polygon
			(pts
				(xy 281.201114 -345.967812) (xy 281.201114 -346.424504) (xy 281.89682 -346.424504) (xy 281.89682 -346.263976)
				(xy 282.45562 -346.263976) (xy 282.45562 -346.670376) (xy 281.89682 -346.670376) (xy 281.89682 -346.449904)
				(xy 281.201114 -346.449904) (xy 281.201114 -346.576904) (xy 281.65679 -346.576904) (xy 281.65679 -346.963492)
				(xy 281.899106 -346.963492) (xy 282.430982 -346.963492) (xy 282.750514 -346.64396) (xy 282.750514 -345.967812)
			)
		)
	)
	(zone
		(layer "F.Cu")
		(hatch none 0.5)
		(connect_pads
			(clearance 0)
		)
		(min_thickness 0.25)
		(keepout
			(tracks allowed)
			(vias allowed)
			(pads allowed)
			(copperpour allowed)
			(footprints allowed)
		)
		(placement
			(enabled no)
			(sheetname "")
		)
		(fill
			(thermal_gap 0.5)
			(thermal_bridge_width 0.5)
			(island_removal_mode 0)
		)
		(polygon
			(pts
				(xy 223.149668 -70.27164) (xy 223.149668 -69.965824) (xy 223.488758 -69.965824) (xy 223.488758 -70.27164)
			)
		)
	)
	(zone
		(layer "F.Cu")
		(hatch none 0.5)
		(connect_pads
			(clearance 0)
		)
		(min_thickness 0.25)
		(keepout
			(tracks allowed)
			(vias allowed)
			(pads allowed)
			(copperpour allowed)
			(footprints not_allowed)
		)
		(placement
			(enabled no)
			(sheetname "")
		)
		(fill
			(thermal_gap 0.5)
			(thermal_bridge_width 0.5)
			(island_removal_mode 0)
		)
		(polygon
			(pts
				(arc
					(start 417.051998 -351.415096)
					(mid 413.952182 -354.514912)
					(end 410.852112 -351.415096)
				)
				(arc
					(start 410.852112 -351.415096)
					(mid 413.952182 -348.315026)
					(end 417.051998 -351.415096)
				)
			)
		)
	)
	(zone
		(layer "F.Cu")
		(hatch none 0.5)
		(connect_pads
			(clearance 0)
		)
		(min_thickness 0.25)
		(keepout
			(tracks allowed)
			(vias allowed)
			(pads allowed)
			(copperpour allowed)
			(footprints allowed)
		)
		(placement
			(enabled no)
			(sheetname "")
		)
		(fill
			(thermal_gap 0.5)
			(thermal_bridge_width 0.5)
			(island_removal_mode 0)
		)
		(polygon
			(pts
				(xy 89.573862 -335.483708) (xy 87.770462 -335.483708) (xy 87.770462 -337.033108) (xy 89.573862 -337.033108)
			)
		)
	)
	(zone
		(layer "F.Cu")
		(hatch none 0.5)
		(connect_pads
			(clearance 0)
		)
		(min_thickness 0.25)
		(keepout
			(tracks allowed)
			(vias allowed)
			(pads allowed)
			(copperpour allowed)
			(footprints not_allowed)
		)
		(placement
			(enabled no)
			(sheetname "")
		)
		(fill
			(thermal_gap 0.5)
			(thermal_bridge_width 0.5)
			(island_removal_mode 0)
		)
		(polygon
			(pts
				(xy 168.706038 -357.145082) (xy 176.376076 -357.145082) (xy 176.376076 -347.544898) (xy 168.706038 -347.544898)
			)
		)
	)
	(zone
		(layer "F.Cu")
		(hatch none 0.5)
		(connect_pads
			(clearance 0)
		)
		(min_thickness 0.25)
		(keepout
			(tracks allowed)
			(vias allowed)
			(pads allowed)
			(copperpour allowed)
			(footprints allowed)
		)
		(placement
			(enabled no)
			(sheetname "")
		)
		(fill
			(thermal_gap 0.5)
			(thermal_bridge_width 0.5)
			(island_removal_mode 0)
		)
		(polygon
			(pts
				(xy 181.862476 -166.179754) (xy 181.862476 -165.090856) (xy 184.25033 -165.090856) (xy 184.25033 -166.179754)
			)
		)
	)
	(zone
		(layer "F.Cu")
		(hatch none 0.5)
		(connect_pads
			(clearance 0)
		)
		(min_thickness 0.25)
		(keepout
			(tracks allowed)
			(vias allowed)
			(pads allowed)
			(copperpour allowed)
			(footprints not_allowed)
		)
		(placement
			(enabled no)
			(sheetname "")
		)
		(fill
			(thermal_gap 0.5)
			(thermal_bridge_width 0.5)
			(island_removal_mode 0)
		)
		(polygon
			(pts
				(arc
					(start 168.74998 -404.789894)
					(mid 171.000166 -402.539708)
					(end 173.250098 -404.789894)
				)
				(arc
					(start 173.250098 -404.789894)
					(mid 171.000166 -407.039826)
					(end 168.74998 -404.789894)
				)
			)
		)
	)
	(zone
		(layer "F.Cu")
		(hatch none 0.5)
		(connect_pads
			(clearance 0)
		)
		(min_thickness 0.25)
		(keepout
			(tracks allowed)
			(vias allowed)
			(pads allowed)
			(copperpour allowed)
			(footprints not_allowed)
		)
		(placement
			(enabled no)
			(sheetname "")
		)
		(fill
			(thermal_gap 0.5)
			(thermal_bridge_width 0.5)
			(island_removal_mode 0)
		)
		(polygon
			(pts
				(xy 189.361826 -87.281258) (xy 189.36462 -59.981084) (xy 168.364662 -59.979052) (xy 168.361868 -87.278972)
			)
		)
	)
	(zone
		(layer "F.Cu")
		(hatch none 0.5)
		(connect_pads
			(clearance 0)
		)
		(min_thickness 0.25)
		(keepout
			(tracks allowed)
			(vias allowed)
			(pads allowed)
			(copperpour allowed)
			(footprints allowed)
		)
		(placement
			(enabled no)
			(sheetname "")
		)
		(fill
			(thermal_gap 0.5)
			(thermal_bridge_width 0.5)
			(island_removal_mode 0)
		)
		(polygon
			(pts
				(xy 116.64188 -373.561102) (xy 116.64188 -372.55704) (xy 118.038372 -372.55704) (xy 118.038372 -373.561102)
			)
		)
	)
	(zone
		(layer "F.Cu")
		(hatch none 0.5)
		(connect_pads
			(clearance 0)
		)
		(min_thickness 0.25)
		(keepout
			(tracks allowed)
			(vias allowed)
			(pads allowed)
			(copperpour allowed)
			(footprints allowed)
		)
		(placement
			(enabled no)
			(sheetname "")
		)
		(fill
			(thermal_gap 0.5)
			(thermal_bridge_width 0.5)
			(island_removal_mode 0)
		)
		(polygon
			(pts
				(xy 346.578428 -379.479302) (xy 346.578428 -378.47524) (xy 347.97492 -378.47524) (xy 347.97492 -379.479302)
			)
		)
	)
	(zone
		(layer "F.Cu")
		(hatch none 0.5)
		(connect_pads
			(clearance 0)
		)
		(min_thickness 0.25)
		(keepout
			(tracks allowed)
			(vias allowed)
			(pads allowed)
			(copperpour allowed)
			(footprints allowed)
		)
		(placement
			(enabled no)
			(sheetname "")
		)
		(fill
			(thermal_gap 0.5)
			(thermal_bridge_width 0.5)
			(island_removal_mode 0)
		)
		(polygon
			(pts
				(xy 311.073038 -357.033068) (xy 311.073038 -355.690678) (xy 311.970166 -355.690678) (xy 311.970166 -357.033068)
			)
		)
	)
	(zone
		(layer "F.Cu")
		(hatch none 0.5)
		(connect_pads
			(clearance 0)
		)
		(min_thickness 0.25)
		(keepout
			(tracks allowed)
			(vias allowed)
			(pads allowed)
			(copperpour allowed)
			(footprints not_allowed)
		)
		(placement
			(enabled no)
			(sheetname "")
		)
		(fill
			(thermal_gap 0.5)
			(thermal_bridge_width 0.5)
			(island_removal_mode 0)
		)
		(polygon
			(pts
				(arc
					(start 361.362498 -431.360072)
					(mid 359.774998 -432.947572)
					(end 358.187498 -431.360072)
				)
				(arc
					(start 358.187498 -431.360072)
					(mid 359.774998 -429.772572)
					(end 361.362498 -431.360072)
				)
			)
		)
	)
	(zone
		(layer "F.Cu")
		(hatch none 0.5)
		(connect_pads
			(clearance 0)
		)
		(min_thickness 0.25)
		(keepout
			(tracks not_allowed)
			(vias allowed)
			(pads allowed)
			(copperpour not_allowed)
			(footprints allowed)
		)
		(placement
			(enabled no)
			(sheetname "")
		)
		(fill
			(thermal_gap 0.5)
			(thermal_bridge_width 0.5)
			(island_removal_mode 0)
		)
		(polygon
			(pts
				(arc
					(start 78.529942 -304.790094)
					(mid 81.330038 -301.989998)
					(end 84.12988 -304.790094)
				)
				(arc
					(start 84.12988 -304.790094)
					(mid 81.330038 -307.589936)
					(end 78.529942 -304.790094)
				)
			)
		)
	)
	(zone
		(layer "F.Cu")
		(hatch none 0.5)
		(connect_pads
			(clearance 0)
		)
		(min_thickness 0.25)
		(keepout
			(tracks allowed)
			(vias allowed)
			(pads allowed)
			(copperpour allowed)
			(footprints allowed)
		)
		(placement
			(enabled no)
			(sheetname "")
		)
		(fill
			(thermal_gap 0.5)
			(thermal_bridge_width 0.5)
			(island_removal_mode 0)
		)
		(polygon
			(pts
				(xy 306.070508 -233.627676) (xy 306.070508 -233.297476) (xy 308.610508 -233.297476) (xy 308.610508 -233.627676)
			)
		)
	)
	(zone
		(layer "F.Cu")
		(hatch none 0.5)
		(connect_pads
			(clearance 0)
		)
		(min_thickness 0.25)
		(keepout
			(tracks not_allowed)
			(vias allowed)
			(pads allowed)
			(copperpour not_allowed)
			(footprints allowed)
		)
		(placement
			(enabled no)
			(sheetname "")
		)
		(fill
			(thermal_gap 0.5)
			(thermal_bridge_width 0.5)
			(island_removal_mode 0)
		)
		(polygon
			(pts
				(arc
					(start 94.383098 -43.850052)
					(mid 97.583244 -47.050198)
					(end 94.383098 -50.25009)
				)
				(arc
					(start 92.782898 -50.25009)
					(mid 89.583006 -47.050198)
					(end 92.782898 -43.850052)
				)
			)
		)
	)
	(zone
		(layer "F.Cu")
		(hatch none 0.5)
		(connect_pads
			(clearance 0)
		)
		(min_thickness 0.25)
		(keepout
			(tracks allowed)
			(vias allowed)
			(pads allowed)
			(copperpour allowed)
			(footprints not_allowed)
		)
		(placement
			(enabled no)
			(sheetname "")
		)
		(fill
			(thermal_gap 0.5)
			(thermal_bridge_width 0.5)
			(island_removal_mode 0)
		)
		(polygon
			(pts
				(arc
					(start 291.349938 -46.150022)
					(mid 281.399996 -55.150091)
					(end 271.450054 -46.150022)
				)
			)
		)
	)
	(zone
		(layer "F.Cu")
		(hatch none 0.5)
		(connect_pads
			(clearance 0)
		)
		(min_thickness 0.25)
		(keepout
			(tracks allowed)
			(vias allowed)
			(pads allowed)
			(copperpour allowed)
			(footprints allowed)
		)
		(placement
			(enabled no)
			(sheetname "")
		)
		(fill
			(thermal_gap 0.5)
			(thermal_bridge_width 0.5)
			(island_removal_mode 0)
		)
		(polygon
			(pts
				(xy 152.03678 -118.46814) (xy 152.03678 -117.08892) (xy 154.90698 -117.08892) (xy 154.90698 -118.46814)
			)
		)
	)
	(zone
		(layer "F.Cu")
		(hatch none 0.5)
		(connect_pads
			(clearance 0)
		)
		(min_thickness 0.25)
		(keepout
			(tracks allowed)
			(vias allowed)
			(pads allowed)
			(copperpour allowed)
			(footprints not_allowed)
		)
		(placement
			(enabled no)
			(sheetname "")
		)
		(fill
			(thermal_gap 0.5)
			(thermal_bridge_width 0.5)
			(island_removal_mode 0)
		)
		(polygon
			(pts
				(xy 422.710102 -44.60494) (xy 432.809904 -44.60494) (xy 432.809904 -28.675076) (xy 422.710102 -28.675076)
			)
		)
	)
	(zone
		(layer "F.Cu")
		(hatch none 0.5)
		(connect_pads
			(clearance 0)
		)
		(min_thickness 0.25)
		(keepout
			(tracks allowed)
			(vias allowed)
			(pads allowed)
			(copperpour allowed)
			(footprints allowed)
		)
		(placement
			(enabled no)
			(sheetname "")
		)
		(fill
			(thermal_gap 0.5)
			(thermal_bridge_width 0.5)
			(island_removal_mode 0)
		)
		(polygon
			(pts
				(xy 147.919186 -224.741232) (xy 144.657318 -224.741232) (xy 143.499586 -225.898964) (xy 143.499586 -259.782564)
				(xy 144.794986 -261.077964) (xy 144.794986 -261.230364) (xy 144.617186 -261.408164) (xy 144.464786 -261.408164)
				(xy 143.804386 -262.068564) (xy 143.804386 -292.192964) (xy 145.150586 -293.539164) (xy 147.632166 -293.539164)
				(xy 147.919186 -293.252144)
			)
		)
	)
	(zone
		(layer "F.Cu")
		(hatch none 0.5)
		(connect_pads
			(clearance 0)
		)
		(min_thickness 0.25)
		(keepout
			(tracks not_allowed)
			(vias allowed)
			(pads allowed)
			(copperpour not_allowed)
			(footprints allowed)
		)
		(placement
			(enabled no)
			(sheetname "")
		)
		(fill
			(thermal_gap 0.5)
			(thermal_bridge_width 0.5)
			(island_removal_mode 0)
		)
		(polygon
			(pts
				(xy 85.077808 -335.678526) (xy 85.077808 -336.639408) (xy 85.320124 -336.639408) (xy 85.320124 -335.678526)
			)
		)
	)
	(zone
		(layer "F.Cu")
		(hatch none 0.5)
		(connect_pads
			(clearance 0)
		)
		(min_thickness 0.25)
		(keepout
			(tracks allowed)
			(vias allowed)
			(pads allowed)
			(copperpour allowed)
			(footprints allowed)
		)
		(placement
			(enabled no)
			(sheetname "")
		)
		(fill
			(thermal_gap 0.5)
			(thermal_bridge_width 0.5)
			(island_removal_mode 0)
		)
		(polygon
			(pts
				(xy 42.44213 -381.225044) (xy 43.446192 -381.225044) (xy 43.446192 -382.621536) (xy 42.44213 -382.621536)
			)
		)
	)
	(zone
		(layer "F.Cu")
		(hatch none 0.5)
		(connect_pads
			(clearance 0)
		)
		(min_thickness 0.25)
		(keepout
			(tracks allowed)
			(vias allowed)
			(pads allowed)
			(copperpour allowed)
			(footprints allowed)
		)
		(placement
			(enabled no)
			(sheetname "")
		)
		(fill
			(thermal_gap 0.5)
			(thermal_bridge_width 0.5)
			(island_removal_mode 0)
		)
		(polygon
			(pts
				(xy 471.728038 -426.061632) (xy 470.953338 -426.061632) (xy 470.864438 -425.972732) (xy 470.864438 -425.225972)
				(xy 470.955878 -425.134532) (xy 471.639138 -425.134532) (xy 471.829638 -425.325032) (xy 471.829638 -425.960032)
			)
		)
	)
	(zone
		(layer "F.Cu")
		(hatch none 0.5)
		(connect_pads
			(clearance 0)
		)
		(min_thickness 0.25)
		(keepout
			(tracks allowed)
			(vias allowed)
			(pads allowed)
			(copperpour allowed)
			(footprints not_allowed)
		)
		(placement
			(enabled no)
			(sheetname "")
		)
		(fill
			(thermal_gap 0.5)
			(thermal_bridge_width 0.5)
			(island_removal_mode 0)
		)
		(polygon
			(pts
				(xy 365.300006 -418.869876) (xy 354.24999 -418.869876) (xy 354.24999 -440.989974) (xy 350.499934 -440.989974)
				(xy 350.499934 -417.889944) (xy 325.071232 -417.889944) (xy 325.071232 -415.170112) (xy 399.49882 -415.170112)
				(xy 399.49882 -417.889944) (xy 377.299982 -417.889944)
				(arc
					(start 377.299982 -430.310036)
					(mid 371.300707 -427.600106)
					(end 365.300006 -430.306988)
				)
			)
		)
	)
	(zone
		(layer "F.Cu")
		(hatch none 0.5)
		(connect_pads
			(clearance 0)
		)
		(min_thickness 0.25)
		(keepout
			(tracks allowed)
			(vias allowed)
			(pads allowed)
			(copperpour allowed)
			(footprints allowed)
		)
		(placement
			(enabled no)
			(sheetname "")
		)
		(fill
			(thermal_gap 0.5)
			(thermal_bridge_width 0.5)
			(island_removal_mode 0)
		)
		(polygon
			(pts
				(xy 10.794746 -135.489696) (xy 10.794746 -133.933946) (xy 11.930634 -133.933946) (xy 11.930634 -135.489696)
			)
		)
	)
	(zone
		(layer "F.Cu")
		(hatch none 0.5)
		(connect_pads
			(clearance 0)
		)
		(min_thickness 0.25)
		(keepout
			(tracks not_allowed)
			(vias allowed)
			(pads allowed)
			(copperpour not_allowed)
			(footprints allowed)
		)
		(placement
			(enabled no)
			(sheetname "")
		)
		(fill
			(thermal_gap 0.5)
			(thermal_bridge_width 0.5)
			(island_removal_mode 0)
		)
		(polygon
			(pts
				(arc
					(start 295.319958 -413.170116)
					(mid 297.570144 -410.91993)
					(end 299.820076 -413.170116)
				)
				(arc
					(start 299.820076 -413.170116)
					(mid 297.570144 -415.420048)
					(end 295.319958 -413.170116)
				)
			)
		)
	)
	(zone
		(layer "F.Cu")
		(hatch none 0.5)
		(connect_pads
			(clearance 0)
		)
		(min_thickness 0.25)
		(keepout
			(tracks allowed)
			(vias allowed)
			(pads allowed)
			(copperpour allowed)
			(footprints allowed)
		)
		(placement
			(enabled no)
			(sheetname "")
		)
		(fill
			(thermal_gap 0.5)
			(thermal_bridge_width 0.5)
			(island_removal_mode 0)
		)
		(polygon
			(pts
				(xy 68.261738 -371.097302) (xy 68.261738 -370.09324) (xy 69.65823 -370.09324) (xy 69.65823 -371.097302)
			)
		)
	)
	(zone
		(layer "F.Cu")
		(hatch none 0.5)
		(connect_pads
			(clearance 0)
		)
		(min_thickness 0.25)
		(keepout
			(tracks allowed)
			(vias allowed)
			(pads allowed)
			(copperpour allowed)
			(footprints allowed)
		)
		(placement
			(enabled no)
			(sheetname "")
		)
		(fill
			(thermal_gap 0.5)
			(thermal_bridge_width 0.5)
			(island_removal_mode 0)
		)
		(polygon
			(pts
				(xy 60.725812 -292.792658) (xy 60.725812 -293.122858) (xy 58.185812 -293.122858) (xy 58.185812 -292.792658)
			)
		)
	)
	(zone
		(layer "F.Cu")
		(hatch none 0.5)
		(connect_pads
			(clearance 0)
		)
		(min_thickness 0.25)
		(keepout
			(tracks allowed)
			(vias allowed)
			(pads allowed)
			(copperpour allowed)
			(footprints not_allowed)
		)
		(placement
			(enabled no)
			(sheetname "")
		)
		(fill
			(thermal_gap 0.5)
			(thermal_bridge_width 0.5)
			(island_removal_mode 0)
		)
		(polygon
			(pts
				(arc
					(start 351.151952 -147.904962)
					(mid 348.052136 -151.004778)
					(end 344.952066 -147.904962)
				)
				(arc
					(start 344.952066 -147.904962)
					(mid 348.052136 -144.804892)
					(end 351.151952 -147.904962)
				)
			)
		)
	)
	(zone
		(layer "F.Cu")
		(hatch none 0.5)
		(connect_pads
			(clearance 0)
		)
		(min_thickness 0.25)
		(keepout
			(tracks allowed)
			(vias allowed)
			(pads allowed)
			(copperpour allowed)
			(footprints not_allowed)
		)
		(placement
			(enabled no)
			(sheetname "")
		)
		(fill
			(thermal_gap 0.5)
			(thermal_bridge_width 0.5)
			(island_removal_mode 0)
		)
		(polygon
			(pts
				(xy 285.471108 -390.369806) (xy 285.471108 -379.369828) (xy 295.28516 -379.369828) (xy 295.28516 -376.169936)
				(xy 429.284892 -376.169936) (xy 429.284892 -379.369828) (xy 439.498994 -379.369828) (xy 439.498994 -390.369806)
				(xy 429.284892 -390.369806) (xy 429.284892 -407.67) (xy 432.99888 -407.67) (xy 432.99888 -418.669978)
				(xy 417.599876 -418.669978) (xy 417.599876 -417.889944) (xy 399.49882 -417.889944) (xy 399.49882 -415.170112)
				(xy 325.071232 -415.170112) (xy 325.071232 -417.889944) (xy 310.20004 -417.889944) (xy 310.20004 -418.669978)
				(xy 291.571172 -418.669978) (xy 291.571172 -407.67) (xy 295.28516 -407.67) (xy 295.28516 -390.369806)
			)
		)
	)
	(zone
		(layer "F.Cu")
		(hatch none 0.5)
		(connect_pads
			(clearance 0)
		)
		(min_thickness 0.25)
		(keepout
			(tracks allowed)
			(vias allowed)
			(pads allowed)
			(copperpour allowed)
			(footprints allowed)
		)
		(placement
			(enabled no)
			(sheetname "")
		)
		(fill
			(thermal_gap 0.5)
			(thermal_bridge_width 0.5)
			(island_removal_mode 0)
		)
		(polygon
			(pts
				(xy 197.13194 -39.34206) (xy 197.13194 -37.0586) (xy 199.18172 -37.0586) (xy 199.18172 -39.34206)
			)
		)
	)
	(zone
		(layer "F.Cu")
		(hatch none 0.5)
		(connect_pads
			(clearance 0)
		)
		(min_thickness 0.25)
		(keepout
			(tracks allowed)
			(vias allowed)
			(pads allowed)
			(copperpour allowed)
			(footprints allowed)
		)
		(placement
			(enabled no)
			(sheetname "")
		)
		(fill
			(thermal_gap 0.5)
			(thermal_bridge_width 0.5)
			(island_removal_mode 0)
		)
		(polygon
			(pts
				(xy 308.66588 -292.792404) (xy 308.66588 -293.122604) (xy 306.12588 -293.122604) (xy 306.12588 -292.792404)
			)
		)
	)
	(zone
		(layer "F.Cu")
		(hatch none 0.5)
		(connect_pads
			(clearance 0)
		)
		(min_thickness 0.25)
		(keepout
			(tracks allowed)
			(vias allowed)
			(pads allowed)
			(copperpour allowed)
			(footprints allowed)
		)
		(placement
			(enabled no)
			(sheetname "")
		)
		(fill
			(thermal_gap 0.5)
			(thermal_bridge_width 0.5)
			(island_removal_mode 0)
		)
		(polygon
			(pts
				(xy 122.316748 -177.807112) (xy 122.316748 -179.712112) (xy 126.329948 -179.712112) (xy 126.329948 -177.807112)
			)
		)
	)
	(zone
		(layer "F.Cu")
		(hatch none 0.5)
		(connect_pads
			(clearance 0)
		)
		(min_thickness 0.25)
		(keepout
			(tracks allowed)
			(vias allowed)
			(pads allowed)
			(copperpour allowed)
			(footprints allowed)
		)
		(placement
			(enabled no)
			(sheetname "")
		)
		(fill
			(thermal_gap 0.5)
			(thermal_bridge_width 0.5)
			(island_removal_mode 0)
		)
		(polygon
			(pts
				(xy 411.574996 -219.17787) (xy 411.574996 -218.84767) (xy 413.236664 -218.84767) (xy 413.236664 -219.17787)
			)
		)
	)
	(zone
		(layer "F.Cu")
		(hatch none 0.5)
		(connect_pads
			(clearance 0)
		)
		(min_thickness 0.25)
		(keepout
			(tracks allowed)
			(vias allowed)
			(pads allowed)
			(copperpour allowed)
			(footprints not_allowed)
		)
		(placement
			(enabled no)
			(sheetname "")
		)
		(fill
			(thermal_gap 0.5)
			(thermal_bridge_width 0.5)
			(island_removal_mode 0)
		)
		(polygon
			(pts
				(xy 162.228022 -329.060048) (xy 208.447894 -329.060048) (xy 208.447894 -182.060088) (xy 162.228022 -182.060088)
			)
		)
	)
	(zone
		(layer "F.Cu")
		(hatch none 0.5)
		(connect_pads
			(clearance 0)
		)
		(min_thickness 0.25)
		(keepout
			(tracks allowed)
			(vias allowed)
			(pads allowed)
			(copperpour allowed)
			(footprints allowed)
		)
		(placement
			(enabled no)
			(sheetname "")
		)
		(fill
			(thermal_gap 0.5)
			(thermal_bridge_width 0.5)
			(island_removal_mode 0)
		)
		(polygon
			(pts
				(xy 447.368168 -419.845236) (xy 447.368168 -420.725346) (xy 448.111626 -421.468804) (xy 449.390008 -422.747186)
				(xy 449.390008 -427.121574) (xy 448.87896 -427.632622) (xy 447.98488 -427.632622) (xy 447.1924 -426.840142)
				(xy 447.1924 -426.06087) (xy 446.655952 -425.524422) (xy 446.655952 -423.410126) (xy 446.66789 -423.398188)
				(xy 446.66789 -421.63873) (xy 444.843154 -421.63873) (xy 442.463428 -421.63873) (xy 441.020962 -420.196264)
				(xy 440.61253 -420.196264) (xy 440.357006 -419.94074) (xy 440.357006 -419.557454) (xy 440.523122 -419.391338)
				(xy 444.24092 -419.391338) (xy 444.694818 -419.845236)
			)
		)
	)
	(zone
		(layer "F.Cu")
		(hatch none 0.5)
		(connect_pads
			(clearance 0)
		)
		(min_thickness 0.25)
		(keepout
			(tracks allowed)
			(vias allowed)
			(pads allowed)
			(copperpour allowed)
			(footprints allowed)
		)
		(placement
			(enabled no)
			(sheetname "")
		)
		(fill
			(thermal_gap 0.5)
			(thermal_bridge_width 0.5)
			(island_removal_mode 0)
		)
		(polygon
			(pts
				(xy 303.51349 -417.424616) (xy 303.51349 -416.420554) (xy 304.909982 -416.420554) (xy 304.909982 -417.424616)
			)
		)
	)
	(zone
		(layer "F.Cu")
		(hatch none 0.5)
		(connect_pads
			(clearance 0)
		)
		(min_thickness 0.25)
		(keepout
			(tracks not_allowed)
			(vias allowed)
			(pads allowed)
			(copperpour not_allowed)
			(footprints allowed)
		)
		(placement
			(enabled no)
			(sheetname "")
		)
		(fill
			(thermal_gap 0.5)
			(thermal_bridge_width 0.5)
			(island_removal_mode 0)
		)
		(polygon
			(pts
				(arc
					(start 388.469886 -304.790094)
					(mid 390.469882 -302.790098)
					(end 392.469878 -304.790094)
				)
				(arc
					(start 392.469878 -304.790094)
					(mid 390.469882 -306.79009)
					(end 388.469886 -304.790094)
				)
			)
		)
	)
	(zone
		(layer "F.Cu")
		(hatch none 0.5)
		(connect_pads
			(clearance 0)
		)
		(min_thickness 0.25)
		(keepout
			(tracks allowed)
			(vias allowed)
			(pads allowed)
			(copperpour allowed)
			(footprints allowed)
		)
		(placement
			(enabled no)
			(sheetname "")
		)
		(fill
			(thermal_gap 0.5)
			(thermal_bridge_width 0.5)
			(island_removal_mode 0)
		)
		(polygon
			(pts
				(xy 301.928022 -347.221556) (xy 300.124622 -347.221556) (xy 300.124622 -348.770956) (xy 301.928022 -348.770956)
			)
		)
	)
	(zone
		(layer "F.Cu")
		(hatch none 0.5)
		(connect_pads
			(clearance 0)
		)
		(min_thickness 0.25)
		(keepout
			(tracks allowed)
			(vias allowed)
			(pads allowed)
			(copperpour allowed)
			(footprints allowed)
		)
		(placement
			(enabled no)
			(sheetname "")
		)
		(fill
			(thermal_gap 0.5)
			(thermal_bridge_width 0.5)
			(island_removal_mode 0)
		)
		(polygon
			(pts
				(xy 175.495966 -31.100014) (xy 175.495966 -29.896562) (xy 176.360328 -29.896562) (xy 176.360328 -31.100014)
			)
		)
	)
	(zone
		(layer "F.Cu")
		(hatch none 0.5)
		(connect_pads
			(clearance 0)
		)
		(min_thickness 0.25)
		(keepout
			(tracks allowed)
			(vias allowed)
			(pads allowed)
			(copperpour allowed)
			(footprints allowed)
		)
		(placement
			(enabled no)
			(sheetname "")
		)
		(fill
			(thermal_gap 0.5)
			(thermal_bridge_width 0.5)
			(island_removal_mode 0)
		)
		(polygon
			(pts
				(xy 411.317694 -300.77791) (xy 411.317694 -300.44771) (xy 413.236664 -300.44771) (xy 413.236664 -300.77791)
			)
		)
	)
	(zone
		(layer "F.Cu")
		(hatch none 0.5)
		(connect_pads
			(clearance 0)
		)
		(min_thickness 0.25)
		(keepout
			(tracks allowed)
			(vias allowed)
			(pads allowed)
			(copperpour allowed)
			(footprints allowed)
		)
		(placement
			(enabled no)
			(sheetname "")
		)
		(fill
			(thermal_gap 0.5)
			(thermal_bridge_width 0.5)
			(island_removal_mode 0)
		)
		(polygon
			(pts
				(xy 389.816848 -5.169916) (xy 389.816848 -20.04822) (xy 439.439812 -20.04822) (xy 439.439812 -5.169916)
			)
		)
	)
	(zone
		(layer "F.Cu")
		(hatch none 0.5)
		(connect_pads
			(clearance 0)
		)
		(min_thickness 0.25)
		(keepout
			(tracks allowed)
			(vias allowed)
			(pads allowed)
			(copperpour allowed)
			(footprints allowed)
		)
		(placement
			(enabled no)
			(sheetname "")
		)
		(fill
			(thermal_gap 0.5)
			(thermal_bridge_width 0.5)
			(island_removal_mode 0)
		)
		(polygon
			(pts
				(xy 163.377626 -292.278308) (xy 163.377626 -291.948108) (xy 165.296596 -291.948108) (xy 165.296596 -292.278308)
			)
		)
	)
	(zone
		(layer "F.Cu")
		(hatch none 0.5)
		(connect_pads
			(clearance 0)
		)
		(min_thickness 0.25)
		(keepout
			(tracks allowed)
			(vias allowed)
			(pads allowed)
			(copperpour allowed)
			(footprints not_allowed)
		)
		(placement
			(enabled no)
			(sheetname "")
		)
		(fill
			(thermal_gap 0.5)
			(thermal_bridge_width 0.5)
			(island_removal_mode 0)
		)
		(polygon
			(pts
				(xy 91.400122 -440.889898) (xy 91.400122 -420.990014) (xy 74.399902 -420.990014) (xy 74.399902 -413.789876)
				(xy 57.300114 -413.789876) (xy 57.300114 -440.989974) (xy 54.200044 -440.989974) (xy 54.200044 -410.69006)
				(xy 77.499972 -410.69006) (xy 77.499972 -417.889944) (xy 94.499938 -417.889944) (xy 94.499938 -440.989974)
			)
		)
	)
	(zone
		(layer "F.Cu")
		(hatch none 0.5)
		(connect_pads
			(clearance 0)
		)
		(min_thickness 0.25)
		(keepout
			(tracks not_allowed)
			(vias allowed)
			(pads allowed)
			(copperpour not_allowed)
			(footprints allowed)
		)
		(placement
			(enabled no)
			(sheetname "")
		)
		(fill
			(thermal_gap 0.5)
			(thermal_bridge_width 0.5)
			(island_removal_mode 0)
		)
		(polygon
			(pts
				(xy 126.010416 -164.492432) (xy 126.010416 -163.53155) (xy 125.7681 -163.53155) (xy 125.7681 -164.492432)
			)
		)
	)
	(zone
		(layer "F.Cu")
		(hatch none 0.5)
		(connect_pads
			(clearance 0)
		)
		(min_thickness 0.25)
		(keepout
			(tracks allowed)
			(vias allowed)
			(pads allowed)
			(copperpour allowed)
			(footprints allowed)
		)
		(placement
			(enabled no)
			(sheetname "")
		)
		(fill
			(thermal_gap 0.5)
			(thermal_bridge_width 0.5)
			(island_removal_mode 0)
		)
		(polygon
			(pts
				(xy 455.301604 -46.148752) (xy 455.301604 -45.651928) (xy 456.68184 -45.651928) (xy 456.68184 -46.148752)
			)
		)
	)
	(zone
		(layer "F.Cu")
		(hatch none 0.5)
		(connect_pads
			(clearance 0)
		)
		(min_thickness 0.25)
		(keepout
			(tracks not_allowed)
			(vias allowed)
			(pads allowed)
			(copperpour not_allowed)
			(footprints allowed)
		)
		(placement
			(enabled no)
			(sheetname "")
		)
		(fill
			(thermal_gap 0.5)
			(thermal_bridge_width 0.5)
			(island_removal_mode 0)
		)
		(polygon
			(pts
				(arc
					(start 417.051998 -351.415096)
					(mid 413.952182 -354.514912)
					(end 410.852112 -351.415096)
				)
				(arc
					(start 410.852112 -351.415096)
					(mid 413.952182 -348.315026)
					(end 417.051998 -351.415096)
				)
			)
		)
	)
	(zone
		(layer "F.Cu")
		(hatch none 0.5)
		(connect_pads
			(clearance 0)
		)
		(min_thickness 0.25)
		(keepout
			(tracks allowed)
			(vias allowed)
			(pads allowed)
			(copperpour allowed)
			(footprints not_allowed)
		)
		(placement
			(enabled no)
			(sheetname "")
		)
		(fill
			(thermal_gap 0.5)
			(thermal_bridge_width 0.5)
			(island_removal_mode 0)
		)
		(polygon
			(pts
				(arc
					(start 115.816126 -340.315042)
					(mid 112.716056 -343.415112)
					(end 109.615986 -340.315042)
				)
				(arc
					(start 109.615986 -340.315042)
					(mid 112.716056 -337.214972)
					(end 115.816126 -340.315042)
				)
			)
		)
	)
	(zone
		(layer "F.Cu")
		(hatch none 0.5)
		(connect_pads
			(clearance 0)
		)
		(min_thickness 0.25)
		(keepout
			(tracks not_allowed)
			(vias allowed)
			(pads allowed)
			(copperpour not_allowed)
			(footprints allowed)
		)
		(placement
			(enabled no)
			(sheetname "")
		)
		(fill
			(thermal_gap 0.5)
			(thermal_bridge_width 0.5)
			(island_removal_mode 0)
		)
		(polygon
			(pts
				(xy 63.70828 -9.094724) (xy 63.825628 -9.094724) (xy 63.876428 -9.043924) (xy 63.876428 -7.596124)
				(xy 63.825628 -7.545324) (xy 63.70828 -7.545324) (xy 63.65748 -7.596124) (xy 63.65748 -9.043924)
			)
		)
	)
	(zone
		(layer "F.Cu")
		(hatch none 0.5)
		(connect_pads
			(clearance 0)
		)
		(min_thickness 0.25)
		(keepout
			(tracks allowed)
			(vias allowed)
			(pads allowed)
			(copperpour allowed)
			(footprints allowed)
		)
		(placement
			(enabled no)
			(sheetname "")
		)
		(fill
			(thermal_gap 0.5)
			(thermal_bridge_width 0.5)
			(island_removal_mode 0)
		)
		(polygon
			(pts
				(xy 308.66588 -283.44241) (xy 308.66588 -283.77261) (xy 306.12588 -283.77261) (xy 306.12588 -283.44241)
			)
		)
	)
	(zone
		(layer "F.Cu")
		(hatch none 0.5)
		(connect_pads
			(clearance 0)
		)
		(min_thickness 0.25)
		(keepout
			(tracks allowed)
			(vias allowed)
			(pads allowed)
			(copperpour allowed)
			(footprints allowed)
		)
		(placement
			(enabled no)
			(sheetname "")
		)
		(fill
			(thermal_gap 0.5)
			(thermal_bridge_width 0.5)
			(island_removal_mode 0)
		)
		(polygon
			(pts
				(xy 208.11744 -37.65296) (xy 208.11744 -35.74542) (xy 209.1182 -35.74542) (xy 209.1182 -37.65296)
			)
		)
	)
	(zone
		(layer "F.Cu")
		(hatch none 0.5)
		(connect_pads
			(clearance 0)
		)
		(min_thickness 0.25)
		(keepout
			(tracks allowed)
			(vias allowed)
			(pads allowed)
			(copperpour allowed)
			(footprints not_allowed)
		)
		(placement
			(enabled no)
			(sheetname "")
		)
		(fill
			(thermal_gap 0.5)
			(thermal_bridge_width 0.5)
			(island_removal_mode 0)
		)
		(polygon
			(pts
				(arc
					(start 67.030092 -258.890008)
					(mid 69.830188 -256.089912)
					(end 72.63003 -258.890008)
				)
				(arc
					(start 72.63003 -258.890008)
					(mid 69.830188 -261.68985)
					(end 67.030092 -258.890008)
				)
			)
		)
	)
	(zone
		(layer "F.Cu")
		(hatch none 0.5)
		(connect_pads
			(clearance 0)
		)
		(min_thickness 0.25)
		(keepout
			(tracks allowed)
			(vias allowed)
			(pads allowed)
			(copperpour allowed)
			(footprints allowed)
		)
		(placement
			(enabled no)
			(sheetname "")
		)
		(fill
			(thermal_gap 0.5)
			(thermal_bridge_width 0.5)
			(island_removal_mode 0)
		)
		(polygon
			(pts
				(xy 163.377626 -213.22792) (xy 163.377626 -212.89772) (xy 165.296596 -212.89772) (xy 165.296596 -213.22792)
			)
		)
	)
	(zone
		(layer "F.Cu")
		(hatch none 0.5)
		(connect_pads
			(clearance 0)
		)
		(min_thickness 0.25)
		(keepout
			(tracks not_allowed)
			(vias allowed)
			(pads allowed)
			(copperpour not_allowed)
			(footprints allowed)
		)
		(placement
			(enabled no)
			(sheetname "")
		)
		(fill
			(thermal_gap 0.5)
			(thermal_bridge_width 0.5)
			(island_removal_mode 0)
		)
		(polygon
			(pts
				(xy 188.746384 -350.571562) (xy 188.746384 -351.028254) (xy 189.44209 -351.028254) (xy 189.44209 -350.867726)
				(xy 190.00089 -350.867726) (xy 190.00089 -351.274126) (xy 189.44209 -351.274126) (xy 189.44209 -351.053654)
				(xy 188.746384 -351.053654) (xy 188.746384 -351.180654) (xy 189.20206 -351.180654) (xy 189.20206 -351.567242)
				(xy 189.444376 -351.567242) (xy 189.976252 -351.567242) (xy 190.295784 -351.24771) (xy 190.295784 -350.571562)
			)
		)
	)
	(zone
		(layer "F.Cu")
		(hatch none 0.5)
		(connect_pads
			(clearance 0)
		)
		(min_thickness 0.25)
		(keepout
			(tracks allowed)
			(vias allowed)
			(pads allowed)
			(copperpour allowed)
			(footprints not_allowed)
		)
		(placement
			(enabled no)
			(sheetname "")
		)
		(fill
			(thermal_gap 0.5)
			(thermal_bridge_width 0.5)
			(island_removal_mode 0)
		)
		(polygon
			(pts
				(xy 227.434902 -350.813878) (xy 205.705964 -350.813878) (xy 205.705964 -354.555044) (xy 203.120244 -357.145082)
				(xy 207.21828 -357.145082) (xy 207.21828 -370.701824) (xy 187.330334 -370.701824) (xy 187.330334 -395.691868)
				(xy 238.430308 -395.691868) (xy 238.430308 -370.701824) (xy 227.434902 -370.701824)
			)
		)
	)
	(zone
		(layer "F.Cu")
		(hatch none 0.5)
		(connect_pads
			(clearance 0)
		)
		(min_thickness 0.25)
		(keepout
			(tracks allowed)
			(vias allowed)
			(pads allowed)
			(copperpour allowed)
			(footprints allowed)
		)
		(placement
			(enabled no)
			(sheetname "")
		)
		(fill
			(thermal_gap 0.5)
			(thermal_bridge_width 0.5)
			(island_removal_mode 0)
		)
		(polygon
			(pts
				(xy 343.33561 -417.424616) (xy 343.33561 -416.420554) (xy 344.732102 -416.420554) (xy 344.732102 -417.424616)
			)
		)
	)
	(zone
		(layer "F.Cu")
		(hatch none 0.5)
		(connect_pads
			(clearance 0)
		)
		(min_thickness 0.25)
		(keepout
			(tracks not_allowed)
			(vias allowed)
			(pads allowed)
			(copperpour not_allowed)
			(footprints allowed)
		)
		(placement
			(enabled no)
			(sheetname "")
		)
		(fill
			(thermal_gap 0.5)
			(thermal_bridge_width 0.5)
			(island_removal_mode 0)
		)
		(polygon
			(pts
				(arc
					(start 270.55191 -347.8149)
					(mid 267.452094 -350.914716)
					(end 264.352024 -347.8149)
				)
				(arc
					(start 264.352024 -347.8149)
					(mid 267.452094 -344.71483)
					(end 270.55191 -347.8149)
				)
			)
		)
	)
	(zone
		(layer "F.Cu")
		(hatch none 0.5)
		(connect_pads
			(clearance 0)
		)
		(min_thickness 0.25)
		(keepout
			(tracks not_allowed)
			(vias allowed)
			(pads allowed)
			(copperpour not_allowed)
			(footprints allowed)
		)
		(placement
			(enabled no)
			(sheetname "")
		)
		(fill
			(thermal_gap 0.5)
			(thermal_bridge_width 0.5)
			(island_removal_mode 0)
		)
		(polygon
			(pts
				(xy 408.6479 -169.34307) (xy 408.6479 -168.886378) (xy 407.952194 -168.886378) (xy 407.952194 -169.046906)
				(xy 407.393394 -169.046906) (xy 407.393394 -168.640506) (xy 407.952194 -168.640506) (xy 407.952194 -168.860978)
				(xy 408.6479 -168.860978) (xy 408.6479 -168.733978) (xy 408.192224 -168.733978) (xy 408.192224 -168.34739)
				(xy 407.949908 -168.34739) (xy 407.418032 -168.34739) (xy 407.0985 -168.666922) (xy 407.0985 -169.34307)
			)
		)
	)
	(zone
		(layer "F.Cu")
		(hatch none 0.5)
		(connect_pads
			(clearance 0)
		)
		(min_thickness 0.25)
		(keepout
			(tracks allowed)
			(vias allowed)
			(pads allowed)
			(copperpour allowed)
			(footprints allowed)
		)
		(placement
			(enabled no)
			(sheetname "")
		)
		(fill
			(thermal_gap 0.5)
			(thermal_bridge_width 0.5)
			(island_removal_mode 0)
		)
		(polygon
			(pts
				(xy 131.95808 -371.097302) (xy 131.95808 -370.09324) (xy 133.354572 -370.09324) (xy 133.354572 -371.097302)
			)
		)
	)
	(zone
		(layer "F.Cu")
		(hatch none 0.5)
		(connect_pads
			(clearance 0)
		)
		(min_thickness 0.25)
		(keepout
			(tracks allowed)
			(vias allowed)
			(pads allowed)
			(copperpour allowed)
			(footprints not_allowed)
		)
		(placement
			(enabled no)
			(sheetname "")
		)
		(fill
			(thermal_gap 0.5)
			(thermal_bridge_width 0.5)
			(island_removal_mode 0)
		)
		(polygon
			(pts
				(xy 264.495026 -183.50992) (xy 264.495026 -327.609962) (xy 270.694912 -327.609962) (xy 270.694912 -183.50992)
			)
		)
	)
	(zone
		(layer "F.Cu")
		(hatch none 0.5)
		(connect_pads
			(clearance 0)
		)
		(min_thickness 0.25)
		(keepout
			(tracks not_allowed)
			(vias allowed)
			(pads allowed)
			(copperpour not_allowed)
			(footprints allowed)
		)
		(placement
			(enabled no)
			(sheetname "")
		)
		(fill
			(thermal_gap 0.5)
			(thermal_bridge_width 0.5)
			(island_removal_mode 0)
		)
		(polygon
			(pts
				(xy 168.758108 -52.910232) (xy 170.358308 -52.910232) (xy 170.409108 -52.859432) (xy 170.409108 -52.740306)
				(xy 170.358308 -52.689506) (xy 168.758108 -52.689506) (xy 168.707308 -52.740306) (xy 168.707308 -52.859432)
			)
		)
	)
	(zone
		(layer "F.Cu")
		(hatch none 0.5)
		(connect_pads
			(clearance 0)
		)
		(min_thickness 0.25)
		(keepout
			(tracks allowed)
			(vias allowed)
			(pads allowed)
			(copperpour allowed)
			(footprints allowed)
		)
		(placement
			(enabled no)
			(sheetname "")
		)
		(fill
			(thermal_gap 0.5)
			(thermal_bridge_width 0.5)
			(island_removal_mode 0)
		)
		(polygon
			(pts
				(xy 155.976828 -373.561102) (xy 155.976828 -372.55704) (xy 157.37332 -372.55704) (xy 157.37332 -373.561102)
			)
		)
	)
	(zone
		(layer "F.Cu")
		(hatch none 0.5)
		(connect_pads
			(clearance 0)
		)
		(min_thickness 0.25)
		(keepout
			(tracks allowed)
			(vias allowed)
			(pads allowed)
			(copperpour allowed)
			(footprints allowed)
		)
		(placement
			(enabled no)
			(sheetname "")
		)
		(fill
			(thermal_gap 0.5)
			(thermal_bridge_width 0.5)
			(island_removal_mode 0)
		)
		(polygon
			(pts
				(xy 90.85326 -144.548606) (xy 90.85326 -144.013936) (xy 91.442032 -144.013936) (xy 91.442032 -144.548606)
			)
		)
	)
	(zone
		(layer "F.Cu")
		(hatch none 0.5)
		(connect_pads
			(clearance 0)
		)
		(min_thickness 0.25)
		(keepout
			(tracks allowed)
			(vias allowed)
			(pads allowed)
			(copperpour allowed)
			(footprints not_allowed)
		)
		(placement
			(enabled no)
			(sheetname "")
		)
		(fill
			(thermal_gap 0.5)
			(thermal_bridge_width 0.5)
			(island_removal_mode 0)
		)
		(polygon
			(pts
				(arc
					(start 458.659992 -347.700092)
					(mid 461.460088 -344.899996)
					(end 464.25993 -347.700092)
				)
				(arc
					(start 464.25993 -347.700092)
					(mid 461.460088 -350.499934)
					(end 458.659992 -347.700092)
				)
			)
		)
	)
	(zone
		(layer "F.Cu")
		(hatch none 0.5)
		(connect_pads
			(clearance 0)
		)
		(min_thickness 0.25)
		(keepout
			(tracks allowed)
			(vias allowed)
			(pads allowed)
			(copperpour allowed)
			(footprints not_allowed)
		)
		(placement
			(enabled no)
			(sheetname "")
		)
		(fill
			(thermal_gap 0.5)
			(thermal_bridge_width 0.5)
			(island_removal_mode 0)
		)
		(polygon
			(pts
				(xy 410.16809 -329.060048) (xy 467.300056 -329.060048) (xy 467.300056 -309.538878) (xy 459.779116 -309.538878)
				(xy 459.779116 -279.871932) (xy 467.300056 -279.871932) (xy 467.300056 -192.321688) (xy 455.666602 -192.321688)
				(xy 455.666602 -182.060088) (xy 410.16809 -182.060088)
			)
		)
	)
	(zone
		(layer "F.Cu")
		(hatch none 0.5)
		(connect_pads
			(clearance 0)
		)
		(min_thickness 0.25)
		(keepout
			(tracks allowed)
			(vias allowed)
			(pads allowed)
			(copperpour allowed)
			(footprints allowed)
		)
		(placement
			(enabled no)
			(sheetname "")
		)
		(fill
			(thermal_gap 0.5)
			(thermal_bridge_width 0.5)
			(island_removal_mode 0)
		)
		(polygon
			(pts
				(xy 306.070508 -204.72781) (xy 306.070508 -204.39761) (xy 308.610508 -204.39761) (xy 308.610508 -204.72781)
			)
		)
	)
	(zone
		(layer "F.Cu")
		(hatch none 0.5)
		(connect_pads
			(clearance 0)
		)
		(min_thickness 0.25)
		(keepout
			(tracks allowed)
			(vias allowed)
			(pads allowed)
			(copperpour allowed)
			(footprints allowed)
		)
		(placement
			(enabled no)
			(sheetname "")
		)
		(fill
			(thermal_gap 0.5)
			(thermal_bridge_width 0.5)
			(island_removal_mode 0)
		)
		(polygon
			(pts
				(xy 101.74351 -379.216412) (xy 102.747572 -379.216412) (xy 102.747572 -380.612904) (xy 101.74351 -380.612904)
			)
		)
	)
	(zone
		(layer "F.Cu")
		(hatch none 0.5)
		(connect_pads
			(clearance 0)
		)
		(min_thickness 0.25)
		(keepout
			(tracks allowed)
			(vias allowed)
			(pads allowed)
			(copperpour allowed)
			(footprints allowed)
		)
		(placement
			(enabled no)
			(sheetname "")
		)
		(fill
			(thermal_gap 0.5)
			(thermal_bridge_width 0.5)
			(island_removal_mode 0)
		)
		(polygon
			(pts
				(xy 373.019066 -143.86433) (xy 373.019066 -142.154402) (xy 374.404128 -142.154402) (xy 374.404128 -143.86433)
			)
		)
	)
	(zone
		(layer "F.Cu")
		(hatch none 0.5)
		(connect_pads
			(clearance 0)
		)
		(min_thickness 0.25)
		(keepout
			(tracks not_allowed)
			(vias allowed)
			(pads allowed)
			(copperpour not_allowed)
			(footprints allowed)
		)
		(placement
			(enabled no)
			(sheetname "")
		)
		(fill
			(thermal_gap 0.5)
			(thermal_bridge_width 0.5)
			(island_removal_mode 0)
		)
		(polygon
			(pts
				(arc
					(start 68.482972 -47.049944)
					(mid 70.383146 -45.14977)
					(end 72.283066 -47.049944)
				)
				(arc
					(start 72.283066 -47.049944)
					(mid 70.383146 -48.949864)
					(end 68.482972 -47.049944)
				)
			)
		)
	)
	(zone
		(layer "F.Cu")
		(hatch none 0.5)
		(connect_pads
			(clearance 0)
		)
		(min_thickness 0.25)
		(keepout
			(tracks not_allowed)
			(vias allowed)
			(pads allowed)
			(copperpour not_allowed)
			(footprints allowed)
		)
		(placement
			(enabled no)
			(sheetname "")
		)
		(fill
			(thermal_gap 0.5)
			(thermal_bridge_width 0.5)
			(island_removal_mode 0)
		)
		(polygon
			(pts
				(arc
					(start 463.799936 -435.600094)
					(mid 458.799946 -440.600084)
					(end 453.799956 -435.600094)
				)
				(arc
					(start 453.799956 -435.600094)
					(mid 458.799946 -430.600104)
					(end 463.799936 -435.600094)
				)
			)
		)
	)
	(zone
		(layer "F.Cu")
		(hatch none 0.5)
		(connect_pads
			(clearance 0)
		)
		(min_thickness 0.25)
		(keepout
			(tracks allowed)
			(vias allowed)
			(pads allowed)
			(copperpour allowed)
			(footprints allowed)
		)
		(placement
			(enabled no)
			(sheetname "")
		)
		(fill
			(thermal_gap 0.5)
			(thermal_bridge_width 0.5)
			(island_removal_mode 0)
		)
		(polygon
			(pts
				(xy 77.360018 -391.360406) (xy 79.166466 -391.360406) (xy 79.455264 -391.071608) (xy 79.455264 -388.252462)
				(xy 79.580232 -388.127494) (xy 98.966274 -388.127494) (xy 98.966274 -390.775952) (xy 98.61677 -391.125456)
				(xy 98.61677 -392.40206) (xy 98.781616 -392.566906) (xy 99.371404 -392.566906) (xy 100.851716 -391.086594)
				(xy 100.851716 -388.176008) (xy 98.62439 -385.948682) (xy 79.441548 -385.948682) (xy 78.826868 -385.334002)
				(xy 78.826868 -384.995166) (xy 78.676246 -384.844544) (xy 77.660246 -384.844544) (xy 77.283818 -385.220972)
				(xy 77.283818 -387.315964) (xy 76.405486 -388.194296) (xy 76.405486 -389.260842) (xy 77.296264 -390.15162)
				(xy 77.296264 -391.296652)
			)
		)
	)
	(zone
		(layer "F.Cu")
		(hatch none 0.5)
		(connect_pads
			(clearance 0)
		)
		(min_thickness 0.25)
		(keepout
			(tracks allowed)
			(vias allowed)
			(pads allowed)
			(copperpour allowed)
			(footprints allowed)
		)
		(placement
			(enabled no)
			(sheetname "")
		)
		(fill
			(thermal_gap 0.5)
			(thermal_bridge_width 0.5)
			(island_removal_mode 0)
		)
		(polygon
			(pts
				(xy 163.377626 -268.478254) (xy 163.377626 -268.148054) (xy 165.296596 -268.148054) (xy 165.296596 -268.478254)
			)
		)
	)
	(zone
		(layer "F.Cu")
		(hatch none 0.5)
		(connect_pads
			(clearance 0)
		)
		(min_thickness 0.25)
		(keepout
			(tracks allowed)
			(vias allowed)
			(pads allowed)
			(copperpour allowed)
			(footprints not_allowed)
		)
		(placement
			(enabled no)
			(sheetname "")
		)
		(fill
			(thermal_gap 0.5)
			(thermal_bridge_width 0.5)
			(island_removal_mode 0)
		)
		(polygon
			(pts
				(arc
					(start 332.769972 -212.989922)
					(mid 329.270106 -216.489788)
					(end 325.769986 -212.989922)
				)
				(arc
					(start 325.769986 -212.989922)
					(mid 329.270106 -209.489802)
					(end 332.769972 -212.989922)
				)
			)
		)
	)
	(zone
		(layer "F.Cu")
		(hatch none 0.5)
		(connect_pads
			(clearance 0)
		)
		(min_thickness 0.25)
		(keepout
			(tracks allowed)
			(vias allowed)
			(pads allowed)
			(copperpour allowed)
			(footprints allowed)
		)
		(placement
			(enabled no)
			(sheetname "")
		)
		(fill
			(thermal_gap 0.5)
			(thermal_bridge_width 0.5)
			(island_removal_mode 0)
		)
		(polygon
			(pts
				(xy 411.317694 -272.727928) (xy 411.317694 -272.397728) (xy 413.236664 -272.397728) (xy 413.236664 -272.727928)
			)
		)
	)
	(zone
		(layer "F.Cu")
		(hatch none 0.5)
		(connect_pads
			(clearance 0)
		)
		(min_thickness 0.25)
		(keepout
			(tracks allowed)
			(vias allowed)
			(pads allowed)
			(copperpour allowed)
			(footprints allowed)
		)
		(placement
			(enabled no)
			(sheetname "")
		)
		(fill
			(thermal_gap 0.5)
			(thermal_bridge_width 0.5)
			(island_removal_mode 0)
		)
		(polygon
			(pts
				(xy 261.281926 -139.356592) (xy 261.281926 -137.885424) (xy 262.504428 -137.885424) (xy 262.504428 -139.356592)
			)
		)
	)
	(zone
		(layer "F.Cu")
		(hatch none 0.5)
		(connect_pads
			(clearance 0)
		)
		(min_thickness 0.25)
		(keepout
			(tracks allowed)
			(vias allowed)
			(pads allowed)
			(copperpour allowed)
			(footprints allowed)
		)
		(placement
			(enabled no)
			(sheetname "")
		)
		(fill
			(thermal_gap 0.5)
			(thermal_bridge_width 0.5)
			(island_removal_mode 0)
		)
		(polygon
			(pts
				(xy 60.725812 -309.792624) (xy 60.725812 -310.122824) (xy 58.185812 -310.122824) (xy 58.185812 -309.792624)
			)
		)
	)
	(zone
		(layer "F.Cu")
		(hatch none 0.5)
		(connect_pads
			(clearance 0)
		)
		(min_thickness 0.25)
		(keepout
			(tracks allowed)
			(vias allowed)
			(pads allowed)
			(copperpour allowed)
			(footprints allowed)
		)
		(placement
			(enabled no)
			(sheetname "")
		)
		(fill
			(thermal_gap 0.5)
			(thermal_bridge_width 0.5)
			(island_removal_mode 0)
		)
		(polygon
			(pts
				(xy 80.367886 -376.024902) (xy 80.367886 -375.02084) (xy 81.764378 -375.02084) (xy 81.764378 -376.024902)
			)
		)
	)
	(zone
		(layer "F.Cu")
		(hatch none 0.5)
		(connect_pads
			(clearance 0)
		)
		(min_thickness 0.25)
		(keepout
			(tracks allowed)
			(vias allowed)
			(pads allowed)
			(copperpour allowed)
			(footprints not_allowed)
		)
		(placement
			(enabled no)
			(sheetname "")
		)
		(fill
			(thermal_gap 0.5)
			(thermal_bridge_width 0.5)
			(island_removal_mode 0)
		)
		(polygon
			(pts
				(arc
					(start 39.319962 -404.789894)
					(mid 41.570148 -402.539708)
					(end 43.82008 -404.789894)
				)
				(arc
					(start 43.82008 -404.789894)
					(mid 41.570148 -407.039826)
					(end 39.319962 -404.789894)
				)
			)
		)
	)
	(zone
		(layer "F.Cu")
		(hatch none 0.5)
		(connect_pads
			(clearance 0)
		)
		(min_thickness 0.25)
		(keepout
			(tracks allowed)
			(vias allowed)
			(pads allowed)
			(copperpour allowed)
			(footprints allowed)
		)
		(placement
			(enabled no)
			(sheetname "")
		)
		(fill
			(thermal_gap 0.5)
			(thermal_bridge_width 0.5)
			(island_removal_mode 0)
		)
		(polygon
			(pts
				(xy 130.90525 -56.123332) (xy 129.754884 -56.123332) (xy 129.754884 -54.668928) (xy 130.90525 -54.668928)
			)
		)
	)
	(zone
		(layer "F.Cu")
		(hatch none 0.5)
		(connect_pads
			(clearance 0)
		)
		(min_thickness 0.25)
		(keepout
			(tracks allowed)
			(vias allowed)
			(pads allowed)
			(copperpour allowed)
			(footprints allowed)
		)
		(placement
			(enabled no)
			(sheetname "")
		)
		(fill
			(thermal_gap 0.5)
			(thermal_bridge_width 0.5)
			(island_removal_mode 0)
		)
		(polygon
			(pts
				(xy 166.011098 -14.36624) (xy 166.011098 -10.591292) (xy 171.874434 -10.591292) (xy 171.874434 -14.36624)
			)
		)
	)
	(zone
		(layer "F.Cu")
		(hatch none 0.5)
		(connect_pads
			(clearance 0)
		)
		(min_thickness 0.25)
		(keepout
			(tracks allowed)
			(vias allowed)
			(pads allowed)
			(copperpour allowed)
			(footprints allowed)
		)
		(placement
			(enabled no)
			(sheetname "")
		)
		(fill
			(thermal_gap 0.5)
			(thermal_bridge_width 0.5)
			(island_removal_mode 0)
		)
		(polygon
			(pts
				(xy 320.85788 -379.479302) (xy 320.85788 -378.47524) (xy 322.254372 -378.47524) (xy 322.254372 -379.479302)
			)
		)
	)
	(zone
		(layer "F.Cu")
		(hatch none 0.5)
		(connect_pads
			(clearance 0)
		)
		(min_thickness 0.25)
		(keepout
			(tracks allowed)
			(vias allowed)
			(pads allowed)
			(copperpour allowed)
			(footprints allowed)
		)
		(placement
			(enabled no)
			(sheetname "")
		)
		(fill
			(thermal_gap 0.5)
			(thermal_bridge_width 0.5)
			(island_removal_mode 0)
		)
		(polygon
			(pts
				(xy 142.06982 -381.225044) (xy 143.073882 -381.225044) (xy 143.073882 -382.621536) (xy 142.06982 -382.621536)
			)
		)
	)
	(zone
		(layer "F.Cu")
		(hatch none 0.5)
		(connect_pads
			(clearance 0)
		)
		(min_thickness 0.25)
		(keepout
			(tracks allowed)
			(vias allowed)
			(pads allowed)
			(copperpour allowed)
			(footprints not_allowed)
		)
		(placement
			(enabled no)
			(sheetname "")
		)
		(fill
			(thermal_gap 0.5)
			(thermal_bridge_width 0.5)
			(island_removal_mode 0)
		)
		(polygon
			(pts
				(xy 358.513888 -16.20647) (xy 358.513888 -19.206464)
				(arc
					(start 351.77222 -19.206464)
					(mid 352.25476 -15.900626)
					(end 353.457002 -12.783566)
				)
				(arc
					(start 380.070868 -12.783566)
					(mid 380.434593 -13.532873)
					(end 380.75616 -14.301216)
				)
				(arc
					(start 380.75616 -14.301216)
					(mid 377.268403 -15.17179)
					(end 374.513856 -17.48155)
				)
				(xy 374.513856 -16.20647)
			)
		)
	)
	(zone
		(layer "F.Cu")
		(hatch none 0.5)
		(connect_pads
			(clearance 0)
		)
		(min_thickness 0.25)
		(keepout
			(tracks allowed)
			(vias allowed)
			(pads allowed)
			(copperpour allowed)
			(footprints allowed)
		)
		(placement
			(enabled no)
			(sheetname "")
		)
		(fill
			(thermal_gap 0.5)
			(thermal_bridge_width 0.5)
			(island_removal_mode 0)
		)
		(polygon
			(pts
				(xy 106.5022 -33.5026) (xy 108.712 -33.5026) (xy 108.9152 -33.2994) (xy 108.9152 -29.6926) (xy 108.9152 -27.940508)
				(xy 108.30433 -27.329638) (xy 106.00436 -27.329638) (xy 104.701086 -26.026364) (xy 103.998522 -26.026364)
				(xy 103.806752 -26.218134) (xy 103.806752 -27.329638) (xy 104.08793 -27.610816) (xy 106.23296 -29.755592)
				(xy 106.23296 -30.11424) (xy 106.2228 -30.1244) (xy 106.2228 -33.2232)
			)
		)
	)
	(zone
		(layer "F.Cu")
		(hatch none 0.5)
		(connect_pads
			(clearance 0)
		)
		(min_thickness 0.25)
		(keepout
			(tracks not_allowed)
			(vias allowed)
			(pads allowed)
			(copperpour not_allowed)
			(footprints allowed)
		)
		(placement
			(enabled no)
			(sheetname "")
		)
		(fill
			(thermal_gap 0.5)
			(thermal_bridge_width 0.5)
			(island_removal_mode 0)
		)
		(polygon
			(pts
				(arc
					(start 314.969906 -258.890008)
					(mid 317.770002 -256.089912)
					(end 320.570098 -258.890008)
				)
				(arc
					(start 320.570098 -258.890008)
					(mid 317.770002 -261.690104)
					(end 314.969906 -258.890008)
				)
			)
		)
	)
	(zone
		(layer "F.Cu")
		(hatch none 0.5)
		(connect_pads
			(clearance 0)
		)
		(min_thickness 0.25)
		(keepout
			(tracks allowed)
			(vias allowed)
			(pads allowed)
			(copperpour allowed)
			(footprints allowed)
		)
		(placement
			(enabled no)
			(sheetname "")
		)
		(fill
			(thermal_gap 0.5)
			(thermal_bridge_width 0.5)
			(island_removal_mode 0)
		)
		(polygon
			(pts
				(xy 398.36217 -381.943102) (xy 398.36217 -380.93904) (xy 399.758662 -380.93904) (xy 399.758662 -381.943102)
			)
		)
	)
	(zone
		(layer "F.Cu")
		(hatch none 0.5)
		(connect_pads
			(clearance 0)
		)
		(min_thickness 0.25)
		(keepout
			(tracks allowed)
			(vias allowed)
			(pads allowed)
			(copperpour allowed)
			(footprints not_allowed)
		)
		(placement
			(enabled no)
			(sheetname "")
		)
		(fill
			(thermal_gap 0.5)
			(thermal_bridge_width 0.5)
			(island_removal_mode 0)
		)
		(polygon
			(pts
				(xy 417.51504 -327.609962) (xy 417.51504 -183.50992) (xy 411.3149 -183.50992) (xy 411.3149 -327.609962)
			)
		)
	)
	(zone
		(layer "F.Cu")
		(hatch none 0.5)
		(connect_pads
			(clearance 0)
		)
		(min_thickness 0.25)
		(keepout
			(tracks allowed)
			(vias allowed)
			(pads allowed)
			(copperpour allowed)
			(footprints not_allowed)
		)
		(placement
			(enabled no)
			(sheetname "")
		)
		(fill
			(thermal_gap 0.5)
			(thermal_bridge_width 0.5)
			(island_removal_mode 0)
		)
		(polygon
			(pts
				(arc
					(start 440.087004 -351.415096)
					(mid 441.952126 -349.549974)
					(end 443.816994 -351.415096)
				)
				(arc
					(start 443.816994 -351.415096)
					(mid 441.952126 -353.279964)
					(end 440.087004 -351.415096)
				)
			)
		)
	)
	(zone
		(layer "F.Cu")
		(hatch none 0.5)
		(connect_pads
			(clearance 0)
		)
		(min_thickness 0.25)
		(keepout
			(tracks allowed)
			(vias allowed)
			(pads allowed)
			(copperpour allowed)
			(footprints not_allowed)
		)
		(placement
			(enabled no)
			(sheetname "")
		)
		(fill
			(thermal_gap 0.5)
			(thermal_bridge_width 0.5)
			(island_removal_mode 0)
		)
		(polygon
			(pts
				(arc
					(start 102.899972 -22.29993)
					(mid 94.899988 -30.299914)
					(end 86.900004 -22.29993)
				)
				(arc
					(start 86.900004 -22.29993)
					(mid 94.899988 -14.299946)
					(end 102.899972 -22.29993)
				)
			)
		)
	)
	(zone
		(layer "F.Cu")
		(hatch none 0.5)
		(connect_pads
			(clearance 0)
		)
		(min_thickness 0.25)
		(keepout
			(tracks allowed)
			(vias allowed)
			(pads allowed)
			(copperpour allowed)
			(footprints not_allowed)
		)
		(placement
			(enabled no)
			(sheetname "")
		)
		(fill
			(thermal_gap 0.5)
			(thermal_bridge_width 0.5)
			(island_removal_mode 0)
		)
		(polygon
			(pts
				(arc
					(start 270.649954 -22.29993)
					(mid 265.649964 -27.29992)
					(end 260.649974 -22.29993)
				)
				(arc
					(start 260.649974 -22.29993)
					(mid 265.649964 -17.29994)
					(end 270.649954 -22.29993)
				)
			)
		)
	)
	(zone
		(layer "F.Cu")
		(hatch none 0.5)
		(connect_pads
			(clearance 0)
		)
		(min_thickness 0.25)
		(keepout
			(tracks allowed)
			(vias allowed)
			(pads allowed)
			(copperpour allowed)
			(footprints allowed)
		)
		(placement
			(enabled no)
			(sheetname "")
		)
		(fill
			(thermal_gap 0.5)
			(thermal_bridge_width 0.5)
			(island_removal_mode 0)
		)
		(polygon
			(pts
				(xy 344.876628 -381.943102) (xy 344.876628 -380.93904) (xy 346.27312 -380.93904) (xy 346.27312 -381.943102)
			)
		)
	)
	(zone
		(layer "F.Cu")
		(hatch none 0.5)
		(connect_pads
			(clearance 0)
		)
		(min_thickness 0.25)
		(keepout
			(tracks not_allowed)
			(vias allowed)
			(pads allowed)
			(copperpour not_allowed)
			(footprints allowed)
		)
		(placement
			(enabled no)
			(sheetname "")
		)
		(fill
			(thermal_gap 0.5)
			(thermal_bridge_width 0.5)
			(island_removal_mode 0)
		)
		(polygon
			(pts
				(arc
					(start 450.54012 -40.420036)
					(mid 447.44005 -43.520106)
					(end 444.33998 -40.420036)
				)
				(arc
					(start 444.33998 -40.420036)
					(mid 447.44005 -37.319966)
					(end 450.54012 -40.420036)
				)
			)
		)
	)
	(zone
		(layer "F.Cu")
		(hatch none 0.5)
		(connect_pads
			(clearance 0)
		)
		(min_thickness 0.25)
		(keepout
			(tracks allowed)
			(vias allowed)
			(pads allowed)
			(copperpour allowed)
			(footprints allowed)
		)
		(placement
			(enabled no)
			(sheetname "")
		)
		(fill
			(thermal_gap 0.5)
			(thermal_bridge_width 0.5)
			(island_removal_mode 0)
		)
		(polygon
			(pts
				(xy 64.577976 -346.61729) (xy 58.227976 -346.61729) (xy 57.592976 -347.25229) (xy 57.592976 -351.82429)
				(xy 58.227976 -352.45929) (xy 64.196976 -352.45929) (xy 64.704976 -351.95129) (xy 64.704976 -346.74429)
			)
		)
	)
	(zone
		(layer "F.Cu")
		(hatch none 0.5)
		(connect_pads
			(clearance 0)
		)
		(min_thickness 0.25)
		(keepout
			(tracks allowed)
			(vias allowed)
			(pads allowed)
			(copperpour allowed)
			(footprints not_allowed)
		)
		(placement
			(enabled no)
			(sheetname "")
		)
		(fill
			(thermal_gap 0.5)
			(thermal_bridge_width 0.5)
			(island_removal_mode 0)
		)
		(polygon
			(pts
				(arc
					(start 105.500424 -435.600094)
					(mid 100.500434 -440.600084)
					(end 95.500444 -435.600094)
				)
				(arc
					(start 95.500444 -435.600094)
					(mid 100.500434 -430.600104)
					(end 105.500424 -435.600094)
				)
			)
		)
	)
	(zone
		(layer "F.Cu")
		(hatch none 0.5)
		(connect_pads
			(clearance 0)
		)
		(min_thickness 0.25)
		(keepout
			(tracks allowed)
			(vias allowed)
			(pads allowed)
			(copperpour allowed)
			(footprints not_allowed)
		)
		(placement
			(enabled no)
			(sheetname "")
		)
		(fill
			(thermal_gap 0.5)
			(thermal_bridge_width 0.5)
			(island_removal_mode 0)
		)
		(polygon
			(pts
				(arc
					(start 422.999916 -413.170116)
					(mid 426.999908 -409.170124)
					(end 430.9999 -413.170116)
				)
				(arc
					(start 430.9999 -413.170116)
					(mid 426.999908 -417.170108)
					(end 422.999916 -413.170116)
				)
			)
		)
	)
	(zone
		(layer "F.Cu")
		(hatch none 0.5)
		(connect_pads
			(clearance 0)
		)
		(min_thickness 0.25)
		(keepout
			(tracks allowed)
			(vias allowed)
			(pads allowed)
			(copperpour allowed)
			(footprints allowed)
		)
		(placement
			(enabled no)
			(sheetname "")
		)
		(fill
			(thermal_gap 0.5)
			(thermal_bridge_width 0.5)
			(island_removal_mode 0)
		)
		(polygon
			(pts
				(xy 107.627928 -412.973774) (xy 106.894376 -412.973774) (xy 106.894376 -411.91688) (xy 107.627928 -411.91688)
			)
		)
	)
	(zone
		(layer "F.Cu")
		(hatch none 0.5)
		(connect_pads
			(clearance 0)
		)
		(min_thickness 0.25)
		(keepout
			(tracks allowed)
			(vias allowed)
			(pads allowed)
			(copperpour allowed)
			(footprints not_allowed)
		)
		(placement
			(enabled no)
			(sheetname "")
		)
		(fill
			(thermal_gap 0.5)
			(thermal_bridge_width 0.5)
			(island_removal_mode 0)
		)
		(polygon
			(pts
				(xy 361.22991 -398.560036) (xy 361.22991 -403.260052) (xy 366.260126 -403.260052) (xy 366.260126 -398.560036)
			)
		)
	)
	(zone
		(layer "F.Cu")
		(hatch none 0.5)
		(connect_pads
			(clearance 0)
		)
		(min_thickness 0.25)
		(keepout
			(tracks allowed)
			(vias allowed)
			(pads allowed)
			(copperpour allowed)
			(footprints allowed)
		)
		(placement
			(enabled no)
			(sheetname "")
		)
		(fill
			(thermal_gap 0.5)
			(thermal_bridge_width 0.5)
			(island_removal_mode 0)
		)
		(polygon
			(pts
				(xy 308.66588 -289.39236) (xy 308.66588 -289.72256) (xy 306.12588 -289.72256) (xy 306.12588 -289.39236)
			)
		)
	)
	(zone
		(layer "F.Cu")
		(hatch none 0.5)
		(connect_pads
			(clearance 0)
		)
		(min_thickness 0.25)
		(keepout
			(tracks allowed)
			(vias allowed)
			(pads allowed)
			(copperpour allowed)
			(footprints not_allowed)
		)
		(placement
			(enabled no)
			(sheetname "")
		)
		(fill
			(thermal_gap 0.5)
			(thermal_bridge_width 0.5)
			(island_removal_mode 0)
		)
		(polygon
			(pts
				(xy 208.447894 -182.060088) (xy 208.447894 -165.596062)
				(arc
					(start 174.066962 -165.596062)
					(mid 168.268365 -168.491546)
					(end 162.228022 -166.141654)
				)
				(xy 162.228022 -182.060088)
			)
		)
	)
	(zone
		(layer "F.Cu")
		(hatch none 0.5)
		(connect_pads
			(clearance 0)
		)
		(min_thickness 0.25)
		(keepout
			(tracks allowed)
			(vias allowed)
			(pads allowed)
			(copperpour allowed)
			(footprints allowed)
		)
		(placement
			(enabled no)
			(sheetname "")
		)
		(fill
			(thermal_gap 0.5)
			(thermal_bridge_width 0.5)
			(island_removal_mode 0)
		)
		(polygon
			(pts
				(xy 58.13044 -208.128108) (xy 58.13044 -207.797908) (xy 60.67044 -207.797908) (xy 60.67044 -208.128108)
			)
		)
	)
	(zone
		(layer "F.Cu")
		(hatch none 0.5)
		(connect_pads
			(clearance 0)
		)
		(min_thickness 0.25)
		(keepout
			(tracks not_allowed)
			(vias allowed)
			(pads allowed)
			(copperpour not_allowed)
			(footprints allowed)
		)
		(placement
			(enabled no)
			(sheetname "")
		)
		(fill
			(thermal_gap 0.5)
			(thermal_bridge_width 0.5)
			(island_removal_mode 0)
		)
		(polygon
			(pts
				(xy 375.175272 -183.493156) (xy 375.175272 -183.036464) (xy 374.479566 -183.036464) (xy 374.479566 -183.196992)
				(xy 373.920766 -183.196992) (xy 373.920766 -182.790592) (xy 374.479566 -182.790592) (xy 374.479566 -183.011064)
				(xy 375.175272 -183.011064) (xy 375.175272 -182.884064) (xy 374.719596 -182.884064) (xy 374.719596 -182.497476)
				(xy 374.47728 -182.497476) (xy 373.945404 -182.497476) (xy 373.625872 -182.817008) (xy 373.625872 -183.493156)
			)
		)
	)
	(zone
		(layer "F.Cu")
		(hatch none 0.5)
		(connect_pads
			(clearance 0)
		)
		(min_thickness 0.25)
		(keepout
			(tracks allowed)
			(vias allowed)
			(pads allowed)
			(copperpour allowed)
			(footprints allowed)
		)
		(placement
			(enabled no)
			(sheetname "")
		)
		(fill
			(thermal_gap 0.5)
			(thermal_bridge_width 0.5)
			(island_removal_mode 0)
		)
		(polygon
			(pts
				(xy 411.317694 -265.92784) (xy 411.317694 -265.59764) (xy 413.236664 -265.59764) (xy 413.236664 -265.92784)
			)
		)
	)
	(zone
		(layer "F.Cu")
		(hatch none 0.5)
		(connect_pads
			(clearance 0)
		)
		(min_thickness 0.25)
		(keepout
			(tracks not_allowed)
			(vias allowed)
			(pads allowed)
			(copperpour not_allowed)
			(footprints allowed)
		)
		(placement
			(enabled no)
			(sheetname "")
		)
		(fill
			(thermal_gap 0.5)
			(thermal_bridge_width 0.5)
			(island_removal_mode 0)
		)
		(polygon
			(pts
				(arc
					(start 57.815988 -167.135048)
					(mid 54.716172 -170.234864)
					(end 51.616102 -167.135048)
				)
				(arc
					(start 51.616102 -167.135048)
					(mid 54.716172 -164.034978)
					(end 57.815988 -167.135048)
				)
			)
		)
	)
	(zone
		(layer "F.Cu")
		(hatch none 0.5)
		(connect_pads
			(clearance 0)
		)
		(min_thickness 0.25)
		(keepout
			(tracks allowed)
			(vias allowed)
			(pads allowed)
			(copperpour allowed)
			(footprints allowed)
		)
		(placement
			(enabled no)
			(sheetname "")
		)
		(fill
			(thermal_gap 0.5)
			(thermal_bridge_width 0.5)
			(island_removal_mode 0)
		)
		(polygon
			(pts
				(xy 132.99313 -409.042616) (xy 132.99313 -408.038554) (xy 134.389622 -408.038554) (xy 134.389622 -409.042616)
			)
		)
	)
	(zone
		(layer "F.Cu")
		(hatch none 0.5)
		(connect_pads
			(clearance 0)
		)
		(min_thickness 0.25)
		(keepout
			(tracks not_allowed)
			(vias allowed)
			(pads allowed)
			(copperpour not_allowed)
			(footprints allowed)
		)
		(placement
			(enabled no)
			(sheetname "")
		)
		(fill
			(thermal_gap 0.5)
			(thermal_bridge_width 0.5)
			(island_removal_mode 0)
		)
		(polygon
			(pts
				(xy 374.719596 -182.043832) (xy 374.719596 -181.08295) (xy 374.47728 -181.08295) (xy 374.47728 -182.043832)
			)
		)
	)
	(zone
		(layer "F.Cu")
		(hatch none 0.5)
		(connect_pads
			(clearance 0)
		)
		(min_thickness 0.25)
		(keepout
			(tracks allowed)
			(vias allowed)
			(pads allowed)
			(copperpour allowed)
			(footprints allowed)
		)
		(placement
			(enabled no)
			(sheetname "")
		)
		(fill
			(thermal_gap 0.5)
			(thermal_bridge_width 0.5)
			(island_removal_mode 0)
		)
		(polygon
			(pts
				(xy 80.160114 -195.358512) (xy 80.160114 -197.263512) (xy 84.173314 -197.263512) (xy 84.173314 -195.358512)
			)
		)
	)
	(zone
		(layer "F.Cu")
		(hatch none 0.5)
		(connect_pads
			(clearance 0)
		)
		(min_thickness 0.25)
		(keepout
			(tracks allowed)
			(vias allowed)
			(pads allowed)
			(copperpour allowed)
			(footprints allowed)
		)
		(placement
			(enabled no)
			(sheetname "")
		)
		(fill
			(thermal_gap 0.5)
			(thermal_bridge_width 0.5)
			(island_removal_mode 0)
		)
		(polygon
			(pts
				(xy 403.46757 -384.406902) (xy 403.46757 -383.40284) (xy 404.864062 -383.40284) (xy 404.864062 -384.406902)
			)
		)
	)
	(zone
		(layer "F.Cu")
		(hatch none 0.5)
		(connect_pads
			(clearance 0)
		)
		(min_thickness 0.25)
		(keepout
			(tracks allowed)
			(vias allowed)
			(pads allowed)
			(copperpour allowed)
			(footprints allowed)
		)
		(placement
			(enabled no)
			(sheetname "")
		)
		(fill
			(thermal_gap 0.5)
			(thermal_bridge_width 0.5)
			(island_removal_mode 0)
		)
		(polygon
			(pts
				(xy 60.725812 -291.092636) (xy 60.725812 -291.422836) (xy 58.185812 -291.422836) (xy 58.185812 -291.092636)
			)
		)
	)
	(zone
		(layer "F.Cu")
		(hatch none 0.5)
		(connect_pads
			(clearance 0)
		)
		(min_thickness 0.25)
		(keepout
			(tracks allowed)
			(vias allowed)
			(pads allowed)
			(copperpour allowed)
			(footprints allowed)
		)
		(placement
			(enabled no)
			(sheetname "")
		)
		(fill
			(thermal_gap 0.5)
			(thermal_bridge_width 0.5)
			(island_removal_mode 0)
		)
		(polygon
			(pts
				(xy 60.725812 -315.742574) (xy 60.725812 -316.072774) (xy 58.185812 -316.072774) (xy 58.185812 -315.742574)
			)
		)
	)
	(zone
		(layer "F.Cu")
		(hatch none 0.5)
		(connect_pads
			(clearance 0)
		)
		(min_thickness 0.25)
		(keepout
			(tracks not_allowed)
			(vias allowed)
			(pads allowed)
			(copperpour not_allowed)
			(footprints allowed)
		)
		(placement
			(enabled no)
			(sheetname "")
		)
		(fill
			(thermal_gap 0.5)
			(thermal_bridge_width 0.5)
			(island_removal_mode 0)
		)
		(polygon
			(pts
				(xy 26.556208 -349.265494) (xy 30.504892 -349.265494) (xy 30.504892 -349.221044) (xy 30.36443 -349.080582)
				(xy 28.944062 -349.080582) (xy 28.944062 -346.921582) (xy 31.100776 -346.921582) (xy 31.100776 -346.6719)
				(xy 28.98648 -346.6719) (xy 28.652724 -347.005656) (xy 28.652724 -349.024956) (xy 26.798524 -349.024956)
				(xy 26.798524 -348.854776) (xy 26.655014 -348.711266) (xy 26.556208 -348.711266)
			)
		)
	)
	(zone
		(layer "F.Cu")
		(hatch none 0.5)
		(connect_pads
			(clearance 0)
		)
		(min_thickness 0.25)
		(keepout
			(tracks allowed)
			(vias allowed)
			(pads allowed)
			(copperpour allowed)
			(footprints allowed)
		)
		(placement
			(enabled no)
			(sheetname "")
		)
		(fill
			(thermal_gap 0.5)
			(thermal_bridge_width 0.5)
			(island_removal_mode 0)
		)
		(polygon
			(pts
				(xy 39.18077 -172.942504) (xy 39.18077 -170.945302) (xy 40.381936 -170.945302) (xy 40.381936 -172.942504)
			)
		)
	)
	(zone
		(layer "F.Cu")
		(hatch none 0.5)
		(connect_pads
			(clearance 0)
		)
		(min_thickness 0.25)
		(keepout
			(tracks allowed)
			(vias allowed)
			(pads allowed)
			(copperpour allowed)
			(footprints allowed)
		)
		(placement
			(enabled no)
			(sheetname "")
		)
		(fill
			(thermal_gap 0.5)
			(thermal_bridge_width 0.5)
			(island_removal_mode 0)
		)
		(polygon
			(pts
				(xy 162.784028 -373.561102) (xy 162.784028 -372.55704) (xy 164.18052 -372.55704) (xy 164.18052 -373.561102)
			)
		)
	)
	(zone
		(layer "F.Cu")
		(hatch none 0.5)
		(connect_pads
			(clearance 0)
		)
		(min_thickness 0.25)
		(keepout
			(tracks not_allowed)
			(vias allowed)
			(pads allowed)
			(copperpour not_allowed)
			(footprints allowed)
		)
		(placement
			(enabled no)
			(sheetname "")
		)
		(fill
			(thermal_gap 0.5)
			(thermal_bridge_width 0.5)
			(island_removal_mode 0)
		)
		(polygon
			(pts
				(xy 43.142408 -347.4212) (xy 43.142408 -348.382082) (xy 43.384724 -348.382082) (xy 43.384724 -347.4212)
			)
		)
	)
	(zone
		(layer "F.Cu")
		(hatch none 0.5)
		(connect_pads
			(clearance 0)
		)
		(min_thickness 0.25)
		(keepout
			(tracks not_allowed)
			(vias allowed)
			(pads allowed)
			(copperpour not_allowed)
			(footprints allowed)
		)
		(placement
			(enabled no)
			(sheetname "")
		)
		(fill
			(thermal_gap 0.5)
			(thermal_bridge_width 0.5)
			(island_removal_mode 0)
		)
		(polygon
			(pts
				(arc
					(start 10.199878 -435.600094)
					(mid 12.999974 -432.799998)
					(end 15.80007 -435.600094)
				)
				(arc
					(start 15.80007 -435.600094)
					(mid 12.999974 -438.40019)
					(end 10.199878 -435.600094)
				)
			)
		)
	)
	(zone
		(layer "F.Cu")
		(hatch none 0.5)
		(connect_pads
			(clearance 0)
		)
		(min_thickness 0.25)
		(keepout
			(tracks not_allowed)
			(vias allowed)
			(pads allowed)
			(copperpour not_allowed)
			(footprints allowed)
		)
		(placement
			(enabled no)
			(sheetname "")
		)
		(fill
			(thermal_gap 0.5)
			(thermal_bridge_width 0.5)
			(island_removal_mode 0)
		)
		(polygon
			(pts
				(arc
					(start 241.650012 -352.49993)
					(mid 236.650022 -357.49992)
					(end 231.650032 -352.49993)
				)
				(arc
					(start 231.650032 -352.49993)
					(mid 236.650022 -347.49994)
					(end 241.650012 -352.49993)
				)
			)
		)
	)
	(zone
		(layer "F.Cu")
		(hatch none 0.5)
		(connect_pads
			(clearance 0)
		)
		(min_thickness 0.25)
		(keepout
			(tracks allowed)
			(vias allowed)
			(pads allowed)
			(copperpour allowed)
			(footprints allowed)
		)
		(placement
			(enabled no)
			(sheetname "")
		)
		(fill
			(thermal_gap 0.5)
			(thermal_bridge_width 0.5)
			(island_removal_mode 0)
		)
		(polygon
			(pts
				(xy 78.146148 -409.042616) (xy 78.146148 -408.038554) (xy 79.54264 -408.038554) (xy 79.54264 -409.042616)
			)
		)
	)
	(zone
		(layer "F.Cu")
		(hatch none 0.5)
		(connect_pads
			(clearance 0)
		)
		(min_thickness 0.25)
		(keepout
			(tracks allowed)
			(vias allowed)
			(pads allowed)
			(copperpour allowed)
			(footprints allowed)
		)
		(placement
			(enabled no)
			(sheetname "")
		)
		(fill
			(thermal_gap 0.5)
			(thermal_bridge_width 0.5)
			(island_removal_mode 0)
		)
		(polygon
			(pts
				(xy 418.78377 -381.943102) (xy 418.78377 -380.93904) (xy 420.180262 -380.93904) (xy 420.180262 -381.943102)
			)
		)
	)
	(zone
		(layer "F.Cu")
		(hatch none 0.5)
		(connect_pads
			(clearance 0)
		)
		(min_thickness 0.25)
		(keepout
			(tracks allowed)
			(vias allowed)
			(pads allowed)
			(copperpour allowed)
			(footprints not_allowed)
		)
		(placement
			(enabled no)
			(sheetname "")
		)
		(fill
			(thermal_gap 0.5)
			(thermal_bridge_width 0.5)
			(island_removal_mode 0)
		)
		(polygon
			(pts
				(arc
					(start 378.100082 -22.29993)
					(mid 380.900178 -19.499834)
					(end 383.70002 -22.29993)
				)
				(arc
					(start 383.70002 -22.29993)
					(mid 380.900178 -25.099772)
					(end 378.100082 -22.29993)
				)
			)
		)
	)
	(zone
		(layer "F.Cu")
		(hatch none 0.5)
		(connect_pads
			(clearance 0)
		)
		(min_thickness 0.25)
		(keepout
			(tracks allowed)
			(vias allowed)
			(pads allowed)
			(copperpour allowed)
			(footprints allowed)
		)
		(placement
			(enabled no)
			(sheetname "")
		)
		(fill
			(thermal_gap 0.5)
			(thermal_bridge_width 0.5)
			(island_removal_mode 0)
		)
		(polygon
			(pts
				(xy 127.4064 -36.10864) (xy 129.2098 -36.10864) (xy 129.5146 -35.80384) (xy 129.5146 -33.87344)
				(xy 129.0574 -33.41624) (xy 127.5334 -33.41624) (xy 127.0508 -33.89884) (xy 127.0508 -35.26536)
				(xy 126.75108 -35.56508) (xy 126.75108 -35.99434) (xy 126.86538 -36.10864)
			)
		)
	)
	(zone
		(layer "F.Cu")
		(hatch none 0.5)
		(connect_pads
			(clearance 0)
		)
		(min_thickness 0.25)
		(keepout
			(tracks allowed)
			(vias allowed)
			(pads allowed)
			(copperpour allowed)
			(footprints not_allowed)
		)
		(placement
			(enabled no)
			(sheetname "")
		)
		(fill
			(thermal_gap 0.5)
			(thermal_bridge_width 0.5)
			(island_removal_mode 0)
		)
		(polygon
			(pts
				(arc
					(start 115.275106 -431.360072)
					(mid 112.025176 -434.610002)
					(end 108.774992 -431.360072)
				)
				(arc
					(start 108.774992 -431.360072)
					(mid 112.025176 -428.109888)
					(end 115.275106 -431.360072)
				)
			)
		)
	)
	(zone
		(layer "F.Cu")
		(hatch none 0.5)
		(connect_pads
			(clearance 0)
		)
		(min_thickness 0.25)
		(keepout
			(tracks allowed)
			(vias allowed)
			(pads allowed)
			(copperpour allowed)
			(footprints allowed)
		)
		(placement
			(enabled no)
			(sheetname "")
		)
		(fill
			(thermal_gap 0.5)
			(thermal_bridge_width 0.5)
			(island_removal_mode 0)
		)
		(polygon
			(pts
				(xy 58.13044 -268.478) (xy 58.13044 -268.1478) (xy 60.67044 -268.1478) (xy 60.67044 -268.478)
			)
		)
	)
	(zone
		(layer "F.Cu")
		(hatch none 0.5)
		(connect_pads
			(clearance 0)
		)
		(min_thickness 0.25)
		(keepout
			(tracks allowed)
			(vias allowed)
			(pads allowed)
			(copperpour allowed)
			(footprints not_allowed)
		)
		(placement
			(enabled no)
			(sheetname "")
		)
		(fill
			(thermal_gap 0.5)
			(thermal_bridge_width 0.5)
			(island_removal_mode 0)
		)
		(polygon
			(pts
				(arc
					(start 73.316084 -344.814906)
					(mid 70.216014 -347.914976)
					(end 67.115944 -344.814906)
				)
				(arc
					(start 67.115944 -344.814906)
					(mid 70.216014 -341.714836)
					(end 73.316084 -344.814906)
				)
			)
		)
	)
	(zone
		(layer "F.Cu")
		(hatch none 0.5)
		(connect_pads
			(clearance 0)
		)
		(min_thickness 0.25)
		(keepout
			(tracks not_allowed)
			(vias allowed)
			(pads allowed)
			(copperpour not_allowed)
			(footprints allowed)
		)
		(placement
			(enabled no)
			(sheetname "")
		)
		(fill
			(thermal_gap 0.5)
			(thermal_bridge_width 0.5)
			(island_removal_mode 0)
		)
		(polygon
			(pts
				(arc
					(start 15.340076 -347.700092)
					(mid 10.340086 -352.700082)
					(end 5.340096 -347.700092)
				)
				(arc
					(start 5.340096 -347.700092)
					(mid 10.340086 -342.700102)
					(end 15.340076 -347.700092)
				)
			)
		)
	)
	(zone
		(layer "F.Cu")
		(hatch none 0.5)
		(connect_pads
			(clearance 0)
		)
		(min_thickness 0.25)
		(keepout
			(tracks not_allowed)
			(vias allowed)
			(pads allowed)
			(copperpour not_allowed)
			(footprints allowed)
		)
		(placement
			(enabled no)
			(sheetname "")
		)
		(fill
			(thermal_gap 0.5)
			(thermal_bridge_width 0.5)
			(island_removal_mode 0)
		)
		(polygon
			(pts
				(arc
					(start 315.587126 -344.814906)
					(mid 317.452248 -342.949784)
					(end 319.317116 -344.814906)
				)
				(arc
					(start 319.317116 -344.814906)
					(mid 317.452248 -346.679774)
					(end 315.587126 -344.814906)
				)
			)
		)
	)
	(zone
		(layer "F.Cu")
		(hatch none 0.5)
		(connect_pads
			(clearance 0)
		)
		(min_thickness 0.25)
		(keepout
			(tracks allowed)
			(vias allowed)
			(pads allowed)
			(copperpour allowed)
			(footprints allowed)
		)
		(placement
			(enabled no)
			(sheetname "")
		)
		(fill
			(thermal_gap 0.5)
			(thermal_bridge_width 0.5)
			(island_removal_mode 0)
		)
		(polygon
			(pts
				(xy 240.363248 -57.30748) (xy 240.363248 -55.195724) (xy 241.351562 -55.195724) (xy 241.351562 -57.30748)
			)
		)
	)
	(zone
		(layer "F.Cu")
		(hatch none 0.5)
		(connect_pads
			(clearance 0)
		)
		(min_thickness 0.25)
		(keepout
			(tracks allowed)
			(vias allowed)
			(pads allowed)
			(copperpour allowed)
			(footprints allowed)
		)
		(placement
			(enabled no)
			(sheetname "")
		)
		(fill
			(thermal_gap 0.5)
			(thermal_bridge_width 0.5)
			(island_removal_mode 0)
		)
		(polygon
			(pts
				(xy 411.574996 -293.977822) (xy 411.574996 -293.647622) (xy 413.236664 -293.647622) (xy 413.236664 -293.977822)
			)
		)
	)
	(zone
		(layer "F.Cu")
		(hatch none 0.5)
		(connect_pads
			(clearance 0)
		)
		(min_thickness 0.25)
		(keepout
			(tracks allowed)
			(vias allowed)
			(pads allowed)
			(copperpour allowed)
			(footprints allowed)
		)
		(placement
			(enabled no)
			(sheetname "")
		)
		(fill
			(thermal_gap 0.5)
			(thermal_bridge_width 0.5)
			(island_removal_mode 0)
		)
		(polygon
			(pts
				(xy 163.621974 -210.678014) (xy 163.621974 -210.347814) (xy 165.296596 -210.347814) (xy 165.296596 -210.678014)
			)
		)
	)
	(zone
		(layer "F.Cu")
		(hatch none 0.5)
		(connect_pads
			(clearance 0)
		)
		(min_thickness 0.25)
		(keepout
			(tracks allowed)
			(vias allowed)
			(pads allowed)
			(copperpour allowed)
			(footprints allowed)
		)
		(placement
			(enabled no)
			(sheetname "")
		)
		(fill
			(thermal_gap 0.5)
			(thermal_bridge_width 0.5)
			(island_removal_mode 0)
		)
		(polygon
			(pts
				(xy 353.909122 -182.110634) (xy 353.909122 -184.015634) (xy 357.922322 -184.015634) (xy 357.922322 -182.110634)
			)
		)
	)
	(zone
		(layer "F.Cu")
		(hatch none 0.5)
		(connect_pads
			(clearance 0)
		)
		(min_thickness 0.25)
		(keepout
			(tracks allowed)
			(vias allowed)
			(pads allowed)
			(copperpour allowed)
			(footprints allowed)
		)
		(placement
			(enabled no)
			(sheetname "")
		)
		(fill
			(thermal_gap 0.5)
			(thermal_bridge_width 0.5)
			(island_removal_mode 0)
		)
		(polygon
			(pts
				(xy 144.064228 -371.097302) (xy 144.064228 -370.09324) (xy 145.46072 -370.09324) (xy 145.46072 -371.097302)
			)
		)
	)
	(zone
		(layer "F.Cu")
		(hatch none 0.5)
		(connect_pads
			(clearance 0)
		)
		(min_thickness 0.25)
		(keepout
			(tracks allowed)
			(vias allowed)
			(pads allowed)
			(copperpour allowed)
			(footprints not_allowed)
		)
		(placement
			(enabled no)
			(sheetname "")
		)
		(fill
			(thermal_gap 0.5)
			(thermal_bridge_width 0.5)
			(island_removal_mode 0)
		)
		(polygon
			(pts
				(arc
					(start 320.552064 -344.814906)
					(mid 317.451994 -347.914976)
					(end 314.351924 -344.814906)
				)
				(arc
					(start 314.351924 -344.814906)
					(mid 317.451994 -341.714836)
					(end 320.552064 -344.814906)
				)
			)
		)
	)
	(zone
		(layer "F.Cu")
		(hatch none 0.5)
		(connect_pads
			(clearance 0)
		)
		(min_thickness 0.25)
		(keepout
			(tracks allowed)
			(vias allowed)
			(pads allowed)
			(copperpour allowed)
			(footprints allowed)
		)
		(placement
			(enabled no)
			(sheetname "")
		)
		(fill
			(thermal_gap 0.5)
			(thermal_bridge_width 0.5)
			(island_removal_mode 0)
		)
		(polygon
			(pts
				(xy 298.73448 -381.943102) (xy 298.73448 -380.93904) (xy 300.130972 -380.93904) (xy 300.130972 -381.943102)
			)
		)
	)
	(zone
		(layer "F.Cu")
		(hatch none 0.5)
		(connect_pads
			(clearance 0)
		)
		(min_thickness 0.25)
		(keepout
			(tracks allowed)
			(vias allowed)
			(pads allowed)
			(copperpour allowed)
			(footprints allowed)
		)
		(placement
			(enabled no)
			(sheetname "")
		)
		(fill
			(thermal_gap 0.5)
			(thermal_bridge_width 0.5)
			(island_removal_mode 0)
		)
		(polygon
			(pts
				(xy 411.317694 -264.227818) (xy 411.317694 -263.897618) (xy 413.236664 -263.897618) (xy 413.236664 -264.227818)
			)
		)
	)
	(zone
		(layer "F.Cu")
		(hatch none 0.5)
		(connect_pads
			(clearance 0)
		)
		(min_thickness 0.25)
		(keepout
			(tracks allowed)
			(vias allowed)
			(pads allowed)
			(copperpour allowed)
			(footprints not_allowed)
		)
		(placement
			(enabled no)
			(sheetname "")
		)
		(fill
			(thermal_gap 0.5)
			(thermal_bridge_width 0.5)
			(island_removal_mode 0)
		)
		(polygon
			(pts
				(arc
					(start 397.20012 -73.859898)
					(mid 412.20009 -58.859928)
					(end 397.20012 -43.859958)
				)
				(xy 397.20012 -49.509934) (xy 400.869912 -49.509934) (xy 400.869912 -68.209922) (xy 397.20012 -68.209922)
			)
		)
	)
	(zone
		(layer "F.Cu")
		(hatch none 0.5)
		(connect_pads
			(clearance 0)
		)
		(min_thickness 0.25)
		(keepout
			(tracks allowed)
			(vias allowed)
			(pads allowed)
			(copperpour allowed)
			(footprints allowed)
		)
		(placement
			(enabled no)
			(sheetname "")
		)
		(fill
			(thermal_gap 0.5)
			(thermal_bridge_width 0.5)
			(island_removal_mode 0)
		)
		(polygon
			(pts
				(xy 411.562042 -238.727742) (xy 411.562042 -238.397542) (xy 413.236664 -238.397542) (xy 413.236664 -238.727742)
			)
		)
	)
	(zone
		(layer "F.Cu")
		(hatch none 0.5)
		(connect_pads
			(clearance 0)
		)
		(min_thickness 0.25)
		(keepout
			(tracks not_allowed)
			(vias allowed)
			(pads allowed)
			(copperpour not_allowed)
			(footprints allowed)
		)
		(placement
			(enabled no)
			(sheetname "")
		)
		(fill
			(thermal_gap 0.5)
			(thermal_bridge_width 0.5)
			(island_removal_mode 0)
		)
		(polygon
			(pts
				(arc
					(start 368.498628 -435.600094)
					(mid 371.298724 -432.799998)
					(end 374.098566 -435.600094)
				)
				(arc
					(start 374.098566 -435.600094)
					(mid 371.298724 -438.399936)
					(end 368.498628 -435.600094)
				)
			)
		)
	)
	(zone
		(layer "F.Cu")
		(hatch none 0.5)
		(connect_pads
			(clearance 0)
		)
		(min_thickness 0.25)
		(keepout
			(tracks allowed)
			(vias allowed)
			(pads allowed)
			(copperpour allowed)
			(footprints not_allowed)
		)
		(placement
			(enabled no)
			(sheetname "")
		)
		(fill
			(thermal_gap 0.5)
			(thermal_bridge_width 0.5)
			(island_removal_mode 0)
		)
		(polygon
			(pts
				(xy 331.95006 -30.48) (xy 331.95006 -55.47995) (xy 364.65002 -55.47995) (xy 364.65002 -30.48)
			)
		)
	)
	(zone
		(layer "F.Cu")
		(hatch none 0.5)
		(connect_pads
			(clearance 0)
		)
		(min_thickness 0.25)
		(keepout
			(tracks not_allowed)
			(vias allowed)
			(pads allowed)
			(copperpour not_allowed)
			(footprints allowed)
		)
		(placement
			(enabled no)
			(sheetname "")
		)
		(fill
			(thermal_gap 0.5)
			(thermal_bridge_width 0.5)
			(island_removal_mode 0)
		)
		(polygon
			(pts
				(arc
					(start 387.67004 -212.989922)
					(mid 390.470136 -210.189826)
					(end 393.269978 -212.989922)
				)
				(arc
					(start 393.269978 -212.989922)
					(mid 390.470136 -215.789764)
					(end 387.67004 -212.989922)
				)
			)
		)
	)
	(zone
		(layer "F.Cu")
		(hatch none 0.5)
		(connect_pads
			(clearance 0)
		)
		(min_thickness 0.25)
		(keepout
			(tracks allowed)
			(vias allowed)
			(pads allowed)
			(copperpour allowed)
			(footprints allowed)
		)
		(placement
			(enabled no)
			(sheetname "")
		)
		(fill
			(thermal_gap 0.5)
			(thermal_bridge_width 0.5)
			(island_removal_mode 0)
		)
		(polygon
			(pts
				(xy 47.513748 -409.042616) (xy 47.513748 -408.038554) (xy 48.91024 -408.038554) (xy 48.91024 -409.042616)
			)
		)
	)
	(zone
		(layer "F.Cu")
		(hatch none 0.5)
		(connect_pads
			(clearance 0)
		)
		(min_thickness 0.25)
		(keepout
			(tracks not_allowed)
			(vias allowed)
			(pads allowed)
			(copperpour not_allowed)
			(footprints allowed)
		)
		(placement
			(enabled no)
			(sheetname "")
		)
		(fill
			(thermal_gap 0.5)
			(thermal_bridge_width 0.5)
			(island_removal_mode 0)
		)
		(polygon
			(pts
				(arc
					(start 168.74998 -404.789894)
					(mid 171.000166 -402.539708)
					(end 173.250098 -404.789894)
				)
				(arc
					(start 173.250098 -404.789894)
					(mid 171.000166 -407.039826)
					(end 168.74998 -404.789894)
				)
			)
		)
	)
	(zone
		(layer "F.Cu")
		(hatch none 0.5)
		(connect_pads
			(clearance 0)
		)
		(min_thickness 0.25)
		(keepout
			(tracks not_allowed)
			(vias allowed)
			(pads allowed)
			(copperpour not_allowed)
			(footprints allowed)
		)
		(placement
			(enabled no)
			(sheetname "")
		)
		(fill
			(thermal_gap 0.5)
			(thermal_bridge_width 0.5)
			(island_removal_mode 0)
		)
		(polygon
			(pts
				(arc
					(start 393.970002 -304.790094)
					(mid 390.470136 -308.28996)
					(end 386.970016 -304.790094)
				)
				(arc
					(start 386.970016 -304.790094)
					(mid 390.470136 -301.289974)
					(end 393.970002 -304.790094)
				)
			)
		)
	)
	(zone
		(layer "F.Cu")
		(hatch none 0.5)
		(connect_pads
			(clearance 0)
		)
		(min_thickness 0.25)
		(keepout
			(tracks allowed)
			(vias allowed)
			(pads allowed)
			(copperpour allowed)
			(footprints not_allowed)
		)
		(placement
			(enabled no)
			(sheetname "")
		)
		(fill
			(thermal_gap 0.5)
			(thermal_bridge_width 0.5)
			(island_removal_mode 0)
		)
		(polygon
			(pts
				(arc
					(start 99.899978 -22.29993)
					(mid 94.899988 -27.29992)
					(end 89.899998 -22.29993)
				)
				(arc
					(start 89.899998 -22.29993)
					(mid 94.899988 -17.29994)
					(end 99.899978 -22.29993)
				)
			)
		)
	)
	(zone
		(layer "F.Cu")
		(hatch none 0.5)
		(connect_pads
			(clearance 0)
		)
		(min_thickness 0.25)
		(keepout
			(tracks allowed)
			(vias allowed)
			(pads allowed)
			(copperpour allowed)
			(footprints allowed)
		)
		(placement
			(enabled no)
			(sheetname "")
		)
		(fill
			(thermal_gap 0.5)
			(thermal_bridge_width 0.5)
			(island_removal_mode 0)
		)
		(polygon
			(pts
				(xy 277.274274 -346.376752) (xy 270.924274 -346.376752) (xy 270.289274 -347.011752) (xy 270.289274 -351.583752)
				(xy 270.924274 -352.218752) (xy 276.893274 -352.218752) (xy 277.401274 -351.710752) (xy 277.401274 -346.503752)
			)
		)
	)
	(zone
		(layer "F.Cu")
		(hatch none 0.5)
		(connect_pads
			(clearance 0)
		)
		(min_thickness 0.25)
		(keepout
			(tracks allowed)
			(vias allowed)
			(pads allowed)
			(copperpour allowed)
			(footprints not_allowed)
		)
		(placement
			(enabled no)
			(sheetname "")
		)
		(fill
			(thermal_gap 0.5)
			(thermal_bridge_width 0.5)
			(island_removal_mode 0)
		)
		(polygon
			(pts
				(arc
					(start 68.350892 -344.814906)
					(mid 70.216014 -342.949784)
					(end 72.080882 -344.814906)
				)
				(arc
					(start 72.080882 -344.814906)
					(mid 70.216014 -346.679774)
					(end 68.350892 -344.814906)
				)
			)
		)
	)
	(zone
		(layer "F.Cu")
		(hatch none 0.5)
		(connect_pads
			(clearance 0)
		)
		(min_thickness 0.25)
		(keepout
			(tracks not_allowed)
			(vias allowed)
			(pads allowed)
			(copperpour not_allowed)
			(footprints allowed)
		)
		(placement
			(enabled no)
			(sheetname "")
		)
		(fill
			(thermal_gap 0.5)
			(thermal_bridge_width 0.5)
			(island_removal_mode 0)
		)
		(polygon
			(pts
				(xy 399.868644 -176.471072) (xy 399.868644 -175.51019) (xy 399.626328 -175.51019) (xy 399.626328 -176.471072)
			)
		)
	)
	(zone
		(layer "F.Cu")
		(hatch none 0.5)
		(connect_pads
			(clearance 0)
		)
		(min_thickness 0.25)
		(keepout
			(tracks allowed)
			(vias allowed)
			(pads allowed)
			(copperpour allowed)
			(footprints not_allowed)
		)
		(placement
			(enabled no)
			(sheetname "")
		)
		(fill
			(thermal_gap 0.5)
			(thermal_bridge_width 0.5)
			(island_removal_mode 0)
		)
		(polygon
			(pts
				(xy 309.568088 -182.060088) (xy 309.568088 -165.596062) (xy 263.347962 -165.596062) (xy 263.347962 -182.060088)
			)
		)
	)
	(zone
		(layer "F.Cu")
		(hatch none 0.5)
		(connect_pads
			(clearance 0)
		)
		(min_thickness 0.25)
		(keepout
			(tracks allowed)
			(vias allowed)
			(pads allowed)
			(copperpour allowed)
			(footprints allowed)
		)
		(placement
			(enabled no)
			(sheetname "")
		)
		(fill
			(thermal_gap 0.5)
			(thermal_bridge_width 0.5)
			(island_removal_mode 0)
		)
		(polygon
			(pts
				(xy 62.829948 -409.042616) (xy 62.829948 -408.038554) (xy 64.22644 -408.038554) (xy 64.22644 -409.042616)
			)
		)
	)
	(zone
		(layer "F.Cu")
		(hatch none 0.5)
		(connect_pads
			(clearance 0)
		)
		(min_thickness 0.25)
		(keepout
			(tracks not_allowed)
			(vias allowed)
			(pads allowed)
			(copperpour not_allowed)
			(footprints allowed)
		)
		(placement
			(enabled no)
			(sheetname "")
		)
		(fill
			(thermal_gap 0.5)
			(thermal_bridge_width 0.5)
			(island_removal_mode 0)
		)
		(polygon
			(pts
				(arc
					(start 84.829904 -212.989922)
					(mid 81.330038 -216.489788)
					(end 77.829918 -212.989922)
				)
				(arc
					(start 77.829918 -212.989922)
					(mid 81.330038 -209.489802)
					(end 84.829904 -212.989922)
				)
			)
		)
	)
	(zone
		(layer "F.Cu")
		(hatch none 0.5)
		(connect_pads
			(clearance 0)
		)
		(min_thickness 0.25)
		(keepout
			(tracks allowed)
			(vias allowed)
			(pads allowed)
			(copperpour allowed)
			(footprints allowed)
		)
		(placement
			(enabled no)
			(sheetname "")
		)
		(fill
			(thermal_gap 0.5)
			(thermal_bridge_width 0.5)
			(island_removal_mode 0)
		)
		(polygon
			(pts
				(xy 63.589154 -153.144728) (xy 63.589154 -151.369268) (xy 69.631814 -151.369268) (xy 71.254874 -149.746208)
				(xy 79.865474 -149.746208) (xy 82.792824 -149.746208) (xy 83.401916 -150.3553) (xy 83.401916 -152.961848)
				(xy 83.219036 -153.144728) (xy 79.809594 -153.144728) (xy 72.992234 -153.144728)
			)
		)
	)
	(zone
		(layer "F.Cu")
		(hatch none 0.5)
		(connect_pads
			(clearance 0)
		)
		(min_thickness 0.25)
		(keepout
			(tracks not_allowed)
			(vias allowed)
			(pads allowed)
			(copperpour not_allowed)
			(footprints allowed)
		)
		(placement
			(enabled no)
			(sheetname "")
		)
		(fill
			(thermal_gap 0.5)
			(thermal_bridge_width 0.5)
			(island_removal_mode 0)
		)
		(polygon
			(pts
				(arc
					(start 462.000092 -22.29993)
					(mid 464.800188 -19.499834)
					(end 467.60003 -22.29993)
				)
				(arc
					(start 467.60003 -22.29993)
					(mid 464.800188 -25.099772)
					(end 462.000092 -22.29993)
				)
			)
		)
	)
	(zone
		(layer "F.Cu")
		(hatch none 0.5)
		(connect_pads
			(clearance 0)
		)
		(min_thickness 0.25)
		(keepout
			(tracks allowed)
			(vias allowed)
			(pads allowed)
			(copperpour allowed)
			(footprints allowed)
		)
		(placement
			(enabled no)
			(sheetname "")
		)
		(fill
			(thermal_gap 0.5)
			(thermal_bridge_width 0.5)
			(island_removal_mode 0)
		)
		(polygon
			(pts
				(xy 410.0322 -195.12026) (xy 410.0322 -191.29248) (xy 456.06716 -191.29248) (xy 456.06716 -195.12026)
			)
		)
	)
	(zone
		(layer "F.Cu")
		(hatch none 0.5)
		(connect_pads
			(clearance 0)
		)
		(min_thickness 0.25)
		(keepout
			(tracks allowed)
			(vias allowed)
			(pads allowed)
			(copperpour allowed)
			(footprints allowed)
		)
		(placement
			(enabled no)
			(sheetname "")
		)
		(fill
			(thermal_gap 0.5)
			(thermal_bridge_width 0.5)
			(island_removal_mode 0)
		)
		(polygon
			(pts
				(xy 411.317694 -213.227666) (xy 411.317694 -212.897466) (xy 413.236664 -212.897466) (xy 413.236664 -213.227666)
			)
		)
	)
	(zone
		(layer "F.Cu")
		(hatch none 0.5)
		(connect_pads
			(clearance 0)
		)
		(min_thickness 0.25)
		(keepout
			(tracks allowed)
			(vias allowed)
			(pads allowed)
			(copperpour allowed)
			(footprints not_allowed)
		)
		(placement
			(enabled no)
			(sheetname "")
		)
		(fill
			(thermal_gap 0.5)
			(thermal_bridge_width 0.5)
			(island_removal_mode 0)
		)
		(polygon
			(pts
				(arc
					(start 314.900056 -160.50006)
					(mid 322.90004 -152.500076)
					(end 330.900024 -160.50006)
				)
				(arc
					(start 330.900024 -160.50006)
					(mid 322.90004 -168.500044)
					(end 314.900056 -160.50006)
				)
			)
		)
	)
	(zone
		(layer "F.Cu")
		(hatch none 0.5)
		(connect_pads
			(clearance 0)
		)
		(min_thickness 0.25)
		(keepout
			(tracks not_allowed)
			(vias allowed)
			(pads allowed)
			(copperpour not_allowed)
			(footprints allowed)
		)
		(placement
			(enabled no)
			(sheetname "")
		)
		(fill
			(thermal_gap 0.5)
			(thermal_bridge_width 0.5)
			(island_removal_mode 0)
		)
		(polygon
			(pts
				(arc
					(start 262.124952 -360.764074)
					(mid 258.12496 -364.764066)
					(end 254.124968 -360.764074)
				)
				(arc
					(start 254.124968 -360.764074)
					(mid 258.12496 -356.764082)
					(end 262.124952 -360.764074)
				)
			)
		)
	)
	(zone
		(layer "F.Cu")
		(hatch none 0.5)
		(connect_pads
			(clearance 0)
		)
		(min_thickness 0.25)
		(keepout
			(tracks allowed)
			(vias allowed)
			(pads allowed)
			(copperpour allowed)
			(footprints not_allowed)
		)
		(placement
			(enabled no)
			(sheetname "")
		)
		(fill
			(thermal_gap 0.5)
			(thermal_bridge_width 0.5)
			(island_removal_mode 0)
		)
		(polygon
			(pts
				(xy 218.710002 -386.409946) (xy 212.780118 -386.409946) (xy 212.780118 -394.34008) (xy 218.710002 -394.34008)
			)
		)
	)
	(zone
		(layer "F.Cu")
		(hatch none 0.5)
		(connect_pads
			(clearance 0)
		)
		(min_thickness 0.25)
		(keepout
			(tracks not_allowed)
			(vias allowed)
			(pads allowed)
			(copperpour not_allowed)
			(footprints allowed)
		)
		(placement
			(enabled no)
			(sheetname "")
		)
		(fill
			(thermal_gap 0.5)
			(thermal_bridge_width 0.5)
			(island_removal_mode 0)
		)
		(polygon
			(pts
				(arc
					(start 466.540088 -399.029936)
					(mid 463.440018 -402.130006)
					(end 460.339948 -399.029936)
				)
				(arc
					(start 460.339948 -399.029936)
					(mid 463.440018 -395.929866)
					(end 466.540088 -399.029936)
				)
			)
		)
	)
	(zone
		(layer "F.Cu")
		(hatch none 0.5)
		(connect_pads
			(clearance 0)
		)
		(min_thickness 0.25)
		(keepout
			(tracks allowed)
			(vias allowed)
			(pads allowed)
			(copperpour allowed)
			(footprints allowed)
		)
		(placement
			(enabled no)
			(sheetname "")
		)
		(fill
			(thermal_gap 0.5)
			(thermal_bridge_width 0.5)
			(island_removal_mode 0)
		)
		(polygon
			(pts
				(xy 58.13044 -226.828096) (xy 58.13044 -226.497896) (xy 60.67044 -226.497896) (xy 60.67044 -226.828096)
			)
		)
	)
	(zone
		(layer "F.Cu")
		(hatch none 0.5)
		(connect_pads
			(clearance 0)
		)
		(min_thickness 0.25)
		(keepout
			(tracks allowed)
			(vias allowed)
			(pads allowed)
			(copperpour allowed)
			(footprints not_allowed)
		)
		(placement
			(enabled no)
			(sheetname "")
		)
		(fill
			(thermal_gap 0.5)
			(thermal_bridge_width 0.5)
			(island_removal_mode 0)
		)
		(polygon
			(pts
				(xy 467.300056 -309.538878) (xy 467.300056 -279.871932) (xy 459.779116 -279.871932) (xy 459.779116 -309.538878)
			)
		)
	)
	(zone
		(layer "F.Cu")
		(hatch none 0.5)
		(connect_pads
			(clearance 0)
		)
		(min_thickness 0.25)
		(keepout
			(tracks allowed)
			(vias allowed)
			(pads allowed)
			(copperpour allowed)
			(footprints not_allowed)
		)
		(placement
			(enabled no)
			(sheetname "")
		)
		(fill
			(thermal_gap 0.5)
			(thermal_bridge_width 0.5)
			(island_removal_mode 0)
		)
		(polygon
			(pts
				(xy 48.896778 -163.314888) (xy 48.896778 -172.315124) (xy 57.954926 -172.315124) (xy 57.954926 -163.314888)
			)
		)
	)
	(zone
		(layer "F.Cu")
		(hatch none 0.5)
		(connect_pads
			(clearance 0)
		)
		(min_thickness 0.25)
		(keepout
			(tracks not_allowed)
			(vias allowed)
			(pads allowed)
			(copperpour not_allowed)
			(footprints allowed)
		)
		(placement
			(enabled no)
			(sheetname "")
		)
		(fill
			(thermal_gap 0.5)
			(thermal_bridge_width 0.5)
			(island_removal_mode 0)
		)
		(polygon
			(pts
				(xy 51.499008 -347.4212) (xy 51.499008 -348.382082) (xy 51.741324 -348.382082) (xy 51.741324 -347.4212)
			)
		)
	)
	(zone
		(layer "F.Cu")
		(hatch none 0.5)
		(connect_pads
			(clearance 0)
		)
		(min_thickness 0.25)
		(keepout
			(tracks allowed)
			(vias allowed)
			(pads allowed)
			(copperpour allowed)
			(footprints not_allowed)
		)
		(placement
			(enabled no)
			(sheetname "")
		)
		(fill
			(thermal_gap 0.5)
			(thermal_bridge_width 0.5)
			(island_removal_mode 0)
		)
		(polygon
			(pts
				(xy 308.414928 -183.50992) (xy 302.215042 -183.50992) (xy 302.215042 -327.609962) (xy 308.414928 -327.609962)
			)
		)
	)
	(zone
		(layer "F.Cu")
		(hatch none 0.5)
		(connect_pads
			(clearance 0)
		)
		(min_thickness 0.25)
		(keepout
			(tracks allowed)
			(vias allowed)
			(pads allowed)
			(copperpour allowed)
			(footprints allowed)
		)
		(placement
			(enabled no)
			(sheetname "")
		)
		(fill
			(thermal_gap 0.5)
			(thermal_bridge_width 0.5)
			(island_removal_mode 0)
		)
		(polygon
			(pts
				(xy 317.45428 -384.406902) (xy 317.45428 -383.40284) (xy 318.850772 -383.40284) (xy 318.850772 -384.406902)
			)
		)
	)
	(zone
		(layer "F.Cu")
		(hatch none 0.5)
		(connect_pads
			(clearance 0)
		)
		(min_thickness 0.25)
		(keepout
			(tracks allowed)
			(vias allowed)
			(pads allowed)
			(copperpour allowed)
			(footprints not_allowed)
		)
		(placement
			(enabled no)
			(sheetname "")
		)
		(fill
			(thermal_gap 0.5)
			(thermal_bridge_width 0.5)
			(island_removal_mode 0)
		)
		(polygon
			(pts
				(arc
					(start 270.55191 -347.8149)
					(mid 267.452094 -350.914716)
					(end 264.352024 -347.8149)
				)
				(arc
					(start 264.352024 -347.8149)
					(mid 267.452094 -344.71483)
					(end 270.55191 -347.8149)
				)
			)
		)
	)
	(zone
		(layer "F.Cu")
		(hatch none 0.5)
		(connect_pads
			(clearance 0)
		)
		(min_thickness 0.25)
		(keepout
			(tracks allowed)
			(vias allowed)
			(pads allowed)
			(copperpour allowed)
			(footprints allowed)
		)
		(placement
			(enabled no)
			(sheetname "")
		)
		(fill
			(thermal_gap 0.5)
			(thermal_bridge_width 0.5)
			(island_removal_mode 0)
		)
		(polygon
			(pts
				(xy 59.766708 -409.042616) (xy 59.766708 -408.038554) (xy 61.1632 -408.038554) (xy 61.1632 -409.042616)
			)
		)
	)
	(zone
		(layer "F.Cu")
		(hatch none 0.5)
		(connect_pads
			(clearance 0)
		)
		(min_thickness 0.25)
		(keepout
			(tracks not_allowed)
			(vias allowed)
			(pads allowed)
			(copperpour not_allowed)
			(footprints allowed)
		)
		(placement
			(enabled no)
			(sheetname "")
		)
		(fill
			(thermal_gap 0.5)
			(thermal_bridge_width 0.5)
			(island_removal_mode 0)
		)
		(polygon
			(pts
				(xy 101.684836 -340.6394) (xy 101.684836 -341.600282) (xy 101.927152 -341.600282) (xy 101.927152 -340.6394)
			)
		)
	)
	(zone
		(layer "F.Cu")
		(hatch none 0.5)
		(connect_pads
			(clearance 0)
		)
		(min_thickness 0.25)
		(keepout
			(tracks allowed)
			(vias allowed)
			(pads allowed)
			(copperpour allowed)
			(footprints not_allowed)
		)
		(placement
			(enabled no)
			(sheetname "")
		)
		(fill
			(thermal_gap 0.5)
			(thermal_bridge_width 0.5)
			(island_removal_mode 0)
		)
		(polygon
			(pts
				(arc
					(start 220.03512 -290.900104)
					(mid 221.900242 -289.034982)
					(end 223.76511 -290.900104)
				)
				(arc
					(start 223.76511 -290.900104)
					(mid 221.900242 -292.764972)
					(end 220.03512 -290.900104)
				)
			)
		)
	)
	(zone
		(layer "F.Cu")
		(hatch none 0.5)
		(connect_pads
			(clearance 0)
		)
		(min_thickness 0.25)
		(keepout
			(tracks allowed)
			(vias allowed)
			(pads allowed)
			(copperpour allowed)
			(footprints allowed)
		)
		(placement
			(enabled no)
			(sheetname "")
		)
		(fill
			(thermal_gap 0.5)
			(thermal_bridge_width 0.5)
			(island_removal_mode 0)
		)
		(polygon
			(pts
				(xy 72.019668 -409.042616) (xy 72.019668 -408.038554) (xy 73.41616 -408.038554) (xy 73.41616 -409.042616)
			)
		)
	)
	(zone
		(layer "F.Cu")
		(hatch none 0.5)
		(connect_pads
			(clearance 0)
		)
		(min_thickness 0.25)
		(keepout
			(tracks allowed)
			(vias allowed)
			(pads allowed)
			(copperpour allowed)
			(footprints not_allowed)
		)
		(placement
			(enabled no)
			(sheetname "")
		)
		(fill
			(thermal_gap 0.5)
			(thermal_bridge_width 0.5)
			(island_removal_mode 0)
		)
		(polygon
			(pts
				(arc
					(start 18.400014 -64.147446)
					(mid 22.574658 -66.269085)
					(end 27.200098 -67.00012)
				)
				(xy 27.200098 -57.53989) (xy 23.150068 -57.53989) (xy 23.150068 -46.459902) (xy 27.200098 -46.459902)
				(arc
					(start 27.200098 -36.999926)
					(mid 22.574634 -37.730889)
					(end 18.400014 -39.8526)
				)
				(arc
					(start 18.400014 -39.8526)
					(mid 14.22537 -37.730961)
					(end 9.59993 -36.999926)
				)
				(xy 9.59993 -46.459902) (xy 13.64996 -46.459902) (xy 13.64996 -57.53989) (xy 9.59993 -57.53989)
				(arc
					(start 9.59993 -67.00012)
					(mid 14.225394 -66.269157)
					(end 18.400014 -64.147446)
				)
			)
		)
	)
	(zone
		(layer "F.Cu")
		(hatch none 0.5)
		(connect_pads
			(clearance 0)
		)
		(min_thickness 0.25)
		(keepout
			(tracks allowed)
			(vias allowed)
			(pads allowed)
			(copperpour allowed)
			(footprints not_allowed)
		)
		(placement
			(enabled no)
			(sheetname "")
		)
		(fill
			(thermal_gap 0.5)
			(thermal_bridge_width 0.5)
			(island_removal_mode 0)
		)
		(polygon
			(pts
				(xy 158.500064 -440.889898) (xy 161.59988 -440.889898) (xy 161.59988 -417.889944) (xy 121.299986 -417.889944)
				(xy 121.299986 -440.889898) (xy 124.400056 -440.889898) (xy 124.400056 -420.990014) (xy 158.500064 -420.990014)
			)
		)
	)
	(zone
		(layer "F.Cu")
		(hatch none 0.5)
		(connect_pads
			(clearance 0)
		)
		(min_thickness 0.25)
		(keepout
			(tracks allowed)
			(vias allowed)
			(pads allowed)
			(copperpour allowed)
			(footprints allowed)
		)
		(placement
			(enabled no)
			(sheetname "")
		)
		(fill
			(thermal_gap 0.5)
			(thermal_bridge_width 0.5)
			(island_removal_mode 0)
		)
		(polygon
			(pts
				(xy 411.317694 -248.927874) (xy 411.317694 -248.597674) (xy 413.236664 -248.597674) (xy 413.236664 -248.927874)
			)
		)
	)
	(zone
		(layer "F.Cu")
		(hatch none 0.5)
		(connect_pads
			(clearance 0)
		)
		(min_thickness 0.25)
		(keepout
			(tracks allowed)
			(vias allowed)
			(pads allowed)
			(copperpour allowed)
			(footprints not_allowed)
		)
		(placement
			(enabled no)
			(sheetname "")
		)
		(fill
			(thermal_gap 0.5)
			(thermal_bridge_width 0.5)
			(island_removal_mode 0)
		)
		(polygon
			(pts
				(arc
					(start 184.749948 -435.600094)
					(mid 179.749958 -440.600084)
					(end 174.749968 -435.600094)
				)
				(arc
					(start 174.749968 -435.600094)
					(mid 179.749958 -430.600104)
					(end 184.749948 -435.600094)
				)
			)
		)
	)
	(zone
		(layer "F.Cu")
		(hatch none 0.5)
		(connect_pads
			(clearance 0)
		)
		(min_thickness 0.25)
		(keepout
			(tracks allowed)
			(vias allowed)
			(pads allowed)
			(copperpour allowed)
			(footprints allowed)
		)
		(placement
			(enabled no)
			(sheetname "")
		)
		(fill
			(thermal_gap 0.5)
			(thermal_bridge_width 0.5)
			(island_removal_mode 0)
		)
		(polygon
			(pts
				(xy 306.070508 -246.377714) (xy 306.070508 -246.047514) (xy 308.610508 -246.047514) (xy 308.610508 -246.377714)
			)
		)
	)
	(zone
		(layer "F.Cu")
		(hatch none 0.5)
		(connect_pads
			(clearance 0)
		)
		(min_thickness 0.25)
		(keepout
			(tracks allowed)
			(vias allowed)
			(pads allowed)
			(copperpour allowed)
			(footprints allowed)
		)
		(placement
			(enabled no)
			(sheetname "")
		)
		(fill
			(thermal_gap 0.5)
			(thermal_bridge_width 0.5)
			(island_removal_mode 0)
		)
		(polygon
			(pts
				(xy 411.317694 -248.077736) (xy 411.317694 -247.747536) (xy 413.236664 -247.747536) (xy 413.236664 -248.077736)
			)
		)
	)
	(zone
		(layer "F.Cu")
		(hatch none 0.5)
		(connect_pads
			(clearance 0)
		)
		(min_thickness 0.25)
		(keepout
			(tracks allowed)
			(vias allowed)
			(pads allowed)
			(copperpour allowed)
			(footprints allowed)
		)
		(placement
			(enabled no)
			(sheetname "")
		)
		(fill
			(thermal_gap 0.5)
			(thermal_bridge_width 0.5)
			(island_removal_mode 0)
		)
		(polygon
			(pts
				(xy 290.571428 -426.58284) (xy 291.746686 -426.58284) (xy 291.746686 -427.547024) (xy 290.571428 -427.547024)
			)
		)
	)
	(zone
		(layer "F.Cu")
		(hatch none 0.5)
		(connect_pads
			(clearance 0)
		)
		(min_thickness 0.25)
		(keepout
			(tracks allowed)
			(vias allowed)
			(pads allowed)
			(copperpour allowed)
			(footprints not_allowed)
		)
		(placement
			(enabled no)
			(sheetname "")
		)
		(fill
			(thermal_gap 0.5)
			(thermal_bridge_width 0.5)
			(island_removal_mode 0)
		)
		(polygon
			(pts
				(arc
					(start 288.820098 -384.869944)
					(mid 291.07003 -382.620012)
					(end 293.319962 -384.869944)
				)
				(arc
					(start 293.319962 -384.869944)
					(mid 291.07003 -387.119876)
					(end 288.820098 -384.869944)
				)
			)
		)
	)
	(zone
		(layer "F.Cu")
		(hatch none 0.5)
		(connect_pads
			(clearance 0)
		)
		(min_thickness 0.25)
		(keepout
			(tracks allowed)
			(vias allowed)
			(pads allowed)
			(copperpour allowed)
			(footprints allowed)
		)
		(placement
			(enabled no)
			(sheetname "")
		)
		(fill
			(thermal_gap 0.5)
			(thermal_bridge_width 0.5)
			(island_removal_mode 0)
		)
		(polygon
			(pts
				(xy 163.634928 -303.32807) (xy 163.634928 -302.99787) (xy 165.296596 -302.99787) (xy 165.296596 -303.32807)
			)
		)
	)
	(zone
		(layer "F.Cu")
		(hatch none 0.5)
		(connect_pads
			(clearance 0)
		)
		(min_thickness 0.25)
		(keepout
			(tracks not_allowed)
			(vias allowed)
			(pads allowed)
			(copperpour not_allowed)
			(footprints allowed)
		)
		(placement
			(enabled no)
			(sheetname "")
		)
		(fill
			(thermal_gap 0.5)
			(thermal_bridge_width 0.5)
			(island_removal_mode 0)
		)
		(polygon
			(pts
				(arc
					(start 298.00296 -74.76109)
					(mid 293.00297 -79.76108)
					(end 288.00298 -74.76109)
				)
				(arc
					(start 288.00298 -66.061082)
					(mid 293.00297 -61.061092)
					(end 298.00296 -66.061082)
				)
			)
		)
	)
	(zone
		(layer "F.Cu")
		(hatch none 0.5)
		(connect_pads
			(clearance 0)
		)
		(min_thickness 0.25)
		(keepout
			(tracks allowed)
			(vias allowed)
			(pads allowed)
			(copperpour allowed)
			(footprints allowed)
		)
		(placement
			(enabled no)
			(sheetname "")
		)
		(fill
			(thermal_gap 0.5)
			(thermal_bridge_width 0.5)
			(island_removal_mode 0)
		)
		(polygon
			(pts
				(xy 356.789228 -379.479302) (xy 356.789228 -378.47524) (xy 358.18572 -378.47524) (xy 358.18572 -379.479302)
			)
		)
	)
	(zone
		(layer "F.Cu")
		(hatch none 0.5)
		(connect_pads
			(clearance 0)
		)
		(min_thickness 0.25)
		(keepout
			(tracks allowed)
			(vias allowed)
			(pads allowed)
			(copperpour allowed)
			(footprints allowed)
		)
		(placement
			(enabled no)
			(sheetname "")
		)
		(fill
			(thermal_gap 0.5)
			(thermal_bridge_width 0.5)
			(island_removal_mode 0)
		)
		(polygon
			(pts
				(xy 185.7502 -30.9245) (xy 193.9417 -30.9245) (xy 195.0593 -29.8069) (xy 195.0593 -22.42058) (xy 191.2112 -18.57248)
				(xy 191.2112 -15.55496) (xy 189.91072 -14.25448) (xy 187.10148 -14.25448) (xy 184.00776 -17.3482)
				(xy 184.00776 -29.18206)
			)
		)
	)
	(zone
		(layer "F.Cu")
		(hatch none 0.5)
		(connect_pads
			(clearance 0)
		)
		(min_thickness 0.25)
		(keepout
			(tracks allowed)
			(vias allowed)
			(pads allowed)
			(copperpour allowed)
			(footprints allowed)
		)
		(placement
			(enabled no)
			(sheetname "")
		)
		(fill
			(thermal_gap 0.5)
			(thermal_bridge_width 0.5)
			(island_removal_mode 0)
		)
		(polygon
			(pts
				(xy 329.375262 -334.863948) (xy 323.025262 -334.863948) (xy 322.390262 -335.498948) (xy 322.390262 -340.070948)
				(xy 323.025262 -340.705948) (xy 328.994262 -340.705948) (xy 329.502262 -340.197948) (xy 329.502262 -334.990948)
			)
		)
	)
	(zone
		(layer "F.Cu")
		(hatch none 0.5)
		(connect_pads
			(clearance 0)
		)
		(min_thickness 0.25)
		(keepout
			(tracks allowed)
			(vias allowed)
			(pads allowed)
			(copperpour allowed)
			(footprints allowed)
		)
		(placement
			(enabled no)
			(sheetname "")
		)
		(fill
			(thermal_gap 0.5)
			(thermal_bridge_width 0.5)
			(island_removal_mode 0)
		)
		(polygon
			(pts
				(xy 308.66588 -300.442376) (xy 308.66588 -300.772576) (xy 306.12588 -300.772576) (xy 306.12588 -300.442376)
			)
		)
	)
	(zone
		(layer "F.Cu")
		(hatch none 0.5)
		(connect_pads
			(clearance 0)
		)
		(min_thickness 0.25)
		(keepout
			(tracks allowed)
			(vias allowed)
			(pads allowed)
			(copperpour allowed)
			(footprints not_allowed)
		)
		(placement
			(enabled no)
			(sheetname "")
		)
		(fill
			(thermal_gap 0.5)
			(thermal_bridge_width 0.5)
			(island_removal_mode 0)
		)
		(polygon
			(pts
				(arc
					(start 412.08706 -351.415096)
					(mid 413.952182 -349.549974)
					(end 415.81705 -351.415096)
				)
				(arc
					(start 415.81705 -351.415096)
					(mid 413.952182 -353.279964)
					(end 412.08706 -351.415096)
				)
			)
		)
	)
	(zone
		(layer "F.Cu")
		(hatch none 0.5)
		(connect_pads
			(clearance 0)
		)
		(min_thickness 0.25)
		(keepout
			(tracks allowed)
			(vias allowed)
			(pads allowed)
			(copperpour allowed)
			(footprints allowed)
		)
		(placement
			(enabled no)
			(sheetname "")
		)
		(fill
			(thermal_gap 0.5)
			(thermal_bridge_width 0.5)
			(island_removal_mode 0)
		)
		(polygon
			(pts
				(xy 60.344812 -237.542832) (xy 60.344812 -237.873032) (xy 57.804812 -237.873032) (xy 57.804812 -237.542832)
			)
		)
	)
	(zone
		(layer "F.Cu")
		(hatch none 0.5)
		(connect_pads
			(clearance 0)
		)
		(min_thickness 0.25)
		(keepout
			(tracks allowed)
			(vias allowed)
			(pads allowed)
			(copperpour allowed)
			(footprints allowed)
		)
		(placement
			(enabled no)
			(sheetname "")
		)
		(fill
			(thermal_gap 0.5)
			(thermal_bridge_width 0.5)
			(island_removal_mode 0)
		)
		(polygon
			(pts
				(xy 300.736508 -148.976334) (xy 300.736508 -146.980148) (xy 301.44339 -146.980148) (xy 301.44339 -148.976334)
			)
		)
	)
	(zone
		(layer "F.Cu")
		(hatch none 0.5)
		(connect_pads
			(clearance 0)
		)
		(min_thickness 0.25)
		(keepout
			(tracks allowed)
			(vias allowed)
			(pads allowed)
			(copperpour allowed)
			(footprints not_allowed)
		)
		(placement
			(enabled no)
			(sheetname "")
		)
		(fill
			(thermal_gap 0.5)
			(thermal_bridge_width 0.5)
			(island_removal_mode 0)
		)
		(polygon
			(pts
				(xy 61.62802 -329.060048) (xy 11.999976 -329.060048)
				(arc
					(start 11.999976 -339.874098)
					(mid 14.652568 -340.961849)
					(end 16.7513 -342.914986)
				)
				(xy 61.62802 -342.914986)
			)
		)
	)
	(zone
		(layer "F.Cu")
		(hatch none 0.5)
		(connect_pads
			(clearance 0)
		)
		(min_thickness 0.25)
		(keepout
			(tracks allowed)
			(vias allowed)
			(pads allowed)
			(copperpour allowed)
			(footprints allowed)
		)
		(placement
			(enabled no)
			(sheetname "")
		)
		(fill
			(thermal_gap 0.5)
			(thermal_bridge_width 0.5)
			(island_removal_mode 0)
		)
		(polygon
			(pts
				(xy 347.773498 -325.414894) (xy 347.773498 -327.319894) (xy 351.786698 -327.319894) (xy 351.786698 -325.414894)
			)
		)
	)
	(zone
		(layer "F.Cu")
		(hatch none 0.5)
		(connect_pads
			(clearance 0)
		)
		(min_thickness 0.25)
		(keepout
			(tracks allowed)
			(vias allowed)
			(pads allowed)
			(copperpour allowed)
			(footprints not_allowed)
		)
		(placement
			(enabled no)
			(sheetname "")
		)
		(fill
			(thermal_gap 0.5)
			(thermal_bridge_width 0.5)
			(island_removal_mode 0)
		)
		(polygon
			(pts
				(arc
					(start 37.969952 -389.439912)
					(mid 34.870136 -392.539728)
					(end 31.770066 -389.439912)
				)
				(arc
					(start 31.770066 -389.439912)
					(mid 34.870136 -386.339842)
					(end 37.969952 -389.439912)
				)
			)
		)
	)
	(zone
		(layer "F.Cu")
		(hatch none 0.5)
		(connect_pads
			(clearance 0)
		)
		(min_thickness 0.25)
		(keepout
			(tracks not_allowed)
			(vias allowed)
			(pads allowed)
			(copperpour not_allowed)
			(footprints allowed)
		)
		(placement
			(enabled no)
			(sheetname "")
		)
		(fill
			(thermal_gap 0.5)
			(thermal_bridge_width 0.5)
			(island_removal_mode 0)
		)
		(polygon
			(pts
				(xy 67.692016 -168.228518) (xy 67.692016 -167.267636) (xy 67.4497 -167.267636) (xy 67.4497 -168.228518)
			)
		)
	)
	(zone
		(layer "F.Cu")
		(hatch none 0.5)
		(connect_pads
			(clearance 0)
		)
		(min_thickness 0.25)
		(keepout
			(tracks allowed)
			(vias allowed)
			(pads allowed)
			(copperpour allowed)
			(footprints allowed)
		)
		(placement
			(enabled no)
			(sheetname "")
		)
		(fill
			(thermal_gap 0.5)
			(thermal_bridge_width 0.5)
			(island_removal_mode 0)
		)
		(polygon
			(pts
				(xy 163.377626 -282.928314) (xy 163.377626 -282.598114) (xy 165.296596 -282.598114) (xy 165.296596 -282.928314)
			)
		)
	)
	(zone
		(layer "F.Cu")
		(hatch none 0.5)
		(connect_pads
			(clearance 0)
		)
		(min_thickness 0.25)
		(keepout
			(tracks allowed)
			(vias allowed)
			(pads allowed)
			(copperpour allowed)
			(footprints allowed)
		)
		(placement
			(enabled no)
			(sheetname "")
		)
		(fill
			(thermal_gap 0.5)
			(thermal_bridge_width 0.5)
			(island_removal_mode 0)
		)
		(polygon
			(pts
				(xy 33.124902 -425.732194) (xy 33.124902 -427.128686) (xy 32.12084 -427.128686) (xy 32.12084 -425.732194)
				(xy 32.12084 -425.205398) (xy 32.257238 -425.069) (xy 32.257238 -423.243756) (xy 32.525462 -422.975532)
				(xy 32.947356 -422.975532) (xy 33.124902 -423.153078) (xy 33.124902 -425.209208)
			)
		)
	)
	(zone
		(layer "F.Cu")
		(hatch none 0.5)
		(connect_pads
			(clearance 0)
		)
		(min_thickness 0.25)
		(keepout
			(tracks allowed)
			(vias allowed)
			(pads allowed)
			(copperpour allowed)
			(footprints allowed)
		)
		(placement
			(enabled no)
			(sheetname "")
		)
		(fill
			(thermal_gap 0.5)
			(thermal_bridge_width 0.5)
			(island_removal_mode 0)
		)
		(polygon
			(pts
				(xy 321.89293 -417.424616) (xy 321.89293 -416.420554) (xy 323.289422 -416.420554) (xy 323.289422 -417.424616)
			)
		)
	)
	(zone
		(layer "F.Cu")
		(hatch none 0.5)
		(connect_pads
			(clearance 0)
		)
		(min_thickness 0.25)
		(keepout
			(tracks allowed)
			(vias allowed)
			(pads allowed)
			(copperpour allowed)
			(footprints not_allowed)
		)
		(placement
			(enabled no)
			(sheetname "")
		)
		(fill
			(thermal_gap 0.5)
			(thermal_bridge_width 0.5)
			(island_removal_mode 0)
		)
		(polygon
			(pts
				(xy 186.006994 -183.50992) (xy 186.006994 -327.609962) (xy 192.20688 -327.609962) (xy 192.20688 -183.50992)
			)
		)
	)
	(zone
		(layer "F.Cu")
		(hatch none 0.5)
		(connect_pads
			(clearance 0)
		)
		(min_thickness 0.25)
		(keepout
			(tracks allowed)
			(vias allowed)
			(pads allowed)
			(copperpour allowed)
			(footprints allowed)
		)
		(placement
			(enabled no)
			(sheetname "")
		)
		(fill
			(thermal_gap 0.5)
			(thermal_bridge_width 0.5)
			(island_removal_mode 0)
		)
		(polygon
			(pts
				(xy 306.070508 -263.37768) (xy 306.070508 -263.04748) (xy 308.610508 -263.04748) (xy 308.610508 -263.37768)
			)
		)
	)
	(zone
		(layer "F.Cu")
		(hatch none 0.5)
		(connect_pads
			(clearance 0)
		)
		(min_thickness 0.25)
		(keepout
			(tracks allowed)
			(vias allowed)
			(pads allowed)
			(copperpour allowed)
			(footprints allowed)
		)
		(placement
			(enabled no)
			(sheetname "")
		)
		(fill
			(thermal_gap 0.5)
			(thermal_bridge_width 0.5)
			(island_removal_mode 0)
		)
		(polygon
			(pts
				(xy 61.454538 -376.024902) (xy 61.454538 -375.02084) (xy 62.85103 -375.02084) (xy 62.85103 -376.024902)
			)
		)
	)
	(zone
		(layer "F.Cu")
		(hatch none 0.5)
		(connect_pads
			(clearance 0)
		)
		(min_thickness 0.25)
		(keepout
			(tracks allowed)
			(vias allowed)
			(pads allowed)
			(copperpour allowed)
			(footprints allowed)
		)
		(placement
			(enabled no)
			(sheetname "")
		)
		(fill
			(thermal_gap 0.5)
			(thermal_bridge_width 0.5)
			(island_removal_mode 0)
		)
		(polygon
			(pts
				(xy 163.23564 -191.385444) (xy 163.23564 -319.663064) (xy 207.31099 -319.663064) (xy 207.31099 -191.385444)
			)
		)
	)
	(zone
		(layer "F.Cu")
		(hatch none 0.5)
		(connect_pads
			(clearance 0)
		)
		(min_thickness 0.25)
		(keepout
			(tracks allowed)
			(vias allowed)
			(pads allowed)
			(copperpour allowed)
			(footprints not_allowed)
		)
		(placement
			(enabled no)
			(sheetname "")
		)
		(fill
			(thermal_gap 0.5)
			(thermal_bridge_width 0.5)
			(island_removal_mode 0)
		)
		(polygon
			(pts
				(xy 295.980104 -401.910042) (xy 295.980104 -406.940004) (xy 300.68012 -406.940004) (xy 300.68012 -401.910042)
			)
		)
	)
	(zone
		(layer "F.Cu")
		(hatch none 0.5)
		(connect_pads
			(clearance 0)
		)
		(min_thickness 0.25)
		(keepout
			(tracks allowed)
			(vias allowed)
			(pads allowed)
			(copperpour allowed)
			(footprints allowed)
		)
		(placement
			(enabled no)
			(sheetname "")
		)
		(fill
			(thermal_gap 0.5)
			(thermal_bridge_width 0.5)
			(island_removal_mode 0)
		)
		(polygon
			(pts
				(xy 84.272628 -409.042616) (xy 84.272628 -408.038554) (xy 85.66912 -408.038554) (xy 85.66912 -409.042616)
			)
		)
	)
	(zone
		(layer "F.Cu")
		(hatch none 0.5)
		(connect_pads
			(clearance 0)
		)
		(min_thickness 0.25)
		(keepout
			(tracks not_allowed)
			(vias allowed)
			(pads allowed)
			(copperpour not_allowed)
			(footprints allowed)
		)
		(placement
			(enabled no)
			(sheetname "")
		)
		(fill
			(thermal_gap 0.5)
			(thermal_bridge_width 0.5)
			(island_removal_mode 0)
		)
		(polygon
			(pts
				(arc
					(start 290.74999 -435.600094)
					(mid 293.550086 -432.799998)
					(end 296.349928 -435.600094)
				)
				(arc
					(start 296.349928 -435.600094)
					(mid 293.550086 -438.399936)
					(end 290.74999 -435.600094)
				)
			)
		)
	)
	(zone
		(layer "F.Cu")
		(hatch none 0.5)
		(connect_pads
			(clearance 0)
		)
		(min_thickness 0.25)
		(keepout
			(tracks allowed)
			(vias allowed)
			(pads allowed)
			(copperpour allowed)
			(footprints not_allowed)
		)
		(placement
			(enabled no)
			(sheetname "")
		)
		(fill
			(thermal_gap 0.5)
			(thermal_bridge_width 0.5)
			(island_removal_mode 0)
		)
		(polygon
			(pts
				(xy 303.502568 -87.293196) (xy 303.502568 -59.993276) (xy 282.504642 -59.99099) (xy 282.501848 -87.29091)
			)
		)
	)
	(zone
		(layer "F.Cu")
		(hatch none 0.5)
		(connect_pads
			(clearance 0)
		)
		(min_thickness 0.25)
		(keepout
			(tracks allowed)
			(vias allowed)
			(pads allowed)
			(copperpour allowed)
			(footprints allowed)
		)
		(placement
			(enabled no)
			(sheetname "")
		)
		(fill
			(thermal_gap 0.5)
			(thermal_bridge_width 0.5)
			(island_removal_mode 0)
		)
		(polygon
			(pts
				(xy 426.38472 -350.77527) (xy 420.03472 -350.77527) (xy 419.39972 -351.41027) (xy 419.39972 -355.98227)
				(xy 420.03472 -356.61727) (xy 426.00372 -356.61727) (xy 426.51172 -356.10927) (xy 426.51172 -350.90227)
			)
		)
	)
	(zone
		(layer "F.Cu")
		(hatch none 0.5)
		(connect_pads
			(clearance 0)
		)
		(min_thickness 0.25)
		(keepout
			(tracks allowed)
			(vias allowed)
			(pads allowed)
			(copperpour allowed)
			(footprints allowed)
		)
		(placement
			(enabled no)
			(sheetname "")
		)
		(fill
			(thermal_gap 0.5)
			(thermal_bridge_width 0.5)
			(island_removal_mode 0)
		)
		(polygon
			(pts
				(xy 310.548274 -346.376752) (xy 304.198274 -346.376752) (xy 303.563274 -347.011752) (xy 303.563274 -351.583752)
				(xy 304.198274 -352.218752) (xy 310.167274 -352.218752) (xy 310.675274 -351.710752) (xy 310.675274 -346.503752)
			)
		)
	)
	(zone
		(layer "F.Cu")
		(hatch none 0.5)
		(connect_pads
			(clearance 0)
		)
		(min_thickness 0.25)
		(keepout
			(tracks allowed)
			(vias allowed)
			(pads allowed)
			(copperpour allowed)
			(footprints not_allowed)
		)
		(placement
			(enabled no)
			(sheetname "")
		)
		(fill
			(thermal_gap 0.5)
			(thermal_bridge_width 0.5)
			(island_removal_mode 0)
		)
		(polygon
			(pts
				(xy 212.780118 -394.34008) (xy 218.710002 -394.34008) (xy 218.710002 -386.409946) (xy 212.780118 -386.409946)
			)
		)
	)
	(zone
		(layer "F.Cu")
		(hatch none 0.5)
		(connect_pads
			(clearance 0)
		)
		(min_thickness 0.25)
		(keepout
			(tracks allowed)
			(vias allowed)
			(pads allowed)
			(copperpour allowed)
			(footprints allowed)
		)
		(placement
			(enabled no)
			(sheetname "")
		)
		(fill
			(thermal_gap 0.5)
			(thermal_bridge_width 0.5)
			(island_removal_mode 0)
		)
		(polygon
			(pts
				(xy 136.1948 -37.8206) (xy 137.8458 -37.8206) (xy 138.1252 -37.5412) (xy 138.1252 -34.671) (xy 137.4394 -33.9852)
				(xy 136.1694 -33.9852) (xy 135.8646 -34.29) (xy 135.8646 -37.4904)
			)
		)
	)
	(zone
		(layer "F.Cu")
		(hatch none 0.5)
		(connect_pads
			(clearance 0)
		)
		(min_thickness 0.25)
		(keepout
			(tracks allowed)
			(vias allowed)
			(pads allowed)
			(copperpour allowed)
			(footprints allowed)
		)
		(placement
			(enabled no)
			(sheetname "")
		)
		(fill
			(thermal_gap 0.5)
			(thermal_bridge_width 0.5)
			(island_removal_mode 0)
		)
		(polygon
			(pts
				(xy 308.66588 -274.092416) (xy 308.66588 -274.422616) (xy 306.12588 -274.422616) (xy 306.12588 -274.092416)
			)
		)
	)
	(zone
		(layer "F.Cu")
		(hatch none 0.5)
		(connect_pads
			(clearance 0)
		)
		(min_thickness 0.25)
		(keepout
			(tracks allowed)
			(vias allowed)
			(pads allowed)
			(copperpour allowed)
			(footprints allowed)
		)
		(placement
			(enabled no)
			(sheetname "")
		)
		(fill
			(thermal_gap 0.5)
			(thermal_bridge_width 0.5)
			(island_removal_mode 0)
		)
		(polygon
			(pts
				(xy 163.377626 -244.677946) (xy 163.377626 -244.347746) (xy 165.296596 -244.347746) (xy 165.296596 -244.677946)
			)
		)
	)
	(zone
		(layer "F.Cu")
		(hatch none 0.5)
		(connect_pads
			(clearance 0)
		)
		(min_thickness 0.25)
		(keepout
			(tracks allowed)
			(vias allowed)
			(pads allowed)
			(copperpour allowed)
			(footprints allowed)
		)
		(placement
			(enabled no)
			(sheetname "")
		)
		(fill
			(thermal_gap 0.5)
			(thermal_bridge_width 0.5)
			(island_removal_mode 0)
		)
		(polygon
			(pts
				(xy 58.13044 -214.927942) (xy 58.13044 -214.597742) (xy 60.67044 -214.597742) (xy 60.67044 -214.927942)
			)
		)
	)
	(zone
		(layer "F.Cu")
		(hatch none 0.5)
		(connect_pads
			(clearance 0)
		)
		(min_thickness 0.25)
		(keepout
			(tracks allowed)
			(vias allowed)
			(pads allowed)
			(copperpour allowed)
			(footprints allowed)
		)
		(placement
			(enabled no)
			(sheetname "")
		)
		(fill
			(thermal_gap 0.5)
			(thermal_bridge_width 0.5)
			(island_removal_mode 0)
		)
		(polygon
			(pts
				(xy 306.070508 -205.577694) (xy 306.070508 -205.247494) (xy 308.610508 -205.247494) (xy 308.610508 -205.577694)
			)
		)
	)
	(zone
		(layer "F.Cu")
		(hatch none 0.5)
		(connect_pads
			(clearance 0)
		)
		(min_thickness 0.25)
		(keepout
			(tracks allowed)
			(vias allowed)
			(pads allowed)
			(copperpour allowed)
			(footprints not_allowed)
		)
		(placement
			(enabled no)
			(sheetname "")
		)
		(fill
			(thermal_gap 0.5)
			(thermal_bridge_width 0.5)
			(island_removal_mode 0)
		)
		(polygon
			(pts
				(arc
					(start 392.622024 -173.315122)
					(mid 389.521954 -176.415192)
					(end 386.421884 -173.315122)
				)
				(arc
					(start 386.421884 -173.315122)
					(mid 389.521954 -170.215052)
					(end 392.622024 -173.315122)
				)
			)
		)
	)
	(zone
		(layer "F.Cu")
		(hatch none 0.5)
		(connect_pads
			(clearance 0)
		)
		(min_thickness 0.25)
		(keepout
			(tracks allowed)
			(vias allowed)
			(pads allowed)
			(copperpour allowed)
			(footprints allowed)
		)
		(placement
			(enabled no)
			(sheetname "")
		)
		(fill
			(thermal_gap 0.5)
			(thermal_bridge_width 0.5)
			(island_removal_mode 0)
		)
		(polygon
			(pts
				(xy 118.34368 -371.097302) (xy 118.34368 -370.09324) (xy 119.740172 -370.09324) (xy 119.740172 -371.097302)
			)
		)
	)
	(zone
		(layer "F.Cu")
		(hatch none 0.5)
		(connect_pads
			(clearance 0)
		)
		(min_thickness 0.25)
		(keepout
			(tracks allowed)
			(vias allowed)
			(pads allowed)
			(copperpour allowed)
			(footprints allowed)
		)
		(placement
			(enabled no)
			(sheetname "")
		)
		(fill
			(thermal_gap 0.5)
			(thermal_bridge_width 0.5)
			(island_removal_mode 0)
		)
		(polygon
			(pts
				(xy 31.352998 -360.466894) (xy 31.352998 -359.462832) (xy 32.15513 -359.462832) (xy 32.15513 -360.466894)
			)
		)
	)
	(zone
		(layer "F.Cu")
		(hatch none 0.5)
		(connect_pads
			(clearance 0)
		)
		(min_thickness 0.25)
		(keepout
			(tracks allowed)
			(vias allowed)
			(pads allowed)
			(copperpour allowed)
			(footprints allowed)
		)
		(placement
			(enabled no)
			(sheetname "")
		)
		(fill
			(thermal_gap 0.5)
			(thermal_bridge_width 0.5)
			(island_removal_mode 0)
		)
		(polygon
			(pts
				(xy 448.19316 -417.877498) (xy 448.968876 -417.877498) (xy 448.968876 -418.616638) (xy 448.19316 -418.616638)
			)
		)
	)
	(zone
		(layer "F.Cu")
		(hatch none 0.5)
		(connect_pads
			(clearance 0)
		)
		(min_thickness 0.25)
		(keepout
			(tracks allowed)
			(vias allowed)
			(pads allowed)
			(copperpour allowed)
			(footprints allowed)
		)
		(placement
			(enabled no)
			(sheetname "")
		)
		(fill
			(thermal_gap 0.5)
			(thermal_bridge_width 0.5)
			(island_removal_mode 0)
		)
		(polygon
			(pts
				(xy 381.150622 -379.479302) (xy 381.150622 -378.47524) (xy 382.547114 -378.47524) (xy 382.547114 -379.479302)
			)
		)
	)
	(zone
		(layer "F.Cu")
		(hatch none 0.5)
		(connect_pads
			(clearance 0)
		)
		(min_thickness 0.25)
		(keepout
			(tracks allowed)
			(vias allowed)
			(pads allowed)
			(copperpour allowed)
			(footprints allowed)
		)
		(placement
			(enabled no)
			(sheetname "")
		)
		(fill
			(thermal_gap 0.5)
			(thermal_bridge_width 0.5)
			(island_removal_mode 0)
		)
		(polygon
			(pts
				(xy 106.086148 -190.790322) (xy 106.086148 -192.695322) (xy 110.099348 -192.695322) (xy 110.099348 -190.790322)
			)
		)
	)
	(zone
		(layer "F.Cu")
		(hatch none 0.5)
		(connect_pads
			(clearance 0)
		)
		(min_thickness 0.25)
		(keepout
			(tracks not_allowed)
			(vias allowed)
			(pads allowed)
			(copperpour not_allowed)
			(footprints allowed)
		)
		(placement
			(enabled no)
			(sheetname "")
		)
		(fill
			(thermal_gap 0.5)
			(thermal_bridge_width 0.5)
			(island_removal_mode 0)
		)
		(polygon
			(pts
				(arc
					(start 298.550076 -435.600094)
					(mid 293.550086 -440.600084)
					(end 288.550096 -435.600094)
				)
				(arc
					(start 288.550096 -435.600094)
					(mid 293.550086 -430.600104)
					(end 298.550076 -435.600094)
				)
			)
		)
	)
	(zone
		(layer "F.Cu")
		(hatch none 0.5)
		(connect_pads
			(clearance 0)
		)
		(min_thickness 0.25)
		(keepout
			(tracks allowed)
			(vias allowed)
			(pads allowed)
			(copperpour allowed)
			(footprints not_allowed)
		)
		(placement
			(enabled no)
			(sheetname "")
		)
		(fill
			(thermal_gap 0.5)
			(thermal_bridge_width 0.5)
			(island_removal_mode 0)
		)
		(polygon
			(pts
				(arc
					(start 32.820102 -376.489976)
					(mid 35.070034 -374.240044)
					(end 37.319966 -376.489976)
				)
				(arc
					(start 37.319966 -376.489976)
					(mid 35.070034 -378.739908)
					(end 32.820102 -376.489976)
				)
			)
		)
	)
	(zone
		(layer "F.Cu")
		(hatch none 0.5)
		(connect_pads
			(clearance 0)
		)
		(min_thickness 0.25)
		(keepout
			(tracks allowed)
			(vias allowed)
			(pads allowed)
			(copperpour allowed)
			(footprints allowed)
		)
		(placement
			(enabled no)
			(sheetname "")
		)
		(fill
			(thermal_gap 0.5)
			(thermal_bridge_width 0.5)
			(island_removal_mode 0)
		)
		(polygon
			(pts
				(xy 128.55448 -376.024902) (xy 128.55448 -375.02084) (xy 129.950972 -375.02084) (xy 129.950972 -376.024902)
			)
		)
	)
	(zone
		(layer "F.Cu")
		(hatch none 0.5)
		(connect_pads
			(clearance 0)
		)
		(min_thickness 0.25)
		(keepout
			(tracks allowed)
			(vias allowed)
			(pads allowed)
			(copperpour allowed)
			(footprints allowed)
		)
		(placement
			(enabled no)
			(sheetname "")
		)
		(fill
			(thermal_gap 0.5)
			(thermal_bridge_width 0.5)
			(island_removal_mode 0)
		)
		(polygon
			(pts
				(xy 199.05345 -378.574808) (xy 199.05345 -379.434598) (xy 197.878192 -379.434598) (xy 197.878192 -378.470414)
				(xy 197.878192 -377.757182) (xy 200.608184 -377.757182) (xy 200.608184 -378.574808)
			)
		)
	)
	(zone
		(layer "F.Cu")
		(hatch none 0.5)
		(connect_pads
			(clearance 0)
		)
		(min_thickness 0.25)
		(keepout
			(tracks allowed)
			(vias allowed)
			(pads allowed)
			(copperpour allowed)
			(footprints not_allowed)
		)
		(placement
			(enabled no)
			(sheetname "")
		)
		(fill
			(thermal_gap 0.5)
			(thermal_bridge_width 0.5)
			(island_removal_mode 0)
		)
		(polygon
			(pts
				(arc
					(start 166.99992 -404.789894)
					(mid 170.999912 -400.789902)
					(end 174.999904 -404.789894)
				)
				(arc
					(start 174.999904 -404.789894)
					(mid 170.999912 -408.789886)
					(end 166.99992 -404.789894)
				)
			)
		)
	)
	(zone
		(layer "F.Cu")
		(hatch none 0.5)
		(connect_pads
			(clearance 0)
		)
		(min_thickness 0.25)
		(keepout
			(tracks allowed)
			(vias allowed)
			(pads allowed)
			(copperpour allowed)
			(footprints allowed)
		)
		(placement
			(enabled no)
			(sheetname "")
		)
		(fill
			(thermal_gap 0.5)
			(thermal_bridge_width 0.5)
			(island_removal_mode 0)
		)
		(polygon
			(pts
				(xy 343.174828 -384.406902) (xy 343.174828 -383.40284) (xy 344.57132 -383.40284) (xy 344.57132 -384.406902)
			)
		)
	)
	(zone
		(layer "F.Cu")
		(hatch none 0.5)
		(connect_pads
			(clearance 0)
		)
		(min_thickness 0.25)
		(keepout
			(tracks allowed)
			(vias allowed)
			(pads allowed)
			(copperpour allowed)
			(footprints allowed)
		)
		(placement
			(enabled no)
			(sheetname "")
		)
		(fill
			(thermal_gap 0.5)
			(thermal_bridge_width 0.5)
			(island_removal_mode 0)
		)
		(polygon
			(pts
				(xy 85.23351 -320.458846) (xy 85.23351 -322.363846) (xy 89.24671 -322.363846) (xy 89.24671 -320.458846)
			)
		)
	)
	(zone
		(layer "F.Cu")
		(hatch none 0.5)
		(connect_pads
			(clearance 0)
		)
		(min_thickness 0.25)
		(keepout
			(tracks allowed)
			(vias allowed)
			(pads allowed)
			(copperpour allowed)
			(footprints not_allowed)
		)
		(placement
			(enabled no)
			(sheetname "")
		)
		(fill
			(thermal_gap 0.5)
			(thermal_bridge_width 0.5)
			(island_removal_mode 0)
		)
		(polygon
			(pts
				(arc
					(start 358.008936 -55.47995)
					(mid 357.204308 -69.974927)
					(end 344.499946 -77.0001)
				)
				(xy 344.499946 -67.540124) (xy 348.549976 -67.540124) (xy 348.549976 -56.459882) (xy 344.499946 -56.459882)
				(xy 344.499946 -55.47995)
			)
		)
	)
	(zone
		(layer "F.Cu")
		(hatch none 0.5)
		(connect_pads
			(clearance 0)
		)
		(min_thickness 0.25)
		(keepout
			(tracks allowed)
			(vias allowed)
			(pads allowed)
			(copperpour allowed)
			(footprints allowed)
		)
		(placement
			(enabled no)
			(sheetname "")
		)
		(fill
			(thermal_gap 0.5)
			(thermal_bridge_width 0.5)
			(island_removal_mode 0)
		)
		(polygon
			(pts
				(xy 151.37257 -409.042616) (xy 151.37257 -408.038554) (xy 152.769062 -408.038554) (xy 152.769062 -409.042616)
			)
		)
	)
	(zone
		(layer "F.Cu")
		(hatch none 0.5)
		(connect_pads
			(clearance 0)
		)
		(min_thickness 0.25)
		(keepout
			(tracks allowed)
			(vias allowed)
			(pads allowed)
			(copperpour allowed)
			(footprints not_allowed)
		)
		(placement
			(enabled no)
			(sheetname "")
		)
		(fill
			(thermal_gap 0.5)
			(thermal_bridge_width 0.5)
			(island_removal_mode 0)
		)
		(polygon
			(pts
				(xy 358.513888 -26.91003) (xy 374.513856 -26.91003) (xy 374.513856 -16.20647) (xy 358.513888 -16.20647)
			)
		)
	)
	(zone
		(layer "F.Cu")
		(hatch none 0.5)
		(connect_pads
			(clearance 0)
		)
		(min_thickness 0.25)
		(keepout
			(tracks allowed)
			(vias allowed)
			(pads allowed)
			(copperpour allowed)
			(footprints not_allowed)
		)
		(placement
			(enabled no)
			(sheetname "")
		)
		(fill
			(thermal_gap 0.5)
			(thermal_bridge_width 0.5)
			(island_removal_mode 0)
		)
		(polygon
			(pts
				(xy 245.124986 -370.701824) (xy 271.124934 -370.701824) (xy 271.124934 -356.605078) (xy 269.352014 -356.605078)
				(xy 269.352014 -351.605088) (xy 263.151874 -351.605088) (xy 263.151874 -350.813878) (xy 245.124986 -350.813878)
			)
		)
	)
	(zone
		(layer "F.Cu")
		(hatch none 0.5)
		(connect_pads
			(clearance 0)
		)
		(min_thickness 0.25)
		(keepout
			(tracks allowed)
			(vias allowed)
			(pads allowed)
			(copperpour allowed)
			(footprints not_allowed)
		)
		(placement
			(enabled no)
			(sheetname "")
		)
		(fill
			(thermal_gap 0.5)
			(thermal_bridge_width 0.5)
			(island_removal_mode 0)
		)
		(polygon
			(pts
				(arc
					(start 393.970002 -212.989922)
					(mid 390.470136 -216.489788)
					(end 386.970016 -212.989922)
				)
				(arc
					(start 386.970016 -212.989922)
					(mid 390.470136 -209.489802)
					(end 393.970002 -212.989922)
				)
			)
		)
	)
	(zone
		(layer "F.Cu")
		(hatch none 0.5)
		(connect_pads
			(clearance 0)
		)
		(min_thickness 0.25)
		(keepout
			(tracks allowed)
			(vias allowed)
			(pads allowed)
			(copperpour allowed)
			(footprints allowed)
		)
		(placement
			(enabled no)
			(sheetname "")
		)
		(fill
			(thermal_gap 0.5)
			(thermal_bridge_width 0.5)
			(island_removal_mode 0)
		)
		(polygon
			(pts
				(xy 138.70686 -108.55452) (xy 138.70686 -107.32516) (xy 140.84046 -107.32516) (xy 140.84046 -108.55452)
			)
		)
	)
	(zone
		(layer "F.Cu")
		(hatch none 0.5)
		(connect_pads
			(clearance 0)
		)
		(min_thickness 0.25)
		(keepout
			(tracks not_allowed)
			(vias allowed)
			(pads allowed)
			(copperpour not_allowed)
			(footprints allowed)
		)
		(placement
			(enabled no)
			(sheetname "")
		)
		(fill
			(thermal_gap 0.5)
			(thermal_bridge_width 0.5)
			(island_removal_mode 0)
		)
		(polygon
			(pts
				(arc
					(start 98.482912 -47.049944)
					(mid 100.383086 -45.14977)
					(end 102.283006 -47.049944)
				)
				(arc
					(start 102.283006 -47.049944)
					(mid 100.383086 -48.949864)
					(end 98.482912 -47.049944)
				)
			)
		)
	)
	(zone
		(layer "F.Cu")
		(hatch none 0.5)
		(connect_pads
			(clearance 0)
		)
		(min_thickness 0.25)
		(keepout
			(tracks allowed)
			(vias allowed)
			(pads allowed)
			(copperpour allowed)
			(footprints allowed)
		)
		(placement
			(enabled no)
			(sheetname "")
		)
		(fill
			(thermal_gap 0.5)
			(thermal_bridge_width 0.5)
			(island_removal_mode 0)
		)
		(polygon
			(pts
				(xy 362.189522 -190.385954) (xy 362.189522 -192.290954) (xy 366.202722 -192.290954) (xy 366.202722 -190.385954)
			)
		)
	)
	(zone
		(layer "F.Cu")
		(hatch none 0.5)
		(connect_pads
			(clearance 0)
		)
		(min_thickness 0.25)
		(keepout
			(tracks allowed)
			(vias allowed)
			(pads allowed)
			(copperpour allowed)
			(footprints allowed)
		)
		(placement
			(enabled no)
			(sheetname "")
		)
		(fill
			(thermal_gap 0.5)
			(thermal_bridge_width 0.5)
			(island_removal_mode 0)
		)
		(polygon
			(pts
				(xy 392.315446 -387.598412) (xy 393.319508 -387.598412) (xy 393.319508 -388.994904) (xy 392.315446 -388.994904)
			)
		)
	)
	(zone
		(layer "F.Cu")
		(hatch none 0.5)
		(connect_pads
			(clearance 0)
		)
		(min_thickness 0.25)
		(keepout
			(tracks allowed)
			(vias allowed)
			(pads allowed)
			(copperpour allowed)
			(footprints not_allowed)
		)
		(placement
			(enabled no)
			(sheetname "")
		)
		(fill
			(thermal_gap 0.5)
			(thermal_bridge_width 0.5)
			(island_removal_mode 0)
		)
		(polygon
			(pts
				(xy 256.15011 -319.65011) (xy 256.15011 -267.1699)
				(arc
					(start 242.61572 -267.1699)
					(mid 236.650107 -280.499697)
					(end 230.68407 -267.1699)
				)
				(xy 215.650064 -267.1699) (xy 215.650064 -319.550034) (xy 208.447894 -319.550034) (xy 208.447894 -319.65011)
			)
		)
	)
	(zone
		(layer "F.Cu")
		(hatch none 0.5)
		(connect_pads
			(clearance 0)
		)
		(min_thickness 0.25)
		(keepout
			(tracks allowed)
			(vias allowed)
			(pads allowed)
			(copperpour allowed)
			(footprints allowed)
		)
		(placement
			(enabled no)
			(sheetname "")
		)
		(fill
			(thermal_gap 0.5)
			(thermal_bridge_width 0.5)
			(island_removal_mode 0)
		)
		(polygon
			(pts
				(xy 411.317694 -227.677726) (xy 411.317694 -227.347526) (xy 413.236664 -227.347526) (xy 413.236664 -227.677726)
			)
		)
	)
	(zone
		(layer "F.Cu")
		(hatch none 0.5)
		(connect_pads
			(clearance 0)
		)
		(min_thickness 0.25)
		(keepout
			(tracks allowed)
			(vias allowed)
			(pads allowed)
			(copperpour allowed)
			(footprints allowed)
		)
		(placement
			(enabled no)
			(sheetname "")
		)
		(fill
			(thermal_gap 0.5)
			(thermal_bridge_width 0.5)
			(island_removal_mode 0)
		)
		(polygon
			(pts
				(xy 19.3929 -133.40334) (xy 20.8661 -133.40334) (xy 20.8661 -134.29234) (xy 19.3929 -134.29234)
			)
		)
	)
	(zone
		(layer "F.Cu")
		(hatch none 0.5)
		(connect_pads
			(clearance 0)
		)
		(min_thickness 0.25)
		(keepout
			(tracks allowed)
			(vias allowed)
			(pads allowed)
			(copperpour allowed)
			(footprints allowed)
		)
		(placement
			(enabled no)
			(sheetname "")
		)
		(fill
			(thermal_gap 0.5)
			(thermal_bridge_width 0.5)
			(island_removal_mode 0)
		)
		(polygon
			(pts
				(xy 328.01941 -417.424616) (xy 328.01941 -416.420554) (xy 329.415902 -416.420554) (xy 329.415902 -417.424616)
			)
		)
	)
	(zone
		(layer "F.Cu")
		(hatch none 0.5)
		(connect_pads
			(clearance 0)
		)
		(min_thickness 0.25)
		(keepout
			(tracks not_allowed)
			(vias allowed)
			(pads allowed)
			(copperpour not_allowed)
			(footprints allowed)
		)
		(placement
			(enabled no)
			(sheetname "")
		)
		(fill
			(thermal_gap 0.5)
			(thermal_bridge_width 0.5)
			(island_removal_mode 0)
		)
		(polygon
			(pts
				(xy 180.419756 -350.546162) (xy 180.419756 -351.002854) (xy 181.115462 -351.002854) (xy 181.115462 -350.842326)
				(xy 181.674262 -350.842326) (xy 181.674262 -351.248726) (xy 181.115462 -351.248726) (xy 181.115462 -351.028254)
				(xy 180.419756 -351.028254) (xy 180.419756 -351.155254) (xy 180.875432 -351.155254) (xy 180.875432 -351.541842)
				(xy 181.117748 -351.541842) (xy 181.649624 -351.541842) (xy 181.969156 -351.22231) (xy 181.969156 -350.546162)
			)
		)
	)
	(zone
		(layer "F.Cu")
		(hatch none 0.5)
		(connect_pads
			(clearance 0)
		)
		(min_thickness 0.25)
		(keepout
			(tracks allowed)
			(vias allowed)
			(pads allowed)
			(copperpour allowed)
			(footprints allowed)
		)
		(placement
			(enabled no)
			(sheetname "")
		)
		(fill
			(thermal_gap 0.5)
			(thermal_bridge_width 0.5)
			(island_removal_mode 0)
		)
		(polygon
			(pts
				(xy 123.537218 -54.664102) (xy 122.58929 -54.664102) (xy 122.58929 -53.151786) (xy 123.537218 -53.151786)
			)
		)
	)
	(zone
		(layer "F.Cu")
		(hatch none 0.5)
		(connect_pads
			(clearance 0)
		)
		(min_thickness 0.25)
		(keepout
			(tracks allowed)
			(vias allowed)
			(pads allowed)
			(copperpour allowed)
			(footprints not_allowed)
		)
		(placement
			(enabled no)
			(sheetname "")
		)
		(fill
			(thermal_gap 0.5)
			(thermal_bridge_width 0.5)
			(island_removal_mode 0)
		)
		(polygon
			(pts
				(xy 237.949994 -41.924986) (xy 242.149884 -41.924986) (xy 242.149884 -37.120068) (xy 237.949994 -37.120068)
			)
		)
	)
	(zone
		(layer "F.Cu")
		(hatch none 0.5)
		(connect_pads
			(clearance 0)
		)
		(min_thickness 0.25)
		(keepout
			(tracks allowed)
			(vias allowed)
			(pads allowed)
			(copperpour allowed)
			(footprints not_allowed)
		)
		(placement
			(enabled no)
			(sheetname "")
		)
		(fill
			(thermal_gap 0.5)
			(thermal_bridge_width 0.5)
			(island_removal_mode 0)
		)
		(polygon
			(pts
				(arc
					(start 68.482972 -47.049944)
					(mid 70.383146 -45.14977)
					(end 72.283066 -47.049944)
				)
				(arc
					(start 72.283066 -47.049944)
					(mid 70.383146 -48.949864)
					(end 68.482972 -47.049944)
				)
			)
		)
	)
	(zone
		(layer "F.Cu")
		(hatch none 0.5)
		(connect_pads
			(clearance 0)
		)
		(min_thickness 0.25)
		(keepout
			(tracks allowed)
			(vias allowed)
			(pads allowed)
			(copperpour allowed)
			(footprints allowed)
		)
		(placement
			(enabled no)
			(sheetname "")
		)
		(fill
			(thermal_gap 0.5)
			(thermal_bridge_width 0.5)
			(island_removal_mode 0)
		)
		(polygon
			(pts
				(xy 411.317694 -268.478) (xy 411.317694 -268.1478) (xy 413.236664 -268.1478) (xy 413.236664 -268.478)
			)
		)
	)
	(zone
		(layer "F.Cu")
		(hatch none 0.5)
		(connect_pads
			(clearance 0)
		)
		(min_thickness 0.25)
		(keepout
			(tracks allowed)
			(vias allowed)
			(pads allowed)
			(copperpour allowed)
			(footprints not_allowed)
		)
		(placement
			(enabled no)
			(sheetname "")
		)
		(fill
			(thermal_gap 0.5)
			(thermal_bridge_width 0.5)
			(island_removal_mode 0)
		)
		(polygon
			(pts
				(arc
					(start 43.310048 -59.965844)
					(mid 43.724196 -44.736492)
					(end 30.599888 -36.999926)
				)
				(xy 30.599888 -46.459902) (xy 34.649918 -46.459902) (xy 34.649918 -57.53989) (xy 30.599888 -57.53989)
				(arc
					(start 30.599888 -67.00012)
					(mid 32.599711 -66.866144)
					(end 34.563812 -66.46672)
				)
				(xy 34.564574 -59.965082)
			)
		)
	)
	(zone
		(layer "F.Cu")
		(hatch none 0.5)
		(connect_pads
			(clearance 0)
		)
		(min_thickness 0.25)
		(keepout
			(tracks allowed)
			(vias allowed)
			(pads allowed)
			(copperpour allowed)
			(footprints allowed)
		)
		(placement
			(enabled no)
			(sheetname "")
		)
		(fill
			(thermal_gap 0.5)
			(thermal_bridge_width 0.5)
			(island_removal_mode 0)
		)
		(polygon
			(pts
				(xy 365.834422 -381.943102) (xy 365.834422 -380.93904) (xy 367.230914 -380.93904) (xy 367.230914 -381.943102)
			)
		)
	)
	(zone
		(layer "F.Cu")
		(hatch none 0.5)
		(connect_pads
			(clearance 0)
		)
		(min_thickness 0.25)
		(keepout
			(tracks allowed)
			(vias allowed)
			(pads allowed)
			(copperpour allowed)
			(footprints not_allowed)
		)
		(placement
			(enabled no)
			(sheetname "")
		)
		(fill
			(thermal_gap 0.5)
			(thermal_bridge_width 0.5)
			(island_removal_mode 0)
		)
		(polygon
			(pts
				(arc
					(start 200.600056 -22.29993)
					(mid 203.400152 -19.499834)
					(end 206.199994 -22.29993)
				)
				(arc
					(start 206.199994 -22.29993)
					(mid 203.400152 -25.099772)
					(end 200.600056 -22.29993)
				)
			)
		)
	)
	(zone
		(layer "F.Cu")
		(hatch none 0.5)
		(connect_pads
			(clearance 0)
		)
		(min_thickness 0.25)
		(keepout
			(tracks allowed)
			(vias allowed)
			(pads allowed)
			(copperpour allowed)
			(footprints allowed)
		)
		(placement
			(enabled no)
			(sheetname "")
		)
		(fill
			(thermal_gap 0.5)
			(thermal_bridge_width 0.5)
			(island_removal_mode 0)
		)
		(polygon
			(pts
				(xy 392.056366 -417.424616) (xy 392.056366 -416.420554) (xy 393.452858 -416.420554) (xy 393.452858 -417.424616)
			)
		)
	)
	(zone
		(layer "F.Cu")
		(hatch none 0.5)
		(connect_pads
			(clearance 0)
		)
		(min_thickness 0.25)
		(keepout
			(tracks allowed)
			(vias allowed)
			(pads allowed)
			(copperpour allowed)
			(footprints allowed)
		)
		(placement
			(enabled no)
			(sheetname "")
		)
		(fill
			(thermal_gap 0.5)
			(thermal_bridge_width 0.5)
			(island_removal_mode 0)
		)
		(polygon
			(pts
				(xy 378.337318 -183.083454) (xy 384.687318 -183.083454) (xy 385.322318 -182.448454) (xy 385.322318 -177.876454)
				(xy 384.687318 -177.241454) (xy 378.718318 -177.241454) (xy 378.210318 -177.749454) (xy 378.210318 -182.956454)
			)
		)
	)
	(zone
		(layer "F.Cu")
		(hatch none 0.5)
		(connect_pads
			(clearance 0)
		)
		(min_thickness 0.25)
		(keepout
			(tracks allowed)
			(vias allowed)
			(pads allowed)
			(copperpour allowed)
			(footprints allowed)
		)
		(placement
			(enabled no)
			(sheetname "")
		)
		(fill
			(thermal_gap 0.5)
			(thermal_bridge_width 0.5)
			(island_removal_mode 0)
		)
		(polygon
			(pts
				(xy 149.483064 -195.6308) (xy 149.483064 -195.1228) (xy 149.678644 -195.1228) (xy 149.678644 -195.6308)
			)
		)
	)
	(zone
		(layer "F.Cu")
		(hatch none 0.5)
		(connect_pads
			(clearance 0)
		)
		(min_thickness 0.25)
		(keepout
			(tracks allowed)
			(vias allowed)
			(pads allowed)
			(copperpour allowed)
			(footprints allowed)
		)
		(placement
			(enabled no)
			(sheetname "")
		)
		(fill
			(thermal_gap 0.5)
			(thermal_bridge_width 0.5)
			(island_removal_mode 0)
		)
		(polygon
			(pts
				(xy 324.95617 -417.424616) (xy 324.95617 -416.420554) (xy 326.352662 -416.420554) (xy 326.352662 -417.424616)
			)
		)
	)
	(zone
		(layer "F.Cu")
		(hatch none 0.5)
		(connect_pads
			(clearance 0)
		)
		(min_thickness 0.25)
		(keepout
			(tracks allowed)
			(vias allowed)
			(pads allowed)
			(copperpour allowed)
			(footprints not_allowed)
		)
		(placement
			(enabled no)
			(sheetname "")
		)
		(fill
			(thermal_gap 0.5)
			(thermal_bridge_width 0.5)
			(island_removal_mode 0)
		)
		(polygon
			(pts
				(xy 263.347962 -342.914986) (xy 263.347962 -329.060048) (xy 309.568088 -329.060048) (xy 309.568088 -342.914986)
			)
		)
	)
	(zone
		(layer "F.Cu")
		(hatch none 0.5)
		(connect_pads
			(clearance 0)
		)
		(min_thickness 0.25)
		(keepout
			(tracks allowed)
			(vias allowed)
			(pads allowed)
			(copperpour allowed)
			(footprints allowed)
		)
		(placement
			(enabled no)
			(sheetname "")
		)
		(fill
			(thermal_gap 0.5)
			(thermal_bridge_width 0.5)
			(island_removal_mode 0)
		)
		(polygon
			(pts
				(xy 411.317694 -199.627744) (xy 411.317694 -199.297544) (xy 413.236664 -199.297544) (xy 413.236664 -199.627744)
			)
		)
	)
	(zone
		(layer "F.Cu")
		(hatch none 0.5)
		(connect_pads
			(clearance 0)
		)
		(min_thickness 0.25)
		(keepout
			(tracks not_allowed)
			(vias allowed)
			(pads allowed)
			(copperpour not_allowed)
			(footprints allowed)
		)
		(placement
			(enabled no)
			(sheetname "")
		)
		(fill
			(thermal_gap 0.5)
			(thermal_bridge_width 0.5)
			(island_removal_mode 0)
		)
		(polygon
			(pts
				(arc
					(start 18.350992 -347.8149)
					(mid 20.216114 -345.949778)
					(end 22.080982 -347.8149)
				)
				(arc
					(start 22.080982 -347.8149)
					(mid 20.216114 -349.679768)
					(end 18.350992 -347.8149)
				)
			)
		)
	)
	(zone
		(layer "F.Cu")
		(hatch none 0.5)
		(connect_pads
			(clearance 0)
		)
		(min_thickness 0.25)
		(keepout
			(tracks allowed)
			(vias allowed)
			(pads allowed)
			(copperpour allowed)
			(footprints allowed)
		)
		(placement
			(enabled no)
			(sheetname "")
		)
		(fill
			(thermal_gap 0.5)
			(thermal_bridge_width 0.5)
			(island_removal_mode 0)
		)
		(polygon
			(pts
				(xy 411.317694 -291.427916) (xy 411.317694 -291.097716) (xy 413.236664 -291.097716) (xy 413.236664 -291.427916)
			)
		)
	)
	(zone
		(layer "F.Cu")
		(hatch none 0.5)
		(connect_pads
			(clearance 0)
		)
		(min_thickness 0.25)
		(keepout
			(tracks not_allowed)
			(vias allowed)
			(pads allowed)
			(copperpour not_allowed)
			(footprints allowed)
		)
		(placement
			(enabled no)
			(sheetname "")
		)
		(fill
			(thermal_gap 0.5)
			(thermal_bridge_width 0.5)
			(island_removal_mode 0)
		)
		(polygon
			(pts
				(arc
					(start 253.000002 -290.900104)
					(mid 249.900186 -293.99992)
					(end 246.800116 -290.900104)
				)
				(arc
					(start 246.800116 -290.900104)
					(mid 249.900186 -287.800034)
					(end 253.000002 -290.900104)
				)
			)
		)
	)
	(zone
		(layer "F.Cu")
		(hatch none 0.5)
		(connect_pads
			(clearance 0)
		)
		(min_thickness 0.25)
		(keepout
			(tracks allowed)
			(vias allowed)
			(pads allowed)
			(copperpour allowed)
			(footprints allowed)
		)
		(placement
			(enabled no)
			(sheetname "")
		)
		(fill
			(thermal_gap 0.5)
			(thermal_bridge_width 0.5)
			(island_removal_mode 0)
		)
		(polygon
			(pts
				(xy 404.455376 -181.208426) (xy 404.455376 -183.113426) (xy 408.468576 -183.113426) (xy 408.468576 -181.208426)
			)
		)
	)
	(zone
		(layer "F.Cu")
		(hatch none 0.5)
		(connect_pads
			(clearance 0)
		)
		(min_thickness 0.25)
		(keepout
			(tracks allowed)
			(vias allowed)
			(pads allowed)
			(copperpour allowed)
			(footprints allowed)
		)
		(placement
			(enabled no)
			(sheetname "")
		)
		(fill
			(thermal_gap 0.5)
			(thermal_bridge_width 0.5)
			(island_removal_mode 0)
		)
		(polygon
			(pts
				(xy 306.070508 -261.677658) (xy 306.070508 -261.347458) (xy 308.610508 -261.347458) (xy 308.610508 -261.677658)
			)
		)
	)
	(zone
		(layer "F.Cu")
		(hatch none 0.5)
		(connect_pads
			(clearance 0)
		)
		(min_thickness 0.25)
		(keepout
			(tracks allowed)
			(vias allowed)
			(pads allowed)
			(copperpour allowed)
			(footprints not_allowed)
		)
		(placement
			(enabled no)
			(sheetname "")
		)
		(fill
			(thermal_gap 0.5)
			(thermal_bridge_width 0.5)
			(island_removal_mode 0)
		)
		(polygon
			(pts
				(arc
					(start 353.534472 -30.48)
					(mid 352.275248 -27.296315)
					(end 351.770696 -23.910036)
				)
				(xy 358.513888 -23.910036) (xy 358.513888 -26.91003)
				(arc
					(start 374.36171 -26.91003)
					(mid 376.869305 -29.210456)
					(end 380.106174 -30.260544)
				)
				(arc
					(start 380.106174 -30.260544)
					(mid 373.656154 -36.72905)
					(end 364.65002 -38.256464)
				)
				(xy 364.65002 -30.48)
			)
		)
	)
	(zone
		(layer "F.Cu")
		(hatch none 0.5)
		(connect_pads
			(clearance 0)
		)
		(min_thickness 0.25)
		(keepout
			(tracks allowed)
			(vias allowed)
			(pads allowed)
			(copperpour allowed)
			(footprints allowed)
		)
		(placement
			(enabled no)
			(sheetname "")
		)
		(fill
			(thermal_gap 0.5)
			(thermal_bridge_width 0.5)
			(island_removal_mode 0)
		)
		(polygon
			(pts
				(xy 163.377626 -266.778232) (xy 163.377626 -266.448032) (xy 165.296596 -266.448032) (xy 165.296596 -266.778232)
			)
		)
	)
	(zone
		(layer "F.Cu")
		(hatch none 0.5)
		(connect_pads
			(clearance 0)
		)
		(min_thickness 0.25)
		(keepout
			(tracks allowed)
			(vias allowed)
			(pads allowed)
			(copperpour allowed)
			(footprints not_allowed)
		)
		(placement
			(enabled no)
			(sheetname "")
		)
		(fill
			(thermal_gap 0.5)
			(thermal_bridge_width 0.5)
			(island_removal_mode 0)
		)
		(polygon
			(pts
				(arc
					(start 392.700002 -43.859958)
					(mid 377.700032 -58.859928)
					(end 392.700002 -73.859898)
				)
				(xy 392.700002 -68.209922) (xy 389.029956 -68.209922) (xy 389.029956 -49.509934) (xy 392.700002 -49.509934)
			)
		)
	)
	(zone
		(layer "F.Cu")
		(hatch none 0.5)
		(connect_pads
			(clearance 0)
		)
		(min_thickness 0.25)
		(keepout
			(tracks not_allowed)
			(vias allowed)
			(pads allowed)
			(copperpour not_allowed)
			(footprints allowed)
		)
		(placement
			(enabled no)
			(sheetname "")
		)
		(fill
			(thermal_gap 0.5)
			(thermal_bridge_width 0.5)
			(island_removal_mode 0)
		)
		(polygon
			(pts
				(arc
					(start 385.899914 -22.29993)
					(mid 380.899924 -27.29992)
					(end 375.899934 -22.29993)
				)
				(arc
					(start 375.899934 -22.29993)
					(mid 380.899924 -17.29994)
					(end 385.899914 -22.29993)
				)
			)
		)
	)
	(zone
		(layer "F.Cu")
		(hatch none 0.5)
		(connect_pads
			(clearance 0)
		)
		(min_thickness 0.25)
		(keepout
			(tracks allowed)
			(vias allowed)
			(pads allowed)
			(copperpour allowed)
			(footprints allowed)
		)
		(placement
			(enabled no)
			(sheetname "")
		)
		(fill
			(thermal_gap 0.5)
			(thermal_bridge_width 0.5)
			(island_removal_mode 0)
		)
		(polygon
			(pts
				(xy 53.640228 -409.042616) (xy 53.640228 -408.038554) (xy 55.03672 -408.038554) (xy 55.03672 -409.042616)
			)
		)
	)
	(zone
		(layer "F.Cu")
		(hatch none 0.5)
		(connect_pads
			(clearance 0)
		)
		(min_thickness 0.25)
		(keepout
			(tracks allowed)
			(vias allowed)
			(pads allowed)
			(copperpour allowed)
			(footprints not_allowed)
		)
		(placement
			(enabled no)
			(sheetname "")
		)
		(fill
			(thermal_gap 0.5)
			(thermal_bridge_width 0.5)
			(island_removal_mode 0)
		)
		(polygon
			(pts
				(xy 199.750934 -183.50992) (xy 193.551048 -183.50992) (xy 193.551048 -327.609962) (xy 199.750934 -327.609962)
			)
		)
	)
	(zone
		(layer "F.Cu")
		(hatch none 0.5)
		(connect_pads
			(clearance 0)
		)
		(min_thickness 0.25)
		(keepout
			(tracks allowed)
			(vias allowed)
			(pads allowed)
			(copperpour allowed)
			(footprints not_allowed)
		)
		(placement
			(enabled no)
			(sheetname "")
		)
		(fill
			(thermal_gap 0.5)
			(thermal_bridge_width 0.5)
			(island_removal_mode 0)
		)
		(polygon
			(pts
				(arc
					(start 438.53989 -399.029936)
					(mid 435.440074 -402.129752)
					(end 432.340004 -399.029936)
				)
				(arc
					(start 432.340004 -399.029936)
					(mid 435.440074 -395.929866)
					(end 438.53989 -399.029936)
				)
			)
		)
	)
	(zone
		(layer "F.Cu")
		(hatch none 0.5)
		(connect_pads
			(clearance 0)
		)
		(min_thickness 0.25)
		(keepout
			(tracks allowed)
			(vias allowed)
			(pads allowed)
			(copperpour allowed)
			(footprints not_allowed)
		)
		(placement
			(enabled no)
			(sheetname "")
		)
		(fill
			(thermal_gap 0.5)
			(thermal_bridge_width 0.5)
			(island_removal_mode 0)
		)
		(polygon
			(pts
				(arc
					(start 173.838362 -440.989974)
					(mid 179.749958 -427.600233)
					(end 185.661554 -440.989974)
				)
			)
		)
	)
	(zone
		(layer "F.Cu")
		(hatch none 0.5)
		(connect_pads
			(clearance 0)
		)
		(min_thickness 0.25)
		(keepout
			(tracks not_allowed)
			(vias allowed)
			(pads allowed)
			(copperpour not_allowed)
			(footprints allowed)
		)
		(placement
			(enabled no)
			(sheetname "")
		)
		(fill
			(thermal_gap 0.5)
			(thermal_bridge_width 0.5)
			(island_removal_mode 0)
		)
		(polygon
			(pts
				(xy 421.143938 -350.365568) (xy 421.143938 -350.82226) (xy 421.839644 -350.82226) (xy 421.839644 -350.661732)
				(xy 422.398444 -350.661732) (xy 422.398444 -351.068132) (xy 421.839644 -351.068132) (xy 421.839644 -350.84766)
				(xy 421.143938 -350.84766) (xy 421.143938 -350.97466) (xy 421.599614 -350.97466) (xy 421.599614 -351.361248)
				(xy 421.84193 -351.361248) (xy 422.373806 -351.361248) (xy 422.693338 -351.041716) (xy 422.693338 -350.365568)
			)
		)
	)
	(zone
		(layer "F.Cu")
		(hatch none 0.5)
		(connect_pads
			(clearance 0)
		)
		(min_thickness 0.25)
		(keepout
			(tracks allowed)
			(vias allowed)
			(pads allowed)
			(copperpour allowed)
			(footprints allowed)
		)
		(placement
			(enabled no)
			(sheetname "")
		)
		(fill
			(thermal_gap 0.5)
			(thermal_bridge_width 0.5)
			(island_removal_mode 0)
		)
		(polygon
			(pts
				(xy 160.39338 -120.02516) (xy 160.39338 -118.76024) (xy 161.12998 -118.76024) (xy 161.12998 -120.02516)
			)
		)
	)
	(zone
		(layer "F.Cu")
		(hatch none 0.5)
		(connect_pads
			(clearance 0)
		)
		(min_thickness 0.25)
		(keepout
			(tracks allowed)
			(vias allowed)
			(pads allowed)
			(copperpour allowed)
			(footprints allowed)
		)
		(placement
			(enabled no)
			(sheetname "")
		)
		(fill
			(thermal_gap 0.5)
			(thermal_bridge_width 0.5)
			(island_removal_mode 0)
		)
		(polygon
			(pts
				(xy 259.551678 -139.380468) (xy 259.551678 -137.903712) (xy 260.708902 -137.903712) (xy 260.708902 -139.380468)
			)
		)
	)
	(zone
		(layer "F.Cu")
		(hatch none 0.5)
		(connect_pads
			(clearance 0)
		)
		(min_thickness 0.25)
		(keepout
			(tracks allowed)
			(vias allowed)
			(pads allowed)
			(copperpour allowed)
			(footprints allowed)
		)
		(placement
			(enabled no)
			(sheetname "")
		)
		(fill
			(thermal_gap 0.5)
			(thermal_bridge_width 0.5)
			(island_removal_mode 0)
		)
		(polygon
			(pts
				(xy 72.799956 -335.03997) (xy 66.449956 -335.03997) (xy 65.814956 -335.67497) (xy 65.814956 -340.24697)
				(xy 66.449956 -340.88197) (xy 72.418956 -340.88197) (xy 72.926956 -340.37397) (xy 72.926956 -335.16697)
			)
		)
	)
	(zone
		(layer "F.Cu")
		(hatch none 0.5)
		(connect_pads
			(clearance 0)
		)
		(min_thickness 0.25)
		(keepout
			(tracks not_allowed)
			(vias allowed)
			(pads allowed)
			(copperpour not_allowed)
			(footprints allowed)
		)
		(placement
			(enabled no)
			(sheetname "")
		)
		(fill
			(thermal_gap 0.5)
			(thermal_bridge_width 0.5)
			(island_removal_mode 0)
		)
		(polygon
			(pts
				(xy 189.362588 -87.300054) (xy 189.362588 -60.000134) (xy 168.364662 -59.997848) (xy 168.361868 -87.297768)
			)
		)
	)
	(zone
		(layer "F.Cu")
		(hatch none 0.5)
		(connect_pads
			(clearance 0)
		)
		(min_thickness 0.25)
		(keepout
			(tracks not_allowed)
			(vias allowed)
			(pads allowed)
			(copperpour not_allowed)
			(footprints allowed)
		)
		(placement
			(enabled no)
			(sheetname "")
		)
		(fill
			(thermal_gap 0.5)
			(thermal_bridge_width 0.5)
			(island_removal_mode 0)
		)
		(polygon
			(pts
				(arc
					(start 456.000104 -435.600094)
					(mid 458.8002 -432.799998)
					(end 461.600042 -435.600094)
				)
				(arc
					(start 461.600042 -435.600094)
					(mid 458.8002 -438.399936)
					(end 456.000104 -435.600094)
				)
			)
		)
	)
	(zone
		(layer "F.Cu")
		(hatch none 0.5)
		(connect_pads
			(clearance 0)
		)
		(min_thickness 0.25)
		(keepout
			(tracks allowed)
			(vias allowed)
			(pads allowed)
			(copperpour allowed)
			(footprints not_allowed)
		)
		(placement
			(enabled no)
			(sheetname "")
		)
		(fill
			(thermal_gap 0.5)
			(thermal_bridge_width 0.5)
			(island_removal_mode 0)
		)
		(polygon
			(pts
				(arc
					(start 385.899914 -22.29993)
					(mid 380.899924 -27.29992)
					(end 375.899934 -22.29993)
				)
				(arc
					(start 375.899934 -22.29993)
					(mid 380.899924 -17.29994)
					(end 385.899914 -22.29993)
				)
			)
		)
	)
	(zone
		(layer "F.Cu")
		(hatch none 0.5)
		(connect_pads
			(clearance 0)
		)
		(min_thickness 0.25)
		(keepout
			(tracks not_allowed)
			(vias allowed)
			(pads allowed)
			(copperpour not_allowed)
			(footprints allowed)
		)
		(placement
			(enabled no)
			(sheetname "")
		)
		(fill
			(thermal_gap 0.5)
			(thermal_bridge_width 0.5)
			(island_removal_mode 0)
		)
		(polygon
			(pts
				(arc
					(start 157.530038 -258.890008)
					(mid 154.030172 -262.389874)
					(end 150.530052 -258.890008)
				)
				(arc
					(start 150.530052 -258.890008)
					(mid 154.030172 -255.389888)
					(end 157.530038 -258.890008)
				)
			)
		)
	)
	(zone
		(layer "F.Cu")
		(hatch none 0.5)
		(connect_pads
			(clearance 0)
		)
		(min_thickness 0.25)
		(keepout
			(tracks not_allowed)
			(vias allowed)
			(pads allowed)
			(copperpour not_allowed)
			(footprints allowed)
		)
		(placement
			(enabled no)
			(sheetname "")
		)
		(fill
			(thermal_gap 0.5)
			(thermal_bridge_width 0.5)
			(island_removal_mode 0)
		)
		(polygon
			(pts
				(arc
					(start 262.850122 -22.29993)
					(mid 265.650218 -19.499834)
					(end 268.45006 -22.29993)
				)
				(arc
					(start 268.45006 -22.29993)
					(mid 265.650218 -25.099772)
					(end 262.850122 -22.29993)
				)
			)
		)
	)
	(zone
		(layer "F.Cu")
		(hatch none 0.5)
		(connect_pads
			(clearance 0)
		)
		(min_thickness 0.25)
		(keepout
			(tracks allowed)
			(vias allowed)
			(pads allowed)
			(copperpour allowed)
			(footprints allowed)
		)
		(placement
			(enabled no)
			(sheetname "")
		)
		(fill
			(thermal_gap 0.5)
			(thermal_bridge_width 0.5)
			(island_removal_mode 0)
		)
		(polygon
			(pts
				(xy 301.838106 -372.094506) (xy 302.26 -372.094506) (xy 302.26 -372.209568) (xy 301.838106 -372.209568)
			)
		)
	)
	(zone
		(layer "F.Cu")
		(hatch none 0.5)
		(connect_pads
			(clearance 0)
		)
		(min_thickness 0.25)
		(keepout
			(tracks allowed)
			(vias allowed)
			(pads allowed)
			(copperpour allowed)
			(footprints allowed)
		)
		(placement
			(enabled no)
			(sheetname "")
		)
		(fill
			(thermal_gap 0.5)
			(thermal_bridge_width 0.5)
			(island_removal_mode 0)
		)
		(polygon
			(pts
				(xy 285.554674 -346.376752) (xy 279.204674 -346.376752) (xy 278.569674 -347.011752) (xy 278.569674 -351.583752)
				(xy 279.204674 -352.218752) (xy 285.173674 -352.218752) (xy 285.681674 -351.710752) (xy 285.681674 -346.503752)
			)
		)
	)
	(zone
		(layer "F.Cu")
		(hatch none 0.5)
		(connect_pads
			(clearance 0)
		)
		(min_thickness 0.25)
		(keepout
			(tracks not_allowed)
			(vias allowed)
			(pads allowed)
			(copperpour not_allowed)
			(footprints allowed)
		)
		(placement
			(enabled no)
			(sheetname "")
		)
		(fill
			(thermal_gap 0.5)
			(thermal_bridge_width 0.5)
			(island_removal_mode 0)
		)
		(polygon
			(pts
				(arc
					(start 11.999976 -22.29993)
					(mid 6.999986 -27.29992)
					(end 1.999996 -22.29993)
				)
				(arc
					(start 1.999996 -22.29993)
					(mid 6.999986 -17.29994)
					(end 11.999976 -22.29993)
				)
			)
		)
	)
	(zone
		(layer "F.Cu")
		(hatch none 0.5)
		(connect_pads
			(clearance 0)
		)
		(min_thickness 0.25)
		(keepout
			(tracks not_allowed)
			(vias allowed)
			(pads allowed)
			(copperpour not_allowed)
			(footprints allowed)
		)
		(placement
			(enabled no)
			(sheetname "")
		)
		(fill
			(thermal_gap 0.5)
			(thermal_bridge_width 0.5)
			(island_removal_mode 0)
		)
		(polygon
			(pts
				(xy 366.358424 -177.071274) (xy 366.358424 -176.110392) (xy 366.116108 -176.110392) (xy 366.116108 -177.071274)
			)
		)
	)
	(zone
		(layer "F.Cu")
		(hatch none 0.5)
		(connect_pads
			(clearance 0)
		)
		(min_thickness 0.25)
		(keepout
			(tracks allowed)
			(vias allowed)
			(pads allowed)
			(copperpour allowed)
			(footprints allowed)
		)
		(placement
			(enabled no)
			(sheetname "")
		)
		(fill
			(thermal_gap 0.5)
			(thermal_bridge_width 0.5)
			(island_removal_mode 0)
		)
		(polygon
			(pts
				(xy 123.421648 -343.474802) (xy 123.421648 -343.052908) (xy 123.53671 -343.052908) (xy 123.53671 -343.474802)
			)
		)
	)
	(zone
		(layer "F.Cu")
		(hatch none 0.5)
		(connect_pads
			(clearance 0)
		)
		(min_thickness 0.25)
		(keepout
			(tracks allowed)
			(vias allowed)
			(pads allowed)
			(copperpour allowed)
			(footprints allowed)
		)
		(placement
			(enabled no)
			(sheetname "")
		)
		(fill
			(thermal_gap 0.5)
			(thermal_bridge_width 0.5)
			(island_removal_mode 0)
		)
		(polygon
			(pts
				(xy 406.87117 -379.479302) (xy 406.87117 -378.47524) (xy 408.267662 -378.47524) (xy 408.267662 -379.479302)
			)
		)
	)
	(zone
		(layer "F.Cu")
		(hatch none 0.5)
		(connect_pads
			(clearance 0)
		)
		(min_thickness 0.25)
		(keepout
			(tracks allowed)
			(vias allowed)
			(pads allowed)
			(copperpour allowed)
			(footprints allowed)
		)
		(placement
			(enabled no)
			(sheetname "")
		)
		(fill
			(thermal_gap 0.5)
			(thermal_bridge_width 0.5)
			(island_removal_mode 0)
		)
		(polygon
			(pts
				(xy 238.58855 -55.240682) (xy 238.58855 -53.308758) (xy 239.711738 -53.308758) (xy 239.711738 -55.240682)
			)
		)
	)
	(zone
		(layer "F.Cu")
		(hatch none 0.5)
		(connect_pads
			(clearance 0)
		)
		(min_thickness 0.25)
		(keepout
			(tracks allowed)
			(vias allowed)
			(pads allowed)
			(copperpour allowed)
			(footprints not_allowed)
		)
		(placement
			(enabled no)
			(sheetname "")
		)
		(fill
			(thermal_gap 0.5)
			(thermal_bridge_width 0.5)
			(island_removal_mode 0)
		)
		(polygon
			(pts
				(arc
					(start 437.500014 -384.869944)
					(mid 433.500022 -388.869936)
					(end 429.50003 -384.869944)
				)
				(arc
					(start 429.50003 -384.869944)
					(mid 433.500022 -380.869952)
					(end 437.500014 -384.869944)
				)
			)
		)
	)
	(zone
		(layer "F.Cu")
		(hatch none 0.5)
		(connect_pads
			(clearance 0)
		)
		(min_thickness 0.25)
		(keepout
			(tracks allowed)
			(vias allowed)
			(pads allowed)
			(copperpour allowed)
			(footprints not_allowed)
		)
		(placement
			(enabled no)
			(sheetname "")
		)
		(fill
			(thermal_gap 0.5)
			(thermal_bridge_width 0.5)
			(island_removal_mode 0)
		)
		(polygon
			(pts
				(arc
					(start 233.849926 -352.49993)
					(mid 236.650022 -349.699834)
					(end 239.450118 -352.49993)
				)
				(arc
					(start 239.450118 -352.49993)
					(mid 236.650022 -355.300026)
					(end 233.849926 -352.49993)
				)
			)
		)
	)
	(zone
		(layer "F.Cu")
		(hatch none 0.5)
		(connect_pads
			(clearance 0)
		)
		(min_thickness 0.25)
		(keepout
			(tracks allowed)
			(vias allowed)
			(pads allowed)
			(copperpour allowed)
			(footprints not_allowed)
		)
		(placement
			(enabled no)
			(sheetname "")
		)
		(fill
			(thermal_gap 0.5)
			(thermal_bridge_width 0.5)
			(island_removal_mode 0)
		)
		(polygon
			(pts
				(arc
					(start 227.65004 -44.500038)
					(mid 228.650038 -43.50004)
					(end 229.650036 -44.500038)
				)
				(arc
					(start 229.650036 -44.500038)
					(mid 228.650038 -45.500036)
					(end 227.65004 -44.500038)
				)
			)
		)
	)
	(zone
		(layer "F.Cu")
		(hatch none 0.5)
		(connect_pads
			(clearance 0)
		)
		(min_thickness 0.25)
		(keepout
			(tracks allowed)
			(vias allowed)
			(pads allowed)
			(copperpour allowed)
			(footprints allowed)
		)
		(placement
			(enabled no)
			(sheetname "")
		)
		(fill
			(thermal_gap 0.5)
			(thermal_bridge_width 0.5)
			(island_removal_mode 0)
		)
		(polygon
			(pts
				(xy 163.377626 -222.577914) (xy 163.377626 -222.247714) (xy 165.296596 -222.247714) (xy 165.296596 -222.577914)
			)
		)
	)
	(zone
		(layer "F.Cu")
		(hatch none 0.5)
		(connect_pads
			(clearance 0)
		)
		(min_thickness 0.25)
		(keepout
			(tracks allowed)
			(vias allowed)
			(pads allowed)
			(copperpour allowed)
			(footprints allowed)
		)
		(placement
			(enabled no)
			(sheetname "")
		)
		(fill
			(thermal_gap 0.5)
			(thermal_bridge_width 0.5)
			(island_removal_mode 0)
		)
		(polygon
			(pts
				(xy 197.187058 -386.662422) (xy 197.187058 -387.522212) (xy 196.0118 -387.522212) (xy 196.0118 -386.558028)
				(xy 196.0118 -385.844796) (xy 198.741792 -385.844796) (xy 198.741792 -385.858766) (xy 198.988934 -385.858766)
				(xy 198.988934 -386.662422) (xy 198.741792 -386.662422)
			)
		)
	)
	(zone
		(layer "F.Cu")
		(hatch none 0.5)
		(connect_pads
			(clearance 0)
		)
		(min_thickness 0.25)
		(keepout
			(tracks allowed)
			(vias allowed)
			(pads allowed)
			(copperpour allowed)
			(footprints allowed)
		)
		(placement
			(enabled no)
			(sheetname "")
		)
		(fill
			(thermal_gap 0.5)
			(thermal_bridge_width 0.5)
			(island_removal_mode 0)
		)
		(polygon
			(pts
				(xy 145.923508 -56.704992) (xy 145.923508 -55.575962) (xy 146.614388 -55.575962) (xy 146.614388 -56.704992)
			)
		)
	)
	(zone
		(layer "F.Cu")
		(hatch none 0.5)
		(connect_pads
			(clearance 0)
		)
		(min_thickness 0.25)
		(keepout
			(tracks allowed)
			(vias allowed)
			(pads allowed)
			(copperpour allowed)
			(footprints allowed)
		)
		(placement
			(enabled no)
			(sheetname "")
		)
		(fill
			(thermal_gap 0.5)
			(thermal_bridge_width 0.5)
			(island_removal_mode 0)
		)
		(polygon
			(pts
				(xy 411.317694 -225.977704) (xy 411.317694 -225.647504) (xy 413.236664 -225.647504) (xy 413.236664 -225.977704)
			)
		)
	)
	(zone
		(layer "F.Cu")
		(hatch none 0.5)
		(connect_pads
			(clearance 0)
		)
		(min_thickness 0.25)
		(keepout
			(tracks allowed)
			(vias allowed)
			(pads allowed)
			(copperpour allowed)
			(footprints allowed)
		)
		(placement
			(enabled no)
			(sheetname "")
		)
		(fill
			(thermal_gap 0.5)
			(thermal_bridge_width 0.5)
			(island_removal_mode 0)
		)
		(polygon
			(pts
				(xy 133.2992 -25.8572) (xy 133.2992 -24.384) (xy 134.1882 -24.384) (xy 134.1882 -25.8572)
			)
		)
	)
	(zone
		(layer "F.Cu")
		(hatch none 0.5)
		(connect_pads
			(clearance 0)
		)
		(min_thickness 0.25)
		(keepout
			(tracks allowed)
			(vias allowed)
			(pads allowed)
			(copperpour allowed)
			(footprints not_allowed)
		)
		(placement
			(enabled no)
			(sheetname "")
		)
		(fill
			(thermal_gap 0.5)
			(thermal_bridge_width 0.5)
			(island_removal_mode 0)
		)
		(polygon
			(pts
				(xy 411.031944 -167.40505) (xy 419.643052 -167.40505) (xy 419.643052 -158.90494) (xy 402.15312 -158.90494)
				(xy 402.15312 -161.874962) (xy 392.462004 -161.874962) (xy 392.462004 -168.654984) (xy 393.462002 -168.654984)
				(xy 393.462002 -175.565054)
				(arc
					(start 391.654538 -175.565054)
					(mid 389.522116 -176.414965)
					(end 387.389624 -175.565054)
				)
				(xy 369.391946 -175.565054) (xy 369.391946 -165.934898) (xy 360.73207 -165.934898) (xy 360.73207 -157.705044)
				(xy 352.222054 -157.705044) (xy 352.222054 -154.617928) (xy 343.462102 -154.617928) (xy 343.462102 -164.885116)
				(xy 351.553018 -164.885116) (xy 351.553018 -173.185074) (xy 360.352848 -173.185074) (xy 360.352848 -181.464966)
				(xy 367.95202 -181.464966) (xy 367.95202 -186.485022) (xy 394.30198 -186.485022) (xy 394.30198 -180.865018)
				(xy 402.592032 -180.865018) (xy 402.592032 -172.235114) (xy 411.031944 -172.235114)
			)
		)
	)
	(zone
		(layer "F.Cu")
		(hatch none 0.5)
		(connect_pads
			(clearance 0)
		)
		(min_thickness 0.25)
		(keepout
			(tracks allowed)
			(vias allowed)
			(pads allowed)
			(copperpour allowed)
			(footprints allowed)
		)
		(placement
			(enabled no)
			(sheetname "")
		)
		(fill
			(thermal_gap 0.5)
			(thermal_bridge_width 0.5)
			(island_removal_mode 0)
		)
		(polygon
			(pts
				(xy 308.66588 -306.392326) (xy 308.66588 -306.722526) (xy 306.12588 -306.722526) (xy 306.12588 -306.392326)
			)
		)
	)
	(zone
		(layer "F.Cu")
		(hatch none 0.5)
		(connect_pads
			(clearance 0)
		)
		(min_thickness 0.25)
		(keepout
			(tracks allowed)
			(vias allowed)
			(pads allowed)
			(copperpour allowed)
			(footprints allowed)
		)
		(placement
			(enabled no)
			(sheetname "")
		)
		(fill
			(thermal_gap 0.5)
			(thermal_bridge_width 0.5)
			(island_removal_mode 0)
		)
		(polygon
			(pts
				(xy 97.844356 -335.06918) (xy 91.494356 -335.06918) (xy 90.859356 -335.70418) (xy 90.859356 -340.27618)
				(xy 91.494356 -340.91118) (xy 97.463356 -340.91118) (xy 97.971356 -340.40318) (xy 97.971356 -335.19618)
			)
		)
	)
	(zone
		(layer "F.Cu")
		(hatch none 0.5)
		(connect_pads
			(clearance 0)
		)
		(min_thickness 0.25)
		(keepout
			(tracks allowed)
			(vias allowed)
			(pads allowed)
			(copperpour allowed)
			(footprints allowed)
		)
		(placement
			(enabled no)
			(sheetname "")
		)
		(fill
			(thermal_gap 0.5)
			(thermal_bridge_width 0.5)
			(island_removal_mode 0)
		)
		(polygon
			(pts
				(xy 411.317694 -233.627676) (xy 411.317694 -233.297476) (xy 413.236664 -233.297476) (xy 413.236664 -233.627676)
			)
		)
	)
	(zone
		(layer "F.Cu")
		(hatch none 0.5)
		(connect_pads
			(clearance 0)
		)
		(min_thickness 0.25)
		(keepout
			(tracks not_allowed)
			(vias allowed)
			(pads allowed)
			(copperpour not_allowed)
			(footprints allowed)
		)
		(placement
			(enabled no)
			(sheetname "")
		)
		(fill
			(thermal_gap 0.5)
			(thermal_bridge_width 0.5)
			(island_removal_mode 0)
		)
		(polygon
			(pts
				(arc
					(start 109.815884 -166.61511)
					(mid 106.716068 -169.714926)
					(end 103.615998 -166.61511)
				)
				(arc
					(start 103.615998 -166.61511)
					(mid 106.716068 -163.51504)
					(end 109.815884 -166.61511)
				)
			)
		)
	)
	(zone
		(layer "F.Cu")
		(hatch none 0.5)
		(connect_pads
			(clearance 0)
		)
		(min_thickness 0.25)
		(keepout
			(tracks not_allowed)
			(vias allowed)
			(pads allowed)
			(copperpour not_allowed)
			(footprints allowed)
		)
		(placement
			(enabled no)
			(sheetname "")
		)
		(fill
			(thermal_gap 0.5)
			(thermal_bridge_width 0.5)
			(island_removal_mode 0)
		)
		(polygon
			(pts
				(xy 126.466092 -165.941756) (xy 126.466092 -165.485064) (xy 125.770386 -165.485064) (xy 125.770386 -165.645592)
				(xy 125.211586 -165.645592) (xy 125.211586 -165.239192) (xy 125.770386 -165.239192) (xy 125.770386 -165.459664)
				(xy 126.466092 -165.459664) (xy 126.466092 -165.332664) (xy 126.010416 -165.332664) (xy 126.010416 -164.946076)
				(xy 125.7681 -164.946076) (xy 125.236224 -164.946076) (xy 124.916692 -165.265608) (xy 124.916692 -165.941756)
			)
		)
	)
	(zone
		(layer "F.Cu")
		(hatch none 0.5)
		(connect_pads
			(clearance 0)
		)
		(min_thickness 0.25)
		(keepout
			(tracks not_allowed)
			(vias allowed)
			(pads allowed)
			(copperpour not_allowed)
			(footprints allowed)
		)
		(placement
			(enabled no)
			(sheetname "")
		)
		(fill
			(thermal_gap 0.5)
			(thermal_bridge_width 0.5)
			(island_removal_mode 0)
		)
		(polygon
			(pts
				(arc
					(start 37.969952 -389.439912)
					(mid 34.870136 -392.539728)
					(end 31.770066 -389.439912)
				)
				(arc
					(start 31.770066 -389.439912)
					(mid 34.870136 -386.339842)
					(end 37.969952 -389.439912)
				)
			)
		)
	)
	(zone
		(layer "F.Cu")
		(hatch none 0.5)
		(connect_pads
			(clearance 0)
		)
		(min_thickness 0.25)
		(keepout
			(tracks not_allowed)
			(vias allowed)
			(pads allowed)
			(copperpour not_allowed)
			(footprints allowed)
		)
		(placement
			(enabled no)
			(sheetname "")
		)
		(fill
			(thermal_gap 0.5)
			(thermal_bridge_width 0.5)
			(island_removal_mode 0)
		)
		(polygon
			(pts
				(arc
					(start 50.951892 -66.060828)
					(mid 45.062902 -60.171838)
					(end 39.173912 -66.060828)
				)
				(arc
					(start 39.173912 -74.760836)
					(mid 45.062902 -80.649826)
					(end 50.951892 -74.760836)
				)
			)
		)
	)
	(zone
		(layer "F.Cu")
		(hatch none 0.5)
		(connect_pads
			(clearance 0)
		)
		(min_thickness 0.25)
		(keepout
			(tracks not_allowed)
			(vias allowed)
			(pads allowed)
			(copperpour not_allowed)
			(footprints allowed)
		)
		(placement
			(enabled no)
			(sheetname "")
		)
		(fill
			(thermal_gap 0.5)
			(thermal_bridge_width 0.5)
			(island_removal_mode 0)
		)
		(polygon
			(pts
				(arc
					(start 115.275106 -431.360072)
					(mid 112.025176 -434.610002)
					(end 108.774992 -431.360072)
				)
				(arc
					(start 108.774992 -431.360072)
					(mid 112.025176 -428.109888)
					(end 115.275106 -431.360072)
				)
			)
		)
	)
	(zone
		(layer "F.Cu")
		(hatch none 0.5)
		(connect_pads
			(clearance 0)
		)
		(min_thickness 0.25)
		(keepout
			(tracks allowed)
			(vias allowed)
			(pads allowed)
			(copperpour allowed)
			(footprints not_allowed)
		)
		(placement
			(enabled no)
			(sheetname "")
		)
		(fill
			(thermal_gap 0.5)
			(thermal_bridge_width 0.5)
			(island_removal_mode 0)
		)
		(polygon
			(pts
				(arc
					(start 37.569902 -404.789894)
					(mid 41.569894 -400.789902)
					(end 45.569886 -404.789894)
				)
				(arc
					(start 45.569886 -404.789894)
					(mid 41.569894 -408.789886)
					(end 37.569902 -404.789894)
				)
			)
		)
	)
	(zone
		(layer "F.Cu")
		(hatch none 0.5)
		(connect_pads
			(clearance 0)
		)
		(min_thickness 0.25)
		(keepout
			(tracks not_allowed)
			(vias allowed)
			(pads allowed)
			(copperpour not_allowed)
			(footprints allowed)
		)
		(placement
			(enabled no)
			(sheetname "")
		)
		(fill
			(thermal_gap 0.5)
			(thermal_bridge_width 0.5)
			(island_removal_mode 0)
		)
		(polygon
			(pts
				(arc
					(start 376.298714 -435.600094)
					(mid 371.298724 -440.600084)
					(end 366.298734 -435.600094)
				)
				(arc
					(start 366.298734 -435.600094)
					(mid 371.298724 -430.600104)
					(end 376.298714 -435.600094)
				)
			)
		)
	)
	(zone
		(layer "F.Cu")
		(hatch none 0.5)
		(connect_pads
			(clearance 0)
		)
		(min_thickness 0.25)
		(keepout
			(tracks allowed)
			(vias allowed)
			(pads allowed)
			(copperpour allowed)
			(footprints allowed)
		)
		(placement
			(enabled no)
			(sheetname "")
		)
		(fill
			(thermal_gap 0.5)
			(thermal_bridge_width 0.5)
			(island_removal_mode 0)
		)
		(polygon
			(pts
				(xy 12.11072 -193.1162) (xy 12.11072 -190.20028) (xy 13.82522 -190.20028) (xy 13.82522 -193.1162)
			)
		)
	)
	(zone
		(layer "F.Cu")
		(hatch none 0.5)
		(connect_pads
			(clearance 0)
		)
		(min_thickness 0.25)
		(keepout
			(tracks allowed)
			(vias allowed)
			(pads allowed)
			(copperpour allowed)
			(footprints not_allowed)
		)
		(placement
			(enabled no)
			(sheetname "")
		)
		(fill
			(thermal_gap 0.5)
			(thermal_bridge_width 0.5)
			(island_removal_mode 0)
		)
		(polygon
			(pts
				(arc
					(start 64.382904 -43.850052)
					(mid 67.58305 -47.050198)
					(end 64.382904 -50.25009)
				)
				(arc
					(start 62.782958 -50.25009)
					(mid 59.583066 -47.050198)
					(end 62.782958 -43.850052)
				)
			)
		)
	)
	(zone
		(layer "F.Cu")
		(hatch none 0.5)
		(connect_pads
			(clearance 0)
		)
		(min_thickness 0.25)
		(keepout
			(tracks allowed)
			(vias allowed)
			(pads allowed)
			(copperpour allowed)
			(footprints allowed)
		)
		(placement
			(enabled no)
			(sheetname "")
		)
		(fill
			(thermal_gap 0.5)
			(thermal_bridge_width 0.5)
			(island_removal_mode 0)
		)
		(polygon
			(pts
				(xy 71.836534 -190.240412) (xy 71.836534 -192.145412) (xy 75.849734 -192.145412) (xy 75.849734 -190.240412)
			)
		)
	)
	(zone
		(layer "F.Cu")
		(hatch none 0.5)
		(connect_pads
			(clearance 0)
		)
		(min_thickness 0.25)
		(keepout
			(tracks allowed)
			(vias allowed)
			(pads allowed)
			(copperpour allowed)
			(footprints allowed)
		)
		(placement
			(enabled no)
			(sheetname "")
		)
		(fill
			(thermal_gap 0.5)
			(thermal_bridge_width 0.5)
			(island_removal_mode 0)
		)
		(polygon
			(pts
				(xy 123.44908 -373.561102) (xy 123.44908 -372.55704) (xy 124.845572 -372.55704) (xy 124.845572 -373.561102)
			)
		)
	)
	(zone
		(layer "F.Cu")
		(hatch none 0.5)
		(connect_pads
			(clearance 0)
		)
		(min_thickness 0.25)
		(keepout
			(tracks allowed)
			(vias allowed)
			(pads allowed)
			(copperpour allowed)
			(footprints not_allowed)
		)
		(placement
			(enabled no)
			(sheetname "")
		)
		(fill
			(thermal_gap 0.5)
			(thermal_bridge_width 0.5)
			(island_removal_mode 0)
		)
		(polygon
			(pts
				(xy 104.878124 -254.88011) (xy 104.878124 -262.880094) (xy 118.977918 -262.880094) (xy 118.977918 -254.88011)
			)
		)
	)
	(zone
		(layer "F.Cu")
		(hatch none 0.5)
		(connect_pads
			(clearance 0)
		)
		(min_thickness 0.25)
		(keepout
			(tracks allowed)
			(vias allowed)
			(pads allowed)
			(copperpour allowed)
			(footprints allowed)
		)
		(placement
			(enabled no)
			(sheetname "")
		)
		(fill
			(thermal_gap 0.5)
			(thermal_bridge_width 0.5)
			(island_removal_mode 0)
		)
		(polygon
			(pts
				(xy 308.66588 -317.442342) (xy 308.66588 -317.772542) (xy 306.12588 -317.772542) (xy 306.12588 -317.442342)
			)
		)
	)
	(zone
		(layer "F.Cu")
		(hatch none 0.5)
		(connect_pads
			(clearance 0)
		)
		(min_thickness 0.25)
		(keepout
			(tracks allowed)
			(vias allowed)
			(pads allowed)
			(copperpour allowed)
			(footprints allowed)
		)
		(placement
			(enabled no)
			(sheetname "")
		)
		(fill
			(thermal_gap 0.5)
			(thermal_bridge_width 0.5)
			(island_removal_mode 0)
		)
		(polygon
			(pts
				(xy 125.15088 -371.097302) (xy 125.15088 -370.09324) (xy 126.547372 -370.09324) (xy 126.547372 -371.097302)
			)
		)
	)
	(zone
		(layer "F.Cu")
		(hatch none 0.5)
		(connect_pads
			(clearance 0)
		)
		(min_thickness 0.25)
		(keepout
			(tracks not_allowed)
			(vias allowed)
			(pads allowed)
			(copperpour not_allowed)
			(footprints allowed)
		)
		(placement
			(enabled no)
			(sheetname "")
		)
		(fill
			(thermal_gap 0.5)
			(thermal_bridge_width 0.5)
			(island_removal_mode 0)
		)
		(polygon
			(pts
				(xy 420.949882 -364.119414) (xy 420.949882 -360.863642) (xy 420.94404 -360.8578) (xy 420.797482 -360.8578)
				(xy 420.797482 -364.119414)
			)
		)
	)
	(zone
		(layer "F.Cu")
		(hatch none 0.5)
		(connect_pads
			(clearance 0)
		)
		(min_thickness 0.25)
		(keepout
			(tracks allowed)
			(vias allowed)
			(pads allowed)
			(copperpour allowed)
			(footprints allowed)
		)
		(placement
			(enabled no)
			(sheetname "")
		)
		(fill
			(thermal_gap 0.5)
			(thermal_bridge_width 0.5)
			(island_removal_mode 0)
		)
		(polygon
			(pts
				(xy 306.070508 -236.177836) (xy 306.070508 -235.847636) (xy 308.610508 -235.847636) (xy 308.610508 -236.177836)
			)
		)
	)
	(zone
		(layer "F.Cu")
		(hatch none 0.5)
		(connect_pads
			(clearance 0)
		)
		(min_thickness 0.25)
		(keepout
			(tracks not_allowed)
			(vias allowed)
			(pads allowed)
			(copperpour not_allowed)
			(footprints allowed)
		)
		(placement
			(enabled no)
			(sheetname "")
		)
		(fill
			(thermal_gap 0.5)
			(thermal_bridge_width 0.5)
			(island_removal_mode 0)
		)
		(polygon
			(pts
				(xy 429.926242 -351.840292) (xy 429.926242 -352.801174) (xy 430.168558 -352.801174) (xy 430.168558 -351.840292)
			)
		)
	)
	(zone
		(layer "F.Cu")
		(hatch none 0.5)
		(connect_pads
			(clearance 0)
		)
		(min_thickness 0.25)
		(keepout
			(tracks allowed)
			(vias allowed)
			(pads allowed)
			(copperpour allowed)
			(footprints allowed)
		)
		(placement
			(enabled no)
			(sheetname "")
		)
		(fill
			(thermal_gap 0.5)
			(thermal_bridge_width 0.5)
			(island_removal_mode 0)
		)
		(polygon
			(pts
				(xy 306.070508 -248.92762) (xy 306.070508 -248.59742) (xy 308.610508 -248.59742) (xy 308.610508 -248.92762)
			)
		)
	)
	(zone
		(layer "F.Cu")
		(hatch none 0.5)
		(connect_pads
			(clearance 0)
		)
		(min_thickness 0.25)
		(keepout
			(tracks not_allowed)
			(vias allowed)
			(pads allowed)
			(copperpour not_allowed)
			(footprints allowed)
		)
		(placement
			(enabled no)
			(sheetname "")
		)
		(fill
			(thermal_gap 0.5)
			(thermal_bridge_width 0.5)
			(island_removal_mode 0)
		)
		(polygon
			(pts
				(xy 65.025778 -10.49528) (xy 64.90843 -10.49528) (xy 64.85763 -10.54608) (xy 64.85763 -11.99388)
				(xy 64.90843 -12.04468) (xy 65.025778 -12.04468) (xy 65.076578 -11.99388) (xy 65.076578 -10.54608)
			)
		)
	)
	(zone
		(layer "F.Cu")
		(hatch none 0.5)
		(connect_pads
			(clearance 0)
		)
		(min_thickness 0.25)
		(keepout
			(tracks allowed)
			(vias allowed)
			(pads allowed)
			(copperpour allowed)
			(footprints allowed)
		)
		(placement
			(enabled no)
			(sheetname "")
		)
		(fill
			(thermal_gap 0.5)
			(thermal_bridge_width 0.5)
			(island_removal_mode 0)
		)
		(polygon
			(pts
				(xy 163.377626 -273.57832) (xy 163.377626 -273.24812) (xy 165.296596 -273.24812) (xy 165.296596 -273.57832)
			)
		)
	)
	(zone
		(layer "F.Cu")
		(hatch none 0.5)
		(connect_pads
			(clearance 0)
		)
		(min_thickness 0.25)
		(keepout
			(tracks allowed)
			(vias allowed)
			(pads allowed)
			(copperpour allowed)
			(footprints allowed)
		)
		(placement
			(enabled no)
			(sheetname "")
		)
		(fill
			(thermal_gap 0.5)
			(thermal_bridge_width 0.5)
			(island_removal_mode 0)
		)
		(polygon
			(pts
				(xy 163.377626 -205.577948) (xy 163.377626 -205.247748) (xy 165.296596 -205.247748) (xy 165.296596 -205.577948)
			)
		)
	)
	(zone
		(layer "F.Cu")
		(hatch none 0.5)
		(connect_pads
			(clearance 0)
		)
		(min_thickness 0.25)
		(keepout
			(tracks not_allowed)
			(vias allowed)
			(pads allowed)
			(copperpour not_allowed)
			(footprints allowed)
		)
		(placement
			(enabled no)
			(sheetname "")
		)
		(fill
			(thermal_gap 0.5)
			(thermal_bridge_width 0.5)
			(island_removal_mode 0)
		)
		(polygon
			(pts
				(arc
					(start 181.61508 -376.489976)
					(mid 173.384972 -376.489976)
					(end 181.61508 -376.489976)
				)
			)
		)
	)
	(zone
		(layer "F.Cu")
		(hatch none 0.5)
		(connect_pads
			(clearance 0)
		)
		(min_thickness 0.25)
		(keepout
			(tracks not_allowed)
			(vias allowed)
			(pads allowed)
			(copperpour not_allowed)
			(footprints allowed)
		)
		(placement
			(enabled no)
			(sheetname "")
		)
		(fill
			(thermal_gap 0.5)
			(thermal_bridge_width 0.5)
			(island_removal_mode 0)
		)
		(polygon
			(pts
				(xy 65.508378 -9.094724) (xy 65.625726 -9.094724) (xy 65.676526 -9.043924) (xy 65.676526 -7.596124)
				(xy 65.625726 -7.545324) (xy 65.508378 -7.545324) (xy 65.457578 -7.596124) (xy 65.457578 -9.043924)
			)
		)
	)
	(zone
		(layer "F.Cu")
		(hatch none 0.5)
		(connect_pads
			(clearance 0)
		)
		(min_thickness 0.25)
		(keepout
			(tracks not_allowed)
			(vias allowed)
			(pads allowed)
			(copperpour not_allowed)
			(footprints allowed)
		)
		(placement
			(enabled no)
			(sheetname "")
		)
		(fill
			(thermal_gap 0.5)
			(thermal_bridge_width 0.5)
			(island_removal_mode 0)
		)
		(polygon
			(pts
				(xy 282.50007 -87.286084) (xy 303.502568 -87.286084) (xy 303.502568 -59.993276) (xy 282.50007 -59.99099)
			)
		)
	)
	(zone
		(layer "F.Cu")
		(hatch none 0.5)
		(connect_pads
			(clearance 0)
		)
		(min_thickness 0.25)
		(keepout
			(tracks not_allowed)
			(vias allowed)
			(pads allowed)
			(copperpour not_allowed)
			(footprints allowed)
		)
		(placement
			(enabled no)
			(sheetname "")
		)
		(fill
			(thermal_gap 0.5)
			(thermal_bridge_width 0.5)
			(island_removal_mode 0)
		)
		(polygon
			(pts
				(xy 303.502568 -87.293196) (xy 303.502568 -59.993276) (xy 282.504642 -59.99099) (xy 282.501848 -87.29091)
			)
		)
	)
	(zone
		(layer "F.Cu")
		(hatch none 0.5)
		(connect_pads
			(clearance 0)
		)
		(min_thickness 0.25)
		(keepout
			(tracks allowed)
			(vias allowed)
			(pads allowed)
			(copperpour allowed)
			(footprints allowed)
		)
		(placement
			(enabled no)
			(sheetname "")
		)
		(fill
			(thermal_gap 0.5)
			(thermal_bridge_width 0.5)
			(island_removal_mode 0)
		)
		(polygon
			(pts
				(xy 163.377626 -237.027974) (xy 163.377626 -236.697774) (xy 165.296596 -236.697774) (xy 165.296596 -237.027974)
			)
		)
	)
	(zone
		(layer "F.Cu")
		(hatch none 0.5)
		(connect_pads
			(clearance 0)
		)
		(min_thickness 0.25)
		(keepout
			(tracks allowed)
			(vias allowed)
			(pads allowed)
			(copperpour allowed)
			(footprints allowed)
		)
		(placement
			(enabled no)
			(sheetname "")
		)
		(fill
			(thermal_gap 0.5)
			(thermal_bridge_width 0.5)
			(island_removal_mode 0)
		)
		(polygon
			(pts
				(xy 163.634928 -228.528118) (xy 163.634928 -228.197918) (xy 165.296596 -228.197918) (xy 165.296596 -228.528118)
			)
		)
	)
	(zone
		(layer "F.Cu")
		(hatch none 0.5)
		(connect_pads
			(clearance 0)
		)
		(min_thickness 0.25)
		(keepout
			(tracks allowed)
			(vias allowed)
			(pads allowed)
			(copperpour allowed)
			(footprints allowed)
		)
		(placement
			(enabled no)
			(sheetname "")
		)
		(fill
			(thermal_gap 0.5)
			(thermal_bridge_width 0.5)
			(island_removal_mode 0)
		)
		(polygon
			(pts
				(xy 410.27477 -384.406902) (xy 410.27477 -383.40284) (xy 411.671262 -383.40284) (xy 411.671262 -384.406902)
			)
		)
	)
	(zone
		(layer "F.Cu")
		(hatch none 0.5)
		(connect_pads
			(clearance 0)
		)
		(min_thickness 0.25)
		(keepout
			(tracks allowed)
			(vias allowed)
			(pads allowed)
			(copperpour allowed)
			(footprints not_allowed)
		)
		(placement
			(enabled no)
			(sheetname "")
		)
		(fill
			(thermal_gap 0.5)
			(thermal_bridge_width 0.5)
			(island_removal_mode 0)
		)
		(polygon
			(pts
				(arc
					(start 162.73145 -160.50006)
					(mid 167.73144 -155.50007)
					(end 172.73143 -160.50006)
				)
				(arc
					(start 172.73143 -160.50006)
					(mid 167.73144 -165.50005)
					(end 162.73145 -160.50006)
				)
			)
		)
	)
	(zone
		(layer "F.Cu")
		(hatch none 0.5)
		(connect_pads
			(clearance 0)
		)
		(min_thickness 0.25)
		(keepout
			(tracks allowed)
			(vias allowed)
			(pads allowed)
			(copperpour allowed)
			(footprints allowed)
		)
		(placement
			(enabled no)
			(sheetname "")
		)
		(fill
			(thermal_gap 0.5)
			(thermal_bridge_width 0.5)
			(island_removal_mode 0)
		)
		(polygon
			(pts
				(xy 47.638462 -347.226382) (xy 45.835062 -347.226382) (xy 45.835062 -348.775782) (xy 47.638462 -348.775782)
			)
		)
	)
	(zone
		(layer "F.Cu")
		(hatch none 0.5)
		(connect_pads
			(clearance 0)
		)
		(min_thickness 0.25)
		(keepout
			(tracks allowed)
			(vias allowed)
			(pads allowed)
			(copperpour allowed)
			(footprints allowed)
		)
		(placement
			(enabled no)
			(sheetname "")
		)
		(fill
			(thermal_gap 0.5)
			(thermal_bridge_width 0.5)
			(island_removal_mode 0)
		)
		(polygon
			(pts
				(xy 344.987118 -161.478976) (xy 350.63176 -161.478976) (xy 351.01276 -161.859976) (xy 351.01276 -164.17544)
				(xy 351.5868 -164.74948) (xy 351.95256 -164.74948) (xy 352.28276 -164.41928) (xy 352.28276 -163.32962)
				(xy 351.972118 -163.018978) (xy 351.972118 -160.843976) (xy 351.972118 -156.271976) (xy 351.337118 -155.636976)
				(xy 345.368118 -155.636976) (xy 344.860118 -156.144976) (xy 344.860118 -161.351976)
			)
		)
	)
	(zone
		(layer "F.Cu")
		(hatch none 0.5)
		(connect_pads
			(clearance 0)
		)
		(min_thickness 0.25)
		(keepout
			(tracks allowed)
			(vias allowed)
			(pads allowed)
			(copperpour allowed)
			(footprints not_allowed)
		)
		(placement
			(enabled no)
			(sheetname "")
		)
		(fill
			(thermal_gap 0.5)
			(thermal_bridge_width 0.5)
			(island_removal_mode 0)
		)
		(polygon
			(pts
				(xy 106.499914 -418.869876) (xy 106.499914 -440.989974) (xy 117.54993 -440.989974) (xy 117.54993 -418.869876)
			)
		)
	)
	(zone
		(layer "F.Cu")
		(hatch none 0.5)
		(connect_pads
			(clearance 0)
		)
		(min_thickness 0.25)
		(keepout
			(tracks allowed)
			(vias allowed)
			(pads allowed)
			(copperpour allowed)
			(footprints allowed)
		)
		(placement
			(enabled no)
			(sheetname "")
		)
		(fill
			(thermal_gap 0.5)
			(thermal_bridge_width 0.5)
			(island_removal_mode 0)
		)
		(polygon
			(pts
				(xy 58.13044 -269.328138) (xy 58.13044 -268.997938) (xy 60.67044 -268.997938) (xy 60.67044 -269.328138)
			)
		)
	)
	(zone
		(layer "F.Cu")
		(hatch none 0.5)
		(connect_pads
			(clearance 0)
		)
		(min_thickness 0.25)
		(keepout
			(tracks allowed)
			(vias allowed)
			(pads allowed)
			(copperpour allowed)
			(footprints allowed)
		)
		(placement
			(enabled no)
			(sheetname "")
		)
		(fill
			(thermal_gap 0.5)
			(thermal_bridge_width 0.5)
			(island_removal_mode 0)
		)
		(polygon
			(pts
				(xy 163.377626 -300.778164) (xy 163.377626 -300.447964) (xy 165.296596 -300.447964) (xy 165.296596 -300.778164)
			)
		)
	)
	(zone
		(layer "F.Cu")
		(hatch none 0.5)
		(connect_pads
			(clearance 0)
		)
		(min_thickness 0.25)
		(keepout
			(tracks allowed)
			(vias allowed)
			(pads allowed)
			(copperpour allowed)
			(footprints not_allowed)
		)
		(placement
			(enabled no)
			(sheetname "")
		)
		(fill
			(thermal_gap 0.5)
			(thermal_bridge_width 0.5)
			(island_removal_mode 0)
		)
		(polygon
			(pts
				(arc
					(start 425.981876 -163.314888)
					(mid 422.88206 -166.414704)
					(end 419.78199 -163.314888)
				)
				(arc
					(start 419.78199 -163.314888)
					(mid 422.88206 -160.214818)
					(end 425.981876 -163.314888)
				)
			)
		)
	)
	(zone
		(layer "F.Cu")
		(hatch none 0.5)
		(connect_pads
			(clearance 0)
		)
		(min_thickness 0.25)
		(keepout
			(tracks allowed)
			(vias allowed)
			(pads allowed)
			(copperpour allowed)
			(footprints allowed)
		)
		(placement
			(enabled no)
			(sheetname "")
		)
		(fill
			(thermal_gap 0.5)
			(thermal_bridge_width 0.5)
			(island_removal_mode 0)
		)
		(polygon
			(pts
				(xy 249.75058 -5.81152) (xy 249.75058 -3.93954) (xy 252.17628 -3.93954) (xy 252.17628 -5.81152)
			)
		)
	)
	(zone
		(layer "F.Cu")
		(hatch none 0.5)
		(connect_pads
			(clearance 0)
		)
		(min_thickness 0.25)
		(keepout
			(tracks allowed)
			(vias allowed)
			(pads allowed)
			(copperpour allowed)
			(footprints not_allowed)
		)
		(placement
			(enabled no)
			(sheetname "")
		)
		(fill
			(thermal_gap 0.5)
			(thermal_bridge_width 0.5)
			(island_removal_mode 0)
		)
		(polygon
			(pts
				(xy 293.327074 -183.50992) (xy 287.126934 -183.50992) (xy 287.126934 -327.609962) (xy 293.327074 -327.609962)
			)
		)
	)
	(zone
		(layer "F.Cu")
		(hatch none 0.5)
		(connect_pads
			(clearance 0)
		)
		(min_thickness 0.25)
		(keepout
			(tracks allowed)
			(vias allowed)
			(pads allowed)
			(copperpour allowed)
			(footprints allowed)
		)
		(placement
			(enabled no)
			(sheetname "")
		)
		(fill
			(thermal_gap 0.5)
			(thermal_bridge_width 0.5)
			(island_removal_mode 0)
		)
		(polygon
			(pts
				(xy 14.02334 -107.312968) (xy 14.02334 -104.790748) (xy 17.10944 -104.790748) (xy 17.10944 -107.312968)
			)
		)
	)
	(zone
		(layer "F.Cu")
		(hatch none 0.5)
		(connect_pads
			(clearance 0)
		)
		(min_thickness 0.25)
		(keepout
			(tracks allowed)
			(vias allowed)
			(pads allowed)
			(copperpour allowed)
			(footprints not_allowed)
		)
		(placement
			(enabled no)
			(sheetname "")
		)
		(fill
			(thermal_gap 0.5)
			(thermal_bridge_width 0.5)
			(island_removal_mode 0)
		)
		(polygon
			(pts
				(xy 19.454114 -161.26333) (xy 40.454072 -161.265616) (xy 40.45585 -144.808448) (xy 129.09677 -144.808448)
				(xy 129.09677 -151.545036) (xy 120.026684 -151.545036) (xy 120.026684 -161.275014) (xy 111.716058 -161.275014)
				(xy 102.20706 -161.275014) (xy 102.20706 -170.835066) (xy 97.726754 -170.835066) (xy 97.726754 -176.224946)
				(xy 84.162138 -176.224946) (xy 84.162138 -172.995082) (xy 77.252068 -172.995082) (xy 77.252068 -167.239188)
				(xy 73.078086 -163.314888) (xy 57.954926 -163.314888) (xy 48.896778 -163.314888) (xy 48.896778 -165.596062)
				(arc
					(start 16.506952 -165.596062)
					(mid 14.520352 -153.679147)
					(end 2.999994 -157.318202)
				)
				(xy 2.999994 -144.808448) (xy 19.455638 -144.808448)
			)
		)
	)
	(zone
		(layer "F.Cu")
		(hatch none 0.5)
		(connect_pads
			(clearance 0)
		)
		(min_thickness 0.25)
		(keepout
			(tracks not_allowed)
			(vias allowed)
			(pads allowed)
			(copperpour not_allowed)
			(footprints allowed)
		)
		(placement
			(enabled no)
			(sheetname "")
		)
		(fill
			(thermal_gap 0.5)
			(thermal_bridge_width 0.5)
			(island_removal_mode 0)
		)
		(polygon
			(pts
				(xy 438.208166 -9.094724) (xy 438.325514 -9.094724) (xy 438.376314 -9.043924) (xy 438.376314 -7.596124)
				(xy 438.325514 -7.545324) (xy 438.208166 -7.545324) (xy 438.157366 -7.596124) (xy 438.157366 -9.043924)
			)
		)
	)
	(zone
		(layer "F.Cu")
		(hatch none 0.5)
		(connect_pads
			(clearance 0)
		)
		(min_thickness 0.25)
		(keepout
			(tracks allowed)
			(vias allowed)
			(pads allowed)
			(copperpour allowed)
			(footprints allowed)
		)
		(placement
			(enabled no)
			(sheetname "")
		)
		(fill
			(thermal_gap 0.5)
			(thermal_bridge_width 0.5)
			(island_removal_mode 0)
		)
		(polygon
			(pts
				(xy 354.339906 -339.810344) (xy 348.794324 -339.810344) (xy 348.497144 -339.513164) (xy 348.497144 -337.187032)
				(xy 347.834204 -336.524092) (xy 347.183964 -336.524092) (xy 346.914724 -336.793332) (xy 346.914724 -338.022692)
				(xy 347.354906 -338.462874) (xy 347.354906 -340.445344) (xy 347.354906 -345.017344) (xy 347.989906 -345.652344)
				(xy 353.958906 -345.652344) (xy 354.466906 -345.144344) (xy 354.466906 -339.937344)
			)
		)
	)
	(zone
		(layer "F.Cu")
		(hatch none 0.5)
		(connect_pads
			(clearance 0)
		)
		(min_thickness 0.25)
		(keepout
			(tracks not_allowed)
			(vias allowed)
			(pads allowed)
			(copperpour not_allowed)
			(footprints allowed)
		)
		(placement
			(enabled no)
			(sheetname "")
		)
		(fill
			(thermal_gap 0.5)
			(thermal_bridge_width 0.5)
			(island_removal_mode 0)
		)
		(polygon
			(pts
				(xy 84.784692 -183.493156) (xy 84.784692 -183.036464) (xy 84.088986 -183.036464) (xy 84.088986 -183.196992)
				(xy 83.530186 -183.196992) (xy 83.530186 -182.790592) (xy 84.088986 -182.790592) (xy 84.088986 -183.011064)
				(xy 84.784692 -183.011064) (xy 84.784692 -182.884064) (xy 84.329016 -182.884064) (xy 84.329016 -182.497476)
				(xy 84.0867 -182.497476) (xy 83.554824 -182.497476) (xy 83.235292 -182.817008) (xy 83.235292 -183.493156)
			)
		)
	)
	(zone
		(layer "F.Cu")
		(hatch none 0.5)
		(connect_pads
			(clearance 0)
		)
		(min_thickness 0.25)
		(keepout
			(tracks allowed)
			(vias allowed)
			(pads allowed)
			(copperpour allowed)
			(footprints allowed)
		)
		(placement
			(enabled no)
			(sheetname "")
		)
		(fill
			(thermal_gap 0.5)
			(thermal_bridge_width 0.5)
			(island_removal_mode 0)
		)
		(polygon
			(pts
				(xy 411.562042 -220.027754) (xy 411.562042 -219.697554) (xy 413.236664 -219.697554) (xy 413.236664 -220.027754)
			)
		)
	)
	(zone
		(layer "F.Cu")
		(hatch none 0.5)
		(connect_pads
			(clearance 0)
		)
		(min_thickness 0.25)
		(keepout
			(tracks allowed)
			(vias allowed)
			(pads allowed)
			(copperpour allowed)
			(footprints allowed)
		)
		(placement
			(enabled no)
			(sheetname "")
		)
		(fill
			(thermal_gap 0.5)
			(thermal_bridge_width 0.5)
			(island_removal_mode 0)
		)
		(polygon
			(pts
				(xy 163.634928 -237.878112) (xy 163.634928 -237.547912) (xy 165.296596 -237.547912) (xy 165.296596 -237.878112)
			)
		)
	)
	(zone
		(layer "F.Cu")
		(hatch none 0.5)
		(connect_pads
			(clearance 0)
		)
		(min_thickness 0.25)
		(keepout
			(tracks allowed)
			(vias allowed)
			(pads allowed)
			(copperpour allowed)
			(footprints allowed)
		)
		(placement
			(enabled no)
			(sheetname "")
		)
		(fill
			(thermal_gap 0.5)
			(thermal_bridge_width 0.5)
			(island_removal_mode 0)
		)
		(polygon
			(pts
				(xy 163.377626 -264.228072) (xy 163.377626 -263.897872) (xy 165.296596 -263.897872) (xy 165.296596 -264.228072)
			)
		)
	)
	(zone
		(layer "F.Cu")
		(hatch none 0.5)
		(connect_pads
			(clearance 0)
		)
		(min_thickness 0.25)
		(keepout
			(tracks allowed)
			(vias allowed)
			(pads allowed)
			(copperpour allowed)
			(footprints allowed)
		)
		(placement
			(enabled no)
			(sheetname "")
		)
		(fill
			(thermal_gap 0.5)
			(thermal_bridge_width 0.5)
			(island_removal_mode 0)
		)
		(polygon
			(pts
				(xy 60.725812 -278.342598) (xy 60.725812 -278.672798) (xy 58.185812 -278.672798) (xy 58.185812 -278.342598)
			)
		)
	)
	(zone
		(layer "F.Cu")
		(hatch none 0.5)
		(connect_pads
			(clearance 0)
		)
		(min_thickness 0.25)
		(keepout
			(tracks allowed)
			(vias allowed)
			(pads allowed)
			(copperpour allowed)
			(footprints not_allowed)
		)
		(placement
			(enabled no)
			(sheetname "")
		)
		(fill
			(thermal_gap 0.5)
			(thermal_bridge_width 0.5)
			(island_removal_mode 0)
		)
		(polygon
			(pts
				(xy 361.22991 -403.260052) (xy 366.260126 -403.260052) (xy 366.260126 -398.560036) (xy 361.22991 -398.560036)
			)
		)
	)
	(zone
		(layer "F.Cu")
		(hatch none 0.5)
		(connect_pads
			(clearance 0)
		)
		(min_thickness 0.25)
		(keepout
			(tracks not_allowed)
			(vias allowed)
			(pads allowed)
			(copperpour not_allowed)
			(footprints allowed)
		)
		(placement
			(enabled no)
			(sheetname "")
		)
		(fill
			(thermal_gap 0.5)
			(thermal_bridge_width 0.5)
			(island_removal_mode 0)
		)
		(polygon
			(pts
				(xy 63.22568 -10.49528) (xy 63.108332 -10.49528) (xy 63.057532 -10.54608) (xy 63.057532 -11.99388)
				(xy 63.108332 -12.04468) (xy 63.22568 -12.04468) (xy 63.27648 -11.99388) (xy 63.27648 -10.54608)
			)
		)
	)
	(zone
		(layer "F.Cu")
		(hatch none 0.5)
		(connect_pads
			(clearance 0)
		)
		(min_thickness 0.25)
		(keepout
			(tracks allowed)
			(vias allowed)
			(pads allowed)
			(copperpour allowed)
			(footprints allowed)
		)
		(placement
			(enabled no)
			(sheetname "")
		)
		(fill
			(thermal_gap 0.5)
			(thermal_bridge_width 0.5)
			(island_removal_mode 0)
		)
		(polygon
			(pts
				(xy 122.112786 -76.35494) (xy 122.112786 -73.18502) (xy 123.867926 -73.18502) (xy 123.867926 -76.35494)
			)
		)
	)
	(zone
		(layer "F.Cu")
		(hatch none 0.5)
		(connect_pads
			(clearance 0)
		)
		(min_thickness 0.25)
		(keepout
			(tracks allowed)
			(vias allowed)
			(pads allowed)
			(copperpour allowed)
			(footprints not_allowed)
		)
		(placement
			(enabled no)
			(sheetname "")
		)
		(fill
			(thermal_gap 0.5)
			(thermal_bridge_width 0.5)
			(island_removal_mode 0)
		)
		(polygon
			(pts
				(arc
					(start 462.000092 -22.29993)
					(mid 464.800188 -19.499834)
					(end 467.60003 -22.29993)
				)
				(arc
					(start 467.60003 -22.29993)
					(mid 464.800188 -25.099772)
					(end 462.000092 -22.29993)
				)
			)
		)
	)
	(zone
		(layer "F.Cu")
		(hatch none 0.5)
		(connect_pads
			(clearance 0)
		)
		(min_thickness 0.25)
		(keepout
			(tracks allowed)
			(vias allowed)
			(pads allowed)
			(copperpour allowed)
			(footprints not_allowed)
		)
		(placement
			(enabled no)
			(sheetname "")
		)
		(fill
			(thermal_gap 0.5)
			(thermal_bridge_width 0.5)
			(island_removal_mode 0)
		)
		(polygon
			(pts
				(arc
					(start 388.899908 -22.29993)
					(mid 380.899924 -30.299914)
					(end 372.89994 -22.29993)
				)
				(arc
					(start 372.89994 -22.29993)
					(mid 380.899924 -14.299946)
					(end 388.899908 -22.29993)
				)
			)
		)
	)
	(zone
		(layer "F.Cu")
		(hatch none 0.5)
		(connect_pads
			(clearance 0)
		)
		(min_thickness 0.25)
		(keepout
			(tracks allowed)
			(vias allowed)
			(pads allowed)
			(copperpour allowed)
			(footprints allowed)
		)
		(placement
			(enabled no)
			(sheetname "")
		)
		(fill
			(thermal_gap 0.5)
			(thermal_bridge_width 0.5)
			(island_removal_mode 0)
		)
		(polygon
			(pts
				(xy 145.24609 -409.042616) (xy 145.24609 -408.038554) (xy 146.642582 -408.038554) (xy 146.642582 -409.042616)
			)
		)
	)
	(zone
		(layer "F.Cu")
		(hatch none 0.5)
		(connect_pads
			(clearance 0)
		)
		(min_thickness 0.25)
		(keepout
			(tracks allowed)
			(vias allowed)
			(pads allowed)
			(copperpour allowed)
			(footprints allowed)
		)
		(placement
			(enabled no)
			(sheetname "")
		)
		(fill
			(thermal_gap 0.5)
			(thermal_bridge_width 0.5)
			(island_removal_mode 0)
		)
		(polygon
			(pts
				(xy 112.3696 -27.5336) (xy 116.1542 -27.5336) (xy 116.4336 -27.2542) (xy 116.4336 -26.3906) (xy 115.9002 -25.8572)
				(xy 114.8588 -25.8572) (xy 114.2238 -25.2222) (xy 114.2238 -24.13) (xy 113.8936 -23.7998) (xy 112.8522 -23.7998)
				(xy 112.268 -24.384) (xy 112.268 -27.432)
			)
		)
	)
	(zone
		(layer "F.Cu")
		(hatch none 0.5)
		(connect_pads
			(clearance 0)
		)
		(min_thickness 0.25)
		(keepout
			(tracks allowed)
			(vias allowed)
			(pads allowed)
			(copperpour allowed)
			(footprints not_allowed)
		)
		(placement
			(enabled no)
			(sheetname "")
		)
		(fill
			(thermal_gap 0.5)
			(thermal_bridge_width 0.5)
			(island_removal_mode 0)
		)
		(polygon
			(pts
				(arc
					(start 366.345724 -435.551834)
					(mid 371.345714 -430.551844)
					(end 376.345704 -435.551834)
				)
				(arc
					(start 376.345704 -435.551834)
					(mid 371.345714 -440.551824)
					(end 366.345724 -435.551834)
				)
			)
		)
	)
	(zone
		(layer "F.Cu")
		(hatch none 0.5)
		(connect_pads
			(clearance 0)
		)
		(min_thickness 0.25)
		(keepout
			(tracks allowed)
			(vias allowed)
			(pads allowed)
			(copperpour allowed)
			(footprints allowed)
		)
		(placement
			(enabled no)
			(sheetname "")
		)
		(fill
			(thermal_gap 0.5)
			(thermal_bridge_width 0.5)
			(island_removal_mode 0)
		)
		(polygon
			(pts
				(xy 337.9724 -5.90042) (xy 337.9724 -3.80746) (xy 340.3092 -3.80746) (xy 340.3092 -5.90042)
			)
		)
	)
	(zone
		(layer "F.Cu")
		(hatch none 0.5)
		(connect_pads
			(clearance 0)
		)
		(min_thickness 0.25)
		(keepout
			(tracks allowed)
			(vias allowed)
			(pads allowed)
			(copperpour allowed)
			(footprints not_allowed)
		)
		(placement
			(enabled no)
			(sheetname "")
		)
		(fill
			(thermal_gap 0.5)
			(thermal_bridge_width 0.5)
			(island_removal_mode 0)
		)
		(polygon
			(pts
				(arc
					(start 424.749976 -413.170116)
					(mid 427.000162 -410.91993)
					(end 429.250094 -413.170116)
				)
				(arc
					(start 429.250094 -413.170116)
					(mid 427.000162 -415.420048)
					(end 424.749976 -413.170116)
				)
			)
		)
	)
	(zone
		(layer "F.Cu")
		(hatch none 0.5)
		(connect_pads
			(clearance 0)
		)
		(min_thickness 0.25)
		(keepout
			(tracks allowed)
			(vias allowed)
			(pads allowed)
			(copperpour allowed)
			(footprints allowed)
		)
		(placement
			(enabled no)
			(sheetname "")
		)
		(fill
			(thermal_gap 0.5)
			(thermal_bridge_width 0.5)
			(island_removal_mode 0)
		)
		(polygon
			(pts
				(xy 99.128834 -139.862052) (xy 99.128834 -141.386052) (xy 93.286834 -141.386052) (xy 93.286834 -139.862052)
			)
		)
	)
	(zone
		(layer "F.Cu")
		(hatch none 0.5)
		(connect_pads
			(clearance 0)
		)
		(min_thickness 0.25)
		(keepout
			(tracks not_allowed)
			(vias allowed)
			(pads allowed)
			(copperpour not_allowed)
			(footprints allowed)
		)
		(placement
			(enabled no)
			(sheetname "")
		)
		(fill
			(thermal_gap 0.5)
			(thermal_bridge_width 0.5)
			(island_removal_mode 0)
		)
		(polygon
			(pts
				(arc
					(start 265.8999 -51.999896)
					(mid 268.649958 -49.249838)
					(end 271.400016 -51.999896)
				)
				(arc
					(start 271.400016 -51.999896)
					(mid 268.649958 -54.749954)
					(end 265.8999 -51.999896)
				)
			)
		)
	)
	(zone
		(layer "F.Cu")
		(hatch none 0.5)
		(connect_pads
			(clearance 0)
		)
		(min_thickness 0.25)
		(keepout
			(tracks allowed)
			(vias allowed)
			(pads allowed)
			(copperpour allowed)
			(footprints not_allowed)
		)
		(placement
			(enabled no)
			(sheetname "")
		)
		(fill
			(thermal_gap 0.5)
			(thermal_bridge_width 0.5)
			(island_removal_mode 0)
		)
		(polygon
			(pts
				(xy 137.750042 -390.180068) (xy 137.750042 -394.880084) (xy 142.780004 -394.880084) (xy 142.780004 -390.180068)
			)
		)
	)
	(zone
		(layer "F.Cu")
		(hatch none 0.5)
		(connect_pads
			(clearance 0)
		)
		(min_thickness 0.25)
		(keepout
			(tracks allowed)
			(vias allowed)
			(pads allowed)
			(copperpour allowed)
			(footprints allowed)
		)
		(placement
			(enabled no)
			(sheetname "")
		)
		(fill
			(thermal_gap 0.5)
			(thermal_bridge_width 0.5)
			(island_removal_mode 0)
		)
		(polygon
			(pts
				(xy 60.344812 -228.192838) (xy 60.344812 -228.523038) (xy 57.804812 -228.523038) (xy 57.804812 -228.192838)
			)
		)
	)
	(zone
		(layer "F.Cu")
		(hatch none 0.5)
		(connect_pads
			(clearance 0)
		)
		(min_thickness 0.25)
		(keepout
			(tracks allowed)
			(vias allowed)
			(pads allowed)
			(copperpour allowed)
			(footprints not_allowed)
		)
		(placement
			(enabled no)
			(sheetname "")
		)
		(fill
			(thermal_gap 0.5)
			(thermal_bridge_width 0.5)
			(island_removal_mode 0)
		)
		(polygon
			(pts
				(arc
					(start 18.350992 -347.8149)
					(mid 20.216114 -345.949778)
					(end 22.080982 -347.8149)
				)
				(arc
					(start 22.080982 -347.8149)
					(mid 20.216114 -349.679768)
					(end 18.350992 -347.8149)
				)
			)
		)
	)
	(zone
		(layer "F.Cu")
		(hatch none 0.5)
		(connect_pads
			(clearance 0)
		)
		(min_thickness 0.25)
		(keepout
			(tracks allowed)
			(vias allowed)
			(pads allowed)
			(copperpour allowed)
			(footprints not_allowed)
		)
		(placement
			(enabled no)
			(sheetname "")
		)
		(fill
			(thermal_gap 0.5)
			(thermal_bridge_width 0.5)
			(island_removal_mode 0)
		)
		(polygon
			(pts
				(arc
					(start 39.070026 -376.489976)
					(mid 35.070034 -380.489968)
					(end 31.070042 -376.489976)
				)
				(arc
					(start 31.070042 -376.489976)
					(mid 35.070034 -372.489984)
					(end 39.070026 -376.489976)
				)
			)
		)
	)
	(zone
		(layer "F.Cu")
		(hatch none 0.5)
		(connect_pads
			(clearance 0)
		)
		(min_thickness 0.25)
		(keepout
			(tracks allowed)
			(vias allowed)
			(pads allowed)
			(copperpour allowed)
			(footprints allowed)
		)
		(placement
			(enabled no)
			(sheetname "")
		)
		(fill
			(thermal_gap 0.5)
			(thermal_bridge_width 0.5)
			(island_removal_mode 0)
		)
		(polygon
			(pts
				(xy 411.317694 -292.278054) (xy 411.317694 -291.947854) (xy 413.236664 -291.947854) (xy 413.236664 -292.278054)
			)
		)
	)
	(zone
		(layer "F.Cu")
		(hatch none 0.5)
		(connect_pads
			(clearance 0)
		)
		(min_thickness 0.25)
		(keepout
			(tracks allowed)
			(vias allowed)
			(pads allowed)
			(copperpour allowed)
			(footprints not_allowed)
		)
		(placement
			(enabled no)
			(sheetname "")
		)
		(fill
			(thermal_gap 0.5)
			(thermal_bridge_width 0.5)
			(island_removal_mode 0)
		)
		(polygon
			(pts
				(arc
					(start 330.731622 -160.50006)
					(mid 322.731638 -168.500044)
					(end 314.7314 -160.50006)
				)
				(arc
					(start 314.7314 -160.50006)
					(mid 322.731638 -152.499822)
					(end 330.731622 -160.50006)
				)
			)
		)
	)
	(zone
		(layer "F.Cu")
		(hatch none 0.5)
		(connect_pads
			(clearance 0)
		)
		(min_thickness 0.25)
		(keepout
			(tracks allowed)
			(vias allowed)
			(pads allowed)
			(copperpour allowed)
			(footprints allowed)
		)
		(placement
			(enabled no)
			(sheetname "")
		)
		(fill
			(thermal_gap 0.5)
			(thermal_bridge_width 0.5)
			(island_removal_mode 0)
		)
		(polygon
			(pts
				(xy 411.574996 -237.877858) (xy 411.574996 -237.547658) (xy 413.236664 -237.547658) (xy 413.236664 -237.877858)
			)
		)
	)
	(zone
		(layer "F.Cu")
		(hatch none 0.5)
		(connect_pads
			(clearance 0)
		)
		(min_thickness 0.25)
		(keepout
			(tracks allowed)
			(vias allowed)
			(pads allowed)
			(copperpour allowed)
			(footprints allowed)
		)
		(placement
			(enabled no)
			(sheetname "")
		)
		(fill
			(thermal_gap 0.5)
			(thermal_bridge_width 0.5)
			(island_removal_mode 0)
		)
		(polygon
			(pts
				(xy 64.35852 -40.15486) (xy 64.35852 -39.46652) (xy 65.64122 -39.46652) (xy 65.64122 -40.15486)
			)
		)
	)
	(zone
		(layer "F.Cu")
		(hatch none 0.5)
		(connect_pads
			(clearance 0)
		)
		(min_thickness 0.25)
		(keepout
			(tracks allowed)
			(vias allowed)
			(pads allowed)
			(copperpour allowed)
			(footprints not_allowed)
		)
		(placement
			(enabled no)
			(sheetname "")
		)
		(fill
			(thermal_gap 0.5)
			(thermal_bridge_width 0.5)
			(island_removal_mode 0)
		)
		(polygon
			(pts
				(xy 15.915894 -351.605088) (xy 22.406356 -351.605088) (xy 22.406356 -350.665034) (xy 23.896066 -350.665034)
				(xy 23.896066 -342.914986) (xy 15.915894 -342.914986)
			)
		)
	)
	(zone
		(layer "F.Cu")
		(hatch none 0.5)
		(connect_pads
			(clearance 0)
		)
		(min_thickness 0.25)
		(keepout
			(tracks allowed)
			(vias allowed)
			(pads allowed)
			(copperpour allowed)
			(footprints allowed)
		)
		(placement
			(enabled no)
			(sheetname "")
		)
		(fill
			(thermal_gap 0.5)
			(thermal_bridge_width 0.5)
			(island_removal_mode 0)
		)
		(polygon
			(pts
				(xy 329.7301 -47.16526) (xy 329.7301 -46.36262) (xy 330.92898 -46.36262) (xy 330.92898 -47.16526)
			)
		)
	)
	(zone
		(layer "F.Cu")
		(hatch none 0.5)
		(connect_pads
			(clearance 0)
		)
		(min_thickness 0.25)
		(keepout
			(tracks allowed)
			(vias allowed)
			(pads allowed)
			(copperpour allowed)
			(footprints allowed)
		)
		(placement
			(enabled no)
			(sheetname "")
		)
		(fill
			(thermal_gap 0.5)
			(thermal_bridge_width 0.5)
			(island_removal_mode 0)
		)
		(polygon
			(pts
				(xy 73.312782 -175.57115) (xy 71.509382 -175.57115) (xy 71.509382 -177.12055) (xy 73.312782 -177.12055)
			)
		)
	)
	(zone
		(layer "F.Cu")
		(hatch none 0.5)
		(connect_pads
			(clearance 0)
		)
		(min_thickness 0.25)
		(keepout
			(tracks allowed)
			(vias allowed)
			(pads allowed)
			(copperpour allowed)
			(footprints allowed)
		)
		(placement
			(enabled no)
			(sheetname "")
		)
		(fill
			(thermal_gap 0.5)
			(thermal_bridge_width 0.5)
			(island_removal_mode 0)
		)
		(polygon
			(pts
				(xy 410.435806 -417.424616) (xy 410.435806 -416.420554) (xy 411.832298 -416.420554) (xy 411.832298 -417.424616)
			)
		)
	)
	(zone
		(layer "F.Cu")
		(hatch none 0.5)
		(connect_pads
			(clearance 0)
		)
		(min_thickness 0.25)
		(keepout
			(tracks allowed)
			(vias allowed)
			(pads allowed)
			(copperpour allowed)
			(footprints allowed)
		)
		(placement
			(enabled no)
			(sheetname "")
		)
		(fill
			(thermal_gap 0.5)
			(thermal_bridge_width 0.5)
			(island_removal_mode 0)
		)
		(polygon
			(pts
				(xy 131.775962 -154.47645) (xy 129.972562 -154.47645) (xy 129.972562 -156.02585) (xy 131.775962 -156.02585)
			)
		)
	)
	(zone
		(layer "F.Cu")
		(hatch none 0.5)
		(connect_pads
			(clearance 0)
		)
		(min_thickness 0.25)
		(keepout
			(tracks allowed)
			(vias allowed)
			(pads allowed)
			(copperpour allowed)
			(footprints allowed)
		)
		(placement
			(enabled no)
			(sheetname "")
		)
		(fill
			(thermal_gap 0.5)
			(thermal_bridge_width 0.5)
			(island_removal_mode 0)
		)
		(polygon
			(pts
				(xy 312.34888 -381.943102) (xy 312.34888 -380.93904) (xy 313.745372 -380.93904) (xy 313.745372 -381.943102)
			)
		)
	)
	(zone
		(layer "F.Cu")
		(hatch none 0.5)
		(connect_pads
			(clearance 0)
		)
		(min_thickness 0.25)
		(keepout
			(tracks allowed)
			(vias allowed)
			(pads allowed)
			(copperpour allowed)
			(footprints allowed)
		)
		(placement
			(enabled no)
			(sheetname "")
		)
		(fill
			(thermal_gap 0.5)
			(thermal_bridge_width 0.5)
			(island_removal_mode 0)
		)
		(polygon
			(pts
				(xy 403.407118 -168.933368) (xy 409.757118 -168.933368) (xy 410.392118 -168.298368) (xy 410.392118 -163.726368)
				(xy 409.757118 -163.091368) (xy 403.788118 -163.091368) (xy 403.280118 -163.599368) (xy 403.280118 -168.806368)
			)
		)
	)
	(zone
		(layer "F.Cu")
		(hatch none 0.5)
		(connect_pads
			(clearance 0)
		)
		(min_thickness 0.25)
		(keepout
			(tracks allowed)
			(vias allowed)
			(pads allowed)
			(copperpour allowed)
			(footprints allowed)
		)
		(placement
			(enabled no)
			(sheetname "")
		)
		(fill
			(thermal_gap 0.5)
			(thermal_bridge_width 0.5)
			(island_removal_mode 0)
		)
		(polygon
			(pts
				(xy 305.91887 -332.196694) (xy 305.91887 -334.101694) (xy 309.93207 -334.101694) (xy 309.93207 -332.196694)
			)
		)
	)
	(zone
		(layer "F.Cu")
		(hatch none 0.5)
		(connect_pads
			(clearance 0)
		)
		(min_thickness 0.25)
		(keepout
			(tracks allowed)
			(vias allowed)
			(pads allowed)
			(copperpour allowed)
			(footprints allowed)
		)
		(placement
			(enabled no)
			(sheetname "")
		)
		(fill
			(thermal_gap 0.5)
			(thermal_bridge_width 0.5)
			(island_removal_mode 0)
		)
		(polygon
			(pts
				(xy 161.80181 -360.936032) (xy 162.100006 -361.234228) (xy 162.018726 -361.315508) (xy 161.72053 -361.017312)
			)
		)
	)
	(zone
		(layer "F.Cu")
		(hatch none 0.5)
		(connect_pads
			(clearance 0)
		)
		(min_thickness 0.25)
		(keepout
			(tracks allowed)
			(vias allowed)
			(pads allowed)
			(copperpour allowed)
			(footprints allowed)
		)
		(placement
			(enabled no)
			(sheetname "")
		)
		(fill
			(thermal_gap 0.5)
			(thermal_bridge_width 0.5)
			(island_removal_mode 0)
		)
		(polygon
			(pts
				(xy 442.358272 -402.368512) (xy 442.358272 -400.06651) (xy 446.341246 -400.06651) (xy 446.617598 -400.06651)
				(xy 447.799714 -401.248626) (xy 447.799714 -402.206968) (xy 447.63817 -402.368512) (xy 447.280284 -402.368512)
				(xy 446.341246 -402.368512)
			)
		)
	)
	(zone
		(layer "F.Cu")
		(hatch none 0.5)
		(connect_pads
			(clearance 0)
		)
		(min_thickness 0.25)
		(keepout
			(tracks allowed)
			(vias allowed)
			(pads allowed)
			(copperpour allowed)
			(footprints allowed)
		)
		(placement
			(enabled no)
			(sheetname "")
		)
		(fill
			(thermal_gap 0.5)
			(thermal_bridge_width 0.5)
			(island_removal_mode 0)
		)
		(polygon
			(pts
				(xy 163.621974 -276.127972) (xy 163.621974 -275.797772) (xy 165.296596 -275.797772) (xy 165.296596 -276.127972)
			)
		)
	)
	(zone
		(layer "F.Cu")
		(hatch none 0.5)
		(connect_pads
			(clearance 0)
		)
		(min_thickness 0.25)
		(keepout
			(tracks allowed)
			(vias allowed)
			(pads allowed)
			(copperpour allowed)
			(footprints not_allowed)
		)
		(placement
			(enabled no)
			(sheetname "")
		)
		(fill
			(thermal_gap 0.5)
			(thermal_bridge_width 0.5)
			(island_removal_mode 0)
		)
		(polygon
			(pts
				(arc
					(start 52.85105 -167.135048)
					(mid 54.716172 -165.269926)
					(end 56.58104 -167.135048)
				)
				(arc
					(start 56.58104 -167.135048)
					(mid 54.716172 -168.999916)
					(end 52.85105 -167.135048)
				)
			)
		)
	)
	(zone
		(layer "F.Cu")
		(hatch none 0.5)
		(connect_pads
			(clearance 0)
		)
		(min_thickness 0.25)
		(keepout
			(tracks allowed)
			(vias allowed)
			(pads allowed)
			(copperpour allowed)
			(footprints not_allowed)
		)
		(placement
			(enabled no)
			(sheetname "")
		)
		(fill
			(thermal_gap 0.5)
			(thermal_bridge_width 0.5)
			(island_removal_mode 0)
		)
		(polygon
			(pts
				(xy 430.559972 -404.850092) (xy 438.85993 -404.850092) (xy 438.85993 -394.24991) (xy 430.559972 -394.24991)
			)
		)
	)
	(zone
		(layer "F.Cu")
		(hatch none 0.5)
		(connect_pads
			(clearance 0)
		)
		(min_thickness 0.25)
		(keepout
			(tracks allowed)
			(vias allowed)
			(pads allowed)
			(copperpour allowed)
			(footprints allowed)
		)
		(placement
			(enabled no)
			(sheetname "")
		)
		(fill
			(thermal_gap 0.5)
			(thermal_bridge_width 0.5)
			(island_removal_mode 0)
		)
		(polygon
			(pts
				(xy 163.377626 -310.978296) (xy 163.377626 -310.648096) (xy 165.296596 -310.648096) (xy 165.296596 -310.978296)
			)
		)
	)
	(zone
		(layer "F.Cu")
		(hatch none 0.5)
		(connect_pads
			(clearance 0)
		)
		(min_thickness 0.25)
		(keepout
			(tracks allowed)
			(vias allowed)
			(pads allowed)
			(copperpour allowed)
			(footprints allowed)
		)
		(placement
			(enabled no)
			(sheetname "")
		)
		(fill
			(thermal_gap 0.5)
			(thermal_bridge_width 0.5)
			(island_removal_mode 0)
		)
		(polygon
			(pts
				(xy 411.317694 -263.377934) (xy 411.317694 -263.047734) (xy 413.236664 -263.047734) (xy 413.236664 -263.377934)
			)
		)
	)
	(zone
		(layer "F.Cu")
		(hatch none 0.5)
		(connect_pads
			(clearance 0)
		)
		(min_thickness 0.25)
		(keepout
			(tracks allowed)
			(vias allowed)
			(pads allowed)
			(copperpour allowed)
			(footprints not_allowed)
		)
		(placement
			(enabled no)
			(sheetname "")
		)
		(fill
			(thermal_gap 0.5)
			(thermal_bridge_width 0.5)
			(island_removal_mode 0)
		)
		(polygon
			(pts
				(arc
					(start 326.47001 -212.989922)
					(mid 329.270106 -210.189826)
					(end 332.069948 -212.989922)
				)
				(arc
					(start 332.069948 -212.989922)
					(mid 329.270106 -215.789764)
					(end 326.47001 -212.989922)
				)
			)
		)
	)
	(zone
		(layer "F.Cu")
		(hatch none 0.5)
		(connect_pads
			(clearance 0)
		)
		(min_thickness 0.25)
		(keepout
			(tracks allowed)
			(vias allowed)
			(pads allowed)
			(copperpour allowed)
			(footprints allowed)
		)
		(placement
			(enabled no)
			(sheetname "")
		)
		(fill
			(thermal_gap 0.5)
			(thermal_bridge_width 0.5)
			(island_removal_mode 0)
		)
		(polygon
			(pts
				(xy 68.985638 -21.426678) (xy 68.985638 -19.674586) (xy 68.654676 -19.343624) (xy 65.332356 -19.343624)
				(xy 65.051432 -19.0627) (xy 65.051432 -18.078704) (xy 65.33261 -17.797526) (xy 70.539102 -17.797526)
				(xy 71.451724 -18.710148) (xy 71.451724 -21.426678)
			)
		)
	)
	(zone
		(layer "F.Cu")
		(hatch none 0.5)
		(connect_pads
			(clearance 0)
		)
		(min_thickness 0.25)
		(keepout
			(tracks not_allowed)
			(vias allowed)
			(pads allowed)
			(copperpour not_allowed)
			(footprints allowed)
		)
		(placement
			(enabled no)
			(sheetname "")
		)
		(fill
			(thermal_gap 0.5)
			(thermal_bridge_width 0.5)
			(island_removal_mode 0)
		)
		(polygon
			(pts
				(arc
					(start 23.31593 -347.8149)
					(mid 20.216114 -350.914716)
					(end 17.116044 -347.8149)
				)
				(arc
					(start 17.116044 -347.8149)
					(mid 20.216114 -344.71483)
					(end 23.31593 -347.8149)
				)
			)
		)
	)
	(zone
		(layer "F.Cu")
		(hatch none 0.5)
		(connect_pads
			(clearance 0)
		)
		(min_thickness 0.25)
		(keepout
			(tracks allowed)
			(vias allowed)
			(pads allowed)
			(copperpour allowed)
			(footprints allowed)
		)
		(placement
			(enabled no)
			(sheetname "")
		)
		(fill
			(thermal_gap 0.5)
			(thermal_bridge_width 0.5)
			(island_removal_mode 0)
		)
		(polygon
			(pts
				(xy 58.13044 -233.62793) (xy 58.13044 -233.29773) (xy 60.67044 -233.29773) (xy 60.67044 -233.62793)
			)
		)
	)
	(zone
		(layer "F.Cu")
		(hatch none 0.5)
		(connect_pads
			(clearance 0)
		)
		(min_thickness 0.25)
		(keepout
			(tracks allowed)
			(vias allowed)
			(pads allowed)
			(copperpour allowed)
			(footprints allowed)
		)
		(placement
			(enabled no)
			(sheetname "")
		)
		(fill
			(thermal_gap 0.5)
			(thermal_bridge_width 0.5)
			(island_removal_mode 0)
		)
		(polygon
			(pts
				(xy 201.52106 -336.96402) (xy 201.52106 -342.20658) (xy 205.53426 -346.21978) (xy 205.53426 -347.9927)
				(xy 200.83272 -347.9927) (xy 200.1901 -347.35008) (xy 200.1901 -347.1799) (xy 200.1901 -336.96402)
			)
		)
	)
	(zone
		(layer "F.Cu")
		(hatch none 0.5)
		(connect_pads
			(clearance 0)
		)
		(min_thickness 0.25)
		(keepout
			(tracks allowed)
			(vias allowed)
			(pads allowed)
			(copperpour allowed)
			(footprints allowed)
		)
		(placement
			(enabled no)
			(sheetname "")
		)
		(fill
			(thermal_gap 0.5)
			(thermal_bridge_width 0.5)
			(island_removal_mode 0)
		)
		(polygon
			(pts
				(xy 346.39885 -417.424616) (xy 346.39885 -416.420554) (xy 347.795342 -416.420554) (xy 347.795342 -417.424616)
			)
		)
	)
	(zone
		(layer "F.Cu")
		(hatch none 0.5)
		(connect_pads
			(clearance 0)
		)
		(min_thickness 0.25)
		(keepout
			(tracks allowed)
			(vias allowed)
			(pads allowed)
			(copperpour allowed)
			(footprints allowed)
		)
		(placement
			(enabled no)
			(sheetname "")
		)
		(fill
			(thermal_gap 0.5)
			(thermal_bridge_width 0.5)
			(island_removal_mode 0)
		)
		(polygon
			(pts
				(xy 166.016432 -349.17634) (xy 166.016432 -349.70466) (xy 166.107618 -349.795846) (xy 166.107618 -350.575372)
				(xy 166.027862 -350.655128) (xy 165.829742 -350.655128) (xy 165.382448 -350.207834) (xy 165.382448 -350.091248)
				(xy 165.052248 -350.091248) (xy 164.339016 -350.091248) (xy 164.339016 -347.361256) (xy 165.156642 -347.361256)
				(xy 166.24173 -347.361256) (xy 166.24173 -349.17634)
			)
		)
	)
	(zone
		(layer "F.Cu")
		(hatch none 0.5)
		(connect_pads
			(clearance 0)
		)
		(min_thickness 0.25)
		(keepout
			(tracks allowed)
			(vias allowed)
			(pads allowed)
			(copperpour allowed)
			(footprints not_allowed)
		)
		(placement
			(enabled no)
			(sheetname "")
		)
		(fill
			(thermal_gap 0.5)
			(thermal_bridge_width 0.5)
			(island_removal_mode 0)
		)
		(polygon
			(pts
				(arc
					(start 271.450054 -21.850096)
					(mid 281.399996 -12.850027)
					(end 291.349938 -21.850096)
				)
			)
		)
	)
	(zone
		(layer "F.Cu")
		(hatch none 0.5)
		(connect_pads
			(clearance 0)
		)
		(min_thickness 0.25)
		(keepout
			(tracks not_allowed)
			(vias allowed)
			(pads allowed)
			(copperpour not_allowed)
			(footprints allowed)
		)
		(placement
			(enabled no)
			(sheetname "")
		)
		(fill
			(thermal_gap 0.5)
			(thermal_bridge_width 0.5)
			(island_removal_mode 0)
		)
		(polygon
			(pts
				(arc
					(start 469.799924 -22.29993)
					(mid 464.799934 -27.29992)
					(end 459.799944 -22.29993)
				)
				(arc
					(start 459.799944 -22.29993)
					(mid 464.799934 -17.29994)
					(end 469.799924 -22.29993)
				)
			)
		)
	)
	(zone
		(layer "F.Cu")
		(hatch none 0.5)
		(connect_pads
			(clearance 0)
		)
		(min_thickness 0.25)
		(keepout
			(tracks allowed)
			(vias allowed)
			(pads allowed)
			(copperpour allowed)
			(footprints not_allowed)
		)
		(placement
			(enabled no)
			(sheetname "")
		)
		(fill
			(thermal_gap 0.5)
			(thermal_bridge_width 0.5)
			(island_removal_mode 0)
		)
		(polygon
			(pts
				(arc
					(start 104.850946 -166.61511)
					(mid 106.716068 -164.749988)
					(end 108.580936 -166.61511)
				)
				(arc
					(start 108.580936 -166.61511)
					(mid 106.716068 -168.479978)
					(end 104.850946 -166.61511)
				)
			)
		)
	)
	(zone
		(layer "F.Cu")
		(hatch none 0.5)
		(connect_pads
			(clearance 0)
		)
		(min_thickness 0.25)
		(keepout
			(tracks allowed)
			(vias allowed)
			(pads allowed)
			(copperpour allowed)
			(footprints not_allowed)
		)
		(placement
			(enabled no)
			(sheetname "")
		)
		(fill
			(thermal_gap 0.5)
			(thermal_bridge_width 0.5)
			(island_removal_mode 0)
		)
		(polygon
			(pts
				(xy 337.050126 -67.540124) (xy 348.549976 -67.540124) (xy 348.549976 -56.459882) (xy 337.050126 -56.459882)
			)
		)
	)
	(zone
		(layer "F.Cu")
		(hatch none 0.5)
		(connect_pads
			(clearance 0)
		)
		(min_thickness 0.25)
		(keepout
			(tracks allowed)
			(vias allowed)
			(pads allowed)
			(copperpour allowed)
			(footprints allowed)
		)
		(placement
			(enabled no)
			(sheetname "")
		)
		(fill
			(thermal_gap 0.5)
			(thermal_bridge_width 0.5)
			(island_removal_mode 0)
		)
		(polygon
			(pts
				(xy 412.786322 -176.382426) (xy 412.786322 -178.287426) (xy 416.799522 -178.287426) (xy 416.799522 -176.382426)
			)
		)
	)
	(zone
		(layer "F.Cu")
		(hatch none 0.5)
		(connect_pads
			(clearance 0)
		)
		(min_thickness 0.25)
		(keepout
			(tracks allowed)
			(vias allowed)
			(pads allowed)
			(copperpour allowed)
			(footprints allowed)
		)
		(placement
			(enabled no)
			(sheetname "")
		)
		(fill
			(thermal_gap 0.5)
			(thermal_bridge_width 0.5)
			(island_removal_mode 0)
		)
		(polygon
			(pts
				(xy 148.30933 -409.042616) (xy 148.30933 -408.038554) (xy 149.705822 -408.038554) (xy 149.705822 -409.042616)
			)
		)
	)
	(zone
		(layer "F.Cu")
		(hatch none 0.5)
		(connect_pads
			(clearance 0)
		)
		(min_thickness 0.25)
		(keepout
			(tracks allowed)
			(vias allowed)
			(pads allowed)
			(copperpour allowed)
			(footprints not_allowed)
		)
		(placement
			(enabled no)
			(sheetname "")
		)
		(fill
			(thermal_gap 0.5)
			(thermal_bridge_width 0.5)
			(island_removal_mode 0)
		)
		(polygon
			(pts
				(arc
					(start 17.999964 -435.600094)
					(mid 12.999974 -440.600084)
					(end 7.999984 -435.600094)
				)
				(arc
					(start 7.999984 -435.600094)
					(mid 12.999974 -430.600104)
					(end 17.999964 -435.600094)
				)
			)
		)
	)
	(zone
		(layer "F.Cu")
		(hatch none 0.5)
		(connect_pads
			(clearance 0)
		)
		(min_thickness 0.25)
		(keepout
			(tracks allowed)
			(vias allowed)
			(pads allowed)
			(copperpour allowed)
			(footprints allowed)
		)
		(placement
			(enabled no)
			(sheetname "")
		)
		(fill
			(thermal_gap 0.5)
			(thermal_bridge_width 0.5)
			(island_removal_mode 0)
		)
		(polygon
			(pts
				(xy 411.317694 -305.542442) (xy 411.317694 -305.872642) (xy 413.236664 -305.872642) (xy 413.236664 -305.542442)
			)
		)
	)
	(zone
		(layer "F.Cu")
		(hatch none 0.5)
		(connect_pads
			(clearance 0)
		)
		(min_thickness 0.25)
		(keepout
			(tracks allowed)
			(vias allowed)
			(pads allowed)
			(copperpour allowed)
			(footprints allowed)
		)
		(placement
			(enabled no)
			(sheetname "")
		)
		(fill
			(thermal_gap 0.5)
			(thermal_bridge_width 0.5)
			(island_removal_mode 0)
		)
		(polygon
			(pts
				(xy 106.855006 -407.40965) (xy 106.121454 -407.40965) (xy 106.121454 -406.352756) (xy 106.855006 -406.352756)
			)
		)
	)
	(zone
		(layer "F.Cu")
		(hatch none 0.5)
		(connect_pads
			(clearance 0)
		)
		(min_thickness 0.25)
		(keepout
			(tracks not_allowed)
			(vias allowed)
			(pads allowed)
			(copperpour not_allowed)
			(footprints allowed)
		)
		(placement
			(enabled no)
			(sheetname "")
		)
		(fill
			(thermal_gap 0.5)
			(thermal_bridge_width 0.5)
			(island_removal_mode 0)
		)
		(polygon
			(pts
				(arc
					(start 424.749976 -413.170116)
					(mid 427.000162 -410.91993)
					(end 429.250094 -413.170116)
				)
				(arc
					(start 429.250094 -413.170116)
					(mid 427.000162 -415.420048)
					(end 424.749976 -413.170116)
				)
			)
		)
	)
	(zone
		(layer "F.Cu")
		(hatch none 0.5)
		(connect_pads
			(clearance 0)
		)
		(min_thickness 0.25)
		(keepout
			(tracks allowed)
			(vias allowed)
			(pads allowed)
			(copperpour allowed)
			(footprints allowed)
		)
		(placement
			(enabled no)
			(sheetname "")
		)
		(fill
			(thermal_gap 0.5)
			(thermal_bridge_width 0.5)
			(island_removal_mode 0)
		)
		(polygon
			(pts
				(xy 131.68376 -42.12336) (xy 131.68376 -40.0304) (xy 132.41782 -40.0304) (xy 132.41782 -42.12336)
			)
		)
	)
	(zone
		(layer "F.Cu")
		(hatch none 0.5)
		(connect_pads
			(clearance 0)
		)
		(min_thickness 0.25)
		(keepout
			(tracks allowed)
			(vias allowed)
			(pads allowed)
			(copperpour allowed)
			(footprints allowed)
		)
		(placement
			(enabled no)
			(sheetname "")
		)
		(fill
			(thermal_gap 0.5)
			(thermal_bridge_width 0.5)
			(island_removal_mode 0)
		)
		(polygon
			(pts
				(xy 88.876886 -373.561102) (xy 88.876886 -372.55704) (xy 90.273378 -372.55704) (xy 90.273378 -373.561102)
			)
		)
	)
	(zone
		(layer "F.Cu")
		(hatch none 0.5)
		(connect_pads
			(clearance 0)
		)
		(min_thickness 0.25)
		(keepout
			(tracks allowed)
			(vias allowed)
			(pads allowed)
			(copperpour allowed)
			(footprints allowed)
		)
		(placement
			(enabled no)
			(sheetname "")
		)
		(fill
			(thermal_gap 0.5)
			(thermal_bridge_width 0.5)
			(island_removal_mode 0)
		)
		(polygon
			(pts
				(xy 106.18089 -340.444582) (xy 104.37749 -340.444582) (xy 104.37749 -341.993982) (xy 106.18089 -341.993982)
			)
		)
	)
	(zone
		(layer "F.Cu")
		(hatch none 0.5)
		(connect_pads
			(clearance 0)
		)
		(min_thickness 0.25)
		(keepout
			(tracks allowed)
			(vias allowed)
			(pads allowed)
			(copperpour allowed)
			(footprints not_allowed)
		)
		(placement
			(enabled no)
			(sheetname "")
		)
		(fill
			(thermal_gap 0.5)
			(thermal_bridge_width 0.5)
			(island_removal_mode 0)
		)
		(polygon
			(pts
				(arc
					(start 248.035064 -290.900104)
					(mid 249.900186 -289.034982)
					(end 251.765054 -290.900104)
				)
				(arc
					(start 251.765054 -290.900104)
					(mid 249.900186 -292.764972)
					(end 248.035064 -290.900104)
				)
			)
		)
	)
	(zone
		(layer "F.Cu")
		(hatch none 0.5)
		(connect_pads
			(clearance 0)
		)
		(min_thickness 0.25)
		(keepout
			(tracks allowed)
			(vias allowed)
			(pads allowed)
			(copperpour allowed)
			(footprints allowed)
		)
		(placement
			(enabled no)
			(sheetname "")
		)
		(fill
			(thermal_gap 0.5)
			(thermal_bridge_width 0.5)
			(island_removal_mode 0)
		)
		(polygon
			(pts
				(xy 381.72263 -142.958312) (xy 381.72263 -142.387574) (xy 382.911604 -142.387574) (xy 382.911604 -142.958312)
			)
		)
	)
	(zone
		(layer "F.Cu")
		(hatch none 0.5)
		(connect_pads
			(clearance 0)
		)
		(min_thickness 0.25)
		(keepout
			(tracks allowed)
			(vias allowed)
			(pads allowed)
			(copperpour allowed)
			(footprints allowed)
		)
		(placement
			(enabled no)
			(sheetname "")
		)
		(fill
			(thermal_gap 0.5)
			(thermal_bridge_width 0.5)
			(island_removal_mode 0)
		)
		(polygon
			(pts
				(xy 411.317694 -271.878044) (xy 411.317694 -271.547844) (xy 413.236664 -271.547844) (xy 413.236664 -271.878044)
			)
		)
	)
	(zone
		(layer "F.Cu")
		(hatch none 0.5)
		(connect_pads
			(clearance 0)
		)
		(min_thickness 0.25)
		(keepout
			(tracks allowed)
			(vias allowed)
			(pads allowed)
			(copperpour allowed)
			(footprints allowed)
		)
		(placement
			(enabled no)
			(sheetname "")
		)
		(fill
			(thermal_gap 0.5)
			(thermal_bridge_width 0.5)
			(island_removal_mode 0)
		)
		(polygon
			(pts
				(xy 58.13044 -242.12804) (xy 58.13044 -241.79784) (xy 60.67044 -241.79784) (xy 60.67044 -242.12804)
			)
		)
	)
	(zone
		(layer "F.Cu")
		(hatch none 0.5)
		(connect_pads
			(clearance 0)
		)
		(min_thickness 0.25)
		(keepout
			(tracks allowed)
			(vias allowed)
			(pads allowed)
			(copperpour allowed)
			(footprints allowed)
		)
		(placement
			(enabled no)
			(sheetname "")
		)
		(fill
			(thermal_gap 0.5)
			(thermal_bridge_width 0.5)
			(island_removal_mode 0)
		)
		(polygon
			(pts
				(xy 306.070508 -224.277682) (xy 306.070508 -223.947482) (xy 308.610508 -223.947482) (xy 308.610508 -224.277682)
			)
		)
	)
	(zone
		(layer "F.Cu")
		(hatch none 0.5)
		(connect_pads
			(clearance 0)
		)
		(min_thickness 0.25)
		(keepout
			(tracks allowed)
			(vias allowed)
			(pads allowed)
			(copperpour allowed)
			(footprints not_allowed)
		)
		(placement
			(enabled no)
			(sheetname "")
		)
		(fill
			(thermal_gap 0.5)
			(thermal_bridge_width 0.5)
			(island_removal_mode 0)
		)
		(polygon
			(pts
				(xy 197.875906 -357.145082) (xy 203.120244 -357.145082) (xy 205.705964 -354.555044) (xy 205.705964 -347.544898)
				(xy 197.875906 -347.544898)
			)
		)
	)
	(zone
		(layer "F.Cu")
		(hatch none 0.5)
		(connect_pads
			(clearance 0)
		)
		(min_thickness 0.25)
		(keepout
			(tracks allowed)
			(vias allowed)
			(pads allowed)
			(copperpour allowed)
			(footprints allowed)
		)
		(placement
			(enabled no)
			(sheetname "")
		)
		(fill
			(thermal_gap 0.5)
			(thermal_bridge_width 0.5)
			(island_removal_mode 0)
		)
		(polygon
			(pts
				(xy 76.875894 -320.458846) (xy 76.875894 -322.363846) (xy 80.889094 -322.363846) (xy 80.889094 -320.458846)
			)
		)
	)
	(zone
		(layer "F.Cu")
		(hatch none 0.5)
		(connect_pads
			(clearance 0)
		)
		(min_thickness 0.25)
		(keepout
			(tracks allowed)
			(vias allowed)
			(pads allowed)
			(copperpour allowed)
			(footprints allowed)
		)
		(placement
			(enabled no)
			(sheetname "")
		)
		(fill
			(thermal_gap 0.5)
			(thermal_bridge_width 0.5)
			(island_removal_mode 0)
		)
		(polygon
			(pts
				(xy 411.317694 -301.628048) (xy 411.317694 -301.297848) (xy 413.236664 -301.297848) (xy 413.236664 -301.628048)
			)
		)
	)
	(zone
		(layer "F.Cu")
		(hatch none 0.5)
		(connect_pads
			(clearance 0)
		)
		(min_thickness 0.25)
		(keepout
			(tracks allowed)
			(vias allowed)
			(pads allowed)
			(copperpour allowed)
			(footprints allowed)
		)
		(placement
			(enabled no)
			(sheetname "")
		)
		(fill
			(thermal_gap 0.5)
			(thermal_bridge_width 0.5)
			(island_removal_mode 0)
		)
		(polygon
			(pts
				(xy 163.377626 -251.478034) (xy 163.377626 -251.147834) (xy 165.296596 -251.147834) (xy 165.296596 -251.478034)
			)
		)
	)
	(zone
		(layer "F.Cu")
		(hatch none 0.5)
		(connect_pads
			(clearance 0)
		)
		(min_thickness 0.25)
		(keepout
			(tracks allowed)
			(vias allowed)
			(pads allowed)
			(copperpour allowed)
			(footprints allowed)
		)
		(placement
			(enabled no)
			(sheetname "")
		)
		(fill
			(thermal_gap 0.5)
			(thermal_bridge_width 0.5)
			(island_removal_mode 0)
		)
		(polygon
			(pts
				(xy 163.377626 -247.228106) (xy 163.377626 -246.897906) (xy 165.296596 -246.897906) (xy 165.296596 -247.228106)
			)
		)
	)
	(zone
		(layer "F.Cu")
		(hatch none 0.5)
		(connect_pads
			(clearance 0)
		)
		(min_thickness 0.25)
		(keepout
			(tracks not_allowed)
			(vias allowed)
			(pads allowed)
			(copperpour not_allowed)
			(footprints allowed)
		)
		(placement
			(enabled no)
			(sheetname "")
		)
		(fill
			(thermal_gap 0.5)
			(thermal_bridge_width 0.5)
			(island_removal_mode 0)
		)
		(polygon
			(pts
				(xy 36.933124 -347.0148) (xy 36.933124 -349.024956) (xy 35.078924 -349.024956) (xy 35.078924 -348.78391)
				(xy 34.836608 -348.78391) (xy 34.836608 -349.265494) (xy 38.675564 -349.265494) (xy 38.675564 -349.080582)
				(xy 37.224462 -349.080582) (xy 37.224462 -346.921582) (xy 39.381176 -346.921582) (xy 39.381176 -346.6719)
				(xy 37.276024 -346.6719)
			)
		)
	)
	(zone
		(layer "F.Cu")
		(hatch none 0.5)
		(connect_pads
			(clearance 0)
		)
		(min_thickness 0.25)
		(keepout
			(tracks not_allowed)
			(vias allowed)
			(pads allowed)
			(copperpour not_allowed)
			(footprints allowed)
		)
		(placement
			(enabled no)
			(sheetname "")
		)
		(fill
			(thermal_gap 0.5)
			(thermal_bridge_width 0.5)
			(island_removal_mode 0)
		)
		(polygon
			(pts
				(xy 437.608218 -9.094724) (xy 437.725566 -9.094724) (xy 437.776366 -9.043924) (xy 437.776366 -7.596124)
				(xy 437.725566 -7.545324) (xy 437.608218 -7.545324) (xy 437.557418 -7.596124) (xy 437.557418 -9.043924)
			)
		)
	)
	(zone
		(layer "F.Cu")
		(hatch none 0.5)
		(connect_pads
			(clearance 0)
		)
		(min_thickness 0.25)
		(keepout
			(tracks allowed)
			(vias allowed)
			(pads allowed)
			(copperpour allowed)
			(footprints allowed)
		)
		(placement
			(enabled no)
			(sheetname "")
		)
		(fill
			(thermal_gap 0.5)
			(thermal_bridge_width 0.5)
			(island_removal_mode 0)
		)
		(polygon
			(pts
				(xy 411.574996 -303.327816) (xy 411.574996 -302.997616) (xy 413.236664 -302.997616) (xy 413.236664 -303.327816)
			)
		)
	)
	(zone
		(layer "F.Cu")
		(hatch none 0.5)
		(connect_pads
			(clearance 0)
		)
		(min_thickness 0.25)
		(keepout
			(tracks allowed)
			(vias allowed)
			(pads allowed)
			(copperpour allowed)
			(footprints not_allowed)
		)
		(placement
			(enabled no)
			(sheetname "")
		)
		(fill
			(thermal_gap 0.5)
			(thermal_bridge_width 0.5)
			(island_removal_mode 0)
		)
		(polygon
			(pts
				(arc
					(start 4.19989 -22.29993)
					(mid 6.999986 -19.499834)
					(end 9.800082 -22.29993)
				)
				(arc
					(start 9.800082 -22.29993)
					(mid 6.999986 -25.100026)
					(end 4.19989 -22.29993)
				)
			)
		)
	)
	(zone
		(layer "F.Cu")
		(hatch none 0.5)
		(connect_pads
			(clearance 0)
		)
		(min_thickness 0.25)
		(keepout
			(tracks allowed)
			(vias allowed)
			(pads allowed)
			(copperpour allowed)
			(footprints allowed)
		)
		(placement
			(enabled no)
			(sheetname "")
		)
		(fill
			(thermal_gap 0.5)
			(thermal_bridge_width 0.5)
			(island_removal_mode 0)
		)
		(polygon
			(pts
				(xy 163.377626 -277.492714) (xy 163.377626 -277.822914) (xy 165.296596 -277.822914) (xy 165.296596 -277.492714)
			)
		)
	)
	(zone
		(layer "F.Cu")
		(hatch none 0.5)
		(connect_pads
			(clearance 0)
		)
		(min_thickness 0.25)
		(keepout
			(tracks allowed)
			(vias allowed)
			(pads allowed)
			(copperpour allowed)
			(footprints allowed)
		)
		(placement
			(enabled no)
			(sheetname "")
		)
		(fill
			(thermal_gap 0.5)
			(thermal_bridge_width 0.5)
			(island_removal_mode 0)
		)
		(polygon
			(pts
				(xy 354.050854 -340.655148) (xy 352.247454 -340.655148) (xy 352.247454 -342.204548) (xy 354.050854 -342.204548)
			)
		)
	)
	(zone
		(layer "F.Cu")
		(hatch none 0.5)
		(connect_pads
			(clearance 0)
		)
		(min_thickness 0.25)
		(keepout
			(tracks allowed)
			(vias allowed)
			(pads allowed)
			(copperpour allowed)
			(footprints not_allowed)
		)
		(placement
			(enabled no)
			(sheetname "")
		)
		(fill
			(thermal_gap 0.5)
			(thermal_bridge_width 0.5)
			(island_removal_mode 0)
		)
		(polygon
			(pts
				(arc
					(start 171.220892 -351.825052)
					(mid 173.086014 -349.95993)
					(end 174.950882 -351.825052)
				)
				(arc
					(start 174.950882 -351.825052)
					(mid 173.086014 -353.68992)
					(end 171.220892 -351.825052)
				)
			)
		)
	)
	(zone
		(layer "F.Cu")
		(hatch none 0.5)
		(connect_pads
			(clearance 0)
		)
		(min_thickness 0.25)
		(keepout
			(tracks allowed)
			(vias allowed)
			(pads allowed)
			(copperpour allowed)
			(footprints allowed)
		)
		(placement
			(enabled no)
			(sheetname "")
		)
		(fill
			(thermal_gap 0.5)
			(thermal_bridge_width 0.5)
			(island_removal_mode 0)
		)
		(polygon
			(pts
				(xy 378.07646 -5.75564) (xy 378.07646 -3.80746) (xy 380.3015 -3.80746) (xy 380.3015 -5.75564)
			)
		)
	)
	(zone
		(layer "F.Cu")
		(hatch none 0.5)
		(connect_pads
			(clearance 0)
		)
		(min_thickness 0.25)
		(keepout
			(tracks allowed)
			(vias allowed)
			(pads allowed)
			(copperpour allowed)
			(footprints not_allowed)
		)
		(placement
			(enabled no)
			(sheetname "")
		)
		(fill
			(thermal_gap 0.5)
			(thermal_bridge_width 0.5)
			(island_removal_mode 0)
		)
		(polygon
			(pts
				(arc
					(start 295.070022 -384.869944)
					(mid 291.07003 -388.869936)
					(end 287.070038 -384.869944)
				)
				(arc
					(start 287.070038 -384.869944)
					(mid 291.07003 -380.869952)
					(end 295.070022 -384.869944)
				)
			)
		)
	)
	(zone
		(layer "F.Cu")
		(hatch none 0.5)
		(connect_pads
			(clearance 0)
		)
		(min_thickness 0.25)
		(keepout
			(tracks allowed)
			(vias allowed)
			(pads allowed)
			(copperpour allowed)
			(footprints not_allowed)
		)
		(placement
			(enabled no)
			(sheetname "")
		)
		(fill
			(thermal_gap 0.5)
			(thermal_bridge_width 0.5)
			(island_removal_mode 0)
		)
		(polygon
			(pts
				(arc
					(start 295.8719 -24.050244)
					(mid 304.871969 -34.000173)
					(end 295.8719 -43.949874)
				)
			)
		)
	)
	(zone
		(layer "F.Cu")
		(hatch none 0.5)
		(connect_pads
			(clearance 0)
		)
		(min_thickness 0.25)
		(keepout
			(tracks not_allowed)
			(vias allowed)
			(pads allowed)
			(copperpour not_allowed)
			(footprints allowed)
		)
		(placement
			(enabled no)
			(sheetname "")
		)
		(fill
			(thermal_gap 0.5)
			(thermal_bridge_width 0.5)
			(island_removal_mode 0)
		)
		(polygon
			(pts
				(arc
					(start 204.186028 -351.825052)
					(mid 201.085958 -354.925122)
					(end 197.985888 -351.825052)
				)
				(arc
					(start 197.985888 -351.825052)
					(mid 201.085958 -348.724982)
					(end 204.186028 -351.825052)
				)
			)
		)
	)
	(zone
		(layer "F.Cu")
		(hatch none 0.5)
		(connect_pads
			(clearance 0)
		)
		(min_thickness 0.25)
		(keepout
			(tracks allowed)
			(vias allowed)
			(pads allowed)
			(copperpour allowed)
			(footprints not_allowed)
		)
		(placement
			(enabled no)
			(sheetname "")
		)
		(fill
			(thermal_gap 0.5)
			(thermal_bridge_width 0.5)
			(island_removal_mode 0)
		)
		(polygon
			(pts
				(xy 108.915962 -344.914982) (xy 108.915962 -336.12455) (xy 100.215954 -336.12455) (xy 100.215954 -331.185012)
				(xy 65.715896 -331.185012) (xy 65.715896 -342.914986) (xy 23.896066 -342.914986) (xy 23.896066 -350.665034)
				(xy 22.406356 -350.665034) (xy 22.406356 -351.605088) (xy 66.216022 -351.605088) (xy 66.216022 -347.646498)
				(xy 66.805556 -347.646498) (xy 66.805556 -345.876626) (xy 66.216022 -345.876626) (xy 66.216022 -341.514938)
				(xy 74.331068 -341.514938) (xy 74.331068 -341.23503) (xy 94.070932 -341.23503) (xy 97.865946 -344.914982)
			)
		)
	)
	(zone
		(layer "F.Cu")
		(hatch none 0.5)
		(connect_pads
			(clearance 0)
		)
		(min_thickness 0.25)
		(keepout
			(tracks not_allowed)
			(vias allowed)
			(pads allowed)
			(copperpour not_allowed)
			(footprints allowed)
		)
		(placement
			(enabled no)
			(sheetname "")
		)
		(fill
			(thermal_gap 0.5)
			(thermal_bridge_width 0.5)
			(island_removal_mode 0)
		)
		(polygon
			(pts
				(xy 63.825628 -10.49528) (xy 63.70828 -10.49528) (xy 63.65748 -10.54608) (xy 63.65748 -11.99388)
				(xy 63.70828 -12.04468) (xy 63.825628 -12.04468) (xy 63.876428 -11.99388) (xy 63.876428 -10.54608)
			)
		)
	)
	(zone
		(layer "F.Cu")
		(hatch none 0.5)
		(connect_pads
			(clearance 0)
		)
		(min_thickness 0.25)
		(keepout
			(tracks not_allowed)
			(vias allowed)
			(pads allowed)
			(copperpour not_allowed)
			(footprints allowed)
		)
		(placement
			(enabled no)
			(sheetname "")
		)
		(fill
			(thermal_gap 0.5)
			(thermal_bridge_width 0.5)
			(island_removal_mode 0)
		)
		(polygon
			(pts
				(xy 180.875432 -351.995486) (xy 180.875432 -352.956368) (xy 181.117748 -352.956368) (xy 181.117748 -351.995486)
			)
		)
	)
	(zone
		(layer "F.Cu")
		(hatch none 0.5)
		(connect_pads
			(clearance 0)
		)
		(min_thickness 0.25)
		(keepout
			(tracks allowed)
			(vias allowed)
			(pads allowed)
			(copperpour allowed)
			(footprints allowed)
		)
		(placement
			(enabled no)
			(sheetname "")
		)
		(fill
			(thermal_gap 0.5)
			(thermal_bridge_width 0.5)
			(island_removal_mode 0)
		)
		(polygon
			(pts
				(xy 60.725812 -280.04262) (xy 60.725812 -280.37282) (xy 58.185812 -280.37282) (xy 58.185812 -280.04262)
			)
		)
	)
	(zone
		(layer "F.Cu")
		(hatch none 0.5)
		(connect_pads
			(clearance 0)
		)
		(min_thickness 0.25)
		(keepout
			(tracks allowed)
			(vias allowed)
			(pads allowed)
			(copperpour allowed)
			(footprints not_allowed)
		)
		(placement
			(enabled no)
			(sheetname "")
		)
		(fill
			(thermal_gap 0.5)
			(thermal_bridge_width 0.5)
			(island_removal_mode 0)
		)
		(polygon
			(pts
				(xy 315.149992 -67.540124) (xy 326.650096 -67.540124) (xy 326.650096 -56.459882) (xy 315.149992 -56.459882)
			)
		)
	)
	(zone
		(layer "F.Cu")
		(hatch none 0.5)
		(connect_pads
			(clearance 0)
		)
		(min_thickness 0.25)
		(keepout
			(tracks allowed)
			(vias allowed)
			(pads allowed)
			(copperpour allowed)
			(footprints allowed)
		)
		(placement
			(enabled no)
			(sheetname "")
		)
		(fill
			(thermal_gap 0.5)
			(thermal_bridge_width 0.5)
			(island_removal_mode 0)
		)
		(polygon
			(pts
				(xy 332.014068 -141.46403) (xy 332.014068 -140.73251) (xy 334.63611 -140.73251) (xy 334.63611 -143.168116)
				(xy 334.63611 -144.387062) (xy 334.02778 -144.995392) (xy 331.331824 -144.995392) (xy 331.191362 -144.85493)
				(xy 331.191362 -142.286736)
			)
		)
	)
	(zone
		(layer "F.Cu")
		(hatch none 0.5)
		(connect_pads
			(clearance 0)
		)
		(min_thickness 0.25)
		(keepout
			(tracks allowed)
			(vias allowed)
			(pads allowed)
			(copperpour allowed)
			(footprints not_allowed)
		)
		(placement
			(enabled no)
			(sheetname "")
		)
		(fill
			(thermal_gap 0.5)
			(thermal_bridge_width 0.5)
			(island_removal_mode 0)
		)
		(polygon
			(pts
				(xy 452.44004 -44.790106) (xy 452.44004 -35.919918) (xy 442.44006 -35.919918) (xy 442.44006 -44.790106)
				(xy 443.93993 -44.790106) (xy 443.93993 -54.28996) (xy 463.289904 -54.28996) (xy 463.289904 -56.289956)
				(xy 470.590118 -56.289956) (xy 470.590118 -46.289976) (xy 463.289904 -46.289976) (xy 463.289904 -47.289974)
				(xy 450.939916 -47.289974) (xy 450.939916 -44.790106)
			)
		)
	)
	(zone
		(layer "F.Cu")
		(hatch none 0.5)
		(connect_pads
			(clearance 0)
		)
		(min_thickness 0.25)
		(keepout
			(tracks allowed)
			(vias allowed)
			(pads allowed)
			(copperpour allowed)
			(footprints allowed)
		)
		(placement
			(enabled no)
			(sheetname "")
		)
		(fill
			(thermal_gap 0.5)
			(thermal_bridge_width 0.5)
			(island_removal_mode 0)
		)
		(polygon
			(pts
				(xy 129.92989 -409.042616) (xy 129.92989 -408.038554) (xy 131.326382 -408.038554) (xy 131.326382 -409.042616)
			)
		)
	)
	(zone
		(layer "F.Cu")
		(hatch none 0.5)
		(connect_pads
			(clearance 0)
		)
		(min_thickness 0.25)
		(keepout
			(tracks allowed)
			(vias allowed)
			(pads allowed)
			(copperpour allowed)
			(footprints allowed)
		)
		(placement
			(enabled no)
			(sheetname "")
		)
		(fill
			(thermal_gap 0.5)
			(thermal_bridge_width 0.5)
			(island_removal_mode 0)
		)
		(polygon
			(pts
				(xy 44.436538 -371.097302) (xy 44.436538 -370.09324) (xy 45.83303 -370.09324) (xy 45.83303 -371.097302)
			)
		)
	)
	(zone
		(layer "F.Cu")
		(hatch none 0.5)
		(connect_pads
			(clearance 0)
		)
		(min_thickness 0.25)
		(keepout
			(tracks allowed)
			(vias allowed)
			(pads allowed)
			(copperpour allowed)
			(footprints allowed)
		)
		(placement
			(enabled no)
			(sheetname "")
		)
		(fill
			(thermal_gap 0.5)
			(thermal_bridge_width 0.5)
			(island_removal_mode 0)
		)
		(polygon
			(pts
				(xy 183.666638 -13.814806) (xy 183.666638 -12.735306) (xy 184.607454 -12.735306) (xy 184.607454 -13.814806)
			)
		)
	)
	(zone
		(layer "F.Cu")
		(hatch none 0.5)
		(connect_pads
			(clearance 0)
		)
		(min_thickness 0.25)
		(keepout
			(tracks allowed)
			(vias allowed)
			(pads allowed)
			(copperpour allowed)
			(footprints not_allowed)
		)
		(placement
			(enabled no)
			(sheetname "")
		)
		(fill
			(thermal_gap 0.5)
			(thermal_bridge_width 0.5)
			(island_removal_mode 0)
		)
		(polygon
			(pts
				(xy 61.62802 -182.060088) (xy 61.62802 -172.315124) (xy 48.896778 -172.315124) (xy 48.896778 -165.596062)
				(arc
					(start 16.506952 -165.596062)
					(mid 14.484636 -167.342594)
					(end 11.999976 -168.3258)
				)
				(xy 11.999976 -182.060088)
			)
		)
	)
	(zone
		(layer "F.Cu")
		(hatch none 0.5)
		(connect_pads
			(clearance 0)
		)
		(min_thickness 0.25)
		(keepout
			(tracks not_allowed)
			(vias allowed)
			(pads allowed)
			(copperpour not_allowed)
			(footprints allowed)
		)
		(placement
			(enabled no)
			(sheetname "")
		)
		(fill
			(thermal_gap 0.5)
			(thermal_bridge_width 0.5)
			(island_removal_mode 0)
		)
		(polygon
			(pts
				(arc
					(start 201.900028 -51.999896)
					(mid 204.650086 -49.249838)
					(end 207.39989 -51.999896)
				)
				(arc
					(start 207.39989 -51.999896)
					(mid 204.650086 -54.7497)
					(end 201.900028 -51.999896)
				)
			)
		)
	)
	(zone
		(layer "F.Cu")
		(hatch none 0.5)
		(connect_pads
			(clearance 0)
		)
		(min_thickness 0.25)
		(keepout
			(tracks allowed)
			(vias allowed)
			(pads allowed)
			(copperpour allowed)
			(footprints not_allowed)
		)
		(placement
			(enabled no)
			(sheetname "")
		)
		(fill
			(thermal_gap 0.5)
			(thermal_bridge_width 0.5)
			(island_removal_mode 0)
		)
		(polygon
			(pts
				(arc
					(start 10.199878 -435.600094)
					(mid 12.999974 -432.799998)
					(end 15.80007 -435.600094)
				)
				(arc
					(start 15.80007 -435.600094)
					(mid 12.999974 -438.40019)
					(end 10.199878 -435.600094)
				)
			)
		)
	)
	(zone
		(layer "F.Cu")
		(hatch none 0.5)
		(connect_pads
			(clearance 0)
		)
		(min_thickness 0.25)
		(keepout
			(tracks allowed)
			(vias allowed)
			(pads allowed)
			(copperpour allowed)
			(footprints allowed)
		)
		(placement
			(enabled no)
			(sheetname "")
		)
		(fill
			(thermal_gap 0.5)
			(thermal_bridge_width 0.5)
			(island_removal_mode 0)
		)
		(polygon
			(pts
				(xy 388.76097 -180.68925) (xy 386.95757 -180.68925) (xy 386.95757 -182.23865) (xy 388.76097 -182.23865)
			)
		)
	)
	(zone
		(layer "F.Cu")
		(hatch none 0.5)
		(connect_pads
			(clearance 0)
		)
		(min_thickness 0.25)
		(keepout
			(tracks allowed)
			(vias allowed)
			(pads allowed)
			(copperpour allowed)
			(footprints allowed)
		)
		(placement
			(enabled no)
			(sheetname "")
		)
		(fill
			(thermal_gap 0.5)
			(thermal_bridge_width 0.5)
			(island_removal_mode 0)
		)
		(polygon
			(pts
				(xy 331.08265 -417.424616) (xy 331.08265 -416.420554) (xy 332.479142 -416.420554) (xy 332.479142 -417.424616)
			)
		)
	)
	(zone
		(layer "F.Cu")
		(hatch none 0.5)
		(connect_pads
			(clearance 0)
		)
		(min_thickness 0.25)
		(keepout
			(tracks allowed)
			(vias allowed)
			(pads allowed)
			(copperpour allowed)
			(footprints allowed)
		)
		(placement
			(enabled no)
			(sheetname "")
		)
		(fill
			(thermal_gap 0.5)
			(thermal_bridge_width 0.5)
			(island_removal_mode 0)
		)
		(polygon
			(pts
				(xy 306.070508 -217.477848) (xy 306.070508 -217.147648) (xy 308.610508 -217.147648) (xy 308.610508 -217.477848)
			)
		)
	)
	(zone
		(layer "F.Cu")
		(hatch none 0.5)
		(connect_pads
			(clearance 0)
		)
		(min_thickness 0.25)
		(keepout
			(tracks allowed)
			(vias allowed)
			(pads allowed)
			(copperpour allowed)
			(footprints not_allowed)
		)
		(placement
			(enabled no)
			(sheetname "")
		)
		(fill
			(thermal_gap 0.5)
			(thermal_bridge_width 0.5)
			(island_removal_mode 0)
		)
		(polygon
			(pts
				(xy 313.16803 -319.030096) (xy 359.817924 -319.030096) (xy 359.817924 -262.880094) (xy 352.817938 -262.880094)
				(xy 352.817938 -254.88011) (xy 366.917986 -254.88011) (xy 366.917986 -262.880094) (xy 359.918 -262.880094)
				(xy 359.918 -319.030096) (xy 406.567894 -319.030096) (xy 406.567894 -198.579994) (xy 313.16803 -198.579994)
			)
		)
	)
	(zone
		(layer "F.Cu")
		(hatch none 0.5)
		(connect_pads
			(clearance 0)
		)
		(min_thickness 0.25)
		(keepout
			(tracks allowed)
			(vias allowed)
			(pads allowed)
			(copperpour allowed)
			(footprints allowed)
		)
		(placement
			(enabled no)
			(sheetname "")
		)
		(fill
			(thermal_gap 0.5)
			(thermal_bridge_width 0.5)
			(island_removal_mode 0)
		)
		(polygon
			(pts
				(xy 227.64496 -293.764716) (xy 229.206298 -293.764716) (xy 229.771448 -293.199566) (xy 230.07828 -293.199566)
				(xy 230.210106 -293.06774) (xy 230.210106 -290.155122) (xy 229.98303 -289.928046) (xy 229.653338 -289.598354)
				(xy 228.405436 -289.598354) (xy 225.853498 -289.598354) (xy 225.667824 -289.784028) (xy 225.667824 -290.105592)
				(xy 226.10699 -290.544758) (xy 227.471986 -290.544758) (xy 227.471986 -293.591742)
			)
		)
	)
	(zone
		(layer "F.Cu")
		(hatch none 0.5)
		(connect_pads
			(clearance 0)
		)
		(min_thickness 0.25)
		(keepout
			(tracks allowed)
			(vias allowed)
			(pads allowed)
			(copperpour allowed)
			(footprints allowed)
		)
		(placement
			(enabled no)
			(sheetname "")
		)
		(fill
			(thermal_gap 0.5)
			(thermal_bridge_width 0.5)
			(island_removal_mode 0)
		)
		(polygon
			(pts
				(xy 106.33964 -129.20472) (xy 106.33964 -127.8001) (xy 106.97464 -127.8001) (xy 106.97464 -129.20472)
			)
		)
	)
	(zone
		(layer "F.Cu")
		(hatch none 0.5)
		(connect_pads
			(clearance 0)
		)
		(min_thickness 0.25)
		(keepout
			(tracks not_allowed)
			(vias allowed)
			(pads allowed)
			(copperpour not_allowed)
			(footprints allowed)
		)
		(placement
			(enabled no)
			(sheetname "")
		)
		(fill
			(thermal_gap 0.5)
			(thermal_bridge_width 0.5)
			(island_removal_mode 0)
		)
		(polygon
			(pts
				(arc
					(start 233.849926 -272.50009)
					(mid 236.650022 -269.699994)
					(end 239.450118 -272.50009)
				)
				(arc
					(start 239.450118 -272.50009)
					(mid 236.650022 -275.300186)
					(end 233.849926 -272.50009)
				)
			)
		)
	)
	(zone
		(layer "F.Cu")
		(hatch none 0.5)
		(connect_pads
			(clearance 0)
		)
		(min_thickness 0.25)
		(keepout
			(tracks allowed)
			(vias allowed)
			(pads allowed)
			(copperpour allowed)
			(footprints not_allowed)
		)
		(placement
			(enabled no)
			(sheetname "")
		)
		(fill
			(thermal_gap 0.5)
			(thermal_bridge_width 0.5)
			(island_removal_mode 0)
		)
		(polygon
			(pts
				(arc
					(start 259.80009 -16.842994)
					(mid 266.512848 -14.346653)
					(end 272.534126 -18.2245)
				)
				(arc
					(start 272.534126 -18.2245)
					(mid 283.292088 -13.030738)
					(end 291.349938 -21.850096)
				)
				(xy 295.8719 -21.850096)
				(arc
					(start 295.8719 -24.050244)
					(mid 303.187241 -28.444991)
					(end 304.446686 -36.885372)
				)
				(arc
					(start 304.446686 -36.885372)
					(mid 311.263245 -40.760198)
					(end 315.193426 -47.54499)
				)
				(arc
					(start 315.193426 -47.54499)
					(mid 317.178275 -47.136846)
					(end 319.200022 -46.999906)
				)
				(xy 319.200022 -56.459882) (xy 322.600066 -56.459882)
				(arc
					(start 322.600066 -46.999906)
					(mid 327.492604 -47.820324)
					(end 331.849984 -50.19167)
				)
				(xy 331.95006 -50.113946) (xy 331.95006 -30.48)
				(arc
					(start 353.506786 -30.48)
					(mid 352.26178 -27.294628)
					(end 351.770696 -23.910036)
				)
				(xy 358.513888 -23.910036) (xy 358.513888 -19.206464)
				(arc
					(start 351.77222 -19.206464)
					(mid 352.25476 -15.900626)
					(end 353.457002 -12.783566)
				)
				(arc
					(start 328.972164 -12.757404)
					(mid 329.006483 -13.198319)
					(end 329.02779 -13.640054)
				)
				(xy 322.286122 -13.640054) (xy 322.286122 -18.352008)
				(arc
					(start 329.026266 -18.352008)
					(mid 314.037467 -32.77604)
					(end 299.048424 -18.352008)
				)
				(xy 306.286154 -18.352008) (xy 306.286154 -13.640054)
				(arc
					(start 299.04436 -13.640054)
					(mid 299.064981 -13.209774)
					(end 299.097954 -12.780264)
				)
				(arc
					(start 260.800088 -12.78001)
					(mid 260.092983 -13.072903)
					(end 259.80009 -13.780008)
				)
			)
		)
	)
	(zone
		(layer "F.Cu")
		(hatch none 0.5)
		(connect_pads
			(clearance 0)
		)
		(min_thickness 0.25)
		(keepout
			(tracks allowed)
			(vias allowed)
			(pads allowed)
			(copperpour allowed)
			(footprints allowed)
		)
		(placement
			(enabled no)
			(sheetname "")
		)
		(fill
			(thermal_gap 0.5)
			(thermal_bridge_width 0.5)
			(island_removal_mode 0)
		)
		(polygon
			(pts
				(xy 308.66588 -302.142398) (xy 308.66588 -302.472598) (xy 306.12588 -302.472598) (xy 306.12588 -302.142398)
			)
		)
	)
	(zone
		(layer "F.Cu")
		(hatch none 0.5)
		(connect_pads
			(clearance 0)
		)
		(min_thickness 0.25)
		(keepout
			(tracks allowed)
			(vias allowed)
			(pads allowed)
			(copperpour allowed)
			(footprints allowed)
		)
		(placement
			(enabled no)
			(sheetname "")
		)
		(fill
			(thermal_gap 0.5)
			(thermal_bridge_width 0.5)
			(island_removal_mode 0)
		)
		(polygon
			(pts
				(xy 142.18285 -409.042616) (xy 142.18285 -408.038554) (xy 143.579342 -408.038554) (xy 143.579342 -409.042616)
			)
		)
	)
	(zone
		(layer "F.Cu")
		(hatch none 0.5)
		(connect_pads
			(clearance 0)
		)
		(min_thickness 0.25)
		(keepout
			(tracks allowed)
			(vias allowed)
			(pads allowed)
			(copperpour allowed)
			(footprints not_allowed)
		)
		(placement
			(enabled no)
			(sheetname "")
		)
		(fill
			(thermal_gap 0.5)
			(thermal_bridge_width 0.5)
			(island_removal_mode 0)
		)
		(polygon
			(pts
				(arc
					(start 262.850122 -22.29993)
					(mid 265.650218 -19.499834)
					(end 268.45006 -22.29993)
				)
				(arc
					(start 268.45006 -22.29993)
					(mid 265.650218 -25.099772)
					(end 262.850122 -22.29993)
				)
			)
		)
	)
	(zone
		(layer "F.Cu")
		(hatch none 0.5)
		(connect_pads
			(clearance 0)
		)
		(min_thickness 0.25)
		(keepout
			(tracks allowed)
			(vias allowed)
			(pads allowed)
			(copperpour allowed)
			(footprints allowed)
		)
		(placement
			(enabled no)
			(sheetname "")
		)
		(fill
			(thermal_gap 0.5)
			(thermal_bridge_width 0.5)
			(island_removal_mode 0)
		)
		(polygon
			(pts
				(xy 35.392868 -368.197892) (xy 39.661084 -368.197892) (xy 39.927784 -367.931192) (xy 39.927784 -366.283748)
				(xy 39.111428 -365.467392) (xy 36.899088 -365.467392) (xy 36.114736 -364.68304) (xy 36.114736 -362.329222)
				(xy 35.753802 -361.968288) (xy 33.933638 -361.968288) (xy 33.149032 -362.752894) (xy 33.149032 -365.954056)
			)
		)
	)
	(zone
		(layer "F.Cu")
		(hatch none 0.5)
		(connect_pads
			(clearance 0)
		)
		(min_thickness 0.25)
		(keepout
			(tracks allowed)
			(vias allowed)
			(pads allowed)
			(copperpour allowed)
			(footprints allowed)
		)
		(placement
			(enabled no)
			(sheetname "")
		)
		(fill
			(thermal_gap 0.5)
			(thermal_bridge_width 0.5)
			(island_removal_mode 0)
		)
		(polygon
			(pts
				(xy 101.840538 -325.41972) (xy 101.840538 -327.32472) (xy 105.853738 -327.32472) (xy 105.853738 -325.41972)
			)
		)
	)
	(zone
		(layer "F.Cu")
		(hatch none 0.5)
		(connect_pads
			(clearance 0)
		)
		(min_thickness 0.25)
		(keepout
			(tracks allowed)
			(vias allowed)
			(pads allowed)
			(copperpour allowed)
			(footprints allowed)
		)
		(placement
			(enabled no)
			(sheetname "")
		)
		(fill
			(thermal_gap 0.5)
			(thermal_bridge_width 0.5)
			(island_removal_mode 0)
		)
		(polygon
			(pts
				(xy 436.00878 -32.35452) (xy 451.24624 -32.35452) (xy 456.5523 -27.04846) (xy 456.5523 -12.8778)
				(xy 455.12228 -11.44778) (xy 449.29552 -11.44778) (xy 447.52768 -13.21562) (xy 437.59374 -13.21562)
				(xy 435.3052 -15.50416) (xy 435.3052 -31.65094)
			)
		)
	)
	(zone
		(layer "F.Cu")
		(hatch none 0.5)
		(connect_pads
			(clearance 0)
		)
		(min_thickness 0.25)
		(keepout
			(tracks allowed)
			(vias allowed)
			(pads allowed)
			(copperpour allowed)
			(footprints allowed)
		)
		(placement
			(enabled no)
			(sheetname "")
		)
		(fill
			(thermal_gap 0.5)
			(thermal_bridge_width 0.5)
			(island_removal_mode 0)
		)
		(polygon
			(pts
				(xy 305.54168 -381.943102) (xy 305.54168 -380.93904) (xy 306.938172 -380.93904) (xy 306.938172 -381.943102)
			)
		)
	)
	(zone
		(layer "F.Cu")
		(hatch none 0.5)
		(connect_pads
			(clearance 0)
		)
		(min_thickness 0.25)
		(keepout
			(tracks allowed)
			(vias allowed)
			(pads allowed)
			(copperpour allowed)
			(footprints not_allowed)
		)
		(placement
			(enabled no)
			(sheetname "")
		)
		(fill
			(thermal_gap 0.5)
			(thermal_bridge_width 0.5)
			(island_removal_mode 0)
		)
		(polygon
			(pts
				(xy 317.449962 -64.840104) (xy 324.350126 -64.840104) (xy 324.350126 -59.159902) (xy 317.449962 -59.159902)
			)
		)
	)
	(zone
		(layer "F.Cu")
		(hatch none 0.5)
		(connect_pads
			(clearance 0)
		)
		(min_thickness 0.25)
		(keepout
			(tracks allowed)
			(vias allowed)
			(pads allowed)
			(copperpour allowed)
			(footprints allowed)
		)
		(placement
			(enabled no)
			(sheetname "")
		)
		(fill
			(thermal_gap 0.5)
			(thermal_bridge_width 0.5)
			(island_removal_mode 0)
		)
		(polygon
			(pts
				(xy 411.317694 -252.327664) (xy 411.317694 -251.997464) (xy 413.236664 -251.997464) (xy 413.236664 -252.327664)
			)
		)
	)
	(zone
		(layer "F.Cu")
		(hatch none 0.5)
		(connect_pads
			(clearance 0)
		)
		(min_thickness 0.25)
		(keepout
			(tracks allowed)
			(vias allowed)
			(pads allowed)
			(copperpour allowed)
			(footprints not_allowed)
		)
		(placement
			(enabled no)
			(sheetname "")
		)
		(fill
			(thermal_gap 0.5)
			(thermal_bridge_width 0.5)
			(island_removal_mode 0)
		)
		(polygon
			(pts
				(arc
					(start 139.729972 -304.790094)
					(mid 142.530068 -301.989998)
					(end 145.32991 -304.790094)
				)
				(arc
					(start 145.32991 -304.790094)
					(mid 142.530068 -307.589936)
					(end 139.729972 -304.790094)
				)
			)
		)
	)
	(zone
		(layer "F.Cu")
		(hatch none 0.5)
		(connect_pads
			(clearance 0)
		)
		(min_thickness 0.25)
		(keepout
			(tracks not_allowed)
			(vias allowed)
			(pads allowed)
			(copperpour not_allowed)
			(footprints allowed)
		)
		(placement
			(enabled no)
			(sheetname "")
		)
		(fill
			(thermal_gap 0.5)
			(thermal_bridge_width 0.5)
			(island_removal_mode 0)
		)
		(polygon
			(pts
				(xy 438.808114 -12.04468) (xy 438.925462 -12.04468) (xy 438.976262 -11.99388) (xy 438.976262 -10.54608)
				(xy 438.925462 -10.49528) (xy 438.808114 -10.49528) (xy 438.757314 -10.54608) (xy 438.757314 -11.99388)
			)
		)
	)
	(zone
		(layer "F.Cu")
		(hatch none 0.5)
		(connect_pads
			(clearance 0)
		)
		(min_thickness 0.25)
		(keepout
			(tracks allowed)
			(vias allowed)
			(pads allowed)
			(copperpour allowed)
			(footprints allowed)
		)
		(placement
			(enabled no)
			(sheetname "")
		)
		(fill
			(thermal_gap 0.5)
			(thermal_bridge_width 0.5)
			(island_removal_mode 0)
		)
		(polygon
			(pts
				(xy 318.82969 -417.424616) (xy 318.82969 -416.420554) (xy 320.226182 -416.420554) (xy 320.226182 -417.424616)
			)
		)
	)
	(zone
		(layer "F.Cu")
		(hatch none 0.5)
		(connect_pads
			(clearance 0)
		)
		(min_thickness 0.25)
		(keepout
			(tracks allowed)
			(vias allowed)
			(pads allowed)
			(copperpour allowed)
			(footprints not_allowed)
		)
		(placement
			(enabled no)
			(sheetname "")
		)
		(fill
			(thermal_gap 0.5)
			(thermal_bridge_width 0.5)
			(island_removal_mode 0)
		)
		(polygon
			(pts
				(xy 269.352014 -356.605078) (xy 313.237118 -356.605078) (xy 313.237118 -351.605088) (xy 269.352014 -351.605088)
			)
		)
	)
	(zone
		(layer "F.Cu")
		(hatch none 0.5)
		(connect_pads
			(clearance 0)
		)
		(min_thickness 0.25)
		(keepout
			(tracks allowed)
			(vias allowed)
			(pads allowed)
			(copperpour allowed)
			(footprints allowed)
		)
		(placement
			(enabled no)
			(sheetname "")
		)
		(fill
			(thermal_gap 0.5)
			(thermal_bridge_width 0.5)
			(island_removal_mode 0)
		)
		(polygon
			(pts
				(xy 58.13044 -217.478102) (xy 58.13044 -217.147902) (xy 60.67044 -217.147902) (xy 60.67044 -217.478102)
			)
		)
	)
	(zone
		(layer "F.Cu")
		(hatch none 0.5)
		(connect_pads
			(clearance 0)
		)
		(min_thickness 0.25)
		(keepout
			(tracks allowed)
			(vias allowed)
			(pads allowed)
			(copperpour allowed)
			(footprints allowed)
		)
		(placement
			(enabled no)
			(sheetname "")
		)
		(fill
			(thermal_gap 0.5)
			(thermal_bridge_width 0.5)
			(island_removal_mode 0)
		)
		(polygon
			(pts
				(xy 257.38582 -66.78676) (xy 257.38582 -65.42786) (xy 258.19862 -65.42786) (xy 258.19862 -66.78676)
			)
		)
	)
	(zone
		(layer "F.Cu")
		(hatch none 0.5)
		(connect_pads
			(clearance 0)
		)
		(min_thickness 0.25)
		(keepout
			(tracks allowed)
			(vias allowed)
			(pads allowed)
			(copperpour allowed)
			(footprints allowed)
		)
		(placement
			(enabled no)
			(sheetname "")
		)
		(fill
			(thermal_gap 0.5)
			(thermal_bridge_width 0.5)
			(island_removal_mode 0)
		)
		(polygon
			(pts
				(xy 34.99231 -332.20152) (xy 34.99231 -334.10652) (xy 39.00551 -334.10652) (xy 39.00551 -332.20152)
			)
		)
	)
	(zone
		(layer "F.Cu")
		(hatch none 0.5)
		(connect_pads
			(clearance 0)
		)
		(min_thickness 0.25)
		(keepout
			(tracks allowed)
			(vias allowed)
			(pads allowed)
			(copperpour allowed)
			(footprints allowed)
		)
		(placement
			(enabled no)
			(sheetname "")
		)
		(fill
			(thermal_gap 0.5)
			(thermal_bridge_width 0.5)
			(island_removal_mode 0)
		)
		(polygon
			(pts
				(xy 161.082228 -376.024902) (xy 161.082228 -375.02084) (xy 162.47872 -375.02084) (xy 162.47872 -376.024902)
			)
		)
	)
	(zone
		(layer "F.Cu")
		(hatch none 0.5)
		(connect_pads
			(clearance 0)
		)
		(min_thickness 0.25)
		(keepout
			(tracks not_allowed)
			(vias allowed)
			(pads allowed)
			(copperpour not_allowed)
			(footprints allowed)
		)
		(placement
			(enabled no)
			(sheetname "")
		)
		(fill
			(thermal_gap 0.5)
			(thermal_bridge_width 0.5)
			(island_removal_mode 0)
		)
		(polygon
			(pts
				(xy 383.5781 -183.535828) (xy 383.5781 -183.079136) (xy 382.882394 -183.079136) (xy 382.882394 -183.239664)
				(xy 382.323594 -183.239664) (xy 382.323594 -182.833264) (xy 382.882394 -182.833264) (xy 382.882394 -183.053736)
				(xy 383.5781 -183.053736) (xy 383.5781 -182.926736) (xy 383.122424 -182.926736) (xy 383.122424 -182.540148)
				(xy 382.880108 -182.540148) (xy 382.348232 -182.540148) (xy 382.0287 -182.85968) (xy 382.0287 -183.535828)
			)
		)
	)
	(zone
		(layer "F.Cu")
		(hatch none 0.5)
		(connect_pads
			(clearance 0)
		)
		(min_thickness 0.25)
		(keepout
			(tracks allowed)
			(vias allowed)
			(pads allowed)
			(copperpour allowed)
			(footprints allowed)
		)
		(placement
			(enabled no)
			(sheetname "")
		)
		(fill
			(thermal_gap 0.5)
			(thermal_bridge_width 0.5)
			(island_removal_mode 0)
		)
		(polygon
			(pts
				(xy 60.725812 -289.392614) (xy 60.725812 -289.722814) (xy 58.185812 -289.722814) (xy 58.185812 -289.392614)
			)
		)
	)
	(zone
		(layer "F.Cu")
		(hatch none 0.5)
		(connect_pads
			(clearance 0)
		)
		(min_thickness 0.25)
		(keepout
			(tracks allowed)
			(vias allowed)
			(pads allowed)
			(copperpour allowed)
			(footprints allowed)
		)
		(placement
			(enabled no)
			(sheetname "")
		)
		(fill
			(thermal_gap 0.5)
			(thermal_bridge_width 0.5)
			(island_removal_mode 0)
		)
		(polygon
			(pts
				(xy 395.083538 -177.510694) (xy 400.77644 -177.510694) (xy 401.06854 -177.802794) (xy 401.06854 -180.19014)
				(xy 401.64258 -180.76418) (xy 402.1582 -180.76418) (xy 402.37664 -180.54574) (xy 402.37664 -179.06492)
				(xy 402.068538 -178.756818) (xy 402.068538 -176.875694) (xy 402.068538 -172.303694) (xy 401.433538 -171.668694)
				(xy 395.464538 -171.668694) (xy 394.956538 -172.176694) (xy 394.956538 -177.383694)
			)
		)
	)
	(zone
		(layer "F.Cu")
		(hatch none 0.5)
		(connect_pads
			(clearance 0)
		)
		(min_thickness 0.25)
		(keepout
			(tracks allowed)
			(vias allowed)
			(pads allowed)
			(copperpour allowed)
			(footprints not_allowed)
		)
		(placement
			(enabled no)
			(sheetname "")
		)
		(fill
			(thermal_gap 0.5)
			(thermal_bridge_width 0.5)
			(island_removal_mode 0)
		)
		(polygon
			(pts
				(arc
					(start 304.446686 -36.885372)
					(mid 301.230635 -41.718013)
					(end 295.8719 -43.949874)
				)
				(xy 295.8719 -46.150022)
				(arc
					(start 291.349938 -46.150022)
					(mid 290.655634 -48.936119)
					(end 289.198304 -51.410108)
				)
				(xy 294.014906 -51.410108) (xy 294.014906 -48.410114) (xy 307.384958 -48.410114) (xy 307.384958 -51.410108)
				(arc
					(start 308.576726 -51.410108)
					(mid 311.634105 -49.047915)
					(end 315.193426 -47.54499)
				)
				(arc
					(start 315.193426 -47.54499)
					(mid 311.26324 -40.760203)
					(end 304.446686 -36.885372)
				)
			)
		)
	)
	(zone
		(layer "F.Cu")
		(hatch none 0.5)
		(connect_pads
			(clearance 0)
		)
		(min_thickness 0.25)
		(keepout
			(tracks allowed)
			(vias allowed)
			(pads allowed)
			(copperpour allowed)
			(footprints not_allowed)
		)
		(placement
			(enabled no)
			(sheetname "")
		)
		(fill
			(thermal_gap 0.5)
			(thermal_bridge_width 0.5)
			(island_removal_mode 0)
		)
		(polygon
			(pts
				(arc
					(start 295.319958 -413.170116)
					(mid 297.570144 -410.91993)
					(end 299.820076 -413.170116)
				)
				(arc
					(start 299.820076 -413.170116)
					(mid 297.570144 -415.420048)
					(end 295.319958 -413.170116)
				)
			)
		)
	)
	(zone
		(layer "F.Cu")
		(hatch none 0.5)
		(connect_pads
			(clearance 0)
		)
		(min_thickness 0.25)
		(keepout
			(tracks allowed)
			(vias allowed)
			(pads allowed)
			(copperpour allowed)
			(footprints allowed)
		)
		(placement
			(enabled no)
			(sheetname "")
		)
		(fill
			(thermal_gap 0.5)
			(thermal_bridge_width 0.5)
			(island_removal_mode 0)
		)
		(polygon
			(pts
				(xy 47.06112 -188.99886) (xy 47.06112 -183.9468) (xy 56.09844 -183.9468) (xy 56.09844 -188.99886)
			)
		)
	)
	(zone
		(layer "F.Cu")
		(hatch none 0.5)
		(connect_pads
			(clearance 0)
		)
		(min_thickness 0.25)
		(keepout
			(tracks allowed)
			(vias allowed)
			(pads allowed)
			(copperpour allowed)
			(footprints allowed)
		)
		(placement
			(enabled no)
			(sheetname "")
		)
		(fill
			(thermal_gap 0.5)
			(thermal_bridge_width 0.5)
			(island_removal_mode 0)
		)
		(polygon
			(pts
				(xy 411.562042 -304.1777) (xy 411.562042 -303.8475) (xy 413.236664 -303.8475) (xy 413.236664 -304.1777)
			)
		)
	)
	(zone
		(layer "F.Cu")
		(hatch none 0.5)
		(connect_pads
			(clearance 0)
		)
		(min_thickness 0.25)
		(keepout
			(tracks allowed)
			(vias allowed)
			(pads allowed)
			(copperpour allowed)
			(footprints not_allowed)
		)
		(placement
			(enabled no)
			(sheetname "")
		)
		(fill
			(thermal_gap 0.5)
			(thermal_bridge_width 0.5)
			(island_removal_mode 0)
		)
		(polygon
			(pts
				(xy 106.499914 -440.88685)
				(arc
					(start 106.499914 -430.289716)
					(mid 100.509365 -427.56021)
					(end 94.499938 -430.247806)
				)
				(arc
					(start 94.499938 -440.844432)
					(mid 94.565277 -440.917607)
					(end 94.63151 -440.989974)
				)
				(xy 106.405934 -440.989974)
			)
		)
	)
	(zone
		(layer "F.Cu")
		(hatch none 0.5)
		(connect_pads
			(clearance 0)
		)
		(min_thickness 0.25)
		(keepout
			(tracks allowed)
			(vias allowed)
			(pads allowed)
			(copperpour allowed)
			(footprints allowed)
		)
		(placement
			(enabled no)
			(sheetname "")
		)
		(fill
			(thermal_gap 0.5)
			(thermal_bridge_width 0.5)
			(island_removal_mode 0)
		)
		(polygon
			(pts
				(xy 370.550694 -195.358512) (xy 370.550694 -197.263512) (xy 374.563894 -197.263512) (xy 374.563894 -195.358512)
			)
		)
	)
	(zone
		(layer "F.Cu")
		(hatch none 0.5)
		(connect_pads
			(clearance 0)
		)
		(min_thickness 0.25)
		(keepout
			(tracks not_allowed)
			(vias allowed)
			(pads allowed)
			(copperpour not_allowed)
			(footprints allowed)
		)
		(placement
			(enabled no)
			(sheetname "")
		)
		(fill
			(thermal_gap 0.5)
			(thermal_bridge_width 0.5)
			(island_removal_mode 0)
		)
		(polygon
			(pts
				(xy 65.625726 -10.49528) (xy 65.508378 -10.49528) (xy 65.457578 -10.54608) (xy 65.457578 -11.99388)
				(xy 65.508378 -12.04468) (xy 65.625726 -12.04468) (xy 65.676526 -11.99388) (xy 65.676526 -10.54608)
			)
		)
	)
	(zone
		(layer "F.Cu")
		(hatch none 0.5)
		(connect_pads
			(clearance 0)
		)
		(min_thickness 0.25)
		(keepout
			(tracks allowed)
			(vias allowed)
			(pads allowed)
			(copperpour allowed)
			(footprints allowed)
		)
		(placement
			(enabled no)
			(sheetname "")
		)
		(fill
			(thermal_gap 0.5)
			(thermal_bridge_width 0.5)
			(island_removal_mode 0)
		)
		(polygon
			(pts
				(xy 121.22531 -165.532054) (xy 126.79426 -165.532054) (xy 127.25908 -165.996874) (xy 127.25908 -168.19626)
				(xy 127.6731 -168.61028) (xy 128.24968 -168.61028) (xy 128.44526 -168.4147) (xy 128.44526 -167.1574)
				(xy 128.21031 -166.92245) (xy 128.21031 -164.897054) (xy 128.21031 -160.325054) (xy 127.57531 -159.690054)
				(xy 121.60631 -159.690054) (xy 121.09831 -160.198054) (xy 121.09831 -165.405054)
			)
		)
	)
	(zone
		(layer "F.Cu")
		(hatch none 0.5)
		(connect_pads
			(clearance 0)
		)
		(min_thickness 0.25)
		(keepout
			(tracks not_allowed)
			(vias allowed)
			(pads allowed)
			(copperpour not_allowed)
			(footprints allowed)
		)
		(placement
			(enabled no)
			(sheetname "")
		)
		(fill
			(thermal_gap 0.5)
			(thermal_bridge_width 0.5)
			(island_removal_mode 0)
		)
		(polygon
			(pts
				(xy 316.083188 -5.625846) (xy 316.083188 -5.530342) (xy 315.486288 -5.530342) (xy 315.486288 -5.123942)
				(xy 316.083188 -5.123942) (xy 316.083188 -5.03047) (xy 315.486288 -5.03047) (xy 315.486288 -4.62407)
				(xy 316.083188 -4.62407) (xy 316.083188 -4.528566) (xy 315.384688 -4.528566) (xy 315.384688 -5.625846)
			)
		)
	)
	(zone
		(layer "F.Cu")
		(hatch none 0.5)
		(connect_pads
			(clearance 0)
		)
		(min_thickness 0.25)
		(keepout
			(tracks allowed)
			(vias allowed)
			(pads allowed)
			(copperpour allowed)
			(footprints allowed)
		)
		(placement
			(enabled no)
			(sheetname "")
		)
		(fill
			(thermal_gap 0.5)
			(thermal_bridge_width 0.5)
			(island_removal_mode 0)
		)
		(polygon
			(pts
				(xy 457.6699 -190.75654) (xy 457.6699 -180.5178) (xy 462.21142 -180.5178) (xy 462.21142 -190.75654)
			)
		)
	)
	(zone
		(layer "F.Cu")
		(hatch none 0.5)
		(connect_pads
			(clearance 0)
		)
		(min_thickness 0.25)
		(keepout
			(tracks allowed)
			(vias allowed)
			(pads allowed)
			(copperpour allowed)
			(footprints not_allowed)
		)
		(placement
			(enabled no)
			(sheetname "")
		)
		(fill
			(thermal_gap 0.5)
			(thermal_bridge_width 0.5)
			(island_removal_mode 0)
		)
		(polygon
			(pts
				(xy 352.222054 -144.808448) (xy 352.222054 -154.617928) (xy 352.222054 -157.705044) (xy 360.73207 -157.705044)
				(xy 360.73207 -165.934898) (xy 369.391946 -165.934898) (xy 369.391946 -175.565054) (xy 384.552952 -175.565054)
				(xy 384.552952 -168.654984) (xy 392.462004 -168.654984) (xy 392.462004 -161.874962) (xy 402.15312 -161.874962)
				(xy 402.15312 -158.90494) (xy 419.643052 -158.90494) (xy 429.681894 -158.90494) (xy 429.681894 -165.596062)
				(arc
					(start 455.292968 -165.596062)
					(mid 456.175697 -154.493579)
					(end 467.300056 -155.032456)
				)
				(xy 467.300056 -144.808448) (xy 452.394066 -144.808448) (xy 452.394066 -161.308542) (xy 431.394108 -161.306256)
				(xy 431.395632 -144.808448)
			)
		)
	)
	(zone
		(layer "F.Cu")
		(hatch none 0.5)
		(connect_pads
			(clearance 0)
		)
		(min_thickness 0.25)
		(keepout
			(tracks allowed)
			(vias allowed)
			(pads allowed)
			(copperpour allowed)
			(footprints allowed)
		)
		(placement
			(enabled no)
			(sheetname "")
		)
		(fill
			(thermal_gap 0.5)
			(thermal_bridge_width 0.5)
			(island_removal_mode 0)
		)
		(polygon
			(pts
				(xy 163.621974 -313.527948) (xy 163.621974 -313.197748) (xy 165.296596 -313.197748) (xy 165.296596 -313.527948)
			)
		)
	)
	(zone
		(layer "F.Cu")
		(hatch none 0.5)
		(connect_pads
			(clearance 0)
		)
		(min_thickness 0.25)
		(keepout
			(tracks allowed)
			(vias allowed)
			(pads allowed)
			(copperpour allowed)
			(footprints allowed)
		)
		(placement
			(enabled no)
			(sheetname "")
		)
		(fill
			(thermal_gap 0.5)
			(thermal_bridge_width 0.5)
			(island_removal_mode 0)
		)
		(polygon
			(pts
				(xy 461.28686 -41.92524) (xy 461.28686 -41.32834) (xy 462.5721 -41.32834) (xy 462.5721 -41.92524)
			)
		)
	)
	(zone
		(layer "F.Cu")
		(hatch none 0.5)
		(connect_pads
			(clearance 0)
		)
		(min_thickness 0.25)
		(keepout
			(tracks allowed)
			(vias allowed)
			(pads allowed)
			(copperpour allowed)
			(footprints not_allowed)
		)
		(placement
			(enabled no)
			(sheetname "")
		)
		(fill
			(thermal_gap 0.5)
			(thermal_bridge_width 0.5)
			(island_removal_mode 0)
		)
		(polygon
			(pts
				(xy 389.029956 -68.209922) (xy 400.869912 -68.209922) (xy 400.869912 -49.509934) (xy 389.029956 -49.509934)
			)
		)
	)
	(zone
		(layer "F.Cu")
		(hatch none 0.5)
		(connect_pads
			(clearance 0)
		)
		(min_thickness 0.25)
		(keepout
			(tracks not_allowed)
			(vias allowed)
			(pads allowed)
			(copperpour not_allowed)
			(footprints allowed)
		)
		(placement
			(enabled no)
			(sheetname "")
		)
		(fill
			(thermal_gap 0.5)
			(thermal_bridge_width 0.5)
			(island_removal_mode 0)
		)
		(polygon
			(pts
				(xy 349.167958 -339.184742) (xy 349.167958 -339.641434) (xy 349.863664 -339.641434) (xy 349.863664 -339.480906)
				(xy 350.422464 -339.480906) (xy 350.422464 -339.887306) (xy 349.863664 -339.887306) (xy 349.863664 -339.666834)
				(xy 349.167958 -339.666834) (xy 349.167958 -339.793834) (xy 349.623634 -339.793834) (xy 349.623634 -340.180422)
				(xy 349.86595 -340.180422) (xy 350.397826 -340.180422) (xy 350.717358 -339.86089) (xy 350.717358 -339.184742)
			)
		)
	)
	(zone
		(layer "F.Cu")
		(hatch none 0.5)
		(connect_pads
			(clearance 0)
		)
		(min_thickness 0.25)
		(keepout
			(tracks allowed)
			(vias allowed)
			(pads allowed)
			(copperpour allowed)
			(footprints not_allowed)
		)
		(placement
			(enabled no)
			(sheetname "")
		)
		(fill
			(thermal_gap 0.5)
			(thermal_bridge_width 0.5)
			(island_removal_mode 0)
		)
		(polygon
			(pts
				(arc
					(start 265.8999 -51.999896)
					(mid 268.649958 -49.249838)
					(end 271.400016 -51.999896)
				)
				(arc
					(start 271.400016 -51.999896)
					(mid 268.649958 -54.749954)
					(end 265.8999 -51.999896)
				)
			)
		)
	)
	(zone
		(layer "F.Cu")
		(hatch none 0.5)
		(connect_pads
			(clearance 0)
		)
		(min_thickness 0.25)
		(keepout
			(tracks allowed)
			(vias allowed)
			(pads allowed)
			(copperpour allowed)
			(footprints allowed)
		)
		(placement
			(enabled no)
			(sheetname "")
		)
		(fill
			(thermal_gap 0.5)
			(thermal_bridge_width 0.5)
			(island_removal_mode 0)
		)
		(polygon
			(pts
				(xy 306.070508 -266.777724) (xy 306.070508 -266.447524) (xy 308.610508 -266.447524) (xy 308.610508 -266.777724)
			)
		)
	)
	(zone
		(layer "F.Cu")
		(hatch none 0.5)
		(connect_pads
			(clearance 0)
		)
		(min_thickness 0.25)
		(keepout
			(tracks allowed)
			(vias allowed)
			(pads allowed)
			(copperpour allowed)
			(footprints allowed)
		)
		(placement
			(enabled no)
			(sheetname "")
		)
		(fill
			(thermal_gap 0.5)
			(thermal_bridge_width 0.5)
			(island_removal_mode 0)
		)
		(polygon
			(pts
				(xy 96.33331 -183.032654) (xy 102.68331 -183.032654) (xy 103.31831 -182.397654) (xy 103.31831 -177.825654)
				(xy 102.68331 -177.190654) (xy 96.71431 -177.190654) (xy 96.20631 -177.698654) (xy 96.20631 -182.905654)
			)
		)
	)
	(zone
		(layer "F.Cu")
		(hatch none 0.5)
		(connect_pads
			(clearance 0)
		)
		(min_thickness 0.25)
		(keepout
			(tracks allowed)
			(vias allowed)
			(pads allowed)
			(copperpour allowed)
			(footprints allowed)
		)
		(placement
			(enabled no)
			(sheetname "")
		)
		(fill
			(thermal_gap 0.5)
			(thermal_bridge_width 0.5)
			(island_removal_mode 0)
		)
		(polygon
			(pts
				(xy 411.317694 -265.077956) (xy 411.317694 -264.747756) (xy 413.236664 -264.747756) (xy 413.236664 -265.077956)
			)
		)
	)
	(zone
		(layer "F.Cu")
		(hatch none 0.5)
		(connect_pads
			(clearance 0)
		)
		(min_thickness 0.25)
		(keepout
			(tracks allowed)
			(vias allowed)
			(pads allowed)
			(copperpour allowed)
			(footprints allowed)
		)
		(placement
			(enabled no)
			(sheetname "")
		)
		(fill
			(thermal_gap 0.5)
			(thermal_bridge_width 0.5)
			(island_removal_mode 0)
		)
		(polygon
			(pts
				(xy 411.317694 -231.927654) (xy 411.317694 -231.597454) (xy 413.236664 -231.597454) (xy 413.236664 -231.927654)
			)
		)
	)
	(zone
		(layer "F.Cu")
		(hatch none 0.5)
		(connect_pads
			(clearance 0)
		)
		(min_thickness 0.25)
		(keepout
			(tracks allowed)
			(vias allowed)
			(pads allowed)
			(copperpour allowed)
			(footprints allowed)
		)
		(placement
			(enabled no)
			(sheetname "")
		)
		(fill
			(thermal_gap 0.5)
			(thermal_bridge_width 0.5)
			(island_removal_mode 0)
		)
		(polygon
			(pts
				(xy 308.66588 -291.092382) (xy 308.66588 -291.422582) (xy 306.12588 -291.422582) (xy 306.12588 -291.092382)
			)
		)
	)
	(zone
		(layer "F.Cu")
		(hatch none 0.5)
		(connect_pads
			(clearance 0)
		)
		(min_thickness 0.25)
		(keepout
			(tracks allowed)
			(vias allowed)
			(pads allowed)
			(copperpour allowed)
			(footprints not_allowed)
		)
		(placement
			(enabled no)
			(sheetname "")
		)
		(fill
			(thermal_gap 0.5)
			(thermal_bridge_width 0.5)
			(island_removal_mode 0)
		)
		(polygon
			(pts
				(arc
					(start 109.815884 -166.61511)
					(mid 106.716068 -169.714926)
					(end 103.615998 -166.61511)
				)
				(arc
					(start 103.615998 -166.61511)
					(mid 106.716068 -163.51504)
					(end 109.815884 -166.61511)
				)
			)
		)
	)
	(zone
		(layer "F.Cu")
		(hatch none 0.5)
		(connect_pads
			(clearance 0)
		)
		(min_thickness 0.25)
		(keepout
			(tracks allowed)
			(vias allowed)
			(pads allowed)
			(copperpour allowed)
			(footprints allowed)
		)
		(placement
			(enabled no)
			(sheetname "")
		)
		(fill
			(thermal_gap 0.5)
			(thermal_bridge_width 0.5)
			(island_removal_mode 0)
		)
		(polygon
			(pts
				(xy 14.9479 -135.482076) (xy 14.9479 -133.615176) (xy 15.97533 -133.615176) (xy 15.97533 -135.482076)
			)
		)
	)
	(zone
		(layer "F.Cu")
		(hatch none 0.5)
		(connect_pads
			(clearance 0)
		)
		(min_thickness 0.25)
		(keepout
			(tracks allowed)
			(vias allowed)
			(pads allowed)
			(copperpour allowed)
			(footprints allowed)
		)
		(placement
			(enabled no)
			(sheetname "")
		)
		(fill
			(thermal_gap 0.5)
			(thermal_bridge_width 0.5)
			(island_removal_mode 0)
		)
		(polygon
			(pts
				(xy 144.45996 -391.360406) (xy 146.266408 -391.360406) (xy 146.555206 -391.071608) (xy 146.555206 -388.252462)
				(xy 146.680174 -388.127494) (xy 166.066216 -388.127494) (xy 166.066216 -390.775952) (xy 165.716712 -391.125456)
				(xy 165.716712 -392.40206) (xy 165.881558 -392.566906) (xy 166.471346 -392.566906) (xy 167.951658 -391.086594)
				(xy 167.951658 -388.176008) (xy 165.724332 -385.948682) (xy 146.54149 -385.948682) (xy 145.92681 -385.334002)
				(xy 145.92681 -384.995166) (xy 145.776188 -384.844544) (xy 144.760188 -384.844544) (xy 144.38376 -385.220972)
				(xy 144.38376 -387.315964) (xy 143.505428 -388.194296) (xy 143.505428 -389.260842) (xy 144.396206 -390.15162)
				(xy 144.396206 -391.296652)
			)
		)
	)
	(zone
		(layer "F.Cu")
		(hatch none 0.5)
		(connect_pads
			(clearance 0)
		)
		(min_thickness 0.25)
		(keepout
			(tracks allowed)
			(vias allowed)
			(pads allowed)
			(copperpour allowed)
			(footprints allowed)
		)
		(placement
			(enabled no)
			(sheetname "")
		)
		(fill
			(thermal_gap 0.5)
			(thermal_bridge_width 0.5)
			(island_removal_mode 0)
		)
		(polygon
			(pts
				(xy 409.760928 -142.889986) (xy 411.141926 -142.889986) (xy 412.059882 -141.97203) (xy 412.059882 -139.704572)
				(xy 411.40888 -139.05357) (xy 409.972764 -139.05357) (xy 409.565094 -139.46124) (xy 409.565094 -142.694152)
			)
		)
	)
	(zone
		(layer "F.Cu")
		(hatch none 0.5)
		(connect_pads
			(clearance 0)
		)
		(min_thickness 0.25)
		(keepout
			(tracks allowed)
			(vias allowed)
			(pads allowed)
			(copperpour allowed)
			(footprints allowed)
		)
		(placement
			(enabled no)
			(sheetname "")
		)
		(fill
			(thermal_gap 0.5)
			(thermal_bridge_width 0.5)
			(island_removal_mode 0)
		)
		(polygon
			(pts
				(xy 44.83227 -391.360406) (xy 46.638718 -391.360406) (xy 46.927516 -391.071608) (xy 46.927516 -388.252462)
				(xy 47.052484 -388.127494) (xy 66.438526 -388.127494) (xy 66.438526 -390.775952) (xy 66.089022 -391.125456)
				(xy 66.089022 -392.40206) (xy 66.253868 -392.566906) (xy 66.843656 -392.566906) (xy 68.323968 -391.086594)
				(xy 68.323968 -388.176008) (xy 66.096642 -385.948682) (xy 46.9138 -385.948682) (xy 46.29912 -385.334002)
				(xy 46.29912 -384.995166) (xy 46.148498 -384.844544) (xy 45.132498 -384.844544) (xy 44.75607 -385.220972)
				(xy 44.75607 -387.315964) (xy 43.877738 -388.194296) (xy 43.877738 -389.260842) (xy 44.768516 -390.15162)
				(xy 44.768516 -391.296652)
			)
		)
	)
	(zone
		(layer "F.Cu")
		(hatch none 0.5)
		(connect_pads
			(clearance 0)
		)
		(min_thickness 0.25)
		(keepout
			(tracks allowed)
			(vias allowed)
			(pads allowed)
			(copperpour allowed)
			(footprints not_allowed)
		)
		(placement
			(enabled no)
			(sheetname "")
		)
		(fill
			(thermal_gap 0.5)
			(thermal_bridge_width 0.5)
			(island_removal_mode 0)
		)
		(polygon
			(pts
				(arc
					(start 293.569898 -413.170116)
					(mid 297.56989 -409.170124)
					(end 301.569882 -413.170116)
				)
				(arc
					(start 301.569882 -413.170116)
					(mid 297.56989 -417.170108)
					(end 293.569898 -413.170116)
				)
			)
		)
	)
	(zone
		(layer "F.Cu")
		(hatch none 0.5)
		(connect_pads
			(clearance 0)
		)
		(min_thickness 0.25)
		(keepout
			(tracks allowed)
			(vias allowed)
			(pads allowed)
			(copperpour allowed)
			(footprints allowed)
		)
		(placement
			(enabled no)
			(sheetname "")
		)
		(fill
			(thermal_gap 0.5)
			(thermal_bridge_width 0.5)
			(island_removal_mode 0)
		)
		(polygon
			(pts
				(xy 42.734738 -373.561102) (xy 42.734738 -372.55704) (xy 44.13123 -372.55704) (xy 44.13123 -373.561102)
			)
		)
	)
	(zone
		(layer "F.Cu")
		(hatch none 0.5)
		(connect_pads
			(clearance 0)
		)
		(min_thickness 0.25)
		(keepout
			(tracks allowed)
			(vias allowed)
			(pads allowed)
			(copperpour allowed)
			(footprints not_allowed)
		)
		(placement
			(enabled no)
			(sheetname "")
		)
		(fill
			(thermal_gap 0.5)
			(thermal_bridge_width 0.5)
			(island_removal_mode 0)
		)
		(polygon
			(pts
				(xy 4.45008 -49.159922) (xy 4.45008 -54.840124) (xy 11.34999 -54.840124) (xy 11.34999 -49.159922)
			)
		)
	)
	(zone
		(layer "F.Cu")
		(hatch none 0.5)
		(connect_pads
			(clearance 0)
		)
		(min_thickness 0.25)
		(keepout
			(tracks allowed)
			(vias allowed)
			(pads allowed)
			(copperpour allowed)
			(footprints allowed)
		)
		(placement
			(enabled no)
			(sheetname "")
		)
		(fill
			(thermal_gap 0.5)
			(thermal_bridge_width 0.5)
			(island_removal_mode 0)
		)
		(polygon
			(pts
				(xy 19.3802 -131.79044) (xy 20.8534 -131.79044) (xy 20.8534 -132.67944) (xy 19.3802 -132.67944)
			)
		)
	)
	(zone
		(layer "F.Cu")
		(hatch none 0.5)
		(connect_pads
			(clearance 0)
		)
		(min_thickness 0.25)
		(keepout
			(tracks allowed)
			(vias allowed)
			(pads allowed)
			(copperpour allowed)
			(footprints allowed)
		)
		(placement
			(enabled no)
			(sheetname "")
		)
		(fill
			(thermal_gap 0.5)
			(thermal_bridge_width 0.5)
			(island_removal_mode 0)
		)
		(polygon
			(pts
				(xy 26.71191 -332.20152) (xy 26.71191 -334.10652) (xy 30.72511 -334.10652) (xy 30.72511 -332.20152)
			)
		)
	)
	(zone
		(layer "F.Cu")
		(hatch none 0.5)
		(connect_pads
			(clearance 0)
		)
		(min_thickness 0.25)
		(keepout
			(tracks allowed)
			(vias allowed)
			(pads allowed)
			(copperpour allowed)
			(footprints allowed)
		)
		(placement
			(enabled no)
			(sheetname "")
		)
		(fill
			(thermal_gap 0.5)
			(thermal_bridge_width 0.5)
			(island_removal_mode 0)
		)
		(polygon
			(pts
				(xy 37.45865 -173.000416) (xy 37.45865 -171.03217) (xy 38.341554 -171.03217) (xy 38.341554 -173.000416)
			)
		)
	)
	(zone
		(layer "F.Cu")
		(hatch none 0.5)
		(connect_pads
			(clearance 0)
		)
		(min_thickness 0.25)
		(keepout
			(tracks allowed)
			(vias allowed)
			(pads allowed)
			(copperpour allowed)
			(footprints allowed)
		)
		(placement
			(enabled no)
			(sheetname "")
		)
		(fill
			(thermal_gap 0.5)
			(thermal_bridge_width 0.5)
			(island_removal_mode 0)
		)
		(polygon
			(pts
				(xy 357.743252 -387.598412) (xy 358.747314 -387.598412) (xy 358.747314 -388.994904) (xy 357.743252 -388.994904)
			)
		)
	)
	(zone
		(layer "F.Cu")
		(hatch none 0.5)
		(connect_pads
			(clearance 0)
		)
		(min_thickness 0.25)
		(keepout
			(tracks not_allowed)
			(vias allowed)
			(pads allowed)
			(copperpour not_allowed)
			(footprints allowed)
		)
		(placement
			(enabled no)
			(sheetname "")
		)
		(fill
			(thermal_gap 0.5)
			(thermal_bridge_width 0.5)
			(island_removal_mode 0)
		)
		(polygon
			(pts
				(arc
					(start 421.016938 -163.314888)
					(mid 422.88206 -161.449766)
					(end 424.746928 -163.314888)
				)
				(arc
					(start 424.746928 -163.314888)
					(mid 422.88206 -165.179756)
					(end 421.016938 -163.314888)
				)
			)
		)
	)
	(zone
		(layer "F.Cu")
		(hatch none 0.5)
		(connect_pads
			(clearance 0)
		)
		(min_thickness 0.25)
		(keepout
			(tracks allowed)
			(vias allowed)
			(pads allowed)
			(copperpour allowed)
			(footprints not_allowed)
		)
		(placement
			(enabled no)
			(sheetname "")
		)
		(fill
			(thermal_gap 0.5)
			(thermal_bridge_width 0.5)
			(island_removal_mode 0)
		)
		(polygon
			(pts
				(xy 458.300074 -329.060048)
				(arc
					(start 458.300074 -340.350602)
					(mid 463.097442 -339.869398)
					(end 467.300056 -342.232488)
				)
				(xy 467.300056 -329.060048)
			)
		)
	)
	(zone
		(layer "F.Cu")
		(hatch none 0.5)
		(connect_pads
			(clearance 0)
		)
		(min_thickness 0.25)
		(keepout
			(tracks not_allowed)
			(vias allowed)
			(pads allowed)
			(copperpour not_allowed)
			(footprints allowed)
		)
		(placement
			(enabled no)
			(sheetname "")
		)
		(fill
			(thermal_gap 0.5)
			(thermal_bridge_width 0.5)
			(island_removal_mode 0)
		)
		(polygon
			(pts
				(xy 272.920714 -345.967812) (xy 272.920714 -346.424504) (xy 273.61642 -346.424504) (xy 273.61642 -346.263976)
				(xy 274.17522 -346.263976) (xy 274.17522 -346.670376) (xy 273.61642 -346.670376) (xy 273.61642 -346.449904)
				(xy 272.920714 -346.449904) (xy 272.920714 -346.576904) (xy 273.37639 -346.576904) (xy 273.37639 -346.963492)
				(xy 273.618706 -346.963492) (xy 274.150582 -346.963492) (xy 274.470114 -346.64396) (xy 274.470114 -345.967812)
			)
		)
	)
	(zone
		(layer "F.Cu")
		(hatch none 0.5)
		(connect_pads
			(clearance 0)
		)
		(min_thickness 0.25)
		(keepout
			(tracks allowed)
			(vias allowed)
			(pads allowed)
			(copperpour allowed)
			(footprints allowed)
		)
		(placement
			(enabled no)
			(sheetname "")
		)
		(fill
			(thermal_gap 0.5)
			(thermal_bridge_width 0.5)
			(island_removal_mode 0)
		)
		(polygon
			(pts
				(xy 70.456298 -9.16178) (xy 70.456298 -6.44525) (xy 72.922384 -6.44525) (xy 72.922384 -9.16178)
			)
		)
	)
	(zone
		(layer "F.Cu")
		(hatch none 0.5)
		(connect_pads
			(clearance 0)
		)
		(min_thickness 0.25)
		(keepout
			(tracks allowed)
			(vias allowed)
			(pads allowed)
			(copperpour allowed)
			(footprints allowed)
		)
		(placement
			(enabled no)
			(sheetname "")
		)
		(fill
			(thermal_gap 0.5)
			(thermal_bridge_width 0.5)
			(island_removal_mode 0)
		)
		(polygon
			(pts
				(xy 90.033602 -180.621178) (xy 88.230202 -180.621178) (xy 88.230202 -182.170578) (xy 90.033602 -182.170578)
			)
		)
	)
	(zone
		(layer "F.Cu")
		(hatch none 0.5)
		(connect_pads
			(clearance 0)
		)
		(min_thickness 0.25)
		(keepout
			(tracks allowed)
			(vias allowed)
			(pads allowed)
			(copperpour allowed)
			(footprints not_allowed)
		)
		(placement
			(enabled no)
			(sheetname "")
		)
		(fill
			(thermal_gap 0.5)
			(thermal_bridge_width 0.5)
			(island_removal_mode 0)
		)
		(polygon
			(pts
				(xy 10.290048 -394.759942) (xy 31.690056 -394.759942) (xy 31.690056 -385.160012) (xy 10.290048 -385.160012)
			)
		)
	)
	(zone
		(layer "F.Cu")
		(hatch none 0.5)
		(connect_pads
			(clearance 0)
		)
		(min_thickness 0.25)
		(keepout
			(tracks allowed)
			(vias allowed)
			(pads allowed)
			(copperpour allowed)
			(footprints allowed)
		)
		(placement
			(enabled no)
			(sheetname "")
		)
		(fill
			(thermal_gap 0.5)
			(thermal_bridge_width 0.5)
			(island_removal_mode 0)
		)
		(polygon
			(pts
				(xy 411.562042 -276.127718) (xy 411.562042 -275.797518) (xy 413.236664 -275.797518) (xy 413.236664 -276.127718)
			)
		)
	)
	(zone
		(layer "F.Cu")
		(hatch none 0.5)
		(connect_pads
			(clearance 0)
		)
		(min_thickness 0.25)
		(keepout
			(tracks allowed)
			(vias allowed)
			(pads allowed)
			(copperpour allowed)
			(footprints allowed)
		)
		(placement
			(enabled no)
			(sheetname "")
		)
		(fill
			(thermal_gap 0.5)
			(thermal_bridge_width 0.5)
			(island_removal_mode 0)
		)
		(polygon
			(pts
				(xy 346.064078 -334.90027) (xy 339.714078 -334.90027) (xy 339.079078 -335.53527) (xy 339.079078 -340.10727)
				(xy 339.714078 -340.74227) (xy 345.683078 -340.74227) (xy 346.191078 -340.23427) (xy 346.191078 -335.02727)
			)
		)
	)
	(zone
		(layer "F.Cu")
		(hatch none 0.5)
		(connect_pads
			(clearance 0)
		)
		(min_thickness 0.25)
		(keepout
			(tracks allowed)
			(vias allowed)
			(pads allowed)
			(copperpour allowed)
			(footprints not_allowed)
		)
		(placement
			(enabled no)
			(sheetname "")
		)
		(fill
			(thermal_gap 0.5)
			(thermal_bridge_width 0.5)
			(island_removal_mode 0)
		)
		(polygon
			(pts
				(xy 226.44989 -46.999906) (xy 230.650034 -46.999906) (xy 230.650034 -41.999916) (xy 226.44989 -41.999916)
			)
		)
	)
	(zone
		(layer "F.Cu")
		(hatch none 0.5)
		(connect_pads
			(clearance 0)
		)
		(min_thickness 0.25)
		(keepout
			(tracks allowed)
			(vias allowed)
			(pads allowed)
			(copperpour allowed)
			(footprints allowed)
		)
		(placement
			(enabled no)
			(sheetname "")
		)
		(fill
			(thermal_gap 0.5)
			(thermal_bridge_width 0.5)
			(island_removal_mode 0)
		)
		(polygon
			(pts
				(xy 65.893188 -409.042616) (xy 65.893188 -408.038554) (xy 67.28968 -408.038554) (xy 67.28968 -409.042616)
			)
		)
	)
	(zone
		(layer "F.Cu")
		(hatch none 0.5)
		(connect_pads
			(clearance 0)
		)
		(min_thickness 0.25)
		(keepout
			(tracks allowed)
			(vias allowed)
			(pads allowed)
			(copperpour allowed)
			(footprints allowed)
		)
		(placement
			(enabled no)
			(sheetname "")
		)
		(fill
			(thermal_gap 0.5)
			(thermal_bridge_width 0.5)
			(island_removal_mode 0)
		)
		(polygon
			(pts
				(xy 283.661358 -420.401496) (xy 282.537408 -420.401496) (xy 282.537408 -419.666928) (xy 282.537408 -418.331396)
				(xy 283.661358 -418.331396)
			)
		)
	)
	(zone
		(layer "F.Cu")
		(hatch none 0.5)
		(connect_pads
			(clearance 0)
		)
		(min_thickness 0.25)
		(keepout
			(tracks allowed)
			(vias allowed)
			(pads allowed)
			(copperpour allowed)
			(footprints not_allowed)
		)
		(placement
			(enabled no)
			(sheetname "")
		)
		(fill
			(thermal_gap 0.5)
			(thermal_bridge_width 0.5)
			(island_removal_mode 0)
		)
		(polygon
			(pts
				(xy 393.759944 -398.560036) (xy 393.759944 -403.260052) (xy 398.789906 -403.260052) (xy 398.789906 -398.560036)
			)
		)
	)
	(zone
		(layer "F.Cu")
		(hatch none 0.5)
		(connect_pads
			(clearance 0)
		)
		(min_thickness 0.25)
		(keepout
			(tracks allowed)
			(vias allowed)
			(pads allowed)
			(copperpour allowed)
			(footprints allowed)
		)
		(placement
			(enabled no)
			(sheetname "")
		)
		(fill
			(thermal_gap 0.5)
			(thermal_bridge_width 0.5)
			(island_removal_mode 0)
		)
		(polygon
			(pts
				(xy 325.215504 -387.598412) (xy 326.219566 -387.598412) (xy 326.219566 -388.994904) (xy 325.215504 -388.994904)
			)
		)
	)
	(zone
		(layer "F.Cu")
		(hatch none 0.5)
		(connect_pads
			(clearance 0)
		)
		(min_thickness 0.25)
		(keepout
			(tracks allowed)
			(vias allowed)
			(pads allowed)
			(copperpour allowed)
			(footprints allowed)
		)
		(placement
			(enabled no)
			(sheetname "")
		)
		(fill
			(thermal_gap 0.5)
			(thermal_bridge_width 0.5)
			(island_removal_mode 0)
		)
		(polygon
			(pts
				(xy 58.13044 -244.677946) (xy 58.13044 -244.347746) (xy 60.67044 -244.347746) (xy 60.67044 -244.677946)
			)
		)
	)
	(zone
		(layer "F.Cu")
		(hatch none 0.5)
		(connect_pads
			(clearance 0)
		)
		(min_thickness 0.25)
		(keepout
			(tracks allowed)
			(vias allowed)
			(pads allowed)
			(copperpour allowed)
			(footprints allowed)
		)
		(placement
			(enabled no)
			(sheetname "")
		)
		(fill
			(thermal_gap 0.5)
			(thermal_bridge_width 0.5)
			(island_removal_mode 0)
		)
		(polygon
			(pts
				(xy 117.67693 -409.042616) (xy 117.67693 -408.038554) (xy 119.073422 -408.038554) (xy 119.073422 -409.042616)
			)
		)
	)
	(zone
		(layer "F.Cu")
		(hatch none 0.5)
		(connect_pads
			(clearance 0)
		)
		(min_thickness 0.25)
		(keepout
			(tracks allowed)
			(vias allowed)
			(pads allowed)
			(copperpour allowed)
			(footprints allowed)
		)
		(placement
			(enabled no)
			(sheetname "")
		)
		(fill
			(thermal_gap 0.5)
			(thermal_bridge_width 0.5)
			(island_removal_mode 0)
		)
		(polygon
			(pts
				(xy 298.441872 -384.069844) (xy 299.445934 -384.069844) (xy 299.445934 -385.466336) (xy 298.441872 -385.466336)
			)
		)
	)
	(zone
		(layer "F.Cu")
		(hatch none 0.5)
		(connect_pads
			(clearance 0)
		)
		(min_thickness 0.25)
		(keepout
			(tracks not_allowed)
			(vias allowed)
			(pads allowed)
			(copperpour not_allowed)
			(footprints allowed)
		)
		(placement
			(enabled no)
			(sheetname "")
		)
		(fill
			(thermal_gap 0.5)
			(thermal_bridge_width 0.5)
			(island_removal_mode 0)
		)
		(polygon
			(pts
				(xy 64.425576 -10.49528) (xy 64.308228 -10.49528) (xy 64.257428 -10.54608) (xy 64.257428 -11.99388)
				(xy 64.308228 -12.04468) (xy 64.425576 -12.04468) (xy 64.476376 -11.99388) (xy 64.476376 -10.54608)
			)
		)
	)
	(zone
		(layer "F.Cu")
		(hatch none 0.5)
		(connect_pads
			(clearance 0)
		)
		(min_thickness 0.25)
		(keepout
			(tracks allowed)
			(vias allowed)
			(pads allowed)
			(copperpour allowed)
			(footprints allowed)
		)
		(placement
			(enabled no)
			(sheetname "")
		)
		(fill
			(thermal_gap 0.5)
			(thermal_bridge_width 0.5)
			(island_removal_mode 0)
		)
		(polygon
			(pts
				(xy 123.317762 -163.13785) (xy 121.514362 -163.13785) (xy 121.514362 -164.68725) (xy 123.317762 -164.68725)
			)
		)
	)
	(zone
		(layer "F.Cu")
		(hatch none 0.5)
		(connect_pads
			(clearance 0)
		)
		(min_thickness 0.25)
		(keepout
			(tracks allowed)
			(vias allowed)
			(pads allowed)
			(copperpour allowed)
			(footprints allowed)
		)
		(placement
			(enabled no)
			(sheetname "")
		)
		(fill
			(thermal_gap 0.5)
			(thermal_bridge_width 0.5)
			(island_removal_mode 0)
		)
		(polygon
			(pts
				(xy 242.25504 -382.949196) (xy 242.25504 -380.219712) (xy 279.717246 -380.219712) (xy 279.717246 -382.949196)
			)
		)
	)
	(zone
		(layer "F.Cu")
		(hatch none 0.5)
		(connect_pads
			(clearance 0)
		)
		(min_thickness 0.25)
		(keepout
			(tracks allowed)
			(vias allowed)
			(pads allowed)
			(copperpour allowed)
			(footprints allowed)
		)
		(placement
			(enabled no)
			(sheetname "")
		)
		(fill
			(thermal_gap 0.5)
			(thermal_bridge_width 0.5)
			(island_removal_mode 0)
		)
		(polygon
			(pts
				(xy 163.377626 -227.67798) (xy 163.377626 -227.34778) (xy 165.296596 -227.34778) (xy 165.296596 -227.67798)
			)
		)
	)
	(zone
		(layer "F.Cu")
		(hatch none 0.5)
		(connect_pads
			(clearance 0)
		)
		(min_thickness 0.25)
		(keepout
			(tracks not_allowed)
			(vias allowed)
			(pads allowed)
			(copperpour not_allowed)
			(footprints allowed)
		)
		(placement
			(enabled no)
			(sheetname "")
		)
		(fill
			(thermal_gap 0.5)
			(thermal_bridge_width 0.5)
			(island_removal_mode 0)
		)
		(polygon
			(pts
				(xy 324.203314 -334.238346) (xy 324.203314 -334.695038) (xy 324.89902 -334.695038) (xy 324.89902 -334.53451)
				(xy 325.45782 -334.53451) (xy 325.45782 -334.94091) (xy 324.89902 -334.94091) (xy 324.89902 -334.720438)
				(xy 324.203314 -334.720438) (xy 324.203314 -334.847438) (xy 324.65899 -334.847438) (xy 324.65899 -335.234026)
				(xy 324.901306 -335.234026) (xy 325.433182 -335.234026) (xy 325.752714 -334.914494) (xy 325.752714 -334.238346)
			)
		)
	)
	(zone
		(layer "F.Cu")
		(hatch none 0.5)
		(connect_pads
			(clearance 0)
		)
		(min_thickness 0.25)
		(keepout
			(tracks allowed)
			(vias allowed)
			(pads allowed)
			(copperpour allowed)
			(footprints not_allowed)
		)
		(placement
			(enabled no)
			(sheetname "")
		)
		(fill
			(thermal_gap 0.5)
			(thermal_bridge_width 0.5)
			(island_removal_mode 0)
		)
		(polygon
			(pts
				(arc
					(start 110.437422 -431.360072)
					(mid 112.024922 -429.772572)
					(end 113.612422 -431.360072)
				)
				(arc
					(start 113.612422 -431.360072)
					(mid 112.024922 -432.947572)
					(end 110.437422 -431.360072)
				)
			)
		)
	)
	(zone
		(layer "F.Cu")
		(hatch none 0.5)
		(connect_pads
			(clearance 0)
		)
		(min_thickness 0.25)
		(keepout
			(tracks allowed)
			(vias allowed)
			(pads allowed)
			(copperpour allowed)
			(footprints not_allowed)
		)
		(placement
			(enabled no)
			(sheetname "")
		)
		(fill
			(thermal_gap 0.5)
			(thermal_bridge_width 0.5)
			(island_removal_mode 0)
		)
		(polygon
			(pts
				(arc
					(start 465.024978 -51.289966)
					(mid 466.8901 -49.424844)
					(end 468.754968 -51.289966)
				)
				(arc
					(start 468.754968 -51.289966)
					(mid 466.8901 -53.154834)
					(end 465.024978 -51.289966)
				)
			)
		)
	)
	(zone
		(layer "F.Cu")
		(hatch none 0.5)
		(connect_pads
			(clearance 0)
		)
		(min_thickness 0.25)
		(keepout
			(tracks allowed)
			(vias allowed)
			(pads allowed)
			(copperpour allowed)
			(footprints allowed)
		)
		(placement
			(enabled no)
			(sheetname "")
		)
		(fill
			(thermal_gap 0.5)
			(thermal_bridge_width 0.5)
			(island_removal_mode 0)
		)
		(polygon
			(pts
				(xy 306.070508 -265.077702) (xy 306.070508 -264.747502) (xy 308.610508 -264.747502) (xy 308.610508 -265.077702)
			)
		)
	)
	(zone
		(layer "F.Cu")
		(hatch none 0.5)
		(connect_pads
			(clearance 0)
		)
		(min_thickness 0.25)
		(keepout
			(tracks allowed)
			(vias allowed)
			(pads allowed)
			(copperpour allowed)
			(footprints allowed)
		)
		(placement
			(enabled no)
			(sheetname "")
		)
		(fill
			(thermal_gap 0.5)
			(thermal_bridge_width 0.5)
			(island_removal_mode 0)
		)
		(polygon
			(pts
				(xy 163.377626 -218.327986) (xy 163.377626 -217.997786) (xy 165.296596 -217.997786) (xy 165.296596 -218.327986)
			)
		)
	)
	(zone
		(layer "F.Cu")
		(hatch none 0.5)
		(connect_pads
			(clearance 0)
		)
		(min_thickness 0.25)
		(keepout
			(tracks allowed)
			(vias allowed)
			(pads allowed)
			(copperpour allowed)
			(footprints not_allowed)
		)
		(placement
			(enabled no)
			(sheetname "")
		)
		(fill
			(thermal_gap 0.5)
			(thermal_bridge_width 0.5)
			(island_removal_mode 0)
		)
		(polygon
			(pts
				(arc
					(start 393.970002 -304.790094)
					(mid 390.470136 -308.28996)
					(end 386.970016 -304.790094)
				)
				(arc
					(start 386.970016 -304.790094)
					(mid 390.470136 -301.289974)
					(end 393.970002 -304.790094)
				)
			)
		)
	)
	(zone
		(layer "F.Cu")
		(hatch none 0.5)
		(connect_pads
			(clearance 0)
		)
		(min_thickness 0.25)
		(keepout
			(tracks not_allowed)
			(vias allowed)
			(pads allowed)
			(copperpour not_allowed)
			(footprints allowed)
		)
		(placement
			(enabled no)
			(sheetname "")
		)
		(fill
			(thermal_gap 0.5)
			(thermal_bridge_width 0.5)
			(island_removal_mode 0)
		)
		(polygon
			(pts
				(arc
					(start 445.051942 -351.415096)
					(mid 441.952126 -354.514912)
					(end 438.852056 -351.415096)
				)
				(arc
					(start 438.852056 -351.415096)
					(mid 441.952126 -348.315026)
					(end 445.051942 -351.415096)
				)
			)
		)
	)
	(zone
		(layer "F.Cu")
		(hatch none 0.5)
		(connect_pads
			(clearance 0)
		)
		(min_thickness 0.25)
		(keepout
			(tracks allowed)
			(vias allowed)
			(pads allowed)
			(copperpour allowed)
			(footprints allowed)
		)
		(placement
			(enabled no)
			(sheetname "")
		)
		(fill
			(thermal_gap 0.5)
			(thermal_bridge_width 0.5)
			(island_removal_mode 0)
		)
		(polygon
			(pts
				(xy 69.215762 -375.812812) (xy 70.219824 -375.812812) (xy 70.219824 -377.209304) (xy 69.215762 -377.209304)
			)
		)
	)
	(zone
		(layer "F.Cu")
		(hatch none 0.5)
		(connect_pads
			(clearance 0)
		)
		(min_thickness 0.25)
		(keepout
			(tracks not_allowed)
			(vias allowed)
			(pads allowed)
			(copperpour not_allowed)
			(footprints allowed)
		)
		(placement
			(enabled no)
			(sheetname "")
		)
		(fill
			(thermal_gap 0.5)
			(thermal_bridge_width 0.5)
			(island_removal_mode 0)
		)
		(polygon
			(pts
				(arc
					(start 363.024928 -431.360072)
					(mid 359.774998 -434.610002)
					(end 356.525068 -431.360072)
				)
				(arc
					(start 356.525068 -431.360072)
					(mid 359.774998 -428.110142)
					(end 363.024928 -431.360072)
				)
			)
		)
	)
	(zone
		(layer "F.Cu")
		(hatch none 0.5)
		(connect_pads
			(clearance 0)
		)
		(min_thickness 0.25)
		(keepout
			(tracks allowed)
			(vias allowed)
			(pads allowed)
			(copperpour allowed)
			(footprints allowed)
		)
		(placement
			(enabled no)
			(sheetname "")
		)
		(fill
			(thermal_gap 0.5)
			(thermal_bridge_width 0.5)
			(island_removal_mode 0)
		)
		(polygon
			(pts
				(xy 308.66588 -287.692338) (xy 308.66588 -288.022538) (xy 306.12588 -288.022538) (xy 306.12588 -287.692338)
			)
		)
	)
	(zone
		(layer "F.Cu")
		(hatch none 0.5)
		(connect_pads
			(clearance 0)
		)
		(min_thickness 0.25)
		(keepout
			(tracks allowed)
			(vias allowed)
			(pads allowed)
			(copperpour allowed)
			(footprints allowed)
		)
		(placement
			(enabled no)
			(sheetname "")
		)
		(fill
			(thermal_gap 0.5)
			(thermal_bridge_width 0.5)
			(island_removal_mode 0)
		)
		(polygon
			(pts
				(xy 58.13044 -236.17809) (xy 58.13044 -235.84789) (xy 60.67044 -235.84789) (xy 60.67044 -236.17809)
			)
		)
	)
	(zone
		(layer "F.Cu")
		(hatch none 0.5)
		(connect_pads
			(clearance 0)
		)
		(min_thickness 0.25)
		(keepout
			(tracks allowed)
			(vias allowed)
			(pads allowed)
			(copperpour allowed)
			(footprints not_allowed)
		)
		(placement
			(enabled no)
			(sheetname "")
		)
		(fill
			(thermal_gap 0.5)
			(thermal_bridge_width 0.5)
			(island_removal_mode 0)
		)
		(polygon
			(pts
				(arc
					(start 315.587126 -344.814906)
					(mid 317.452248 -342.949784)
					(end 319.317116 -344.814906)
				)
				(arc
					(start 319.317116 -344.814906)
					(mid 317.452248 -346.679774)
					(end 315.587126 -344.814906)
				)
			)
		)
	)
	(zone
		(layer "F.Cu")
		(hatch none 0.5)
		(connect_pads
			(clearance 0)
		)
		(min_thickness 0.25)
		(keepout
			(tracks allowed)
			(vias allowed)
			(pads allowed)
			(copperpour allowed)
			(footprints allowed)
		)
		(placement
			(enabled no)
			(sheetname "")
		)
		(fill
			(thermal_gap 0.5)
			(thermal_bridge_width 0.5)
			(island_removal_mode 0)
		)
		(polygon
			(pts
				(xy 411.317694 -222.57766) (xy 411.317694 -222.24746) (xy 413.236664 -222.24746) (xy 413.236664 -222.57766)
			)
		)
	)
	(zone
		(layer "F.Cu")
		(hatch none 0.5)
		(connect_pads
			(clearance 0)
		)
		(min_thickness 0.25)
		(keepout
			(tracks allowed)
			(vias allowed)
			(pads allowed)
			(copperpour allowed)
			(footprints allowed)
		)
		(placement
			(enabled no)
			(sheetname "")
		)
		(fill
			(thermal_gap 0.5)
			(thermal_bridge_width 0.5)
			(island_removal_mode 0)
		)
		(polygon
			(pts
				(xy 90.399108 -409.042616) (xy 90.399108 -408.038554) (xy 91.7956 -408.038554) (xy 91.7956 -409.042616)
			)
		)
	)
	(zone
		(layer "F.Cu")
		(hatch none 0.5)
		(connect_pads
			(clearance 0)
		)
		(min_thickness 0.25)
		(keepout
			(tracks allowed)
			(vias allowed)
			(pads allowed)
			(copperpour allowed)
			(footprints allowed)
		)
		(placement
			(enabled no)
			(sheetname "")
		)
		(fill
			(thermal_gap 0.5)
			(thermal_bridge_width 0.5)
			(island_removal_mode 0)
		)
		(polygon
			(pts
				(xy 75.262486 -373.561102) (xy 75.262486 -372.55704) (xy 76.658978 -372.55704) (xy 76.658978 -373.561102)
			)
		)
	)
	(zone
		(layer "F.Cu")
		(hatch none 0.5)
		(connect_pads
			(clearance 0)
		)
		(min_thickness 0.25)
		(keepout
			(tracks allowed)
			(vias allowed)
			(pads allowed)
			(copperpour allowed)
			(footprints allowed)
		)
		(placement
			(enabled no)
			(sheetname "")
		)
		(fill
			(thermal_gap 0.5)
			(thermal_bridge_width 0.5)
			(island_removal_mode 0)
		)
		(polygon
			(pts
				(xy 160.56229 -409.042616) (xy 160.56229 -408.038554) (xy 161.958782 -408.038554) (xy 161.958782 -409.042616)
			)
		)
	)
	(zone
		(layer "F.Cu")
		(hatch none 0.5)
		(connect_pads
			(clearance 0)
		)
		(min_thickness 0.25)
		(keepout
			(tracks allowed)
			(vias allowed)
			(pads allowed)
			(copperpour allowed)
			(footprints not_allowed)
		)
		(placement
			(enabled no)
			(sheetname "")
		)
		(fill
			(thermal_gap 0.5)
			(thermal_bridge_width 0.5)
			(island_removal_mode 0)
		)
		(polygon
			(pts
				(xy 197.875906 -347.544898) (xy 176.376076 -347.544898) (xy 176.376076 -357.145082) (xy 197.875906 -357.145082)
			)
		)
	)
	(zone
		(layer "F.Cu")
		(hatch none 0.5)
		(connect_pads
			(clearance 0)
		)
		(min_thickness 0.25)
		(keepout
			(tracks allowed)
			(vias allowed)
			(pads allowed)
			(copperpour allowed)
			(footprints allowed)
		)
		(placement
			(enabled no)
			(sheetname "")
		)
		(fill
			(thermal_gap 0.5)
			(thermal_bridge_width 0.5)
			(island_removal_mode 0)
		)
		(polygon
			(pts
				(xy 139.11961 -409.042616) (xy 139.11961 -408.038554) (xy 140.516102 -408.038554) (xy 140.516102 -409.042616)
			)
		)
	)
	(zone
		(layer "F.Cu")
		(hatch none 0.5)
		(connect_pads
			(clearance 0)
		)
		(min_thickness 0.25)
		(keepout
			(tracks not_allowed)
			(vias allowed)
			(pads allowed)
			(copperpour not_allowed)
			(footprints allowed)
		)
		(placement
			(enabled no)
			(sheetname "")
		)
		(fill
			(thermal_gap 0.5)
			(thermal_bridge_width 0.5)
			(island_removal_mode 0)
		)
		(polygon
			(pts
				(arc
					(start 392.622024 -173.315122)
					(mid 389.521954 -176.415192)
					(end 386.421884 -173.315122)
				)
				(arc
					(start 386.421884 -173.315122)
					(mid 389.521954 -170.215052)
					(end 392.622024 -173.315122)
				)
			)
		)
	)
	(zone
		(layer "F.Cu")
		(hatch none 0.5)
		(connect_pads
			(clearance 0)
		)
		(min_thickness 0.25)
		(keepout
			(tracks allowed)
			(vias allowed)
			(pads allowed)
			(copperpour allowed)
			(footprints allowed)
		)
		(placement
			(enabled no)
			(sheetname "")
		)
		(fill
			(thermal_gap 0.5)
			(thermal_bridge_width 0.5)
			(island_removal_mode 0)
		)
		(polygon
			(pts
				(xy 302.140366 -355.044502) (xy 302.140366 -354.367084) (xy 305.01336 -354.367084) (xy 305.01336 -355.044502)
			)
		)
	)
	(zone
		(layer "F.Cu")
		(hatch none 0.5)
		(connect_pads
			(clearance 0)
		)
		(min_thickness 0.25)
		(keepout
			(tracks allowed)
			(vias allowed)
			(pads allowed)
			(copperpour allowed)
			(footprints allowed)
		)
		(placement
			(enabled no)
			(sheetname "")
		)
		(fill
			(thermal_gap 0.5)
			(thermal_bridge_width 0.5)
			(island_removal_mode 0)
		)
		(polygon
			(pts
				(xy 163.377626 -263.378188) (xy 163.377626 -263.047988) (xy 165.296596 -263.047988) (xy 165.296596 -263.378188)
			)
		)
	)
	(zone
		(layer "F.Cu")
		(hatch none 0.5)
		(connect_pads
			(clearance 0)
		)
		(min_thickness 0.25)
		(keepout
			(tracks allowed)
			(vias allowed)
			(pads allowed)
			(copperpour allowed)
			(footprints not_allowed)
		)
		(placement
			(enabled no)
			(sheetname "")
		)
		(fill
			(thermal_gap 0.5)
			(thermal_bridge_width 0.5)
			(island_removal_mode 0)
		)
		(polygon
			(pts
				(arc
					(start 376.298714 -435.600094)
					(mid 371.298724 -440.600084)
					(end 366.298734 -435.600094)
				)
				(arc
					(start 366.298734 -435.600094)
					(mid 371.298724 -430.600104)
					(end 376.298714 -435.600094)
				)
			)
		)
	)
	(zone
		(layer "F.Cu")
		(hatch none 0.5)
		(connect_pads
			(clearance 0)
		)
		(min_thickness 0.25)
		(keepout
			(tracks not_allowed)
			(vias allowed)
			(pads allowed)
			(copperpour not_allowed)
			(footprints allowed)
		)
		(placement
			(enabled no)
			(sheetname "")
		)
		(fill
			(thermal_gap 0.5)
			(thermal_bridge_width 0.5)
			(island_removal_mode 0)
		)
		(polygon
			(pts
				(arc
					(start 351.151952 -147.904962)
					(mid 348.052136 -151.004778)
					(end 344.952066 -147.904962)
				)
				(arc
					(start 344.952066 -147.904962)
					(mid 348.052136 -144.804892)
					(end 351.151952 -147.904962)
				)
			)
		)
	)
	(zone
		(layer "F.Cu")
		(hatch none 0.5)
		(connect_pads
			(clearance 0)
		)
		(min_thickness 0.25)
		(keepout
			(tracks allowed)
			(vias allowed)
			(pads allowed)
			(copperpour allowed)
			(footprints not_allowed)
		)
		(placement
			(enabled no)
			(sheetname "")
		)
		(fill
			(thermal_gap 0.5)
			(thermal_bridge_width 0.5)
			(island_removal_mode 0)
		)
		(polygon
			(pts
				(arc
					(start 175.731424 -160.50006)
					(mid 167.73144 -168.500044)
					(end 159.731456 -160.50006)
				)
				(arc
					(start 159.731456 -160.50006)
					(mid 167.73144 -152.500076)
					(end 175.731424 -160.50006)
				)
			)
		)
	)
	(zone
		(layer "F.Cu")
		(hatch none 0.5)
		(connect_pads
			(clearance 0)
		)
		(min_thickness 0.25)
		(keepout
			(tracks allowed)
			(vias allowed)
			(pads allowed)
			(copperpour allowed)
			(footprints allowed)
		)
		(placement
			(enabled no)
			(sheetname "")
		)
		(fill
			(thermal_gap 0.5)
			(thermal_bridge_width 0.5)
			(island_removal_mode 0)
		)
		(polygon
			(pts
				(xy 130.2512 -28.0162) (xy 130.2512 -26.4668) (xy 130.2512 -25.776428) (xy 130.550666 -25.476962)
				(xy 131.662424 -25.476962) (xy 131.8768 -25.691338) (xy 131.8768 -26.4668) (xy 131.8768 -28.0162)
				(xy 131.8768 -29.735018) (xy 131.61137 -30.000448) (xy 130.525266 -30.000448) (xy 130.2512 -29.726382)
			)
		)
	)
	(zone
		(layer "F.Cu")
		(hatch none 0.5)
		(connect_pads
			(clearance 0)
		)
		(min_thickness 0.25)
		(keepout
			(tracks allowed)
			(vias allowed)
			(pads allowed)
			(copperpour allowed)
			(footprints allowed)
		)
		(placement
			(enabled no)
			(sheetname "")
		)
		(fill
			(thermal_gap 0.5)
			(thermal_bridge_width 0.5)
			(island_removal_mode 0)
		)
		(polygon
			(pts
				(xy 424.843194 -384.194812) (xy 425.847256 -384.194812) (xy 425.847256 -385.591304) (xy 424.843194 -385.591304)
			)
		)
	)
	(zone
		(layer "F.Cu")
		(hatch none 0.5)
		(connect_pads
			(clearance 0)
		)
		(min_thickness 0.25)
		(keepout
			(tracks allowed)
			(vias allowed)
			(pads allowed)
			(copperpour allowed)
			(footprints not_allowed)
		)
		(placement
			(enabled no)
			(sheetname "")
		)
		(fill
			(thermal_gap 0.5)
			(thermal_bridge_width 0.5)
			(island_removal_mode 0)
		)
		(polygon
			(pts
				(xy 285.78302 -183.50992) (xy 279.58288 -183.50992) (xy 279.58288 -327.609962) (xy 285.78302 -327.609962)
			)
		)
	)
	(zone
		(layer "F.Cu")
		(hatch none 0.5)
		(connect_pads
			(clearance 0)
		)
		(min_thickness 0.25)
		(keepout
			(tracks allowed)
			(vias allowed)
			(pads allowed)
			(copperpour allowed)
			(footprints allowed)
		)
		(placement
			(enabled no)
			(sheetname "")
		)
		(fill
			(thermal_gap 0.5)
			(thermal_bridge_width 0.5)
			(island_removal_mode 0)
		)
		(polygon
			(pts
				(xy 424.843194 -387.598412) (xy 425.847256 -387.598412) (xy 425.847256 -388.994904) (xy 424.843194 -388.994904)
			)
		)
	)
	(zone
		(layer "F.Cu")
		(hatch none 0.5)
		(connect_pads
			(clearance 0)
		)
		(min_thickness 0.25)
		(keepout
			(tracks not_allowed)
			(vias allowed)
			(pads allowed)
			(copperpour not_allowed)
			(footprints allowed)
		)
		(placement
			(enabled no)
			(sheetname "")
		)
		(fill
			(thermal_gap 0.5)
			(thermal_bridge_width 0.5)
			(island_removal_mode 0)
		)
		(polygon
			(pts
				(arc
					(start 17.999964 -435.600094)
					(mid 12.999974 -440.600084)
					(end 7.999984 -435.600094)
				)
				(arc
					(start 7.999984 -435.600094)
					(mid 12.999974 -430.600104)
					(end 17.999964 -435.600094)
				)
			)
		)
	)
	(zone
		(layer "F.Cu")
		(hatch none 0.5)
		(connect_pads
			(clearance 0)
		)
		(min_thickness 0.25)
		(keepout
			(tracks not_allowed)
			(vias allowed)
			(pads allowed)
			(copperpour not_allowed)
			(footprints allowed)
		)
		(placement
			(enabled no)
			(sheetname "")
		)
		(fill
			(thermal_gap 0.5)
			(thermal_bridge_width 0.5)
			(island_removal_mode 0)
		)
		(polygon
			(pts
				(xy 59.830208 -347.4212) (xy 59.830208 -348.382082) (xy 60.072524 -348.382082) (xy 60.072524 -347.4212)
			)
		)
	)
	(zone
		(layer "F.Cu")
		(hatch none 0.5)
		(connect_pads
			(clearance 0)
		)
		(min_thickness 0.25)
		(keepout
			(tracks allowed)
			(vias allowed)
			(pads allowed)
			(copperpour allowed)
			(footprints allowed)
		)
		(placement
			(enabled no)
			(sheetname "")
		)
		(fill
			(thermal_gap 0.5)
			(thermal_bridge_width 0.5)
			(island_removal_mode 0)
		)
		(polygon
			(pts
				(xy 163.634928 -293.978076) (xy 163.634928 -293.647876) (xy 165.296596 -293.647876) (xy 165.296596 -293.978076)
			)
		)
	)
	(zone
		(layer "F.Cu")
		(hatch none 0.5)
		(connect_pads
			(clearance 0)
		)
		(min_thickness 0.25)
		(keepout
			(tracks not_allowed)
			(vias allowed)
			(pads allowed)
			(copperpour not_allowed)
			(footprints allowed)
		)
		(placement
			(enabled no)
			(sheetname "")
		)
		(fill
			(thermal_gap 0.5)
			(thermal_bridge_width 0.5)
			(island_removal_mode 0)
		)
		(polygon
			(pts
				(xy 281.65679 -347.417136) (xy 281.65679 -348.378018) (xy 281.899106 -348.378018) (xy 281.899106 -347.417136)
			)
		)
	)
	(zone
		(layer "F.Cu")
		(hatch none 0.5)
		(connect_pads
			(clearance 0)
		)
		(min_thickness 0.25)
		(keepout
			(tracks not_allowed)
			(vias allowed)
			(pads allowed)
			(copperpour not_allowed)
			(footprints allowed)
		)
		(placement
			(enabled no)
			(sheetname "")
		)
		(fill
			(thermal_gap 0.5)
			(thermal_bridge_width 0.5)
			(island_removal_mode 0)
		)
		(polygon
			(pts
				(arc
					(start 358.086914 -340.315042)
					(mid 359.952036 -338.44992)
					(end 361.816904 -340.315042)
				)
				(arc
					(start 361.816904 -340.315042)
					(mid 359.952036 -342.17991)
					(end 358.086914 -340.315042)
				)
			)
		)
	)
	(zone
		(layer "F.Cu")
		(hatch none 0.5)
		(connect_pads
			(clearance 0)
		)
		(min_thickness 0.25)
		(keepout
			(tracks not_allowed)
			(vias allowed)
			(pads allowed)
			(copperpour not_allowed)
			(footprints allowed)
		)
		(placement
			(enabled no)
			(sheetname "")
		)
		(fill
			(thermal_gap 0.5)
			(thermal_bridge_width 0.5)
			(island_removal_mode 0)
		)
		(polygon
			(pts
				(arc
					(start 332.769972 -304.790094)
					(mid 329.270106 -308.28996)
					(end 325.769986 -304.790094)
				)
				(arc
					(start 325.769986 -304.790094)
					(mid 329.270106 -301.289974)
					(end 332.769972 -304.790094)
				)
			)
		)
	)
	(zone
		(layer "F.Cu")
		(hatch none 0.5)
		(connect_pads
			(clearance 0)
		)
		(min_thickness 0.25)
		(keepout
			(tracks allowed)
			(vias allowed)
			(pads allowed)
			(copperpour allowed)
			(footprints allowed)
		)
		(placement
			(enabled no)
			(sheetname "")
		)
		(fill
			(thermal_gap 0.5)
			(thermal_bridge_width 0.5)
			(island_removal_mode 0)
		)
		(polygon
			(pts
				(xy 163.377626 -233.62793) (xy 163.377626 -233.29773) (xy 165.296596 -233.29773) (xy 165.296596 -233.62793)
			)
		)
	)
	(zone
		(layer "F.Cu")
		(hatch none 0.5)
		(connect_pads
			(clearance 0)
		)
		(min_thickness 0.25)
		(keepout
			(tracks allowed)
			(vias allowed)
			(pads allowed)
			(copperpour allowed)
			(footprints not_allowed)
		)
		(placement
			(enabled no)
			(sheetname "")
		)
		(fill
			(thermal_gap 0.5)
			(thermal_bridge_width 0.5)
			(island_removal_mode 0)
		)
		(polygon
			(pts
				(xy 391.230104 -52.31003) (xy 391.230104 -65.41008) (xy 398.670018 -65.41008) (xy 398.670018 -52.31003)
			)
		)
	)
	(zone
		(layer "F.Cu")
		(hatch none 0.5)
		(connect_pads
			(clearance 0)
		)
		(min_thickness 0.25)
		(keepout
			(tracks allowed)
			(vias allowed)
			(pads allowed)
			(copperpour allowed)
			(footprints allowed)
		)
		(placement
			(enabled no)
			(sheetname "")
		)
		(fill
			(thermal_gap 0.5)
			(thermal_bridge_width 0.5)
			(island_removal_mode 0)
		)
		(polygon
			(pts
				(xy 102.02418 -141.77518) (xy 102.02418 -140.74648) (xy 103.94188 -140.74648) (xy 103.94188 -141.77518)
			)
		)
	)
	(zone
		(layer "F.Cu")
		(hatch none 0.5)
		(connect_pads
			(clearance 0)
		)
		(min_thickness 0.25)
		(keepout
			(tracks allowed)
			(vias allowed)
			(pads allowed)
			(copperpour allowed)
			(footprints allowed)
		)
		(placement
			(enabled no)
			(sheetname "")
		)
		(fill
			(thermal_gap 0.5)
			(thermal_bridge_width 0.5)
			(island_removal_mode 0)
		)
		(polygon
			(pts
				(xy 68.52031 -320.480436) (xy 68.52031 -322.385436) (xy 72.53351 -322.385436) (xy 72.53351 -320.480436)
			)
		)
	)
	(zone
		(layer "F.Cu")
		(hatch none 0.5)
		(connect_pads
			(clearance 0)
		)
		(min_thickness 0.25)
		(keepout
			(tracks allowed)
			(vias allowed)
			(pads allowed)
			(copperpour allowed)
			(footprints allowed)
		)
		(placement
			(enabled no)
			(sheetname "")
		)
		(fill
			(thermal_gap 0.5)
			(thermal_bridge_width 0.5)
			(island_removal_mode 0)
		)
		(polygon
			(pts
				(xy 398.069562 -384.069844) (xy 399.073624 -384.069844) (xy 399.073624 -385.466336) (xy 398.069562 -385.466336)
			)
		)
	)
	(zone
		(layer "F.Cu")
		(hatch none 0.5)
		(connect_pads
			(clearance 0)
		)
		(min_thickness 0.25)
		(keepout
			(tracks allowed)
			(vias allowed)
			(pads allowed)
			(copperpour allowed)
			(footprints allowed)
		)
		(placement
			(enabled no)
			(sheetname "")
		)
		(fill
			(thermal_gap 0.5)
			(thermal_bridge_width 0.5)
			(island_removal_mode 0)
		)
		(polygon
			(pts
				(xy 163.377626 -296.192702) (xy 163.377626 -296.522902) (xy 165.296596 -296.522902) (xy 165.296596 -296.192702)
			)
		)
	)
	(zone
		(layer "F.Cu")
		(hatch none 0.5)
		(connect_pads
			(clearance 0)
		)
		(min_thickness 0.25)
		(keepout
			(tracks allowed)
			(vias allowed)
			(pads allowed)
			(copperpour allowed)
			(footprints not_allowed)
		)
		(placement
			(enabled no)
			(sheetname "")
		)
		(fill
			(thermal_gap 0.5)
			(thermal_bridge_width 0.5)
			(island_removal_mode 0)
		)
		(polygon
			(pts
				(arc
					(start 328.975974 -12.783566)
					(mid 329.009393 -13.224113)
					(end 329.029822 -13.665454)
				)
				(xy 322.284598 -13.665454) (xy 322.284598 -12.783566)
			)
		)
	)
	(zone
		(layer "F.Cu")
		(hatch none 0.5)
		(connect_pads
			(clearance 0)
		)
		(min_thickness 0.25)
		(keepout
			(tracks not_allowed)
			(vias allowed)
			(pads allowed)
			(copperpour not_allowed)
			(footprints allowed)
		)
		(placement
			(enabled no)
			(sheetname "")
		)
		(fill
			(thermal_gap 0.5)
			(thermal_bridge_width 0.5)
			(island_removal_mode 0)
		)
		(polygon
			(pts
				(arc
					(start 320.552064 -344.814906)
					(mid 317.451994 -347.914976)
					(end 314.351924 -344.814906)
				)
				(arc
					(start 314.351924 -344.814906)
					(mid 317.451994 -341.714836)
					(end 320.552064 -344.814906)
				)
			)
		)
	)
	(zone
		(layer "F.Cu")
		(hatch none 0.5)
		(connect_pads
			(clearance 0)
		)
		(min_thickness 0.25)
		(keepout
			(tracks allowed)
			(vias allowed)
			(pads allowed)
			(copperpour allowed)
			(footprints not_allowed)
		)
		(placement
			(enabled no)
			(sheetname "")
		)
		(fill
			(thermal_gap 0.5)
			(thermal_bridge_width 0.5)
			(island_removal_mode 0)
		)
		(polygon
			(pts
				(xy 309.085996 -13.439902) (xy 309.085996 -18.539968) (xy 319.486026 -18.539968) (xy 319.486026 -13.439902)
			)
		)
	)
	(zone
		(layer "F.Cu")
		(hatch none 0.5)
		(connect_pads
			(clearance 0)
		)
		(min_thickness 0.25)
		(keepout
			(tracks not_allowed)
			(vias allowed)
			(pads allowed)
			(copperpour not_allowed)
			(footprints allowed)
		)
		(placement
			(enabled no)
			(sheetname "")
		)
		(fill
			(thermal_gap 0.5)
			(thermal_bridge_width 0.5)
			(island_removal_mode 0)
		)
		(polygon
			(pts
				(xy 421.599614 -351.814892) (xy 421.599614 -352.775774) (xy 421.84193 -352.775774) (xy 421.84193 -351.814892)
			)
		)
	)
	(zone
		(layer "F.Cu")
		(hatch none 0.5)
		(connect_pads
			(clearance 0)
		)
		(min_thickness 0.25)
		(keepout
			(tracks not_allowed)
			(vias allowed)
			(pads allowed)
			(copperpour not_allowed)
			(footprints allowed)
		)
		(placement
			(enabled no)
			(sheetname "")
		)
		(fill
			(thermal_gap 0.5)
			(thermal_bridge_width 0.5)
			(island_removal_mode 0)
		)
		(polygon
			(pts
				(arc
					(start 248.035064 -290.900104)
					(mid 249.900186 -289.034982)
					(end 251.765054 -290.900104)
				)
				(arc
					(start 251.765054 -290.900104)
					(mid 249.900186 -292.764972)
					(end 248.035064 -290.900104)
				)
			)
		)
	)
	(zone
		(layer "F.Cu")
		(hatch none 0.5)
		(connect_pads
			(clearance 0)
		)
		(min_thickness 0.25)
		(keepout
			(tracks allowed)
			(vias allowed)
			(pads allowed)
			(copperpour allowed)
			(footprints allowed)
		)
		(placement
			(enabled no)
			(sheetname "")
		)
		(fill
			(thermal_gap 0.5)
			(thermal_bridge_width 0.5)
			(island_removal_mode 0)
		)
		(polygon
			(pts
				(xy 60.725812 -317.442596) (xy 60.725812 -317.772796) (xy 58.185812 -317.772796) (xy 58.185812 -317.442596)
			)
		)
	)
	(zone
		(layer "F.Cu")
		(hatch none 0.5)
		(connect_pads
			(clearance 0)
		)
		(min_thickness 0.25)
		(keepout
			(tracks allowed)
			(vias allowed)
			(pads allowed)
			(copperpour allowed)
			(footprints not_allowed)
		)
		(placement
			(enabled no)
			(sheetname "")
		)
		(fill
			(thermal_gap 0.5)
			(thermal_bridge_width 0.5)
			(island_removal_mode 0)
		)
		(polygon
			(pts
				(xy 2.999994 -182.060088) (xy 2.999994 -190.215012) (xy 16.199104 -190.215012) (xy 16.199104 -199.053958)
				(xy 2.999994 -199.053958) (xy 2.999994 -320.36004) (xy 11.66495 -320.36004) (xy 11.66495 -329.060048)
				(xy 61.62802 -329.060048) (xy 61.62802 -182.060088)
			)
		)
	)
	(zone
		(layer "F.Cu")
		(hatch none 0.5)
		(connect_pads
			(clearance 0)
		)
		(min_thickness 0.25)
		(keepout
			(tracks allowed)
			(vias allowed)
			(pads allowed)
			(copperpour allowed)
			(footprints allowed)
		)
		(placement
			(enabled no)
			(sheetname "")
		)
		(fill
			(thermal_gap 0.5)
			(thermal_bridge_width 0.5)
			(island_removal_mode 0)
		)
		(polygon
			(pts
				(xy 411.574996 -200.477882) (xy 411.574996 -200.147682) (xy 413.236664 -200.147682) (xy 413.236664 -200.477882)
			)
		)
	)
	(zone
		(layer "F.Cu")
		(hatch none 0.5)
		(connect_pads
			(clearance 0)
		)
		(min_thickness 0.25)
		(keepout
			(tracks allowed)
			(vias allowed)
			(pads allowed)
			(copperpour allowed)
			(footprints allowed)
		)
		(placement
			(enabled no)
			(sheetname "")
		)
		(fill
			(thermal_gap 0.5)
			(thermal_bridge_width 0.5)
			(island_removal_mode 0)
		)
		(polygon
			(pts
				(xy 58.13044 -224.277936) (xy 58.13044 -223.947736) (xy 60.67044 -223.947736) (xy 60.67044 -224.277936)
			)
		)
	)
	(zone
		(layer "F.Cu")
		(hatch none 0.5)
		(connect_pads
			(clearance 0)
		)
		(min_thickness 0.25)
		(keepout
			(tracks not_allowed)
			(vias allowed)
			(pads allowed)
			(copperpour not_allowed)
			(footprints allowed)
		)
		(placement
			(enabled no)
			(sheetname "")
		)
		(fill
			(thermal_gap 0.5)
			(thermal_bridge_width 0.5)
			(island_removal_mode 0)
		)
		(polygon
			(pts
				(arc
					(start 233.849926 -352.49993)
					(mid 236.650022 -349.699834)
					(end 239.450118 -352.49993)
				)
				(arc
					(start 239.450118 -352.49993)
					(mid 236.650022 -355.300026)
					(end 233.849926 -352.49993)
				)
			)
		)
	)
	(zone
		(layer "F.Cu")
		(hatch none 0.5)
		(connect_pads
			(clearance 0)
		)
		(min_thickness 0.25)
		(keepout
			(tracks allowed)
			(vias allowed)
			(pads allowed)
			(copperpour allowed)
			(footprints allowed)
		)
		(placement
			(enabled no)
			(sheetname "")
		)
		(fill
			(thermal_gap 0.5)
			(thermal_bridge_width 0.5)
			(island_removal_mode 0)
		)
		(polygon
			(pts
				(xy 163.377626 -214.927942) (xy 163.377626 -214.597742) (xy 165.296596 -214.597742) (xy 165.296596 -214.927942)
			)
		)
	)
	(zone
		(layer "F.Cu")
		(hatch none 0.5)
		(connect_pads
			(clearance 0)
		)
		(min_thickness 0.25)
		(keepout
			(tracks not_allowed)
			(vias allowed)
			(pads allowed)
			(copperpour not_allowed)
			(footprints allowed)
		)
		(placement
			(enabled no)
			(sheetname "")
		)
		(fill
			(thermal_gap 0.5)
			(thermal_bridge_width 0.5)
			(island_removal_mode 0)
		)
		(polygon
			(pts
				(xy 400.32432 -177.920396) (xy 400.32432 -177.463704) (xy 399.628614 -177.463704) (xy 399.628614 -177.624232)
				(xy 399.069814 -177.624232) (xy 399.069814 -177.217832) (xy 399.628614 -177.217832) (xy 399.628614 -177.438304)
				(xy 400.32432 -177.438304) (xy 400.32432 -177.311304) (xy 399.868644 -177.311304) (xy 399.868644 -176.924716)
				(xy 399.626328 -176.924716) (xy 399.094452 -176.924716) (xy 398.77492 -177.244248) (xy 398.77492 -177.920396)
			)
		)
	)
	(zone
		(layer "F.Cu")
		(hatch none 0.5)
		(connect_pads
			(clearance 0)
		)
		(min_thickness 0.25)
		(keepout
			(tracks allowed)
			(vias allowed)
			(pads allowed)
			(copperpour allowed)
			(footprints allowed)
		)
		(placement
			(enabled no)
			(sheetname "")
		)
		(fill
			(thermal_gap 0.5)
			(thermal_bridge_width 0.5)
			(island_removal_mode 0)
		)
		(polygon
			(pts
				(xy 130.597148 -169.145712) (xy 130.597148 -171.050712) (xy 134.610348 -171.050712) (xy 134.610348 -169.145712)
			)
		)
	)
	(zone
		(layer "F.Cu")
		(hatch none 0.5)
		(connect_pads
			(clearance 0)
		)
		(min_thickness 0.25)
		(keepout
			(tracks allowed)
			(vias allowed)
			(pads allowed)
			(copperpour allowed)
			(footprints allowed)
		)
		(placement
			(enabled no)
			(sheetname "")
		)
		(fill
			(thermal_gap 0.5)
			(thermal_bridge_width 0.5)
			(island_removal_mode 0)
		)
		(polygon
			(pts
				(xy 157.678628 -371.097302) (xy 157.678628 -370.09324) (xy 159.07512 -370.09324) (xy 159.07512 -371.097302)
			)
		)
	)
	(zone
		(layer "F.Cu")
		(hatch none 0.5)
		(connect_pads
			(clearance 0)
		)
		(min_thickness 0.25)
		(keepout
			(tracks allowed)
			(vias allowed)
			(pads allowed)
			(copperpour allowed)
			(footprints allowed)
		)
		(placement
			(enabled no)
			(sheetname "")
		)
		(fill
			(thermal_gap 0.5)
			(thermal_bridge_width 0.5)
			(island_removal_mode 0)
		)
		(polygon
			(pts
				(xy 58.13044 -214.078058) (xy 58.13044 -213.747858) (xy 60.67044 -213.747858) (xy 60.67044 -214.078058)
			)
		)
	)
	(zone
		(layer "F.Cu")
		(hatch none 0.5)
		(connect_pads
			(clearance 0)
		)
		(min_thickness 0.25)
		(keepout
			(tracks not_allowed)
			(vias allowed)
			(pads allowed)
			(copperpour not_allowed)
			(footprints allowed)
		)
		(placement
			(enabled no)
			(sheetname "")
		)
		(fill
			(thermal_gap 0.5)
			(thermal_bridge_width 0.5)
			(island_removal_mode 0)
		)
		(polygon
			(pts
				(xy 168.758108 -52.410106) (xy 170.358308 -52.410106) (xy 170.409108 -52.359306) (xy 170.409108 -52.24018)
				(xy 170.358308 -52.18938) (xy 168.758108 -52.18938) (xy 168.707308 -52.24018) (xy 168.707308 -52.359306)
			)
		)
	)
	(zone
		(layer "F.Cu")
		(hatch none 0.5)
		(connect_pads
			(clearance 0)
		)
		(min_thickness 0.25)
		(keepout
			(tracks allowed)
			(vias allowed)
			(pads allowed)
			(copperpour allowed)
			(footprints allowed)
		)
		(placement
			(enabled no)
			(sheetname "")
		)
		(fill
			(thermal_gap 0.5)
			(thermal_bridge_width 0.5)
			(island_removal_mode 0)
		)
		(polygon
			(pts
				(xy 428.549054 -103.04399) (xy 428.549054 -101.70668) (xy 429.145954 -101.70668) (xy 429.145954 -103.04399)
			)
		)
	)
	(zone
		(layer "F.Cu")
		(hatch none 0.5)
		(connect_pads
			(clearance 0)
		)
		(min_thickness 0.25)
		(keepout
			(tracks allowed)
			(vias allowed)
			(pads allowed)
			(copperpour allowed)
			(footprints allowed)
		)
		(placement
			(enabled no)
			(sheetname "")
		)
		(fill
			(thermal_gap 0.5)
			(thermal_bridge_width 0.5)
			(island_removal_mode 0)
		)
		(polygon
			(pts
				(xy 434.422296 -351.645474) (xy 432.618896 -351.645474) (xy 432.618896 -353.194874) (xy 434.422296 -353.194874)
			)
		)
	)
	(zone
		(layer "F.Cu")
		(hatch none 0.5)
		(connect_pads
			(clearance 0)
		)
		(min_thickness 0.25)
		(keepout
			(tracks allowed)
			(vias allowed)
			(pads allowed)
			(copperpour allowed)
			(footprints not_allowed)
		)
		(placement
			(enabled no)
			(sheetname "")
		)
		(fill
			(thermal_gap 0.5)
			(thermal_bridge_width 0.5)
			(island_removal_mode 0)
		)
		(polygon
			(pts
				(xy 105.220008 -390.180068) (xy 105.220008 -394.880084) (xy 110.24997 -394.880084) (xy 110.24997 -390.180068)
			)
		)
	)
	(zone
		(layer "F.Cu")
		(hatch none 0.5)
		(connect_pads
			(clearance 0)
		)
		(min_thickness 0.25)
		(keepout
			(tracks allowed)
			(vias allowed)
			(pads allowed)
			(copperpour allowed)
			(footprints allowed)
		)
		(placement
			(enabled no)
			(sheetname "")
		)
		(fill
			(thermal_gap 0.5)
			(thermal_bridge_width 0.5)
			(island_removal_mode 0)
		)
		(polygon
			(pts
				(xy 328.39914 4.318) (xy 328.39914 6.43382) (xy 330.55814 6.43382) (xy 330.55814 4.318)
			)
		)
	)
	(zone
		(layer "F.Cu")
		(hatch none 0.5)
		(connect_pads
			(clearance 0)
		)
		(min_thickness 0.25)
		(keepout
			(tracks allowed)
			(vias allowed)
			(pads allowed)
			(copperpour allowed)
			(footprints not_allowed)
		)
		(placement
			(enabled no)
			(sheetname "")
		)
		(fill
			(thermal_gap 0.5)
			(thermal_bridge_width 0.5)
			(island_removal_mode 0)
		)
		(polygon
			(pts
				(xy 352.817938 -254.88011) (xy 352.817938 -262.880094) (xy 366.917986 -262.880094) (xy 366.917986 -254.88011)
			)
		)
	)
	(zone
		(layer "F.Cu")
		(hatch none 0.5)
		(connect_pads
			(clearance 0)
		)
		(min_thickness 0.25)
		(keepout
			(tracks not_allowed)
			(vias allowed)
			(pads allowed)
			(copperpour not_allowed)
			(footprints allowed)
		)
		(placement
			(enabled no)
			(sheetname "")
		)
		(fill
			(thermal_gap 0.5)
			(thermal_bridge_width 0.5)
			(island_removal_mode 0)
		)
		(polygon
			(pts
				(xy 420.949882 -360.207814) (xy 420.949882 -360.055414) (xy 417.08832 -360.055414) (xy 417.08832 -360.207814)
				(xy 420.797482 -360.207814)
			)
		)
	)
	(zone
		(layer "F.Cu")
		(hatch none 0.5)
		(connect_pads
			(clearance 0)
		)
		(min_thickness 0.25)
		(keepout
			(tracks allowed)
			(vias allowed)
			(pads allowed)
			(copperpour allowed)
			(footprints allowed)
		)
		(placement
			(enabled no)
			(sheetname "")
		)
		(fill
			(thermal_gap 0.5)
			(thermal_bridge_width 0.5)
			(island_removal_mode 0)
		)
		(polygon
			(pts
				(xy 308.66588 -311.492392) (xy 308.66588 -311.822592) (xy 306.12588 -311.822592) (xy 306.12588 -311.492392)
			)
		)
	)
	(zone
		(layer "F.Cu")
		(hatch none 0.5)
		(connect_pads
			(clearance 0)
		)
		(min_thickness 0.25)
		(keepout
			(tracks allowed)
			(vias allowed)
			(pads allowed)
			(copperpour allowed)
			(footprints not_allowed)
		)
		(placement
			(enabled no)
			(sheetname "")
		)
		(fill
			(thermal_gap 0.5)
			(thermal_bridge_width 0.5)
			(island_removal_mode 0)
		)
		(polygon
			(pts
				(xy 263.151874 -351.605088) (xy 269.352014 -351.605088) (xy 269.352014 -350.665034) (xy 271.132046 -350.665034)
				(xy 271.132046 -344.41511) (xy 270.542258 -344.41511) (xy 270.542258 -342.914986) (xy 263.151874 -342.914986)
			)
		)
	)
	(zone
		(layer "F.Cu")
		(hatch none 0.5)
		(connect_pads
			(clearance 0)
		)
		(min_thickness 0.25)
		(keepout
			(tracks allowed)
			(vias allowed)
			(pads allowed)
			(copperpour allowed)
			(footprints allowed)
		)
		(placement
			(enabled no)
			(sheetname "")
		)
		(fill
			(thermal_gap 0.5)
			(thermal_bridge_width 0.5)
			(island_removal_mode 0)
		)
		(polygon
			(pts
				(xy 411.317694 -235.327698) (xy 411.317694 -234.997498) (xy 413.236664 -234.997498) (xy 413.236664 -235.327698)
			)
		)
	)
	(zone
		(layer "F.Cu")
		(hatch none 0.5)
		(connect_pads
			(clearance 0)
		)
		(min_thickness 0.25)
		(keepout
			(tracks allowed)
			(vias allowed)
			(pads allowed)
			(copperpour allowed)
			(footprints allowed)
		)
		(placement
			(enabled no)
			(sheetname "")
		)
		(fill
			(thermal_gap 0.5)
			(thermal_bridge_width 0.5)
			(island_removal_mode 0)
		)
		(polygon
			(pts
				(xy 163.377626 -314.89269) (xy 163.377626 -315.22289) (xy 165.296596 -315.22289) (xy 165.296596 -314.89269)
			)
		)
	)
	(zone
		(layer "F.Cu")
		(hatch none 0.5)
		(connect_pads
			(clearance 0)
		)
		(min_thickness 0.25)
		(keepout
			(tracks allowed)
			(vias allowed)
			(pads allowed)
			(copperpour allowed)
			(footprints allowed)
		)
		(placement
			(enabled no)
			(sheetname "")
		)
		(fill
			(thermal_gap 0.5)
			(thermal_bridge_width 0.5)
			(island_removal_mode 0)
		)
		(polygon
			(pts
				(xy 285.437834 -416.078162) (xy 285.437834 -414.902904) (xy 286.402018 -414.902904) (xy 286.402018 -416.078162)
			)
		)
	)
	(zone
		(layer "F.Cu")
		(hatch none 0.5)
		(connect_pads
			(clearance 0)
		)
		(min_thickness 0.25)
		(keepout
			(tracks allowed)
			(vias allowed)
			(pads allowed)
			(copperpour allowed)
			(footprints allowed)
		)
		(placement
			(enabled no)
			(sheetname "")
		)
		(fill
			(thermal_gap 0.5)
			(thermal_bridge_width 0.5)
			(island_removal_mode 0)
		)
		(polygon
			(pts
				(xy 322.808854 -320.45402) (xy 322.808854 -322.35902) (xy 326.822054 -322.35902) (xy 326.822054 -320.45402)
			)
		)
	)
	(zone
		(layer "F.Cu")
		(hatch none 0.5)
		(connect_pads
			(clearance 0)
		)
		(min_thickness 0.25)
		(keepout
			(tracks allowed)
			(vias allowed)
			(pads allowed)
			(copperpour allowed)
			(footprints allowed)
		)
		(placement
			(enabled no)
			(sheetname "")
		)
		(fill
			(thermal_gap 0.5)
			(thermal_bridge_width 0.5)
			(island_removal_mode 0)
		)
		(polygon
			(pts
				(xy 191.06007 -25.052782) (xy 191.06007 -24.727916) (xy 191.384936 -24.727916) (xy 191.384936 -25.052782)
			)
		)
	)
	(zone
		(layer "F.Cu")
		(hatch none 0.5)
		(connect_pads
			(clearance 0)
		)
		(min_thickness 0.25)
		(keepout
			(tracks allowed)
			(vias allowed)
			(pads allowed)
			(copperpour allowed)
			(footprints allowed)
		)
		(placement
			(enabled no)
			(sheetname "")
		)
		(fill
			(thermal_gap 0.5)
			(thermal_bridge_width 0.5)
			(island_removal_mode 0)
		)
		(polygon
			(pts
				(xy 386.668518 -183.083454) (xy 393.018518 -183.083454) (xy 393.653518 -182.448454) (xy 393.653518 -177.876454)
				(xy 393.018518 -177.241454) (xy 387.049518 -177.241454) (xy 386.541518 -177.749454) (xy 386.541518 -182.956454)
			)
		)
	)
	(zone
		(layer "F.Cu")
		(hatch none 0.5)
		(connect_pads
			(clearance 0)
		)
		(min_thickness 0.25)
		(keepout
			(tracks allowed)
			(vias allowed)
			(pads allowed)
			(copperpour allowed)
			(footprints allowed)
		)
		(placement
			(enabled no)
			(sheetname "")
		)
		(fill
			(thermal_gap 0.5)
			(thermal_bridge_width 0.5)
			(island_removal_mode 0)
		)
		(polygon
			(pts
				(xy 426.095668 -351.620074) (xy 424.292268 -351.620074) (xy 424.292268 -353.169474) (xy 426.095668 -353.169474)
			)
		)
	)
	(zone
		(layer "F.Cu")
		(hatch none 0.5)
		(connect_pads
			(clearance 0)
		)
		(min_thickness 0.25)
		(keepout
			(tracks allowed)
			(vias allowed)
			(pads allowed)
			(copperpour allowed)
			(footprints allowed)
		)
		(placement
			(enabled no)
			(sheetname "")
		)
		(fill
			(thermal_gap 0.5)
			(thermal_bridge_width 0.5)
			(island_removal_mode 0)
		)
		(polygon
			(pts
				(xy 324.434454 -223.33331) (xy 325.425054 -223.33331) (xy 328.015854 -225.92411) (xy 328.015854 -260.31571)
				(xy 327.380854 -260.95071) (xy 327.380854 -261.25551) (xy 327.533254 -261.40791) (xy 327.761854 -261.40791)
				(xy 328.346054 -261.99211) (xy 328.346054 -292.21811) (xy 326.898254 -293.66591) (xy 324.249542 -293.66591)
				(xy 323.895974 -293.312342) (xy 323.895974 -226.66579) (xy 324.434454 -226.12731)
			)
		)
	)
	(zone
		(layer "F.Cu")
		(hatch none 0.5)
		(connect_pads
			(clearance 0)
		)
		(min_thickness 0.25)
		(keepout
			(tracks allowed)
			(vias allowed)
			(pads allowed)
			(copperpour allowed)
			(footprints allowed)
		)
		(placement
			(enabled no)
			(sheetname "")
		)
		(fill
			(thermal_gap 0.5)
			(thermal_bridge_width 0.5)
			(island_removal_mode 0)
		)
		(polygon
			(pts
				(xy 163.634928 -209.82813) (xy 163.634928 -209.49793) (xy 165.296596 -209.49793) (xy 165.296596 -209.82813)
			)
		)
	)
	(zone
		(layer "F.Cu")
		(hatch none 0.5)
		(connect_pads
			(clearance 0)
		)
		(min_thickness 0.25)
		(keepout
			(tracks not_allowed)
			(vias allowed)
			(pads allowed)
			(copperpour not_allowed)
			(footprints allowed)
		)
		(placement
			(enabled no)
			(sheetname "")
		)
		(fill
			(thermal_gap 0.5)
			(thermal_bridge_width 0.5)
			(island_removal_mode 0)
		)
		(polygon
			(pts
				(xy 153.953718 -58.163206) (xy 156.042614 -58.163206) (xy 156.042614 -57.15) (xy 155.899866 -57.15)
				(xy 155.899866 -58.020458) (xy 154.096466 -58.020458) (xy 154.096466 -57.144158) (xy 153.953718 -57.144158)
			)
		)
	)
	(zone
		(layer "F.Cu")
		(hatch none 0.5)
		(connect_pads
			(clearance 0)
		)
		(min_thickness 0.25)
		(keepout
			(tracks not_allowed)
			(vias allowed)
			(pads allowed)
			(copperpour not_allowed)
			(footprints allowed)
		)
		(placement
			(enabled no)
			(sheetname "")
		)
		(fill
			(thermal_gap 0.5)
			(thermal_bridge_width 0.5)
			(island_removal_mode 0)
		)
		(polygon
			(pts
				(xy 306.65039 -347.417136) (xy 306.65039 -348.378018) (xy 306.892706 -348.378018) (xy 306.892706 -347.417136)
			)
		)
	)
	(zone
		(layer "F.Cu")
		(hatch none 0.5)
		(connect_pads
			(clearance 0)
		)
		(min_thickness 0.25)
		(keepout
			(tracks allowed)
			(vias allowed)
			(pads allowed)
			(copperpour allowed)
			(footprints allowed)
		)
		(placement
			(enabled no)
			(sheetname "")
		)
		(fill
			(thermal_gap 0.5)
			(thermal_bridge_width 0.5)
			(island_removal_mode 0)
		)
		(polygon
			(pts
				(xy 180.0098 -54.371748) (xy 180.0098 -52.695348) (xy 181.0512 -52.695348) (xy 181.0512 -54.371748)
			)
		)
	)
	(zone
		(layer "F.Cu")
		(hatch none 0.5)
		(connect_pads
			(clearance 0)
		)
		(min_thickness 0.25)
		(keepout
			(tracks allowed)
			(vias allowed)
			(pads allowed)
			(copperpour allowed)
			(footprints allowed)
		)
		(placement
			(enabled no)
			(sheetname "")
		)
		(fill
			(thermal_gap 0.5)
			(thermal_bridge_width 0.5)
			(island_removal_mode 0)
		)
		(polygon
			(pts
				(xy 90.378788 -146.044158) (xy 90.378788 -144.710912) (xy 90.733118 -144.710912) (xy 90.733118 -146.044158)
			)
		)
	)
	(zone
		(layer "F.Cu")
		(hatch none 0.5)
		(connect_pads
			(clearance 0)
		)
		(min_thickness 0.25)
		(keepout
			(tracks allowed)
			(vias allowed)
			(pads allowed)
			(copperpour allowed)
			(footprints allowed)
		)
		(placement
			(enabled no)
			(sheetname "")
		)
		(fill
			(thermal_gap 0.5)
			(thermal_bridge_width 0.5)
			(island_removal_mode 0)
		)
		(polygon
			(pts
				(xy 60.344812 -218.842844) (xy 60.344812 -219.173044) (xy 57.804812 -219.173044) (xy 57.804812 -218.842844)
			)
		)
	)
	(zone
		(layer "F.Cu")
		(hatch none 0.5)
		(connect_pads
			(clearance 0)
		)
		(min_thickness 0.25)
		(keepout
			(tracks allowed)
			(vias allowed)
			(pads allowed)
			(copperpour allowed)
			(footprints allowed)
		)
		(placement
			(enabled no)
			(sheetname "")
		)
		(fill
			(thermal_gap 0.5)
			(thermal_bridge_width 0.5)
			(island_removal_mode 0)
		)
		(polygon
			(pts
				(xy 357.743252 -384.194812) (xy 358.747314 -384.194812) (xy 358.747314 -385.591304) (xy 357.743252 -385.591304)
			)
		)
	)
	(zone
		(layer "F.Cu")
		(hatch none 0.5)
		(connect_pads
			(clearance 0)
		)
		(min_thickness 0.25)
		(keepout
			(tracks allowed)
			(vias allowed)
			(pads allowed)
			(copperpour allowed)
			(footprints allowed)
		)
		(placement
			(enabled no)
			(sheetname "")
		)
		(fill
			(thermal_gap 0.5)
			(thermal_bridge_width 0.5)
			(island_removal_mode 0)
		)
		(polygon
			(pts
				(xy 90.578686 -371.097302) (xy 90.578686 -370.09324) (xy 91.975178 -370.09324) (xy 91.975178 -371.097302)
			)
		)
	)
	(zone
		(layer "F.Cu")
		(hatch none 0.5)
		(connect_pads
			(clearance 0)
		)
		(min_thickness 0.25)
		(keepout
			(tracks not_allowed)
			(vias allowed)
			(pads allowed)
			(copperpour not_allowed)
			(footprints allowed)
		)
		(placement
			(enabled no)
			(sheetname "")
		)
		(fill
			(thermal_gap 0.5)
			(thermal_bridge_width 0.5)
			(island_removal_mode 0)
		)
		(polygon
			(pts
				(arc
					(start 36.548314 -416.601402)
					(mid 35.880294 -416.601402)
					(end 36.548314 -416.601402)
				)
			)
		)
	)
	(zone
		(layer "F.Cu")
		(hatch none 0.5)
		(connect_pads
			(clearance 0)
		)
		(min_thickness 0.25)
		(keepout
			(tracks allowed)
			(vias allowed)
			(pads allowed)
			(copperpour allowed)
			(footprints allowed)
		)
		(placement
			(enabled no)
			(sheetname "")
		)
		(fill
			(thermal_gap 0.5)
			(thermal_bridge_width 0.5)
			(island_removal_mode 0)
		)
		(polygon
			(pts
				(xy 58.13044 -242.977924) (xy 58.13044 -242.647724) (xy 60.67044 -242.647724) (xy 60.67044 -242.977924)
			)
		)
	)
	(zone
		(layer "F.Cu")
		(hatch none 0.5)
		(connect_pads
			(clearance 0)
		)
		(min_thickness 0.25)
		(keepout
			(tracks allowed)
			(vias allowed)
			(pads allowed)
			(copperpour allowed)
			(footprints allowed)
		)
		(placement
			(enabled no)
			(sheetname "")
		)
		(fill
			(thermal_gap 0.5)
			(thermal_bridge_width 0.5)
			(island_removal_mode 0)
		)
		(polygon
			(pts
				(xy 64.326262 -347.226382) (xy 62.522862 -347.226382) (xy 62.522862 -348.775782) (xy 64.326262 -348.775782)
			)
		)
	)
	(zone
		(layer "F.Cu")
		(hatch none 0.5)
		(connect_pads
			(clearance 0)
		)
		(min_thickness 0.25)
		(keepout
			(tracks allowed)
			(vias allowed)
			(pads allowed)
			(copperpour allowed)
			(footprints not_allowed)
		)
		(placement
			(enabled no)
			(sheetname "")
		)
		(fill
			(thermal_gap 0.5)
			(thermal_bridge_width 0.5)
			(island_removal_mode 0)
		)
		(polygon
			(pts
				(arc
					(start 229.430326 -388.161784)
					(mid 225.430334 -392.161776)
					(end 221.430342 -388.161784)
				)
				(arc
					(start 221.430342 -388.161784)
					(mid 225.430334 -384.161792)
					(end 229.430326 -388.161784)
				)
			)
		)
	)
	(zone
		(layers "F.Cu" "B.Cu")
		(hatch none 0.5)
		(connect_pads
			(clearance 0)
		)
		(min_thickness 0.25)
		(keepout
			(tracks not_allowed)
			(vias allowed)
			(pads allowed)
			(copperpour not_allowed)
			(footprints allowed)
		)
		(placement
			(enabled no)
			(sheetname "")
		)
		(fill yes
			(thermal_gap 0.5)
			(thermal_bridge_width 0.5)
			(island_removal_mode 0)
		)
		(polygon
			(pts
				(arc
					(start 334.510888 -303.817528)
					(mid 333.842868 -303.817528)
					(end 334.510888 -303.817528)
				)
			)
		)
	)
	(zone
		(layers "F.Cu" "B.Cu")
		(hatch none 0.5)
		(connect_pads
			(clearance 0)
		)
		(min_thickness 0.25)
		(keepout
			(tracks allowed)
			(vias allowed)
			(pads allowed)
			(copperpour allowed)
			(footprints not_allowed)
		)
		(placement
			(enabled no)
			(sheetname "")
		)
		(fill yes
			(thermal_gap 0.5)
			(thermal_bridge_width 0.5)
			(island_removal_mode 0)
		)
		(polygon
			(pts
				(arc
					(start 233.884978 -79.149956)
					(mid 235.89996 -84.950265)
					(end 237.914942 -79.149956)
				)
			)
		)
	)
	(zone
		(layers "F.Cu" "B.Cu")
		(hatch none 0.5)
		(connect_pads
			(clearance 0)
		)
		(min_thickness 0.25)
		(keepout
			(tracks not_allowed)
			(vias allowed)
			(pads allowed)
			(copperpour not_allowed)
			(footprints allowed)
		)
		(placement
			(enabled no)
			(sheetname "")
		)
		(fill yes
			(thermal_gap 0.5)
			(thermal_bridge_width 0.5)
			(island_removal_mode 0)
		)
		(polygon
			(pts
				(arc
					(start 79.908146 -309.504588)
					(mid 79.240126 -309.504588)
					(end 79.908146 -309.504588)
				)
			)
		)
	)
	(zone
		(layers "F.Cu" "B.Cu")
		(hatch none 0.5)
		(connect_pads
			(clearance 0)
		)
		(min_thickness 0.25)
		(keepout
			(tracks not_allowed)
			(vias allowed)
			(pads allowed)
			(copperpour not_allowed)
			(footprints allowed)
		)
		(placement
			(enabled no)
			(sheetname "")
		)
		(fill yes
			(thermal_gap 0.5)
			(thermal_bridge_width 0.5)
			(island_removal_mode 0)
		)
		(polygon
			(pts
				(arc
					(start 79.908146 -308.640988)
					(mid 79.240126 -308.640988)
					(end 79.908146 -308.640988)
				)
			)
		)
	)
	(zone
		(layers "F.Cu" "B.Cu")
		(hatch none 0.5)
		(connect_pads
			(clearance 0)
		)
		(min_thickness 0.25)
		(keepout
			(tracks not_allowed)
			(vias allowed)
			(pads allowed)
			(copperpour not_allowed)
			(footprints allowed)
		)
		(placement
			(enabled no)
			(sheetname "")
		)
		(fill yes
			(thermal_gap 0.5)
			(thermal_bridge_width 0.5)
			(island_removal_mode 0)
		)
		(polygon
			(pts
				(arc
					(start 49.528476 -416.573208)
					(mid 48.860456 -416.573208)
					(end 49.528476 -416.573208)
				)
			)
		)
	)
	(zone
		(layers "F.Cu" "B.Cu")
		(hatch none 0.5)
		(connect_pads
			(clearance 0)
		)
		(min_thickness 0.25)
		(keepout
			(tracks not_allowed)
			(vias allowed)
			(pads allowed)
			(copperpour not_allowed)
			(footprints allowed)
		)
		(placement
			(enabled no)
			(sheetname "")
		)
		(fill yes
			(thermal_gap 0.5)
			(thermal_bridge_width 0.5)
			(island_removal_mode 0)
		)
		(polygon
			(pts
				(arc
					(start 334.510888 -304.681128)
					(mid 333.842868 -304.681128)
					(end 334.510888 -304.681128)
				)
			)
		)
	)
	(zone
		(layers "F.Cu" "B.Cu")
		(hatch none 0.5)
		(connect_pads
			(clearance 0)
		)
		(min_thickness 0.25)
		(keepout
			(tracks not_allowed)
			(vias allowed)
			(pads allowed)
			(copperpour not_allowed)
			(footprints allowed)
		)
		(placement
			(enabled no)
			(sheetname "")
		)
		(fill yes
			(thermal_gap 0.5)
			(thermal_bridge_width 0.5)
			(island_removal_mode 0)
		)
		(polygon
			(pts
				(arc
					(start 342.234012 -308.439566)
					(mid 341.565992 -308.439566)
					(end 342.234012 -308.439566)
				)
			)
		)
	)
	(zone
		(layers "F.Cu" "B.Cu")
		(hatch none 0.5)
		(connect_pads
			(clearance 0)
		)
		(min_thickness 0.25)
		(keepout
			(tracks not_allowed)
			(vias allowed)
			(pads allowed)
			(copperpour not_allowed)
			(footprints allowed)
		)
		(placement
			(enabled no)
			(sheetname "")
		)
		(fill yes
			(thermal_gap 0.5)
			(thermal_bridge_width 0.5)
			(island_removal_mode 0)
		)
		(polygon
			(pts
				(arc
					(start 99.641406 -310.603646)
					(mid 98.973386 -310.603646)
					(end 99.641406 -310.603646)
				)
			)
		)
	)
	(zone
		(layers "F.Cu" "B.Cu")
		(hatch none 0.5)
		(connect_pads
			(clearance 0)
		)
		(min_thickness 0.25)
		(keepout
			(tracks not_allowed)
			(vias allowed)
			(pads allowed)
			(copperpour not_allowed)
			(footprints allowed)
		)
		(placement
			(enabled no)
			(sheetname "")
		)
		(fill yes
			(thermal_gap 0.5)
			(thermal_bridge_width 0.5)
			(island_removal_mode 0)
		)
		(polygon
			(pts
				(arc
					(start 99.04603 -314.133738)
					(mid 98.37801 -314.133738)
					(end 99.04603 -314.133738)
				)
			)
		)
	)
	(zone
		(layers "F.Cu" "B.Cu")
		(hatch none 0.5)
		(connect_pads
			(clearance 0)
		)
		(min_thickness 0.25)
		(keepout
			(tracks not_allowed)
			(vias allowed)
			(pads allowed)
			(copperpour not_allowed)
			(footprints allowed)
		)
		(placement
			(enabled no)
			(sheetname "")
		)
		(fill yes
			(thermal_gap 0.5)
			(thermal_bridge_width 0.5)
			(island_removal_mode 0)
		)
		(polygon
			(pts
				(arc
					(start 94.854014 -308.47157)
					(mid 94.185994 -308.47157)
					(end 94.854014 -308.47157)
				)
			)
		)
	)
	(zone
		(layers "F.Cu" "B.Cu")
		(hatch none 0.5)
		(connect_pads
			(clearance 0)
		)
		(min_thickness 0.25)
		(keepout
			(tracks not_allowed)
			(vias allowed)
			(pads allowed)
			(copperpour not_allowed)
			(footprints allowed)
		)
		(placement
			(enabled no)
			(sheetname "")
		)
		(fill yes
			(thermal_gap 0.5)
			(thermal_bridge_width 0.5)
			(island_removal_mode 0)
		)
		(polygon
			(pts
				(arc
					(start 341.211154 -305.569366)
					(mid 340.543134 -305.569366)
					(end 341.211154 -305.569366)
				)
			)
		)
	)
	(zone
		(layers "F.Cu" "B.Cu")
		(hatch none 0.5)
		(connect_pads
			(clearance 0)
		)
		(min_thickness 0.25)
		(keepout
			(tracks not_allowed)
			(vias allowed)
			(pads allowed)
			(copperpour not_allowed)
			(footprints allowed)
		)
		(placement
			(enabled no)
			(sheetname "")
		)
		(fill yes
			(thermal_gap 0.5)
			(thermal_bridge_width 0.5)
			(island_removal_mode 0)
		)
		(polygon
			(pts
				(arc
					(start 49.528476 -417.436808)
					(mid 48.860456 -417.436808)
					(end 49.528476 -417.436808)
				)
			)
		)
	)
	(zone
		(layers "F.Cu" "B.Cu")
		(hatch none 0.5)
		(connect_pads
			(clearance 0)
		)
		(min_thickness 0.25)
		(keepout
			(tracks not_allowed)
			(vias allowed)
			(pads allowed)
			(copperpour not_allowed)
			(footprints allowed)
		)
		(placement
			(enabled no)
			(sheetname "")
		)
		(fill yes
			(thermal_gap 0.5)
			(thermal_bridge_width 0.5)
			(island_removal_mode 0)
		)
		(polygon
			(pts
				(arc
					(start 233.884978 -79.149956)
					(mid 235.89996 -84.950265)
					(end 237.914942 -79.149956)
				)
			)
		)
	)
	(zone
		(layers "F.Cu" "B.Cu")
		(hatch none 0.5)
		(connect_pads
			(clearance 0)
		)
		(min_thickness 0.25)
		(keepout
			(tracks not_allowed)
			(vias allowed)
			(pads allowed)
			(copperpour not_allowed)
			(footprints allowed)
		)
		(placement
			(enabled no)
			(sheetname "")
		)
		(fill yes
			(thermal_gap 0.5)
			(thermal_bridge_width 0.5)
			(island_removal_mode 0)
		)
		(polygon
			(pts
				(arc
					(start 348.488 -311.513728)
					(mid 347.81998 -311.513728)
					(end 348.488 -311.513728)
				)
			)
		)
	)
	(zone
		(layers "F.Cu" "B.Cu")
		(hatch none 0.5)
		(connect_pads
			(clearance 0)
		)
		(min_thickness 0.25)
		(keepout
			(tracks not_allowed)
			(vias allowed)
			(pads allowed)
			(copperpour not_allowed)
			(footprints allowed)
		)
		(placement
			(enabled no)
			(sheetname "")
		)
		(fill yes
			(thermal_gap 0.5)
			(thermal_bridge_width 0.5)
			(island_removal_mode 0)
		)
		(polygon
			(pts
				(arc
					(start 348.488 -310.650128)
					(mid 347.81998 -310.650128)
					(end 348.488 -310.650128)
				)
			)
		)
	)
	(zone
		(layers "F.Cu" "B.Cu")
		(hatch none 0.5)
		(connect_pads
			(clearance 0)
		)
		(min_thickness 0.25)
		(keepout
			(tracks not_allowed)
			(vias allowed)
			(pads allowed)
			(copperpour not_allowed)
			(footprints allowed)
		)
		(placement
			(enabled no)
			(sheetname "")
		)
		(fill yes
			(thermal_gap 0.5)
			(thermal_bridge_width 0.5)
			(island_removal_mode 0)
		)
		(polygon
			(pts
				(arc
					(start 93.990414 -308.47157)
					(mid 93.322394 -308.47157)
					(end 93.990414 -308.47157)
				)
			)
		)
	)
	(zone
		(layers "F.Cu" "B.Cu")
		(hatch none 0.5)
		(connect_pads
			(clearance 0)
		)
		(min_thickness 0.25)
		(keepout
			(tracks not_allowed)
			(vias allowed)
			(pads allowed)
			(copperpour not_allowed)
			(footprints allowed)
		)
		(placement
			(enabled no)
			(sheetname "")
		)
		(fill yes
			(thermal_gap 0.5)
			(thermal_bridge_width 0.5)
			(island_removal_mode 0)
		)
		(polygon
			(pts
				(arc
					(start 99.641406 -309.740046)
					(mid 98.973386 -309.740046)
					(end 99.641406 -309.740046)
				)
			)
		)
	)
	(zone
		(layers "F.Cu" "B.Cu")
		(hatch none 0.5)
		(connect_pads
			(clearance 0)
		)
		(min_thickness 0.25)
		(keepout
			(tracks not_allowed)
			(vias allowed)
			(pads allowed)
			(copperpour not_allowed)
			(footprints allowed)
		)
		(placement
			(enabled no)
			(sheetname "")
		)
		(fill yes
			(thermal_gap 0.5)
			(thermal_bridge_width 0.5)
			(island_removal_mode 0)
		)
		(polygon
			(pts
				(arc
					(start 342.234012 -309.303166)
					(mid 341.565992 -309.303166)
					(end 342.234012 -309.303166)
				)
			)
		)
	)
	(zone
		(layers "F.Cu" "B.Cu")
		(hatch none 0.5)
		(connect_pads
			(clearance 0)
		)
		(min_thickness 0.25)
		(keepout
			(tracks not_allowed)
			(vias allowed)
			(pads allowed)
			(copperpour not_allowed)
			(footprints allowed)
		)
		(placement
			(enabled no)
			(sheetname "")
		)
		(fill yes
			(thermal_gap 0.5)
			(thermal_bridge_width 0.5)
			(island_removal_mode 0)
		)
		(polygon
			(pts
				(arc
					(start 341.211154 -306.432966)
					(mid 340.543134 -306.432966)
					(end 341.211154 -306.432966)
				)
			)
		)
	)
	(zone
		(layers "F.Cu" "B.Cu")
		(hatch none 0.5)
		(connect_pads
			(clearance 0)
		)
		(min_thickness 0.25)
		(keepout
			(tracks not_allowed)
			(vias allowed)
			(pads allowed)
			(copperpour not_allowed)
			(footprints allowed)
		)
		(placement
			(enabled no)
			(sheetname "")
		)
		(fill yes
			(thermal_gap 0.5)
			(thermal_bridge_width 0.5)
			(island_removal_mode 0)
		)
		(polygon
			(pts
				(arc
					(start 99.04603 -314.997338)
					(mid 98.37801 -314.997338)
					(end 99.04603 -314.997338)
				)
			)
		)
	)
	(zone
		(layers "F.Cu" "B.Cu" "In1.Cu" "In2.Cu" "In3.Cu" "In4.Cu" "In5.Cu" "In6.Cu"
			"In7.Cu" "In8.Cu" "In9.Cu" "In10.Cu" "In11.Cu" "In12.Cu" "In13.Cu" "In14.Cu"
			"In15.Cu" "In16.Cu"
		)
		(hatch none 0.5)
		(connect_pads
			(clearance 0)
		)
		(min_thickness 0.25)
		(keepout
			(tracks not_allowed)
			(vias allowed)
			(pads allowed)
			(copperpour not_allowed)
			(footprints allowed)
		)
		(placement
			(enabled no)
			(sheetname "")
		)
		(fill
			(thermal_gap 0.5)
			(thermal_bridge_width 0.5)
			(island_removal_mode 0)
		)
		(polygon
			(pts
				(arc
					(start 409.82519 -400.811238)
					(mid 409.44419 -400.430238)
					(end 409.06319 -400.811238)
				)
				(arc
					(start 409.06319 -401.674838)
					(mid 409.44419 -402.055838)
					(end 409.82519 -401.674838)
				)
			)
		)
	)
	(zone
		(layers "F.Cu" "B.Cu" "In1.Cu" "In2.Cu" "In3.Cu" "In4.Cu" "In5.Cu" "In6.Cu"
			"In7.Cu" "In8.Cu" "In9.Cu" "In10.Cu" "In11.Cu" "In12.Cu" "In13.Cu" "In14.Cu"
			"In15.Cu" "In16.Cu"
		)
		(hatch none 0.5)
		(connect_pads
			(clearance 0)
		)
		(min_thickness 0.25)
		(keepout
			(tracks not_allowed)
			(vias allowed)
			(pads allowed)
			(copperpour not_allowed)
			(footprints allowed)
		)
		(placement
			(enabled no)
			(sheetname "")
		)
		(fill yes
			(thermal_gap 0.5)
			(thermal_bridge_width 0.5)
			(island_removal_mode 0)
		)
		(polygon
			(pts
				(arc
					(start 309.936388 -394.552424)
					(mid 310.046359 -394.653478)
					(end 310.19115 -394.690092)
				)
				(arc
					(start 310.19115 -394.690092)
					(mid 310.406676 -394.600818)
					(end 310.49595 -394.385292)
				)
				(arc
					(start 310.49595 -394.385292)
					(mid 310.485613 -394.306553)
					(end 310.45531 -394.233146)
				)
				(arc
					(start 310.06288 -393.554204)
					(mid 309.950483 -393.432587)
					(end 309.7911 -393.38758)
				)
				(arc
					(start 309.7911 -393.38758)
					(mid 309.575574 -393.476854)
					(end 309.4863 -393.69238)
				)
				(arc
					(start 309.4863 -393.69238)
					(mid 309.495878 -393.768442)
					(end 309.524146 -393.8397)
				)
				(xy 309.921402 -394.527024) (xy 309.933594 -394.54836) (xy 309.936134 -394.552678)
			)
		)
	)
	(zone
		(layers "F.Cu" "B.Cu" "In1.Cu" "In2.Cu" "In3.Cu" "In4.Cu" "In5.Cu" "In6.Cu"
			"In7.Cu" "In8.Cu" "In9.Cu" "In10.Cu" "In11.Cu" "In12.Cu" "In13.Cu" "In14.Cu"
			"In15.Cu" "In16.Cu"
		)
		(hatch none 0.5)
		(connect_pads
			(clearance 0)
		)
		(min_thickness 0.25)
		(keepout
			(tracks not_allowed)
			(vias allowed)
			(pads allowed)
			(copperpour not_allowed)
			(footprints allowed)
		)
		(placement
			(enabled no)
			(sheetname "")
		)
		(fill
			(thermal_gap 0.5)
			(thermal_bridge_width 0.5)
			(island_removal_mode 0)
		)
		(polygon
			(pts
				(arc
					(start 173.355 -74.767948)
					(mid 178.86299 -80.275938)
					(end 184.37098 -74.767948)
				)
				(arc
					(start 184.37098 -66.06794)
					(mid 178.86299 -60.55995)
					(end 173.355 -66.06794)
				)
			)
		)
	)
	(zone
		(layers "F.Cu" "B.Cu" "In1.Cu" "In2.Cu" "In3.Cu" "In4.Cu" "In5.Cu" "In6.Cu"
			"In7.Cu" "In8.Cu" "In9.Cu" "In10.Cu" "In11.Cu" "In12.Cu" "In13.Cu" "In14.Cu"
			"In15.Cu" "In16.Cu"
		)
		(hatch none 0.5)
		(connect_pads
			(clearance 0)
		)
		(min_thickness 0.25)
		(keepout
			(tracks not_allowed)
			(vias allowed)
			(pads allowed)
			(copperpour not_allowed)
			(footprints allowed)
		)
		(placement
			(enabled no)
			(sheetname "")
		)
		(fill
			(thermal_gap 0.5)
			(thermal_bridge_width 0.5)
			(island_removal_mode 0)
		)
		(polygon
			(pts
				(arc
					(start 383.036572 -398.016476)
					(mid 383.146543 -398.11753)
					(end 383.291334 -398.154144)
				)
				(arc
					(start 383.291334 -398.154144)
					(mid 383.50686 -398.06487)
					(end 383.596134 -397.849344)
				)
				(arc
					(start 383.596134 -397.849344)
					(mid 383.585797 -397.770605)
					(end 383.555494 -397.697198)
				)
				(arc
					(start 383.163064 -397.018256)
					(mid 383.050667 -396.896639)
					(end 382.891284 -396.851632)
				)
				(arc
					(start 382.891284 -396.851632)
					(mid 382.675758 -396.940906)
					(end 382.586484 -397.156432)
				)
				(arc
					(start 382.586484 -397.156432)
					(mid 382.596062 -397.232494)
					(end 382.62433 -397.303752)
				)
				(xy 383.021586 -397.991076) (xy 383.033778 -398.012412) (xy 383.036318 -398.01673)
			)
		)
	)
	(zone
		(layers "F.Cu" "B.Cu" "In1.Cu" "In2.Cu" "In3.Cu" "In4.Cu" "In5.Cu" "In6.Cu"
			"In7.Cu" "In8.Cu" "In9.Cu" "In10.Cu" "In11.Cu" "In12.Cu" "In13.Cu" "In14.Cu"
			"In15.Cu" "In16.Cu"
		)
		(hatch none 0.5)
		(connect_pads
			(clearance 0)
		)
		(min_thickness 0.25)
		(keepout
			(tracks not_allowed)
			(vias allowed)
			(pads allowed)
			(copperpour not_allowed)
			(footprints allowed)
		)
		(placement
			(enabled no)
			(sheetname "")
		)
		(fill
			(thermal_gap 0.5)
			(thermal_bridge_width 0.5)
			(island_removal_mode 0)
		)
		(polygon
			(pts
				(arc
					(start 141.291564 -386.926074)
					(mid 140.910564 -386.545074)
					(end 140.529564 -386.926074)
				)
				(arc
					(start 140.529564 -387.789674)
					(mid 140.910564 -388.170674)
					(end 141.291564 -387.789674)
				)
			)
		)
	)
	(zone
		(layers "F.Cu" "B.Cu" "In1.Cu" "In2.Cu" "In3.Cu" "In4.Cu" "In5.Cu" "In6.Cu"
			"In7.Cu" "In8.Cu" "In9.Cu" "In10.Cu" "In11.Cu" "In12.Cu" "In13.Cu" "In14.Cu"
			"In15.Cu" "In16.Cu"
		)
		(hatch none 0.5)
		(connect_pads
			(clearance 0)
		)
		(min_thickness 0.25)
		(keepout
			(tracks not_allowed)
			(vias allowed)
			(pads allowed)
			(copperpour not_allowed)
			(footprints allowed)
		)
		(placement
			(enabled no)
			(sheetname "")
		)
		(fill
			(thermal_gap 0.5)
			(thermal_bridge_width 0.5)
			(island_removal_mode 0)
		)
		(polygon
			(pts
				(arc
					(start 65.138554 -368.65433)
					(mid 64.757554 -369.03533)
					(end 65.138554 -369.41633)
				)
				(arc
					(start 66.002154 -369.41633)
					(mid 66.383154 -369.03533)
					(end 66.002154 -368.65433)
				)
			)
		)
	)
	(zone
		(layers "F.Cu" "B.Cu" "In1.Cu" "In2.Cu" "In3.Cu" "In4.Cu" "In5.Cu" "In6.Cu"
			"In7.Cu" "In8.Cu" "In9.Cu" "In10.Cu" "In11.Cu" "In12.Cu" "In13.Cu" "In14.Cu"
			"In15.Cu" "In16.Cu"
		)
		(hatch none 0.5)
		(connect_pads
			(clearance 0)
		)
		(min_thickness 0.25)
		(keepout
			(tracks not_allowed)
			(vias allowed)
			(pads allowed)
			(copperpour not_allowed)
			(footprints allowed)
		)
		(placement
			(enabled no)
			(sheetname "")
		)
		(fill
			(thermal_gap 0.5)
			(thermal_bridge_width 0.5)
			(island_removal_mode 0)
		)
		(polygon
			(pts
				(arc
					(start 438.876948 5.71881)
					(mid 439.308748 5.28701)
					(end 439.740548 5.71881)
				)
				(arc
					(start 439.740548 6.58241)
					(mid 439.308748 7.01421)
					(end 438.876948 6.58241)
				)
			)
		)
	)
	(zone
		(layers "F.Cu" "B.Cu" "In1.Cu" "In2.Cu" "In3.Cu" "In4.Cu" "In5.Cu" "In6.Cu"
			"In7.Cu" "In8.Cu" "In9.Cu" "In10.Cu" "In11.Cu" "In12.Cu" "In13.Cu" "In14.Cu"
			"In15.Cu" "In16.Cu"
		)
		(hatch none 0.5)
		(connect_pads
			(clearance 0)
		)
		(min_thickness 0.25)
		(keepout
			(tracks not_allowed)
			(vias allowed)
			(pads allowed)
			(copperpour not_allowed)
			(footprints allowed)
		)
		(placement
			(enabled no)
			(sheetname "")
		)
		(fill
			(thermal_gap 0.5)
			(thermal_bridge_width 0.5)
			(island_removal_mode 0)
		)
		(polygon
			(pts
				(arc
					(start 131.741926 -406.62352)
					(mid 131.360926 -407.00452)
					(end 131.741926 -407.38552)
				)
				(arc
					(start 132.605526 -407.38552)
					(mid 132.986526 -407.00452)
					(end 132.605526 -406.62352)
				)
			)
		)
	)
	(zone
		(layers "F.Cu" "B.Cu" "In1.Cu" "In2.Cu" "In3.Cu" "In4.Cu" "In5.Cu" "In6.Cu"
			"In7.Cu" "In8.Cu" "In9.Cu" "In10.Cu" "In11.Cu" "In12.Cu" "In13.Cu" "In14.Cu"
			"In15.Cu" "In16.Cu"
		)
		(hatch none 0.5)
		(connect_pads
			(clearance 0)
		)
		(min_thickness 0.25)
		(keepout
			(tracks not_allowed)
			(vias allowed)
			(pads allowed)
			(copperpour not_allowed)
			(footprints allowed)
		)
		(placement
			(enabled no)
			(sheetname "")
		)
		(fill
			(thermal_gap 0.5)
			(thermal_bridge_width 0.5)
			(island_removal_mode 0)
		)
		(polygon
			(pts
				(arc
					(start 39.554912 -74.760836)
					(mid 45.062902 -80.268826)
					(end 50.570892 -74.760836)
				)
				(arc
					(start 50.570892 -66.060828)
					(mid 45.062902 -60.552838)
					(end 39.554912 -66.060828)
				)
			)
		)
	)
	(zone
		(layers "F.Cu" "B.Cu" "In1.Cu" "In2.Cu" "In3.Cu" "In4.Cu" "In5.Cu" "In6.Cu"
			"In7.Cu" "In8.Cu" "In9.Cu" "In10.Cu" "In11.Cu" "In12.Cu" "In13.Cu" "In14.Cu"
			"In15.Cu" "In16.Cu"
		)
		(hatch none 0.5)
		(connect_pads
			(clearance 0)
		)
		(min_thickness 0.25)
		(keepout
			(tracks not_allowed)
			(vias allowed)
			(pads allowed)
			(copperpour not_allowed)
			(footprints allowed)
		)
		(placement
			(enabled no)
			(sheetname "")
		)
		(fill
			(thermal_gap 0.5)
			(thermal_bridge_width 0.5)
			(island_removal_mode 0)
		)
		(polygon
			(pts
				(arc
					(start 406.120346 -4.582414)
					(mid 405.739346 -4.963414)
					(end 406.120346 -5.344414)
				)
				(arc
					(start 406.983946 -5.344414)
					(mid 407.364946 -4.963414)
					(end 406.983946 -4.582414)
				)
			)
		)
	)
	(zone
		(layers "F.Cu" "B.Cu" "In1.Cu" "In2.Cu" "In3.Cu" "In4.Cu" "In5.Cu" "In6.Cu"
			"In7.Cu" "In8.Cu" "In9.Cu" "In10.Cu" "In11.Cu" "In12.Cu" "In13.Cu" "In14.Cu"
			"In15.Cu" "In16.Cu"
		)
		(hatch none 0.5)
		(connect_pads
			(clearance 0)
		)
		(min_thickness 0.25)
		(keepout
			(tracks not_allowed)
			(vias allowed)
			(pads allowed)
			(copperpour not_allowed)
			(footprints allowed)
		)
		(placement
			(enabled no)
			(sheetname "")
		)
		(fill
			(thermal_gap 0.5)
			(thermal_bridge_width 0.5)
			(island_removal_mode 0)
		)
		(polygon
			(pts
				(arc
					(start 423.86758 -17.23136)
					(mid 423.48658 -17.61236)
					(end 423.86758 -17.99336)
				)
				(arc
					(start 424.73118 -17.99336)
					(mid 425.11218 -17.61236)
					(end 424.73118 -17.23136)
				)
			)
		)
	)
	(zone
		(layers "F.Cu" "B.Cu" "In1.Cu" "In2.Cu" "In3.Cu" "In4.Cu" "In5.Cu" "In6.Cu"
			"In7.Cu" "In8.Cu" "In9.Cu" "In10.Cu" "In11.Cu" "In12.Cu" "In13.Cu" "In14.Cu"
			"In15.Cu" "In16.Cu"
		)
		(hatch none 0.5)
		(connect_pads
			(clearance 0)
		)
		(min_thickness 0.25)
		(keepout
			(tracks not_allowed)
			(vias allowed)
			(pads allowed)
			(copperpour not_allowed)
			(footprints allowed)
		)
		(placement
			(enabled no)
			(sheetname "")
		)
		(fill
			(thermal_gap 0.5)
			(thermal_bridge_width 0.5)
			(island_removal_mode 0)
		)
		(polygon
			(pts
				(arc
					(start 320.641726 -418.031168)
					(mid 320.260726 -418.412168)
					(end 320.641726 -418.793168)
				)
				(arc
					(start 321.505326 -418.793168)
					(mid 321.886326 -418.412168)
					(end 321.505326 -418.031168)
				)
			)
		)
	)
	(zone
		(layers "F.Cu" "B.Cu" "In1.Cu" "In2.Cu" "In3.Cu" "In4.Cu" "In5.Cu" "In6.Cu"
			"In7.Cu" "In8.Cu" "In9.Cu" "In10.Cu" "In11.Cu" "In12.Cu" "In13.Cu" "In14.Cu"
			"In15.Cu" "In16.Cu"
		)
		(hatch none 0.5)
		(connect_pads
			(clearance 0)
		)
		(min_thickness 0.25)
		(keepout
			(tracks not_allowed)
			(vias allowed)
			(pads allowed)
			(copperpour not_allowed)
			(footprints allowed)
		)
		(placement
			(enabled no)
			(sheetname "")
		)
		(fill
			(thermal_gap 0.5)
			(thermal_bridge_width 0.5)
			(island_removal_mode 0)
		)
		(polygon
			(pts
				(arc
					(start 120.11533 -32.64408)
					(mid 119.73433 -33.02508)
					(end 120.11533 -33.40608)
				)
				(arc
					(start 120.97893 -33.40608)
					(mid 121.35993 -33.02508)
					(end 120.97893 -32.64408)
				)
			)
		)
	)
	(zone
		(layers "F.Cu" "B.Cu" "In1.Cu" "In2.Cu" "In3.Cu" "In4.Cu" "In5.Cu" "In6.Cu"
			"In7.Cu" "In8.Cu" "In9.Cu" "In10.Cu" "In11.Cu" "In12.Cu" "In13.Cu" "In14.Cu"
			"In15.Cu" "In16.Cu"
		)
		(hatch none 0.5)
		(connect_pads
			(clearance 0)
		)
		(min_thickness 0.25)
		(keepout
			(tracks not_allowed)
			(vias allowed)
			(pads allowed)
			(copperpour not_allowed)
			(footprints allowed)
		)
		(placement
			(enabled no)
			(sheetname "")
		)
		(fill yes
			(thermal_gap 0.5)
			(thermal_bridge_width 0.5)
			(island_removal_mode 0)
		)
		(polygon
			(pts
				(arc
					(start 65.936622 -386.170424)
					(mid 66.046593 -386.271478)
					(end 66.191384 -386.308092)
				)
				(arc
					(start 66.191384 -386.308092)
					(mid 66.40691 -386.218818)
					(end 66.496184 -386.003292)
				)
				(arc
					(start 66.496184 -386.003292)
					(mid 66.485847 -385.924553)
					(end 66.455544 -385.851146)
				)
				(arc
					(start 66.063114 -385.172204)
					(mid 65.950717 -385.050587)
					(end 65.791334 -385.00558)
				)
				(arc
					(start 65.791334 -385.00558)
					(mid 65.575808 -385.094854)
					(end 65.486534 -385.31038)
				)
				(arc
					(start 65.486534 -385.31038)
					(mid 65.496112 -385.386442)
					(end 65.52438 -385.4577)
				)
				(xy 65.921636 -386.145024) (xy 65.933828 -386.16636) (xy 65.936368 -386.170678)
			)
		)
	)
	(zone
		(layers "F.Cu" "B.Cu" "In1.Cu" "In2.Cu" "In3.Cu" "In4.Cu" "In5.Cu" "In6.Cu"
			"In7.Cu" "In8.Cu" "In9.Cu" "In10.Cu" "In11.Cu" "In12.Cu" "In13.Cu" "In14.Cu"
			"In15.Cu" "In16.Cu"
		)
		(hatch none 0.5)
		(connect_pads
			(clearance 0)
		)
		(min_thickness 0.25)
		(keepout
			(tracks not_allowed)
			(vias allowed)
			(pads allowed)
			(copperpour not_allowed)
			(footprints allowed)
		)
		(placement
			(enabled no)
			(sheetname "")
		)
		(fill yes
			(thermal_gap 0.5)
			(thermal_bridge_width 0.5)
			(island_removal_mode 0)
		)
		(polygon
			(pts
				(arc
					(start 129.436368 -386.170424)
					(mid 129.546339 -386.271478)
					(end 129.69113 -386.308092)
				)
				(arc
					(start 129.69113 -386.308092)
					(mid 129.906656 -386.218818)
					(end 129.99593 -386.003292)
				)
				(arc
					(start 129.99593 -386.003292)
					(mid 129.985593 -385.924553)
					(end 129.95529 -385.851146)
				)
				(arc
					(start 129.56286 -385.172204)
					(mid 129.450463 -385.050587)
					(end 129.29108 -385.00558)
				)
				(arc
					(start 129.29108 -385.00558)
					(mid 129.075554 -385.094854)
					(end 128.98628 -385.31038)
				)
				(arc
					(start 128.98628 -385.31038)
					(mid 128.995858 -385.386442)
					(end 129.024126 -385.4577)
				)
				(xy 129.421382 -386.145024) (xy 129.433574 -386.16636) (xy 129.436114 -386.170678)
			)
		)
	)
	(zone
		(layers "F.Cu" "B.Cu" "In1.Cu" "In2.Cu" "In3.Cu" "In4.Cu" "In5.Cu" "In6.Cu"
			"In7.Cu" "In8.Cu" "In9.Cu" "In10.Cu" "In11.Cu" "In12.Cu" "In13.Cu" "In14.Cu"
			"In15.Cu" "In16.Cu"
		)
		(hatch none 0.5)
		(connect_pads
			(clearance 0)
		)
		(min_thickness 0.25)
		(keepout
			(tracks not_allowed)
			(vias allowed)
			(pads allowed)
			(copperpour not_allowed)
			(footprints allowed)
		)
		(placement
			(enabled no)
			(sheetname "")
		)
		(fill
			(thermal_gap 0.5)
			(thermal_bridge_width 0.5)
			(island_removal_mode 0)
		)
		(polygon
			(pts
				(arc
					(start 428.235618 -6.344158)
					(mid 427.854618 -6.725158)
					(end 428.235618 -7.106158)
				)
				(arc
					(start 429.099218 -7.106158)
					(mid 429.480218 -6.725158)
					(end 429.099218 -6.344158)
				)
			)
		)
	)
	(zone
		(layers "F.Cu" "B.Cu" "In1.Cu" "In2.Cu" "In3.Cu" "In4.Cu" "In5.Cu" "In6.Cu"
			"In7.Cu" "In8.Cu" "In9.Cu" "In10.Cu" "In11.Cu" "In12.Cu" "In13.Cu" "In14.Cu"
			"In15.Cu" "In16.Cu"
		)
		(hatch none 0.5)
		(connect_pads
			(clearance 0)
		)
		(min_thickness 0.25)
		(keepout
			(tracks not_allowed)
			(vias allowed)
			(pads allowed)
			(copperpour not_allowed)
			(footprints allowed)
		)
		(placement
			(enabled no)
			(sheetname "")
		)
		(fill
			(thermal_gap 0.5)
			(thermal_bridge_width 0.5)
			(island_removal_mode 0)
		)
		(polygon
			(pts
				(arc
					(start 119.836438 -389.634476)
					(mid 119.946409 -389.73553)
					(end 120.0912 -389.772144)
				)
				(arc
					(start 120.0912 -389.772144)
					(mid 120.306726 -389.68287)
					(end 120.396 -389.467344)
				)
				(arc
					(start 120.396 -389.467344)
					(mid 120.385663 -389.388605)
					(end 120.35536 -389.315198)
				)
				(arc
					(start 119.96293 -388.636256)
					(mid 119.850533 -388.514639)
					(end 119.69115 -388.469632)
				)
				(arc
					(start 119.69115 -388.469632)
					(mid 119.475624 -388.558906)
					(end 119.38635 -388.774432)
				)
				(arc
					(start 119.38635 -388.774432)
					(mid 119.395928 -388.850494)
					(end 119.424196 -388.921752)
				)
				(xy 119.821452 -389.609076) (xy 119.833644 -389.630412) (xy 119.836184 -389.63473)
			)
		)
	)
	(zone
		(layers "F.Cu" "B.Cu" "In1.Cu" "In2.Cu" "In3.Cu" "In4.Cu" "In5.Cu" "In6.Cu"
			"In7.Cu" "In8.Cu" "In9.Cu" "In10.Cu" "In11.Cu" "In12.Cu" "In13.Cu" "In14.Cu"
			"In15.Cu" "In16.Cu"
		)
		(hatch none 0.5)
		(connect_pads
			(clearance 0)
		)
		(min_thickness 0.25)
		(keepout
			(tracks not_allowed)
			(vias allowed)
			(pads allowed)
			(copperpour not_allowed)
			(footprints allowed)
		)
		(placement
			(enabled no)
			(sheetname "")
		)
		(fill
			(thermal_gap 0.5)
			(thermal_bridge_width 0.5)
			(island_removal_mode 0)
		)
		(polygon
			(pts
				(arc
					(start 314.331096 -377.03633)
					(mid 313.950096 -377.41733)
					(end 314.331096 -377.79833)
				)
				(arc
					(start 315.194696 -377.79833)
					(mid 315.575696 -377.41733)
					(end 315.194696 -377.03633)
				)
			)
		)
	)
	(zone
		(layers "F.Cu" "B.Cu" "In1.Cu" "In2.Cu" "In3.Cu" "In4.Cu" "In5.Cu" "In6.Cu"
			"In7.Cu" "In8.Cu" "In9.Cu" "In10.Cu" "In11.Cu" "In12.Cu" "In13.Cu" "In14.Cu"
			"In15.Cu" "In16.Cu"
		)
		(hatch none 0.5)
		(connect_pads
			(clearance 0)
		)
		(min_thickness 0.25)
		(keepout
			(tracks not_allowed)
			(vias allowed)
			(pads allowed)
			(copperpour not_allowed)
			(footprints allowed)
		)
		(placement
			(enabled no)
			(sheetname "")
		)
		(fill
			(thermal_gap 0.5)
			(thermal_bridge_width 0.5)
			(island_removal_mode 0)
		)
		(polygon
			(pts
				(arc
					(start 390.033764 -17.23136)
					(mid 389.652764 -17.61236)
					(end 390.033764 -17.99336)
				)
				(arc
					(start 390.897364 -17.99336)
					(mid 391.278364 -17.61236)
					(end 390.897364 -17.23136)
				)
			)
		)
	)
	(zone
		(layers "F.Cu" "B.Cu" "In1.Cu" "In2.Cu" "In3.Cu" "In4.Cu" "In5.Cu" "In6.Cu"
			"In7.Cu" "In8.Cu" "In9.Cu" "In10.Cu" "In11.Cu" "In12.Cu" "In13.Cu" "In14.Cu"
			"In15.Cu" "In16.Cu"
		)
		(hatch none 0.5)
		(connect_pads
			(clearance 0)
		)
		(min_thickness 0.25)
		(keepout
			(tracks not_allowed)
			(vias allowed)
			(pads allowed)
			(copperpour not_allowed)
			(footprints allowed)
		)
		(placement
			(enabled no)
			(sheetname "")
		)
		(fill
			(thermal_gap 0.5)
			(thermal_bridge_width 0.5)
			(island_removal_mode 0)
		)
		(polygon
			(pts
				(arc
					(start 94.107 -214.992458)
					(mid 94.488 -215.373458)
					(end 94.869 -214.992458)
				)
				(arc
					(start 94.869 -214.128858)
					(mid 94.488 -213.747858)
					(end 94.107 -214.128858)
				)
			)
		)
	)
	(zone
		(layers "F.Cu" "B.Cu" "In1.Cu" "In2.Cu" "In3.Cu" "In4.Cu" "In5.Cu" "In6.Cu"
			"In7.Cu" "In8.Cu" "In9.Cu" "In10.Cu" "In11.Cu" "In12.Cu" "In13.Cu" "In14.Cu"
			"In15.Cu" "In16.Cu"
		)
		(hatch none 0.5)
		(connect_pads
			(clearance 0)
		)
		(min_thickness 0.25)
		(keepout
			(tracks not_allowed)
			(vias allowed)
			(pads allowed)
			(copperpour not_allowed)
			(footprints allowed)
		)
		(placement
			(enabled no)
			(sheetname "")
		)
		(fill yes
			(thermal_gap 0.5)
			(thermal_bridge_width 0.5)
			(island_removal_mode 0)
		)
		(polygon
			(pts
				(arc
					(start 381.836422 -394.552424)
					(mid 381.946393 -394.653478)
					(end 382.091184 -394.690092)
				)
				(arc
					(start 382.091184 -394.690092)
					(mid 382.30671 -394.600818)
					(end 382.395984 -394.385292)
				)
				(arc
					(start 382.395984 -394.385292)
					(mid 382.385647 -394.306553)
					(end 382.355344 -394.233146)
				)
				(arc
					(start 381.962914 -393.554204)
					(mid 381.850517 -393.432587)
					(end 381.691134 -393.38758)
				)
				(arc
					(start 381.691134 -393.38758)
					(mid 381.475608 -393.476854)
					(end 381.386334 -393.69238)
				)
				(arc
					(start 381.386334 -393.69238)
					(mid 381.395912 -393.768442)
					(end 381.42418 -393.8397)
				)
				(xy 381.821436 -394.527024) (xy 381.833628 -394.54836) (xy 381.836168 -394.552678)
			)
		)
	)
	(zone
		(layers "F.Cu" "B.Cu" "In1.Cu" "In2.Cu" "In3.Cu" "In4.Cu" "In5.Cu" "In6.Cu"
			"In7.Cu" "In8.Cu" "In9.Cu" "In10.Cu" "In11.Cu" "In12.Cu" "In13.Cu" "In14.Cu"
			"In15.Cu" "In16.Cu"
		)
		(hatch none 0.5)
		(connect_pads
			(clearance 0)
		)
		(min_thickness 0.25)
		(keepout
			(tracks not_allowed)
			(vias allowed)
			(pads allowed)
			(copperpour not_allowed)
			(footprints allowed)
		)
		(placement
			(enabled no)
			(sheetname "")
		)
		(fill
			(thermal_gap 0.5)
			(thermal_bridge_width 0.5)
			(island_removal_mode 0)
		)
		(polygon
			(pts
				(arc
					(start 49.575466 -416.573208)
					(mid 49.194466 -416.192208)
					(end 48.813466 -416.573208)
				)
				(arc
					(start 48.813466 -417.436808)
					(mid 49.194466 -417.817808)
					(end 49.575466 -417.436808)
				)
			)
		)
	)
	(zone
		(layers "F.Cu" "B.Cu" "In1.Cu" "In2.Cu" "In3.Cu" "In4.Cu" "In5.Cu" "In6.Cu"
			"In7.Cu" "In8.Cu" "In9.Cu" "In10.Cu" "In11.Cu" "In12.Cu" "In13.Cu" "In14.Cu"
			"In15.Cu" "In16.Cu"
		)
		(hatch none 0.5)
		(connect_pads
			(clearance 0)
		)
		(min_thickness 0.25)
		(keepout
			(tracks not_allowed)
			(vias allowed)
			(pads allowed)
			(copperpour not_allowed)
			(footprints allowed)
		)
		(placement
			(enabled no)
			(sheetname "")
		)
		(fill
			(thermal_gap 0.5)
			(thermal_bridge_width 0.5)
			(island_removal_mode 0)
		)
		(polygon
			(pts
				(arc
					(start 130.210306 -412.189168)
					(mid 129.829306 -412.570168)
					(end 130.210306 -412.951168)
				)
				(arc
					(start 131.073906 -412.951168)
					(mid 131.454906 -412.570168)
					(end 131.073906 -412.189168)
				)
			)
		)
	)
	(zone
		(layers "F.Cu" "B.Cu" "In1.Cu" "In2.Cu" "In3.Cu" "In4.Cu" "In5.Cu" "In6.Cu"
			"In7.Cu" "In8.Cu" "In9.Cu" "In10.Cu" "In11.Cu" "In12.Cu" "In13.Cu" "In14.Cu"
			"In15.Cu" "In16.Cu"
		)
		(hatch none 0.5)
		(connect_pads
			(clearance 0)
		)
		(min_thickness 0.25)
		(keepout
			(tracks not_allowed)
			(vias allowed)
			(pads allowed)
			(copperpour not_allowed)
			(footprints allowed)
		)
		(placement
			(enabled no)
			(sheetname "")
		)
		(fill
			(thermal_gap 0.5)
			(thermal_bridge_width 0.5)
			(island_removal_mode 0)
		)
		(polygon
			(pts
				(xy 513.515102 -433.21224) (xy 513.819902 -433.51704) (xy 513.819902 -423.51706) (xy 513.515102 -423.82186)
			)
		)
	)
	(zone
		(layers "F.Cu" "B.Cu" "In1.Cu" "In2.Cu" "In3.Cu" "In4.Cu" "In5.Cu" "In6.Cu"
			"In7.Cu" "In8.Cu" "In9.Cu" "In10.Cu" "In11.Cu" "In12.Cu" "In13.Cu" "In14.Cu"
			"In15.Cu" "In16.Cu"
		)
		(hatch none 0.5)
		(connect_pads
			(clearance 0)
		)
		(min_thickness 0.25)
		(keepout
			(tracks not_allowed)
			(vias allowed)
			(pads allowed)
			(copperpour not_allowed)
			(footprints allowed)
		)
		(placement
			(enabled no)
			(sheetname "")
		)
		(fill
			(thermal_gap 0.5)
			(thermal_bridge_width 0.5)
			(island_removal_mode 0)
		)
		(polygon
			(pts
				(arc
					(start 360.186224 -387.878828)
					(mid 359.805224 -387.497828)
					(end 359.424224 -387.878828)
				)
				(arc
					(start 359.424224 -388.742428)
					(mid 359.805224 -389.123428)
					(end 360.186224 -388.742428)
				)
			)
		)
	)
	(zone
		(layers "F.Cu" "B.Cu" "In1.Cu" "In2.Cu" "In3.Cu" "In4.Cu" "In5.Cu" "In6.Cu"
			"In7.Cu" "In8.Cu" "In9.Cu" "In10.Cu" "In11.Cu" "In12.Cu" "In13.Cu" "In14.Cu"
			"In15.Cu" "In16.Cu"
		)
		(hatch none 0.5)
		(connect_pads
			(clearance 0)
		)
		(min_thickness 0.25)
		(keepout
			(tracks not_allowed)
			(vias allowed)
			(pads allowed)
			(copperpour not_allowed)
			(footprints allowed)
		)
		(placement
			(enabled no)
			(sheetname "")
		)
		(fill
			(thermal_gap 0.5)
			(thermal_bridge_width 0.5)
			(island_removal_mode 0)
		)
		(polygon
			(pts
				(arc
					(start 199.466708 -153.774902)
					(mid 188.443108 -153.774902)
					(end 199.466708 -153.774902)
				)
			)
		)
	)
	(zone
		(layers "F.Cu" "B.Cu" "In1.Cu" "In2.Cu" "In3.Cu" "In4.Cu" "In5.Cu" "In6.Cu"
			"In7.Cu" "In8.Cu" "In9.Cu" "In10.Cu" "In11.Cu" "In12.Cu" "In13.Cu" "In14.Cu"
			"In15.Cu" "In16.Cu"
		)
		(hatch none 0.5)
		(connect_pads
			(clearance 0)
		)
		(min_thickness 0.25)
		(keepout
			(tracks not_allowed)
			(vias allowed)
			(pads allowed)
			(copperpour not_allowed)
			(footprints allowed)
		)
		(placement
			(enabled no)
			(sheetname "")
		)
		(fill
			(thermal_gap 0.5)
			(thermal_bridge_width 0.5)
			(island_removal_mode 0)
		)
		(polygon
			(pts
				(arc
					(start 74.33945 -375.96826)
					(mid 73.95845 -375.58726)
					(end 73.57745 -375.96826)
				)
				(arc
					(start 73.57745 -376.83186)
					(mid 73.95845 -377.21286)
					(end 74.33945 -376.83186)
				)
			)
		)
	)
	(zone
		(layers "F.Cu" "B.Cu" "In1.Cu" "In2.Cu" "In3.Cu" "In4.Cu" "In5.Cu" "In6.Cu"
			"In7.Cu" "In8.Cu" "In9.Cu" "In10.Cu" "In11.Cu" "In12.Cu" "In13.Cu" "In14.Cu"
			"In15.Cu" "In16.Cu"
		)
		(hatch none 0.5)
		(connect_pads
			(clearance 0)
		)
		(min_thickness 0.25)
		(keepout
			(tracks not_allowed)
			(vias allowed)
			(pads allowed)
			(copperpour not_allowed)
			(footprints allowed)
		)
		(placement
			(enabled no)
			(sheetname "")
		)
		(fill
			(thermal_gap 0.5)
			(thermal_bridge_width 0.5)
			(island_removal_mode 0)
		)
		(polygon
			(pts
				(arc
					(start 390.805162 -418.031168)
					(mid 390.424162 -418.412168)
					(end 390.805162 -418.793168)
				)
				(arc
					(start 391.668762 -418.793168)
					(mid 392.049762 -418.412168)
					(end 391.668762 -418.031168)
				)
			)
		)
	)
	(zone
		(layers "F.Cu" "B.Cu" "In1.Cu" "In2.Cu" "In3.Cu" "In4.Cu" "In5.Cu" "In6.Cu"
			"In7.Cu" "In8.Cu" "In9.Cu" "In10.Cu" "In11.Cu" "In12.Cu" "In13.Cu" "In14.Cu"
			"In15.Cu" "In16.Cu"
		)
		(hatch none 0.5)
		(connect_pads
			(clearance 0)
		)
		(min_thickness 0.25)
		(keepout
			(tracks not_allowed)
			(vias allowed)
			(pads allowed)
			(copperpour not_allowed)
			(footprints allowed)
		)
		(placement
			(enabled no)
			(sheetname "")
		)
		(fill
			(thermal_gap 0.5)
			(thermal_bridge_width 0.5)
			(island_removal_mode 0)
		)
		(polygon
			(pts
				(arc
					(start 445.82969 -12.483846)
					(mid 445.44869 -12.864846)
					(end 445.82969 -13.245846)
				)
				(arc
					(start 446.69329 -13.245846)
					(mid 447.07429 -12.864846)
					(end 446.69329 -12.483846)
				)
			)
		)
	)
	(zone
		(layers "F.Cu" "B.Cu" "In1.Cu" "In2.Cu" "In3.Cu" "In4.Cu" "In5.Cu" "In6.Cu"
			"In7.Cu" "In8.Cu" "In9.Cu" "In10.Cu" "In11.Cu" "In12.Cu" "In13.Cu" "In14.Cu"
			"In15.Cu" "In16.Cu"
		)
		(hatch none 0.5)
		(connect_pads
			(clearance 0)
		)
		(min_thickness 0.25)
		(keepout
			(tracks not_allowed)
			(vias allowed)
			(pads allowed)
			(copperpour not_allowed)
			(footprints allowed)
		)
		(placement
			(enabled no)
			(sheetname "")
		)
		(fill
			(thermal_gap 0.5)
			(thermal_bridge_width 0.5)
			(island_removal_mode 0)
		)
		(polygon
			(pts
				(arc
					(start 141.014704 -17.763744)
					(mid 140.633704 -18.144744)
					(end 141.014704 -18.525744)
				)
				(arc
					(start 141.878304 -18.525744)
					(mid 142.259304 -18.144744)
					(end 141.878304 -17.763744)
				)
			)
		)
	)
	(zone
		(layers "F.Cu" "B.Cu" "In1.Cu" "In2.Cu" "In3.Cu" "In4.Cu" "In5.Cu" "In6.Cu"
			"In7.Cu" "In8.Cu" "In9.Cu" "In10.Cu" "In11.Cu" "In12.Cu" "In13.Cu" "In14.Cu"
			"In15.Cu" "In16.Cu"
		)
		(hatch none 0.5)
		(connect_pads
			(clearance 0)
		)
		(min_thickness 0.25)
		(keepout
			(tracks not_allowed)
			(vias allowed)
			(pads allowed)
			(copperpour not_allowed)
			(footprints allowed)
		)
		(placement
			(enabled no)
			(sheetname "")
		)
		(fill
			(thermal_gap 0.5)
			(thermal_bridge_width 0.5)
			(island_removal_mode 0)
		)
		(polygon
			(pts
				(arc
					(start 16.282162 -5.169916)
					(mid 14.351762 -5.169916)
					(end 16.282162 -5.169916)
				)
			)
		)
	)
	(zone
		(layers "F.Cu" "B.Cu" "In1.Cu" "In2.Cu" "In3.Cu" "In4.Cu" "In5.Cu" "In6.Cu"
			"In7.Cu" "In8.Cu" "In9.Cu" "In10.Cu" "In11.Cu" "In12.Cu" "In13.Cu" "In14.Cu"
			"In15.Cu" "In16.Cu"
		)
		(hatch none 0.5)
		(connect_pads
			(clearance 0)
		)
		(min_thickness 0.25)
		(keepout
			(tracks not_allowed)
			(vias allowed)
			(pads allowed)
			(copperpour not_allowed)
			(footprints allowed)
		)
		(placement
			(enabled no)
			(sheetname "")
		)
		(fill
			(thermal_gap 0.5)
			(thermal_bridge_width 0.5)
			(island_removal_mode 0)
		)
		(polygon
			(pts
				(arc
					(start 341.263986 -398.016476)
					(mid 341.373957 -398.11753)
					(end 341.518748 -398.154144)
				)
				(arc
					(start 341.518748 -398.154144)
					(mid 341.734274 -398.06487)
					(end 341.823548 -397.849344)
				)
				(arc
					(start 341.823548 -397.849344)
					(mid 341.813211 -397.770605)
					(end 341.782908 -397.697198)
				)
				(arc
					(start 341.390478 -397.018256)
					(mid 341.278081 -396.896639)
					(end 341.118698 -396.851632)
				)
				(arc
					(start 341.118698 -396.851632)
					(mid 340.903172 -396.940906)
					(end 340.813898 -397.156432)
				)
				(arc
					(start 340.813898 -397.156432)
					(mid 340.823476 -397.232494)
					(end 340.851744 -397.303752)
				)
				(xy 341.249 -397.991076) (xy 341.261192 -398.012412) (xy 341.263732 -398.01673)
			)
		)
	)
	(zone
		(layers "F.Cu" "B.Cu" "In1.Cu" "In2.Cu" "In3.Cu" "In4.Cu" "In5.Cu" "In6.Cu"
			"In7.Cu" "In8.Cu" "In9.Cu" "In10.Cu" "In11.Cu" "In12.Cu" "In13.Cu" "In14.Cu"
			"In15.Cu" "In16.Cu"
		)
		(hatch none 0.5)
		(connect_pads
			(clearance 0)
		)
		(min_thickness 0.25)
		(keepout
			(tracks not_allowed)
			(vias allowed)
			(pads allowed)
			(copperpour not_allowed)
			(footprints allowed)
		)
		(placement
			(enabled no)
			(sheetname "")
		)
		(fill
			(thermal_gap 0.5)
			(thermal_bridge_width 0.5)
			(island_removal_mode 0)
		)
		(polygon
			(pts
				(arc
					(start 81.489804 -404.08352)
					(mid 81.108804 -404.46452)
					(end 81.489804 -404.84552)
				)
				(arc
					(start 82.353404 -404.84552)
					(mid 82.734404 -404.46452)
					(end 82.353404 -404.08352)
				)
			)
		)
	)
	(zone
		(layers "F.Cu" "B.Cu" "In1.Cu" "In2.Cu" "In3.Cu" "In4.Cu" "In5.Cu" "In6.Cu"
			"In7.Cu" "In8.Cu" "In9.Cu" "In10.Cu" "In11.Cu" "In12.Cu" "In13.Cu" "In14.Cu"
			"In15.Cu" "In16.Cu"
		)
		(hatch none 0.5)
		(connect_pads
			(clearance 0)
		)
		(min_thickness 0.25)
		(keepout
			(tracks not_allowed)
			(vias allowed)
			(pads allowed)
			(copperpour not_allowed)
			(footprints allowed)
		)
		(placement
			(enabled no)
			(sheetname "")
		)
		(fill
			(thermal_gap 0.5)
			(thermal_bridge_width 0.5)
			(island_removal_mode 0)
		)
		(polygon
			(pts
				(arc
					(start 381.431292 -377.03633)
					(mid 381.050292 -377.41733)
					(end 381.431292 -377.79833)
				)
				(arc
					(start 382.294892 -377.79833)
					(mid 382.675892 -377.41733)
					(end 382.294892 -377.03633)
				)
			)
		)
	)
	(zone
		(layers "F.Cu" "B.Cu" "In1.Cu" "In2.Cu" "In3.Cu" "In4.Cu" "In5.Cu" "In6.Cu"
			"In7.Cu" "In8.Cu" "In9.Cu" "In10.Cu" "In11.Cu" "In12.Cu" "In13.Cu" "In14.Cu"
			"In15.Cu" "In16.Cu"
		)
		(hatch none 0.5)
		(connect_pads
			(clearance 0)
		)
		(min_thickness 0.25)
		(keepout
			(tracks not_allowed)
			(vias allowed)
			(pads allowed)
			(copperpour not_allowed)
			(footprints allowed)
		)
		(placement
			(enabled no)
			(sheetname "")
		)
		(fill
			(thermal_gap 0.5)
			(thermal_bridge_width 0.5)
			(island_removal_mode 0)
		)
		(polygon
			(pts
				(arc
					(start 96.325182 -392.429238)
					(mid 95.944182 -392.048238)
					(end 95.563182 -392.429238)
				)
				(arc
					(start 95.563182 -393.292838)
					(mid 95.944182 -393.673838)
					(end 96.325182 -393.292838)
				)
			)
		)
	)
	(zone
		(layers "F.Cu" "B.Cu" "In1.Cu" "In2.Cu" "In3.Cu" "In4.Cu" "In5.Cu" "In6.Cu"
			"In7.Cu" "In8.Cu" "In9.Cu" "In10.Cu" "In11.Cu" "In12.Cu" "In13.Cu" "In14.Cu"
			"In15.Cu" "In16.Cu"
		)
		(hatch none 0.5)
		(connect_pads
			(clearance 0)
		)
		(min_thickness 0.25)
		(keepout
			(tracks not_allowed)
			(vias allowed)
			(pads allowed)
			(copperpour not_allowed)
			(footprints allowed)
		)
		(placement
			(enabled no)
			(sheetname "")
		)
		(fill
			(thermal_gap 0.5)
			(thermal_bridge_width 0.5)
			(island_removal_mode 0)
		)
		(polygon
			(pts
				(arc
					(start 438.876948 8.25881)
					(mid 439.308748 7.82701)
					(end 439.740548 8.25881)
				)
				(arc
					(start 439.740548 9.12241)
					(mid 439.308748 9.55421)
					(end 438.876948 9.12241)
				)
			)
		)
	)
	(zone
		(layers "F.Cu" "B.Cu" "In1.Cu" "In2.Cu" "In3.Cu" "In4.Cu" "In5.Cu" "In6.Cu"
			"In7.Cu" "In8.Cu" "In9.Cu" "In10.Cu" "In11.Cu" "In12.Cu" "In13.Cu" "In14.Cu"
			"In15.Cu" "In16.Cu"
		)
		(hatch none 0.5)
		(connect_pads
			(clearance 0)
		)
		(min_thickness 0.25)
		(keepout
			(tracks not_allowed)
			(vias allowed)
			(pads allowed)
			(copperpour not_allowed)
			(footprints allowed)
		)
		(placement
			(enabled no)
			(sheetname "")
		)
		(fill
			(thermal_gap 0.5)
			(thermal_bridge_width 0.5)
			(island_removal_mode 0)
		)
		(polygon
			(pts
				(arc
					(start 79.958184 -409.649168)
					(mid 79.577184 -410.030168)
					(end 79.958184 -410.411168)
				)
				(arc
					(start 80.821784 -410.411168)
					(mid 81.202784 -410.030168)
					(end 80.821784 -409.649168)
				)
			)
		)
	)
	(zone
		(layers "F.Cu" "B.Cu" "In1.Cu" "In2.Cu" "In3.Cu" "In4.Cu" "In5.Cu" "In6.Cu"
			"In7.Cu" "In8.Cu" "In9.Cu" "In10.Cu" "In11.Cu" "In12.Cu" "In13.Cu" "In14.Cu"
			"In15.Cu" "In16.Cu"
		)
		(hatch none 0.5)
		(connect_pads
			(clearance 0)
		)
		(min_thickness 0.25)
		(keepout
			(tracks not_allowed)
			(vias allowed)
			(pads allowed)
			(copperpour not_allowed)
			(footprints allowed)
		)
		(placement
			(enabled no)
			(sheetname "")
		)
		(fill
			(thermal_gap 0.5)
			(thermal_bridge_width 0.5)
			(island_removal_mode 0)
		)
		(polygon
			(pts
				(arc
					(start 404.589742 -420.571168)
					(mid 404.208742 -420.952168)
					(end 404.589742 -421.333168)
				)
				(arc
					(start 405.453342 -421.333168)
					(mid 405.834342 -420.952168)
					(end 405.453342 -420.571168)
				)
			)
		)
	)
	(zone
		(layers "F.Cu" "B.Cu" "In1.Cu" "In2.Cu" "In3.Cu" "In4.Cu" "In5.Cu" "In6.Cu"
			"In7.Cu" "In8.Cu" "In9.Cu" "In10.Cu" "In11.Cu" "In12.Cu" "In13.Cu" "In14.Cu"
			"In15.Cu" "In16.Cu"
		)
		(hatch none 0.5)
		(connect_pads
			(clearance 0)
		)
		(min_thickness 0.25)
		(keepout
			(tracks not_allowed)
			(vias allowed)
			(pads allowed)
			(copperpour not_allowed)
			(footprints allowed)
		)
		(placement
			(enabled no)
			(sheetname "")
		)
		(fill
			(thermal_gap 0.5)
			(thermal_bridge_width 0.5)
			(island_removal_mode 0)
		)
		(polygon
			(pts
				(arc
					(start 49.136554 -389.634476)
					(mid 49.246525 -389.73553)
					(end 49.391316 -389.772144)
				)
				(arc
					(start 49.391316 -389.772144)
					(mid 49.606842 -389.68287)
					(end 49.696116 -389.467344)
				)
				(arc
					(start 49.696116 -389.467344)
					(mid 49.685779 -389.388605)
					(end 49.655476 -389.315198)
				)
				(arc
					(start 49.263046 -388.636256)
					(mid 49.150649 -388.514639)
					(end 48.991266 -388.469632)
				)
				(arc
					(start 48.991266 -388.469632)
					(mid 48.77574 -388.558906)
					(end 48.686466 -388.774432)
				)
				(arc
					(start 48.686466 -388.774432)
					(mid 48.696044 -388.850494)
					(end 48.724312 -388.921752)
				)
				(xy 49.121568 -389.609076) (xy 49.13376 -389.630412) (xy 49.1363 -389.63473)
			)
		)
	)
	(zone
		(layers "F.Cu" "B.Cu" "In1.Cu" "In2.Cu" "In3.Cu" "In4.Cu" "In5.Cu" "In6.Cu"
			"In7.Cu" "In8.Cu" "In9.Cu" "In10.Cu" "In11.Cu" "In12.Cu" "In13.Cu" "In14.Cu"
			"In15.Cu" "In16.Cu"
		)
		(hatch none 0.5)
		(connect_pads
			(clearance 0)
		)
		(min_thickness 0.25)
		(keepout
			(tracks not_allowed)
			(vias allowed)
			(pads allowed)
			(copperpour not_allowed)
			(footprints allowed)
		)
		(placement
			(enabled no)
			(sheetname "")
		)
		(fill
			(thermal_gap 0.5)
			(thermal_bridge_width 0.5)
			(island_removal_mode 0)
		)
		(polygon
			(pts
				(arc
					(start 326.768206 -418.031168)
					(mid 326.387206 -418.412168)
					(end 326.768206 -418.793168)
				)
				(arc
					(start 327.631806 -418.793168)
					(mid 328.012806 -418.412168)
					(end 327.631806 -418.031168)
				)
			)
		)
	)
	(zone
		(layers "F.Cu" "B.Cu" "In1.Cu" "In2.Cu" "In3.Cu" "In4.Cu" "In5.Cu" "In6.Cu"
			"In7.Cu" "In8.Cu" "In9.Cu" "In10.Cu" "In11.Cu" "In12.Cu" "In13.Cu" "In14.Cu"
			"In15.Cu" "In16.Cu"
		)
		(hatch none 0.5)
		(connect_pads
			(clearance 0)
		)
		(min_thickness 0.25)
		(keepout
			(tracks not_allowed)
			(vias allowed)
			(pads allowed)
			(copperpour not_allowed)
			(footprints allowed)
		)
		(placement
			(enabled no)
			(sheetname "")
		)
		(fill
			(thermal_gap 0.5)
			(thermal_bridge_width 0.5)
			(island_removal_mode 0)
		)
		(polygon
			(pts
				(arc
					(start 8.725408 -178.618388)
					(mid 9.106408 -178.999388)
					(end 9.487408 -178.618388)
				)
				(arc
					(start 9.487408 -177.754788)
					(mid 9.106408 -177.373788)
					(end 8.725408 -177.754788)
				)
			)
		)
	)
	(zone
		(layers "F.Cu" "B.Cu" "In1.Cu" "In2.Cu" "In3.Cu" "In4.Cu" "In5.Cu" "In6.Cu"
			"In7.Cu" "In8.Cu" "In9.Cu" "In10.Cu" "In11.Cu" "In12.Cu" "In13.Cu" "In14.Cu"
			"In15.Cu" "In16.Cu"
		)
		(hatch none 0.5)
		(connect_pads
			(clearance 0)
		)
		(min_thickness 0.25)
		(keepout
			(tracks not_allowed)
			(vias allowed)
			(pads allowed)
			(copperpour not_allowed)
			(footprints allowed)
		)
		(placement
			(enabled no)
			(sheetname "")
		)
		(fill
			(thermal_gap 0.5)
			(thermal_bridge_width 0.5)
			(island_removal_mode 0)
		)
		(polygon
			(pts
				(arc
					(start 137.868406 -409.649168)
					(mid 137.487406 -410.030168)
					(end 137.868406 -410.411168)
				)
				(arc
					(start 138.732006 -410.411168)
					(mid 139.113006 -410.030168)
					(end 138.732006 -409.649168)
				)
			)
		)
	)
	(zone
		(layers "F.Cu" "B.Cu" "In1.Cu" "In2.Cu" "In3.Cu" "In4.Cu" "In5.Cu" "In6.Cu"
			"In7.Cu" "In8.Cu" "In9.Cu" "In10.Cu" "In11.Cu" "In12.Cu" "In13.Cu" "In14.Cu"
			"In15.Cu" "In16.Cu"
		)
		(hatch none 0.5)
		(connect_pads
			(clearance 0)
		)
		(min_thickness 0.25)
		(keepout
			(tracks not_allowed)
			(vias allowed)
			(pads allowed)
			(copperpour not_allowed)
			(footprints allowed)
		)
		(placement
			(enabled no)
			(sheetname "")
		)
		(fill
			(thermal_gap 0.5)
			(thermal_bridge_width 0.5)
			(island_removal_mode 0)
		)
		(polygon
			(pts
				(arc
					(start 90.064336 -389.634476)
					(mid 90.174307 -389.73553)
					(end 90.319098 -389.772144)
				)
				(arc
					(start 90.319098 -389.772144)
					(mid 90.534624 -389.68287)
					(end 90.623898 -389.467344)
				)
				(arc
					(start 90.623898 -389.467344)
					(mid 90.613561 -389.388605)
					(end 90.583258 -389.315198)
				)
				(arc
					(start 90.190828 -388.636256)
					(mid 90.078431 -388.514639)
					(end 89.919048 -388.469632)
				)
				(arc
					(start 89.919048 -388.469632)
					(mid 89.703522 -388.558906)
					(end 89.614248 -388.774432)
				)
				(arc
					(start 89.614248 -388.774432)
					(mid 89.623826 -388.850494)
					(end 89.652094 -388.921752)
				)
				(xy 90.04935 -389.609076) (xy 90.061542 -389.630412) (xy 90.064082 -389.63473)
			)
		)
	)
	(zone
		(layers "F.Cu" "B.Cu" "In1.Cu" "In2.Cu" "In3.Cu" "In4.Cu" "In5.Cu" "In6.Cu"
			"In7.Cu" "In8.Cu" "In9.Cu" "In10.Cu" "In11.Cu" "In12.Cu" "In13.Cu" "In14.Cu"
			"In15.Cu" "In16.Cu"
		)
		(hatch none 0.5)
		(connect_pads
			(clearance 0)
		)
		(min_thickness 0.25)
		(keepout
			(tracks not_allowed)
			(vias allowed)
			(pads allowed)
			(copperpour not_allowed)
			(footprints allowed)
		)
		(placement
			(enabled no)
			(sheetname "")
		)
		(fill
			(thermal_gap 0.5)
			(thermal_bridge_width 0.5)
			(island_removal_mode 0)
		)
		(polygon
			(pts
				(arc
					(start 308.388766 -418.031168)
					(mid 308.007766 -418.412168)
					(end 308.388766 -418.793168)
				)
				(arc
					(start 309.252366 -418.793168)
					(mid 309.633366 -418.412168)
					(end 309.252366 -418.031168)
				)
			)
		)
	)
	(zone
		(layers "F.Cu" "B.Cu" "In1.Cu" "In2.Cu" "In3.Cu" "In4.Cu" "In5.Cu" "In6.Cu"
			"In7.Cu" "In8.Cu" "In9.Cu" "In10.Cu" "In11.Cu" "In12.Cu" "In13.Cu" "In14.Cu"
			"In15.Cu" "In16.Cu"
		)
		(hatch none 0.5)
		(connect_pads
			(clearance 0)
		)
		(min_thickness 0.25)
		(keepout
			(tracks not_allowed)
			(vias allowed)
			(pads allowed)
			(copperpour not_allowed)
			(footprints allowed)
		)
		(placement
			(enabled no)
			(sheetname "")
		)
		(fill
			(thermal_gap 0.5)
			(thermal_bridge_width 0.5)
			(island_removal_mode 0)
		)
		(polygon
			(pts
				(arc
					(start 324.541896 -377.03633)
					(mid 324.160896 -377.41733)
					(end 324.541896 -377.79833)
				)
				(arc
					(start 325.405496 -377.79833)
					(mid 325.786496 -377.41733)
					(end 325.405496 -377.03633)
				)
			)
		)
	)
	(zone
		(layers "F.Cu" "B.Cu" "In1.Cu" "In2.Cu" "In3.Cu" "In4.Cu" "In5.Cu" "In6.Cu"
			"In7.Cu" "In8.Cu" "In9.Cu" "In10.Cu" "In11.Cu" "In12.Cu" "In13.Cu" "In14.Cu"
			"In15.Cu" "In16.Cu"
		)
		(hatch none 0.5)
		(connect_pads
			(clearance 0)
		)
		(min_thickness 0.25)
		(keepout
			(tracks not_allowed)
			(vias allowed)
			(pads allowed)
			(copperpour not_allowed)
			(footprints allowed)
		)
		(placement
			(enabled no)
			(sheetname "")
		)
		(fill
			(thermal_gap 0.5)
			(thermal_bridge_width 0.5)
			(island_removal_mode 0)
		)
		(polygon
			(pts
				(arc
					(start 142.642844 -371.11813)
					(mid 142.261844 -371.49913)
					(end 142.642844 -371.88013)
				)
				(arc
					(start 143.506444 -371.88013)
					(mid 143.887444 -371.49913)
					(end 143.506444 -371.11813)
				)
			)
		)
	)
	(zone
		(layers "F.Cu" "B.Cu" "In1.Cu" "In2.Cu" "In3.Cu" "In4.Cu" "In5.Cu" "In6.Cu"
			"In7.Cu" "In8.Cu" "In9.Cu" "In10.Cu" "In11.Cu" "In12.Cu" "In13.Cu" "In14.Cu"
			"In15.Cu" "In16.Cu"
		)
		(hatch none 0.5)
		(connect_pads
			(clearance 0)
		)
		(min_thickness 0.25)
		(keepout
			(tracks not_allowed)
			(vias allowed)
			(pads allowed)
			(copperpour not_allowed)
			(footprints allowed)
		)
		(placement
			(enabled no)
			(sheetname "")
		)
		(fill
			(thermal_gap 0.5)
			(thermal_bridge_width 0.5)
			(island_removal_mode 0)
		)
		(polygon
			(pts
				(arc
					(start 161.434018 -170.249596)
					(mid 161.053018 -170.630596)
					(end 161.434018 -171.011596)
				)
				(arc
					(start 162.297618 -171.011596)
					(mid 162.678618 -170.630596)
					(end 162.297618 -170.249596)
				)
			)
		)
	)
	(zone
		(layers "F.Cu" "B.Cu" "In1.Cu" "In2.Cu" "In3.Cu" "In4.Cu" "In5.Cu" "In6.Cu"
			"In7.Cu" "In8.Cu" "In9.Cu" "In10.Cu" "In11.Cu" "In12.Cu" "In13.Cu" "In14.Cu"
			"In15.Cu" "In16.Cu"
		)
		(hatch none 0.5)
		(connect_pads
			(clearance 0)
		)
		(min_thickness 0.25)
		(keepout
			(tracks not_allowed)
			(vias allowed)
			(pads allowed)
			(copperpour not_allowed)
			(footprints allowed)
		)
		(placement
			(enabled no)
			(sheetname "")
		)
		(fill
			(thermal_gap 0.5)
			(thermal_bridge_width 0.5)
			(island_removal_mode 0)
		)
		(polygon
			(pts
				(arc
					(start 152.364186 -389.634476)
					(mid 152.474157 -389.73553)
					(end 152.618948 -389.772144)
				)
				(arc
					(start 152.618948 -389.772144)
					(mid 152.834474 -389.68287)
					(end 152.923748 -389.467344)
				)
				(arc
					(start 152.923748 -389.467344)
					(mid 152.913411 -389.388605)
					(end 152.883108 -389.315198)
				)
				(arc
					(start 152.490678 -388.636256)
					(mid 152.378281 -388.514639)
					(end 152.218898 -388.469632)
				)
				(arc
					(start 152.218898 -388.469632)
					(mid 152.003372 -388.558906)
					(end 151.914098 -388.774432)
				)
				(arc
					(start 151.914098 -388.774432)
					(mid 151.923676 -388.850494)
					(end 151.951944 -388.921752)
				)
				(xy 152.3492 -389.609076) (xy 152.361392 -389.630412) (xy 152.363932 -389.63473)
			)
		)
	)
	(zone
		(layers "F.Cu" "B.Cu" "In1.Cu" "In2.Cu" "In3.Cu" "In4.Cu" "In5.Cu" "In6.Cu"
			"In7.Cu" "In8.Cu" "In9.Cu" "In10.Cu" "In11.Cu" "In12.Cu" "In13.Cu" "In14.Cu"
			"In15.Cu" "In16.Cu"
		)
		(hatch none 0.5)
		(connect_pads
			(clearance 0)
		)
		(min_thickness 0.25)
		(keepout
			(tracks not_allowed)
			(vias allowed)
			(pads allowed)
			(copperpour not_allowed)
			(footprints allowed)
		)
		(placement
			(enabled no)
			(sheetname "")
		)
		(fill
			(thermal_gap 0.5)
			(thermal_bridge_width 0.5)
			(island_removal_mode 0)
		)
		(polygon
			(pts
				(arc
					(start 152.625298 -392.429238)
					(mid 152.244298 -392.048238)
					(end 151.863298 -392.429238)
				)
				(arc
					(start 151.863298 -393.292838)
					(mid 152.244298 -393.673838)
					(end 152.625298 -393.292838)
				)
			)
		)
	)
	(zone
		(layers "F.Cu" "B.Cu" "In1.Cu" "In2.Cu" "In3.Cu" "In4.Cu" "In5.Cu" "In6.Cu"
			"In7.Cu" "In8.Cu" "In9.Cu" "In10.Cu" "In11.Cu" "In12.Cu" "In13.Cu" "In14.Cu"
			"In15.Cu" "In16.Cu"
		)
		(hatch none 0.5)
		(connect_pads
			(clearance 0)
		)
		(min_thickness 0.25)
		(keepout
			(tracks not_allowed)
			(vias allowed)
			(pads allowed)
			(copperpour not_allowed)
			(footprints allowed)
		)
		(placement
			(enabled no)
			(sheetname "")
		)
		(fill
			(thermal_gap 0.5)
			(thermal_bridge_width 0.5)
			(island_removal_mode 0)
		)
		(polygon
			(pts
				(arc
					(start 58.14187 -424.360594)
					(mid 58.164188 -424.414476)
					(end 58.21807 -424.436794)
				)
				(arc
					(start 59.15787 -424.436794)
					(mid 59.211752 -424.414476)
					(end 59.23407 -424.360594)
				)
				(arc
					(start 59.23407 -421.81907)
					(mid 59.211752 -421.765188)
					(end 59.15787 -421.74287)
				)
				(arc
					(start 58.21807 -421.74287)
					(mid 58.164188 -421.765188)
					(end 58.14187 -421.81907)
				)
			)
		)
	)
	(zone
		(layers "F.Cu" "B.Cu" "In1.Cu" "In2.Cu" "In3.Cu" "In4.Cu" "In5.Cu" "In6.Cu"
			"In7.Cu" "In8.Cu" "In9.Cu" "In10.Cu" "In11.Cu" "In12.Cu" "In13.Cu" "In14.Cu"
			"In15.Cu" "In16.Cu"
		)
		(hatch none 0.5)
		(connect_pads
			(clearance 0)
		)
		(min_thickness 0.25)
		(keepout
			(tracks not_allowed)
			(vias allowed)
			(pads allowed)
			(copperpour not_allowed)
			(footprints allowed)
		)
		(placement
			(enabled no)
			(sheetname "")
		)
		(fill
			(thermal_gap 0.5)
			(thermal_bridge_width 0.5)
			(island_removal_mode 0)
		)
		(polygon
			(pts
				(arc
					(start 380.083822 -420.571168)
					(mid 379.702822 -420.952168)
					(end 380.083822 -421.333168)
				)
				(arc
					(start 380.947422 -421.333168)
					(mid 381.328422 -420.952168)
					(end 380.947422 -420.571168)
				)
			)
		)
	)
	(zone
		(layers "F.Cu" "B.Cu" "In1.Cu" "In2.Cu" "In3.Cu" "In4.Cu" "In5.Cu" "In6.Cu"
			"In7.Cu" "In8.Cu" "In9.Cu" "In10.Cu" "In11.Cu" "In12.Cu" "In13.Cu" "In14.Cu"
			"In15.Cu" "In16.Cu"
		)
		(hatch none 0.5)
		(connect_pads
			(clearance 0)
		)
		(min_thickness 0.25)
		(keepout
			(tracks not_allowed)
			(vias allowed)
			(pads allowed)
			(copperpour not_allowed)
			(footprints allowed)
		)
		(placement
			(enabled no)
			(sheetname "")
		)
		(fill
			(thermal_gap 0.5)
			(thermal_bridge_width 0.5)
			(island_removal_mode 0)
		)
		(polygon
			(pts
				(arc
					(start 397.29156 -395.308074)
					(mid 396.91056 -394.927074)
					(end 396.52956 -395.308074)
				)
				(arc
					(start 396.52956 -396.171674)
					(mid 396.91056 -396.552674)
					(end 397.29156 -396.171674)
				)
			)
		)
	)
	(zone
		(layers "F.Cu" "B.Cu" "In1.Cu" "In2.Cu" "In3.Cu" "In4.Cu" "In5.Cu" "In6.Cu"
			"In7.Cu" "In8.Cu" "In9.Cu" "In10.Cu" "In11.Cu" "In12.Cu" "In13.Cu" "In14.Cu"
			"In15.Cu" "In16.Cu"
		)
		(hatch none 0.5)
		(connect_pads
			(clearance 0)
		)
		(min_thickness 0.25)
		(keepout
			(tracks not_allowed)
			(vias allowed)
			(pads allowed)
			(copperpour not_allowed)
			(footprints allowed)
		)
		(placement
			(enabled no)
			(sheetname "")
		)
		(fill
			(thermal_gap 0.5)
			(thermal_bridge_width 0.5)
			(island_removal_mode 0)
		)
		(polygon
			(pts
				(arc
					(start 151.652986 -412.189168)
					(mid 151.271986 -412.570168)
					(end 151.652986 -412.951168)
				)
				(arc
					(start 152.516586 -412.951168)
					(mid 152.897586 -412.570168)
					(end 152.516586 -412.189168)
				)
			)
		)
	)
	(zone
		(layers "F.Cu" "B.Cu" "In1.Cu" "In2.Cu" "In3.Cu" "In4.Cu" "In5.Cu" "In6.Cu"
			"In7.Cu" "In8.Cu" "In9.Cu" "In10.Cu" "In11.Cu" "In12.Cu" "In13.Cu" "In14.Cu"
			"In15.Cu" "In16.Cu"
		)
		(hatch none 0.5)
		(connect_pads
			(clearance 0)
		)
		(min_thickness 0.25)
		(keepout
			(tracks not_allowed)
			(vias allowed)
			(pads allowed)
			(copperpour not_allowed)
			(footprints allowed)
		)
		(placement
			(enabled no)
			(sheetname "")
		)
		(fill
			(thermal_gap 0.5)
			(thermal_bridge_width 0.5)
			(island_removal_mode 0)
		)
		(polygon
			(pts
				(arc
					(start 26.709878 -17.23136)
					(mid 26.328878 -17.61236)
					(end 26.709878 -17.99336)
				)
				(arc
					(start 27.573478 -17.99336)
					(mid 27.954478 -17.61236)
					(end 27.573478 -17.23136)
				)
			)
		)
	)
	(zone
		(layers "F.Cu" "B.Cu" "In1.Cu" "In2.Cu" "In3.Cu" "In4.Cu" "In5.Cu" "In6.Cu"
			"In7.Cu" "In8.Cu" "In9.Cu" "In10.Cu" "In11.Cu" "In12.Cu" "In13.Cu" "In14.Cu"
			"In15.Cu" "In16.Cu"
		)
		(hatch none 0.5)
		(connect_pads
			(clearance 0)
		)
		(min_thickness 0.25)
		(keepout
			(tracks not_allowed)
			(vias allowed)
			(pads allowed)
			(copperpour not_allowed)
			(footprints allowed)
		)
		(placement
			(enabled no)
			(sheetname "")
		)
		(fill
			(thermal_gap 0.5)
			(thermal_bridge_width 0.5)
			(island_removal_mode 0)
		)
		(polygon
			(pts
				(arc
					(start 403.74824 -381.96393)
					(mid 403.36724 -382.34493)
					(end 403.74824 -382.72593)
				)
				(arc
					(start 404.61184 -382.72593)
					(mid 404.99284 -382.34493)
					(end 404.61184 -381.96393)
				)
			)
		)
	)
	(zone
		(layers "F.Cu" "B.Cu" "In1.Cu" "In2.Cu" "In3.Cu" "In4.Cu" "In5.Cu" "In6.Cu"
			"In7.Cu" "In8.Cu" "In9.Cu" "In10.Cu" "In11.Cu" "In12.Cu" "In13.Cu" "In14.Cu"
			"In15.Cu" "In16.Cu"
		)
		(hatch none 0.5)
		(connect_pads
			(clearance 0)
		)
		(min_thickness 0.25)
		(keepout
			(tracks not_allowed)
			(vias allowed)
			(pads allowed)
			(copperpour not_allowed)
			(footprints allowed)
		)
		(placement
			(enabled no)
			(sheetname "")
		)
		(fill
			(thermal_gap 0.5)
			(thermal_bridge_width 0.5)
			(island_removal_mode 0)
		)
		(polygon
			(pts
				(arc
					(start 72.300084 -404.08352)
					(mid 71.919084 -404.46452)
					(end 72.300084 -404.84552)
				)
				(arc
					(start 73.163684 -404.84552)
					(mid 73.544684 -404.46452)
					(end 73.163684 -404.08352)
				)
			)
		)
	)
	(zone
		(layers "F.Cu" "B.Cu" "In1.Cu" "In2.Cu" "In3.Cu" "In4.Cu" "In5.Cu" "In6.Cu"
			"In7.Cu" "In8.Cu" "In9.Cu" "In10.Cu" "In11.Cu" "In12.Cu" "In13.Cu" "In14.Cu"
			"In15.Cu" "In16.Cu"
		)
		(hatch none 0.5)
		(connect_pads
			(clearance 0)
		)
		(min_thickness 0.25)
		(keepout
			(tracks not_allowed)
			(vias allowed)
			(pads allowed)
			(copperpour not_allowed)
			(footprints allowed)
		)
		(placement
			(enabled no)
			(sheetname "")
		)
		(fill
			(thermal_gap 0.5)
			(thermal_bridge_width 0.5)
			(island_removal_mode 0)
		)
		(polygon
			(pts
				(arc
					(start 431.834544 -12.483846)
					(mid 431.453544 -12.864846)
					(end 431.834544 -13.245846)
				)
				(arc
					(start 432.698144 -13.245846)
					(mid 433.079144 -12.864846)
					(end 432.698144 -12.483846)
				)
			)
		)
	)
	(zone
		(layers "F.Cu" "B.Cu" "In1.Cu" "In2.Cu" "In3.Cu" "In4.Cu" "In5.Cu" "In6.Cu"
			"In7.Cu" "In8.Cu" "In9.Cu" "In10.Cu" "In11.Cu" "In12.Cu" "In13.Cu" "In14.Cu"
			"In15.Cu" "In16.Cu"
		)
		(hatch none 0.5)
		(connect_pads
			(clearance 0)
		)
		(min_thickness 0.25)
		(keepout
			(tracks not_allowed)
			(vias allowed)
			(pads allowed)
			(copperpour not_allowed)
			(footprints allowed)
		)
		(placement
			(enabled no)
			(sheetname "")
		)
		(fill
			(thermal_gap 0.5)
			(thermal_bridge_width 0.5)
			(island_removal_mode 0)
		)
		(polygon
			(pts
				(arc
					(start 454.94702 -6.169914)
					(mid 453.01662 -6.169914)
					(end 454.94702 -6.169914)
				)
			)
		)
	)
	(zone
		(layers "F.Cu" "B.Cu" "In1.Cu" "In2.Cu" "In3.Cu" "In4.Cu" "In5.Cu" "In6.Cu"
			"In7.Cu" "In8.Cu" "In9.Cu" "In10.Cu" "In11.Cu" "In12.Cu" "In13.Cu" "In14.Cu"
			"In15.Cu" "In16.Cu"
		)
		(hatch none 0.5)
		(connect_pads
			(clearance 0)
		)
		(min_thickness 0.25)
		(keepout
			(tracks not_allowed)
			(vias allowed)
			(pads allowed)
			(copperpour not_allowed)
			(footprints allowed)
		)
		(placement
			(enabled no)
			(sheetname "")
		)
		(fill
			(thermal_gap 0.5)
			(thermal_bridge_width 0.5)
			(island_removal_mode 0)
		)
		(polygon
			(pts
				(arc
					(start 38.925754 -6.344158)
					(mid 38.544754 -6.725158)
					(end 38.925754 -7.106158)
				)
				(arc
					(start 39.789354 -7.106158)
					(mid 40.170354 -6.725158)
					(end 39.789354 -6.344158)
				)
			)
		)
	)
	(zone
		(layers "F.Cu" "B.Cu" "In1.Cu" "In2.Cu" "In3.Cu" "In4.Cu" "In5.Cu" "In6.Cu"
			"In7.Cu" "In8.Cu" "In9.Cu" "In10.Cu" "In11.Cu" "In12.Cu" "In13.Cu" "In14.Cu"
			"In15.Cu" "In16.Cu"
		)
		(hatch none 0.5)
		(connect_pads
			(clearance 0)
		)
		(min_thickness 0.25)
		(keepout
			(tracks not_allowed)
			(vias allowed)
			(pads allowed)
			(copperpour not_allowed)
			(footprints allowed)
		)
		(placement
			(enabled no)
			(sheetname "")
		)
		(fill yes
			(thermal_gap 0.5)
			(thermal_bridge_width 0.5)
			(island_removal_mode 0)
		)
		(polygon
			(pts
				(arc
					(start 80.464406 -386.170424)
					(mid 80.574377 -386.271478)
					(end 80.719168 -386.308092)
				)
				(arc
					(start 80.719168 -386.308092)
					(mid 80.934694 -386.218818)
					(end 81.023968 -386.003292)
				)
				(arc
					(start 81.023968 -386.003292)
					(mid 81.013631 -385.924553)
					(end 80.983328 -385.851146)
				)
				(arc
					(start 80.590898 -385.172204)
					(mid 80.478501 -385.050587)
					(end 80.319118 -385.00558)
				)
				(arc
					(start 80.319118 -385.00558)
					(mid 80.103592 -385.094854)
					(end 80.014318 -385.31038)
				)
				(arc
					(start 80.014318 -385.31038)
					(mid 80.023896 -385.386442)
					(end 80.052164 -385.4577)
				)
				(xy 80.44942 -386.145024) (xy 80.461612 -386.16636) (xy 80.464152 -386.170678)
			)
		)
	)
	(zone
		(layers "F.Cu" "B.Cu" "In1.Cu" "In2.Cu" "In3.Cu" "In4.Cu" "In5.Cu" "In6.Cu"
			"In7.Cu" "In8.Cu" "In9.Cu" "In10.Cu" "In11.Cu" "In12.Cu" "In13.Cu" "In14.Cu"
			"In15.Cu" "In16.Cu"
		)
		(hatch none 0.5)
		(connect_pads
			(clearance 0)
		)
		(min_thickness 0.25)
		(keepout
			(tracks not_allowed)
			(vias allowed)
			(pads allowed)
			(copperpour not_allowed)
			(footprints allowed)
		)
		(placement
			(enabled no)
			(sheetname "")
		)
		(fill
			(thermal_gap 0.5)
			(thermal_bridge_width 0.5)
			(island_removal_mode 0)
		)
		(polygon
			(pts
				(arc
					(start 89.125298 -392.429238)
					(mid 88.744298 -392.048238)
					(end 88.363298 -392.429238)
				)
				(arc
					(start 88.363298 -393.292838)
					(mid 88.744298 -393.673838)
					(end 89.125298 -393.292838)
				)
			)
		)
	)
	(zone
		(layers "F.Cu" "B.Cu" "In1.Cu" "In2.Cu" "In3.Cu" "In4.Cu" "In5.Cu" "In6.Cu"
			"In7.Cu" "In8.Cu" "In9.Cu" "In10.Cu" "In11.Cu" "In12.Cu" "In13.Cu" "In14.Cu"
			"In15.Cu" "In16.Cu"
		)
		(hatch none 0.5)
		(connect_pads
			(clearance 0)
		)
		(min_thickness 0.25)
		(keepout
			(tracks not_allowed)
			(vias allowed)
			(pads allowed)
			(copperpour not_allowed)
			(footprints allowed)
		)
		(placement
			(enabled no)
			(sheetname "")
		)
		(fill
			(thermal_gap 0.5)
			(thermal_bridge_width 0.5)
			(island_removal_mode 0)
		)
		(polygon
			(pts
				(arc
					(start 74.33945 -381.50546)
					(mid 73.95845 -381.12446)
					(end 73.57745 -381.50546)
				)
				(arc
					(start 73.57745 -382.36906)
					(mid 73.95845 -382.75006)
					(end 74.33945 -382.36906)
				)
			)
		)
	)
	(zone
		(layers "F.Cu" "B.Cu" "In1.Cu" "In2.Cu" "In3.Cu" "In4.Cu" "In5.Cu" "In6.Cu"
			"In7.Cu" "In8.Cu" "In9.Cu" "In10.Cu" "In11.Cu" "In12.Cu" "In13.Cu" "In14.Cu"
			"In15.Cu" "In16.Cu"
		)
		(hatch none 0.5)
		(connect_pads
			(clearance 0)
		)
		(min_thickness 0.25)
		(keepout
			(tracks not_allowed)
			(vias allowed)
			(pads allowed)
			(copperpour not_allowed)
			(footprints allowed)
		)
		(placement
			(enabled no)
			(sheetname "")
		)
		(fill yes
			(thermal_gap 0.5)
			(thermal_bridge_width 0.5)
			(island_removal_mode 0)
		)
		(polygon
			(pts
				(arc
					(start 420.364158 -394.552424)
					(mid 420.474129 -394.653478)
					(end 420.61892 -394.690092)
				)
				(arc
					(start 420.61892 -394.690092)
					(mid 420.834446 -394.600818)
					(end 420.92372 -394.385292)
				)
				(arc
					(start 420.92372 -394.385292)
					(mid 420.913383 -394.306553)
					(end 420.88308 -394.233146)
				)
				(arc
					(start 420.49065 -393.554204)
					(mid 420.378253 -393.432587)
					(end 420.21887 -393.38758)
				)
				(arc
					(start 420.21887 -393.38758)
					(mid 420.003344 -393.476854)
					(end 419.91407 -393.69238)
				)
				(arc
					(start 419.91407 -393.69238)
					(mid 419.923648 -393.768442)
					(end 419.951916 -393.8397)
				)
				(xy 420.349172 -394.527024) (xy 420.361364 -394.54836) (xy 420.363904 -394.552678)
			)
		)
	)
	(zone
		(layers "F.Cu" "B.Cu" "In1.Cu" "In2.Cu" "In3.Cu" "In4.Cu" "In5.Cu" "In6.Cu"
			"In7.Cu" "In8.Cu" "In9.Cu" "In10.Cu" "In11.Cu" "In12.Cu" "In13.Cu" "In14.Cu"
			"In15.Cu" "In16.Cu"
		)
		(hatch none 0.5)
		(connect_pads
			(clearance 0)
		)
		(min_thickness 0.25)
		(keepout
			(tracks not_allowed)
			(vias allowed)
			(pads allowed)
			(copperpour not_allowed)
			(footprints allowed)
		)
		(placement
			(enabled no)
			(sheetname "")
		)
		(fill yes
			(thermal_gap 0.5)
			(thermal_bridge_width 0.5)
			(island_removal_mode 0)
		)
		(polygon
			(pts
				(arc
					(start 96.064324 -386.170424)
					(mid 96.174295 -386.271478)
					(end 96.319086 -386.308092)
				)
				(arc
					(start 96.319086 -386.308092)
					(mid 96.534612 -386.218818)
					(end 96.623886 -386.003292)
				)
				(arc
					(start 96.623886 -386.003292)
					(mid 96.613549 -385.924553)
					(end 96.583246 -385.851146)
				)
				(arc
					(start 96.190816 -385.172204)
					(mid 96.078419 -385.050587)
					(end 95.919036 -385.00558)
				)
				(arc
					(start 95.919036 -385.00558)
					(mid 95.70351 -385.094854)
					(end 95.614236 -385.31038)
				)
				(arc
					(start 95.614236 -385.31038)
					(mid 95.623814 -385.386442)
					(end 95.652082 -385.4577)
				)
				(xy 96.049338 -386.145024) (xy 96.06153 -386.16636) (xy 96.06407 -386.170678)
			)
		)
	)
	(zone
		(layers "F.Cu" "B.Cu" "In1.Cu" "In2.Cu" "In3.Cu" "In4.Cu" "In5.Cu" "In6.Cu"
			"In7.Cu" "In8.Cu" "In9.Cu" "In10.Cu" "In11.Cu" "In12.Cu" "In13.Cu" "In14.Cu"
			"In15.Cu" "In16.Cu"
		)
		(hatch none 0.5)
		(connect_pads
			(clearance 0)
		)
		(min_thickness 0.25)
		(keepout
			(tracks not_allowed)
			(vias allowed)
			(pads allowed)
			(copperpour not_allowed)
			(footprints allowed)
		)
		(placement
			(enabled no)
			(sheetname "")
		)
		(fill
			(thermal_gap 0.5)
			(thermal_bridge_width 0.5)
			(island_removal_mode 0)
		)
		(polygon
			(pts
				(arc
					(start 414.625282 -400.811238)
					(mid 414.244282 -400.430238)
					(end 413.863282 -400.811238)
				)
				(arc
					(start 413.863282 -401.674838)
					(mid 414.244282 -402.055838)
					(end 414.625282 -401.674838)
				)
			)
		)
	)
	(zone
		(layers "F.Cu" "B.Cu" "In1.Cu" "In2.Cu" "In3.Cu" "In4.Cu" "In5.Cu" "In6.Cu"
			"In7.Cu" "In8.Cu" "In9.Cu" "In10.Cu" "In11.Cu" "In12.Cu" "In13.Cu" "In14.Cu"
			"In15.Cu" "In16.Cu"
		)
		(hatch none 0.5)
		(connect_pads
			(clearance 0)
		)
		(min_thickness 0.25)
		(keepout
			(tracks not_allowed)
			(vias allowed)
			(pads allowed)
			(copperpour not_allowed)
			(footprints allowed)
		)
		(placement
			(enabled no)
			(sheetname "")
		)
		(fill
			(thermal_gap 0.5)
			(thermal_bridge_width 0.5)
			(island_removal_mode 0)
		)
		(polygon
			(pts
				(arc
					(start 303.793906 -420.571168)
					(mid 303.412906 -420.952168)
					(end 303.793906 -421.333168)
				)
				(arc
					(start 304.657506 -421.333168)
					(mid 305.038506 -420.952168)
					(end 304.657506 -420.571168)
				)
			)
		)
	)
	(zone
		(layers "F.Cu" "B.Cu" "In1.Cu" "In2.Cu" "In3.Cu" "In4.Cu" "In5.Cu" "In6.Cu"
			"In7.Cu" "In8.Cu" "In9.Cu" "In10.Cu" "In11.Cu" "In12.Cu" "In13.Cu" "In14.Cu"
			"In15.Cu" "In16.Cu"
		)
		(hatch none 0.5)
		(connect_pads
			(clearance 0)
		)
		(min_thickness 0.25)
		(keepout
			(tracks not_allowed)
			(vias allowed)
			(pads allowed)
			(copperpour not_allowed)
			(footprints allowed)
		)
		(placement
			(enabled no)
			(sheetname "")
		)
		(fill
			(thermal_gap 0.5)
			(thermal_bridge_width 0.5)
			(island_removal_mode 0)
		)
		(polygon
			(pts
				(arc
					(start 148.589746 -412.189168)
					(mid 148.208746 -412.570168)
					(end 148.589746 -412.951168)
				)
				(arc
					(start 149.453346 -412.951168)
					(mid 149.834346 -412.570168)
					(end 149.453346 -412.189168)
				)
			)
		)
	)
	(zone
		(layers "F.Cu" "B.Cu" "In1.Cu" "In2.Cu" "In3.Cu" "In4.Cu" "In5.Cu" "In6.Cu"
			"In7.Cu" "In8.Cu" "In9.Cu" "In10.Cu" "In11.Cu" "In12.Cu" "In13.Cu" "In14.Cu"
			"In15.Cu" "In16.Cu"
		)
		(hatch none 0.5)
		(connect_pads
			(clearance 0)
		)
		(min_thickness 0.25)
		(keepout
			(tracks not_allowed)
			(vias allowed)
			(pads allowed)
			(copperpour not_allowed)
			(footprints allowed)
		)
		(placement
			(enabled no)
			(sheetname "")
		)
		(fill
			(thermal_gap 0.5)
			(thermal_bridge_width 0.5)
			(island_removal_mode 0)
		)
		(polygon
			(pts
				(arc
					(start 37.884862 -17.232122)
					(mid 37.503862 -17.613122)
					(end 37.884862 -17.994122)
				)
				(arc
					(start 38.748462 -17.994122)
					(mid 39.129462 -17.613122)
					(end 38.748462 -17.232122)
				)
			)
		)
	)
	(zone
		(layers "F.Cu" "B.Cu" "In1.Cu" "In2.Cu" "In3.Cu" "In4.Cu" "In5.Cu" "In6.Cu"
			"In7.Cu" "In8.Cu" "In9.Cu" "In10.Cu" "In11.Cu" "In12.Cu" "In13.Cu" "In14.Cu"
			"In15.Cu" "In16.Cu"
		)
		(hatch none 0.5)
		(connect_pads
			(clearance 0)
		)
		(min_thickness 0.25)
		(keepout
			(tracks not_allowed)
			(vias allowed)
			(pads allowed)
			(copperpour not_allowed)
			(footprints allowed)
		)
		(placement
			(enabled no)
			(sheetname "")
		)
		(fill
			(thermal_gap 0.5)
			(thermal_bridge_width 0.5)
			(island_removal_mode 0)
		)
		(polygon
			(pts
				(arc
					(start 348.464124 -398.016476)
					(mid 348.574095 -398.11753)
					(end 348.718886 -398.154144)
				)
				(arc
					(start 348.718886 -398.154144)
					(mid 348.934412 -398.06487)
					(end 349.023686 -397.849344)
				)
				(arc
					(start 349.023686 -397.849344)
					(mid 349.013349 -397.770605)
					(end 348.983046 -397.697198)
				)
				(arc
					(start 348.590616 -397.018256)
					(mid 348.478219 -396.896639)
					(end 348.318836 -396.851632)
				)
				(arc
					(start 348.318836 -396.851632)
					(mid 348.10331 -396.940906)
					(end 348.014036 -397.156432)
				)
				(arc
					(start 348.014036 -397.156432)
					(mid 348.023614 -397.232494)
					(end 348.051882 -397.303752)
				)
				(xy 348.449138 -397.991076) (xy 348.46133 -398.012412) (xy 348.46387 -398.01673)
			)
		)
	)
	(zone
		(layers "F.Cu" "B.Cu" "In1.Cu" "In2.Cu" "In3.Cu" "In4.Cu" "In5.Cu" "In6.Cu"
			"In7.Cu" "In8.Cu" "In9.Cu" "In10.Cu" "In11.Cu" "In12.Cu" "In13.Cu" "In14.Cu"
			"In15.Cu" "In16.Cu"
		)
		(hatch none 0.5)
		(connect_pads
			(clearance 0)
		)
		(min_thickness 0.25)
		(keepout
			(tracks not_allowed)
			(vias allowed)
			(pads allowed)
			(copperpour not_allowed)
			(footprints allowed)
		)
		(placement
			(enabled no)
			(sheetname "")
		)
		(fill yes
			(thermal_gap 0.5)
			(thermal_bridge_width 0.5)
			(island_removal_mode 0)
		)
		(polygon
			(pts
				(arc
					(start 121.036588 -386.170424)
					(mid 121.146559 -386.271478)
					(end 121.29135 -386.308092)
				)
				(arc
					(start 121.29135 -386.308092)
					(mid 121.506876 -386.218818)
					(end 121.59615 -386.003292)
				)
				(arc
					(start 121.59615 -386.003292)
					(mid 121.585813 -385.924553)
					(end 121.55551 -385.851146)
				)
				(arc
					(start 121.16308 -385.172204)
					(mid 121.050683 -385.050587)
					(end 120.8913 -385.00558)
				)
				(arc
					(start 120.8913 -385.00558)
					(mid 120.675774 -385.094854)
					(end 120.5865 -385.31038)
				)
				(arc
					(start 120.5865 -385.31038)
					(mid 120.596078 -385.386442)
					(end 120.624346 -385.4577)
				)
				(xy 121.021602 -386.145024) (xy 121.033794 -386.16636) (xy 121.036334 -386.170678)
			)
		)
	)
	(zone
		(layers "F.Cu" "B.Cu" "In1.Cu" "In2.Cu" "In3.Cu" "In4.Cu" "In5.Cu" "In6.Cu"
			"In7.Cu" "In8.Cu" "In9.Cu" "In10.Cu" "In11.Cu" "In12.Cu" "In13.Cu" "In14.Cu"
			"In15.Cu" "In16.Cu"
		)
		(hatch none 0.5)
		(connect_pads
			(clearance 0)
		)
		(min_thickness 0.25)
		(keepout
			(tracks not_allowed)
			(vias allowed)
			(pads allowed)
			(copperpour not_allowed)
			(footprints allowed)
		)
		(placement
			(enabled no)
			(sheetname "")
		)
		(fill
			(thermal_gap 0.5)
			(thermal_bridge_width 0.5)
			(island_removal_mode 0)
		)
		(polygon
			(pts
				(arc
					(start 66.19748 -392.429238)
					(mid 65.81648 -392.048238)
					(end 65.43548 -392.429238)
				)
				(arc
					(start 65.43548 -393.292838)
					(mid 65.81648 -393.673838)
					(end 66.19748 -393.292838)
				)
			)
		)
	)
	(zone
		(layers "F.Cu" "B.Cu" "In1.Cu" "In2.Cu" "In3.Cu" "In4.Cu" "In5.Cu" "In6.Cu"
			"In7.Cu" "In8.Cu" "In9.Cu" "In10.Cu" "In11.Cu" "In12.Cu" "In13.Cu" "In14.Cu"
			"In15.Cu" "In16.Cu"
		)
		(hatch none 0.5)
		(connect_pads
			(clearance 0)
		)
		(min_thickness 0.25)
		(keepout
			(tracks not_allowed)
			(vias allowed)
			(pads allowed)
			(copperpour not_allowed)
			(footprints allowed)
		)
		(placement
			(enabled no)
			(sheetname "")
		)
		(fill yes
			(thermal_gap 0.5)
			(thermal_bridge_width 0.5)
			(island_removal_mode 0)
		)
		(polygon
			(pts
				(arc
					(start 410.764228 -394.552424)
					(mid 410.874199 -394.653478)
					(end 411.01899 -394.690092)
				)
				(arc
					(start 411.01899 -394.690092)
					(mid 411.234516 -394.600818)
					(end 411.32379 -394.385292)
				)
				(arc
					(start 411.32379 -394.385292)
					(mid 411.313453 -394.306553)
					(end 411.28315 -394.233146)
				)
				(arc
					(start 410.89072 -393.554204)
					(mid 410.778323 -393.432587)
					(end 410.61894 -393.38758)
				)
				(arc
					(start 410.61894 -393.38758)
					(mid 410.403414 -393.476854)
					(end 410.31414 -393.69238)
				)
				(arc
					(start 410.31414 -393.69238)
					(mid 410.323718 -393.768442)
					(end 410.351986 -393.8397)
				)
				(xy 410.749242 -394.527024) (xy 410.761434 -394.54836) (xy 410.763974 -394.552678)
			)
		)
	)
	(zone
		(layers "F.Cu" "B.Cu" "In1.Cu" "In2.Cu" "In3.Cu" "In4.Cu" "In5.Cu" "In6.Cu"
			"In7.Cu" "In8.Cu" "In9.Cu" "In10.Cu" "In11.Cu" "In12.Cu" "In13.Cu" "In14.Cu"
			"In15.Cu" "In16.Cu"
		)
		(hatch none 0.5)
		(connect_pads
			(clearance 0)
		)
		(min_thickness 0.25)
		(keepout
			(tracks not_allowed)
			(vias allowed)
			(pads allowed)
			(copperpour not_allowed)
			(footprints allowed)
		)
		(placement
			(enabled no)
			(sheetname "")
		)
		(fill
			(thermal_gap 0.5)
			(thermal_bridge_width 0.5)
			(island_removal_mode 0)
		)
		(polygon
			(pts
				(arc
					(start 418.374322 -415.00552)
					(mid 417.993322 -415.38652)
					(end 418.374322 -415.76752)
				)
				(arc
					(start 419.237922 -415.76752)
					(mid 419.618922 -415.38652)
					(end 419.237922 -415.00552)
				)
			)
		)
	)
	(zone
		(layers "F.Cu" "B.Cu" "In1.Cu" "In2.Cu" "In3.Cu" "In4.Cu" "In5.Cu" "In6.Cu"
			"In7.Cu" "In8.Cu" "In9.Cu" "In10.Cu" "In11.Cu" "In12.Cu" "In13.Cu" "In14.Cu"
			"In15.Cu" "In16.Cu"
		)
		(hatch none 0.5)
		(connect_pads
			(clearance 0)
		)
		(min_thickness 0.25)
		(keepout
			(tracks not_allowed)
			(vias allowed)
			(pads allowed)
			(copperpour not_allowed)
			(footprints allowed)
		)
		(placement
			(enabled no)
			(sheetname "")
		)
		(fill
			(thermal_gap 0.5)
			(thermal_bridge_width 0.5)
			(island_removal_mode 0)
		)
		(polygon
			(pts
				(arc
					(start 121.020586 -412.189168)
					(mid 120.639586 -412.570168)
					(end 121.020586 -412.951168)
				)
				(arc
					(start 121.884186 -412.951168)
					(mid 122.265186 -412.570168)
					(end 121.884186 -412.189168)
				)
			)
		)
	)
	(zone
		(layers "F.Cu" "B.Cu" "In1.Cu" "In2.Cu" "In3.Cu" "In4.Cu" "In5.Cu" "In6.Cu"
			"In7.Cu" "In8.Cu" "In9.Cu" "In10.Cu" "In11.Cu" "In12.Cu" "In13.Cu" "In14.Cu"
			"In15.Cu" "In16.Cu"
		)
		(hatch none 0.5)
		(connect_pads
			(clearance 0)
		)
		(min_thickness 0.25)
		(keepout
			(tracks not_allowed)
			(vias allowed)
			(pads allowed)
			(copperpour not_allowed)
			(footprints allowed)
		)
		(placement
			(enabled no)
			(sheetname "")
		)
		(fill
			(thermal_gap 0.5)
			(thermal_bridge_width 0.5)
			(island_removal_mode 0)
		)
		(polygon
			(pts
				(arc
					(start 150.225252 -392.429238)
					(mid 149.844252 -392.048238)
					(end 149.463252 -392.429238)
				)
				(arc
					(start 149.463252 -393.292838)
					(mid 149.844252 -393.673838)
					(end 150.225252 -393.292838)
				)
			)
		)
	)
	(zone
		(layers "F.Cu" "B.Cu" "In1.Cu" "In2.Cu" "In3.Cu" "In4.Cu" "In5.Cu" "In6.Cu"
			"In7.Cu" "In8.Cu" "In9.Cu" "In10.Cu" "In11.Cu" "In12.Cu" "In13.Cu" "In14.Cu"
			"In15.Cu" "In16.Cu"
		)
		(hatch none 0.5)
		(connect_pads
			(clearance 0)
		)
		(min_thickness 0.25)
		(keepout
			(tracks not_allowed)
			(vias allowed)
			(pads allowed)
			(copperpour not_allowed)
			(footprints allowed)
		)
		(placement
			(enabled no)
			(sheetname "")
		)
		(fill
			(thermal_gap 0.5)
			(thermal_bridge_width 0.5)
			(island_removal_mode 0)
		)
		(polygon
			(pts
				(arc
					(start 418.374322 -418.031168)
					(mid 417.993322 -418.412168)
					(end 418.374322 -418.793168)
				)
				(arc
					(start 419.237922 -418.793168)
					(mid 419.618922 -418.412168)
					(end 419.237922 -418.031168)
				)
			)
		)
	)
	(zone
		(layers "F.Cu" "B.Cu" "In1.Cu" "In2.Cu" "In3.Cu" "In4.Cu" "In5.Cu" "In6.Cu"
			"In7.Cu" "In8.Cu" "In9.Cu" "In10.Cu" "In11.Cu" "In12.Cu" "In13.Cu" "In14.Cu"
			"In15.Cu" "In16.Cu"
		)
		(hatch none 0.5)
		(connect_pads
			(clearance 0)
		)
		(min_thickness 0.25)
		(keepout
			(tracks not_allowed)
			(vias allowed)
			(pads allowed)
			(copperpour not_allowed)
			(footprints allowed)
		)
		(placement
			(enabled no)
			(sheetname "")
		)
		(fill
			(thermal_gap 0.5)
			(thermal_bridge_width 0.5)
			(island_removal_mode 0)
		)
		(polygon
			(pts
				(arc
					(start 404.589742 -412.46552)
					(mid 404.208742 -412.84652)
					(end 404.589742 -413.22752)
				)
				(arc
					(start 405.453342 -413.22752)
					(mid 405.834342 -412.84652)
					(end 405.453342 -412.46552)
				)
			)
		)
	)
	(zone
		(layers "F.Cu" "B.Cu" "In1.Cu" "In2.Cu" "In3.Cu" "In4.Cu" "In5.Cu" "In6.Cu"
			"In7.Cu" "In8.Cu" "In9.Cu" "In10.Cu" "In11.Cu" "In12.Cu" "In13.Cu" "In14.Cu"
			"In15.Cu" "In16.Cu"
		)
		(hatch none 0.5)
		(connect_pads
			(clearance 0)
		)
		(min_thickness 0.25)
		(keepout
			(tracks not_allowed)
			(vias allowed)
			(pads allowed)
			(copperpour not_allowed)
			(footprints allowed)
		)
		(placement
			(enabled no)
			(sheetname "")
		)
		(fill
			(thermal_gap 0.5)
			(thermal_bridge_width 0.5)
			(island_removal_mode 0)
		)
		(polygon
			(pts
				(arc
					(start 314.736226 -394.552424)
					(mid 314.846197 -394.653478)
					(end 314.990988 -394.690092)
				)
				(arc
					(start 314.990988 -394.690092)
					(mid 315.206514 -394.600818)
					(end 315.295788 -394.385292)
				)
				(arc
					(start 315.295788 -394.385292)
					(mid 315.285451 -394.306553)
					(end 315.255148 -394.233146)
				)
				(arc
					(start 314.862718 -393.554204)
					(mid 314.750321 -393.432587)
					(end 314.590938 -393.38758)
				)
				(arc
					(start 314.590938 -393.38758)
					(mid 314.375412 -393.476854)
					(end 314.286138 -393.69238)
				)
				(arc
					(start 314.286138 -393.69238)
					(mid 314.295716 -393.768442)
					(end 314.323984 -393.8397)
				)
				(xy 314.72124 -394.527024) (xy 314.733432 -394.54836) (xy 314.735972 -394.552678)
			)
		)
	)
	(zone
		(layers "F.Cu" "B.Cu" "In1.Cu" "In2.Cu" "In3.Cu" "In4.Cu" "In5.Cu" "In6.Cu"
			"In7.Cu" "In8.Cu" "In9.Cu" "In10.Cu" "In11.Cu" "In12.Cu" "In13.Cu" "In14.Cu"
			"In15.Cu" "In16.Cu"
		)
		(hatch none 0.5)
		(connect_pads
			(clearance 0)
		)
		(min_thickness 0.25)
		(keepout
			(tracks not_allowed)
			(vias allowed)
			(pads allowed)
			(copperpour not_allowed)
			(footprints allowed)
		)
		(placement
			(enabled no)
			(sheetname "")
		)
		(fill
			(thermal_gap 0.5)
			(thermal_bridge_width 0.5)
			(island_removal_mode 0)
		)
		(polygon
			(pts
				(arc
					(start 332.894686 -418.031168)
					(mid 332.513686 -418.412168)
					(end 332.894686 -418.793168)
				)
				(arc
					(start 333.758286 -418.793168)
					(mid 334.139286 -418.412168)
					(end 333.758286 -418.031168)
				)
			)
		)
	)
	(zone
		(layers "F.Cu" "B.Cu" "In1.Cu" "In2.Cu" "In3.Cu" "In4.Cu" "In5.Cu" "In6.Cu"
			"In7.Cu" "In8.Cu" "In9.Cu" "In10.Cu" "In11.Cu" "In12.Cu" "In13.Cu" "In14.Cu"
			"In15.Cu" "In16.Cu"
		)
		(hatch none 0.5)
		(connect_pads
			(clearance 0)
		)
		(min_thickness 0.25)
		(keepout
			(tracks not_allowed)
			(vias allowed)
			(pads allowed)
			(copperpour not_allowed)
			(footprints allowed)
		)
		(placement
			(enabled no)
			(sheetname "")
		)
		(fill
			(thermal_gap 0.5)
			(thermal_bridge_width 0.5)
			(island_removal_mode 0)
		)
		(polygon
			(pts
				(arc
					(start 94.106746 -209.023458)
					(mid 94.487746 -209.404458)
					(end 94.868746 -209.023458)
				)
				(arc
					(start 94.868746 -208.159858)
					(mid 94.487746 -207.778858)
					(end 94.106746 -208.159858)
				)
			)
		)
	)
	(zone
		(layers "F.Cu" "B.Cu" "In1.Cu" "In2.Cu" "In3.Cu" "In4.Cu" "In5.Cu" "In6.Cu"
			"In7.Cu" "In8.Cu" "In9.Cu" "In10.Cu" "In11.Cu" "In12.Cu" "In13.Cu" "In14.Cu"
			"In15.Cu" "In16.Cu"
		)
		(hatch none 0.5)
		(connect_pads
			(clearance 0)
		)
		(min_thickness 0.25)
		(keepout
			(tracks not_allowed)
			(vias allowed)
			(pads allowed)
			(copperpour not_allowed)
			(footprints allowed)
		)
		(placement
			(enabled no)
			(sheetname "")
		)
		(fill
			(thermal_gap 0.5)
			(thermal_bridge_width 0.5)
			(island_removal_mode 0)
		)
		(polygon
			(pts
				(arc
					(start 90.679524 -412.189168)
					(mid 90.298524 -412.570168)
					(end 90.679524 -412.951168)
				)
				(arc
					(start 91.543124 -412.951168)
					(mid 91.924124 -412.570168)
					(end 91.543124 -412.189168)
				)
			)
		)
	)
	(zone
		(layers "F.Cu" "B.Cu" "In1.Cu" "In2.Cu" "In3.Cu" "In4.Cu" "In5.Cu" "In6.Cu"
			"In7.Cu" "In8.Cu" "In9.Cu" "In10.Cu" "In11.Cu" "In12.Cu" "In13.Cu" "In14.Cu"
			"In15.Cu" "In16.Cu"
		)
		(hatch none 0.5)
		(connect_pads
			(clearance 0)
		)
		(min_thickness 0.25)
		(keepout
			(tracks not_allowed)
			(vias allowed)
			(pads allowed)
			(copperpour not_allowed)
			(footprints allowed)
		)
		(placement
			(enabled no)
			(sheetname "")
		)
		(fill
			(thermal_gap 0.5)
			(thermal_bridge_width 0.5)
			(island_removal_mode 0)
		)
		(polygon
			(pts
				(arc
					(start 371.297454 -400.811238)
					(mid 370.916454 -400.430238)
					(end 370.535454 -400.811238)
				)
				(arc
					(start 370.535454 -401.674838)
					(mid 370.916454 -402.055838)
					(end 371.297454 -401.674838)
				)
			)
		)
	)
	(zone
		(layers "F.Cu" "B.Cu" "In1.Cu" "In2.Cu" "In3.Cu" "In4.Cu" "In5.Cu" "In6.Cu"
			"In7.Cu" "In8.Cu" "In9.Cu" "In10.Cu" "In11.Cu" "In12.Cu" "In13.Cu" "In14.Cu"
			"In15.Cu" "In16.Cu"
		)
		(hatch none 0.5)
		(connect_pads
			(clearance 0)
		)
		(min_thickness 0.25)
		(keepout
			(tracks not_allowed)
			(vias allowed)
			(pads allowed)
			(copperpour not_allowed)
			(footprints allowed)
		)
		(placement
			(enabled no)
			(sheetname "")
		)
		(fill
			(thermal_gap 0.5)
			(thermal_bridge_width 0.5)
			(island_removal_mode 0)
		)
		(polygon
			(pts
				(arc
					(start 38.97503 -413.4485)
					(mid 39.35603 -413.8295)
					(end 39.73703 -413.4485)
				)
				(arc
					(start 39.73703 -412.5849)
					(mid 39.35603 -412.2039)
					(end 38.97503 -412.5849)
				)
			)
		)
	)
	(zone
		(layers "F.Cu" "B.Cu" "In1.Cu" "In2.Cu" "In3.Cu" "In4.Cu" "In5.Cu" "In6.Cu"
			"In7.Cu" "In8.Cu" "In9.Cu" "In10.Cu" "In11.Cu" "In12.Cu" "In13.Cu" "In14.Cu"
			"In15.Cu" "In16.Cu"
		)
		(hatch none 0.5)
		(connect_pads
			(clearance 0)
		)
		(min_thickness 0.25)
		(keepout
			(tracks not_allowed)
			(vias allowed)
			(pads allowed)
			(copperpour not_allowed)
			(footprints allowed)
		)
		(placement
			(enabled no)
			(sheetname "")
		)
		(fill
			(thermal_gap 0.5)
			(thermal_bridge_width 0.5)
			(island_removal_mode 0)
		)
		(polygon
			(pts
				(arc
					(start 111.322104 -409.040076)
					(mid 110.941104 -408.659076)
					(end 110.560104 -409.040076)
				)
				(arc
					(start 110.560104 -409.903676)
					(mid 110.941104 -410.284676)
					(end 111.322104 -409.903676)
				)
			)
		)
	)
	(zone
		(layers "F.Cu" "B.Cu" "In1.Cu" "In2.Cu" "In3.Cu" "In4.Cu" "In5.Cu" "In6.Cu"
			"In7.Cu" "In8.Cu" "In9.Cu" "In10.Cu" "In11.Cu" "In12.Cu" "In13.Cu" "In14.Cu"
			"In15.Cu" "In16.Cu"
		)
		(hatch none 0.5)
		(connect_pads
			(clearance 0)
		)
		(min_thickness 0.25)
		(keepout
			(tracks not_allowed)
			(vias allowed)
			(pads allowed)
			(copperpour not_allowed)
			(footprints allowed)
		)
		(placement
			(enabled no)
			(sheetname "")
		)
		(fill
			(thermal_gap 0.5)
			(thermal_bridge_width 0.5)
			(island_removal_mode 0)
		)
		(polygon
			(pts
				(arc
					(start 125.431296 -368.65433)
					(mid 125.050296 -369.03533)
					(end 125.431296 -369.41633)
				)
				(arc
					(start 126.294896 -369.41633)
					(mid 126.675896 -369.03533)
					(end 126.294896 -368.65433)
				)
			)
		)
	)
	(zone
		(layers "F.Cu" "B.Cu" "In1.Cu" "In2.Cu" "In3.Cu" "In4.Cu" "In5.Cu" "In6.Cu"
			"In7.Cu" "In8.Cu" "In9.Cu" "In10.Cu" "In11.Cu" "In12.Cu" "In13.Cu" "In14.Cu"
			"In15.Cu" "In16.Cu"
		)
		(hatch none 0.5)
		(connect_pads
			(clearance 0)
		)
		(min_thickness 0.25)
		(keepout
			(tracks not_allowed)
			(vias allowed)
			(pads allowed)
			(copperpour not_allowed)
			(footprints allowed)
		)
		(placement
			(enabled no)
			(sheetname "")
		)
		(fill
			(thermal_gap 0.5)
			(thermal_bridge_width 0.5)
			(island_removal_mode 0)
		)
		(polygon
			(pts
				(arc
					(start 129.69748 -392.429238)
					(mid 129.31648 -392.048238)
					(end 128.93548 -392.429238)
				)
				(arc
					(start 128.93548 -393.292838)
					(mid 129.31648 -393.673838)
					(end 129.69748 -393.292838)
				)
			)
		)
	)
	(zone
		(layers "F.Cu" "B.Cu" "In1.Cu" "In2.Cu" "In3.Cu" "In4.Cu" "In5.Cu" "In6.Cu"
			"In7.Cu" "In8.Cu" "In9.Cu" "In10.Cu" "In11.Cu" "In12.Cu" "In13.Cu" "In14.Cu"
			"In15.Cu" "In16.Cu"
		)
		(hatch none 0.5)
		(connect_pads
			(clearance 0)
		)
		(min_thickness 0.25)
		(keepout
			(tracks not_allowed)
			(vias allowed)
			(pads allowed)
			(copperpour not_allowed)
			(footprints allowed)
		)
		(placement
			(enabled no)
			(sheetname "")
		)
		(fill
			(thermal_gap 0.5)
			(thermal_bridge_width 0.5)
			(island_removal_mode 0)
		)
		(polygon
			(pts
				(arc
					(start 309.936388 -398.016476)
					(mid 310.046359 -398.11753)
					(end 310.19115 -398.154144)
				)
				(arc
					(start 310.19115 -398.154144)
					(mid 310.406676 -398.06487)
					(end 310.49595 -397.849344)
				)
				(arc
					(start 310.49595 -397.849344)
					(mid 310.485613 -397.770605)
					(end 310.45531 -397.697198)
				)
				(arc
					(start 310.06288 -397.018256)
					(mid 309.950483 -396.896639)
					(end 309.7911 -396.851632)
				)
				(arc
					(start 309.7911 -396.851632)
					(mid 309.575574 -396.940906)
					(end 309.4863 -397.156432)
				)
				(arc
					(start 309.4863 -397.156432)
					(mid 309.495878 -397.232494)
					(end 309.524146 -397.303752)
				)
				(xy 309.921402 -397.991076) (xy 309.933594 -398.012412) (xy 309.936134 -398.01673)
			)
		)
	)
	(zone
		(layers "F.Cu" "B.Cu" "In1.Cu" "In2.Cu" "In3.Cu" "In4.Cu" "In5.Cu" "In6.Cu"
			"In7.Cu" "In8.Cu" "In9.Cu" "In10.Cu" "In11.Cu" "In12.Cu" "In13.Cu" "In14.Cu"
			"In15.Cu" "In16.Cu"
		)
		(hatch none 0.5)
		(connect_pads
			(clearance 0)
		)
		(min_thickness 0.25)
		(keepout
			(tracks not_allowed)
			(vias allowed)
			(pads allowed)
			(copperpour not_allowed)
			(footprints allowed)
		)
		(placement
			(enabled no)
			(sheetname "")
		)
		(fill
			(thermal_gap 0.5)
			(thermal_bridge_width 0.5)
			(island_removal_mode 0)
		)
		(polygon
			(pts
				(arc
					(start 384.678682 -415.00552)
					(mid 384.297682 -415.38652)
					(end 384.678682 -415.76752)
				)
				(arc
					(start 385.542282 -415.76752)
					(mid 385.923282 -415.38652)
					(end 385.542282 -415.00552)
				)
			)
		)
	)
	(zone
		(layers "F.Cu" "B.Cu" "In1.Cu" "In2.Cu" "In3.Cu" "In4.Cu" "In5.Cu" "In6.Cu"
			"In7.Cu" "In8.Cu" "In9.Cu" "In10.Cu" "In11.Cu" "In12.Cu" "In13.Cu" "In14.Cu"
			"In15.Cu" "In16.Cu"
		)
		(hatch none 0.5)
		(connect_pads
			(clearance 0)
		)
		(min_thickness 0.25)
		(keepout
			(tracks not_allowed)
			(vias allowed)
			(pads allowed)
			(copperpour not_allowed)
			(footprints allowed)
		)
		(placement
			(enabled no)
			(sheetname "")
		)
		(fill
			(thermal_gap 0.5)
			(thermal_bridge_width 0.5)
			(island_removal_mode 0)
		)
		(polygon
			(pts
				(arc
					(start 319.536318 -394.552424)
					(mid 319.646289 -394.653478)
					(end 319.79108 -394.690092)
				)
				(arc
					(start 319.79108 -394.690092)
					(mid 320.006606 -394.600818)
					(end 320.09588 -394.385292)
				)
				(arc
					(start 320.09588 -394.385292)
					(mid 320.085543 -394.306553)
					(end 320.05524 -394.233146)
				)
				(arc
					(start 319.66281 -393.554204)
					(mid 319.550413 -393.432587)
					(end 319.39103 -393.38758)
				)
				(arc
					(start 319.39103 -393.38758)
					(mid 319.175504 -393.476854)
					(end 319.08623 -393.69238)
				)
				(arc
					(start 319.08623 -393.69238)
					(mid 319.095808 -393.768442)
					(end 319.124076 -393.8397)
				)
				(xy 319.521332 -394.527024) (xy 319.533524 -394.54836) (xy 319.536064 -394.552678)
			)
		)
	)
	(zone
		(layers "F.Cu" "B.Cu" "In1.Cu" "In2.Cu" "In3.Cu" "In4.Cu" "In5.Cu" "In6.Cu"
			"In7.Cu" "In8.Cu" "In9.Cu" "In10.Cu" "In11.Cu" "In12.Cu" "In13.Cu" "In14.Cu"
			"In15.Cu" "In16.Cu"
		)
		(hatch none 0.5)
		(connect_pads
			(clearance 0)
		)
		(min_thickness 0.25)
		(keepout
			(tracks not_allowed)
			(vias allowed)
			(pads allowed)
			(copperpour not_allowed)
			(footprints allowed)
		)
		(placement
			(enabled no)
			(sheetname "")
		)
		(fill
			(thermal_gap 0.5)
			(thermal_bridge_width 0.5)
			(island_removal_mode 0)
		)
		(polygon
			(pts
				(arc
					(start 312.983626 -420.571168)
					(mid 312.602626 -420.952168)
					(end 312.983626 -421.333168)
				)
				(arc
					(start 313.847226 -421.333168)
					(mid 314.228226 -420.952168)
					(end 313.847226 -420.571168)
				)
			)
		)
	)
	(zone
		(layers "F.Cu" "B.Cu" "In1.Cu" "In2.Cu" "In3.Cu" "In4.Cu" "In5.Cu" "In6.Cu"
			"In7.Cu" "In8.Cu" "In9.Cu" "In10.Cu" "In11.Cu" "In12.Cu" "In13.Cu" "In14.Cu"
			"In15.Cu" "In16.Cu"
		)
		(hatch none 0.5)
		(connect_pads
			(clearance 0)
		)
		(min_thickness 0.25)
		(keepout
			(tracks not_allowed)
			(vias allowed)
			(pads allowed)
			(copperpour not_allowed)
			(footprints allowed)
		)
		(placement
			(enabled no)
			(sheetname "")
		)
		(fill
			(thermal_gap 0.5)
			(thermal_bridge_width 0.5)
			(island_removal_mode 0)
		)
		(polygon
			(pts
				(arc
					(start 127.036576 -389.634476)
					(mid 127.146547 -389.73553)
					(end 127.291338 -389.772144)
				)
				(arc
					(start 127.291338 -389.772144)
					(mid 127.506864 -389.68287)
					(end 127.596138 -389.467344)
				)
				(arc
					(start 127.596138 -389.467344)
					(mid 127.585801 -389.388605)
					(end 127.555498 -389.315198)
				)
				(arc
					(start 127.163068 -388.636256)
					(mid 127.050671 -388.514639)
					(end 126.891288 -388.469632)
				)
				(arc
					(start 126.891288 -388.469632)
					(mid 126.675762 -388.558906)
					(end 126.586488 -388.774432)
				)
				(arc
					(start 126.586488 -388.774432)
					(mid 126.596066 -388.850494)
					(end 126.624334 -388.921752)
				)
				(xy 127.02159 -389.609076) (xy 127.033782 -389.630412) (xy 127.036322 -389.63473)
			)
		)
	)
	(zone
		(layers "F.Cu" "B.Cu" "In1.Cu" "In2.Cu" "In3.Cu" "In4.Cu" "In5.Cu" "In6.Cu"
			"In7.Cu" "In8.Cu" "In9.Cu" "In10.Cu" "In11.Cu" "In12.Cu" "In13.Cu" "In14.Cu"
			"In15.Cu" "In16.Cu"
		)
		(hatch none 0.5)
		(connect_pads
			(clearance 0)
		)
		(min_thickness 0.25)
		(keepout
			(tracks not_allowed)
			(vias allowed)
			(pads allowed)
			(copperpour not_allowed)
			(footprints allowed)
		)
		(placement
			(enabled no)
			(sheetname "")
		)
		(fill
			(thermal_gap 0.5)
			(thermal_bridge_width 0.5)
			(island_removal_mode 0)
		)
		(polygon
			(pts
				(arc
					(start 345.12504 -400.811238)
					(mid 344.74404 -400.430238)
					(end 344.36304 -400.811238)
				)
				(arc
					(start 344.36304 -401.674838)
					(mid 344.74404 -402.055838)
					(end 345.12504 -401.674838)
				)
			)
		)
	)
	(zone
		(layers "F.Cu" "B.Cu" "In1.Cu" "In2.Cu" "In3.Cu" "In4.Cu" "In5.Cu" "In6.Cu"
			"In7.Cu" "In8.Cu" "In9.Cu" "In10.Cu" "In11.Cu" "In12.Cu" "In13.Cu" "In14.Cu"
			"In15.Cu" "In16.Cu"
		)
		(hatch none 0.5)
		(connect_pads
			(clearance 0)
		)
		(min_thickness 0.25)
		(keepout
			(tracks not_allowed)
			(vias allowed)
			(pads allowed)
			(copperpour not_allowed)
			(footprints allowed)
		)
		(placement
			(enabled no)
			(sheetname "")
		)
		(fill
			(thermal_gap 0.5)
			(thermal_bridge_width 0.5)
			(island_removal_mode 0)
		)
		(polygon
			(pts
				(arc
					(start 134.805166 -409.649168)
					(mid 134.424166 -410.030168)
					(end 134.805166 -410.411168)
				)
				(arc
					(start 135.668766 -410.411168)
					(mid 136.049766 -410.030168)
					(end 135.668766 -409.649168)
				)
			)
		)
	)
	(zone
		(layers "F.Cu" "B.Cu" "In1.Cu" "In2.Cu" "In3.Cu" "In4.Cu" "In5.Cu" "In6.Cu"
			"In7.Cu" "In8.Cu" "In9.Cu" "In10.Cu" "In11.Cu" "In12.Cu" "In13.Cu" "In14.Cu"
			"In15.Cu" "In16.Cu"
		)
		(hatch none 0.5)
		(connect_pads
			(clearance 0)
		)
		(min_thickness 0.25)
		(keepout
			(tracks not_allowed)
			(vias allowed)
			(pads allowed)
			(copperpour not_allowed)
			(footprints allowed)
		)
		(placement
			(enabled no)
			(sheetname "")
		)
		(fill
			(thermal_gap 0.5)
			(thermal_bridge_width 0.5)
			(island_removal_mode 0)
		)
		(polygon
			(pts
				(arc
					(start 92.211144 -406.62352)
					(mid 91.830144 -407.00452)
					(end 92.211144 -407.38552)
				)
				(arc
					(start 93.074744 -407.38552)
					(mid 93.455744 -407.00452)
					(end 93.074744 -406.62352)
				)
			)
		)
	)
	(zone
		(layers "F.Cu" "B.Cu" "In1.Cu" "In2.Cu" "In3.Cu" "In4.Cu" "In5.Cu" "In6.Cu"
			"In7.Cu" "In8.Cu" "In9.Cu" "In10.Cu" "In11.Cu" "In12.Cu" "In13.Cu" "In14.Cu"
			"In15.Cu" "In16.Cu"
		)
		(hatch none 0.5)
		(connect_pads
			(clearance 0)
		)
		(min_thickness 0.25)
		(keepout
			(tracks not_allowed)
			(vias allowed)
			(pads allowed)
			(copperpour not_allowed)
			(footprints allowed)
		)
		(placement
			(enabled no)
			(sheetname "")
		)
		(fill
			(thermal_gap 0.5)
			(thermal_bridge_width 0.5)
			(island_removal_mode 0)
		)
		(polygon
			(pts
				(arc
					(start 307.7972 -400.811238)
					(mid 307.4162 -400.430238)
					(end 307.0352 -400.811238)
				)
				(arc
					(start 307.0352 -401.674838)
					(mid 307.4162 -402.055838)
					(end 307.7972 -401.674838)
				)
			)
		)
	)
	(zone
		(layers "F.Cu" "B.Cu" "In1.Cu" "In2.Cu" "In3.Cu" "In4.Cu" "In5.Cu" "In6.Cu"
			"In7.Cu" "In8.Cu" "In9.Cu" "In10.Cu" "In11.Cu" "In12.Cu" "In13.Cu" "In14.Cu"
			"In15.Cu" "In16.Cu"
		)
		(hatch none 0.5)
		(connect_pads
			(clearance 0)
		)
		(min_thickness 0.25)
		(keepout
			(tracks not_allowed)
			(vias allowed)
			(pads allowed)
			(copperpour not_allowed)
			(footprints allowed)
		)
		(placement
			(enabled no)
			(sheetname "")
		)
		(fill
			(thermal_gap 0.5)
			(thermal_bridge_width 0.5)
			(island_removal_mode 0)
		)
		(polygon
			(pts
				(arc
					(start 372.425722 -415.00552)
					(mid 372.044722 -415.38652)
					(end 372.425722 -415.76752)
				)
				(arc
					(start 373.289322 -415.76752)
					(mid 373.670322 -415.38652)
					(end 373.289322 -415.00552)
				)
			)
		)
	)
	(zone
		(layers "F.Cu" "B.Cu" "In1.Cu" "In2.Cu" "In3.Cu" "In4.Cu" "In5.Cu" "In6.Cu"
			"In7.Cu" "In8.Cu" "In9.Cu" "In10.Cu" "In11.Cu" "In12.Cu" "In13.Cu" "In14.Cu"
			"In15.Cu" "In16.Cu"
		)
		(hatch none 0.5)
		(connect_pads
			(clearance 0)
		)
		(min_thickness 0.25)
		(keepout
			(tracks not_allowed)
			(vias allowed)
			(pads allowed)
			(copperpour not_allowed)
			(footprints allowed)
		)
		(placement
			(enabled no)
			(sheetname "")
		)
		(fill
			(thermal_gap 0.5)
			(thermal_bridge_width 0.5)
			(island_removal_mode 0)
		)
		(polygon
			(pts
				(arc
					(start 353.666044 -377.03633)
					(mid 353.285044 -377.41733)
					(end 353.666044 -377.79833)
				)
				(arc
					(start 354.529644 -377.79833)
					(mid 354.910644 -377.41733)
					(end 354.529644 -377.03633)
				)
			)
		)
	)
	(zone
		(layers "F.Cu" "B.Cu" "In1.Cu" "In2.Cu" "In3.Cu" "In4.Cu" "In5.Cu" "In6.Cu"
			"In7.Cu" "In8.Cu" "In9.Cu" "In10.Cu" "In11.Cu" "In12.Cu" "In13.Cu" "In14.Cu"
			"In15.Cu" "In16.Cu"
		)
		(hatch none 0.5)
		(connect_pads
			(clearance 0)
		)
		(min_thickness 0.25)
		(keepout
			(tracks not_allowed)
			(vias allowed)
			(pads allowed)
			(copperpour not_allowed)
			(footprints allowed)
		)
		(placement
			(enabled no)
			(sheetname "")
		)
		(fill
			(thermal_gap 0.5)
			(thermal_bridge_width 0.5)
			(island_removal_mode 0)
		)
		(polygon
			(pts
				(arc
					(start 343.616026 -420.571168)
					(mid 343.235026 -420.952168)
					(end 343.616026 -421.333168)
				)
				(arc
					(start 344.479626 -421.333168)
					(mid 344.860626 -420.952168)
					(end 344.479626 -420.571168)
				)
			)
		)
	)
	(zone
		(layers "F.Cu" "B.Cu" "In1.Cu" "In2.Cu" "In3.Cu" "In4.Cu" "In5.Cu" "In6.Cu"
			"In7.Cu" "In8.Cu" "In9.Cu" "In10.Cu" "In11.Cu" "In12.Cu" "In13.Cu" "In14.Cu"
			"In15.Cu" "In16.Cu"
		)
		(hatch none 0.5)
		(connect_pads
			(clearance 0)
		)
		(min_thickness 0.25)
		(keepout
			(tracks not_allowed)
			(vias allowed)
			(pads allowed)
			(copperpour not_allowed)
			(footprints allowed)
		)
		(placement
			(enabled no)
			(sheetname "")
		)
		(fill
			(thermal_gap 0.5)
			(thermal_bridge_width 0.5)
			(island_removal_mode 0)
		)
		(polygon
			(pts
				(arc
					(start 83.021424 -409.649168)
					(mid 82.640424 -410.030168)
					(end 83.021424 -410.411168)
				)
				(arc
					(start 83.885024 -410.411168)
					(mid 84.266024 -410.030168)
					(end 83.885024 -409.649168)
				)
			)
		)
	)
	(zone
		(layers "F.Cu" "B.Cu" "In1.Cu" "In2.Cu" "In3.Cu" "In4.Cu" "In5.Cu" "In6.Cu"
			"In7.Cu" "In8.Cu" "In9.Cu" "In10.Cu" "In11.Cu" "In12.Cu" "In13.Cu" "In14.Cu"
			"In15.Cu" "In16.Cu"
		)
		(hatch none 0.5)
		(connect_pads
			(clearance 0)
		)
		(min_thickness 0.25)
		(keepout
			(tracks not_allowed)
			(vias allowed)
			(pads allowed)
			(copperpour not_allowed)
			(footprints allowed)
		)
		(placement
			(enabled no)
			(sheetname "")
		)
		(fill yes
			(thermal_gap 0.5)
			(thermal_bridge_width 0.5)
			(island_removal_mode 0)
		)
		(polygon
			(pts
				(arc
					(start 320.736468 -394.552424)
					(mid 320.846439 -394.653478)
					(end 320.99123 -394.690092)
				)
				(arc
					(start 320.99123 -394.690092)
					(mid 321.206756 -394.600818)
					(end 321.29603 -394.385292)
				)
				(arc
					(start 321.29603 -394.385292)
					(mid 321.285693 -394.306553)
					(end 321.25539 -394.233146)
				)
				(arc
					(start 320.86296 -393.554204)
					(mid 320.750563 -393.432587)
					(end 320.59118 -393.38758)
				)
				(arc
					(start 320.59118 -393.38758)
					(mid 320.375654 -393.476854)
					(end 320.28638 -393.69238)
				)
				(arc
					(start 320.28638 -393.69238)
					(mid 320.295958 -393.768442)
					(end 320.324226 -393.8397)
				)
				(xy 320.721482 -394.527024) (xy 320.733674 -394.54836) (xy 320.736214 -394.552678)
			)
		)
	)
	(zone
		(layers "F.Cu" "B.Cu" "In1.Cu" "In2.Cu" "In3.Cu" "In4.Cu" "In5.Cu" "In6.Cu"
			"In7.Cu" "In8.Cu" "In9.Cu" "In10.Cu" "In11.Cu" "In12.Cu" "In13.Cu" "In14.Cu"
			"In15.Cu" "In16.Cu"
		)
		(hatch none 0.5)
		(connect_pads
			(clearance 0)
		)
		(min_thickness 0.25)
		(keepout
			(tracks not_allowed)
			(vias allowed)
			(pads allowed)
			(copperpour not_allowed)
			(footprints allowed)
		)
		(placement
			(enabled no)
			(sheetname "")
		)
		(fill
			(thermal_gap 0.5)
			(thermal_bridge_width 0.5)
			(island_removal_mode 0)
		)
		(polygon
			(pts
				(arc
					(start 51.5366 -389.634476)
					(mid 51.646571 -389.73553)
					(end 51.791362 -389.772144)
				)
				(arc
					(start 51.791362 -389.772144)
					(mid 52.006888 -389.68287)
					(end 52.096162 -389.467344)
				)
				(arc
					(start 52.096162 -389.467344)
					(mid 52.085825 -389.388605)
					(end 52.055522 -389.315198)
				)
				(arc
					(start 51.663092 -388.636256)
					(mid 51.550695 -388.514639)
					(end 51.391312 -388.469632)
				)
				(arc
					(start 51.391312 -388.469632)
					(mid 51.175786 -388.558906)
					(end 51.086512 -388.774432)
				)
				(arc
					(start 51.086512 -388.774432)
					(mid 51.09609 -388.850494)
					(end 51.124358 -388.921752)
				)
				(xy 51.521614 -389.609076) (xy 51.533806 -389.630412) (xy 51.536346 -389.63473)
			)
		)
	)
	(zone
		(layers "F.Cu" "B.Cu" "In1.Cu" "In2.Cu" "In3.Cu" "In4.Cu" "In5.Cu" "In6.Cu"
			"In7.Cu" "In8.Cu" "In9.Cu" "In10.Cu" "In11.Cu" "In12.Cu" "In13.Cu" "In14.Cu"
			"In15.Cu" "In16.Cu"
		)
		(hatch none 0.5)
		(connect_pads
			(clearance 0)
		)
		(min_thickness 0.25)
		(keepout
			(tracks not_allowed)
			(vias allowed)
			(pads allowed)
			(copperpour not_allowed)
			(footprints allowed)
		)
		(placement
			(enabled no)
			(sheetname "")
		)
		(fill
			(thermal_gap 0.5)
			(thermal_bridge_width 0.5)
			(island_removal_mode 0)
		)
		(polygon
			(pts
				(arc
					(start 330.191364 -395.308074)
					(mid 329.810364 -394.927074)
					(end 329.429364 -395.308074)
				)
				(arc
					(start 329.429364 -396.171674)
					(mid 329.810364 -396.552674)
					(end 330.191364 -396.171674)
				)
			)
		)
	)
	(zone
		(layers "F.Cu" "B.Cu" "In1.Cu" "In2.Cu" "In3.Cu" "In4.Cu" "In5.Cu" "In6.Cu"
			"In7.Cu" "In8.Cu" "In9.Cu" "In10.Cu" "In11.Cu" "In12.Cu" "In13.Cu" "In14.Cu"
			"In15.Cu" "In16.Cu"
		)
		(hatch none 0.5)
		(connect_pads
			(clearance 0)
		)
		(min_thickness 0.25)
		(keepout
			(tracks not_allowed)
			(vias allowed)
			(pads allowed)
			(copperpour not_allowed)
			(footprints allowed)
		)
		(placement
			(enabled no)
			(sheetname "")
		)
		(fill
			(thermal_gap 0.5)
			(thermal_bridge_width 0.5)
			(island_removal_mode 0)
		)
		(polygon
			(pts
				(arc
					(start 349.742506 -412.46552)
					(mid 349.361506 -412.84652)
					(end 349.742506 -413.22752)
				)
				(arc
					(start 350.606106 -413.22752)
					(mid 350.987106 -412.84652)
					(end 350.606106 -412.46552)
				)
			)
		)
	)
	(zone
		(layers "F.Cu" "B.Cu" "In1.Cu" "In2.Cu" "In3.Cu" "In4.Cu" "In5.Cu" "In6.Cu"
			"In7.Cu" "In8.Cu" "In9.Cu" "In10.Cu" "In11.Cu" "In12.Cu" "In13.Cu" "In14.Cu"
			"In15.Cu" "In16.Cu"
		)
		(hatch none 0.5)
		(connect_pads
			(clearance 0)
		)
		(min_thickness 0.25)
		(keepout
			(tracks not_allowed)
			(vias allowed)
			(pads allowed)
			(copperpour not_allowed)
			(footprints allowed)
		)
		(placement
			(enabled no)
			(sheetname "")
		)
		(fill
			(thermal_gap 0.5)
			(thermal_bridge_width 0.5)
			(island_removal_mode 0)
		)
		(polygon
			(pts
				(arc
					(start 94.262702 -373.58193)
					(mid 93.881702 -373.96293)
					(end 94.262702 -374.34393)
				)
				(arc
					(start 95.126302 -374.34393)
					(mid 95.507302 -373.96293)
					(end 95.126302 -373.58193)
				)
			)
		)
	)
	(zone
		(layers "F.Cu" "B.Cu" "In1.Cu" "In2.Cu" "In3.Cu" "In4.Cu" "In5.Cu" "In6.Cu"
			"In7.Cu" "In8.Cu" "In9.Cu" "In10.Cu" "In11.Cu" "In12.Cu" "In13.Cu" "In14.Cu"
			"In15.Cu" "In16.Cu"
		)
		(hatch none 0.5)
		(connect_pads
			(clearance 0)
		)
		(min_thickness 0.25)
		(keepout
			(tracks not_allowed)
			(vias allowed)
			(pads allowed)
			(copperpour not_allowed)
			(footprints allowed)
		)
		(placement
			(enabled no)
			(sheetname "")
		)
		(fill yes
			(thermal_gap 0.5)
			(thermal_bridge_width 0.5)
			(island_removal_mode 0)
		)
		(polygon
			(pts
				(arc
					(start 430.9999 -413.170116)
					(mid 426.999908 -417.170108)
					(end 422.999916 -413.170116)
				)
				(arc
					(start 422.999916 -413.170116)
					(mid 426.999908 -409.170124)
					(end 430.9999 -413.170116)
				)
			)
		)
	)
	(zone
		(layers "F.Cu" "B.Cu" "In1.Cu" "In2.Cu" "In3.Cu" "In4.Cu" "In5.Cu" "In6.Cu"
			"In7.Cu" "In8.Cu" "In9.Cu" "In10.Cu" "In11.Cu" "In12.Cu" "In13.Cu" "In14.Cu"
			"In15.Cu" "In16.Cu"
		)
		(hatch none 0.5)
		(connect_pads
			(clearance 0)
		)
		(min_thickness 0.25)
		(keepout
			(tracks not_allowed)
			(vias allowed)
			(pads allowed)
			(copperpour not_allowed)
			(footprints allowed)
		)
		(placement
			(enabled no)
			(sheetname "")
		)
		(fill
			(thermal_gap 0.5)
			(thermal_bridge_width 0.5)
			(island_removal_mode 0)
		)
		(polygon
			(pts
				(arc
					(start 50.13579 -6.344158)
					(mid 49.75479 -6.725158)
					(end 50.13579 -7.106158)
				)
				(arc
					(start 50.99939 -7.106158)
					(mid 51.38039 -6.725158)
					(end 50.99939 -6.344158)
				)
			)
		)
	)
	(zone
		(layers "F.Cu" "B.Cu" "In1.Cu" "In2.Cu" "In3.Cu" "In4.Cu" "In5.Cu" "In6.Cu"
			"In7.Cu" "In8.Cu" "In9.Cu" "In10.Cu" "In11.Cu" "In12.Cu" "In13.Cu" "In14.Cu"
			"In15.Cu" "In16.Cu"
		)
		(hatch none 0.5)
		(connect_pads
			(clearance 0)
		)
		(min_thickness 0.25)
		(keepout
			(tracks not_allowed)
			(vias allowed)
			(pads allowed)
			(copperpour not_allowed)
			(footprints allowed)
		)
		(placement
			(enabled no)
			(sheetname "")
		)
		(fill
			(thermal_gap 0.5)
			(thermal_bridge_width 0.5)
			(island_removal_mode 0)
		)
		(polygon
			(pts
				(arc
					(start 337.924902 -400.811238)
					(mid 337.543902 -400.430238)
					(end 337.162902 -400.811238)
				)
				(arc
					(start 337.162902 -401.674838)
					(mid 337.543902 -402.055838)
					(end 337.924902 -401.674838)
				)
			)
		)
	)
	(zone
		(layers "F.Cu" "B.Cu" "In1.Cu" "In2.Cu" "In3.Cu" "In4.Cu" "In5.Cu" "In6.Cu"
			"In7.Cu" "In8.Cu" "In9.Cu" "In10.Cu" "In11.Cu" "In12.Cu" "In13.Cu" "In14.Cu"
			"In15.Cu" "In16.Cu"
		)
		(hatch none 0.5)
		(connect_pads
			(clearance 0)
		)
		(min_thickness 0.25)
		(keepout
			(tracks not_allowed)
			(vias allowed)
			(pads allowed)
			(copperpour not_allowed)
			(footprints allowed)
		)
		(placement
			(enabled no)
			(sheetname "")
		)
		(fill
			(thermal_gap 0.5)
			(thermal_bridge_width 0.5)
			(island_removal_mode 0)
		)
		(polygon
			(pts
				(arc
					(start 320.736214 -398.016476)
					(mid 320.846185 -398.11753)
					(end 320.990976 -398.154144)
				)
				(arc
					(start 320.990976 -398.154144)
					(mid 321.206502 -398.06487)
					(end 321.295776 -397.849344)
				)
				(arc
					(start 321.295776 -397.849344)
					(mid 321.285439 -397.770605)
					(end 321.255136 -397.697198)
				)
				(arc
					(start 320.862706 -397.018256)
					(mid 320.750309 -396.896639)
					(end 320.590926 -396.851632)
				)
				(arc
					(start 320.590926 -396.851632)
					(mid 320.3754 -396.940906)
					(end 320.286126 -397.156432)
				)
				(arc
					(start 320.286126 -397.156432)
					(mid 320.295704 -397.232494)
					(end 320.323972 -397.303752)
				)
				(xy 320.721228 -397.991076) (xy 320.73342 -398.012412) (xy 320.73596 -398.01673)
			)
		)
	)
	(zone
		(layers "F.Cu" "B.Cu" "In1.Cu" "In2.Cu" "In3.Cu" "In4.Cu" "In5.Cu" "In6.Cu"
			"In7.Cu" "In8.Cu" "In9.Cu" "In10.Cu" "In11.Cu" "In12.Cu" "In13.Cu" "In14.Cu"
			"In15.Cu" "In16.Cu"
		)
		(hatch none 0.5)
		(connect_pads
			(clearance 0)
		)
		(min_thickness 0.25)
		(keepout
			(tracks not_allowed)
			(vias allowed)
			(pads allowed)
			(copperpour not_allowed)
			(footprints allowed)
		)
		(placement
			(enabled no)
			(sheetname "")
		)
		(fill
			(thermal_gap 0.5)
			(thermal_bridge_width 0.5)
			(island_removal_mode 0)
		)
		(polygon
			(pts
				(arc
					(start 70.768464 -409.649168)
					(mid 70.387464 -410.030168)
					(end 70.768464 -410.411168)
				)
				(arc
					(start 71.632064 -410.411168)
					(mid 72.013064 -410.030168)
					(end 71.632064 -409.649168)
				)
			)
		)
	)
	(zone
		(layers "F.Cu" "B.Cu" "In1.Cu" "In2.Cu" "In3.Cu" "In4.Cu" "In5.Cu" "In6.Cu"
			"In7.Cu" "In8.Cu" "In9.Cu" "In10.Cu" "In11.Cu" "In12.Cu" "In13.Cu" "In14.Cu"
			"In15.Cu" "In16.Cu"
		)
		(hatch none 0.5)
		(connect_pads
			(clearance 0)
		)
		(min_thickness 0.25)
		(keepout
			(tracks not_allowed)
			(vias allowed)
			(pads allowed)
			(copperpour not_allowed)
			(footprints allowed)
		)
		(placement
			(enabled no)
			(sheetname "")
		)
		(fill
			(thermal_gap 0.5)
			(thermal_bridge_width 0.5)
			(island_removal_mode 0)
		)
		(polygon
			(pts
				(arc
					(start 60.047124 -404.08352)
					(mid 59.666124 -404.46452)
					(end 60.047124 -404.84552)
				)
				(arc
					(start 60.910724 -404.84552)
					(mid 61.291724 -404.46452)
					(end 60.910724 -404.08352)
				)
			)
		)
	)
	(zone
		(layers "F.Cu" "B.Cu" "In1.Cu" "In2.Cu" "In3.Cu" "In4.Cu" "In5.Cu" "In6.Cu"
			"In7.Cu" "In8.Cu" "In9.Cu" "In10.Cu" "In11.Cu" "In12.Cu" "In13.Cu" "In14.Cu"
			"In15.Cu" "In16.Cu"
		)
		(hatch none 0.5)
		(connect_pads
			(clearance 0)
		)
		(min_thickness 0.25)
		(keepout
			(tracks not_allowed)
			(vias allowed)
			(pads allowed)
			(copperpour not_allowed)
			(footprints allowed)
		)
		(placement
			(enabled no)
			(sheetname "")
		)
		(fill
			(thermal_gap 0.5)
			(thermal_bridge_width 0.5)
			(island_removal_mode 0)
		)
		(polygon
			(pts
				(arc
					(start 82.864198 -389.634476)
					(mid 82.974169 -389.73553)
					(end 83.11896 -389.772144)
				)
				(arc
					(start 83.11896 -389.772144)
					(mid 83.334486 -389.68287)
					(end 83.42376 -389.467344)
				)
				(arc
					(start 83.42376 -389.467344)
					(mid 83.413423 -389.388605)
					(end 83.38312 -389.315198)
				)
				(arc
					(start 82.99069 -388.636256)
					(mid 82.878293 -388.514639)
					(end 82.71891 -388.469632)
				)
				(arc
					(start 82.71891 -388.469632)
					(mid 82.503384 -388.558906)
					(end 82.41411 -388.774432)
				)
				(arc
					(start 82.41411 -388.774432)
					(mid 82.423688 -388.850494)
					(end 82.451956 -388.921752)
				)
				(xy 82.849212 -389.609076) (xy 82.861404 -389.630412) (xy 82.863944 -389.63473)
			)
		)
	)
	(zone
		(layers "F.Cu" "B.Cu" "In1.Cu" "In2.Cu" "In3.Cu" "In4.Cu" "In5.Cu" "In6.Cu"
			"In7.Cu" "In8.Cu" "In9.Cu" "In10.Cu" "In11.Cu" "In12.Cu" "In13.Cu" "In14.Cu"
			"In15.Cu" "In16.Cu"
		)
		(hatch none 0.5)
		(connect_pads
			(clearance 0)
		)
		(min_thickness 0.25)
		(keepout
			(tracks not_allowed)
			(vias allowed)
			(pads allowed)
			(copperpour not_allowed)
			(footprints allowed)
		)
		(placement
			(enabled no)
			(sheetname "")
		)
		(fill
			(thermal_gap 0.5)
			(thermal_bridge_width 0.5)
			(island_removal_mode 0)
		)
		(polygon
			(pts
				(arc
					(start 89.147904 -406.62352)
					(mid 88.766904 -407.00452)
					(end 89.147904 -407.38552)
				)
				(arc
					(start 90.011504 -407.38552)
					(mid 90.392504 -407.00452)
					(end 90.011504 -406.62352)
				)
			)
		)
	)
	(zone
		(layers "F.Cu" "B.Cu" "In1.Cu" "In2.Cu" "In3.Cu" "In4.Cu" "In5.Cu" "In6.Cu"
			"In7.Cu" "In8.Cu" "In9.Cu" "In10.Cu" "In11.Cu" "In12.Cu" "In13.Cu" "In14.Cu"
			"In15.Cu" "In16.Cu"
		)
		(hatch none 0.5)
		(connect_pads
			(clearance 0)
		)
		(min_thickness 0.25)
		(keepout
			(tracks not_allowed)
			(vias allowed)
			(pads allowed)
			(copperpour not_allowed)
			(footprints allowed)
		)
		(placement
			(enabled no)
			(sheetname "")
		)
		(fill
			(thermal_gap 0.5)
			(thermal_bridge_width 0.5)
			(island_removal_mode 0)
		)
		(polygon
			(pts
				(arc
					(start 403.564344 -398.016476)
					(mid 403.674315 -398.11753)
					(end 403.819106 -398.154144)
				)
				(arc
					(start 403.819106 -398.154144)
					(mid 404.034632 -398.06487)
					(end 404.123906 -397.849344)
				)
				(arc
					(start 404.123906 -397.849344)
					(mid 404.113569 -397.770605)
					(end 404.083266 -397.697198)
				)
				(arc
					(start 403.690836 -397.018256)
					(mid 403.578439 -396.896639)
					(end 403.419056 -396.851632)
				)
				(arc
					(start 403.419056 -396.851632)
					(mid 403.20353 -396.940906)
					(end 403.114256 -397.156432)
				)
				(arc
					(start 403.114256 -397.156432)
					(mid 403.123834 -397.232494)
					(end 403.152102 -397.303752)
				)
				(xy 403.549358 -397.991076) (xy 403.56155 -398.012412) (xy 403.56409 -398.01673)
			)
		)
	)
	(zone
		(layers "F.Cu" "B.Cu" "In1.Cu" "In2.Cu" "In3.Cu" "In4.Cu" "In5.Cu" "In6.Cu"
			"In7.Cu" "In8.Cu" "In9.Cu" "In10.Cu" "In11.Cu" "In12.Cu" "In13.Cu" "In14.Cu"
			"In15.Cu" "In16.Cu"
		)
		(hatch none 0.5)
		(connect_pads
			(clearance 0)
		)
		(min_thickness 0.25)
		(keepout
			(tracks not_allowed)
			(vias allowed)
			(pads allowed)
			(copperpour not_allowed)
			(footprints allowed)
		)
		(placement
			(enabled no)
			(sheetname "")
		)
		(fill
			(thermal_gap 0.5)
			(thermal_bridge_width 0.5)
			(island_removal_mode 0)
		)
		(polygon
			(pts
				(arc
					(start 50.33645 -389.634476)
					(mid 50.446421 -389.73553)
					(end 50.591212 -389.772144)
				)
				(arc
					(start 50.591212 -389.772144)
					(mid 50.806738 -389.68287)
					(end 50.896012 -389.467344)
				)
				(arc
					(start 50.896012 -389.467344)
					(mid 50.885675 -389.388605)
					(end 50.855372 -389.315198)
				)
				(arc
					(start 50.462942 -388.636256)
					(mid 50.350545 -388.514639)
					(end 50.191162 -388.469632)
				)
				(arc
					(start 50.191162 -388.469632)
					(mid 49.975636 -388.558906)
					(end 49.886362 -388.774432)
				)
				(arc
					(start 49.886362 -388.774432)
					(mid 49.89594 -388.850494)
					(end 49.924208 -388.921752)
				)
				(xy 50.321464 -389.609076) (xy 50.333656 -389.630412) (xy 50.336196 -389.63473)
			)
		)
	)
	(zone
		(layers "F.Cu" "B.Cu" "In1.Cu" "In2.Cu" "In3.Cu" "In4.Cu" "In5.Cu" "In6.Cu"
			"In7.Cu" "In8.Cu" "In9.Cu" "In10.Cu" "In11.Cu" "In12.Cu" "In13.Cu" "In14.Cu"
			"In15.Cu" "In16.Cu"
		)
		(hatch none 0.5)
		(connect_pads
			(clearance 0)
		)
		(min_thickness 0.25)
		(keepout
			(tracks not_allowed)
			(vias allowed)
			(pads allowed)
			(copperpour not_allowed)
			(footprints allowed)
		)
		(placement
			(enabled no)
			(sheetname "")
		)
		(fill
			(thermal_gap 0.5)
			(thermal_bridge_width 0.5)
			(island_removal_mode 0)
		)
		(polygon
			(pts
				(arc
					(start 129.436368 -389.634476)
					(mid 129.546339 -389.73553)
					(end 129.69113 -389.772144)
				)
				(arc
					(start 129.69113 -389.772144)
					(mid 129.906656 -389.68287)
					(end 129.99593 -389.467344)
				)
				(arc
					(start 129.99593 -389.467344)
					(mid 129.985593 -389.388605)
					(end 129.95529 -389.315198)
				)
				(arc
					(start 129.56286 -388.636256)
					(mid 129.450463 -388.514639)
					(end 129.29108 -388.469632)
				)
				(arc
					(start 129.29108 -388.469632)
					(mid 129.075554 -388.558906)
					(end 128.98628 -388.774432)
				)
				(arc
					(start 128.98628 -388.774432)
					(mid 128.995858 -388.850494)
					(end 129.024126 -388.921752)
				)
				(xy 129.421382 -389.609076) (xy 129.433574 -389.630412) (xy 129.436114 -389.63473)
			)
		)
	)
	(zone
		(layers "F.Cu" "B.Cu" "In1.Cu" "In2.Cu" "In3.Cu" "In4.Cu" "In5.Cu" "In6.Cu"
			"In7.Cu" "In8.Cu" "In9.Cu" "In10.Cu" "In11.Cu" "In12.Cu" "In13.Cu" "In14.Cu"
			"In15.Cu" "In16.Cu"
		)
		(hatch none 0.5)
		(connect_pads
			(clearance 0)
		)
		(min_thickness 0.25)
		(keepout
			(tracks not_allowed)
			(vias allowed)
			(pads allowed)
			(copperpour not_allowed)
			(footprints allowed)
		)
		(placement
			(enabled no)
			(sheetname "")
		)
		(fill
			(thermal_gap 0.5)
			(thermal_bridge_width 0.5)
			(island_removal_mode 0)
		)
		(polygon
			(pts
				(arc
					(start 159.825436 -392.429238)
					(mid 159.444436 -392.048238)
					(end 159.063436 -392.429238)
				)
				(arc
					(start 159.063436 -393.292838)
					(mid 159.444436 -393.673838)
					(end 159.825436 -393.292838)
				)
			)
		)
	)
	(zone
		(layers "F.Cu" "B.Cu" "In1.Cu" "In2.Cu" "In3.Cu" "In4.Cu" "In5.Cu" "In6.Cu"
			"In7.Cu" "In8.Cu" "In9.Cu" "In10.Cu" "In11.Cu" "In12.Cu" "In13.Cu" "In14.Cu"
			"In15.Cu" "In16.Cu"
		)
		(hatch none 0.5)
		(connect_pads
			(clearance 0)
		)
		(min_thickness 0.25)
		(keepout
			(tracks not_allowed)
			(vias allowed)
			(pads allowed)
			(copperpour not_allowed)
			(footprints allowed)
		)
		(placement
			(enabled no)
			(sheetname "")
		)
		(fill
			(thermal_gap 0.5)
			(thermal_bridge_width 0.5)
			(island_removal_mode 0)
		)
		(polygon
			(pts
				(arc
					(start 395.400022 -420.571168)
					(mid 395.019022 -420.952168)
					(end 395.400022 -421.333168)
				)
				(arc
					(start 396.263622 -421.333168)
					(mid 396.644622 -420.952168)
					(end 396.263622 -420.571168)
				)
			)
		)
	)
	(zone
		(layers "F.Cu" "B.Cu" "In1.Cu" "In2.Cu" "In3.Cu" "In4.Cu" "In5.Cu" "In6.Cu"
			"In7.Cu" "In8.Cu" "In9.Cu" "In10.Cu" "In11.Cu" "In12.Cu" "In13.Cu" "In14.Cu"
			"In15.Cu" "In16.Cu"
		)
		(hatch none 0.5)
		(connect_pads
			(clearance 0)
		)
		(min_thickness 0.25)
		(keepout
			(tracks not_allowed)
			(vias allowed)
			(pads allowed)
			(copperpour not_allowed)
			(footprints allowed)
		)
		(placement
			(enabled no)
			(sheetname "")
		)
		(fill
			(thermal_gap 0.5)
			(thermal_bridge_width 0.5)
			(island_removal_mode 0)
		)
		(polygon
			(pts
				(arc
					(start 343.455244 -381.96393)
					(mid 343.074244 -382.34493)
					(end 343.455244 -382.72593)
				)
				(arc
					(start 344.318844 -382.72593)
					(mid 344.699844 -382.34493)
					(end 344.318844 -381.96393)
				)
			)
		)
	)
	(zone
		(layers "F.Cu" "B.Cu" "In1.Cu" "In2.Cu" "In3.Cu" "In4.Cu" "In5.Cu" "In6.Cu"
			"In7.Cu" "In8.Cu" "In9.Cu" "In10.Cu" "In11.Cu" "In12.Cu" "In13.Cu" "In14.Cu"
			"In15.Cu" "In16.Cu"
		)
		(hatch none 0.5)
		(connect_pads
			(clearance 0)
		)
		(min_thickness 0.25)
		(keepout
			(tracks not_allowed)
			(vias allowed)
			(pads allowed)
			(copperpour not_allowed)
			(footprints allowed)
		)
		(placement
			(enabled no)
			(sheetname "")
		)
		(fill
			(thermal_gap 0.5)
			(thermal_bridge_width 0.5)
			(island_removal_mode 0)
		)
		(polygon
			(pts
				(arc
					(start 407.164286 -398.016476)
					(mid 407.274257 -398.11753)
					(end 407.419048 -398.154144)
				)
				(arc
					(start 407.419048 -398.154144)
					(mid 407.634574 -398.06487)
					(end 407.723848 -397.849344)
				)
				(arc
					(start 407.723848 -397.849344)
					(mid 407.713511 -397.770605)
					(end 407.683208 -397.697198)
				)
				(arc
					(start 407.290778 -397.018256)
					(mid 407.178381 -396.896639)
					(end 407.018998 -396.851632)
				)
				(arc
					(start 407.018998 -396.851632)
					(mid 406.803472 -396.940906)
					(end 406.714198 -397.156432)
				)
				(arc
					(start 406.714198 -397.156432)
					(mid 406.723776 -397.232494)
					(end 406.752044 -397.303752)
				)
				(xy 407.1493 -397.991076) (xy 407.161492 -398.012412) (xy 407.164032 -398.01673)
			)
		)
	)
	(zone
		(layers "F.Cu" "B.Cu" "In1.Cu" "In2.Cu" "In3.Cu" "In4.Cu" "In5.Cu" "In6.Cu"
			"In7.Cu" "In8.Cu" "In9.Cu" "In10.Cu" "In11.Cu" "In12.Cu" "In13.Cu" "In14.Cu"
			"In15.Cu" "In16.Cu"
		)
		(hatch none 0.5)
		(connect_pads
			(clearance 0)
		)
		(min_thickness 0.25)
		(keepout
			(tracks not_allowed)
			(vias allowed)
			(pads allowed)
			(copperpour not_allowed)
			(footprints allowed)
		)
		(placement
			(enabled no)
			(sheetname "")
		)
		(fill
			(thermal_gap 0.5)
			(thermal_bridge_width 0.5)
			(island_removal_mode 0)
		)
		(polygon
			(pts
				(arc
					(start 142.335504 -369.54587)
					(mid 141.954504 -369.16487)
					(end 141.573504 -369.54587)
				)
				(arc
					(start 141.573504 -370.40947)
					(mid 141.954504 -370.79047)
					(end 142.335504 -370.40947)
				)
			)
		)
	)
	(zone
		(layers "F.Cu" "B.Cu" "In1.Cu" "In2.Cu" "In3.Cu" "In4.Cu" "In5.Cu" "In6.Cu"
			"In7.Cu" "In8.Cu" "In9.Cu" "In10.Cu" "In11.Cu" "In12.Cu" "In13.Cu" "In14.Cu"
			"In15.Cu" "In16.Cu"
		)
		(hatch none 0.5)
		(connect_pads
			(clearance 0)
		)
		(min_thickness 0.25)
		(keepout
			(tracks not_allowed)
			(vias allowed)
			(pads allowed)
			(copperpour not_allowed)
			(footprints allowed)
		)
		(placement
			(enabled no)
			(sheetname "")
		)
		(fill
			(thermal_gap 0.5)
			(thermal_bridge_width 0.5)
			(island_removal_mode 0)
		)
		(polygon
			(pts
				(arc
					(start 15.573502 -105.664)
					(mid 15.954502 -106.045)
					(end 16.335502 -105.664)
				)
				(arc
					(start 16.335502 -104.6734)
					(mid 15.954502 -104.2924)
					(end 15.573502 -104.6734)
				)
			)
		)
	)
	(zone
		(layers "F.Cu" "B.Cu" "In1.Cu" "In2.Cu" "In3.Cu" "In4.Cu" "In5.Cu" "In6.Cu"
			"In7.Cu" "In8.Cu" "In9.Cu" "In10.Cu" "In11.Cu" "In12.Cu" "In13.Cu" "In14.Cu"
			"In15.Cu" "In16.Cu"
		)
		(hatch none 0.5)
		(connect_pads
			(clearance 0)
		)
		(min_thickness 0.25)
		(keepout
			(tracks not_allowed)
			(vias allowed)
			(pads allowed)
			(copperpour not_allowed)
			(footprints allowed)
		)
		(placement
			(enabled no)
			(sheetname "")
		)
		(fill yes
			(thermal_gap 0.5)
			(thermal_bridge_width 0.5)
			(island_removal_mode 0)
		)
		(polygon
			(pts
				(arc
					(start 116.236496 -386.170424)
					(mid 116.346467 -386.271478)
					(end 116.491258 -386.308092)
				)
				(arc
					(start 116.491258 -386.308092)
					(mid 116.706784 -386.218818)
					(end 116.796058 -386.003292)
				)
				(arc
					(start 116.796058 -386.003292)
					(mid 116.785721 -385.924553)
					(end 116.755418 -385.851146)
				)
				(arc
					(start 116.362988 -385.172204)
					(mid 116.250591 -385.050587)
					(end 116.091208 -385.00558)
				)
				(arc
					(start 116.091208 -385.00558)
					(mid 115.875682 -385.094854)
					(end 115.786408 -385.31038)
				)
				(arc
					(start 115.786408 -385.31038)
					(mid 115.795986 -385.386442)
					(end 115.824254 -385.4577)
				)
				(xy 116.22151 -386.145024) (xy 116.233702 -386.16636) (xy 116.236242 -386.170678)
			)
		)
	)
	(zone
		(layers "F.Cu" "B.Cu" "In1.Cu" "In2.Cu" "In3.Cu" "In4.Cu" "In5.Cu" "In6.Cu"
			"In7.Cu" "In8.Cu" "In9.Cu" "In10.Cu" "In11.Cu" "In12.Cu" "In13.Cu" "In14.Cu"
			"In15.Cu" "In16.Cu"
		)
		(hatch none 0.5)
		(connect_pads
			(clearance 0)
		)
		(min_thickness 0.25)
		(keepout
			(tracks not_allowed)
			(vias allowed)
			(pads allowed)
			(copperpour not_allowed)
			(footprints allowed)
		)
		(placement
			(enabled no)
			(sheetname "")
		)
		(fill
			(thermal_gap 0.5)
			(thermal_bridge_width 0.5)
			(island_removal_mode 0)
		)
		(polygon
			(pts
				(arc
					(start 320.28257 -258.880102)
					(mid 315.25337 -258.880102)
					(end 320.28257 -258.880102)
				)
			)
		)
	)
	(zone
		(layers "F.Cu" "B.Cu" "In1.Cu" "In2.Cu" "In3.Cu" "In4.Cu" "In5.Cu" "In6.Cu"
			"In7.Cu" "In8.Cu" "In9.Cu" "In10.Cu" "In11.Cu" "In12.Cu" "In13.Cu" "In14.Cu"
			"In15.Cu" "In16.Cu"
		)
		(hatch none 0.5)
		(connect_pads
			(clearance 0)
		)
		(min_thickness 0.25)
		(keepout
			(tracks not_allowed)
			(vias allowed)
			(pads allowed)
			(copperpour not_allowed)
			(footprints allowed)
		)
		(placement
			(enabled no)
			(sheetname "")
		)
		(fill
			(thermal_gap 0.5)
			(thermal_bridge_width 0.5)
			(island_removal_mode 0)
		)
		(polygon
			(pts
				(arc
					(start 157.42539 -392.429238)
					(mid 157.04439 -392.048238)
					(end 156.66339 -392.429238)
				)
				(arc
					(start 156.66339 -393.292838)
					(mid 157.04439 -393.673838)
					(end 157.42539 -393.292838)
				)
			)
		)
	)
	(zone
		(layers "F.Cu" "B.Cu" "In1.Cu" "In2.Cu" "In3.Cu" "In4.Cu" "In5.Cu" "In6.Cu"
			"In7.Cu" "In8.Cu" "In9.Cu" "In10.Cu" "In11.Cu" "In12.Cu" "In13.Cu" "In14.Cu"
			"In15.Cu" "In16.Cu"
		)
		(hatch none 0.5)
		(connect_pads
			(clearance 0)
		)
		(min_thickness 0.25)
		(keepout
			(tracks not_allowed)
			(vias allowed)
			(pads allowed)
			(copperpour not_allowed)
			(footprints allowed)
		)
		(placement
			(enabled no)
			(sheetname "")
		)
		(fill
			(thermal_gap 0.5)
			(thermal_bridge_width 0.5)
			(island_removal_mode 0)
		)
		(polygon
			(pts
				(arc
					(start 58.14187 -420.760398)
					(mid 58.164188 -420.81428)
					(end 58.21807 -420.836598)
				)
				(arc
					(start 59.15787 -420.836598)
					(mid 59.211752 -420.81428)
					(end 59.23407 -420.760398)
				)
				(arc
					(start 59.23407 -418.218874)
					(mid 59.211752 -418.164992)
					(end 59.15787 -418.142674)
				)
				(arc
					(start 58.21807 -418.142674)
					(mid 58.164188 -418.164992)
					(end 58.14187 -418.218874)
				)
			)
		)
	)
	(zone
		(layers "F.Cu" "B.Cu" "In1.Cu" "In2.Cu" "In3.Cu" "In4.Cu" "In5.Cu" "In6.Cu"
			"In7.Cu" "In8.Cu" "In9.Cu" "In10.Cu" "In11.Cu" "In12.Cu" "In13.Cu" "In14.Cu"
			"In15.Cu" "In16.Cu"
		)
		(hatch none 0.5)
		(connect_pads
			(clearance 0)
		)
		(min_thickness 0.25)
		(keepout
			(tracks not_allowed)
			(vias allowed)
			(pads allowed)
			(copperpour not_allowed)
			(footprints allowed)
		)
		(placement
			(enabled no)
			(sheetname "")
		)
		(fill
			(thermal_gap 0.5)
			(thermal_bridge_width 0.5)
			(island_removal_mode 0)
		)
		(polygon
			(pts
				(arc
					(start 127.147066 -412.189168)
					(mid 126.766066 -412.570168)
					(end 127.147066 -412.951168)
				)
				(arc
					(start 128.010666 -412.951168)
					(mid 128.391666 -412.570168)
					(end 128.010666 -412.189168)
				)
			)
		)
	)
	(zone
		(layers "F.Cu" "B.Cu" "In1.Cu" "In2.Cu" "In3.Cu" "In4.Cu" "In5.Cu" "In6.Cu"
			"In7.Cu" "In8.Cu" "In9.Cu" "In10.Cu" "In11.Cu" "In12.Cu" "In13.Cu" "In14.Cu"
			"In15.Cu" "In16.Cu"
		)
		(hatch none 0.5)
		(connect_pads
			(clearance 0)
		)
		(min_thickness 0.25)
		(keepout
			(tracks not_allowed)
			(vias allowed)
			(pads allowed)
			(copperpour not_allowed)
			(footprints allowed)
		)
		(placement
			(enabled no)
			(sheetname "")
		)
		(fill yes
			(thermal_gap 0.5)
			(thermal_bridge_width 0.5)
			(island_removal_mode 0)
		)
		(polygon
			(pts
				(arc
					(start 407.164286 -394.552424)
					(mid 407.274257 -394.653478)
					(end 407.419048 -394.690092)
				)
				(arc
					(start 407.419048 -394.690092)
					(mid 407.634574 -394.600818)
					(end 407.723848 -394.385292)
				)
				(arc
					(start 407.723848 -394.385292)
					(mid 407.713511 -394.306553)
					(end 407.683208 -394.233146)
				)
				(arc
					(start 407.290778 -393.554204)
					(mid 407.178381 -393.432587)
					(end 407.018998 -393.38758)
				)
				(arc
					(start 407.018998 -393.38758)
					(mid 406.803472 -393.476854)
					(end 406.714198 -393.69238)
				)
				(arc
					(start 406.714198 -393.69238)
					(mid 406.723776 -393.768442)
					(end 406.752044 -393.8397)
				)
				(xy 407.1493 -394.527024) (xy 407.161492 -394.54836) (xy 407.164032 -394.552678)
			)
		)
	)
	(zone
		(layers "F.Cu" "B.Cu" "In1.Cu" "In2.Cu" "In3.Cu" "In4.Cu" "In5.Cu" "In6.Cu"
			"In7.Cu" "In8.Cu" "In9.Cu" "In10.Cu" "In11.Cu" "In12.Cu" "In13.Cu" "In14.Cu"
			"In15.Cu" "In16.Cu"
		)
		(hatch none 0.5)
		(connect_pads
			(clearance 0)
		)
		(min_thickness 0.25)
		(keepout
			(tracks not_allowed)
			(vias allowed)
			(pads allowed)
			(copperpour not_allowed)
			(footprints allowed)
		)
		(placement
			(enabled no)
			(sheetname "")
		)
		(fill
			(thermal_gap 0.5)
			(thermal_bridge_width 0.5)
			(island_removal_mode 0)
		)
		(polygon
			(pts
				(arc
					(start 340.051644 -377.03633)
					(mid 339.670644 -377.41733)
					(end 340.051644 -377.79833)
				)
				(arc
					(start 340.915244 -377.79833)
					(mid 341.296244 -377.41733)
					(end 340.915244 -377.03633)
				)
			)
		)
	)
	(zone
		(layers "F.Cu" "B.Cu" "In1.Cu" "In2.Cu" "In3.Cu" "In4.Cu" "In5.Cu" "In6.Cu"
			"In7.Cu" "In8.Cu" "In9.Cu" "In10.Cu" "In11.Cu" "In12.Cu" "In13.Cu" "In14.Cu"
			"In15.Cu" "In16.Cu"
		)
		(hatch none 0.5)
		(connect_pads
			(clearance 0)
		)
		(min_thickness 0.25)
		(keepout
			(tracks not_allowed)
			(vias allowed)
			(pads allowed)
			(copperpour not_allowed)
			(footprints allowed)
		)
		(placement
			(enabled no)
			(sheetname "")
		)
		(fill
			(thermal_gap 0.5)
			(thermal_bridge_width 0.5)
			(island_removal_mode 0)
		)
		(polygon
			(pts
				(arc
					(start 426.440346 -4.582414)
					(mid 426.059346 -4.963414)
					(end 426.440346 -5.344414)
				)
				(arc
					(start 427.303946 -5.344414)
					(mid 427.684946 -4.963414)
					(end 427.303946 -4.582414)
				)
			)
		)
	)
	(zone
		(layers "F.Cu" "B.Cu" "In1.Cu" "In2.Cu" "In3.Cu" "In4.Cu" "In5.Cu" "In6.Cu"
			"In7.Cu" "In8.Cu" "In9.Cu" "In10.Cu" "In11.Cu" "In12.Cu" "In13.Cu" "In14.Cu"
			"In15.Cu" "In16.Cu"
		)
		(hatch none 0.5)
		(connect_pads
			(clearance 0)
		)
		(min_thickness 0.25)
		(keepout
			(tracks not_allowed)
			(vias allowed)
			(pads allowed)
			(copperpour not_allowed)
			(footprints allowed)
		)
		(placement
			(enabled no)
			(sheetname "")
		)
		(fill
			(thermal_gap 0.5)
			(thermal_bridge_width 0.5)
			(island_removal_mode 0)
		)
		(polygon
			(pts
				(arc
					(start 136.336786 -412.189168)
					(mid 135.955786 -412.570168)
					(end 136.336786 -412.951168)
				)
				(arc
					(start 137.200386 -412.951168)
					(mid 137.581386 -412.570168)
					(end 137.200386 -412.189168)
				)
			)
		)
	)
	(zone
		(layers "F.Cu" "B.Cu" "In1.Cu" "In2.Cu" "In3.Cu" "In4.Cu" "In5.Cu" "In6.Cu"
			"In7.Cu" "In8.Cu" "In9.Cu" "In10.Cu" "In11.Cu" "In12.Cu" "In13.Cu" "In14.Cu"
			"In15.Cu" "In16.Cu"
		)
		(hatch none 0.5)
		(connect_pads
			(clearance 0)
		)
		(min_thickness 0.25)
		(keepout
			(tracks not_allowed)
			(vias allowed)
			(pads allowed)
			(copperpour not_allowed)
			(footprints allowed)
		)
		(placement
			(enabled no)
			(sheetname "")
		)
		(fill
			(thermal_gap 0.5)
			(thermal_bridge_width 0.5)
			(island_removal_mode 0)
		)
		(polygon
			(pts
				(arc
					(start 429.4886 -17.232122)
					(mid 429.1076 -17.613122)
					(end 429.4886 -17.994122)
				)
				(arc
					(start 430.3522 -17.994122)
					(mid 430.7332 -17.613122)
					(end 430.3522 -17.232122)
				)
			)
		)
	)
	(zone
		(layers "F.Cu" "B.Cu" "In1.Cu" "In2.Cu" "In3.Cu" "In4.Cu" "In5.Cu" "In6.Cu"
			"In7.Cu" "In8.Cu" "In9.Cu" "In10.Cu" "In11.Cu" "In12.Cu" "In13.Cu" "In14.Cu"
			"In15.Cu" "In16.Cu"
		)
		(hatch none 0.5)
		(connect_pads
			(clearance 0)
		)
		(min_thickness 0.25)
		(keepout
			(tracks not_allowed)
			(vias allowed)
			(pads allowed)
			(copperpour not_allowed)
			(footprints allowed)
		)
		(placement
			(enabled no)
			(sheetname "")
		)
		(fill
			(thermal_gap 0.5)
			(thermal_bridge_width 0.5)
			(island_removal_mode 0)
		)
		(polygon
			(pts
				(arc
					(start 255.546098 -213.806024)
					(mid 255.927098 -214.187024)
					(end 256.308098 -213.806024)
				)
				(arc
					(start 256.308098 -212.942424)
					(mid 255.927098 -212.561424)
					(end 255.546098 -212.942424)
				)
			)
		)
	)
	(zone
		(layers "F.Cu" "B.Cu" "In1.Cu" "In2.Cu" "In3.Cu" "In4.Cu" "In5.Cu" "In6.Cu"
			"In7.Cu" "In8.Cu" "In9.Cu" "In10.Cu" "In11.Cu" "In12.Cu" "In13.Cu" "In14.Cu"
			"In15.Cu" "In16.Cu"
		)
		(hatch none 0.5)
		(connect_pads
			(clearance 0)
		)
		(min_thickness 0.25)
		(keepout
			(tracks not_allowed)
			(vias allowed)
			(pads allowed)
			(copperpour not_allowed)
			(footprints allowed)
		)
		(placement
			(enabled no)
			(sheetname "")
		)
		(fill
			(thermal_gap 0.5)
			(thermal_bridge_width 0.5)
			(island_removal_mode 0)
		)
		(polygon
			(pts
				(arc
					(start 29.503878 -18.75536)
					(mid 29.122878 -19.13636)
					(end 29.503878 -19.51736)
				)
				(arc
					(start 30.367478 -19.51736)
					(mid 30.748478 -19.13636)
					(end 30.367478 -18.75536)
				)
			)
		)
	)
	(zone
		(layers "F.Cu" "B.Cu" "In1.Cu" "In2.Cu" "In3.Cu" "In4.Cu" "In5.Cu" "In6.Cu"
			"In7.Cu" "In8.Cu" "In9.Cu" "In10.Cu" "In11.Cu" "In12.Cu" "In13.Cu" "In14.Cu"
			"In15.Cu" "In16.Cu"
		)
		(hatch none 0.5)
		(connect_pads
			(clearance 0)
		)
		(min_thickness 0.25)
		(keepout
			(tracks not_allowed)
			(vias allowed)
			(pads allowed)
			(copperpour not_allowed)
			(footprints allowed)
		)
		(placement
			(enabled no)
			(sheetname "")
		)
		(fill
			(thermal_gap 0.5)
			(thermal_bridge_width 0.5)
			(island_removal_mode 0)
		)
		(polygon
			(pts
				(arc
					(start 377.020582 -420.571168)
					(mid 376.639582 -420.952168)
					(end 377.020582 -421.333168)
				)
				(arc
					(start 377.884182 -421.333168)
					(mid 378.265182 -420.952168)
					(end 377.884182 -420.571168)
				)
			)
		)
	)
	(zone
		(layers "F.Cu" "B.Cu" "In1.Cu" "In2.Cu" "In3.Cu" "In4.Cu" "In5.Cu" "In6.Cu"
			"In7.Cu" "In8.Cu" "In9.Cu" "In10.Cu" "In11.Cu" "In12.Cu" "In13.Cu" "In14.Cu"
			"In15.Cu" "In16.Cu"
		)
		(hatch none 0.5)
		(connect_pads
			(clearance 0)
		)
		(min_thickness 0.25)
		(keepout
			(tracks not_allowed)
			(vias allowed)
			(pads allowed)
			(copperpour not_allowed)
			(footprints allowed)
		)
		(placement
			(enabled no)
			(sheetname "")
		)
		(fill yes
			(thermal_gap 0.5)
			(thermal_bridge_width 0.5)
			(island_removal_mode 0)
		)
		(polygon
			(pts
				(arc
					(start 86.464394 -386.170424)
					(mid 86.574365 -386.271478)
					(end 86.719156 -386.308092)
				)
				(arc
					(start 86.719156 -386.308092)
					(mid 86.934682 -386.218818)
					(end 87.023956 -386.003292)
				)
				(arc
					(start 87.023956 -386.003292)
					(mid 87.013619 -385.924553)
					(end 86.983316 -385.851146)
				)
				(arc
					(start 86.590886 -385.172204)
					(mid 86.478489 -385.050587)
					(end 86.319106 -385.00558)
				)
				(arc
					(start 86.319106 -385.00558)
					(mid 86.10358 -385.094854)
					(end 86.014306 -385.31038)
				)
				(arc
					(start 86.014306 -385.31038)
					(mid 86.023884 -385.386442)
					(end 86.052152 -385.4577)
				)
				(xy 86.449408 -386.145024) (xy 86.4616 -386.16636) (xy 86.46414 -386.170678)
			)
		)
	)
	(zone
		(layers "F.Cu" "B.Cu" "In1.Cu" "In2.Cu" "In3.Cu" "In4.Cu" "In5.Cu" "In6.Cu"
			"In7.Cu" "In8.Cu" "In9.Cu" "In10.Cu" "In11.Cu" "In12.Cu" "In13.Cu" "In14.Cu"
			"In15.Cu" "In16.Cu"
		)
		(hatch none 0.5)
		(connect_pads
			(clearance 0)
		)
		(min_thickness 0.25)
		(keepout
			(tracks not_allowed)
			(vias allowed)
			(pads allowed)
			(copperpour not_allowed)
			(footprints allowed)
		)
		(placement
			(enabled no)
			(sheetname "")
		)
		(fill
			(thermal_gap 0.5)
			(thermal_bridge_width 0.5)
			(island_removal_mode 0)
		)
		(polygon
			(pts
				(arc
					(start 447.40703 -153.774394)
					(mid 436.38343 -153.774394)
					(end 447.40703 -153.774394)
				)
			)
		)
	)
	(zone
		(layers "F.Cu" "B.Cu" "In1.Cu" "In2.Cu" "In3.Cu" "In4.Cu" "In5.Cu" "In6.Cu"
			"In7.Cu" "In8.Cu" "In9.Cu" "In10.Cu" "In11.Cu" "In12.Cu" "In13.Cu" "In14.Cu"
			"In15.Cu" "In16.Cu"
		)
		(hatch none 0.5)
		(connect_pads
			(clearance 0)
		)
		(min_thickness 0.25)
		(keepout
			(tracks not_allowed)
			(vias allowed)
			(pads allowed)
			(copperpour not_allowed)
			(footprints allowed)
		)
		(placement
			(enabled no)
			(sheetname "")
		)
		(fill
			(thermal_gap 0.5)
			(thermal_bridge_width 0.5)
			(island_removal_mode 0)
		)
		(polygon
			(pts
				(arc
					(start 87.925402 -392.429238)
					(mid 87.544402 -392.048238)
					(end 87.163402 -392.429238)
				)
				(arc
					(start 87.163402 -393.292838)
					(mid 87.544402 -393.673838)
					(end 87.925402 -393.292838)
				)
			)
		)
	)
	(zone
		(layers "F.Cu" "B.Cu" "In1.Cu" "In2.Cu" "In3.Cu" "In4.Cu" "In5.Cu" "In6.Cu"
			"In7.Cu" "In8.Cu" "In9.Cu" "In10.Cu" "In11.Cu" "In12.Cu" "In13.Cu" "In14.Cu"
			"In15.Cu" "In16.Cu"
		)
		(hatch none 0.5)
		(connect_pads
			(clearance 0)
		)
		(min_thickness 0.25)
		(keepout
			(tracks not_allowed)
			(vias allowed)
			(pads allowed)
			(copperpour not_allowed)
			(footprints allowed)
		)
		(placement
			(enabled no)
			(sheetname "")
		)
		(fill yes
			(thermal_gap 0.5)
			(thermal_bridge_width 0.5)
			(island_removal_mode 0)
		)
		(polygon
			(pts
				(arc
					(start 51.5366 -386.170424)
					(mid 51.646571 -386.271478)
					(end 51.791362 -386.308092)
				)
				(arc
					(start 51.791362 -386.308092)
					(mid 52.006888 -386.218818)
					(end 52.096162 -386.003292)
				)
				(arc
					(start 52.096162 -386.003292)
					(mid 52.085825 -385.924553)
					(end 52.055522 -385.851146)
				)
				(arc
					(start 51.663092 -385.172204)
					(mid 51.550695 -385.050587)
					(end 51.391312 -385.00558)
				)
				(arc
					(start 51.391312 -385.00558)
					(mid 51.175786 -385.094854)
					(end 51.086512 -385.31038)
				)
				(arc
					(start 51.086512 -385.31038)
					(mid 51.09609 -385.386442)
					(end 51.124358 -385.4577)
				)
				(xy 51.521614 -386.145024) (xy 51.533806 -386.16636) (xy 51.536346 -386.170678)
			)
		)
	)
	(zone
		(layers "F.Cu" "B.Cu" "In1.Cu" "In2.Cu" "In3.Cu" "In4.Cu" "In5.Cu" "In6.Cu"
			"In7.Cu" "In8.Cu" "In9.Cu" "In10.Cu" "In11.Cu" "In12.Cu" "In13.Cu" "In14.Cu"
			"In15.Cu" "In16.Cu"
		)
		(hatch none 0.5)
		(connect_pads
			(clearance 0)
		)
		(min_thickness 0.25)
		(keepout
			(tracks not_allowed)
			(vias allowed)
			(pads allowed)
			(copperpour not_allowed)
			(footprints allowed)
		)
		(placement
			(enabled no)
			(sheetname "")
		)
		(fill
			(thermal_gap 0.5)
			(thermal_bridge_width 0.5)
			(island_removal_mode 0)
		)
		(polygon
			(pts
				(arc
					(start 282.917138 -407.175716)
					(mid 282.536138 -407.556716)
					(end 282.917138 -407.937716)
				)
				(arc
					(start 283.780738 -407.937716)
					(mid 284.161738 -407.556716)
					(end 283.780738 -407.175716)
				)
			)
		)
	)
	(zone
		(layers "F.Cu" "B.Cu" "In1.Cu" "In2.Cu" "In3.Cu" "In4.Cu" "In5.Cu" "In6.Cu"
			"In7.Cu" "In8.Cu" "In9.Cu" "In10.Cu" "In11.Cu" "In12.Cu" "In13.Cu" "In14.Cu"
			"In15.Cu" "In16.Cu"
		)
		(hatch none 0.5)
		(connect_pads
			(clearance 0)
		)
		(min_thickness 0.25)
		(keepout
			(tracks not_allowed)
			(vias allowed)
			(pads allowed)
			(copperpour not_allowed)
			(footprints allowed)
		)
		(placement
			(enabled no)
			(sheetname "")
		)
		(fill
			(thermal_gap 0.5)
			(thermal_bridge_width 0.5)
			(island_removal_mode 0)
		)
		(polygon
			(pts
				(arc
					(start 350.863916 -398.016476)
					(mid 350.973887 -398.11753)
					(end 351.118678 -398.154144)
				)
				(arc
					(start 351.118678 -398.154144)
					(mid 351.334204 -398.06487)
					(end 351.423478 -397.849344)
				)
				(arc
					(start 351.423478 -397.849344)
					(mid 351.413141 -397.770605)
					(end 351.382838 -397.697198)
				)
				(arc
					(start 350.990408 -397.018256)
					(mid 350.878011 -396.896639)
					(end 350.718628 -396.851632)
				)
				(arc
					(start 350.718628 -396.851632)
					(mid 350.503102 -396.940906)
					(end 350.413828 -397.156432)
				)
				(arc
					(start 350.413828 -397.156432)
					(mid 350.423406 -397.232494)
					(end 350.451674 -397.303752)
				)
				(xy 350.84893 -397.991076) (xy 350.861122 -398.012412) (xy 350.863662 -398.01673)
			)
		)
	)
	(zone
		(layers "F.Cu" "B.Cu" "In1.Cu" "In2.Cu" "In3.Cu" "In4.Cu" "In5.Cu" "In6.Cu"
			"In7.Cu" "In8.Cu" "In9.Cu" "In10.Cu" "In11.Cu" "In12.Cu" "In13.Cu" "In14.Cu"
			"In15.Cu" "In16.Cu"
		)
		(hatch none 0.5)
		(connect_pads
			(clearance 0)
		)
		(min_thickness 0.25)
		(keepout
			(tracks not_allowed)
			(vias allowed)
			(pads allowed)
			(copperpour not_allowed)
			(footprints allowed)
		)
		(placement
			(enabled no)
			(sheetname "")
		)
		(fill
			(thermal_gap 0.5)
			(thermal_bridge_width 0.5)
			(island_removal_mode 0)
		)
		(polygon
			(pts
				(arc
					(start 378.497592 -400.811238)
					(mid 378.116592 -400.430238)
					(end 377.735592 -400.811238)
				)
				(arc
					(start 377.735592 -401.674838)
					(mid 378.116592 -402.055838)
					(end 378.497592 -401.674838)
				)
			)
		)
	)
	(zone
		(layers "F.Cu" "B.Cu" "In1.Cu" "In2.Cu" "In3.Cu" "In4.Cu" "In5.Cu" "In6.Cu"
			"In7.Cu" "In8.Cu" "In9.Cu" "In10.Cu" "In11.Cu" "In12.Cu" "In13.Cu" "In14.Cu"
			"In15.Cu" "In16.Cu"
		)
		(hatch none 0.5)
		(connect_pads
			(clearance 0)
		)
		(min_thickness 0.25)
		(keepout
			(tracks not_allowed)
			(vias allowed)
			(pads allowed)
			(copperpour not_allowed)
			(footprints allowed)
		)
		(placement
			(enabled no)
			(sheetname "")
		)
		(fill
			(thermal_gap 0.5)
			(thermal_bridge_width 0.5)
			(island_removal_mode 0)
		)
		(polygon
			(pts
				(arc
					(start 15.533878 -17.23136)
					(mid 15.152878 -17.61236)
					(end 15.533878 -17.99336)
				)
				(arc
					(start 16.397478 -17.99336)
					(mid 16.778478 -17.61236)
					(end 16.397478 -17.23136)
				)
			)
		)
	)
	(zone
		(layers "F.Cu" "B.Cu" "In1.Cu" "In2.Cu" "In3.Cu" "In4.Cu" "In5.Cu" "In6.Cu"
			"In7.Cu" "In8.Cu" "In9.Cu" "In10.Cu" "In11.Cu" "In12.Cu" "In13.Cu" "In14.Cu"
			"In15.Cu" "In16.Cu"
		)
		(hatch none 0.5)
		(connect_pads
			(clearance 0)
		)
		(min_thickness 0.25)
		(keepout
			(tracks not_allowed)
			(vias allowed)
			(pads allowed)
			(copperpour not_allowed)
			(footprints allowed)
		)
		(placement
			(enabled no)
			(sheetname "")
		)
		(fill
			(thermal_gap 0.5)
			(thermal_bridge_width 0.5)
			(island_removal_mode 0)
		)
		(polygon
			(pts
				(arc
					(start 63.436754 -371.11813)
					(mid 63.055754 -371.49913)
					(end 63.436754 -371.88013)
				)
				(arc
					(start 64.300354 -371.88013)
					(mid 64.681354 -371.49913)
					(end 64.300354 -371.11813)
				)
			)
		)
	)
	(zone
		(layers "F.Cu" "B.Cu" "In1.Cu" "In2.Cu" "In3.Cu" "In4.Cu" "In5.Cu" "In6.Cu"
			"In7.Cu" "In8.Cu" "In9.Cu" "In10.Cu" "In11.Cu" "In12.Cu" "In13.Cu" "In14.Cu"
			"In15.Cu" "In16.Cu"
		)
		(hatch none 0.5)
		(connect_pads
			(clearance 0)
		)
		(min_thickness 0.25)
		(keepout
			(tracks not_allowed)
			(vias allowed)
			(pads allowed)
			(copperpour not_allowed)
			(footprints allowed)
		)
		(placement
			(enabled no)
			(sheetname "")
		)
		(fill
			(thermal_gap 0.5)
			(thermal_bridge_width 0.5)
			(island_removal_mode 0)
		)
		(polygon
			(pts
				(arc
					(start 64.141858 -425.360592)
					(mid 64.164176 -425.414474)
					(end 64.218058 -425.436792)
				)
				(arc
					(start 65.157858 -425.436792)
					(mid 65.21174 -425.414474)
					(end 65.234058 -425.360592)
				)
				(arc
					(start 65.234058 -422.819068)
					(mid 65.21174 -422.765186)
					(end 65.157858 -422.742868)
				)
				(arc
					(start 64.218058 -422.742868)
					(mid 64.164176 -422.765186)
					(end 64.141858 -422.819068)
				)
			)
		)
	)
	(zone
		(layers "F.Cu" "B.Cu" "In1.Cu" "In2.Cu" "In3.Cu" "In4.Cu" "In5.Cu" "In6.Cu"
			"In7.Cu" "In8.Cu" "In9.Cu" "In10.Cu" "In11.Cu" "In12.Cu" "In13.Cu" "In14.Cu"
			"In15.Cu" "In16.Cu"
		)
		(hatch none 0.5)
		(connect_pads
			(clearance 0)
		)
		(min_thickness 0.25)
		(keepout
			(tracks not_allowed)
			(vias allowed)
			(pads allowed)
			(copperpour not_allowed)
			(footprints allowed)
		)
		(placement
			(enabled no)
			(sheetname "")
		)
		(fill
			(thermal_gap 0.5)
			(thermal_bridge_width 0.5)
			(island_removal_mode 0)
		)
		(polygon
			(pts
				(arc
					(start 351.274126 -415.00552)
					(mid 350.893126 -415.38652)
					(end 351.274126 -415.76752)
				)
				(arc
					(start 352.137726 -415.76752)
					(mid 352.518726 -415.38652)
					(end 352.137726 -415.00552)
				)
			)
		)
	)
	(zone
		(layers "F.Cu" "B.Cu" "In1.Cu" "In2.Cu" "In3.Cu" "In4.Cu" "In5.Cu" "In6.Cu"
			"In7.Cu" "In8.Cu" "In9.Cu" "In10.Cu" "In11.Cu" "In12.Cu" "In13.Cu" "In14.Cu"
			"In15.Cu" "In16.Cu"
		)
		(hatch none 0.5)
		(connect_pads
			(clearance 0)
		)
		(min_thickness 0.25)
		(keepout
			(tracks not_allowed)
			(vias allowed)
			(pads allowed)
			(copperpour not_allowed)
			(footprints allowed)
		)
		(placement
			(enabled no)
			(sheetname "")
		)
		(fill
			(thermal_gap 0.5)
			(thermal_bridge_width 0.5)
			(island_removal_mode 0)
		)
		(polygon
			(pts
				(arc
					(start 154.716226 -404.08352)
					(mid 154.335226 -404.46452)
					(end 154.716226 -404.84552)
				)
				(arc
					(start 155.579826 -404.84552)
					(mid 155.960826 -404.46452)
					(end 155.579826 -404.08352)
				)
			)
		)
	)
	(zone
		(layers "F.Cu" "B.Cu" "In1.Cu" "In2.Cu" "In3.Cu" "In4.Cu" "In5.Cu" "In6.Cu"
			"In7.Cu" "In8.Cu" "In9.Cu" "In10.Cu" "In11.Cu" "In12.Cu" "In13.Cu" "In14.Cu"
			"In15.Cu" "In16.Cu"
		)
		(hatch none 0.5)
		(connect_pads
			(clearance 0)
		)
		(min_thickness 0.25)
		(keepout
			(tracks not_allowed)
			(vias allowed)
			(pads allowed)
			(copperpour not_allowed)
			(footprints allowed)
		)
		(placement
			(enabled no)
			(sheetname "")
		)
		(fill
			(thermal_gap 0.5)
			(thermal_bridge_width 0.5)
			(island_removal_mode 0)
		)
		(polygon
			(pts
				(arc
					(start 70.141846 -424.360594)
					(mid 70.164164 -424.414476)
					(end 70.218046 -424.436794)
				)
				(arc
					(start 71.157846 -424.436794)
					(mid 71.211728 -424.414476)
					(end 71.234046 -424.360594)
				)
				(arc
					(start 71.234046 -421.81907)
					(mid 71.211728 -421.765188)
					(end 71.157846 -421.74287)
				)
				(arc
					(start 70.218046 -421.74287)
					(mid 70.164164 -421.765188)
					(end 70.141846 -421.81907)
				)
			)
		)
	)
	(zone
		(layers "F.Cu" "B.Cu" "In1.Cu" "In2.Cu" "In3.Cu" "In4.Cu" "In5.Cu" "In6.Cu"
			"In7.Cu" "In8.Cu" "In9.Cu" "In10.Cu" "In11.Cu" "In12.Cu" "In13.Cu" "In14.Cu"
			"In15.Cu" "In16.Cu"
		)
		(hatch none 0.5)
		(connect_pads
			(clearance 0)
		)
		(min_thickness 0.25)
		(keepout
			(tracks not_allowed)
			(vias allowed)
			(pads allowed)
			(copperpour not_allowed)
			(footprints allowed)
		)
		(placement
			(enabled no)
			(sheetname "")
		)
		(fill
			(thermal_gap 0.5)
			(thermal_bridge_width 0.5)
			(island_removal_mode 0)
		)
		(polygon
			(pts
				(arc
					(start 407.425144 -400.811238)
					(mid 407.044144 -400.430238)
					(end 406.663144 -400.811238)
				)
				(arc
					(start 406.663144 -401.674838)
					(mid 407.044144 -402.055838)
					(end 407.425144 -401.674838)
				)
			)
		)
	)
	(zone
		(layers "F.Cu" "B.Cu" "In1.Cu" "In2.Cu" "In3.Cu" "In4.Cu" "In5.Cu" "In6.Cu"
			"In7.Cu" "In8.Cu" "In9.Cu" "In10.Cu" "In11.Cu" "In12.Cu" "In13.Cu" "In14.Cu"
			"In15.Cu" "In16.Cu"
		)
		(hatch none 0.5)
		(connect_pads
			(clearance 0)
		)
		(min_thickness 0.25)
		(keepout
			(tracks not_allowed)
			(vias allowed)
			(pads allowed)
			(copperpour not_allowed)
			(footprints allowed)
		)
		(placement
			(enabled no)
			(sheetname "")
		)
		(fill
			(thermal_gap 0.5)
			(thermal_bridge_width 0.5)
			(island_removal_mode 0)
		)
		(polygon
			(pts
				(arc
					(start 124.55652 -33.005268)
					(mid 124.17552 -33.386268)
					(end 124.55652 -33.767268)
				)
				(arc
					(start 125.42012 -33.767268)
					(mid 125.80112 -33.386268)
					(end 125.42012 -33.005268)
				)
			)
		)
	)
	(zone
		(layers "F.Cu" "B.Cu" "In1.Cu" "In2.Cu" "In3.Cu" "In4.Cu" "In5.Cu" "In6.Cu"
			"In7.Cu" "In8.Cu" "In9.Cu" "In10.Cu" "In11.Cu" "In12.Cu" "In13.Cu" "In14.Cu"
			"In15.Cu" "In16.Cu"
		)
		(hatch none 0.5)
		(connect_pads
			(clearance 0)
		)
		(min_thickness 0.25)
		(keepout
			(tracks not_allowed)
			(vias allowed)
			(pads allowed)
			(copperpour not_allowed)
			(footprints allowed)
		)
		(placement
			(enabled no)
			(sheetname "")
		)
		(fill
			(thermal_gap 0.5)
			(thermal_bridge_width 0.5)
			(island_removal_mode 0)
		)
		(polygon
			(pts
				(arc
					(start 353.264216 -394.552424)
					(mid 353.374187 -394.653478)
					(end 353.518978 -394.690092)
				)
				(arc
					(start 353.518978 -394.690092)
					(mid 353.734504 -394.600818)
					(end 353.823778 -394.385292)
				)
				(arc
					(start 353.823778 -394.385292)
					(mid 353.813441 -394.306553)
					(end 353.783138 -394.233146)
				)
				(arc
					(start 353.390708 -393.554204)
					(mid 353.278311 -393.432587)
					(end 353.118928 -393.38758)
				)
				(arc
					(start 353.118928 -393.38758)
					(mid 352.903402 -393.476854)
					(end 352.814128 -393.69238)
				)
				(arc
					(start 352.814128 -393.69238)
					(mid 352.823706 -393.768442)
					(end 352.851974 -393.8397)
				)
				(xy 353.24923 -394.527024) (xy 353.261422 -394.54836) (xy 353.263962 -394.552678)
			)
		)
	)
	(zone
		(layers "F.Cu" "B.Cu" "In1.Cu" "In2.Cu" "In3.Cu" "In4.Cu" "In5.Cu" "In6.Cu"
			"In7.Cu" "In8.Cu" "In9.Cu" "In10.Cu" "In11.Cu" "In12.Cu" "In13.Cu" "In14.Cu"
			"In15.Cu" "In16.Cu"
		)
		(hatch none 0.5)
		(connect_pads
			(clearance 0)
		)
		(min_thickness 0.25)
		(keepout
			(tracks not_allowed)
			(vias allowed)
			(pads allowed)
			(copperpour not_allowed)
			(footprints allowed)
		)
		(placement
			(enabled no)
			(sheetname "")
		)
		(fill
			(thermal_gap 0.5)
			(thermal_bridge_width 0.5)
			(island_removal_mode 0)
		)
		(polygon
			(pts
				(arc
					(start 147.058126 -409.649168)
					(mid 146.677126 -410.030168)
					(end 147.058126 -410.411168)
				)
				(arc
					(start 147.921726 -410.411168)
					(mid 148.302726 -410.030168)
					(end 147.921726 -409.649168)
				)
			)
		)
	)
	(zone
		(layers "F.Cu" "B.Cu" "In1.Cu" "In2.Cu" "In3.Cu" "In4.Cu" "In5.Cu" "In6.Cu"
			"In7.Cu" "In8.Cu" "In9.Cu" "In10.Cu" "In11.Cu" "In12.Cu" "In13.Cu" "In14.Cu"
			"In15.Cu" "In16.Cu"
		)
		(hatch none 0.5)
		(connect_pads
			(clearance 0)
		)
		(min_thickness 0.25)
		(keepout
			(tracks not_allowed)
			(vias allowed)
			(pads allowed)
			(copperpour not_allowed)
			(footprints allowed)
		)
		(placement
			(enabled no)
			(sheetname "")
		)
		(fill
			(thermal_gap 0.5)
			(thermal_bridge_width 0.5)
			(island_removal_mode 0)
		)
		(polygon
			(pts
				(arc
					(start 384.678682 -418.031168)
					(mid 384.297682 -418.412168)
					(end 384.678682 -418.793168)
				)
				(arc
					(start 385.542282 -418.793168)
					(mid 385.923282 -418.412168)
					(end 385.542282 -418.031168)
				)
			)
		)
	)
	(zone
		(layers "F.Cu" "B.Cu" "In1.Cu" "In2.Cu" "In3.Cu" "In4.Cu" "In5.Cu" "In6.Cu"
			"In7.Cu" "In8.Cu" "In9.Cu" "In10.Cu" "In11.Cu" "In12.Cu" "In13.Cu" "In14.Cu"
			"In15.Cu" "In16.Cu"
		)
		(hatch none 0.5)
		(connect_pads
			(clearance 0)
		)
		(min_thickness 0.25)
		(keepout
			(tracks not_allowed)
			(vias allowed)
			(pads allowed)
			(copperpour not_allowed)
			(footprints allowed)
		)
		(placement
			(enabled no)
			(sheetname "")
		)
		(fill
			(thermal_gap 0.5)
			(thermal_bridge_width 0.5)
			(island_removal_mode 0)
		)
		(polygon
			(pts
				(arc
					(start 21.943314 -425.328334)
					(mid 22.324314 -425.709334)
					(end 22.705314 -425.328334)
				)
				(arc
					(start 22.705314 -424.464734)
					(mid 22.324314 -424.083734)
					(end 21.943314 -424.464734)
				)
			)
		)
	)
	(zone
		(layers "F.Cu" "B.Cu" "In1.Cu" "In2.Cu" "In3.Cu" "In4.Cu" "In5.Cu" "In6.Cu"
			"In7.Cu" "In8.Cu" "In9.Cu" "In10.Cu" "In11.Cu" "In12.Cu" "In13.Cu" "In14.Cu"
			"In15.Cu" "In16.Cu"
		)
		(hatch none 0.5)
		(connect_pads
			(clearance 0)
		)
		(min_thickness 0.25)
		(keepout
			(tracks not_allowed)
			(vias allowed)
			(pads allowed)
			(copperpour not_allowed)
			(footprints allowed)
		)
		(placement
			(enabled no)
			(sheetname "")
		)
		(fill
			(thermal_gap 0.5)
			(thermal_bridge_width 0.5)
			(island_removal_mode 0)
		)
		(polygon
			(pts
				(arc
					(start 130.897376 -392.429238)
					(mid 130.516376 -392.048238)
					(end 130.135376 -392.429238)
				)
				(arc
					(start 130.135376 -393.292838)
					(mid 130.516376 -393.673838)
					(end 130.897376 -393.292838)
				)
			)
		)
	)
	(zone
		(layers "F.Cu" "B.Cu" "In1.Cu" "In2.Cu" "In3.Cu" "In4.Cu" "In5.Cu" "In6.Cu"
			"In7.Cu" "In8.Cu" "In9.Cu" "In10.Cu" "In11.Cu" "In12.Cu" "In13.Cu" "In14.Cu"
			"In15.Cu" "In16.Cu"
		)
		(hatch none 0.5)
		(connect_pads
			(clearance 0)
		)
		(min_thickness 0.25)
		(keepout
			(tracks not_allowed)
			(vias allowed)
			(pads allowed)
			(copperpour not_allowed)
			(footprints allowed)
		)
		(placement
			(enabled no)
			(sheetname "")
		)
		(fill
			(thermal_gap 0.5)
			(thermal_bridge_width 0.5)
			(island_removal_mode 0)
		)
		(polygon
			(pts
				(arc
					(start 348.210886 -418.031168)
					(mid 347.829886 -418.412168)
					(end 348.210886 -418.793168)
				)
				(arc
					(start 349.074486 -418.793168)
					(mid 349.455486 -418.412168)
					(end 349.074486 -418.031168)
				)
			)
		)
	)
	(zone
		(layers "F.Cu" "B.Cu" "In1.Cu" "In2.Cu" "In3.Cu" "In4.Cu" "In5.Cu" "In6.Cu"
			"In7.Cu" "In8.Cu" "In9.Cu" "In10.Cu" "In11.Cu" "In12.Cu" "In13.Cu" "In14.Cu"
			"In15.Cu" "In16.Cu"
		)
		(hatch none 0.5)
		(connect_pads
			(clearance 0)
		)
		(min_thickness 0.25)
		(keepout
			(tracks not_allowed)
			(vias allowed)
			(pads allowed)
			(copperpour not_allowed)
			(footprints allowed)
		)
		(placement
			(enabled no)
			(sheetname "")
		)
		(fill
			(thermal_gap 0.5)
			(thermal_bridge_width 0.5)
			(island_removal_mode 0)
		)
		(polygon
			(pts
				(arc
					(start 156.247846 -406.62352)
					(mid 155.866846 -407.00452)
					(end 156.247846 -407.38552)
				)
				(arc
					(start 157.111446 -407.38552)
					(mid 157.492446 -407.00452)
					(end 157.111446 -406.62352)
				)
			)
		)
	)
	(zone
		(layers "F.Cu" "B.Cu" "In1.Cu" "In2.Cu" "In3.Cu" "In4.Cu" "In5.Cu" "In6.Cu"
			"In7.Cu" "In8.Cu" "In9.Cu" "In10.Cu" "In11.Cu" "In12.Cu" "In13.Cu" "In14.Cu"
			"In15.Cu" "In16.Cu"
		)
		(hatch none 0.5)
		(connect_pads
			(clearance 0)
		)
		(min_thickness 0.25)
		(keepout
			(tracks not_allowed)
			(vias allowed)
			(pads allowed)
			(copperpour not_allowed)
			(footprints allowed)
		)
		(placement
			(enabled no)
			(sheetname "")
		)
		(fill
			(thermal_gap 0.5)
			(thermal_bridge_width 0.5)
			(island_removal_mode 0)
		)
		(polygon
			(pts
				(arc
					(start 153.564336 -389.634476)
					(mid 153.674307 -389.73553)
					(end 153.819098 -389.772144)
				)
				(arc
					(start 153.819098 -389.772144)
					(mid 154.034624 -389.68287)
					(end 154.123898 -389.467344)
				)
				(arc
					(start 154.123898 -389.467344)
					(mid 154.113561 -389.388605)
					(end 154.083258 -389.315198)
				)
				(arc
					(start 153.690828 -388.636256)
					(mid 153.578431 -388.514639)
					(end 153.419048 -388.469632)
				)
				(arc
					(start 153.419048 -388.469632)
					(mid 153.203522 -388.558906)
					(end 153.114248 -388.774432)
				)
				(arc
					(start 153.114248 -388.774432)
					(mid 153.123826 -388.850494)
					(end 153.152094 -388.921752)
				)
				(xy 153.54935 -389.609076) (xy 153.561542 -389.630412) (xy 153.564082 -389.63473)
			)
		)
	)
	(zone
		(layers "F.Cu" "B.Cu" "In1.Cu" "In2.Cu" "In3.Cu" "In4.Cu" "In5.Cu" "In6.Cu"
			"In7.Cu" "In8.Cu" "In9.Cu" "In10.Cu" "In11.Cu" "In12.Cu" "In13.Cu" "In14.Cu"
			"In15.Cu" "In16.Cu"
		)
		(hatch none 0.5)
		(connect_pads
			(clearance 0)
		)
		(min_thickness 0.25)
		(keepout
			(tracks not_allowed)
			(vias allowed)
			(pads allowed)
			(copperpour not_allowed)
			(footprints allowed)
		)
		(placement
			(enabled no)
			(sheetname "")
		)
		(fill
			(thermal_gap 0.5)
			(thermal_bridge_width 0.5)
			(island_removal_mode 0)
		)
		(polygon
			(pts
				(arc
					(start 255.546098 -211.011516)
					(mid 255.927098 -211.392516)
					(end 256.308098 -211.011516)
				)
				(arc
					(start 256.308098 -210.147916)
					(mid 255.927098 -209.766916)
					(end 255.546098 -210.147916)
				)
			)
		)
	)
	(zone
		(layers "F.Cu" "B.Cu" "In1.Cu" "In2.Cu" "In3.Cu" "In4.Cu" "In5.Cu" "In6.Cu"
			"In7.Cu" "In8.Cu" "In9.Cu" "In10.Cu" "In11.Cu" "In12.Cu" "In13.Cu" "In14.Cu"
			"In15.Cu" "In16.Cu"
		)
		(hatch none 0.5)
		(connect_pads
			(clearance 0)
		)
		(min_thickness 0.25)
		(keepout
			(tracks not_allowed)
			(vias allowed)
			(pads allowed)
			(copperpour not_allowed)
			(footprints allowed)
		)
		(placement
			(enabled no)
			(sheetname "")
		)
		(fill
			(thermal_gap 0.5)
			(thermal_bridge_width 0.5)
			(island_removal_mode 0)
		)
		(polygon
			(pts
				(arc
					(start 50.597562 -392.429238)
					(mid 50.216562 -392.048238)
					(end 49.835562 -392.429238)
				)
				(arc
					(start 49.835562 -393.292838)
					(mid 50.216562 -393.673838)
					(end 50.597562 -393.292838)
				)
			)
		)
	)
	(zone
		(layers "F.Cu" "B.Cu" "In1.Cu" "In2.Cu" "In3.Cu" "In4.Cu" "In5.Cu" "In6.Cu"
			"In7.Cu" "In8.Cu" "In9.Cu" "In10.Cu" "In11.Cu" "In12.Cu" "In13.Cu" "In14.Cu"
			"In15.Cu" "In16.Cu"
		)
		(hatch none 0.5)
		(connect_pads
			(clearance 0)
		)
		(min_thickness 0.25)
		(keepout
			(tracks not_allowed)
			(vias allowed)
			(pads allowed)
			(copperpour not_allowed)
			(footprints allowed)
		)
		(placement
			(enabled no)
			(sheetname "")
		)
		(fill
			(thermal_gap 0.5)
			(thermal_bridge_width 0.5)
			(island_removal_mode 0)
		)
		(polygon
			(pts
				(arc
					(start 321.936364 -398.016476)
					(mid 322.046335 -398.11753)
					(end 322.191126 -398.154144)
				)
				(arc
					(start 322.191126 -398.154144)
					(mid 322.406652 -398.06487)
					(end 322.495926 -397.849344)
				)
				(arc
					(start 322.495926 -397.849344)
					(mid 322.485589 -397.770605)
					(end 322.455286 -397.697198)
				)
				(arc
					(start 322.062856 -397.018256)
					(mid 321.950459 -396.896639)
					(end 321.791076 -396.851632)
				)
				(arc
					(start 321.791076 -396.851632)
					(mid 321.57555 -396.940906)
					(end 321.486276 -397.156432)
				)
				(arc
					(start 321.486276 -397.156432)
					(mid 321.495854 -397.232494)
					(end 321.524122 -397.303752)
				)
				(xy 321.921378 -397.991076) (xy 321.93357 -398.012412) (xy 321.93611 -398.01673)
			)
		)
	)
	(zone
		(layers "F.Cu" "B.Cu" "In1.Cu" "In2.Cu" "In3.Cu" "In4.Cu" "In5.Cu" "In6.Cu"
			"In7.Cu" "In8.Cu" "In9.Cu" "In10.Cu" "In11.Cu" "In12.Cu" "In13.Cu" "In14.Cu"
			"In15.Cu" "In16.Cu"
		)
		(hatch none 0.5)
		(connect_pads
			(clearance 0)
		)
		(min_thickness 0.25)
		(keepout
			(tracks not_allowed)
			(vias allowed)
			(pads allowed)
			(copperpour not_allowed)
			(footprints allowed)
		)
		(placement
			(enabled no)
			(sheetname "")
		)
		(fill
			(thermal_gap 0.5)
			(thermal_bridge_width 0.5)
			(island_removal_mode 0)
		)
		(polygon
			(pts
				(arc
					(start 311.397396 -400.811238)
					(mid 311.016396 -400.430238)
					(end 310.635396 -400.811238)
				)
				(arc
					(start 310.635396 -401.674838)
					(mid 311.016396 -402.055838)
					(end 311.397396 -401.674838)
				)
			)
		)
	)
	(zone
		(layers "F.Cu" "B.Cu" "In1.Cu" "In2.Cu" "In3.Cu" "In4.Cu" "In5.Cu" "In6.Cu"
			"In7.Cu" "In8.Cu" "In9.Cu" "In10.Cu" "In11.Cu" "In12.Cu" "In13.Cu" "In14.Cu"
			"In15.Cu" "In16.Cu"
		)
		(hatch none 0.5)
		(connect_pads
			(clearance 0)
		)
		(min_thickness 0.25)
		(keepout
			(tracks not_allowed)
			(vias allowed)
			(pads allowed)
			(copperpour not_allowed)
			(footprints allowed)
		)
		(placement
			(enabled no)
			(sheetname "")
		)
		(fill yes
			(thermal_gap 0.5)
			(thermal_bridge_width 0.5)
			(island_removal_mode 0)
		)
		(polygon
			(pts
				(arc
					(start 165.564312 -386.170424)
					(mid 165.674283 -386.271478)
					(end 165.819074 -386.308092)
				)
				(arc
					(start 165.819074 -386.308092)
					(mid 166.0346 -386.218818)
					(end 166.123874 -386.003292)
				)
				(arc
					(start 166.123874 -386.003292)
					(mid 166.113537 -385.924553)
					(end 166.083234 -385.851146)
				)
				(arc
					(start 165.690804 -385.172204)
					(mid 165.578407 -385.050587)
					(end 165.419024 -385.00558)
				)
				(arc
					(start 165.419024 -385.00558)
					(mid 165.203498 -385.094854)
					(end 165.114224 -385.31038)
				)
				(arc
					(start 165.114224 -385.31038)
					(mid 165.123802 -385.386442)
					(end 165.15207 -385.4577)
				)
				(xy 165.549326 -386.145024) (xy 165.561518 -386.16636) (xy 165.564058 -386.170678)
			)
		)
	)
	(zone
		(layers "F.Cu" "B.Cu" "In1.Cu" "In2.Cu" "In3.Cu" "In4.Cu" "In5.Cu" "In6.Cu"
			"In7.Cu" "In8.Cu" "In9.Cu" "In10.Cu" "In11.Cu" "In12.Cu" "In13.Cu" "In14.Cu"
			"In15.Cu" "In16.Cu"
		)
		(hatch none 0.5)
		(connect_pads
			(clearance 0)
		)
		(min_thickness 0.25)
		(keepout
			(tracks not_allowed)
			(vias allowed)
			(pads allowed)
			(copperpour not_allowed)
			(footprints allowed)
		)
		(placement
			(enabled no)
			(sheetname "")
		)
		(fill
			(thermal_gap 0.5)
			(thermal_bridge_width 0.5)
			(island_removal_mode 0)
		)
		(polygon
			(pts
				(arc
					(start 461.799686 -33.899856)
					(mid 464.799934 -36.900104)
					(end 467.800182 -33.899856)
				)
				(arc
					(start 467.800182 -32.299656)
					(mid 464.799934 -29.299408)
					(end 461.799686 -32.299656)
				)
			)
		)
	)
	(zone
		(layers "F.Cu" "B.Cu" "In1.Cu" "In2.Cu" "In3.Cu" "In4.Cu" "In5.Cu" "In6.Cu"
			"In7.Cu" "In8.Cu" "In9.Cu" "In10.Cu" "In11.Cu" "In12.Cu" "In13.Cu" "In14.Cu"
			"In15.Cu" "In16.Cu"
		)
		(hatch none 0.5)
		(connect_pads
			(clearance 0)
		)
		(min_thickness 0.25)
		(keepout
			(tracks not_allowed)
			(vias allowed)
			(pads allowed)
			(copperpour not_allowed)
			(footprints allowed)
		)
		(placement
			(enabled no)
			(sheetname "")
		)
		(fill
			(thermal_gap 0.5)
			(thermal_bridge_width 0.5)
			(island_removal_mode 0)
		)
		(polygon
			(pts
				(arc
					(start 97.26422 -389.634476)
					(mid 97.374191 -389.73553)
					(end 97.518982 -389.772144)
				)
				(arc
					(start 97.518982 -389.772144)
					(mid 97.734508 -389.68287)
					(end 97.823782 -389.467344)
				)
				(arc
					(start 97.823782 -389.467344)
					(mid 97.813445 -389.388605)
					(end 97.783142 -389.315198)
				)
				(arc
					(start 97.390712 -388.636256)
					(mid 97.278315 -388.514639)
					(end 97.118932 -388.469632)
				)
				(arc
					(start 97.118932 -388.469632)
					(mid 96.903406 -388.558906)
					(end 96.814132 -388.774432)
				)
				(arc
					(start 96.814132 -388.774432)
					(mid 96.82371 -388.850494)
					(end 96.851978 -388.921752)
				)
				(xy 97.249234 -389.609076) (xy 97.261426 -389.630412) (xy 97.263966 -389.63473)
			)
		)
	)
	(zone
		(layers "F.Cu" "B.Cu" "In1.Cu" "In2.Cu" "In3.Cu" "In4.Cu" "In5.Cu" "In6.Cu"
			"In7.Cu" "In8.Cu" "In9.Cu" "In10.Cu" "In11.Cu" "In12.Cu" "In13.Cu" "In14.Cu"
			"In15.Cu" "In16.Cu"
		)
		(hatch none 0.5)
		(connect_pads
			(clearance 0)
		)
		(min_thickness 0.25)
		(keepout
			(tracks not_allowed)
			(vias allowed)
			(pads allowed)
			(copperpour not_allowed)
			(footprints allowed)
		)
		(placement
			(enabled no)
			(sheetname "")
		)
		(fill
			(thermal_gap 0.5)
			(thermal_bridge_width 0.5)
			(island_removal_mode 0)
		)
		(polygon
			(pts
				(arc
					(start 52.736496 -389.634476)
					(mid 52.846467 -389.73553)
					(end 52.991258 -389.772144)
				)
				(arc
					(start 52.991258 -389.772144)
					(mid 53.206784 -389.68287)
					(end 53.296058 -389.467344)
				)
				(arc
					(start 53.296058 -389.467344)
					(mid 53.285721 -389.388605)
					(end 53.255418 -389.315198)
				)
				(arc
					(start 52.862988 -388.636256)
					(mid 52.750591 -388.514639)
					(end 52.591208 -388.469632)
				)
				(arc
					(start 52.591208 -388.469632)
					(mid 52.375682 -388.558906)
					(end 52.286408 -388.774432)
				)
				(arc
					(start 52.286408 -388.774432)
					(mid 52.295986 -388.850494)
					(end 52.324254 -388.921752)
				)
				(xy 52.72151 -389.609076) (xy 52.733702 -389.630412) (xy 52.736242 -389.63473)
			)
		)
	)
	(zone
		(layers "F.Cu" "B.Cu" "In1.Cu" "In2.Cu" "In3.Cu" "In4.Cu" "In5.Cu" "In6.Cu"
			"In7.Cu" "In8.Cu" "In9.Cu" "In10.Cu" "In11.Cu" "In12.Cu" "In13.Cu" "In14.Cu"
			"In15.Cu" "In16.Cu"
		)
		(hatch none 0.5)
		(connect_pads
			(clearance 0)
		)
		(min_thickness 0.25)
		(keepout
			(tracks not_allowed)
			(vias allowed)
			(pads allowed)
			(copperpour not_allowed)
			(footprints allowed)
		)
		(placement
			(enabled no)
			(sheetname "")
		)
		(fill
			(thermal_gap 0.5)
			(thermal_bridge_width 0.5)
			(island_removal_mode 0)
		)
		(polygon
			(pts
				(arc
					(start 342.084406 -418.031168)
					(mid 341.703406 -418.412168)
					(end 342.084406 -418.793168)
				)
				(arc
					(start 342.948006 -418.793168)
					(mid 343.329006 -418.412168)
					(end 342.948006 -418.031168)
				)
			)
		)
	)
	(zone
		(layers "F.Cu" "B.Cu" "In1.Cu" "In2.Cu" "In3.Cu" "In4.Cu" "In5.Cu" "In6.Cu"
			"In7.Cu" "In8.Cu" "In9.Cu" "In10.Cu" "In11.Cu" "In12.Cu" "In13.Cu" "In14.Cu"
			"In15.Cu" "In16.Cu"
		)
		(hatch none 0.5)
		(connect_pads
			(clearance 0)
		)
		(min_thickness 0.25)
		(keepout
			(tracks not_allowed)
			(vias allowed)
			(pads allowed)
			(copperpour not_allowed)
			(footprints allowed)
		)
		(placement
			(enabled no)
			(sheetname "")
		)
		(fill yes
			(thermal_gap 0.5)
			(thermal_bridge_width 0.5)
			(island_removal_mode 0)
		)
		(polygon
			(pts
				(arc
					(start 437.500014 -384.869944)
					(mid 433.500022 -388.869936)
					(end 429.50003 -384.869944)
				)
				(arc
					(start 429.50003 -384.869944)
					(mid 433.500022 -380.869952)
					(end 437.500014 -384.869944)
				)
			)
		)
	)
	(zone
		(layers "F.Cu" "B.Cu" "In1.Cu" "In2.Cu" "In3.Cu" "In4.Cu" "In5.Cu" "In6.Cu"
			"In7.Cu" "In8.Cu" "In9.Cu" "In10.Cu" "In11.Cu" "In12.Cu" "In13.Cu" "In14.Cu"
			"In15.Cu" "In16.Cu"
		)
		(hatch none 0.5)
		(connect_pads
			(clearance 0)
		)
		(min_thickness 0.25)
		(keepout
			(tracks not_allowed)
			(vias allowed)
			(pads allowed)
			(copperpour not_allowed)
			(footprints allowed)
		)
		(placement
			(enabled no)
			(sheetname "")
		)
		(fill
			(thermal_gap 0.5)
			(thermal_bridge_width 0.5)
			(island_removal_mode 0)
		)
		(polygon
			(pts
				(xy 516.219694 -423.51706) (xy 516.219694 -433.51704) (xy 516.524494 -433.21224) (xy 516.524494 -423.82186)
			)
		)
	)
	(zone
		(layers "F.Cu" "B.Cu" "In1.Cu" "In2.Cu" "In3.Cu" "In4.Cu" "In5.Cu" "In6.Cu"
			"In7.Cu" "In8.Cu" "In9.Cu" "In10.Cu" "In11.Cu" "In12.Cu" "In13.Cu" "In14.Cu"
			"In15.Cu" "In16.Cu"
		)
		(hatch none 0.5)
		(connect_pads
			(clearance 0)
		)
		(min_thickness 0.25)
		(keepout
			(tracks not_allowed)
			(vias allowed)
			(pads allowed)
			(copperpour not_allowed)
			(footprints allowed)
		)
		(placement
			(enabled no)
			(sheetname "")
		)
		(fill
			(thermal_gap 0.5)
			(thermal_bridge_width 0.5)
			(island_removal_mode 0)
		)
		(polygon
			(pts
				(arc
					(start 339.021166 -418.031168)
					(mid 338.640166 -418.412168)
					(end 339.021166 -418.793168)
				)
				(arc
					(start 339.884766 -418.793168)
					(mid 340.265766 -418.412168)
					(end 339.884766 -418.031168)
				)
			)
		)
	)
	(zone
		(layers "F.Cu" "B.Cu" "In1.Cu" "In2.Cu" "In3.Cu" "In4.Cu" "In5.Cu" "In6.Cu"
			"In7.Cu" "In8.Cu" "In9.Cu" "In10.Cu" "In11.Cu" "In12.Cu" "In13.Cu" "In14.Cu"
			"In15.Cu" "In16.Cu"
		)
		(hatch none 0.5)
		(connect_pads
			(clearance 0)
		)
		(min_thickness 0.25)
		(keepout
			(tracks not_allowed)
			(vias allowed)
			(pads allowed)
			(copperpour not_allowed)
			(footprints allowed)
		)
		(placement
			(enabled no)
			(sheetname "")
		)
		(fill
			(thermal_gap 0.5)
			(thermal_bridge_width 0.5)
			(island_removal_mode 0)
		)
		(polygon
			(pts
				(arc
					(start 364.763812 -395.308074)
					(mid 364.382812 -394.927074)
					(end 364.001812 -395.308074)
				)
				(arc
					(start 364.001812 -396.171674)
					(mid 364.382812 -396.552674)
					(end 364.763812 -396.171674)
				)
			)
		)
	)
	(zone
		(layers "F.Cu" "B.Cu" "In1.Cu" "In2.Cu" "In3.Cu" "In4.Cu" "In5.Cu" "In6.Cu"
			"In7.Cu" "In8.Cu" "In9.Cu" "In10.Cu" "In11.Cu" "In12.Cu" "In13.Cu" "In14.Cu"
			"In15.Cu" "In16.Cu"
		)
		(hatch none 0.5)
		(connect_pads
			(clearance 0)
		)
		(min_thickness 0.25)
		(keepout
			(tracks not_allowed)
			(vias allowed)
			(pads allowed)
			(copperpour not_allowed)
			(footprints allowed)
		)
		(placement
			(enabled no)
			(sheetname "")
		)
		(fill
			(thermal_gap 0.5)
			(thermal_bridge_width 0.5)
			(island_removal_mode 0)
		)
		(polygon
			(pts
				(arc
					(start 316.01283 -2.968244)
					(mid 316.44463 -3.400044)
					(end 316.87643 -2.968244)
				)
				(arc
					(start 316.87643 -2.104644)
					(mid 316.44463 -1.672844)
					(end 316.01283 -2.104644)
				)
			)
		)
	)
	(zone
		(layers "F.Cu" "B.Cu" "In1.Cu" "In2.Cu" "In3.Cu" "In4.Cu" "In5.Cu" "In6.Cu"
			"In7.Cu" "In8.Cu" "In9.Cu" "In10.Cu" "In11.Cu" "In12.Cu" "In13.Cu" "In14.Cu"
			"In15.Cu" "In16.Cu"
		)
		(hatch none 0.5)
		(connect_pads
			(clearance 0)
		)
		(min_thickness 0.25)
		(keepout
			(tracks not_allowed)
			(vias allowed)
			(pads allowed)
			(copperpour not_allowed)
			(footprints allowed)
		)
		(placement
			(enabled no)
			(sheetname "")
		)
		(fill
			(thermal_gap 0.5)
			(thermal_bridge_width 0.5)
			(island_removal_mode 0)
		)
		(polygon
			(pts
				(arc
					(start 413.164274 -398.016476)
					(mid 413.274245 -398.11753)
					(end 413.419036 -398.154144)
				)
				(arc
					(start 413.419036 -398.154144)
					(mid 413.634562 -398.06487)
					(end 413.723836 -397.849344)
				)
				(arc
					(start 413.723836 -397.849344)
					(mid 413.713499 -397.770605)
					(end 413.683196 -397.697198)
				)
				(arc
					(start 413.290766 -397.018256)
					(mid 413.178369 -396.896639)
					(end 413.018986 -396.851632)
				)
				(arc
					(start 413.018986 -396.851632)
					(mid 412.80346 -396.940906)
					(end 412.714186 -397.156432)
				)
				(arc
					(start 412.714186 -397.156432)
					(mid 412.723764 -397.232494)
					(end 412.752032 -397.303752)
				)
				(xy 413.149288 -397.991076) (xy 413.16148 -398.012412) (xy 413.16402 -398.01673)
			)
		)
	)
	(zone
		(layers "F.Cu" "B.Cu" "In1.Cu" "In2.Cu" "In3.Cu" "In4.Cu" "In5.Cu" "In6.Cu"
			"In7.Cu" "In8.Cu" "In9.Cu" "In10.Cu" "In11.Cu" "In12.Cu" "In13.Cu" "In14.Cu"
			"In15.Cu" "In16.Cu"
		)
		(hatch none 0.5)
		(connect_pads
			(clearance 0)
		)
		(min_thickness 0.25)
		(keepout
			(tracks not_allowed)
			(vias allowed)
			(pads allowed)
			(copperpour not_allowed)
			(footprints allowed)
		)
		(placement
			(enabled no)
			(sheetname "")
		)
		(fill
			(thermal_gap 0.5)
			(thermal_bridge_width 0.5)
			(island_removal_mode 0)
		)
		(polygon
			(pts
				(arc
					(start 386.897372 -400.811238)
					(mid 386.516372 -400.430238)
					(end 386.135372 -400.811238)
				)
				(arc
					(start 386.135372 -401.674838)
					(mid 386.516372 -402.055838)
					(end 386.897372 -401.674838)
				)
			)
		)
	)
	(zone
		(layers "F.Cu" "B.Cu" "In1.Cu" "In2.Cu" "In3.Cu" "In4.Cu" "In5.Cu" "In6.Cu"
			"In7.Cu" "In8.Cu" "In9.Cu" "In10.Cu" "In11.Cu" "In12.Cu" "In13.Cu" "In14.Cu"
			"In15.Cu" "In16.Cu"
		)
		(hatch none 0.5)
		(connect_pads
			(clearance 0)
		)
		(min_thickness 0.25)
		(keepout
			(tracks not_allowed)
			(vias allowed)
			(pads allowed)
			(copperpour not_allowed)
			(footprints allowed)
		)
		(placement
			(enabled no)
			(sheetname "")
		)
		(fill
			(thermal_gap 0.5)
			(thermal_bridge_width 0.5)
			(island_removal_mode 0)
		)
		(polygon
			(pts
				(arc
					(start 133.036564 -389.634476)
					(mid 133.146535 -389.73553)
					(end 133.291326 -389.772144)
				)
				(arc
					(start 133.291326 -389.772144)
					(mid 133.506852 -389.68287)
					(end 133.596126 -389.467344)
				)
				(arc
					(start 133.596126 -389.467344)
					(mid 133.585789 -389.388605)
					(end 133.555486 -389.315198)
				)
				(arc
					(start 133.163056 -388.636256)
					(mid 133.050659 -388.514639)
					(end 132.891276 -388.469632)
				)
				(arc
					(start 132.891276 -388.469632)
					(mid 132.67575 -388.558906)
					(end 132.586476 -388.774432)
				)
				(arc
					(start 132.586476 -388.774432)
					(mid 132.596054 -388.850494)
					(end 132.624322 -388.921752)
				)
				(xy 133.021578 -389.609076) (xy 133.03377 -389.630412) (xy 133.03631 -389.63473)
			)
		)
	)
	(zone
		(layers "F.Cu" "B.Cu" "In1.Cu" "In2.Cu" "In3.Cu" "In4.Cu" "In5.Cu" "In6.Cu"
			"In7.Cu" "In8.Cu" "In9.Cu" "In10.Cu" "In11.Cu" "In12.Cu" "In13.Cu" "In14.Cu"
			"In15.Cu" "In16.Cu"
		)
		(hatch none 0.5)
		(connect_pads
			(clearance 0)
		)
		(min_thickness 0.25)
		(keepout
			(tracks not_allowed)
			(vias allowed)
			(pads allowed)
			(copperpour not_allowed)
			(footprints allowed)
		)
		(placement
			(enabled no)
			(sheetname "")
		)
		(fill
			(thermal_gap 0.5)
			(thermal_bridge_width 0.5)
			(island_removal_mode 0)
		)
		(polygon
			(pts
				(arc
					(start 49.397412 -392.429238)
					(mid 49.016412 -392.048238)
					(end 48.635412 -392.429238)
				)
				(arc
					(start 48.635412 -393.292838)
					(mid 49.016412 -393.673838)
					(end 49.397412 -393.292838)
				)
			)
		)
	)
	(zone
		(layers "F.Cu" "B.Cu" "In1.Cu" "In2.Cu" "In3.Cu" "In4.Cu" "In5.Cu" "In6.Cu"
			"In7.Cu" "In8.Cu" "In9.Cu" "In10.Cu" "In11.Cu" "In12.Cu" "In13.Cu" "In14.Cu"
			"In15.Cu" "In16.Cu"
		)
		(hatch none 0.5)
		(connect_pads
			(clearance 0)
		)
		(min_thickness 0.25)
		(keepout
			(tracks not_allowed)
			(vias allowed)
			(pads allowed)
			(copperpour not_allowed)
			(footprints allowed)
		)
		(placement
			(enabled no)
			(sheetname "")
		)
		(fill
			(thermal_gap 0.5)
			(thermal_bridge_width 0.5)
			(island_removal_mode 0)
		)
		(polygon
			(pts
				(arc
					(start 145.526506 -404.08352)
					(mid 145.145506 -404.46452)
					(end 145.526506 -404.84552)
				)
				(arc
					(start 146.390106 -404.84552)
					(mid 146.771106 -404.46452)
					(end 146.390106 -404.08352)
				)
			)
		)
	)
	(zone
		(layers "F.Cu" "B.Cu" "In1.Cu" "In2.Cu" "In3.Cu" "In4.Cu" "In5.Cu" "In6.Cu"
			"In7.Cu" "In8.Cu" "In9.Cu" "In10.Cu" "In11.Cu" "In12.Cu" "In13.Cu" "In14.Cu"
			"In15.Cu" "In16.Cu"
		)
		(hatch none 0.5)
		(connect_pads
			(clearance 0)
		)
		(min_thickness 0.25)
		(keepout
			(tracks not_allowed)
			(vias allowed)
			(pads allowed)
			(copperpour not_allowed)
			(footprints allowed)
		)
		(placement
			(enabled no)
			(sheetname "")
		)
		(fill
			(thermal_gap 0.5)
			(thermal_bridge_width 0.5)
			(island_removal_mode 0)
		)
		(polygon
			(pts
				(arc
					(start 72.141842 -425.360592)
					(mid 72.16416 -425.414474)
					(end 72.218042 -425.436792)
				)
				(arc
					(start 73.157842 -425.436792)
					(mid 73.211724 -425.414474)
					(end 73.234042 -425.360592)
				)
				(arc
					(start 73.234042 -422.819068)
					(mid 73.211724 -422.765186)
					(end 73.157842 -422.742868)
				)
				(arc
					(start 72.218042 -422.742868)
					(mid 72.16416 -422.765186)
					(end 72.141842 -422.819068)
				)
			)
		)
	)
	(zone
		(layers "F.Cu" "B.Cu" "In1.Cu" "In2.Cu" "In3.Cu" "In4.Cu" "In5.Cu" "In6.Cu"
			"In7.Cu" "In8.Cu" "In9.Cu" "In10.Cu" "In11.Cu" "In12.Cu" "In13.Cu" "In14.Cu"
			"In15.Cu" "In16.Cu"
		)
		(hatch none 0.5)
		(connect_pads
			(clearance 0)
		)
		(min_thickness 0.25)
		(keepout
			(tracks not_allowed)
			(vias allowed)
			(pads allowed)
			(copperpour not_allowed)
			(footprints allowed)
		)
		(placement
			(enabled no)
			(sheetname "")
		)
		(fill
			(thermal_gap 0.5)
			(thermal_bridge_width 0.5)
			(island_removal_mode 0)
		)
		(polygon
			(pts
				(arc
					(start 178.630834 -49.48174)
					(mid 179.011834 -49.86274)
					(end 179.392834 -49.48174)
				)
				(arc
					(start 179.392834 -48.61814)
					(mid 179.011834 -48.23714)
					(end 178.630834 -48.61814)
				)
			)
		)
	)
	(zone
		(layers "F.Cu" "B.Cu" "In1.Cu" "In2.Cu" "In3.Cu" "In4.Cu" "In5.Cu" "In6.Cu"
			"In7.Cu" "In8.Cu" "In9.Cu" "In10.Cu" "In11.Cu" "In12.Cu" "In13.Cu" "In14.Cu"
			"In15.Cu" "In16.Cu"
		)
		(hatch none 0.5)
		(connect_pads
			(clearance 0)
		)
		(min_thickness 0.25)
		(keepout
			(tracks not_allowed)
			(vias allowed)
			(pads allowed)
			(copperpour not_allowed)
			(footprints allowed)
		)
		(placement
			(enabled no)
			(sheetname "")
		)
		(fill
			(thermal_gap 0.5)
			(thermal_bridge_width 0.5)
			(island_removal_mode 0)
		)
		(polygon
			(pts
				(arc
					(start 74.191622 -386.926074)
					(mid 73.810622 -386.545074)
					(end 73.429622 -386.926074)
				)
				(arc
					(start 73.429622 -387.789674)
					(mid 73.810622 -388.170674)
					(end 74.191622 -387.789674)
				)
			)
		)
	)
	(zone
		(layers "F.Cu" "B.Cu" "In1.Cu" "In2.Cu" "In3.Cu" "In4.Cu" "In5.Cu" "In6.Cu"
			"In7.Cu" "In8.Cu" "In9.Cu" "In10.Cu" "In11.Cu" "In12.Cu" "In13.Cu" "In14.Cu"
			"In15.Cu" "In16.Cu"
		)
		(hatch none 0.5)
		(connect_pads
			(clearance 0)
		)
		(min_thickness 0.25)
		(keepout
			(tracks not_allowed)
			(vias allowed)
			(pads allowed)
			(copperpour not_allowed)
			(footprints allowed)
		)
		(placement
			(enabled no)
			(sheetname "")
		)
		(fill
			(thermal_gap 0.5)
			(thermal_bridge_width 0.5)
			(island_removal_mode 0)
		)
		(polygon
			(pts
				(arc
					(start 193.447162 -11.449812)
					(mid 191.516762 -11.449812)
					(end 193.447162 -11.449812)
				)
			)
		)
	)
	(zone
		(layers "F.Cu" "B.Cu" "In1.Cu" "In2.Cu" "In3.Cu" "In4.Cu" "In5.Cu" "In6.Cu"
			"In7.Cu" "In8.Cu" "In9.Cu" "In10.Cu" "In11.Cu" "In12.Cu" "In13.Cu" "In14.Cu"
			"In15.Cu" "In16.Cu"
		)
		(hatch none 0.5)
		(connect_pads
			(clearance 0)
		)
		(min_thickness 0.25)
		(keepout
			(tracks not_allowed)
			(vias allowed)
			(pads allowed)
			(copperpour not_allowed)
			(footprints allowed)
		)
		(placement
			(enabled no)
			(sheetname "")
		)
		(fill yes
			(thermal_gap 0.5)
			(thermal_bridge_width 0.5)
			(island_removal_mode 0)
		)
		(polygon
			(pts
				(arc
					(start 346.064078 -394.552424)
					(mid 346.174049 -394.653478)
					(end 346.31884 -394.690092)
				)
				(arc
					(start 346.31884 -394.690092)
					(mid 346.534366 -394.600818)
					(end 346.62364 -394.385292)
				)
				(arc
					(start 346.62364 -394.385292)
					(mid 346.613303 -394.306553)
					(end 346.583 -394.233146)
				)
				(arc
					(start 346.19057 -393.554204)
					(mid 346.078173 -393.432587)
					(end 345.91879 -393.38758)
				)
				(arc
					(start 345.91879 -393.38758)
					(mid 345.703264 -393.476854)
					(end 345.61399 -393.69238)
				)
				(arc
					(start 345.61399 -393.69238)
					(mid 345.623568 -393.768442)
					(end 345.651836 -393.8397)
				)
				(xy 346.049092 -394.527024) (xy 346.061284 -394.54836) (xy 346.063824 -394.552678)
			)
		)
	)
	(zone
		(layers "F.Cu" "B.Cu" "In1.Cu" "In2.Cu" "In3.Cu" "In4.Cu" "In5.Cu" "In6.Cu"
			"In7.Cu" "In8.Cu" "In9.Cu" "In10.Cu" "In11.Cu" "In12.Cu" "In13.Cu" "In14.Cu"
			"In15.Cu" "In16.Cu"
		)
		(hatch none 0.5)
		(connect_pads
			(clearance 0)
		)
		(min_thickness 0.25)
		(keepout
			(tracks not_allowed)
			(vias allowed)
			(pads allowed)
			(copperpour not_allowed)
			(footprints allowed)
		)
		(placement
			(enabled no)
			(sheetname "")
		)
		(fill
			(thermal_gap 0.5)
			(thermal_bridge_width 0.5)
			(island_removal_mode 0)
		)
		(polygon
			(pts
				(arc
					(start 383.297684 -400.811238)
					(mid 382.916684 -400.430238)
					(end 382.535684 -400.811238)
				)
				(arc
					(start 382.535684 -401.674838)
					(mid 382.916684 -402.055838)
					(end 383.297684 -401.674838)
				)
			)
		)
	)
	(zone
		(layers "F.Cu" "B.Cu" "In1.Cu" "In2.Cu" "In3.Cu" "In4.Cu" "In5.Cu" "In6.Cu"
			"In7.Cu" "In8.Cu" "In9.Cu" "In10.Cu" "In11.Cu" "In12.Cu" "In13.Cu" "In14.Cu"
			"In15.Cu" "In16.Cu"
		)
		(hatch none 0.5)
		(connect_pads
			(clearance 0)
		)
		(min_thickness 0.25)
		(keepout
			(tracks not_allowed)
			(vias allowed)
			(pads allowed)
			(copperpour not_allowed)
			(footprints allowed)
		)
		(placement
			(enabled no)
			(sheetname "")
		)
		(fill
			(thermal_gap 0.5)
			(thermal_bridge_width 0.5)
			(island_removal_mode 0)
		)
		(polygon
			(pts
				(arc
					(start 39.98214 -426.290994)
					(mid 40.36314 -425.909994)
					(end 39.98214 -425.528994)
				)
				(arc
					(start 39.11854 -425.528994)
					(mid 38.73754 -425.909994)
					(end 39.11854 -426.290994)
				)
			)
		)
	)
	(zone
		(layers "F.Cu" "B.Cu" "In1.Cu" "In2.Cu" "In3.Cu" "In4.Cu" "In5.Cu" "In6.Cu"
			"In7.Cu" "In8.Cu" "In9.Cu" "In10.Cu" "In11.Cu" "In12.Cu" "In13.Cu" "In14.Cu"
			"In15.Cu" "In16.Cu"
		)
		(hatch none 0.5)
		(connect_pads
			(clearance 0)
		)
		(min_thickness 0.25)
		(keepout
			(tracks not_allowed)
			(vias allowed)
			(pads allowed)
			(copperpour not_allowed)
			(footprints allowed)
		)
		(placement
			(enabled no)
			(sheetname "")
		)
		(fill
			(thermal_gap 0.5)
			(thermal_bridge_width 0.5)
			(island_removal_mode 0)
		)
		(polygon
			(pts
				(arc
					(start 319.436496 -379.50013)
					(mid 319.055496 -379.88113)
					(end 319.436496 -380.26213)
				)
				(arc
					(start 320.300096 -380.26213)
					(mid 320.681096 -379.88113)
					(end 320.300096 -379.50013)
				)
			)
		)
	)
	(zone
		(layers "F.Cu" "B.Cu" "In1.Cu" "In2.Cu" "In3.Cu" "In4.Cu" "In5.Cu" "In6.Cu"
			"In7.Cu" "In8.Cu" "In9.Cu" "In10.Cu" "In11.Cu" "In12.Cu" "In13.Cu" "In14.Cu"
			"In15.Cu" "In16.Cu"
		)
		(hatch none 0.5)
		(connect_pads
			(clearance 0)
		)
		(min_thickness 0.25)
		(keepout
			(tracks not_allowed)
			(vias allowed)
			(pads allowed)
			(copperpour not_allowed)
			(footprints allowed)
		)
		(placement
			(enabled no)
			(sheetname "")
		)
		(fill
			(thermal_gap 0.5)
			(thermal_bridge_width 0.5)
			(island_removal_mode 0)
		)
		(polygon
			(pts
				(arc
					(start 415.48558 -18.75536)
					(mid 415.10458 -19.13636)
					(end 415.48558 -19.51736)
				)
				(arc
					(start 416.34918 -19.51736)
					(mid 416.73018 -19.13636)
					(end 416.34918 -18.75536)
				)
			)
		)
	)
	(zone
		(layers "F.Cu" "B.Cu" "In1.Cu" "In2.Cu" "In3.Cu" "In4.Cu" "In5.Cu" "In6.Cu"
			"In7.Cu" "In8.Cu" "In9.Cu" "In10.Cu" "In11.Cu" "In12.Cu" "In13.Cu" "In14.Cu"
			"In15.Cu" "In16.Cu"
		)
		(hatch none 0.5)
		(connect_pads
			(clearance 0)
		)
		(min_thickness 0.25)
		(keepout
			(tracks not_allowed)
			(vias allowed)
			(pads allowed)
			(copperpour not_allowed)
			(footprints allowed)
		)
		(placement
			(enabled no)
			(sheetname "")
		)
		(fill yes
			(thermal_gap 0.5)
			(thermal_bridge_width 0.5)
			(island_removal_mode 0)
		)
		(polygon
			(pts
				(arc
					(start 55.136542 -386.170424)
					(mid 55.246513 -386.271478)
					(end 55.391304 -386.308092)
				)
				(arc
					(start 55.391304 -386.308092)
					(mid 55.60683 -386.218818)
					(end 55.696104 -386.003292)
				)
				(arc
					(start 55.696104 -386.003292)
					(mid 55.685767 -385.924553)
					(end 55.655464 -385.851146)
				)
				(arc
					(start 55.263034 -385.172204)
					(mid 55.150637 -385.050587)
					(end 54.991254 -385.00558)
				)
				(arc
					(start 54.991254 -385.00558)
					(mid 54.775728 -385.094854)
					(end 54.686454 -385.31038)
				)
				(arc
					(start 54.686454 -385.31038)
					(mid 54.696032 -385.386442)
					(end 54.7243 -385.4577)
				)
				(xy 55.121556 -386.145024) (xy 55.133748 -386.16636) (xy 55.136288 -386.170678)
			)
		)
	)
	(zone
		(layers "F.Cu" "B.Cu" "In1.Cu" "In2.Cu" "In3.Cu" "In4.Cu" "In5.Cu" "In6.Cu"
			"In7.Cu" "In8.Cu" "In9.Cu" "In10.Cu" "In11.Cu" "In12.Cu" "In13.Cu" "In14.Cu"
			"In15.Cu" "In16.Cu"
		)
		(hatch none 0.5)
		(connect_pads
			(clearance 0)
		)
		(min_thickness 0.25)
		(keepout
			(tracks not_allowed)
			(vias allowed)
			(pads allowed)
			(copperpour not_allowed)
			(footprints allowed)
		)
		(placement
			(enabled no)
			(sheetname "")
		)
		(fill
			(thermal_gap 0.5)
			(thermal_bridge_width 0.5)
			(island_removal_mode 0)
		)
		(polygon
			(pts
				(arc
					(start 21.421344 -421.269922)
					(mid 21.802344 -421.650922)
					(end 22.183344 -421.269922)
				)
				(arc
					(start 22.183344 -420.406322)
					(mid 21.802344 -420.025322)
					(end 21.421344 -420.406322)
				)
			)
		)
	)
	(zone
		(layers "F.Cu" "B.Cu" "In1.Cu" "In2.Cu" "In3.Cu" "In4.Cu" "In5.Cu" "In6.Cu"
			"In7.Cu" "In8.Cu" "In9.Cu" "In10.Cu" "In11.Cu" "In12.Cu" "In13.Cu" "In14.Cu"
			"In15.Cu" "In16.Cu"
		)
		(hatch none 0.5)
		(connect_pads
			(clearance 0)
		)
		(min_thickness 0.25)
		(keepout
			(tracks not_allowed)
			(vias allowed)
			(pads allowed)
			(copperpour not_allowed)
			(footprints allowed)
		)
		(placement
			(enabled no)
			(sheetname "")
		)
		(fill
			(thermal_gap 0.5)
			(thermal_bridge_width 0.5)
			(island_removal_mode 0)
		)
		(polygon
			(pts
				(arc
					(start 115.297458 -392.429238)
					(mid 114.916458 -392.048238)
					(end 114.535458 -392.429238)
				)
				(arc
					(start 114.535458 -393.292838)
					(mid 114.916458 -393.673838)
					(end 115.297458 -393.292838)
				)
			)
		)
	)
	(zone
		(layers "F.Cu" "B.Cu" "In1.Cu" "In2.Cu" "In3.Cu" "In4.Cu" "In5.Cu" "In6.Cu"
			"In7.Cu" "In8.Cu" "In9.Cu" "In10.Cu" "In11.Cu" "In12.Cu" "In13.Cu" "In14.Cu"
			"In15.Cu" "In16.Cu"
		)
		(hatch none 0.5)
		(connect_pads
			(clearance 0)
		)
		(min_thickness 0.25)
		(keepout
			(tracks not_allowed)
			(vias allowed)
			(pads allowed)
			(copperpour not_allowed)
			(footprints allowed)
		)
		(placement
			(enabled no)
			(sheetname "")
		)
		(fill
			(thermal_gap 0.5)
			(thermal_bridge_width 0.5)
			(island_removal_mode 0)
		)
		(polygon
			(pts
				(arc
					(start 313.53633 -398.016476)
					(mid 313.646301 -398.11753)
					(end 313.791092 -398.154144)
				)
				(arc
					(start 313.791092 -398.154144)
					(mid 314.006618 -398.06487)
					(end 314.095892 -397.849344)
				)
				(arc
					(start 314.095892 -397.849344)
					(mid 314.085555 -397.770605)
					(end 314.055252 -397.697198)
				)
				(arc
					(start 313.662822 -397.018256)
					(mid 313.550425 -396.896639)
					(end 313.391042 -396.851632)
				)
				(arc
					(start 313.391042 -396.851632)
					(mid 313.175516 -396.940906)
					(end 313.086242 -397.156432)
				)
				(arc
					(start 313.086242 -397.156432)
					(mid 313.09582 -397.232494)
					(end 313.124088 -397.303752)
				)
				(xy 313.521344 -397.991076) (xy 313.533536 -398.012412) (xy 313.536076 -398.01673)
			)
		)
	)
	(zone
		(layers "F.Cu" "B.Cu" "In1.Cu" "In2.Cu" "In3.Cu" "In4.Cu" "In5.Cu" "In6.Cu"
			"In7.Cu" "In8.Cu" "In9.Cu" "In10.Cu" "In11.Cu" "In12.Cu" "In13.Cu" "In14.Cu"
			"In15.Cu" "In16.Cu"
		)
		(hatch none 0.5)
		(connect_pads
			(clearance 0)
		)
		(min_thickness 0.25)
		(keepout
			(tracks not_allowed)
			(vias allowed)
			(pads allowed)
			(copperpour not_allowed)
			(footprints allowed)
		)
		(placement
			(enabled no)
			(sheetname "")
		)
		(fill
			(thermal_gap 0.5)
			(thermal_bridge_width 0.5)
			(island_removal_mode 0)
		)
		(polygon
			(pts
				(arc
					(start 376.097546 -400.811238)
					(mid 375.716546 -400.430238)
					(end 375.335546 -400.811238)
				)
				(arc
					(start 375.335546 -401.674838)
					(mid 375.716546 -402.055838)
					(end 376.097546 -401.674838)
				)
			)
		)
	)
	(zone
		(layers "F.Cu" "B.Cu" "In1.Cu" "In2.Cu" "In3.Cu" "In4.Cu" "In5.Cu" "In6.Cu"
			"In7.Cu" "In8.Cu" "In9.Cu" "In10.Cu" "In11.Cu" "In12.Cu" "In13.Cu" "In14.Cu"
			"In15.Cu" "In16.Cu"
		)
		(hatch none 0.5)
		(connect_pads
			(clearance 0)
		)
		(min_thickness 0.25)
		(keepout
			(tracks not_allowed)
			(vias allowed)
			(pads allowed)
			(copperpour not_allowed)
			(footprints allowed)
		)
		(placement
			(enabled no)
			(sheetname "")
		)
		(fill yes
			(thermal_gap 0.5)
			(thermal_bridge_width 0.5)
			(island_removal_mode 0)
		)
		(polygon
			(pts
				(arc
					(start 414.36417 -394.552424)
					(mid 414.474141 -394.653478)
					(end 414.618932 -394.690092)
				)
				(arc
					(start 414.618932 -394.690092)
					(mid 414.834458 -394.600818)
					(end 414.923732 -394.385292)
				)
				(arc
					(start 414.923732 -394.385292)
					(mid 414.913395 -394.306553)
					(end 414.883092 -394.233146)
				)
				(arc
					(start 414.490662 -393.554204)
					(mid 414.378265 -393.432587)
					(end 414.218882 -393.38758)
				)
				(arc
					(start 414.218882 -393.38758)
					(mid 414.003356 -393.476854)
					(end 413.914082 -393.69238)
				)
				(arc
					(start 413.914082 -393.69238)
					(mid 413.92366 -393.768442)
					(end 413.951928 -393.8397)
				)
				(xy 414.349184 -394.527024) (xy 414.361376 -394.54836) (xy 414.363916 -394.552678)
			)
		)
	)
	(zone
		(layers "F.Cu" "B.Cu" "In1.Cu" "In2.Cu" "In3.Cu" "In4.Cu" "In5.Cu" "In6.Cu"
			"In7.Cu" "In8.Cu" "In9.Cu" "In10.Cu" "In11.Cu" "In12.Cu" "In13.Cu" "In14.Cu"
			"In15.Cu" "In16.Cu"
		)
		(hatch none 0.5)
		(connect_pads
			(clearance 0)
		)
		(min_thickness 0.25)
		(keepout
			(tracks not_allowed)
			(vias allowed)
			(pads allowed)
			(copperpour not_allowed)
			(footprints allowed)
		)
		(placement
			(enabled no)
			(sheetname "")
		)
		(fill
			(thermal_gap 0.5)
			(thermal_bridge_width 0.5)
			(island_removal_mode 0)
		)
		(polygon
			(pts
				(arc
					(start 386.210302 -420.571168)
					(mid 385.829302 -420.952168)
					(end 386.210302 -421.333168)
				)
				(arc
					(start 387.073902 -421.333168)
					(mid 387.454902 -420.952168)
					(end 387.073902 -420.571168)
				)
			)
		)
	)
	(zone
		(layers "F.Cu" "B.Cu" "In1.Cu" "In2.Cu" "In3.Cu" "In4.Cu" "In5.Cu" "In6.Cu"
			"In7.Cu" "In8.Cu" "In9.Cu" "In10.Cu" "In11.Cu" "In12.Cu" "In13.Cu" "In14.Cu"
			"In15.Cu" "In16.Cu"
		)
		(hatch none 0.5)
		(connect_pads
			(clearance 0)
		)
		(min_thickness 0.25)
		(keepout
			(tracks not_allowed)
			(vias allowed)
			(pads allowed)
			(copperpour not_allowed)
			(footprints allowed)
		)
		(placement
			(enabled no)
			(sheetname "")
		)
		(fill
			(thermal_gap 0.5)
			(thermal_bridge_width 0.5)
			(island_removal_mode 0)
		)
		(polygon
			(pts
				(arc
					(start 113.033556 -23.668736)
					(mid 112.652556 -24.049736)
					(end 113.033556 -24.430736)
				)
				(arc
					(start 113.897156 -24.430736)
					(mid 114.278156 -24.049736)
					(end 113.897156 -23.668736)
				)
			)
		)
	)
	(zone
		(layers "F.Cu" "B.Cu" "In1.Cu" "In2.Cu" "In3.Cu" "In4.Cu" "In5.Cu" "In6.Cu"
			"In7.Cu" "In8.Cu" "In9.Cu" "In10.Cu" "In11.Cu" "In12.Cu" "In13.Cu" "In14.Cu"
			"In15.Cu" "In16.Cu"
		)
		(hatch none 0.5)
		(connect_pads
			(clearance 0)
		)
		(min_thickness 0.25)
		(keepout
			(tracks not_allowed)
			(vias allowed)
			(pads allowed)
			(copperpour not_allowed)
			(footprints allowed)
		)
		(placement
			(enabled no)
			(sheetname "")
		)
		(fill
			(thermal_gap 0.5)
			(thermal_bridge_width 0.5)
			(island_removal_mode 0)
		)
		(polygon
			(pts
				(arc
					(start 317.578486 -418.031168)
					(mid 317.197486 -418.412168)
					(end 317.578486 -418.793168)
				)
				(arc
					(start 318.442086 -418.793168)
					(mid 318.823086 -418.412168)
					(end 318.442086 -418.031168)
				)
			)
		)
	)
	(zone
		(layers "F.Cu" "B.Cu" "In1.Cu" "In2.Cu" "In3.Cu" "In4.Cu" "In5.Cu" "In6.Cu"
			"In7.Cu" "In8.Cu" "In9.Cu" "In10.Cu" "In11.Cu" "In12.Cu" "In13.Cu" "In14.Cu"
			"In15.Cu" "In16.Cu"
		)
		(hatch none 0.5)
		(connect_pads
			(clearance 0)
		)
		(min_thickness 0.25)
		(keepout
			(tracks not_allowed)
			(vias allowed)
			(pads allowed)
			(copperpour not_allowed)
			(footprints allowed)
		)
		(placement
			(enabled no)
			(sheetname "")
		)
		(fill
			(thermal_gap 0.5)
			(thermal_bridge_width 0.5)
			(island_removal_mode 0)
		)
		(polygon
			(pts
				(arc
					(start 156.247846 -409.649168)
					(mid 155.866846 -410.030168)
					(end 156.247846 -410.411168)
				)
				(arc
					(start 157.111446 -410.411168)
					(mid 157.492446 -410.030168)
					(end 157.111446 -409.649168)
				)
			)
		)
	)
	(zone
		(layers "F.Cu" "B.Cu" "In1.Cu" "In2.Cu" "In3.Cu" "In4.Cu" "In5.Cu" "In6.Cu"
			"In7.Cu" "In8.Cu" "In9.Cu" "In10.Cu" "In11.Cu" "In12.Cu" "In13.Cu" "In14.Cu"
			"In15.Cu" "In16.Cu"
		)
		(hatch none 0.5)
		(connect_pads
			(clearance 0)
		)
		(min_thickness 0.25)
		(keepout
			(tracks not_allowed)
			(vias allowed)
			(pads allowed)
			(copperpour not_allowed)
			(footprints allowed)
		)
		(placement
			(enabled no)
			(sheetname "")
		)
		(fill
			(thermal_gap 0.5)
			(thermal_bridge_width 0.5)
			(island_removal_mode 0)
		)
		(polygon
			(pts
				(arc
					(start 92.211144 -409.649168)
					(mid 91.830144 -410.030168)
					(end 92.211144 -410.411168)
				)
				(arc
					(start 93.074744 -410.411168)
					(mid 93.455744 -410.030168)
					(end 93.074744 -409.649168)
				)
			)
		)
	)
	(zone
		(layers "F.Cu" "B.Cu" "In1.Cu" "In2.Cu" "In3.Cu" "In4.Cu" "In5.Cu" "In6.Cu"
			"In7.Cu" "In8.Cu" "In9.Cu" "In10.Cu" "In11.Cu" "In12.Cu" "In13.Cu" "In14.Cu"
			"In15.Cu" "In16.Cu"
		)
		(hatch none 0.5)
		(connect_pads
			(clearance 0)
		)
		(min_thickness 0.25)
		(keepout
			(tracks not_allowed)
			(vias allowed)
			(pads allowed)
			(copperpour not_allowed)
			(footprints allowed)
		)
		(placement
			(enabled no)
			(sheetname "")
		)
		(fill
			(thermal_gap 0.5)
			(thermal_bridge_width 0.5)
			(island_removal_mode 0)
		)
		(polygon
			(pts
				(arc
					(start 83.021424 -406.62352)
					(mid 82.640424 -407.00452)
					(end 83.021424 -407.38552)
				)
				(arc
					(start 83.885024 -407.38552)
					(mid 84.266024 -407.00452)
					(end 83.885024 -406.62352)
				)
			)
		)
	)
	(zone
		(layers "F.Cu" "B.Cu" "In1.Cu" "In2.Cu" "In3.Cu" "In4.Cu" "In5.Cu" "In6.Cu"
			"In7.Cu" "In8.Cu" "In9.Cu" "In10.Cu" "In11.Cu" "In12.Cu" "In13.Cu" "In14.Cu"
			"In15.Cu" "In16.Cu"
		)
		(hatch none 0.5)
		(connect_pads
			(clearance 0)
		)
		(min_thickness 0.25)
		(keepout
			(tracks not_allowed)
			(vias allowed)
			(pads allowed)
			(copperpour not_allowed)
			(footprints allowed)
		)
		(placement
			(enabled no)
			(sheetname "")
		)
		(fill
			(thermal_gap 0.5)
			(thermal_bridge_width 0.5)
			(island_removal_mode 0)
		)
		(polygon
			(pts
				(arc
					(start 20.179792 -133.480302)
					(mid 20.560792 -133.861302)
					(end 20.941792 -133.480302)
				)
				(arc
					(start 20.941792 -132.489702)
					(mid 20.560792 -132.108702)
					(end 20.179792 -132.489702)
				)
			)
		)
	)
	(zone
		(layers "F.Cu" "B.Cu" "In1.Cu" "In2.Cu" "In3.Cu" "In4.Cu" "In5.Cu" "In6.Cu"
			"In7.Cu" "In8.Cu" "In9.Cu" "In10.Cu" "In11.Cu" "In12.Cu" "In13.Cu" "In14.Cu"
			"In15.Cu" "In16.Cu"
		)
		(hatch none 0.5)
		(connect_pads
			(clearance 0)
		)
		(min_thickness 0.25)
		(keepout
			(tracks not_allowed)
			(vias allowed)
			(pads allowed)
			(copperpour not_allowed)
			(footprints allowed)
		)
		(placement
			(enabled no)
			(sheetname "")
		)
		(fill
			(thermal_gap 0.5)
			(thermal_bridge_width 0.5)
			(island_removal_mode 0)
		)
		(polygon
			(pts
				(arc
					(start 353.263962 -398.016476)
					(mid 353.373933 -398.11753)
					(end 353.518724 -398.154144)
				)
				(arc
					(start 353.518724 -398.154144)
					(mid 353.73425 -398.06487)
					(end 353.823524 -397.849344)
				)
				(arc
					(start 353.823524 -397.849344)
					(mid 353.813187 -397.770605)
					(end 353.782884 -397.697198)
				)
				(arc
					(start 353.390454 -397.018256)
					(mid 353.278057 -396.896639)
					(end 353.118674 -396.851632)
				)
				(arc
					(start 353.118674 -396.851632)
					(mid 352.903148 -396.940906)
					(end 352.813874 -397.156432)
				)
				(arc
					(start 352.813874 -397.156432)
					(mid 352.823452 -397.232494)
					(end 352.85172 -397.303752)
				)
				(xy 353.248976 -397.991076) (xy 353.261168 -398.012412) (xy 353.263708 -398.01673)
			)
		)
	)
	(zone
		(layers "F.Cu" "B.Cu" "In1.Cu" "In2.Cu" "In3.Cu" "In4.Cu" "In5.Cu" "In6.Cu"
			"In7.Cu" "In8.Cu" "In9.Cu" "In10.Cu" "In11.Cu" "In12.Cu" "In13.Cu" "In14.Cu"
			"In15.Cu" "In16.Cu"
		)
		(hatch none 0.5)
		(connect_pads
			(clearance 0)
		)
		(min_thickness 0.25)
		(keepout
			(tracks not_allowed)
			(vias allowed)
			(pads allowed)
			(copperpour not_allowed)
			(footprints allowed)
		)
		(placement
			(enabled no)
			(sheetname "")
		)
		(fill
			(thermal_gap 0.5)
			(thermal_bridge_width 0.5)
			(island_removal_mode 0)
		)
		(polygon
			(pts
				(arc
					(start 35.466782 -153.765504)
					(mid 24.443182 -153.765504)
					(end 35.466782 -153.765504)
				)
			)
		)
	)
	(zone
		(layers "F.Cu" "B.Cu" "In1.Cu" "In2.Cu" "In3.Cu" "In4.Cu" "In5.Cu" "In6.Cu"
			"In7.Cu" "In8.Cu" "In9.Cu" "In10.Cu" "In11.Cu" "In12.Cu" "In13.Cu" "In14.Cu"
			"In15.Cu" "In16.Cu"
		)
		(hatch none 0.5)
		(connect_pads
			(clearance 0)
		)
		(min_thickness 0.25)
		(keepout
			(tracks not_allowed)
			(vias allowed)
			(pads allowed)
			(copperpour not_allowed)
			(footprints allowed)
		)
		(placement
			(enabled no)
			(sheetname "")
		)
		(fill yes
			(thermal_gap 0.5)
			(thermal_bridge_width 0.5)
			(island_removal_mode 0)
		)
		(polygon
			(pts
				(arc
					(start 337.664044 -394.552424)
					(mid 337.774015 -394.653478)
					(end 337.918806 -394.690092)
				)
				(arc
					(start 337.918806 -394.690092)
					(mid 338.134332 -394.600818)
					(end 338.223606 -394.385292)
				)
				(arc
					(start 338.223606 -394.385292)
					(mid 338.213269 -394.306553)
					(end 338.182966 -394.233146)
				)
				(arc
					(start 337.790536 -393.554204)
					(mid 337.678139 -393.432587)
					(end 337.518756 -393.38758)
				)
				(arc
					(start 337.518756 -393.38758)
					(mid 337.30323 -393.476854)
					(end 337.213956 -393.69238)
				)
				(arc
					(start 337.213956 -393.69238)
					(mid 337.223534 -393.768442)
					(end 337.251802 -393.8397)
				)
				(xy 337.649058 -394.527024) (xy 337.66125 -394.54836) (xy 337.66379 -394.552678)
			)
		)
	)
	(zone
		(layers "F.Cu" "B.Cu" "In1.Cu" "In2.Cu" "In3.Cu" "In4.Cu" "In5.Cu" "In6.Cu"
			"In7.Cu" "In8.Cu" "In9.Cu" "In10.Cu" "In11.Cu" "In12.Cu" "In13.Cu" "In14.Cu"
			"In15.Cu" "In16.Cu"
		)
		(hatch none 0.5)
		(connect_pads
			(clearance 0)
		)
		(min_thickness 0.25)
		(keepout
			(tracks not_allowed)
			(vias allowed)
			(pads allowed)
			(copperpour not_allowed)
			(footprints allowed)
		)
		(placement
			(enabled no)
			(sheetname "")
		)
		(fill
			(thermal_gap 0.5)
			(thermal_bridge_width 0.5)
			(island_removal_mode 0)
		)
		(polygon
			(pts
				(arc
					(start 56.336438 -389.634476)
					(mid 56.446409 -389.73553)
					(end 56.5912 -389.772144)
				)
				(arc
					(start 56.5912 -389.772144)
					(mid 56.806726 -389.68287)
					(end 56.896 -389.467344)
				)
				(arc
					(start 56.896 -389.467344)
					(mid 56.885663 -389.388605)
					(end 56.85536 -389.315198)
				)
				(arc
					(start 56.46293 -388.636256)
					(mid 56.350533 -388.514639)
					(end 56.19115 -388.469632)
				)
				(arc
					(start 56.19115 -388.469632)
					(mid 55.975624 -388.558906)
					(end 55.88635 -388.774432)
				)
				(arc
					(start 55.88635 -388.774432)
					(mid 55.895928 -388.850494)
					(end 55.924196 -388.921752)
				)
				(xy 56.321452 -389.609076) (xy 56.333644 -389.630412) (xy 56.336184 -389.63473)
			)
		)
	)
	(zone
		(layers "F.Cu" "B.Cu" "In1.Cu" "In2.Cu" "In3.Cu" "In4.Cu" "In5.Cu" "In6.Cu"
			"In7.Cu" "In8.Cu" "In9.Cu" "In10.Cu" "In11.Cu" "In12.Cu" "In13.Cu" "In14.Cu"
			"In15.Cu" "In16.Cu"
		)
		(hatch none 0.5)
		(connect_pads
			(clearance 0)
		)
		(min_thickness 0.25)
		(keepout
			(tracks not_allowed)
			(vias allowed)
			(pads allowed)
			(copperpour not_allowed)
			(footprints allowed)
		)
		(placement
			(enabled no)
			(sheetname "")
		)
		(fill
			(thermal_gap 0.5)
			(thermal_bridge_width 0.5)
			(island_removal_mode 0)
		)
		(polygon
			(pts
				(arc
					(start 317.734696 -381.96393)
					(mid 317.353696 -382.34493)
					(end 317.734696 -382.72593)
				)
				(arc
					(start 318.598296 -382.72593)
					(mid 318.979296 -382.34493)
					(end 318.598296 -381.96393)
				)
			)
		)
	)
	(zone
		(layers "F.Cu" "B.Cu" "In1.Cu" "In2.Cu" "In3.Cu" "In4.Cu" "In5.Cu" "In6.Cu"
			"In7.Cu" "In8.Cu" "In9.Cu" "In10.Cu" "In11.Cu" "In12.Cu" "In13.Cu" "In14.Cu"
			"In15.Cu" "In16.Cu"
		)
		(hatch none 0.5)
		(connect_pads
			(clearance 0)
		)
		(min_thickness 0.25)
		(keepout
			(tracks not_allowed)
			(vias allowed)
			(pads allowed)
			(copperpour not_allowed)
			(footprints allowed)
		)
		(placement
			(enabled no)
			(sheetname "")
		)
		(fill
			(thermal_gap 0.5)
			(thermal_bridge_width 0.5)
			(island_removal_mode 0)
		)
		(polygon
			(pts
				(arc
					(start 51.524154 -368.65433)
					(mid 51.143154 -369.03533)
					(end 51.524154 -369.41633)
				)
				(arc
					(start 52.387754 -369.41633)
					(mid 52.768754 -369.03533)
					(end 52.387754 -368.65433)
				)
			)
		)
	)
	(zone
		(layers "F.Cu" "B.Cu" "In1.Cu" "In2.Cu" "In3.Cu" "In4.Cu" "In5.Cu" "In6.Cu"
			"In7.Cu" "In8.Cu" "In9.Cu" "In10.Cu" "In11.Cu" "In12.Cu" "In13.Cu" "In14.Cu"
			"In15.Cu" "In16.Cu"
		)
		(hatch none 0.5)
		(connect_pads
			(clearance 0)
		)
		(min_thickness 0.25)
		(keepout
			(tracks not_allowed)
			(vias allowed)
			(pads allowed)
			(copperpour not_allowed)
			(footprints allowed)
		)
		(placement
			(enabled no)
			(sheetname "")
		)
		(fill
			(thermal_gap 0.5)
			(thermal_bridge_width 0.5)
			(island_removal_mode 0)
		)
		(polygon
			(pts
				(arc
					(start 135.615172 -11.574018)
					(mid 135.234172 -11.955018)
					(end 135.615172 -12.336018)
				)
				(arc
					(start 136.478772 -12.336018)
					(mid 136.859772 -11.955018)
					(end 136.478772 -11.574018)
				)
			)
		)
	)
	(zone
		(layers "F.Cu" "B.Cu" "In1.Cu" "In2.Cu" "In3.Cu" "In4.Cu" "In5.Cu" "In6.Cu"
			"In7.Cu" "In8.Cu" "In9.Cu" "In10.Cu" "In11.Cu" "In12.Cu" "In13.Cu" "In14.Cu"
			"In15.Cu" "In16.Cu"
		)
		(hatch none 0.5)
		(connect_pads
			(clearance 0)
		)
		(min_thickness 0.25)
		(keepout
			(tracks not_allowed)
			(vias allowed)
			(pads allowed)
			(copperpour not_allowed)
			(footprints allowed)
		)
		(placement
			(enabled no)
			(sheetname "")
		)
		(fill
			(thermal_gap 0.5)
			(thermal_bridge_width 0.5)
			(island_removal_mode 0)
		)
		(polygon
			(pts
				(arc
					(start 348.53499 -310.650128)
					(mid 348.15399 -310.269128)
					(end 347.77299 -310.650128)
				)
				(arc
					(start 347.77299 -311.513728)
					(mid 348.15399 -311.894728)
					(end 348.53499 -311.513728)
				)
			)
		)
	)
	(zone
		(layers "F.Cu" "B.Cu" "In1.Cu" "In2.Cu" "In3.Cu" "In4.Cu" "In5.Cu" "In6.Cu"
			"In7.Cu" "In8.Cu" "In9.Cu" "In10.Cu" "In11.Cu" "In12.Cu" "In13.Cu" "In14.Cu"
			"In15.Cu" "In16.Cu"
		)
		(hatch none 0.5)
		(connect_pads
			(clearance 0)
		)
		(min_thickness 0.25)
		(keepout
			(tracks not_allowed)
			(vias allowed)
			(pads allowed)
			(copperpour not_allowed)
			(footprints allowed)
		)
		(placement
			(enabled no)
			(sheetname "")
		)
		(fill yes
			(thermal_gap 0.5)
			(thermal_bridge_width 0.5)
			(island_removal_mode 0)
		)
		(polygon
			(pts
				(arc
					(start 39.070026 -376.489976)
					(mid 35.070034 -380.489968)
					(end 31.070042 -376.489976)
				)
				(arc
					(start 31.070042 -376.489976)
					(mid 35.070034 -372.489984)
					(end 39.070026 -376.489976)
				)
			)
		)
	)
	(zone
		(layers "F.Cu" "B.Cu" "In1.Cu" "In2.Cu" "In3.Cu" "In4.Cu" "In5.Cu" "In6.Cu"
			"In7.Cu" "In8.Cu" "In9.Cu" "In10.Cu" "In11.Cu" "In12.Cu" "In13.Cu" "In14.Cu"
			"In15.Cu" "In16.Cu"
		)
		(hatch none 0.5)
		(connect_pads
			(clearance 0)
		)
		(min_thickness 0.25)
		(keepout
			(tracks not_allowed)
			(vias allowed)
			(pads allowed)
			(copperpour not_allowed)
			(footprints allowed)
		)
		(placement
			(enabled no)
			(sheetname "")
		)
		(fill
			(thermal_gap 0.5)
			(thermal_bridge_width 0.5)
			(island_removal_mode 0)
		)
		(polygon
			(pts
				(arc
					(start 183.95442 5.632196)
					(mid 184.38622 5.200396)
					(end 184.81802 5.632196)
				)
				(arc
					(start 184.81802 6.495796)
					(mid 184.38622 6.927596)
					(end 183.95442 6.495796)
				)
			)
		)
	)
	(zone
		(layers "F.Cu" "B.Cu" "In1.Cu" "In2.Cu" "In3.Cu" "In4.Cu" "In5.Cu" "In6.Cu"
			"In7.Cu" "In8.Cu" "In9.Cu" "In10.Cu" "In11.Cu" "In12.Cu" "In13.Cu" "In14.Cu"
			"In15.Cu" "In16.Cu"
		)
		(hatch none 0.5)
		(connect_pads
			(clearance 0)
		)
		(min_thickness 0.25)
		(keepout
			(tracks not_allowed)
			(vias allowed)
			(pads allowed)
			(copperpour not_allowed)
			(footprints allowed)
		)
		(placement
			(enabled no)
			(sheetname "")
		)
		(fill
			(thermal_gap 0.5)
			(thermal_bridge_width 0.5)
			(island_removal_mode 0)
		)
		(polygon
			(pts
				(arc
					(start 66.173604 -404.08352)
					(mid 65.792604 -404.46452)
					(end 66.173604 -404.84552)
				)
				(arc
					(start 67.037204 -404.84552)
					(mid 67.418204 -404.46452)
					(end 67.037204 -404.08352)
				)
			)
		)
	)
	(zone
		(layers "F.Cu" "B.Cu" "In1.Cu" "In2.Cu" "In3.Cu" "In4.Cu" "In5.Cu" "In6.Cu"
			"In7.Cu" "In8.Cu" "In9.Cu" "In10.Cu" "In11.Cu" "In12.Cu" "In13.Cu" "In14.Cu"
			"In15.Cu" "In16.Cu"
		)
		(hatch none 0.5)
		(connect_pads
			(clearance 0)
		)
		(min_thickness 0.25)
		(keepout
			(tracks not_allowed)
			(vias allowed)
			(pads allowed)
			(copperpour not_allowed)
			(footprints allowed)
		)
		(placement
			(enabled no)
			(sheetname "")
		)
		(fill
			(thermal_gap 0.5)
			(thermal_bridge_width 0.5)
			(island_removal_mode 0)
		)
		(polygon
			(pts
				(arc
					(start 7.09549 7.400036)
					(mid 2.90449 7.400036)
					(end 7.09549 7.400036)
				)
			)
		)
	)
	(zone
		(layers "F.Cu" "B.Cu" "In1.Cu" "In2.Cu" "In3.Cu" "In4.Cu" "In5.Cu" "In6.Cu"
			"In7.Cu" "In8.Cu" "In9.Cu" "In10.Cu" "In11.Cu" "In12.Cu" "In13.Cu" "In14.Cu"
			"In15.Cu" "In16.Cu"
		)
		(hatch none 0.5)
		(connect_pads
			(clearance 0)
		)
		(min_thickness 0.25)
		(keepout
			(tracks not_allowed)
			(vias allowed)
			(pads allowed)
			(copperpour not_allowed)
			(footprints allowed)
		)
		(placement
			(enabled no)
			(sheetname "")
		)
		(fill yes
			(thermal_gap 0.5)
			(thermal_bridge_width 0.5)
			(island_removal_mode 0)
		)
		(polygon
			(pts
				(arc
					(start 133.036564 -386.170424)
					(mid 133.146535 -386.271478)
					(end 133.291326 -386.308092)
				)
				(arc
					(start 133.291326 -386.308092)
					(mid 133.506852 -386.218818)
					(end 133.596126 -386.003292)
				)
				(arc
					(start 133.596126 -386.003292)
					(mid 133.585789 -385.924553)
					(end 133.555486 -385.851146)
				)
				(arc
					(start 133.163056 -385.172204)
					(mid 133.050659 -385.050587)
					(end 132.891276 -385.00558)
				)
				(arc
					(start 132.891276 -385.00558)
					(mid 132.67575 -385.094854)
					(end 132.586476 -385.31038)
				)
				(arc
					(start 132.586476 -385.31038)
					(mid 132.596054 -385.386442)
					(end 132.624322 -385.4577)
				)
				(xy 133.021578 -386.145024) (xy 133.03377 -386.16636) (xy 133.03631 -386.170678)
			)
		)
	)
	(zone
		(layers "F.Cu" "B.Cu" "In1.Cu" "In2.Cu" "In3.Cu" "In4.Cu" "In5.Cu" "In6.Cu"
			"In7.Cu" "In8.Cu" "In9.Cu" "In10.Cu" "In11.Cu" "In12.Cu" "In13.Cu" "In14.Cu"
			"In15.Cu" "In16.Cu"
		)
		(hatch none 0.5)
		(connect_pads
			(clearance 0)
		)
		(min_thickness 0.25)
		(keepout
			(tracks not_allowed)
			(vias allowed)
			(pads allowed)
			(copperpour not_allowed)
			(footprints allowed)
		)
		(placement
			(enabled no)
			(sheetname "")
		)
		(fill
			(thermal_gap 0.5)
			(thermal_bridge_width 0.5)
			(island_removal_mode 0)
		)
		(polygon
			(pts
				(arc
					(start 162.374326 -406.62352)
					(mid 161.993326 -407.00452)
					(end 162.374326 -407.38552)
				)
				(arc
					(start 163.237926 -407.38552)
					(mid 163.618926 -407.00452)
					(end 163.237926 -406.62352)
				)
			)
		)
	)
	(zone
		(layers "F.Cu" "B.Cu" "In1.Cu" "In2.Cu" "In3.Cu" "In4.Cu" "In5.Cu" "In6.Cu"
			"In7.Cu" "In8.Cu" "In9.Cu" "In10.Cu" "In11.Cu" "In12.Cu" "In13.Cu" "In14.Cu"
			"In15.Cu" "In16.Cu"
		)
		(hatch none 0.5)
		(connect_pads
			(clearance 0)
		)
		(min_thickness 0.25)
		(keepout
			(tracks not_allowed)
			(vias allowed)
			(pads allowed)
			(copperpour not_allowed)
			(footprints allowed)
		)
		(placement
			(enabled no)
			(sheetname "")
		)
		(fill
			(thermal_gap 0.5)
			(thermal_bridge_width 0.5)
			(island_removal_mode 0)
		)
		(polygon
			(pts
				(arc
					(start 90.859102 -368.65433)
					(mid 90.478102 -369.03533)
					(end 90.859102 -369.41633)
				)
				(arc
					(start 91.722702 -369.41633)
					(mid 92.103702 -369.03533)
					(end 91.722702 -368.65433)
				)
			)
		)
	)
	(zone
		(layers "F.Cu" "B.Cu" "In1.Cu" "In2.Cu" "In3.Cu" "In4.Cu" "In5.Cu" "In6.Cu"
			"In7.Cu" "In8.Cu" "In9.Cu" "In10.Cu" "In11.Cu" "In12.Cu" "In13.Cu" "In14.Cu"
			"In15.Cu" "In16.Cu"
		)
		(hatch none 0.5)
		(connect_pads
			(clearance 0)
		)
		(min_thickness 0.25)
		(keepout
			(tracks not_allowed)
			(vias allowed)
			(pads allowed)
			(copperpour not_allowed)
			(footprints allowed)
		)
		(placement
			(enabled no)
			(sheetname "")
		)
		(fill
			(thermal_gap 0.5)
			(thermal_bridge_width 0.5)
			(island_removal_mode 0)
		)
		(polygon
			(pts
				(arc
					(start 28.186126 -428.564802)
					(mid 28.567126 -428.183802)
					(end 28.186126 -427.802802)
				)
				(arc
					(start 27.322526 -427.802802)
					(mid 26.941526 -428.183802)
					(end 27.322526 -428.564802)
				)
			)
		)
	)
	(zone
		(layers "F.Cu" "B.Cu" "In1.Cu" "In2.Cu" "In3.Cu" "In4.Cu" "In5.Cu" "In6.Cu"
			"In7.Cu" "In8.Cu" "In9.Cu" "In10.Cu" "In11.Cu" "In12.Cu" "In13.Cu" "In14.Cu"
			"In15.Cu" "In16.Cu"
		)
		(hatch none 0.5)
		(connect_pads
			(clearance 0)
		)
		(min_thickness 0.25)
		(keepout
			(tracks not_allowed)
			(vias allowed)
			(pads allowed)
			(copperpour not_allowed)
			(footprints allowed)
		)
		(placement
			(enabled no)
			(sheetname "")
		)
		(fill
			(thermal_gap 0.5)
			(thermal_bridge_width 0.5)
			(island_removal_mode 0)
		)
		(polygon
			(pts
				(arc
					(start 63.110364 -404.08352)
					(mid 62.729364 -404.46452)
					(end 63.110364 -404.84552)
				)
				(arc
					(start 63.973964 -404.84552)
					(mid 64.354964 -404.46452)
					(end 63.973964 -404.08352)
				)
			)
		)
	)
	(zone
		(layers "F.Cu" "B.Cu" "In1.Cu" "In2.Cu" "In3.Cu" "In4.Cu" "In5.Cu" "In6.Cu"
			"In7.Cu" "In8.Cu" "In9.Cu" "In10.Cu" "In11.Cu" "In12.Cu" "In13.Cu" "In14.Cu"
			"In15.Cu" "In16.Cu"
		)
		(hatch none 0.5)
		(connect_pads
			(clearance 0)
		)
		(min_thickness 0.25)
		(keepout
			(tracks not_allowed)
			(vias allowed)
			(pads allowed)
			(copperpour not_allowed)
			(footprints allowed)
		)
		(placement
			(enabled no)
			(sheetname "")
		)
		(fill
			(thermal_gap 0.5)
			(thermal_bridge_width 0.5)
			(island_removal_mode 0)
		)
		(polygon
			(pts
				(arc
					(start 400.34464 -377.03633)
					(mid 399.96364 -377.41733)
					(end 400.34464 -377.79833)
				)
				(arc
					(start 401.20824 -377.79833)
					(mid 401.58924 -377.41733)
					(end 401.20824 -377.03633)
				)
			)
		)
	)
	(zone
		(layers "F.Cu" "B.Cu" "In1.Cu" "In2.Cu" "In3.Cu" "In4.Cu" "In5.Cu" "In6.Cu"
			"In7.Cu" "In8.Cu" "In9.Cu" "In10.Cu" "In11.Cu" "In12.Cu" "In13.Cu" "In14.Cu"
			"In15.Cu" "In16.Cu"
		)
		(hatch none 0.5)
		(connect_pads
			(clearance 0)
		)
		(min_thickness 0.25)
		(keepout
			(tracks not_allowed)
			(vias allowed)
			(pads allowed)
			(copperpour not_allowed)
			(footprints allowed)
		)
		(placement
			(enabled no)
			(sheetname "")
		)
		(fill
			(thermal_gap 0.5)
			(thermal_bridge_width 0.5)
			(island_removal_mode 0)
		)
		(polygon
			(pts
				(arc
					(start 401.526502 -412.46552)
					(mid 401.145502 -412.84652)
					(end 401.526502 -413.22752)
				)
				(arc
					(start 402.390102 -413.22752)
					(mid 402.771102 -412.84652)
					(end 402.390102 -412.46552)
				)
			)
		)
	)
	(zone
		(layers "F.Cu" "B.Cu" "In1.Cu" "In2.Cu" "In3.Cu" "In4.Cu" "In5.Cu" "In6.Cu"
			"In7.Cu" "In8.Cu" "In9.Cu" "In10.Cu" "In11.Cu" "In12.Cu" "In13.Cu" "In14.Cu"
			"In15.Cu" "In16.Cu"
		)
		(hatch none 0.5)
		(connect_pads
			(clearance 0)
		)
		(min_thickness 0.25)
		(keepout
			(tracks not_allowed)
			(vias allowed)
			(pads allowed)
			(copperpour not_allowed)
			(footprints allowed)
		)
		(placement
			(enabled no)
			(sheetname "")
		)
		(fill yes
			(thermal_gap 0.5)
			(thermal_bridge_width 0.5)
			(island_removal_mode 0)
		)
		(polygon
			(pts
				(arc
					(start 64.736472 -386.170424)
					(mid 64.846443 -386.271478)
					(end 64.991234 -386.308092)
				)
				(arc
					(start 64.991234 -386.308092)
					(mid 65.20676 -386.218818)
					(end 65.296034 -386.003292)
				)
				(arc
					(start 65.296034 -386.003292)
					(mid 65.285697 -385.924553)
					(end 65.255394 -385.851146)
				)
				(arc
					(start 64.862964 -385.172204)
					(mid 64.750567 -385.050587)
					(end 64.591184 -385.00558)
				)
				(arc
					(start 64.591184 -385.00558)
					(mid 64.375658 -385.094854)
					(end 64.286384 -385.31038)
				)
				(arc
					(start 64.286384 -385.31038)
					(mid 64.295962 -385.386442)
					(end 64.32423 -385.4577)
				)
				(xy 64.721486 -386.145024) (xy 64.733678 -386.16636) (xy 64.736218 -386.170678)
			)
		)
	)
	(zone
		(layers "F.Cu" "B.Cu" "In1.Cu" "In2.Cu" "In3.Cu" "In4.Cu" "In5.Cu" "In6.Cu"
			"In7.Cu" "In8.Cu" "In9.Cu" "In10.Cu" "In11.Cu" "In12.Cu" "In13.Cu" "In14.Cu"
			"In15.Cu" "In16.Cu"
		)
		(hatch none 0.5)
		(connect_pads
			(clearance 0)
		)
		(min_thickness 0.25)
		(keepout
			(tracks not_allowed)
			(vias allowed)
			(pads allowed)
			(copperpour not_allowed)
			(footprints allowed)
		)
		(placement
			(enabled no)
			(sheetname "")
		)
		(fill
			(thermal_gap 0.5)
			(thermal_bridge_width 0.5)
			(island_removal_mode 0)
		)
		(polygon
			(pts
				(arc
					(start 116.236496 -389.634476)
					(mid 116.346467 -389.73553)
					(end 116.491258 -389.772144)
				)
				(arc
					(start 116.491258 -389.772144)
					(mid 116.706784 -389.68287)
					(end 116.796058 -389.467344)
				)
				(arc
					(start 116.796058 -389.467344)
					(mid 116.785721 -389.388605)
					(end 116.755418 -389.315198)
				)
				(arc
					(start 116.362988 -388.636256)
					(mid 116.250591 -388.514639)
					(end 116.091208 -388.469632)
				)
				(arc
					(start 116.091208 -388.469632)
					(mid 115.875682 -388.558906)
					(end 115.786408 -388.774432)
				)
				(arc
					(start 115.786408 -388.774432)
					(mid 115.795986 -388.850494)
					(end 115.824254 -388.921752)
				)
				(xy 116.22151 -389.609076) (xy 116.233702 -389.630412) (xy 116.236242 -389.63473)
			)
		)
	)
	(zone
		(layers "F.Cu" "B.Cu" "In1.Cu" "In2.Cu" "In3.Cu" "In4.Cu" "In5.Cu" "In6.Cu"
			"In7.Cu" "In8.Cu" "In9.Cu" "In10.Cu" "In11.Cu" "In12.Cu" "In13.Cu" "In14.Cu"
			"In15.Cu" "In16.Cu"
		)
		(hatch none 0.5)
		(connect_pads
			(clearance 0)
		)
		(min_thickness 0.25)
		(keepout
			(tracks not_allowed)
			(vias allowed)
			(pads allowed)
			(copperpour not_allowed)
			(footprints allowed)
		)
		(placement
			(enabled no)
			(sheetname "")
		)
		(fill
			(thermal_gap 0.5)
			(thermal_bridge_width 0.5)
			(island_removal_mode 0)
		)
		(polygon
			(pts
				(arc
					(start 86.725252 -392.429238)
					(mid 86.344252 -392.048238)
					(end 85.963252 -392.429238)
				)
				(arc
					(start 85.963252 -393.292838)
					(mid 86.344252 -393.673838)
					(end 86.725252 -393.292838)
				)
			)
		)
	)
	(zone
		(layers "F.Cu" "B.Cu" "In1.Cu" "In2.Cu" "In3.Cu" "In4.Cu" "In5.Cu" "In6.Cu"
			"In7.Cu" "In8.Cu" "In9.Cu" "In10.Cu" "In11.Cu" "In12.Cu" "In13.Cu" "In14.Cu"
			"In15.Cu" "In16.Cu"
		)
		(hatch none 0.5)
		(connect_pads
			(clearance 0)
		)
		(min_thickness 0.25)
		(keepout
			(tracks not_allowed)
			(vias allowed)
			(pads allowed)
			(copperpour not_allowed)
			(footprints allowed)
		)
		(placement
			(enabled no)
			(sheetname "")
		)
		(fill
			(thermal_gap 0.5)
			(thermal_bridge_width 0.5)
			(island_removal_mode 0)
		)
		(polygon
			(pts
				(arc
					(start 431.846482 -6.35127)
					(mid 431.465482 -6.73227)
					(end 431.846482 -7.11327)
				)
				(arc
					(start 432.710082 -7.11327)
					(mid 433.091082 -6.73227)
					(end 432.710082 -6.35127)
				)
			)
		)
	)
	(zone
		(layers "F.Cu" "B.Cu" "In1.Cu" "In2.Cu" "In3.Cu" "In4.Cu" "In5.Cu" "In6.Cu"
			"In7.Cu" "In8.Cu" "In9.Cu" "In10.Cu" "In11.Cu" "In12.Cu" "In13.Cu" "In14.Cu"
			"In15.Cu" "In16.Cu"
		)
		(hatch none 0.5)
		(connect_pads
			(clearance 0)
		)
		(min_thickness 0.25)
		(keepout
			(tracks not_allowed)
			(vias allowed)
			(pads allowed)
			(copperpour not_allowed)
			(footprints allowed)
		)
		(placement
			(enabled no)
			(sheetname "")
		)
		(fill
			(thermal_gap 0.5)
			(thermal_bridge_width 0.5)
			(island_removal_mode 0)
		)
		(polygon
			(pts
				(arc
					(start 350.86417 -394.552424)
					(mid 350.974141 -394.653478)
					(end 351.118932 -394.690092)
				)
				(arc
					(start 351.118932 -394.690092)
					(mid 351.334458 -394.600818)
					(end 351.423732 -394.385292)
				)
				(arc
					(start 351.423732 -394.385292)
					(mid 351.413395 -394.306553)
					(end 351.383092 -394.233146)
				)
				(arc
					(start 350.990662 -393.554204)
					(mid 350.878265 -393.432587)
					(end 350.718882 -393.38758)
				)
				(arc
					(start 350.718882 -393.38758)
					(mid 350.503356 -393.476854)
					(end 350.414082 -393.69238)
				)
				(arc
					(start 350.414082 -393.69238)
					(mid 350.42366 -393.768442)
					(end 350.451928 -393.8397)
				)
				(xy 350.849184 -394.527024) (xy 350.861376 -394.54836) (xy 350.863916 -394.552678)
			)
		)
	)
	(zone
		(layers "F.Cu" "B.Cu" "In1.Cu" "In2.Cu" "In3.Cu" "In4.Cu" "In5.Cu" "In6.Cu"
			"In7.Cu" "In8.Cu" "In9.Cu" "In10.Cu" "In11.Cu" "In12.Cu" "In13.Cu" "In14.Cu"
			"In15.Cu" "In16.Cu"
		)
		(hatch none 0.5)
		(connect_pads
			(clearance 0)
		)
		(min_thickness 0.25)
		(keepout
			(tracks not_allowed)
			(vias allowed)
			(pads allowed)
			(copperpour not_allowed)
			(footprints allowed)
		)
		(placement
			(enabled no)
			(sheetname "")
		)
		(fill
			(thermal_gap 0.5)
			(thermal_bridge_width 0.5)
			(island_removal_mode 0)
		)
		(polygon
			(pts
				(arc
					(start 328.299826 -420.571168)
					(mid 327.918826 -420.952168)
					(end 328.299826 -421.333168)
				)
				(arc
					(start 329.163426 -421.333168)
					(mid 329.544426 -420.952168)
					(end 329.163426 -420.571168)
				)
			)
		)
	)
	(zone
		(layers "F.Cu" "B.Cu" "In1.Cu" "In2.Cu" "In3.Cu" "In4.Cu" "In5.Cu" "In6.Cu"
			"In7.Cu" "In8.Cu" "In9.Cu" "In10.Cu" "In11.Cu" "In12.Cu" "In13.Cu" "In14.Cu"
			"In15.Cu" "In16.Cu"
		)
		(hatch none 0.5)
		(connect_pads
			(clearance 0)
		)
		(min_thickness 0.25)
		(keepout
			(tracks not_allowed)
			(vias allowed)
			(pads allowed)
			(copperpour not_allowed)
			(footprints allowed)
		)
		(placement
			(enabled no)
			(sheetname "")
		)
		(fill
			(thermal_gap 0.5)
			(thermal_bridge_width 0.5)
			(island_removal_mode 0)
		)
		(polygon
			(pts
				(arc
					(start 96.064324 -389.634476)
					(mid 96.174295 -389.73553)
					(end 96.319086 -389.772144)
				)
				(arc
					(start 96.319086 -389.772144)
					(mid 96.534612 -389.68287)
					(end 96.623886 -389.467344)
				)
				(arc
					(start 96.623886 -389.467344)
					(mid 96.613549 -389.388605)
					(end 96.583246 -389.315198)
				)
				(arc
					(start 96.190816 -388.636256)
					(mid 96.078419 -388.514639)
					(end 95.919036 -388.469632)
				)
				(arc
					(start 95.919036 -388.469632)
					(mid 95.70351 -388.558906)
					(end 95.614236 -388.774432)
				)
				(arc
					(start 95.614236 -388.774432)
					(mid 95.623814 -388.850494)
					(end 95.652082 -388.921752)
				)
				(xy 96.049338 -389.609076) (xy 96.06153 -389.630412) (xy 96.06407 -389.63473)
			)
		)
	)
	(zone
		(layers "F.Cu" "B.Cu" "In1.Cu" "In2.Cu" "In3.Cu" "In4.Cu" "In5.Cu" "In6.Cu"
			"In7.Cu" "In8.Cu" "In9.Cu" "In10.Cu" "In11.Cu" "In12.Cu" "In13.Cu" "In14.Cu"
			"In15.Cu" "In16.Cu"
		)
		(hatch none 0.5)
		(connect_pads
			(clearance 0)
		)
		(min_thickness 0.25)
		(keepout
			(tracks not_allowed)
			(vias allowed)
			(pads allowed)
			(copperpour not_allowed)
			(footprints allowed)
		)
		(placement
			(enabled no)
			(sheetname "")
		)
		(fill
			(thermal_gap 0.5)
			(thermal_bridge_width 0.5)
			(island_removal_mode 0)
		)
		(polygon
			(pts
				(arc
					(start 20.82038 -4.582414)
					(mid 20.43938 -4.963414)
					(end 20.82038 -5.344414)
				)
				(arc
					(start 21.68398 -5.344414)
					(mid 22.06498 -4.963414)
					(end 21.68398 -4.582414)
				)
			)
		)
	)
	(zone
		(layers "F.Cu" "B.Cu" "In1.Cu" "In2.Cu" "In3.Cu" "In4.Cu" "In5.Cu" "In6.Cu"
			"In7.Cu" "In8.Cu" "In9.Cu" "In10.Cu" "In11.Cu" "In12.Cu" "In13.Cu" "In14.Cu"
			"In15.Cu" "In16.Cu"
		)
		(hatch none 0.5)
		(connect_pads
			(clearance 0)
		)
		(min_thickness 0.25)
		(keepout
			(tracks not_allowed)
			(vias allowed)
			(pads allowed)
			(copperpour not_allowed)
			(footprints allowed)
		)
		(placement
			(enabled no)
			(sheetname "")
		)
		(fill
			(thermal_gap 0.5)
			(thermal_bridge_width 0.5)
			(island_removal_mode 0)
		)
		(polygon
			(pts
				(arc
					(start 255.546098 -208.217008)
					(mid 255.927098 -208.598008)
					(end 256.308098 -208.217008)
				)
				(arc
					(start 256.308098 -207.353408)
					(mid 255.927098 -206.972408)
					(end 255.546098 -207.353408)
				)
			)
		)
	)
	(zone
		(layers "F.Cu" "B.Cu" "In1.Cu" "In2.Cu" "In3.Cu" "In4.Cu" "In5.Cu" "In6.Cu"
			"In7.Cu" "In8.Cu" "In9.Cu" "In10.Cu" "In11.Cu" "In12.Cu" "In13.Cu" "In14.Cu"
			"In15.Cu" "In16.Cu"
		)
		(hatch none 0.5)
		(connect_pads
			(clearance 0)
		)
		(min_thickness 0.25)
		(keepout
			(tracks not_allowed)
			(vias allowed)
			(pads allowed)
			(copperpour not_allowed)
			(footprints allowed)
		)
		(placement
			(enabled no)
			(sheetname "")
		)
		(fill
			(thermal_gap 0.5)
			(thermal_bridge_width 0.5)
			(island_removal_mode 0)
		)
		(polygon
			(pts
				(arc
					(start 79.958184 -406.62352)
					(mid 79.577184 -407.00452)
					(end 79.958184 -407.38552)
				)
				(arc
					(start 80.821784 -407.38552)
					(mid 81.202784 -407.00452)
					(end 80.821784 -406.62352)
				)
			)
		)
	)
	(zone
		(layers "F.Cu" "B.Cu" "In1.Cu" "In2.Cu" "In3.Cu" "In4.Cu" "In5.Cu" "In6.Cu"
			"In7.Cu" "In8.Cu" "In9.Cu" "In10.Cu" "In11.Cu" "In12.Cu" "In13.Cu" "In14.Cu"
			"In15.Cu" "In16.Cu"
		)
		(hatch none 0.5)
		(connect_pads
			(clearance 0)
		)
		(min_thickness 0.25)
		(keepout
			(tracks not_allowed)
			(vias allowed)
			(pads allowed)
			(copperpour not_allowed)
			(footprints allowed)
		)
		(placement
			(enabled no)
			(sheetname "")
		)
		(fill
			(thermal_gap 0.5)
			(thermal_bridge_width 0.5)
			(island_removal_mode 0)
		)
		(polygon
			(pts
				(arc
					(start 314.736226 -398.016476)
					(mid 314.846197 -398.11753)
					(end 314.990988 -398.154144)
				)
				(arc
					(start 314.990988 -398.154144)
					(mid 315.206514 -398.06487)
					(end 315.295788 -397.849344)
				)
				(arc
					(start 315.295788 -397.849344)
					(mid 315.285451 -397.770605)
					(end 315.255148 -397.697198)
				)
				(arc
					(start 314.862718 -397.018256)
					(mid 314.750321 -396.896639)
					(end 314.590938 -396.851632)
				)
				(arc
					(start 314.590938 -396.851632)
					(mid 314.375412 -396.940906)
					(end 314.286138 -397.156432)
				)
				(arc
					(start 314.286138 -397.156432)
					(mid 314.295716 -397.232494)
					(end 314.323984 -397.303752)
				)
				(xy 314.72124 -397.991076) (xy 314.733432 -398.012412) (xy 314.735972 -398.01673)
			)
		)
	)
	(zone
		(layers "F.Cu" "B.Cu" "In1.Cu" "In2.Cu" "In3.Cu" "In4.Cu" "In5.Cu" "In6.Cu"
			"In7.Cu" "In8.Cu" "In9.Cu" "In10.Cu" "In11.Cu" "In12.Cu" "In13.Cu" "In14.Cu"
			"In15.Cu" "In16.Cu"
		)
		(hatch none 0.5)
		(connect_pads
			(clearance 0)
		)
		(min_thickness 0.25)
		(keepout
			(tracks not_allowed)
			(vias allowed)
			(pads allowed)
			(copperpour not_allowed)
			(footprints allowed)
		)
		(placement
			(enabled no)
			(sheetname "")
		)
		(fill
			(thermal_gap 0.5)
			(thermal_bridge_width 0.5)
			(island_removal_mode 0)
		)
		(polygon
			(pts
				(arc
					(start 387.506464 9.959848)
					(mid 385.652264 9.959848)
					(end 387.506464 9.959848)
				)
			)
		)
	)
	(zone
		(layers "F.Cu" "B.Cu" "In1.Cu" "In2.Cu" "In3.Cu" "In4.Cu" "In5.Cu" "In6.Cu"
			"In7.Cu" "In8.Cu" "In9.Cu" "In10.Cu" "In11.Cu" "In12.Cu" "In13.Cu" "In14.Cu"
			"In15.Cu" "In16.Cu"
		)
		(hatch none 0.5)
		(connect_pads
			(clearance 0)
		)
		(min_thickness 0.25)
		(keepout
			(tracks not_allowed)
			(vias allowed)
			(pads allowed)
			(copperpour not_allowed)
			(footprints allowed)
		)
		(placement
			(enabled no)
			(sheetname "")
		)
		(fill
			(thermal_gap 0.5)
			(thermal_bridge_width 0.5)
			(island_removal_mode 0)
		)
		(polygon
			(pts
				(arc
					(start 92.782898 -44.049696)
					(mid 89.78265 -47.049944)
					(end 92.782898 -50.050192)
				)
				(arc
					(start 94.383098 -50.050192)
					(mid 97.383346 -47.049944)
					(end 94.383098 -44.049696)
				)
			)
		)
	)
	(zone
		(layers "F.Cu" "B.Cu" "In1.Cu" "In2.Cu" "In3.Cu" "In4.Cu" "In5.Cu" "In6.Cu"
			"In7.Cu" "In8.Cu" "In9.Cu" "In10.Cu" "In11.Cu" "In12.Cu" "In13.Cu" "In14.Cu"
			"In15.Cu" "In16.Cu"
		)
		(hatch none 0.5)
		(connect_pads
			(clearance 0)
		)
		(min_thickness 0.25)
		(keepout
			(tracks not_allowed)
			(vias allowed)
			(pads allowed)
			(copperpour not_allowed)
			(footprints allowed)
		)
		(placement
			(enabled no)
			(sheetname "")
		)
		(fill
			(thermal_gap 0.5)
			(thermal_bridge_width 0.5)
			(island_removal_mode 0)
		)
		(polygon
			(pts
				(arc
					(start 418.225224 -400.811238)
					(mid 417.844224 -400.430238)
					(end 417.463224 -400.811238)
				)
				(arc
					(start 417.463224 -401.674838)
					(mid 417.844224 -402.055838)
					(end 418.225224 -401.674838)
				)
			)
		)
	)
	(zone
		(layers "F.Cu" "B.Cu" "In1.Cu" "In2.Cu" "In3.Cu" "In4.Cu" "In5.Cu" "In6.Cu"
			"In7.Cu" "In8.Cu" "In9.Cu" "In10.Cu" "In11.Cu" "In12.Cu" "In13.Cu" "In14.Cu"
			"In15.Cu" "In16.Cu"
		)
		(hatch none 0.5)
		(connect_pads
			(clearance 0)
		)
		(min_thickness 0.25)
		(keepout
			(tracks not_allowed)
			(vias allowed)
			(pads allowed)
			(copperpour not_allowed)
			(footprints allowed)
		)
		(placement
			(enabled no)
			(sheetname "")
		)
		(fill
			(thermal_gap 0.5)
			(thermal_bridge_width 0.5)
			(island_removal_mode 0)
		)
		(polygon
			(pts
				(arc
					(start 108.911644 -375.96826)
					(mid 108.530644 -375.58726)
					(end 108.149644 -375.96826)
				)
				(arc
					(start 108.149644 -376.83186)
					(mid 108.530644 -377.21286)
					(end 108.911644 -376.83186)
				)
			)
		)
	)
	(zone
		(layers "F.Cu" "B.Cu" "In1.Cu" "In2.Cu" "In3.Cu" "In4.Cu" "In5.Cu" "In6.Cu"
			"In7.Cu" "In8.Cu" "In9.Cu" "In10.Cu" "In11.Cu" "In12.Cu" "In13.Cu" "In14.Cu"
			"In15.Cu" "In16.Cu"
		)
		(hatch none 0.5)
		(connect_pads
			(clearance 0)
		)
		(min_thickness 0.25)
		(keepout
			(tracks not_allowed)
			(vias allowed)
			(pads allowed)
			(copperpour not_allowed)
			(footprints allowed)
		)
		(placement
			(enabled no)
			(sheetname "")
		)
		(fill yes
			(thermal_gap 0.5)
			(thermal_bridge_width 0.5)
			(island_removal_mode 0)
		)
		(polygon
			(pts
				(arc
					(start 384.236468 -394.552424)
					(mid 384.346439 -394.653478)
					(end 384.49123 -394.690092)
				)
				(arc
					(start 384.49123 -394.690092)
					(mid 384.706756 -394.600818)
					(end 384.79603 -394.385292)
				)
				(arc
					(start 384.79603 -394.385292)
					(mid 384.785693 -394.306553)
					(end 384.75539 -394.233146)
				)
				(arc
					(start 384.36296 -393.554204)
					(mid 384.250563 -393.432587)
					(end 384.09118 -393.38758)
				)
				(arc
					(start 384.09118 -393.38758)
					(mid 383.875654 -393.476854)
					(end 383.78638 -393.69238)
				)
				(arc
					(start 383.78638 -393.69238)
					(mid 383.795958 -393.768442)
					(end 383.824226 -393.8397)
				)
				(xy 384.221482 -394.527024) (xy 384.233674 -394.54836) (xy 384.236214 -394.552678)
			)
		)
	)
	(zone
		(layers "F.Cu" "B.Cu" "In1.Cu" "In2.Cu" "In3.Cu" "In4.Cu" "In5.Cu" "In6.Cu"
			"In7.Cu" "In8.Cu" "In9.Cu" "In10.Cu" "In11.Cu" "In12.Cu" "In13.Cu" "In14.Cu"
			"In15.Cu" "In16.Cu"
		)
		(hatch none 0.5)
		(connect_pads
			(clearance 0)
		)
		(min_thickness 0.25)
		(keepout
			(tracks not_allowed)
			(vias allowed)
			(pads allowed)
			(copperpour not_allowed)
			(footprints allowed)
		)
		(placement
			(enabled no)
			(sheetname "")
		)
		(fill
			(thermal_gap 0.5)
			(thermal_bridge_width 0.5)
			(island_removal_mode 0)
		)
		(polygon
			(pts
				(arc
					(start 117.957346 -412.189168)
					(mid 117.576346 -412.570168)
					(end 117.957346 -412.951168)
				)
				(arc
					(start 118.820946 -412.951168)
					(mid 119.201946 -412.570168)
					(end 118.820946 -412.189168)
				)
			)
		)
	)
	(zone
		(layers "F.Cu" "B.Cu" "In1.Cu" "In2.Cu" "In3.Cu" "In4.Cu" "In5.Cu" "In6.Cu"
			"In7.Cu" "In8.Cu" "In9.Cu" "In10.Cu" "In11.Cu" "In12.Cu" "In13.Cu" "In14.Cu"
			"In15.Cu" "In16.Cu"
		)
		(hatch none 0.5)
		(connect_pads
			(clearance 0)
		)
		(min_thickness 0.25)
		(keepout
			(tracks not_allowed)
			(vias allowed)
			(pads allowed)
			(copperpour not_allowed)
			(footprints allowed)
		)
		(placement
			(enabled no)
			(sheetname "")
		)
		(fill
			(thermal_gap 0.5)
			(thermal_bridge_width 0.5)
			(island_removal_mode 0)
		)
		(polygon
			(pts
				(arc
					(start 8.725408 -173.07814)
					(mid 9.106408 -173.45914)
					(end 9.487408 -173.07814)
				)
				(arc
					(start 9.487408 -172.21454)
					(mid 9.106408 -171.83354)
					(end 8.725408 -172.21454)
				)
			)
		)
	)
	(zone
		(layers "F.Cu" "B.Cu" "In1.Cu" "In2.Cu" "In3.Cu" "In4.Cu" "In5.Cu" "In6.Cu"
			"In7.Cu" "In8.Cu" "In9.Cu" "In10.Cu" "In11.Cu" "In12.Cu" "In13.Cu" "In14.Cu"
			"In15.Cu" "In16.Cu"
		)
		(hatch none 0.5)
		(connect_pads
			(clearance 0)
		)
		(min_thickness 0.25)
		(keepout
			(tracks not_allowed)
			(vias allowed)
			(pads allowed)
			(copperpour not_allowed)
			(footprints allowed)
		)
		(placement
			(enabled no)
			(sheetname "")
		)
		(fill
			(thermal_gap 0.5)
			(thermal_bridge_width 0.5)
			(island_removal_mode 0)
		)
		(polygon
			(pts
				(arc
					(start 312.336434 -394.552424)
					(mid 312.446405 -394.653478)
					(end 312.591196 -394.690092)
				)
				(arc
					(start 312.591196 -394.690092)
					(mid 312.806722 -394.600818)
					(end 312.895996 -394.385292)
				)
				(arc
					(start 312.895996 -394.385292)
					(mid 312.885659 -394.306553)
					(end 312.855356 -394.233146)
				)
				(arc
					(start 312.462926 -393.554204)
					(mid 312.350529 -393.432587)
					(end 312.191146 -393.38758)
				)
				(arc
					(start 312.191146 -393.38758)
					(mid 311.97562 -393.476854)
					(end 311.886346 -393.69238)
				)
				(arc
					(start 311.886346 -393.69238)
					(mid 311.895924 -393.768442)
					(end 311.924192 -393.8397)
				)
				(xy 312.321448 -394.527024) (xy 312.33364 -394.54836) (xy 312.33618 -394.552678)
			)
		)
	)
	(zone
		(layers "F.Cu" "B.Cu" "In1.Cu" "In2.Cu" "In3.Cu" "In4.Cu" "In5.Cu" "In6.Cu"
			"In7.Cu" "In8.Cu" "In9.Cu" "In10.Cu" "In11.Cu" "In12.Cu" "In13.Cu" "In14.Cu"
			"In15.Cu" "In16.Cu"
		)
		(hatch none 0.5)
		(connect_pads
			(clearance 0)
		)
		(min_thickness 0.25)
		(keepout
			(tracks not_allowed)
			(vias allowed)
			(pads allowed)
			(copperpour not_allowed)
			(footprints allowed)
		)
		(placement
			(enabled no)
			(sheetname "")
		)
		(fill
			(thermal_gap 0.5)
			(thermal_bridge_width 0.5)
			(island_removal_mode 0)
		)
		(polygon
			(pts
				(arc
					(start 156.257244 -371.11813)
					(mid 155.876244 -371.49913)
					(end 156.257244 -371.88013)
				)
				(arc
					(start 157.120844 -371.88013)
					(mid 157.501844 -371.49913)
					(end 157.120844 -371.11813)
				)
			)
		)
	)
	(zone
		(layers "F.Cu" "B.Cu" "In1.Cu" "In2.Cu" "In3.Cu" "In4.Cu" "In5.Cu" "In6.Cu"
			"In7.Cu" "In8.Cu" "In9.Cu" "In10.Cu" "In11.Cu" "In12.Cu" "In13.Cu" "In14.Cu"
			"In15.Cu" "In16.Cu"
		)
		(hatch none 0.5)
		(connect_pads
			(clearance 0)
		)
		(min_thickness 0.25)
		(keepout
			(tracks not_allowed)
			(vias allowed)
			(pads allowed)
			(copperpour not_allowed)
			(footprints allowed)
		)
		(placement
			(enabled no)
			(sheetname "")
		)
		(fill
			(thermal_gap 0.5)
			(thermal_bridge_width 0.5)
			(island_removal_mode 0)
		)
		(polygon
			(pts
				(arc
					(start 351.125028 -400.811238)
					(mid 350.744028 -400.430238)
					(end 350.363028 -400.811238)
				)
				(arc
					(start 350.363028 -401.674838)
					(mid 350.744028 -402.055838)
					(end 351.125028 -401.674838)
				)
			)
		)
	)
	(zone
		(layers "F.Cu" "B.Cu" "In1.Cu" "In2.Cu" "In3.Cu" "In4.Cu" "In5.Cu" "In6.Cu"
			"In7.Cu" "In8.Cu" "In9.Cu" "In10.Cu" "In11.Cu" "In12.Cu" "In13.Cu" "In14.Cu"
			"In15.Cu" "In16.Cu"
		)
		(hatch none 0.5)
		(connect_pads
			(clearance 0)
		)
		(min_thickness 0.25)
		(keepout
			(tracks not_allowed)
			(vias allowed)
			(pads allowed)
			(copperpour not_allowed)
			(footprints allowed)
		)
		(placement
			(enabled no)
			(sheetname "")
		)
		(fill
			(thermal_gap 0.5)
			(thermal_bridge_width 0.5)
			(island_removal_mode 0)
		)
		(polygon
			(pts
				(arc
					(start 347.263974 -398.016476)
					(mid 347.373945 -398.11753)
					(end 347.518736 -398.154144)
				)
				(arc
					(start 347.518736 -398.154144)
					(mid 347.734262 -398.06487)
					(end 347.823536 -397.849344)
				)
				(arc
					(start 347.823536 -397.849344)
					(mid 347.813199 -397.770605)
					(end 347.782896 -397.697198)
				)
				(arc
					(start 347.390466 -397.018256)
					(mid 347.278069 -396.896639)
					(end 347.118686 -396.851632)
				)
				(arc
					(start 347.118686 -396.851632)
					(mid 346.90316 -396.940906)
					(end 346.813886 -397.156432)
				)
				(arc
					(start 346.813886 -397.156432)
					(mid 346.823464 -397.232494)
					(end 346.851732 -397.303752)
				)
				(xy 347.248988 -397.991076) (xy 347.26118 -398.012412) (xy 347.26372 -398.01673)
			)
		)
	)
	(zone
		(layers "F.Cu" "B.Cu" "In1.Cu" "In2.Cu" "In3.Cu" "In4.Cu" "In5.Cu" "In6.Cu"
			"In7.Cu" "In8.Cu" "In9.Cu" "In10.Cu" "In11.Cu" "In12.Cu" "In13.Cu" "In14.Cu"
			"In15.Cu" "In16.Cu"
		)
		(hatch none 0.5)
		(connect_pads
			(clearance 0)
		)
		(min_thickness 0.25)
		(keepout
			(tracks not_allowed)
			(vias allowed)
			(pads allowed)
			(copperpour not_allowed)
			(footprints allowed)
		)
		(placement
			(enabled no)
			(sheetname "")
		)
		(fill
			(thermal_gap 0.5)
			(thermal_bridge_width 0.5)
			(island_removal_mode 0)
		)
		(polygon
			(pts
				(arc
					(start 326.768206 -415.00552)
					(mid 326.387206 -415.38652)
					(end 326.768206 -415.76752)
				)
				(arc
					(start 327.631806 -415.76752)
					(mid 328.012806 -415.38652)
					(end 327.631806 -415.00552)
				)
			)
		)
	)
	(zone
		(layers "F.Cu" "B.Cu" "In1.Cu" "In2.Cu" "In3.Cu" "In4.Cu" "In5.Cu" "In6.Cu"
			"In7.Cu" "In8.Cu" "In9.Cu" "In10.Cu" "In11.Cu" "In12.Cu" "In13.Cu" "In14.Cu"
			"In15.Cu" "In16.Cu"
		)
		(hatch none 0.5)
		(connect_pads
			(clearance 0)
		)
		(min_thickness 0.25)
		(keepout
			(tracks not_allowed)
			(vias allowed)
			(pads allowed)
			(copperpour not_allowed)
			(footprints allowed)
		)
		(placement
			(enabled no)
			(sheetname "")
		)
		(fill
			(thermal_gap 0.5)
			(thermal_bridge_width 0.5)
			(island_removal_mode 0)
		)
		(polygon
			(pts
				(arc
					(start 137.868406 -406.62352)
					(mid 137.487406 -407.00452)
					(end 137.868406 -407.38552)
				)
				(arc
					(start 138.732006 -407.38552)
					(mid 139.113006 -407.00452)
					(end 138.732006 -406.62352)
				)
			)
		)
	)
	(zone
		(layers "F.Cu" "B.Cu" "In1.Cu" "In2.Cu" "In3.Cu" "In4.Cu" "In5.Cu" "In6.Cu"
			"In7.Cu" "In8.Cu" "In9.Cu" "In10.Cu" "In11.Cu" "In12.Cu" "In13.Cu" "In14.Cu"
			"In15.Cu" "In16.Cu"
		)
		(hatch none 0.5)
		(connect_pads
			(clearance 0)
		)
		(min_thickness 0.25)
		(keepout
			(tracks not_allowed)
			(vias allowed)
			(pads allowed)
			(copperpour not_allowed)
			(footprints allowed)
		)
		(placement
			(enabled no)
			(sheetname "")
		)
		(fill
			(thermal_gap 0.5)
			(thermal_bridge_width 0.5)
			(island_removal_mode 0)
		)
		(polygon
			(pts
				(arc
					(start 390.509506 8.25881)
					(mid 390.941306 7.82701)
					(end 391.373106 8.25881)
				)
				(arc
					(start 391.373106 9.12241)
					(mid 390.941306 9.55421)
					(end 390.509506 9.12241)
				)
			)
		)
	)
	(zone
		(layers "F.Cu" "B.Cu" "In1.Cu" "In2.Cu" "In3.Cu" "In4.Cu" "In5.Cu" "In6.Cu"
			"In7.Cu" "In8.Cu" "In9.Cu" "In10.Cu" "In11.Cu" "In12.Cu" "In13.Cu" "In14.Cu"
			"In15.Cu" "In16.Cu"
		)
		(hatch none 0.5)
		(connect_pads
			(clearance 0)
		)
		(min_thickness 0.25)
		(keepout
			(tracks not_allowed)
			(vias allowed)
			(pads allowed)
			(copperpour not_allowed)
			(footprints allowed)
		)
		(placement
			(enabled no)
			(sheetname "")
		)
		(fill
			(thermal_gap 0.5)
			(thermal_bridge_width 0.5)
			(island_removal_mode 0)
		)
		(polygon
			(pts
				(xy 519.60526 -453.533002) (xy 528.99564 -453.533002) (xy 529.30044 -453.228202) (xy 519.30046 -453.228202)
			)
		)
	)
	(zone
		(layers "F.Cu" "B.Cu" "In1.Cu" "In2.Cu" "In3.Cu" "In4.Cu" "In5.Cu" "In6.Cu"
			"In7.Cu" "In8.Cu" "In9.Cu" "In10.Cu" "In11.Cu" "In12.Cu" "In13.Cu" "In14.Cu"
			"In15.Cu" "In16.Cu"
		)
		(hatch none 0.5)
		(connect_pads
			(clearance 0)
		)
		(min_thickness 0.25)
		(keepout
			(tracks not_allowed)
			(vias allowed)
			(pads allowed)
			(copperpour not_allowed)
			(footprints allowed)
		)
		(placement
			(enabled no)
			(sheetname "")
		)
		(fill
			(thermal_gap 0.5)
			(thermal_bridge_width 0.5)
			(island_removal_mode 0)
		)
		(polygon
			(pts
				(arc
					(start 173.065186 -37.049964)
					(mid 170.601386 -37.049964)
					(end 173.065186 -37.049964)
				)
			)
		)
	)
	(zone
		(layers "F.Cu" "B.Cu" "In1.Cu" "In2.Cu" "In3.Cu" "In4.Cu" "In5.Cu" "In6.Cu"
			"In7.Cu" "In8.Cu" "In9.Cu" "In10.Cu" "In11.Cu" "In12.Cu" "In13.Cu" "In14.Cu"
			"In15.Cu" "In16.Cu"
		)
		(hatch none 0.5)
		(connect_pads
			(clearance 0)
		)
		(min_thickness 0.25)
		(keepout
			(tracks not_allowed)
			(vias allowed)
			(pads allowed)
			(copperpour not_allowed)
			(footprints allowed)
		)
		(placement
			(enabled no)
			(sheetname "")
		)
		(fill
			(thermal_gap 0.5)
			(thermal_bridge_width 0.5)
			(island_removal_mode 0)
		)
		(polygon
			(pts
				(arc
					(start 133.33984 -25.62733)
					(mid 133.72084 -26.00833)
					(end 134.10184 -25.62733)
				)
				(arc
					(start 134.10184 -24.76373)
					(mid 133.72084 -24.38273)
					(end 133.33984 -24.76373)
				)
			)
		)
	)
	(zone
		(layers "F.Cu" "B.Cu" "In1.Cu" "In2.Cu" "In3.Cu" "In4.Cu" "In5.Cu" "In6.Cu"
			"In7.Cu" "In8.Cu" "In9.Cu" "In10.Cu" "In11.Cu" "In12.Cu" "In13.Cu" "In14.Cu"
			"In15.Cu" "In16.Cu"
		)
		(hatch none 0.5)
		(connect_pads
			(clearance 0)
		)
		(min_thickness 0.25)
		(keepout
			(tracks not_allowed)
			(vias allowed)
			(pads allowed)
			(copperpour not_allowed)
			(footprints allowed)
		)
		(placement
			(enabled no)
			(sheetname "")
		)
		(fill
			(thermal_gap 0.5)
			(thermal_bridge_width 0.5)
			(island_removal_mode 0)
		)
		(polygon
			(pts
				(arc
					(start 345.147646 -418.031168)
					(mid 344.766646 -418.412168)
					(end 345.147646 -418.793168)
				)
				(arc
					(start 346.011246 -418.793168)
					(mid 346.392246 -418.412168)
					(end 346.011246 -418.031168)
				)
			)
		)
	)
	(zone
		(layers "F.Cu" "B.Cu" "In1.Cu" "In2.Cu" "In3.Cu" "In4.Cu" "In5.Cu" "In6.Cu"
			"In7.Cu" "In8.Cu" "In9.Cu" "In10.Cu" "In11.Cu" "In12.Cu" "In13.Cu" "In14.Cu"
			"In15.Cu" "In16.Cu"
		)
		(hatch none 0.5)
		(connect_pads
			(clearance 0)
		)
		(min_thickness 0.25)
		(keepout
			(tracks not_allowed)
			(vias allowed)
			(pads allowed)
			(copperpour not_allowed)
			(footprints allowed)
		)
		(placement
			(enabled no)
			(sheetname "")
		)
		(fill
			(thermal_gap 0.5)
			(thermal_bridge_width 0.5)
			(island_removal_mode 0)
		)
		(polygon
			(pts
				(arc
					(start 165.82517 -392.429238)
					(mid 165.44417 -392.048238)
					(end 165.06317 -392.429238)
				)
				(arc
					(start 165.06317 -393.292838)
					(mid 165.44417 -393.673838)
					(end 165.82517 -393.292838)
				)
			)
		)
	)
	(zone
		(layers "F.Cu" "B.Cu" "In1.Cu" "In2.Cu" "In3.Cu" "In4.Cu" "In5.Cu" "In6.Cu"
			"In7.Cu" "In8.Cu" "In9.Cu" "In10.Cu" "In11.Cu" "In12.Cu" "In13.Cu" "In14.Cu"
			"In15.Cu" "In16.Cu"
		)
		(hatch none 0.5)
		(connect_pads
			(clearance 0)
		)
		(min_thickness 0.25)
		(keepout
			(tracks not_allowed)
			(vias allowed)
			(pads allowed)
			(copperpour not_allowed)
			(footprints allowed)
		)
		(placement
			(enabled no)
			(sheetname "")
		)
		(fill
			(thermal_gap 0.5)
			(thermal_bridge_width 0.5)
			(island_removal_mode 0)
		)
		(polygon
			(pts
				(arc
					(start 20.019772 -138.001502)
					(mid 20.400772 -138.382502)
					(end 20.781772 -138.001502)
				)
				(arc
					(start 20.781772 -137.010902)
					(mid 20.400772 -136.629902)
					(end 20.019772 -137.010902)
				)
			)
		)
	)
	(zone
		(layers "F.Cu" "B.Cu" "In1.Cu" "In2.Cu" "In3.Cu" "In4.Cu" "In5.Cu" "In6.Cu"
			"In7.Cu" "In8.Cu" "In9.Cu" "In10.Cu" "In11.Cu" "In12.Cu" "In13.Cu" "In14.Cu"
			"In15.Cu" "In16.Cu"
		)
		(hatch none 0.5)
		(connect_pads
			(clearance 0)
		)
		(min_thickness 0.25)
		(keepout
			(tracks not_allowed)
			(vias allowed)
			(pads allowed)
			(copperpour not_allowed)
			(footprints allowed)
		)
		(placement
			(enabled no)
			(sheetname "")
		)
		(fill
			(thermal_gap 0.5)
			(thermal_bridge_width 0.5)
			(island_removal_mode 0)
		)
		(polygon
			(pts
				(arc
					(start 319.797176 -400.811238)
					(mid 319.416176 -400.430238)
					(end 319.035176 -400.811238)
				)
				(arc
					(start 319.035176 -401.674838)
					(mid 319.416176 -402.055838)
					(end 319.797176 -401.674838)
				)
			)
		)
	)
	(zone
		(layers "F.Cu" "B.Cu" "In1.Cu" "In2.Cu" "In3.Cu" "In4.Cu" "In5.Cu" "In6.Cu"
			"In7.Cu" "In8.Cu" "In9.Cu" "In10.Cu" "In11.Cu" "In12.Cu" "In13.Cu" "In14.Cu"
			"In15.Cu" "In16.Cu"
		)
		(hatch none 0.5)
		(connect_pads
			(clearance 0)
		)
		(min_thickness 0.25)
		(keepout
			(tracks not_allowed)
			(vias allowed)
			(pads allowed)
			(copperpour not_allowed)
			(footprints allowed)
		)
		(placement
			(enabled no)
			(sheetname "")
		)
		(fill
			(thermal_gap 0.5)
			(thermal_bridge_width 0.5)
			(island_removal_mode 0)
		)
		(polygon
			(pts
				(arc
					(start 49.325784 -406.62352)
					(mid 48.944784 -407.00452)
					(end 49.325784 -407.38552)
				)
				(arc
					(start 50.189384 -407.38552)
					(mid 50.570384 -407.00452)
					(end 50.189384 -406.62352)
				)
			)
		)
	)
	(zone
		(layers "F.Cu" "B.Cu" "In1.Cu" "In2.Cu" "In3.Cu" "In4.Cu" "In5.Cu" "In6.Cu"
			"In7.Cu" "In8.Cu" "In9.Cu" "In10.Cu" "In11.Cu" "In12.Cu" "In13.Cu" "In14.Cu"
			"In15.Cu" "In16.Cu"
		)
		(hatch none 0.5)
		(connect_pads
			(clearance 0)
		)
		(min_thickness 0.25)
		(keepout
			(tracks not_allowed)
			(vias allowed)
			(pads allowed)
			(copperpour not_allowed)
			(footprints allowed)
		)
		(placement
			(enabled no)
			(sheetname "")
		)
		(fill
			(thermal_gap 0.5)
			(thermal_bridge_width 0.5)
			(island_removal_mode 0)
		)
		(polygon
			(pts
				(arc
					(start 55.452264 -409.649168)
					(mid 55.071264 -410.030168)
					(end 55.452264 -410.411168)
				)
				(arc
					(start 56.315864 -410.411168)
					(mid 56.696864 -410.030168)
					(end 56.315864 -409.649168)
				)
			)
		)
	)
	(zone
		(layers "F.Cu" "B.Cu" "In1.Cu" "In2.Cu" "In3.Cu" "In4.Cu" "In5.Cu" "In6.Cu"
			"In7.Cu" "In8.Cu" "In9.Cu" "In10.Cu" "In11.Cu" "In12.Cu" "In13.Cu" "In14.Cu"
			"In15.Cu" "In16.Cu"
		)
		(hatch none 0.5)
		(connect_pads
			(clearance 0)
		)
		(min_thickness 0.25)
		(keepout
			(tracks not_allowed)
			(vias allowed)
			(pads allowed)
			(copperpour not_allowed)
			(footprints allowed)
		)
		(placement
			(enabled no)
			(sheetname "")
		)
		(fill
			(thermal_gap 0.5)
			(thermal_bridge_width 0.5)
			(island_removal_mode 0)
		)
		(polygon
			(pts
				(arc
					(start 161.025332 -392.429238)
					(mid 160.644332 -392.048238)
					(end 160.263332 -392.429238)
				)
				(arc
					(start 160.263332 -393.292838)
					(mid 160.644332 -393.673838)
					(end 161.025332 -393.292838)
				)
			)
		)
	)
	(zone
		(layers "F.Cu" "B.Cu" "In1.Cu" "In2.Cu" "In3.Cu" "In4.Cu" "In5.Cu" "In6.Cu"
			"In7.Cu" "In8.Cu" "In9.Cu" "In10.Cu" "In11.Cu" "In12.Cu" "In13.Cu" "In14.Cu"
			"In15.Cu" "In16.Cu"
		)
		(hatch none 0.5)
		(connect_pads
			(clearance 0)
		)
		(min_thickness 0.25)
		(keepout
			(tracks not_allowed)
			(vias allowed)
			(pads allowed)
			(copperpour not_allowed)
			(footprints allowed)
		)
		(placement
			(enabled no)
			(sheetname "")
		)
		(fill yes
			(thermal_gap 0.5)
			(thermal_bridge_width 0.5)
			(island_removal_mode 0)
		)
		(polygon
			(pts
				(arc
					(start 119.836438 -386.170424)
					(mid 119.946409 -386.271478)
					(end 120.0912 -386.308092)
				)
				(arc
					(start 120.0912 -386.308092)
					(mid 120.306726 -386.218818)
					(end 120.396 -386.003292)
				)
				(arc
					(start 120.396 -386.003292)
					(mid 120.385663 -385.924553)
					(end 120.35536 -385.851146)
				)
				(arc
					(start 119.96293 -385.172204)
					(mid 119.850533 -385.050587)
					(end 119.69115 -385.00558)
				)
				(arc
					(start 119.69115 -385.00558)
					(mid 119.475624 -385.094854)
					(end 119.38635 -385.31038)
				)
				(arc
					(start 119.38635 -385.31038)
					(mid 119.395928 -385.386442)
					(end 119.424196 -385.4577)
				)
				(xy 119.821452 -386.145024) (xy 119.833644 -386.16636) (xy 119.836184 -386.170678)
			)
		)
	)
	(zone
		(layers "F.Cu" "B.Cu" "In1.Cu" "In2.Cu" "In3.Cu" "In4.Cu" "In5.Cu" "In6.Cu"
			"In7.Cu" "In8.Cu" "In9.Cu" "In10.Cu" "In11.Cu" "In12.Cu" "In13.Cu" "In14.Cu"
			"In15.Cu" "In16.Cu"
		)
		(hatch none 0.5)
		(connect_pads
			(clearance 0)
		)
		(min_thickness 0.25)
		(keepout
			(tracks not_allowed)
			(vias allowed)
			(pads allowed)
			(copperpour not_allowed)
			(footprints allowed)
		)
		(placement
			(enabled no)
			(sheetname "")
		)
		(fill
			(thermal_gap 0.5)
			(thermal_bridge_width 0.5)
			(island_removal_mode 0)
		)
		(polygon
			(pts
				(arc
					(start 142.463266 -404.08352)
					(mid 142.082266 -404.46452)
					(end 142.463266 -404.84552)
				)
				(arc
					(start 143.326866 -404.84552)
					(mid 143.707866 -404.46452)
					(end 143.326866 -404.08352)
				)
			)
		)
	)
	(zone
		(layers "F.Cu" "B.Cu" "In1.Cu" "In2.Cu" "In3.Cu" "In4.Cu" "In5.Cu" "In6.Cu"
			"In7.Cu" "In8.Cu" "In9.Cu" "In10.Cu" "In11.Cu" "In12.Cu" "In13.Cu" "In14.Cu"
			"In15.Cu" "In16.Cu"
		)
		(hatch none 0.5)
		(connect_pads
			(clearance 0)
		)
		(min_thickness 0.25)
		(keepout
			(tracks not_allowed)
			(vias allowed)
			(pads allowed)
			(copperpour not_allowed)
			(footprints allowed)
		)
		(placement
			(enabled no)
			(sheetname "")
		)
		(fill
			(thermal_gap 0.5)
			(thermal_bridge_width 0.5)
			(island_removal_mode 0)
		)
		(polygon
			(pts
				(arc
					(start 430.040288 -4.582414)
					(mid 429.659288 -4.963414)
					(end 430.040288 -5.344414)
				)
				(arc
					(start 430.903888 -5.344414)
					(mid 431.284888 -4.963414)
					(end 430.903888 -4.582414)
				)
			)
		)
	)
	(zone
		(layers "F.Cu" "B.Cu" "In1.Cu" "In2.Cu" "In3.Cu" "In4.Cu" "In5.Cu" "In6.Cu"
			"In7.Cu" "In8.Cu" "In9.Cu" "In10.Cu" "In11.Cu" "In12.Cu" "In13.Cu" "In14.Cu"
			"In15.Cu" "In16.Cu"
		)
		(hatch none 0.5)
		(connect_pads
			(clearance 0)
		)
		(min_thickness 0.25)
		(keepout
			(tracks not_allowed)
			(vias allowed)
			(pads allowed)
			(copperpour not_allowed)
			(footprints allowed)
		)
		(placement
			(enabled no)
			(sheetname "")
		)
		(fill
			(thermal_gap 0.5)
			(thermal_bridge_width 0.5)
			(island_removal_mode 0)
		)
		(polygon
			(pts
				(arc
					(start 411.02534 -400.811238)
					(mid 410.64434 -400.430238)
					(end 410.26334 -400.811238)
				)
				(arc
					(start 410.26334 -401.674838)
					(mid 410.64434 -402.055838)
					(end 411.02534 -401.674838)
				)
			)
		)
	)
	(zone
		(layers "F.Cu" "B.Cu" "In1.Cu" "In2.Cu" "In3.Cu" "In4.Cu" "In5.Cu" "In6.Cu"
			"In7.Cu" "In8.Cu" "In9.Cu" "In10.Cu" "In11.Cu" "In12.Cu" "In13.Cu" "In14.Cu"
			"In15.Cu" "In16.Cu"
		)
		(hatch none 0.5)
		(connect_pads
			(clearance 0)
		)
		(min_thickness 0.25)
		(keepout
			(tracks not_allowed)
			(vias allowed)
			(pads allowed)
			(copperpour not_allowed)
			(footprints allowed)
		)
		(placement
			(enabled no)
			(sheetname "")
		)
		(fill
			(thermal_gap 0.5)
			(thermal_bridge_width 0.5)
			(island_removal_mode 0)
		)
		(polygon
			(pts
				(arc
					(start 371.036596 -398.016476)
					(mid 371.146567 -398.11753)
					(end 371.291358 -398.154144)
				)
				(arc
					(start 371.291358 -398.154144)
					(mid 371.506884 -398.06487)
					(end 371.596158 -397.849344)
				)
				(arc
					(start 371.596158 -397.849344)
					(mid 371.585821 -397.770605)
					(end 371.555518 -397.697198)
				)
				(arc
					(start 371.163088 -397.018256)
					(mid 371.050691 -396.896639)
					(end 370.891308 -396.851632)
				)
				(arc
					(start 370.891308 -396.851632)
					(mid 370.675782 -396.940906)
					(end 370.586508 -397.156432)
				)
				(arc
					(start 370.586508 -397.156432)
					(mid 370.596086 -397.232494)
					(end 370.624354 -397.303752)
				)
				(xy 371.02161 -397.991076) (xy 371.033802 -398.012412) (xy 371.036342 -398.01673)
			)
		)
	)
	(zone
		(layers "F.Cu" "B.Cu" "In1.Cu" "In2.Cu" "In3.Cu" "In4.Cu" "In5.Cu" "In6.Cu"
			"In7.Cu" "In8.Cu" "In9.Cu" "In10.Cu" "In11.Cu" "In12.Cu" "In13.Cu" "In14.Cu"
			"In15.Cu" "In16.Cu"
		)
		(hatch none 0.5)
		(connect_pads
			(clearance 0)
		)
		(min_thickness 0.25)
		(keepout
			(tracks not_allowed)
			(vias allowed)
			(pads allowed)
			(copperpour not_allowed)
			(footprints allowed)
		)
		(placement
			(enabled no)
			(sheetname "")
		)
		(fill
			(thermal_gap 0.5)
			(thermal_bridge_width 0.5)
			(island_removal_mode 0)
		)
		(polygon
			(pts
				(arc
					(start 86.084664 -409.649168)
					(mid 85.703664 -410.030168)
					(end 86.084664 -410.411168)
				)
				(arc
					(start 86.948264 -410.411168)
					(mid 87.329264 -410.030168)
					(end 86.948264 -409.649168)
				)
			)
		)
	)
	(zone
		(layers "F.Cu" "B.Cu" "In1.Cu" "In2.Cu" "In3.Cu" "In4.Cu" "In5.Cu" "In6.Cu"
			"In7.Cu" "In8.Cu" "In9.Cu" "In10.Cu" "In11.Cu" "In12.Cu" "In13.Cu" "In14.Cu"
			"In15.Cu" "In16.Cu"
		)
		(hatch none 0.5)
		(connect_pads
			(clearance 0)
		)
		(min_thickness 0.25)
		(keepout
			(tracks not_allowed)
			(vias allowed)
			(pads allowed)
			(copperpour not_allowed)
			(footprints allowed)
		)
		(placement
			(enabled no)
			(sheetname "")
		)
		(fill
			(thermal_gap 0.5)
			(thermal_bridge_width 0.5)
			(island_removal_mode 0)
		)
		(polygon
			(pts
				(arc
					(start 108.911644 -381.50546)
					(mid 108.530644 -381.12446)
					(end 108.149644 -381.50546)
				)
				(arc
					(start 108.149644 -382.36906)
					(mid 108.530644 -382.75006)
					(end 108.911644 -382.36906)
				)
			)
		)
	)
	(zone
		(layers "F.Cu" "B.Cu" "In1.Cu" "In2.Cu" "In3.Cu" "In4.Cu" "In5.Cu" "In6.Cu"
			"In7.Cu" "In8.Cu" "In9.Cu" "In10.Cu" "In11.Cu" "In12.Cu" "In13.Cu" "In14.Cu"
			"In15.Cu" "In16.Cu"
		)
		(hatch none 0.5)
		(connect_pads
			(clearance 0)
		)
		(min_thickness 0.25)
		(keepout
			(tracks not_allowed)
			(vias allowed)
			(pads allowed)
			(copperpour not_allowed)
			(footprints allowed)
		)
		(placement
			(enabled no)
			(sheetname "")
		)
		(fill
			(thermal_gap 0.5)
			(thermal_bridge_width 0.5)
			(island_removal_mode 0)
		)
		(polygon
			(pts
				(arc
					(start 303.793906 -412.46552)
					(mid 303.412906 -412.84652)
					(end 303.793906 -413.22752)
				)
				(arc
					(start 304.657506 -413.22752)
					(mid 305.038506 -412.84652)
					(end 304.657506 -412.46552)
				)
			)
		)
	)
	(zone
		(layers "F.Cu" "B.Cu" "In1.Cu" "In2.Cu" "In3.Cu" "In4.Cu" "In5.Cu" "In6.Cu"
			"In7.Cu" "In8.Cu" "In9.Cu" "In10.Cu" "In11.Cu" "In12.Cu" "In13.Cu" "In14.Cu"
			"In15.Cu" "In16.Cu"
		)
		(hatch none 0.5)
		(connect_pads
			(clearance 0)
		)
		(min_thickness 0.25)
		(keepout
			(tracks not_allowed)
			(vias allowed)
			(pads allowed)
			(copperpour not_allowed)
			(footprints allowed)
		)
		(placement
			(enabled no)
			(sheetname "")
		)
		(fill
			(thermal_gap 0.5)
			(thermal_bridge_width 0.5)
			(island_removal_mode 0)
		)
		(polygon
			(pts
				(arc
					(start 136.336786 -404.08352)
					(mid 135.955786 -404.46452)
					(end 136.336786 -404.84552)
				)
				(arc
					(start 137.200386 -404.84552)
					(mid 137.581386 -404.46452)
					(end 137.200386 -404.08352)
				)
			)
		)
	)
	(zone
		(layers "F.Cu" "B.Cu" "In1.Cu" "In2.Cu" "In3.Cu" "In4.Cu" "In5.Cu" "In6.Cu"
			"In7.Cu" "In8.Cu" "In9.Cu" "In10.Cu" "In11.Cu" "In12.Cu" "In13.Cu" "In14.Cu"
			"In15.Cu" "In16.Cu"
		)
		(hatch none 0.5)
		(connect_pads
			(clearance 0)
		)
		(min_thickness 0.25)
		(keepout
			(tracks not_allowed)
			(vias allowed)
			(pads allowed)
			(copperpour not_allowed)
			(footprints allowed)
		)
		(placement
			(enabled no)
			(sheetname "")
		)
		(fill
			(thermal_gap 0.5)
			(thermal_bridge_width 0.5)
			(island_removal_mode 0)
		)
		(polygon
			(pts
				(arc
					(start 343.616026 -412.46552)
					(mid 343.235026 -412.84652)
					(end 343.616026 -413.22752)
				)
				(arc
					(start 344.479626 -413.22752)
					(mid 344.860626 -412.84652)
					(end 344.479626 -412.46552)
				)
			)
		)
	)
	(zone
		(layers "F.Cu" "B.Cu" "In1.Cu" "In2.Cu" "In3.Cu" "In4.Cu" "In5.Cu" "In6.Cu"
			"In7.Cu" "In8.Cu" "In9.Cu" "In10.Cu" "In11.Cu" "In12.Cu" "In13.Cu" "In14.Cu"
			"In15.Cu" "In16.Cu"
		)
		(hatch none 0.5)
		(connect_pads
			(clearance 0)
		)
		(min_thickness 0.25)
		(keepout
			(tracks not_allowed)
			(vias allowed)
			(pads allowed)
			(copperpour not_allowed)
			(footprints allowed)
		)
		(placement
			(enabled no)
			(sheetname "")
		)
		(fill yes
			(thermal_gap 0.5)
			(thermal_bridge_width 0.5)
			(island_removal_mode 0)
		)
		(polygon
			(pts
				(arc
					(start 49.136554 -386.170424)
					(mid 49.246525 -386.271478)
					(end 49.391316 -386.308092)
				)
				(arc
					(start 49.391316 -386.308092)
					(mid 49.606842 -386.218818)
					(end 49.696116 -386.003292)
				)
				(arc
					(start 49.696116 -386.003292)
					(mid 49.685779 -385.924553)
					(end 49.655476 -385.851146)
				)
				(arc
					(start 49.263046 -385.172204)
					(mid 49.150649 -385.050587)
					(end 48.991266 -385.00558)
				)
				(arc
					(start 48.991266 -385.00558)
					(mid 48.77574 -385.094854)
					(end 48.686466 -385.31038)
				)
				(arc
					(start 48.686466 -385.31038)
					(mid 48.696044 -385.386442)
					(end 48.724312 -385.4577)
				)
				(xy 49.121568 -386.145024) (xy 49.13376 -386.16636) (xy 49.1363 -386.170678)
			)
		)
	)
	(zone
		(layers "F.Cu" "B.Cu" "In1.Cu" "In2.Cu" "In3.Cu" "In4.Cu" "In5.Cu" "In6.Cu"
			"In7.Cu" "In8.Cu" "In9.Cu" "In10.Cu" "In11.Cu" "In12.Cu" "In13.Cu" "In14.Cu"
			"In15.Cu" "In16.Cu"
		)
		(hatch none 0.5)
		(connect_pads
			(clearance 0)
		)
		(min_thickness 0.25)
		(keepout
			(tracks not_allowed)
			(vias allowed)
			(pads allowed)
			(copperpour not_allowed)
			(footprints allowed)
		)
		(placement
			(enabled no)
			(sheetname "")
		)
		(fill
			(thermal_gap 0.5)
			(thermal_bridge_width 0.5)
			(island_removal_mode 0)
		)
		(polygon
			(pts
				(arc
					(start 432.283616 -18.75536)
					(mid 431.902616 -19.13636)
					(end 432.283616 -19.51736)
				)
				(arc
					(start 433.147216 -19.51736)
					(mid 433.528216 -19.13636)
					(end 433.147216 -18.75536)
				)
			)
		)
	)
	(zone
		(layers "F.Cu" "B.Cu" "In1.Cu" "In2.Cu" "In3.Cu" "In4.Cu" "In5.Cu" "In6.Cu"
			"In7.Cu" "In8.Cu" "In9.Cu" "In10.Cu" "In11.Cu" "In12.Cu" "In13.Cu" "In14.Cu"
			"In15.Cu" "In16.Cu"
		)
		(hatch none 0.5)
		(connect_pads
			(clearance 0)
		)
		(min_thickness 0.25)
		(keepout
			(tracks not_allowed)
			(vias allowed)
			(pads allowed)
			(copperpour not_allowed)
			(footprints allowed)
		)
		(placement
			(enabled no)
			(sheetname "")
		)
		(fill
			(thermal_gap 0.5)
			(thermal_bridge_width 0.5)
			(island_removal_mode 0)
		)
		(polygon
			(pts
				(arc
					(start 388.097522 -400.811238)
					(mid 387.716522 -400.430238)
					(end 387.335522 -400.811238)
				)
				(arc
					(start 387.335522 -401.674838)
					(mid 387.716522 -402.055838)
					(end 388.097522 -401.674838)
				)
			)
		)
	)
	(zone
		(layers "F.Cu" "B.Cu" "In1.Cu" "In2.Cu" "In3.Cu" "In4.Cu" "In5.Cu" "In6.Cu"
			"In7.Cu" "In8.Cu" "In9.Cu" "In10.Cu" "In11.Cu" "In12.Cu" "In13.Cu" "In14.Cu"
			"In15.Cu" "In16.Cu"
		)
		(hatch none 0.5)
		(connect_pads
			(clearance 0)
		)
		(min_thickness 0.25)
		(keepout
			(tracks not_allowed)
			(vias allowed)
			(pads allowed)
			(copperpour not_allowed)
			(footprints allowed)
		)
		(placement
			(enabled no)
			(sheetname "")
		)
		(fill
			(thermal_gap 0.5)
			(thermal_bridge_width 0.5)
			(island_removal_mode 0)
		)
		(polygon
			(pts
				(arc
					(start 322.197222 -400.811238)
					(mid 321.816222 -400.430238)
					(end 321.435222 -400.811238)
				)
				(arc
					(start 321.435222 -401.674838)
					(mid 321.816222 -402.055838)
					(end 322.197222 -401.674838)
				)
			)
		)
	)
	(zone
		(layers "F.Cu" "B.Cu" "In1.Cu" "In2.Cu" "In3.Cu" "In4.Cu" "In5.Cu" "In6.Cu"
			"In7.Cu" "In8.Cu" "In9.Cu" "In10.Cu" "In11.Cu" "In12.Cu" "In13.Cu" "In14.Cu"
			"In15.Cu" "In16.Cu"
		)
		(hatch none 0.5)
		(connect_pads
			(clearance 0)
		)
		(min_thickness 0.25)
		(keepout
			(tracks not_allowed)
			(vias allowed)
			(pads allowed)
			(copperpour not_allowed)
			(footprints allowed)
		)
		(placement
			(enabled no)
			(sheetname "")
		)
		(fill yes
			(thermal_gap 0.5)
			(thermal_bridge_width 0.5)
			(island_removal_mode 0)
		)
		(polygon
			(pts
				(arc
					(start 56.336438 -386.170424)
					(mid 56.446409 -386.271478)
					(end 56.5912 -386.308092)
				)
				(arc
					(start 56.5912 -386.308092)
					(mid 56.806726 -386.218818)
					(end 56.896 -386.003292)
				)
				(arc
					(start 56.896 -386.003292)
					(mid 56.885663 -385.924553)
					(end 56.85536 -385.851146)
				)
				(arc
					(start 56.46293 -385.172204)
					(mid 56.350533 -385.050587)
					(end 56.19115 -385.00558)
				)
				(arc
					(start 56.19115 -385.00558)
					(mid 55.975624 -385.094854)
					(end 55.88635 -385.31038)
				)
				(arc
					(start 55.88635 -385.31038)
					(mid 55.895928 -385.386442)
					(end 55.924196 -385.4577)
				)
				(xy 56.321452 -386.145024) (xy 56.333644 -386.16636) (xy 56.336184 -386.170678)
			)
		)
	)
	(zone
		(layers "F.Cu" "B.Cu" "In1.Cu" "In2.Cu" "In3.Cu" "In4.Cu" "In5.Cu" "In6.Cu"
			"In7.Cu" "In8.Cu" "In9.Cu" "In10.Cu" "In11.Cu" "In12.Cu" "In13.Cu" "In14.Cu"
			"In15.Cu" "In16.Cu"
		)
		(hatch none 0.5)
		(connect_pads
			(clearance 0)
		)
		(min_thickness 0.25)
		(keepout
			(tracks not_allowed)
			(vias allowed)
			(pads allowed)
			(copperpour not_allowed)
			(footprints allowed)
		)
		(placement
			(enabled no)
			(sheetname "")
		)
		(fill yes
			(thermal_gap 0.5)
			(thermal_bridge_width 0.5)
			(island_removal_mode 0)
		)
		(polygon
			(pts
				(arc
					(start 164.364162 -386.170424)
					(mid 164.474133 -386.271478)
					(end 164.618924 -386.308092)
				)
				(arc
					(start 164.618924 -386.308092)
					(mid 164.83445 -386.218818)
					(end 164.923724 -386.003292)
				)
				(arc
					(start 164.923724 -386.003292)
					(mid 164.913387 -385.924553)
					(end 164.883084 -385.851146)
				)
				(arc
					(start 164.490654 -385.172204)
					(mid 164.378257 -385.050587)
					(end 164.218874 -385.00558)
				)
				(arc
					(start 164.218874 -385.00558)
					(mid 164.003348 -385.094854)
					(end 163.914074 -385.31038)
				)
				(arc
					(start 163.914074 -385.31038)
					(mid 163.923652 -385.386442)
					(end 163.95192 -385.4577)
				)
				(xy 164.349176 -386.145024) (xy 164.361368 -386.16636) (xy 164.363908 -386.170678)
			)
		)
	)
	(zone
		(layers "F.Cu" "B.Cu" "In1.Cu" "In2.Cu" "In3.Cu" "In4.Cu" "In5.Cu" "In6.Cu"
			"In7.Cu" "In8.Cu" "In9.Cu" "In10.Cu" "In11.Cu" "In12.Cu" "In13.Cu" "In14.Cu"
			"In15.Cu" "In16.Cu"
		)
		(hatch none 0.5)
		(connect_pads
			(clearance 0)
		)
		(min_thickness 0.25)
		(keepout
			(tracks not_allowed)
			(vias allowed)
			(pads allowed)
			(copperpour not_allowed)
			(footprints allowed)
		)
		(placement
			(enabled no)
			(sheetname "")
		)
		(fill
			(thermal_gap 0.5)
			(thermal_bridge_width 0.5)
			(island_removal_mode 0)
		)
		(polygon
			(pts
				(arc
					(start 340.552786 -412.46552)
					(mid 340.171786 -412.84652)
					(end 340.552786 -413.22752)
				)
				(arc
					(start 341.416386 -413.22752)
					(mid 341.797386 -412.84652)
					(end 341.416386 -412.46552)
				)
			)
		)
	)
	(zone
		(layers "F.Cu" "B.Cu" "In1.Cu" "In2.Cu" "In3.Cu" "In4.Cu" "In5.Cu" "In6.Cu"
			"In7.Cu" "In8.Cu" "In9.Cu" "In10.Cu" "In11.Cu" "In12.Cu" "In13.Cu" "In14.Cu"
			"In15.Cu" "In16.Cu"
		)
		(hatch none 0.5)
		(connect_pads
			(clearance 0)
		)
		(min_thickness 0.25)
		(keepout
			(tracks not_allowed)
			(vias allowed)
			(pads allowed)
			(copperpour not_allowed)
			(footprints allowed)
		)
		(placement
			(enabled no)
			(sheetname "")
		)
		(fill
			(thermal_gap 0.5)
			(thermal_bridge_width 0.5)
			(island_removal_mode 0)
		)
		(polygon
			(pts
				(arc
					(start 387.741922 -418.031168)
					(mid 387.360922 -418.412168)
					(end 387.741922 -418.793168)
				)
				(arc
					(start 388.605522 -418.793168)
					(mid 388.986522 -418.412168)
					(end 388.605522 -418.031168)
				)
			)
		)
	)
	(zone
		(layers "F.Cu" "B.Cu" "In1.Cu" "In2.Cu" "In3.Cu" "In4.Cu" "In5.Cu" "In6.Cu"
			"In7.Cu" "In8.Cu" "In9.Cu" "In10.Cu" "In11.Cu" "In12.Cu" "In13.Cu" "In14.Cu"
			"In15.Cu" "In16.Cu"
		)
		(hatch none 0.5)
		(connect_pads
			(clearance 0)
		)
		(min_thickness 0.25)
		(keepout
			(tracks not_allowed)
			(vias allowed)
			(pads allowed)
			(copperpour not_allowed)
			(footprints allowed)
		)
		(placement
			(enabled no)
			(sheetname "")
		)
		(fill
			(thermal_gap 0.5)
			(thermal_bridge_width 0.5)
			(island_removal_mode 0)
		)
		(polygon
			(pts
				(arc
					(start 327.658476 -387.878828)
					(mid 327.277476 -387.497828)
					(end 326.896476 -387.878828)
				)
				(arc
					(start 326.896476 -388.742428)
					(mid 327.277476 -389.123428)
					(end 327.658476 -388.742428)
				)
			)
		)
	)
	(zone
		(layers "F.Cu" "B.Cu" "In1.Cu" "In2.Cu" "In3.Cu" "In4.Cu" "In5.Cu" "In6.Cu"
			"In7.Cu" "In8.Cu" "In9.Cu" "In10.Cu" "In11.Cu" "In12.Cu" "In13.Cu" "In14.Cu"
			"In15.Cu" "In16.Cu"
		)
		(hatch none 0.5)
		(connect_pads
			(clearance 0)
		)
		(min_thickness 0.25)
		(keepout
			(tracks not_allowed)
			(vias allowed)
			(pads allowed)
			(copperpour not_allowed)
			(footprints allowed)
		)
		(placement
			(enabled no)
			(sheetname "")
		)
		(fill
			(thermal_gap 0.5)
			(thermal_bridge_width 0.5)
			(island_removal_mode 0)
		)
		(polygon
			(pts
				(arc
					(start 178.630834 -52.481734)
					(mid 179.011834 -52.862734)
					(end 179.392834 -52.481734)
				)
				(arc
					(start 179.392834 -51.618134)
					(mid 179.011834 -51.237134)
					(end 178.630834 -51.618134)
				)
			)
		)
	)
	(zone
		(layers "F.Cu" "B.Cu" "In1.Cu" "In2.Cu" "In3.Cu" "In4.Cu" "In5.Cu" "In6.Cu"
			"In7.Cu" "In8.Cu" "In9.Cu" "In10.Cu" "In11.Cu" "In12.Cu" "In13.Cu" "In14.Cu"
			"In15.Cu" "In16.Cu"
		)
		(hatch none 0.5)
		(connect_pads
			(clearance 0)
		)
		(min_thickness 0.25)
		(keepout
			(tracks not_allowed)
			(vias allowed)
			(pads allowed)
			(copperpour not_allowed)
			(footprints allowed)
		)
		(placement
			(enabled no)
			(sheetname "")
		)
		(fill
			(thermal_gap 0.5)
			(thermal_bridge_width 0.5)
			(island_removal_mode 0)
		)
		(polygon
			(pts
				(arc
					(start 133.297422 -392.429238)
					(mid 132.916422 -392.048238)
					(end 132.535422 -392.429238)
				)
				(arc
					(start 132.535422 -393.292838)
					(mid 132.916422 -393.673838)
					(end 133.297422 -393.292838)
				)
			)
		)
	)
	(zone
		(layers "F.Cu" "B.Cu" "In1.Cu" "In2.Cu" "In3.Cu" "In4.Cu" "In5.Cu" "In6.Cu"
			"In7.Cu" "In8.Cu" "In9.Cu" "In10.Cu" "In11.Cu" "In12.Cu" "In13.Cu" "In14.Cu"
			"In15.Cu" "In16.Cu"
		)
		(hatch none 0.5)
		(connect_pads
			(clearance 0)
		)
		(min_thickness 0.25)
		(keepout
			(tracks not_allowed)
			(vias allowed)
			(pads allowed)
			(copperpour not_allowed)
			(footprints allowed)
		)
		(placement
			(enabled no)
			(sheetname "")
		)
		(fill
			(thermal_gap 0.5)
			(thermal_bridge_width 0.5)
			(island_removal_mode 0)
		)
		(polygon
			(pts
				(arc
					(start 153.825194 -392.429238)
					(mid 153.444194 -392.048238)
					(end 153.063194 -392.429238)
				)
				(arc
					(start 153.063194 -393.292838)
					(mid 153.444194 -393.673838)
					(end 153.825194 -393.292838)
				)
			)
		)
	)
	(zone
		(layers "F.Cu" "B.Cu" "In1.Cu" "In2.Cu" "In3.Cu" "In4.Cu" "In5.Cu" "In6.Cu"
			"In7.Cu" "In8.Cu" "In9.Cu" "In10.Cu" "In11.Cu" "In12.Cu" "In13.Cu" "In14.Cu"
			"In15.Cu" "In16.Cu"
		)
		(hatch none 0.5)
		(connect_pads
			(clearance 0)
		)
		(min_thickness 0.25)
		(keepout
			(tracks not_allowed)
			(vias allowed)
			(pads allowed)
			(copperpour not_allowed)
			(footprints allowed)
		)
		(placement
			(enabled no)
			(sheetname "")
		)
		(fill
			(thermal_gap 0.5)
			(thermal_bridge_width 0.5)
			(island_removal_mode 0)
		)
		(polygon
			(pts
				(arc
					(start 336.725006 -400.811238)
					(mid 336.344006 -400.430238)
					(end 335.963006 -400.811238)
				)
				(arc
					(start 335.963006 -401.674838)
					(mid 336.344006 -402.055838)
					(end 336.725006 -401.674838)
				)
			)
		)
	)
	(zone
		(layers "F.Cu" "B.Cu" "In1.Cu" "In2.Cu" "In3.Cu" "In4.Cu" "In5.Cu" "In6.Cu"
			"In7.Cu" "In8.Cu" "In9.Cu" "In10.Cu" "In11.Cu" "In12.Cu" "In13.Cu" "In14.Cu"
			"In15.Cu" "In16.Cu"
		)
		(hatch none 0.5)
		(connect_pads
			(clearance 0)
		)
		(min_thickness 0.25)
		(keepout
			(tracks not_allowed)
			(vias allowed)
			(pads allowed)
			(copperpour not_allowed)
			(footprints allowed)
		)
		(placement
			(enabled no)
			(sheetname "")
		)
		(fill
			(thermal_gap 0.5)
			(thermal_bridge_width 0.5)
			(island_removal_mode 0)
		)
		(polygon
			(pts
				(arc
					(start 133.273546 -412.189168)
					(mid 132.892546 -412.570168)
					(end 133.273546 -412.951168)
				)
				(arc
					(start 134.137146 -412.951168)
					(mid 134.518146 -412.570168)
					(end 134.137146 -412.189168)
				)
			)
		)
	)
	(zone
		(layers "F.Cu" "B.Cu" "In1.Cu" "In2.Cu" "In3.Cu" "In4.Cu" "In5.Cu" "In6.Cu"
			"In7.Cu" "In8.Cu" "In9.Cu" "In10.Cu" "In11.Cu" "In12.Cu" "In13.Cu" "In14.Cu"
			"In15.Cu" "In16.Cu"
		)
		(hatch none 0.5)
		(connect_pads
			(clearance 0)
		)
		(min_thickness 0.25)
		(keepout
			(tracks not_allowed)
			(vias allowed)
			(pads allowed)
			(copperpour not_allowed)
			(footprints allowed)
		)
		(placement
			(enabled no)
			(sheetname "")
		)
		(fill
			(thermal_gap 0.5)
			(thermal_bridge_width 0.5)
			(island_removal_mode 0)
		)
		(polygon
			(pts
				(arc
					(start 160.842706 -412.189168)
					(mid 160.461706 -412.570168)
					(end 160.842706 -412.951168)
				)
				(arc
					(start 161.706306 -412.951168)
					(mid 162.087306 -412.570168)
					(end 161.706306 -412.189168)
				)
			)
		)
	)
	(zone
		(layers "F.Cu" "B.Cu" "In1.Cu" "In2.Cu" "In3.Cu" "In4.Cu" "In5.Cu" "In6.Cu"
			"In7.Cu" "In8.Cu" "In9.Cu" "In10.Cu" "In11.Cu" "In12.Cu" "In13.Cu" "In14.Cu"
			"In15.Cu" "In16.Cu"
		)
		(hatch none 0.5)
		(connect_pads
			(clearance 0)
		)
		(min_thickness 0.25)
		(keepout
			(tracks not_allowed)
			(vias allowed)
			(pads allowed)
			(copperpour not_allowed)
			(footprints allowed)
		)
		(placement
			(enabled no)
			(sheetname "")
		)
		(fill yes
			(thermal_gap 0.5)
			(thermal_bridge_width 0.5)
			(island_removal_mode 0)
		)
		(polygon
			(pts
				(arc
					(start 152.364186 -386.170424)
					(mid 152.474157 -386.271478)
					(end 152.618948 -386.308092)
				)
				(arc
					(start 152.618948 -386.308092)
					(mid 152.834474 -386.218818)
					(end 152.923748 -386.003292)
				)
				(arc
					(start 152.923748 -386.003292)
					(mid 152.913411 -385.924553)
					(end 152.883108 -385.851146)
				)
				(arc
					(start 152.490678 -385.172204)
					(mid 152.378281 -385.050587)
					(end 152.218898 -385.00558)
				)
				(arc
					(start 152.218898 -385.00558)
					(mid 152.003372 -385.094854)
					(end 151.914098 -385.31038)
				)
				(arc
					(start 151.914098 -385.31038)
					(mid 151.923676 -385.386442)
					(end 151.951944 -385.4577)
				)
				(xy 152.3492 -386.145024) (xy 152.361392 -386.16636) (xy 152.363932 -386.170678)
			)
		)
	)
	(zone
		(layers "F.Cu" "B.Cu" "In1.Cu" "In2.Cu" "In3.Cu" "In4.Cu" "In5.Cu" "In6.Cu"
			"In7.Cu" "In8.Cu" "In9.Cu" "In10.Cu" "In11.Cu" "In12.Cu" "In13.Cu" "In14.Cu"
			"In15.Cu" "In16.Cu"
		)
		(hatch none 0.5)
		(connect_pads
			(clearance 0)
		)
		(min_thickness 0.25)
		(keepout
			(tracks not_allowed)
			(vias allowed)
			(pads allowed)
			(copperpour not_allowed)
			(footprints allowed)
		)
		(placement
			(enabled no)
			(sheetname "")
		)
		(fill
			(thermal_gap 0.5)
			(thermal_bridge_width 0.5)
			(island_removal_mode 0)
		)
		(polygon
			(pts
				(arc
					(start 373.6975 -400.811238)
					(mid 373.3165 -400.430238)
					(end 372.9355 -400.811238)
				)
				(arc
					(start 372.9355 -401.674838)
					(mid 373.3165 -402.055838)
					(end 373.6975 -401.674838)
				)
			)
		)
	)
	(zone
		(layers "F.Cu" "B.Cu" "In1.Cu" "In2.Cu" "In3.Cu" "In4.Cu" "In5.Cu" "In6.Cu"
			"In7.Cu" "In8.Cu" "In9.Cu" "In10.Cu" "In11.Cu" "In12.Cu" "In13.Cu" "In14.Cu"
			"In15.Cu" "In16.Cu"
		)
		(hatch none 0.5)
		(connect_pads
			(clearance 0)
		)
		(min_thickness 0.25)
		(keepout
			(tracks not_allowed)
			(vias allowed)
			(pads allowed)
			(copperpour not_allowed)
			(footprints allowed)
		)
		(placement
			(enabled no)
			(sheetname "")
		)
		(fill
			(thermal_gap 0.5)
			(thermal_bridge_width 0.5)
			(island_removal_mode 0)
		)
		(polygon
			(pts
				(arc
					(start 45.57014 -404.789894)
					(mid 41.570148 -408.789886)
					(end 37.570156 -404.789894)
				)
				(arc
					(start 37.570156 -404.789894)
					(mid 41.570148 -400.789902)
					(end 45.57014 -404.789894)
				)
			)
		)
	)
	(zone
		(layers "F.Cu" "B.Cu" "In1.Cu" "In2.Cu" "In3.Cu" "In4.Cu" "In5.Cu" "In6.Cu"
			"In7.Cu" "In8.Cu" "In9.Cu" "In10.Cu" "In11.Cu" "In12.Cu" "In13.Cu" "In14.Cu"
			"In15.Cu" "In16.Cu"
		)
		(hatch none 0.5)
		(connect_pads
			(clearance 0)
		)
		(min_thickness 0.25)
		(keepout
			(tracks not_allowed)
			(vias allowed)
			(pads allowed)
			(copperpour not_allowed)
			(footprints allowed)
		)
		(placement
			(enabled no)
			(sheetname "")
		)
		(fill yes
			(thermal_gap 0.5)
			(thermal_bridge_width 0.5)
			(island_removal_mode 0)
		)
		(polygon
			(pts
				(arc
					(start 91.264232 -386.170424)
					(mid 91.374203 -386.271478)
					(end 91.518994 -386.308092)
				)
				(arc
					(start 91.518994 -386.308092)
					(mid 91.73452 -386.218818)
					(end 91.823794 -386.003292)
				)
				(arc
					(start 91.823794 -386.003292)
					(mid 91.813457 -385.924553)
					(end 91.783154 -385.851146)
				)
				(arc
					(start 91.390724 -385.172204)
					(mid 91.278327 -385.050587)
					(end 91.118944 -385.00558)
				)
				(arc
					(start 91.118944 -385.00558)
					(mid 90.903418 -385.094854)
					(end 90.814144 -385.31038)
				)
				(arc
					(start 90.814144 -385.31038)
					(mid 90.823722 -385.386442)
					(end 90.85199 -385.4577)
				)
				(xy 91.249246 -386.145024) (xy 91.261438 -386.16636) (xy 91.263978 -386.170678)
			)
		)
	)
	(zone
		(layers "F.Cu" "B.Cu" "In1.Cu" "In2.Cu" "In3.Cu" "In4.Cu" "In5.Cu" "In6.Cu"
			"In7.Cu" "In8.Cu" "In9.Cu" "In10.Cu" "In11.Cu" "In12.Cu" "In13.Cu" "In14.Cu"
			"In15.Cu" "In16.Cu"
		)
		(hatch none 0.5)
		(connect_pads
			(clearance 0)
		)
		(min_thickness 0.25)
		(keepout
			(tracks not_allowed)
			(vias allowed)
			(pads allowed)
			(copperpour not_allowed)
			(footprints allowed)
		)
		(placement
			(enabled no)
			(sheetname "")
		)
		(fill
			(thermal_gap 0.5)
			(thermal_bridge_width 0.5)
			(island_removal_mode 0)
		)
		(polygon
			(pts
				(arc
					(start 53.920644 -412.189168)
					(mid 53.539644 -412.570168)
					(end 53.920644 -412.951168)
				)
				(arc
					(start 54.784244 -412.951168)
					(mid 55.165244 -412.570168)
					(end 54.784244 -412.189168)
				)
			)
		)
	)
	(zone
		(layers "F.Cu" "B.Cu" "In1.Cu" "In2.Cu" "In3.Cu" "In4.Cu" "In5.Cu" "In6.Cu"
			"In7.Cu" "In8.Cu" "In9.Cu" "In10.Cu" "In11.Cu" "In12.Cu" "In13.Cu" "In14.Cu"
			"In15.Cu" "In16.Cu"
		)
		(hatch none 0.5)
		(connect_pads
			(clearance 0)
		)
		(min_thickness 0.25)
		(keepout
			(tracks not_allowed)
			(vias allowed)
			(pads allowed)
			(copperpour not_allowed)
			(footprints allowed)
		)
		(placement
			(enabled no)
			(sheetname "")
		)
		(fill
			(thermal_gap 0.5)
			(thermal_bridge_width 0.5)
			(island_removal_mode 0)
		)
		(polygon
			(pts
				(arc
					(start 42.415714 -422.194228)
					(mid 42.034714 -421.813228)
					(end 41.653714 -422.194228)
				)
				(arc
					(start 41.653714 -423.057828)
					(mid 42.034714 -423.438828)
					(end 42.415714 -423.057828)
				)
			)
		)
	)
	(zone
		(layers "F.Cu" "B.Cu" "In1.Cu" "In2.Cu" "In3.Cu" "In4.Cu" "In5.Cu" "In6.Cu"
			"In7.Cu" "In8.Cu" "In9.Cu" "In10.Cu" "In11.Cu" "In12.Cu" "In13.Cu" "In14.Cu"
			"In15.Cu" "In16.Cu"
		)
		(hatch none 0.5)
		(connect_pads
			(clearance 0)
		)
		(min_thickness 0.25)
		(keepout
			(tracks not_allowed)
			(vias allowed)
			(pads allowed)
			(copperpour not_allowed)
			(footprints allowed)
		)
		(placement
			(enabled no)
			(sheetname "")
		)
		(fill
			(thermal_gap 0.5)
			(thermal_bridge_width 0.5)
			(island_removal_mode 0)
		)
		(polygon
			(pts
				(arc
					(start 183.95442 3.092196)
					(mid 184.38622 2.660396)
					(end 184.81802 3.092196)
				)
				(arc
					(start 184.81802 3.955796)
					(mid 184.38622 4.387596)
					(end 183.95442 3.955796)
				)
			)
		)
	)
	(zone
		(layers "F.Cu" "B.Cu" "In1.Cu" "In2.Cu" "In3.Cu" "In4.Cu" "In5.Cu" "In6.Cu"
			"In7.Cu" "In8.Cu" "In9.Cu" "In10.Cu" "In11.Cu" "In12.Cu" "In13.Cu" "In14.Cu"
			"In15.Cu" "In16.Cu"
		)
		(hatch none 0.5)
		(connect_pads
			(clearance 0)
		)
		(min_thickness 0.25)
		(keepout
			(tracks not_allowed)
			(vias allowed)
			(pads allowed)
			(copperpour not_allowed)
			(footprints allowed)
		)
		(placement
			(enabled no)
			(sheetname "")
		)
		(fill yes
			(thermal_gap 0.5)
			(thermal_bridge_width 0.5)
			(island_removal_mode 0)
		)
		(polygon
			(pts
				(arc
					(start 163.164266 -386.170424)
					(mid 163.274237 -386.271478)
					(end 163.419028 -386.308092)
				)
				(arc
					(start 163.419028 -386.308092)
					(mid 163.634554 -386.218818)
					(end 163.723828 -386.003292)
				)
				(arc
					(start 163.723828 -386.003292)
					(mid 163.713491 -385.924553)
					(end 163.683188 -385.851146)
				)
				(arc
					(start 163.290758 -385.172204)
					(mid 163.178361 -385.050587)
					(end 163.018978 -385.00558)
				)
				(arc
					(start 163.018978 -385.00558)
					(mid 162.803452 -385.094854)
					(end 162.714178 -385.31038)
				)
				(arc
					(start 162.714178 -385.31038)
					(mid 162.723756 -385.386442)
					(end 162.752024 -385.4577)
				)
				(xy 163.14928 -386.145024) (xy 163.161472 -386.16636) (xy 163.164012 -386.170678)
			)
		)
	)
	(zone
		(layers "F.Cu" "B.Cu" "In1.Cu" "In2.Cu" "In3.Cu" "In4.Cu" "In5.Cu" "In6.Cu"
			"In7.Cu" "In8.Cu" "In9.Cu" "In10.Cu" "In11.Cu" "In12.Cu" "In13.Cu" "In14.Cu"
			"In15.Cu" "In16.Cu"
		)
		(hatch none 0.5)
		(connect_pads
			(clearance 0)
		)
		(min_thickness 0.25)
		(keepout
			(tracks not_allowed)
			(vias allowed)
			(pads allowed)
			(copperpour not_allowed)
			(footprints allowed)
		)
		(placement
			(enabled no)
			(sheetname "")
		)
		(fill yes
			(thermal_gap 0.5)
			(thermal_bridge_width 0.5)
			(island_removal_mode 0)
		)
		(polygon
			(pts
				(arc
					(start 417.964112 -394.552424)
					(mid 418.074083 -394.653478)
					(end 418.218874 -394.690092)
				)
				(arc
					(start 418.218874 -394.690092)
					(mid 418.4344 -394.600818)
					(end 418.523674 -394.385292)
				)
				(arc
					(start 418.523674 -394.385292)
					(mid 418.513337 -394.306553)
					(end 418.483034 -394.233146)
				)
				(arc
					(start 418.090604 -393.554204)
					(mid 417.978207 -393.432587)
					(end 417.818824 -393.38758)
				)
				(arc
					(start 417.818824 -393.38758)
					(mid 417.603298 -393.476854)
					(end 417.514024 -393.69238)
				)
				(arc
					(start 417.514024 -393.69238)
					(mid 417.523602 -393.768442)
					(end 417.55187 -393.8397)
				)
				(xy 417.949126 -394.527024) (xy 417.961318 -394.54836) (xy 417.963858 -394.552678)
			)
		)
	)
	(zone
		(layers "F.Cu" "B.Cu" "In1.Cu" "In2.Cu" "In3.Cu" "In4.Cu" "In5.Cu" "In6.Cu"
			"In7.Cu" "In8.Cu" "In9.Cu" "In10.Cu" "In11.Cu" "In12.Cu" "In13.Cu" "In14.Cu"
			"In15.Cu" "In16.Cu"
		)
		(hatch none 0.5)
		(connect_pads
			(clearance 0)
		)
		(min_thickness 0.25)
		(keepout
			(tracks not_allowed)
			(vias allowed)
			(pads allowed)
			(copperpour not_allowed)
			(footprints allowed)
		)
		(placement
			(enabled no)
			(sheetname "")
		)
		(fill
			(thermal_gap 0.5)
			(thermal_bridge_width 0.5)
			(island_removal_mode 0)
		)
		(polygon
			(pts
				(arc
					(start 311.452006 -418.031168)
					(mid 311.071006 -418.412168)
					(end 311.452006 -418.793168)
				)
				(arc
					(start 312.315606 -418.793168)
					(mid 312.696606 -418.412168)
					(end 312.315606 -418.031168)
				)
			)
		)
	)
	(zone
		(layers "F.Cu" "B.Cu" "In1.Cu" "In2.Cu" "In3.Cu" "In4.Cu" "In5.Cu" "In6.Cu"
			"In7.Cu" "In8.Cu" "In9.Cu" "In10.Cu" "In11.Cu" "In12.Cu" "In13.Cu" "In14.Cu"
			"In15.Cu" "In16.Cu"
		)
		(hatch none 0.5)
		(connect_pads
			(clearance 0)
		)
		(min_thickness 0.25)
		(keepout
			(tracks not_allowed)
			(vias allowed)
			(pads allowed)
			(copperpour not_allowed)
			(footprints allowed)
		)
		(placement
			(enabled no)
			(sheetname "")
		)
		(fill
			(thermal_gap 0.5)
			(thermal_bridge_width 0.5)
			(island_removal_mode 0)
		)
		(polygon
			(pts
				(arc
					(start 410.716222 -412.46552)
					(mid 410.335222 -412.84652)
					(end 410.716222 -413.22752)
				)
				(arc
					(start 411.579822 -413.22752)
					(mid 411.960822 -412.84652)
					(end 411.579822 -412.46552)
				)
			)
		)
	)
	(zone
		(layers "F.Cu" "B.Cu" "In1.Cu" "In2.Cu" "In3.Cu" "In4.Cu" "In5.Cu" "In6.Cu"
			"In7.Cu" "In8.Cu" "In9.Cu" "In10.Cu" "In11.Cu" "In12.Cu" "In13.Cu" "In14.Cu"
			"In15.Cu" "In16.Cu"
		)
		(hatch none 0.5)
		(connect_pads
			(clearance 0)
		)
		(min_thickness 0.25)
		(keepout
			(tracks not_allowed)
			(vias allowed)
			(pads allowed)
			(copperpour not_allowed)
			(footprints allowed)
		)
		(placement
			(enabled no)
			(sheetname "")
		)
		(fill
			(thermal_gap 0.5)
			(thermal_bridge_width 0.5)
			(island_removal_mode 0)
		)
		(polygon
			(pts
				(arc
					(start 22.615652 -6.344158)
					(mid 22.234652 -6.725158)
					(end 22.615652 -7.106158)
				)
				(arc
					(start 23.479252 -7.106158)
					(mid 23.860252 -6.725158)
					(end 23.479252 -6.344158)
				)
			)
		)
	)
	(zone
		(layers "F.Cu" "B.Cu" "In1.Cu" "In2.Cu" "In3.Cu" "In4.Cu" "In5.Cu" "In6.Cu"
			"In7.Cu" "In8.Cu" "In9.Cu" "In10.Cu" "In11.Cu" "In12.Cu" "In13.Cu" "In14.Cu"
			"In15.Cu" "In16.Cu"
		)
		(hatch none 0.5)
		(connect_pads
			(clearance 0)
		)
		(min_thickness 0.25)
		(keepout
			(tracks not_allowed)
			(vias allowed)
			(pads allowed)
			(copperpour not_allowed)
			(footprints allowed)
		)
		(placement
			(enabled no)
			(sheetname "")
		)
		(fill
			(thermal_gap 0.5)
			(thermal_bridge_width 0.5)
			(island_removal_mode 0)
		)
		(polygon
			(pts
				(arc
					(start 405.45004 -379.50013)
					(mid 405.06904 -379.88113)
					(end 405.45004 -380.26213)
				)
				(arc
					(start 406.31364 -380.26213)
					(mid 406.69464 -379.88113)
					(end 406.31364 -379.50013)
				)
			)
		)
	)
	(zone
		(layers "F.Cu" "B.Cu" "In1.Cu" "In2.Cu" "In3.Cu" "In4.Cu" "In5.Cu" "In6.Cu"
			"In7.Cu" "In8.Cu" "In9.Cu" "In10.Cu" "In11.Cu" "In12.Cu" "In13.Cu" "In14.Cu"
			"In15.Cu" "In16.Cu"
		)
		(hatch none 0.5)
		(connect_pads
			(clearance 0)
		)
		(min_thickness 0.25)
		(keepout
			(tracks not_allowed)
			(vias allowed)
			(pads allowed)
			(copperpour not_allowed)
			(footprints allowed)
		)
		(placement
			(enabled no)
			(sheetname "")
		)
		(fill
			(thermal_gap 0.5)
			(thermal_bridge_width 0.5)
			(island_removal_mode 0)
		)
		(polygon
			(pts
				(arc
					(start 397.439388 -389.88746)
					(mid 397.058388 -389.50646)
					(end 396.677388 -389.88746)
				)
				(arc
					(start 396.677388 -390.75106)
					(mid 397.058388 -391.13206)
					(end 397.439388 -390.75106)
				)
			)
		)
	)
	(zone
		(layers "F.Cu" "B.Cu" "In1.Cu" "In2.Cu" "In3.Cu" "In4.Cu" "In5.Cu" "In6.Cu"
			"In7.Cu" "In8.Cu" "In9.Cu" "In10.Cu" "In11.Cu" "In12.Cu" "In13.Cu" "In14.Cu"
			"In15.Cu" "In16.Cu"
		)
		(hatch none 0.5)
		(connect_pads
			(clearance 0)
		)
		(min_thickness 0.25)
		(keepout
			(tracks not_allowed)
			(vias allowed)
			(pads allowed)
			(copperpour not_allowed)
			(footprints allowed)
		)
		(placement
			(enabled no)
			(sheetname "")
		)
		(fill
			(thermal_gap 0.5)
			(thermal_bridge_width 0.5)
			(island_removal_mode 0)
		)
		(polygon
			(pts
				(xy 520.418568 -312.913014) (xy 529.808948 -312.913014) (xy 530.113748 -312.608214) (xy 520.113768 -312.608214)
			)
		)
	)
	(zone
		(layers "F.Cu" "B.Cu" "In1.Cu" "In2.Cu" "In3.Cu" "In4.Cu" "In5.Cu" "In6.Cu"
			"In7.Cu" "In8.Cu" "In9.Cu" "In10.Cu" "In11.Cu" "In12.Cu" "In13.Cu" "In14.Cu"
			"In15.Cu" "In16.Cu"
		)
		(hatch none 0.5)
		(connect_pads
			(clearance 0)
		)
		(min_thickness 0.25)
		(keepout
			(tracks not_allowed)
			(vias allowed)
			(pads allowed)
			(copperpour not_allowed)
			(footprints allowed)
		)
		(placement
			(enabled no)
			(sheetname "")
		)
		(fill
			(thermal_gap 0.5)
			(thermal_bridge_width 0.5)
			(island_removal_mode 0)
		)
		(polygon
			(pts
				(arc
					(start 130.215132 -11.458702)
					(mid 129.834132 -11.839702)
					(end 130.215132 -12.220702)
				)
				(arc
					(start 131.078732 -12.220702)
					(mid 131.459732 -11.839702)
					(end 131.078732 -11.458702)
				)
			)
		)
	)
	(zone
		(layers "F.Cu" "B.Cu" "In1.Cu" "In2.Cu" "In3.Cu" "In4.Cu" "In5.Cu" "In6.Cu"
			"In7.Cu" "In8.Cu" "In9.Cu" "In10.Cu" "In11.Cu" "In12.Cu" "In13.Cu" "In14.Cu"
			"In15.Cu" "In16.Cu"
		)
		(hatch none 0.5)
		(connect_pads
			(clearance 0)
		)
		(min_thickness 0.25)
		(keepout
			(tracks not_allowed)
			(vias allowed)
			(pads allowed)
			(copperpour not_allowed)
			(footprints allowed)
		)
		(placement
			(enabled no)
			(sheetname "")
		)
		(fill
			(thermal_gap 0.5)
			(thermal_bridge_width 0.5)
			(island_removal_mode 0)
		)
		(polygon
			(pts
				(arc
					(start 379.436376 -398.016476)
					(mid 379.546347 -398.11753)
					(end 379.691138 -398.154144)
				)
				(arc
					(start 379.691138 -398.154144)
					(mid 379.906664 -398.06487)
					(end 379.995938 -397.849344)
				)
				(arc
					(start 379.995938 -397.849344)
					(mid 379.985601 -397.770605)
					(end 379.955298 -397.697198)
				)
				(arc
					(start 379.562868 -397.018256)
					(mid 379.450471 -396.896639)
					(end 379.291088 -396.851632)
				)
				(arc
					(start 379.291088 -396.851632)
					(mid 379.075562 -396.940906)
					(end 378.986288 -397.156432)
				)
				(arc
					(start 378.986288 -397.156432)
					(mid 378.995866 -397.232494)
					(end 379.024134 -397.303752)
				)
				(xy 379.42139 -397.991076) (xy 379.433582 -398.012412) (xy 379.436122 -398.01673)
			)
		)
	)
	(zone
		(layers "F.Cu" "B.Cu" "In1.Cu" "In2.Cu" "In3.Cu" "In4.Cu" "In5.Cu" "In6.Cu"
			"In7.Cu" "In8.Cu" "In9.Cu" "In10.Cu" "In11.Cu" "In12.Cu" "In13.Cu" "In14.Cu"
			"In15.Cu" "In16.Cu"
		)
		(hatch none 0.5)
		(connect_pads
			(clearance 0)
		)
		(min_thickness 0.25)
		(keepout
			(tracks not_allowed)
			(vias allowed)
			(pads allowed)
			(copperpour not_allowed)
			(footprints allowed)
		)
		(placement
			(enabled no)
			(sheetname "")
		)
		(fill
			(thermal_gap 0.5)
			(thermal_bridge_width 0.5)
			(island_removal_mode 0)
		)
		(polygon
			(pts
				(arc
					(start 48.120554 -373.58193)
					(mid 47.739554 -373.96293)
					(end 48.120554 -374.34393)
				)
				(arc
					(start 48.984154 -374.34393)
					(mid 49.365154 -373.96293)
					(end 48.984154 -373.58193)
				)
			)
		)
	)
	(zone
		(layers "F.Cu" "B.Cu" "In1.Cu" "In2.Cu" "In3.Cu" "In4.Cu" "In5.Cu" "In6.Cu"
			"In7.Cu" "In8.Cu" "In9.Cu" "In10.Cu" "In11.Cu" "In12.Cu" "In13.Cu" "In14.Cu"
			"In15.Cu" "In16.Cu"
		)
		(hatch none 0.5)
		(connect_pads
			(clearance 0)
		)
		(min_thickness 0.25)
		(keepout
			(tracks not_allowed)
			(vias allowed)
			(pads allowed)
			(copperpour not_allowed)
			(footprints allowed)
		)
		(placement
			(enabled no)
			(sheetname "")
		)
		(fill yes
			(thermal_gap 0.5)
			(thermal_bridge_width 0.5)
			(island_removal_mode 0)
		)
		(polygon
			(pts
				(arc
					(start 147.564348 -386.170424)
					(mid 147.674319 -386.271478)
					(end 147.81911 -386.308092)
				)
				(arc
					(start 147.81911 -386.308092)
					(mid 148.034636 -386.218818)
					(end 148.12391 -386.003292)
				)
				(arc
					(start 148.12391 -386.003292)
					(mid 148.113573 -385.924553)
					(end 148.08327 -385.851146)
				)
				(arc
					(start 147.69084 -385.172204)
					(mid 147.578443 -385.050587)
					(end 147.41906 -385.00558)
				)
				(arc
					(start 147.41906 -385.00558)
					(mid 147.203534 -385.094854)
					(end 147.11426 -385.31038)
				)
				(arc
					(start 147.11426 -385.31038)
					(mid 147.123838 -385.386442)
					(end 147.152106 -385.4577)
				)
				(xy 147.549362 -386.145024) (xy 147.561554 -386.16636) (xy 147.564094 -386.170678)
			)
		)
	)
	(zone
		(layers "F.Cu" "B.Cu" "In1.Cu" "In2.Cu" "In3.Cu" "In4.Cu" "In5.Cu" "In6.Cu"
			"In7.Cu" "In8.Cu" "In9.Cu" "In10.Cu" "In11.Cu" "In12.Cu" "In13.Cu" "In14.Cu"
			"In15.Cu" "In16.Cu"
		)
		(hatch none 0.5)
		(connect_pads
			(clearance 0)
		)
		(min_thickness 0.25)
		(keepout
			(tracks not_allowed)
			(vias allowed)
			(pads allowed)
			(copperpour not_allowed)
			(footprints allowed)
		)
		(placement
			(enabled no)
			(sheetname "")
		)
		(fill
			(thermal_gap 0.5)
			(thermal_bridge_width 0.5)
			(island_removal_mode 0)
		)
		(polygon
			(pts
				(arc
					(start 337.489546 -412.46552)
					(mid 337.108546 -412.84652)
					(end 337.489546 -413.22752)
				)
				(arc
					(start 338.353146 -413.22752)
					(mid 338.734146 -412.84652)
					(end 338.353146 -412.46552)
				)
			)
		)
	)
	(zone
		(layers "F.Cu" "B.Cu" "In1.Cu" "In2.Cu" "In3.Cu" "In4.Cu" "In5.Cu" "In6.Cu"
			"In7.Cu" "In8.Cu" "In9.Cu" "In10.Cu" "In11.Cu" "In12.Cu" "In13.Cu" "In14.Cu"
			"In15.Cu" "In16.Cu"
		)
		(hatch none 0.5)
		(connect_pads
			(clearance 0)
		)
		(min_thickness 0.25)
		(keepout
			(tracks not_allowed)
			(vias allowed)
			(pads allowed)
			(copperpour not_allowed)
			(footprints allowed)
		)
		(placement
			(enabled no)
			(sheetname "")
		)
		(fill
			(thermal_gap 0.5)
			(thermal_bridge_width 0.5)
			(island_removal_mode 0)
		)
		(polygon
			(pts
				(arc
					(start 89.157302 -371.11813)
					(mid 88.776302 -371.49913)
					(end 89.157302 -371.88013)
				)
				(arc
					(start 90.020902 -371.88013)
					(mid 90.401902 -371.49913)
					(end 90.020902 -371.11813)
				)
			)
		)
	)
	(zone
		(layers "F.Cu" "B.Cu" "In1.Cu" "In2.Cu" "In3.Cu" "In4.Cu" "In5.Cu" "In6.Cu"
			"In7.Cu" "In8.Cu" "In9.Cu" "In10.Cu" "In11.Cu" "In12.Cu" "In13.Cu" "In14.Cu"
			"In15.Cu" "In16.Cu"
		)
		(hatch none 0.5)
		(connect_pads
			(clearance 0)
		)
		(min_thickness 0.25)
		(keepout
			(tracks not_allowed)
			(vias allowed)
			(pads allowed)
			(copperpour not_allowed)
			(footprints allowed)
		)
		(placement
			(enabled no)
			(sheetname "")
		)
		(fill
			(thermal_gap 0.5)
			(thermal_bridge_width 0.5)
			(island_removal_mode 0)
		)
		(polygon
			(pts
				(arc
					(start 329.831446 -418.031168)
					(mid 329.450446 -418.412168)
					(end 329.831446 -418.793168)
				)
				(arc
					(start 330.695046 -418.793168)
					(mid 331.076046 -418.412168)
					(end 330.695046 -418.031168)
				)
			)
		)
	)
	(zone
		(layers "F.Cu" "B.Cu" "In1.Cu" "In2.Cu" "In3.Cu" "In4.Cu" "In5.Cu" "In6.Cu"
			"In7.Cu" "In8.Cu" "In9.Cu" "In10.Cu" "In11.Cu" "In12.Cu" "In13.Cu" "In14.Cu"
			"In15.Cu" "In16.Cu"
		)
		(hatch none 0.5)
		(connect_pads
			(clearance 0)
		)
		(min_thickness 0.25)
		(keepout
			(tracks not_allowed)
			(vias allowed)
			(pads allowed)
			(copperpour not_allowed)
			(footprints allowed)
		)
		(placement
			(enabled no)
			(sheetname "")
		)
		(fill yes
			(thermal_gap 0.5)
			(thermal_bridge_width 0.5)
			(island_removal_mode 0)
		)
		(polygon
			(pts
				(arc
					(start 404.76424 -394.552424)
					(mid 404.874211 -394.653478)
					(end 405.019002 -394.690092)
				)
				(arc
					(start 405.019002 -394.690092)
					(mid 405.234528 -394.600818)
					(end 405.323802 -394.385292)
				)
				(arc
					(start 405.323802 -394.385292)
					(mid 405.313465 -394.306553)
					(end 405.283162 -394.233146)
				)
				(arc
					(start 404.890732 -393.554204)
					(mid 404.778335 -393.432587)
					(end 404.618952 -393.38758)
				)
				(arc
					(start 404.618952 -393.38758)
					(mid 404.403426 -393.476854)
					(end 404.314152 -393.69238)
				)
				(arc
					(start 404.314152 -393.69238)
					(mid 404.32373 -393.768442)
					(end 404.351998 -393.8397)
				)
				(xy 404.749254 -394.527024) (xy 404.761446 -394.54836) (xy 404.763986 -394.552678)
			)
		)
	)
	(zone
		(layers "F.Cu" "B.Cu" "In1.Cu" "In2.Cu" "In3.Cu" "In4.Cu" "In5.Cu" "In6.Cu"
			"In7.Cu" "In8.Cu" "In9.Cu" "In10.Cu" "In11.Cu" "In12.Cu" "In13.Cu" "In14.Cu"
			"In15.Cu" "In16.Cu"
		)
		(hatch none 0.5)
		(connect_pads
			(clearance 0)
		)
		(min_thickness 0.25)
		(keepout
			(tracks not_allowed)
			(vias allowed)
			(pads allowed)
			(copperpour not_allowed)
			(footprints allowed)
		)
		(placement
			(enabled no)
			(sheetname "")
		)
		(fill
			(thermal_gap 0.5)
			(thermal_bridge_width 0.5)
			(island_removal_mode 0)
		)
		(polygon
			(pts
				(arc
					(start 397.115538 -6.344158)
					(mid 396.734538 -6.725158)
					(end 397.115538 -7.106158)
				)
				(arc
					(start 397.979138 -7.106158)
					(mid 398.360138 -6.725158)
					(end 397.979138 -6.344158)
				)
			)
		)
	)
	(zone
		(layers "F.Cu" "B.Cu" "In1.Cu" "In2.Cu" "In3.Cu" "In4.Cu" "In5.Cu" "In6.Cu"
			"In7.Cu" "In8.Cu" "In9.Cu" "In10.Cu" "In11.Cu" "In12.Cu" "In13.Cu" "In14.Cu"
			"In15.Cu" "In16.Cu"
		)
		(hatch none 0.5)
		(connect_pads
			(clearance 0)
		)
		(min_thickness 0.25)
		(keepout
			(tracks not_allowed)
			(vias allowed)
			(pads allowed)
			(copperpour not_allowed)
			(footprints allowed)
		)
		(placement
			(enabled no)
			(sheetname "")
		)
		(fill yes
			(thermal_gap 0.5)
			(thermal_bridge_width 0.5)
			(island_removal_mode 0)
		)
		(polygon
			(pts
				(arc
					(start 372.236492 -394.552424)
					(mid 372.346463 -394.653478)
					(end 372.491254 -394.690092)
				)
				(arc
					(start 372.491254 -394.690092)
					(mid 372.70678 -394.600818)
					(end 372.796054 -394.385292)
				)
				(arc
					(start 372.796054 -394.385292)
					(mid 372.785717 -394.306553)
					(end 372.755414 -394.233146)
				)
				(arc
					(start 372.362984 -393.554204)
					(mid 372.250587 -393.432587)
					(end 372.091204 -393.38758)
				)
				(arc
					(start 372.091204 -393.38758)
					(mid 371.875678 -393.476854)
					(end 371.786404 -393.69238)
				)
				(arc
					(start 371.786404 -393.69238)
					(mid 371.795982 -393.768442)
					(end 371.82425 -393.8397)
				)
				(xy 372.221506 -394.527024) (xy 372.233698 -394.54836) (xy 372.236238 -394.552678)
			)
		)
	)
	(zone
		(layers "F.Cu" "B.Cu" "In1.Cu" "In2.Cu" "In3.Cu" "In4.Cu" "In5.Cu" "In6.Cu"
			"In7.Cu" "In8.Cu" "In9.Cu" "In10.Cu" "In11.Cu" "In12.Cu" "In13.Cu" "In14.Cu"
			"In15.Cu" "In16.Cu"
		)
		(hatch none 0.5)
		(connect_pads
			(clearance 0)
		)
		(min_thickness 0.25)
		(keepout
			(tracks not_allowed)
			(vias allowed)
			(pads allowed)
			(copperpour not_allowed)
			(footprints allowed)
		)
		(placement
			(enabled no)
			(sheetname "")
		)
		(fill
			(thermal_gap 0.5)
			(thermal_bridge_width 0.5)
			(island_removal_mode 0)
		)
		(polygon
			(pts
				(arc
					(start 7.09549 -458.028294)
					(mid 2.90449 -458.028294)
					(end 7.09549 -458.028294)
				)
			)
		)
	)
	(zone
		(layers "F.Cu" "B.Cu" "In1.Cu" "In2.Cu" "In3.Cu" "In4.Cu" "In5.Cu" "In6.Cu"
			"In7.Cu" "In8.Cu" "In9.Cu" "In10.Cu" "In11.Cu" "In12.Cu" "In13.Cu" "In14.Cu"
			"In15.Cu" "In16.Cu"
		)
		(hatch none 0.5)
		(connect_pads
			(clearance 0)
		)
		(min_thickness 0.25)
		(keepout
			(tracks not_allowed)
			(vias allowed)
			(pads allowed)
			(copperpour not_allowed)
			(footprints allowed)
		)
		(placement
			(enabled no)
			(sheetname "")
		)
		(fill
			(thermal_gap 0.5)
			(thermal_bridge_width 0.5)
			(island_removal_mode 0)
		)
		(polygon
			(pts
				(arc
					(start 141.439392 -381.50546)
					(mid 141.058392 -381.12446)
					(end 140.677392 -381.50546)
				)
				(arc
					(start 140.677392 -382.36906)
					(mid 141.058392 -382.75006)
					(end 141.439392 -382.36906)
				)
			)
		)
	)
	(zone
		(layers "F.Cu" "B.Cu" "In1.Cu" "In2.Cu" "In3.Cu" "In4.Cu" "In5.Cu" "In6.Cu"
			"In7.Cu" "In8.Cu" "In9.Cu" "In10.Cu" "In11.Cu" "In12.Cu" "In13.Cu" "In14.Cu"
			"In15.Cu" "In16.Cu"
		)
		(hatch none 0.5)
		(connect_pads
			(clearance 0)
		)
		(min_thickness 0.25)
		(keepout
			(tracks not_allowed)
			(vias allowed)
			(pads allowed)
			(copperpour not_allowed)
			(footprints allowed)
		)
		(placement
			(enabled no)
			(sheetname "")
		)
		(fill
			(thermal_gap 0.5)
			(thermal_bridge_width 0.5)
			(island_removal_mode 0)
		)
		(polygon
			(pts
				(arc
					(start 15.473934 -109.043724)
					(mid 15.092934 -109.424724)
					(end 15.473934 -109.805724)
				)
				(arc
					(start 16.464534 -109.805724)
					(mid 16.845534 -109.424724)
					(end 16.464534 -109.043724)
				)
			)
		)
	)
	(zone
		(layers "F.Cu" "B.Cu" "In1.Cu" "In2.Cu" "In3.Cu" "In4.Cu" "In5.Cu" "In6.Cu"
			"In7.Cu" "In8.Cu" "In9.Cu" "In10.Cu" "In11.Cu" "In12.Cu" "In13.Cu" "In14.Cu"
			"In15.Cu" "In16.Cu"
		)
		(hatch none 0.5)
		(connect_pads
			(clearance 0)
		)
		(min_thickness 0.25)
		(keepout
			(tracks not_allowed)
			(vias allowed)
			(pads allowed)
			(copperpour not_allowed)
			(footprints allowed)
		)
		(placement
			(enabled no)
			(sheetname "")
		)
		(fill
			(thermal_gap 0.5)
			(thermal_bridge_width 0.5)
			(island_removal_mode 0)
		)
		(polygon
			(pts
				(arc
					(start 409.184602 -415.00552)
					(mid 408.803602 -415.38652)
					(end 409.184602 -415.76752)
				)
				(arc
					(start 410.048202 -415.76752)
					(mid 410.429202 -415.38652)
					(end 410.048202 -415.00552)
				)
			)
		)
	)
	(zone
		(layers "F.Cu" "B.Cu" "In1.Cu" "In2.Cu" "In3.Cu" "In4.Cu" "In5.Cu" "In6.Cu"
			"In7.Cu" "In8.Cu" "In9.Cu" "In10.Cu" "In11.Cu" "In12.Cu" "In13.Cu" "In14.Cu"
			"In15.Cu" "In16.Cu"
		)
		(hatch none 0.5)
		(connect_pads
			(clearance 0)
		)
		(min_thickness 0.25)
		(keepout
			(tracks not_allowed)
			(vias allowed)
			(pads allowed)
			(copperpour not_allowed)
			(footprints allowed)
		)
		(placement
			(enabled no)
			(sheetname "")
		)
		(fill
			(thermal_gap 0.5)
			(thermal_bridge_width 0.5)
			(island_removal_mode 0)
		)
		(polygon
			(pts
				(arc
					(start 18.326862 -18.756122)
					(mid 17.945862 -19.137122)
					(end 18.326862 -19.518122)
				)
				(arc
					(start 19.190462 -19.518122)
					(mid 19.571462 -19.137122)
					(end 19.190462 -18.756122)
				)
			)
		)
	)
	(zone
		(layers "F.Cu" "B.Cu" "In1.Cu" "In2.Cu" "In3.Cu" "In4.Cu" "In5.Cu" "In6.Cu"
			"In7.Cu" "In8.Cu" "In9.Cu" "In10.Cu" "In11.Cu" "In12.Cu" "In13.Cu" "In14.Cu"
			"In15.Cu" "In16.Cu"
		)
		(hatch none 0.5)
		(connect_pads
			(clearance 0)
		)
		(min_thickness 0.25)
		(keepout
			(tracks not_allowed)
			(vias allowed)
			(pads allowed)
			(copperpour not_allowed)
			(footprints allowed)
		)
		(placement
			(enabled no)
			(sheetname "")
		)
		(fill yes
			(thermal_gap 0.5)
			(thermal_bridge_width 0.5)
			(island_removal_mode 0)
		)
		(polygon
			(pts
				(arc
					(start 62.336426 -386.170424)
					(mid 62.446397 -386.271478)
					(end 62.591188 -386.308092)
				)
				(arc
					(start 62.591188 -386.308092)
					(mid 62.806714 -386.218818)
					(end 62.895988 -386.003292)
				)
				(arc
					(start 62.895988 -386.003292)
					(mid 62.885651 -385.924553)
					(end 62.855348 -385.851146)
				)
				(arc
					(start 62.462918 -385.172204)
					(mid 62.350521 -385.050587)
					(end 62.191138 -385.00558)
				)
				(arc
					(start 62.191138 -385.00558)
					(mid 61.975612 -385.094854)
					(end 61.886338 -385.31038)
				)
				(arc
					(start 61.886338 -385.31038)
					(mid 61.895916 -385.386442)
					(end 61.924184 -385.4577)
				)
				(xy 62.32144 -386.145024) (xy 62.333632 -386.16636) (xy 62.336172 -386.170678)
			)
		)
	)
	(zone
		(layers "F.Cu" "B.Cu" "In1.Cu" "In2.Cu" "In3.Cu" "In4.Cu" "In5.Cu" "In6.Cu"
			"In7.Cu" "In8.Cu" "In9.Cu" "In10.Cu" "In11.Cu" "In12.Cu" "In13.Cu" "In14.Cu"
			"In15.Cu" "In16.Cu"
		)
		(hatch none 0.5)
		(connect_pads
			(clearance 0)
		)
		(min_thickness 0.25)
		(keepout
			(tracks not_allowed)
			(vias allowed)
			(pads allowed)
			(copperpour not_allowed)
			(footprints allowed)
		)
		(placement
			(enabled no)
			(sheetname "")
		)
		(fill yes
			(thermal_gap 0.5)
			(thermal_bridge_width 0.5)
			(island_removal_mode 0)
		)
		(polygon
			(pts
				(arc
					(start 115.0366 -386.170424)
					(mid 115.146571 -386.271478)
					(end 115.291362 -386.308092)
				)
				(arc
					(start 115.291362 -386.308092)
					(mid 115.506888 -386.218818)
					(end 115.596162 -386.003292)
				)
				(arc
					(start 115.596162 -386.003292)
					(mid 115.585825 -385.924553)
					(end 115.555522 -385.851146)
				)
				(arc
					(start 115.163092 -385.172204)
					(mid 115.050695 -385.050587)
					(end 114.891312 -385.00558)
				)
				(arc
					(start 114.891312 -385.00558)
					(mid 114.675786 -385.094854)
					(end 114.586512 -385.31038)
				)
				(arc
					(start 114.586512 -385.31038)
					(mid 114.59609 -385.386442)
					(end 114.624358 -385.4577)
				)
				(xy 115.021614 -386.145024) (xy 115.033806 -386.16636) (xy 115.036346 -386.170678)
			)
		)
	)
	(zone
		(layers "F.Cu" "B.Cu" "In1.Cu" "In2.Cu" "In3.Cu" "In4.Cu" "In5.Cu" "In6.Cu"
			"In7.Cu" "In8.Cu" "In9.Cu" "In10.Cu" "In11.Cu" "In12.Cu" "In13.Cu" "In14.Cu"
			"In15.Cu" "In16.Cu"
		)
		(hatch none 0.5)
		(connect_pads
			(clearance 0)
		)
		(min_thickness 0.25)
		(keepout
			(tracks not_allowed)
			(vias allowed)
			(pads allowed)
			(copperpour not_allowed)
			(footprints allowed)
		)
		(placement
			(enabled no)
			(sheetname "")
		)
		(fill yes
			(thermal_gap 0.5)
			(thermal_bridge_width 0.5)
			(island_removal_mode 0)
		)
		(polygon
			(pts
				(arc
					(start 336.464148 -394.552424)
					(mid 336.574119 -394.653478)
					(end 336.71891 -394.690092)
				)
				(arc
					(start 336.71891 -394.690092)
					(mid 336.934436 -394.600818)
					(end 337.02371 -394.385292)
				)
				(arc
					(start 337.02371 -394.385292)
					(mid 337.013373 -394.306553)
					(end 336.98307 -394.233146)
				)
				(arc
					(start 336.59064 -393.554204)
					(mid 336.478243 -393.432587)
					(end 336.31886 -393.38758)
				)
				(arc
					(start 336.31886 -393.38758)
					(mid 336.103334 -393.476854)
					(end 336.01406 -393.69238)
				)
				(arc
					(start 336.01406 -393.69238)
					(mid 336.023638 -393.768442)
					(end 336.051906 -393.8397)
				)
				(xy 336.449162 -394.527024) (xy 336.461354 -394.54836) (xy 336.463894 -394.552678)
			)
		)
	)
	(zone
		(layers "F.Cu" "B.Cu" "In1.Cu" "In2.Cu" "In3.Cu" "In4.Cu" "In5.Cu" "In6.Cu"
			"In7.Cu" "In8.Cu" "In9.Cu" "In10.Cu" "In11.Cu" "In12.Cu" "In13.Cu" "In14.Cu"
			"In15.Cu" "In16.Cu"
		)
		(hatch none 0.5)
		(connect_pads
			(clearance 0)
		)
		(min_thickness 0.25)
		(keepout
			(tracks not_allowed)
			(vias allowed)
			(pads allowed)
			(copperpour not_allowed)
			(footprints allowed)
		)
		(placement
			(enabled no)
			(sheetname "")
		)
		(fill
			(thermal_gap 0.5)
			(thermal_bridge_width 0.5)
			(island_removal_mode 0)
		)
		(polygon
			(pts
				(arc
					(start 380.636526 -398.016476)
					(mid 380.746497 -398.11753)
					(end 380.891288 -398.154144)
				)
				(arc
					(start 380.891288 -398.154144)
					(mid 381.106814 -398.06487)
					(end 381.196088 -397.849344)
				)
				(arc
					(start 381.196088 -397.849344)
					(mid 381.185751 -397.770605)
					(end 381.155448 -397.697198)
				)
				(arc
					(start 380.763018 -397.018256)
					(mid 380.650621 -396.896639)
					(end 380.491238 -396.851632)
				)
				(arc
					(start 380.491238 -396.851632)
					(mid 380.275712 -396.940906)
					(end 380.186438 -397.156432)
				)
				(arc
					(start 380.186438 -397.156432)
					(mid 380.196016 -397.232494)
					(end 380.224284 -397.303752)
				)
				(xy 380.62154 -397.991076) (xy 380.633732 -398.012412) (xy 380.636272 -398.01673)
			)
		)
	)
	(zone
		(layers "F.Cu" "B.Cu" "In1.Cu" "In2.Cu" "In3.Cu" "In4.Cu" "In5.Cu" "In6.Cu"
			"In7.Cu" "In8.Cu" "In9.Cu" "In10.Cu" "In11.Cu" "In12.Cu" "In13.Cu" "In14.Cu"
			"In15.Cu" "In16.Cu"
		)
		(hatch none 0.5)
		(connect_pads
			(clearance 0)
		)
		(min_thickness 0.25)
		(keepout
			(tracks not_allowed)
			(vias allowed)
			(pads allowed)
			(copperpour not_allowed)
			(footprints allowed)
		)
		(placement
			(enabled no)
			(sheetname "")
		)
		(fill
			(thermal_gap 0.5)
			(thermal_bridge_width 0.5)
			(island_removal_mode 0)
		)
		(polygon
			(pts
				(arc
					(start 129.431288 -219.412058)
					(mid 129.050288 -219.793058)
					(end 129.431288 -220.174058)
				)
				(arc
					(start 130.447288 -220.174058)
					(mid 130.828288 -219.793058)
					(end 130.447288 -219.412058)
				)
			)
		)
	)
	(zone
		(layers "F.Cu" "B.Cu" "In1.Cu" "In2.Cu" "In3.Cu" "In4.Cu" "In5.Cu" "In6.Cu"
			"In7.Cu" "In8.Cu" "In9.Cu" "In10.Cu" "In11.Cu" "In12.Cu" "In13.Cu" "In14.Cu"
			"In15.Cu" "In16.Cu"
		)
		(hatch none 0.5)
		(connect_pads
			(clearance 0)
		)
		(min_thickness 0.25)
		(keepout
			(tracks not_allowed)
			(vias allowed)
			(pads allowed)
			(copperpour not_allowed)
			(footprints allowed)
		)
		(placement
			(enabled no)
			(sheetname "")
		)
		(fill
			(thermal_gap 0.5)
			(thermal_bridge_width 0.5)
			(island_removal_mode 0)
		)
		(polygon
			(pts
				(arc
					(start 148.589746 -404.08352)
					(mid 148.208746 -404.46452)
					(end 148.589746 -404.84552)
				)
				(arc
					(start 149.453346 -404.84552)
					(mid 149.834346 -404.46452)
					(end 149.453346 -404.08352)
				)
			)
		)
	)
	(zone
		(layers "F.Cu" "B.Cu" "In1.Cu" "In2.Cu" "In3.Cu" "In4.Cu" "In5.Cu" "In6.Cu"
			"In7.Cu" "In8.Cu" "In9.Cu" "In10.Cu" "In11.Cu" "In12.Cu" "In13.Cu" "In14.Cu"
			"In15.Cu" "In16.Cu"
		)
		(hatch none 0.5)
		(connect_pads
			(clearance 0)
		)
		(min_thickness 0.25)
		(keepout
			(tracks not_allowed)
			(vias allowed)
			(pads allowed)
			(copperpour not_allowed)
			(footprints allowed)
		)
		(placement
			(enabled no)
			(sheetname "")
		)
		(fill
			(thermal_gap 0.5)
			(thermal_bridge_width 0.5)
			(island_removal_mode 0)
		)
		(polygon
			(pts
				(arc
					(start 308.388766 -415.00552)
					(mid 308.007766 -415.38652)
					(end 308.388766 -415.76752)
				)
				(arc
					(start 309.252366 -415.76752)
					(mid 309.633366 -415.38652)
					(end 309.252366 -415.00552)
				)
			)
		)
	)
	(zone
		(layers "F.Cu" "B.Cu" "In1.Cu" "In2.Cu" "In3.Cu" "In4.Cu" "In5.Cu" "In6.Cu"
			"In7.Cu" "In8.Cu" "In9.Cu" "In10.Cu" "In11.Cu" "In12.Cu" "In13.Cu" "In14.Cu"
			"In15.Cu" "In16.Cu"
		)
		(hatch none 0.5)
		(connect_pads
			(clearance 0)
		)
		(min_thickness 0.25)
		(keepout
			(tracks not_allowed)
			(vias allowed)
			(pads allowed)
			(copperpour not_allowed)
			(footprints allowed)
		)
		(placement
			(enabled no)
			(sheetname "")
		)
		(fill
			(thermal_gap 0.5)
			(thermal_bridge_width 0.5)
			(island_removal_mode 0)
		)
		(polygon
			(pts
				(arc
					(start 161.362644 -373.58193)
					(mid 160.981644 -373.96293)
					(end 161.362644 -374.34393)
				)
				(arc
					(start 162.226244 -374.34393)
					(mid 162.607244 -373.96293)
					(end 162.226244 -373.58193)
				)
			)
		)
	)
	(zone
		(layers "F.Cu" "B.Cu" "In1.Cu" "In2.Cu" "In3.Cu" "In4.Cu" "In5.Cu" "In6.Cu"
			"In7.Cu" "In8.Cu" "In9.Cu" "In10.Cu" "In11.Cu" "In12.Cu" "In13.Cu" "In14.Cu"
			"In15.Cu" "In16.Cu"
		)
		(hatch none 0.5)
		(connect_pads
			(clearance 0)
		)
		(min_thickness 0.25)
		(keepout
			(tracks not_allowed)
			(vias allowed)
			(pads allowed)
			(copperpour not_allowed)
			(footprints allowed)
		)
		(placement
			(enabled no)
			(sheetname "")
		)
		(fill
			(thermal_gap 0.5)
			(thermal_bridge_width 0.5)
			(island_removal_mode 0)
		)
		(polygon
			(pts
				(arc
					(start 90.325448 -392.429238)
					(mid 89.944448 -392.048238)
					(end 89.563448 -392.429238)
				)
				(arc
					(start 89.563448 -393.292838)
					(mid 89.944448 -393.673838)
					(end 90.325448 -393.292838)
				)
			)
		)
	)
	(zone
		(layers "F.Cu" "B.Cu" "In1.Cu" "In2.Cu" "In3.Cu" "In4.Cu" "In5.Cu" "In6.Cu"
			"In7.Cu" "In8.Cu" "In9.Cu" "In10.Cu" "In11.Cu" "In12.Cu" "In13.Cu" "In14.Cu"
			"In15.Cu" "In16.Cu"
		)
		(hatch none 0.5)
		(connect_pads
			(clearance 0)
		)
		(min_thickness 0.25)
		(keepout
			(tracks not_allowed)
			(vias allowed)
			(pads allowed)
			(copperpour not_allowed)
			(footprints allowed)
		)
		(placement
			(enabled no)
			(sheetname "")
		)
		(fill
			(thermal_gap 0.5)
			(thermal_bridge_width 0.5)
			(island_removal_mode 0)
		)
		(polygon
			(pts
				(arc
					(start 308.99735 -400.811238)
					(mid 308.61635 -400.430238)
					(end 308.23535 -400.811238)
				)
				(arc
					(start 308.23535 -401.674838)
					(mid 308.61635 -402.055838)
					(end 308.99735 -401.674838)
				)
			)
		)
	)
	(zone
		(layers "F.Cu" "B.Cu" "In1.Cu" "In2.Cu" "In3.Cu" "In4.Cu" "In5.Cu" "In6.Cu"
			"In7.Cu" "In8.Cu" "In9.Cu" "In10.Cu" "In11.Cu" "In12.Cu" "In13.Cu" "In14.Cu"
			"In15.Cu" "In16.Cu"
		)
		(hatch none 0.5)
		(connect_pads
			(clearance 0)
		)
		(min_thickness 0.25)
		(keepout
			(tracks not_allowed)
			(vias allowed)
			(pads allowed)
			(copperpour not_allowed)
			(footprints allowed)
		)
		(placement
			(enabled no)
			(sheetname "")
		)
		(fill
			(thermal_gap 0.5)
			(thermal_bridge_width 0.5)
			(island_removal_mode 0)
		)
		(polygon
			(pts
				(arc
					(start 116.922296 -371.11813)
					(mid 116.541296 -371.49913)
					(end 116.922296 -371.88013)
				)
				(arc
					(start 117.785896 -371.88013)
					(mid 118.166896 -371.49913)
					(end 117.785896 -371.11813)
				)
			)
		)
	)
	(zone
		(layers "F.Cu" "B.Cu" "In1.Cu" "In2.Cu" "In3.Cu" "In4.Cu" "In5.Cu" "In6.Cu"
			"In7.Cu" "In8.Cu" "In9.Cu" "In10.Cu" "In11.Cu" "In12.Cu" "In13.Cu" "In14.Cu"
			"In15.Cu" "In16.Cu"
		)
		(hatch none 0.5)
		(connect_pads
			(clearance 0)
		)
		(min_thickness 0.25)
		(keepout
			(tracks not_allowed)
			(vias allowed)
			(pads allowed)
			(copperpour not_allowed)
			(footprints allowed)
		)
		(placement
			(enabled no)
			(sheetname "")
		)
		(fill
			(thermal_gap 0.5)
			(thermal_bridge_width 0.5)
			(island_removal_mode 0)
		)
		(polygon
			(pts
				(arc
					(start 159.311086 -409.649168)
					(mid 158.930086 -410.030168)
					(end 159.311086 -410.411168)
				)
				(arc
					(start 160.174686 -410.411168)
					(mid 160.555686 -410.030168)
					(end 160.174686 -409.649168)
				)
			)
		)
	)
	(zone
		(layers "F.Cu" "B.Cu" "In1.Cu" "In2.Cu" "In3.Cu" "In4.Cu" "In5.Cu" "In6.Cu"
			"In7.Cu" "In8.Cu" "In9.Cu" "In10.Cu" "In11.Cu" "In12.Cu" "In13.Cu" "In14.Cu"
			"In15.Cu" "In16.Cu"
		)
		(hatch none 0.5)
		(connect_pads
			(clearance 0)
		)
		(min_thickness 0.25)
		(keepout
			(tracks not_allowed)
			(vias allowed)
			(pads allowed)
			(copperpour not_allowed)
			(footprints allowed)
		)
		(placement
			(enabled no)
			(sheetname "")
		)
		(fill
			(thermal_gap 0.5)
			(thermal_bridge_width 0.5)
			(island_removal_mode 0)
		)
		(polygon
			(pts
				(arc
					(start 127.147066 -404.08352)
					(mid 126.766066 -404.46452)
					(end 127.147066 -404.84552)
				)
				(arc
					(start 128.010666 -404.84552)
					(mid 128.391666 -404.46452)
					(end 128.010666 -404.08352)
				)
			)
		)
	)
	(zone
		(layers "F.Cu" "B.Cu" "In1.Cu" "In2.Cu" "In3.Cu" "In4.Cu" "In5.Cu" "In6.Cu"
			"In7.Cu" "In8.Cu" "In9.Cu" "In10.Cu" "In11.Cu" "In12.Cu" "In13.Cu" "In14.Cu"
			"In15.Cu" "In16.Cu"
		)
		(hatch none 0.5)
		(connect_pads
			(clearance 0)
		)
		(min_thickness 0.25)
		(keepout
			(tracks not_allowed)
			(vias allowed)
			(pads allowed)
			(copperpour not_allowed)
			(footprints allowed)
		)
		(placement
			(enabled no)
			(sheetname "")
		)
		(fill
			(thermal_gap 0.5)
			(thermal_bridge_width 0.5)
			(island_removal_mode 0)
		)
		(polygon
			(pts
				(arc
					(start 320.641726 -415.00552)
					(mid 320.260726 -415.38652)
					(end 320.641726 -415.76752)
				)
				(arc
					(start 321.505326 -415.76752)
					(mid 321.886326 -415.38652)
					(end 321.505326 -415.00552)
				)
			)
		)
	)
	(zone
		(layers "F.Cu" "B.Cu" "In1.Cu" "In2.Cu" "In3.Cu" "In4.Cu" "In5.Cu" "In6.Cu"
			"In7.Cu" "In8.Cu" "In9.Cu" "In10.Cu" "In11.Cu" "In12.Cu" "In13.Cu" "In14.Cu"
			"In15.Cu" "In16.Cu"
		)
		(hatch none 0.5)
		(connect_pads
			(clearance 0)
		)
		(min_thickness 0.25)
		(keepout
			(tracks not_allowed)
			(vias allowed)
			(pads allowed)
			(copperpour not_allowed)
			(footprints allowed)
		)
		(placement
			(enabled no)
			(sheetname "")
		)
		(fill
			(thermal_gap 0.5)
			(thermal_bridge_width 0.5)
			(island_removal_mode 0)
		)
		(polygon
			(pts
				(arc
					(start 164.766244 -368.65433)
					(mid 164.385244 -369.03533)
					(end 164.766244 -369.41633)
				)
				(arc
					(start 165.629844 -369.41633)
					(mid 166.010844 -369.03533)
					(end 165.629844 -368.65433)
				)
			)
		)
	)
	(zone
		(layers "F.Cu" "B.Cu" "In1.Cu" "In2.Cu" "In3.Cu" "In4.Cu" "In5.Cu" "In6.Cu"
			"In7.Cu" "In8.Cu" "In9.Cu" "In10.Cu" "In11.Cu" "In12.Cu" "In13.Cu" "In14.Cu"
			"In15.Cu" "In16.Cu"
		)
		(hatch none 0.5)
		(connect_pads
			(clearance 0)
		)
		(min_thickness 0.25)
		(keepout
			(tracks not_allowed)
			(vias allowed)
			(pads allowed)
			(copperpour not_allowed)
			(footprints allowed)
		)
		(placement
			(enabled no)
			(sheetname "")
		)
		(fill
			(thermal_gap 0.5)
			(thermal_bridge_width 0.5)
			(island_removal_mode 0)
		)
		(polygon
			(pts
				(arc
					(start 468.89543 -448.989958)
					(mid 464.70443 -448.989958)
					(end 468.89543 -448.989958)
				)
			)
		)
	)
	(zone
		(layers "F.Cu" "B.Cu" "In1.Cu" "In2.Cu" "In3.Cu" "In4.Cu" "In5.Cu" "In6.Cu"
			"In7.Cu" "In8.Cu" "In9.Cu" "In10.Cu" "In11.Cu" "In12.Cu" "In13.Cu" "In14.Cu"
			"In15.Cu" "In16.Cu"
		)
		(hatch none 0.5)
		(connect_pads
			(clearance 0)
		)
		(min_thickness 0.25)
		(keepout
			(tracks not_allowed)
			(vias allowed)
			(pads allowed)
			(copperpour not_allowed)
			(footprints allowed)
		)
		(placement
			(enabled no)
			(sheetname "")
		)
		(fill
			(thermal_gap 0.5)
			(thermal_bridge_width 0.5)
			(island_removal_mode 0)
		)
		(polygon
			(pts
				(arc
					(start 128.678686 -406.62352)
					(mid 128.297686 -407.00452)
					(end 128.678686 -407.38552)
				)
				(arc
					(start 129.542286 -407.38552)
					(mid 129.923286 -407.00452)
					(end 129.542286 -406.62352)
				)
			)
		)
	)
	(zone
		(layers "F.Cu" "B.Cu" "In1.Cu" "In2.Cu" "In3.Cu" "In4.Cu" "In5.Cu" "In6.Cu"
			"In7.Cu" "In8.Cu" "In9.Cu" "In10.Cu" "In11.Cu" "In12.Cu" "In13.Cu" "In14.Cu"
			"In15.Cu" "In16.Cu"
		)
		(hatch none 0.5)
		(connect_pads
			(clearance 0)
		)
		(min_thickness 0.25)
		(keepout
			(tracks not_allowed)
			(vias allowed)
			(pads allowed)
			(copperpour not_allowed)
			(footprints allowed)
		)
		(placement
			(enabled no)
			(sheetname "")
		)
		(fill
			(thermal_gap 0.5)
			(thermal_bridge_width 0.5)
			(island_removal_mode 0)
		)
		(polygon
			(pts
				(arc
					(start 42.376344 -425.469558)
					(mid 41.995344 -425.088558)
					(end 41.614344 -425.469558)
				)
				(arc
					(start 41.614344 -426.333158)
					(mid 41.995344 -426.714158)
					(end 42.376344 -426.333158)
				)
			)
		)
	)
	(zone
		(layers "F.Cu" "B.Cu" "In1.Cu" "In2.Cu" "In3.Cu" "In4.Cu" "In5.Cu" "In6.Cu"
			"In7.Cu" "In8.Cu" "In9.Cu" "In10.Cu" "In11.Cu" "In12.Cu" "In13.Cu" "In14.Cu"
			"In15.Cu" "In16.Cu"
		)
		(hatch none 0.5)
		(connect_pads
			(clearance 0)
		)
		(min_thickness 0.25)
		(keepout
			(tracks not_allowed)
			(vias allowed)
			(pads allowed)
			(copperpour not_allowed)
			(footprints allowed)
		)
		(placement
			(enabled no)
			(sheetname "")
		)
		(fill
			(thermal_gap 0.5)
			(thermal_bridge_width 0.5)
			(island_removal_mode 0)
		)
		(polygon
			(pts
				(arc
					(start 62.141862 -424.360594)
					(mid 62.16418 -424.414476)
					(end 62.218062 -424.436794)
				)
				(arc
					(start 63.157862 -424.436794)
					(mid 63.211744 -424.414476)
					(end 63.234062 -424.360594)
				)
				(arc
					(start 63.234062 -421.81907)
					(mid 63.211744 -421.765188)
					(end 63.157862 -421.74287)
				)
				(arc
					(start 62.218062 -421.74287)
					(mid 62.16418 -421.765188)
					(end 62.141862 -421.81907)
				)
			)
		)
	)
	(zone
		(layers "F.Cu" "B.Cu" "In1.Cu" "In2.Cu" "In3.Cu" "In4.Cu" "In5.Cu" "In6.Cu"
			"In7.Cu" "In8.Cu" "In9.Cu" "In10.Cu" "In11.Cu" "In12.Cu" "In13.Cu" "In14.Cu"
			"In15.Cu" "In16.Cu"
		)
		(hatch none 0.5)
		(connect_pads
			(clearance 0)
		)
		(min_thickness 0.25)
		(keepout
			(tracks not_allowed)
			(vias allowed)
			(pads allowed)
			(copperpour not_allowed)
			(footprints allowed)
		)
		(placement
			(enabled no)
			(sheetname "")
		)
		(fill yes
			(thermal_gap 0.5)
			(thermal_bridge_width 0.5)
			(island_removal_mode 0)
		)
		(polygon
			(pts
				(arc
					(start 118.636542 -386.170424)
					(mid 118.746513 -386.271478)
					(end 118.891304 -386.308092)
				)
				(arc
					(start 118.891304 -386.308092)
					(mid 119.10683 -386.218818)
					(end 119.196104 -386.003292)
				)
				(arc
					(start 119.196104 -386.003292)
					(mid 119.185767 -385.924553)
					(end 119.155464 -385.851146)
				)
				(arc
					(start 118.763034 -385.172204)
					(mid 118.650637 -385.050587)
					(end 118.491254 -385.00558)
				)
				(arc
					(start 118.491254 -385.00558)
					(mid 118.275728 -385.094854)
					(end 118.186454 -385.31038)
				)
				(arc
					(start 118.186454 -385.31038)
					(mid 118.196032 -385.386442)
					(end 118.2243 -385.4577)
				)
				(xy 118.621556 -386.145024) (xy 118.633748 -386.16636) (xy 118.636288 -386.170678)
			)
		)
	)
	(zone
		(layers "F.Cu" "B.Cu" "In1.Cu" "In2.Cu" "In3.Cu" "In4.Cu" "In5.Cu" "In6.Cu"
			"In7.Cu" "In8.Cu" "In9.Cu" "In10.Cu" "In11.Cu" "In12.Cu" "In13.Cu" "In14.Cu"
			"In15.Cu" "In16.Cu"
		)
		(hatch none 0.5)
		(connect_pads
			(clearance 0)
		)
		(min_thickness 0.25)
		(keepout
			(tracks not_allowed)
			(vias allowed)
			(pads allowed)
			(copperpour not_allowed)
			(footprints allowed)
		)
		(placement
			(enabled no)
			(sheetname "")
		)
		(fill
			(thermal_gap 0.5)
			(thermal_bridge_width 0.5)
			(island_removal_mode 0)
		)
		(polygon
			(pts
				(xy 519.30046 -450.82841) (xy 529.30044 -450.82841) (xy 528.99564 -450.52361) (xy 519.60526 -450.52361)
			)
		)
	)
	(zone
		(layers "F.Cu" "B.Cu" "In1.Cu" "In2.Cu" "In3.Cu" "In4.Cu" "In5.Cu" "In6.Cu"
			"In7.Cu" "In8.Cu" "In9.Cu" "In10.Cu" "In11.Cu" "In12.Cu" "In13.Cu" "In14.Cu"
			"In15.Cu" "In16.Cu"
		)
		(hatch none 0.5)
		(connect_pads
			(clearance 0)
		)
		(min_thickness 0.25)
		(keepout
			(tracks not_allowed)
			(vias allowed)
			(pads allowed)
			(copperpour not_allowed)
			(footprints allowed)
		)
		(placement
			(enabled no)
			(sheetname "")
		)
		(fill
			(thermal_gap 0.5)
			(thermal_bridge_width 0.5)
			(island_removal_mode 0)
		)
		(polygon
			(pts
				(arc
					(start 358.572562 -434.774086)
					(mid 359.774998 -438.585484)
					(end 360.977434 -434.774086)
				)
				(arc
					(start 360.977434 -434.774086)
					(mid 362.729118 -433.451607)
					(end 363.394498 -431.360072)
				)
				(arc
					(start 363.394498 -431.360072)
					(mid 359.774998 -427.740572)
					(end 356.155498 -431.360072)
				)
				(arc
					(start 356.155498 -431.360072)
					(mid 356.820941 -433.451562)
					(end 358.572562 -434.774086)
				)
			)
		)
	)
	(zone
		(layers "F.Cu" "B.Cu" "In1.Cu" "In2.Cu" "In3.Cu" "In4.Cu" "In5.Cu" "In6.Cu"
			"In7.Cu" "In8.Cu" "In9.Cu" "In10.Cu" "In11.Cu" "In12.Cu" "In13.Cu" "In14.Cu"
			"In15.Cu" "In16.Cu"
		)
		(hatch none 0.5)
		(connect_pads
			(clearance 0)
		)
		(min_thickness 0.25)
		(keepout
			(tracks not_allowed)
			(vias allowed)
			(pads allowed)
			(copperpour not_allowed)
			(footprints allowed)
		)
		(placement
			(enabled no)
			(sheetname "")
		)
		(fill
			(thermal_gap 0.5)
			(thermal_bridge_width 0.5)
			(island_removal_mode 0)
		)
		(polygon
			(pts
				(arc
					(start 336.648044 -381.96393)
					(mid 336.267044 -382.34493)
					(end 336.648044 -382.72593)
				)
				(arc
					(start 337.511644 -382.72593)
					(mid 337.892644 -382.34493)
					(end 337.511644 -381.96393)
				)
			)
		)
	)
	(zone
		(layers "F.Cu" "B.Cu" "In1.Cu" "In2.Cu" "In3.Cu" "In4.Cu" "In5.Cu" "In6.Cu"
			"In7.Cu" "In8.Cu" "In9.Cu" "In10.Cu" "In11.Cu" "In12.Cu" "In13.Cu" "In14.Cu"
			"In15.Cu" "In16.Cu"
		)
		(hatch none 0.5)
		(connect_pads
			(clearance 0)
		)
		(min_thickness 0.25)
		(keepout
			(tracks not_allowed)
			(vias allowed)
			(pads allowed)
			(copperpour not_allowed)
			(footprints allowed)
		)
		(placement
			(enabled no)
			(sheetname "")
		)
		(fill
			(thermal_gap 0.5)
			(thermal_bridge_width 0.5)
			(island_removal_mode 0)
		)
		(polygon
			(pts
				(arc
					(start 62.782958 -43.850052)
					(mid 59.583066 -47.049944)
					(end 62.782958 -50.249836)
				)
				(arc
					(start 64.382904 -50.249836)
					(mid 67.582796 -47.049944)
					(end 64.382904 -43.850052)
				)
			)
		)
	)
	(zone
		(layers "F.Cu" "B.Cu" "In1.Cu" "In2.Cu" "In3.Cu" "In4.Cu" "In5.Cu" "In6.Cu"
			"In7.Cu" "In8.Cu" "In9.Cu" "In10.Cu" "In11.Cu" "In12.Cu" "In13.Cu" "In14.Cu"
			"In15.Cu" "In16.Cu"
		)
		(hatch none 0.5)
		(connect_pads
			(clearance 0)
		)
		(min_thickness 0.25)
		(keepout
			(tracks not_allowed)
			(vias allowed)
			(pads allowed)
			(copperpour not_allowed)
			(footprints allowed)
		)
		(placement
			(enabled no)
			(sheetname "")
		)
		(fill
			(thermal_gap 0.5)
			(thermal_bridge_width 0.5)
			(island_removal_mode 0)
		)
		(polygon
			(pts
				(arc
					(start 415.23031 -4.582414)
					(mid 414.84931 -4.963414)
					(end 415.23031 -5.344414)
				)
				(arc
					(start 416.09391 -5.344414)
					(mid 416.47491 -4.963414)
					(end 416.09391 -4.582414)
				)
			)
		)
	)
	(zone
		(layers "F.Cu" "B.Cu" "In1.Cu" "In2.Cu" "In3.Cu" "In4.Cu" "In5.Cu" "In6.Cu"
			"In7.Cu" "In8.Cu" "In9.Cu" "In10.Cu" "In11.Cu" "In12.Cu" "In13.Cu" "In14.Cu"
			"In15.Cu" "In16.Cu"
		)
		(hatch none 0.5)
		(connect_pads
			(clearance 0)
		)
		(min_thickness 0.25)
		(keepout
			(tracks not_allowed)
			(vias allowed)
			(pads allowed)
			(copperpour not_allowed)
			(footprints allowed)
		)
		(placement
			(enabled no)
			(sheetname "")
		)
		(fill
			(thermal_gap 0.5)
			(thermal_bridge_width 0.5)
			(island_removal_mode 0)
		)
		(polygon
			(pts
				(arc
					(start 64.641984 -409.649168)
					(mid 64.260984 -410.030168)
					(end 64.641984 -410.411168)
				)
				(arc
					(start 65.505584 -410.411168)
					(mid 65.886584 -410.030168)
					(end 65.505584 -409.649168)
				)
			)
		)
	)
	(zone
		(layers "F.Cu" "B.Cu" "In1.Cu" "In2.Cu" "In3.Cu" "In4.Cu" "In5.Cu" "In6.Cu"
			"In7.Cu" "In8.Cu" "In9.Cu" "In10.Cu" "In11.Cu" "In12.Cu" "In13.Cu" "In14.Cu"
			"In15.Cu" "In16.Cu"
		)
		(hatch none 0.5)
		(connect_pads
			(clearance 0)
		)
		(min_thickness 0.25)
		(keepout
			(tracks not_allowed)
			(vias allowed)
			(pads allowed)
			(copperpour not_allowed)
			(footprints allowed)
		)
		(placement
			(enabled no)
			(sheetname "")
		)
		(fill
			(thermal_gap 0.5)
			(thermal_bridge_width 0.5)
			(island_removal_mode 0)
		)
		(polygon
			(pts
				(arc
					(start 115.220496 -373.58193)
					(mid 114.839496 -373.96293)
					(end 115.220496 -374.34393)
				)
				(arc
					(start 116.084096 -374.34393)
					(mid 116.465096 -373.96293)
					(end 116.084096 -373.58193)
				)
			)
		)
	)
	(zone
		(layers "F.Cu" "B.Cu" "In1.Cu" "In2.Cu" "In3.Cu" "In4.Cu" "In5.Cu" "In6.Cu"
			"In7.Cu" "In8.Cu" "In9.Cu" "In10.Cu" "In11.Cu" "In12.Cu" "In13.Cu" "In14.Cu"
			"In15.Cu" "In16.Cu"
		)
		(hatch none 0.5)
		(connect_pads
			(clearance 0)
		)
		(min_thickness 0.25)
		(keepout
			(tracks not_allowed)
			(vias allowed)
			(pads allowed)
			(copperpour not_allowed)
			(footprints allowed)
		)
		(placement
			(enabled no)
			(sheetname "")
		)
		(fill
			(thermal_gap 0.5)
			(thermal_bridge_width 0.5)
			(island_removal_mode 0)
		)
		(polygon
			(pts
				(arc
					(start 164.364162 -389.634476)
					(mid 164.474133 -389.73553)
					(end 164.618924 -389.772144)
				)
				(arc
					(start 164.618924 -389.772144)
					(mid 164.83445 -389.68287)
					(end 164.923724 -389.467344)
				)
				(arc
					(start 164.923724 -389.467344)
					(mid 164.913387 -389.388605)
					(end 164.883084 -389.315198)
				)
				(arc
					(start 164.490654 -388.636256)
					(mid 164.378257 -388.514639)
					(end 164.218874 -388.469632)
				)
				(arc
					(start 164.218874 -388.469632)
					(mid 164.003348 -388.558906)
					(end 163.914074 -388.774432)
				)
				(arc
					(start 163.914074 -388.774432)
					(mid 163.923652 -388.850494)
					(end 163.95192 -388.921752)
				)
				(xy 164.349176 -389.609076) (xy 164.361368 -389.630412) (xy 164.363908 -389.63473)
			)
		)
	)
	(zone
		(layers "F.Cu" "B.Cu" "In1.Cu" "In2.Cu" "In3.Cu" "In4.Cu" "In5.Cu" "In6.Cu"
			"In7.Cu" "In8.Cu" "In9.Cu" "In10.Cu" "In11.Cu" "In12.Cu" "In13.Cu" "In14.Cu"
			"In15.Cu" "In16.Cu"
		)
		(hatch none 0.5)
		(connect_pads
			(clearance 0)
		)
		(min_thickness 0.25)
		(keepout
			(tracks not_allowed)
			(vias allowed)
			(pads allowed)
			(copperpour not_allowed)
			(footprints allowed)
		)
		(placement
			(enabled no)
			(sheetname "")
		)
		(fill
			(thermal_gap 0.5)
			(thermal_bridge_width 0.5)
			(island_removal_mode 0)
		)
		(polygon
			(pts
				(arc
					(start 282.853892 -373.956834)
					(mid 283.234892 -374.337834)
					(end 283.615892 -373.956834)
				)
				(arc
					(start 283.615892 -373.093234)
					(mid 283.234892 -372.712234)
					(end 282.853892 -373.093234)
				)
			)
		)
	)
	(zone
		(layers "F.Cu" "B.Cu" "In1.Cu" "In2.Cu" "In3.Cu" "In4.Cu" "In5.Cu" "In6.Cu"
			"In7.Cu" "In8.Cu" "In9.Cu" "In10.Cu" "In11.Cu" "In12.Cu" "In13.Cu" "In14.Cu"
			"In15.Cu" "In16.Cu"
		)
		(hatch none 0.5)
		(connect_pads
			(clearance 0)
		)
		(min_thickness 0.25)
		(keepout
			(tracks not_allowed)
			(vias allowed)
			(pads allowed)
			(copperpour not_allowed)
			(footprints allowed)
		)
		(placement
			(enabled no)
			(sheetname "")
		)
		(fill
			(thermal_gap 0.5)
			(thermal_bridge_width 0.5)
			(island_removal_mode 0)
		)
		(polygon
			(pts
				(arc
					(start 339.125052 -400.811238)
					(mid 338.744052 -400.430238)
					(end 338.363052 -400.811238)
				)
				(arc
					(start 338.363052 -401.674838)
					(mid 338.744052 -402.055838)
					(end 339.125052 -401.674838)
				)
			)
		)
	)
	(zone
		(layers "F.Cu" "B.Cu" "In1.Cu" "In2.Cu" "In3.Cu" "In4.Cu" "In5.Cu" "In6.Cu"
			"In7.Cu" "In8.Cu" "In9.Cu" "In10.Cu" "In11.Cu" "In12.Cu" "In13.Cu" "In14.Cu"
			"In15.Cu" "In16.Cu"
		)
		(hatch none 0.5)
		(connect_pads
			(clearance 0)
		)
		(min_thickness 0.25)
		(keepout
			(tracks not_allowed)
			(vias allowed)
			(pads allowed)
			(copperpour not_allowed)
			(footprints allowed)
		)
		(placement
			(enabled no)
			(sheetname "")
		)
		(fill
			(thermal_gap 0.5)
			(thermal_bridge_width 0.5)
			(island_removal_mode 0)
		)
		(polygon
			(pts
				(arc
					(start 84.553044 -412.189168)
					(mid 84.172044 -412.570168)
					(end 84.553044 -412.951168)
				)
				(arc
					(start 85.416644 -412.951168)
					(mid 85.797644 -412.570168)
					(end 85.416644 -412.189168)
				)
			)
		)
	)
	(zone
		(layers "F.Cu" "B.Cu" "In1.Cu" "In2.Cu" "In3.Cu" "In4.Cu" "In5.Cu" "In6.Cu"
			"In7.Cu" "In8.Cu" "In9.Cu" "In10.Cu" "In11.Cu" "In12.Cu" "In13.Cu" "In14.Cu"
			"In15.Cu" "In16.Cu"
		)
		(hatch none 0.5)
		(connect_pads
			(clearance 0)
		)
		(min_thickness 0.25)
		(keepout
			(tracks not_allowed)
			(vias allowed)
			(pads allowed)
			(copperpour not_allowed)
			(footprints allowed)
		)
		(placement
			(enabled no)
			(sheetname "")
		)
		(fill
			(thermal_gap 0.5)
			(thermal_bridge_width 0.5)
			(island_removal_mode 0)
		)
		(polygon
			(pts
				(arc
					(start 151.151844 -368.65433)
					(mid 150.770844 -369.03533)
					(end 151.151844 -369.41633)
				)
				(arc
					(start 152.015444 -369.41633)
					(mid 152.396444 -369.03533)
					(end 152.015444 -368.65433)
				)
			)
		)
	)
	(zone
		(layers "F.Cu" "B.Cu" "In1.Cu" "In2.Cu" "In3.Cu" "In4.Cu" "In5.Cu" "In6.Cu"
			"In7.Cu" "In8.Cu" "In9.Cu" "In10.Cu" "In11.Cu" "In12.Cu" "In13.Cu" "In14.Cu"
			"In15.Cu" "In16.Cu"
		)
		(hatch none 0.5)
		(connect_pads
			(clearance 0)
		)
		(min_thickness 0.25)
		(keepout
			(tracks not_allowed)
			(vias allowed)
			(pads allowed)
			(copperpour not_allowed)
			(footprints allowed)
		)
		(placement
			(enabled no)
			(sheetname "")
		)
		(fill
			(thermal_gap 0.5)
			(thermal_bridge_width 0.5)
			(island_removal_mode 0)
		)
		(polygon
			(pts
				(arc
					(start 116.600224 -23.774654)
					(mid 116.219224 -24.155654)
					(end 116.600224 -24.536654)
				)
				(arc
					(start 117.463824 -24.536654)
					(mid 117.844824 -24.155654)
					(end 117.463824 -23.774654)
				)
			)
		)
	)
	(zone
		(layers "F.Cu" "B.Cu" "In1.Cu" "In2.Cu" "In3.Cu" "In4.Cu" "In5.Cu" "In6.Cu"
			"In7.Cu" "In8.Cu" "In9.Cu" "In10.Cu" "In11.Cu" "In12.Cu" "In13.Cu" "In14.Cu"
			"In15.Cu" "In16.Cu"
		)
		(hatch none 0.5)
		(connect_pads
			(clearance 0)
		)
		(min_thickness 0.25)
		(keepout
			(tracks not_allowed)
			(vias allowed)
			(pads allowed)
			(copperpour not_allowed)
			(footprints allowed)
		)
		(placement
			(enabled no)
			(sheetname "")
		)
		(fill yes
			(thermal_gap 0.5)
			(thermal_bridge_width 0.5)
			(island_removal_mode 0)
		)
		(polygon
			(pts
				(arc
					(start 340.06409 -394.552424)
					(mid 340.174061 -394.653478)
					(end 340.318852 -394.690092)
				)
				(arc
					(start 340.318852 -394.690092)
					(mid 340.534378 -394.600818)
					(end 340.623652 -394.385292)
				)
				(arc
					(start 340.623652 -394.385292)
					(mid 340.613315 -394.306553)
					(end 340.583012 -394.233146)
				)
				(arc
					(start 340.190582 -393.554204)
					(mid 340.078185 -393.432587)
					(end 339.918802 -393.38758)
				)
				(arc
					(start 339.918802 -393.38758)
					(mid 339.703276 -393.476854)
					(end 339.614002 -393.69238)
				)
				(arc
					(start 339.614002 -393.69238)
					(mid 339.62358 -393.768442)
					(end 339.651848 -393.8397)
				)
				(xy 340.049104 -394.527024) (xy 340.061296 -394.54836) (xy 340.063836 -394.552678)
			)
		)
	)
	(zone
		(layers "F.Cu" "B.Cu" "In1.Cu" "In2.Cu" "In3.Cu" "In4.Cu" "In5.Cu" "In6.Cu"
			"In7.Cu" "In8.Cu" "In9.Cu" "In10.Cu" "In11.Cu" "In12.Cu" "In13.Cu" "In14.Cu"
			"In15.Cu" "In16.Cu"
		)
		(hatch none 0.5)
		(connect_pads
			(clearance 0)
		)
		(min_thickness 0.25)
		(keepout
			(tracks not_allowed)
			(vias allowed)
			(pads allowed)
			(copperpour not_allowed)
			(footprints allowed)
		)
		(placement
			(enabled no)
			(sheetname "")
		)
		(fill
			(thermal_gap 0.5)
			(thermal_bridge_width 0.5)
			(island_removal_mode 0)
		)
		(polygon
			(pts
				(arc
					(start 130.536696 -371.11813)
					(mid 130.155696 -371.49913)
					(end 130.536696 -371.88013)
				)
				(arc
					(start 131.400296 -371.88013)
					(mid 131.781296 -371.49913)
					(end 131.400296 -371.11813)
				)
			)
		)
	)
	(zone
		(layers "F.Cu" "B.Cu" "In1.Cu" "In2.Cu" "In3.Cu" "In4.Cu" "In5.Cu" "In6.Cu"
			"In7.Cu" "In8.Cu" "In9.Cu" "In10.Cu" "In11.Cu" "In12.Cu" "In13.Cu" "In14.Cu"
			"In15.Cu" "In16.Cu"
		)
		(hatch none 0.5)
		(connect_pads
			(clearance 0)
		)
		(min_thickness 0.25)
		(keepout
			(tracks not_allowed)
			(vias allowed)
			(pads allowed)
			(copperpour not_allowed)
			(footprints allowed)
		)
		(placement
			(enabled no)
			(sheetname "")
		)
		(fill
			(thermal_gap 0.5)
			(thermal_bridge_width 0.5)
			(island_removal_mode 0)
		)
		(polygon
			(pts
				(arc
					(start 63.797434 -392.429238)
					(mid 63.416434 -392.048238)
					(end 63.035434 -392.429238)
				)
				(arc
					(start 63.035434 -393.292838)
					(mid 63.416434 -393.673838)
					(end 63.797434 -393.292838)
				)
			)
		)
	)
	(zone
		(layers "F.Cu" "B.Cu" "In1.Cu" "In2.Cu" "In3.Cu" "In4.Cu" "In5.Cu" "In6.Cu"
			"In7.Cu" "In8.Cu" "In9.Cu" "In10.Cu" "In11.Cu" "In12.Cu" "In13.Cu" "In14.Cu"
			"In15.Cu" "In16.Cu"
		)
		(hatch none 0.5)
		(connect_pads
			(clearance 0)
		)
		(min_thickness 0.25)
		(keepout
			(tracks not_allowed)
			(vias allowed)
			(pads allowed)
			(copperpour not_allowed)
			(footprints allowed)
		)
		(placement
			(enabled no)
			(sheetname "")
		)
		(fill
			(thermal_gap 0.5)
			(thermal_bridge_width 0.5)
			(island_removal_mode 0)
		)
		(polygon
			(pts
				(arc
					(start 338.86394 -398.016476)
					(mid 338.973911 -398.11753)
					(end 339.118702 -398.154144)
				)
				(arc
					(start 339.118702 -398.154144)
					(mid 339.334228 -398.06487)
					(end 339.423502 -397.849344)
				)
				(arc
					(start 339.423502 -397.849344)
					(mid 339.413165 -397.770605)
					(end 339.382862 -397.697198)
				)
				(arc
					(start 338.990432 -397.018256)
					(mid 338.878035 -396.896639)
					(end 338.718652 -396.851632)
				)
				(arc
					(start 338.718652 -396.851632)
					(mid 338.503126 -396.940906)
					(end 338.413852 -397.156432)
				)
				(arc
					(start 338.413852 -397.156432)
					(mid 338.42343 -397.232494)
					(end 338.451698 -397.303752)
				)
				(xy 338.848954 -397.991076) (xy 338.861146 -398.012412) (xy 338.863686 -398.01673)
			)
		)
	)
	(zone
		(layers "F.Cu" "B.Cu" "In1.Cu" "In2.Cu" "In3.Cu" "In4.Cu" "In5.Cu" "In6.Cu"
			"In7.Cu" "In8.Cu" "In9.Cu" "In10.Cu" "In11.Cu" "In12.Cu" "In13.Cu" "In14.Cu"
			"In15.Cu" "In16.Cu"
		)
		(hatch none 0.5)
		(connect_pads
			(clearance 0)
		)
		(min_thickness 0.25)
		(keepout
			(tracks not_allowed)
			(vias allowed)
			(pads allowed)
			(copperpour not_allowed)
			(footprints allowed)
		)
		(placement
			(enabled no)
			(sheetname "")
		)
		(fill yes
			(thermal_gap 0.5)
			(thermal_bridge_width 0.5)
			(island_removal_mode 0)
		)
		(polygon
			(pts
				(arc
					(start 158.364174 -386.170424)
					(mid 158.474145 -386.271478)
					(end 158.618936 -386.308092)
				)
				(arc
					(start 158.618936 -386.308092)
					(mid 158.834462 -386.218818)
					(end 158.923736 -386.003292)
				)
				(arc
					(start 158.923736 -386.003292)
					(mid 158.913399 -385.924553)
					(end 158.883096 -385.851146)
				)
				(arc
					(start 158.490666 -385.172204)
					(mid 158.378269 -385.050587)
					(end 158.218886 -385.00558)
				)
				(arc
					(start 158.218886 -385.00558)
					(mid 158.00336 -385.094854)
					(end 157.914086 -385.31038)
				)
				(arc
					(start 157.914086 -385.31038)
					(mid 157.923664 -385.386442)
					(end 157.951932 -385.4577)
				)
				(xy 158.349188 -386.145024) (xy 158.36138 -386.16636) (xy 158.36392 -386.170678)
			)
		)
	)
	(zone
		(layers "F.Cu" "B.Cu" "In1.Cu" "In2.Cu" "In3.Cu" "In4.Cu" "In5.Cu" "In6.Cu"
			"In7.Cu" "In8.Cu" "In9.Cu" "In10.Cu" "In11.Cu" "In12.Cu" "In13.Cu" "In14.Cu"
			"In15.Cu" "In16.Cu"
		)
		(hatch none 0.5)
		(connect_pads
			(clearance 0)
		)
		(min_thickness 0.25)
		(keepout
			(tracks not_allowed)
			(vias allowed)
			(pads allowed)
			(copperpour not_allowed)
			(footprints allowed)
		)
		(placement
			(enabled no)
			(sheetname "")
		)
		(fill yes
			(thermal_gap 0.5)
			(thermal_bridge_width 0.5)
			(island_removal_mode 0)
		)
		(polygon
			(pts
				(arc
					(start 295.070022 -384.869944)
					(mid 291.07003 -388.869936)
					(end 287.070038 -384.869944)
				)
				(arc
					(start 287.070038 -384.869944)
					(mid 291.07003 -380.869952)
					(end 295.070022 -384.869944)
				)
			)
		)
	)
	(zone
		(layers "F.Cu" "B.Cu" "In1.Cu" "In2.Cu" "In3.Cu" "In4.Cu" "In5.Cu" "In6.Cu"
			"In7.Cu" "In8.Cu" "In9.Cu" "In10.Cu" "In11.Cu" "In12.Cu" "In13.Cu" "In14.Cu"
			"In15.Cu" "In16.Cu"
		)
		(hatch none 0.5)
		(connect_pads
			(clearance 0)
		)
		(min_thickness 0.25)
		(keepout
			(tracks not_allowed)
			(vias allowed)
			(pads allowed)
			(copperpour not_allowed)
			(footprints allowed)
		)
		(placement
			(enabled no)
			(sheetname "")
		)
		(fill
			(thermal_gap 0.5)
			(thermal_bridge_width 0.5)
			(island_removal_mode 0)
		)
		(polygon
			(pts
				(arc
					(start 145.042636 -212.98027)
					(mid 140.012928 -212.98027)
					(end 145.042636 -212.98027)
				)
			)
		)
	)
	(zone
		(layers "F.Cu" "B.Cu" "In1.Cu" "In2.Cu" "In3.Cu" "In4.Cu" "In5.Cu" "In6.Cu"
			"In7.Cu" "In8.Cu" "In9.Cu" "In10.Cu" "In11.Cu" "In12.Cu" "In13.Cu" "In14.Cu"
			"In15.Cu" "In16.Cu"
		)
		(hatch none 0.5)
		(connect_pads
			(clearance 0)
		)
		(min_thickness 0.25)
		(keepout
			(tracks not_allowed)
			(vias allowed)
			(pads allowed)
			(copperpour not_allowed)
			(footprints allowed)
		)
		(placement
			(enabled no)
			(sheetname "")
		)
		(fill
			(thermal_gap 0.5)
			(thermal_bridge_width 0.5)
			(island_removal_mode 0)
		)
		(polygon
			(pts
				(arc
					(start 334.426306 -412.46552)
					(mid 334.045306 -412.84652)
					(end 334.426306 -413.22752)
				)
				(arc
					(start 335.289906 -413.22752)
					(mid 335.670906 -412.84652)
					(end 335.289906 -412.46552)
				)
			)
		)
	)
	(zone
		(layers "F.Cu" "B.Cu" "In1.Cu" "In2.Cu" "In3.Cu" "In4.Cu" "In5.Cu" "In6.Cu"
			"In7.Cu" "In8.Cu" "In9.Cu" "In10.Cu" "In11.Cu" "In12.Cu" "In13.Cu" "In14.Cu"
			"In15.Cu" "In16.Cu"
		)
		(hatch none 0.5)
		(connect_pads
			(clearance 0)
		)
		(min_thickness 0.25)
		(keepout
			(tracks not_allowed)
			(vias allowed)
			(pads allowed)
			(copperpour not_allowed)
			(footprints allowed)
		)
		(placement
			(enabled no)
			(sheetname "")
		)
		(fill
			(thermal_gap 0.5)
			(thermal_bridge_width 0.5)
			(island_removal_mode 0)
		)
		(polygon
			(pts
				(arc
					(start 384.236468 -398.016476)
					(mid 384.346439 -398.11753)
					(end 384.49123 -398.154144)
				)
				(arc
					(start 384.49123 -398.154144)
					(mid 384.706756 -398.06487)
					(end 384.79603 -397.849344)
				)
				(arc
					(start 384.79603 -397.849344)
					(mid 384.785693 -397.770605)
					(end 384.75539 -397.697198)
				)
				(arc
					(start 384.36296 -397.018256)
					(mid 384.250563 -396.896639)
					(end 384.09118 -396.851632)
				)
				(arc
					(start 384.09118 -396.851632)
					(mid 383.875654 -396.940906)
					(end 383.78638 -397.156432)
				)
				(arc
					(start 383.78638 -397.156432)
					(mid 383.795958 -397.232494)
					(end 383.824226 -397.303752)
				)
				(xy 384.221482 -397.991076) (xy 384.233674 -398.012412) (xy 384.236214 -398.01673)
			)
		)
	)
	(zone
		(layers "F.Cu" "B.Cu" "In1.Cu" "In2.Cu" "In3.Cu" "In4.Cu" "In5.Cu" "In6.Cu"
			"In7.Cu" "In8.Cu" "In9.Cu" "In10.Cu" "In11.Cu" "In12.Cu" "In13.Cu" "In14.Cu"
			"In15.Cu" "In16.Cu"
		)
		(hatch none 0.5)
		(connect_pads
			(clearance 0)
		)
		(min_thickness 0.25)
		(keepout
			(tracks not_allowed)
			(vias allowed)
			(pads allowed)
			(copperpour not_allowed)
			(footprints allowed)
		)
		(placement
			(enabled no)
			(sheetname "")
		)
		(fill
			(thermal_gap 0.5)
			(thermal_bridge_width 0.5)
			(island_removal_mode 0)
		)
		(polygon
			(pts
				(arc
					(start 125.836426 -389.634476)
					(mid 125.946397 -389.73553)
					(end 126.091188 -389.772144)
				)
				(arc
					(start 126.091188 -389.772144)
					(mid 126.306714 -389.68287)
					(end 126.395988 -389.467344)
				)
				(arc
					(start 126.395988 -389.467344)
					(mid 126.385651 -389.388605)
					(end 126.355348 -389.315198)
				)
				(arc
					(start 125.962918 -388.636256)
					(mid 125.850521 -388.514639)
					(end 125.691138 -388.469632)
				)
				(arc
					(start 125.691138 -388.469632)
					(mid 125.475612 -388.558906)
					(end 125.386338 -388.774432)
				)
				(arc
					(start 125.386338 -388.774432)
					(mid 125.395916 -388.850494)
					(end 125.424184 -388.921752)
				)
				(xy 125.82144 -389.609076) (xy 125.833632 -389.630412) (xy 125.836172 -389.63473)
			)
		)
	)
	(zone
		(layers "F.Cu" "B.Cu" "In1.Cu" "In2.Cu" "In3.Cu" "In4.Cu" "In5.Cu" "In6.Cu"
			"In7.Cu" "In8.Cu" "In9.Cu" "In10.Cu" "In11.Cu" "In12.Cu" "In13.Cu" "In14.Cu"
			"In15.Cu" "In16.Cu"
		)
		(hatch none 0.5)
		(connect_pads
			(clearance 0)
		)
		(min_thickness 0.25)
		(keepout
			(tracks not_allowed)
			(vias allowed)
			(pads allowed)
			(copperpour not_allowed)
			(footprints allowed)
		)
		(placement
			(enabled no)
			(sheetname "")
		)
		(fill
			(thermal_gap 0.5)
			(thermal_bridge_width 0.5)
			(island_removal_mode 0)
		)
		(polygon
			(pts
				(arc
					(start 122.552206 -406.62352)
					(mid 122.171206 -407.00452)
					(end 122.552206 -407.38552)
				)
				(arc
					(start 123.415806 -407.38552)
					(mid 123.796806 -407.00452)
					(end 123.415806 -406.62352)
				)
			)
		)
	)
	(zone
		(layers "F.Cu" "B.Cu" "In1.Cu" "In2.Cu" "In3.Cu" "In4.Cu" "In5.Cu" "In6.Cu"
			"In7.Cu" "In8.Cu" "In9.Cu" "In10.Cu" "In11.Cu" "In12.Cu" "In13.Cu" "In14.Cu"
			"In15.Cu" "In16.Cu"
		)
		(hatch none 0.5)
		(connect_pads
			(clearance 0)
		)
		(min_thickness 0.25)
		(keepout
			(tracks not_allowed)
			(vias allowed)
			(pads allowed)
			(copperpour not_allowed)
			(footprints allowed)
		)
		(placement
			(enabled no)
			(sheetname "")
		)
		(fill
			(thermal_gap 0.5)
			(thermal_bridge_width 0.5)
			(island_removal_mode 0)
		)
		(polygon
			(pts
				(arc
					(start 314.997338 -400.811238)
					(mid 314.616338 -400.430238)
					(end 314.235338 -400.811238)
				)
				(arc
					(start 314.235338 -401.674838)
					(mid 314.616338 -402.055838)
					(end 314.997338 -401.674838)
				)
			)
		)
	)
	(zone
		(layers "F.Cu" "B.Cu" "In1.Cu" "In2.Cu" "In3.Cu" "In4.Cu" "In5.Cu" "In6.Cu"
			"In7.Cu" "In8.Cu" "In9.Cu" "In10.Cu" "In11.Cu" "In12.Cu" "In13.Cu" "In14.Cu"
			"In15.Cu" "In16.Cu"
		)
		(hatch none 0.5)
		(connect_pads
			(clearance 0)
		)
		(min_thickness 0.25)
		(keepout
			(tracks not_allowed)
			(vias allowed)
			(pads allowed)
			(copperpour not_allowed)
			(footprints allowed)
		)
		(placement
			(enabled no)
			(sheetname "")
		)
		(fill
			(thermal_gap 0.5)
			(thermal_bridge_width 0.5)
			(island_removal_mode 0)
		)
		(polygon
			(pts
				(arc
					(start 352.064066 -398.016476)
					(mid 352.174037 -398.11753)
					(end 352.318828 -398.154144)
				)
				(arc
					(start 352.318828 -398.154144)
					(mid 352.534354 -398.06487)
					(end 352.623628 -397.849344)
				)
				(arc
					(start 352.623628 -397.849344)
					(mid 352.613291 -397.770605)
					(end 352.582988 -397.697198)
				)
				(arc
					(start 352.190558 -397.018256)
					(mid 352.078161 -396.896639)
					(end 351.918778 -396.851632)
				)
				(arc
					(start 351.918778 -396.851632)
					(mid 351.703252 -396.940906)
					(end 351.613978 -397.156432)
				)
				(arc
					(start 351.613978 -397.156432)
					(mid 351.623556 -397.232494)
					(end 351.651824 -397.303752)
				)
				(xy 352.04908 -397.991076) (xy 352.061272 -398.012412) (xy 352.063812 -398.01673)
			)
		)
	)
	(zone
		(layers "F.Cu" "B.Cu" "In1.Cu" "In2.Cu" "In3.Cu" "In4.Cu" "In5.Cu" "In6.Cu"
			"In7.Cu" "In8.Cu" "In9.Cu" "In10.Cu" "In11.Cu" "In12.Cu" "In13.Cu" "In14.Cu"
			"In15.Cu" "In16.Cu"
		)
		(hatch none 0.5)
		(connect_pads
			(clearance 0)
		)
		(min_thickness 0.25)
		(keepout
			(tracks not_allowed)
			(vias allowed)
			(pads allowed)
			(copperpour not_allowed)
			(footprints allowed)
		)
		(placement
			(enabled no)
			(sheetname "")
		)
		(fill
			(thermal_gap 0.5)
			(thermal_bridge_width 0.5)
			(island_removal_mode 0)
		)
		(polygon
			(pts
				(arc
					(start 80.464406 -389.634476)
					(mid 80.574377 -389.73553)
					(end 80.719168 -389.772144)
				)
				(arc
					(start 80.719168 -389.772144)
					(mid 80.934694 -389.68287)
					(end 81.023968 -389.467344)
				)
				(arc
					(start 81.023968 -389.467344)
					(mid 81.013631 -389.388605)
					(end 80.983328 -389.315198)
				)
				(arc
					(start 80.590898 -388.636256)
					(mid 80.478501 -388.514639)
					(end 80.319118 -388.469632)
				)
				(arc
					(start 80.319118 -388.469632)
					(mid 80.103592 -388.558906)
					(end 80.014318 -388.774432)
				)
				(arc
					(start 80.014318 -388.774432)
					(mid 80.023896 -388.850494)
					(end 80.052164 -388.921752)
				)
				(xy 80.44942 -389.609076) (xy 80.461612 -389.630412) (xy 80.464152 -389.63473)
			)
		)
	)
	(zone
		(layers "F.Cu" "B.Cu" "In1.Cu" "In2.Cu" "In3.Cu" "In4.Cu" "In5.Cu" "In6.Cu"
			"In7.Cu" "In8.Cu" "In9.Cu" "In10.Cu" "In11.Cu" "In12.Cu" "In13.Cu" "In14.Cu"
			"In15.Cu" "In16.Cu"
		)
		(hatch none 0.5)
		(connect_pads
			(clearance 0)
		)
		(min_thickness 0.25)
		(keepout
			(tracks not_allowed)
			(vias allowed)
			(pads allowed)
			(copperpour not_allowed)
			(footprints allowed)
		)
		(placement
			(enabled no)
			(sheetname "")
		)
		(fill
			(thermal_gap 0.5)
			(thermal_bridge_width 0.5)
			(island_removal_mode 0)
		)
		(polygon
			(pts
				(arc
					(start 373.957342 -420.571168)
					(mid 373.576342 -420.952168)
					(end 373.957342 -421.333168)
				)
				(arc
					(start 374.820942 -421.333168)
					(mid 375.201942 -420.952168)
					(end 374.820942 -420.571168)
				)
			)
		)
	)
	(zone
		(layers "F.Cu" "B.Cu" "In1.Cu" "In2.Cu" "In3.Cu" "In4.Cu" "In5.Cu" "In6.Cu"
			"In7.Cu" "In8.Cu" "In9.Cu" "In10.Cu" "In11.Cu" "In12.Cu" "In13.Cu" "In14.Cu"
			"In15.Cu" "In16.Cu"
		)
		(hatch none 0.5)
		(connect_pads
			(clearance 0)
		)
		(min_thickness 0.25)
		(keepout
			(tracks not_allowed)
			(vias allowed)
			(pads allowed)
			(copperpour not_allowed)
			(footprints allowed)
		)
		(placement
			(enabled no)
			(sheetname "")
		)
		(fill
			(thermal_gap 0.5)
			(thermal_bridge_width 0.5)
			(island_removal_mode 0)
		)
		(polygon
			(pts
				(arc
					(start 385.697476 -400.811238)
					(mid 385.316476 -400.430238)
					(end 384.935476 -400.811238)
				)
				(arc
					(start 384.935476 -401.674838)
					(mid 385.316476 -402.055838)
					(end 385.697476 -401.674838)
				)
			)
		)
	)
	(zone
		(layers "F.Cu" "B.Cu" "In1.Cu" "In2.Cu" "In3.Cu" "In4.Cu" "In5.Cu" "In6.Cu"
			"In7.Cu" "In8.Cu" "In9.Cu" "In10.Cu" "In11.Cu" "In12.Cu" "In13.Cu" "In14.Cu"
			"In15.Cu" "In16.Cu"
		)
		(hatch none 0.5)
		(connect_pads
			(clearance 0)
		)
		(min_thickness 0.25)
		(keepout
			(tracks not_allowed)
			(vias allowed)
			(pads allowed)
			(copperpour not_allowed)
			(footprints allowed)
		)
		(placement
			(enabled no)
			(sheetname "")
		)
		(fill
			(thermal_gap 0.5)
			(thermal_bridge_width 0.5)
			(island_removal_mode 0)
		)
		(polygon
			(pts
				(arc
					(start 386.536692 -379.50013)
					(mid 386.155692 -379.88113)
					(end 386.536692 -380.26213)
				)
				(arc
					(start 387.400292 -380.26213)
					(mid 387.781292 -379.88113)
					(end 387.400292 -379.50013)
				)
			)
		)
	)
	(zone
		(layers "F.Cu" "B.Cu" "In1.Cu" "In2.Cu" "In3.Cu" "In4.Cu" "In5.Cu" "In6.Cu"
			"In7.Cu" "In8.Cu" "In9.Cu" "In10.Cu" "In11.Cu" "In12.Cu" "In13.Cu" "In14.Cu"
			"In15.Cu" "In16.Cu"
		)
		(hatch none 0.5)
		(connect_pads
			(clearance 0)
		)
		(min_thickness 0.25)
		(keepout
			(tracks not_allowed)
			(vias allowed)
			(pads allowed)
			(copperpour not_allowed)
			(footprints allowed)
		)
		(placement
			(enabled no)
			(sheetname "")
		)
		(fill
			(thermal_gap 0.5)
			(thermal_bridge_width 0.5)
			(island_removal_mode 0)
		)
		(polygon
			(pts
				(arc
					(start 418.27958 -17.23136)
					(mid 417.89858 -17.61236)
					(end 418.27958 -17.99336)
				)
				(arc
					(start 419.14318 -17.99336)
					(mid 419.52418 -17.61236)
					(end 419.14318 -17.23136)
				)
			)
		)
	)
	(zone
		(layers "F.Cu" "B.Cu" "In1.Cu" "In2.Cu" "In3.Cu" "In4.Cu" "In5.Cu" "In6.Cu"
			"In7.Cu" "In8.Cu" "In9.Cu" "In10.Cu" "In11.Cu" "In12.Cu" "In13.Cu" "In14.Cu"
			"In15.Cu" "In16.Cu"
		)
		(hatch none 0.5)
		(connect_pads
			(clearance 0)
		)
		(min_thickness 0.25)
		(keepout
			(tracks not_allowed)
			(vias allowed)
			(pads allowed)
			(copperpour not_allowed)
			(footprints allowed)
		)
		(placement
			(enabled no)
			(sheetname "")
		)
		(fill
			(thermal_gap 0.5)
			(thermal_bridge_width 0.5)
			(island_removal_mode 0)
		)
		(polygon
			(pts
				(arc
					(start 51.797458 -392.429238)
					(mid 51.416458 -392.048238)
					(end 51.035458 -392.429238)
				)
				(arc
					(start 51.035458 -393.292838)
					(mid 51.416458 -393.673838)
					(end 51.797458 -393.292838)
				)
			)
		)
	)
	(zone
		(layers "F.Cu" "B.Cu" "In1.Cu" "In2.Cu" "In3.Cu" "In4.Cu" "In5.Cu" "In6.Cu"
			"In7.Cu" "In8.Cu" "In9.Cu" "In10.Cu" "In11.Cu" "In12.Cu" "In13.Cu" "In14.Cu"
			"In15.Cu" "In16.Cu"
		)
		(hatch none 0.5)
		(connect_pads
			(clearance 0)
		)
		(min_thickness 0.25)
		(keepout
			(tracks not_allowed)
			(vias allowed)
			(pads allowed)
			(copperpour not_allowed)
			(footprints allowed)
		)
		(placement
			(enabled no)
			(sheetname "")
		)
		(fill
			(thermal_gap 0.5)
			(thermal_bridge_width 0.5)
			(island_removal_mode 0)
		)
		(polygon
			(pts
				(arc
					(start 412.247842 -418.031168)
					(mid 411.866842 -418.412168)
					(end 412.247842 -418.793168)
				)
				(arc
					(start 413.111442 -418.793168)
					(mid 413.492442 -418.412168)
					(end 413.111442 -418.031168)
				)
			)
		)
	)
	(zone
		(layers "F.Cu" "B.Cu" "In1.Cu" "In2.Cu" "In3.Cu" "In4.Cu" "In5.Cu" "In6.Cu"
			"In7.Cu" "In8.Cu" "In9.Cu" "In10.Cu" "In11.Cu" "In12.Cu" "In13.Cu" "In14.Cu"
			"In15.Cu" "In16.Cu"
		)
		(hatch none 0.5)
		(connect_pads
			(clearance 0)
		)
		(min_thickness 0.25)
		(keepout
			(tracks not_allowed)
			(vias allowed)
			(pads allowed)
			(copperpour not_allowed)
			(footprints allowed)
		)
		(placement
			(enabled no)
			(sheetname "")
		)
		(fill
			(thermal_gap 0.5)
			(thermal_bridge_width 0.5)
			(island_removal_mode 0)
		)
		(polygon
			(pts
				(arc
					(start 395.400022 -412.46552)
					(mid 395.019022 -412.84652)
					(end 395.400022 -413.22752)
				)
				(arc
					(start 396.263622 -413.22752)
					(mid 396.644622 -412.84652)
					(end 396.263622 -412.46552)
				)
			)
		)
	)
	(zone
		(layers "F.Cu" "B.Cu" "In1.Cu" "In2.Cu" "In3.Cu" "In4.Cu" "In5.Cu" "In6.Cu"
			"In7.Cu" "In8.Cu" "In9.Cu" "In10.Cu" "In11.Cu" "In12.Cu" "In13.Cu" "In14.Cu"
			"In15.Cu" "In16.Cu"
		)
		(hatch none 0.5)
		(connect_pads
			(clearance 0)
		)
		(min_thickness 0.25)
		(keepout
			(tracks not_allowed)
			(vias allowed)
			(pads allowed)
			(copperpour not_allowed)
			(footprints allowed)
		)
		(placement
			(enabled no)
			(sheetname "")
		)
		(fill
			(thermal_gap 0.5)
			(thermal_bridge_width 0.5)
			(island_removal_mode 0)
		)
		(polygon
			(pts
				(arc
					(start 43.779694 -17.23136)
					(mid 43.398694 -17.61236)
					(end 43.779694 -17.99336)
				)
				(arc
					(start 44.643294 -17.99336)
					(mid 45.024294 -17.61236)
					(end 44.643294 -17.23136)
				)
			)
		)
	)
	(zone
		(layers "F.Cu" "B.Cu" "In1.Cu" "In2.Cu" "In3.Cu" "In4.Cu" "In5.Cu" "In6.Cu"
			"In7.Cu" "In8.Cu" "In9.Cu" "In10.Cu" "In11.Cu" "In12.Cu" "In13.Cu" "In14.Cu"
			"In15.Cu" "In16.Cu"
		)
		(hatch none 0.5)
		(connect_pads
			(clearance 0)
		)
		(min_thickness 0.25)
		(keepout
			(tracks not_allowed)
			(vias allowed)
			(pads allowed)
			(copperpour not_allowed)
			(footprints allowed)
		)
		(placement
			(enabled no)
			(sheetname "")
		)
		(fill
			(thermal_gap 0.5)
			(thermal_bridge_width 0.5)
			(island_removal_mode 0)
		)
		(polygon
			(pts
				(arc
					(start 32.296862 -17.232122)
					(mid 31.915862 -17.613122)
					(end 32.296862 -17.994122)
				)
				(arc
					(start 33.160462 -17.994122)
					(mid 33.541462 -17.613122)
					(end 33.160462 -17.232122)
				)
			)
		)
	)
	(zone
		(layers "F.Cu" "B.Cu" "In1.Cu" "In2.Cu" "In3.Cu" "In4.Cu" "In5.Cu" "In6.Cu"
			"In7.Cu" "In8.Cu" "In9.Cu" "In10.Cu" "In11.Cu" "In12.Cu" "In13.Cu" "In14.Cu"
			"In15.Cu" "In16.Cu"
		)
		(hatch none 0.5)
		(connect_pads
			(clearance 0)
		)
		(min_thickness 0.25)
		(keepout
			(tracks not_allowed)
			(vias allowed)
			(pads allowed)
			(copperpour not_allowed)
			(footprints allowed)
		)
		(placement
			(enabled no)
			(sheetname "")
		)
		(fill yes
			(thermal_gap 0.5)
			(thermal_bridge_width 0.5)
			(island_removal_mode 0)
		)
		(polygon
			(pts
				(arc
					(start 63.536576 -386.170424)
					(mid 63.646547 -386.271478)
					(end 63.791338 -386.308092)
				)
				(arc
					(start 63.791338 -386.308092)
					(mid 64.006864 -386.218818)
					(end 64.096138 -386.003292)
				)
				(arc
					(start 64.096138 -386.003292)
					(mid 64.085801 -385.924553)
					(end 64.055498 -385.851146)
				)
				(arc
					(start 63.663068 -385.172204)
					(mid 63.550671 -385.050587)
					(end 63.391288 -385.00558)
				)
				(arc
					(start 63.391288 -385.00558)
					(mid 63.175762 -385.094854)
					(end 63.086488 -385.31038)
				)
				(arc
					(start 63.086488 -385.31038)
					(mid 63.096066 -385.386442)
					(end 63.124334 -385.4577)
				)
				(xy 63.52159 -386.145024) (xy 63.533782 -386.16636) (xy 63.536322 -386.170678)
			)
		)
	)
	(zone
		(layers "F.Cu" "B.Cu" "In1.Cu" "In2.Cu" "In3.Cu" "In4.Cu" "In5.Cu" "In6.Cu"
			"In7.Cu" "In8.Cu" "In9.Cu" "In10.Cu" "In11.Cu" "In12.Cu" "In13.Cu" "In14.Cu"
			"In15.Cu" "In16.Cu"
		)
		(hatch none 0.5)
		(connect_pads
			(clearance 0)
		)
		(min_thickness 0.25)
		(keepout
			(tracks not_allowed)
			(vias allowed)
			(pads allowed)
			(copperpour not_allowed)
			(footprints allowed)
		)
		(placement
			(enabled no)
			(sheetname "")
		)
		(fill
			(thermal_gap 0.5)
			(thermal_bridge_width 0.5)
			(island_removal_mode 0)
		)
		(polygon
			(pts
				(arc
					(start 337.664044 -398.016476)
					(mid 337.774015 -398.11753)
					(end 337.918806 -398.154144)
				)
				(arc
					(start 337.918806 -398.154144)
					(mid 338.134332 -398.06487)
					(end 338.223606 -397.849344)
				)
				(arc
					(start 338.223606 -397.849344)
					(mid 338.213269 -397.770605)
					(end 338.182966 -397.697198)
				)
				(arc
					(start 337.790536 -397.018256)
					(mid 337.678139 -396.896639)
					(end 337.518756 -396.851632)
				)
				(arc
					(start 337.518756 -396.851632)
					(mid 337.30323 -396.940906)
					(end 337.213956 -397.156432)
				)
				(arc
					(start 337.213956 -397.156432)
					(mid 337.223534 -397.232494)
					(end 337.251802 -397.303752)
				)
				(xy 337.649058 -397.991076) (xy 337.66125 -398.012412) (xy 337.66379 -398.01673)
			)
		)
	)
	(zone
		(layers "F.Cu" "B.Cu" "In1.Cu" "In2.Cu" "In3.Cu" "In4.Cu" "In5.Cu" "In6.Cu"
			"In7.Cu" "In8.Cu" "In9.Cu" "In10.Cu" "In11.Cu" "In12.Cu" "In13.Cu" "In14.Cu"
			"In15.Cu" "In16.Cu"
		)
		(hatch none 0.5)
		(connect_pads
			(clearance 0)
		)
		(min_thickness 0.25)
		(keepout
			(tracks not_allowed)
			(vias allowed)
			(pads allowed)
			(copperpour not_allowed)
			(footprints allowed)
		)
		(placement
			(enabled no)
			(sheetname "")
		)
		(fill
			(thermal_gap 0.5)
			(thermal_bridge_width 0.5)
			(island_removal_mode 0)
		)
		(polygon
			(pts
				(arc
					(start 378.027692 -381.96393)
					(mid 377.646692 -382.34493)
					(end 378.027692 -382.72593)
				)
				(arc
					(start 378.891292 -382.72593)
					(mid 379.272292 -382.34493)
					(end 378.891292 -381.96393)
				)
			)
		)
	)
	(zone
		(layers "F.Cu" "B.Cu" "In1.Cu" "In2.Cu" "In3.Cu" "In4.Cu" "In5.Cu" "In6.Cu"
			"In7.Cu" "In8.Cu" "In9.Cu" "In10.Cu" "In11.Cu" "In12.Cu" "In13.Cu" "In14.Cu"
			"In15.Cu" "In16.Cu"
		)
		(hatch none 0.5)
		(connect_pads
			(clearance 0)
		)
		(min_thickness 0.25)
		(keepout
			(tracks not_allowed)
			(vias allowed)
			(pads allowed)
			(copperpour not_allowed)
			(footprints allowed)
		)
		(placement
			(enabled no)
			(sheetname "")
		)
		(fill
			(thermal_gap 0.5)
			(thermal_bridge_width 0.5)
			(island_removal_mode 0)
		)
		(polygon
			(pts
				(arc
					(start 320.997326 -400.811238)
					(mid 320.616326 -400.430238)
					(end 320.235326 -400.811238)
				)
				(arc
					(start 320.235326 -401.674838)
					(mid 320.616326 -402.055838)
					(end 320.997326 -401.674838)
				)
			)
		)
	)
	(zone
		(layers "F.Cu" "B.Cu" "In1.Cu" "In2.Cu" "In3.Cu" "In4.Cu" "In5.Cu" "In6.Cu"
			"In7.Cu" "In8.Cu" "In9.Cu" "In10.Cu" "In11.Cu" "In12.Cu" "In13.Cu" "In14.Cu"
			"In15.Cu" "In16.Cu"
		)
		(hatch none 0.5)
		(connect_pads
			(clearance 0)
		)
		(min_thickness 0.25)
		(keepout
			(tracks not_allowed)
			(vias allowed)
			(pads allowed)
			(copperpour not_allowed)
			(footprints allowed)
		)
		(placement
			(enabled no)
			(sheetname "")
		)
		(fill
			(thermal_gap 0.5)
			(thermal_bridge_width 0.5)
			(island_removal_mode 0)
		)
		(polygon
			(pts
				(arc
					(start 307.536342 -398.016476)
					(mid 307.646313 -398.11753)
					(end 307.791104 -398.154144)
				)
				(arc
					(start 307.791104 -398.154144)
					(mid 308.00663 -398.06487)
					(end 308.095904 -397.849344)
				)
				(arc
					(start 308.095904 -397.849344)
					(mid 308.085567 -397.770605)
					(end 308.055264 -397.697198)
				)
				(arc
					(start 307.662834 -397.018256)
					(mid 307.550437 -396.896639)
					(end 307.391054 -396.851632)
				)
				(arc
					(start 307.391054 -396.851632)
					(mid 307.175528 -396.940906)
					(end 307.086254 -397.156432)
				)
				(arc
					(start 307.086254 -397.156432)
					(mid 307.095832 -397.232494)
					(end 307.1241 -397.303752)
				)
				(xy 307.521356 -397.991076) (xy 307.533548 -398.012412) (xy 307.536088 -398.01673)
			)
		)
	)
	(zone
		(layers "F.Cu" "B.Cu" "In1.Cu" "In2.Cu" "In3.Cu" "In4.Cu" "In5.Cu" "In6.Cu"
			"In7.Cu" "In8.Cu" "In9.Cu" "In10.Cu" "In11.Cu" "In12.Cu" "In13.Cu" "In14.Cu"
			"In15.Cu" "In16.Cu"
		)
		(hatch none 0.5)
		(connect_pads
			(clearance 0)
		)
		(min_thickness 0.25)
		(keepout
			(tracks not_allowed)
			(vias allowed)
			(pads allowed)
			(copperpour not_allowed)
			(footprints allowed)
		)
		(placement
			(enabled no)
			(sheetname "")
		)
		(fill
			(thermal_gap 0.5)
			(thermal_bridge_width 0.5)
			(island_removal_mode 0)
		)
		(polygon
			(pts
				(arc
					(start 415.825432 -400.811238)
					(mid 415.444432 -400.430238)
					(end 415.063432 -400.811238)
				)
				(arc
					(start 415.063432 -401.674838)
					(mid 415.444432 -402.055838)
					(end 415.825432 -401.674838)
				)
			)
		)
	)
	(zone
		(layers "F.Cu" "B.Cu" "In1.Cu" "In2.Cu" "In3.Cu" "In4.Cu" "In5.Cu" "In6.Cu"
			"In7.Cu" "In8.Cu" "In9.Cu" "In10.Cu" "In11.Cu" "In12.Cu" "In13.Cu" "In14.Cu"
			"In15.Cu" "In16.Cu"
		)
		(hatch none 0.5)
		(connect_pads
			(clearance 0)
		)
		(min_thickness 0.25)
		(keepout
			(tracks not_allowed)
			(vias allowed)
			(pads allowed)
			(copperpour not_allowed)
			(footprints allowed)
		)
		(placement
			(enabled no)
			(sheetname "")
		)
		(fill
			(thermal_gap 0.5)
			(thermal_bridge_width 0.5)
			(island_removal_mode 0)
		)
		(polygon
			(pts
				(arc
					(start 419.06444 -379.50013)
					(mid 418.68344 -379.88113)
					(end 419.06444 -380.26213)
				)
				(arc
					(start 419.92804 -380.26213)
					(mid 420.30904 -379.88113)
					(end 419.92804 -379.50013)
				)
			)
		)
	)
	(zone
		(layers "F.Cu" "B.Cu" "In1.Cu" "In2.Cu" "In3.Cu" "In4.Cu" "In5.Cu" "In6.Cu"
			"In7.Cu" "In8.Cu" "In9.Cu" "In10.Cu" "In11.Cu" "In12.Cu" "In13.Cu" "In14.Cu"
			"In15.Cu" "In16.Cu"
		)
		(hatch none 0.5)
		(connect_pads
			(clearance 0)
		)
		(min_thickness 0.25)
		(keepout
			(tracks not_allowed)
			(vias allowed)
			(pads allowed)
			(copperpour not_allowed)
			(footprints allowed)
		)
		(placement
			(enabled no)
			(sheetname "")
		)
		(fill
			(thermal_gap 0.5)
			(thermal_bridge_width 0.5)
			(island_removal_mode 0)
		)
		(polygon
			(pts
				(arc
					(start 311.452006 -415.00552)
					(mid 311.071006 -415.38652)
					(end 311.452006 -415.76752)
				)
				(arc
					(start 312.315606 -415.76752)
					(mid 312.696606 -415.38652)
					(end 312.315606 -415.00552)
				)
			)
		)
	)
	(zone
		(layers "F.Cu" "B.Cu" "In1.Cu" "In2.Cu" "In3.Cu" "In4.Cu" "In5.Cu" "In6.Cu"
			"In7.Cu" "In8.Cu" "In9.Cu" "In10.Cu" "In11.Cu" "In12.Cu" "In13.Cu" "In14.Cu"
			"In15.Cu" "In16.Cu"
		)
		(hatch none 0.5)
		(connect_pads
			(clearance 0)
		)
		(min_thickness 0.25)
		(keepout
			(tracks not_allowed)
			(vias allowed)
			(pads allowed)
			(copperpour not_allowed)
			(footprints allowed)
		)
		(placement
			(enabled no)
			(sheetname "")
		)
		(fill
			(thermal_gap 0.5)
			(thermal_bridge_width 0.5)
			(island_removal_mode 0)
		)
		(polygon
			(pts
				(arc
					(start 158.625286 -392.429238)
					(mid 158.244286 -392.048238)
					(end 157.863286 -392.429238)
				)
				(arc
					(start 157.863286 -393.292838)
					(mid 158.244286 -393.673838)
					(end 158.625286 -393.292838)
				)
			)
		)
	)
	(zone
		(layers "F.Cu" "B.Cu" "In1.Cu" "In2.Cu" "In3.Cu" "In4.Cu" "In5.Cu" "In6.Cu"
			"In7.Cu" "In8.Cu" "In9.Cu" "In10.Cu" "In11.Cu" "In12.Cu" "In13.Cu" "In14.Cu"
			"In15.Cu" "In16.Cu"
		)
		(hatch none 0.5)
		(connect_pads
			(clearance 0)
		)
		(min_thickness 0.25)
		(keepout
			(tracks not_allowed)
			(vias allowed)
			(pads allowed)
			(copperpour not_allowed)
			(footprints allowed)
		)
		(placement
			(enabled no)
			(sheetname "")
		)
		(fill
			(thermal_gap 0.5)
			(thermal_bridge_width 0.5)
			(island_removal_mode 0)
		)
		(polygon
			(pts
				(xy 513.515102 -357.01224) (xy 513.819902 -357.31704) (xy 513.819902 -347.31706) (xy 513.515102 -347.62186)
			)
		)
	)
	(zone
		(layers "F.Cu" "B.Cu" "In1.Cu" "In2.Cu" "In3.Cu" "In4.Cu" "In5.Cu" "In6.Cu"
			"In7.Cu" "In8.Cu" "In9.Cu" "In10.Cu" "In11.Cu" "In12.Cu" "In13.Cu" "In14.Cu"
			"In15.Cu" "In16.Cu"
		)
		(hatch none 0.5)
		(connect_pads
			(clearance 0)
		)
		(min_thickness 0.25)
		(keepout
			(tracks not_allowed)
			(vias allowed)
			(pads allowed)
			(copperpour not_allowed)
			(footprints allowed)
		)
		(placement
			(enabled no)
			(sheetname "")
		)
		(fill
			(thermal_gap 0.5)
			(thermal_bridge_width 0.5)
			(island_removal_mode 0)
		)
		(polygon
			(pts
				(arc
					(start 371.220492 -381.96393)
					(mid 370.839492 -382.34493)
					(end 371.220492 -382.72593)
				)
				(arc
					(start 372.084092 -382.72593)
					(mid 372.465092 -382.34493)
					(end 372.084092 -381.96393)
				)
			)
		)
	)
	(zone
		(layers "F.Cu" "B.Cu" "In1.Cu" "In2.Cu" "In3.Cu" "In4.Cu" "In5.Cu" "In6.Cu"
			"In7.Cu" "In8.Cu" "In9.Cu" "In10.Cu" "In11.Cu" "In12.Cu" "In13.Cu" "In14.Cu"
			"In15.Cu" "In16.Cu"
		)
		(hatch none 0.5)
		(connect_pads
			(clearance 0)
		)
		(min_thickness 0.25)
		(keepout
			(tracks not_allowed)
			(vias allowed)
			(pads allowed)
			(copperpour not_allowed)
			(footprints allowed)
		)
		(placement
			(enabled no)
			(sheetname "")
		)
		(fill
			(thermal_gap 0.5)
			(thermal_bridge_width 0.5)
			(island_removal_mode 0)
		)
		(polygon
			(pts
				(arc
					(start 374.897396 -400.811238)
					(mid 374.516396 -400.430238)
					(end 374.135396 -400.811238)
				)
				(arc
					(start 374.135396 -401.674838)
					(mid 374.516396 -402.055838)
					(end 374.897396 -401.674838)
				)
			)
		)
	)
	(zone
		(layers "F.Cu" "B.Cu" "In1.Cu" "In2.Cu" "In3.Cu" "In4.Cu" "In5.Cu" "In6.Cu"
			"In7.Cu" "In8.Cu" "In9.Cu" "In10.Cu" "In11.Cu" "In12.Cu" "In13.Cu" "In14.Cu"
			"In15.Cu" "In16.Cu"
		)
		(hatch none 0.5)
		(connect_pads
			(clearance 0)
		)
		(min_thickness 0.25)
		(keepout
			(tracks not_allowed)
			(vias allowed)
			(pads allowed)
			(copperpour not_allowed)
			(footprints allowed)
		)
		(placement
			(enabled no)
			(sheetname "")
		)
		(fill
			(thermal_gap 0.5)
			(thermal_bridge_width 0.5)
			(island_removal_mode 0)
		)
		(polygon
			(pts
				(arc
					(start 57.536588 -389.634476)
					(mid 57.646559 -389.73553)
					(end 57.79135 -389.772144)
				)
				(arc
					(start 57.79135 -389.772144)
					(mid 58.006876 -389.68287)
					(end 58.09615 -389.467344)
				)
				(arc
					(start 58.09615 -389.467344)
					(mid 58.085813 -389.388605)
					(end 58.05551 -389.315198)
				)
				(arc
					(start 57.66308 -388.636256)
					(mid 57.550683 -388.514639)
					(end 57.3913 -388.469632)
				)
				(arc
					(start 57.3913 -388.469632)
					(mid 57.175774 -388.558906)
					(end 57.0865 -388.774432)
				)
				(arc
					(start 57.0865 -388.774432)
					(mid 57.096078 -388.850494)
					(end 57.124346 -388.921752)
				)
				(xy 57.521602 -389.609076) (xy 57.533794 -389.630412) (xy 57.536334 -389.63473)
			)
		)
	)
	(zone
		(layers "F.Cu" "B.Cu" "In1.Cu" "In2.Cu" "In3.Cu" "In4.Cu" "In5.Cu" "In6.Cu"
			"In7.Cu" "In8.Cu" "In9.Cu" "In10.Cu" "In11.Cu" "In12.Cu" "In13.Cu" "In14.Cu"
			"In15.Cu" "In16.Cu"
		)
		(hatch none 0.5)
		(connect_pads
			(clearance 0)
		)
		(min_thickness 0.25)
		(keepout
			(tracks not_allowed)
			(vias allowed)
			(pads allowed)
			(copperpour not_allowed)
			(footprints allowed)
		)
		(placement
			(enabled no)
			(sheetname "")
		)
		(fill
			(thermal_gap 0.5)
			(thermal_bridge_width 0.5)
			(island_removal_mode 0)
		)
		(polygon
			(pts
				(arc
					(start 155.025344 -392.429238)
					(mid 154.644344 -392.048238)
					(end 154.263344 -392.429238)
				)
				(arc
					(start 154.263344 -393.292838)
					(mid 154.644344 -393.673838)
					(end 155.025344 -393.292838)
				)
			)
		)
	)
	(zone
		(layers "F.Cu" "B.Cu" "In1.Cu" "In2.Cu" "In3.Cu" "In4.Cu" "In5.Cu" "In6.Cu"
			"In7.Cu" "In8.Cu" "In9.Cu" "In10.Cu" "In11.Cu" "In12.Cu" "In13.Cu" "In14.Cu"
			"In15.Cu" "In16.Cu"
		)
		(hatch none 0.5)
		(connect_pads
			(clearance 0)
		)
		(min_thickness 0.25)
		(keepout
			(tracks not_allowed)
			(vias allowed)
			(pads allowed)
			(copperpour not_allowed)
			(footprints allowed)
		)
		(placement
			(enabled no)
			(sheetname "")
		)
		(fill
			(thermal_gap 0.5)
			(thermal_bridge_width 0.5)
			(island_removal_mode 0)
		)
		(polygon
			(pts
				(arc
					(start 381.615442 -415.00552)
					(mid 381.234442 -415.38652)
					(end 381.615442 -415.76752)
				)
				(arc
					(start 382.479042 -415.76752)
					(mid 382.860042 -415.38652)
					(end 382.479042 -415.00552)
				)
			)
		)
	)
	(zone
		(layers "F.Cu" "B.Cu" "In1.Cu" "In2.Cu" "In3.Cu" "In4.Cu" "In5.Cu" "In6.Cu"
			"In7.Cu" "In8.Cu" "In9.Cu" "In10.Cu" "In11.Cu" "In12.Cu" "In13.Cu" "In14.Cu"
			"In15.Cu" "In16.Cu"
		)
		(hatch none 0.5)
		(connect_pads
			(clearance 0)
		)
		(min_thickness 0.25)
		(keepout
			(tracks not_allowed)
			(vias allowed)
			(pads allowed)
			(copperpour not_allowed)
			(footprints allowed)
		)
		(placement
			(enabled no)
			(sheetname "")
		)
		(fill
			(thermal_gap 0.5)
			(thermal_bridge_width 0.5)
			(island_removal_mode 0)
		)
		(polygon
			(pts
				(arc
					(start 153.184606 -406.62352)
					(mid 152.803606 -407.00452)
					(end 153.184606 -407.38552)
				)
				(arc
					(start 154.048206 -407.38552)
					(mid 154.429206 -407.00452)
					(end 154.048206 -406.62352)
				)
			)
		)
	)
	(zone
		(layers "F.Cu" "B.Cu" "In1.Cu" "In2.Cu" "In3.Cu" "In4.Cu" "In5.Cu" "In6.Cu"
			"In7.Cu" "In8.Cu" "In9.Cu" "In10.Cu" "In11.Cu" "In12.Cu" "In13.Cu" "In14.Cu"
			"In15.Cu" "In16.Cu"
		)
		(hatch none 0.5)
		(connect_pads
			(clearance 0)
		)
		(min_thickness 0.25)
		(keepout
			(tracks not_allowed)
			(vias allowed)
			(pads allowed)
			(copperpour not_allowed)
			(footprints allowed)
		)
		(placement
			(enabled no)
			(sheetname "")
		)
		(fill
			(thermal_gap 0.5)
			(thermal_bridge_width 0.5)
			(island_removal_mode 0)
		)
		(polygon
			(pts
				(arc
					(start 420.62527 -400.811238)
					(mid 420.24427 -400.430238)
					(end 419.86327 -400.811238)
				)
				(arc
					(start 419.86327 -401.674838)
					(mid 420.24427 -402.055838)
					(end 420.62527 -401.674838)
				)
			)
		)
	)
	(zone
		(layers "F.Cu" "B.Cu" "In1.Cu" "In2.Cu" "In3.Cu" "In4.Cu" "In5.Cu" "In6.Cu"
			"In7.Cu" "In8.Cu" "In9.Cu" "In10.Cu" "In11.Cu" "In12.Cu" "In13.Cu" "In14.Cu"
			"In15.Cu" "In16.Cu"
		)
		(hatch none 0.5)
		(connect_pads
			(clearance 0)
		)
		(min_thickness 0.25)
		(keepout
			(tracks not_allowed)
			(vias allowed)
			(pads allowed)
			(copperpour not_allowed)
			(footprints allowed)
		)
		(placement
			(enabled no)
			(sheetname "")
		)
		(fill
			(thermal_gap 0.5)
			(thermal_bridge_width 0.5)
			(island_removal_mode 0)
		)
		(polygon
			(pts
				(arc
					(start 40.730424 -4.582414)
					(mid 40.349424 -4.963414)
					(end 40.730424 -5.344414)
				)
				(arc
					(start 41.594024 -5.344414)
					(mid 41.975024 -4.963414)
					(end 41.594024 -4.582414)
				)
			)
		)
	)
	(zone
		(layers "F.Cu" "B.Cu" "In1.Cu" "In2.Cu" "In3.Cu" "In4.Cu" "In5.Cu" "In6.Cu"
			"In7.Cu" "In8.Cu" "In9.Cu" "In10.Cu" "In11.Cu" "In12.Cu" "In13.Cu" "In14.Cu"
			"In15.Cu" "In16.Cu"
		)
		(hatch none 0.5)
		(connect_pads
			(clearance 0)
		)
		(min_thickness 0.25)
		(keepout
			(tracks not_allowed)
			(vias allowed)
			(pads allowed)
			(copperpour not_allowed)
			(footprints allowed)
		)
		(placement
			(enabled no)
			(sheetname "")
		)
		(fill
			(thermal_gap 0.5)
			(thermal_bridge_width 0.5)
			(island_removal_mode 0)
		)
		(polygon
			(pts
				(arc
					(start 319.536318 -398.016476)
					(mid 319.646289 -398.11753)
					(end 319.79108 -398.154144)
				)
				(arc
					(start 319.79108 -398.154144)
					(mid 320.006606 -398.06487)
					(end 320.09588 -397.849344)
				)
				(arc
					(start 320.09588 -397.849344)
					(mid 320.085543 -397.770605)
					(end 320.05524 -397.697198)
				)
				(arc
					(start 319.66281 -397.018256)
					(mid 319.550413 -396.896639)
					(end 319.39103 -396.851632)
				)
				(arc
					(start 319.39103 -396.851632)
					(mid 319.175504 -396.940906)
					(end 319.08623 -397.156432)
				)
				(arc
					(start 319.08623 -397.156432)
					(mid 319.095808 -397.232494)
					(end 319.124076 -397.303752)
				)
				(xy 319.521332 -397.991076) (xy 319.533524 -398.012412) (xy 319.536064 -398.01673)
			)
		)
	)
	(zone
		(layers "F.Cu" "B.Cu" "In1.Cu" "In2.Cu" "In3.Cu" "In4.Cu" "In5.Cu" "In6.Cu"
			"In7.Cu" "In8.Cu" "In9.Cu" "In10.Cu" "In11.Cu" "In12.Cu" "In13.Cu" "In14.Cu"
			"In15.Cu" "In16.Cu"
		)
		(hatch none 0.5)
		(connect_pads
			(clearance 0)
		)
		(min_thickness 0.25)
		(keepout
			(tracks not_allowed)
			(vias allowed)
			(pads allowed)
			(copperpour not_allowed)
			(footprints allowed)
		)
		(placement
			(enabled no)
			(sheetname "")
		)
		(fill
			(thermal_gap 0.5)
			(thermal_bridge_width 0.5)
			(island_removal_mode 0)
		)
		(polygon
			(pts
				(arc
					(start 346.32519 -400.811238)
					(mid 345.94419 -400.430238)
					(end 345.56319 -400.811238)
				)
				(arc
					(start 345.56319 -401.674838)
					(mid 345.94419 -402.055838)
					(end 346.32519 -401.674838)
				)
			)
		)
	)
	(zone
		(layers "F.Cu" "B.Cu" "In1.Cu" "In2.Cu" "In3.Cu" "In4.Cu" "In5.Cu" "In6.Cu"
			"In7.Cu" "In8.Cu" "In9.Cu" "In10.Cu" "In11.Cu" "In12.Cu" "In13.Cu" "In14.Cu"
			"In15.Cu" "In16.Cu"
		)
		(hatch none 0.5)
		(connect_pads
			(clearance 0)
		)
		(min_thickness 0.25)
		(keepout
			(tracks not_allowed)
			(vias allowed)
			(pads allowed)
			(copperpour not_allowed)
			(footprints allowed)
		)
		(placement
			(enabled no)
			(sheetname "")
		)
		(fill
			(thermal_gap 0.5)
			(thermal_bridge_width 0.5)
			(island_removal_mode 0)
		)
		(polygon
			(pts
				(arc
					(start 405.964136 -398.016476)
					(mid 406.074107 -398.11753)
					(end 406.218898 -398.154144)
				)
				(arc
					(start 406.218898 -398.154144)
					(mid 406.434424 -398.06487)
					(end 406.523698 -397.849344)
				)
				(arc
					(start 406.523698 -397.849344)
					(mid 406.513361 -397.770605)
					(end 406.483058 -397.697198)
				)
				(arc
					(start 406.090628 -397.018256)
					(mid 405.978231 -396.896639)
					(end 405.818848 -396.851632)
				)
				(arc
					(start 405.818848 -396.851632)
					(mid 405.603322 -396.940906)
					(end 405.514048 -397.156432)
				)
				(arc
					(start 405.514048 -397.156432)
					(mid 405.523626 -397.232494)
					(end 405.551894 -397.303752)
				)
				(xy 405.94915 -397.991076) (xy 405.961342 -398.012412) (xy 405.963882 -398.01673)
			)
		)
	)
	(zone
		(layers "F.Cu" "B.Cu" "In1.Cu" "In2.Cu" "In3.Cu" "In4.Cu" "In5.Cu" "In6.Cu"
			"In7.Cu" "In8.Cu" "In9.Cu" "In10.Cu" "In11.Cu" "In12.Cu" "In13.Cu" "In14.Cu"
			"In15.Cu" "In16.Cu"
		)
		(hatch none 0.5)
		(connect_pads
			(clearance 0)
		)
		(min_thickness 0.25)
		(keepout
			(tracks not_allowed)
			(vias allowed)
			(pads allowed)
			(copperpour not_allowed)
			(footprints allowed)
		)
		(placement
			(enabled no)
			(sheetname "")
		)
		(fill
			(thermal_gap 0.5)
			(thermal_bridge_width 0.5)
			(island_removal_mode 0)
		)
		(polygon
			(pts
				(arc
					(start 83.842352 -212.98027)
					(mid 78.81366 -212.98027)
					(end 83.842352 -212.98027)
				)
			)
		)
	)
	(zone
		(layers "F.Cu" "B.Cu" "In1.Cu" "In2.Cu" "In3.Cu" "In4.Cu" "In5.Cu" "In6.Cu"
			"In7.Cu" "In8.Cu" "In9.Cu" "In10.Cu" "In11.Cu" "In12.Cu" "In13.Cu" "In14.Cu"
			"In15.Cu" "In16.Cu"
		)
		(hatch none 0.5)
		(connect_pads
			(clearance 0)
		)
		(min_thickness 0.25)
		(keepout
			(tracks not_allowed)
			(vias allowed)
			(pads allowed)
			(copperpour not_allowed)
			(footprints allowed)
		)
		(placement
			(enabled no)
			(sheetname "")
		)
		(fill
			(thermal_gap 0.5)
			(thermal_bridge_width 0.5)
			(island_removal_mode 0)
		)
		(polygon
			(pts
				(arc
					(start 345.157044 -379.50013)
					(mid 344.776044 -379.88113)
					(end 345.157044 -380.26213)
				)
				(arc
					(start 346.020644 -380.26213)
					(mid 346.401644 -379.88113)
					(end 346.020644 -379.50013)
				)
			)
		)
	)
	(zone
		(layers "F.Cu" "B.Cu" "In1.Cu" "In2.Cu" "In3.Cu" "In4.Cu" "In5.Cu" "In6.Cu"
			"In7.Cu" "In8.Cu" "In9.Cu" "In10.Cu" "In11.Cu" "In12.Cu" "In13.Cu" "In14.Cu"
			"In15.Cu" "In16.Cu"
		)
		(hatch none 0.5)
		(connect_pads
			(clearance 0)
		)
		(min_thickness 0.25)
		(keepout
			(tracks not_allowed)
			(vias allowed)
			(pads allowed)
			(copperpour not_allowed)
			(footprints allowed)
		)
		(placement
			(enabled no)
			(sheetname "")
		)
		(fill
			(thermal_gap 0.5)
			(thermal_bridge_width 0.5)
			(island_removal_mode 0)
		)
		(polygon
			(pts
				(arc
					(start 221.78645 -191.000888)
					(mid 222.16745 -190.619888)
					(end 221.78645 -190.238888)
				)
				(arc
					(start 220.79585 -190.238888)
					(mid 220.41485 -190.619888)
					(end 220.79585 -191.000888)
				)
			)
		)
	)
	(zone
		(layers "F.Cu" "B.Cu" "In1.Cu" "In2.Cu" "In3.Cu" "In4.Cu" "In5.Cu" "In6.Cu"
			"In7.Cu" "In8.Cu" "In9.Cu" "In10.Cu" "In11.Cu" "In12.Cu" "In13.Cu" "In14.Cu"
			"In15.Cu" "In16.Cu"
		)
		(hatch none 0.5)
		(connect_pads
			(clearance 0)
		)
		(min_thickness 0.25)
		(keepout
			(tracks not_allowed)
			(vias allowed)
			(pads allowed)
			(copperpour not_allowed)
			(footprints allowed)
		)
		(placement
			(enabled no)
			(sheetname "")
		)
		(fill
			(thermal_gap 0.5)
			(thermal_bridge_width 0.5)
			(island_removal_mode 0)
		)
		(polygon
			(pts
				(arc
					(start 55.452264 -406.62352)
					(mid 55.071264 -407.00452)
					(end 55.452264 -407.38552)
				)
				(arc
					(start 56.315864 -407.38552)
					(mid 56.696864 -407.00452)
					(end 56.315864 -406.62352)
				)
			)
		)
	)
	(zone
		(layers "F.Cu" "B.Cu" "In1.Cu" "In2.Cu" "In3.Cu" "In4.Cu" "In5.Cu" "In6.Cu"
			"In7.Cu" "In8.Cu" "In9.Cu" "In10.Cu" "In11.Cu" "In12.Cu" "In13.Cu" "In14.Cu"
			"In15.Cu" "In16.Cu"
		)
		(hatch none 0.5)
		(connect_pads
			(clearance 0)
		)
		(min_thickness 0.25)
		(keepout
			(tracks not_allowed)
			(vias allowed)
			(pads allowed)
			(copperpour not_allowed)
			(footprints allowed)
		)
		(placement
			(enabled no)
			(sheetname "")
		)
		(fill
			(thermal_gap 0.5)
			(thermal_bridge_width 0.5)
			(island_removal_mode 0)
		)
		(polygon
			(pts
				(arc
					(start 56.983884 -412.189168)
					(mid 56.602884 -412.570168)
					(end 56.983884 -412.951168)
				)
				(arc
					(start 57.847484 -412.951168)
					(mid 58.228484 -412.570168)
					(end 57.847484 -412.189168)
				)
			)
		)
	)
	(zone
		(layers "F.Cu" "B.Cu" "In1.Cu" "In2.Cu" "In3.Cu" "In4.Cu" "In5.Cu" "In6.Cu"
			"In7.Cu" "In8.Cu" "In9.Cu" "In10.Cu" "In11.Cu" "In12.Cu" "In13.Cu" "In14.Cu"
			"In15.Cu" "In16.Cu"
		)
		(hatch none 0.5)
		(connect_pads
			(clearance 0)
		)
		(min_thickness 0.25)
		(keepout
			(tracks not_allowed)
			(vias allowed)
			(pads allowed)
			(copperpour not_allowed)
			(footprints allowed)
		)
		(placement
			(enabled no)
			(sheetname "")
		)
		(fill
			(thermal_gap 0.5)
			(thermal_bridge_width 0.5)
			(island_removal_mode 0)
		)
		(polygon
			(pts
				(arc
					(start 72.342502 -258.880356)
					(mid 67.313302 -258.880356)
					(end 72.342502 -258.880356)
				)
			)
		)
	)
	(zone
		(layers "F.Cu" "B.Cu" "In1.Cu" "In2.Cu" "In3.Cu" "In4.Cu" "In5.Cu" "In6.Cu"
			"In7.Cu" "In8.Cu" "In9.Cu" "In10.Cu" "In11.Cu" "In12.Cu" "In13.Cu" "In14.Cu"
			"In15.Cu" "In16.Cu"
		)
		(hatch none 0.5)
		(connect_pads
			(clearance 0)
		)
		(min_thickness 0.25)
		(keepout
			(tracks not_allowed)
			(vias allowed)
			(pads allowed)
			(copperpour not_allowed)
			(footprints allowed)
		)
		(placement
			(enabled no)
			(sheetname "")
		)
		(fill yes
			(thermal_gap 0.5)
			(thermal_bridge_width 0.5)
			(island_removal_mode 0)
		)
		(polygon
			(pts
				(arc
					(start 371.036596 -394.552424)
					(mid 371.146567 -394.653478)
					(end 371.291358 -394.690092)
				)
				(arc
					(start 371.291358 -394.690092)
					(mid 371.506884 -394.600818)
					(end 371.596158 -394.385292)
				)
				(arc
					(start 371.596158 -394.385292)
					(mid 371.585821 -394.306553)
					(end 371.555518 -394.233146)
				)
				(arc
					(start 371.163088 -393.554204)
					(mid 371.050691 -393.432587)
					(end 370.891308 -393.38758)
				)
				(arc
					(start 370.891308 -393.38758)
					(mid 370.675782 -393.476854)
					(end 370.586508 -393.69238)
				)
				(arc
					(start 370.586508 -393.69238)
					(mid 370.596086 -393.768442)
					(end 370.624354 -393.8397)
				)
				(xy 371.02161 -394.527024) (xy 371.033802 -394.54836) (xy 371.036342 -394.552678)
			)
		)
	)
	(zone
		(layers "F.Cu" "B.Cu" "In1.Cu" "In2.Cu" "In3.Cu" "In4.Cu" "In5.Cu" "In6.Cu"
			"In7.Cu" "In8.Cu" "In9.Cu" "In10.Cu" "In11.Cu" "In12.Cu" "In13.Cu" "In14.Cu"
			"In15.Cu" "In16.Cu"
		)
		(hatch none 0.5)
		(connect_pads
			(clearance 0)
		)
		(min_thickness 0.25)
		(keepout
			(tracks not_allowed)
			(vias allowed)
			(pads allowed)
			(copperpour not_allowed)
			(footprints allowed)
		)
		(placement
			(enabled no)
			(sheetname "")
		)
		(fill
			(thermal_gap 0.5)
			(thermal_bridge_width 0.5)
			(island_removal_mode 0)
		)
		(polygon
			(pts
				(arc
					(start 342.281002 -308.439566)
					(mid 341.900002 -308.058566)
					(end 341.519002 -308.439566)
				)
				(arc
					(start 341.519002 -309.303166)
					(mid 341.900002 -309.684166)
					(end 342.281002 -309.303166)
				)
			)
		)
	)
	(zone
		(layers "F.Cu" "B.Cu" "In1.Cu" "In2.Cu" "In3.Cu" "In4.Cu" "In5.Cu" "In6.Cu"
			"In7.Cu" "In8.Cu" "In9.Cu" "In10.Cu" "In11.Cu" "In12.Cu" "In13.Cu" "In14.Cu"
			"In15.Cu" "In16.Cu"
		)
		(hatch none 0.5)
		(connect_pads
			(clearance 0)
		)
		(min_thickness 0.25)
		(keepout
			(tracks not_allowed)
			(vias allowed)
			(pads allowed)
			(copperpour not_allowed)
			(footprints allowed)
		)
		(placement
			(enabled no)
			(sheetname "")
		)
		(fill
			(thermal_gap 0.5)
			(thermal_bridge_width 0.5)
			(island_removal_mode 0)
		)
		(polygon
			(pts
				(arc
					(start 58.997596 -392.429238)
					(mid 58.616596 -392.048238)
					(end 58.235596 -392.429238)
				)
				(arc
					(start 58.235596 -393.292838)
					(mid 58.616596 -393.673838)
					(end 58.997596 -393.292838)
				)
			)
		)
	)
	(zone
		(layers "F.Cu" "B.Cu" "In1.Cu" "In2.Cu" "In3.Cu" "In4.Cu" "In5.Cu" "In6.Cu"
			"In7.Cu" "In8.Cu" "In9.Cu" "In10.Cu" "In11.Cu" "In12.Cu" "In13.Cu" "In14.Cu"
			"In15.Cu" "In16.Cu"
		)
		(hatch none 0.5)
		(connect_pads
			(clearance 0)
		)
		(min_thickness 0.25)
		(keepout
			(tracks not_allowed)
			(vias allowed)
			(pads allowed)
			(copperpour not_allowed)
			(footprints allowed)
		)
		(placement
			(enabled no)
			(sheetname "")
		)
		(fill
			(thermal_gap 0.5)
			(thermal_bridge_width 0.5)
			(island_removal_mode 0)
		)
		(polygon
			(pts
				(arc
					(start 78.42377 -417.5125)
					(mid 78.04277 -417.1315)
					(end 77.66177 -417.5125)
				)
				(arc
					(start 77.66177 -418.3761)
					(mid 78.04277 -418.7571)
					(end 78.42377 -418.3761)
				)
			)
		)
	)
	(zone
		(layers "F.Cu" "B.Cu" "In1.Cu" "In2.Cu" "In3.Cu" "In4.Cu" "In5.Cu" "In6.Cu"
			"In7.Cu" "In8.Cu" "In9.Cu" "In10.Cu" "In11.Cu" "In12.Cu" "In13.Cu" "In14.Cu"
			"In15.Cu" "In16.Cu"
		)
		(hatch none 0.5)
		(connect_pads
			(clearance 0)
		)
		(min_thickness 0.25)
		(keepout
			(tracks not_allowed)
			(vias allowed)
			(pads allowed)
			(copperpour not_allowed)
			(footprints allowed)
		)
		(placement
			(enabled no)
			(sheetname "")
		)
		(fill
			(thermal_gap 0.5)
			(thermal_bridge_width 0.5)
			(island_removal_mode 0)
		)
		(polygon
			(pts
				(arc
					(start 151.425148 -392.429238)
					(mid 151.044148 -392.048238)
					(end 150.663148 -392.429238)
				)
				(arc
					(start 150.663148 -393.292838)
					(mid 151.044148 -393.673838)
					(end 151.425148 -393.292838)
				)
			)
		)
	)
	(zone
		(layers "F.Cu" "B.Cu" "In1.Cu" "In2.Cu" "In3.Cu" "In4.Cu" "In5.Cu" "In6.Cu"
			"In7.Cu" "In8.Cu" "In9.Cu" "In10.Cu" "In11.Cu" "In12.Cu" "In13.Cu" "In14.Cu"
			"In15.Cu" "In16.Cu"
		)
		(hatch none 0.5)
		(connect_pads
			(clearance 0)
		)
		(min_thickness 0.25)
		(keepout
			(tracks not_allowed)
			(vias allowed)
			(pads allowed)
			(copperpour not_allowed)
			(footprints allowed)
		)
		(placement
			(enabled no)
			(sheetname "")
		)
		(fill
			(thermal_gap 0.5)
			(thermal_bridge_width 0.5)
			(island_removal_mode 0)
		)
		(polygon
			(pts
				(arc
					(start 60.141866 -421.760396)
					(mid 60.164184 -421.814278)
					(end 60.218066 -421.836596)
				)
				(arc
					(start 61.157866 -421.836596)
					(mid 61.211748 -421.814278)
					(end 61.234066 -421.760396)
				)
				(arc
					(start 61.234066 -419.218872)
					(mid 61.211748 -419.16499)
					(end 61.157866 -419.142672)
				)
				(arc
					(start 60.218066 -419.142672)
					(mid 60.164184 -419.16499)
					(end 60.141866 -419.218872)
				)
			)
		)
	)
	(zone
		(layers "F.Cu" "B.Cu" "In1.Cu" "In2.Cu" "In3.Cu" "In4.Cu" "In5.Cu" "In6.Cu"
			"In7.Cu" "In8.Cu" "In9.Cu" "In10.Cu" "In11.Cu" "In12.Cu" "In13.Cu" "In14.Cu"
			"In15.Cu" "In16.Cu"
		)
		(hatch none 0.5)
		(connect_pads
			(clearance 0)
		)
		(min_thickness 0.25)
		(keepout
			(tracks not_allowed)
			(vias allowed)
			(pads allowed)
			(copperpour not_allowed)
			(footprints allowed)
		)
		(placement
			(enabled no)
			(sheetname "")
		)
		(fill
			(thermal_gap 0.5)
			(thermal_bridge_width 0.5)
			(island_removal_mode 0)
		)
		(polygon
			(pts
				(arc
					(start 62.597538 -392.429238)
					(mid 62.216538 -392.048238)
					(end 61.835538 -392.429238)
				)
				(arc
					(start 61.835538 -393.292838)
					(mid 62.216538 -393.673838)
					(end 62.597538 -393.292838)
				)
			)
		)
	)
	(zone
		(layers "F.Cu" "B.Cu" "In1.Cu" "In2.Cu" "In3.Cu" "In4.Cu" "In5.Cu" "In6.Cu"
			"In7.Cu" "In8.Cu" "In9.Cu" "In10.Cu" "In11.Cu" "In12.Cu" "In13.Cu" "In14.Cu"
			"In15.Cu" "In16.Cu"
		)
		(hatch none 0.5)
		(connect_pads
			(clearance 0)
		)
		(min_thickness 0.25)
		(keepout
			(tracks not_allowed)
			(vias allowed)
			(pads allowed)
			(copperpour not_allowed)
			(footprints allowed)
		)
		(placement
			(enabled no)
			(sheetname "")
		)
		(fill
			(thermal_gap 0.5)
			(thermal_bridge_width 0.5)
			(island_removal_mode 0)
		)
		(polygon
			(pts
				(arc
					(start 406.121362 -418.031168)
					(mid 405.740362 -418.412168)
					(end 406.121362 -418.793168)
				)
				(arc
					(start 406.984962 -418.793168)
					(mid 407.365962 -418.412168)
					(end 406.984962 -418.031168)
				)
			)
		)
	)
	(zone
		(layers "F.Cu" "B.Cu" "In1.Cu" "In2.Cu" "In3.Cu" "In4.Cu" "In5.Cu" "In6.Cu"
			"In7.Cu" "In8.Cu" "In9.Cu" "In10.Cu" "In11.Cu" "In12.Cu" "In13.Cu" "In14.Cu"
			"In15.Cu" "In16.Cu"
		)
		(hatch none 0.5)
		(connect_pads
			(clearance 0)
		)
		(min_thickness 0.25)
		(keepout
			(tracks not_allowed)
			(vias allowed)
			(pads allowed)
			(copperpour not_allowed)
			(footprints allowed)
		)
		(placement
			(enabled no)
			(sheetname "")
		)
		(fill
			(thermal_gap 0.5)
			(thermal_bridge_width 0.5)
			(island_removal_mode 0)
		)
		(polygon
			(pts
				(arc
					(start 415.311082 -418.031168)
					(mid 414.930082 -418.412168)
					(end 415.311082 -418.793168)
				)
				(arc
					(start 416.174682 -418.793168)
					(mid 416.555682 -418.412168)
					(end 416.174682 -418.031168)
				)
			)
		)
	)
	(zone
		(layers "F.Cu" "B.Cu" "In1.Cu" "In2.Cu" "In3.Cu" "In4.Cu" "In5.Cu" "In6.Cu"
			"In7.Cu" "In8.Cu" "In9.Cu" "In10.Cu" "In11.Cu" "In12.Cu" "In13.Cu" "In14.Cu"
			"In15.Cu" "In16.Cu"
		)
		(hatch none 0.5)
		(connect_pads
			(clearance 0)
		)
		(min_thickness 0.25)
		(keepout
			(tracks not_allowed)
			(vias allowed)
			(pads allowed)
			(copperpour not_allowed)
			(footprints allowed)
		)
		(placement
			(enabled no)
			(sheetname "")
		)
		(fill
			(thermal_gap 0.5)
			(thermal_bridge_width 0.5)
			(island_removal_mode 0)
		)
		(polygon
			(pts
				(arc
					(start 398.64284 -379.50013)
					(mid 398.26184 -379.88113)
					(end 398.64284 -380.26213)
				)
				(arc
					(start 399.50644 -380.26213)
					(mid 399.88744 -379.88113)
					(end 399.50644 -379.50013)
				)
			)
		)
	)
	(zone
		(layers "F.Cu" "B.Cu" "In1.Cu" "In2.Cu" "In3.Cu" "In4.Cu" "In5.Cu" "In6.Cu"
			"In7.Cu" "In8.Cu" "In9.Cu" "In10.Cu" "In11.Cu" "In12.Cu" "In13.Cu" "In14.Cu"
			"In15.Cu" "In16.Cu"
		)
		(hatch none 0.5)
		(connect_pads
			(clearance 0)
		)
		(min_thickness 0.25)
		(keepout
			(tracks not_allowed)
			(vias allowed)
			(pads allowed)
			(copperpour not_allowed)
			(footprints allowed)
		)
		(placement
			(enabled no)
			(sheetname "")
		)
		(fill
			(thermal_gap 0.5)
			(thermal_bridge_width 0.5)
			(island_removal_mode 0)
		)
		(polygon
			(pts
				(arc
					(start 87.66429 -389.634476)
					(mid 87.774261 -389.73553)
					(end 87.919052 -389.772144)
				)
				(arc
					(start 87.919052 -389.772144)
					(mid 88.134578 -389.68287)
					(end 88.223852 -389.467344)
				)
				(arc
					(start 88.223852 -389.467344)
					(mid 88.213515 -389.388605)
					(end 88.183212 -389.315198)
				)
				(arc
					(start 87.790782 -388.636256)
					(mid 87.678385 -388.514639)
					(end 87.519002 -388.469632)
				)
				(arc
					(start 87.519002 -388.469632)
					(mid 87.303476 -388.558906)
					(end 87.214202 -388.774432)
				)
				(arc
					(start 87.214202 -388.774432)
					(mid 87.22378 -388.850494)
					(end 87.252048 -388.921752)
				)
				(xy 87.649304 -389.609076) (xy 87.661496 -389.630412) (xy 87.664036 -389.63473)
			)
		)
	)
	(zone
		(layers "F.Cu" "B.Cu" "In1.Cu" "In2.Cu" "In3.Cu" "In4.Cu" "In5.Cu" "In6.Cu"
			"In7.Cu" "In8.Cu" "In9.Cu" "In10.Cu" "In11.Cu" "In12.Cu" "In13.Cu" "In14.Cu"
			"In15.Cu" "In16.Cu"
		)
		(hatch none 0.5)
		(connect_pads
			(clearance 0)
		)
		(min_thickness 0.25)
		(keepout
			(tracks not_allowed)
			(vias allowed)
			(pads allowed)
			(copperpour not_allowed)
			(footprints allowed)
		)
		(placement
			(enabled no)
			(sheetname "")
		)
		(fill
			(thermal_gap 0.5)
			(thermal_bridge_width 0.5)
			(island_removal_mode 0)
		)
		(polygon
			(pts
				(arc
					(start 140.137134 -20.541488)
					(mid 140.518134 -20.160488)
					(end 140.137134 -19.779488)
				)
				(arc
					(start 139.146534 -19.779488)
					(mid 138.765534 -20.160488)
					(end 139.146534 -20.541488)
				)
			)
		)
	)
	(zone
		(layers "F.Cu" "B.Cu" "In1.Cu" "In2.Cu" "In3.Cu" "In4.Cu" "In5.Cu" "In6.Cu"
			"In7.Cu" "In8.Cu" "In9.Cu" "In10.Cu" "In11.Cu" "In12.Cu" "In13.Cu" "In14.Cu"
			"In15.Cu" "In16.Cu"
		)
		(hatch none 0.5)
		(connect_pads
			(clearance 0)
		)
		(min_thickness 0.25)
		(keepout
			(tracks not_allowed)
			(vias allowed)
			(pads allowed)
			(copperpour not_allowed)
			(footprints allowed)
		)
		(placement
			(enabled no)
			(sheetname "")
		)
		(fill
			(thermal_gap 0.5)
			(thermal_bridge_width 0.5)
			(island_removal_mode 0)
		)
		(polygon
			(pts
				(arc
					(start 123.697492 -392.429238)
					(mid 123.316492 -392.048238)
					(end 122.935492 -392.429238)
				)
				(arc
					(start 122.935492 -393.292838)
					(mid 123.316492 -393.673838)
					(end 123.697492 -393.292838)
				)
			)
		)
	)
	(zone
		(layers "F.Cu" "B.Cu" "In1.Cu" "In2.Cu" "In3.Cu" "In4.Cu" "In5.Cu" "In6.Cu"
			"In7.Cu" "In8.Cu" "In9.Cu" "In10.Cu" "In11.Cu" "In12.Cu" "In13.Cu" "In14.Cu"
			"In15.Cu" "In16.Cu"
		)
		(hatch none 0.5)
		(connect_pads
			(clearance 0)
		)
		(min_thickness 0.25)
		(keepout
			(tracks not_allowed)
			(vias allowed)
			(pads allowed)
			(copperpour not_allowed)
			(footprints allowed)
		)
		(placement
			(enabled no)
			(sheetname "")
		)
		(fill yes
			(thermal_gap 0.5)
			(thermal_bridge_width 0.5)
			(island_removal_mode 0)
		)
		(polygon
			(pts
				(arc
					(start 341.263986 -394.552424)
					(mid 341.373957 -394.653478)
					(end 341.518748 -394.690092)
				)
				(arc
					(start 341.518748 -394.690092)
					(mid 341.734274 -394.600818)
					(end 341.823548 -394.385292)
				)
				(arc
					(start 341.823548 -394.385292)
					(mid 341.813211 -394.306553)
					(end 341.782908 -394.233146)
				)
				(arc
					(start 341.390478 -393.554204)
					(mid 341.278081 -393.432587)
					(end 341.118698 -393.38758)
				)
				(arc
					(start 341.118698 -393.38758)
					(mid 340.903172 -393.476854)
					(end 340.813898 -393.69238)
				)
				(arc
					(start 340.813898 -393.69238)
					(mid 340.823476 -393.768442)
					(end 340.851744 -393.8397)
				)
				(xy 341.249 -394.527024) (xy 341.261192 -394.54836) (xy 341.263732 -394.552678)
			)
		)
	)
	(zone
		(layers "F.Cu" "B.Cu" "In1.Cu" "In2.Cu" "In3.Cu" "In4.Cu" "In5.Cu" "In6.Cu"
			"In7.Cu" "In8.Cu" "In9.Cu" "In10.Cu" "In11.Cu" "In12.Cu" "In13.Cu" "In14.Cu"
			"In15.Cu" "In16.Cu"
		)
		(hatch none 0.5)
		(connect_pads
			(clearance 0)
		)
		(min_thickness 0.25)
		(keepout
			(tracks not_allowed)
			(vias allowed)
			(pads allowed)
			(copperpour not_allowed)
			(footprints allowed)
		)
		(placement
			(enabled no)
			(sheetname "")
		)
		(fill
			(thermal_gap 0.5)
			(thermal_bridge_width 0.5)
			(island_removal_mode 0)
		)
		(polygon
			(pts
				(arc
					(start 426.695616 -18.75536)
					(mid 426.314616 -19.13636)
					(end 426.695616 -19.51736)
				)
				(arc
					(start 427.559216 -19.51736)
					(mid 427.940216 -19.13636)
					(end 427.559216 -18.75536)
				)
			)
		)
	)
	(zone
		(layers "F.Cu" "B.Cu" "In1.Cu" "In2.Cu" "In3.Cu" "In4.Cu" "In5.Cu" "In6.Cu"
			"In7.Cu" "In8.Cu" "In9.Cu" "In10.Cu" "In11.Cu" "In12.Cu" "In13.Cu" "In14.Cu"
			"In15.Cu" "In16.Cu"
		)
		(hatch none 0.5)
		(connect_pads
			(clearance 0)
		)
		(min_thickness 0.25)
		(keepout
			(tracks not_allowed)
			(vias allowed)
			(pads allowed)
			(copperpour not_allowed)
			(footprints allowed)
		)
		(placement
			(enabled no)
			(sheetname "")
		)
		(fill
			(thermal_gap 0.5)
			(thermal_bridge_width 0.5)
			(island_removal_mode 0)
		)
		(polygon
			(pts
				(arc
					(start 104.186482 -376.093228)
					(mid 103.805482 -375.712228)
					(end 103.424482 -376.093228)
				)
				(arc
					(start 103.424482 -376.956828)
					(mid 103.805482 -377.337828)
					(end 104.186482 -376.956828)
				)
			)
		)
	)
	(zone
		(layers "F.Cu" "B.Cu" "In1.Cu" "In2.Cu" "In3.Cu" "In4.Cu" "In5.Cu" "In6.Cu"
			"In7.Cu" "In8.Cu" "In9.Cu" "In10.Cu" "In11.Cu" "In12.Cu" "In13.Cu" "In14.Cu"
			"In15.Cu" "In16.Cu"
		)
		(hatch none 0.5)
		(connect_pads
			(clearance 0)
		)
		(min_thickness 0.25)
		(keepout
			(tracks not_allowed)
			(vias allowed)
			(pads allowed)
			(copperpour not_allowed)
			(footprints allowed)
		)
		(placement
			(enabled no)
			(sheetname "")
		)
		(fill
			(thermal_gap 0.5)
			(thermal_bridge_width 0.5)
			(island_removal_mode 0)
		)
		(polygon
			(pts
				(arc
					(start 67.705224 -406.62352)
					(mid 67.324224 -407.00452)
					(end 67.705224 -407.38552)
				)
				(arc
					(start 68.568824 -407.38552)
					(mid 68.949824 -407.00452)
					(end 68.568824 -406.62352)
				)
			)
		)
	)
	(zone
		(layers "F.Cu" "B.Cu" "In1.Cu" "In2.Cu" "In3.Cu" "In4.Cu" "In5.Cu" "In6.Cu"
			"In7.Cu" "In8.Cu" "In9.Cu" "In10.Cu" "In11.Cu" "In12.Cu" "In13.Cu" "In14.Cu"
			"In15.Cu" "In16.Cu"
		)
		(hatch none 0.5)
		(connect_pads
			(clearance 0)
		)
		(min_thickness 0.25)
		(keepout
			(tracks not_allowed)
			(vias allowed)
			(pads allowed)
			(copperpour not_allowed)
			(footprints allowed)
		)
		(placement
			(enabled no)
			(sheetname "")
		)
		(fill
			(thermal_gap 0.5)
			(thermal_bridge_width 0.5)
			(island_removal_mode 0)
		)
		(polygon
			(pts
				(arc
					(start 406.225248 -400.811238)
					(mid 405.844248 -400.430238)
					(end 405.463248 -400.811238)
				)
				(arc
					(start 405.463248 -401.674838)
					(mid 405.844248 -402.055838)
					(end 406.225248 -401.674838)
				)
			)
		)
	)
	(zone
		(layers "F.Cu" "B.Cu" "In1.Cu" "In2.Cu" "In3.Cu" "In4.Cu" "In5.Cu" "In6.Cu"
			"In7.Cu" "In8.Cu" "In9.Cu" "In10.Cu" "In11.Cu" "In12.Cu" "In13.Cu" "In14.Cu"
			"In15.Cu" "In16.Cu"
		)
		(hatch none 0.5)
		(connect_pads
			(clearance 0)
		)
		(min_thickness 0.25)
		(keepout
			(tracks not_allowed)
			(vias allowed)
			(pads allowed)
			(copperpour not_allowed)
			(footprints allowed)
		)
		(placement
			(enabled no)
			(sheetname "")
		)
		(fill
			(thermal_gap 0.5)
			(thermal_bridge_width 0.5)
			(island_removal_mode 0)
		)
		(polygon
			(pts
				(arc
					(start 411.964124 -398.016476)
					(mid 412.074095 -398.11753)
					(end 412.218886 -398.154144)
				)
				(arc
					(start 412.218886 -398.154144)
					(mid 412.434412 -398.06487)
					(end 412.523686 -397.849344)
				)
				(arc
					(start 412.523686 -397.849344)
					(mid 412.513349 -397.770605)
					(end 412.483046 -397.697198)
				)
				(arc
					(start 412.090616 -397.018256)
					(mid 411.978219 -396.896639)
					(end 411.818836 -396.851632)
				)
				(arc
					(start 411.818836 -396.851632)
					(mid 411.60331 -396.940906)
					(end 411.514036 -397.156432)
				)
				(arc
					(start 411.514036 -397.156432)
					(mid 411.523614 -397.232494)
					(end 411.551882 -397.303752)
				)
				(xy 411.949138 -397.991076) (xy 411.96133 -398.012412) (xy 411.96387 -398.01673)
			)
		)
	)
	(zone
		(layers "F.Cu" "B.Cu" "In1.Cu" "In2.Cu" "In3.Cu" "In4.Cu" "In5.Cu" "In6.Cu"
			"In7.Cu" "In8.Cu" "In9.Cu" "In10.Cu" "In11.Cu" "In12.Cu" "In13.Cu" "In14.Cu"
			"In15.Cu" "In16.Cu"
		)
		(hatch none 0.5)
		(connect_pads
			(clearance 0)
		)
		(min_thickness 0.25)
		(keepout
			(tracks not_allowed)
			(vias allowed)
			(pads allowed)
			(copperpour not_allowed)
			(footprints allowed)
		)
		(placement
			(enabled no)
			(sheetname "")
		)
		(fill
			(thermal_gap 0.5)
			(thermal_bridge_width 0.5)
			(island_removal_mode 0)
		)
		(polygon
			(pts
				(arc
					(start 255.546098 -194.296284)
					(mid 255.927098 -194.677284)
					(end 256.308098 -194.296284)
				)
				(arc
					(start 256.308098 -193.432684)
					(mid 255.927098 -193.051684)
					(end 255.546098 -193.432684)
				)
			)
		)
	)
	(zone
		(layers "F.Cu" "B.Cu" "In1.Cu" "In2.Cu" "In3.Cu" "In4.Cu" "In5.Cu" "In6.Cu"
			"In7.Cu" "In8.Cu" "In9.Cu" "In10.Cu" "In11.Cu" "In12.Cu" "In13.Cu" "In14.Cu"
			"In15.Cu" "In16.Cu"
		)
		(hatch none 0.5)
		(connect_pads
			(clearance 0)
		)
		(min_thickness 0.25)
		(keepout
			(tracks not_allowed)
			(vias allowed)
			(pads allowed)
			(copperpour not_allowed)
			(footprints allowed)
		)
		(placement
			(enabled no)
			(sheetname "")
		)
		(fill
			(thermal_gap 0.5)
			(thermal_bridge_width 0.5)
			(island_removal_mode 0)
		)
		(polygon
			(pts
				(arc
					(start 346.064078 -398.016476)
					(mid 346.174049 -398.11753)
					(end 346.31884 -398.154144)
				)
				(arc
					(start 346.31884 -398.154144)
					(mid 346.534366 -398.06487)
					(end 346.62364 -397.849344)
				)
				(arc
					(start 346.62364 -397.849344)
					(mid 346.613303 -397.770605)
					(end 346.583 -397.697198)
				)
				(arc
					(start 346.19057 -397.018256)
					(mid 346.078173 -396.896639)
					(end 345.91879 -396.851632)
				)
				(arc
					(start 345.91879 -396.851632)
					(mid 345.703264 -396.940906)
					(end 345.61399 -397.156432)
				)
				(arc
					(start 345.61399 -397.156432)
					(mid 345.623568 -397.232494)
					(end 345.651836 -397.303752)
				)
				(xy 346.049092 -397.991076) (xy 346.061284 -398.012412) (xy 346.063824 -398.01673)
			)
		)
	)
	(zone
		(layers "F.Cu" "B.Cu" "In1.Cu" "In2.Cu" "In3.Cu" "In4.Cu" "In5.Cu" "In6.Cu"
			"In7.Cu" "In8.Cu" "In9.Cu" "In10.Cu" "In11.Cu" "In12.Cu" "In13.Cu" "In14.Cu"
			"In15.Cu" "In16.Cu"
		)
		(hatch none 0.5)
		(connect_pads
			(clearance 0)
		)
		(min_thickness 0.25)
		(keepout
			(tracks not_allowed)
			(vias allowed)
			(pads allowed)
			(copperpour not_allowed)
			(footprints allowed)
		)
		(placement
			(enabled no)
			(sheetname "")
		)
		(fill
			(thermal_gap 0.5)
			(thermal_bridge_width 0.5)
			(island_removal_mode 0)
		)
		(polygon
			(pts
				(arc
					(start 340.06409 -398.016476)
					(mid 340.174061 -398.11753)
					(end 340.318852 -398.154144)
				)
				(arc
					(start 340.318852 -398.154144)
					(mid 340.534378 -398.06487)
					(end 340.623652 -397.849344)
				)
				(arc
					(start 340.623652 -397.849344)
					(mid 340.613315 -397.770605)
					(end 340.583012 -397.697198)
				)
				(arc
					(start 340.190582 -397.018256)
					(mid 340.078185 -396.896639)
					(end 339.918802 -396.851632)
				)
				(arc
					(start 339.918802 -396.851632)
					(mid 339.703276 -396.940906)
					(end 339.614002 -397.156432)
				)
				(arc
					(start 339.614002 -397.156432)
					(mid 339.62358 -397.232494)
					(end 339.651848 -397.303752)
				)
				(xy 340.049104 -397.991076) (xy 340.061296 -398.012412) (xy 340.063836 -398.01673)
			)
		)
	)
	(zone
		(layers "F.Cu" "B.Cu" "In1.Cu" "In2.Cu" "In3.Cu" "In4.Cu" "In5.Cu" "In6.Cu"
			"In7.Cu" "In8.Cu" "In9.Cu" "In10.Cu" "In11.Cu" "In12.Cu" "In13.Cu" "In14.Cu"
			"In15.Cu" "In16.Cu"
		)
		(hatch none 0.5)
		(connect_pads
			(clearance 0)
		)
		(min_thickness 0.25)
		(keepout
			(tracks not_allowed)
			(vias allowed)
			(pads allowed)
			(copperpour not_allowed)
			(footprints allowed)
		)
		(placement
			(enabled no)
			(sheetname "")
		)
		(fill
			(thermal_gap 0.5)
			(thermal_bridge_width 0.5)
			(island_removal_mode 0)
		)
		(polygon
			(pts
				(arc
					(start 390.805162 -415.00552)
					(mid 390.424162 -415.38652)
					(end 390.805162 -415.76752)
				)
				(arc
					(start 391.668762 -415.76752)
					(mid 392.049762 -415.38652)
					(end 391.668762 -415.00552)
				)
			)
		)
	)
	(zone
		(layers "F.Cu" "B.Cu" "In1.Cu" "In2.Cu" "In3.Cu" "In4.Cu" "In5.Cu" "In6.Cu"
			"In7.Cu" "In8.Cu" "In9.Cu" "In10.Cu" "In11.Cu" "In12.Cu" "In13.Cu" "In14.Cu"
			"In15.Cu" "In16.Cu"
		)
		(hatch none 0.5)
		(connect_pads
			(clearance 0)
		)
		(min_thickness 0.25)
		(keepout
			(tracks not_allowed)
			(vias allowed)
			(pads allowed)
			(copperpour not_allowed)
			(footprints allowed)
		)
		(placement
			(enabled no)
			(sheetname "")
		)
		(fill
			(thermal_gap 0.5)
			(thermal_bridge_width 0.5)
			(island_removal_mode 0)
		)
		(polygon
			(pts
				(arc
					(start 298.630086 -5.508244)
					(mid 299.061886 -5.940044)
					(end 299.493686 -5.508244)
				)
				(arc
					(start 299.493686 -4.644644)
					(mid 299.061886 -4.212844)
					(end 298.630086 -4.644644)
				)
			)
		)
	)
	(zone
		(layers "F.Cu" "B.Cu" "In1.Cu" "In2.Cu" "In3.Cu" "In4.Cu" "In5.Cu" "In6.Cu"
			"In7.Cu" "In8.Cu" "In9.Cu" "In10.Cu" "In11.Cu" "In12.Cu" "In13.Cu" "In14.Cu"
			"In15.Cu" "In16.Cu"
		)
		(hatch none 0.5)
		(connect_pads
			(clearance 0)
		)
		(min_thickness 0.25)
		(keepout
			(tracks not_allowed)
			(vias allowed)
			(pads allowed)
			(copperpour not_allowed)
			(footprints allowed)
		)
		(placement
			(enabled no)
			(sheetname "")
		)
		(fill
			(thermal_gap 0.5)
			(thermal_bridge_width 0.5)
			(island_removal_mode 0)
		)
		(polygon
			(pts
				(arc
					(start 175.584104 -369.217448)
					(mid 175.203104 -369.598448)
					(end 175.584104 -369.979448)
				)
				(arc
					(start 176.447704 -369.979448)
					(mid 176.828704 -369.598448)
					(end 176.447704 -369.217448)
				)
			)
		)
	)
	(zone
		(layers "F.Cu" "B.Cu" "In1.Cu" "In2.Cu" "In3.Cu" "In4.Cu" "In5.Cu" "In6.Cu"
			"In7.Cu" "In8.Cu" "In9.Cu" "In10.Cu" "In11.Cu" "In12.Cu" "In13.Cu" "In14.Cu"
			"In15.Cu" "In16.Cu"
		)
		(hatch none 0.5)
		(connect_pads
			(clearance 0)
		)
		(min_thickness 0.25)
		(keepout
			(tracks not_allowed)
			(vias allowed)
			(pads allowed)
			(copperpour not_allowed)
			(footprints allowed)
		)
		(placement
			(enabled no)
			(sheetname "")
		)
		(fill
			(thermal_gap 0.5)
			(thermal_bridge_width 0.5)
			(island_removal_mode 0)
		)
		(polygon
			(pts
				(arc
					(start 310.197246 -400.811238)
					(mid 309.816246 -400.430238)
					(end 309.435246 -400.811238)
				)
				(arc
					(start 309.435246 -401.674838)
					(mid 309.816246 -402.055838)
					(end 310.197246 -401.674838)
				)
			)
		)
	)
	(zone
		(layers "F.Cu" "B.Cu" "In1.Cu" "In2.Cu" "In3.Cu" "In4.Cu" "In5.Cu" "In6.Cu"
			"In7.Cu" "In8.Cu" "In9.Cu" "In10.Cu" "In11.Cu" "In12.Cu" "In13.Cu" "In14.Cu"
			"In15.Cu" "In16.Cu"
		)
		(hatch none 0.5)
		(connect_pads
			(clearance 0)
		)
		(min_thickness 0.25)
		(keepout
			(tracks not_allowed)
			(vias allowed)
			(pads allowed)
			(copperpour not_allowed)
			(footprints allowed)
		)
		(placement
			(enabled no)
			(sheetname "")
		)
		(fill
			(thermal_gap 0.5)
			(thermal_bridge_width 0.5)
			(island_removal_mode 0)
		)
		(polygon
			(pts
				(arc
					(start 178.630834 -55.481728)
					(mid 179.011834 -55.862728)
					(end 179.392834 -55.481728)
				)
				(arc
					(start 179.392834 -54.618128)
					(mid 179.011834 -54.237128)
					(end 178.630834 -54.618128)
				)
			)
		)
	)
	(zone
		(layers "F.Cu" "B.Cu" "In1.Cu" "In2.Cu" "In3.Cu" "In4.Cu" "In5.Cu" "In6.Cu"
			"In7.Cu" "In8.Cu" "In9.Cu" "In10.Cu" "In11.Cu" "In12.Cu" "In13.Cu" "In14.Cu"
			"In15.Cu" "In16.Cu"
		)
		(hatch none 0.5)
		(connect_pads
			(clearance 0)
		)
		(min_thickness 0.25)
		(keepout
			(tracks not_allowed)
			(vias allowed)
			(pads allowed)
			(copperpour not_allowed)
			(footprints allowed)
		)
		(placement
			(enabled no)
			(sheetname "")
		)
		(fill
			(thermal_gap 0.5)
			(thermal_bridge_width 0.5)
			(island_removal_mode 0)
		)
		(polygon
			(pts
				(arc
					(start 15.201646 -357.208074)
					(mid 14.820646 -356.827074)
					(end 14.439646 -357.208074)
				)
				(arc
					(start 14.439646 -358.071674)
					(mid 14.820646 -358.452674)
					(end 15.201646 -358.071674)
				)
			)
		)
	)
	(zone
		(layers "F.Cu" "B.Cu" "In1.Cu" "In2.Cu" "In3.Cu" "In4.Cu" "In5.Cu" "In6.Cu"
			"In7.Cu" "In8.Cu" "In9.Cu" "In10.Cu" "In11.Cu" "In12.Cu" "In13.Cu" "In14.Cu"
			"In15.Cu" "In16.Cu"
		)
		(hatch none 0.5)
		(connect_pads
			(clearance 0)
		)
		(min_thickness 0.25)
		(keepout
			(tracks not_allowed)
			(vias allowed)
			(pads allowed)
			(copperpour not_allowed)
			(footprints allowed)
		)
		(placement
			(enabled no)
			(sheetname "")
		)
		(fill
			(thermal_gap 0.5)
			(thermal_bridge_width 0.5)
			(island_removal_mode 0)
		)
		(polygon
			(pts
				(arc
					(start 433.212494 -164.097716)
					(mid 433.593494 -163.716716)
					(end 433.212494 -163.335716)
				)
				(arc
					(start 432.221894 -163.335716)
					(mid 431.840894 -163.716716)
					(end 432.221894 -164.097716)
				)
			)
		)
	)
	(zone
		(layers "F.Cu" "B.Cu" "In1.Cu" "In2.Cu" "In3.Cu" "In4.Cu" "In5.Cu" "In6.Cu"
			"In7.Cu" "In8.Cu" "In9.Cu" "In10.Cu" "In11.Cu" "In12.Cu" "In13.Cu" "In14.Cu"
			"In15.Cu" "In16.Cu"
		)
		(hatch none 0.5)
		(connect_pads
			(clearance 0)
		)
		(min_thickness 0.25)
		(keepout
			(tracks not_allowed)
			(vias allowed)
			(pads allowed)
			(copperpour not_allowed)
			(footprints allowed)
		)
		(placement
			(enabled no)
			(sheetname "")
		)
		(fill
			(thermal_gap 0.5)
			(thermal_bridge_width 0.5)
			(island_removal_mode 0)
		)
		(polygon
			(pts
				(arc
					(start 343.925144 -400.811238)
					(mid 343.544144 -400.430238)
					(end 343.163144 -400.811238)
				)
				(arc
					(start 343.163144 -401.674838)
					(mid 343.544144 -402.055838)
					(end 343.925144 -401.674838)
				)
			)
		)
	)
	(zone
		(layers "F.Cu" "B.Cu" "In1.Cu" "In2.Cu" "In3.Cu" "In4.Cu" "In5.Cu" "In6.Cu"
			"In7.Cu" "In8.Cu" "In9.Cu" "In10.Cu" "In11.Cu" "In12.Cu" "In13.Cu" "In14.Cu"
			"In15.Cu" "In16.Cu"
		)
		(hatch none 0.5)
		(connect_pads
			(clearance 0)
		)
		(min_thickness 0.25)
		(keepout
			(tracks not_allowed)
			(vias allowed)
			(pads allowed)
			(copperpour not_allowed)
			(footprints allowed)
		)
		(placement
			(enabled no)
			(sheetname "")
		)
		(fill
			(thermal_gap 0.5)
			(thermal_bridge_width 0.5)
			(island_removal_mode 0)
		)
		(polygon
			(pts
				(arc
					(start 312.33618 -398.016476)
					(mid 312.446151 -398.11753)
					(end 312.590942 -398.154144)
				)
				(arc
					(start 312.590942 -398.154144)
					(mid 312.806468 -398.06487)
					(end 312.895742 -397.849344)
				)
				(arc
					(start 312.895742 -397.849344)
					(mid 312.885405 -397.770605)
					(end 312.855102 -397.697198)
				)
				(arc
					(start 312.462672 -397.018256)
					(mid 312.350275 -396.896639)
					(end 312.190892 -396.851632)
				)
				(arc
					(start 312.190892 -396.851632)
					(mid 311.975366 -396.940906)
					(end 311.886092 -397.156432)
				)
				(arc
					(start 311.886092 -397.156432)
					(mid 311.89567 -397.232494)
					(end 311.923938 -397.303752)
				)
				(xy 312.321194 -397.991076) (xy 312.333386 -398.012412) (xy 312.335926 -398.01673)
			)
		)
	)
	(zone
		(layers "F.Cu" "B.Cu" "In1.Cu" "In2.Cu" "In3.Cu" "In4.Cu" "In5.Cu" "In6.Cu"
			"In7.Cu" "In8.Cu" "In9.Cu" "In10.Cu" "In11.Cu" "In12.Cu" "In13.Cu" "In14.Cu"
			"In15.Cu" "In16.Cu"
		)
		(hatch none 0.5)
		(connect_pads
			(clearance 0)
		)
		(min_thickness 0.25)
		(keepout
			(tracks not_allowed)
			(vias allowed)
			(pads allowed)
			(copperpour not_allowed)
			(footprints allowed)
		)
		(placement
			(enabled no)
			(sheetname "")
		)
		(fill
			(thermal_gap 0.5)
			(thermal_bridge_width 0.5)
			(island_removal_mode 0)
		)
		(polygon
			(pts
				(arc
					(start 159.564324 -389.634476)
					(mid 159.674295 -389.73553)
					(end 159.819086 -389.772144)
				)
				(arc
					(start 159.819086 -389.772144)
					(mid 160.034612 -389.68287)
					(end 160.123886 -389.467344)
				)
				(arc
					(start 160.123886 -389.467344)
					(mid 160.113549 -389.388605)
					(end 160.083246 -389.315198)
				)
				(arc
					(start 159.690816 -388.636256)
					(mid 159.578419 -388.514639)
					(end 159.419036 -388.469632)
				)
				(arc
					(start 159.419036 -388.469632)
					(mid 159.20351 -388.558906)
					(end 159.114236 -388.774432)
				)
				(arc
					(start 159.114236 -388.774432)
					(mid 159.123814 -388.850494)
					(end 159.152082 -388.921752)
				)
				(xy 159.549338 -389.609076) (xy 159.56153 -389.630412) (xy 159.56407 -389.63473)
			)
		)
	)
	(zone
		(layers "F.Cu" "B.Cu" "In1.Cu" "In2.Cu" "In3.Cu" "In4.Cu" "In5.Cu" "In6.Cu"
			"In7.Cu" "In8.Cu" "In9.Cu" "In10.Cu" "In11.Cu" "In12.Cu" "In13.Cu" "In14.Cu"
			"In15.Cu" "In16.Cu"
		)
		(hatch none 0.5)
		(connect_pads
			(clearance 0)
		)
		(min_thickness 0.25)
		(keepout
			(tracks not_allowed)
			(vias allowed)
			(pads allowed)
			(copperpour not_allowed)
			(footprints allowed)
		)
		(placement
			(enabled no)
			(sheetname "")
		)
		(fill yes
			(thermal_gap 0.5)
			(thermal_bridge_width 0.5)
			(island_removal_mode 0)
		)
		(polygon
			(pts
				(arc
					(start 127.036576 -386.170424)
					(mid 127.146547 -386.271478)
					(end 127.291338 -386.308092)
				)
				(arc
					(start 127.291338 -386.308092)
					(mid 127.506864 -386.218818)
					(end 127.596138 -386.003292)
				)
				(arc
					(start 127.596138 -386.003292)
					(mid 127.585801 -385.924553)
					(end 127.555498 -385.851146)
				)
				(arc
					(start 127.163068 -385.172204)
					(mid 127.050671 -385.050587)
					(end 126.891288 -385.00558)
				)
				(arc
					(start 126.891288 -385.00558)
					(mid 126.675762 -385.094854)
					(end 126.586488 -385.31038)
				)
				(arc
					(start 126.586488 -385.31038)
					(mid 126.596066 -385.386442)
					(end 126.624334 -385.4577)
				)
				(xy 127.02159 -386.145024) (xy 127.033782 -386.16636) (xy 127.036322 -386.170678)
			)
		)
	)
	(zone
		(layers "F.Cu" "B.Cu" "In1.Cu" "In2.Cu" "In3.Cu" "In4.Cu" "In5.Cu" "In6.Cu"
			"In7.Cu" "In8.Cu" "In9.Cu" "In10.Cu" "In11.Cu" "In12.Cu" "In13.Cu" "In14.Cu"
			"In15.Cu" "In16.Cu"
		)
		(hatch none 0.5)
		(connect_pads
			(clearance 0)
		)
		(min_thickness 0.25)
		(keepout
			(tracks not_allowed)
			(vias allowed)
			(pads allowed)
			(copperpour not_allowed)
			(footprints allowed)
		)
		(placement
			(enabled no)
			(sheetname "")
		)
		(fill
			(thermal_gap 0.5)
			(thermal_bridge_width 0.5)
			(island_removal_mode 0)
		)
		(polygon
			(pts
				(arc
					(start 69.236844 -412.189168)
					(mid 68.855844 -412.570168)
					(end 69.236844 -412.951168)
				)
				(arc
					(start 70.100444 -412.951168)
					(mid 70.481444 -412.570168)
					(end 70.100444 -412.189168)
				)
			)
		)
	)
	(zone
		(layers "F.Cu" "B.Cu" "In1.Cu" "In2.Cu" "In3.Cu" "In4.Cu" "In5.Cu" "In6.Cu"
			"In7.Cu" "In8.Cu" "In9.Cu" "In10.Cu" "In11.Cu" "In12.Cu" "In13.Cu" "In14.Cu"
			"In15.Cu" "In16.Cu"
		)
		(hatch none 0.5)
		(connect_pads
			(clearance 0)
		)
		(min_thickness 0.25)
		(keepout
			(tracks not_allowed)
			(vias allowed)
			(pads allowed)
			(copperpour not_allowed)
			(footprints allowed)
		)
		(placement
			(enabled no)
			(sheetname "")
		)
		(fill
			(thermal_gap 0.5)
			(thermal_bridge_width 0.5)
			(island_removal_mode 0)
		)
		(polygon
			(pts
				(arc
					(start 331.78242 -212.980016)
					(mid 326.753728 -212.980016)
					(end 331.78242 -212.980016)
				)
			)
		)
	)
	(zone
		(layers "F.Cu" "B.Cu" "In1.Cu" "In2.Cu" "In3.Cu" "In4.Cu" "In5.Cu" "In6.Cu"
			"In7.Cu" "In8.Cu" "In9.Cu" "In10.Cu" "In11.Cu" "In12.Cu" "In13.Cu" "In14.Cu"
			"In15.Cu" "In16.Cu"
		)
		(hatch none 0.5)
		(connect_pads
			(clearance 0)
		)
		(min_thickness 0.25)
		(keepout
			(tracks not_allowed)
			(vias allowed)
			(pads allowed)
			(copperpour not_allowed)
			(footprints allowed)
		)
		(placement
			(enabled no)
			(sheetname "")
		)
		(fill
			(thermal_gap 0.5)
			(thermal_bridge_width 0.5)
			(island_removal_mode 0)
		)
		(polygon
			(pts
				(arc
					(start 77.244702 -368.65433)
					(mid 76.863702 -369.03533)
					(end 77.244702 -369.41633)
				)
				(arc
					(start 78.108302 -369.41633)
					(mid 78.489302 -369.03533)
					(end 78.108302 -368.65433)
				)
			)
		)
	)
	(zone
		(layers "F.Cu" "B.Cu" "In1.Cu" "In2.Cu" "In3.Cu" "In4.Cu" "In5.Cu" "In6.Cu"
			"In7.Cu" "In8.Cu" "In9.Cu" "In10.Cu" "In11.Cu" "In12.Cu" "In13.Cu" "In14.Cu"
			"In15.Cu" "In16.Cu"
		)
		(hatch none 0.5)
		(connect_pads
			(clearance 0)
		)
		(min_thickness 0.25)
		(keepout
			(tracks not_allowed)
			(vias allowed)
			(pads allowed)
			(copperpour not_allowed)
			(footprints allowed)
		)
		(placement
			(enabled no)
			(sheetname "")
		)
		(fill
			(thermal_gap 0.5)
			(thermal_bridge_width 0.5)
			(island_removal_mode 0)
		)
		(polygon
			(pts
				(arc
					(start 332.894686 -415.00552)
					(mid 332.513686 -415.38652)
					(end 332.894686 -415.76752)
				)
				(arc
					(start 333.758286 -415.76752)
					(mid 334.139286 -415.38652)
					(end 333.758286 -415.00552)
				)
			)
		)
	)
	(zone
		(layers "F.Cu" "B.Cu" "In1.Cu" "In2.Cu" "In3.Cu" "In4.Cu" "In5.Cu" "In6.Cu"
			"In7.Cu" "In8.Cu" "In9.Cu" "In10.Cu" "In11.Cu" "In12.Cu" "In13.Cu" "In14.Cu"
			"In15.Cu" "In16.Cu"
		)
		(hatch none 0.5)
		(connect_pads
			(clearance 0)
		)
		(min_thickness 0.25)
		(keepout
			(tracks not_allowed)
			(vias allowed)
			(pads allowed)
			(copperpour not_allowed)
			(footprints allowed)
		)
		(placement
			(enabled no)
			(sheetname "")
		)
		(fill
			(thermal_gap 0.5)
			(thermal_bridge_width 0.5)
			(island_removal_mode 0)
		)
		(polygon
			(pts
				(arc
					(start 81.664302 -389.634476)
					(mid 81.774273 -389.73553)
					(end 81.919064 -389.772144)
				)
				(arc
					(start 81.919064 -389.772144)
					(mid 82.13459 -389.68287)
					(end 82.223864 -389.467344)
				)
				(arc
					(start 82.223864 -389.467344)
					(mid 82.213527 -389.388605)
					(end 82.183224 -389.315198)
				)
				(arc
					(start 81.790794 -388.636256)
					(mid 81.678397 -388.514639)
					(end 81.519014 -388.469632)
				)
				(arc
					(start 81.519014 -388.469632)
					(mid 81.303488 -388.558906)
					(end 81.214214 -388.774432)
				)
				(arc
					(start 81.214214 -388.774432)
					(mid 81.223792 -388.850494)
					(end 81.25206 -388.921752)
				)
				(xy 81.649316 -389.609076) (xy 81.661508 -389.630412) (xy 81.664048 -389.63473)
			)
		)
	)
	(zone
		(layers "F.Cu" "B.Cu" "In1.Cu" "In2.Cu" "In3.Cu" "In4.Cu" "In5.Cu" "In6.Cu"
			"In7.Cu" "In8.Cu" "In9.Cu" "In10.Cu" "In11.Cu" "In12.Cu" "In13.Cu" "In14.Cu"
			"In15.Cu" "In16.Cu"
		)
		(hatch none 0.5)
		(connect_pads
			(clearance 0)
		)
		(min_thickness 0.25)
		(keepout
			(tracks not_allowed)
			(vias allowed)
			(pads allowed)
			(copperpour not_allowed)
			(footprints allowed)
		)
		(placement
			(enabled no)
			(sheetname "")
		)
		(fill
			(thermal_gap 0.5)
			(thermal_bridge_width 0.5)
			(island_removal_mode 0)
		)
		(polygon
			(pts
				(arc
					(start 287.864296 -406.550622)
					(mid 287.483296 -406.169622)
					(end 287.102296 -406.550622)
				)
				(arc
					(start 287.102296 -407.414222)
					(mid 287.483296 -407.795222)
					(end 287.864296 -407.414222)
				)
			)
		)
	)
	(zone
		(layers "F.Cu" "B.Cu" "In1.Cu" "In2.Cu" "In3.Cu" "In4.Cu" "In5.Cu" "In6.Cu"
			"In7.Cu" "In8.Cu" "In9.Cu" "In10.Cu" "In11.Cu" "In12.Cu" "In13.Cu" "In14.Cu"
			"In15.Cu" "In16.Cu"
		)
		(hatch none 0.5)
		(connect_pads
			(clearance 0)
		)
		(min_thickness 0.25)
		(keepout
			(tracks not_allowed)
			(vias allowed)
			(pads allowed)
			(copperpour not_allowed)
			(footprints allowed)
		)
		(placement
			(enabled no)
			(sheetname "")
		)
		(fill
			(thermal_gap 0.5)
			(thermal_bridge_width 0.5)
			(island_removal_mode 0)
		)
		(polygon
			(pts
				(arc
					(start 41.811702 -381.50546)
					(mid 41.430702 -381.12446)
					(end 41.049702 -381.50546)
				)
				(arc
					(start 41.049702 -382.36906)
					(mid 41.430702 -382.75006)
					(end 41.811702 -382.36906)
				)
			)
		)
	)
	(zone
		(layers "F.Cu" "B.Cu" "In1.Cu" "In2.Cu" "In3.Cu" "In4.Cu" "In5.Cu" "In6.Cu"
			"In7.Cu" "In8.Cu" "In9.Cu" "In10.Cu" "In11.Cu" "In12.Cu" "In13.Cu" "In14.Cu"
			"In15.Cu" "In16.Cu"
		)
		(hatch none 0.5)
		(connect_pads
			(clearance 0)
		)
		(min_thickness 0.25)
		(keepout
			(tracks not_allowed)
			(vias allowed)
			(pads allowed)
			(copperpour not_allowed)
			(footprints allowed)
		)
		(placement
			(enabled no)
			(sheetname "")
		)
		(fill
			(thermal_gap 0.5)
			(thermal_bridge_width 0.5)
			(island_removal_mode 0)
		)
		(polygon
			(pts
				(arc
					(start 390.509506 5.71881)
					(mid 390.941306 5.28701)
					(end 391.373106 5.71881)
				)
				(arc
					(start 391.373106 6.58241)
					(mid 390.941306 7.01421)
					(end 390.509506 6.58241)
				)
			)
		)
	)
	(zone
		(layers "F.Cu" "B.Cu" "In1.Cu" "In2.Cu" "In3.Cu" "In4.Cu" "In5.Cu" "In6.Cu"
			"In7.Cu" "In8.Cu" "In9.Cu" "In10.Cu" "In11.Cu" "In12.Cu" "In13.Cu" "In14.Cu"
			"In15.Cu" "In16.Cu"
		)
		(hatch none 0.5)
		(connect_pads
			(clearance 0)
		)
		(min_thickness 0.25)
		(keepout
			(tracks not_allowed)
			(vias allowed)
			(pads allowed)
			(copperpour not_allowed)
			(footprints allowed)
		)
		(placement
			(enabled no)
			(sheetname "")
		)
		(fill
			(thermal_gap 0.5)
			(thermal_bridge_width 0.5)
			(island_removal_mode 0)
		)
		(polygon
			(pts
				(arc
					(start 41.663874 -386.926074)
					(mid 41.282874 -386.545074)
					(end 40.901874 -386.926074)
				)
				(arc
					(start 40.901874 -387.789674)
					(mid 41.282874 -388.170674)
					(end 41.663874 -387.789674)
				)
			)
		)
	)
	(zone
		(layers "F.Cu" "B.Cu" "In1.Cu" "In2.Cu" "In3.Cu" "In4.Cu" "In5.Cu" "In6.Cu"
			"In7.Cu" "In8.Cu" "In9.Cu" "In10.Cu" "In11.Cu" "In12.Cu" "In13.Cu" "In14.Cu"
			"In15.Cu" "In16.Cu"
		)
		(hatch none 0.5)
		(connect_pads
			(clearance 0)
		)
		(min_thickness 0.25)
		(keepout
			(tracks not_allowed)
			(vias allowed)
			(pads allowed)
			(copperpour not_allowed)
			(footprints allowed)
		)
		(placement
			(enabled no)
			(sheetname "")
		)
		(fill
			(thermal_gap 0.5)
			(thermal_bridge_width 0.5)
			(island_removal_mode 0)
		)
		(polygon
			(pts
				(arc
					(start 108.763816 -386.926074)
					(mid 108.382816 -386.545074)
					(end 108.001816 -386.926074)
				)
				(arc
					(start 108.001816 -387.789674)
					(mid 108.382816 -388.170674)
					(end 108.763816 -387.789674)
				)
			)
		)
	)
	(zone
		(layers "F.Cu" "B.Cu" "In1.Cu" "In2.Cu" "In3.Cu" "In4.Cu" "In5.Cu" "In6.Cu"
			"In7.Cu" "In8.Cu" "In9.Cu" "In10.Cu" "In11.Cu" "In12.Cu" "In13.Cu" "In14.Cu"
			"In15.Cu" "In16.Cu"
		)
		(hatch none 0.5)
		(connect_pads
			(clearance 0)
		)
		(min_thickness 0.25)
		(keepout
			(tracks not_allowed)
			(vias allowed)
			(pads allowed)
			(copperpour not_allowed)
			(footprints allowed)
		)
		(placement
			(enabled no)
			(sheetname "")
		)
		(fill
			(thermal_gap 0.5)
			(thermal_bridge_width 0.5)
			(island_removal_mode 0)
		)
		(polygon
			(pts
				(arc
					(start 378.552202 -418.031168)
					(mid 378.171202 -418.412168)
					(end 378.552202 -418.793168)
				)
				(arc
					(start 379.415802 -418.793168)
					(mid 379.796802 -418.412168)
					(end 379.415802 -418.031168)
				)
			)
		)
	)
	(zone
		(layers "F.Cu" "B.Cu" "In1.Cu" "In2.Cu" "In3.Cu" "In4.Cu" "In5.Cu" "In6.Cu"
			"In7.Cu" "In8.Cu" "In9.Cu" "In10.Cu" "In11.Cu" "In12.Cu" "In13.Cu" "In14.Cu"
			"In15.Cu" "In16.Cu"
		)
		(hatch none 0.5)
		(connect_pads
			(clearance 0)
		)
		(min_thickness 0.25)
		(keepout
			(tracks not_allowed)
			(vias allowed)
			(pads allowed)
			(copperpour not_allowed)
			(footprints allowed)
		)
		(placement
			(enabled no)
			(sheetname "")
		)
		(fill
			(thermal_gap 0.5)
			(thermal_bridge_width 0.5)
			(island_removal_mode 0)
		)
		(polygon
			(pts
				(xy 516.219694 -347.31706) (xy 516.219694 -357.31704) (xy 516.524494 -357.01224) (xy 516.524494 -347.62186)
			)
		)
	)
	(zone
		(layers "F.Cu" "B.Cu" "In1.Cu" "In2.Cu" "In3.Cu" "In4.Cu" "In5.Cu" "In6.Cu"
			"In7.Cu" "In8.Cu" "In9.Cu" "In10.Cu" "In11.Cu" "In12.Cu" "In13.Cu" "In14.Cu"
			"In15.Cu" "In16.Cu"
		)
		(hatch none 0.5)
		(connect_pads
			(clearance 0)
		)
		(min_thickness 0.25)
		(keepout
			(tracks not_allowed)
			(vias allowed)
			(pads allowed)
			(copperpour not_allowed)
			(footprints allowed)
		)
		(placement
			(enabled no)
			(sheetname "")
		)
		(fill
			(thermal_gap 0.5)
			(thermal_bridge_width 0.5)
			(island_removal_mode 0)
		)
		(polygon
			(pts
				(arc
					(start 380.083822 -412.46552)
					(mid 379.702822 -412.84652)
					(end 380.083822 -413.22752)
				)
				(arc
					(start 380.947422 -413.22752)
					(mid 381.328422 -412.84652)
					(end 380.947422 -412.46552)
				)
			)
		)
	)
	(zone
		(layers "F.Cu" "B.Cu" "In1.Cu" "In2.Cu" "In3.Cu" "In4.Cu" "In5.Cu" "In6.Cu"
			"In7.Cu" "In8.Cu" "In9.Cu" "In10.Cu" "In11.Cu" "In12.Cu" "In13.Cu" "In14.Cu"
			"In15.Cu" "In16.Cu"
		)
		(hatch none 0.5)
		(connect_pads
			(clearance 0)
		)
		(min_thickness 0.25)
		(keepout
			(tracks not_allowed)
			(vias allowed)
			(pads allowed)
			(copperpour not_allowed)
			(footprints allowed)
		)
		(placement
			(enabled no)
			(sheetname "")
		)
		(fill yes
			(thermal_gap 0.5)
			(thermal_bridge_width 0.5)
			(island_removal_mode 0)
		)
		(polygon
			(pts
				(arc
					(start 421.564308 -394.552424)
					(mid 421.674279 -394.653478)
					(end 421.81907 -394.690092)
				)
				(arc
					(start 421.81907 -394.690092)
					(mid 422.034596 -394.600818)
					(end 422.12387 -394.385292)
				)
				(arc
					(start 422.12387 -394.385292)
					(mid 422.113533 -394.306553)
					(end 422.08323 -394.233146)
				)
				(arc
					(start 421.6908 -393.554204)
					(mid 421.578403 -393.432587)
					(end 421.41902 -393.38758)
				)
				(arc
					(start 421.41902 -393.38758)
					(mid 421.203494 -393.476854)
					(end 421.11422 -393.69238)
				)
				(arc
					(start 421.11422 -393.69238)
					(mid 421.123798 -393.768442)
					(end 421.152066 -393.8397)
				)
				(xy 421.549322 -394.527024) (xy 421.561514 -394.54836) (xy 421.564054 -394.552678)
			)
		)
	)
	(zone
		(layers "F.Cu" "B.Cu" "In1.Cu" "In2.Cu" "In3.Cu" "In4.Cu" "In5.Cu" "In6.Cu"
			"In7.Cu" "In8.Cu" "In9.Cu" "In10.Cu" "In11.Cu" "In12.Cu" "In13.Cu" "In14.Cu"
			"In15.Cu" "In16.Cu"
		)
		(hatch none 0.5)
		(connect_pads
			(clearance 0)
		)
		(min_thickness 0.25)
		(keepout
			(tracks not_allowed)
			(vias allowed)
			(pads allowed)
			(copperpour not_allowed)
			(footprints allowed)
		)
		(placement
			(enabled no)
			(sheetname "")
		)
		(fill
			(thermal_gap 0.5)
			(thermal_bridge_width 0.5)
			(island_removal_mode 0)
		)
		(polygon
			(pts
				(arc
					(start 165.564312 -389.634476)
					(mid 165.674283 -389.73553)
					(end 165.819074 -389.772144)
				)
				(arc
					(start 165.819074 -389.772144)
					(mid 166.0346 -389.68287)
					(end 166.123874 -389.467344)
				)
				(arc
					(start 166.123874 -389.467344)
					(mid 166.113537 -389.388605)
					(end 166.083234 -389.315198)
				)
				(arc
					(start 165.690804 -388.636256)
					(mid 165.578407 -388.514639)
					(end 165.419024 -388.469632)
				)
				(arc
					(start 165.419024 -388.469632)
					(mid 165.203498 -388.558906)
					(end 165.114224 -388.774432)
				)
				(arc
					(start 165.114224 -388.774432)
					(mid 165.123802 -388.850494)
					(end 165.15207 -388.921752)
				)
				(xy 165.549326 -389.609076) (xy 165.561518 -389.630412) (xy 165.564058 -389.63473)
			)
		)
	)
	(zone
		(layers "F.Cu" "B.Cu" "In1.Cu" "In2.Cu" "In3.Cu" "In4.Cu" "In5.Cu" "In6.Cu"
			"In7.Cu" "In8.Cu" "In9.Cu" "In10.Cu" "In11.Cu" "In12.Cu" "In13.Cu" "In14.Cu"
			"In15.Cu" "In16.Cu"
		)
		(hatch none 0.5)
		(connect_pads
			(clearance 0)
		)
		(min_thickness 0.25)
		(keepout
			(tracks not_allowed)
			(vias allowed)
			(pads allowed)
			(copperpour not_allowed)
			(footprints allowed)
		)
		(placement
			(enabled no)
			(sheetname "")
		)
		(fill
			(thermal_gap 0.5)
			(thermal_bridge_width 0.5)
			(island_removal_mode 0)
		)
		(polygon
			(pts
				(arc
					(start 53.920644 -404.08352)
					(mid 53.539644 -404.46452)
					(end 53.920644 -404.84552)
				)
				(arc
					(start 54.784244 -404.84552)
					(mid 55.165244 -404.46452)
					(end 54.784244 -404.08352)
				)
			)
		)
	)
	(zone
		(layers "F.Cu" "B.Cu" "In1.Cu" "In2.Cu" "In3.Cu" "In4.Cu" "In5.Cu" "In6.Cu"
			"In7.Cu" "In8.Cu" "In9.Cu" "In10.Cu" "In11.Cu" "In12.Cu" "In13.Cu" "In14.Cu"
			"In15.Cu" "In16.Cu"
		)
		(hatch none 0.5)
		(connect_pads
			(clearance 0)
		)
		(min_thickness 0.25)
		(keepout
			(tracks not_allowed)
			(vias allowed)
			(pads allowed)
			(copperpour not_allowed)
			(footprints allowed)
		)
		(placement
			(enabled no)
			(sheetname "")
		)
		(fill
			(thermal_gap 0.5)
			(thermal_bridge_width 0.5)
			(island_removal_mode 0)
		)
		(polygon
			(pts
				(arc
					(start 92.464382 -389.634476)
					(mid 92.574353 -389.73553)
					(end 92.719144 -389.772144)
				)
				(arc
					(start 92.719144 -389.772144)
					(mid 92.93467 -389.68287)
					(end 93.023944 -389.467344)
				)
				(arc
					(start 93.023944 -389.467344)
					(mid 93.013607 -389.388605)
					(end 92.983304 -389.315198)
				)
				(arc
					(start 92.590874 -388.636256)
					(mid 92.478477 -388.514639)
					(end 92.319094 -388.469632)
				)
				(arc
					(start 92.319094 -388.469632)
					(mid 92.103568 -388.558906)
					(end 92.014294 -388.774432)
				)
				(arc
					(start 92.014294 -388.774432)
					(mid 92.023872 -388.850494)
					(end 92.05214 -388.921752)
				)
				(xy 92.449396 -389.609076) (xy 92.461588 -389.630412) (xy 92.464128 -389.63473)
			)
		)
	)
	(zone
		(layers "F.Cu" "B.Cu" "In1.Cu" "In2.Cu" "In3.Cu" "In4.Cu" "In5.Cu" "In6.Cu"
			"In7.Cu" "In8.Cu" "In9.Cu" "In10.Cu" "In11.Cu" "In12.Cu" "In13.Cu" "In14.Cu"
			"In15.Cu" "In16.Cu"
		)
		(hatch none 0.5)
		(connect_pads
			(clearance 0)
		)
		(min_thickness 0.25)
		(keepout
			(tracks not_allowed)
			(vias allowed)
			(pads allowed)
			(copperpour not_allowed)
			(footprints allowed)
		)
		(placement
			(enabled no)
			(sheetname "")
		)
		(fill
			(thermal_gap 0.5)
			(thermal_bridge_width 0.5)
			(island_removal_mode 0)
		)
		(polygon
			(pts
				(arc
					(start 43.015154 -371.11813)
					(mid 42.634154 -371.49913)
					(end 43.015154 -371.88013)
				)
				(arc
					(start 43.878754 -371.88013)
					(mid 44.259754 -371.49913)
					(end 43.878754 -371.11813)
				)
			)
		)
	)
	(zone
		(layers "F.Cu" "B.Cu" "In1.Cu" "In2.Cu" "In3.Cu" "In4.Cu" "In5.Cu" "In6.Cu"
			"In7.Cu" "In8.Cu" "In9.Cu" "In10.Cu" "In11.Cu" "In12.Cu" "In13.Cu" "In14.Cu"
			"In15.Cu" "In16.Cu"
		)
		(hatch none 0.5)
		(connect_pads
			(clearance 0)
		)
		(min_thickness 0.25)
		(keepout
			(tracks not_allowed)
			(vias allowed)
			(pads allowed)
			(copperpour not_allowed)
			(footprints allowed)
		)
		(placement
			(enabled no)
			(sheetname "")
		)
		(fill
			(thermal_gap 0.5)
			(thermal_bridge_width 0.5)
			(island_removal_mode 0)
		)
		(polygon
			(pts
				(arc
					(start 319.110106 -420.571168)
					(mid 318.729106 -420.952168)
					(end 319.110106 -421.333168)
				)
				(arc
					(start 319.973706 -421.333168)
					(mid 320.354706 -420.952168)
					(end 319.973706 -420.571168)
				)
			)
		)
	)
	(zone
		(layers "F.Cu" "B.Cu" "In1.Cu" "In2.Cu" "In3.Cu" "In4.Cu" "In5.Cu" "In6.Cu"
			"In7.Cu" "In8.Cu" "In9.Cu" "In10.Cu" "In11.Cu" "In12.Cu" "In13.Cu" "In14.Cu"
			"In15.Cu" "In16.Cu"
		)
		(hatch none 0.5)
		(connect_pads
			(clearance 0)
		)
		(min_thickness 0.25)
		(keepout
			(tracks not_allowed)
			(vias allowed)
			(pads allowed)
			(copperpour not_allowed)
			(footprints allowed)
		)
		(placement
			(enabled no)
			(sheetname "")
		)
		(fill
			(thermal_gap 0.5)
			(thermal_bridge_width 0.5)
			(island_removal_mode 0)
		)
		(polygon
			(pts
				(arc
					(start 377.020582 -412.46552)
					(mid 376.639582 -412.84652)
					(end 377.020582 -413.22752)
				)
				(arc
					(start 377.884182 -413.22752)
					(mid 378.265182 -412.84652)
					(end 377.884182 -412.46552)
				)
			)
		)
	)
	(zone
		(layers "F.Cu" "B.Cu" "In1.Cu" "In2.Cu" "In3.Cu" "In4.Cu" "In5.Cu" "In6.Cu"
			"In7.Cu" "In8.Cu" "In9.Cu" "In10.Cu" "In11.Cu" "In12.Cu" "In13.Cu" "In14.Cu"
			"In15.Cu" "In16.Cu"
		)
		(hatch none 0.5)
		(connect_pads
			(clearance 0)
		)
		(min_thickness 0.25)
		(keepout
			(tracks not_allowed)
			(vias allowed)
			(pads allowed)
			(copperpour not_allowed)
			(footprints allowed)
		)
		(placement
			(enabled no)
			(sheetname "")
		)
		(fill
			(thermal_gap 0.5)
			(thermal_bridge_width 0.5)
			(island_removal_mode 0)
		)
		(polygon
			(pts
				(arc
					(start 348.210886 -415.00552)
					(mid 347.829886 -415.38652)
					(end 348.210886 -415.76752)
				)
				(arc
					(start 349.074486 -415.76752)
					(mid 349.455486 -415.38652)
					(end 349.074486 -415.00552)
				)
			)
		)
	)
	(zone
		(layers "F.Cu" "B.Cu" "In1.Cu" "In2.Cu" "In3.Cu" "In4.Cu" "In5.Cu" "In6.Cu"
			"In7.Cu" "In8.Cu" "In9.Cu" "In10.Cu" "In11.Cu" "In12.Cu" "In13.Cu" "In14.Cu"
			"In15.Cu" "In16.Cu"
		)
		(hatch none 0.5)
		(connect_pads
			(clearance 0)
		)
		(min_thickness 0.25)
		(keepout
			(tracks not_allowed)
			(vias allowed)
			(pads allowed)
			(copperpour not_allowed)
			(footprints allowed)
		)
		(placement
			(enabled no)
			(sheetname "")
		)
		(fill
			(thermal_gap 0.5)
			(thermal_bridge_width 0.5)
			(island_removal_mode 0)
		)
		(polygon
			(pts
				(arc
					(start 75.363324 -404.08352)
					(mid 74.982324 -404.46452)
					(end 75.363324 -404.84552)
				)
				(arc
					(start 76.226924 -404.84552)
					(mid 76.607924 -404.46452)
					(end 76.226924 -404.08352)
				)
			)
		)
	)
	(zone
		(layers "F.Cu" "B.Cu" "In1.Cu" "In2.Cu" "In3.Cu" "In4.Cu" "In5.Cu" "In6.Cu"
			"In7.Cu" "In8.Cu" "In9.Cu" "In10.Cu" "In11.Cu" "In12.Cu" "In13.Cu" "In14.Cu"
			"In15.Cu" "In16.Cu"
		)
		(hatch none 0.5)
		(connect_pads
			(clearance 0)
		)
		(min_thickness 0.25)
		(keepout
			(tracks not_allowed)
			(vias allowed)
			(pads allowed)
			(copperpour not_allowed)
			(footprints allowed)
		)
		(placement
			(enabled no)
			(sheetname "")
		)
		(fill
			(thermal_gap 0.5)
			(thermal_bridge_width 0.5)
			(island_removal_mode 0)
		)
		(polygon
			(pts
				(arc
					(start 325.236586 -412.46552)
					(mid 324.855586 -412.84652)
					(end 325.236586 -413.22752)
				)
				(arc
					(start 326.100186 -413.22752)
					(mid 326.481186 -412.84652)
					(end 326.100186 -412.46552)
				)
			)
		)
	)
	(zone
		(layers "F.Cu" "B.Cu" "In1.Cu" "In2.Cu" "In3.Cu" "In4.Cu" "In5.Cu" "In6.Cu"
			"In7.Cu" "In8.Cu" "In9.Cu" "In10.Cu" "In11.Cu" "In12.Cu" "In13.Cu" "In14.Cu"
			"In15.Cu" "In16.Cu"
		)
		(hatch none 0.5)
		(connect_pads
			(clearance 0)
		)
		(min_thickness 0.25)
		(keepout
			(tracks not_allowed)
			(vias allowed)
			(pads allowed)
			(copperpour not_allowed)
			(footprints allowed)
		)
		(placement
			(enabled no)
			(sheetname "")
		)
		(fill
			(thermal_gap 0.5)
			(thermal_bridge_width 0.5)
			(island_removal_mode 0)
		)
		(polygon
			(pts
				(arc
					(start 105.272078 -405.297132)
					(mid 105.272078 -404.758144)
					(end 104.73309 -404.758144)
				)
				(arc
					(start 104.122474 -405.369014)
					(mid 104.122601 -405.907621)
					(end 104.661208 -405.907748)
				)
			)
		)
	)
	(zone
		(layers "F.Cu" "B.Cu" "In1.Cu" "In2.Cu" "In3.Cu" "In4.Cu" "In5.Cu" "In6.Cu"
			"In7.Cu" "In8.Cu" "In9.Cu" "In10.Cu" "In11.Cu" "In12.Cu" "In13.Cu" "In14.Cu"
			"In15.Cu" "In16.Cu"
		)
		(hatch none 0.5)
		(connect_pads
			(clearance 0)
		)
		(min_thickness 0.25)
		(keepout
			(tracks not_allowed)
			(vias allowed)
			(pads allowed)
			(copperpour not_allowed)
			(footprints allowed)
		)
		(placement
			(enabled no)
			(sheetname "")
		)
		(fill
			(thermal_gap 0.5)
			(thermal_bridge_width 0.5)
			(island_removal_mode 0)
		)
		(polygon
			(pts
				(arc
					(start 62.336426 -389.634476)
					(mid 62.446397 -389.73553)
					(end 62.591188 -389.772144)
				)
				(arc
					(start 62.591188 -389.772144)
					(mid 62.806714 -389.68287)
					(end 62.895988 -389.467344)
				)
				(arc
					(start 62.895988 -389.467344)
					(mid 62.885651 -389.388605)
					(end 62.855348 -389.315198)
				)
				(arc
					(start 62.462918 -388.636256)
					(mid 62.350521 -388.514639)
					(end 62.191138 -388.469632)
				)
				(arc
					(start 62.191138 -388.469632)
					(mid 61.975612 -388.558906)
					(end 61.886338 -388.774432)
				)
				(arc
					(start 61.886338 -388.774432)
					(mid 61.895916 -388.850494)
					(end 61.924184 -388.921752)
				)
				(xy 62.32144 -389.609076) (xy 62.333632 -389.630412) (xy 62.336172 -389.63473)
			)
		)
	)
	(zone
		(layers "F.Cu" "B.Cu" "In1.Cu" "In2.Cu" "In3.Cu" "In4.Cu" "In5.Cu" "In6.Cu"
			"In7.Cu" "In8.Cu" "In9.Cu" "In10.Cu" "In11.Cu" "In12.Cu" "In13.Cu" "In14.Cu"
			"In15.Cu" "In16.Cu"
		)
		(hatch none 0.5)
		(connect_pads
			(clearance 0)
		)
		(min_thickness 0.25)
		(keepout
			(tracks not_allowed)
			(vias allowed)
			(pads allowed)
			(copperpour not_allowed)
			(footprints allowed)
		)
		(placement
			(enabled no)
			(sheetname "")
		)
		(fill yes
			(thermal_gap 0.5)
			(thermal_bridge_width 0.5)
			(island_removal_mode 0)
		)
		(polygon
			(pts
				(arc
					(start 413.164274 -394.552424)
					(mid 413.274245 -394.653478)
					(end 413.419036 -394.690092)
				)
				(arc
					(start 413.419036 -394.690092)
					(mid 413.634562 -394.600818)
					(end 413.723836 -394.385292)
				)
				(arc
					(start 413.723836 -394.385292)
					(mid 413.713499 -394.306553)
					(end 413.683196 -394.233146)
				)
				(arc
					(start 413.290766 -393.554204)
					(mid 413.178369 -393.432587)
					(end 413.018986 -393.38758)
				)
				(arc
					(start 413.018986 -393.38758)
					(mid 412.80346 -393.476854)
					(end 412.714186 -393.69238)
				)
				(arc
					(start 412.714186 -393.69238)
					(mid 412.723764 -393.768442)
					(end 412.752032 -393.8397)
				)
				(xy 413.149288 -394.527024) (xy 413.16148 -394.54836) (xy 413.16402 -394.552678)
			)
		)
	)
	(zone
		(layers "F.Cu" "B.Cu" "In1.Cu" "In2.Cu" "In3.Cu" "In4.Cu" "In5.Cu" "In6.Cu"
			"In7.Cu" "In8.Cu" "In9.Cu" "In10.Cu" "In11.Cu" "In12.Cu" "In13.Cu" "In14.Cu"
			"In15.Cu" "In16.Cu"
		)
		(hatch none 0.5)
		(connect_pads
			(clearance 0)
		)
		(min_thickness 0.25)
		(keepout
			(tracks not_allowed)
			(vias allowed)
			(pads allowed)
			(copperpour not_allowed)
			(footprints allowed)
		)
		(placement
			(enabled no)
			(sheetname "")
		)
		(fill
			(thermal_gap 0.5)
			(thermal_bridge_width 0.5)
			(island_removal_mode 0)
		)
		(polygon
			(pts
				(arc
					(start 61.734954 -373.58193)
					(mid 61.353954 -373.96293)
					(end 61.734954 -374.34393)
				)
				(arc
					(start 62.598554 -374.34393)
					(mid 62.979554 -373.96293)
					(end 62.598554 -373.58193)
				)
			)
		)
	)
	(zone
		(layers "F.Cu" "B.Cu" "In1.Cu" "In2.Cu" "In3.Cu" "In4.Cu" "In5.Cu" "In6.Cu"
			"In7.Cu" "In8.Cu" "In9.Cu" "In10.Cu" "In11.Cu" "In12.Cu" "In13.Cu" "In14.Cu"
			"In15.Cu" "In16.Cu"
		)
		(hatch none 0.5)
		(connect_pads
			(clearance 0)
		)
		(min_thickness 0.25)
		(keepout
			(tracks not_allowed)
			(vias allowed)
			(pads allowed)
			(copperpour not_allowed)
			(footprints allowed)
		)
		(placement
			(enabled no)
			(sheetname "")
		)
		(fill
			(thermal_gap 0.5)
			(thermal_bridge_width 0.5)
			(island_removal_mode 0)
		)
		(polygon
			(pts
				(arc
					(start 51.94046 -4.582414)
					(mid 51.55946 -4.963414)
					(end 51.94046 -5.344414)
				)
				(arc
					(start 52.80406 -5.344414)
					(mid 53.18506 -4.963414)
					(end 52.80406 -4.582414)
				)
			)
		)
	)
	(zone
		(layers "F.Cu" "B.Cu" "In1.Cu" "In2.Cu" "In3.Cu" "In4.Cu" "In5.Cu" "In6.Cu"
			"In7.Cu" "In8.Cu" "In9.Cu" "In10.Cu" "In11.Cu" "In12.Cu" "In13.Cu" "In14.Cu"
			"In15.Cu" "In16.Cu"
		)
		(hatch none 0.5)
		(connect_pads
			(clearance 0)
		)
		(min_thickness 0.25)
		(keepout
			(tracks not_allowed)
			(vias allowed)
			(pads allowed)
			(copperpour not_allowed)
			(footprints allowed)
		)
		(placement
			(enabled no)
			(sheetname "")
		)
		(fill
			(thermal_gap 0.5)
			(thermal_bridge_width 0.5)
			(island_removal_mode 0)
		)
		(polygon
			(pts
				(arc
					(start 162.374326 -409.649168)
					(mid 161.993326 -410.030168)
					(end 162.374326 -410.411168)
				)
				(arc
					(start 163.237926 -410.411168)
					(mid 163.618926 -410.030168)
					(end 163.237926 -409.649168)
				)
			)
		)
	)
	(zone
		(layers "F.Cu" "B.Cu" "In1.Cu" "In2.Cu" "In3.Cu" "In4.Cu" "In5.Cu" "In6.Cu"
			"In7.Cu" "In8.Cu" "In9.Cu" "In10.Cu" "In11.Cu" "In12.Cu" "In13.Cu" "In14.Cu"
			"In15.Cu" "In16.Cu"
		)
		(hatch none 0.5)
		(connect_pads
			(clearance 0)
		)
		(min_thickness 0.25)
		(keepout
			(tracks not_allowed)
			(vias allowed)
			(pads allowed)
			(copperpour not_allowed)
			(footprints allowed)
		)
		(placement
			(enabled no)
			(sheetname "")
		)
		(fill
			(thermal_gap 0.5)
			(thermal_bridge_width 0.5)
			(island_removal_mode 0)
		)
		(polygon
			(pts
				(arc
					(start 334.426306 -420.571168)
					(mid 334.045306 -420.952168)
					(end 334.426306 -421.333168)
				)
				(arc
					(start 335.289906 -421.333168)
					(mid 335.670906 -420.952168)
					(end 335.289906 -420.571168)
				)
			)
		)
	)
	(zone
		(layers "F.Cu" "B.Cu" "In1.Cu" "In2.Cu" "In3.Cu" "In4.Cu" "In5.Cu" "In6.Cu"
			"In7.Cu" "In8.Cu" "In9.Cu" "In10.Cu" "In11.Cu" "In12.Cu" "In13.Cu" "In14.Cu"
			"In15.Cu" "In16.Cu"
		)
		(hatch none 0.5)
		(connect_pads
			(clearance 0)
		)
		(min_thickness 0.25)
		(keepout
			(tracks not_allowed)
			(vias allowed)
			(pads allowed)
			(copperpour not_allowed)
			(footprints allowed)
		)
		(placement
			(enabled no)
			(sheetname "")
		)
		(fill
			(thermal_gap 0.5)
			(thermal_bridge_width 0.5)
			(island_removal_mode 0)
		)
		(polygon
			(pts
				(arc
					(start 31.62046 -4.582414)
					(mid 31.23946 -4.963414)
					(end 31.62046 -5.344414)
				)
				(arc
					(start 32.48406 -5.344414)
					(mid 32.86506 -4.963414)
					(end 32.48406 -4.582414)
				)
			)
		)
	)
	(zone
		(layers "F.Cu" "B.Cu" "In1.Cu" "In2.Cu" "In3.Cu" "In4.Cu" "In5.Cu" "In6.Cu"
			"In7.Cu" "In8.Cu" "In9.Cu" "In10.Cu" "In11.Cu" "In12.Cu" "In13.Cu" "In14.Cu"
			"In15.Cu" "In16.Cu"
		)
		(hatch none 0.5)
		(connect_pads
			(clearance 0)
		)
		(min_thickness 0.25)
		(keepout
			(tracks not_allowed)
			(vias allowed)
			(pads allowed)
			(copperpour not_allowed)
			(footprints allowed)
		)
		(placement
			(enabled no)
			(sheetname "")
		)
		(fill
			(thermal_gap 0.5)
			(thermal_bridge_width 0.5)
			(island_removal_mode 0)
		)
		(polygon
			(pts
				(arc
					(start 408.625294 -400.811238)
					(mid 408.244294 -400.430238)
					(end 407.863294 -400.811238)
				)
				(arc
					(start 407.863294 -401.674838)
					(mid 408.244294 -402.055838)
					(end 408.625294 -401.674838)
				)
			)
		)
	)
	(zone
		(layers "F.Cu" "B.Cu" "In1.Cu" "In2.Cu" "In3.Cu" "In4.Cu" "In5.Cu" "In6.Cu"
			"In7.Cu" "In8.Cu" "In9.Cu" "In10.Cu" "In11.Cu" "In12.Cu" "In13.Cu" "In14.Cu"
			"In15.Cu" "In16.Cu"
		)
		(hatch none 0.5)
		(connect_pads
			(clearance 0)
		)
		(min_thickness 0.25)
		(keepout
			(tracks not_allowed)
			(vias allowed)
			(pads allowed)
			(copperpour not_allowed)
			(footprints allowed)
		)
		(placement
			(enabled no)
			(sheetname "")
		)
		(fill
			(thermal_gap 0.5)
			(thermal_bridge_width 0.5)
			(island_removal_mode 0)
		)
		(polygon
			(pts
				(arc
					(start 342.084406 -415.00552)
					(mid 341.703406 -415.38652)
					(end 342.084406 -415.76752)
				)
				(arc
					(start 342.948006 -415.76752)
					(mid 343.329006 -415.38652)
					(end 342.948006 -415.00552)
				)
			)
		)
	)
	(zone
		(layers "F.Cu" "B.Cu" "In1.Cu" "In2.Cu" "In3.Cu" "In4.Cu" "In5.Cu" "In6.Cu"
			"In7.Cu" "In8.Cu" "In9.Cu" "In10.Cu" "In11.Cu" "In12.Cu" "In13.Cu" "In14.Cu"
			"In15.Cu" "In16.Cu"
		)
		(hatch none 0.5)
		(connect_pads
			(clearance 0)
		)
		(min_thickness 0.25)
		(keepout
			(tracks not_allowed)
			(vias allowed)
			(pads allowed)
			(copperpour not_allowed)
			(footprints allowed)
		)
		(placement
			(enabled no)
			(sheetname "")
		)
		(fill
			(thermal_gap 0.5)
			(thermal_bridge_width 0.5)
			(island_removal_mode 0)
		)
		(polygon
			(pts
				(arc
					(start 346.858844 -377.03633)
					(mid 346.477844 -377.41733)
					(end 346.858844 -377.79833)
				)
				(arc
					(start 347.722444 -377.79833)
					(mid 348.103444 -377.41733)
					(end 347.722444 -377.03633)
				)
			)
		)
	)
	(zone
		(layers "F.Cu" "B.Cu" "In1.Cu" "In2.Cu" "In3.Cu" "In4.Cu" "In5.Cu" "In6.Cu"
			"In7.Cu" "In8.Cu" "In9.Cu" "In10.Cu" "In11.Cu" "In12.Cu" "In13.Cu" "In14.Cu"
			"In15.Cu" "In16.Cu"
		)
		(hatch none 0.5)
		(connect_pads
			(clearance 0)
		)
		(min_thickness 0.25)
		(keepout
			(tracks not_allowed)
			(vias allowed)
			(pads allowed)
			(copperpour not_allowed)
			(footprints allowed)
		)
		(placement
			(enabled no)
			(sheetname "")
		)
		(fill
			(thermal_gap 0.5)
			(thermal_bridge_width 0.5)
			(island_removal_mode 0)
		)
		(polygon
			(pts
				(arc
					(start 86.464394 -389.634476)
					(mid 86.574365 -389.73553)
					(end 86.719156 -389.772144)
				)
				(arc
					(start 86.719156 -389.772144)
					(mid 86.934682 -389.68287)
					(end 87.023956 -389.467344)
				)
				(arc
					(start 87.023956 -389.467344)
					(mid 87.013619 -389.388605)
					(end 86.983316 -389.315198)
				)
				(arc
					(start 86.590886 -388.636256)
					(mid 86.478489 -388.514639)
					(end 86.319106 -388.469632)
				)
				(arc
					(start 86.319106 -388.469632)
					(mid 86.10358 -388.558906)
					(end 86.014306 -388.774432)
				)
				(arc
					(start 86.014306 -388.774432)
					(mid 86.023884 -388.850494)
					(end 86.052152 -388.921752)
				)
				(xy 86.449408 -389.609076) (xy 86.4616 -389.630412) (xy 86.46414 -389.63473)
			)
		)
	)
	(zone
		(layers "F.Cu" "B.Cu" "In1.Cu" "In2.Cu" "In3.Cu" "In4.Cu" "In5.Cu" "In6.Cu"
			"In7.Cu" "In8.Cu" "In9.Cu" "In10.Cu" "In11.Cu" "In12.Cu" "In13.Cu" "In14.Cu"
			"In15.Cu" "In16.Cu"
		)
		(hatch none 0.5)
		(connect_pads
			(clearance 0)
		)
		(min_thickness 0.25)
		(keepout
			(tracks not_allowed)
			(vias allowed)
			(pads allowed)
			(copperpour not_allowed)
			(footprints allowed)
		)
		(placement
			(enabled no)
			(sheetname "")
		)
		(fill
			(thermal_gap 0.5)
			(thermal_bridge_width 0.5)
			(island_removal_mode 0)
		)
		(polygon
			(pts
				(arc
					(start 305.136296 -398.016476)
					(mid 305.246267 -398.11753)
					(end 305.391058 -398.154144)
				)
				(arc
					(start 305.391058 -398.154144)
					(mid 305.606584 -398.06487)
					(end 305.695858 -397.849344)
				)
				(arc
					(start 305.695858 -397.849344)
					(mid 305.685521 -397.770605)
					(end 305.655218 -397.697198)
				)
				(arc
					(start 305.262788 -397.018256)
					(mid 305.150391 -396.896639)
					(end 304.991008 -396.851632)
				)
				(arc
					(start 304.991008 -396.851632)
					(mid 304.775482 -396.940906)
					(end 304.686208 -397.156432)
				)
				(arc
					(start 304.686208 -397.156432)
					(mid 304.695786 -397.232494)
					(end 304.724054 -397.303752)
				)
				(xy 305.12131 -397.991076) (xy 305.133502 -398.012412) (xy 305.136042 -398.01673)
			)
		)
	)
	(zone
		(layers "F.Cu" "B.Cu" "In1.Cu" "In2.Cu" "In3.Cu" "In4.Cu" "In5.Cu" "In6.Cu"
			"In7.Cu" "In8.Cu" "In9.Cu" "In10.Cu" "In11.Cu" "In12.Cu" "In13.Cu" "In14.Cu"
			"In15.Cu" "In16.Cu"
		)
		(hatch none 0.5)
		(connect_pads
			(clearance 0)
		)
		(min_thickness 0.25)
		(keepout
			(tracks not_allowed)
			(vias allowed)
			(pads allowed)
			(copperpour not_allowed)
			(footprints allowed)
		)
		(placement
			(enabled no)
			(sheetname "")
		)
		(fill
			(thermal_gap 0.5)
			(thermal_bridge_width 0.5)
			(island_removal_mode 0)
		)
		(polygon
			(pts
				(arc
					(start 71.658734 -379.496828)
					(mid 71.277734 -379.115828)
					(end 70.896734 -379.496828)
				)
				(arc
					(start 70.896734 -380.360428)
					(mid 71.277734 -380.741428)
					(end 71.658734 -380.360428)
				)
			)
		)
	)
	(zone
		(layers "F.Cu" "B.Cu" "In1.Cu" "In2.Cu" "In3.Cu" "In4.Cu" "In5.Cu" "In6.Cu"
			"In7.Cu" "In8.Cu" "In9.Cu" "In10.Cu" "In11.Cu" "In12.Cu" "In13.Cu" "In14.Cu"
			"In15.Cu" "In16.Cu"
		)
		(hatch none 0.5)
		(connect_pads
			(clearance 0)
		)
		(min_thickness 0.25)
		(keepout
			(tracks not_allowed)
			(vias allowed)
			(pads allowed)
			(copperpour not_allowed)
			(footprints allowed)
		)
		(placement
			(enabled no)
			(sheetname "")
		)
		(fill
			(thermal_gap 0.5)
			(thermal_bridge_width 0.5)
			(island_removal_mode 0)
		)
		(polygon
			(pts
				(arc
					(start 364.380272 -0.428244)
					(mid 364.812072 -0.860044)
					(end 365.243872 -0.428244)
				)
				(arc
					(start 365.243872 0.435356)
					(mid 364.812072 0.867156)
					(end 364.380272 0.435356)
				)
			)
		)
	)
	(zone
		(layers "F.Cu" "B.Cu" "In1.Cu" "In2.Cu" "In3.Cu" "In4.Cu" "In5.Cu" "In6.Cu"
			"In7.Cu" "In8.Cu" "In9.Cu" "In10.Cu" "In11.Cu" "In12.Cu" "In13.Cu" "In14.Cu"
			"In15.Cu" "In16.Cu"
		)
		(hatch none 0.5)
		(connect_pads
			(clearance 0)
		)
		(min_thickness 0.25)
		(keepout
			(tracks not_allowed)
			(vias allowed)
			(pads allowed)
			(copperpour not_allowed)
			(footprints allowed)
		)
		(placement
			(enabled no)
			(sheetname "")
		)
		(fill
			(thermal_gap 0.5)
			(thermal_bridge_width 0.5)
			(island_removal_mode 0)
		)
		(polygon
			(pts
				(arc
					(start 57.335674 -6.344158)
					(mid 56.954674 -6.725158)
					(end 57.335674 -7.106158)
				)
				(arc
					(start 58.199274 -7.106158)
					(mid 58.580274 -6.725158)
					(end 58.199274 -6.344158)
				)
			)
		)
	)
	(zone
		(layers "F.Cu" "B.Cu" "In1.Cu" "In2.Cu" "In3.Cu" "In4.Cu" "In5.Cu" "In6.Cu"
			"In7.Cu" "In8.Cu" "In9.Cu" "In10.Cu" "In11.Cu" "In12.Cu" "In13.Cu" "In14.Cu"
			"In15.Cu" "In16.Cu"
		)
		(hatch none 0.5)
		(connect_pads
			(clearance 0)
		)
		(min_thickness 0.25)
		(keepout
			(tracks not_allowed)
			(vias allowed)
			(pads allowed)
			(copperpour not_allowed)
			(footprints allowed)
		)
		(placement
			(enabled no)
			(sheetname "")
		)
		(fill
			(thermal_gap 0.5)
			(thermal_bridge_width 0.5)
			(island_removal_mode 0)
		)
		(polygon
			(pts
				(arc
					(start 52.19573 -18.75536)
					(mid 51.81473 -19.13636)
					(end 52.19573 -19.51736)
				)
				(arc
					(start 53.05933 -19.51736)
					(mid 53.44033 -19.13636)
					(end 53.05933 -18.75536)
				)
			)
		)
	)
	(zone
		(layers "F.Cu" "B.Cu" "In1.Cu" "In2.Cu" "In3.Cu" "In4.Cu" "In5.Cu" "In6.Cu"
			"In7.Cu" "In8.Cu" "In9.Cu" "In10.Cu" "In11.Cu" "In12.Cu" "In13.Cu" "In14.Cu"
			"In15.Cu" "In16.Cu"
		)
		(hatch none 0.5)
		(connect_pads
			(clearance 0)
		)
		(min_thickness 0.25)
		(keepout
			(tracks not_allowed)
			(vias allowed)
			(pads allowed)
			(copperpour not_allowed)
			(footprints allowed)
		)
		(placement
			(enabled no)
			(sheetname "")
		)
		(fill
			(thermal_gap 0.5)
			(thermal_bridge_width 0.5)
			(island_removal_mode 0)
		)
		(polygon
			(pts
				(arc
					(start 393.868402 -418.031168)
					(mid 393.487402 -418.412168)
					(end 393.868402 -418.793168)
				)
				(arc
					(start 394.732002 -418.793168)
					(mid 395.113002 -418.412168)
					(end 394.732002 -418.031168)
				)
			)
		)
	)
	(zone
		(layers "F.Cu" "B.Cu" "In1.Cu" "In2.Cu" "In3.Cu" "In4.Cu" "In5.Cu" "In6.Cu"
			"In7.Cu" "In8.Cu" "In9.Cu" "In10.Cu" "In11.Cu" "In12.Cu" "In13.Cu" "In14.Cu"
			"In15.Cu" "In16.Cu"
		)
		(hatch none 0.5)
		(connect_pads
			(clearance 0)
		)
		(min_thickness 0.25)
		(keepout
			(tracks not_allowed)
			(vias allowed)
			(pads allowed)
			(copperpour not_allowed)
			(footprints allowed)
		)
		(placement
			(enabled no)
			(sheetname "")
		)
		(fill yes
			(thermal_gap 0.5)
			(thermal_bridge_width 0.5)
			(island_removal_mode 0)
		)
		(polygon
			(pts
				(arc
					(start 123.43638 -386.170424)
					(mid 123.546351 -386.271478)
					(end 123.691142 -386.308092)
				)
				(arc
					(start 123.691142 -386.308092)
					(mid 123.906668 -386.218818)
					(end 123.995942 -386.003292)
				)
				(arc
					(start 123.995942 -386.003292)
					(mid 123.985605 -385.924553)
					(end 123.955302 -385.851146)
				)
				(arc
					(start 123.562872 -385.172204)
					(mid 123.450475 -385.050587)
					(end 123.291092 -385.00558)
				)
				(arc
					(start 123.291092 -385.00558)
					(mid 123.075566 -385.094854)
					(end 122.986292 -385.31038)
				)
				(arc
					(start 122.986292 -385.31038)
					(mid 122.99587 -385.386442)
					(end 123.024138 -385.4577)
				)
				(xy 123.421394 -386.145024) (xy 123.433586 -386.16636) (xy 123.436126 -386.170678)
			)
		)
	)
	(zone
		(layers "F.Cu" "B.Cu" "In1.Cu" "In2.Cu" "In3.Cu" "In4.Cu" "In5.Cu" "In6.Cu"
			"In7.Cu" "In8.Cu" "In9.Cu" "In10.Cu" "In11.Cu" "In12.Cu" "In13.Cu" "In14.Cu"
			"In15.Cu" "In16.Cu"
		)
		(hatch none 0.5)
		(connect_pads
			(clearance 0)
		)
		(min_thickness 0.25)
		(keepout
			(tracks not_allowed)
			(vias allowed)
			(pads allowed)
			(copperpour not_allowed)
			(footprints allowed)
		)
		(placement
			(enabled no)
			(sheetname "")
		)
		(fill
			(thermal_gap 0.5)
			(thermal_bridge_width 0.5)
			(island_removal_mode 0)
		)
		(polygon
			(pts
				(arc
					(start 93.664278 -389.634476)
					(mid 93.774249 -389.73553)
					(end 93.91904 -389.772144)
				)
				(arc
					(start 93.91904 -389.772144)
					(mid 94.134566 -389.68287)
					(end 94.22384 -389.467344)
				)
				(arc
					(start 94.22384 -389.467344)
					(mid 94.213503 -389.388605)
					(end 94.1832 -389.315198)
				)
				(arc
					(start 93.79077 -388.636256)
					(mid 93.678373 -388.514639)
					(end 93.51899 -388.469632)
				)
				(arc
					(start 93.51899 -388.469632)
					(mid 93.303464 -388.558906)
					(end 93.21419 -388.774432)
				)
				(arc
					(start 93.21419 -388.774432)
					(mid 93.223768 -388.850494)
					(end 93.252036 -388.921752)
				)
				(xy 93.649292 -389.609076) (xy 93.661484 -389.630412) (xy 93.664024 -389.63473)
			)
		)
	)
	(zone
		(layers "F.Cu" "B.Cu" "In1.Cu" "In2.Cu" "In3.Cu" "In4.Cu" "In5.Cu" "In6.Cu"
			"In7.Cu" "In8.Cu" "In9.Cu" "In10.Cu" "In11.Cu" "In12.Cu" "In13.Cu" "In14.Cu"
			"In15.Cu" "In16.Cu"
		)
		(hatch none 0.5)
		(connect_pads
			(clearance 0)
		)
		(min_thickness 0.25)
		(keepout
			(tracks not_allowed)
			(vias allowed)
			(pads allowed)
			(copperpour not_allowed)
			(footprints allowed)
		)
		(placement
			(enabled no)
			(sheetname "")
		)
		(fill
			(thermal_gap 0.5)
			(thermal_bridge_width 0.5)
			(island_removal_mode 0)
		)
		(polygon
			(pts
				(arc
					(start 407.652982 -412.46552)
					(mid 407.271982 -412.84652)
					(end 407.652982 -413.22752)
				)
				(arc
					(start 408.516582 -413.22752)
					(mid 408.897582 -412.84652)
					(end 408.516582 -412.46552)
				)
			)
		)
	)
	(zone
		(layers "F.Cu" "B.Cu" "In1.Cu" "In2.Cu" "In3.Cu" "In4.Cu" "In5.Cu" "In6.Cu"
			"In7.Cu" "In8.Cu" "In9.Cu" "In10.Cu" "In11.Cu" "In12.Cu" "In13.Cu" "In14.Cu"
			"In15.Cu" "In16.Cu"
		)
		(hatch none 0.5)
		(connect_pads
			(clearance 0)
		)
		(min_thickness 0.25)
		(keepout
			(tracks not_allowed)
			(vias allowed)
			(pads allowed)
			(copperpour not_allowed)
			(footprints allowed)
		)
		(placement
			(enabled no)
			(sheetname "")
		)
		(fill
			(thermal_gap 0.5)
			(thermal_bridge_width 0.5)
			(island_removal_mode 0)
		)
		(polygon
			(pts
				(arc
					(start 403.058122 -418.031168)
					(mid 402.677122 -418.412168)
					(end 403.058122 -418.793168)
				)
				(arc
					(start 403.921722 -418.793168)
					(mid 404.302722 -418.412168)
					(end 403.921722 -418.031168)
				)
			)
		)
	)
	(zone
		(layers "F.Cu" "B.Cu" "In1.Cu" "In2.Cu" "In3.Cu" "In4.Cu" "In5.Cu" "In6.Cu"
			"In7.Cu" "In8.Cu" "In9.Cu" "In10.Cu" "In11.Cu" "In12.Cu" "In13.Cu" "In14.Cu"
			"In15.Cu" "In16.Cu"
		)
		(hatch none 0.5)
		(connect_pads
			(clearance 0)
		)
		(min_thickness 0.25)
		(keepout
			(tracks not_allowed)
			(vias allowed)
			(pads allowed)
			(copperpour not_allowed)
			(footprints allowed)
		)
		(placement
			(enabled no)
			(sheetname "")
		)
		(fill
			(thermal_gap 0.5)
			(thermal_bridge_width 0.5)
			(island_removal_mode 0)
		)
		(polygon
			(pts
				(arc
					(start 338.864194 -394.552424)
					(mid 338.974165 -394.653478)
					(end 339.118956 -394.690092)
				)
				(arc
					(start 339.118956 -394.690092)
					(mid 339.334482 -394.600818)
					(end 339.423756 -394.385292)
				)
				(arc
					(start 339.423756 -394.385292)
					(mid 339.413419 -394.306553)
					(end 339.383116 -394.233146)
				)
				(arc
					(start 338.990686 -393.554204)
					(mid 338.878289 -393.432587)
					(end 338.718906 -393.38758)
				)
				(arc
					(start 338.718906 -393.38758)
					(mid 338.50338 -393.476854)
					(end 338.414106 -393.69238)
				)
				(arc
					(start 338.414106 -393.69238)
					(mid 338.423684 -393.768442)
					(end 338.451952 -393.8397)
				)
				(xy 338.849208 -394.527024) (xy 338.8614 -394.54836) (xy 338.86394 -394.552678)
			)
		)
	)
	(zone
		(layers "F.Cu" "B.Cu" "In1.Cu" "In2.Cu" "In3.Cu" "In4.Cu" "In5.Cu" "In6.Cu"
			"In7.Cu" "In8.Cu" "In9.Cu" "In10.Cu" "In11.Cu" "In12.Cu" "In13.Cu" "In14.Cu"
			"In15.Cu" "In16.Cu"
		)
		(hatch none 0.5)
		(connect_pads
			(clearance 0)
		)
		(min_thickness 0.25)
		(keepout
			(tracks not_allowed)
			(vias allowed)
			(pads allowed)
			(copperpour not_allowed)
			(footprints allowed)
		)
		(placement
			(enabled no)
			(sheetname "")
		)
		(fill
			(thermal_gap 0.5)
			(thermal_bridge_width 0.5)
			(island_removal_mode 0)
		)
		(polygon
			(pts
				(arc
					(start 297.663616 -395.308074)
					(mid 297.282616 -394.927074)
					(end 296.901616 -395.308074)
				)
				(arc
					(start 296.901616 -396.171674)
					(mid 297.282616 -396.552674)
					(end 297.663616 -396.171674)
				)
			)
		)
	)
	(zone
		(layers "F.Cu" "B.Cu" "In1.Cu" "In2.Cu" "In3.Cu" "In4.Cu" "In5.Cu" "In6.Cu"
			"In7.Cu" "In8.Cu" "In9.Cu" "In10.Cu" "In11.Cu" "In12.Cu" "In13.Cu" "In14.Cu"
			"In15.Cu" "In16.Cu"
		)
		(hatch none 0.5)
		(connect_pads
			(clearance 0)
		)
		(min_thickness 0.25)
		(keepout
			(tracks not_allowed)
			(vias allowed)
			(pads allowed)
			(copperpour not_allowed)
			(footprints allowed)
		)
		(placement
			(enabled no)
			(sheetname "")
		)
		(fill yes
			(thermal_gap 0.5)
			(thermal_bridge_width 0.5)
			(island_removal_mode 0)
		)
		(polygon
			(pts
				(arc
					(start 58.736484 -386.170424)
					(mid 58.846455 -386.271478)
					(end 58.991246 -386.308092)
				)
				(arc
					(start 58.991246 -386.308092)
					(mid 59.206772 -386.218818)
					(end 59.296046 -386.003292)
				)
				(arc
					(start 59.296046 -386.003292)
					(mid 59.285709 -385.924553)
					(end 59.255406 -385.851146)
				)
				(arc
					(start 58.862976 -385.172204)
					(mid 58.750579 -385.050587)
					(end 58.591196 -385.00558)
				)
				(arc
					(start 58.591196 -385.00558)
					(mid 58.37567 -385.094854)
					(end 58.286396 -385.31038)
				)
				(arc
					(start 58.286396 -385.31038)
					(mid 58.295974 -385.386442)
					(end 58.324242 -385.4577)
				)
				(xy 58.721498 -386.145024) (xy 58.73369 -386.16636) (xy 58.73623 -386.170678)
			)
		)
	)
	(zone
		(layers "F.Cu" "B.Cu" "In1.Cu" "In2.Cu" "In3.Cu" "In4.Cu" "In5.Cu" "In6.Cu"
			"In7.Cu" "In8.Cu" "In9.Cu" "In10.Cu" "In11.Cu" "In12.Cu" "In13.Cu" "In14.Cu"
			"In15.Cu" "In16.Cu"
		)
		(hatch none 0.5)
		(connect_pads
			(clearance 0)
		)
		(min_thickness 0.25)
		(keepout
			(tracks not_allowed)
			(vias allowed)
			(pads allowed)
			(copperpour not_allowed)
			(footprints allowed)
		)
		(placement
			(enabled no)
			(sheetname "")
		)
		(fill
			(thermal_gap 0.5)
			(thermal_bridge_width 0.5)
			(island_removal_mode 0)
		)
		(polygon
			(pts
				(arc
					(start 81.92516 -392.429238)
					(mid 81.54416 -392.048238)
					(end 81.16316 -392.429238)
				)
				(arc
					(start 81.16316 -393.292838)
					(mid 81.54416 -393.673838)
					(end 81.92516 -393.292838)
				)
			)
		)
	)
	(zone
		(layers "F.Cu" "B.Cu" "In1.Cu" "In2.Cu" "In3.Cu" "In4.Cu" "In5.Cu" "In6.Cu"
			"In7.Cu" "In8.Cu" "In9.Cu" "In10.Cu" "In11.Cu" "In12.Cu" "In13.Cu" "In14.Cu"
			"In15.Cu" "In16.Cu"
		)
		(hatch none 0.5)
		(connect_pads
			(clearance 0)
		)
		(min_thickness 0.25)
		(keepout
			(tracks not_allowed)
			(vias allowed)
			(pads allowed)
			(copperpour not_allowed)
			(footprints allowed)
		)
		(placement
			(enabled no)
			(sheetname "")
		)
		(fill
			(thermal_gap 0.5)
			(thermal_bridge_width 0.5)
			(island_removal_mode 0)
		)
		(polygon
			(pts
				(arc
					(start 50.857404 -404.08352)
					(mid 50.476404 -404.46452)
					(end 50.857404 -404.84552)
				)
				(arc
					(start 51.721004 -404.84552)
					(mid 52.102004 -404.46452)
					(end 51.721004 -404.08352)
				)
			)
		)
	)
	(zone
		(layers "F.Cu" "B.Cu" "In1.Cu" "In2.Cu" "In3.Cu" "In4.Cu" "In5.Cu" "In6.Cu"
			"In7.Cu" "In8.Cu" "In9.Cu" "In10.Cu" "In11.Cu" "In12.Cu" "In13.Cu" "In14.Cu"
			"In15.Cu" "In16.Cu"
		)
		(hatch none 0.5)
		(connect_pads
			(clearance 0)
		)
		(min_thickness 0.25)
		(keepout
			(tracks not_allowed)
			(vias allowed)
			(pads allowed)
			(copperpour not_allowed)
			(footprints allowed)
		)
		(placement
			(enabled no)
			(sheetname "")
		)
		(fill yes
			(thermal_gap 0.5)
			(thermal_bridge_width 0.5)
			(island_removal_mode 0)
		)
		(polygon
			(pts
				(arc
					(start 82.864198 -386.170424)
					(mid 82.974169 -386.271478)
					(end 83.11896 -386.308092)
				)
				(arc
					(start 83.11896 -386.308092)
					(mid 83.334486 -386.218818)
					(end 83.42376 -386.003292)
				)
				(arc
					(start 83.42376 -386.003292)
					(mid 83.413423 -385.924553)
					(end 83.38312 -385.851146)
				)
				(arc
					(start 82.99069 -385.172204)
					(mid 82.878293 -385.050587)
					(end 82.71891 -385.00558)
				)
				(arc
					(start 82.71891 -385.00558)
					(mid 82.503384 -385.094854)
					(end 82.41411 -385.31038)
				)
				(arc
					(start 82.41411 -385.31038)
					(mid 82.423688 -385.386442)
					(end 82.451956 -385.4577)
				)
				(xy 82.849212 -386.145024) (xy 82.861404 -386.16636) (xy 82.863944 -386.170678)
			)
		)
	)
	(zone
		(layers "F.Cu" "B.Cu" "In1.Cu" "In2.Cu" "In3.Cu" "In4.Cu" "In5.Cu" "In6.Cu"
			"In7.Cu" "In8.Cu" "In9.Cu" "In10.Cu" "In11.Cu" "In12.Cu" "In13.Cu" "In14.Cu"
			"In15.Cu" "In16.Cu"
		)
		(hatch none 0.5)
		(connect_pads
			(clearance 0)
		)
		(min_thickness 0.25)
		(keepout
			(tracks not_allowed)
			(vias allowed)
			(pads allowed)
			(copperpour not_allowed)
			(footprints allowed)
		)
		(placement
			(enabled no)
			(sheetname "")
		)
		(fill yes
			(thermal_gap 0.5)
			(thermal_bridge_width 0.5)
			(island_removal_mode 0)
		)
		(polygon
			(pts
				(arc
					(start 386.636514 -394.552424)
					(mid 386.746485 -394.653478)
					(end 386.891276 -394.690092)
				)
				(arc
					(start 386.891276 -394.690092)
					(mid 387.106802 -394.600818)
					(end 387.196076 -394.385292)
				)
				(arc
					(start 387.196076 -394.385292)
					(mid 387.185739 -394.306553)
					(end 387.155436 -394.233146)
				)
				(arc
					(start 386.763006 -393.554204)
					(mid 386.650609 -393.432587)
					(end 386.491226 -393.38758)
				)
				(arc
					(start 386.491226 -393.38758)
					(mid 386.2757 -393.476854)
					(end 386.186426 -393.69238)
				)
				(arc
					(start 386.186426 -393.69238)
					(mid 386.196004 -393.768442)
					(end 386.224272 -393.8397)
				)
				(xy 386.621528 -394.527024) (xy 386.63372 -394.54836) (xy 386.63626 -394.552678)
			)
		)
	)
	(zone
		(layers "F.Cu" "B.Cu" "In1.Cu" "In2.Cu" "In3.Cu" "In4.Cu" "In5.Cu" "In6.Cu"
			"In7.Cu" "In8.Cu" "In9.Cu" "In10.Cu" "In11.Cu" "In12.Cu" "In13.Cu" "In14.Cu"
			"In15.Cu" "In16.Cu"
		)
		(hatch none 0.5)
		(connect_pads
			(clearance 0)
		)
		(min_thickness 0.25)
		(keepout
			(tracks not_allowed)
			(vias allowed)
			(pads allowed)
			(copperpour not_allowed)
			(footprints allowed)
		)
		(placement
			(enabled no)
			(sheetname "")
		)
		(fill
			(thermal_gap 0.5)
			(thermal_bridge_width 0.5)
			(island_removal_mode 0)
		)
		(polygon
			(pts
				(arc
					(start 314.515246 -418.031168)
					(mid 314.134246 -418.412168)
					(end 314.515246 -418.793168)
				)
				(arc
					(start 315.378846 -418.793168)
					(mid 315.759846 -418.412168)
					(end 315.378846 -418.031168)
				)
			)
		)
	)
	(zone
		(layers "F.Cu" "B.Cu" "In1.Cu" "In2.Cu" "In3.Cu" "In4.Cu" "In5.Cu" "In6.Cu"
			"In7.Cu" "In8.Cu" "In9.Cu" "In10.Cu" "In11.Cu" "In12.Cu" "In13.Cu" "In14.Cu"
			"In15.Cu" "In16.Cu"
		)
		(hatch none 0.5)
		(connect_pads
			(clearance 0)
		)
		(min_thickness 0.25)
		(keepout
			(tracks not_allowed)
			(vias allowed)
			(pads allowed)
			(copperpour not_allowed)
			(footprints allowed)
		)
		(placement
			(enabled no)
			(sheetname "")
		)
		(fill
			(thermal_gap 0.5)
			(thermal_bridge_width 0.5)
			(island_removal_mode 0)
		)
		(polygon
			(pts
				(arc
					(start 91.264232 -389.634476)
					(mid 91.374203 -389.73553)
					(end 91.518994 -389.772144)
				)
				(arc
					(start 91.518994 -389.772144)
					(mid 91.73452 -389.68287)
					(end 91.823794 -389.467344)
				)
				(arc
					(start 91.823794 -389.467344)
					(mid 91.813457 -389.388605)
					(end 91.783154 -389.315198)
				)
				(arc
					(start 91.390724 -388.636256)
					(mid 91.278327 -388.514639)
					(end 91.118944 -388.469632)
				)
				(arc
					(start 91.118944 -388.469632)
					(mid 90.903418 -388.558906)
					(end 90.814144 -388.774432)
				)
				(arc
					(start 90.814144 -388.774432)
					(mid 90.823722 -388.850494)
					(end 90.85199 -388.921752)
				)
				(xy 91.249246 -389.609076) (xy 91.261438 -389.630412) (xy 91.263978 -389.63473)
			)
		)
	)
	(zone
		(layers "F.Cu" "B.Cu" "In1.Cu" "In2.Cu" "In3.Cu" "In4.Cu" "In5.Cu" "In6.Cu"
			"In7.Cu" "In8.Cu" "In9.Cu" "In10.Cu" "In11.Cu" "In12.Cu" "In13.Cu" "In14.Cu"
			"In15.Cu" "In16.Cu"
		)
		(hatch none 0.5)
		(connect_pads
			(clearance 0)
		)
		(min_thickness 0.25)
		(keepout
			(tracks not_allowed)
			(vias allowed)
			(pads allowed)
			(copperpour not_allowed)
			(footprints allowed)
		)
		(placement
			(enabled no)
			(sheetname "")
		)
		(fill
			(thermal_gap 0.5)
			(thermal_bridge_width 0.5)
			(island_removal_mode 0)
		)
		(polygon
			(pts
				(arc
					(start 304.120296 -381.96393)
					(mid 303.739296 -382.34493)
					(end 304.120296 -382.72593)
				)
				(arc
					(start 304.983896 -382.72593)
					(mid 305.364896 -382.34493)
					(end 304.983896 -381.96393)
				)
			)
		)
	)
	(zone
		(layers "F.Cu" "B.Cu" "In1.Cu" "In2.Cu" "In3.Cu" "In4.Cu" "In5.Cu" "In6.Cu"
			"In7.Cu" "In8.Cu" "In9.Cu" "In10.Cu" "In11.Cu" "In12.Cu" "In13.Cu" "In14.Cu"
			"In15.Cu" "In16.Cu"
		)
		(hatch none 0.5)
		(connect_pads
			(clearance 0)
		)
		(min_thickness 0.25)
		(keepout
			(tracks not_allowed)
			(vias allowed)
			(pads allowed)
			(copperpour not_allowed)
			(footprints allowed)
		)
		(placement
			(enabled no)
			(sheetname "")
		)
		(fill
			(thermal_gap 0.5)
			(thermal_bridge_width 0.5)
			(island_removal_mode 0)
		)
		(polygon
			(pts
				(arc
					(start 98.843084 3.092196)
					(mid 99.274884 2.660396)
					(end 99.706684 3.092196)
				)
				(arc
					(start 99.706684 3.955796)
					(mid 99.274884 4.387596)
					(end 98.843084 3.955796)
				)
			)
		)
	)
	(zone
		(layers "F.Cu" "B.Cu" "In1.Cu" "In2.Cu" "In3.Cu" "In4.Cu" "In5.Cu" "In6.Cu"
			"In7.Cu" "In8.Cu" "In9.Cu" "In10.Cu" "In11.Cu" "In12.Cu" "In13.Cu" "In14.Cu"
			"In15.Cu" "In16.Cu"
		)
		(hatch none 0.5)
		(connect_pads
			(clearance 0)
		)
		(min_thickness 0.25)
		(keepout
			(tracks not_allowed)
			(vias allowed)
			(pads allowed)
			(copperpour not_allowed)
			(footprints allowed)
		)
		(placement
			(enabled no)
			(sheetname "")
		)
		(fill
			(thermal_gap 0.5)
			(thermal_bridge_width 0.5)
			(island_removal_mode 0)
		)
		(polygon
			(pts
				(arc
					(start 398.920208 -4.582414)
					(mid 398.539208 -4.963414)
					(end 398.920208 -5.344414)
				)
				(arc
					(start 399.783808 -5.344414)
					(mid 400.164808 -4.963414)
					(end 399.783808 -4.582414)
				)
			)
		)
	)
	(zone
		(layers "F.Cu" "B.Cu" "In1.Cu" "In2.Cu" "In3.Cu" "In4.Cu" "In5.Cu" "In6.Cu"
			"In7.Cu" "In8.Cu" "In9.Cu" "In10.Cu" "In11.Cu" "In12.Cu" "In13.Cu" "In14.Cu"
			"In15.Cu" "In16.Cu"
		)
		(hatch none 0.5)
		(connect_pads
			(clearance 0)
		)
		(min_thickness 0.25)
		(keepout
			(tracks not_allowed)
			(vias allowed)
			(pads allowed)
			(copperpour not_allowed)
			(footprints allowed)
		)
		(placement
			(enabled no)
			(sheetname "")
		)
		(fill
			(thermal_gap 0.5)
			(thermal_bridge_width 0.5)
			(island_removal_mode 0)
		)
		(polygon
			(pts
				(arc
					(start 117.697504 -392.429238)
					(mid 117.316504 -392.048238)
					(end 116.935504 -392.429238)
				)
				(arc
					(start 116.935504 -393.292838)
					(mid 117.316504 -393.673838)
					(end 117.697504 -393.292838)
				)
			)
		)
	)
	(zone
		(layers "F.Cu" "B.Cu" "In1.Cu" "In2.Cu" "In3.Cu" "In4.Cu" "In5.Cu" "In6.Cu"
			"In7.Cu" "In8.Cu" "In9.Cu" "In10.Cu" "In11.Cu" "In12.Cu" "In13.Cu" "In14.Cu"
			"In15.Cu" "In16.Cu"
		)
		(hatch none 0.5)
		(connect_pads
			(clearance 0)
		)
		(min_thickness 0.25)
		(keepout
			(tracks not_allowed)
			(vias allowed)
			(pads allowed)
			(copperpour not_allowed)
			(footprints allowed)
		)
		(placement
			(enabled no)
			(sheetname "")
		)
		(fill
			(thermal_gap 0.5)
			(thermal_bridge_width 0.5)
			(island_removal_mode 0)
		)
		(polygon
			(pts
				(arc
					(start 81.489804 -412.189168)
					(mid 81.108804 -412.570168)
					(end 81.489804 -412.951168)
				)
				(arc
					(start 82.353404 -412.951168)
					(mid 82.734404 -412.570168)
					(end 82.353404 -412.189168)
				)
			)
		)
	)
	(zone
		(layers "F.Cu" "B.Cu" "In1.Cu" "In2.Cu" "In3.Cu" "In4.Cu" "In5.Cu" "In6.Cu"
			"In7.Cu" "In8.Cu" "In9.Cu" "In10.Cu" "In11.Cu" "In12.Cu" "In13.Cu" "In14.Cu"
			"In15.Cu" "In16.Cu"
		)
		(hatch none 0.5)
		(connect_pads
			(clearance 0)
		)
		(min_thickness 0.25)
		(keepout
			(tracks not_allowed)
			(vias allowed)
			(pads allowed)
			(copperpour not_allowed)
			(footprints allowed)
		)
		(placement
			(enabled no)
			(sheetname "")
		)
		(fill yes
			(thermal_gap 0.5)
			(thermal_bridge_width 0.5)
			(island_removal_mode 0)
		)
		(polygon
			(pts
				(arc
					(start 130.636518 -386.170424)
					(mid 130.746489 -386.271478)
					(end 130.89128 -386.308092)
				)
				(arc
					(start 130.89128 -386.308092)
					(mid 131.106806 -386.218818)
					(end 131.19608 -386.003292)
				)
				(arc
					(start 131.19608 -386.003292)
					(mid 131.185743 -385.924553)
					(end 131.15544 -385.851146)
				)
				(arc
					(start 130.76301 -385.172204)
					(mid 130.650613 -385.050587)
					(end 130.49123 -385.00558)
				)
				(arc
					(start 130.49123 -385.00558)
					(mid 130.275704 -385.094854)
					(end 130.18643 -385.31038)
				)
				(arc
					(start 130.18643 -385.31038)
					(mid 130.196008 -385.386442)
					(end 130.224276 -385.4577)
				)
				(xy 130.621532 -386.145024) (xy 130.633724 -386.16636) (xy 130.636264 -386.170678)
			)
		)
	)
	(zone
		(layers "F.Cu" "B.Cu" "In1.Cu" "In2.Cu" "In3.Cu" "In4.Cu" "In5.Cu" "In6.Cu"
			"In7.Cu" "In8.Cu" "In9.Cu" "In10.Cu" "In11.Cu" "In12.Cu" "In13.Cu" "In14.Cu"
			"In15.Cu" "In16.Cu"
		)
		(hatch none 0.5)
		(connect_pads
			(clearance 0)
		)
		(min_thickness 0.25)
		(keepout
			(tracks not_allowed)
			(vias allowed)
			(pads allowed)
			(copperpour not_allowed)
			(footprints allowed)
		)
		(placement
			(enabled no)
			(sheetname "")
		)
		(fill
			(thermal_gap 0.5)
			(thermal_bridge_width 0.5)
			(island_removal_mode 0)
		)
		(polygon
			(pts
				(arc
					(start 91.525344 -392.429238)
					(mid 91.144344 -392.048238)
					(end 90.763344 -392.429238)
				)
				(arc
					(start 90.763344 -393.292838)
					(mid 91.144344 -393.673838)
					(end 91.525344 -393.292838)
				)
			)
		)
	)
	(zone
		(layers "F.Cu" "B.Cu" "In1.Cu" "In2.Cu" "In3.Cu" "In4.Cu" "In5.Cu" "In6.Cu"
			"In7.Cu" "In8.Cu" "In9.Cu" "In10.Cu" "In11.Cu" "In12.Cu" "In13.Cu" "In14.Cu"
			"In15.Cu" "In16.Cu"
		)
		(hatch none 0.5)
		(connect_pads
			(clearance 0)
		)
		(min_thickness 0.25)
		(keepout
			(tracks not_allowed)
			(vias allowed)
			(pads allowed)
			(copperpour not_allowed)
			(footprints allowed)
		)
		(placement
			(enabled no)
			(sheetname "")
		)
		(fill
			(thermal_gap 0.5)
			(thermal_bridge_width 0.5)
			(island_removal_mode 0)
		)
		(polygon
			(pts
				(arc
					(start 410.716222 -420.571168)
					(mid 410.335222 -420.952168)
					(end 410.716222 -421.333168)
				)
				(arc
					(start 411.579822 -421.333168)
					(mid 411.960822 -420.952168)
					(end 411.579822 -420.571168)
				)
			)
		)
	)
	(zone
		(layers "F.Cu" "B.Cu" "In1.Cu" "In2.Cu" "In3.Cu" "In4.Cu" "In5.Cu" "In6.Cu"
			"In7.Cu" "In8.Cu" "In9.Cu" "In10.Cu" "In11.Cu" "In12.Cu" "In13.Cu" "In14.Cu"
			"In15.Cu" "In16.Cu"
		)
		(hatch none 0.5)
		(connect_pads
			(clearance 0)
		)
		(min_thickness 0.25)
		(keepout
			(tracks not_allowed)
			(vias allowed)
			(pads allowed)
			(copperpour not_allowed)
			(footprints allowed)
		)
		(placement
			(enabled no)
			(sheetname "")
		)
		(fill
			(thermal_gap 0.5)
			(thermal_bridge_width 0.5)
			(island_removal_mode 0)
		)
		(polygon
			(pts
				(arc
					(start 93.742764 -412.189168)
					(mid 93.361764 -412.570168)
					(end 93.742764 -412.951168)
				)
				(arc
					(start 94.606364 -412.951168)
					(mid 94.987364 -412.570168)
					(end 94.606364 -412.189168)
				)
			)
		)
	)
	(zone
		(layers "F.Cu" "B.Cu" "In1.Cu" "In2.Cu" "In3.Cu" "In4.Cu" "In5.Cu" "In6.Cu"
			"In7.Cu" "In8.Cu" "In9.Cu" "In10.Cu" "In11.Cu" "In12.Cu" "In13.Cu" "In14.Cu"
			"In15.Cu" "In16.Cu"
		)
		(hatch none 0.5)
		(connect_pads
			(clearance 0)
		)
		(min_thickness 0.25)
		(keepout
			(tracks not_allowed)
			(vias allowed)
			(pads allowed)
			(copperpour not_allowed)
			(footprints allowed)
		)
		(placement
			(enabled no)
			(sheetname "")
		)
		(fill
			(thermal_gap 0.5)
			(thermal_bridge_width 0.5)
			(island_removal_mode 0)
		)
		(polygon
			(pts
				(arc
					(start 316.046866 -412.46552)
					(mid 315.665866 -412.84652)
					(end 316.046866 -413.22752)
				)
				(arc
					(start 316.910466 -413.22752)
					(mid 317.291466 -412.84652)
					(end 316.910466 -412.46552)
				)
			)
		)
	)
	(zone
		(layers "F.Cu" "B.Cu" "In1.Cu" "In2.Cu" "In3.Cu" "In4.Cu" "In5.Cu" "In6.Cu"
			"In7.Cu" "In8.Cu" "In9.Cu" "In10.Cu" "In11.Cu" "In12.Cu" "In13.Cu" "In14.Cu"
			"In15.Cu" "In16.Cu"
		)
		(hatch none 0.5)
		(connect_pads
			(clearance 0)
		)
		(min_thickness 0.25)
		(keepout
			(tracks not_allowed)
			(vias allowed)
			(pads allowed)
			(copperpour not_allowed)
			(footprints allowed)
		)
		(placement
			(enabled no)
			(sheetname "")
		)
		(fill
			(thermal_gap 0.5)
			(thermal_bridge_width 0.5)
			(island_removal_mode 0)
		)
		(polygon
			(pts
				(arc
					(start 105.660444 -32.405066)
					(mid 106.041444 -32.786066)
					(end 106.422444 -32.405066)
				)
				(arc
					(start 106.422444 -31.541466)
					(mid 106.041444 -31.160466)
					(end 105.660444 -31.541466)
				)
			)
		)
	)
	(zone
		(layers "F.Cu" "B.Cu" "In1.Cu" "In2.Cu" "In3.Cu" "In4.Cu" "In5.Cu" "In6.Cu"
			"In7.Cu" "In8.Cu" "In9.Cu" "In10.Cu" "In11.Cu" "In12.Cu" "In13.Cu" "In14.Cu"
			"In15.Cu" "In16.Cu"
		)
		(hatch none 0.5)
		(connect_pads
			(clearance 0)
		)
		(min_thickness 0.25)
		(keepout
			(tracks not_allowed)
			(vias allowed)
			(pads allowed)
			(copperpour not_allowed)
			(footprints allowed)
		)
		(placement
			(enabled no)
			(sheetname "")
		)
		(fill
			(thermal_gap 0.5)
			(thermal_bridge_width 0.5)
			(island_removal_mode 0)
		)
		(polygon
			(pts
				(arc
					(start 336.464148 -398.016476)
					(mid 336.574119 -398.11753)
					(end 336.71891 -398.154144)
				)
				(arc
					(start 336.71891 -398.154144)
					(mid 336.934436 -398.06487)
					(end 337.02371 -397.849344)
				)
				(arc
					(start 337.02371 -397.849344)
					(mid 337.013373 -397.770605)
					(end 336.98307 -397.697198)
				)
				(arc
					(start 336.59064 -397.018256)
					(mid 336.478243 -396.896639)
					(end 336.31886 -396.851632)
				)
				(arc
					(start 336.31886 -396.851632)
					(mid 336.103334 -396.940906)
					(end 336.01406 -397.156432)
				)
				(arc
					(start 336.01406 -397.156432)
					(mid 336.023638 -397.232494)
					(end 336.051906 -397.303752)
				)
				(xy 336.449162 -397.991076) (xy 336.461354 -398.012412) (xy 336.463894 -398.01673)
			)
		)
	)
	(zone
		(layers "F.Cu" "B.Cu" "In1.Cu" "In2.Cu" "In3.Cu" "In4.Cu" "In5.Cu" "In6.Cu"
			"In7.Cu" "In8.Cu" "In9.Cu" "In10.Cu" "In11.Cu" "In12.Cu" "In13.Cu" "In14.Cu"
			"In15.Cu" "In16.Cu"
		)
		(hatch none 0.5)
		(connect_pads
			(clearance 0)
		)
		(min_thickness 0.25)
		(keepout
			(tracks not_allowed)
			(vias allowed)
			(pads allowed)
			(copperpour not_allowed)
			(footprints allowed)
		)
		(placement
			(enabled no)
			(sheetname "")
		)
		(fill
			(thermal_gap 0.5)
			(thermal_bridge_width 0.5)
			(island_removal_mode 0)
		)
		(polygon
			(pts
				(arc
					(start 35.091878 -18.75536)
					(mid 34.710878 -19.13636)
					(end 35.091878 -19.51736)
				)
				(arc
					(start 35.955478 -19.51736)
					(mid 36.336478 -19.13636)
					(end 35.955478 -18.75536)
				)
			)
		)
	)
	(zone
		(layers "F.Cu" "B.Cu" "In1.Cu" "In2.Cu" "In3.Cu" "In4.Cu" "In5.Cu" "In6.Cu"
			"In7.Cu" "In8.Cu" "In9.Cu" "In10.Cu" "In11.Cu" "In12.Cu" "In13.Cu" "In14.Cu"
			"In15.Cu" "In16.Cu"
		)
		(hatch none 0.5)
		(connect_pads
			(clearance 0)
		)
		(min_thickness 0.25)
		(keepout
			(tracks not_allowed)
			(vias allowed)
			(pads allowed)
			(copperpour not_allowed)
			(footprints allowed)
		)
		(placement
			(enabled no)
			(sheetname "")
		)
		(fill yes
			(thermal_gap 0.5)
			(thermal_bridge_width 0.5)
			(island_removal_mode 0)
		)
		(polygon
			(pts
				(arc
					(start 53.936646 -386.170424)
					(mid 54.046617 -386.271478)
					(end 54.191408 -386.308092)
				)
				(arc
					(start 54.191408 -386.308092)
					(mid 54.406934 -386.218818)
					(end 54.496208 -386.003292)
				)
				(arc
					(start 54.496208 -386.003292)
					(mid 54.485871 -385.924553)
					(end 54.455568 -385.851146)
				)
				(arc
					(start 54.063138 -385.172204)
					(mid 53.950741 -385.050587)
					(end 53.791358 -385.00558)
				)
				(arc
					(start 53.791358 -385.00558)
					(mid 53.575832 -385.094854)
					(end 53.486558 -385.31038)
				)
				(arc
					(start 53.486558 -385.31038)
					(mid 53.496136 -385.386442)
					(end 53.524404 -385.4577)
				)
				(xy 53.92166 -386.145024) (xy 53.933852 -386.16636) (xy 53.936392 -386.170678)
			)
		)
	)
	(zone
		(layers "F.Cu" "B.Cu" "In1.Cu" "In2.Cu" "In3.Cu" "In4.Cu" "In5.Cu" "In6.Cu"
			"In7.Cu" "In8.Cu" "In9.Cu" "In10.Cu" "In11.Cu" "In12.Cu" "In13.Cu" "In14.Cu"
			"In15.Cu" "In16.Cu"
		)
		(hatch none 0.5)
		(connect_pads
			(clearance 0)
		)
		(min_thickness 0.25)
		(keepout
			(tracks not_allowed)
			(vias allowed)
			(pads allowed)
			(copperpour not_allowed)
			(footprints allowed)
		)
		(placement
			(enabled no)
			(sheetname "")
		)
		(fill
			(thermal_gap 0.5)
			(thermal_bridge_width 0.5)
			(island_removal_mode 0)
		)
		(polygon
			(pts
				(arc
					(start 396.931642 -418.031168)
					(mid 396.550642 -418.412168)
					(end 396.931642 -418.793168)
				)
				(arc
					(start 397.795242 -418.793168)
					(mid 398.176242 -418.412168)
					(end 397.795242 -418.031168)
				)
			)
		)
	)
	(zone
		(layers "F.Cu" "B.Cu" "In1.Cu" "In2.Cu" "In3.Cu" "In4.Cu" "In5.Cu" "In6.Cu"
			"In7.Cu" "In8.Cu" "In9.Cu" "In10.Cu" "In11.Cu" "In12.Cu" "In13.Cu" "In14.Cu"
			"In15.Cu" "In16.Cu"
		)
		(hatch none 0.5)
		(connect_pads
			(clearance 0)
		)
		(min_thickness 0.25)
		(keepout
			(tracks not_allowed)
			(vias allowed)
			(pads allowed)
			(copperpour not_allowed)
			(footprints allowed)
		)
		(placement
			(enabled no)
			(sheetname "")
		)
		(fill
			(thermal_gap 0.5)
			(thermal_bridge_width 0.5)
			(island_removal_mode 0)
		)
		(polygon
			(pts
				(arc
					(start 83.842352 -304.780442)
					(mid 78.81366 -304.780442)
					(end 83.842352 -304.780442)
				)
			)
		)
	)
	(zone
		(layers "F.Cu" "B.Cu" "In1.Cu" "In2.Cu" "In3.Cu" "In4.Cu" "In5.Cu" "In6.Cu"
			"In7.Cu" "In8.Cu" "In9.Cu" "In10.Cu" "In11.Cu" "In12.Cu" "In13.Cu" "In14.Cu"
			"In15.Cu" "In16.Cu"
		)
		(hatch none 0.5)
		(connect_pads
			(clearance 0)
		)
		(min_thickness 0.25)
		(keepout
			(tracks not_allowed)
			(vias allowed)
			(pads allowed)
			(copperpour not_allowed)
			(footprints allowed)
		)
		(placement
			(enabled no)
			(sheetname "")
		)
		(fill
			(thermal_gap 0.5)
			(thermal_bridge_width 0.5)
			(island_removal_mode 0)
		)
		(polygon
			(pts
				(arc
					(start 290.830254 -420.524432)
					(mid 291.211254 -420.905432)
					(end 291.592254 -420.524432)
				)
				(arc
					(start 291.592254 -419.660832)
					(mid 291.211254 -419.279832)
					(end 290.830254 -419.660832)
				)
			)
		)
	)
	(zone
		(layers "F.Cu" "B.Cu" "In1.Cu" "In2.Cu" "In3.Cu" "In4.Cu" "In5.Cu" "In6.Cu"
			"In7.Cu" "In8.Cu" "In9.Cu" "In10.Cu" "In11.Cu" "In12.Cu" "In13.Cu" "In14.Cu"
			"In15.Cu" "In16.Cu"
		)
		(hatch none 0.5)
		(connect_pads
			(clearance 0)
		)
		(min_thickness 0.25)
		(keepout
			(tracks not_allowed)
			(vias allowed)
			(pads allowed)
			(copperpour not_allowed)
			(footprints allowed)
		)
		(placement
			(enabled no)
			(sheetname "")
		)
		(fill
			(thermal_gap 0.5)
			(thermal_bridge_width 0.5)
			(island_removal_mode 0)
		)
		(polygon
			(pts
				(arc
					(start 274.39112 -433.04206)
					(mid 267.27912 -433.04206)
					(end 274.39112 -433.04206)
				)
			)
		)
	)
	(zone
		(layers "F.Cu" "B.Cu" "In1.Cu" "In2.Cu" "In3.Cu" "In4.Cu" "In5.Cu" "In6.Cu"
			"In7.Cu" "In8.Cu" "In9.Cu" "In10.Cu" "In11.Cu" "In12.Cu" "In13.Cu" "In14.Cu"
			"In15.Cu" "In16.Cu"
		)
		(hatch none 0.5)
		(connect_pads
			(clearance 0)
		)
		(min_thickness 0.25)
		(keepout
			(tracks not_allowed)
			(vias allowed)
			(pads allowed)
			(copperpour not_allowed)
			(footprints allowed)
		)
		(placement
			(enabled no)
			(sheetname "")
		)
		(fill
			(thermal_gap 0.5)
			(thermal_bridge_width 0.5)
			(island_removal_mode 0)
		)
		(polygon
			(pts
				(arc
					(start 114.120422 -424.74007)
					(mid 109.929422 -424.74007)
					(end 114.120422 -424.74007)
				)
			)
		)
	)
	(zone
		(layers "F.Cu" "B.Cu" "In1.Cu" "In2.Cu" "In3.Cu" "In4.Cu" "In5.Cu" "In6.Cu"
			"In7.Cu" "In8.Cu" "In9.Cu" "In10.Cu" "In11.Cu" "In12.Cu" "In13.Cu" "In14.Cu"
			"In15.Cu" "In16.Cu"
		)
		(hatch none 0.5)
		(connect_pads
			(clearance 0)
		)
		(min_thickness 0.25)
		(keepout
			(tracks not_allowed)
			(vias allowed)
			(pads allowed)
			(copperpour not_allowed)
			(footprints allowed)
		)
		(placement
			(enabled no)
			(sheetname "")
		)
		(fill
			(thermal_gap 0.5)
			(thermal_bridge_width 0.5)
			(island_removal_mode 0)
		)
		(polygon
			(pts
				(arc
					(start 130.210306 -404.08352)
					(mid 129.829306 -404.46452)
					(end 130.210306 -404.84552)
				)
				(arc
					(start 131.073906 -404.84552)
					(mid 131.454906 -404.46452)
					(end 131.073906 -404.08352)
				)
			)
		)
	)
	(zone
		(layers "F.Cu" "B.Cu" "In1.Cu" "In2.Cu" "In3.Cu" "In4.Cu" "In5.Cu" "In6.Cu"
			"In7.Cu" "In8.Cu" "In9.Cu" "In10.Cu" "In11.Cu" "In12.Cu" "In13.Cu" "In14.Cu"
			"In15.Cu" "In16.Cu"
		)
		(hatch none 0.5)
		(connect_pads
			(clearance 0)
		)
		(min_thickness 0.25)
		(keepout
			(tracks not_allowed)
			(vias allowed)
			(pads allowed)
			(copperpour not_allowed)
			(footprints allowed)
		)
		(placement
			(enabled no)
			(sheetname "")
		)
		(fill yes
			(thermal_gap 0.5)
			(thermal_bridge_width 0.5)
			(island_removal_mode 0)
		)
		(polygon
			(pts
				(arc
					(start 151.16429 -386.170424)
					(mid 151.274261 -386.271478)
					(end 151.419052 -386.308092)
				)
				(arc
					(start 151.419052 -386.308092)
					(mid 151.634578 -386.218818)
					(end 151.723852 -386.003292)
				)
				(arc
					(start 151.723852 -386.003292)
					(mid 151.713515 -385.924553)
					(end 151.683212 -385.851146)
				)
				(arc
					(start 151.290782 -385.172204)
					(mid 151.178385 -385.050587)
					(end 151.019002 -385.00558)
				)
				(arc
					(start 151.019002 -385.00558)
					(mid 150.803476 -385.094854)
					(end 150.714202 -385.31038)
				)
				(arc
					(start 150.714202 -385.31038)
					(mid 150.72378 -385.386442)
					(end 150.752048 -385.4577)
				)
				(xy 151.149304 -386.145024) (xy 151.161496 -386.16636) (xy 151.164036 -386.170678)
			)
		)
	)
	(zone
		(layers "F.Cu" "B.Cu" "In1.Cu" "In2.Cu" "In3.Cu" "In4.Cu" "In5.Cu" "In6.Cu"
			"In7.Cu" "In8.Cu" "In9.Cu" "In10.Cu" "In11.Cu" "In12.Cu" "In13.Cu" "In14.Cu"
			"In15.Cu" "In16.Cu"
		)
		(hatch none 0.5)
		(connect_pads
			(clearance 0)
		)
		(min_thickness 0.25)
		(keepout
			(tracks not_allowed)
			(vias allowed)
			(pads allowed)
			(copperpour not_allowed)
			(footprints allowed)
		)
		(placement
			(enabled no)
			(sheetname "")
		)
		(fill
			(thermal_gap 0.5)
			(thermal_bridge_width 0.5)
			(island_removal_mode 0)
		)
		(polygon
			(pts
				(arc
					(start 255.546098 -197.07352)
					(mid 255.927098 -197.45452)
					(end 256.308098 -197.07352)
				)
				(arc
					(start 256.308098 -196.20992)
					(mid 255.927098 -195.82892)
					(end 255.546098 -196.20992)
				)
			)
		)
	)
	(zone
		(layers "F.Cu" "B.Cu" "In1.Cu" "In2.Cu" "In3.Cu" "In4.Cu" "In5.Cu" "In6.Cu"
			"In7.Cu" "In8.Cu" "In9.Cu" "In10.Cu" "In11.Cu" "In12.Cu" "In13.Cu" "In14.Cu"
			"In15.Cu" "In16.Cu"
		)
		(hatch none 0.5)
		(connect_pads
			(clearance 0)
		)
		(min_thickness 0.25)
		(keepout
			(tracks not_allowed)
			(vias allowed)
			(pads allowed)
			(copperpour not_allowed)
			(footprints allowed)
		)
		(placement
			(enabled no)
			(sheetname "")
		)
		(fill
			(thermal_gap 0.5)
			(thermal_bridge_width 0.5)
			(island_removal_mode 0)
		)
		(polygon
			(pts
				(arc
					(start 144.61744 -31.67634)
					(mid 144.99844 -32.05734)
					(end 145.37944 -31.67634)
				)
				(arc
					(start 145.37944 -30.81274)
					(mid 144.99844 -30.43174)
					(end 144.61744 -30.81274)
				)
			)
		)
	)
	(zone
		(layers "F.Cu" "B.Cu" "In1.Cu" "In2.Cu" "In3.Cu" "In4.Cu" "In5.Cu" "In6.Cu"
			"In7.Cu" "In8.Cu" "In9.Cu" "In10.Cu" "In11.Cu" "In12.Cu" "In13.Cu" "In14.Cu"
			"In15.Cu" "In16.Cu"
		)
		(hatch none 0.5)
		(connect_pads
			(clearance 0)
		)
		(min_thickness 0.25)
		(keepout
			(tracks not_allowed)
			(vias allowed)
			(pads allowed)
			(copperpour not_allowed)
			(footprints allowed)
		)
		(placement
			(enabled no)
			(sheetname "")
		)
		(fill yes
			(thermal_gap 0.5)
			(thermal_bridge_width 0.5)
			(island_removal_mode 0)
		)
		(polygon
			(pts
				(arc
					(start 374.636538 -394.552424)
					(mid 374.746509 -394.653478)
					(end 374.8913 -394.690092)
				)
				(arc
					(start 374.8913 -394.690092)
					(mid 375.106826 -394.600818)
					(end 375.1961 -394.385292)
				)
				(arc
					(start 375.1961 -394.385292)
					(mid 375.185763 -394.306553)
					(end 375.15546 -394.233146)
				)
				(arc
					(start 374.76303 -393.554204)
					(mid 374.650633 -393.432587)
					(end 374.49125 -393.38758)
				)
				(arc
					(start 374.49125 -393.38758)
					(mid 374.275724 -393.476854)
					(end 374.18645 -393.69238)
				)
				(arc
					(start 374.18645 -393.69238)
					(mid 374.196028 -393.768442)
					(end 374.224296 -393.8397)
				)
				(xy 374.621552 -394.527024) (xy 374.633744 -394.54836) (xy 374.636284 -394.552678)
			)
		)
	)
	(zone
		(layers "F.Cu" "B.Cu" "In1.Cu" "In2.Cu" "In3.Cu" "In4.Cu" "In5.Cu" "In6.Cu"
			"In7.Cu" "In8.Cu" "In9.Cu" "In10.Cu" "In11.Cu" "In12.Cu" "In13.Cu" "In14.Cu"
			"In15.Cu" "In16.Cu"
		)
		(hatch none 0.5)
		(connect_pads
			(clearance 0)
		)
		(min_thickness 0.25)
		(keepout
			(tracks not_allowed)
			(vias allowed)
			(pads allowed)
			(copperpour not_allowed)
			(footprints allowed)
		)
		(placement
			(enabled no)
			(sheetname "")
		)
		(fill
			(thermal_gap 0.5)
			(thermal_bridge_width 0.5)
			(island_removal_mode 0)
		)
		(polygon
			(pts
				(arc
					(start 344.863928 -398.016476)
					(mid 344.973899 -398.11753)
					(end 345.11869 -398.154144)
				)
				(arc
					(start 345.11869 -398.154144)
					(mid 345.334216 -398.06487)
					(end 345.42349 -397.849344)
				)
				(arc
					(start 345.42349 -397.849344)
					(mid 345.413153 -397.770605)
					(end 345.38285 -397.697198)
				)
				(arc
					(start 344.99042 -397.018256)
					(mid 344.878023 -396.896639)
					(end 344.71864 -396.851632)
				)
				(arc
					(start 344.71864 -396.851632)
					(mid 344.503114 -396.940906)
					(end 344.41384 -397.156432)
				)
				(arc
					(start 344.41384 -397.156432)
					(mid 344.423418 -397.232494)
					(end 344.451686 -397.303752)
				)
				(xy 344.848942 -397.991076) (xy 344.861134 -398.012412) (xy 344.863674 -398.01673)
			)
		)
	)
	(zone
		(layers "F.Cu" "B.Cu" "In1.Cu" "In2.Cu" "In3.Cu" "In4.Cu" "In5.Cu" "In6.Cu"
			"In7.Cu" "In8.Cu" "In9.Cu" "In10.Cu" "In11.Cu" "In12.Cu" "In13.Cu" "In14.Cu"
			"In15.Cu" "In16.Cu"
		)
		(hatch none 0.5)
		(connect_pads
			(clearance 0)
		)
		(min_thickness 0.25)
		(keepout
			(tracks not_allowed)
			(vias allowed)
			(pads allowed)
			(copperpour not_allowed)
			(footprints allowed)
		)
		(placement
			(enabled no)
			(sheetname "")
		)
		(fill
			(thermal_gap 0.5)
			(thermal_bridge_width 0.5)
			(island_removal_mode 0)
		)
		(polygon
			(pts
				(arc
					(start 480.895406 -12.451334)
					(mid 476.704406 -12.451334)
					(end 480.895406 -12.451334)
				)
			)
		)
	)
	(zone
		(layers "F.Cu" "B.Cu" "In1.Cu" "In2.Cu" "In3.Cu" "In4.Cu" "In5.Cu" "In6.Cu"
			"In7.Cu" "In8.Cu" "In9.Cu" "In10.Cu" "In11.Cu" "In12.Cu" "In13.Cu" "In14.Cu"
			"In15.Cu" "In16.Cu"
		)
		(hatch none 0.5)
		(connect_pads
			(clearance 0)
		)
		(min_thickness 0.25)
		(keepout
			(tracks not_allowed)
			(vias allowed)
			(pads allowed)
			(copperpour not_allowed)
			(footprints allowed)
		)
		(placement
			(enabled no)
			(sheetname "")
		)
		(fill
			(thermal_gap 0.5)
			(thermal_bridge_width 0.5)
			(island_removal_mode 0)
		)
		(polygon
			(pts
				(arc
					(start 68.14185 -425.360592)
					(mid 68.164168 -425.414474)
					(end 68.21805 -425.436792)
				)
				(arc
					(start 69.15785 -425.436792)
					(mid 69.211732 -425.414474)
					(end 69.23405 -425.360592)
				)
				(arc
					(start 69.23405 -422.819068)
					(mid 69.211732 -422.765186)
					(end 69.15785 -422.742868)
				)
				(arc
					(start 68.21805 -422.742868)
					(mid 68.164168 -422.765186)
					(end 68.14185 -422.819068)
				)
			)
		)
	)
	(zone
		(layers "F.Cu" "B.Cu" "In1.Cu" "In2.Cu" "In3.Cu" "In4.Cu" "In5.Cu" "In6.Cu"
			"In7.Cu" "In8.Cu" "In9.Cu" "In10.Cu" "In11.Cu" "In12.Cu" "In13.Cu" "In14.Cu"
			"In15.Cu" "In16.Cu"
		)
		(hatch none 0.5)
		(connect_pads
			(clearance 0)
		)
		(min_thickness 0.25)
		(keepout
			(tracks not_allowed)
			(vias allowed)
			(pads allowed)
			(copperpour not_allowed)
			(footprints allowed)
		)
		(placement
			(enabled no)
			(sheetname "")
		)
		(fill yes
			(thermal_gap 0.5)
			(thermal_bridge_width 0.5)
			(island_removal_mode 0)
		)
		(polygon
			(pts
				(arc
					(start 81.664302 -386.170424)
					(mid 81.774273 -386.271478)
					(end 81.919064 -386.308092)
				)
				(arc
					(start 81.919064 -386.308092)
					(mid 82.13459 -386.218818)
					(end 82.223864 -386.003292)
				)
				(arc
					(start 82.223864 -386.003292)
					(mid 82.213527 -385.924553)
					(end 82.183224 -385.851146)
				)
				(arc
					(start 81.790794 -385.172204)
					(mid 81.678397 -385.050587)
					(end 81.519014 -385.00558)
				)
				(arc
					(start 81.519014 -385.00558)
					(mid 81.303488 -385.094854)
					(end 81.214214 -385.31038)
				)
				(arc
					(start 81.214214 -385.31038)
					(mid 81.223792 -385.386442)
					(end 81.25206 -385.4577)
				)
				(xy 81.649316 -386.145024) (xy 81.661508 -386.16636) (xy 81.664048 -386.170678)
			)
		)
	)
	(zone
		(layers "F.Cu" "B.Cu" "In1.Cu" "In2.Cu" "In3.Cu" "In4.Cu" "In5.Cu" "In6.Cu"
			"In7.Cu" "In8.Cu" "In9.Cu" "In10.Cu" "In11.Cu" "In12.Cu" "In13.Cu" "In14.Cu"
			"In15.Cu" "In16.Cu"
		)
		(hatch none 0.5)
		(connect_pads
			(clearance 0)
		)
		(min_thickness 0.25)
		(keepout
			(tracks not_allowed)
			(vias allowed)
			(pads allowed)
			(copperpour not_allowed)
			(footprints allowed)
		)
		(placement
			(enabled no)
			(sheetname "")
		)
		(fill
			(thermal_gap 0.5)
			(thermal_bridge_width 0.5)
			(island_removal_mode 0)
		)
		(polygon
			(pts
				(arc
					(start 346.679266 -412.46552)
					(mid 346.298266 -412.84652)
					(end 346.679266 -413.22752)
				)
				(arc
					(start 347.542866 -413.22752)
					(mid 347.923866 -412.84652)
					(end 347.542866 -412.46552)
				)
			)
		)
	)
	(zone
		(layers "F.Cu" "B.Cu" "In1.Cu" "In2.Cu" "In3.Cu" "In4.Cu" "In5.Cu" "In6.Cu"
			"In7.Cu" "In8.Cu" "In9.Cu" "In10.Cu" "In11.Cu" "In12.Cu" "In13.Cu" "In14.Cu"
			"In15.Cu" "In16.Cu"
		)
		(hatch none 0.5)
		(connect_pads
			(clearance 0)
		)
		(min_thickness 0.25)
		(keepout
			(tracks not_allowed)
			(vias allowed)
			(pads allowed)
			(copperpour not_allowed)
			(footprints allowed)
		)
		(placement
			(enabled no)
			(sheetname "")
		)
		(fill
			(thermal_gap 0.5)
			(thermal_bridge_width 0.5)
			(island_removal_mode 0)
		)
		(polygon
			(pts
				(arc
					(start 160.842706 -404.08352)
					(mid 160.461706 -404.46452)
					(end 160.842706 -404.84552)
				)
				(arc
					(start 161.706306 -404.84552)
					(mid 162.087306 -404.46452)
					(end 161.706306 -404.08352)
				)
			)
		)
	)
	(zone
		(layers "F.Cu" "B.Cu" "In1.Cu" "In2.Cu" "In3.Cu" "In4.Cu" "In5.Cu" "In6.Cu"
			"In7.Cu" "In8.Cu" "In9.Cu" "In10.Cu" "In11.Cu" "In12.Cu" "In13.Cu" "In14.Cu"
			"In15.Cu" "In16.Cu"
		)
		(hatch none 0.5)
		(connect_pads
			(clearance 0)
		)
		(min_thickness 0.25)
		(keepout
			(tracks not_allowed)
			(vias allowed)
			(pads allowed)
			(copperpour not_allowed)
			(footprints allowed)
		)
		(placement
			(enabled no)
			(sheetname "")
		)
		(fill
			(thermal_gap 0.5)
			(thermal_bridge_width 0.5)
			(island_removal_mode 0)
		)
		(polygon
			(pts
				(arc
					(start 283.407104 -153.766012)
					(mid 272.383504 -153.766012)
					(end 283.407104 -153.766012)
				)
			)
		)
	)
	(zone
		(layers "F.Cu" "B.Cu" "In1.Cu" "In2.Cu" "In3.Cu" "In4.Cu" "In5.Cu" "In6.Cu"
			"In7.Cu" "In8.Cu" "In9.Cu" "In10.Cu" "In11.Cu" "In12.Cu" "In13.Cu" "In14.Cu"
			"In15.Cu" "In16.Cu"
		)
		(hatch none 0.5)
		(connect_pads
			(clearance 0)
		)
		(min_thickness 0.25)
		(keepout
			(tracks not_allowed)
			(vias allowed)
			(pads allowed)
			(copperpour not_allowed)
			(footprints allowed)
		)
		(placement
			(enabled no)
			(sheetname "")
		)
		(fill
			(thermal_gap 0.5)
			(thermal_bridge_width 0.5)
			(island_removal_mode 0)
		)
		(polygon
			(pts
				(arc
					(start 78.426564 -412.189168)
					(mid 78.045564 -412.570168)
					(end 78.426564 -412.951168)
				)
				(arc
					(start 79.290164 -412.951168)
					(mid 79.671164 -412.570168)
					(end 79.290164 -412.189168)
				)
			)
		)
	)
	(zone
		(layers "F.Cu" "B.Cu" "In1.Cu" "In2.Cu" "In3.Cu" "In4.Cu" "In5.Cu" "In6.Cu"
			"In7.Cu" "In8.Cu" "In9.Cu" "In10.Cu" "In11.Cu" "In12.Cu" "In13.Cu" "In14.Cu"
			"In15.Cu" "In16.Cu"
		)
		(hatch none 0.5)
		(connect_pads
			(clearance 0)
		)
		(min_thickness 0.25)
		(keepout
			(tracks not_allowed)
			(vias allowed)
			(pads allowed)
			(copperpour not_allowed)
			(footprints allowed)
		)
		(placement
			(enabled no)
			(sheetname "")
		)
		(fill
			(thermal_gap 0.5)
			(thermal_bridge_width 0.5)
			(island_removal_mode 0)
		)
		(polygon
			(pts
				(arc
					(start 341.258144 -305.569366)
					(mid 340.877144 -305.188366)
					(end 340.496144 -305.569366)
				)
				(arc
					(start 340.496144 -306.432966)
					(mid 340.877144 -306.813966)
					(end 341.258144 -306.432966)
				)
			)
		)
	)
	(zone
		(layers "F.Cu" "B.Cu" "In1.Cu" "In2.Cu" "In3.Cu" "In4.Cu" "In5.Cu" "In6.Cu"
			"In7.Cu" "In8.Cu" "In9.Cu" "In10.Cu" "In11.Cu" "In12.Cu" "In13.Cu" "In14.Cu"
			"In15.Cu" "In16.Cu"
		)
		(hatch none 0.5)
		(connect_pads
			(clearance 0)
		)
		(min_thickness 0.25)
		(keepout
			(tracks not_allowed)
			(vias allowed)
			(pads allowed)
			(copperpour not_allowed)
			(footprints allowed)
		)
		(placement
			(enabled no)
			(sheetname "")
		)
		(fill yes
			(thermal_gap 0.5)
			(thermal_bridge_width 0.5)
			(island_removal_mode 0)
		)
		(polygon
			(pts
				(arc
					(start 94.864174 -386.170424)
					(mid 94.974145 -386.271478)
					(end 95.118936 -386.308092)
				)
				(arc
					(start 95.118936 -386.308092)
					(mid 95.334462 -386.218818)
					(end 95.423736 -386.003292)
				)
				(arc
					(start 95.423736 -386.003292)
					(mid 95.413399 -385.924553)
					(end 95.383096 -385.851146)
				)
				(arc
					(start 94.990666 -385.172204)
					(mid 94.878269 -385.050587)
					(end 94.718886 -385.00558)
				)
				(arc
					(start 94.718886 -385.00558)
					(mid 94.50336 -385.094854)
					(end 94.414086 -385.31038)
				)
				(arc
					(start 94.414086 -385.31038)
					(mid 94.423664 -385.386442)
					(end 94.451932 -385.4577)
				)
				(xy 94.849188 -386.145024) (xy 94.86138 -386.16636) (xy 94.86392 -386.170678)
			)
		)
	)
	(zone
		(layers "F.Cu" "B.Cu" "In1.Cu" "In2.Cu" "In3.Cu" "In4.Cu" "In5.Cu" "In6.Cu"
			"In7.Cu" "In8.Cu" "In9.Cu" "In10.Cu" "In11.Cu" "In12.Cu" "In13.Cu" "In14.Cu"
			"In15.Cu" "In16.Cu"
		)
		(hatch none 0.5)
		(connect_pads
			(clearance 0)
		)
		(min_thickness 0.25)
		(keepout
			(tracks not_allowed)
			(vias allowed)
			(pads allowed)
			(copperpour not_allowed)
			(footprints allowed)
		)
		(placement
			(enabled no)
			(sheetname "")
		)
		(fill
			(thermal_gap 0.5)
			(thermal_bridge_width 0.5)
			(island_removal_mode 0)
		)
		(polygon
			(pts
				(arc
					(start 144.344644 -368.65433)
					(mid 143.963644 -369.03533)
					(end 144.344644 -369.41633)
				)
				(arc
					(start 145.208244 -369.41633)
					(mid 145.589244 -369.03533)
					(end 145.208244 -368.65433)
				)
			)
		)
	)
	(zone
		(layers "F.Cu" "B.Cu" "In1.Cu" "In2.Cu" "In3.Cu" "In4.Cu" "In5.Cu" "In6.Cu"
			"In7.Cu" "In8.Cu" "In9.Cu" "In10.Cu" "In11.Cu" "In12.Cu" "In13.Cu" "In14.Cu"
			"In15.Cu" "In16.Cu"
		)
		(hatch none 0.5)
		(connect_pads
			(clearance 0)
		)
		(min_thickness 0.25)
		(keepout
			(tracks not_allowed)
			(vias allowed)
			(pads allowed)
			(copperpour not_allowed)
			(footprints allowed)
		)
		(placement
			(enabled no)
			(sheetname "")
		)
		(fill yes
			(thermal_gap 0.5)
			(thermal_bridge_width 0.5)
			(island_removal_mode 0)
		)
		(polygon
			(pts
				(arc
					(start 61.13653 -386.170424)
					(mid 61.246501 -386.271478)
					(end 61.391292 -386.308092)
				)
				(arc
					(start 61.391292 -386.308092)
					(mid 61.606818 -386.218818)
					(end 61.696092 -386.003292)
				)
				(arc
					(start 61.696092 -386.003292)
					(mid 61.685755 -385.924553)
					(end 61.655452 -385.851146)
				)
				(arc
					(start 61.263022 -385.172204)
					(mid 61.150625 -385.050587)
					(end 60.991242 -385.00558)
				)
				(arc
					(start 60.991242 -385.00558)
					(mid 60.775716 -385.094854)
					(end 60.686442 -385.31038)
				)
				(arc
					(start 60.686442 -385.31038)
					(mid 60.69602 -385.386442)
					(end 60.724288 -385.4577)
				)
				(xy 61.121544 -386.145024) (xy 61.133736 -386.16636) (xy 61.136276 -386.170678)
			)
		)
	)
	(zone
		(layers "F.Cu" "B.Cu" "In1.Cu" "In2.Cu" "In3.Cu" "In4.Cu" "In5.Cu" "In6.Cu"
			"In7.Cu" "In8.Cu" "In9.Cu" "In10.Cu" "In11.Cu" "In12.Cu" "In13.Cu" "In14.Cu"
			"In15.Cu" "In16.Cu"
		)
		(hatch none 0.5)
		(connect_pads
			(clearance 0)
		)
		(min_thickness 0.25)
		(keepout
			(tracks not_allowed)
			(vias allowed)
			(pads allowed)
			(copperpour not_allowed)
			(footprints allowed)
		)
		(placement
			(enabled no)
			(sheetname "")
		)
		(fill
			(thermal_gap 0.5)
			(thermal_bridge_width 0.5)
			(island_removal_mode 0)
		)
		(polygon
			(pts
				(arc
					(start 52.389024 -409.649168)
					(mid 52.008024 -410.030168)
					(end 52.389024 -410.411168)
				)
				(arc
					(start 53.252624 -410.411168)
					(mid 53.633624 -410.030168)
					(end 53.252624 -409.649168)
				)
			)
		)
	)
	(zone
		(layers "F.Cu" "B.Cu" "In1.Cu" "In2.Cu" "In3.Cu" "In4.Cu" "In5.Cu" "In6.Cu"
			"In7.Cu" "In8.Cu" "In9.Cu" "In10.Cu" "In11.Cu" "In12.Cu" "In13.Cu" "In14.Cu"
			"In15.Cu" "In16.Cu"
		)
		(hatch none 0.5)
		(connect_pads
			(clearance 0)
		)
		(min_thickness 0.25)
		(keepout
			(tracks not_allowed)
			(vias allowed)
			(pads allowed)
			(copperpour not_allowed)
			(footprints allowed)
		)
		(placement
			(enabled no)
			(sheetname "")
		)
		(fill
			(thermal_gap 0.5)
			(thermal_bridge_width 0.5)
			(island_removal_mode 0)
		)
		(polygon
			(pts
				(arc
					(start 408.364182 -398.016476)
					(mid 408.474153 -398.11753)
					(end 408.618944 -398.154144)
				)
				(arc
					(start 408.618944 -398.154144)
					(mid 408.83447 -398.06487)
					(end 408.923744 -397.849344)
				)
				(arc
					(start 408.923744 -397.849344)
					(mid 408.913407 -397.770605)
					(end 408.883104 -397.697198)
				)
				(arc
					(start 408.490674 -397.018256)
					(mid 408.378277 -396.896639)
					(end 408.218894 -396.851632)
				)
				(arc
					(start 408.218894 -396.851632)
					(mid 408.003368 -396.940906)
					(end 407.914094 -397.156432)
				)
				(arc
					(start 407.914094 -397.156432)
					(mid 407.923672 -397.232494)
					(end 407.95194 -397.303752)
				)
				(xy 408.349196 -397.991076) (xy 408.361388 -398.012412) (xy 408.363928 -398.01673)
			)
		)
	)
	(zone
		(layers "F.Cu" "B.Cu" "In1.Cu" "In2.Cu" "In3.Cu" "In4.Cu" "In5.Cu" "In6.Cu"
			"In7.Cu" "In8.Cu" "In9.Cu" "In10.Cu" "In11.Cu" "In12.Cu" "In13.Cu" "In14.Cu"
			"In15.Cu" "In16.Cu"
		)
		(hatch none 0.5)
		(connect_pads
			(clearance 0)
		)
		(min_thickness 0.25)
		(keepout
			(tracks not_allowed)
			(vias allowed)
			(pads allowed)
			(copperpour not_allowed)
			(footprints allowed)
		)
		(placement
			(enabled no)
			(sheetname "")
		)
		(fill
			(thermal_gap 0.5)
			(thermal_bridge_width 0.5)
			(island_removal_mode 0)
		)
		(polygon
			(pts
				(arc
					(start 331.542644 -379.50013)
					(mid 331.161644 -379.88113)
					(end 331.542644 -380.26213)
				)
				(arc
					(start 332.406244 -380.26213)
					(mid 332.787244 -379.88113)
					(end 332.406244 -379.50013)
				)
			)
		)
	)
	(zone
		(layers "F.Cu" "B.Cu" "In1.Cu" "In2.Cu" "In3.Cu" "In4.Cu" "In5.Cu" "In6.Cu"
			"In7.Cu" "In8.Cu" "In9.Cu" "In10.Cu" "In11.Cu" "In12.Cu" "In13.Cu" "In14.Cu"
			"In15.Cu" "In16.Cu"
		)
		(hatch none 0.5)
		(connect_pads
			(clearance 0)
		)
		(min_thickness 0.25)
		(keepout
			(tracks not_allowed)
			(vias allowed)
			(pads allowed)
			(copperpour not_allowed)
			(footprints allowed)
		)
		(placement
			(enabled no)
			(sheetname "")
		)
		(fill
			(thermal_gap 0.5)
			(thermal_bridge_width 0.5)
			(island_removal_mode 0)
		)
		(polygon
			(pts
				(arc
					(start 305.397154 -400.811238)
					(mid 305.016154 -400.430238)
					(end 304.635154 -400.811238)
				)
				(arc
					(start 304.635154 -401.674838)
					(mid 305.016154 -402.055838)
					(end 305.397154 -401.674838)
				)
			)
		)
	)
	(zone
		(layers "F.Cu" "B.Cu" "In1.Cu" "In2.Cu" "In3.Cu" "In4.Cu" "In5.Cu" "In6.Cu"
			"In7.Cu" "In8.Cu" "In9.Cu" "In10.Cu" "In11.Cu" "In12.Cu" "In13.Cu" "In14.Cu"
			"In15.Cu" "In16.Cu"
		)
		(hatch none 0.5)
		(connect_pads
			(clearance 0)
		)
		(min_thickness 0.25)
		(keepout
			(tracks not_allowed)
			(vias allowed)
			(pads allowed)
			(copperpour not_allowed)
			(footprints allowed)
		)
		(placement
			(enabled no)
			(sheetname "")
		)
		(fill
			(thermal_gap 0.5)
			(thermal_bridge_width 0.5)
			(island_removal_mode 0)
		)
		(polygon
			(pts
				(arc
					(start 78.426564 -404.08352)
					(mid 78.045564 -404.46452)
					(end 78.426564 -404.84552)
				)
				(arc
					(start 79.290164 -404.84552)
					(mid 79.671164 -404.46452)
					(end 79.290164 -404.08352)
				)
			)
		)
	)
	(zone
		(layers "F.Cu" "B.Cu" "In1.Cu" "In2.Cu" "In3.Cu" "In4.Cu" "In5.Cu" "In6.Cu"
			"In7.Cu" "In8.Cu" "In9.Cu" "In10.Cu" "In11.Cu" "In12.Cu" "In13.Cu" "In14.Cu"
			"In15.Cu" "In16.Cu"
		)
		(hatch none 0.5)
		(connect_pads
			(clearance 0)
		)
		(min_thickness 0.25)
		(keepout
			(tracks not_allowed)
			(vias allowed)
			(pads allowed)
			(copperpour not_allowed)
			(footprints allowed)
		)
		(placement
			(enabled no)
			(sheetname "")
		)
		(fill
			(thermal_gap 0.5)
			(thermal_bridge_width 0.5)
			(island_removal_mode 0)
		)
		(polygon
			(pts
				(arc
					(start 49.367694 -17.23136)
					(mid 48.986694 -17.61236)
					(end 49.367694 -17.99336)
				)
				(arc
					(start 50.231294 -17.99336)
					(mid 50.612294 -17.61236)
					(end 50.231294 -17.23136)
				)
			)
		)
	)
	(zone
		(layers "F.Cu" "B.Cu" "In1.Cu" "In2.Cu" "In3.Cu" "In4.Cu" "In5.Cu" "In6.Cu"
			"In7.Cu" "In8.Cu" "In9.Cu" "In10.Cu" "In11.Cu" "In12.Cu" "In13.Cu" "In14.Cu"
			"In15.Cu" "In16.Cu"
		)
		(hatch none 0.5)
		(connect_pads
			(clearance 0)
		)
		(min_thickness 0.25)
		(keepout
			(tracks not_allowed)
			(vias allowed)
			(pads allowed)
			(copperpour not_allowed)
			(footprints allowed)
		)
		(placement
			(enabled no)
			(sheetname "")
		)
		(fill
			(thermal_gap 0.5)
			(thermal_bridge_width 0.5)
			(island_removal_mode 0)
		)
		(polygon
			(pts
				(arc
					(start 207.212184 -351.54743)
					(mid 206.831184 -351.16643)
					(end 206.450184 -351.54743)
				)
				(arc
					(start 206.450184 -352.41103)
					(mid 206.831184 -352.79203)
					(end 207.212184 -352.41103)
				)
			)
		)
	)
	(zone
		(layers "F.Cu" "B.Cu" "In1.Cu" "In2.Cu" "In3.Cu" "In4.Cu" "In5.Cu" "In6.Cu"
			"In7.Cu" "In8.Cu" "In9.Cu" "In10.Cu" "In11.Cu" "In12.Cu" "In13.Cu" "In14.Cu"
			"In15.Cu" "In16.Cu"
		)
		(hatch none 0.5)
		(connect_pads
			(clearance 0)
		)
		(min_thickness 0.25)
		(keepout
			(tracks not_allowed)
			(vias allowed)
			(pads allowed)
			(copperpour not_allowed)
			(footprints allowed)
		)
		(placement
			(enabled no)
			(sheetname "")
		)
		(fill
			(thermal_gap 0.5)
			(thermal_bridge_width 0.5)
			(island_removal_mode 0)
		)
		(polygon
			(pts
				(arc
					(start 149.450044 -371.11813)
					(mid 149.069044 -371.49913)
					(end 149.450044 -371.88013)
				)
				(arc
					(start 150.313644 -371.88013)
					(mid 150.694644 -371.49913)
					(end 150.313644 -371.11813)
				)
			)
		)
	)
	(zone
		(layers "F.Cu" "B.Cu" "In1.Cu" "In2.Cu" "In3.Cu" "In4.Cu" "In5.Cu" "In6.Cu"
			"In7.Cu" "In8.Cu" "In9.Cu" "In10.Cu" "In11.Cu" "In12.Cu" "In13.Cu" "In14.Cu"
			"In15.Cu" "In16.Cu"
		)
		(hatch none 0.5)
		(connect_pads
			(clearance 0)
		)
		(min_thickness 0.25)
		(keepout
			(tracks not_allowed)
			(vias allowed)
			(pads allowed)
			(copperpour not_allowed)
			(footprints allowed)
		)
		(placement
			(enabled no)
			(sheetname "")
		)
		(fill
			(thermal_gap 0.5)
			(thermal_bridge_width 0.5)
			(island_removal_mode 0)
		)
		(polygon
			(pts
				(arc
					(start 389.297418 -400.811238)
					(mid 388.916418 -400.430238)
					(end 388.535418 -400.811238)
				)
				(arc
					(start 388.535418 -401.674838)
					(mid 388.916418 -402.055838)
					(end 389.297418 -401.674838)
				)
			)
		)
	)
	(zone
		(layers "F.Cu" "B.Cu" "In1.Cu" "In2.Cu" "In3.Cu" "In4.Cu" "In5.Cu" "In6.Cu"
			"In7.Cu" "In8.Cu" "In9.Cu" "In10.Cu" "In11.Cu" "In12.Cu" "In13.Cu" "In14.Cu"
			"In15.Cu" "In16.Cu"
		)
		(hatch none 0.5)
		(connect_pads
			(clearance 0)
		)
		(min_thickness 0.25)
		(keepout
			(tracks not_allowed)
			(vias allowed)
			(pads allowed)
			(copperpour not_allowed)
			(footprints allowed)
		)
		(placement
			(enabled no)
			(sheetname "")
		)
		(fill
			(thermal_gap 0.5)
			(thermal_bridge_width 0.5)
			(island_removal_mode 0)
		)
		(polygon
			(pts
				(arc
					(start 138.758676 -376.093228)
					(mid 138.377676 -375.712228)
					(end 137.996676 -376.093228)
				)
				(arc
					(start 137.996676 -376.956828)
					(mid 138.377676 -377.337828)
					(end 138.758676 -376.956828)
				)
			)
		)
	)
	(zone
		(layers "F.Cu" "B.Cu" "In1.Cu" "In2.Cu" "In3.Cu" "In4.Cu" "In5.Cu" "In6.Cu"
			"In7.Cu" "In8.Cu" "In9.Cu" "In10.Cu" "In11.Cu" "In12.Cu" "In13.Cu" "In14.Cu"
			"In15.Cu" "In16.Cu"
		)
		(hatch none 0.5)
		(connect_pads
			(clearance 0)
		)
		(min_thickness 0.25)
		(keepout
			(tracks not_allowed)
			(vias allowed)
			(pads allowed)
			(copperpour not_allowed)
			(footprints allowed)
		)
		(placement
			(enabled no)
			(sheetname "")
		)
		(fill yes
			(thermal_gap 0.5)
			(thermal_bridge_width 0.5)
			(island_removal_mode 0)
		)
		(polygon
			(pts
				(arc
					(start 59.936634 -386.170424)
					(mid 60.046605 -386.271478)
					(end 60.191396 -386.308092)
				)
				(arc
					(start 60.191396 -386.308092)
					(mid 60.406922 -386.218818)
					(end 60.496196 -386.003292)
				)
				(arc
					(start 60.496196 -386.003292)
					(mid 60.485859 -385.924553)
					(end 60.455556 -385.851146)
				)
				(arc
					(start 60.063126 -385.172204)
					(mid 59.950729 -385.050587)
					(end 59.791346 -385.00558)
				)
				(arc
					(start 59.791346 -385.00558)
					(mid 59.57582 -385.094854)
					(end 59.486546 -385.31038)
				)
				(arc
					(start 59.486546 -385.31038)
					(mid 59.496124 -385.386442)
					(end 59.524392 -385.4577)
				)
				(xy 59.921648 -386.145024) (xy 59.93384 -386.16636) (xy 59.93638 -386.170678)
			)
		)
	)
	(zone
		(layers "F.Cu" "B.Cu" "In1.Cu" "In2.Cu" "In3.Cu" "In4.Cu" "In5.Cu" "In6.Cu"
			"In7.Cu" "In8.Cu" "In9.Cu" "In10.Cu" "In11.Cu" "In12.Cu" "In13.Cu" "In14.Cu"
			"In15.Cu" "In16.Cu"
		)
		(hatch none 0.5)
		(connect_pads
			(clearance 0)
		)
		(min_thickness 0.25)
		(keepout
			(tracks not_allowed)
			(vias allowed)
			(pads allowed)
			(copperpour not_allowed)
			(footprints allowed)
		)
		(placement
			(enabled no)
			(sheetname "")
		)
		(fill
			(thermal_gap 0.5)
			(thermal_bridge_width 0.5)
			(island_removal_mode 0)
		)
		(polygon
			(pts
				(arc
					(start 421.295068 -74.767948)
					(mid 426.803058 -80.275938)
					(end 432.311048 -74.767948)
				)
				(arc
					(start 432.311048 -66.06794)
					(mid 426.803058 -60.55995)
					(end 421.295068 -66.06794)
				)
			)
		)
	)
	(zone
		(layers "F.Cu" "B.Cu" "In1.Cu" "In2.Cu" "In3.Cu" "In4.Cu" "In5.Cu" "In6.Cu"
			"In7.Cu" "In8.Cu" "In9.Cu" "In10.Cu" "In11.Cu" "In12.Cu" "In13.Cu" "In14.Cu"
			"In15.Cu" "In16.Cu"
		)
		(hatch none 0.5)
		(connect_pads
			(clearance 0)
		)
		(min_thickness 0.25)
		(keepout
			(tracks not_allowed)
			(vias allowed)
			(pads allowed)
			(copperpour not_allowed)
			(footprints allowed)
		)
		(placement
			(enabled no)
			(sheetname "")
		)
		(fill
			(thermal_gap 0.5)
			(thermal_bridge_width 0.5)
			(island_removal_mode 0)
		)
		(polygon
			(pts
				(arc
					(start 427.28642 -384.475228)
					(mid 426.90542 -384.094228)
					(end 426.52442 -384.475228)
				)
				(arc
					(start 426.52442 -385.338828)
					(mid 426.90542 -385.719828)
					(end 427.28642 -385.338828)
				)
			)
		)
	)
	(zone
		(layers "F.Cu" "B.Cu" "In1.Cu" "In2.Cu" "In3.Cu" "In4.Cu" "In5.Cu" "In6.Cu"
			"In7.Cu" "In8.Cu" "In9.Cu" "In10.Cu" "In11.Cu" "In12.Cu" "In13.Cu" "In14.Cu"
			"In15.Cu" "In16.Cu"
		)
		(hatch none 0.5)
		(connect_pads
			(clearance 0)
		)
		(min_thickness 0.25)
		(keepout
			(tracks not_allowed)
			(vias allowed)
			(pads allowed)
			(copperpour not_allowed)
			(footprints allowed)
		)
		(placement
			(enabled no)
			(sheetname "")
		)
		(fill
			(thermal_gap 0.5)
			(thermal_bridge_width 0.5)
			(island_removal_mode 0)
		)
		(polygon
			(pts
				(arc
					(start 63.110364 -412.189168)
					(mid 62.729364 -412.570168)
					(end 63.110364 -412.951168)
				)
				(arc
					(start 63.973964 -412.951168)
					(mid 64.354964 -412.570168)
					(end 63.973964 -412.189168)
				)
			)
		)
	)
	(zone
		(layers "F.Cu" "B.Cu" "In1.Cu" "In2.Cu" "In3.Cu" "In4.Cu" "In5.Cu" "In6.Cu"
			"In7.Cu" "In8.Cu" "In9.Cu" "In10.Cu" "In11.Cu" "In12.Cu" "In13.Cu" "In14.Cu"
			"In15.Cu" "In16.Cu"
		)
		(hatch none 0.5)
		(connect_pads
			(clearance 0)
		)
		(min_thickness 0.25)
		(keepout
			(tracks not_allowed)
			(vias allowed)
			(pads allowed)
			(copperpour not_allowed)
			(footprints allowed)
		)
		(placement
			(enabled no)
			(sheetname "")
		)
		(fill yes
			(thermal_gap 0.5)
			(thermal_bridge_width 0.5)
			(island_removal_mode 0)
		)
		(polygon
			(pts
				(arc
					(start 181.500018 -376.489976)
					(mid 177.500026 -380.489968)
					(end 173.500034 -376.489976)
				)
				(arc
					(start 173.500034 -376.489976)
					(mid 177.500026 -372.489984)
					(end 181.500018 -376.489976)
				)
			)
		)
	)
	(zone
		(layers "F.Cu" "B.Cu" "In1.Cu" "In2.Cu" "In3.Cu" "In4.Cu" "In5.Cu" "In6.Cu"
			"In7.Cu" "In8.Cu" "In9.Cu" "In10.Cu" "In11.Cu" "In12.Cu" "In13.Cu" "In14.Cu"
			"In15.Cu" "In16.Cu"
		)
		(hatch none 0.5)
		(connect_pads
			(clearance 0)
		)
		(min_thickness 0.25)
		(keepout
			(tracks not_allowed)
			(vias allowed)
			(pads allowed)
			(copperpour not_allowed)
			(footprints allowed)
		)
		(placement
			(enabled no)
			(sheetname "")
		)
		(fill
			(thermal_gap 0.5)
			(thermal_bridge_width 0.5)
			(island_removal_mode 0)
		)
		(polygon
			(pts
				(arc
					(start 373.436388 -398.016476)
					(mid 373.546359 -398.11753)
					(end 373.69115 -398.154144)
				)
				(arc
					(start 373.69115 -398.154144)
					(mid 373.906676 -398.06487)
					(end 373.99595 -397.849344)
				)
				(arc
					(start 373.99595 -397.849344)
					(mid 373.985613 -397.770605)
					(end 373.95531 -397.697198)
				)
				(arc
					(start 373.56288 -397.018256)
					(mid 373.450483 -396.896639)
					(end 373.2911 -396.851632)
				)
				(arc
					(start 373.2911 -396.851632)
					(mid 373.075574 -396.940906)
					(end 372.9863 -397.156432)
				)
				(arc
					(start 372.9863 -397.156432)
					(mid 372.995878 -397.232494)
					(end 373.024146 -397.303752)
				)
				(xy 373.421402 -397.991076) (xy 373.433594 -398.012412) (xy 373.436134 -398.01673)
			)
		)
	)
	(zone
		(layers "F.Cu" "B.Cu" "In1.Cu" "In2.Cu" "In3.Cu" "In4.Cu" "In5.Cu" "In6.Cu"
			"In7.Cu" "In8.Cu" "In9.Cu" "In10.Cu" "In11.Cu" "In12.Cu" "In13.Cu" "In14.Cu"
			"In15.Cu" "In16.Cu"
		)
		(hatch none 0.5)
		(connect_pads
			(clearance 0)
		)
		(min_thickness 0.25)
		(keepout
			(tracks not_allowed)
			(vias allowed)
			(pads allowed)
			(copperpour not_allowed)
			(footprints allowed)
		)
		(placement
			(enabled no)
			(sheetname "")
		)
		(fill
			(thermal_gap 0.5)
			(thermal_bridge_width 0.5)
			(island_removal_mode 0)
		)
		(polygon
			(pts
				(arc
					(start 8.725408 -170.29303)
					(mid 9.106408 -170.67403)
					(end 9.487408 -170.29303)
				)
				(arc
					(start 9.487408 -169.42943)
					(mid 9.106408 -169.04843)
					(end 8.725408 -169.42943)
				)
			)
		)
	)
	(zone
		(layers "F.Cu" "B.Cu" "In1.Cu" "In2.Cu" "In3.Cu" "In4.Cu" "In5.Cu" "In6.Cu"
			"In7.Cu" "In8.Cu" "In9.Cu" "In10.Cu" "In11.Cu" "In12.Cu" "In13.Cu" "In14.Cu"
			"In15.Cu" "In16.Cu"
		)
		(hatch none 0.5)
		(connect_pads
			(clearance 0)
		)
		(min_thickness 0.25)
		(keepout
			(tracks not_allowed)
			(vias allowed)
			(pads allowed)
			(copperpour not_allowed)
			(footprints allowed)
		)
		(placement
			(enabled no)
			(sheetname "")
		)
		(fill
			(thermal_gap 0.5)
			(thermal_bridge_width 0.5)
			(island_removal_mode 0)
		)
		(polygon
			(pts
				(arc
					(start 101.069902 -368.65433)
					(mid 100.688902 -369.03533)
					(end 101.069902 -369.41633)
				)
				(arc
					(start 101.933502 -369.41633)
					(mid 102.314502 -369.03533)
					(end 101.933502 -368.65433)
				)
			)
		)
	)
	(zone
		(layers "F.Cu" "B.Cu" "In1.Cu" "In2.Cu" "In3.Cu" "In4.Cu" "In5.Cu" "In6.Cu"
			"In7.Cu" "In8.Cu" "In9.Cu" "In10.Cu" "In11.Cu" "In12.Cu" "In13.Cu" "In14.Cu"
			"In15.Cu" "In16.Cu"
		)
		(hatch none 0.5)
		(connect_pads
			(clearance 0)
		)
		(min_thickness 0.25)
		(keepout
			(tracks not_allowed)
			(vias allowed)
			(pads allowed)
			(copperpour not_allowed)
			(footprints allowed)
		)
		(placement
			(enabled no)
			(sheetname "")
		)
		(fill
			(thermal_gap 0.5)
			(thermal_bridge_width 0.5)
			(island_removal_mode 0)
		)
		(polygon
			(pts
				(arc
					(start 309.920386 -420.571168)
					(mid 309.539386 -420.952168)
					(end 309.920386 -421.333168)
				)
				(arc
					(start 310.783986 -421.333168)
					(mid 311.164986 -420.952168)
					(end 310.783986 -420.571168)
				)
			)
		)
	)
	(zone
		(layers "F.Cu" "B.Cu" "In1.Cu" "In2.Cu" "In3.Cu" "In4.Cu" "In5.Cu" "In6.Cu"
			"In7.Cu" "In8.Cu" "In9.Cu" "In10.Cu" "In11.Cu" "In12.Cu" "In13.Cu" "In14.Cu"
			"In15.Cu" "In16.Cu"
		)
		(hatch none 0.5)
		(connect_pads
			(clearance 0)
		)
		(min_thickness 0.25)
		(keepout
			(tracks not_allowed)
			(vias allowed)
			(pads allowed)
			(copperpour not_allowed)
			(footprints allowed)
		)
		(placement
			(enabled no)
			(sheetname "")
		)
		(fill yes
			(thermal_gap 0.5)
			(thermal_bridge_width 0.5)
			(island_removal_mode 0)
		)
		(polygon
			(pts
				(arc
					(start 308.736238 -394.552424)
					(mid 308.846209 -394.653478)
					(end 308.991 -394.690092)
				)
				(arc
					(start 308.991 -394.690092)
					(mid 309.206526 -394.600818)
					(end 309.2958 -394.385292)
				)
				(arc
					(start 309.2958 -394.385292)
					(mid 309.285463 -394.306553)
					(end 309.25516 -394.233146)
				)
				(arc
					(start 308.86273 -393.554204)
					(mid 308.750333 -393.432587)
					(end 308.59095 -393.38758)
				)
				(arc
					(start 308.59095 -393.38758)
					(mid 308.375424 -393.476854)
					(end 308.28615 -393.69238)
				)
				(arc
					(start 308.28615 -393.69238)
					(mid 308.295728 -393.768442)
					(end 308.323996 -393.8397)
				)
				(xy 308.721252 -394.527024) (xy 308.733444 -394.54836) (xy 308.735984 -394.552678)
			)
		)
	)
	(zone
		(layers "F.Cu" "B.Cu" "In1.Cu" "In2.Cu" "In3.Cu" "In4.Cu" "In5.Cu" "In6.Cu"
			"In7.Cu" "In8.Cu" "In9.Cu" "In10.Cu" "In11.Cu" "In12.Cu" "In13.Cu" "In14.Cu"
			"In15.Cu" "In16.Cu"
		)
		(hatch none 0.5)
		(connect_pads
			(clearance 0)
		)
		(min_thickness 0.25)
		(keepout
			(tracks not_allowed)
			(vias allowed)
			(pads allowed)
			(copperpour not_allowed)
			(footprints allowed)
		)
		(placement
			(enabled no)
			(sheetname "")
		)
		(fill
			(thermal_gap 0.5)
			(thermal_bridge_width 0.5)
			(island_removal_mode 0)
		)
		(polygon
			(pts
				(arc
					(start 318.336168 -398.016476)
					(mid 318.446139 -398.11753)
					(end 318.59093 -398.154144)
				)
				(arc
					(start 318.59093 -398.154144)
					(mid 318.806456 -398.06487)
					(end 318.89573 -397.849344)
				)
				(arc
					(start 318.89573 -397.849344)
					(mid 318.885393 -397.770605)
					(end 318.85509 -397.697198)
				)
				(arc
					(start 318.46266 -397.018256)
					(mid 318.350263 -396.896639)
					(end 318.19088 -396.851632)
				)
				(arc
					(start 318.19088 -396.851632)
					(mid 317.975354 -396.940906)
					(end 317.88608 -397.156432)
				)
				(arc
					(start 317.88608 -397.156432)
					(mid 317.895658 -397.232494)
					(end 317.923926 -397.303752)
				)
				(xy 318.321182 -397.991076) (xy 318.333374 -398.012412) (xy 318.335914 -398.01673)
			)
		)
	)
	(zone
		(layers "F.Cu" "B.Cu" "In1.Cu" "In2.Cu" "In3.Cu" "In4.Cu" "In5.Cu" "In6.Cu"
			"In7.Cu" "In8.Cu" "In9.Cu" "In10.Cu" "In11.Cu" "In12.Cu" "In13.Cu" "In14.Cu"
			"In15.Cu" "In16.Cu"
		)
		(hatch none 0.5)
		(connect_pads
			(clearance 0)
		)
		(min_thickness 0.25)
		(keepout
			(tracks not_allowed)
			(vias allowed)
			(pads allowed)
			(copperpour not_allowed)
			(footprints allowed)
		)
		(placement
			(enabled no)
			(sheetname "")
		)
		(fill
			(thermal_gap 0.5)
			(thermal_bridge_width 0.5)
			(island_removal_mode 0)
		)
		(polygon
			(pts
				(arc
					(start 87.616284 -404.08352)
					(mid 87.235284 -404.46452)
					(end 87.616284 -404.84552)
				)
				(arc
					(start 88.479884 -404.84552)
					(mid 88.860884 -404.46452)
					(end 88.479884 -404.08352)
				)
			)
		)
	)
	(zone
		(layers "F.Cu" "B.Cu" "In1.Cu" "In2.Cu" "In3.Cu" "In4.Cu" "In5.Cu" "In6.Cu"
			"In7.Cu" "In8.Cu" "In9.Cu" "In10.Cu" "In11.Cu" "In12.Cu" "In13.Cu" "In14.Cu"
			"In15.Cu" "In16.Cu"
		)
		(hatch none 0.5)
		(connect_pads
			(clearance 0)
		)
		(min_thickness 0.25)
		(keepout
			(tracks not_allowed)
			(vias allowed)
			(pads allowed)
			(copperpour not_allowed)
			(footprints allowed)
		)
		(placement
			(enabled no)
			(sheetname "")
		)
		(fill
			(thermal_gap 0.5)
			(thermal_bridge_width 0.5)
			(island_removal_mode 0)
		)
		(polygon
			(pts
				(arc
					(start 138.758676 -379.496828)
					(mid 138.377676 -379.115828)
					(end 137.996676 -379.496828)
				)
				(arc
					(start 137.996676 -380.360428)
					(mid 138.377676 -380.741428)
					(end 138.758676 -380.360428)
				)
			)
		)
	)
	(zone
		(layers "F.Cu" "B.Cu" "In1.Cu" "In2.Cu" "In3.Cu" "In4.Cu" "In5.Cu" "In6.Cu"
			"In7.Cu" "In8.Cu" "In9.Cu" "In10.Cu" "In11.Cu" "In12.Cu" "In13.Cu" "In14.Cu"
			"In15.Cu" "In16.Cu"
		)
		(hatch none 0.5)
		(connect_pads
			(clearance 0)
		)
		(min_thickness 0.25)
		(keepout
			(tracks not_allowed)
			(vias allowed)
			(pads allowed)
			(copperpour not_allowed)
			(footprints allowed)
		)
		(placement
			(enabled no)
			(sheetname "")
		)
		(fill
			(thermal_gap 0.5)
			(thermal_bridge_width 0.5)
			(island_removal_mode 0)
		)
		(polygon
			(pts
				(arc
					(start 19.01571 -6.344158)
					(mid 18.63471 -6.725158)
					(end 19.01571 -7.106158)
				)
				(arc
					(start 19.87931 -7.106158)
					(mid 20.26031 -6.725158)
					(end 19.87931 -6.344158)
				)
			)
		)
	)
	(zone
		(layers "F.Cu" "B.Cu" "In1.Cu" "In2.Cu" "In3.Cu" "In4.Cu" "In5.Cu" "In6.Cu"
			"In7.Cu" "In8.Cu" "In9.Cu" "In10.Cu" "In11.Cu" "In12.Cu" "In13.Cu" "In14.Cu"
			"In15.Cu" "In16.Cu"
		)
		(hatch none 0.5)
		(connect_pads
			(clearance 0)
		)
		(min_thickness 0.25)
		(keepout
			(tracks not_allowed)
			(vias allowed)
			(pads allowed)
			(copperpour not_allowed)
			(footprints allowed)
		)
		(placement
			(enabled no)
			(sheetname "")
		)
		(fill
			(thermal_gap 0.5)
			(thermal_bridge_width 0.5)
			(island_removal_mode 0)
		)
		(polygon
			(pts
				(arc
					(start 297.811444 -389.88746)
					(mid 297.430444 -389.50646)
					(end 297.049444 -389.88746)
				)
				(arc
					(start 297.049444 -390.75106)
					(mid 297.430444 -391.13206)
					(end 297.811444 -390.75106)
				)
			)
		)
	)
	(zone
		(layers "F.Cu" "B.Cu" "In1.Cu" "In2.Cu" "In3.Cu" "In4.Cu" "In5.Cu" "In6.Cu"
			"In7.Cu" "In8.Cu" "In9.Cu" "In10.Cu" "In11.Cu" "In12.Cu" "In13.Cu" "In14.Cu"
			"In15.Cu" "In16.Cu"
		)
		(hatch none 0.5)
		(connect_pads
			(clearance 0)
		)
		(min_thickness 0.25)
		(keepout
			(tracks not_allowed)
			(vias allowed)
			(pads allowed)
			(copperpour not_allowed)
			(footprints allowed)
		)
		(placement
			(enabled no)
			(sheetname "")
		)
		(fill
			(thermal_gap 0.5)
			(thermal_bridge_width 0.5)
			(island_removal_mode 0)
		)
		(polygon
			(pts
				(arc
					(start 41.811702 -375.96826)
					(mid 41.430702 -375.58726)
					(end 41.049702 -375.96826)
				)
				(arc
					(start 41.049702 -376.83186)
					(mid 41.430702 -377.21286)
					(end 41.811702 -376.83186)
				)
			)
		)
	)
	(zone
		(layers "F.Cu" "B.Cu" "In1.Cu" "In2.Cu" "In3.Cu" "In4.Cu" "In5.Cu" "In6.Cu"
			"In7.Cu" "In8.Cu" "In9.Cu" "In10.Cu" "In11.Cu" "In12.Cu" "In13.Cu" "In14.Cu"
			"In15.Cu" "In16.Cu"
		)
		(hatch none 0.5)
		(connect_pads
			(clearance 0)
		)
		(min_thickness 0.25)
		(keepout
			(tracks not_allowed)
			(vias allowed)
			(pads allowed)
			(copperpour not_allowed)
			(footprints allowed)
		)
		(placement
			(enabled no)
			(sheetname "")
		)
		(fill yes
			(thermal_gap 0.5)
			(thermal_bridge_width 0.5)
			(island_removal_mode 0)
		)
		(polygon
			(pts
				(arc
					(start 148.764244 -386.170424)
					(mid 148.874215 -386.271478)
					(end 149.019006 -386.308092)
				)
				(arc
					(start 149.019006 -386.308092)
					(mid 149.234532 -386.218818)
					(end 149.323806 -386.003292)
				)
				(arc
					(start 149.323806 -386.003292)
					(mid 149.313469 -385.924553)
					(end 149.283166 -385.851146)
				)
				(arc
					(start 148.890736 -385.172204)
					(mid 148.778339 -385.050587)
					(end 148.618956 -385.00558)
				)
				(arc
					(start 148.618956 -385.00558)
					(mid 148.40343 -385.094854)
					(end 148.314156 -385.31038)
				)
				(arc
					(start 148.314156 -385.31038)
					(mid 148.323734 -385.386442)
					(end 148.352002 -385.4577)
				)
				(xy 148.749258 -386.145024) (xy 148.76145 -386.16636) (xy 148.76399 -386.170678)
			)
		)
	)
	(zone
		(layers "F.Cu" "B.Cu" "In1.Cu" "In2.Cu" "In3.Cu" "In4.Cu" "In5.Cu" "In6.Cu"
			"In7.Cu" "In8.Cu" "In9.Cu" "In10.Cu" "In11.Cu" "In12.Cu" "In13.Cu" "In14.Cu"
			"In15.Cu" "In16.Cu"
		)
		(hatch none 0.5)
		(connect_pads
			(clearance 0)
		)
		(min_thickness 0.25)
		(keepout
			(tracks not_allowed)
			(vias allowed)
			(pads allowed)
			(copperpour not_allowed)
			(footprints allowed)
		)
		(placement
			(enabled no)
			(sheetname "")
		)
		(fill
			(thermal_gap 0.5)
			(thermal_bridge_width 0.5)
			(island_removal_mode 0)
		)
		(polygon
			(pts
				(arc
					(start 149.025102 -392.429238)
					(mid 148.644102 -392.048238)
					(end 148.263102 -392.429238)
				)
				(arc
					(start 148.263102 -393.292838)
					(mid 148.644102 -393.673838)
					(end 149.025102 -393.292838)
				)
			)
		)
	)
	(zone
		(layers "F.Cu" "B.Cu" "In1.Cu" "In2.Cu" "In3.Cu" "In4.Cu" "In5.Cu" "In6.Cu"
			"In7.Cu" "In8.Cu" "In9.Cu" "In10.Cu" "In11.Cu" "In12.Cu" "In13.Cu" "In14.Cu"
			"In15.Cu" "In16.Cu"
		)
		(hatch none 0.5)
		(connect_pads
			(clearance 0)
		)
		(min_thickness 0.25)
		(keepout
			(tracks not_allowed)
			(vias allowed)
			(pads allowed)
			(copperpour not_allowed)
			(footprints allowed)
		)
		(placement
			(enabled no)
			(sheetname "")
		)
		(fill
			(thermal_gap 0.5)
			(thermal_bridge_width 0.5)
			(island_removal_mode 0)
		)
		(polygon
			(pts
				(arc
					(start 163.064444 -371.11813)
					(mid 162.683444 -371.49913)
					(end 163.064444 -371.88013)
				)
				(arc
					(start 163.928044 -371.88013)
					(mid 164.309044 -371.49913)
					(end 163.928044 -371.11813)
				)
			)
		)
	)
	(zone
		(layers "F.Cu" "B.Cu" "In1.Cu" "In2.Cu" "In3.Cu" "In4.Cu" "In5.Cu" "In6.Cu"
			"In7.Cu" "In8.Cu" "In9.Cu" "In10.Cu" "In11.Cu" "In12.Cu" "In13.Cu" "In14.Cu"
			"In15.Cu" "In16.Cu"
		)
		(hatch none 0.5)
		(connect_pads
			(clearance 0)
		)
		(min_thickness 0.25)
		(keepout
			(tracks not_allowed)
			(vias allowed)
			(pads allowed)
			(copperpour not_allowed)
			(footprints allowed)
		)
		(placement
			(enabled no)
			(sheetname "")
		)
		(fill
			(thermal_gap 0.5)
			(thermal_bridge_width 0.5)
			(island_removal_mode 0)
		)
		(polygon
			(pts
				(arc
					(start 298.630086 -2.968244)
					(mid 299.061886 -3.400044)
					(end 299.493686 -2.968244)
				)
				(arc
					(start 299.493686 -2.104644)
					(mid 299.061886 -1.672844)
					(end 298.630086 -2.104644)
				)
			)
		)
	)
	(zone
		(layers "F.Cu" "B.Cu" "In1.Cu" "In2.Cu" "In3.Cu" "In4.Cu" "In5.Cu" "In6.Cu"
			"In7.Cu" "In8.Cu" "In9.Cu" "In10.Cu" "In11.Cu" "In12.Cu" "In13.Cu" "In14.Cu"
			"In15.Cu" "In16.Cu"
		)
		(hatch none 0.5)
		(connect_pads
			(clearance 0)
		)
		(min_thickness 0.25)
		(keepout
			(tracks not_allowed)
			(vias allowed)
			(pads allowed)
			(copperpour not_allowed)
			(footprints allowed)
		)
		(placement
			(enabled no)
			(sheetname "")
		)
		(fill
			(thermal_gap 0.5)
			(thermal_bridge_width 0.5)
			(island_removal_mode 0)
		)
		(polygon
			(pts
				(arc
					(start 161.964116 -389.634476)
					(mid 162.074087 -389.73553)
					(end 162.218878 -389.772144)
				)
				(arc
					(start 162.218878 -389.772144)
					(mid 162.434404 -389.68287)
					(end 162.523678 -389.467344)
				)
				(arc
					(start 162.523678 -389.467344)
					(mid 162.513341 -389.388605)
					(end 162.483038 -389.315198)
				)
				(arc
					(start 162.090608 -388.636256)
					(mid 161.978211 -388.514639)
					(end 161.818828 -388.469632)
				)
				(arc
					(start 161.818828 -388.469632)
					(mid 161.603302 -388.558906)
					(end 161.514028 -388.774432)
				)
				(arc
					(start 161.514028 -388.774432)
					(mid 161.523606 -388.850494)
					(end 161.551874 -388.921752)
				)
				(xy 161.94913 -389.609076) (xy 161.961322 -389.630412) (xy 161.963862 -389.63473)
			)
		)
	)
	(zone
		(layers "F.Cu" "B.Cu" "In1.Cu" "In2.Cu" "In3.Cu" "In4.Cu" "In5.Cu" "In6.Cu"
			"In7.Cu" "In8.Cu" "In9.Cu" "In10.Cu" "In11.Cu" "In12.Cu" "In13.Cu" "In14.Cu"
			"In15.Cu" "In16.Cu"
		)
		(hatch none 0.5)
		(connect_pads
			(clearance 0)
		)
		(min_thickness 0.25)
		(keepout
			(tracks not_allowed)
			(vias allowed)
			(pads allowed)
			(copperpour not_allowed)
			(footprints allowed)
		)
		(placement
			(enabled no)
			(sheetname "")
		)
		(fill
			(thermal_gap 0.5)
			(thermal_bridge_width 0.5)
			(island_removal_mode 0)
		)
		(polygon
			(pts
				(arc
					(start 64.997584 -392.429238)
					(mid 64.616584 -392.048238)
					(end 64.235584 -392.429238)
				)
				(arc
					(start 64.235584 -393.292838)
					(mid 64.616584 -393.673838)
					(end 64.997584 -393.292838)
				)
			)
		)
	)
	(zone
		(layers "F.Cu" "B.Cu" "In1.Cu" "In2.Cu" "In3.Cu" "In4.Cu" "In5.Cu" "In6.Cu"
			"In7.Cu" "In8.Cu" "In9.Cu" "In10.Cu" "In11.Cu" "In12.Cu" "In13.Cu" "In14.Cu"
			"In15.Cu" "In16.Cu"
		)
		(hatch none 0.5)
		(connect_pads
			(clearance 0)
		)
		(min_thickness 0.25)
		(keepout
			(tracks not_allowed)
			(vias allowed)
			(pads allowed)
			(copperpour not_allowed)
			(footprints allowed)
		)
		(placement
			(enabled no)
			(sheetname "")
		)
		(fill
			(thermal_gap 0.5)
			(thermal_bridge_width 0.5)
			(island_removal_mode 0)
		)
		(polygon
			(pts
				(arc
					(start 164.671756 -145.457926)
					(mid 165.052756 -145.076926)
					(end 164.671756 -144.695926)
				)
				(arc
					(start 163.681156 -144.695926)
					(mid 163.300156 -145.076926)
					(end 163.681156 -145.457926)
				)
			)
		)
	)
	(zone
		(layers "F.Cu" "B.Cu" "In1.Cu" "In2.Cu" "In3.Cu" "In4.Cu" "In5.Cu" "In6.Cu"
			"In7.Cu" "In8.Cu" "In9.Cu" "In10.Cu" "In11.Cu" "In12.Cu" "In13.Cu" "In14.Cu"
			"In15.Cu" "In16.Cu"
		)
		(hatch none 0.5)
		(connect_pads
			(clearance 0)
		)
		(min_thickness 0.25)
		(keepout
			(tracks not_allowed)
			(vias allowed)
			(pads allowed)
			(copperpour not_allowed)
			(footprints allowed)
		)
		(placement
			(enabled no)
			(sheetname "")
		)
		(fill
			(thermal_gap 0.5)
			(thermal_bridge_width 0.5)
			(island_removal_mode 0)
		)
		(polygon
			(pts
				(arc
					(start 52.572666 -418.77742)
					(mid 52.191666 -418.39642)
					(end 51.810666 -418.77742)
				)
				(arc
					(start 51.810666 -419.64102)
					(mid 52.191666 -420.02202)
					(end 52.572666 -419.64102)
				)
			)
		)
	)
	(zone
		(layers "F.Cu" "B.Cu" "In1.Cu" "In2.Cu" "In3.Cu" "In4.Cu" "In5.Cu" "In6.Cu"
			"In7.Cu" "In8.Cu" "In9.Cu" "In10.Cu" "In11.Cu" "In12.Cu" "In13.Cu" "In14.Cu"
			"In15.Cu" "In16.Cu"
		)
		(hatch none 0.5)
		(connect_pads
			(clearance 0)
		)
		(min_thickness 0.25)
		(keepout
			(tracks not_allowed)
			(vias allowed)
			(pads allowed)
			(copperpour not_allowed)
			(footprints allowed)
		)
		(placement
			(enabled no)
			(sheetname "")
		)
		(fill
			(thermal_gap 0.5)
			(thermal_bridge_width 0.5)
			(island_removal_mode 0)
		)
		(polygon
			(pts
				(arc
					(start 25.893522 -427.752002)
					(mid 25.512522 -427.371002)
					(end 25.131522 -427.752002)
				)
				(arc
					(start 25.131522 -428.615602)
					(mid 25.512522 -428.996602)
					(end 25.893522 -428.615602)
				)
			)
		)
	)
	(zone
		(layers "F.Cu" "B.Cu" "In1.Cu" "In2.Cu" "In3.Cu" "In4.Cu" "In5.Cu" "In6.Cu"
			"In7.Cu" "In8.Cu" "In9.Cu" "In10.Cu" "In11.Cu" "In12.Cu" "In13.Cu" "In14.Cu"
			"In15.Cu" "In16.Cu"
		)
		(hatch none 0.5)
		(connect_pads
			(clearance 0)
		)
		(min_thickness 0.25)
		(keepout
			(tracks not_allowed)
			(vias allowed)
			(pads allowed)
			(copperpour not_allowed)
			(footprints allowed)
		)
		(placement
			(enabled no)
			(sheetname "")
		)
		(fill
			(thermal_gap 0.5)
			(thermal_bridge_width 0.5)
			(island_removal_mode 0)
		)
		(polygon
			(pts
				(arc
					(start 82.350102 -371.11813)
					(mid 81.969102 -371.49913)
					(end 82.350102 -371.88013)
				)
				(arc
					(start 83.213702 -371.88013)
					(mid 83.594702 -371.49913)
					(end 83.213702 -371.11813)
				)
			)
		)
	)
	(zone
		(layers "F.Cu" "B.Cu" "In1.Cu" "In2.Cu" "In3.Cu" "In4.Cu" "In5.Cu" "In6.Cu"
			"In7.Cu" "In8.Cu" "In9.Cu" "In10.Cu" "In11.Cu" "In12.Cu" "In13.Cu" "In14.Cu"
			"In15.Cu" "In16.Cu"
		)
		(hatch none 0.5)
		(connect_pads
			(clearance 0)
		)
		(min_thickness 0.25)
		(keepout
			(tracks not_allowed)
			(vias allowed)
			(pads allowed)
			(copperpour not_allowed)
			(footprints allowed)
		)
		(placement
			(enabled no)
			(sheetname "")
		)
		(fill
			(thermal_gap 0.5)
			(thermal_bridge_width 0.5)
			(island_removal_mode 0)
		)
		(polygon
			(pts
				(arc
					(start 150.121366 -406.62352)
					(mid 149.740366 -407.00452)
					(end 150.121366 -407.38552)
				)
				(arc
					(start 150.984966 -407.38552)
					(mid 151.365966 -407.00452)
					(end 150.984966 -406.62352)
				)
			)
		)
	)
	(zone
		(layers "F.Cu" "B.Cu" "In1.Cu" "In2.Cu" "In3.Cu" "In4.Cu" "In5.Cu" "In6.Cu"
			"In7.Cu" "In8.Cu" "In9.Cu" "In10.Cu" "In11.Cu" "In12.Cu" "In13.Cu" "In14.Cu"
			"In15.Cu" "In16.Cu"
		)
		(hatch none 0.5)
		(connect_pads
			(clearance 0)
		)
		(min_thickness 0.25)
		(keepout
			(tracks not_allowed)
			(vias allowed)
			(pads allowed)
			(copperpour not_allowed)
			(footprints allowed)
		)
		(placement
			(enabled no)
			(sheetname "")
		)
		(fill
			(thermal_gap 0.5)
			(thermal_bridge_width 0.5)
			(island_removal_mode 0)
		)
		(polygon
			(pts
				(arc
					(start 330.339192 -384.35026)
					(mid 329.958192 -383.96926)
					(end 329.577192 -384.35026)
				)
				(arc
					(start 329.577192 -385.21386)
					(mid 329.958192 -385.59486)
					(end 330.339192 -385.21386)
				)
			)
		)
	)
	(zone
		(layers "F.Cu" "B.Cu" "In1.Cu" "In2.Cu" "In3.Cu" "In4.Cu" "In5.Cu" "In6.Cu"
			"In7.Cu" "In8.Cu" "In9.Cu" "In10.Cu" "In11.Cu" "In12.Cu" "In13.Cu" "In14.Cu"
			"In15.Cu" "In16.Cu"
		)
		(hatch none 0.5)
		(connect_pads
			(clearance 0)
		)
		(min_thickness 0.25)
		(keepout
			(tracks not_allowed)
			(vias allowed)
			(pads allowed)
			(copperpour not_allowed)
			(footprints allowed)
		)
		(placement
			(enabled no)
			(sheetname "")
		)
		(fill
			(thermal_gap 0.5)
			(thermal_bridge_width 0.5)
			(island_removal_mode 0)
		)
		(polygon
			(pts
				(arc
					(start 369.515644 -19.397726)
					(mid 368.507264 -20.406106)
					(end 369.515644 -21.414486)
				)
				(arc
					(start 369.541044 -21.414486)
					(mid 370.245096 -21.122858)
					(end 370.536724 -20.418806)
				)
				(arc
					(start 370.536724 -20.418806)
					(mid 370.237657 -19.696793)
					(end 369.515644 -19.397726)
				)
			)
		)
	)
	(zone
		(layers "F.Cu" "B.Cu" "In1.Cu" "In2.Cu" "In3.Cu" "In4.Cu" "In5.Cu" "In6.Cu"
			"In7.Cu" "In8.Cu" "In9.Cu" "In10.Cu" "In11.Cu" "In12.Cu" "In13.Cu" "In14.Cu"
			"In15.Cu" "In16.Cu"
		)
		(hatch none 0.5)
		(connect_pads
			(clearance 0)
		)
		(min_thickness 0.25)
		(keepout
			(tracks not_allowed)
			(vias allowed)
			(pads allowed)
			(copperpour not_allowed)
			(footprints allowed)
		)
		(placement
			(enabled no)
			(sheetname "")
		)
		(fill
			(thermal_gap 0.5)
			(thermal_bridge_width 0.5)
			(island_removal_mode 0)
		)
		(polygon
			(pts
				(arc
					(start 289.454336 -418.254688)
					(mid 289.835336 -418.635688)
					(end 290.216336 -418.254688)
				)
				(arc
					(start 290.216336 -417.391088)
					(mid 289.835336 -417.010088)
					(end 289.454336 -417.391088)
				)
			)
		)
	)
	(zone
		(layers "F.Cu" "B.Cu" "In1.Cu" "In2.Cu" "In3.Cu" "In4.Cu" "In5.Cu" "In6.Cu"
			"In7.Cu" "In8.Cu" "In9.Cu" "In10.Cu" "In11.Cu" "In12.Cu" "In13.Cu" "In14.Cu"
			"In15.Cu" "In16.Cu"
		)
		(hatch none 0.5)
		(connect_pads
			(clearance 0)
		)
		(min_thickness 0.25)
		(keepout
			(tracks not_allowed)
			(vias allowed)
			(pads allowed)
			(copperpour not_allowed)
			(footprints allowed)
		)
		(placement
			(enabled no)
			(sheetname "")
		)
		(fill
			(thermal_gap 0.5)
			(thermal_bridge_width 0.5)
			(island_removal_mode 0)
		)
		(polygon
			(pts
				(arc
					(start 90.679524 -404.08352)
					(mid 90.298524 -404.46452)
					(end 90.679524 -404.84552)
				)
				(arc
					(start 91.543124 -404.84552)
					(mid 91.924124 -404.46452)
					(end 91.543124 -404.08352)
				)
			)
		)
	)
	(zone
		(layers "F.Cu" "B.Cu" "In1.Cu" "In2.Cu" "In3.Cu" "In4.Cu" "In5.Cu" "In6.Cu"
			"In7.Cu" "In8.Cu" "In9.Cu" "In10.Cu" "In11.Cu" "In12.Cu" "In13.Cu" "In14.Cu"
			"In15.Cu" "In16.Cu"
		)
		(hatch none 0.5)
		(connect_pads
			(clearance 0)
		)
		(min_thickness 0.25)
		(keepout
			(tracks not_allowed)
			(vias allowed)
			(pads allowed)
			(copperpour not_allowed)
			(footprints allowed)
		)
		(placement
			(enabled no)
			(sheetname "")
		)
		(fill
			(thermal_gap 0.5)
			(thermal_bridge_width 0.5)
			(island_removal_mode 0)
		)
		(polygon
			(pts
				(arc
					(start 46.572678 -18.756122)
					(mid 46.191678 -19.137122)
					(end 46.572678 -19.518122)
				)
				(arc
					(start 47.436278 -19.518122)
					(mid 47.817278 -19.137122)
					(end 47.436278 -18.756122)
				)
			)
		)
	)
	(zone
		(layers "F.Cu" "B.Cu" "In1.Cu" "In2.Cu" "In3.Cu" "In4.Cu" "In5.Cu" "In6.Cu"
			"In7.Cu" "In8.Cu" "In9.Cu" "In10.Cu" "In11.Cu" "In12.Cu" "In13.Cu" "In14.Cu"
			"In15.Cu" "In16.Cu"
		)
		(hatch none 0.5)
		(connect_pads
			(clearance 0)
		)
		(min_thickness 0.25)
		(keepout
			(tracks not_allowed)
			(vias allowed)
			(pads allowed)
			(copperpour not_allowed)
			(footprints allowed)
		)
		(placement
			(enabled no)
			(sheetname "")
		)
		(fill
			(thermal_gap 0.5)
			(thermal_bridge_width 0.5)
			(island_removal_mode 0)
		)
		(polygon
			(pts
				(arc
					(start 312.983626 -412.46552)
					(mid 312.602626 -412.84652)
					(end 312.983626 -413.22752)
				)
				(arc
					(start 313.847226 -413.22752)
					(mid 314.228226 -412.84652)
					(end 313.847226 -412.46552)
				)
			)
		)
	)
	(zone
		(layers "F.Cu" "B.Cu" "In1.Cu" "In2.Cu" "In3.Cu" "In4.Cu" "In5.Cu" "In6.Cu"
			"In7.Cu" "In8.Cu" "In9.Cu" "In10.Cu" "In11.Cu" "In12.Cu" "In13.Cu" "In14.Cu"
			"In15.Cu" "In16.Cu"
		)
		(hatch none 0.5)
		(connect_pads
			(clearance 0)
		)
		(min_thickness 0.25)
		(keepout
			(tracks not_allowed)
			(vias allowed)
			(pads allowed)
			(copperpour not_allowed)
			(footprints allowed)
		)
		(placement
			(enabled no)
			(sheetname "")
		)
		(fill
			(thermal_gap 0.5)
			(thermal_bridge_width 0.5)
			(island_removal_mode 0)
		)
		(polygon
			(pts
				(arc
					(start 29.81579 -6.344158)
					(mid 29.43479 -6.725158)
					(end 29.81579 -7.106158)
				)
				(arc
					(start 30.67939 -7.106158)
					(mid 31.06039 -6.725158)
					(end 30.67939 -6.344158)
				)
			)
		)
	)
	(zone
		(layers "F.Cu" "B.Cu" "In1.Cu" "In2.Cu" "In3.Cu" "In4.Cu" "In5.Cu" "In6.Cu"
			"In7.Cu" "In8.Cu" "In9.Cu" "In10.Cu" "In11.Cu" "In12.Cu" "In13.Cu" "In14.Cu"
			"In15.Cu" "In16.Cu"
		)
		(hatch none 0.5)
		(connect_pads
			(clearance 0)
		)
		(min_thickness 0.25)
		(keepout
			(tracks not_allowed)
			(vias allowed)
			(pads allowed)
			(copperpour not_allowed)
			(footprints allowed)
		)
		(placement
			(enabled no)
			(sheetname "")
		)
		(fill
			(thermal_gap 0.5)
			(thermal_bridge_width 0.5)
			(island_removal_mode 0)
		)
		(polygon
			(pts
				(arc
					(start 424.16984 -377.03633)
					(mid 423.78884 -377.41733)
					(end 424.16984 -377.79833)
				)
				(arc
					(start 425.03344 -377.79833)
					(mid 425.41444 -377.41733)
					(end 425.03344 -377.03633)
				)
			)
		)
	)
	(zone
		(layers "F.Cu" "B.Cu" "In1.Cu" "In2.Cu" "In3.Cu" "In4.Cu" "In5.Cu" "In6.Cu"
			"In7.Cu" "In8.Cu" "In9.Cu" "In10.Cu" "In11.Cu" "In12.Cu" "In13.Cu" "In14.Cu"
			"In15.Cu" "In16.Cu"
		)
		(hatch none 0.5)
		(connect_pads
			(clearance 0)
		)
		(min_thickness 0.25)
		(keepout
			(tracks not_allowed)
			(vias allowed)
			(pads allowed)
			(copperpour not_allowed)
			(footprints allowed)
		)
		(placement
			(enabled no)
			(sheetname "")
		)
		(fill
			(thermal_gap 0.5)
			(thermal_bridge_width 0.5)
			(island_removal_mode 0)
		)
		(polygon
			(pts
				(arc
					(start 154.764232 -389.634476)
					(mid 154.874203 -389.73553)
					(end 155.018994 -389.772144)
				)
				(arc
					(start 155.018994 -389.772144)
					(mid 155.23452 -389.68287)
					(end 155.323794 -389.467344)
				)
				(arc
					(start 155.323794 -389.467344)
					(mid 155.313457 -389.388605)
					(end 155.283154 -389.315198)
				)
				(arc
					(start 154.890724 -388.636256)
					(mid 154.778327 -388.514639)
					(end 154.618944 -388.469632)
				)
				(arc
					(start 154.618944 -388.469632)
					(mid 154.403418 -388.558906)
					(end 154.314144 -388.774432)
				)
				(arc
					(start 154.314144 -388.774432)
					(mid 154.323722 -388.850494)
					(end 154.35199 -388.921752)
				)
				(xy 154.749246 -389.609076) (xy 154.761438 -389.630412) (xy 154.763978 -389.63473)
			)
		)
	)
	(zone
		(layers "F.Cu" "B.Cu" "In1.Cu" "In2.Cu" "In3.Cu" "In4.Cu" "In5.Cu" "In6.Cu"
			"In7.Cu" "In8.Cu" "In9.Cu" "In10.Cu" "In11.Cu" "In12.Cu" "In13.Cu" "In14.Cu"
			"In15.Cu" "In16.Cu"
		)
		(hatch none 0.5)
		(connect_pads
			(clearance 0)
		)
		(min_thickness 0.25)
		(keepout
			(tracks not_allowed)
			(vias allowed)
			(pads allowed)
			(copperpour not_allowed)
			(footprints allowed)
		)
		(placement
			(enabled no)
			(sheetname "")
		)
		(fill
			(thermal_gap 0.5)
			(thermal_bridge_width 0.5)
			(island_removal_mode 0)
		)
		(polygon
			(pts
				(xy 520.113768 -310.208422) (xy 530.113748 -310.208422) (xy 529.808948 -309.903622) (xy 520.418568 -309.903622)
			)
		)
	)
	(zone
		(layers "F.Cu" "B.Cu" "In1.Cu" "In2.Cu" "In3.Cu" "In4.Cu" "In5.Cu" "In6.Cu"
			"In7.Cu" "In8.Cu" "In9.Cu" "In10.Cu" "In11.Cu" "In12.Cu" "In13.Cu" "In14.Cu"
			"In15.Cu" "In16.Cu"
		)
		(hatch none 0.5)
		(connect_pads
			(clearance 0)
		)
		(min_thickness 0.25)
		(keepout
			(tracks not_allowed)
			(vias allowed)
			(pads allowed)
			(copperpour not_allowed)
			(footprints allowed)
		)
		(placement
			(enabled no)
			(sheetname "")
		)
		(fill
			(thermal_gap 0.5)
			(thermal_bridge_width 0.5)
			(island_removal_mode 0)
		)
		(polygon
			(pts
				(arc
					(start 171.286424 -376.093228)
					(mid 170.905424 -375.712228)
					(end 170.524424 -376.093228)
				)
				(arc
					(start 170.524424 -376.956828)
					(mid 170.905424 -377.337828)
					(end 171.286424 -376.956828)
				)
			)
		)
	)
	(zone
		(layers "F.Cu" "B.Cu" "In1.Cu" "In2.Cu" "In3.Cu" "In4.Cu" "In5.Cu" "In6.Cu"
			"In7.Cu" "In8.Cu" "In9.Cu" "In10.Cu" "In11.Cu" "In12.Cu" "In13.Cu" "In14.Cu"
			"In15.Cu" "In16.Cu"
		)
		(hatch none 0.5)
		(connect_pads
			(clearance 0)
		)
		(min_thickness 0.25)
		(keepout
			(tracks not_allowed)
			(vias allowed)
			(pads allowed)
			(copperpour not_allowed)
			(footprints allowed)
		)
		(placement
			(enabled no)
			(sheetname "")
		)
		(fill
			(thermal_gap 0.5)
			(thermal_bridge_width 0.5)
			(island_removal_mode 0)
		)
		(polygon
			(pts
				(arc
					(start 71.330312 -6.20649)
					(mid 70.949312 -6.58749)
					(end 71.330312 -6.96849)
				)
				(arc
					(start 72.193912 -6.96849)
					(mid 72.574912 -6.58749)
					(end 72.193912 -6.20649)
				)
			)
		)
	)
	(zone
		(layers "F.Cu" "B.Cu" "In1.Cu" "In2.Cu" "In3.Cu" "In4.Cu" "In5.Cu" "In6.Cu"
			"In7.Cu" "In8.Cu" "In9.Cu" "In10.Cu" "In11.Cu" "In12.Cu" "In13.Cu" "In14.Cu"
			"In15.Cu" "In16.Cu"
		)
		(hatch none 0.5)
		(connect_pads
			(clearance 0)
		)
		(min_thickness 0.25)
		(keepout
			(tracks not_allowed)
			(vias allowed)
			(pads allowed)
			(copperpour not_allowed)
			(footprints allowed)
		)
		(placement
			(enabled no)
			(sheetname "")
		)
		(fill
			(thermal_gap 0.5)
			(thermal_bridge_width 0.5)
			(island_removal_mode 0)
		)
		(polygon
			(pts
				(arc
					(start 61.578744 -406.62352)
					(mid 61.197744 -407.00452)
					(end 61.578744 -407.38552)
				)
				(arc
					(start 62.442344 -407.38552)
					(mid 62.823344 -407.00452)
					(end 62.442344 -406.62352)
				)
			)
		)
	)
	(zone
		(layers "F.Cu" "B.Cu" "In1.Cu" "In2.Cu" "In3.Cu" "In4.Cu" "In5.Cu" "In6.Cu"
			"In7.Cu" "In8.Cu" "In9.Cu" "In10.Cu" "In11.Cu" "In12.Cu" "In13.Cu" "In14.Cu"
			"In15.Cu" "In16.Cu"
		)
		(hatch none 0.5)
		(connect_pads
			(clearance 0)
		)
		(min_thickness 0.25)
		(keepout
			(tracks not_allowed)
			(vias allowed)
			(pads allowed)
			(copperpour not_allowed)
			(footprints allowed)
		)
		(placement
			(enabled no)
			(sheetname "")
		)
		(fill
			(thermal_gap 0.5)
			(thermal_bridge_width 0.5)
			(island_removal_mode 0)
		)
		(polygon
			(pts
				(arc
					(start 122.552206 -409.649168)
					(mid 122.171206 -410.030168)
					(end 122.552206 -410.411168)
				)
				(arc
					(start 123.415806 -410.411168)
					(mid 123.796806 -410.030168)
					(end 123.415806 -409.649168)
				)
			)
		)
	)
	(zone
		(layers "F.Cu" "B.Cu" "In1.Cu" "In2.Cu" "In3.Cu" "In4.Cu" "In5.Cu" "In6.Cu"
			"In7.Cu" "In8.Cu" "In9.Cu" "In10.Cu" "In11.Cu" "In12.Cu" "In13.Cu" "In14.Cu"
			"In15.Cu" "In16.Cu"
		)
		(hatch none 0.5)
		(connect_pads
			(clearance 0)
		)
		(min_thickness 0.25)
		(keepout
			(tracks not_allowed)
			(vias allowed)
			(pads allowed)
			(copperpour not_allowed)
			(footprints allowed)
		)
		(placement
			(enabled no)
			(sheetname "")
		)
		(fill
			(thermal_gap 0.5)
			(thermal_bridge_width 0.5)
			(island_removal_mode 0)
		)
		(polygon
			(pts
				(arc
					(start 397.439388 -384.35026)
					(mid 397.058388 -383.96926)
					(end 396.677388 -384.35026)
				)
				(arc
					(start 396.677388 -385.21386)
					(mid 397.058388 -385.59486)
					(end 397.439388 -385.21386)
				)
			)
		)
	)
	(zone
		(layers "F.Cu" "B.Cu" "In1.Cu" "In2.Cu" "In3.Cu" "In4.Cu" "In5.Cu" "In6.Cu"
			"In7.Cu" "In8.Cu" "In9.Cu" "In10.Cu" "In11.Cu" "In12.Cu" "In13.Cu" "In14.Cu"
			"In15.Cu" "In16.Cu"
		)
		(hatch none 0.5)
		(connect_pads
			(clearance 0)
		)
		(min_thickness 0.25)
		(keepout
			(tracks not_allowed)
			(vias allowed)
			(pads allowed)
			(copperpour not_allowed)
			(footprints allowed)
		)
		(placement
			(enabled no)
			(sheetname "")
		)
		(fill
			(thermal_gap 0.5)
			(thermal_bridge_width 0.5)
			(island_removal_mode 0)
		)
		(polygon
			(pts
				(arc
					(start 287.49498 -74.760836)
					(mid 293.00297 -80.268826)
					(end 298.51096 -74.760836)
				)
				(arc
					(start 298.51096 -66.060828)
					(mid 293.00297 -60.552838)
					(end 287.49498 -66.060828)
				)
			)
		)
	)
	(zone
		(layers "F.Cu" "B.Cu" "In1.Cu" "In2.Cu" "In3.Cu" "In4.Cu" "In5.Cu" "In6.Cu"
			"In7.Cu" "In8.Cu" "In9.Cu" "In10.Cu" "In11.Cu" "In12.Cu" "In13.Cu" "In14.Cu"
			"In15.Cu" "In16.Cu"
		)
		(hatch none 0.5)
		(connect_pads
			(clearance 0)
		)
		(min_thickness 0.25)
		(keepout
			(tracks not_allowed)
			(vias allowed)
			(pads allowed)
			(copperpour not_allowed)
			(footprints allowed)
		)
		(placement
			(enabled no)
			(sheetname "")
		)
		(fill
			(thermal_gap 0.5)
			(thermal_bridge_width 0.5)
			(island_removal_mode 0)
		)
		(polygon
			(pts
				(arc
					(start 409.591764 -18.75536)
					(mid 409.210764 -19.13636)
					(end 409.591764 -19.51736)
				)
				(arc
					(start 410.455364 -19.51736)
					(mid 410.836364 -19.13636)
					(end 410.455364 -18.75536)
				)
			)
		)
	)
	(zone
		(layers "F.Cu" "B.Cu" "In1.Cu" "In2.Cu" "In3.Cu" "In4.Cu" "In5.Cu" "In6.Cu"
			"In7.Cu" "In8.Cu" "In9.Cu" "In10.Cu" "In11.Cu" "In12.Cu" "In13.Cu" "In14.Cu"
			"In15.Cu" "In16.Cu"
		)
		(hatch none 0.5)
		(connect_pads
			(clearance 0)
		)
		(min_thickness 0.25)
		(keepout
			(tracks not_allowed)
			(vias allowed)
			(pads allowed)
			(copperpour not_allowed)
			(footprints allowed)
		)
		(placement
			(enabled no)
			(sheetname "")
		)
		(fill
			(thermal_gap 0.5)
			(thermal_bridge_width 0.5)
			(island_removal_mode 0)
		)
		(polygon
			(pts
				(arc
					(start 364.91164 -389.88746)
					(mid 364.53064 -389.50646)
					(end 364.14964 -389.88746)
				)
				(arc
					(start 364.14964 -390.75106)
					(mid 364.53064 -391.13206)
					(end 364.91164 -390.75106)
				)
			)
		)
	)
	(zone
		(layers "F.Cu" "B.Cu" "In1.Cu" "In2.Cu" "In3.Cu" "In4.Cu" "In5.Cu" "In6.Cu"
			"In7.Cu" "In8.Cu" "In9.Cu" "In10.Cu" "In11.Cu" "In12.Cu" "In13.Cu" "In14.Cu"
			"In15.Cu" "In16.Cu"
		)
		(hatch none 0.5)
		(connect_pads
			(clearance 0)
		)
		(min_thickness 0.25)
		(keepout
			(tracks not_allowed)
			(vias allowed)
			(pads allowed)
			(copperpour not_allowed)
			(footprints allowed)
		)
		(placement
			(enabled no)
			(sheetname "")
		)
		(fill
			(thermal_gap 0.5)
			(thermal_bridge_width 0.5)
			(island_removal_mode 0)
		)
		(polygon
			(pts
				(arc
					(start 306.597304 -400.811238)
					(mid 306.216304 -400.430238)
					(end 305.835304 -400.811238)
				)
				(arc
					(start 305.835304 -401.674838)
					(mid 306.216304 -402.055838)
					(end 306.597304 -401.674838)
				)
			)
		)
	)
	(zone
		(layers "F.Cu" "B.Cu" "In1.Cu" "In2.Cu" "In3.Cu" "In4.Cu" "In5.Cu" "In6.Cu"
			"In7.Cu" "In8.Cu" "In9.Cu" "In10.Cu" "In11.Cu" "In12.Cu" "In13.Cu" "In14.Cu"
			"In15.Cu" "In16.Cu"
		)
		(hatch none 0.5)
		(connect_pads
			(clearance 0)
		)
		(min_thickness 0.25)
		(keepout
			(tracks not_allowed)
			(vias allowed)
			(pads allowed)
			(copperpour not_allowed)
			(footprints allowed)
		)
		(placement
			(enabled no)
			(sheetname "")
		)
		(fill
			(thermal_gap 0.5)
			(thermal_bridge_width 0.5)
			(island_removal_mode 0)
		)
		(polygon
			(pts
				(arc
					(start 122.236484 -389.634476)
					(mid 122.346455 -389.73553)
					(end 122.491246 -389.772144)
				)
				(arc
					(start 122.491246 -389.772144)
					(mid 122.706772 -389.68287)
					(end 122.796046 -389.467344)
				)
				(arc
					(start 122.796046 -389.467344)
					(mid 122.785709 -389.388605)
					(end 122.755406 -389.315198)
				)
				(arc
					(start 122.362976 -388.636256)
					(mid 122.250579 -388.514639)
					(end 122.091196 -388.469632)
				)
				(arc
					(start 122.091196 -388.469632)
					(mid 121.87567 -388.558906)
					(end 121.786396 -388.774432)
				)
				(arc
					(start 121.786396 -388.774432)
					(mid 121.795974 -388.850494)
					(end 121.824242 -388.921752)
				)
				(xy 122.221498 -389.609076) (xy 122.23369 -389.630412) (xy 122.23623 -389.63473)
			)
		)
	)
	(zone
		(layers "F.Cu" "B.Cu" "In1.Cu" "In2.Cu" "In3.Cu" "In4.Cu" "In5.Cu" "In6.Cu"
			"In7.Cu" "In8.Cu" "In9.Cu" "In10.Cu" "In11.Cu" "In12.Cu" "In13.Cu" "In14.Cu"
			"In15.Cu" "In16.Cu"
		)
		(hatch none 0.5)
		(connect_pads
			(clearance 0)
		)
		(min_thickness 0.25)
		(keepout
			(tracks not_allowed)
			(vias allowed)
			(pads allowed)
			(copperpour not_allowed)
			(footprints allowed)
		)
		(placement
			(enabled no)
			(sheetname "")
		)
		(fill
			(thermal_gap 0.5)
			(thermal_bridge_width 0.5)
			(island_removal_mode 0)
		)
		(polygon
			(pts
				(arc
					(start 140.27912 -31.65856)
					(mid 140.66012 -32.03956)
					(end 141.04112 -31.65856)
				)
				(arc
					(start 141.04112 -30.79496)
					(mid 140.66012 -30.41396)
					(end 140.27912 -30.79496)
				)
			)
		)
	)
	(zone
		(layers "F.Cu" "B.Cu" "In1.Cu" "In2.Cu" "In3.Cu" "In4.Cu" "In5.Cu" "In6.Cu"
			"In7.Cu" "In8.Cu" "In9.Cu" "In10.Cu" "In11.Cu" "In12.Cu" "In13.Cu" "In14.Cu"
			"In15.Cu" "In16.Cu"
		)
		(hatch none 0.5)
		(connect_pads
			(clearance 0)
		)
		(min_thickness 0.25)
		(keepout
			(tracks not_allowed)
			(vias allowed)
			(pads allowed)
			(copperpour not_allowed)
			(footprints allowed)
		)
		(placement
			(enabled no)
			(sheetname "")
		)
		(fill
			(thermal_gap 0.5)
			(thermal_bridge_width 0.5)
			(island_removal_mode 0)
		)
		(polygon
			(pts
				(arc
					(start 317.578486 -415.00552)
					(mid 317.197486 -415.38652)
					(end 317.578486 -415.76752)
				)
				(arc
					(start 318.442086 -415.76752)
					(mid 318.823086 -415.38652)
					(end 318.442086 -415.00552)
				)
			)
		)
	)
	(zone
		(layers "F.Cu" "B.Cu" "In1.Cu" "In2.Cu" "In3.Cu" "In4.Cu" "In5.Cu" "In6.Cu"
			"In7.Cu" "In8.Cu" "In9.Cu" "In10.Cu" "In11.Cu" "In12.Cu" "In13.Cu" "In14.Cu"
			"In15.Cu" "In16.Cu"
		)
		(hatch none 0.5)
		(connect_pads
			(clearance 0)
		)
		(min_thickness 0.25)
		(keepout
			(tracks not_allowed)
			(vias allowed)
			(pads allowed)
			(copperpour not_allowed)
			(footprints allowed)
		)
		(placement
			(enabled no)
			(sheetname "")
		)
		(fill
			(thermal_gap 0.5)
			(thermal_bridge_width 0.5)
			(island_removal_mode 0)
		)
		(polygon
			(pts
				(arc
					(start 54.988714 -17.232122)
					(mid 54.607714 -17.613122)
					(end 54.988714 -17.994122)
				)
				(arc
					(start 55.852314 -17.994122)
					(mid 56.233314 -17.613122)
					(end 55.852314 -17.232122)
				)
			)
		)
	)
	(zone
		(layers "F.Cu" "B.Cu" "In1.Cu" "In2.Cu" "In3.Cu" "In4.Cu" "In5.Cu" "In6.Cu"
			"In7.Cu" "In8.Cu" "In9.Cu" "In10.Cu" "In11.Cu" "In12.Cu" "In13.Cu" "In14.Cu"
			"In15.Cu" "In16.Cu"
		)
		(hatch none 0.5)
		(connect_pads
			(clearance 0)
		)
		(min_thickness 0.25)
		(keepout
			(tracks not_allowed)
			(vias allowed)
			(pads allowed)
			(copperpour not_allowed)
			(footprints allowed)
		)
		(placement
			(enabled no)
			(sheetname "")
		)
		(fill
			(thermal_gap 0.5)
			(thermal_bridge_width 0.5)
			(island_removal_mode 0)
		)
		(polygon
			(pts
				(arc
					(start 128.497584 -392.429238)
					(mid 128.116584 -392.048238)
					(end 127.735584 -392.429238)
				)
				(arc
					(start 127.735584 -393.292838)
					(mid 128.116584 -393.673838)
					(end 128.497584 -393.292838)
				)
			)
		)
	)
	(zone
		(layers "F.Cu" "B.Cu" "In1.Cu" "In2.Cu" "In3.Cu" "In4.Cu" "In5.Cu" "In6.Cu"
			"In7.Cu" "In8.Cu" "In9.Cu" "In10.Cu" "In11.Cu" "In12.Cu" "In13.Cu" "In14.Cu"
			"In15.Cu" "In16.Cu"
		)
		(hatch none 0.5)
		(connect_pads
			(clearance 0)
		)
		(min_thickness 0.25)
		(keepout
			(tracks not_allowed)
			(vias allowed)
			(pads allowed)
			(copperpour not_allowed)
			(footprints allowed)
		)
		(placement
			(enabled no)
			(sheetname "")
		)
		(fill yes
			(thermal_gap 0.5)
			(thermal_bridge_width 0.5)
			(island_removal_mode 0)
		)
		(polygon
			(pts
				(arc
					(start 373.436388 -394.552424)
					(mid 373.546359 -394.653478)
					(end 373.69115 -394.690092)
				)
				(arc
					(start 373.69115 -394.690092)
					(mid 373.906676 -394.600818)
					(end 373.99595 -394.385292)
				)
				(arc
					(start 373.99595 -394.385292)
					(mid 373.985613 -394.306553)
					(end 373.95531 -394.233146)
				)
				(arc
					(start 373.56288 -393.554204)
					(mid 373.450483 -393.432587)
					(end 373.2911 -393.38758)
				)
				(arc
					(start 373.2911 -393.38758)
					(mid 373.075574 -393.476854)
					(end 372.9863 -393.69238)
				)
				(arc
					(start 372.9863 -393.69238)
					(mid 372.995878 -393.768442)
					(end 373.024146 -393.8397)
				)
				(xy 373.421402 -394.527024) (xy 373.433594 -394.54836) (xy 373.436134 -394.552678)
			)
		)
	)
	(zone
		(layers "F.Cu" "B.Cu" "In1.Cu" "In2.Cu" "In3.Cu" "In4.Cu" "In5.Cu" "In6.Cu"
			"In7.Cu" "In8.Cu" "In9.Cu" "In10.Cu" "In11.Cu" "In12.Cu" "In13.Cu" "In14.Cu"
			"In15.Cu" "In16.Cu"
		)
		(hatch none 0.5)
		(connect_pads
			(clearance 0)
		)
		(min_thickness 0.25)
		(keepout
			(tracks not_allowed)
			(vias allowed)
			(pads allowed)
			(copperpour not_allowed)
			(footprints allowed)
		)
		(placement
			(enabled no)
			(sheetname "")
		)
		(fill
			(thermal_gap 0.5)
			(thermal_bridge_width 0.5)
			(island_removal_mode 0)
		)
		(polygon
			(pts
				(arc
					(start 128.236472 -389.634476)
					(mid 128.346443 -389.73553)
					(end 128.491234 -389.772144)
				)
				(arc
					(start 128.491234 -389.772144)
					(mid 128.70676 -389.68287)
					(end 128.796034 -389.467344)
				)
				(arc
					(start 128.796034 -389.467344)
					(mid 128.785697 -389.388605)
					(end 128.755394 -389.315198)
				)
				(arc
					(start 128.362964 -388.636256)
					(mid 128.250567 -388.514639)
					(end 128.091184 -388.469632)
				)
				(arc
					(start 128.091184 -388.469632)
					(mid 127.875658 -388.558906)
					(end 127.786384 -388.774432)
				)
				(arc
					(start 127.786384 -388.774432)
					(mid 127.795962 -388.850494)
					(end 127.82423 -388.921752)
				)
				(xy 128.221486 -389.609076) (xy 128.233678 -389.630412) (xy 128.236218 -389.63473)
			)
		)
	)
	(zone
		(layers "F.Cu" "B.Cu" "In1.Cu" "In2.Cu" "In3.Cu" "In4.Cu" "In5.Cu" "In6.Cu"
			"In7.Cu" "In8.Cu" "In9.Cu" "In10.Cu" "In11.Cu" "In12.Cu" "In13.Cu" "In14.Cu"
			"In15.Cu" "In16.Cu"
		)
		(hatch none 0.5)
		(connect_pads
			(clearance 0)
		)
		(min_thickness 0.25)
		(keepout
			(tracks not_allowed)
			(vias allowed)
			(pads allowed)
			(copperpour not_allowed)
			(footprints allowed)
		)
		(placement
			(enabled no)
			(sheetname "")
		)
		(fill
			(thermal_gap 0.5)
			(thermal_bridge_width 0.5)
			(island_removal_mode 0)
		)
		(polygon
			(pts
				(arc
					(start 132.238496 -368.65433)
					(mid 131.857496 -369.03533)
					(end 132.238496 -369.41633)
				)
				(arc
					(start 133.102096 -369.41633)
					(mid 133.483096 -369.03533)
					(end 133.102096 -368.65433)
				)
			)
		)
	)
	(zone
		(layers "F.Cu" "B.Cu" "In1.Cu" "In2.Cu" "In3.Cu" "In4.Cu" "In5.Cu" "In6.Cu"
			"In7.Cu" "In8.Cu" "In9.Cu" "In10.Cu" "In11.Cu" "In12.Cu" "In13.Cu" "In14.Cu"
			"In15.Cu" "In16.Cu"
		)
		(hatch none 0.5)
		(connect_pads
			(clearance 0)
		)
		(min_thickness 0.25)
		(keepout
			(tracks not_allowed)
			(vias allowed)
			(pads allowed)
			(copperpour not_allowed)
			(footprints allowed)
		)
		(placement
			(enabled no)
			(sheetname "")
		)
		(fill yes
			(thermal_gap 0.5)
			(thermal_bridge_width 0.5)
			(island_removal_mode 0)
		)
		(polygon
			(pts
				(arc
					(start 416.764216 -394.552424)
					(mid 416.874187 -394.653478)
					(end 417.018978 -394.690092)
				)
				(arc
					(start 417.018978 -394.690092)
					(mid 417.234504 -394.600818)
					(end 417.323778 -394.385292)
				)
				(arc
					(start 417.323778 -394.385292)
					(mid 417.313441 -394.306553)
					(end 417.283138 -394.233146)
				)
				(arc
					(start 416.890708 -393.554204)
					(mid 416.778311 -393.432587)
					(end 416.618928 -393.38758)
				)
				(arc
					(start 416.618928 -393.38758)
					(mid 416.403402 -393.476854)
					(end 416.314128 -393.69238)
				)
				(arc
					(start 416.314128 -393.69238)
					(mid 416.323706 -393.768442)
					(end 416.351974 -393.8397)
				)
				(xy 416.74923 -394.527024) (xy 416.761422 -394.54836) (xy 416.763962 -394.552678)
			)
		)
	)
	(zone
		(layers "F.Cu" "B.Cu" "In1.Cu" "In2.Cu" "In3.Cu" "In4.Cu" "In5.Cu" "In6.Cu"
			"In7.Cu" "In8.Cu" "In9.Cu" "In10.Cu" "In11.Cu" "In12.Cu" "In13.Cu" "In14.Cu"
			"In15.Cu" "In16.Cu"
		)
		(hatch none 0.5)
		(connect_pads
			(clearance 0)
		)
		(min_thickness 0.25)
		(keepout
			(tracks not_allowed)
			(vias allowed)
			(pads allowed)
			(copperpour not_allowed)
			(footprints allowed)
		)
		(placement
			(enabled no)
			(sheetname "")
		)
		(fill
			(thermal_gap 0.5)
			(thermal_bridge_width 0.5)
			(island_removal_mode 0)
		)
		(polygon
			(pts
				(arc
					(start 372.49735 -400.811238)
					(mid 372.11635 -400.430238)
					(end 371.73535 -400.811238)
				)
				(arc
					(start 371.73535 -401.674838)
					(mid 372.11635 -402.055838)
					(end 372.49735 -401.674838)
				)
			)
		)
	)
	(zone
		(layers "F.Cu" "B.Cu" "In1.Cu" "In2.Cu" "In3.Cu" "In4.Cu" "In5.Cu" "In6.Cu"
			"In7.Cu" "In8.Cu" "In9.Cu" "In10.Cu" "In11.Cu" "In12.Cu" "In13.Cu" "In14.Cu"
			"In15.Cu" "In16.Cu"
		)
		(hatch none 0.5)
		(connect_pads
			(clearance 0)
		)
		(min_thickness 0.25)
		(keepout
			(tracks not_allowed)
			(vias allowed)
			(pads allowed)
			(copperpour not_allowed)
			(footprints allowed)
		)
		(placement
			(enabled no)
			(sheetname "")
		)
		(fill
			(thermal_gap 0.5)
			(thermal_bridge_width 0.5)
			(island_removal_mode 0)
		)
		(polygon
			(pts
				(arc
					(start 415.311082 -415.00552)
					(mid 414.930082 -415.38652)
					(end 415.311082 -415.76752)
				)
				(arc
					(start 416.174682 -415.76752)
					(mid 416.555682 -415.38652)
					(end 416.174682 -415.00552)
				)
			)
		)
	)
	(zone
		(layers "F.Cu" "B.Cu" "In1.Cu" "In2.Cu" "In3.Cu" "In4.Cu" "In5.Cu" "In6.Cu"
			"In7.Cu" "In8.Cu" "In9.Cu" "In10.Cu" "In11.Cu" "In12.Cu" "In13.Cu" "In14.Cu"
			"In15.Cu" "In16.Cu"
		)
		(hatch none 0.5)
		(connect_pads
			(clearance 0)
		)
		(min_thickness 0.25)
		(keepout
			(tracks not_allowed)
			(vias allowed)
			(pads allowed)
			(copperpour not_allowed)
			(footprints allowed)
		)
		(placement
			(enabled no)
			(sheetname "")
		)
		(fill
			(thermal_gap 0.5)
			(thermal_bridge_width 0.5)
			(island_removal_mode 0)
		)
		(polygon
			(pts
				(arc
					(start 410.764228 -398.016476)
					(mid 410.874199 -398.11753)
					(end 411.01899 -398.154144)
				)
				(arc
					(start 411.01899 -398.154144)
					(mid 411.234516 -398.06487)
					(end 411.32379 -397.849344)
				)
				(arc
					(start 411.32379 -397.849344)
					(mid 411.313453 -397.770605)
					(end 411.28315 -397.697198)
				)
				(arc
					(start 410.89072 -397.018256)
					(mid 410.778323 -396.896639)
					(end 410.61894 -396.851632)
				)
				(arc
					(start 410.61894 -396.851632)
					(mid 410.403414 -396.940906)
					(end 410.31414 -397.156432)
				)
				(arc
					(start 410.31414 -397.156432)
					(mid 410.323718 -397.232494)
					(end 410.351986 -397.303752)
				)
				(xy 410.749242 -397.991076) (xy 410.761434 -398.012412) (xy 410.763974 -398.01673)
			)
		)
	)
	(zone
		(layers "F.Cu" "B.Cu" "In1.Cu" "In2.Cu" "In3.Cu" "In4.Cu" "In5.Cu" "In6.Cu"
			"In7.Cu" "In8.Cu" "In9.Cu" "In10.Cu" "In11.Cu" "In12.Cu" "In13.Cu" "In14.Cu"
			"In15.Cu" "In16.Cu"
		)
		(hatch none 0.5)
		(connect_pads
			(clearance 0)
		)
		(min_thickness 0.25)
		(keepout
			(tracks not_allowed)
			(vias allowed)
			(pads allowed)
			(copperpour not_allowed)
			(footprints allowed)
		)
		(placement
			(enabled no)
			(sheetname "")
		)
		(fill
			(thermal_gap 0.5)
			(thermal_bridge_width 0.5)
			(island_removal_mode 0)
		)
		(polygon
			(pts
				(arc
					(start 366.115092 -379.50013)
					(mid 365.734092 -379.88113)
					(end 366.115092 -380.26213)
				)
				(arc
					(start 366.978692 -380.26213)
					(mid 367.359692 -379.88113)
					(end 366.978692 -379.50013)
				)
			)
		)
	)
	(zone
		(layers "F.Cu" "B.Cu" "In1.Cu" "In2.Cu" "In3.Cu" "In4.Cu" "In5.Cu" "In6.Cu"
			"In7.Cu" "In8.Cu" "In9.Cu" "In10.Cu" "In11.Cu" "In12.Cu" "In13.Cu" "In14.Cu"
			"In15.Cu" "In16.Cu"
		)
		(hatch none 0.5)
		(connect_pads
			(clearance 0)
		)
		(min_thickness 0.25)
		(keepout
			(tracks not_allowed)
			(vias allowed)
			(pads allowed)
			(copperpour not_allowed)
			(footprints allowed)
		)
		(placement
			(enabled no)
			(sheetname "")
		)
		(fill
			(thermal_gap 0.5)
			(thermal_bridge_width 0.5)
			(island_removal_mode 0)
		)
		(polygon
			(pts
				(arc
					(start 55.136542 -389.634476)
					(mid 55.246513 -389.73553)
					(end 55.391304 -389.772144)
				)
				(arc
					(start 55.391304 -389.772144)
					(mid 55.60683 -389.68287)
					(end 55.696104 -389.467344)
				)
				(arc
					(start 55.696104 -389.467344)
					(mid 55.685767 -389.388605)
					(end 55.655464 -389.315198)
				)
				(arc
					(start 55.263034 -388.636256)
					(mid 55.150637 -388.514639)
					(end 54.991254 -388.469632)
				)
				(arc
					(start 54.991254 -388.469632)
					(mid 54.775728 -388.558906)
					(end 54.686454 -388.774432)
				)
				(arc
					(start 54.686454 -388.774432)
					(mid 54.696032 -388.850494)
					(end 54.7243 -388.921752)
				)
				(xy 55.121556 -389.609076) (xy 55.133748 -389.630412) (xy 55.136288 -389.63473)
			)
		)
	)
	(zone
		(layers "F.Cu" "B.Cu" "In1.Cu" "In2.Cu" "In3.Cu" "In4.Cu" "In5.Cu" "In6.Cu"
			"In7.Cu" "In8.Cu" "In9.Cu" "In10.Cu" "In11.Cu" "In12.Cu" "In13.Cu" "In14.Cu"
			"In15.Cu" "In16.Cu"
		)
		(hatch none 0.5)
		(connect_pads
			(clearance 0)
		)
		(min_thickness 0.25)
		(keepout
			(tracks not_allowed)
			(vias allowed)
			(pads allowed)
			(copperpour not_allowed)
			(footprints allowed)
		)
		(placement
			(enabled no)
			(sheetname "")
		)
		(fill yes
			(thermal_gap 0.5)
			(thermal_bridge_width 0.5)
			(island_removal_mode 0)
		)
		(polygon
			(pts
				(arc
					(start 88.864186 -386.170424)
					(mid 88.974157 -386.271478)
					(end 89.118948 -386.308092)
				)
				(arc
					(start 89.118948 -386.308092)
					(mid 89.334474 -386.218818)
					(end 89.423748 -386.003292)
				)
				(arc
					(start 89.423748 -386.003292)
					(mid 89.413411 -385.924553)
					(end 89.383108 -385.851146)
				)
				(arc
					(start 88.990678 -385.172204)
					(mid 88.878281 -385.050587)
					(end 88.718898 -385.00558)
				)
				(arc
					(start 88.718898 -385.00558)
					(mid 88.503372 -385.094854)
					(end 88.414098 -385.31038)
				)
				(arc
					(start 88.414098 -385.31038)
					(mid 88.423676 -385.386442)
					(end 88.451944 -385.4577)
				)
				(xy 88.8492 -386.145024) (xy 88.861392 -386.16636) (xy 88.863932 -386.170678)
			)
		)
	)
	(zone
		(layers "F.Cu" "B.Cu" "In1.Cu" "In2.Cu" "In3.Cu" "In4.Cu" "In5.Cu" "In6.Cu"
			"In7.Cu" "In8.Cu" "In9.Cu" "In10.Cu" "In11.Cu" "In12.Cu" "In13.Cu" "In14.Cu"
			"In15.Cu" "In16.Cu"
		)
		(hatch none 0.5)
		(connect_pads
			(clearance 0)
		)
		(min_thickness 0.25)
		(keepout
			(tracks not_allowed)
			(vias allowed)
			(pads allowed)
			(copperpour not_allowed)
			(footprints allowed)
		)
		(placement
			(enabled no)
			(sheetname "")
		)
		(fill
			(thermal_gap 0.5)
			(thermal_bridge_width 0.5)
			(island_removal_mode 0)
		)
		(polygon
			(pts
				(arc
					(start 70.768464 -406.62352)
					(mid 70.387464 -407.00452)
					(end 70.768464 -407.38552)
				)
				(arc
					(start 71.632064 -407.38552)
					(mid 72.013064 -407.00452)
					(end 71.632064 -406.62352)
				)
			)
		)
	)
	(zone
		(layers "F.Cu" "B.Cu" "In1.Cu" "In2.Cu" "In3.Cu" "In4.Cu" "In5.Cu" "In6.Cu"
			"In7.Cu" "In8.Cu" "In9.Cu" "In10.Cu" "In11.Cu" "In12.Cu" "In13.Cu" "In14.Cu"
			"In15.Cu" "In16.Cu"
		)
		(hatch none 0.5)
		(connect_pads
			(clearance 0)
		)
		(min_thickness 0.25)
		(keepout
			(tracks not_allowed)
			(vias allowed)
			(pads allowed)
			(copperpour not_allowed)
			(footprints allowed)
		)
		(placement
			(enabled no)
			(sheetname "")
		)
		(fill
			(thermal_gap 0.5)
			(thermal_bridge_width 0.5)
			(island_removal_mode 0)
		)
		(polygon
			(pts
				(arc
					(start 389.03656 -398.016476)
					(mid 389.146531 -398.11753)
					(end 389.291322 -398.154144)
				)
				(arc
					(start 389.291322 -398.154144)
					(mid 389.506848 -398.06487)
					(end 389.596122 -397.849344)
				)
				(arc
					(start 389.596122 -397.849344)
					(mid 389.585785 -397.770605)
					(end 389.555482 -397.697198)
				)
				(arc
					(start 389.163052 -397.018256)
					(mid 389.050655 -396.896639)
					(end 388.891272 -396.851632)
				)
				(arc
					(start 388.891272 -396.851632)
					(mid 388.675746 -396.940906)
					(end 388.586472 -397.156432)
				)
				(arc
					(start 388.586472 -397.156432)
					(mid 388.59605 -397.232494)
					(end 388.624318 -397.303752)
				)
				(xy 389.021574 -397.991076) (xy 389.033766 -398.012412) (xy 389.036306 -398.01673)
			)
		)
	)
	(zone
		(layers "F.Cu" "B.Cu" "In1.Cu" "In2.Cu" "In3.Cu" "In4.Cu" "In5.Cu" "In6.Cu"
			"In7.Cu" "In8.Cu" "In9.Cu" "In10.Cu" "In11.Cu" "In12.Cu" "In13.Cu" "In14.Cu"
			"In15.Cu" "In16.Cu"
		)
		(hatch none 0.5)
		(connect_pads
			(clearance 0)
		)
		(min_thickness 0.25)
		(keepout
			(tracks not_allowed)
			(vias allowed)
			(pads allowed)
			(copperpour not_allowed)
			(footprints allowed)
		)
		(placement
			(enabled no)
			(sheetname "")
		)
		(fill
			(thermal_gap 0.5)
			(thermal_bridge_width 0.5)
			(island_removal_mode 0)
		)
		(polygon
			(pts
				(arc
					(start 61.13653 -389.634476)
					(mid 61.246501 -389.73553)
					(end 61.391292 -389.772144)
				)
				(arc
					(start 61.391292 -389.772144)
					(mid 61.606818 -389.68287)
					(end 61.696092 -389.467344)
				)
				(arc
					(start 61.696092 -389.467344)
					(mid 61.685755 -389.388605)
					(end 61.655452 -389.315198)
				)
				(arc
					(start 61.263022 -388.636256)
					(mid 61.150625 -388.514639)
					(end 60.991242 -388.469632)
				)
				(arc
					(start 60.991242 -388.469632)
					(mid 60.775716 -388.558906)
					(end 60.686442 -388.774432)
				)
				(arc
					(start 60.686442 -388.774432)
					(mid 60.69602 -388.850494)
					(end 60.724288 -388.921752)
				)
				(xy 61.121544 -389.609076) (xy 61.133736 -389.630412) (xy 61.136276 -389.63473)
			)
		)
	)
	(zone
		(layers "F.Cu" "B.Cu" "In1.Cu" "In2.Cu" "In3.Cu" "In4.Cu" "In5.Cu" "In6.Cu"
			"In7.Cu" "In8.Cu" "In9.Cu" "In10.Cu" "In11.Cu" "In12.Cu" "In13.Cu" "In14.Cu"
			"In15.Cu" "In16.Cu"
		)
		(hatch none 0.5)
		(connect_pads
			(clearance 0)
		)
		(min_thickness 0.25)
		(keepout
			(tracks not_allowed)
			(vias allowed)
			(pads allowed)
			(copperpour not_allowed)
			(footprints allowed)
		)
		(placement
			(enabled no)
			(sheetname "")
		)
		(fill
			(thermal_gap 0.5)
			(thermal_bridge_width 0.5)
			(island_removal_mode 0)
		)
		(polygon
			(pts
				(arc
					(start 164.625274 -392.429238)
					(mid 164.244274 -392.048238)
					(end 163.863274 -392.429238)
				)
				(arc
					(start 163.863274 -393.292838)
					(mid 164.244274 -393.673838)
					(end 164.625274 -393.292838)
				)
			)
		)
	)
	(zone
		(layers "F.Cu" "B.Cu" "In1.Cu" "In2.Cu" "In3.Cu" "In4.Cu" "In5.Cu" "In6.Cu"
			"In7.Cu" "In8.Cu" "In9.Cu" "In10.Cu" "In11.Cu" "In12.Cu" "In13.Cu" "In14.Cu"
			"In15.Cu" "In16.Cu"
		)
		(hatch none 0.5)
		(connect_pads
			(clearance 0)
		)
		(min_thickness 0.25)
		(keepout
			(tracks not_allowed)
			(vias allowed)
			(pads allowed)
			(copperpour not_allowed)
			(footprints allowed)
		)
		(placement
			(enabled no)
			(sheetname "")
		)
		(fill
			(thermal_gap 0.5)
			(thermal_bridge_width 0.5)
			(island_removal_mode 0)
		)
		(polygon
			(pts
				(arc
					(start 128.678686 -409.649168)
					(mid 128.297686 -410.030168)
					(end 128.678686 -410.411168)
				)
				(arc
					(start 129.542286 -410.411168)
					(mid 129.923286 -410.030168)
					(end 129.542286 -409.649168)
				)
			)
		)
	)
	(zone
		(layers "F.Cu" "B.Cu" "In1.Cu" "In2.Cu" "In3.Cu" "In4.Cu" "In5.Cu" "In6.Cu"
			"In7.Cu" "In8.Cu" "In9.Cu" "In10.Cu" "In11.Cu" "In12.Cu" "In13.Cu" "In14.Cu"
			"In15.Cu" "In16.Cu"
		)
		(hatch none 0.5)
		(connect_pads
			(clearance 0)
		)
		(min_thickness 0.25)
		(keepout
			(tracks not_allowed)
			(vias allowed)
			(pads allowed)
			(copperpour not_allowed)
			(footprints allowed)
		)
		(placement
			(enabled no)
			(sheetname "")
		)
		(fill
			(thermal_gap 0.5)
			(thermal_bridge_width 0.5)
			(island_removal_mode 0)
		)
		(polygon
			(pts
				(arc
					(start 394.758672 -387.878828)
					(mid 394.377672 -387.497828)
					(end 393.996672 -387.878828)
				)
				(arc
					(start 393.996672 -388.742428)
					(mid 394.377672 -389.123428)
					(end 394.758672 -388.742428)
				)
			)
		)
	)
	(zone
		(layers "F.Cu" "B.Cu" "In1.Cu" "In2.Cu" "In3.Cu" "In4.Cu" "In5.Cu" "In6.Cu"
			"In7.Cu" "In8.Cu" "In9.Cu" "In10.Cu" "In11.Cu" "In12.Cu" "In13.Cu" "In14.Cu"
			"In15.Cu" "In16.Cu"
		)
		(hatch none 0.5)
		(connect_pads
			(clearance 0)
		)
		(min_thickness 0.25)
		(keepout
			(tracks not_allowed)
			(vias allowed)
			(pads allowed)
			(copperpour not_allowed)
			(footprints allowed)
		)
		(placement
			(enabled no)
			(sheetname "")
		)
		(fill yes
			(thermal_gap 0.5)
			(thermal_bridge_width 0.5)
			(island_removal_mode 0)
		)
		(polygon
			(pts
				(arc
					(start 47.936658 -386.170424)
					(mid 48.046629 -386.271478)
					(end 48.19142 -386.308092)
				)
				(arc
					(start 48.19142 -386.308092)
					(mid 48.406946 -386.218818)
					(end 48.49622 -386.003292)
				)
				(arc
					(start 48.49622 -386.003292)
					(mid 48.485883 -385.924553)
					(end 48.45558 -385.851146)
				)
				(arc
					(start 48.06315 -385.172204)
					(mid 47.950753 -385.050587)
					(end 47.79137 -385.00558)
				)
				(arc
					(start 47.79137 -385.00558)
					(mid 47.575844 -385.094854)
					(end 47.48657 -385.31038)
				)
				(arc
					(start 47.48657 -385.31038)
					(mid 47.496148 -385.386442)
					(end 47.524416 -385.4577)
				)
				(xy 47.921672 -386.145024) (xy 47.933864 -386.16636) (xy 47.936404 -386.170678)
			)
		)
	)
	(zone
		(layers "F.Cu" "B.Cu" "In1.Cu" "In2.Cu" "In3.Cu" "In4.Cu" "In5.Cu" "In6.Cu"
			"In7.Cu" "In8.Cu" "In9.Cu" "In10.Cu" "In11.Cu" "In12.Cu" "In13.Cu" "In14.Cu"
			"In15.Cu" "In16.Cu"
		)
		(hatch none 0.5)
		(connect_pads
			(clearance 0)
		)
		(min_thickness 0.25)
		(keepout
			(tracks not_allowed)
			(vias allowed)
			(pads allowed)
			(copperpour not_allowed)
			(footprints allowed)
		)
		(placement
			(enabled no)
			(sheetname "")
		)
		(fill
			(thermal_gap 0.5)
			(thermal_bridge_width 0.5)
			(island_removal_mode 0)
		)
		(polygon
			(pts
				(arc
					(start 11.67384 -108.535724)
					(mid 11.29284 -108.916724)
					(end 11.67384 -109.297724)
				)
				(arc
					(start 12.53744 -109.297724)
					(mid 12.91844 -108.916724)
					(end 12.53744 -108.535724)
				)
			)
		)
	)
	(zone
		(layers "F.Cu" "B.Cu" "In1.Cu" "In2.Cu" "In3.Cu" "In4.Cu" "In5.Cu" "In6.Cu"
			"In7.Cu" "In8.Cu" "In9.Cu" "In10.Cu" "In11.Cu" "In12.Cu" "In13.Cu" "In14.Cu"
			"In15.Cu" "In16.Cu"
		)
		(hatch none 0.5)
		(connect_pads
			(clearance 0)
		)
		(min_thickness 0.25)
		(keepout
			(tracks not_allowed)
			(vias allowed)
			(pads allowed)
			(copperpour not_allowed)
			(footprints allowed)
		)
		(placement
			(enabled no)
			(sheetname "")
		)
		(fill
			(thermal_gap 0.5)
			(thermal_bridge_width 0.5)
			(island_removal_mode 0)
		)
		(polygon
			(pts
				(arc
					(start 137.414762 -17.763744)
					(mid 137.033762 -18.144744)
					(end 137.414762 -18.525744)
				)
				(arc
					(start 138.278362 -18.525744)
					(mid 138.659362 -18.144744)
					(end 138.278362 -17.763744)
				)
			)
		)
	)
	(zone
		(layers "F.Cu" "B.Cu" "In1.Cu" "In2.Cu" "In3.Cu" "In4.Cu" "In5.Cu" "In6.Cu"
			"In7.Cu" "In8.Cu" "In9.Cu" "In10.Cu" "In11.Cu" "In12.Cu" "In13.Cu" "In14.Cu"
			"In15.Cu" "In16.Cu"
		)
		(hatch none 0.5)
		(connect_pads
			(clearance 0)
		)
		(min_thickness 0.25)
		(keepout
			(tracks not_allowed)
			(vias allowed)
			(pads allowed)
			(copperpour not_allowed)
			(footprints allowed)
		)
		(placement
			(enabled no)
			(sheetname "")
		)
		(fill
			(thermal_gap 0.5)
			(thermal_bridge_width 0.5)
			(island_removal_mode 0)
		)
		(polygon
			(pts
				(arc
					(start 98.33102 -314.997338)
					(mid 98.71202 -315.378338)
					(end 99.09302 -314.997338)
				)
				(arc
					(start 99.09302 -314.133738)
					(mid 98.71202 -313.752738)
					(end 98.33102 -314.133738)
				)
			)
		)
	)
	(zone
		(layers "F.Cu" "B.Cu" "In1.Cu" "In2.Cu" "In3.Cu" "In4.Cu" "In5.Cu" "In6.Cu"
			"In7.Cu" "In8.Cu" "In9.Cu" "In10.Cu" "In11.Cu" "In12.Cu" "In13.Cu" "In14.Cu"
			"In15.Cu" "In16.Cu"
		)
		(hatch none 0.5)
		(connect_pads
			(clearance 0)
		)
		(min_thickness 0.25)
		(keepout
			(tracks not_allowed)
			(vias allowed)
			(pads allowed)
			(copperpour not_allowed)
			(footprints allowed)
		)
		(placement
			(enabled no)
			(sheetname "")
		)
		(fill
			(thermal_gap 0.5)
			(thermal_bridge_width 0.5)
			(island_removal_mode 0)
		)
		(polygon
			(pts
				(arc
					(start 204.54112 -433.04206)
					(mid 197.42912 -433.04206)
					(end 204.54112 -433.04206)
				)
			)
		)
	)
	(zone
		(layers "F.Cu" "B.Cu" "In1.Cu" "In2.Cu" "In3.Cu" "In4.Cu" "In5.Cu" "In6.Cu"
			"In7.Cu" "In8.Cu" "In9.Cu" "In10.Cu" "In11.Cu" "In12.Cu" "In13.Cu" "In14.Cu"
			"In15.Cu" "In16.Cu"
		)
		(hatch none 0.5)
		(connect_pads
			(clearance 0)
		)
		(min_thickness 0.25)
		(keepout
			(tracks not_allowed)
			(vias allowed)
			(pads allowed)
			(copperpour not_allowed)
			(footprints allowed)
		)
		(placement
			(enabled no)
			(sheetname "")
		)
		(fill
			(thermal_gap 0.5)
			(thermal_bridge_width 0.5)
			(island_removal_mode 0)
		)
		(polygon
			(pts
				(arc
					(start 381.615442 -418.031168)
					(mid 381.234442 -418.412168)
					(end 381.615442 -418.793168)
				)
				(arc
					(start 382.479042 -418.793168)
					(mid 382.860042 -418.412168)
					(end 382.479042 -418.031168)
				)
			)
		)
	)
	(zone
		(layers "F.Cu" "B.Cu" "In1.Cu" "In2.Cu" "In3.Cu" "In4.Cu" "In5.Cu" "In6.Cu"
			"In7.Cu" "In8.Cu" "In9.Cu" "In10.Cu" "In11.Cu" "In12.Cu" "In13.Cu" "In14.Cu"
			"In15.Cu" "In16.Cu"
		)
		(hatch none 0.5)
		(connect_pads
			(clearance 0)
		)
		(min_thickness 0.25)
		(keepout
			(tracks not_allowed)
			(vias allowed)
			(pads allowed)
			(copperpour not_allowed)
			(footprints allowed)
		)
		(placement
			(enabled no)
			(sheetname "")
		)
		(fill
			(thermal_gap 0.5)
			(thermal_bridge_width 0.5)
			(island_removal_mode 0)
		)
		(polygon
			(pts
				(arc
					(start 145.042636 -304.780442)
					(mid 140.012928 -304.780442)
					(end 145.042636 -304.780442)
				)
			)
		)
	)
	(zone
		(layers "F.Cu" "B.Cu" "In1.Cu" "In2.Cu" "In3.Cu" "In4.Cu" "In5.Cu" "In6.Cu"
			"In7.Cu" "In8.Cu" "In9.Cu" "In10.Cu" "In11.Cu" "In12.Cu" "In13.Cu" "In14.Cu"
			"In15.Cu" "In16.Cu"
		)
		(hatch none 0.5)
		(connect_pads
			(clearance 0)
		)
		(min_thickness 0.25)
		(keepout
			(tracks not_allowed)
			(vias allowed)
			(pads allowed)
			(copperpour not_allowed)
			(footprints allowed)
		)
		(placement
			(enabled no)
			(sheetname "")
		)
		(fill yes
			(thermal_gap 0.5)
			(thermal_bridge_width 0.5)
			(island_removal_mode 0)
		)
		(polygon
			(pts
				(arc
					(start 349.66402 -394.552424)
					(mid 349.773991 -394.653478)
					(end 349.918782 -394.690092)
				)
				(arc
					(start 349.918782 -394.690092)
					(mid 350.134308 -394.600818)
					(end 350.223582 -394.385292)
				)
				(arc
					(start 350.223582 -394.385292)
					(mid 350.213245 -394.306553)
					(end 350.182942 -394.233146)
				)
				(arc
					(start 349.790512 -393.554204)
					(mid 349.678115 -393.432587)
					(end 349.518732 -393.38758)
				)
				(arc
					(start 349.518732 -393.38758)
					(mid 349.303206 -393.476854)
					(end 349.213932 -393.69238)
				)
				(arc
					(start 349.213932 -393.69238)
					(mid 349.22351 -393.768442)
					(end 349.251778 -393.8397)
				)
				(xy 349.649034 -394.527024) (xy 349.661226 -394.54836) (xy 349.663766 -394.552678)
			)
		)
	)
	(zone
		(layers "F.Cu" "B.Cu" "In1.Cu" "In2.Cu" "In3.Cu" "In4.Cu" "In5.Cu" "In6.Cu"
			"In7.Cu" "In8.Cu" "In9.Cu" "In10.Cu" "In11.Cu" "In12.Cu" "In13.Cu" "In14.Cu"
			"In15.Cu" "In16.Cu"
		)
		(hatch none 0.5)
		(connect_pads
			(clearance 0)
		)
		(min_thickness 0.25)
		(keepout
			(tracks not_allowed)
			(vias allowed)
			(pads allowed)
			(copperpour not_allowed)
			(footprints allowed)
		)
		(placement
			(enabled no)
			(sheetname "")
		)
		(fill
			(thermal_gap 0.5)
			(thermal_bridge_width 0.5)
			(island_removal_mode 0)
		)
		(polygon
			(pts
				(arc
					(start 72.300084 -412.189168)
					(mid 71.919084 -412.570168)
					(end 72.300084 -412.951168)
				)
				(arc
					(start 73.163684 -412.951168)
					(mid 73.544684 -412.570168)
					(end 73.163684 -412.189168)
				)
			)
		)
	)
	(zone
		(layers "F.Cu" "B.Cu" "In1.Cu" "In2.Cu" "In3.Cu" "In4.Cu" "In5.Cu" "In6.Cu"
			"In7.Cu" "In8.Cu" "In9.Cu" "In10.Cu" "In11.Cu" "In12.Cu" "In13.Cu" "In14.Cu"
			"In15.Cu" "In16.Cu"
		)
		(hatch none 0.5)
		(connect_pads
			(clearance 0)
		)
		(min_thickness 0.25)
		(keepout
			(tracks not_allowed)
			(vias allowed)
			(pads allowed)
			(copperpour not_allowed)
			(footprints allowed)
		)
		(placement
			(enabled no)
			(sheetname "")
		)
		(fill
			(thermal_gap 0.5)
			(thermal_bridge_width 0.5)
			(island_removal_mode 0)
		)
		(polygon
			(pts
				(arc
					(start 340.324948 -400.811238)
					(mid 339.943948 -400.430238)
					(end 339.562948 -400.811238)
				)
				(arc
					(start 339.562948 -401.674838)
					(mid 339.943948 -402.055838)
					(end 340.324948 -401.674838)
				)
			)
		)
	)
	(zone
		(layers "F.Cu" "B.Cu" "In1.Cu" "In2.Cu" "In3.Cu" "In4.Cu" "In5.Cu" "In6.Cu"
			"In7.Cu" "In8.Cu" "In9.Cu" "In10.Cu" "In11.Cu" "In12.Cu" "In13.Cu" "In14.Cu"
			"In15.Cu" "In16.Cu"
		)
		(hatch none 0.5)
		(connect_pads
			(clearance 0)
		)
		(min_thickness 0.25)
		(keepout
			(tracks not_allowed)
			(vias allowed)
			(pads allowed)
			(copperpour not_allowed)
			(footprints allowed)
		)
		(placement
			(enabled no)
			(sheetname "")
		)
		(fill yes
			(thermal_gap 0.5)
			(thermal_bridge_width 0.5)
			(island_removal_mode 0)
		)
		(polygon
			(pts
				(arc
					(start 408.364182 -394.552424)
					(mid 408.474153 -394.653478)
					(end 408.618944 -394.690092)
				)
				(arc
					(start 408.618944 -394.690092)
					(mid 408.83447 -394.600818)
					(end 408.923744 -394.385292)
				)
				(arc
					(start 408.923744 -394.385292)
					(mid 408.913407 -394.306553)
					(end 408.883104 -394.233146)
				)
				(arc
					(start 408.490674 -393.554204)
					(mid 408.378277 -393.432587)
					(end 408.218894 -393.38758)
				)
				(arc
					(start 408.218894 -393.38758)
					(mid 408.003368 -393.476854)
					(end 407.914094 -393.69238)
				)
				(arc
					(start 407.914094 -393.69238)
					(mid 407.923672 -393.768442)
					(end 407.95194 -393.8397)
				)
				(xy 408.349196 -394.527024) (xy 408.361388 -394.54836) (xy 408.363928 -394.552678)
			)
		)
	)
	(zone
		(layers "F.Cu" "B.Cu" "In1.Cu" "In2.Cu" "In3.Cu" "In4.Cu" "In5.Cu" "In6.Cu"
			"In7.Cu" "In8.Cu" "In9.Cu" "In10.Cu" "In11.Cu" "In12.Cu" "In13.Cu" "In14.Cu"
			"In15.Cu" "In16.Cu"
		)
		(hatch none 0.5)
		(connect_pads
			(clearance 0)
		)
		(min_thickness 0.25)
		(keepout
			(tracks not_allowed)
			(vias allowed)
			(pads allowed)
			(copperpour not_allowed)
			(footprints allowed)
		)
		(placement
			(enabled no)
			(sheetname "")
		)
		(fill
			(thermal_gap 0.5)
			(thermal_bridge_width 0.5)
			(island_removal_mode 0)
		)
		(polygon
			(pts
				(arc
					(start 121.297446 -392.429238)
					(mid 120.916446 -392.048238)
					(end 120.535446 -392.429238)
				)
				(arc
					(start 120.535446 -393.292838)
					(mid 120.916446 -393.673838)
					(end 121.297446 -393.292838)
				)
			)
		)
	)
	(zone
		(layers "F.Cu" "B.Cu" "In1.Cu" "In2.Cu" "In3.Cu" "In4.Cu" "In5.Cu" "In6.Cu"
			"In7.Cu" "In8.Cu" "In9.Cu" "In10.Cu" "In11.Cu" "In12.Cu" "In13.Cu" "In14.Cu"
			"In15.Cu" "In16.Cu"
		)
		(hatch none 0.5)
		(connect_pads
			(clearance 0)
		)
		(min_thickness 0.25)
		(keepout
			(tracks not_allowed)
			(vias allowed)
			(pads allowed)
			(copperpour not_allowed)
			(footprints allowed)
		)
		(placement
			(enabled no)
			(sheetname "")
		)
		(fill
			(thermal_gap 0.5)
			(thermal_bridge_width 0.5)
			(island_removal_mode 0)
		)
		(polygon
			(pts
				(arc
					(start 417.964112 -398.016476)
					(mid 418.074083 -398.11753)
					(end 418.218874 -398.154144)
				)
				(arc
					(start 418.218874 -398.154144)
					(mid 418.4344 -398.06487)
					(end 418.523674 -397.849344)
				)
				(arc
					(start 418.523674 -397.849344)
					(mid 418.513337 -397.770605)
					(end 418.483034 -397.697198)
				)
				(arc
					(start 418.090604 -397.018256)
					(mid 417.978207 -396.896639)
					(end 417.818824 -396.851632)
				)
				(arc
					(start 417.818824 -396.851632)
					(mid 417.603298 -396.940906)
					(end 417.514024 -397.156432)
				)
				(arc
					(start 417.514024 -397.156432)
					(mid 417.523602 -397.232494)
					(end 417.55187 -397.303752)
				)
				(xy 417.949126 -397.991076) (xy 417.961318 -398.012412) (xy 417.963858 -398.01673)
			)
		)
	)
	(zone
		(layers "F.Cu" "B.Cu" "In1.Cu" "In2.Cu" "In3.Cu" "In4.Cu" "In5.Cu" "In6.Cu"
			"In7.Cu" "In8.Cu" "In9.Cu" "In10.Cu" "In11.Cu" "In12.Cu" "In13.Cu" "In14.Cu"
			"In15.Cu" "In16.Cu"
		)
		(hatch none 0.5)
		(connect_pads
			(clearance 0)
		)
		(min_thickness 0.25)
		(keepout
			(tracks not_allowed)
			(vias allowed)
			(pads allowed)
			(copperpour not_allowed)
			(footprints allowed)
		)
		(placement
			(enabled no)
			(sheetname "")
		)
		(fill
			(thermal_gap 0.5)
			(thermal_bridge_width 0.5)
			(island_removal_mode 0)
		)
		(polygon
			(pts
				(arc
					(start 80.725264 -392.429238)
					(mid 80.344264 -392.048238)
					(end 79.963264 -392.429238)
				)
				(arc
					(start 79.963264 -393.292838)
					(mid 80.344264 -393.673838)
					(end 80.725264 -393.292838)
				)
			)
		)
	)
	(zone
		(layers "F.Cu" "B.Cu" "In1.Cu" "In2.Cu" "In3.Cu" "In4.Cu" "In5.Cu" "In6.Cu"
			"In7.Cu" "In8.Cu" "In9.Cu" "In10.Cu" "In11.Cu" "In12.Cu" "In13.Cu" "In14.Cu"
			"In15.Cu" "In16.Cu"
		)
		(hatch none 0.5)
		(connect_pads
			(clearance 0)
		)
		(min_thickness 0.25)
		(keepout
			(tracks not_allowed)
			(vias allowed)
			(pads allowed)
			(copperpour not_allowed)
			(footprints allowed)
		)
		(placement
			(enabled no)
			(sheetname "")
		)
		(fill yes
			(thermal_gap 0.5)
			(thermal_bridge_width 0.5)
			(island_removal_mode 0)
		)
		(polygon
			(pts
				(arc
					(start 385.436364 -394.552424)
					(mid 385.546335 -394.653478)
					(end 385.691126 -394.690092)
				)
				(arc
					(start 385.691126 -394.690092)
					(mid 385.906652 -394.600818)
					(end 385.995926 -394.385292)
				)
				(arc
					(start 385.995926 -394.385292)
					(mid 385.985589 -394.306553)
					(end 385.955286 -394.233146)
				)
				(arc
					(start 385.562856 -393.554204)
					(mid 385.450459 -393.432587)
					(end 385.291076 -393.38758)
				)
				(arc
					(start 385.291076 -393.38758)
					(mid 385.07555 -393.476854)
					(end 384.986276 -393.69238)
				)
				(arc
					(start 384.986276 -393.69238)
					(mid 384.995854 -393.768442)
					(end 385.024122 -393.8397)
				)
				(xy 385.421378 -394.527024) (xy 385.43357 -394.54836) (xy 385.43611 -394.552678)
			)
		)
	)
	(zone
		(layers "F.Cu" "B.Cu" "In1.Cu" "In2.Cu" "In3.Cu" "In4.Cu" "In5.Cu" "In6.Cu"
			"In7.Cu" "In8.Cu" "In9.Cu" "In10.Cu" "In11.Cu" "In12.Cu" "In13.Cu" "In14.Cu"
			"In15.Cu" "In16.Cu"
		)
		(hatch none 0.5)
		(connect_pads
			(clearance 0)
		)
		(min_thickness 0.25)
		(keepout
			(tracks not_allowed)
			(vias allowed)
			(pads allowed)
			(copperpour not_allowed)
			(footprints allowed)
		)
		(placement
			(enabled no)
			(sheetname "")
		)
		(fill
			(thermal_gap 0.5)
			(thermal_bridge_width 0.5)
			(island_removal_mode 0)
		)
		(polygon
			(pts
				(arc
					(start 139.400026 -412.189168)
					(mid 139.019026 -412.570168)
					(end 139.400026 -412.951168)
				)
				(arc
					(start 140.263626 -412.951168)
					(mid 140.644626 -412.570168)
					(end 140.263626 -412.189168)
				)
			)
		)
	)
	(zone
		(layers "F.Cu" "B.Cu" "In1.Cu" "In2.Cu" "In3.Cu" "In4.Cu" "In5.Cu" "In6.Cu"
			"In7.Cu" "In8.Cu" "In9.Cu" "In10.Cu" "In11.Cu" "In12.Cu" "In13.Cu" "In14.Cu"
			"In15.Cu" "In16.Cu"
		)
		(hatch none 0.5)
		(connect_pads
			(clearance 0)
		)
		(min_thickness 0.25)
		(keepout
			(tracks not_allowed)
			(vias allowed)
			(pads allowed)
			(copperpour not_allowed)
			(footprints allowed)
		)
		(placement
			(enabled no)
			(sheetname "")
		)
		(fill
			(thermal_gap 0.5)
			(thermal_bridge_width 0.5)
			(island_removal_mode 0)
		)
		(polygon
			(pts
				(arc
					(start 316.01283 -0.428244)
					(mid 316.44463 -0.860044)
					(end 316.87643 -0.428244)
				)
				(arc
					(start 316.87643 0.435356)
					(mid 316.44463 0.867156)
					(end 316.01283 0.435356)
				)
			)
		)
	)
	(zone
		(layers "F.Cu" "B.Cu" "In1.Cu" "In2.Cu" "In3.Cu" "In4.Cu" "In5.Cu" "In6.Cu"
			"In7.Cu" "In8.Cu" "In9.Cu" "In10.Cu" "In11.Cu" "In12.Cu" "In13.Cu" "In14.Cu"
			"In15.Cu" "In16.Cu"
		)
		(hatch none 0.5)
		(connect_pads
			(clearance 0)
		)
		(min_thickness 0.25)
		(keepout
			(tracks not_allowed)
			(vias allowed)
			(pads allowed)
			(copperpour not_allowed)
			(footprints allowed)
		)
		(placement
			(enabled no)
			(sheetname "")
		)
		(fill
			(thermal_gap 0.5)
			(thermal_bridge_width 0.5)
			(island_removal_mode 0)
		)
		(polygon
			(pts
				(arc
					(start 354.72497 -400.811238)
					(mid 354.34397 -400.430238)
					(end 353.96297 -400.811238)
				)
				(arc
					(start 353.96297 -401.674838)
					(mid 354.34397 -402.055838)
					(end 354.72497 -401.674838)
				)
			)
		)
	)
	(zone
		(layers "F.Cu" "B.Cu" "In1.Cu" "In2.Cu" "In3.Cu" "In4.Cu" "In5.Cu" "In6.Cu"
			"In7.Cu" "In8.Cu" "In9.Cu" "In10.Cu" "In11.Cu" "In12.Cu" "In13.Cu" "In14.Cu"
			"In15.Cu" "In16.Cu"
		)
		(hatch none 0.5)
		(connect_pads
			(clearance 0)
		)
		(min_thickness 0.25)
		(keepout
			(tracks not_allowed)
			(vias allowed)
			(pads allowed)
			(copperpour not_allowed)
			(footprints allowed)
		)
		(placement
			(enabled no)
			(sheetname "")
		)
		(fill
			(thermal_gap 0.5)
			(thermal_bridge_width 0.5)
			(island_removal_mode 0)
		)
		(polygon
			(pts
				(arc
					(start 61.578744 -409.649168)
					(mid 61.197744 -410.030168)
					(end 61.578744 -410.411168)
				)
				(arc
					(start 62.442344 -410.411168)
					(mid 62.823344 -410.030168)
					(end 62.442344 -409.649168)
				)
			)
		)
	)
	(zone
		(layers "F.Cu" "B.Cu" "In1.Cu" "In2.Cu" "In3.Cu" "In4.Cu" "In5.Cu" "In6.Cu"
			"In7.Cu" "In8.Cu" "In9.Cu" "In10.Cu" "In11.Cu" "In12.Cu" "In13.Cu" "In14.Cu"
			"In15.Cu" "In16.Cu"
		)
		(hatch none 0.5)
		(connect_pads
			(clearance 0)
		)
		(min_thickness 0.25)
		(keepout
			(tracks not_allowed)
			(vias allowed)
			(pads allowed)
			(copperpour not_allowed)
			(footprints allowed)
		)
		(placement
			(enabled no)
			(sheetname "")
		)
		(fill
			(thermal_gap 0.5)
			(thermal_bridge_width 0.5)
			(island_removal_mode 0)
		)
		(polygon
			(pts
				(arc
					(start 58.515504 -406.62352)
					(mid 58.134504 -407.00452)
					(end 58.515504 -407.38552)
				)
				(arc
					(start 59.379104 -407.38552)
					(mid 59.760104 -407.00452)
					(end 59.379104 -406.62352)
				)
			)
		)
	)
	(zone
		(layers "F.Cu" "B.Cu" "In1.Cu" "In2.Cu" "In3.Cu" "In4.Cu" "In5.Cu" "In6.Cu"
			"In7.Cu" "In8.Cu" "In9.Cu" "In10.Cu" "In11.Cu" "In12.Cu" "In13.Cu" "In14.Cu"
			"In15.Cu" "In16.Cu"
		)
		(hatch none 0.5)
		(connect_pads
			(clearance 0)
		)
		(min_thickness 0.25)
		(keepout
			(tracks not_allowed)
			(vias allowed)
			(pads allowed)
			(copperpour not_allowed)
			(footprints allowed)
		)
		(placement
			(enabled no)
			(sheetname "")
		)
		(fill
			(thermal_gap 0.5)
			(thermal_bridge_width 0.5)
			(island_removal_mode 0)
		)
		(polygon
			(pts
				(arc
					(start 124.083826 -412.189168)
					(mid 123.702826 -412.570168)
					(end 124.083826 -412.951168)
				)
				(arc
					(start 124.947426 -412.951168)
					(mid 125.328426 -412.570168)
					(end 124.947426 -412.189168)
				)
			)
		)
	)
	(zone
		(layers "F.Cu" "B.Cu" "In1.Cu" "In2.Cu" "In3.Cu" "In4.Cu" "In5.Cu" "In6.Cu"
			"In7.Cu" "In8.Cu" "In9.Cu" "In10.Cu" "In11.Cu" "In12.Cu" "In13.Cu" "In14.Cu"
			"In15.Cu" "In16.Cu"
		)
		(hatch none 0.5)
		(connect_pads
			(clearance 0)
		)
		(min_thickness 0.25)
		(keepout
			(tracks not_allowed)
			(vias allowed)
			(pads allowed)
			(copperpour not_allowed)
			(footprints allowed)
		)
		(placement
			(enabled no)
			(sheetname "")
		)
		(fill
			(thermal_gap 0.5)
			(thermal_bridge_width 0.5)
			(island_removal_mode 0)
		)
		(polygon
			(pts
				(arc
					(start 114.894106 -404.08352)
					(mid 114.513106 -404.46452)
					(end 114.894106 -404.84552)
				)
				(arc
					(start 115.757706 -404.84552)
					(mid 116.138706 -404.46452)
					(end 115.757706 -404.08352)
				)
			)
		)
	)
	(zone
		(layers "F.Cu" "B.Cu" "In1.Cu" "In2.Cu" "In3.Cu" "In4.Cu" "In5.Cu" "In6.Cu"
			"In7.Cu" "In8.Cu" "In9.Cu" "In10.Cu" "In11.Cu" "In12.Cu" "In13.Cu" "In14.Cu"
			"In15.Cu" "In16.Cu"
		)
		(hatch none 0.5)
		(connect_pads
			(clearance 0)
		)
		(min_thickness 0.25)
		(keepout
			(tracks not_allowed)
			(vias allowed)
			(pads allowed)
			(copperpour not_allowed)
			(footprints allowed)
		)
		(placement
			(enabled no)
			(sheetname "")
		)
		(fill
			(thermal_gap 0.5)
			(thermal_bridge_width 0.5)
			(island_removal_mode 0)
		)
		(polygon
			(pts
				(arc
					(start 53.735732 -6.344158)
					(mid 53.354732 -6.725158)
					(end 53.735732 -7.106158)
				)
				(arc
					(start 54.599332 -7.106158)
					(mid 54.980332 -6.725158)
					(end 54.599332 -6.344158)
				)
			)
		)
	)
	(zone
		(layers "F.Cu" "B.Cu" "In1.Cu" "In2.Cu" "In3.Cu" "In4.Cu" "In5.Cu" "In6.Cu"
			"In7.Cu" "In8.Cu" "In9.Cu" "In10.Cu" "In11.Cu" "In12.Cu" "In13.Cu" "In14.Cu"
			"In15.Cu" "In16.Cu"
		)
		(hatch none 0.5)
		(connect_pads
			(clearance 0)
		)
		(min_thickness 0.25)
		(keepout
			(tracks not_allowed)
			(vias allowed)
			(pads allowed)
			(copperpour not_allowed)
			(footprints allowed)
		)
		(placement
			(enabled no)
			(sheetname "")
		)
		(fill yes
			(thermal_gap 0.5)
			(thermal_bridge_width 0.5)
			(island_removal_mode 0)
		)
		(polygon
			(pts
				(arc
					(start 87.66429 -386.170424)
					(mid 87.774261 -386.271478)
					(end 87.919052 -386.308092)
				)
				(arc
					(start 87.919052 -386.308092)
					(mid 88.134578 -386.218818)
					(end 88.223852 -386.003292)
				)
				(arc
					(start 88.223852 -386.003292)
					(mid 88.213515 -385.924553)
					(end 88.183212 -385.851146)
				)
				(arc
					(start 87.790782 -385.172204)
					(mid 87.678385 -385.050587)
					(end 87.519002 -385.00558)
				)
				(arc
					(start 87.519002 -385.00558)
					(mid 87.303476 -385.094854)
					(end 87.214202 -385.31038)
				)
				(arc
					(start 87.214202 -385.31038)
					(mid 87.22378 -385.386442)
					(end 87.252048 -385.4577)
				)
				(xy 87.649304 -386.145024) (xy 87.661496 -386.16636) (xy 87.664036 -386.170678)
			)
		)
	)
	(zone
		(layers "F.Cu" "B.Cu" "In1.Cu" "In2.Cu" "In3.Cu" "In4.Cu" "In5.Cu" "In6.Cu"
			"In7.Cu" "In8.Cu" "In9.Cu" "In10.Cu" "In11.Cu" "In12.Cu" "In13.Cu" "In14.Cu"
			"In15.Cu" "In16.Cu"
		)
		(hatch none 0.5)
		(connect_pads
			(clearance 0)
		)
		(min_thickness 0.25)
		(keepout
			(tracks not_allowed)
			(vias allowed)
			(pads allowed)
			(copperpour not_allowed)
			(footprints allowed)
		)
		(placement
			(enabled no)
			(sheetname "")
		)
		(fill
			(thermal_gap 0.5)
			(thermal_bridge_width 0.5)
			(island_removal_mode 0)
		)
		(polygon
			(pts
				(arc
					(start 84.325206 -392.429238)
					(mid 83.944206 -392.048238)
					(end 83.563206 -392.429238)
				)
				(arc
					(start 83.563206 -393.292838)
					(mid 83.944206 -393.673838)
					(end 84.325206 -393.292838)
				)
			)
		)
	)
	(zone
		(layers "F.Cu" "B.Cu" "In1.Cu" "In2.Cu" "In3.Cu" "In4.Cu" "In5.Cu" "In6.Cu"
			"In7.Cu" "In8.Cu" "In9.Cu" "In10.Cu" "In11.Cu" "In12.Cu" "In13.Cu" "In14.Cu"
			"In15.Cu" "In16.Cu"
		)
		(hatch none 0.5)
		(connect_pads
			(clearance 0)
		)
		(min_thickness 0.25)
		(keepout
			(tracks not_allowed)
			(vias allowed)
			(pads allowed)
			(copperpour not_allowed)
			(footprints allowed)
		)
		(placement
			(enabled no)
			(sheetname "")
		)
		(fill
			(thermal_gap 0.5)
			(thermal_bridge_width 0.5)
			(island_removal_mode 0)
		)
		(polygon
			(pts
				(arc
					(start 130.636518 -389.634476)
					(mid 130.746489 -389.73553)
					(end 130.89128 -389.772144)
				)
				(arc
					(start 130.89128 -389.772144)
					(mid 131.106806 -389.68287)
					(end 131.19608 -389.467344)
				)
				(arc
					(start 131.19608 -389.467344)
					(mid 131.185743 -389.388605)
					(end 131.15544 -389.315198)
				)
				(arc
					(start 130.76301 -388.636256)
					(mid 130.650613 -388.514639)
					(end 130.49123 -388.469632)
				)
				(arc
					(start 130.49123 -388.469632)
					(mid 130.275704 -388.558906)
					(end 130.18643 -388.774432)
				)
				(arc
					(start 130.18643 -388.774432)
					(mid 130.196008 -388.850494)
					(end 130.224276 -388.921752)
				)
				(xy 130.621532 -389.609076) (xy 130.633724 -389.630412) (xy 130.636264 -389.63473)
			)
		)
	)
	(zone
		(layers "F.Cu" "B.Cu" "In1.Cu" "In2.Cu" "In3.Cu" "In4.Cu" "In5.Cu" "In6.Cu"
			"In7.Cu" "In8.Cu" "In9.Cu" "In10.Cu" "In11.Cu" "In12.Cu" "In13.Cu" "In14.Cu"
			"In15.Cu" "In16.Cu"
		)
		(hatch none 0.5)
		(connect_pads
			(clearance 0)
		)
		(min_thickness 0.25)
		(keepout
			(tracks not_allowed)
			(vias allowed)
			(pads allowed)
			(copperpour not_allowed)
			(footprints allowed)
		)
		(placement
			(enabled no)
			(sheetname "")
		)
		(fill yes
			(thermal_gap 0.5)
			(thermal_bridge_width 0.5)
			(island_removal_mode 0)
		)
		(polygon
			(pts
				(arc
					(start 149.96414 -386.170424)
					(mid 150.074111 -386.271478)
					(end 150.218902 -386.308092)
				)
				(arc
					(start 150.218902 -386.308092)
					(mid 150.434428 -386.218818)
					(end 150.523702 -386.003292)
				)
				(arc
					(start 150.523702 -386.003292)
					(mid 150.513365 -385.924553)
					(end 150.483062 -385.851146)
				)
				(arc
					(start 150.090632 -385.172204)
					(mid 149.978235 -385.050587)
					(end 149.818852 -385.00558)
				)
				(arc
					(start 149.818852 -385.00558)
					(mid 149.603326 -385.094854)
					(end 149.514052 -385.31038)
				)
				(arc
					(start 149.514052 -385.31038)
					(mid 149.52363 -385.386442)
					(end 149.551898 -385.4577)
				)
				(xy 149.949154 -386.145024) (xy 149.961346 -386.16636) (xy 149.963886 -386.170678)
			)
		)
	)
	(zone
		(layers "F.Cu" "B.Cu" "In1.Cu" "In2.Cu" "In3.Cu" "In4.Cu" "In5.Cu" "In6.Cu"
			"In7.Cu" "In8.Cu" "In9.Cu" "In10.Cu" "In11.Cu" "In12.Cu" "In13.Cu" "In14.Cu"
			"In15.Cu" "In16.Cu"
		)
		(hatch none 0.5)
		(connect_pads
			(clearance 0)
		)
		(min_thickness 0.25)
		(keepout
			(tracks not_allowed)
			(vias allowed)
			(pads allowed)
			(copperpour not_allowed)
			(footprints allowed)
		)
		(placement
			(enabled no)
			(sheetname "")
		)
		(fill
			(thermal_gap 0.5)
			(thermal_bridge_width 0.5)
			(island_removal_mode 0)
		)
		(polygon
			(pts
				(arc
					(start 147.058126 -406.62352)
					(mid 146.677126 -407.00452)
					(end 147.058126 -407.38552)
				)
				(arc
					(start 147.921726 -407.38552)
					(mid 148.302726 -407.00452)
					(end 147.921726 -406.62352)
				)
			)
		)
	)
	(zone
		(layers "F.Cu" "B.Cu" "In1.Cu" "In2.Cu" "In3.Cu" "In4.Cu" "In5.Cu" "In6.Cu"
			"In7.Cu" "In8.Cu" "In9.Cu" "In10.Cu" "In11.Cu" "In12.Cu" "In13.Cu" "In14.Cu"
			"In15.Cu" "In16.Cu"
		)
		(hatch none 0.5)
		(connect_pads
			(clearance 0)
		)
		(min_thickness 0.25)
		(keepout
			(tracks not_allowed)
			(vias allowed)
			(pads allowed)
			(copperpour not_allowed)
			(footprints allowed)
		)
		(placement
			(enabled no)
			(sheetname "")
		)
		(fill
			(thermal_gap 0.5)
			(thermal_bridge_width 0.5)
			(island_removal_mode 0)
		)
		(polygon
			(pts
				(arc
					(start 339.021166 -415.00552)
					(mid 338.640166 -415.38652)
					(end 339.021166 -415.76752)
				)
				(arc
					(start 339.884766 -415.76752)
					(mid 340.265766 -415.38652)
					(end 339.884766 -415.00552)
				)
			)
		)
	)
	(zone
		(layers "F.Cu" "B.Cu" "In1.Cu" "In2.Cu" "In3.Cu" "In4.Cu" "In5.Cu" "In6.Cu"
			"In7.Cu" "In8.Cu" "In9.Cu" "In10.Cu" "In11.Cu" "In12.Cu" "In13.Cu" "In14.Cu"
			"In15.Cu" "In16.Cu"
		)
		(hatch none 0.5)
		(connect_pads
			(clearance 0)
		)
		(min_thickness 0.25)
		(keepout
			(tracks not_allowed)
			(vias allowed)
			(pads allowed)
			(copperpour not_allowed)
			(footprints allowed)
		)
		(placement
			(enabled no)
			(sheetname "")
		)
		(fill
			(thermal_gap 0.5)
			(thermal_bridge_width 0.5)
			(island_removal_mode 0)
		)
		(polygon
			(pts
				(arc
					(start 149.96414 -389.634476)
					(mid 150.074111 -389.73553)
					(end 150.218902 -389.772144)
				)
				(arc
					(start 150.218902 -389.772144)
					(mid 150.434428 -389.68287)
					(end 150.523702 -389.467344)
				)
				(arc
					(start 150.523702 -389.467344)
					(mid 150.513365 -389.388605)
					(end 150.483062 -389.315198)
				)
				(arc
					(start 150.090632 -388.636256)
					(mid 149.978235 -388.514639)
					(end 149.818852 -388.469632)
				)
				(arc
					(start 149.818852 -388.469632)
					(mid 149.603326 -388.558906)
					(end 149.514052 -388.774432)
				)
				(arc
					(start 149.514052 -388.774432)
					(mid 149.52363 -388.850494)
					(end 149.551898 -388.921752)
				)
				(xy 149.949154 -389.609076) (xy 149.961346 -389.630412) (xy 149.963886 -389.63473)
			)
		)
	)
	(zone
		(layers "F.Cu" "B.Cu" "In1.Cu" "In2.Cu" "In3.Cu" "In4.Cu" "In5.Cu" "In6.Cu"
			"In7.Cu" "In8.Cu" "In9.Cu" "In10.Cu" "In11.Cu" "In12.Cu" "In13.Cu" "In14.Cu"
			"In15.Cu" "In16.Cu"
		)
		(hatch none 0.5)
		(connect_pads
			(clearance 0)
		)
		(min_thickness 0.25)
		(keepout
			(tracks not_allowed)
			(vias allowed)
			(pads allowed)
			(copperpour not_allowed)
			(footprints allowed)
		)
		(placement
			(enabled no)
			(sheetname "")
		)
		(fill
			(thermal_gap 0.5)
			(thermal_bridge_width 0.5)
			(island_removal_mode 0)
		)
		(polygon
			(pts
				(arc
					(start 148.764244 -389.634476)
					(mid 148.874215 -389.73553)
					(end 149.019006 -389.772144)
				)
				(arc
					(start 149.019006 -389.772144)
					(mid 149.234532 -389.68287)
					(end 149.323806 -389.467344)
				)
				(arc
					(start 149.323806 -389.467344)
					(mid 149.313469 -389.388605)
					(end 149.283166 -389.315198)
				)
				(arc
					(start 148.890736 -388.636256)
					(mid 148.778339 -388.514639)
					(end 148.618956 -388.469632)
				)
				(arc
					(start 148.618956 -388.469632)
					(mid 148.40343 -388.558906)
					(end 148.314156 -388.774432)
				)
				(arc
					(start 148.314156 -388.774432)
					(mid 148.323734 -388.850494)
					(end 148.352002 -388.921752)
				)
				(xy 148.749258 -389.609076) (xy 148.76145 -389.630412) (xy 148.76399 -389.63473)
			)
		)
	)
	(zone
		(layers "F.Cu" "B.Cu" "In1.Cu" "In2.Cu" "In3.Cu" "In4.Cu" "In5.Cu" "In6.Cu"
			"In7.Cu" "In8.Cu" "In9.Cu" "In10.Cu" "In11.Cu" "In12.Cu" "In13.Cu" "In14.Cu"
			"In15.Cu" "In16.Cu"
		)
		(hatch none 0.5)
		(connect_pads
			(clearance 0)
		)
		(min_thickness 0.25)
		(keepout
			(tracks not_allowed)
			(vias allowed)
			(pads allowed)
			(copperpour not_allowed)
			(footprints allowed)
		)
		(placement
			(enabled no)
			(sheetname "")
		)
		(fill
			(thermal_gap 0.5)
			(thermal_bridge_width 0.5)
			(island_removal_mode 0)
		)
		(polygon
			(pts
				(arc
					(start 284.386782 -403.351492)
					(mid 284.005782 -402.970492)
					(end 283.624782 -403.351492)
				)
				(arc
					(start 283.624782 -404.215092)
					(mid 284.005782 -404.596092)
					(end 284.386782 -404.215092)
				)
			)
		)
	)
	(zone
		(layers "F.Cu" "B.Cu" "In1.Cu" "In2.Cu" "In3.Cu" "In4.Cu" "In5.Cu" "In6.Cu"
			"In7.Cu" "In8.Cu" "In9.Cu" "In10.Cu" "In11.Cu" "In12.Cu" "In13.Cu" "In14.Cu"
			"In15.Cu" "In16.Cu"
		)
		(hatch none 0.5)
		(connect_pads
			(clearance 0)
		)
		(min_thickness 0.25)
		(keepout
			(tracks not_allowed)
			(vias allowed)
			(pads allowed)
			(copperpour not_allowed)
			(footprints allowed)
		)
		(placement
			(enabled no)
			(sheetname "")
		)
		(fill
			(thermal_gap 0.5)
			(thermal_bridge_width 0.5)
			(island_removal_mode 0)
		)
		(polygon
			(pts
				(arc
					(start 101.327204 -29.51861)
					(mid 101.708204 -29.89961)
					(end 102.089204 -29.51861)
				)
				(arc
					(start 102.089204 -28.65501)
					(mid 101.708204 -28.27401)
					(end 101.327204 -28.65501)
				)
			)
		)
	)
	(zone
		(layers "F.Cu" "B.Cu" "In1.Cu" "In2.Cu" "In3.Cu" "In4.Cu" "In5.Cu" "In6.Cu"
			"In7.Cu" "In8.Cu" "In9.Cu" "In10.Cu" "In11.Cu" "In12.Cu" "In13.Cu" "In14.Cu"
			"In15.Cu" "In16.Cu"
		)
		(hatch none 0.5)
		(connect_pads
			(clearance 0)
		)
		(min_thickness 0.25)
		(keepout
			(tracks not_allowed)
			(vias allowed)
			(pads allowed)
			(copperpour not_allowed)
			(footprints allowed)
		)
		(placement
			(enabled no)
			(sheetname "")
		)
		(fill
			(thermal_gap 0.5)
			(thermal_bridge_width 0.5)
			(island_removal_mode 0)
		)
		(polygon
			(pts
				(arc
					(start 305.325526 -418.031168)
					(mid 304.944526 -418.412168)
					(end 305.325526 -418.793168)
				)
				(arc
					(start 306.189126 -418.793168)
					(mid 306.570126 -418.412168)
					(end 306.189126 -418.031168)
				)
			)
		)
	)
	(zone
		(layers "F.Cu" "B.Cu" "In1.Cu" "In2.Cu" "In3.Cu" "In4.Cu" "In5.Cu" "In6.Cu"
			"In7.Cu" "In8.Cu" "In9.Cu" "In10.Cu" "In11.Cu" "In12.Cu" "In13.Cu" "In14.Cu"
			"In15.Cu" "In16.Cu"
		)
		(hatch none 0.5)
		(connect_pads
			(clearance 0)
		)
		(min_thickness 0.25)
		(keepout
			(tracks not_allowed)
			(vias allowed)
			(pads allowed)
			(copperpour not_allowed)
			(footprints allowed)
		)
		(placement
			(enabled no)
			(sheetname "")
		)
		(fill
			(thermal_gap 0.5)
			(thermal_bridge_width 0.5)
			(island_removal_mode 0)
		)
		(polygon
			(pts
				(arc
					(start 379.729492 -379.50013)
					(mid 379.348492 -379.88113)
					(end 379.729492 -380.26213)
				)
				(arc
					(start 380.593092 -380.26213)
					(mid 380.974092 -379.88113)
					(end 380.593092 -379.50013)
				)
			)
		)
	)
	(zone
		(layers "F.Cu" "B.Cu" "In1.Cu" "In2.Cu" "In3.Cu" "In4.Cu" "In5.Cu" "In6.Cu"
			"In7.Cu" "In8.Cu" "In9.Cu" "In10.Cu" "In11.Cu" "In12.Cu" "In13.Cu" "In14.Cu"
			"In15.Cu" "In16.Cu"
		)
		(hatch none 0.5)
		(connect_pads
			(clearance 0)
		)
		(min_thickness 0.25)
		(keepout
			(tracks not_allowed)
			(vias allowed)
			(pads allowed)
			(copperpour not_allowed)
			(footprints allowed)
		)
		(placement
			(enabled no)
			(sheetname "")
		)
		(fill
			(thermal_gap 0.5)
			(thermal_bridge_width 0.5)
			(island_removal_mode 0)
		)
		(polygon
			(pts
				(arc
					(start 170.335702 -10.404856)
					(mid 169.954702 -10.785856)
					(end 170.335702 -11.166856)
				)
				(arc
					(start 171.199302 -11.166856)
					(mid 171.580302 -10.785856)
					(end 171.199302 -10.404856)
				)
			)
		)
	)
	(zone
		(layers "F.Cu" "B.Cu" "In1.Cu" "In2.Cu" "In3.Cu" "In4.Cu" "In5.Cu" "In6.Cu"
			"In7.Cu" "In8.Cu" "In9.Cu" "In10.Cu" "In11.Cu" "In12.Cu" "In13.Cu" "In14.Cu"
			"In15.Cu" "In16.Cu"
		)
		(hatch none 0.5)
		(connect_pads
			(clearance 0)
		)
		(min_thickness 0.25)
		(keepout
			(tracks not_allowed)
			(vias allowed)
			(pads allowed)
			(copperpour not_allowed)
			(footprints allowed)
		)
		(placement
			(enabled no)
			(sheetname "")
		)
		(fill
			(thermal_gap 0.5)
			(thermal_bridge_width 0.5)
			(island_removal_mode 0)
		)
		(polygon
			(pts
				(arc
					(start 407.652982 -420.571168)
					(mid 407.271982 -420.952168)
					(end 407.652982 -421.333168)
				)
				(arc
					(start 408.516582 -421.333168)
					(mid 408.897582 -420.952168)
					(end 408.516582 -420.571168)
				)
			)
		)
	)
	(zone
		(layers "F.Cu" "B.Cu" "In1.Cu" "In2.Cu" "In3.Cu" "In4.Cu" "In5.Cu" "In6.Cu"
			"In7.Cu" "In8.Cu" "In9.Cu" "In10.Cu" "In11.Cu" "In12.Cu" "In13.Cu" "In14.Cu"
			"In15.Cu" "In16.Cu"
		)
		(hatch none 0.5)
		(connect_pads
			(clearance 0)
		)
		(min_thickness 0.25)
		(keepout
			(tracks not_allowed)
			(vias allowed)
			(pads allowed)
			(copperpour not_allowed)
			(footprints allowed)
		)
		(placement
			(enabled no)
			(sheetname "")
		)
		(fill
			(thermal_gap 0.5)
			(thermal_bridge_width 0.5)
			(island_removal_mode 0)
		)
		(polygon
			(pts
				(arc
					(start 48.197516 -392.429238)
					(mid 47.816516 -392.048238)
					(end 47.435516 -392.429238)
				)
				(arc
					(start 47.435516 -393.292838)
					(mid 47.816516 -393.673838)
					(end 48.197516 -393.292838)
				)
			)
		)
	)
	(zone
		(layers "F.Cu" "B.Cu" "In1.Cu" "In2.Cu" "In3.Cu" "In4.Cu" "In5.Cu" "In6.Cu"
			"In7.Cu" "In8.Cu" "In9.Cu" "In10.Cu" "In11.Cu" "In12.Cu" "In13.Cu" "In14.Cu"
			"In15.Cu" "In16.Cu"
		)
		(hatch none 0.5)
		(connect_pads
			(clearance 0)
		)
		(min_thickness 0.25)
		(keepout
			(tracks not_allowed)
			(vias allowed)
			(pads allowed)
			(copperpour not_allowed)
			(footprints allowed)
		)
		(placement
			(enabled no)
			(sheetname "")
		)
		(fill
			(thermal_gap 0.5)
			(thermal_bridge_width 0.5)
			(island_removal_mode 0)
		)
		(polygon
			(pts
				(arc
					(start 345.147646 -415.00552)
					(mid 344.766646 -415.38652)
					(end 345.147646 -415.76752)
				)
				(arc
					(start 346.011246 -415.76752)
					(mid 346.392246 -415.38652)
					(end 346.011246 -415.00552)
				)
			)
		)
	)
	(zone
		(layers "F.Cu" "B.Cu" "In1.Cu" "In2.Cu" "In3.Cu" "In4.Cu" "In5.Cu" "In6.Cu"
			"In7.Cu" "In8.Cu" "In9.Cu" "In10.Cu" "In11.Cu" "In12.Cu" "In13.Cu" "In14.Cu"
			"In15.Cu" "In16.Cu"
		)
		(hatch none 0.5)
		(connect_pads
			(clearance 0)
		)
		(min_thickness 0.25)
		(keepout
			(tracks not_allowed)
			(vias allowed)
			(pads allowed)
			(copperpour not_allowed)
			(footprints allowed)
		)
		(placement
			(enabled no)
			(sheetname "")
		)
		(fill
			(thermal_gap 0.5)
			(thermal_bridge_width 0.5)
			(island_removal_mode 0)
		)
		(polygon
			(pts
				(arc
					(start 56.629554 -371.11813)
					(mid 56.248554 -371.49913)
					(end 56.629554 -371.88013)
				)
				(arc
					(start 57.493154 -371.88013)
					(mid 57.874154 -371.49913)
					(end 57.493154 -371.11813)
				)
			)
		)
	)
	(zone
		(layers "F.Cu" "B.Cu" "In1.Cu" "In2.Cu" "In3.Cu" "In4.Cu" "In5.Cu" "In6.Cu"
			"In7.Cu" "In8.Cu" "In9.Cu" "In10.Cu" "In11.Cu" "In12.Cu" "In13.Cu" "In14.Cu"
			"In15.Cu" "In16.Cu"
		)
		(hatch none 0.5)
		(connect_pads
			(clearance 0)
		)
		(min_thickness 0.25)
		(keepout
			(tracks not_allowed)
			(vias allowed)
			(pads allowed)
			(copperpour not_allowed)
			(footprints allowed)
		)
		(placement
			(enabled no)
			(sheetname "")
		)
		(fill
			(thermal_gap 0.5)
			(thermal_bridge_width 0.5)
			(island_removal_mode 0)
		)
		(polygon
			(pts
				(arc
					(start 52.389024 -406.62352)
					(mid 52.008024 -407.00452)
					(end 52.389024 -407.38552)
				)
				(arc
					(start 53.252624 -407.38552)
					(mid 53.633624 -407.00452)
					(end 53.252624 -406.62352)
				)
			)
		)
	)
	(zone
		(layers "F.Cu" "B.Cu" "In1.Cu" "In2.Cu" "In3.Cu" "In4.Cu" "In5.Cu" "In6.Cu"
			"In7.Cu" "In8.Cu" "In9.Cu" "In10.Cu" "In11.Cu" "In12.Cu" "In13.Cu" "In14.Cu"
			"In15.Cu" "In16.Cu"
		)
		(hatch none 0.5)
		(connect_pads
			(clearance 0)
		)
		(min_thickness 0.25)
		(keepout
			(tracks not_allowed)
			(vias allowed)
			(pads allowed)
			(copperpour not_allowed)
			(footprints allowed)
		)
		(placement
			(enabled no)
			(sheetname "")
		)
		(fill
			(thermal_gap 0.5)
			(thermal_bridge_width 0.5)
			(island_removal_mode 0)
		)
		(polygon
			(pts
				(arc
					(start 331.363066 -412.46552)
					(mid 330.982066 -412.84652)
					(end 331.363066 -413.22752)
				)
				(arc
					(start 332.226666 -413.22752)
					(mid 332.607666 -412.84652)
					(end 332.226666 -412.46552)
				)
			)
		)
	)
	(zone
		(layers "F.Cu" "B.Cu" "In1.Cu" "In2.Cu" "In3.Cu" "In4.Cu" "In5.Cu" "In6.Cu"
			"In7.Cu" "In8.Cu" "In9.Cu" "In10.Cu" "In11.Cu" "In12.Cu" "In13.Cu" "In14.Cu"
			"In15.Cu" "In16.Cu"
		)
		(hatch none 0.5)
		(connect_pads
			(clearance 0)
		)
		(min_thickness 0.25)
		(keepout
			(tracks not_allowed)
			(vias allowed)
			(pads allowed)
			(copperpour not_allowed)
			(footprints allowed)
		)
		(placement
			(enabled no)
			(sheetname "")
		)
		(fill
			(thermal_gap 0.5)
			(thermal_bridge_width 0.5)
			(island_removal_mode 0)
		)
		(polygon
			(pts
				(arc
					(start 71.658734 -376.093228)
					(mid 71.277734 -375.712228)
					(end 70.896734 -376.093228)
				)
				(arc
					(start 70.896734 -376.956828)
					(mid 71.277734 -377.337828)
					(end 71.658734 -376.956828)
				)
			)
		)
	)
	(zone
		(layers "F.Cu" "B.Cu" "In1.Cu" "In2.Cu" "In3.Cu" "In4.Cu" "In5.Cu" "In6.Cu"
			"In7.Cu" "In8.Cu" "In9.Cu" "In10.Cu" "In11.Cu" "In12.Cu" "In13.Cu" "In14.Cu"
			"In15.Cu" "In16.Cu"
		)
		(hatch none 0.5)
		(connect_pads
			(clearance 0)
		)
		(min_thickness 0.25)
		(keepout
			(tracks not_allowed)
			(vias allowed)
			(pads allowed)
			(copperpour not_allowed)
			(footprints allowed)
		)
		(placement
			(enabled no)
			(sheetname "")
		)
		(fill
			(thermal_gap 0.5)
			(thermal_bridge_width 0.5)
			(island_removal_mode 0)
		)
		(polygon
			(pts
				(arc
					(start 58.736484 -389.634476)
					(mid 58.846455 -389.73553)
					(end 58.991246 -389.772144)
				)
				(arc
					(start 58.991246 -389.772144)
					(mid 59.206772 -389.68287)
					(end 59.296046 -389.467344)
				)
				(arc
					(start 59.296046 -389.467344)
					(mid 59.285709 -389.388605)
					(end 59.255406 -389.315198)
				)
				(arc
					(start 58.862976 -388.636256)
					(mid 58.750579 -388.514639)
					(end 58.591196 -388.469632)
				)
				(arc
					(start 58.591196 -388.469632)
					(mid 58.37567 -388.558906)
					(end 58.286396 -388.774432)
				)
				(arc
					(start 58.286396 -388.774432)
					(mid 58.295974 -388.850494)
					(end 58.324242 -388.921752)
				)
				(xy 58.721498 -389.609076) (xy 58.73369 -389.630412) (xy 58.73623 -389.63473)
			)
		)
	)
	(zone
		(layers "F.Cu" "B.Cu" "In1.Cu" "In2.Cu" "In3.Cu" "In4.Cu" "In5.Cu" "In6.Cu"
			"In7.Cu" "In8.Cu" "In9.Cu" "In10.Cu" "In11.Cu" "In12.Cu" "In13.Cu" "In14.Cu"
			"In15.Cu" "In16.Cu"
		)
		(hatch none 0.5)
		(connect_pads
			(clearance 0)
		)
		(min_thickness 0.25)
		(keepout
			(tracks not_allowed)
			(vias allowed)
			(pads allowed)
			(copperpour not_allowed)
			(footprints allowed)
		)
		(placement
			(enabled no)
			(sheetname "")
		)
		(fill
			(thermal_gap 0.5)
			(thermal_bridge_width 0.5)
			(island_removal_mode 0)
		)
		(polygon
			(pts
				(arc
					(start 382.097534 -400.811238)
					(mid 381.716534 -400.430238)
					(end 381.335534 -400.811238)
				)
				(arc
					(start 381.335534 -401.674838)
					(mid 381.716534 -402.055838)
					(end 382.097534 -401.674838)
				)
			)
		)
	)
	(zone
		(layers "F.Cu" "B.Cu" "In1.Cu" "In2.Cu" "In3.Cu" "In4.Cu" "In5.Cu" "In6.Cu"
			"In7.Cu" "In8.Cu" "In9.Cu" "In10.Cu" "In11.Cu" "In12.Cu" "In13.Cu" "In14.Cu"
			"In15.Cu" "In16.Cu"
		)
		(hatch none 0.5)
		(connect_pads
			(clearance 0)
		)
		(min_thickness 0.25)
		(keepout
			(tracks not_allowed)
			(vias allowed)
			(pads allowed)
			(copperpour not_allowed)
			(footprints allowed)
		)
		(placement
			(enabled no)
			(sheetname "")
		)
		(fill
			(thermal_gap 0.5)
			(thermal_bridge_width 0.5)
			(island_removal_mode 0)
		)
		(polygon
			(pts
				(arc
					(start 378.552202 -415.00552)
					(mid 378.171202 -415.38652)
					(end 378.552202 -415.76752)
				)
				(arc
					(start 379.415802 -415.76752)
					(mid 379.796802 -415.38652)
					(end 379.415802 -415.00552)
				)
			)
		)
	)
	(zone
		(layers "F.Cu" "B.Cu" "In1.Cu" "In2.Cu" "In3.Cu" "In4.Cu" "In5.Cu" "In6.Cu"
			"In7.Cu" "In8.Cu" "In9.Cu" "In10.Cu" "In11.Cu" "In12.Cu" "In13.Cu" "In14.Cu"
			"In15.Cu" "In16.Cu"
		)
		(hatch none 0.5)
		(connect_pads
			(clearance 0)
		)
		(min_thickness 0.25)
		(keepout
			(tracks not_allowed)
			(vias allowed)
			(pads allowed)
			(copperpour not_allowed)
			(footprints allowed)
		)
		(placement
			(enabled no)
			(sheetname "")
		)
		(fill
			(thermal_gap 0.5)
			(thermal_bridge_width 0.5)
			(island_removal_mode 0)
		)
		(polygon
			(pts
				(arc
					(start 415.56432 -398.016476)
					(mid 415.674291 -398.11753)
					(end 415.819082 -398.154144)
				)
				(arc
					(start 415.819082 -398.154144)
					(mid 416.034608 -398.06487)
					(end 416.123882 -397.849344)
				)
				(arc
					(start 416.123882 -397.849344)
					(mid 416.113545 -397.770605)
					(end 416.083242 -397.697198)
				)
				(arc
					(start 415.690812 -397.018256)
					(mid 415.578415 -396.896639)
					(end 415.419032 -396.851632)
				)
				(arc
					(start 415.419032 -396.851632)
					(mid 415.203506 -396.940906)
					(end 415.114232 -397.156432)
				)
				(arc
					(start 415.114232 -397.156432)
					(mid 415.12381 -397.232494)
					(end 415.152078 -397.303752)
				)
				(xy 415.549334 -397.991076) (xy 415.561526 -398.012412) (xy 415.564066 -398.01673)
			)
		)
	)
	(zone
		(layers "F.Cu" "B.Cu" "In1.Cu" "In2.Cu" "In3.Cu" "In4.Cu" "In5.Cu" "In6.Cu"
			"In7.Cu" "In8.Cu" "In9.Cu" "In10.Cu" "In11.Cu" "In12.Cu" "In13.Cu" "In14.Cu"
			"In15.Cu" "In16.Cu"
		)
		(hatch none 0.5)
		(connect_pads
			(clearance 0)
		)
		(min_thickness 0.25)
		(keepout
			(tracks not_allowed)
			(vias allowed)
			(pads allowed)
			(copperpour not_allowed)
			(footprints allowed)
		)
		(placement
			(enabled no)
			(sheetname "")
		)
		(fill
			(thermal_gap 0.5)
			(thermal_bridge_width 0.5)
			(island_removal_mode 0)
		)
		(polygon
			(pts
				(arc
					(start 213.51875 -5.508244)
					(mid 213.95055 -5.940044)
					(end 214.38235 -5.508244)
				)
				(arc
					(start 214.38235 -4.644644)
					(mid 213.95055 -4.212844)
					(end 213.51875 -4.644644)
				)
			)
		)
	)
	(zone
		(layers "F.Cu" "B.Cu" "In1.Cu" "In2.Cu" "In3.Cu" "In4.Cu" "In5.Cu" "In6.Cu"
			"In7.Cu" "In8.Cu" "In9.Cu" "In10.Cu" "In11.Cu" "In12.Cu" "In13.Cu" "In14.Cu"
			"In15.Cu" "In16.Cu"
		)
		(hatch none 0.5)
		(connect_pads
			(clearance 0)
		)
		(min_thickness 0.25)
		(keepout
			(tracks not_allowed)
			(vias allowed)
			(pads allowed)
			(copperpour not_allowed)
			(footprints allowed)
		)
		(placement
			(enabled no)
			(sheetname "")
		)
		(fill
			(thermal_gap 0.5)
			(thermal_bridge_width 0.5)
			(island_removal_mode 0)
		)
		(polygon
			(pts
				(arc
					(start 353.525074 -400.811238)
					(mid 353.144074 -400.430238)
					(end 352.763074 -400.811238)
				)
				(arc
					(start 352.763074 -401.674838)
					(mid 353.144074 -402.055838)
					(end 353.525074 -401.674838)
				)
			)
		)
	)
	(zone
		(layers "F.Cu" "B.Cu" "In1.Cu" "In2.Cu" "In3.Cu" "In4.Cu" "In5.Cu" "In6.Cu"
			"In7.Cu" "In8.Cu" "In9.Cu" "In10.Cu" "In11.Cu" "In12.Cu" "In13.Cu" "In14.Cu"
			"In15.Cu" "In16.Cu"
		)
		(hatch none 0.5)
		(connect_pads
			(clearance 0)
		)
		(min_thickness 0.25)
		(keepout
			(tracks not_allowed)
			(vias allowed)
			(pads allowed)
			(copperpour not_allowed)
			(footprints allowed)
		)
		(placement
			(enabled no)
			(sheetname "")
		)
		(fill yes
			(thermal_gap 0.5)
			(thermal_bridge_width 0.5)
			(island_removal_mode 0)
		)
		(polygon
			(pts
				(arc
					(start 305.136296 -394.552424)
					(mid 305.246267 -394.653478)
					(end 305.391058 -394.690092)
				)
				(arc
					(start 305.391058 -394.690092)
					(mid 305.606584 -394.600818)
					(end 305.695858 -394.385292)
				)
				(arc
					(start 305.695858 -394.385292)
					(mid 305.685521 -394.306553)
					(end 305.655218 -394.233146)
				)
				(arc
					(start 305.262788 -393.554204)
					(mid 305.150391 -393.432587)
					(end 304.991008 -393.38758)
				)
				(arc
					(start 304.991008 -393.38758)
					(mid 304.775482 -393.476854)
					(end 304.686208 -393.69238)
				)
				(arc
					(start 304.686208 -393.69238)
					(mid 304.695786 -393.768442)
					(end 304.724054 -393.8397)
				)
				(xy 305.12131 -394.527024) (xy 305.133502 -394.54836) (xy 305.136042 -394.552678)
			)
		)
	)
	(zone
		(layers "F.Cu" "B.Cu" "In1.Cu" "In2.Cu" "In3.Cu" "In4.Cu" "In5.Cu" "In6.Cu"
			"In7.Cu" "In8.Cu" "In9.Cu" "In10.Cu" "In11.Cu" "In12.Cu" "In13.Cu" "In14.Cu"
			"In15.Cu" "In16.Cu"
		)
		(hatch none 0.5)
		(connect_pads
			(clearance 0)
		)
		(min_thickness 0.25)
		(keepout
			(tracks not_allowed)
			(vias allowed)
			(pads allowed)
			(copperpour not_allowed)
			(footprints allowed)
		)
		(placement
			(enabled no)
			(sheetname "")
		)
		(fill
			(thermal_gap 0.5)
			(thermal_bridge_width 0.5)
			(island_removal_mode 0)
		)
		(polygon
			(pts
				(arc
					(start 413.95904 -377.03633)
					(mid 413.57804 -377.41733)
					(end 413.95904 -377.79833)
				)
				(arc
					(start 414.82264 -377.79833)
					(mid 415.20364 -377.41733)
					(end 414.82264 -377.03633)
				)
			)
		)
	)
	(zone
		(layers "F.Cu" "B.Cu" "In1.Cu" "In2.Cu" "In3.Cu" "In4.Cu" "In5.Cu" "In6.Cu"
			"In7.Cu" "In8.Cu" "In9.Cu" "In10.Cu" "In11.Cu" "In12.Cu" "In13.Cu" "In14.Cu"
			"In15.Cu" "In16.Cu"
		)
		(hatch none 0.5)
		(connect_pads
			(clearance 0)
		)
		(min_thickness 0.25)
		(keepout
			(tracks not_allowed)
			(vias allowed)
			(pads allowed)
			(copperpour not_allowed)
			(footprints allowed)
		)
		(placement
			(enabled no)
			(sheetname "")
		)
		(fill
			(thermal_gap 0.5)
			(thermal_bridge_width 0.5)
			(island_removal_mode 0)
		)
		(polygon
			(pts
				(arc
					(start 122.497596 -392.429238)
					(mid 122.116596 -392.048238)
					(end 121.735596 -392.429238)
				)
				(arc
					(start 121.735596 -393.292838)
					(mid 122.116596 -393.673838)
					(end 122.497596 -393.292838)
				)
			)
		)
	)
	(zone
		(layers "F.Cu" "B.Cu" "In1.Cu" "In2.Cu" "In3.Cu" "In4.Cu" "In5.Cu" "In6.Cu"
			"In7.Cu" "In8.Cu" "In9.Cu" "In10.Cu" "In11.Cu" "In12.Cu" "In13.Cu" "In14.Cu"
			"In15.Cu" "In16.Cu"
		)
		(hatch none 0.5)
		(connect_pads
			(clearance 0)
		)
		(min_thickness 0.25)
		(keepout
			(tracks not_allowed)
			(vias allowed)
			(pads allowed)
			(copperpour not_allowed)
			(footprints allowed)
		)
		(placement
			(enabled no)
			(sheetname "")
		)
		(fill
			(thermal_gap 0.5)
			(thermal_bridge_width 0.5)
			(island_removal_mode 0)
		)
		(polygon
			(pts
				(arc
					(start 80.447134 -6.169914)
					(mid 78.516734 -6.169914)
					(end 80.447134 -6.169914)
				)
			)
		)
	)
	(zone
		(layers "F.Cu" "B.Cu" "In1.Cu" "In2.Cu" "In3.Cu" "In4.Cu" "In5.Cu" "In6.Cu"
			"In7.Cu" "In8.Cu" "In9.Cu" "In10.Cu" "In11.Cu" "In12.Cu" "In13.Cu" "In14.Cu"
			"In15.Cu" "In16.Cu"
		)
		(hatch none 0.5)
		(connect_pads
			(clearance 0)
		)
		(min_thickness 0.25)
		(keepout
			(tracks not_allowed)
			(vias allowed)
			(pads allowed)
			(copperpour not_allowed)
			(footprints allowed)
		)
		(placement
			(enabled no)
			(sheetname "")
		)
		(fill
			(thermal_gap 0.5)
			(thermal_bridge_width 0.5)
			(island_removal_mode 0)
		)
		(polygon
			(pts
				(arc
					(start 98.46437 -389.634476)
					(mid 98.574341 -389.73553)
					(end 98.719132 -389.772144)
				)
				(arc
					(start 98.719132 -389.772144)
					(mid 98.934658 -389.68287)
					(end 99.023932 -389.467344)
				)
				(arc
					(start 99.023932 -389.467344)
					(mid 99.013595 -389.388605)
					(end 98.983292 -389.315198)
				)
				(arc
					(start 98.590862 -388.636256)
					(mid 98.478465 -388.514639)
					(end 98.319082 -388.469632)
				)
				(arc
					(start 98.319082 -388.469632)
					(mid 98.103556 -388.558906)
					(end 98.014282 -388.774432)
				)
				(arc
					(start 98.014282 -388.774432)
					(mid 98.02386 -388.850494)
					(end 98.052128 -388.921752)
				)
				(xy 98.449384 -389.609076) (xy 98.461576 -389.630412) (xy 98.464116 -389.63473)
			)
		)
	)
	(zone
		(layers "F.Cu" "B.Cu" "In1.Cu" "In2.Cu" "In3.Cu" "In4.Cu" "In5.Cu" "In6.Cu"
			"In7.Cu" "In8.Cu" "In9.Cu" "In10.Cu" "In11.Cu" "In12.Cu" "In13.Cu" "In14.Cu"
			"In15.Cu" "In16.Cu"
		)
		(hatch none 0.5)
		(connect_pads
			(clearance 0)
		)
		(min_thickness 0.25)
		(keepout
			(tracks not_allowed)
			(vias allowed)
			(pads allowed)
			(copperpour not_allowed)
			(footprints allowed)
		)
		(placement
			(enabled no)
			(sheetname "")
		)
		(fill
			(thermal_gap 0.5)
			(thermal_bridge_width 0.5)
			(island_removal_mode 0)
		)
		(polygon
			(pts
				(arc
					(start 41.20769 -415.383726)
					(mid 41.58869 -415.764726)
					(end 41.96969 -415.383726)
				)
				(arc
					(start 41.96969 -414.520126)
					(mid 41.58869 -414.139126)
					(end 41.20769 -414.520126)
				)
			)
		)
	)
	(zone
		(layers "F.Cu" "B.Cu" "In1.Cu" "In2.Cu" "In3.Cu" "In4.Cu" "In5.Cu" "In6.Cu"
			"In7.Cu" "In8.Cu" "In9.Cu" "In10.Cu" "In11.Cu" "In12.Cu" "In13.Cu" "In14.Cu"
			"In15.Cu" "In16.Cu"
		)
		(hatch none 0.5)
		(connect_pads
			(clearance 0)
		)
		(min_thickness 0.25)
		(keepout
			(tracks not_allowed)
			(vias allowed)
			(pads allowed)
			(copperpour not_allowed)
			(footprints allowed)
		)
		(placement
			(enabled no)
			(sheetname "")
		)
		(fill
			(thermal_gap 0.5)
			(thermal_bridge_width 0.5)
			(island_removal_mode 0)
		)
		(polygon
			(pts
				(arc
					(start 59.936634 -389.634476)
					(mid 60.046605 -389.73553)
					(end 60.191396 -389.772144)
				)
				(arc
					(start 60.191396 -389.772144)
					(mid 60.406922 -389.68287)
					(end 60.496196 -389.467344)
				)
				(arc
					(start 60.496196 -389.467344)
					(mid 60.485859 -389.388605)
					(end 60.455556 -389.315198)
				)
				(arc
					(start 60.063126 -388.636256)
					(mid 59.950729 -388.514639)
					(end 59.791346 -388.469632)
				)
				(arc
					(start 59.791346 -388.469632)
					(mid 59.57582 -388.558906)
					(end 59.486546 -388.774432)
				)
				(arc
					(start 59.486546 -388.774432)
					(mid 59.496124 -388.850494)
					(end 59.524392 -388.921752)
				)
				(xy 59.921648 -389.609076) (xy 59.93384 -389.630412) (xy 59.93638 -389.63473)
			)
		)
	)
	(zone
		(layers "F.Cu" "B.Cu" "In1.Cu" "In2.Cu" "In3.Cu" "In4.Cu" "In5.Cu" "In6.Cu"
			"In7.Cu" "In8.Cu" "In9.Cu" "In10.Cu" "In11.Cu" "In12.Cu" "In13.Cu" "In14.Cu"
			"In15.Cu" "In16.Cu"
		)
		(hatch none 0.5)
		(connect_pads
			(clearance 0)
		)
		(min_thickness 0.25)
		(keepout
			(tracks not_allowed)
			(vias allowed)
			(pads allowed)
			(copperpour not_allowed)
			(footprints allowed)
		)
		(placement
			(enabled no)
			(sheetname "")
		)
		(fill yes
			(thermal_gap 0.5)
			(thermal_bridge_width 0.5)
			(island_removal_mode 0)
		)
		(polygon
			(pts
				(arc
					(start 128.236472 -386.170424)
					(mid 128.346443 -386.271478)
					(end 128.491234 -386.308092)
				)
				(arc
					(start 128.491234 -386.308092)
					(mid 128.70676 -386.218818)
					(end 128.796034 -386.003292)
				)
				(arc
					(start 128.796034 -386.003292)
					(mid 128.785697 -385.924553)
					(end 128.755394 -385.851146)
				)
				(arc
					(start 128.362964 -385.172204)
					(mid 128.250567 -385.050587)
					(end 128.091184 -385.00558)
				)
				(arc
					(start 128.091184 -385.00558)
					(mid 127.875658 -385.094854)
					(end 127.786384 -385.31038)
				)
				(arc
					(start 127.786384 -385.31038)
					(mid 127.795962 -385.386442)
					(end 127.82423 -385.4577)
				)
				(xy 128.221486 -386.145024) (xy 128.233678 -386.16636) (xy 128.236218 -386.170678)
			)
		)
	)
	(zone
		(layers "F.Cu" "B.Cu" "In1.Cu" "In2.Cu" "In3.Cu" "In4.Cu" "In5.Cu" "In6.Cu"
			"In7.Cu" "In8.Cu" "In9.Cu" "In10.Cu" "In11.Cu" "In12.Cu" "In13.Cu" "In14.Cu"
			"In15.Cu" "In16.Cu"
		)
		(hatch none 0.5)
		(connect_pads
			(clearance 0)
		)
		(min_thickness 0.25)
		(keepout
			(tracks not_allowed)
			(vias allowed)
			(pads allowed)
			(copperpour not_allowed)
			(footprints allowed)
		)
		(placement
			(enabled no)
			(sheetname "")
		)
		(fill
			(thermal_gap 0.5)
			(thermal_bridge_width 0.5)
			(island_removal_mode 0)
		)
		(polygon
			(pts
				(arc
					(start 93.742764 -404.08352)
					(mid 93.361764 -404.46452)
					(end 93.742764 -404.84552)
				)
				(arc
					(start 94.606364 -404.84552)
					(mid 94.987364 -404.46452)
					(end 94.606364 -404.08352)
				)
			)
		)
	)
	(zone
		(layers "F.Cu" "B.Cu" "In1.Cu" "In2.Cu" "In3.Cu" "In4.Cu" "In5.Cu" "In6.Cu"
			"In7.Cu" "In8.Cu" "In9.Cu" "In10.Cu" "In11.Cu" "In12.Cu" "In13.Cu" "In14.Cu"
			"In15.Cu" "In16.Cu"
		)
		(hatch none 0.5)
		(connect_pads
			(clearance 0)
		)
		(min_thickness 0.25)
		(keepout
			(tracks not_allowed)
			(vias allowed)
			(pads allowed)
			(copperpour not_allowed)
			(footprints allowed)
		)
		(placement
			(enabled no)
			(sheetname "")
		)
		(fill
			(thermal_gap 0.5)
			(thermal_bridge_width 0.5)
			(island_removal_mode 0)
		)
		(polygon
			(pts
				(arc
					(start 140.23467 -28.118562)
					(mid 139.85367 -28.499562)
					(end 140.23467 -28.880562)
				)
				(arc
					(start 141.09827 -28.880562)
					(mid 141.47927 -28.499562)
					(end 141.09827 -28.118562)
				)
			)
		)
	)
	(zone
		(layers "F.Cu" "B.Cu" "In1.Cu" "In2.Cu" "In3.Cu" "In4.Cu" "In5.Cu" "In6.Cu"
			"In7.Cu" "In8.Cu" "In9.Cu" "In10.Cu" "In11.Cu" "In12.Cu" "In13.Cu" "In14.Cu"
			"In15.Cu" "In16.Cu"
		)
		(hatch none 0.5)
		(connect_pads
			(clearance 0)
		)
		(min_thickness 0.25)
		(keepout
			(tracks not_allowed)
			(vias allowed)
			(pads allowed)
			(copperpour not_allowed)
			(footprints allowed)
		)
		(placement
			(enabled no)
			(sheetname "")
		)
		(fill yes
			(thermal_gap 0.5)
			(thermal_bridge_width 0.5)
			(island_removal_mode 0)
		)
		(polygon
			(pts
				(arc
					(start 98.46437 -386.170424)
					(mid 98.574341 -386.271478)
					(end 98.719132 -386.308092)
				)
				(arc
					(start 98.719132 -386.308092)
					(mid 98.934658 -386.218818)
					(end 99.023932 -386.003292)
				)
				(arc
					(start 99.023932 -386.003292)
					(mid 99.013595 -385.924553)
					(end 98.983292 -385.851146)
				)
				(arc
					(start 98.590862 -385.172204)
					(mid 98.478465 -385.050587)
					(end 98.319082 -385.00558)
				)
				(arc
					(start 98.319082 -385.00558)
					(mid 98.103556 -385.094854)
					(end 98.014282 -385.31038)
				)
				(arc
					(start 98.014282 -385.31038)
					(mid 98.02386 -385.386442)
					(end 98.052128 -385.4577)
				)
				(xy 98.449384 -386.145024) (xy 98.461576 -386.16636) (xy 98.464116 -386.170678)
			)
		)
	)
	(zone
		(layers "F.Cu" "B.Cu" "In1.Cu" "In2.Cu" "In3.Cu" "In4.Cu" "In5.Cu" "In6.Cu"
			"In7.Cu" "In8.Cu" "In9.Cu" "In10.Cu" "In11.Cu" "In12.Cu" "In13.Cu" "In14.Cu"
			"In15.Cu" "In16.Cu"
		)
		(hatch none 0.5)
		(connect_pads
			(clearance 0)
		)
		(min_thickness 0.25)
		(keepout
			(tracks not_allowed)
			(vias allowed)
			(pads allowed)
			(copperpour not_allowed)
			(footprints allowed)
		)
		(placement
			(enabled no)
			(sheetname "")
		)
		(fill
			(thermal_gap 0.5)
			(thermal_bridge_width 0.5)
			(island_removal_mode 0)
		)
		(polygon
			(pts
				(arc
					(start 394.758672 -384.475228)
					(mid 394.377672 -384.094228)
					(end 393.996672 -384.475228)
				)
				(arc
					(start 393.996672 -385.338828)
					(mid 394.377672 -385.719828)
					(end 394.758672 -385.338828)
				)
			)
		)
	)
	(zone
		(layers "F.Cu" "B.Cu" "In1.Cu" "In2.Cu" "In3.Cu" "In4.Cu" "In5.Cu" "In6.Cu"
			"In7.Cu" "In8.Cu" "In9.Cu" "In10.Cu" "In11.Cu" "In12.Cu" "In13.Cu" "In14.Cu"
			"In15.Cu" "In16.Cu"
		)
		(hatch none 0.5)
		(connect_pads
			(clearance 0)
		)
		(min_thickness 0.25)
		(keepout
			(tracks not_allowed)
			(vias allowed)
			(pads allowed)
			(copperpour not_allowed)
			(footprints allowed)
		)
		(placement
			(enabled no)
			(sheetname "")
		)
		(fill
			(thermal_gap 0.5)
			(thermal_bridge_width 0.5)
			(island_removal_mode 0)
		)
		(polygon
			(pts
				(arc
					(start 315.936376 -398.016476)
					(mid 316.046347 -398.11753)
					(end 316.191138 -398.154144)
				)
				(arc
					(start 316.191138 -398.154144)
					(mid 316.406664 -398.06487)
					(end 316.495938 -397.849344)
				)
				(arc
					(start 316.495938 -397.849344)
					(mid 316.485601 -397.770605)
					(end 316.455298 -397.697198)
				)
				(arc
					(start 316.062868 -397.018256)
					(mid 315.950471 -396.896639)
					(end 315.791088 -396.851632)
				)
				(arc
					(start 315.791088 -396.851632)
					(mid 315.575562 -396.940906)
					(end 315.486288 -397.156432)
				)
				(arc
					(start 315.486288 -397.156432)
					(mid 315.495866 -397.232494)
					(end 315.524134 -397.303752)
				)
				(xy 315.92139 -397.991076) (xy 315.933582 -398.012412) (xy 315.936122 -398.01673)
			)
		)
	)
	(zone
		(layers "F.Cu" "B.Cu" "In1.Cu" "In2.Cu" "In3.Cu" "In4.Cu" "In5.Cu" "In6.Cu"
			"In7.Cu" "In8.Cu" "In9.Cu" "In10.Cu" "In11.Cu" "In12.Cu" "In13.Cu" "In14.Cu"
			"In15.Cu" "In16.Cu"
		)
		(hatch none 0.5)
		(connect_pads
			(clearance 0)
		)
		(min_thickness 0.25)
		(keepout
			(tracks not_allowed)
			(vias allowed)
			(pads allowed)
			(copperpour not_allowed)
			(footprints allowed)
		)
		(placement
			(enabled no)
			(sheetname "")
		)
		(fill
			(thermal_gap 0.5)
			(thermal_bridge_width 0.5)
			(island_removal_mode 0)
		)
		(polygon
			(pts
				(arc
					(start 477.39554 -328.073258)
					(mid 473.20454 -328.073258)
					(end 477.39554 -328.073258)
				)
			)
		)
	)
	(zone
		(layers "F.Cu" "B.Cu" "In1.Cu" "In2.Cu" "In3.Cu" "In4.Cu" "In5.Cu" "In6.Cu"
			"In7.Cu" "In8.Cu" "In9.Cu" "In10.Cu" "In11.Cu" "In12.Cu" "In13.Cu" "In14.Cu"
			"In15.Cu" "In16.Cu"
		)
		(hatch none 0.5)
		(connect_pads
			(clearance 0)
		)
		(min_thickness 0.25)
		(keepout
			(tracks not_allowed)
			(vias allowed)
			(pads allowed)
			(copperpour not_allowed)
			(footprints allowed)
		)
		(placement
			(enabled no)
			(sheetname "")
		)
		(fill
			(thermal_gap 0.5)
			(thermal_bridge_width 0.5)
			(island_removal_mode 0)
		)
		(polygon
			(pts
				(arc
					(start 94.864174 -389.634476)
					(mid 94.974145 -389.73553)
					(end 95.118936 -389.772144)
				)
				(arc
					(start 95.118936 -389.772144)
					(mid 95.334462 -389.68287)
					(end 95.423736 -389.467344)
				)
				(arc
					(start 95.423736 -389.467344)
					(mid 95.413399 -389.388605)
					(end 95.383096 -389.315198)
				)
				(arc
					(start 94.990666 -388.636256)
					(mid 94.878269 -388.514639)
					(end 94.718886 -388.469632)
				)
				(arc
					(start 94.718886 -388.469632)
					(mid 94.50336 -388.558906)
					(end 94.414086 -388.774432)
				)
				(arc
					(start 94.414086 -388.774432)
					(mid 94.423664 -388.850494)
					(end 94.451932 -388.921752)
				)
				(xy 94.849188 -389.609076) (xy 94.86138 -389.630412) (xy 94.86392 -389.63473)
			)
		)
	)
	(zone
		(layers "F.Cu" "B.Cu" "In1.Cu" "In2.Cu" "In3.Cu" "In4.Cu" "In5.Cu" "In6.Cu"
			"In7.Cu" "In8.Cu" "In9.Cu" "In10.Cu" "In11.Cu" "In12.Cu" "In13.Cu" "In14.Cu"
			"In15.Cu" "In16.Cu"
		)
		(hatch none 0.5)
		(connect_pads
			(clearance 0)
		)
		(min_thickness 0.25)
		(keepout
			(tracks not_allowed)
			(vias allowed)
			(pads allowed)
			(copperpour not_allowed)
			(footprints allowed)
		)
		(placement
			(enabled no)
			(sheetname "")
		)
		(fill
			(thermal_gap 0.5)
			(thermal_bridge_width 0.5)
			(island_removal_mode 0)
		)
		(polygon
			(pts
				(arc
					(start 47.794164 -404.08352)
					(mid 47.413164 -404.46452)
					(end 47.794164 -404.84552)
				)
				(arc
					(start 48.657764 -404.84552)
					(mid 49.038764 -404.46452)
					(end 48.657764 -404.08352)
				)
			)
		)
	)
	(zone
		(layers "F.Cu" "B.Cu" "In1.Cu" "In2.Cu" "In3.Cu" "In4.Cu" "In5.Cu" "In6.Cu"
			"In7.Cu" "In8.Cu" "In9.Cu" "In10.Cu" "In11.Cu" "In12.Cu" "In13.Cu" "In14.Cu"
			"In15.Cu" "In16.Cu"
		)
		(hatch none 0.5)
		(connect_pads
			(clearance 0)
		)
		(min_thickness 0.25)
		(keepout
			(tracks not_allowed)
			(vias allowed)
			(pads allowed)
			(copperpour not_allowed)
			(footprints allowed)
		)
		(placement
			(enabled no)
			(sheetname "")
		)
		(fill
			(thermal_gap 0.5)
			(thermal_bridge_width 0.5)
			(island_removal_mode 0)
		)
		(polygon
			(pts
				(arc
					(start 421.072564 -18.756122)
					(mid 420.691564 -19.137122)
					(end 421.072564 -19.518122)
				)
				(arc
					(start 421.936164 -19.518122)
					(mid 422.317164 -19.137122)
					(end 421.936164 -18.756122)
				)
			)
		)
	)
	(zone
		(layers "F.Cu" "B.Cu" "In1.Cu" "In2.Cu" "In3.Cu" "In4.Cu" "In5.Cu" "In6.Cu"
			"In7.Cu" "In8.Cu" "In9.Cu" "In10.Cu" "In11.Cu" "In12.Cu" "In13.Cu" "In14.Cu"
			"In15.Cu" "In16.Cu"
		)
		(hatch none 0.5)
		(connect_pads
			(clearance 0)
		)
		(min_thickness 0.25)
		(keepout
			(tracks not_allowed)
			(vias allowed)
			(pads allowed)
			(copperpour not_allowed)
			(footprints allowed)
		)
		(placement
			(enabled no)
			(sheetname "")
		)
		(fill
			(thermal_gap 0.5)
			(thermal_bridge_width 0.5)
			(island_removal_mode 0)
		)
		(polygon
			(pts
				(arc
					(start 11.714226 -106.447336)
					(mid 12.095226 -106.828336)
					(end 12.476226 -106.447336)
				)
				(arc
					(start 12.476226 -105.456736)
					(mid 12.095226 -105.075736)
					(end 11.714226 -105.456736)
				)
			)
		)
	)
	(zone
		(layers "F.Cu" "B.Cu" "In1.Cu" "In2.Cu" "In3.Cu" "In4.Cu" "In5.Cu" "In6.Cu"
			"In7.Cu" "In8.Cu" "In9.Cu" "In10.Cu" "In11.Cu" "In12.Cu" "In13.Cu" "In14.Cu"
			"In15.Cu" "In16.Cu"
		)
		(hatch none 0.5)
		(connect_pads
			(clearance 0)
		)
		(min_thickness 0.25)
		(keepout
			(tracks not_allowed)
			(vias allowed)
			(pads allowed)
			(copperpour not_allowed)
			(footprints allowed)
		)
		(placement
			(enabled no)
			(sheetname "")
		)
		(fill
			(thermal_gap 0.5)
			(thermal_bridge_width 0.5)
			(island_removal_mode 0)
		)
		(polygon
			(pts
				(arc
					(start 155.964128 -389.634476)
					(mid 156.074099 -389.73553)
					(end 156.21889 -389.772144)
				)
				(arc
					(start 156.21889 -389.772144)
					(mid 156.434416 -389.68287)
					(end 156.52369 -389.467344)
				)
				(arc
					(start 156.52369 -389.467344)
					(mid 156.513353 -389.388605)
					(end 156.48305 -389.315198)
				)
				(arc
					(start 156.09062 -388.636256)
					(mid 155.978223 -388.514639)
					(end 155.81884 -388.469632)
				)
				(arc
					(start 155.81884 -388.469632)
					(mid 155.603314 -388.558906)
					(end 155.51404 -388.774432)
				)
				(arc
					(start 155.51404 -388.774432)
					(mid 155.523618 -388.850494)
					(end 155.551886 -388.921752)
				)
				(xy 155.949142 -389.609076) (xy 155.961334 -389.630412) (xy 155.963874 -389.63473)
			)
		)
	)
	(zone
		(layers "F.Cu" "B.Cu" "In1.Cu" "In2.Cu" "In3.Cu" "In4.Cu" "In5.Cu" "In6.Cu"
			"In7.Cu" "In8.Cu" "In9.Cu" "In10.Cu" "In11.Cu" "In12.Cu" "In13.Cu" "In14.Cu"
			"In15.Cu" "In16.Cu"
		)
		(hatch none 0.5)
		(connect_pads
			(clearance 0)
		)
		(min_thickness 0.25)
		(keepout
			(tracks not_allowed)
			(vias allowed)
			(pads allowed)
			(copperpour not_allowed)
			(footprints allowed)
		)
		(placement
			(enabled no)
			(sheetname "")
		)
		(fill
			(thermal_gap 0.5)
			(thermal_bridge_width 0.5)
			(island_removal_mode 0)
		)
		(polygon
			(pts
				(arc
					(start 58.331354 -368.65433)
					(mid 57.950354 -369.03533)
					(end 58.331354 -369.41633)
				)
				(arc
					(start 59.194954 -369.41633)
					(mid 59.575954 -369.03533)
					(end 59.194954 -368.65433)
				)
			)
		)
	)
	(zone
		(layers "F.Cu" "B.Cu" "In1.Cu" "In2.Cu" "In3.Cu" "In4.Cu" "In5.Cu" "In6.Cu"
			"In7.Cu" "In8.Cu" "In9.Cu" "In10.Cu" "In11.Cu" "In12.Cu" "In13.Cu" "In14.Cu"
			"In15.Cu" "In16.Cu"
		)
		(hatch none 0.5)
		(connect_pads
			(clearance 0)
		)
		(min_thickness 0.25)
		(keepout
			(tracks not_allowed)
			(vias allowed)
			(pads allowed)
			(copperpour not_allowed)
			(footprints allowed)
		)
		(placement
			(enabled no)
			(sheetname "")
		)
		(fill
			(thermal_gap 0.5)
			(thermal_bridge_width 0.5)
			(island_removal_mode 0)
		)
		(polygon
			(pts
				(arc
					(start 312.629296 -379.50013)
					(mid 312.248296 -379.88113)
					(end 312.629296 -380.26213)
				)
				(arc
					(start 313.492896 -380.26213)
					(mid 313.873896 -379.88113)
					(end 313.492896 -379.50013)
				)
			)
		)
	)
	(zone
		(layers "F.Cu" "B.Cu" "In1.Cu" "In2.Cu" "In3.Cu" "In4.Cu" "In5.Cu" "In6.Cu"
			"In7.Cu" "In8.Cu" "In9.Cu" "In10.Cu" "In11.Cu" "In12.Cu" "In13.Cu" "In14.Cu"
			"In15.Cu" "In16.Cu"
		)
		(hatch none 0.5)
		(connect_pads
			(clearance 0)
		)
		(min_thickness 0.25)
		(keepout
			(tracks not_allowed)
			(vias allowed)
			(pads allowed)
			(copperpour not_allowed)
			(footprints allowed)
		)
		(placement
			(enabled no)
			(sheetname "")
		)
		(fill
			(thermal_gap 0.5)
			(thermal_bridge_width 0.5)
			(island_removal_mode 0)
		)
		(polygon
			(pts
				(arc
					(start 97.525332 -392.429238)
					(mid 97.144332 -392.048238)
					(end 96.763332 -392.429238)
				)
				(arc
					(start 96.763332 -393.292838)
					(mid 97.144332 -393.673838)
					(end 97.525332 -393.292838)
				)
			)
		)
	)
	(zone
		(layers "F.Cu" "B.Cu" "In1.Cu" "In2.Cu" "In3.Cu" "In4.Cu" "In5.Cu" "In6.Cu"
			"In7.Cu" "In8.Cu" "In9.Cu" "In10.Cu" "In11.Cu" "In12.Cu" "In13.Cu" "In14.Cu"
			"In15.Cu" "In16.Cu"
		)
		(hatch none 0.5)
		(connect_pads
			(clearance 0)
		)
		(min_thickness 0.25)
		(keepout
			(tracks not_allowed)
			(vias allowed)
			(pads allowed)
			(copperpour not_allowed)
			(footprints allowed)
		)
		(placement
			(enabled no)
			(sheetname "")
		)
		(fill
			(thermal_gap 0.5)
			(thermal_bridge_width 0.5)
			(island_removal_mode 0)
		)
		(polygon
			(pts
				(arc
					(start 285.949136 -421.94607)
					(mid 285.568136 -422.32707)
					(end 285.949136 -422.70807)
				)
				(arc
					(start 286.812736 -422.70807)
					(mid 287.193736 -422.32707)
					(end 286.812736 -421.94607)
				)
			)
		)
	)
	(zone
		(layers "F.Cu" "B.Cu" "In1.Cu" "In2.Cu" "In3.Cu" "In4.Cu" "In5.Cu" "In6.Cu"
			"In7.Cu" "In8.Cu" "In9.Cu" "In10.Cu" "In11.Cu" "In12.Cu" "In13.Cu" "In14.Cu"
			"In15.Cu" "In16.Cu"
		)
		(hatch none 0.5)
		(connect_pads
			(clearance 0)
		)
		(min_thickness 0.25)
		(keepout
			(tracks not_allowed)
			(vias allowed)
			(pads allowed)
			(copperpour not_allowed)
			(footprints allowed)
		)
		(placement
			(enabled no)
			(sheetname "")
		)
		(fill
			(thermal_gap 0.5)
			(thermal_bridge_width 0.5)
			(island_removal_mode 0)
		)
		(polygon
			(pts
				(arc
					(start 421.564308 -398.016476)
					(mid 421.674279 -398.11753)
					(end 421.81907 -398.154144)
				)
				(arc
					(start 421.81907 -398.154144)
					(mid 422.034596 -398.06487)
					(end 422.12387 -397.849344)
				)
				(arc
					(start 422.12387 -397.849344)
					(mid 422.113533 -397.770605)
					(end 422.08323 -397.697198)
				)
				(arc
					(start 421.6908 -397.018256)
					(mid 421.578403 -396.896639)
					(end 421.41902 -396.851632)
				)
				(arc
					(start 421.41902 -396.851632)
					(mid 421.203494 -396.940906)
					(end 421.11422 -397.156432)
				)
				(arc
					(start 421.11422 -397.156432)
					(mid 421.123798 -397.232494)
					(end 421.152066 -397.303752)
				)
				(xy 421.549322 -397.991076) (xy 421.561514 -398.012412) (xy 421.564054 -398.01673)
			)
		)
	)
	(zone
		(layers "F.Cu" "B.Cu" "In1.Cu" "In2.Cu" "In3.Cu" "In4.Cu" "In5.Cu" "In6.Cu"
			"In7.Cu" "In8.Cu" "In9.Cu" "In10.Cu" "In11.Cu" "In12.Cu" "In13.Cu" "In14.Cu"
			"In15.Cu" "In16.Cu"
		)
		(hatch none 0.5)
		(connect_pads
			(clearance 0)
		)
		(min_thickness 0.25)
		(keepout
			(tracks not_allowed)
			(vias allowed)
			(pads allowed)
			(copperpour not_allowed)
			(footprints allowed)
		)
		(placement
			(enabled no)
			(sheetname "")
		)
		(fill
			(thermal_gap 0.5)
			(thermal_bridge_width 0.5)
			(island_removal_mode 0)
		)
		(polygon
			(pts
				(arc
					(start 364.380272 7.191756)
					(mid 364.812072 6.759956)
					(end 365.243872 7.191756)
				)
				(arc
					(start 365.243872 8.055356)
					(mid 364.812072 8.487156)
					(end 364.380272 8.055356)
				)
			)
		)
	)
	(zone
		(layers "F.Cu" "B.Cu" "In1.Cu" "In2.Cu" "In3.Cu" "In4.Cu" "In5.Cu" "In6.Cu"
			"In7.Cu" "In8.Cu" "In9.Cu" "In10.Cu" "In11.Cu" "In12.Cu" "In13.Cu" "In14.Cu"
			"In15.Cu" "In16.Cu"
		)
		(hatch none 0.5)
		(connect_pads
			(clearance 0)
		)
		(min_thickness 0.25)
		(keepout
			(tracks not_allowed)
			(vias allowed)
			(pads allowed)
			(copperpour not_allowed)
			(footprints allowed)
		)
		(placement
			(enabled no)
			(sheetname "")
		)
		(fill yes
			(thermal_gap 0.5)
			(thermal_bridge_width 0.5)
			(island_removal_mode 0)
		)
		(polygon
			(pts
				(arc
					(start 50.33645 -386.170424)
					(mid 50.446421 -386.271478)
					(end 50.591212 -386.308092)
				)
				(arc
					(start 50.591212 -386.308092)
					(mid 50.806738 -386.218818)
					(end 50.896012 -386.003292)
				)
				(arc
					(start 50.896012 -386.003292)
					(mid 50.885675 -385.924553)
					(end 50.855372 -385.851146)
				)
				(arc
					(start 50.462942 -385.172204)
					(mid 50.350545 -385.050587)
					(end 50.191162 -385.00558)
				)
				(arc
					(start 50.191162 -385.00558)
					(mid 49.975636 -385.094854)
					(end 49.886362 -385.31038)
				)
				(arc
					(start 49.886362 -385.31038)
					(mid 49.89594 -385.386442)
					(end 49.924208 -385.4577)
				)
				(xy 50.321464 -386.145024) (xy 50.333656 -386.16636) (xy 50.336196 -386.170678)
			)
		)
	)
	(zone
		(layers "F.Cu" "B.Cu" "In1.Cu" "In2.Cu" "In3.Cu" "In4.Cu" "In5.Cu" "In6.Cu"
			"In7.Cu" "In8.Cu" "In9.Cu" "In10.Cu" "In11.Cu" "In12.Cu" "In13.Cu" "In14.Cu"
			"In15.Cu" "In16.Cu"
		)
		(hatch none 0.5)
		(connect_pads
			(clearance 0)
		)
		(min_thickness 0.25)
		(keepout
			(tracks not_allowed)
			(vias allowed)
			(pads allowed)
			(copperpour not_allowed)
			(footprints allowed)
		)
		(placement
			(enabled no)
			(sheetname "")
		)
		(fill
			(thermal_gap 0.5)
			(thermal_bridge_width 0.5)
			(island_removal_mode 0)
		)
		(polygon
			(pts
				(arc
					(start 374.636538 -398.016476)
					(mid 374.746509 -398.11753)
					(end 374.8913 -398.154144)
				)
				(arc
					(start 374.8913 -398.154144)
					(mid 375.106826 -398.06487)
					(end 375.1961 -397.849344)
				)
				(arc
					(start 375.1961 -397.849344)
					(mid 375.185763 -397.770605)
					(end 375.15546 -397.697198)
				)
				(arc
					(start 374.76303 -397.018256)
					(mid 374.650633 -396.896639)
					(end 374.49125 -396.851632)
				)
				(arc
					(start 374.49125 -396.851632)
					(mid 374.275724 -396.940906)
					(end 374.18645 -397.156432)
				)
				(arc
					(start 374.18645 -397.156432)
					(mid 374.196028 -397.232494)
					(end 374.224296 -397.303752)
				)
				(xy 374.621552 -397.991076) (xy 374.633744 -398.012412) (xy 374.636284 -398.01673)
			)
		)
	)
	(zone
		(layers "F.Cu" "B.Cu" "In1.Cu" "In2.Cu" "In3.Cu" "In4.Cu" "In5.Cu" "In6.Cu"
			"In7.Cu" "In8.Cu" "In9.Cu" "In10.Cu" "In11.Cu" "In12.Cu" "In13.Cu" "In14.Cu"
			"In15.Cu" "In16.Cu"
		)
		(hatch none 0.5)
		(connect_pads
			(clearance 0)
		)
		(min_thickness 0.25)
		(keepout
			(tracks not_allowed)
			(vias allowed)
			(pads allowed)
			(copperpour not_allowed)
			(footprints allowed)
		)
		(placement
			(enabled no)
			(sheetname "")
		)
		(fill
			(thermal_gap 0.5)
			(thermal_bridge_width 0.5)
			(island_removal_mode 0)
		)
		(polygon
			(pts
				(arc
					(start 406.121362 -415.00552)
					(mid 405.740362 -415.38652)
					(end 406.121362 -415.76752)
				)
				(arc
					(start 406.984962 -415.76752)
					(mid 407.365962 -415.38652)
					(end 406.984962 -415.00552)
				)
			)
		)
	)
	(zone
		(layers "F.Cu" "B.Cu" "In1.Cu" "In2.Cu" "In3.Cu" "In4.Cu" "In5.Cu" "In6.Cu"
			"In7.Cu" "In8.Cu" "In9.Cu" "In10.Cu" "In11.Cu" "In12.Cu" "In13.Cu" "In14.Cu"
			"In15.Cu" "In16.Cu"
		)
		(hatch none 0.5)
		(connect_pads
			(clearance 0)
		)
		(min_thickness 0.25)
		(keepout
			(tracks not_allowed)
			(vias allowed)
			(pads allowed)
			(copperpour not_allowed)
			(footprints allowed)
		)
		(placement
			(enabled no)
			(sheetname "")
		)
		(fill
			(thermal_gap 0.5)
			(thermal_bridge_width 0.5)
			(island_removal_mode 0)
		)
		(polygon
			(pts
				(arc
					(start 118.624096 -368.65433)
					(mid 118.243096 -369.03533)
					(end 118.624096 -369.41633)
				)
				(arc
					(start 119.487696 -369.41633)
					(mid 119.868696 -369.03533)
					(end 119.487696 -368.65433)
				)
			)
		)
	)
	(zone
		(layers "F.Cu" "B.Cu" "In1.Cu" "In2.Cu" "In3.Cu" "In4.Cu" "In5.Cu" "In6.Cu"
			"In7.Cu" "In8.Cu" "In9.Cu" "In10.Cu" "In11.Cu" "In12.Cu" "In13.Cu" "In14.Cu"
			"In15.Cu" "In16.Cu"
		)
		(hatch none 0.5)
		(connect_pads
			(clearance 0)
		)
		(min_thickness 0.25)
		(keepout
			(tracks not_allowed)
			(vias allowed)
			(pads allowed)
			(copperpour not_allowed)
			(footprints allowed)
		)
		(placement
			(enabled no)
			(sheetname "")
		)
		(fill
			(thermal_gap 0.5)
			(thermal_bridge_width 0.5)
			(island_removal_mode 0)
		)
		(polygon
			(pts
				(arc
					(start 69.236844 -404.08352)
					(mid 68.855844 -404.46452)
					(end 69.236844 -404.84552)
				)
				(arc
					(start 70.100444 -404.84552)
					(mid 70.481444 -404.46452)
					(end 70.100444 -404.08352)
				)
			)
		)
	)
	(zone
		(layers "F.Cu" "B.Cu" "In1.Cu" "In2.Cu" "In3.Cu" "In4.Cu" "In5.Cu" "In6.Cu"
			"In7.Cu" "In8.Cu" "In9.Cu" "In10.Cu" "In11.Cu" "In12.Cu" "In13.Cu" "In14.Cu"
			"In15.Cu" "In16.Cu"
		)
		(hatch none 0.5)
		(connect_pads
			(clearance 0)
		)
		(min_thickness 0.25)
		(keepout
			(tracks not_allowed)
			(vias allowed)
			(pads allowed)
			(copperpour not_allowed)
			(footprints allowed)
		)
		(placement
			(enabled no)
			(sheetname "")
		)
		(fill
			(thermal_gap 0.5)
			(thermal_bridge_width 0.5)
			(island_removal_mode 0)
		)
		(polygon
			(pts
				(arc
					(start 84.051902 -368.65433)
					(mid 83.670902 -369.03533)
					(end 84.051902 -369.41633)
				)
				(arc
					(start 84.915502 -369.41633)
					(mid 85.296502 -369.03533)
					(end 84.915502 -368.65433)
				)
			)
		)
	)
	(zone
		(layers "F.Cu" "B.Cu" "In1.Cu" "In2.Cu" "In3.Cu" "In4.Cu" "In5.Cu" "In6.Cu"
			"In7.Cu" "In8.Cu" "In9.Cu" "In10.Cu" "In11.Cu" "In12.Cu" "In13.Cu" "In14.Cu"
			"In15.Cu" "In16.Cu"
		)
		(hatch none 0.5)
		(connect_pads
			(clearance 0)
		)
		(min_thickness 0.25)
		(keepout
			(tracks not_allowed)
			(vias allowed)
			(pads allowed)
			(copperpour not_allowed)
			(footprints allowed)
		)
		(placement
			(enabled no)
			(sheetname "")
		)
		(fill yes
			(thermal_gap 0.5)
			(thermal_bridge_width 0.5)
			(island_removal_mode 0)
		)
		(polygon
			(pts
				(arc
					(start 154.764232 -386.170424)
					(mid 154.874203 -386.271478)
					(end 155.018994 -386.308092)
				)
				(arc
					(start 155.018994 -386.308092)
					(mid 155.23452 -386.218818)
					(end 155.323794 -386.003292)
				)
				(arc
					(start 155.323794 -386.003292)
					(mid 155.313457 -385.924553)
					(end 155.283154 -385.851146)
				)
				(arc
					(start 154.890724 -385.172204)
					(mid 154.778327 -385.050587)
					(end 154.618944 -385.00558)
				)
				(arc
					(start 154.618944 -385.00558)
					(mid 154.403418 -385.094854)
					(end 154.314144 -385.31038)
				)
				(arc
					(start 154.314144 -385.31038)
					(mid 154.323722 -385.386442)
					(end 154.35199 -385.4577)
				)
				(xy 154.749246 -386.145024) (xy 154.761438 -386.16636) (xy 154.763978 -386.170678)
			)
		)
	)
	(zone
		(layers "F.Cu" "B.Cu" "In1.Cu" "In2.Cu" "In3.Cu" "In4.Cu" "In5.Cu" "In6.Cu"
			"In7.Cu" "In8.Cu" "In9.Cu" "In10.Cu" "In11.Cu" "In12.Cu" "In13.Cu" "In14.Cu"
			"In15.Cu" "In16.Cu"
		)
		(hatch none 0.5)
		(connect_pads
			(clearance 0)
		)
		(min_thickness 0.25)
		(keepout
			(tracks not_allowed)
			(vias allowed)
			(pads allowed)
			(copperpour not_allowed)
			(footprints allowed)
		)
		(placement
			(enabled no)
			(sheetname "")
		)
		(fill
			(thermal_gap 0.5)
			(thermal_bridge_width 0.5)
			(island_removal_mode 0)
		)
		(polygon
			(pts
				(arc
					(start 85.264244 -389.634476)
					(mid 85.374215 -389.73553)
					(end 85.519006 -389.772144)
				)
				(arc
					(start 85.519006 -389.772144)
					(mid 85.734532 -389.68287)
					(end 85.823806 -389.467344)
				)
				(arc
					(start 85.823806 -389.467344)
					(mid 85.813469 -389.388605)
					(end 85.783166 -389.315198)
				)
				(arc
					(start 85.390736 -388.636256)
					(mid 85.278339 -388.514639)
					(end 85.118956 -388.469632)
				)
				(arc
					(start 85.118956 -388.469632)
					(mid 84.90343 -388.558906)
					(end 84.814156 -388.774432)
				)
				(arc
					(start 84.814156 -388.774432)
					(mid 84.823734 -388.850494)
					(end 84.852002 -388.921752)
				)
				(xy 85.249258 -389.609076) (xy 85.26145 -389.630412) (xy 85.26399 -389.63473)
			)
		)
	)
	(zone
		(layers "F.Cu" "B.Cu" "In1.Cu" "In2.Cu" "In3.Cu" "In4.Cu" "In5.Cu" "In6.Cu"
			"In7.Cu" "In8.Cu" "In9.Cu" "In10.Cu" "In11.Cu" "In12.Cu" "In13.Cu" "In14.Cu"
			"In15.Cu" "In16.Cu"
		)
		(hatch none 0.5)
		(connect_pads
			(clearance 0)
		)
		(min_thickness 0.25)
		(keepout
			(tracks not_allowed)
			(vias allowed)
			(pads allowed)
			(copperpour not_allowed)
			(footprints allowed)
		)
		(placement
			(enabled no)
			(sheetname "")
		)
		(fill
			(thermal_gap 0.5)
			(thermal_bridge_width 0.5)
			(island_removal_mode 0)
		)
		(polygon
			(pts
				(arc
					(start 327.658476 -384.475228)
					(mid 327.277476 -384.094228)
					(end 326.896476 -384.475228)
				)
				(arc
					(start 326.896476 -385.338828)
					(mid 327.277476 -385.719828)
					(end 327.658476 -385.338828)
				)
			)
		)
	)
	(zone
		(layers "F.Cu" "B.Cu" "In1.Cu" "In2.Cu" "In3.Cu" "In4.Cu" "In5.Cu" "In6.Cu"
			"In7.Cu" "In8.Cu" "In9.Cu" "In10.Cu" "In11.Cu" "In12.Cu" "In13.Cu" "In14.Cu"
			"In15.Cu" "In16.Cu"
		)
		(hatch none 0.5)
		(connect_pads
			(clearance 0)
		)
		(min_thickness 0.25)
		(keepout
			(tracks not_allowed)
			(vias allowed)
			(pads allowed)
			(copperpour not_allowed)
			(footprints allowed)
		)
		(placement
			(enabled no)
			(sheetname "")
		)
		(fill
			(thermal_gap 0.5)
			(thermal_bridge_width 0.5)
			(island_removal_mode 0)
		)
		(polygon
			(pts
				(arc
					(start 404.003764 -18.75536)
					(mid 403.622764 -19.13636)
					(end 404.003764 -19.51736)
				)
				(arc
					(start 404.867364 -19.51736)
					(mid 405.248364 -19.13636)
					(end 404.867364 -18.75536)
				)
			)
		)
	)
	(zone
		(layers "F.Cu" "B.Cu" "In1.Cu" "In2.Cu" "In3.Cu" "In4.Cu" "In5.Cu" "In6.Cu"
			"In7.Cu" "In8.Cu" "In9.Cu" "In10.Cu" "In11.Cu" "In12.Cu" "In13.Cu" "In14.Cu"
			"In15.Cu" "In16.Cu"
		)
		(hatch none 0.5)
		(connect_pads
			(clearance 0)
		)
		(min_thickness 0.25)
		(keepout
			(tracks not_allowed)
			(vias allowed)
			(pads allowed)
			(copperpour not_allowed)
			(footprints allowed)
		)
		(placement
			(enabled no)
			(sheetname "")
		)
		(fill
			(thermal_gap 0.5)
			(thermal_bridge_width 0.5)
			(island_removal_mode 0)
		)
		(polygon
			(pts
				(arc
					(start 87.616284 -412.189168)
					(mid 87.235284 -412.570168)
					(end 87.616284 -412.951168)
				)
				(arc
					(start 88.479884 -412.951168)
					(mid 88.860884 -412.570168)
					(end 88.479884 -412.189168)
				)
			)
		)
	)
	(zone
		(layers "F.Cu" "B.Cu" "In1.Cu" "In2.Cu" "In3.Cu" "In4.Cu" "In5.Cu" "In6.Cu"
			"In7.Cu" "In8.Cu" "In9.Cu" "In10.Cu" "In11.Cu" "In12.Cu" "In13.Cu" "In14.Cu"
			"In15.Cu" "In16.Cu"
		)
		(hatch none 0.5)
		(connect_pads
			(clearance 0)
		)
		(min_thickness 0.25)
		(keepout
			(tracks not_allowed)
			(vias allowed)
			(pads allowed)
			(copperpour not_allowed)
			(footprints allowed)
		)
		(placement
			(enabled no)
			(sheetname "")
		)
		(fill
			(thermal_gap 0.5)
			(thermal_bridge_width 0.5)
			(island_removal_mode 0)
		)
		(polygon
			(pts
				(arc
					(start 319.110106 -412.46552)
					(mid 318.729106 -412.84652)
					(end 319.110106 -413.22752)
				)
				(arc
					(start 319.973706 -413.22752)
					(mid 320.354706 -412.84652)
					(end 319.973706 -412.46552)
				)
			)
		)
	)
	(zone
		(layers "F.Cu" "B.Cu" "In1.Cu" "In2.Cu" "In3.Cu" "In4.Cu" "In5.Cu" "In6.Cu"
			"In7.Cu" "In8.Cu" "In9.Cu" "In10.Cu" "In11.Cu" "In12.Cu" "In13.Cu" "In14.Cu"
			"In15.Cu" "In16.Cu"
		)
		(hatch none 0.5)
		(connect_pads
			(clearance 0)
		)
		(min_thickness 0.25)
		(keepout
			(tracks not_allowed)
			(vias allowed)
			(pads allowed)
			(copperpour not_allowed)
			(footprints allowed)
		)
		(placement
			(enabled no)
			(sheetname "")
		)
		(fill
			(thermal_gap 0.5)
			(thermal_bridge_width 0.5)
			(island_removal_mode 0)
		)
		(polygon
			(pts
				(arc
					(start 133.273546 -404.08352)
					(mid 132.892546 -404.46452)
					(end 133.273546 -404.84552)
				)
				(arc
					(start 134.137146 -404.84552)
					(mid 134.518146 -404.46452)
					(end 134.137146 -404.08352)
				)
			)
		)
	)
	(zone
		(layers "F.Cu" "B.Cu" "In1.Cu" "In2.Cu" "In3.Cu" "In4.Cu" "In5.Cu" "In6.Cu"
			"In7.Cu" "In8.Cu" "In9.Cu" "In10.Cu" "In11.Cu" "In12.Cu" "In13.Cu" "In14.Cu"
			"In15.Cu" "In16.Cu"
		)
		(hatch none 0.5)
		(connect_pads
			(clearance 0)
		)
		(min_thickness 0.25)
		(keepout
			(tracks not_allowed)
			(vias allowed)
			(pads allowed)
			(copperpour not_allowed)
			(footprints allowed)
		)
		(placement
			(enabled no)
			(sheetname "")
		)
		(fill yes
			(thermal_gap 0.5)
			(thermal_bridge_width 0.5)
			(island_removal_mode 0)
		)
		(polygon
			(pts
				(arc
					(start 117.436392 -386.170424)
					(mid 117.546363 -386.271478)
					(end 117.691154 -386.308092)
				)
				(arc
					(start 117.691154 -386.308092)
					(mid 117.90668 -386.218818)
					(end 117.995954 -386.003292)
				)
				(arc
					(start 117.995954 -386.003292)
					(mid 117.985617 -385.924553)
					(end 117.955314 -385.851146)
				)
				(arc
					(start 117.562884 -385.172204)
					(mid 117.450487 -385.050587)
					(end 117.291104 -385.00558)
				)
				(arc
					(start 117.291104 -385.00558)
					(mid 117.075578 -385.094854)
					(end 116.986304 -385.31038)
				)
				(arc
					(start 116.986304 -385.31038)
					(mid 116.995882 -385.386442)
					(end 117.02415 -385.4577)
				)
				(xy 117.421406 -386.145024) (xy 117.433598 -386.16636) (xy 117.436138 -386.170678)
			)
		)
	)
	(zone
		(layers "F.Cu" "B.Cu" "In1.Cu" "In2.Cu" "In3.Cu" "In4.Cu" "In5.Cu" "In6.Cu"
			"In7.Cu" "In8.Cu" "In9.Cu" "In10.Cu" "In11.Cu" "In12.Cu" "In13.Cu" "In14.Cu"
			"In15.Cu" "In16.Cu"
		)
		(hatch none 0.5)
		(connect_pads
			(clearance 0)
		)
		(min_thickness 0.25)
		(keepout
			(tracks not_allowed)
			(vias allowed)
			(pads allowed)
			(copperpour not_allowed)
			(footprints allowed)
		)
		(placement
			(enabled no)
			(sheetname "")
		)
		(fill
			(thermal_gap 0.5)
			(thermal_bridge_width 0.5)
			(island_removal_mode 0)
		)
		(polygon
			(pts
				(arc
					(start 306.336446 -394.552424)
					(mid 306.446417 -394.653478)
					(end 306.591208 -394.690092)
				)
				(arc
					(start 306.591208 -394.690092)
					(mid 306.806734 -394.600818)
					(end 306.896008 -394.385292)
				)
				(arc
					(start 306.896008 -394.385292)
					(mid 306.885671 -394.306553)
					(end 306.855368 -394.233146)
				)
				(arc
					(start 306.462938 -393.554204)
					(mid 306.350541 -393.432587)
					(end 306.191158 -393.38758)
				)
				(arc
					(start 306.191158 -393.38758)
					(mid 305.975632 -393.476854)
					(end 305.886358 -393.69238)
				)
				(arc
					(start 305.886358 -393.69238)
					(mid 305.895936 -393.768442)
					(end 305.924204 -393.8397)
				)
				(xy 306.32146 -394.527024) (xy 306.333652 -394.54836) (xy 306.336192 -394.552678)
			)
		)
	)
	(zone
		(layers "F.Cu" "B.Cu" "In1.Cu" "In2.Cu" "In3.Cu" "In4.Cu" "In5.Cu" "In6.Cu"
			"In7.Cu" "In8.Cu" "In9.Cu" "In10.Cu" "In11.Cu" "In12.Cu" "In13.Cu" "In14.Cu"
			"In15.Cu" "In16.Cu"
		)
		(hatch none 0.5)
		(connect_pads
			(clearance 0)
		)
		(min_thickness 0.25)
		(keepout
			(tracks not_allowed)
			(vias allowed)
			(pads allowed)
			(copperpour not_allowed)
			(footprints allowed)
		)
		(placement
			(enabled no)
			(sheetname "")
		)
		(fill yes
			(thermal_gap 0.5)
			(thermal_bridge_width 0.5)
			(island_removal_mode 0)
		)
		(polygon
			(pts
				(arc
					(start 97.26422 -386.170424)
					(mid 97.374191 -386.271478)
					(end 97.518982 -386.308092)
				)
				(arc
					(start 97.518982 -386.308092)
					(mid 97.734508 -386.218818)
					(end 97.823782 -386.003292)
				)
				(arc
					(start 97.823782 -386.003292)
					(mid 97.813445 -385.924553)
					(end 97.783142 -385.851146)
				)
				(arc
					(start 97.390712 -385.172204)
					(mid 97.278315 -385.050587)
					(end 97.118932 -385.00558)
				)
				(arc
					(start 97.118932 -385.00558)
					(mid 96.903406 -385.094854)
					(end 96.814132 -385.31038)
				)
				(arc
					(start 96.814132 -385.31038)
					(mid 96.82371 -385.386442)
					(end 96.851978 -385.4577)
				)
				(xy 97.249234 -386.145024) (xy 97.261426 -386.16636) (xy 97.263966 -386.170678)
			)
		)
	)
	(zone
		(layers "F.Cu" "B.Cu" "In1.Cu" "In2.Cu" "In3.Cu" "In4.Cu" "In5.Cu" "In6.Cu"
			"In7.Cu" "In8.Cu" "In9.Cu" "In10.Cu" "In11.Cu" "In12.Cu" "In13.Cu" "In14.Cu"
			"In15.Cu" "In16.Cu"
		)
		(hatch none 0.5)
		(connect_pads
			(clearance 0)
		)
		(min_thickness 0.25)
		(keepout
			(tracks not_allowed)
			(vias allowed)
			(pads allowed)
			(copperpour not_allowed)
			(footprints allowed)
		)
		(placement
			(enabled no)
			(sheetname "")
		)
		(fill
			(thermal_gap 0.5)
			(thermal_bridge_width 0.5)
			(island_removal_mode 0)
		)
		(polygon
			(pts
				(arc
					(start 128.834896 -373.58193)
					(mid 128.453896 -373.96293)
					(end 128.834896 -374.34393)
				)
				(arc
					(start 129.698496 -374.34393)
					(mid 130.079496 -373.96293)
					(end 129.698496 -373.58193)
				)
			)
		)
	)
	(zone
		(layers "F.Cu" "B.Cu" "In1.Cu" "In2.Cu" "In3.Cu" "In4.Cu" "In5.Cu" "In6.Cu"
			"In7.Cu" "In8.Cu" "In9.Cu" "In10.Cu" "In11.Cu" "In12.Cu" "In13.Cu" "In14.Cu"
			"In15.Cu" "In16.Cu"
		)
		(hatch none 0.5)
		(connect_pads
			(clearance 0)
		)
		(min_thickness 0.25)
		(keepout
			(tracks not_allowed)
			(vias allowed)
			(pads allowed)
			(copperpour not_allowed)
			(footprints allowed)
		)
		(placement
			(enabled no)
			(sheetname "")
		)
		(fill
			(thermal_gap 0.5)
			(thermal_bridge_width 0.5)
			(island_removal_mode 0)
		)
		(polygon
			(pts
				(arc
					(start 157.164278 -389.634476)
					(mid 157.274249 -389.73553)
					(end 157.41904 -389.772144)
				)
				(arc
					(start 157.41904 -389.772144)
					(mid 157.634566 -389.68287)
					(end 157.72384 -389.467344)
				)
				(arc
					(start 157.72384 -389.467344)
					(mid 157.713503 -389.388605)
					(end 157.6832 -389.315198)
				)
				(arc
					(start 157.29077 -388.636256)
					(mid 157.178373 -388.514639)
					(end 157.01899 -388.469632)
				)
				(arc
					(start 157.01899 -388.469632)
					(mid 156.803464 -388.558906)
					(end 156.71419 -388.774432)
				)
				(arc
					(start 156.71419 -388.774432)
					(mid 156.723768 -388.850494)
					(end 156.752036 -388.921752)
				)
				(xy 157.149292 -389.609076) (xy 157.161484 -389.630412) (xy 157.164024 -389.63473)
			)
		)
	)
	(zone
		(layers "F.Cu" "B.Cu" "In1.Cu" "In2.Cu" "In3.Cu" "In4.Cu" "In5.Cu" "In6.Cu"
			"In7.Cu" "In8.Cu" "In9.Cu" "In10.Cu" "In11.Cu" "In12.Cu" "In13.Cu" "In14.Cu"
			"In15.Cu" "In16.Cu"
		)
		(hatch none 0.5)
		(connect_pads
			(clearance 0)
		)
		(min_thickness 0.25)
		(keepout
			(tracks not_allowed)
			(vias allowed)
			(pads allowed)
			(copperpour not_allowed)
			(footprints allowed)
		)
		(placement
			(enabled no)
			(sheetname "")
		)
		(fill yes
			(thermal_gap 0.5)
			(thermal_bridge_width 0.5)
			(island_removal_mode 0)
		)
		(polygon
			(pts
				(arc
					(start 419.164262 -394.552424)
					(mid 419.274233 -394.653478)
					(end 419.419024 -394.690092)
				)
				(arc
					(start 419.419024 -394.690092)
					(mid 419.63455 -394.600818)
					(end 419.723824 -394.385292)
				)
				(arc
					(start 419.723824 -394.385292)
					(mid 419.713487 -394.306553)
					(end 419.683184 -394.233146)
				)
				(arc
					(start 419.290754 -393.554204)
					(mid 419.178357 -393.432587)
					(end 419.018974 -393.38758)
				)
				(arc
					(start 419.018974 -393.38758)
					(mid 418.803448 -393.476854)
					(end 418.714174 -393.69238)
				)
				(arc
					(start 418.714174 -393.69238)
					(mid 418.723752 -393.768442)
					(end 418.75202 -393.8397)
				)
				(xy 419.149276 -394.527024) (xy 419.161468 -394.54836) (xy 419.164008 -394.552678)
			)
		)
	)
	(zone
		(layers "F.Cu" "B.Cu" "In1.Cu" "In2.Cu" "In3.Cu" "In4.Cu" "In5.Cu" "In6.Cu"
			"In7.Cu" "In8.Cu" "In9.Cu" "In10.Cu" "In11.Cu" "In12.Cu" "In13.Cu" "In14.Cu"
			"In15.Cu" "In16.Cu"
		)
		(hatch none 0.5)
		(connect_pads
			(clearance 0)
		)
		(min_thickness 0.25)
		(keepout
			(tracks not_allowed)
			(vias allowed)
			(pads allowed)
			(copperpour not_allowed)
			(footprints allowed)
		)
		(placement
			(enabled no)
			(sheetname "")
		)
		(fill
			(thermal_gap 0.5)
			(thermal_bridge_width 0.5)
			(island_removal_mode 0)
		)
		(polygon
			(pts
				(arc
					(start 399.994882 -418.031168)
					(mid 399.613882 -418.412168)
					(end 399.994882 -418.793168)
				)
				(arc
					(start 400.858482 -418.793168)
					(mid 401.239482 -418.412168)
					(end 400.858482 -418.031168)
				)
			)
		)
	)
	(zone
		(layers "F.Cu" "B.Cu" "In1.Cu" "In2.Cu" "In3.Cu" "In4.Cu" "In5.Cu" "In6.Cu"
			"In7.Cu" "In8.Cu" "In9.Cu" "In10.Cu" "In11.Cu" "In12.Cu" "In13.Cu" "In14.Cu"
			"In15.Cu" "In16.Cu"
		)
		(hatch none 0.5)
		(connect_pads
			(clearance 0)
		)
		(min_thickness 0.25)
		(keepout
			(tracks not_allowed)
			(vias allowed)
			(pads allowed)
			(copperpour not_allowed)
			(footprints allowed)
		)
		(placement
			(enabled no)
			(sheetname "")
		)
		(fill
			(thermal_gap 0.5)
			(thermal_bridge_width 0.5)
			(island_removal_mode 0)
		)
		(polygon
			(pts
				(arc
					(start 445.830452 -6.344158)
					(mid 445.449452 -6.725158)
					(end 445.830452 -7.106158)
				)
				(arc
					(start 446.694052 -7.106158)
					(mid 447.075052 -6.725158)
					(end 446.694052 -6.344158)
				)
			)
		)
	)
	(zone
		(layers "F.Cu" "B.Cu" "In1.Cu" "In2.Cu" "In3.Cu" "In4.Cu" "In5.Cu" "In6.Cu"
			"In7.Cu" "In8.Cu" "In9.Cu" "In10.Cu" "In11.Cu" "In12.Cu" "In13.Cu" "In14.Cu"
			"In15.Cu" "In16.Cu"
		)
		(hatch none 0.5)
		(connect_pads
			(clearance 0)
		)
		(min_thickness 0.25)
		(keepout
			(tracks not_allowed)
			(vias allowed)
			(pads allowed)
			(copperpour not_allowed)
			(footprints allowed)
		)
		(placement
			(enabled no)
			(sheetname "")
		)
		(fill
			(thermal_gap 0.5)
			(thermal_bridge_width 0.5)
			(island_removal_mode 0)
		)
		(polygon
			(pts
				(arc
					(start 141.439392 -375.96826)
					(mid 141.058392 -375.58726)
					(end 140.677392 -375.96826)
				)
				(arc
					(start 140.677392 -376.83186)
					(mid 141.058392 -377.21286)
					(end 141.439392 -376.83186)
				)
			)
		)
	)
	(zone
		(layers "F.Cu" "B.Cu" "In1.Cu" "In2.Cu" "In3.Cu" "In4.Cu" "In5.Cu" "In6.Cu"
			"In7.Cu" "In8.Cu" "In9.Cu" "In10.Cu" "In11.Cu" "In12.Cu" "In13.Cu" "In14.Cu"
			"In15.Cu" "In16.Cu"
		)
		(hatch none 0.5)
		(connect_pads
			(clearance 0)
		)
		(min_thickness 0.25)
		(keepout
			(tracks not_allowed)
			(vias allowed)
			(pads allowed)
			(copperpour not_allowed)
			(footprints allowed)
		)
		(placement
			(enabled no)
			(sheetname "")
		)
		(fill yes
			(thermal_gap 0.5)
			(thermal_bridge_width 0.5)
			(island_removal_mode 0)
		)
		(polygon
			(pts
				(arc
					(start 405.964136 -394.552424)
					(mid 406.074107 -394.653478)
					(end 406.218898 -394.690092)
				)
				(arc
					(start 406.218898 -394.690092)
					(mid 406.434424 -394.600818)
					(end 406.523698 -394.385292)
				)
				(arc
					(start 406.523698 -394.385292)
					(mid 406.513361 -394.306553)
					(end 406.483058 -394.233146)
				)
				(arc
					(start 406.090628 -393.554204)
					(mid 405.978231 -393.432587)
					(end 405.818848 -393.38758)
				)
				(arc
					(start 405.818848 -393.38758)
					(mid 405.603322 -393.476854)
					(end 405.514048 -393.69238)
				)
				(arc
					(start 405.514048 -393.69238)
					(mid 405.523626 -393.768442)
					(end 405.551894 -393.8397)
				)
				(xy 405.94915 -394.527024) (xy 405.961342 -394.54836) (xy 405.963882 -394.552678)
			)
		)
	)
	(zone
		(layers "F.Cu" "B.Cu" "In1.Cu" "In2.Cu" "In3.Cu" "In4.Cu" "In5.Cu" "In6.Cu"
			"In7.Cu" "In8.Cu" "In9.Cu" "In10.Cu" "In11.Cu" "In12.Cu" "In13.Cu" "In14.Cu"
			"In15.Cu" "In16.Cu"
		)
		(hatch none 0.5)
		(connect_pads
			(clearance 0)
		)
		(min_thickness 0.25)
		(keepout
			(tracks not_allowed)
			(vias allowed)
			(pads allowed)
			(copperpour not_allowed)
			(footprints allowed)
		)
		(placement
			(enabled no)
			(sheetname "")
		)
		(fill
			(thermal_gap 0.5)
			(thermal_bridge_width 0.5)
			(island_removal_mode 0)
		)
		(polygon
			(pts
				(arc
					(start 301.570136 -413.170116)
					(mid 297.570144 -417.170108)
					(end 293.570152 -413.170116)
				)
				(arc
					(start 293.570152 -413.170116)
					(mid 297.570144 -409.170124)
					(end 301.570136 -413.170116)
				)
			)
		)
	)
	(zone
		(layers "F.Cu" "B.Cu" "In1.Cu" "In2.Cu" "In3.Cu" "In4.Cu" "In5.Cu" "In6.Cu"
			"In7.Cu" "In8.Cu" "In9.Cu" "In10.Cu" "In11.Cu" "In12.Cu" "In13.Cu" "In14.Cu"
			"In15.Cu" "In16.Cu"
		)
		(hatch none 0.5)
		(connect_pads
			(clearance 0)
		)
		(min_thickness 0.25)
		(keepout
			(tracks not_allowed)
			(vias allowed)
			(pads allowed)
			(copperpour not_allowed)
			(footprints allowed)
		)
		(placement
			(enabled no)
			(sheetname "")
		)
		(fill yes
			(thermal_gap 0.5)
			(thermal_bridge_width 0.5)
			(island_removal_mode 0)
		)
		(polygon
			(pts
				(arc
					(start 90.064336 -386.170424)
					(mid 90.174307 -386.271478)
					(end 90.319098 -386.308092)
				)
				(arc
					(start 90.319098 -386.308092)
					(mid 90.534624 -386.218818)
					(end 90.623898 -386.003292)
				)
				(arc
					(start 90.623898 -386.003292)
					(mid 90.613561 -385.924553)
					(end 90.583258 -385.851146)
				)
				(arc
					(start 90.190828 -385.172204)
					(mid 90.078431 -385.050587)
					(end 89.919048 -385.00558)
				)
				(arc
					(start 89.919048 -385.00558)
					(mid 89.703522 -385.094854)
					(end 89.614248 -385.31038)
				)
				(arc
					(start 89.614248 -385.31038)
					(mid 89.623826 -385.386442)
					(end 89.652094 -385.4577)
				)
				(xy 90.04935 -386.145024) (xy 90.061542 -386.16636) (xy 90.064082 -386.170678)
			)
		)
	)
	(zone
		(layers "F.Cu" "B.Cu" "In1.Cu" "In2.Cu" "In3.Cu" "In4.Cu" "In5.Cu" "In6.Cu"
			"In7.Cu" "In8.Cu" "In9.Cu" "In10.Cu" "In11.Cu" "In12.Cu" "In13.Cu" "In14.Cu"
			"In15.Cu" "In16.Cu"
		)
		(hatch none 0.5)
		(connect_pads
			(clearance 0)
		)
		(min_thickness 0.25)
		(keepout
			(tracks not_allowed)
			(vias allowed)
			(pads allowed)
			(copperpour not_allowed)
			(footprints allowed)
		)
		(placement
			(enabled no)
			(sheetname "")
		)
		(fill
			(thermal_gap 0.5)
			(thermal_bridge_width 0.5)
			(island_removal_mode 0)
		)
		(polygon
			(pts
				(arc
					(start 416.842702 -420.571168)
					(mid 416.461702 -420.952168)
					(end 416.842702 -421.333168)
				)
				(arc
					(start 417.706302 -421.333168)
					(mid 418.087302 -420.952168)
					(end 417.706302 -420.571168)
				)
			)
		)
	)
	(zone
		(layers "F.Cu" "B.Cu" "In1.Cu" "In2.Cu" "In3.Cu" "In4.Cu" "In5.Cu" "In6.Cu"
			"In7.Cu" "In8.Cu" "In9.Cu" "In10.Cu" "In11.Cu" "In12.Cu" "In13.Cu" "In14.Cu"
			"In15.Cu" "In16.Cu"
		)
		(hatch none 0.5)
		(connect_pads
			(clearance 0)
		)
		(min_thickness 0.25)
		(keepout
			(tracks not_allowed)
			(vias allowed)
			(pads allowed)
			(copperpour not_allowed)
			(footprints allowed)
		)
		(placement
			(enabled no)
			(sheetname "")
		)
		(fill
			(thermal_gap 0.5)
			(thermal_bridge_width 0.5)
			(island_removal_mode 0)
		)
		(polygon
			(pts
				(arc
					(start 305.325526 -415.00552)
					(mid 304.944526 -415.38652)
					(end 305.325526 -415.76752)
				)
				(arc
					(start 306.189126 -415.76752)
					(mid 306.570126 -415.38652)
					(end 306.189126 -415.00552)
				)
			)
		)
	)
	(zone
		(layers "F.Cu" "B.Cu" "In1.Cu" "In2.Cu" "In3.Cu" "In4.Cu" "In5.Cu" "In6.Cu"
			"In7.Cu" "In8.Cu" "In9.Cu" "In10.Cu" "In11.Cu" "In12.Cu" "In13.Cu" "In14.Cu"
			"In15.Cu" "In16.Cu"
		)
		(hatch none 0.5)
		(connect_pads
			(clearance 0)
		)
		(min_thickness 0.25)
		(keepout
			(tracks not_allowed)
			(vias allowed)
			(pads allowed)
			(copperpour not_allowed)
			(footprints allowed)
		)
		(placement
			(enabled no)
			(sheetname "")
		)
		(fill
			(thermal_gap 0.5)
			(thermal_bridge_width 0.5)
			(island_removal_mode 0)
		)
		(polygon
			(pts
				(arc
					(start 303.9364 -398.016476)
					(mid 304.046371 -398.11753)
					(end 304.191162 -398.154144)
				)
				(arc
					(start 304.191162 -398.154144)
					(mid 304.406688 -398.06487)
					(end 304.495962 -397.849344)
				)
				(arc
					(start 304.495962 -397.849344)
					(mid 304.485625 -397.770605)
					(end 304.455322 -397.697198)
				)
				(arc
					(start 304.062892 -397.018256)
					(mid 303.950495 -396.896639)
					(end 303.791112 -396.851632)
				)
				(arc
					(start 303.791112 -396.851632)
					(mid 303.575586 -396.940906)
					(end 303.486312 -397.156432)
				)
				(arc
					(start 303.486312 -397.156432)
					(mid 303.49589 -397.232494)
					(end 303.524158 -397.303752)
				)
				(xy 303.921414 -397.991076) (xy 303.933606 -398.012412) (xy 303.936146 -398.01673)
			)
		)
	)
	(zone
		(layers "F.Cu" "B.Cu" "In1.Cu" "In2.Cu" "In3.Cu" "In4.Cu" "In5.Cu" "In6.Cu"
			"In7.Cu" "In8.Cu" "In9.Cu" "In10.Cu" "In11.Cu" "In12.Cu" "In13.Cu" "In14.Cu"
			"In15.Cu" "In16.Cu"
		)
		(hatch none 0.5)
		(connect_pads
			(clearance 0)
		)
		(min_thickness 0.25)
		(keepout
			(tracks not_allowed)
			(vias allowed)
			(pads allowed)
			(copperpour not_allowed)
			(footprints allowed)
		)
		(placement
			(enabled no)
			(sheetname "")
		)
		(fill
			(thermal_gap 0.5)
			(thermal_bridge_width 0.5)
			(island_removal_mode 0)
		)
		(polygon
			(pts
				(arc
					(start 102.642924 -32.94761)
					(mid 103.023924 -33.32861)
					(end 103.404924 -32.94761)
				)
				(arc
					(start 103.404924 -31.95701)
					(mid 103.023924 -31.57601)
					(end 102.642924 -31.95701)
				)
			)
		)
	)
	(zone
		(layers "F.Cu" "B.Cu" "In1.Cu" "In2.Cu" "In3.Cu" "In4.Cu" "In5.Cu" "In6.Cu"
			"In7.Cu" "In8.Cu" "In9.Cu" "In10.Cu" "In11.Cu" "In12.Cu" "In13.Cu" "In14.Cu"
			"In15.Cu" "In16.Cu"
		)
		(hatch none 0.5)
		(connect_pads
			(clearance 0)
		)
		(min_thickness 0.25)
		(keepout
			(tracks not_allowed)
			(vias allowed)
			(pads allowed)
			(copperpour not_allowed)
			(footprints allowed)
		)
		(placement
			(enabled no)
			(sheetname "")
		)
		(fill
			(thermal_gap 0.5)
			(thermal_bridge_width 0.5)
			(island_removal_mode 0)
		)
		(polygon
			(pts
				(arc
					(start 338.349844 -379.50013)
					(mid 337.968844 -379.88113)
					(end 338.349844 -380.26213)
				)
				(arc
					(start 339.213444 -380.26213)
					(mid 339.594444 -379.88113)
					(end 339.213444 -379.50013)
				)
			)
		)
	)
	(zone
		(layers "F.Cu" "B.Cu" "In1.Cu" "In2.Cu" "In3.Cu" "In4.Cu" "In5.Cu" "In6.Cu"
			"In7.Cu" "In8.Cu" "In9.Cu" "In10.Cu" "In11.Cu" "In12.Cu" "In13.Cu" "In14.Cu"
			"In15.Cu" "In16.Cu"
		)
		(hatch none 0.5)
		(connect_pads
			(clearance 0)
		)
		(min_thickness 0.25)
		(keepout
			(tracks not_allowed)
			(vias allowed)
			(pads allowed)
			(copperpour not_allowed)
			(footprints allowed)
		)
		(placement
			(enabled no)
			(sheetname "")
		)
		(fill yes
			(thermal_gap 0.5)
			(thermal_bridge_width 0.5)
			(island_removal_mode 0)
		)
		(polygon
			(pts
				(arc
					(start 380.636526 -394.552424)
					(mid 380.746497 -394.653478)
					(end 380.891288 -394.690092)
				)
				(arc
					(start 380.891288 -394.690092)
					(mid 381.106814 -394.600818)
					(end 381.196088 -394.385292)
				)
				(arc
					(start 381.196088 -394.385292)
					(mid 381.185751 -394.306553)
					(end 381.155448 -394.233146)
				)
				(arc
					(start 380.763018 -393.554204)
					(mid 380.650621 -393.432587)
					(end 380.491238 -393.38758)
				)
				(arc
					(start 380.491238 -393.38758)
					(mid 380.275712 -393.476854)
					(end 380.186438 -393.69238)
				)
				(arc
					(start 380.186438 -393.69238)
					(mid 380.196016 -393.768442)
					(end 380.224284 -393.8397)
				)
				(xy 380.62154 -394.527024) (xy 380.633732 -394.54836) (xy 380.636272 -394.552678)
			)
		)
	)
	(zone
		(layers "F.Cu" "B.Cu" "In1.Cu" "In2.Cu" "In3.Cu" "In4.Cu" "In5.Cu" "In6.Cu"
			"In7.Cu" "In8.Cu" "In9.Cu" "In10.Cu" "In11.Cu" "In12.Cu" "In13.Cu" "In14.Cu"
			"In15.Cu" "In16.Cu"
		)
		(hatch none 0.5)
		(connect_pads
			(clearance 0)
		)
		(min_thickness 0.25)
		(keepout
			(tracks not_allowed)
			(vias allowed)
			(pads allowed)
			(copperpour not_allowed)
			(footprints allowed)
		)
		(placement
			(enabled no)
			(sheetname "")
		)
		(fill
			(thermal_gap 0.5)
			(thermal_bridge_width 0.5)
			(island_removal_mode 0)
		)
		(polygon
			(pts
				(arc
					(start 97.666302 -368.65433)
					(mid 97.285302 -369.03533)
					(end 97.666302 -369.41633)
				)
				(arc
					(start 98.529902 -369.41633)
					(mid 98.910902 -369.03533)
					(end 98.529902 -368.65433)
				)
			)
		)
	)
	(zone
		(layers "F.Cu" "B.Cu" "In1.Cu" "In2.Cu" "In3.Cu" "In4.Cu" "In5.Cu" "In6.Cu"
			"In7.Cu" "In8.Cu" "In9.Cu" "In10.Cu" "In11.Cu" "In12.Cu" "In13.Cu" "In14.Cu"
			"In15.Cu" "In16.Cu"
		)
		(hatch none 0.5)
		(connect_pads
			(clearance 0)
		)
		(min_thickness 0.25)
		(keepout
			(tracks not_allowed)
			(vias allowed)
			(pads allowed)
			(copperpour not_allowed)
			(footprints allowed)
		)
		(placement
			(enabled no)
			(sheetname "")
		)
		(fill
			(thermal_gap 0.5)
			(thermal_bridge_width 0.5)
			(island_removal_mode 0)
		)
		(polygon
			(pts
				(arc
					(start 132.02031 -9.862312)
					(mid 131.63931 -10.243312)
					(end 132.02031 -10.624312)
				)
				(arc
					(start 132.88391 -10.624312)
					(mid 133.26491 -10.243312)
					(end 132.88391 -9.862312)
				)
			)
		)
	)
	(zone
		(layers "F.Cu" "B.Cu" "In1.Cu" "In2.Cu" "In3.Cu" "In4.Cu" "In5.Cu" "In6.Cu"
			"In7.Cu" "In8.Cu" "In9.Cu" "In10.Cu" "In11.Cu" "In12.Cu" "In13.Cu" "In14.Cu"
			"In15.Cu" "In16.Cu"
		)
		(hatch none 0.5)
		(connect_pads
			(clearance 0)
		)
		(min_thickness 0.25)
		(keepout
			(tracks not_allowed)
			(vias allowed)
			(pads allowed)
			(copperpour not_allowed)
			(footprints allowed)
		)
		(placement
			(enabled no)
			(sheetname "")
		)
		(fill
			(thermal_gap 0.5)
			(thermal_bridge_width 0.5)
			(island_removal_mode 0)
		)
		(polygon
			(pts
				(arc
					(start 530.895306 -458.028294)
					(mid 526.704306 -458.028294)
					(end 530.895306 -458.028294)
				)
			)
		)
	)
	(zone
		(layers "F.Cu" "B.Cu" "In1.Cu" "In2.Cu" "In3.Cu" "In4.Cu" "In5.Cu" "In6.Cu"
			"In7.Cu" "In8.Cu" "In9.Cu" "In10.Cu" "In11.Cu" "In12.Cu" "In13.Cu" "In14.Cu"
			"In15.Cu" "In16.Cu"
		)
		(name "Route Keepin")
		(hatch none 0.5)
		(connect_pads
			(clearance 0)
		)
		(min_thickness 0.25)
		(keepout
			(tracks allowed)
			(vias allowed)
			(pads allowed)
			(copperpour allowed)
			(footprints allowed)
		)
		(placement
			(enabled no)
			(sheetname "")
		)
		(fill
			(thermal_gap 0.5)
			(thermal_bridge_width 0.5)
			(island_removal_mode 0)
		)
		(polygon
			(pts
				(arc
					(start 474.307916 -461.028288)
					(mid 474.744912 -462.083288)
					(end 475.799912 -462.520284)
				)
				(arc
					(start 531.7998 -462.520284)
					(mid 532.8548 -462.083288)
					(end 533.291796 -461.028288)
				)
				(arc
					(start 533.291796 -455.0283)
					(mid 532.8548 -453.9733)
					(end 531.7998 -453.536304)
				)
				(arc
					(start 516.019796 -453.536304)
					(mid 514.246375 -452.801729)
					(end 513.5118 -451.028308)
				)
				(arc
					(start 513.5118 -312.408316)
					(mid 514.246375 -310.634895)
					(end 516.019796 -309.90032)
				)
				(arc
					(start 531.7998 -309.90032)
					(mid 532.8548 -309.463324)
					(end 533.291796 -308.408324)
				)
				(arc
					(start 533.291796 10.40003)
					(mid 532.8548 11.45503)
					(end 531.7998 11.892026)
				)
				(arc
					(start 475.799912 11.892026)
					(mid 474.744912 11.45503)
					(end 474.307916 10.40003)
				)
				(arc
					(start 474.307916 -77.67193)
					(mid 473.964721 -79.396816)
					(end 472.987624 -80.859122)
				)
				(arc
					(start 471.245184 -82.601562)
					(mid 470.921671 -83.085639)
					(end 470.80805 -83.656678)
				)
				(arc
					(start 470.80805 -404.871936)
					(mid 470.464855 -406.596822)
					(end 469.487758 -408.059128)
				)
				(arc
					(start 468.244936 -409.30195)
					(mid 467.921608 -409.785939)
					(end 467.808056 -410.356812)
				)
				(xy 467.808056 -418.45738) (xy 464.79206 -418.45738)
				(arc
					(start 464.79206 -409.528264)
					(mid 464.983018 -408.568632)
					(end 465.526628 -407.75509)
				)
				(arc
					(start 467.355174 -405.926544)
					(mid 467.678507 -405.442687)
					(end 467.792054 -404.871936)
				)
				(arc
					(start 467.792054 -82.82813)
					(mid 467.983012 -81.868498)
					(end 468.526622 -81.054956)
				)
				(arc
					(start 470.85504 -78.726538)
					(mid 471.178373 -78.242681)
					(end 471.29192 -77.67193)
				)
				(arc
					(start 471.29192 -13.780008)
					(mid 470.854924 -12.725008)
					(end 469.799924 -12.288012)
				)
				(xy 464.447636 -12.288012) (xy 464.447636 -9.272016)
				(arc
					(start 469.799924 -9.272016)
					(mid 470.854924 -8.83502)
					(end 471.29192 -7.78002)
				)
				(arc
					(start 471.29192 10.40003)
					(mid 470.854924 11.45503)
					(end 469.799924 11.892026)
				)
				(arc
					(start 1.999996 11.892026)
					(mid 0.944996 11.45503)
					(end 0.508 10.40003)
				)
				(arc
					(start 0.508 -7.78002)
					(mid 0.944996 -8.83502)
					(end 1.999996 -9.272016)
				)
				(arc
					(start 9.10209 -9.272016)
					(mid 10.15709 -8.83502)
					(end 10.594086 -7.78002)
				)
				(arc
					(start 10.594086 0.40005)
					(mid 11.328661 2.173471)
					(end 13.102082 2.908046)
				)
				(arc
					(start 81.701894 2.908046)
					(mid 83.475315 2.173471)
					(end 84.20989 0.40005)
				)
				(arc
					(start 84.20989 -7.78002)
					(mid 84.646886 -8.83502)
					(end 85.701886 -9.272016)
				)
				(arc
					(start 122.102118 -9.272016)
					(mid 123.157118 -8.83502)
					(end 123.594114 -7.78002)
				)
				(arc
					(start 123.594114 -4.879848)
					(mid 124.328689 -3.106427)
					(end 126.10211 -2.371852)
				)
				(arc
					(start 194.701922 -2.371852)
					(mid 196.475343 -3.106427)
					(end 197.209918 -4.879848)
				)
				(arc
					(start 197.209918 -7.78002)
					(mid 197.646914 -8.83502)
					(end 198.701914 -9.272016)
				)
				(arc
					(start 223.300036 -9.272016)
					(mid 225.073457 -10.006591)
					(end 225.808032 -11.780012)
				)
				(arc
					(start 225.808032 -33.120076)
					(mid 225.952135 -33.467971)
					(end 226.30003 -33.612074)
				)
				(arc
					(start 255.800098 -33.612074)
					(mid 256.147993 -33.467971)
					(end 256.292096 -33.120076)
				)
				(arc
					(start 256.292096 -11.780012)
					(mid 257.026671 -10.006591)
					(end 258.800092 -9.272016)
				)
				(arc
					(start 383.601976 -9.272016)
					(mid 384.656976 -8.83502)
					(end 385.093972 -7.78002)
				)
				(arc
					(start 385.093972 0.40005)
					(mid 385.828547 2.173471)
					(end 387.601968 2.908046)
				)
				(arc
					(start 456.202034 2.908046)
					(mid 457.975455 2.173471)
					(end 458.71003 0.40005)
				)
				(arc
					(start 458.71003 -7.78002)
					(mid 459.147026 -8.83502)
					(end 460.202026 -9.272016)
				)
				(xy 464.439 -9.272016) (xy 464.439 -12.288012)
				(arc
					(start 458.20203 -12.288012)
					(mid 456.428609 -11.553437)
					(end 455.694034 -9.780016)
				)
				(xy 455.694034 -0.508) (xy 388.109968 -0.508)
				(arc
					(start 388.109968 -9.780016)
					(mid 387.375393 -11.553437)
					(end 385.601972 -12.288012)
				)
				(arc
					(start 260.800088 -12.288012)
					(mid 259.745088 -12.725008)
					(end 259.308092 -13.780008)
				)
				(arc
					(start 259.308092 -34.120074)
					(mid 258.573517 -35.893495)
					(end 256.800096 -36.62807)
				)
				(arc
					(start 225.300032 -36.62807)
					(mid 223.526611 -35.893495)
					(end 222.792036 -34.120074)
				)
				(arc
					(start 222.792036 -13.780008)
					(mid 222.35504 -12.725008)
					(end 221.30004 -12.288012)
				)
				(arc
					(start 196.701918 -12.288012)
					(mid 194.928497 -11.553437)
					(end 194.193922 -9.780016)
				)
				(xy 194.193922 -5.787898) (xy 126.61011 -5.787898)
				(arc
					(start 126.61011 -9.780016)
					(mid 125.875535 -11.553437)
					(end 124.102114 -12.288012)
				)
				(arc
					(start 83.70189 -12.288012)
					(mid 81.928469 -11.553437)
					(end 81.193894 -9.780016)
				)
				(xy 81.193894 -0.508) (xy 13.610082 -0.508)
				(arc
					(start 13.610082 -9.780016)
					(mid 12.875507 -11.553437)
					(end 11.102086 -12.288012)
				)
				(arc
					(start 1.999996 -12.288012)
					(mid 0.944996 -12.725008)
					(end 0.508 -13.780008)
				)
				(arc
					(start 0.508 -77.67193)
					(mid 0.621601 -78.242658)
					(end 0.94488 -78.726538)
				)
				(arc
					(start 1.773428 -79.555086)
					(mid 2.317047 -80.368624)
					(end 2.507996 -81.32826)
				)
				(arc
					(start 2.507996 -403.371812)
					(mid 2.621533 -403.942691)
					(end 2.944876 -404.426674)
				)
				(arc
					(start 6.273292 -407.75509)
					(mid 6.817042 -408.568731)
					(end 7.008114 -409.528518)
				)
				(arc
					(start 7.008114 -439.989976)
					(mid 7.44511 -441.044976)
					(end 8.50011 -441.481972)
				)
				(xy 194.496944 -441.481972)
				(arc
					(start 194.496944 -441.17006)
					(mid 194.792217 -440.457207)
					(end 195.50507 -440.161934)
				)
				(arc
					(start 276.314916 -440.161934)
					(mid 277.027769 -440.457207)
					(end 277.323042 -441.17006)
				)
				(xy 277.323042 -441.481972)
				(arc
					(start 463.300064 -441.481972)
					(mid 464.355064 -441.044976)
					(end 464.79206 -439.989976)
				)
				(xy 464.79206 -418.46881) (xy 467.808056 -418.46881)
				(arc
					(start 467.808056 -439.989976)
					(mid 468.245052 -441.044976)
					(end 469.300052 -441.481972)
				)
				(arc
					(start 471.79992 -441.481972)
					(mid 473.573341 -442.216547)
					(end 474.307916 -443.989968)
				)
			)
		)
	)
	(zone
		(layers "F.Cu" "B.Cu" "In1.Cu" "In2.Cu" "In3.Cu" "In4.Cu" "In5.Cu" "In6.Cu"
			"In7.Cu" "In8.Cu" "In9.Cu" "In10.Cu" "In11.Cu" "In12.Cu" "In13.Cu" "In14.Cu"
			"In15.Cu" "In16.Cu"
		)
		(hatch none 0.5)
		(connect_pads
			(clearance 0)
		)
		(min_thickness 0.25)
		(keepout
			(tracks not_allowed)
			(vias allowed)
			(pads allowed)
			(copperpour not_allowed)
			(footprints allowed)
		)
		(placement
			(enabled no)
			(sheetname "")
		)
		(fill yes
			(thermal_gap 0.5)
			(thermal_bridge_width 0.5)
			(island_removal_mode 0)
		)
		(polygon
			(pts
				(arc
					(start 318.336422 -394.552424)
					(mid 318.446393 -394.653478)
					(end 318.591184 -394.690092)
				)
				(arc
					(start 318.591184 -394.690092)
					(mid 318.80671 -394.600818)
					(end 318.895984 -394.385292)
				)
				(arc
					(start 318.895984 -394.385292)
					(mid 318.885647 -394.306553)
					(end 318.855344 -394.233146)
				)
				(arc
					(start 318.462914 -393.554204)
					(mid 318.350517 -393.432587)
					(end 318.191134 -393.38758)
				)
				(arc
					(start 318.191134 -393.38758)
					(mid 317.975608 -393.476854)
					(end 317.886334 -393.69238)
				)
				(arc
					(start 317.886334 -393.69238)
					(mid 317.895912 -393.768442)
					(end 317.92418 -393.8397)
				)
				(xy 318.321436 -394.527024) (xy 318.333628 -394.54836) (xy 318.336168 -394.552678)
			)
		)
	)
	(zone
		(layers "F.Cu" "B.Cu" "In1.Cu" "In2.Cu" "In3.Cu" "In4.Cu" "In5.Cu" "In6.Cu"
			"In7.Cu" "In8.Cu" "In9.Cu" "In10.Cu" "In11.Cu" "In12.Cu" "In13.Cu" "In14.Cu"
			"In15.Cu" "In16.Cu"
		)
		(hatch none 0.5)
		(connect_pads
			(clearance 0)
		)
		(min_thickness 0.25)
		(keepout
			(tracks not_allowed)
			(vias allowed)
			(pads allowed)
			(copperpour not_allowed)
			(footprints allowed)
		)
		(placement
			(enabled no)
			(sheetname "")
		)
		(fill
			(thermal_gap 0.5)
			(thermal_bridge_width 0.5)
			(island_removal_mode 0)
		)
		(polygon
			(pts
				(arc
					(start 115.0366 -389.634476)
					(mid 115.146571 -389.73553)
					(end 115.291362 -389.772144)
				)
				(arc
					(start 115.291362 -389.772144)
					(mid 115.506888 -389.68287)
					(end 115.596162 -389.467344)
				)
				(arc
					(start 115.596162 -389.467344)
					(mid 115.585825 -389.388605)
					(end 115.555522 -389.315198)
				)
				(arc
					(start 115.163092 -388.636256)
					(mid 115.050695 -388.514639)
					(end 114.891312 -388.469632)
				)
				(arc
					(start 114.891312 -388.469632)
					(mid 114.675786 -388.558906)
					(end 114.586512 -388.774432)
				)
				(arc
					(start 114.586512 -388.774432)
					(mid 114.59609 -388.850494)
					(end 114.624358 -388.921752)
				)
				(xy 115.021614 -389.609076) (xy 115.033806 -389.630412) (xy 115.036346 -389.63473)
			)
		)
	)
	(zone
		(layers "F.Cu" "B.Cu" "In1.Cu" "In2.Cu" "In3.Cu" "In4.Cu" "In5.Cu" "In6.Cu"
			"In7.Cu" "In8.Cu" "In9.Cu" "In10.Cu" "In11.Cu" "In12.Cu" "In13.Cu" "In14.Cu"
			"In15.Cu" "In16.Cu"
		)
		(hatch none 0.5)
		(connect_pads
			(clearance 0)
		)
		(min_thickness 0.25)
		(keepout
			(tracks not_allowed)
			(vias allowed)
			(pads allowed)
			(copperpour not_allowed)
			(footprints allowed)
		)
		(placement
			(enabled no)
			(sheetname "")
		)
		(fill
			(thermal_gap 0.5)
			(thermal_bridge_width 0.5)
			(island_removal_mode 0)
		)
		(polygon
			(pts
				(arc
					(start 378.23648 -398.016476)
					(mid 378.346451 -398.11753)
					(end 378.491242 -398.154144)
				)
				(arc
					(start 378.491242 -398.154144)
					(mid 378.706768 -398.06487)
					(end 378.796042 -397.849344)
				)
				(arc
					(start 378.796042 -397.849344)
					(mid 378.785705 -397.770605)
					(end 378.755402 -397.697198)
				)
				(arc
					(start 378.362972 -397.018256)
					(mid 378.250575 -396.896639)
					(end 378.091192 -396.851632)
				)
				(arc
					(start 378.091192 -396.851632)
					(mid 377.875666 -396.940906)
					(end 377.786392 -397.156432)
				)
				(arc
					(start 377.786392 -397.156432)
					(mid 377.79597 -397.232494)
					(end 377.824238 -397.303752)
				)
				(xy 378.221494 -397.991076) (xy 378.233686 -398.012412) (xy 378.236226 -398.01673)
			)
		)
	)
	(zone
		(layers "F.Cu" "B.Cu" "In1.Cu" "In2.Cu" "In3.Cu" "In4.Cu" "In5.Cu" "In6.Cu"
			"In7.Cu" "In8.Cu" "In9.Cu" "In10.Cu" "In11.Cu" "In12.Cu" "In13.Cu" "In14.Cu"
			"In15.Cu" "In16.Cu"
		)
		(hatch none 0.5)
		(connect_pads
			(clearance 0)
		)
		(min_thickness 0.25)
		(keepout
			(tracks not_allowed)
			(vias allowed)
			(pads allowed)
			(copperpour not_allowed)
			(footprints allowed)
		)
		(placement
			(enabled no)
			(sheetname "")
		)
		(fill
			(thermal_gap 0.5)
			(thermal_bridge_width 0.5)
			(island_removal_mode 0)
		)
		(polygon
			(pts
				(arc
					(start 140.931646 -409.649168)
					(mid 140.550646 -410.030168)
					(end 140.931646 -410.411168)
				)
				(arc
					(start 141.795246 -410.411168)
					(mid 142.176246 -410.030168)
					(end 141.795246 -409.649168)
				)
			)
		)
	)
	(zone
		(layers "F.Cu" "B.Cu" "In1.Cu" "In2.Cu" "In3.Cu" "In4.Cu" "In5.Cu" "In6.Cu"
			"In7.Cu" "In8.Cu" "In9.Cu" "In10.Cu" "In11.Cu" "In12.Cu" "In13.Cu" "In14.Cu"
			"In15.Cu" "In16.Cu"
		)
		(hatch none 0.5)
		(connect_pads
			(clearance 0)
		)
		(min_thickness 0.25)
		(keepout
			(tracks not_allowed)
			(vias allowed)
			(pads allowed)
			(copperpour not_allowed)
			(footprints allowed)
		)
		(placement
			(enabled no)
			(sheetname "")
		)
		(fill
			(thermal_gap 0.5)
			(thermal_bridge_width 0.5)
			(island_removal_mode 0)
		)
		(polygon
			(pts
				(arc
					(start 392.826748 -18.756122)
					(mid 392.445748 -19.137122)
					(end 392.826748 -19.518122)
				)
				(arc
					(start 393.690348 -19.518122)
					(mid 394.071348 -19.137122)
					(end 393.690348 -18.756122)
				)
			)
		)
	)
	(zone
		(layers "F.Cu" "B.Cu" "In1.Cu" "In2.Cu" "In3.Cu" "In4.Cu" "In5.Cu" "In6.Cu"
			"In7.Cu" "In8.Cu" "In9.Cu" "In10.Cu" "In11.Cu" "In12.Cu" "In13.Cu" "In14.Cu"
			"In15.Cu" "In16.Cu"
		)
		(hatch none 0.5)
		(connect_pads
			(clearance 0)
		)
		(min_thickness 0.25)
		(keepout
			(tracks not_allowed)
			(vias allowed)
			(pads allowed)
			(copperpour not_allowed)
			(footprints allowed)
		)
		(placement
			(enabled no)
			(sheetname "")
		)
		(fill
			(thermal_gap 0.5)
			(thermal_bridge_width 0.5)
			(island_removal_mode 0)
		)
		(polygon
			(pts
				(arc
					(start 398.415764 -18.75536)
					(mid 398.034764 -19.13636)
					(end 398.415764 -19.51736)
				)
				(arc
					(start 399.279364 -19.51736)
					(mid 399.660364 -19.13636)
					(end 399.279364 -18.75536)
				)
			)
		)
	)
	(zone
		(layers "F.Cu" "B.Cu" "In1.Cu" "In2.Cu" "In3.Cu" "In4.Cu" "In5.Cu" "In6.Cu"
			"In7.Cu" "In8.Cu" "In9.Cu" "In10.Cu" "In11.Cu" "In12.Cu" "In13.Cu" "In14.Cu"
			"In15.Cu" "In16.Cu"
		)
		(hatch none 0.5)
		(connect_pads
			(clearance 0)
		)
		(min_thickness 0.25)
		(keepout
			(tracks not_allowed)
			(vias allowed)
			(pads allowed)
			(copperpour not_allowed)
			(footprints allowed)
		)
		(placement
			(enabled no)
			(sheetname "")
		)
		(fill
			(thermal_gap 0.5)
			(thermal_bridge_width 0.5)
			(island_removal_mode 0)
		)
		(polygon
			(pts
				(arc
					(start 217.725498 -86.54034)
					(mid 217.344498 -86.92134)
					(end 217.725498 -87.30234)
				)
				(arc
					(start 218.589098 -87.30234)
					(mid 218.970098 -86.92134)
					(end 218.589098 -86.54034)
				)
			)
		)
	)
	(zone
		(layers "F.Cu" "B.Cu" "In1.Cu" "In2.Cu" "In3.Cu" "In4.Cu" "In5.Cu" "In6.Cu"
			"In7.Cu" "In8.Cu" "In9.Cu" "In10.Cu" "In11.Cu" "In12.Cu" "In13.Cu" "In14.Cu"
			"In15.Cu" "In16.Cu"
		)
		(hatch none 0.5)
		(connect_pads
			(clearance 0)
		)
		(min_thickness 0.25)
		(keepout
			(tracks not_allowed)
			(vias allowed)
			(pads allowed)
			(copperpour not_allowed)
			(footprints allowed)
		)
		(placement
			(enabled no)
			(sheetname "")
		)
		(fill
			(thermal_gap 0.5)
			(thermal_bridge_width 0.5)
			(island_removal_mode 0)
		)
		(polygon
			(pts
				(arc
					(start 311.287414 -18.147538)
					(mid 312.295794 -17.139158)
					(end 311.287414 -16.130778)
				)
				(arc
					(start 311.262014 -16.130778)
					(mid 310.557962 -16.422406)
					(end 310.266334 -17.126458)
				)
				(arc
					(start 310.266334 -17.126458)
					(mid 310.565401 -17.848471)
					(end 311.287414 -18.147538)
				)
			)
		)
	)
	(zone
		(layers "F.Cu" "B.Cu" "In1.Cu" "In2.Cu" "In3.Cu" "In4.Cu" "In5.Cu" "In6.Cu"
			"In7.Cu" "In8.Cu" "In9.Cu" "In10.Cu" "In11.Cu" "In12.Cu" "In13.Cu" "In14.Cu"
			"In15.Cu" "In16.Cu"
		)
		(hatch none 0.5)
		(connect_pads
			(clearance 0)
		)
		(min_thickness 0.25)
		(keepout
			(tracks not_allowed)
			(vias allowed)
			(pads allowed)
			(copperpour not_allowed)
			(footprints allowed)
		)
		(placement
			(enabled no)
			(sheetname "")
		)
		(fill
			(thermal_gap 0.5)
			(thermal_bridge_width 0.5)
			(island_removal_mode 0)
		)
		(polygon
			(pts
				(arc
					(start 255.546098 -199.868028)
					(mid 255.927098 -200.249028)
					(end 256.308098 -199.868028)
				)
				(arc
					(start 256.308098 -199.004428)
					(mid 255.927098 -198.623428)
					(end 255.546098 -199.004428)
				)
			)
		)
	)
	(zone
		(layers "F.Cu" "B.Cu" "In1.Cu" "In2.Cu" "In3.Cu" "In4.Cu" "In5.Cu" "In6.Cu"
			"In7.Cu" "In8.Cu" "In9.Cu" "In10.Cu" "In11.Cu" "In12.Cu" "In13.Cu" "In14.Cu"
			"In15.Cu" "In16.Cu"
		)
		(hatch none 0.5)
		(connect_pads
			(clearance 0)
		)
		(min_thickness 0.25)
		(keepout
			(tracks not_allowed)
			(vias allowed)
			(pads allowed)
			(copperpour not_allowed)
			(footprints allowed)
		)
		(placement
			(enabled no)
			(sheetname "")
		)
		(fill
			(thermal_gap 0.5)
			(thermal_bridge_width 0.5)
			(island_removal_mode 0)
		)
		(polygon
			(pts
				(arc
					(start 372.922292 -379.50013)
					(mid 372.541292 -379.88113)
					(end 372.922292 -380.26213)
				)
				(arc
					(start 373.785892 -380.26213)
					(mid 374.166892 -379.88113)
					(end 373.785892 -379.50013)
				)
			)
		)
	)
	(zone
		(layers "F.Cu" "B.Cu" "In1.Cu" "In2.Cu" "In3.Cu" "In4.Cu" "In5.Cu" "In6.Cu"
			"In7.Cu" "In8.Cu" "In9.Cu" "In10.Cu" "In11.Cu" "In12.Cu" "In13.Cu" "In14.Cu"
			"In15.Cu" "In16.Cu"
		)
		(hatch none 0.5)
		(connect_pads
			(clearance 0)
		)
		(min_thickness 0.25)
		(keepout
			(tracks not_allowed)
			(vias allowed)
			(pads allowed)
			(copperpour not_allowed)
			(footprints allowed)
		)
		(placement
			(enabled no)
			(sheetname "")
		)
		(fill
			(thermal_gap 0.5)
			(thermal_bridge_width 0.5)
			(island_removal_mode 0)
		)
		(polygon
			(pts
				(arc
					(start 304.197258 -400.811238)
					(mid 303.816258 -400.430238)
					(end 303.435258 -400.811238)
				)
				(arc
					(start 303.435258 -401.674838)
					(mid 303.816258 -402.055838)
					(end 304.197258 -401.674838)
				)
			)
		)
	)
	(zone
		(layers "F.Cu" "B.Cu" "In1.Cu" "In2.Cu" "In3.Cu" "In4.Cu" "In5.Cu" "In6.Cu"
			"In7.Cu" "In8.Cu" "In9.Cu" "In10.Cu" "In11.Cu" "In12.Cu" "In13.Cu" "In14.Cu"
			"In15.Cu" "In16.Cu"
		)
		(hatch none 0.5)
		(connect_pads
			(clearance 0)
		)
		(min_thickness 0.25)
		(keepout
			(tracks not_allowed)
			(vias allowed)
			(pads allowed)
			(copperpour not_allowed)
			(footprints allowed)
		)
		(placement
			(enabled no)
			(sheetname "")
		)
		(fill
			(thermal_gap 0.5)
			(thermal_bridge_width 0.5)
			(island_removal_mode 0)
		)
		(polygon
			(pts
				(arc
					(start 413.779462 -412.46552)
					(mid 413.398462 -412.84652)
					(end 413.779462 -413.22752)
				)
				(arc
					(start 414.643062 -413.22752)
					(mid 415.024062 -412.84652)
					(end 414.643062 -412.46552)
				)
			)
		)
	)
	(zone
		(layers "F.Cu" "B.Cu" "In1.Cu" "In2.Cu" "In3.Cu" "In4.Cu" "In5.Cu" "In6.Cu"
			"In7.Cu" "In8.Cu" "In9.Cu" "In10.Cu" "In11.Cu" "In12.Cu" "In13.Cu" "In14.Cu"
			"In15.Cu" "In16.Cu"
		)
		(hatch none 0.5)
		(connect_pads
			(clearance 0)
		)
		(min_thickness 0.25)
		(keepout
			(tracks not_allowed)
			(vias allowed)
			(pads allowed)
			(copperpour not_allowed)
			(footprints allowed)
		)
		(placement
			(enabled no)
			(sheetname "")
		)
		(fill
			(thermal_gap 0.5)
			(thermal_bridge_width 0.5)
			(island_removal_mode 0)
		)
		(polygon
			(pts
				(arc
					(start 64.641984 -406.62352)
					(mid 64.260984 -407.00452)
					(end 64.641984 -407.38552)
				)
				(arc
					(start 65.505584 -407.38552)
					(mid 65.886584 -407.00452)
					(end 65.505584 -406.62352)
				)
			)
		)
	)
	(zone
		(layers "F.Cu" "B.Cu" "In1.Cu" "In2.Cu" "In3.Cu" "In4.Cu" "In5.Cu" "In6.Cu"
			"In7.Cu" "In8.Cu" "In9.Cu" "In10.Cu" "In11.Cu" "In12.Cu" "In13.Cu" "In14.Cu"
			"In15.Cu" "In16.Cu"
		)
		(hatch none 0.5)
		(connect_pads
			(clearance 0)
		)
		(min_thickness 0.25)
		(keepout
			(tracks not_allowed)
			(vias allowed)
			(pads allowed)
			(copperpour not_allowed)
			(footprints allowed)
		)
		(placement
			(enabled no)
			(sheetname "")
		)
		(fill yes
			(thermal_gap 0.5)
			(thermal_bridge_width 0.5)
			(island_removal_mode 0)
		)
		(polygon
			(pts
				(arc
					(start 52.736496 -386.170424)
					(mid 52.846467 -386.271478)
					(end 52.991258 -386.308092)
				)
				(arc
					(start 52.991258 -386.308092)
					(mid 53.206784 -386.218818)
					(end 53.296058 -386.003292)
				)
				(arc
					(start 53.296058 -386.003292)
					(mid 53.285721 -385.924553)
					(end 53.255418 -385.851146)
				)
				(arc
					(start 52.862988 -385.172204)
					(mid 52.750591 -385.050587)
					(end 52.591208 -385.00558)
				)
				(arc
					(start 52.591208 -385.00558)
					(mid 52.375682 -385.094854)
					(end 52.286408 -385.31038)
				)
				(arc
					(start 52.286408 -385.31038)
					(mid 52.295986 -385.386442)
					(end 52.324254 -385.4577)
				)
				(xy 52.72151 -386.145024) (xy 52.733702 -386.16636) (xy 52.736242 -386.170678)
			)
		)
	)
	(zone
		(layers "F.Cu" "B.Cu" "In1.Cu" "In2.Cu" "In3.Cu" "In4.Cu" "In5.Cu" "In6.Cu"
			"In7.Cu" "In8.Cu" "In9.Cu" "In10.Cu" "In11.Cu" "In12.Cu" "In13.Cu" "In14.Cu"
			"In15.Cu" "In16.Cu"
		)
		(hatch none 0.5)
		(connect_pads
			(clearance 0)
		)
		(min_thickness 0.25)
		(keepout
			(tracks not_allowed)
			(vias allowed)
			(pads allowed)
			(copperpour not_allowed)
			(footprints allowed)
		)
		(placement
			(enabled no)
			(sheetname "")
		)
		(fill
			(thermal_gap 0.5)
			(thermal_bridge_width 0.5)
			(island_removal_mode 0)
		)
		(polygon
			(pts
				(arc
					(start 88.864186 -389.634476)
					(mid 88.974157 -389.73553)
					(end 89.118948 -389.772144)
				)
				(arc
					(start 89.118948 -389.772144)
					(mid 89.334474 -389.68287)
					(end 89.423748 -389.467344)
				)
				(arc
					(start 89.423748 -389.467344)
					(mid 89.413411 -389.388605)
					(end 89.383108 -389.315198)
				)
				(arc
					(start 88.990678 -388.636256)
					(mid 88.878281 -388.514639)
					(end 88.718898 -388.469632)
				)
				(arc
					(start 88.718898 -388.469632)
					(mid 88.503372 -388.558906)
					(end 88.414098 -388.774432)
				)
				(arc
					(start 88.414098 -388.774432)
					(mid 88.423676 -388.850494)
					(end 88.451944 -388.921752)
				)
				(xy 88.8492 -389.609076) (xy 88.861392 -389.630412) (xy 88.863932 -389.63473)
			)
		)
	)
	(zone
		(layers "F.Cu" "B.Cu" "In1.Cu" "In2.Cu" "In3.Cu" "In4.Cu" "In5.Cu" "In6.Cu"
			"In7.Cu" "In8.Cu" "In9.Cu" "In10.Cu" "In11.Cu" "In12.Cu" "In13.Cu" "In14.Cu"
			"In15.Cu" "In16.Cu"
		)
		(hatch none 0.5)
		(connect_pads
			(clearance 0)
		)
		(min_thickness 0.25)
		(keepout
			(tracks not_allowed)
			(vias allowed)
			(pads allowed)
			(copperpour not_allowed)
			(footprints allowed)
		)
		(placement
			(enabled no)
			(sheetname "")
		)
		(fill
			(thermal_gap 0.5)
			(thermal_bridge_width 0.5)
			(island_removal_mode 0)
		)
		(polygon
			(pts
				(arc
					(start 459.409546 -32.053276)
					(mid 455.218546 -32.053276)
					(end 459.409546 -32.053276)
				)
			)
		)
	)
	(zone
		(layers "F.Cu" "B.Cu" "In1.Cu" "In2.Cu" "In3.Cu" "In4.Cu" "In5.Cu" "In6.Cu"
			"In7.Cu" "In8.Cu" "In9.Cu" "In10.Cu" "In11.Cu" "In12.Cu" "In13.Cu" "In14.Cu"
			"In15.Cu" "In16.Cu"
		)
		(hatch none 0.5)
		(connect_pads
			(clearance 0)
		)
		(min_thickness 0.25)
		(keepout
			(tracks not_allowed)
			(vias allowed)
			(pads allowed)
			(copperpour not_allowed)
			(footprints allowed)
		)
		(placement
			(enabled no)
			(sheetname "")
		)
		(fill
			(thermal_gap 0.5)
			(thermal_bridge_width 0.5)
			(island_removal_mode 0)
		)
		(polygon
			(pts
				(arc
					(start 300.716696 -377.03633)
					(mid 300.335696 -377.41733)
					(end 300.716696 -377.79833)
				)
				(arc
					(start 301.580296 -377.79833)
					(mid 301.961296 -377.41733)
					(end 301.580296 -377.03633)
				)
			)
		)
	)
	(zone
		(layers "F.Cu" "B.Cu" "In1.Cu" "In2.Cu" "In3.Cu" "In4.Cu" "In5.Cu" "In6.Cu"
			"In7.Cu" "In8.Cu" "In9.Cu" "In10.Cu" "In11.Cu" "In12.Cu" "In13.Cu" "In14.Cu"
			"In15.Cu" "In16.Cu"
		)
		(hatch none 0.5)
		(connect_pads
			(clearance 0)
		)
		(min_thickness 0.25)
		(keepout
			(tracks not_allowed)
			(vias allowed)
			(pads allowed)
			(copperpour not_allowed)
			(footprints allowed)
		)
		(placement
			(enabled no)
			(sheetname "")
		)
		(fill
			(thermal_gap 0.5)
			(thermal_bridge_width 0.5)
			(island_removal_mode 0)
		)
		(polygon
			(pts
				(arc
					(start 116.425726 -409.649168)
					(mid 116.044726 -410.030168)
					(end 116.425726 -410.411168)
				)
				(arc
					(start 117.289326 -410.411168)
					(mid 117.670326 -410.030168)
					(end 117.289326 -409.649168)
				)
			)
		)
	)
	(zone
		(layers "F.Cu" "B.Cu" "In1.Cu" "In2.Cu" "In3.Cu" "In4.Cu" "In5.Cu" "In6.Cu"
			"In7.Cu" "In8.Cu" "In9.Cu" "In10.Cu" "In11.Cu" "In12.Cu" "In13.Cu" "In14.Cu"
			"In15.Cu" "In16.Cu"
		)
		(hatch none 0.5)
		(connect_pads
			(clearance 0)
		)
		(min_thickness 0.25)
		(keepout
			(tracks not_allowed)
			(vias allowed)
			(pads allowed)
			(copperpour not_allowed)
			(footprints allowed)
		)
		(placement
			(enabled no)
			(sheetname "")
		)
		(fill
			(thermal_gap 0.5)
			(thermal_bridge_width 0.5)
			(island_removal_mode 0)
		)
		(polygon
			(pts
				(arc
					(start 163.164266 -389.634476)
					(mid 163.274237 -389.73553)
					(end 163.419028 -389.772144)
				)
				(arc
					(start 163.419028 -389.772144)
					(mid 163.634554 -389.68287)
					(end 163.723828 -389.467344)
				)
				(arc
					(start 163.723828 -389.467344)
					(mid 163.713491 -389.388605)
					(end 163.683188 -389.315198)
				)
				(arc
					(start 163.290758 -388.636256)
					(mid 163.178361 -388.514639)
					(end 163.018978 -388.469632)
				)
				(arc
					(start 163.018978 -388.469632)
					(mid 162.803452 -388.558906)
					(end 162.714178 -388.774432)
				)
				(arc
					(start 162.714178 -388.774432)
					(mid 162.723756 -388.850494)
					(end 162.752024 -388.921752)
				)
				(xy 163.14928 -389.609076) (xy 163.161472 -389.630412) (xy 163.164012 -389.63473)
			)
		)
	)
	(zone
		(layers "F.Cu" "B.Cu" "In1.Cu" "In2.Cu" "In3.Cu" "In4.Cu" "In5.Cu" "In6.Cu"
			"In7.Cu" "In8.Cu" "In9.Cu" "In10.Cu" "In11.Cu" "In12.Cu" "In13.Cu" "In14.Cu"
			"In15.Cu" "In16.Cu"
		)
		(hatch none 0.5)
		(connect_pads
			(clearance 0)
		)
		(min_thickness 0.25)
		(keepout
			(tracks not_allowed)
			(vias allowed)
			(pads allowed)
			(copperpour not_allowed)
			(footprints allowed)
		)
		(placement
			(enabled no)
			(sheetname "")
		)
		(fill
			(thermal_gap 0.5)
			(thermal_bridge_width 0.5)
			(island_removal_mode 0)
		)
		(polygon
			(pts
				(arc
					(start 333.244444 -377.03633)
					(mid 332.863444 -377.41733)
					(end 333.244444 -377.79833)
				)
				(arc
					(start 334.108044 -377.79833)
					(mid 334.489044 -377.41733)
					(end 334.108044 -377.03633)
				)
			)
		)
	)
	(zone
		(layers "F.Cu" "B.Cu" "In1.Cu" "In2.Cu" "In3.Cu" "In4.Cu" "In5.Cu" "In6.Cu"
			"In7.Cu" "In8.Cu" "In9.Cu" "In10.Cu" "In11.Cu" "In12.Cu" "In13.Cu" "In14.Cu"
			"In15.Cu" "In16.Cu"
		)
		(hatch none 0.5)
		(connect_pads
			(clearance 0)
		)
		(min_thickness 0.25)
		(keepout
			(tracks not_allowed)
			(vias allowed)
			(pads allowed)
			(copperpour not_allowed)
			(footprints allowed)
		)
		(placement
			(enabled no)
			(sheetname "")
		)
		(fill
			(thermal_gap 0.5)
			(thermal_bridge_width 0.5)
			(island_removal_mode 0)
		)
		(polygon
			(pts
				(arc
					(start 64.736472 -389.634476)
					(mid 64.846443 -389.73553)
					(end 64.991234 -389.772144)
				)
				(arc
					(start 64.991234 -389.772144)
					(mid 65.20676 -389.68287)
					(end 65.296034 -389.467344)
				)
				(arc
					(start 65.296034 -389.467344)
					(mid 65.285697 -389.388605)
					(end 65.255394 -389.315198)
				)
				(arc
					(start 64.862964 -388.636256)
					(mid 64.750567 -388.514639)
					(end 64.591184 -388.469632)
				)
				(arc
					(start 64.591184 -388.469632)
					(mid 64.375658 -388.558906)
					(end 64.286384 -388.774432)
				)
				(arc
					(start 64.286384 -388.774432)
					(mid 64.295962 -388.850494)
					(end 64.32423 -388.921752)
				)
				(xy 64.721486 -389.609076) (xy 64.733678 -389.630412) (xy 64.736218 -389.63473)
			)
		)
	)
	(zone
		(layers "F.Cu" "B.Cu" "In1.Cu" "In2.Cu" "In3.Cu" "In4.Cu" "In5.Cu" "In6.Cu"
			"In7.Cu" "In8.Cu" "In9.Cu" "In10.Cu" "In11.Cu" "In12.Cu" "In13.Cu" "In14.Cu"
			"In15.Cu" "In16.Cu"
		)
		(hatch none 0.5)
		(connect_pads
			(clearance 0)
		)
		(min_thickness 0.25)
		(keepout
			(tracks not_allowed)
			(vias allowed)
			(pads allowed)
			(copperpour not_allowed)
			(footprints allowed)
		)
		(placement
			(enabled no)
			(sheetname "")
		)
		(fill yes
			(thermal_gap 0.5)
			(thermal_bridge_width 0.5)
			(island_removal_mode 0)
		)
		(polygon
			(pts
				(arc
					(start 378.23648 -394.552424)
					(mid 378.346451 -394.653478)
					(end 378.491242 -394.690092)
				)
				(arc
					(start 378.491242 -394.690092)
					(mid 378.706768 -394.600818)
					(end 378.796042 -394.385292)
				)
				(arc
					(start 378.796042 -394.385292)
					(mid 378.785705 -394.306553)
					(end 378.755402 -394.233146)
				)
				(arc
					(start 378.362972 -393.554204)
					(mid 378.250575 -393.432587)
					(end 378.091192 -393.38758)
				)
				(arc
					(start 378.091192 -393.38758)
					(mid 377.875666 -393.476854)
					(end 377.786392 -393.69238)
				)
				(arc
					(start 377.786392 -393.69238)
					(mid 377.79597 -393.768442)
					(end 377.824238 -393.8397)
				)
				(xy 378.221494 -394.527024) (xy 378.233686 -394.54836) (xy 378.236226 -394.552678)
			)
		)
	)
	(zone
		(layers "F.Cu" "B.Cu" "In1.Cu" "In2.Cu" "In3.Cu" "In4.Cu" "In5.Cu" "In6.Cu"
			"In7.Cu" "In8.Cu" "In9.Cu" "In10.Cu" "In11.Cu" "In12.Cu" "In13.Cu" "In14.Cu"
			"In15.Cu" "In16.Cu"
		)
		(hatch none 0.5)
		(connect_pads
			(clearance 0)
		)
		(min_thickness 0.25)
		(keepout
			(tracks not_allowed)
			(vias allowed)
			(pads allowed)
			(copperpour not_allowed)
			(footprints allowed)
		)
		(placement
			(enabled no)
			(sheetname "")
		)
		(fill
			(thermal_gap 0.5)
			(thermal_bridge_width 0.5)
			(island_removal_mode 0)
		)
		(polygon
			(pts
				(arc
					(start 468.89543 -4.780026)
					(mid 464.70443 -4.780026)
					(end 468.89543 -4.780026)
				)
			)
		)
	)
	(zone
		(layers "F.Cu" "B.Cu" "In1.Cu" "In2.Cu" "In3.Cu" "In4.Cu" "In5.Cu" "In6.Cu"
			"In7.Cu" "In8.Cu" "In9.Cu" "In10.Cu" "In11.Cu" "In12.Cu" "In13.Cu" "In14.Cu"
			"In15.Cu" "In16.Cu"
		)
		(hatch none 0.5)
		(connect_pads
			(clearance 0)
		)
		(min_thickness 0.25)
		(keepout
			(tracks not_allowed)
			(vias allowed)
			(pads allowed)
			(copperpour not_allowed)
			(footprints allowed)
		)
		(placement
			(enabled no)
			(sheetname "")
		)
		(fill
			(thermal_gap 0.5)
			(thermal_bridge_width 0.5)
			(island_removal_mode 0)
		)
		(polygon
			(pts
				(arc
					(start 95.274384 -406.62352)
					(mid 94.893384 -407.00452)
					(end 95.274384 -407.38552)
				)
				(arc
					(start 96.137984 -407.38552)
					(mid 96.518984 -407.00452)
					(end 96.137984 -406.62352)
				)
			)
		)
	)
	(zone
		(layers "F.Cu" "B.Cu" "In1.Cu" "In2.Cu" "In3.Cu" "In4.Cu" "In5.Cu" "In6.Cu"
			"In7.Cu" "In8.Cu" "In9.Cu" "In10.Cu" "In11.Cu" "In12.Cu" "In13.Cu" "In14.Cu"
			"In15.Cu" "In16.Cu"
		)
		(hatch none 0.5)
		(connect_pads
			(clearance 0)
		)
		(min_thickness 0.25)
		(keepout
			(tracks not_allowed)
			(vias allowed)
			(pads allowed)
			(copperpour not_allowed)
			(footprints allowed)
		)
		(placement
			(enabled no)
			(sheetname "")
		)
		(fill
			(thermal_gap 0.5)
			(thermal_bridge_width 0.5)
			(island_removal_mode 0)
		)
		(polygon
			(pts
				(arc
					(start 44.716954 -368.65433)
					(mid 44.335954 -369.03533)
					(end 44.716954 -369.41633)
				)
				(arc
					(start 45.580554 -369.41633)
					(mid 45.961554 -369.03533)
					(end 45.580554 -368.65433)
				)
			)
		)
	)
	(zone
		(layers "F.Cu" "B.Cu" "In1.Cu" "In2.Cu" "In3.Cu" "In4.Cu" "In5.Cu" "In6.Cu"
			"In7.Cu" "In8.Cu" "In9.Cu" "In10.Cu" "In11.Cu" "In12.Cu" "In13.Cu" "In14.Cu"
			"In15.Cu" "In16.Cu"
		)
		(hatch none 0.5)
		(connect_pads
			(clearance 0)
		)
		(min_thickness 0.25)
		(keepout
			(tracks not_allowed)
			(vias allowed)
			(pads allowed)
			(copperpour not_allowed)
			(footprints allowed)
		)
		(placement
			(enabled no)
			(sheetname "")
		)
		(fill
			(thermal_gap 0.5)
			(thermal_bridge_width 0.5)
			(island_removal_mode 0)
		)
		(polygon
			(pts
				(arc
					(start 102.193598 -409.563824)
					(mid 102.574598 -409.944824)
					(end 102.955598 -409.563824)
				)
				(arc
					(start 102.955598 -408.700224)
					(mid 102.574598 -408.319224)
					(end 102.193598 -408.700224)
				)
			)
		)
	)
	(zone
		(layers "F.Cu" "B.Cu" "In1.Cu" "In2.Cu" "In3.Cu" "In4.Cu" "In5.Cu" "In6.Cu"
			"In7.Cu" "In8.Cu" "In9.Cu" "In10.Cu" "In11.Cu" "In12.Cu" "In13.Cu" "In14.Cu"
			"In15.Cu" "In16.Cu"
		)
		(hatch none 0.5)
		(connect_pads
			(clearance 0)
		)
		(min_thickness 0.25)
		(keepout
			(tracks not_allowed)
			(vias allowed)
			(pads allowed)
			(copperpour not_allowed)
			(footprints allowed)
		)
		(placement
			(enabled no)
			(sheetname "")
		)
		(fill yes
			(thermal_gap 0.5)
			(thermal_bridge_width 0.5)
			(island_removal_mode 0)
		)
		(polygon
			(pts
				(arc
					(start 347.263974 -394.552424)
					(mid 347.373945 -394.653478)
					(end 347.518736 -394.690092)
				)
				(arc
					(start 347.518736 -394.690092)
					(mid 347.734262 -394.600818)
					(end 347.823536 -394.385292)
				)
				(arc
					(start 347.823536 -394.385292)
					(mid 347.813199 -394.306553)
					(end 347.782896 -394.233146)
				)
				(arc
					(start 347.390466 -393.554204)
					(mid 347.278069 -393.432587)
					(end 347.118686 -393.38758)
				)
				(arc
					(start 347.118686 -393.38758)
					(mid 346.90316 -393.476854)
					(end 346.813886 -393.69238)
				)
				(arc
					(start 346.813886 -393.69238)
					(mid 346.823464 -393.768442)
					(end 346.851732 -393.8397)
				)
				(xy 347.248988 -394.527024) (xy 347.26118 -394.54836) (xy 347.26372 -394.552678)
			)
		)
	)
	(zone
		(layers "F.Cu" "B.Cu" "In1.Cu" "In2.Cu" "In3.Cu" "In4.Cu" "In5.Cu" "In6.Cu"
			"In7.Cu" "In8.Cu" "In9.Cu" "In10.Cu" "In11.Cu" "In12.Cu" "In13.Cu" "In14.Cu"
			"In15.Cu" "In16.Cu"
		)
		(hatch none 0.5)
		(connect_pads
			(clearance 0)
		)
		(min_thickness 0.25)
		(keepout
			(tracks not_allowed)
			(vias allowed)
			(pads allowed)
			(copperpour not_allowed)
			(footprints allowed)
		)
		(placement
			(enabled no)
			(sheetname "")
		)
		(fill
			(thermal_gap 0.5)
			(thermal_bridge_width 0.5)
			(island_removal_mode 0)
		)
		(polygon
			(pts
				(arc
					(start 233.71556 -78.64221)
					(mid 235.89996 -85.458093)
					(end 238.08436 -78.64221)
				)
			)
		)
	)
	(zone
		(layers "F.Cu" "B.Cu" "In1.Cu" "In2.Cu" "In3.Cu" "In4.Cu" "In5.Cu" "In6.Cu"
			"In7.Cu" "In8.Cu" "In9.Cu" "In10.Cu" "In11.Cu" "In12.Cu" "In13.Cu" "In14.Cu"
			"In15.Cu" "In16.Cu"
		)
		(hatch none 0.5)
		(connect_pads
			(clearance 0)
		)
		(min_thickness 0.25)
		(keepout
			(tracks not_allowed)
			(vias allowed)
			(pads allowed)
			(copperpour not_allowed)
			(footprints allowed)
		)
		(placement
			(enabled no)
			(sheetname "")
		)
		(fill
			(thermal_gap 0.5)
			(thermal_bridge_width 0.5)
			(island_removal_mode 0)
		)
		(polygon
			(pts
				(arc
					(start 76.894944 -409.649168)
					(mid 76.513944 -410.030168)
					(end 76.894944 -410.411168)
				)
				(arc
					(start 77.758544 -410.411168)
					(mid 78.139544 -410.030168)
					(end 77.758544 -409.649168)
				)
			)
		)
	)
	(zone
		(layers "F.Cu" "B.Cu" "In1.Cu" "In2.Cu" "In3.Cu" "In4.Cu" "In5.Cu" "In6.Cu"
			"In7.Cu" "In8.Cu" "In9.Cu" "In10.Cu" "In11.Cu" "In12.Cu" "In13.Cu" "In14.Cu"
			"In15.Cu" "In16.Cu"
		)
		(hatch none 0.5)
		(connect_pads
			(clearance 0)
		)
		(min_thickness 0.25)
		(keepout
			(tracks not_allowed)
			(vias allowed)
			(pads allowed)
			(copperpour not_allowed)
			(footprints allowed)
		)
		(placement
			(enabled no)
			(sheetname "")
		)
		(fill
			(thermal_gap 0.5)
			(thermal_bridge_width 0.5)
			(island_removal_mode 0)
		)
		(polygon
			(pts
				(arc
					(start 412.384748 -17.232122)
					(mid 412.003748 -17.613122)
					(end 412.384748 -17.994122)
				)
				(arc
					(start 413.248348 -17.994122)
					(mid 413.629348 -17.613122)
					(end 413.248348 -17.232122)
				)
			)
		)
	)
	(zone
		(layers "F.Cu" "B.Cu" "In1.Cu" "In2.Cu" "In3.Cu" "In4.Cu" "In5.Cu" "In6.Cu"
			"In7.Cu" "In8.Cu" "In9.Cu" "In10.Cu" "In11.Cu" "In12.Cu" "In13.Cu" "In14.Cu"
			"In15.Cu" "In16.Cu"
		)
		(hatch none 0.5)
		(connect_pads
			(clearance 0)
		)
		(min_thickness 0.25)
		(keepout
			(tracks not_allowed)
			(vias allowed)
			(pads allowed)
			(copperpour not_allowed)
			(footprints allowed)
		)
		(placement
			(enabled no)
			(sheetname "")
		)
		(fill
			(thermal_gap 0.5)
			(thermal_bridge_width 0.5)
			(island_removal_mode 0)
		)
		(polygon
			(pts
				(arc
					(start 52.997608 -392.429238)
					(mid 52.616608 -392.048238)
					(end 52.235608 -392.429238)
				)
				(arc
					(start 52.235608 -393.292838)
					(mid 52.616608 -393.673838)
					(end 52.997608 -393.292838)
				)
			)
		)
	)
	(zone
		(layers "F.Cu" "B.Cu" "In1.Cu" "In2.Cu" "In3.Cu" "In4.Cu" "In5.Cu" "In6.Cu"
			"In7.Cu" "In8.Cu" "In9.Cu" "In10.Cu" "In11.Cu" "In12.Cu" "In13.Cu" "In14.Cu"
			"In15.Cu" "In16.Cu"
		)
		(hatch none 0.5)
		(connect_pads
			(clearance 0)
		)
		(min_thickness 0.25)
		(keepout
			(tracks not_allowed)
			(vias allowed)
			(pads allowed)
			(copperpour not_allowed)
			(footprints allowed)
		)
		(placement
			(enabled no)
			(sheetname "")
		)
		(fill yes
			(thermal_gap 0.5)
			(thermal_bridge_width 0.5)
			(island_removal_mode 0)
		)
		(polygon
			(pts
				(arc
					(start 159.564324 -386.170424)
					(mid 159.674295 -386.271478)
					(end 159.819086 -386.308092)
				)
				(arc
					(start 159.819086 -386.308092)
					(mid 160.034612 -386.218818)
					(end 160.123886 -386.003292)
				)
				(arc
					(start 160.123886 -386.003292)
					(mid 160.113549 -385.924553)
					(end 160.083246 -385.851146)
				)
				(arc
					(start 159.690816 -385.172204)
					(mid 159.578419 -385.050587)
					(end 159.419036 -385.00558)
				)
				(arc
					(start 159.419036 -385.00558)
					(mid 159.20351 -385.094854)
					(end 159.114236 -385.31038)
				)
				(arc
					(start 159.114236 -385.31038)
					(mid 159.123814 -385.386442)
					(end 159.152082 -385.4577)
				)
				(xy 159.549338 -386.145024) (xy 159.56153 -386.16636) (xy 159.56407 -386.170678)
			)
		)
	)
	(zone
		(layers "F.Cu" "B.Cu" "In1.Cu" "In2.Cu" "In3.Cu" "In4.Cu" "In5.Cu" "In6.Cu"
			"In7.Cu" "In8.Cu" "In9.Cu" "In10.Cu" "In11.Cu" "In12.Cu" "In13.Cu" "In14.Cu"
			"In15.Cu" "In16.Cu"
		)
		(hatch none 0.5)
		(connect_pads
			(clearance 0)
		)
		(min_thickness 0.25)
		(keepout
			(tracks not_allowed)
			(vias allowed)
			(pads allowed)
			(copperpour not_allowed)
			(footprints allowed)
		)
		(placement
			(enabled no)
			(sheetname "")
		)
		(fill
			(thermal_gap 0.5)
			(thermal_bridge_width 0.5)
			(island_removal_mode 0)
		)
		(polygon
			(pts
				(arc
					(start 157.959044 -368.65433)
					(mid 157.578044 -369.03533)
					(end 157.959044 -369.41633)
				)
				(arc
					(start 158.822644 -369.41633)
					(mid 159.203644 -369.03533)
					(end 158.822644 -368.65433)
				)
			)
		)
	)
	(zone
		(layers "F.Cu" "B.Cu" "In1.Cu" "In2.Cu" "In3.Cu" "In4.Cu" "In5.Cu" "In6.Cu"
			"In7.Cu" "In8.Cu" "In9.Cu" "In10.Cu" "In11.Cu" "In12.Cu" "In13.Cu" "In14.Cu"
			"In15.Cu" "In16.Cu"
		)
		(hatch none 0.5)
		(connect_pads
			(clearance 0)
		)
		(min_thickness 0.25)
		(keepout
			(tracks not_allowed)
			(vias allowed)
			(pads allowed)
			(copperpour not_allowed)
			(footprints allowed)
		)
		(placement
			(enabled no)
			(sheetname "")
		)
		(fill
			(thermal_gap 0.5)
			(thermal_bridge_width 0.5)
			(island_removal_mode 0)
		)
		(polygon
			(pts
				(arc
					(start 413.42564 -6.344158)
					(mid 413.04464 -6.725158)
					(end 413.42564 -7.106158)
				)
				(arc
					(start 414.28924 -7.106158)
					(mid 414.67024 -6.725158)
					(end 414.28924 -6.344158)
				)
			)
		)
	)
	(zone
		(layers "F.Cu" "B.Cu" "In1.Cu" "In2.Cu" "In3.Cu" "In4.Cu" "In5.Cu" "In6.Cu"
			"In7.Cu" "In8.Cu" "In9.Cu" "In10.Cu" "In11.Cu" "In12.Cu" "In13.Cu" "In14.Cu"
			"In15.Cu" "In16.Cu"
		)
		(hatch none 0.5)
		(connect_pads
			(clearance 0)
		)
		(min_thickness 0.25)
		(keepout
			(tracks not_allowed)
			(vias allowed)
			(pads allowed)
			(copperpour not_allowed)
			(footprints allowed)
		)
		(placement
			(enabled no)
			(sheetname "")
		)
		(fill
			(thermal_gap 0.5)
			(thermal_bridge_width 0.5)
			(island_removal_mode 0)
		)
		(polygon
			(pts
				(arc
					(start 67.705224 -409.649168)
					(mid 67.324224 -410.030168)
					(end 67.705224 -410.411168)
				)
				(arc
					(start 68.568824 -410.411168)
					(mid 68.949824 -410.030168)
					(end 68.568824 -409.649168)
				)
			)
		)
	)
	(zone
		(layers "F.Cu" "B.Cu" "In1.Cu" "In2.Cu" "In3.Cu" "In4.Cu" "In5.Cu" "In6.Cu"
			"In7.Cu" "In8.Cu" "In9.Cu" "In10.Cu" "In11.Cu" "In12.Cu" "In13.Cu" "In14.Cu"
			"In15.Cu" "In16.Cu"
		)
		(hatch none 0.5)
		(connect_pads
			(clearance 0)
		)
		(min_thickness 0.25)
		(keepout
			(tracks not_allowed)
			(vias allowed)
			(pads allowed)
			(copperpour not_allowed)
			(footprints allowed)
		)
		(placement
			(enabled no)
			(sheetname "")
		)
		(fill
			(thermal_gap 0.5)
			(thermal_bridge_width 0.5)
			(island_removal_mode 0)
		)
		(polygon
			(pts
				(arc
					(start 156.542486 -258.880356)
					(mid 151.513286 -258.880356)
					(end 156.542486 -258.880356)
				)
			)
		)
	)
	(zone
		(layers "F.Cu" "B.Cu" "In1.Cu" "In2.Cu" "In3.Cu" "In4.Cu" "In5.Cu" "In6.Cu"
			"In7.Cu" "In8.Cu" "In9.Cu" "In10.Cu" "In11.Cu" "In12.Cu" "In13.Cu" "In14.Cu"
			"In15.Cu" "In16.Cu"
		)
		(hatch none 0.5)
		(connect_pads
			(clearance 0)
		)
		(min_thickness 0.25)
		(keepout
			(tracks not_allowed)
			(vias allowed)
			(pads allowed)
			(copperpour not_allowed)
			(footprints allowed)
		)
		(placement
			(enabled no)
			(sheetname "")
		)
		(fill
			(thermal_gap 0.5)
			(thermal_bridge_width 0.5)
			(island_removal_mode 0)
		)
		(polygon
			(pts
				(arc
					(start 395.320266 -4.582414)
					(mid 394.939266 -4.963414)
					(end 395.320266 -5.344414)
				)
				(arc
					(start 396.183866 -5.344414)
					(mid 396.564866 -4.963414)
					(end 396.183866 -4.582414)
				)
			)
		)
	)
	(zone
		(layers "F.Cu" "B.Cu" "In1.Cu" "In2.Cu" "In3.Cu" "In4.Cu" "In5.Cu" "In6.Cu"
			"In7.Cu" "In8.Cu" "In9.Cu" "In10.Cu" "In11.Cu" "In12.Cu" "In13.Cu" "In14.Cu"
			"In15.Cu" "In16.Cu"
		)
		(hatch none 0.5)
		(connect_pads
			(clearance 0)
		)
		(min_thickness 0.25)
		(keepout
			(tracks not_allowed)
			(vias allowed)
			(pads allowed)
			(copperpour not_allowed)
			(footprints allowed)
		)
		(placement
			(enabled no)
			(sheetname "")
		)
		(fill
			(thermal_gap 0.5)
			(thermal_bridge_width 0.5)
			(island_removal_mode 0)
		)
		(polygon
			(pts
				(arc
					(start 53.936646 -389.634476)
					(mid 54.046617 -389.73553)
					(end 54.191408 -389.772144)
				)
				(arc
					(start 54.191408 -389.772144)
					(mid 54.406934 -389.68287)
					(end 54.496208 -389.467344)
				)
				(arc
					(start 54.496208 -389.467344)
					(mid 54.485871 -389.388605)
					(end 54.455568 -389.315198)
				)
				(arc
					(start 54.063138 -388.636256)
					(mid 53.950741 -388.514639)
					(end 53.791358 -388.469632)
				)
				(arc
					(start 53.791358 -388.469632)
					(mid 53.575832 -388.558906)
					(end 53.486558 -388.774432)
				)
				(arc
					(start 53.486558 -388.774432)
					(mid 53.496136 -388.850494)
					(end 53.524404 -388.921752)
				)
				(xy 53.92166 -389.609076) (xy 53.933852 -389.630412) (xy 53.936392 -389.63473)
			)
		)
	)
	(zone
		(layers "F.Cu" "B.Cu" "In1.Cu" "In2.Cu" "In3.Cu" "In4.Cu" "In5.Cu" "In6.Cu"
			"In7.Cu" "In8.Cu" "In9.Cu" "In10.Cu" "In11.Cu" "In12.Cu" "In13.Cu" "In14.Cu"
			"In15.Cu" "In16.Cu"
		)
		(hatch none 0.5)
		(connect_pads
			(clearance 0)
		)
		(min_thickness 0.25)
		(keepout
			(tracks not_allowed)
			(vias allowed)
			(pads allowed)
			(copperpour not_allowed)
			(footprints allowed)
		)
		(placement
			(enabled no)
			(sheetname "")
		)
		(fill yes
			(thermal_gap 0.5)
			(thermal_bridge_width 0.5)
			(island_removal_mode 0)
		)
		(polygon
			(pts
				(arc
					(start 387.83641 -394.552424)
					(mid 387.946381 -394.653478)
					(end 388.091172 -394.690092)
				)
				(arc
					(start 388.091172 -394.690092)
					(mid 388.306698 -394.600818)
					(end 388.395972 -394.385292)
				)
				(arc
					(start 388.395972 -394.385292)
					(mid 388.385635 -394.306553)
					(end 388.355332 -394.233146)
				)
				(arc
					(start 387.962902 -393.554204)
					(mid 387.850505 -393.432587)
					(end 387.691122 -393.38758)
				)
				(arc
					(start 387.691122 -393.38758)
					(mid 387.475596 -393.476854)
					(end 387.386322 -393.69238)
				)
				(arc
					(start 387.386322 -393.69238)
					(mid 387.3959 -393.768442)
					(end 387.424168 -393.8397)
				)
				(xy 387.821424 -394.527024) (xy 387.833616 -394.54836) (xy 387.836156 -394.552678)
			)
		)
	)
	(zone
		(layers "F.Cu" "B.Cu" "In1.Cu" "In2.Cu" "In3.Cu" "In4.Cu" "In5.Cu" "In6.Cu"
			"In7.Cu" "In8.Cu" "In9.Cu" "In10.Cu" "In11.Cu" "In12.Cu" "In13.Cu" "In14.Cu"
			"In15.Cu" "In16.Cu"
		)
		(hatch none 0.5)
		(connect_pads
			(clearance 0)
		)
		(min_thickness 0.25)
		(keepout
			(tracks not_allowed)
			(vias allowed)
			(pads allowed)
			(copperpour not_allowed)
			(footprints allowed)
		)
		(placement
			(enabled no)
			(sheetname "")
		)
		(fill
			(thermal_gap 0.5)
			(thermal_bridge_width 0.5)
			(island_removal_mode 0)
		)
		(polygon
			(pts
				(arc
					(start 347.525086 -400.811238)
					(mid 347.144086 -400.430238)
					(end 346.763086 -400.811238)
				)
				(arc
					(start 346.763086 -401.674838)
					(mid 347.144086 -402.055838)
					(end 347.525086 -401.674838)
				)
			)
		)
	)
	(zone
		(layers "F.Cu" "B.Cu" "In1.Cu" "In2.Cu" "In3.Cu" "In4.Cu" "In5.Cu" "In6.Cu"
			"In7.Cu" "In8.Cu" "In9.Cu" "In10.Cu" "In11.Cu" "In12.Cu" "In13.Cu" "In14.Cu"
			"In15.Cu" "In16.Cu"
		)
		(hatch none 0.5)
		(connect_pads
			(clearance 0)
		)
		(min_thickness 0.25)
		(keepout
			(tracks not_allowed)
			(vias allowed)
			(pads allowed)
			(copperpour not_allowed)
			(footprints allowed)
		)
		(placement
			(enabled no)
			(sheetname "")
		)
		(fill
			(thermal_gap 0.5)
			(thermal_bridge_width 0.5)
			(island_removal_mode 0)
		)
		(polygon
			(pts
				(arc
					(start 404.315676 -6.344158)
					(mid 403.934676 -6.725158)
					(end 404.315676 -7.106158)
				)
				(arc
					(start 405.179276 -7.106158)
					(mid 405.560276 -6.725158)
					(end 405.179276 -6.344158)
				)
			)
		)
	)
	(zone
		(layers "F.Cu" "B.Cu" "In1.Cu" "In2.Cu" "In3.Cu" "In4.Cu" "In5.Cu" "In6.Cu"
			"In7.Cu" "In8.Cu" "In9.Cu" "In10.Cu" "In11.Cu" "In12.Cu" "In13.Cu" "In14.Cu"
			"In15.Cu" "In16.Cu"
		)
		(hatch none 0.5)
		(connect_pads
			(clearance 0)
		)
		(min_thickness 0.25)
		(keepout
			(tracks not_allowed)
			(vias allowed)
			(pads allowed)
			(copperpour not_allowed)
			(footprints allowed)
		)
		(placement
			(enabled no)
			(sheetname "")
		)
		(fill yes
			(thermal_gap 0.5)
			(thermal_bridge_width 0.5)
			(island_removal_mode 0)
		)
		(polygon
			(pts
				(arc
					(start 85.264244 -386.170424)
					(mid 85.374215 -386.271478)
					(end 85.519006 -386.308092)
				)
				(arc
					(start 85.519006 -386.308092)
					(mid 85.734532 -386.218818)
					(end 85.823806 -386.003292)
				)
				(arc
					(start 85.823806 -386.003292)
					(mid 85.813469 -385.924553)
					(end 85.783166 -385.851146)
				)
				(arc
					(start 85.390736 -385.172204)
					(mid 85.278339 -385.050587)
					(end 85.118956 -385.00558)
				)
				(arc
					(start 85.118956 -385.00558)
					(mid 84.90343 -385.094854)
					(end 84.814156 -385.31038)
				)
				(arc
					(start 84.814156 -385.31038)
					(mid 84.823734 -385.386442)
					(end 84.852002 -385.4577)
				)
				(xy 85.249258 -386.145024) (xy 85.26145 -386.16636) (xy 85.26399 -386.170678)
			)
		)
	)
	(zone
		(layers "F.Cu" "B.Cu" "In1.Cu" "In2.Cu" "In3.Cu" "In4.Cu" "In5.Cu" "In6.Cu"
			"In7.Cu" "In8.Cu" "In9.Cu" "In10.Cu" "In11.Cu" "In12.Cu" "In13.Cu" "In14.Cu"
			"In15.Cu" "In16.Cu"
		)
		(hatch none 0.5)
		(connect_pads
			(clearance 0)
		)
		(min_thickness 0.25)
		(keepout
			(tracks not_allowed)
			(vias allowed)
			(pads allowed)
			(copperpour not_allowed)
			(footprints allowed)
		)
		(placement
			(enabled no)
			(sheetname "")
		)
		(fill
			(thermal_gap 0.5)
			(thermal_bridge_width 0.5)
			(island_removal_mode 0)
		)
		(polygon
			(pts
				(arc
					(start 380.897638 -400.811238)
					(mid 380.516638 -400.430238)
					(end 380.135638 -400.811238)
				)
				(arc
					(start 380.135638 -401.674838)
					(mid 380.516638 -402.055838)
					(end 380.897638 -401.674838)
				)
			)
		)
	)
	(zone
		(layers "F.Cu" "B.Cu" "In1.Cu" "In2.Cu" "In3.Cu" "In4.Cu" "In5.Cu" "In6.Cu"
			"In7.Cu" "In8.Cu" "In9.Cu" "In10.Cu" "In11.Cu" "In12.Cu" "In13.Cu" "In14.Cu"
			"In15.Cu" "In16.Cu"
		)
		(hatch none 0.5)
		(connect_pads
			(clearance 0)
		)
		(min_thickness 0.25)
		(keepout
			(tracks not_allowed)
			(vias allowed)
			(pads allowed)
			(copperpour not_allowed)
			(footprints allowed)
		)
		(placement
			(enabled no)
			(sheetname "")
		)
		(fill
			(thermal_gap 0.5)
			(thermal_bridge_width 0.5)
			(island_removal_mode 0)
		)
		(polygon
			(pts
				(arc
					(start 84.064348 -389.634476)
					(mid 84.174319 -389.73553)
					(end 84.31911 -389.772144)
				)
				(arc
					(start 84.31911 -389.772144)
					(mid 84.534636 -389.68287)
					(end 84.62391 -389.467344)
				)
				(arc
					(start 84.62391 -389.467344)
					(mid 84.613573 -389.388605)
					(end 84.58327 -389.315198)
				)
				(arc
					(start 84.19084 -388.636256)
					(mid 84.078443 -388.514639)
					(end 83.91906 -388.469632)
				)
				(arc
					(start 83.91906 -388.469632)
					(mid 83.703534 -388.558906)
					(end 83.61426 -388.774432)
				)
				(arc
					(start 83.61426 -388.774432)
					(mid 83.623838 -388.850494)
					(end 83.652106 -388.921752)
				)
				(xy 84.049362 -389.609076) (xy 84.061554 -389.630412) (xy 84.064094 -389.63473)
			)
		)
	)
	(zone
		(layers "F.Cu" "B.Cu" "In1.Cu" "In2.Cu" "In3.Cu" "In4.Cu" "In5.Cu" "In6.Cu"
			"In7.Cu" "In8.Cu" "In9.Cu" "In10.Cu" "In11.Cu" "In12.Cu" "In13.Cu" "In14.Cu"
			"In15.Cu" "In16.Cu"
		)
		(hatch none 0.5)
		(connect_pads
			(clearance 0)
		)
		(min_thickness 0.25)
		(keepout
			(tracks not_allowed)
			(vias allowed)
			(pads allowed)
			(copperpour not_allowed)
			(footprints allowed)
		)
		(placement
			(enabled no)
			(sheetname "")
		)
		(fill yes
			(thermal_gap 0.5)
			(thermal_bridge_width 0.5)
			(island_removal_mode 0)
		)
		(polygon
			(pts
				(arc
					(start 415.56432 -394.552424)
					(mid 415.674291 -394.653478)
					(end 415.819082 -394.690092)
				)
				(arc
					(start 415.819082 -394.690092)
					(mid 416.034608 -394.600818)
					(end 416.123882 -394.385292)
				)
				(arc
					(start 416.123882 -394.385292)
					(mid 416.113545 -394.306553)
					(end 416.083242 -394.233146)
				)
				(arc
					(start 415.690812 -393.554204)
					(mid 415.578415 -393.432587)
					(end 415.419032 -393.38758)
				)
				(arc
					(start 415.419032 -393.38758)
					(mid 415.203506 -393.476854)
					(end 415.114232 -393.69238)
				)
				(arc
					(start 415.114232 -393.69238)
					(mid 415.12381 -393.768442)
					(end 415.152078 -393.8397)
				)
				(xy 415.549334 -394.527024) (xy 415.561526 -394.54836) (xy 415.564066 -394.552678)
			)
		)
	)
	(zone
		(layers "F.Cu" "B.Cu" "In1.Cu" "In2.Cu" "In3.Cu" "In4.Cu" "In5.Cu" "In6.Cu"
			"In7.Cu" "In8.Cu" "In9.Cu" "In10.Cu" "In11.Cu" "In12.Cu" "In13.Cu" "In14.Cu"
			"In15.Cu" "In16.Cu"
		)
		(hatch none 0.5)
		(connect_pads
			(clearance 0)
		)
		(min_thickness 0.25)
		(keepout
			(tracks not_allowed)
			(vias allowed)
			(pads allowed)
			(copperpour not_allowed)
			(footprints allowed)
		)
		(placement
			(enabled no)
			(sheetname "")
		)
		(fill
			(thermal_gap 0.5)
			(thermal_bridge_width 0.5)
			(island_removal_mode 0)
		)
		(polygon
			(pts
				(arc
					(start 349.66402 -398.016476)
					(mid 349.773991 -398.11753)
					(end 349.918782 -398.154144)
				)
				(arc
					(start 349.918782 -398.154144)
					(mid 350.134308 -398.06487)
					(end 350.223582 -397.849344)
				)
				(arc
					(start 350.223582 -397.849344)
					(mid 350.213245 -397.770605)
					(end 350.182942 -397.697198)
				)
				(arc
					(start 349.790512 -397.018256)
					(mid 349.678115 -396.896639)
					(end 349.518732 -396.851632)
				)
				(arc
					(start 349.518732 -396.851632)
					(mid 349.303206 -396.940906)
					(end 349.213932 -397.156432)
				)
				(arc
					(start 349.213932 -397.156432)
					(mid 349.22351 -397.232494)
					(end 349.251778 -397.303752)
				)
				(xy 349.649034 -397.991076) (xy 349.661226 -398.012412) (xy 349.663766 -398.01673)
			)
		)
	)
	(zone
		(layers "F.Cu" "B.Cu" "In1.Cu" "In2.Cu" "In3.Cu" "In4.Cu" "In5.Cu" "In6.Cu"
			"In7.Cu" "In8.Cu" "In9.Cu" "In10.Cu" "In11.Cu" "In12.Cu" "In13.Cu" "In14.Cu"
			"In15.Cu" "In16.Cu"
		)
		(hatch none 0.5)
		(connect_pads
			(clearance 0)
		)
		(min_thickness 0.25)
		(keepout
			(tracks not_allowed)
			(vias allowed)
			(pads allowed)
			(copperpour not_allowed)
			(footprints allowed)
		)
		(placement
			(enabled no)
			(sheetname "")
		)
		(fill
			(thermal_gap 0.5)
			(thermal_bridge_width 0.5)
			(island_removal_mode 0)
		)
		(polygon
			(pts
				(arc
					(start 55.540402 -4.582414)
					(mid 55.159402 -4.963414)
					(end 55.540402 -5.344414)
				)
				(arc
					(start 56.404002 -5.344414)
					(mid 56.785002 -4.963414)
					(end 56.404002 -4.582414)
				)
			)
		)
	)
	(zone
		(layers "F.Cu" "B.Cu" "In1.Cu" "In2.Cu" "In3.Cu" "In4.Cu" "In5.Cu" "In6.Cu"
			"In7.Cu" "In8.Cu" "In9.Cu" "In10.Cu" "In11.Cu" "In12.Cu" "In13.Cu" "In14.Cu"
			"In15.Cu" "In16.Cu"
		)
		(hatch none 0.5)
		(connect_pads
			(clearance 0)
		)
		(min_thickness 0.25)
		(keepout
			(tracks not_allowed)
			(vias allowed)
			(pads allowed)
			(copperpour not_allowed)
			(footprints allowed)
		)
		(placement
			(enabled no)
			(sheetname "")
		)
		(fill
			(thermal_gap 0.5)
			(thermal_bridge_width 0.5)
			(island_removal_mode 0)
		)
		(polygon
			(pts
				(arc
					(start 94.520004 -308.85257)
					(mid 94.901004 -308.47157)
					(end 94.520004 -308.09057)
				)
				(arc
					(start 93.656404 -308.09057)
					(mid 93.275404 -308.47157)
					(end 93.656404 -308.85257)
				)
			)
		)
	)
	(zone
		(layers "F.Cu" "B.Cu" "In1.Cu" "In2.Cu" "In3.Cu" "In4.Cu" "In5.Cu" "In6.Cu"
			"In7.Cu" "In8.Cu" "In9.Cu" "In10.Cu" "In11.Cu" "In12.Cu" "In13.Cu" "In14.Cu"
			"In15.Cu" "In16.Cu"
		)
		(hatch none 0.5)
		(connect_pads
			(clearance 0)
		)
		(min_thickness 0.25)
		(keepout
			(tracks not_allowed)
			(vias allowed)
			(pads allowed)
			(copperpour not_allowed)
			(footprints allowed)
		)
		(placement
			(enabled no)
			(sheetname "")
		)
		(fill yes
			(thermal_gap 0.5)
			(thermal_bridge_width 0.5)
			(island_removal_mode 0)
		)
		(polygon
			(pts
				(arc
					(start 155.964128 -386.170424)
					(mid 156.074099 -386.271478)
					(end 156.21889 -386.308092)
				)
				(arc
					(start 156.21889 -386.308092)
					(mid 156.434416 -386.218818)
					(end 156.52369 -386.003292)
				)
				(arc
					(start 156.52369 -386.003292)
					(mid 156.513353 -385.924553)
					(end 156.48305 -385.851146)
				)
				(arc
					(start 156.09062 -385.172204)
					(mid 155.978223 -385.050587)
					(end 155.81884 -385.00558)
				)
				(arc
					(start 155.81884 -385.00558)
					(mid 155.603314 -385.094854)
					(end 155.51404 -385.31038)
				)
				(arc
					(start 155.51404 -385.31038)
					(mid 155.523618 -385.386442)
					(end 155.551886 -385.4577)
				)
				(xy 155.949142 -386.145024) (xy 155.961334 -386.16636) (xy 155.963874 -386.170678)
			)
		)
	)
	(zone
		(layers "F.Cu" "B.Cu" "In1.Cu" "In2.Cu" "In3.Cu" "In4.Cu" "In5.Cu" "In6.Cu"
			"In7.Cu" "In8.Cu" "In9.Cu" "In10.Cu" "In11.Cu" "In12.Cu" "In13.Cu" "In14.Cu"
			"In15.Cu" "In16.Cu"
		)
		(hatch none 0.5)
		(connect_pads
			(clearance 0)
		)
		(min_thickness 0.25)
		(keepout
			(tracks not_allowed)
			(vias allowed)
			(pads allowed)
			(copperpour not_allowed)
			(footprints allowed)
		)
		(placement
			(enabled no)
			(sheetname "")
		)
		(fill
			(thermal_gap 0.5)
			(thermal_bridge_width 0.5)
			(island_removal_mode 0)
		)
		(polygon
			(pts
				(arc
					(start 122.027696 -373.58193)
					(mid 121.646696 -373.96293)
					(end 122.027696 -374.34393)
				)
				(arc
					(start 122.891296 -374.34393)
					(mid 123.272296 -373.96293)
					(end 122.891296 -373.58193)
				)
			)
		)
	)
	(zone
		(layers "F.Cu" "B.Cu" "In1.Cu" "In2.Cu" "In3.Cu" "In4.Cu" "In5.Cu" "In6.Cu"
			"In7.Cu" "In8.Cu" "In9.Cu" "In10.Cu" "In11.Cu" "In12.Cu" "In13.Cu" "In14.Cu"
			"In15.Cu" "In16.Cu"
		)
		(hatch none 0.5)
		(connect_pads
			(clearance 0)
		)
		(min_thickness 0.25)
		(keepout
			(tracks not_allowed)
			(vias allowed)
			(pads allowed)
			(copperpour not_allowed)
			(footprints allowed)
		)
		(placement
			(enabled no)
			(sheetname "")
		)
		(fill yes
			(thermal_gap 0.5)
			(thermal_bridge_width 0.5)
			(island_removal_mode 0)
		)
		(polygon
			(pts
				(arc
					(start 157.164278 -386.170424)
					(mid 157.274249 -386.271478)
					(end 157.41904 -386.308092)
				)
				(arc
					(start 157.41904 -386.308092)
					(mid 157.634566 -386.218818)
					(end 157.72384 -386.003292)
				)
				(arc
					(start 157.72384 -386.003292)
					(mid 157.713503 -385.924553)
					(end 157.6832 -385.851146)
				)
				(arc
					(start 157.29077 -385.172204)
					(mid 157.178373 -385.050587)
					(end 157.01899 -385.00558)
				)
				(arc
					(start 157.01899 -385.00558)
					(mid 156.803464 -385.094854)
					(end 156.71419 -385.31038)
				)
				(arc
					(start 156.71419 -385.31038)
					(mid 156.723768 -385.386442)
					(end 156.752036 -385.4577)
				)
				(xy 157.149292 -386.145024) (xy 157.161484 -386.16636) (xy 157.164024 -386.170678)
			)
		)
	)
	(zone
		(layers "F.Cu" "B.Cu" "In1.Cu" "In2.Cu" "In3.Cu" "In4.Cu" "In5.Cu" "In6.Cu"
			"In7.Cu" "In8.Cu" "In9.Cu" "In10.Cu" "In11.Cu" "In12.Cu" "In13.Cu" "In14.Cu"
			"In15.Cu" "In16.Cu"
		)
		(hatch none 0.5)
		(connect_pads
			(clearance 0)
		)
		(min_thickness 0.25)
		(keepout
			(tracks not_allowed)
			(vias allowed)
			(pads allowed)
			(copperpour not_allowed)
			(footprints allowed)
		)
		(placement
			(enabled no)
			(sheetname "")
		)
		(fill
			(thermal_gap 0.5)
			(thermal_bridge_width 0.5)
			(island_removal_mode 0)
		)
		(polygon
			(pts
				(arc
					(start 417.36264 -381.96393)
					(mid 416.98164 -382.34493)
					(end 417.36264 -382.72593)
				)
				(arc
					(start 418.22624 -382.72593)
					(mid 418.60724 -382.34493)
					(end 418.22624 -381.96393)
				)
			)
		)
	)
	(zone
		(layers "F.Cu" "B.Cu" "In1.Cu" "In2.Cu" "In3.Cu" "In4.Cu" "In5.Cu" "In6.Cu"
			"In7.Cu" "In8.Cu" "In9.Cu" "In10.Cu" "In11.Cu" "In12.Cu" "In13.Cu" "In14.Cu"
			"In15.Cu" "In16.Cu"
		)
		(hatch none 0.5)
		(connect_pads
			(clearance 0)
		)
		(min_thickness 0.25)
		(keepout
			(tracks not_allowed)
			(vias allowed)
			(pads allowed)
			(copperpour not_allowed)
			(footprints allowed)
		)
		(placement
			(enabled no)
			(sheetname "")
		)
		(fill
			(thermal_gap 0.5)
			(thermal_bridge_width 0.5)
			(island_removal_mode 0)
		)
		(polygon
			(pts
				(arc
					(start 207.92186 -51.999896)
					(mid 201.36866 -51.999896)
					(end 207.92186 -51.999896)
				)
			)
		)
	)
	(zone
		(layers "F.Cu" "B.Cu" "In1.Cu" "In2.Cu" "In3.Cu" "In4.Cu" "In5.Cu" "In6.Cu"
			"In7.Cu" "In8.Cu" "In9.Cu" "In10.Cu" "In11.Cu" "In12.Cu" "In13.Cu" "In14.Cu"
			"In15.Cu" "In16.Cu"
		)
		(hatch none 0.5)
		(connect_pads
			(clearance 0)
		)
		(min_thickness 0.25)
		(keepout
			(tracks not_allowed)
			(vias allowed)
			(pads allowed)
			(copperpour not_allowed)
			(footprints allowed)
		)
		(placement
			(enabled no)
			(sheetname "")
		)
		(fill yes
			(thermal_gap 0.5)
			(thermal_bridge_width 0.5)
			(island_removal_mode 0)
		)
		(polygon
			(pts
				(arc
					(start 379.436376 -394.552424)
					(mid 379.546347 -394.653478)
					(end 379.691138 -394.690092)
				)
				(arc
					(start 379.691138 -394.690092)
					(mid 379.906664 -394.600818)
					(end 379.995938 -394.385292)
				)
				(arc
					(start 379.995938 -394.385292)
					(mid 379.985601 -394.306553)
					(end 379.955298 -394.233146)
				)
				(arc
					(start 379.562868 -393.554204)
					(mid 379.450471 -393.432587)
					(end 379.291088 -393.38758)
				)
				(arc
					(start 379.291088 -393.38758)
					(mid 379.075562 -393.476854)
					(end 378.986288 -393.69238)
				)
				(arc
					(start 378.986288 -393.69238)
					(mid 378.995866 -393.768442)
					(end 379.024134 -393.8397)
				)
				(xy 379.42139 -394.527024) (xy 379.433582 -394.54836) (xy 379.436122 -394.552678)
			)
		)
	)
	(zone
		(layers "F.Cu" "B.Cu" "In1.Cu" "In2.Cu" "In3.Cu" "In4.Cu" "In5.Cu" "In6.Cu"
			"In7.Cu" "In8.Cu" "In9.Cu" "In10.Cu" "In11.Cu" "In12.Cu" "In13.Cu" "In14.Cu"
			"In15.Cu" "In16.Cu"
		)
		(hatch none 0.5)
		(connect_pads
			(clearance 0)
		)
		(min_thickness 0.25)
		(keepout
			(tracks not_allowed)
			(vias allowed)
			(pads allowed)
			(copperpour not_allowed)
			(footprints allowed)
		)
		(placement
			(enabled no)
			(sheetname "")
		)
		(fill
			(thermal_gap 0.5)
			(thermal_bridge_width 0.5)
			(island_removal_mode 0)
		)
		(polygon
			(pts
				(arc
					(start 322.173346 -412.46552)
					(mid 321.792346 -412.84652)
					(end 322.173346 -413.22752)
				)
				(arc
					(start 323.036946 -413.22752)
					(mid 323.417946 -412.84652)
					(end 323.036946 -412.46552)
				)
			)
		)
	)
	(zone
		(layers "F.Cu" "B.Cu" "In1.Cu" "In2.Cu" "In3.Cu" "In4.Cu" "In5.Cu" "In6.Cu"
			"In7.Cu" "In8.Cu" "In9.Cu" "In10.Cu" "In11.Cu" "In12.Cu" "In13.Cu" "In14.Cu"
			"In15.Cu" "In16.Cu"
		)
		(hatch none 0.5)
		(connect_pads
			(clearance 0)
		)
		(min_thickness 0.25)
		(keepout
			(tracks not_allowed)
			(vias allowed)
			(pads allowed)
			(copperpour not_allowed)
			(footprints allowed)
		)
		(placement
			(enabled no)
			(sheetname "")
		)
		(fill
			(thermal_gap 0.5)
			(thermal_bridge_width 0.5)
			(island_removal_mode 0)
		)
		(polygon
			(pts
				(arc
					(start 322.173346 -420.571168)
					(mid 321.792346 -420.952168)
					(end 322.173346 -421.333168)
				)
				(arc
					(start 323.036946 -421.333168)
					(mid 323.417946 -420.952168)
					(end 323.036946 -420.571168)
				)
			)
		)
	)
	(zone
		(layers "F.Cu" "B.Cu" "In1.Cu" "In2.Cu" "In3.Cu" "In4.Cu" "In5.Cu" "In6.Cu"
			"In7.Cu" "In8.Cu" "In9.Cu" "In10.Cu" "In11.Cu" "In12.Cu" "In13.Cu" "In14.Cu"
			"In15.Cu" "In16.Cu"
		)
		(hatch none 0.5)
		(connect_pads
			(clearance 0)
		)
		(min_thickness 0.25)
		(keepout
			(tracks not_allowed)
			(vias allowed)
			(pads allowed)
			(copperpour not_allowed)
			(footprints allowed)
		)
		(placement
			(enabled no)
			(sheetname "")
		)
		(fill
			(thermal_gap 0.5)
			(thermal_bridge_width 0.5)
			(island_removal_mode 0)
		)
		(polygon
			(pts
				(arc
					(start 360.186224 -384.475228)
					(mid 359.805224 -384.094228)
					(end 359.424224 -384.475228)
				)
				(arc
					(start 359.424224 -385.338828)
					(mid 359.805224 -385.719828)
					(end 360.186224 -385.338828)
				)
			)
		)
	)
	(zone
		(layers "F.Cu" "B.Cu" "In1.Cu" "In2.Cu" "In3.Cu" "In4.Cu" "In5.Cu" "In6.Cu"
			"In7.Cu" "In8.Cu" "In9.Cu" "In10.Cu" "In11.Cu" "In12.Cu" "In13.Cu" "In14.Cu"
			"In15.Cu" "In16.Cu"
		)
		(hatch none 0.5)
		(connect_pads
			(clearance 0)
		)
		(min_thickness 0.25)
		(keepout
			(tracks not_allowed)
			(vias allowed)
			(pads allowed)
			(copperpour not_allowed)
			(footprints allowed)
		)
		(placement
			(enabled no)
			(sheetname "")
		)
		(fill
			(thermal_gap 0.5)
			(thermal_bridge_width 0.5)
			(island_removal_mode 0)
		)
		(polygon
			(pts
				(arc
					(start 168.169844 -368.65433)
					(mid 167.788844 -369.03533)
					(end 168.169844 -369.41633)
				)
				(arc
					(start 169.033444 -369.41633)
					(mid 169.414444 -369.03533)
					(end 169.033444 -368.65433)
				)
			)
		)
	)
	(zone
		(layers "F.Cu" "B.Cu" "In1.Cu" "In2.Cu" "In3.Cu" "In4.Cu" "In5.Cu" "In6.Cu"
			"In7.Cu" "In8.Cu" "In9.Cu" "In10.Cu" "In11.Cu" "In12.Cu" "In13.Cu" "In14.Cu"
			"In15.Cu" "In16.Cu"
		)
		(hatch none 0.5)
		(connect_pads
			(clearance 0)
		)
		(min_thickness 0.25)
		(keepout
			(tracks not_allowed)
			(vias allowed)
			(pads allowed)
			(copperpour not_allowed)
			(footprints allowed)
		)
		(placement
			(enabled no)
			(sheetname "")
		)
		(fill
			(thermal_gap 0.5)
			(thermal_bridge_width 0.5)
			(island_removal_mode 0)
		)
		(polygon
			(pts
				(arc
					(start 316.01283 7.191756)
					(mid 316.44463 6.759956)
					(end 316.87643 7.191756)
				)
				(arc
					(start 316.87643 8.055356)
					(mid 316.44463 8.487156)
					(end 316.01283 8.055356)
				)
			)
		)
	)
	(zone
		(layers "F.Cu" "B.Cu" "In1.Cu" "In2.Cu" "In3.Cu" "In4.Cu" "In5.Cu" "In6.Cu"
			"In7.Cu" "In8.Cu" "In9.Cu" "In10.Cu" "In11.Cu" "In12.Cu" "In13.Cu" "In14.Cu"
			"In15.Cu" "In16.Cu"
		)
		(hatch none 0.5)
		(connect_pads
			(clearance 0)
		)
		(min_thickness 0.25)
		(keepout
			(tracks not_allowed)
			(vias allowed)
			(pads allowed)
			(copperpour not_allowed)
			(footprints allowed)
		)
		(placement
			(enabled no)
			(sheetname "")
		)
		(fill
			(thermal_gap 0.5)
			(thermal_bridge_width 0.5)
			(island_removal_mode 0)
		)
		(polygon
			(pts
				(arc
					(start 349.925132 -400.811238)
					(mid 349.544132 -400.430238)
					(end 349.163132 -400.811238)
				)
				(arc
					(start 349.163132 -401.674838)
					(mid 349.544132 -402.055838)
					(end 349.925132 -401.674838)
				)
			)
		)
	)
	(zone
		(layers "F.Cu" "B.Cu" "In1.Cu" "In2.Cu" "In3.Cu" "In4.Cu" "In5.Cu" "In6.Cu"
			"In7.Cu" "In8.Cu" "In9.Cu" "In10.Cu" "In11.Cu" "In12.Cu" "In13.Cu" "In14.Cu"
			"In15.Cu" "In16.Cu"
		)
		(hatch none 0.5)
		(connect_pads
			(clearance 0)
		)
		(min_thickness 0.25)
		(keepout
			(tracks not_allowed)
			(vias allowed)
			(pads allowed)
			(copperpour not_allowed)
			(footprints allowed)
		)
		(placement
			(enabled no)
			(sheetname "")
		)
		(fill
			(thermal_gap 0.5)
			(thermal_bridge_width 0.5)
			(island_removal_mode 0)
		)
		(polygon
			(pts
				(arc
					(start 164.174932 -149.559264)
					(mid 163.793932 -149.940264)
					(end 164.174932 -150.321264)
				)
				(arc
					(start 165.165532 -150.321264)
					(mid 165.546532 -149.940264)
					(end 165.165532 -149.559264)
				)
			)
		)
	)
	(zone
		(layers "F.Cu" "B.Cu" "In1.Cu" "In2.Cu" "In3.Cu" "In4.Cu" "In5.Cu" "In6.Cu"
			"In7.Cu" "In8.Cu" "In9.Cu" "In10.Cu" "In11.Cu" "In12.Cu" "In13.Cu" "In14.Cu"
			"In15.Cu" "In16.Cu"
		)
		(hatch none 0.5)
		(connect_pads
			(clearance 0)
		)
		(min_thickness 0.25)
		(keepout
			(tracks not_allowed)
			(vias allowed)
			(pads allowed)
			(copperpour not_allowed)
			(footprints allowed)
		)
		(placement
			(enabled no)
			(sheetname "")
		)
		(fill
			(thermal_gap 0.5)
			(thermal_bridge_width 0.5)
			(island_removal_mode 0)
		)
		(polygon
			(pts
				(arc
					(start 157.779466 -412.189168)
					(mid 157.398466 -412.570168)
					(end 157.779466 -412.951168)
				)
				(arc
					(start 158.643066 -412.951168)
					(mid 159.024066 -412.570168)
					(end 158.643066 -412.189168)
				)
			)
		)
	)
	(zone
		(layers "F.Cu" "B.Cu" "In1.Cu" "In2.Cu" "In3.Cu" "In4.Cu" "In5.Cu" "In6.Cu"
			"In7.Cu" "In8.Cu" "In9.Cu" "In10.Cu" "In11.Cu" "In12.Cu" "In13.Cu" "In14.Cu"
			"In15.Cu" "In16.Cu"
		)
		(hatch none 0.5)
		(connect_pads
			(clearance 0)
		)
		(min_thickness 0.25)
		(keepout
			(tracks not_allowed)
			(vias allowed)
			(pads allowed)
			(copperpour not_allowed)
			(footprints allowed)
		)
		(placement
			(enabled no)
			(sheetname "")
		)
		(fill
			(thermal_gap 0.5)
			(thermal_bridge_width 0.5)
			(island_removal_mode 0)
		)
		(polygon
			(pts
				(arc
					(start 172.823886 -57.049924)
					(mid 170.842686 -57.049924)
					(end 172.823886 -57.049924)
				)
			)
		)
	)
	(zone
		(layers "F.Cu" "B.Cu" "In1.Cu" "In2.Cu" "In3.Cu" "In4.Cu" "In5.Cu" "In6.Cu"
			"In7.Cu" "In8.Cu" "In9.Cu" "In10.Cu" "In11.Cu" "In12.Cu" "In13.Cu" "In14.Cu"
			"In15.Cu" "In16.Cu"
		)
		(hatch none 0.5)
		(connect_pads
			(clearance 0)
		)
		(min_thickness 0.25)
		(keepout
			(tracks not_allowed)
			(vias allowed)
			(pads allowed)
			(copperpour not_allowed)
			(footprints allowed)
		)
		(placement
			(enabled no)
			(sheetname "")
		)
		(fill
			(thermal_gap 0.5)
			(thermal_bridge_width 0.5)
			(island_removal_mode 0)
		)
		(polygon
			(pts
				(arc
					(start 338.534248 -217.140282)
					(mid 338.153248 -217.521282)
					(end 338.534248 -217.902282)
				)
				(arc
					(start 339.550248 -217.902282)
					(mid 339.931248 -217.521282)
					(end 339.550248 -217.140282)
				)
			)
		)
	)
	(zone
		(layers "F.Cu" "B.Cu" "In1.Cu" "In2.Cu" "In3.Cu" "In4.Cu" "In5.Cu" "In6.Cu"
			"In7.Cu" "In8.Cu" "In9.Cu" "In10.Cu" "In11.Cu" "In12.Cu" "In13.Cu" "In14.Cu"
			"In15.Cu" "In16.Cu"
		)
		(hatch none 0.5)
		(connect_pads
			(clearance 0)
		)
		(min_thickness 0.25)
		(keepout
			(tracks not_allowed)
			(vias allowed)
			(pads allowed)
			(copperpour not_allowed)
			(footprints allowed)
		)
		(placement
			(enabled no)
			(sheetname "")
		)
		(fill
			(thermal_gap 0.5)
			(thermal_bridge_width 0.5)
			(island_removal_mode 0)
		)
		(polygon
			(pts
				(arc
					(start 330.339192 -389.88746)
					(mid 329.958192 -389.50646)
					(end 329.577192 -389.88746)
				)
				(arc
					(start 329.577192 -390.75106)
					(mid 329.958192 -391.13206)
					(end 330.339192 -390.75106)
				)
			)
		)
	)
	(zone
		(layers "F.Cu" "B.Cu" "In1.Cu" "In2.Cu" "In3.Cu" "In4.Cu" "In5.Cu" "In6.Cu"
			"In7.Cu" "In8.Cu" "In9.Cu" "In10.Cu" "In11.Cu" "In12.Cu" "In13.Cu" "In14.Cu"
			"In15.Cu" "In16.Cu"
		)
		(hatch none 0.5)
		(connect_pads
			(clearance 0)
		)
		(min_thickness 0.25)
		(keepout
			(tracks not_allowed)
			(vias allowed)
			(pads allowed)
			(copperpour not_allowed)
			(footprints allowed)
		)
		(placement
			(enabled no)
			(sheetname "")
		)
		(fill
			(thermal_gap 0.5)
			(thermal_bridge_width 0.5)
			(island_removal_mode 0)
		)
		(polygon
			(pts
				(arc
					(start 329.831446 -415.00552)
					(mid 329.450446 -415.38652)
					(end 329.831446 -415.76752)
				)
				(arc
					(start 330.695046 -415.76752)
					(mid 331.076046 -415.38652)
					(end 330.695046 -415.00552)
				)
			)
		)
	)
	(zone
		(layers "F.Cu" "B.Cu" "In1.Cu" "In2.Cu" "In3.Cu" "In4.Cu" "In5.Cu" "In6.Cu"
			"In7.Cu" "In8.Cu" "In9.Cu" "In10.Cu" "In11.Cu" "In12.Cu" "In13.Cu" "In14.Cu"
			"In15.Cu" "In16.Cu"
		)
		(hatch none 0.5)
		(connect_pads
			(clearance 0)
		)
		(min_thickness 0.25)
		(keepout
			(tracks not_allowed)
			(vias allowed)
			(pads allowed)
			(copperpour not_allowed)
			(footprints allowed)
		)
		(placement
			(enabled no)
			(sheetname "")
		)
		(fill
			(thermal_gap 0.5)
			(thermal_bridge_width 0.5)
			(island_removal_mode 0)
		)
		(polygon
			(pts
				(arc
					(start 235.265214 -60.375038)
					(mid 233.334814 -60.375038)
					(end 235.265214 -60.375038)
				)
			)
		)
	)
	(zone
		(layers "F.Cu" "B.Cu" "In1.Cu" "In2.Cu" "In3.Cu" "In4.Cu" "In5.Cu" "In6.Cu"
			"In7.Cu" "In8.Cu" "In9.Cu" "In10.Cu" "In11.Cu" "In12.Cu" "In13.Cu" "In14.Cu"
			"In15.Cu" "In16.Cu"
		)
		(hatch none 0.5)
		(connect_pads
			(clearance 0)
		)
		(min_thickness 0.25)
		(keepout
			(tracks not_allowed)
			(vias allowed)
			(pads allowed)
			(copperpour not_allowed)
			(footprints allowed)
		)
		(placement
			(enabled no)
			(sheetname "")
		)
		(fill
			(thermal_gap 0.5)
			(thermal_bridge_width 0.5)
			(island_removal_mode 0)
		)
		(polygon
			(pts
				(arc
					(start 403.825202 -400.811238)
					(mid 403.444202 -400.430238)
					(end 403.063202 -400.811238)
				)
				(arc
					(start 403.063202 -401.674838)
					(mid 403.444202 -402.055838)
					(end 403.825202 -401.674838)
				)
			)
		)
	)
	(zone
		(layers "F.Cu" "B.Cu" "In1.Cu" "In2.Cu" "In3.Cu" "In4.Cu" "In5.Cu" "In6.Cu"
			"In7.Cu" "In8.Cu" "In9.Cu" "In10.Cu" "In11.Cu" "In12.Cu" "In13.Cu" "In14.Cu"
			"In15.Cu" "In16.Cu"
		)
		(hatch none 0.5)
		(connect_pads
			(clearance 0)
		)
		(min_thickness 0.25)
		(keepout
			(tracks not_allowed)
			(vias allowed)
			(pads allowed)
			(copperpour not_allowed)
			(footprints allowed)
		)
		(placement
			(enabled no)
			(sheetname "")
		)
		(fill
			(thermal_gap 0.5)
			(thermal_bridge_width 0.5)
			(island_removal_mode 0)
		)
		(polygon
			(pts
				(arc
					(start 352.324924 -400.811238)
					(mid 351.943924 -400.430238)
					(end 351.562924 -400.811238)
				)
				(arc
					(start 351.562924 -401.674838)
					(mid 351.943924 -402.055838)
					(end 352.324924 -401.674838)
				)
			)
		)
	)
	(zone
		(layers "F.Cu" "B.Cu" "In1.Cu" "In2.Cu" "In3.Cu" "In4.Cu" "In5.Cu" "In6.Cu"
			"In7.Cu" "In8.Cu" "In9.Cu" "In10.Cu" "In11.Cu" "In12.Cu" "In13.Cu" "In14.Cu"
			"In15.Cu" "In16.Cu"
		)
		(hatch none 0.5)
		(connect_pads
			(clearance 0)
		)
		(min_thickness 0.25)
		(keepout
			(tracks not_allowed)
			(vias allowed)
			(pads allowed)
			(copperpour not_allowed)
			(footprints allowed)
		)
		(placement
			(enabled no)
			(sheetname "")
		)
		(fill
			(thermal_gap 0.5)
			(thermal_bridge_width 0.5)
			(island_removal_mode 0)
		)
		(polygon
			(pts
				(arc
					(start 151.652986 -404.08352)
					(mid 151.271986 -404.46452)
					(end 151.652986 -404.84552)
				)
				(arc
					(start 152.516586 -404.84552)
					(mid 152.897586 -404.46452)
					(end 152.516586 -404.08352)
				)
			)
		)
	)
	(zone
		(layers "F.Cu" "B.Cu" "In1.Cu" "In2.Cu" "In3.Cu" "In4.Cu" "In5.Cu" "In6.Cu"
			"In7.Cu" "In8.Cu" "In9.Cu" "In10.Cu" "In11.Cu" "In12.Cu" "In13.Cu" "In14.Cu"
			"In15.Cu" "In16.Cu"
		)
		(hatch none 0.5)
		(connect_pads
			(clearance 0)
		)
		(min_thickness 0.25)
		(keepout
			(tracks not_allowed)
			(vias allowed)
			(pads allowed)
			(copperpour not_allowed)
			(footprints allowed)
		)
		(placement
			(enabled no)
			(sheetname "")
		)
		(fill
			(thermal_gap 0.5)
			(thermal_bridge_width 0.5)
			(island_removal_mode 0)
		)
		(polygon
			(pts
				(arc
					(start 94.107 -212.140038)
					(mid 94.488 -212.521038)
					(end 94.869 -212.140038)
				)
				(arc
					(start 94.869 -211.276438)
					(mid 94.488 -210.895438)
					(end 94.107 -211.276438)
				)
			)
		)
	)
	(zone
		(layers "F.Cu" "B.Cu" "In1.Cu" "In2.Cu" "In3.Cu" "In4.Cu" "In5.Cu" "In6.Cu"
			"In7.Cu" "In8.Cu" "In9.Cu" "In10.Cu" "In11.Cu" "In12.Cu" "In13.Cu" "In14.Cu"
			"In15.Cu" "In16.Cu"
		)
		(hatch none 0.5)
		(connect_pads
			(clearance 0)
		)
		(min_thickness 0.25)
		(keepout
			(tracks not_allowed)
			(vias allowed)
			(pads allowed)
			(copperpour not_allowed)
			(footprints allowed)
		)
		(placement
			(enabled no)
			(sheetname "")
		)
		(fill
			(thermal_gap 0.5)
			(thermal_bridge_width 0.5)
			(island_removal_mode 0)
		)
		(polygon
			(pts
				(arc
					(start 393.868402 -415.00552)
					(mid 393.487402 -415.38652)
					(end 393.868402 -415.76752)
				)
				(arc
					(start 394.732002 -415.76752)
					(mid 395.113002 -415.38652)
					(end 394.732002 -415.00552)
				)
			)
		)
	)
	(zone
		(layers "F.Cu" "B.Cu" "In1.Cu" "In2.Cu" "In3.Cu" "In4.Cu" "In5.Cu" "In6.Cu"
			"In7.Cu" "In8.Cu" "In9.Cu" "In10.Cu" "In11.Cu" "In12.Cu" "In13.Cu" "In14.Cu"
			"In15.Cu" "In16.Cu"
		)
		(hatch none 0.5)
		(connect_pads
			(clearance 0)
		)
		(min_thickness 0.25)
		(keepout
			(tracks not_allowed)
			(vias allowed)
			(pads allowed)
			(copperpour not_allowed)
			(footprints allowed)
		)
		(placement
			(enabled no)
			(sheetname "")
		)
		(fill
			(thermal_gap 0.5)
			(thermal_bridge_width 0.5)
			(island_removal_mode 0)
		)
		(polygon
			(pts
				(arc
					(start 83.12531 -392.429238)
					(mid 82.74431 -392.048238)
					(end 82.36331 -392.429238)
				)
				(arc
					(start 82.36331 -393.292838)
					(mid 82.74431 -393.673838)
					(end 83.12531 -393.292838)
				)
			)
		)
	)
	(zone
		(layers "F.Cu" "B.Cu" "In1.Cu" "In2.Cu" "In3.Cu" "In4.Cu" "In5.Cu" "In6.Cu"
			"In7.Cu" "In8.Cu" "In9.Cu" "In10.Cu" "In11.Cu" "In12.Cu" "In13.Cu" "In14.Cu"
			"In15.Cu" "In16.Cu"
		)
		(hatch none 0.5)
		(connect_pads
			(clearance 0)
		)
		(min_thickness 0.25)
		(keepout
			(tracks not_allowed)
			(vias allowed)
			(pads allowed)
			(copperpour not_allowed)
			(footprints allowed)
		)
		(placement
			(enabled no)
			(sheetname "")
		)
		(fill
			(thermal_gap 0.5)
			(thermal_bridge_width 0.5)
			(island_removal_mode 0)
		)
		(polygon
			(pts
				(arc
					(start 143.994886 -406.62352)
					(mid 143.613886 -407.00452)
					(end 143.994886 -407.38552)
				)
				(arc
					(start 144.858486 -407.38552)
					(mid 145.239486 -407.00452)
					(end 144.858486 -406.62352)
				)
			)
		)
	)
	(zone
		(layers "F.Cu" "B.Cu" "In1.Cu" "In2.Cu" "In3.Cu" "In4.Cu" "In5.Cu" "In6.Cu"
			"In7.Cu" "In8.Cu" "In9.Cu" "In10.Cu" "In11.Cu" "In12.Cu" "In13.Cu" "In14.Cu"
			"In15.Cu" "In16.Cu"
		)
		(hatch none 0.5)
		(connect_pads
			(clearance 0)
		)
		(min_thickness 0.25)
		(keepout
			(tracks not_allowed)
			(vias allowed)
			(pads allowed)
			(copperpour not_allowed)
			(footprints allowed)
		)
		(placement
			(enabled no)
			(sheetname "")
		)
		(fill
			(thermal_gap 0.5)
			(thermal_bridge_width 0.5)
			(island_removal_mode 0)
		)
		(polygon
			(pts
				(arc
					(start 49.325784 -409.649168)
					(mid 48.944784 -410.030168)
					(end 49.325784 -410.411168)
				)
				(arc
					(start 50.189384 -410.411168)
					(mid 50.570384 -410.030168)
					(end 50.189384 -409.649168)
				)
			)
		)
	)
	(zone
		(layers "F.Cu" "B.Cu" "In1.Cu" "In2.Cu" "In3.Cu" "In4.Cu" "In5.Cu" "In6.Cu"
			"In7.Cu" "In8.Cu" "In9.Cu" "In10.Cu" "In11.Cu" "In12.Cu" "In13.Cu" "In14.Cu"
			"In15.Cu" "In16.Cu"
		)
		(hatch none 0.5)
		(connect_pads
			(clearance 0)
		)
		(min_thickness 0.25)
		(keepout
			(tracks not_allowed)
			(vias allowed)
			(pads allowed)
			(copperpour not_allowed)
			(footprints allowed)
		)
		(placement
			(enabled no)
			(sheetname "")
		)
		(fill
			(thermal_gap 0.5)
			(thermal_bridge_width 0.5)
			(island_removal_mode 0)
		)
		(polygon
			(pts
				(arc
					(start 98.843084 5.632196)
					(mid 99.274884 5.200396)
					(end 99.706684 5.632196)
				)
				(arc
					(start 99.706684 6.495796)
					(mid 99.274884 6.927596)
					(end 98.843084 6.495796)
				)
			)
		)
	)
	(zone
		(layers "F.Cu" "B.Cu" "In1.Cu" "In2.Cu" "In3.Cu" "In4.Cu" "In5.Cu" "In6.Cu"
			"In7.Cu" "In8.Cu" "In9.Cu" "In10.Cu" "In11.Cu" "In12.Cu" "In13.Cu" "In14.Cu"
			"In15.Cu" "In16.Cu"
		)
		(hatch none 0.5)
		(connect_pads
			(clearance 0)
		)
		(min_thickness 0.25)
		(keepout
			(tracks not_allowed)
			(vias allowed)
			(pads allowed)
			(copperpour not_allowed)
			(footprints allowed)
		)
		(placement
			(enabled no)
			(sheetname "")
		)
		(fill
			(thermal_gap 0.5)
			(thermal_bridge_width 0.5)
			(island_removal_mode 0)
		)
		(polygon
			(pts
				(arc
					(start 26.215594 -6.344158)
					(mid 25.834594 -6.725158)
					(end 26.215594 -7.106158)
				)
				(arc
					(start 27.079194 -7.106158)
					(mid 27.460194 -6.725158)
					(end 27.079194 -6.344158)
				)
			)
		)
	)
	(zone
		(layers "F.Cu" "B.Cu" "In1.Cu" "In2.Cu" "In3.Cu" "In4.Cu" "In5.Cu" "In6.Cu"
			"In7.Cu" "In8.Cu" "In9.Cu" "In10.Cu" "In11.Cu" "In12.Cu" "In13.Cu" "In14.Cu"
			"In15.Cu" "In16.Cu"
		)
		(hatch none 0.5)
		(connect_pads
			(clearance 0)
		)
		(min_thickness 0.25)
		(keepout
			(tracks not_allowed)
			(vias allowed)
			(pads allowed)
			(copperpour not_allowed)
			(footprints allowed)
		)
		(placement
			(enabled no)
			(sheetname "")
		)
		(fill yes
			(thermal_gap 0.5)
			(thermal_bridge_width 0.5)
			(island_removal_mode 0)
		)
		(polygon
			(pts
				(arc
					(start 174.999904 -404.789894)
					(mid 170.999912 -408.789886)
					(end 166.99992 -404.789894)
				)
				(arc
					(start 166.99992 -404.789894)
					(mid 170.999912 -400.789902)
					(end 174.999904 -404.789894)
				)
			)
		)
	)
	(zone
		(layers "F.Cu" "B.Cu" "In1.Cu" "In2.Cu" "In3.Cu" "In4.Cu" "In5.Cu" "In6.Cu"
			"In7.Cu" "In8.Cu" "In9.Cu" "In10.Cu" "In11.Cu" "In12.Cu" "In13.Cu" "In14.Cu"
			"In15.Cu" "In16.Cu"
		)
		(hatch none 0.5)
		(connect_pads
			(clearance 0)
		)
		(min_thickness 0.25)
		(keepout
			(tracks not_allowed)
			(vias allowed)
			(pads allowed)
			(copperpour not_allowed)
			(footprints allowed)
		)
		(placement
			(enabled no)
			(sheetname "")
		)
		(fill
			(thermal_gap 0.5)
			(thermal_bridge_width 0.5)
			(island_removal_mode 0)
		)
		(polygon
			(pts
				(arc
					(start 373.957342 -412.46552)
					(mid 373.576342 -412.84652)
					(end 373.957342 -413.22752)
				)
				(arc
					(start 374.820942 -413.22752)
					(mid 375.201942 -412.84652)
					(end 374.820942 -412.46552)
				)
			)
		)
	)
	(zone
		(layers "F.Cu" "B.Cu" "In1.Cu" "In2.Cu" "In3.Cu" "In4.Cu" "In5.Cu" "In6.Cu"
			"In7.Cu" "In8.Cu" "In9.Cu" "In10.Cu" "In11.Cu" "In12.Cu" "In13.Cu" "In14.Cu"
			"In15.Cu" "In16.Cu"
		)
		(hatch none 0.5)
		(connect_pads
			(clearance 0)
		)
		(min_thickness 0.25)
		(keepout
			(tracks not_allowed)
			(vias allowed)
			(pads allowed)
			(copperpour not_allowed)
			(footprints allowed)
		)
		(placement
			(enabled no)
			(sheetname "")
		)
		(fill yes
			(thermal_gap 0.5)
			(thermal_bridge_width 0.5)
			(island_removal_mode 0)
		)
		(polygon
			(pts
				(arc
					(start 403.564344 -394.552424)
					(mid 403.674315 -394.653478)
					(end 403.819106 -394.690092)
				)
				(arc
					(start 403.819106 -394.690092)
					(mid 404.034632 -394.600818)
					(end 404.123906 -394.385292)
				)
				(arc
					(start 404.123906 -394.385292)
					(mid 404.113569 -394.306553)
					(end 404.083266 -394.233146)
				)
				(arc
					(start 403.690836 -393.554204)
					(mid 403.578439 -393.432587)
					(end 403.419056 -393.38758)
				)
				(arc
					(start 403.419056 -393.38758)
					(mid 403.20353 -393.476854)
					(end 403.114256 -393.69238)
				)
				(arc
					(start 403.114256 -393.69238)
					(mid 403.123834 -393.768442)
					(end 403.152102 -393.8397)
				)
				(xy 403.549358 -394.527024) (xy 403.56155 -394.54836) (xy 403.56409 -394.552678)
			)
		)
	)
	(zone
		(layers "F.Cu" "B.Cu" "In1.Cu" "In2.Cu" "In3.Cu" "In4.Cu" "In5.Cu" "In6.Cu"
			"In7.Cu" "In8.Cu" "In9.Cu" "In10.Cu" "In11.Cu" "In12.Cu" "In13.Cu" "In14.Cu"
			"In15.Cu" "In16.Cu"
		)
		(hatch none 0.5)
		(connect_pads
			(clearance 0)
		)
		(min_thickness 0.25)
		(keepout
			(tracks not_allowed)
			(vias allowed)
			(pads allowed)
			(copperpour not_allowed)
			(footprints allowed)
		)
		(placement
			(enabled no)
			(sheetname "")
		)
		(fill yes
			(thermal_gap 0.5)
			(thermal_bridge_width 0.5)
			(island_removal_mode 0)
		)
		(polygon
			(pts
				(arc
					(start 303.9364 -394.552424)
					(mid 304.046371 -394.653478)
					(end 304.191162 -394.690092)
				)
				(arc
					(start 304.191162 -394.690092)
					(mid 304.406688 -394.600818)
					(end 304.495962 -394.385292)
				)
				(arc
					(start 304.495962 -394.385292)
					(mid 304.485625 -394.306553)
					(end 304.455322 -394.233146)
				)
				(arc
					(start 304.062892 -393.554204)
					(mid 303.950495 -393.432587)
					(end 303.791112 -393.38758)
				)
				(arc
					(start 303.791112 -393.38758)
					(mid 303.575586 -393.476854)
					(end 303.486312 -393.69238)
				)
				(arc
					(start 303.486312 -393.69238)
					(mid 303.49589 -393.768442)
					(end 303.524158 -393.8397)
				)
				(xy 303.921414 -394.527024) (xy 303.933606 -394.54836) (xy 303.936146 -394.552678)
			)
		)
	)
	(zone
		(layers "F.Cu" "B.Cu" "In1.Cu" "In2.Cu" "In3.Cu" "In4.Cu" "In5.Cu" "In6.Cu"
			"In7.Cu" "In8.Cu" "In9.Cu" "In10.Cu" "In11.Cu" "In12.Cu" "In13.Cu" "In14.Cu"
			"In15.Cu" "In16.Cu"
		)
		(hatch none 0.5)
		(connect_pads
			(clearance 0)
		)
		(min_thickness 0.25)
		(keepout
			(tracks not_allowed)
			(vias allowed)
			(pads allowed)
			(copperpour not_allowed)
			(footprints allowed)
		)
		(placement
			(enabled no)
			(sheetname "")
		)
		(fill
			(thermal_gap 0.5)
			(thermal_bridge_width 0.5)
			(island_removal_mode 0)
		)
		(polygon
			(pts
				(arc
					(start 427.28642 -387.878828)
					(mid 426.90542 -387.497828)
					(end 426.52442 -387.878828)
				)
				(arc
					(start 426.52442 -388.742428)
					(mid 426.90542 -389.123428)
					(end 427.28642 -388.742428)
				)
			)
		)
	)
	(zone
		(layers "F.Cu" "B.Cu" "In1.Cu" "In2.Cu" "In3.Cu" "In4.Cu" "In5.Cu" "In6.Cu"
			"In7.Cu" "In8.Cu" "In9.Cu" "In10.Cu" "In11.Cu" "In12.Cu" "In13.Cu" "In14.Cu"
			"In15.Cu" "In16.Cu"
		)
		(hatch none 0.5)
		(connect_pads
			(clearance 0)
		)
		(min_thickness 0.25)
		(keepout
			(tracks not_allowed)
			(vias allowed)
			(pads allowed)
			(copperpour not_allowed)
			(footprints allowed)
		)
		(placement
			(enabled no)
			(sheetname "")
		)
		(fill
			(thermal_gap 0.5)
			(thermal_bridge_width 0.5)
			(island_removal_mode 0)
		)
		(polygon
			(pts
				(arc
					(start 412.247842 -415.00552)
					(mid 411.866842 -415.38652)
					(end 412.247842 -415.76752)
				)
				(arc
					(start 413.111442 -415.76752)
					(mid 413.492442 -415.38652)
					(end 413.111442 -415.00552)
				)
			)
		)
	)
	(zone
		(layers "F.Cu" "B.Cu" "In1.Cu" "In2.Cu" "In3.Cu" "In4.Cu" "In5.Cu" "In6.Cu"
			"In7.Cu" "In8.Cu" "In9.Cu" "In10.Cu" "In11.Cu" "In12.Cu" "In13.Cu" "In14.Cu"
			"In15.Cu" "In16.Cu"
		)
		(hatch none 0.5)
		(connect_pads
			(clearance 0)
		)
		(min_thickness 0.25)
		(keepout
			(tracks not_allowed)
			(vias allowed)
			(pads allowed)
			(copperpour not_allowed)
			(footprints allowed)
		)
		(placement
			(enabled no)
			(sheetname "")
		)
		(fill
			(thermal_gap 0.5)
			(thermal_bridge_width 0.5)
			(island_removal_mode 0)
		)
		(polygon
			(pts
				(arc
					(start 57.78373 -18.75536)
					(mid 57.40273 -19.13636)
					(end 57.78373 -19.51736)
				)
				(arc
					(start 58.64733 -19.51736)
					(mid 59.02833 -19.13636)
					(end 58.64733 -18.75536)
				)
			)
		)
	)
	(zone
		(layers "F.Cu" "B.Cu" "In1.Cu" "In2.Cu" "In3.Cu" "In4.Cu" "In5.Cu" "In6.Cu"
			"In7.Cu" "In8.Cu" "In9.Cu" "In10.Cu" "In11.Cu" "In12.Cu" "In13.Cu" "In14.Cu"
			"In15.Cu" "In16.Cu"
		)
		(hatch none 0.5)
		(connect_pads
			(clearance 0)
		)
		(min_thickness 0.25)
		(keepout
			(tracks not_allowed)
			(vias allowed)
			(pads allowed)
			(copperpour not_allowed)
			(footprints allowed)
		)
		(placement
			(enabled no)
			(sheetname "")
		)
		(fill
			(thermal_gap 0.5)
			(thermal_bridge_width 0.5)
			(island_removal_mode 0)
		)
		(polygon
			(pts
				(arc
					(start 181.660546 -50.949098)
					(mid 182.041546 -51.330098)
					(end 182.422546 -50.949098)
				)
				(arc
					(start 182.422546 -50.085498)
					(mid 182.041546 -49.704498)
					(end 181.660546 -50.085498)
				)
			)
		)
	)
	(zone
		(layers "F.Cu" "B.Cu" "In1.Cu" "In2.Cu" "In3.Cu" "In4.Cu" "In5.Cu" "In6.Cu"
			"In7.Cu" "In8.Cu" "In9.Cu" "In10.Cu" "In11.Cu" "In12.Cu" "In13.Cu" "In14.Cu"
			"In15.Cu" "In16.Cu"
		)
		(hatch none 0.5)
		(connect_pads
			(clearance 0)
		)
		(min_thickness 0.25)
		(keepout
			(tracks not_allowed)
			(vias allowed)
			(pads allowed)
			(copperpour not_allowed)
			(footprints allowed)
		)
		(placement
			(enabled no)
			(sheetname "")
		)
		(fill
			(thermal_gap 0.5)
			(thermal_bridge_width 0.5)
			(island_removal_mode 0)
		)
		(polygon
			(pts
				(arc
					(start 116.425726 -406.62352)
					(mid 116.044726 -407.00452)
					(end 116.425726 -407.38552)
				)
				(arc
					(start 117.289326 -407.38552)
					(mid 117.670326 -407.00452)
					(end 117.289326 -406.62352)
				)
			)
		)
	)
	(zone
		(layers "F.Cu" "B.Cu" "In1.Cu" "In2.Cu" "In3.Cu" "In4.Cu" "In5.Cu" "In6.Cu"
			"In7.Cu" "In8.Cu" "In9.Cu" "In10.Cu" "In11.Cu" "In12.Cu" "In13.Cu" "In14.Cu"
			"In15.Cu" "In16.Cu"
		)
		(hatch none 0.5)
		(connect_pads
			(clearance 0)
		)
		(min_thickness 0.25)
		(keepout
			(tracks not_allowed)
			(vias allowed)
			(pads allowed)
			(copperpour not_allowed)
			(footprints allowed)
		)
		(placement
			(enabled no)
			(sheetname "")
		)
		(fill yes
			(thermal_gap 0.5)
			(thermal_bridge_width 0.5)
			(island_removal_mode 0)
		)
		(polygon
			(pts
				(arc
					(start 122.236484 -386.170424)
					(mid 122.346455 -386.271478)
					(end 122.491246 -386.308092)
				)
				(arc
					(start 122.491246 -386.308092)
					(mid 122.706772 -386.218818)
					(end 122.796046 -386.003292)
				)
				(arc
					(start 122.796046 -386.003292)
					(mid 122.785709 -385.924553)
					(end 122.755406 -385.851146)
				)
				(arc
					(start 122.362976 -385.172204)
					(mid 122.250579 -385.050587)
					(end 122.091196 -385.00558)
				)
				(arc
					(start 122.091196 -385.00558)
					(mid 121.87567 -385.094854)
					(end 121.786396 -385.31038)
				)
				(arc
					(start 121.786396 -385.31038)
					(mid 121.795974 -385.386442)
					(end 121.824242 -385.4577)
				)
				(xy 122.221498 -386.145024) (xy 122.23369 -386.16636) (xy 122.23623 -386.170678)
			)
		)
	)
	(zone
		(layers "F.Cu" "B.Cu" "In1.Cu" "In2.Cu" "In3.Cu" "In4.Cu" "In5.Cu" "In6.Cu"
			"In7.Cu" "In8.Cu" "In9.Cu" "In10.Cu" "In11.Cu" "In12.Cu" "In13.Cu" "In14.Cu"
			"In15.Cu" "In16.Cu"
		)
		(hatch none 0.5)
		(connect_pads
			(clearance 0)
		)
		(min_thickness 0.25)
		(keepout
			(tracks not_allowed)
			(vias allowed)
			(pads allowed)
			(copperpour not_allowed)
			(footprints allowed)
		)
		(placement
			(enabled no)
			(sheetname "")
		)
		(fill
			(thermal_gap 0.5)
			(thermal_bridge_width 0.5)
			(island_removal_mode 0)
		)
		(polygon
			(pts
				(arc
					(start 139.129262 -369.343178)
					(mid 138.748262 -368.962178)
					(end 138.367262 -369.343178)
				)
				(arc
					(start 138.367262 -370.206778)
					(mid 138.748262 -370.587778)
					(end 139.129262 -370.206778)
				)
			)
		)
	)
	(zone
		(layers "F.Cu" "B.Cu" "In1.Cu" "In2.Cu" "In3.Cu" "In4.Cu" "In5.Cu" "In6.Cu"
			"In7.Cu" "In8.Cu" "In9.Cu" "In10.Cu" "In11.Cu" "In12.Cu" "In13.Cu" "In14.Cu"
			"In15.Cu" "In16.Cu"
		)
		(hatch none 0.5)
		(connect_pads
			(clearance 0)
		)
		(min_thickness 0.25)
		(keepout
			(tracks not_allowed)
			(vias allowed)
			(pads allowed)
			(copperpour not_allowed)
			(footprints allowed)
		)
		(placement
			(enabled no)
			(sheetname "")
		)
		(fill
			(thermal_gap 0.5)
			(thermal_bridge_width 0.5)
			(island_removal_mode 0)
		)
		(polygon
			(pts
				(arc
					(start 57.334658 -12.483846)
					(mid 56.953658 -12.864846)
					(end 57.334658 -13.245846)
				)
				(arc
					(start 58.198258 -13.245846)
					(mid 58.579258 -12.864846)
					(end 58.198258 -12.483846)
				)
			)
		)
	)
	(zone
		(layers "F.Cu" "B.Cu" "In1.Cu" "In2.Cu" "In3.Cu" "In4.Cu" "In5.Cu" "In6.Cu"
			"In7.Cu" "In8.Cu" "In9.Cu" "In10.Cu" "In11.Cu" "In12.Cu" "In13.Cu" "In14.Cu"
			"In15.Cu" "In16.Cu"
		)
		(hatch none 0.5)
		(connect_pads
			(clearance 0)
		)
		(min_thickness 0.25)
		(keepout
			(tracks not_allowed)
			(vias allowed)
			(pads allowed)
			(copperpour not_allowed)
			(footprints allowed)
		)
		(placement
			(enabled no)
			(sheetname "")
		)
		(fill
			(thermal_gap 0.5)
			(thermal_bridge_width 0.5)
			(island_removal_mode 0)
		)
		(polygon
			(pts
				(arc
					(start 346.679266 -420.571168)
					(mid 346.298266 -420.952168)
					(end 346.679266 -421.333168)
				)
				(arc
					(start 347.542866 -421.333168)
					(mid 347.923866 -420.952168)
					(end 347.542866 -420.571168)
				)
			)
		)
	)
	(zone
		(layers "F.Cu" "B.Cu" "In1.Cu" "In2.Cu" "In3.Cu" "In4.Cu" "In5.Cu" "In6.Cu"
			"In7.Cu" "In8.Cu" "In9.Cu" "In10.Cu" "In11.Cu" "In12.Cu" "In13.Cu" "In14.Cu"
			"In15.Cu" "In16.Cu"
		)
		(hatch none 0.5)
		(connect_pads
			(clearance 0)
		)
		(min_thickness 0.25)
		(keepout
			(tracks not_allowed)
			(vias allowed)
			(pads allowed)
			(copperpour not_allowed)
			(footprints allowed)
		)
		(placement
			(enabled no)
			(sheetname "")
		)
		(fill
			(thermal_gap 0.5)
			(thermal_bridge_width 0.5)
			(island_removal_mode 0)
		)
		(polygon
			(pts
				(arc
					(start 387.741922 -415.00552)
					(mid 387.360922 -415.38652)
					(end 387.741922 -415.76752)
				)
				(arc
					(start 388.605522 -415.76752)
					(mid 388.986522 -415.38652)
					(end 388.605522 -415.00552)
				)
			)
		)
	)
	(zone
		(layers "F.Cu" "B.Cu" "In1.Cu" "In2.Cu" "In3.Cu" "In4.Cu" "In5.Cu" "In6.Cu"
			"In7.Cu" "In8.Cu" "In9.Cu" "In10.Cu" "In11.Cu" "In12.Cu" "In13.Cu" "In14.Cu"
			"In15.Cu" "In16.Cu"
		)
		(hatch none 0.5)
		(connect_pads
			(clearance 0)
		)
		(min_thickness 0.25)
		(keepout
			(tracks not_allowed)
			(vias allowed)
			(pads allowed)
			(copperpour not_allowed)
			(footprints allowed)
		)
		(placement
			(enabled no)
			(sheetname "")
		)
		(fill yes
			(thermal_gap 0.5)
			(thermal_bridge_width 0.5)
			(island_removal_mode 0)
		)
		(polygon
			(pts
				(arc
					(start 389.03656 -394.552424)
					(mid 389.146531 -394.653478)
					(end 389.291322 -394.690092)
				)
				(arc
					(start 389.291322 -394.690092)
					(mid 389.506848 -394.600818)
					(end 389.596122 -394.385292)
				)
				(arc
					(start 389.596122 -394.385292)
					(mid 389.585785 -394.306553)
					(end 389.555482 -394.233146)
				)
				(arc
					(start 389.163052 -393.554204)
					(mid 389.050655 -393.432587)
					(end 388.891272 -393.38758)
				)
				(arc
					(start 388.891272 -393.38758)
					(mid 388.675746 -393.476854)
					(end 388.586472 -393.69238)
				)
				(arc
					(start 388.586472 -393.69238)
					(mid 388.59605 -393.768442)
					(end 388.624318 -393.8397)
				)
				(xy 389.021574 -394.527024) (xy 389.033766 -394.54836) (xy 389.036306 -394.552678)
			)
		)
	)
	(zone
		(layers "F.Cu" "B.Cu" "In1.Cu" "In2.Cu" "In3.Cu" "In4.Cu" "In5.Cu" "In6.Cu"
			"In7.Cu" "In8.Cu" "In9.Cu" "In10.Cu" "In11.Cu" "In12.Cu" "In13.Cu" "In14.Cu"
			"In15.Cu" "In16.Cu"
		)
		(hatch none 0.5)
		(connect_pads
			(clearance 0)
		)
		(min_thickness 0.25)
		(keepout
			(tracks not_allowed)
			(vias allowed)
			(pads allowed)
			(copperpour not_allowed)
			(footprints allowed)
		)
		(placement
			(enabled no)
			(sheetname "")
		)
		(fill
			(thermal_gap 0.5)
			(thermal_bridge_width 0.5)
			(island_removal_mode 0)
		)
		(polygon
			(pts
				(arc
					(start 24.420322 -4.582414)
					(mid 24.039322 -4.963414)
					(end 24.420322 -5.344414)
				)
				(arc
					(start 25.283922 -5.344414)
					(mid 25.664922 -4.963414)
					(end 25.283922 -4.582414)
				)
			)
		)
	)
	(zone
		(layers "F.Cu" "B.Cu" "In1.Cu" "In2.Cu" "In3.Cu" "In4.Cu" "In5.Cu" "In6.Cu"
			"In7.Cu" "In8.Cu" "In9.Cu" "In10.Cu" "In11.Cu" "In12.Cu" "In13.Cu" "In14.Cu"
			"In15.Cu" "In16.Cu"
		)
		(hatch none 0.5)
		(connect_pads
			(clearance 0)
		)
		(min_thickness 0.25)
		(keepout
			(tracks not_allowed)
			(vias allowed)
			(pads allowed)
			(copperpour not_allowed)
			(footprints allowed)
		)
		(placement
			(enabled no)
			(sheetname "")
		)
		(fill
			(thermal_gap 0.5)
			(thermal_bridge_width 0.5)
			(island_removal_mode 0)
		)
		(polygon
			(pts
				(arc
					(start 122.52452 -35.672268)
					(mid 122.14352 -36.053268)
					(end 122.52452 -36.434268)
				)
				(arc
					(start 123.38812 -36.434268)
					(mid 123.76912 -36.053268)
					(end 123.38812 -35.672268)
				)
			)
		)
	)
	(zone
		(layers "F.Cu" "B.Cu" "In1.Cu" "In2.Cu" "In3.Cu" "In4.Cu" "In5.Cu" "In6.Cu"
			"In7.Cu" "In8.Cu" "In9.Cu" "In10.Cu" "In11.Cu" "In12.Cu" "In13.Cu" "In14.Cu"
			"In15.Cu" "In16.Cu"
		)
		(hatch none 0.5)
		(connect_pads
			(clearance 0)
		)
		(min_thickness 0.25)
		(keepout
			(tracks not_allowed)
			(vias allowed)
			(pads allowed)
			(copperpour not_allowed)
			(footprints allowed)
		)
		(placement
			(enabled no)
			(sheetname "")
		)
		(fill
			(thermal_gap 0.5)
			(thermal_bridge_width 0.5)
			(island_removal_mode 0)
		)
		(polygon
			(pts
				(arc
					(start 50.857404 -412.189168)
					(mid 50.476404 -412.570168)
					(end 50.857404 -412.951168)
				)
				(arc
					(start 51.721004 -412.951168)
					(mid 52.102004 -412.570168)
					(end 51.721004 -412.189168)
				)
			)
		)
	)
	(zone
		(layers "F.Cu" "B.Cu" "In1.Cu" "In2.Cu" "In3.Cu" "In4.Cu" "In5.Cu" "In6.Cu"
			"In7.Cu" "In8.Cu" "In9.Cu" "In10.Cu" "In11.Cu" "In12.Cu" "In13.Cu" "In14.Cu"
			"In15.Cu" "In16.Cu"
		)
		(hatch none 0.5)
		(connect_pads
			(clearance 0)
		)
		(min_thickness 0.25)
		(keepout
			(tracks not_allowed)
			(vias allowed)
			(pads allowed)
			(copperpour not_allowed)
			(footprints allowed)
		)
		(placement
			(enabled no)
			(sheetname "")
		)
		(fill
			(thermal_gap 0.5)
			(thermal_bridge_width 0.5)
			(island_removal_mode 0)
		)
		(polygon
			(pts
				(arc
					(start 351.964244 -379.50013)
					(mid 351.583244 -379.88113)
					(end 351.964244 -380.26213)
				)
				(arc
					(start 352.827844 -380.26213)
					(mid 353.208844 -379.88113)
					(end 352.827844 -379.50013)
				)
			)
		)
	)
	(zone
		(layers "F.Cu" "B.Cu" "In1.Cu" "In2.Cu" "In3.Cu" "In4.Cu" "In5.Cu" "In6.Cu"
			"In7.Cu" "In8.Cu" "In9.Cu" "In10.Cu" "In11.Cu" "In12.Cu" "In13.Cu" "In14.Cu"
			"In15.Cu" "In16.Cu"
		)
		(hatch none 0.5)
		(connect_pads
			(clearance 0)
		)
		(min_thickness 0.25)
		(keepout
			(tracks not_allowed)
			(vias allowed)
			(pads allowed)
			(copperpour not_allowed)
			(footprints allowed)
		)
		(placement
			(enabled no)
			(sheetname "")
		)
		(fill
			(thermal_gap 0.5)
			(thermal_bridge_width 0.5)
			(island_removal_mode 0)
		)
		(polygon
			(pts
				(arc
					(start 385.436364 -398.016476)
					(mid 385.546335 -398.11753)
					(end 385.691126 -398.154144)
				)
				(arc
					(start 385.691126 -398.154144)
					(mid 385.906652 -398.06487)
					(end 385.995926 -397.849344)
				)
				(arc
					(start 385.995926 -397.849344)
					(mid 385.985589 -397.770605)
					(end 385.955286 -397.697198)
				)
				(arc
					(start 385.562856 -397.018256)
					(mid 385.450459 -396.896639)
					(end 385.291076 -396.851632)
				)
				(arc
					(start 385.291076 -396.851632)
					(mid 385.07555 -396.940906)
					(end 384.986276 -397.156432)
				)
				(arc
					(start 384.986276 -397.156432)
					(mid 384.995854 -397.232494)
					(end 385.024122 -397.303752)
				)
				(xy 385.421378 -397.991076) (xy 385.43357 -398.012412) (xy 385.43611 -398.01673)
			)
		)
	)
	(zone
		(layers "F.Cu" "B.Cu" "In1.Cu" "In2.Cu" "In3.Cu" "In4.Cu" "In5.Cu" "In6.Cu"
			"In7.Cu" "In8.Cu" "In9.Cu" "In10.Cu" "In11.Cu" "In12.Cu" "In13.Cu" "In14.Cu"
			"In15.Cu" "In16.Cu"
		)
		(hatch none 0.5)
		(connect_pads
			(clearance 0)
		)
		(min_thickness 0.25)
		(keepout
			(tracks not_allowed)
			(vias allowed)
			(pads allowed)
			(copperpour not_allowed)
			(footprints allowed)
		)
		(placement
			(enabled no)
			(sheetname "")
		)
		(fill
			(thermal_gap 0.5)
			(thermal_bridge_width 0.5)
			(island_removal_mode 0)
		)
		(polygon
			(pts
				(arc
					(start 413.779462 -420.571168)
					(mid 413.398462 -420.952168)
					(end 413.779462 -421.333168)
				)
				(arc
					(start 414.643062 -421.333168)
					(mid 415.024062 -420.952168)
					(end 414.643062 -420.571168)
				)
			)
		)
	)
	(zone
		(layers "F.Cu" "B.Cu" "In1.Cu" "In2.Cu" "In3.Cu" "In4.Cu" "In5.Cu" "In6.Cu"
			"In7.Cu" "In8.Cu" "In9.Cu" "In10.Cu" "In11.Cu" "In12.Cu" "In13.Cu" "In14.Cu"
			"In15.Cu" "In16.Cu"
		)
		(hatch none 0.5)
		(connect_pads
			(clearance 0)
		)
		(min_thickness 0.25)
		(keepout
			(tracks not_allowed)
			(vias allowed)
			(pads allowed)
			(copperpour not_allowed)
			(footprints allowed)
		)
		(placement
			(enabled no)
			(sheetname "")
		)
		(fill
			(thermal_gap 0.5)
			(thermal_bridge_width 0.5)
			(island_removal_mode 0)
		)
		(polygon
			(pts
				(arc
					(start 317.136272 -394.552424)
					(mid 317.246243 -394.653478)
					(end 317.391034 -394.690092)
				)
				(arc
					(start 317.391034 -394.690092)
					(mid 317.60656 -394.600818)
					(end 317.695834 -394.385292)
				)
				(arc
					(start 317.695834 -394.385292)
					(mid 317.685497 -394.306553)
					(end 317.655194 -394.233146)
				)
				(arc
					(start 317.262764 -393.554204)
					(mid 317.150367 -393.432587)
					(end 316.990984 -393.38758)
				)
				(arc
					(start 316.990984 -393.38758)
					(mid 316.775458 -393.476854)
					(end 316.686184 -393.69238)
				)
				(arc
					(start 316.686184 -393.69238)
					(mid 316.695762 -393.768442)
					(end 316.72403 -393.8397)
				)
				(xy 317.121286 -394.527024) (xy 317.133478 -394.54836) (xy 317.136018 -394.552678)
			)
		)
	)
	(zone
		(layers "F.Cu" "B.Cu" "In1.Cu" "In2.Cu" "In3.Cu" "In4.Cu" "In5.Cu" "In6.Cu"
			"In7.Cu" "In8.Cu" "In9.Cu" "In10.Cu" "In11.Cu" "In12.Cu" "In13.Cu" "In14.Cu"
			"In15.Cu" "In16.Cu"
		)
		(hatch none 0.5)
		(connect_pads
			(clearance 0)
		)
		(min_thickness 0.25)
		(keepout
			(tracks not_allowed)
			(vias allowed)
			(pads allowed)
			(copperpour not_allowed)
			(footprints allowed)
		)
		(placement
			(enabled no)
			(sheetname "")
		)
		(fill
			(thermal_gap 0.5)
			(thermal_bridge_width 0.5)
			(island_removal_mode 0)
		)
		(polygon
			(pts
				(arc
					(start 84.553044 -404.08352)
					(mid 84.172044 -404.46452)
					(end 84.553044 -404.84552)
				)
				(arc
					(start 85.416644 -404.84552)
					(mid 85.797644 -404.46452)
					(end 85.416644 -404.08352)
				)
			)
		)
	)
	(zone
		(layers "F.Cu" "B.Cu" "In1.Cu" "In2.Cu" "In3.Cu" "In4.Cu" "In5.Cu" "In6.Cu"
			"In7.Cu" "In8.Cu" "In9.Cu" "In10.Cu" "In11.Cu" "In12.Cu" "In13.Cu" "In14.Cu"
			"In15.Cu" "In16.Cu"
		)
		(hatch none 0.5)
		(connect_pads
			(clearance 0)
		)
		(min_thickness 0.25)
		(keepout
			(tracks not_allowed)
			(vias allowed)
			(pads allowed)
			(copperpour not_allowed)
			(footprints allowed)
		)
		(placement
			(enabled no)
			(sheetname "")
		)
		(fill
			(thermal_gap 0.5)
			(thermal_bridge_width 0.5)
			(island_removal_mode 0)
		)
		(polygon
			(pts
				(arc
					(start 10.205466 -425.887642)
					(mid 10.586466 -426.268642)
					(end 10.967466 -425.887642)
				)
				(arc
					(start 10.967466 -425.024042)
					(mid 10.586466 -424.643042)
					(end 10.205466 -425.024042)
				)
			)
		)
	)
	(zone
		(layers "F.Cu" "B.Cu" "In1.Cu" "In2.Cu" "In3.Cu" "In4.Cu" "In5.Cu" "In6.Cu"
			"In7.Cu" "In8.Cu" "In9.Cu" "In10.Cu" "In11.Cu" "In12.Cu" "In13.Cu" "In14.Cu"
			"In15.Cu" "In16.Cu"
		)
		(hatch none 0.5)
		(connect_pads
			(clearance 0)
		)
		(min_thickness 0.25)
		(keepout
			(tracks not_allowed)
			(vias allowed)
			(pads allowed)
			(copperpour not_allowed)
			(footprints allowed)
		)
		(placement
			(enabled no)
			(sheetname "")
		)
		(fill
			(thermal_gap 0.5)
			(thermal_bridge_width 0.5)
			(island_removal_mode 0)
		)
		(polygon
			(pts
				(arc
					(start 127.297688 -392.429238)
					(mid 126.916688 -392.048238)
					(end 126.535688 -392.429238)
				)
				(arc
					(start 126.535688 -393.292838)
					(mid 126.916688 -393.673838)
					(end 127.297688 -393.292838)
				)
			)
		)
	)
	(zone
		(layers "F.Cu" "B.Cu" "In1.Cu" "In2.Cu" "In3.Cu" "In4.Cu" "In5.Cu" "In6.Cu"
			"In7.Cu" "In8.Cu" "In9.Cu" "In10.Cu" "In11.Cu" "In12.Cu" "In13.Cu" "In14.Cu"
			"In15.Cu" "In16.Cu"
		)
		(hatch none 0.5)
		(connect_pads
			(clearance 0)
		)
		(min_thickness 0.25)
		(keepout
			(tracks not_allowed)
			(vias allowed)
			(pads allowed)
			(copperpour not_allowed)
			(footprints allowed)
		)
		(placement
			(enabled no)
			(sheetname "")
		)
		(fill
			(thermal_gap 0.5)
			(thermal_bridge_width 0.5)
			(island_removal_mode 0)
		)
		(polygon
			(pts
				(arc
					(start 372.425722 -418.031168)
					(mid 372.044722 -418.412168)
					(end 372.425722 -418.793168)
				)
				(arc
					(start 373.289322 -418.793168)
					(mid 373.670322 -418.412168)
					(end 373.289322 -418.031168)
				)
			)
		)
	)
	(zone
		(layers "F.Cu" "B.Cu" "In1.Cu" "In2.Cu" "In3.Cu" "In4.Cu" "In5.Cu" "In6.Cu"
			"In7.Cu" "In8.Cu" "In9.Cu" "In10.Cu" "In11.Cu" "In12.Cu" "In13.Cu" "In14.Cu"
			"In15.Cu" "In16.Cu"
		)
		(hatch none 0.5)
		(connect_pads
			(clearance 0)
		)
		(min_thickness 0.25)
		(keepout
			(tracks not_allowed)
			(vias allowed)
			(pads allowed)
			(copperpour not_allowed)
			(footprints allowed)
		)
		(placement
			(enabled no)
			(sheetname "")
		)
		(fill
			(thermal_gap 0.5)
			(thermal_bridge_width 0.5)
			(island_removal_mode 0)
		)
		(polygon
			(pts
				(arc
					(start 317.397384 -400.811238)
					(mid 317.016384 -400.430238)
					(end 316.635384 -400.811238)
				)
				(arc
					(start 316.635384 -401.674838)
					(mid 317.016384 -402.055838)
					(end 317.397384 -401.674838)
				)
			)
		)
	)
	(zone
		(layers "F.Cu" "B.Cu" "In1.Cu" "In2.Cu" "In3.Cu" "In4.Cu" "In5.Cu" "In6.Cu"
			"In7.Cu" "In8.Cu" "In9.Cu" "In10.Cu" "In11.Cu" "In12.Cu" "In13.Cu" "In14.Cu"
			"In15.Cu" "In16.Cu"
		)
		(hatch none 0.5)
		(connect_pads
			(clearance 0)
		)
		(min_thickness 0.25)
		(keepout
			(tracks not_allowed)
			(vias allowed)
			(pads allowed)
			(copperpour not_allowed)
			(footprints allowed)
		)
		(placement
			(enabled no)
			(sheetname "")
		)
		(fill
			(thermal_gap 0.5)
			(thermal_bridge_width 0.5)
			(island_removal_mode 0)
		)
		(polygon
			(pts
				(arc
					(start 412.225236 -400.811238)
					(mid 411.844236 -400.430238)
					(end 411.463236 -400.811238)
				)
				(arc
					(start 411.463236 -401.674838)
					(mid 411.844236 -402.055838)
					(end 412.225236 -401.674838)
				)
			)
		)
	)
	(zone
		(layers "F.Cu" "B.Cu" "In1.Cu" "In2.Cu" "In3.Cu" "In4.Cu" "In5.Cu" "In6.Cu"
			"In7.Cu" "In8.Cu" "In9.Cu" "In10.Cu" "In11.Cu" "In12.Cu" "In13.Cu" "In14.Cu"
			"In15.Cu" "In16.Cu"
		)
		(hatch none 0.5)
		(connect_pads
			(clearance 0)
		)
		(min_thickness 0.25)
		(keepout
			(tracks not_allowed)
			(vias allowed)
			(pads allowed)
			(copperpour not_allowed)
			(footprints allowed)
		)
		(placement
			(enabled no)
			(sheetname "")
		)
		(fill
			(thermal_gap 0.5)
			(thermal_bridge_width 0.5)
			(island_removal_mode 0)
		)
		(polygon
			(pts
				(arc
					(start 375.488962 -415.00552)
					(mid 375.107962 -415.38652)
					(end 375.488962 -415.76752)
				)
				(arc
					(start 376.352562 -415.76752)
					(mid 376.733562 -415.38652)
					(end 376.352562 -415.00552)
				)
			)
		)
	)
	(zone
		(layers "F.Cu" "B.Cu" "In1.Cu" "In2.Cu" "In3.Cu" "In4.Cu" "In5.Cu" "In6.Cu"
			"In7.Cu" "In8.Cu" "In9.Cu" "In10.Cu" "In11.Cu" "In12.Cu" "In13.Cu" "In14.Cu"
			"In15.Cu" "In16.Cu"
		)
		(hatch none 0.5)
		(connect_pads
			(clearance 0)
		)
		(min_thickness 0.25)
		(keepout
			(tracks not_allowed)
			(vias allowed)
			(pads allowed)
			(copperpour not_allowed)
			(footprints allowed)
		)
		(placement
			(enabled no)
			(sheetname "")
		)
		(fill
			(thermal_gap 0.5)
			(thermal_bridge_width 0.5)
			(island_removal_mode 0)
		)
		(polygon
			(pts
				(arc
					(start 95.125286 -392.429238)
					(mid 94.744286 -392.048238)
					(end 94.363286 -392.429238)
				)
				(arc
					(start 94.363286 -393.292838)
					(mid 94.744286 -393.673838)
					(end 95.125286 -393.292838)
				)
			)
		)
	)
	(zone
		(layers "F.Cu" "B.Cu" "In1.Cu" "In2.Cu" "In3.Cu" "In4.Cu" "In5.Cu" "In6.Cu"
			"In7.Cu" "In8.Cu" "In9.Cu" "In10.Cu" "In11.Cu" "In12.Cu" "In13.Cu" "In14.Cu"
			"In15.Cu" "In16.Cu"
		)
		(hatch none 0.5)
		(connect_pads
			(clearance 0)
		)
		(min_thickness 0.25)
		(keepout
			(tracks not_allowed)
			(vias allowed)
			(pads allowed)
			(copperpour not_allowed)
			(footprints allowed)
		)
		(placement
			(enabled no)
			(sheetname "")
		)
		(fill
			(thermal_gap 0.5)
			(thermal_bridge_width 0.5)
			(island_removal_mode 0)
		)
		(polygon
			(pts
				(arc
					(start 126.097538 -392.429238)
					(mid 125.716538 -392.048238)
					(end 125.335538 -392.429238)
				)
				(arc
					(start 125.335538 -393.292838)
					(mid 125.716538 -393.673838)
					(end 126.097538 -393.292838)
				)
			)
		)
	)
	(zone
		(layers "F.Cu" "B.Cu" "In1.Cu" "In2.Cu" "In3.Cu" "In4.Cu" "In5.Cu" "In6.Cu"
			"In7.Cu" "In8.Cu" "In9.Cu" "In10.Cu" "In11.Cu" "In12.Cu" "In13.Cu" "In14.Cu"
			"In15.Cu" "In16.Cu"
		)
		(hatch none 0.5)
		(connect_pads
			(clearance 0)
		)
		(min_thickness 0.25)
		(keepout
			(tracks not_allowed)
			(vias allowed)
			(pads allowed)
			(copperpour not_allowed)
			(footprints allowed)
		)
		(placement
			(enabled no)
			(sheetname "")
		)
		(fill
			(thermal_gap 0.5)
			(thermal_bridge_width 0.5)
			(island_removal_mode 0)
		)
		(polygon
			(pts
				(arc
					(start 54.197504 -392.429238)
					(mid 53.816504 -392.048238)
					(end 53.435504 -392.429238)
				)
				(arc
					(start 53.435504 -393.292838)
					(mid 53.816504 -393.673838)
					(end 54.197504 -393.292838)
				)
			)
		)
	)
	(zone
		(layers "F.Cu" "B.Cu" "In1.Cu" "In2.Cu" "In3.Cu" "In4.Cu" "In5.Cu" "In6.Cu"
			"In7.Cu" "In8.Cu" "In9.Cu" "In10.Cu" "In11.Cu" "In12.Cu" "In13.Cu" "In14.Cu"
			"In15.Cu" "In16.Cu"
		)
		(hatch none 0.5)
		(connect_pads
			(clearance 0)
		)
		(min_thickness 0.25)
		(keepout
			(tracks not_allowed)
			(vias allowed)
			(pads allowed)
			(copperpour not_allowed)
			(footprints allowed)
		)
		(placement
			(enabled no)
			(sheetname "")
		)
		(fill yes
			(thermal_gap 0.5)
			(thermal_bridge_width 0.5)
			(island_removal_mode 0)
		)
		(polygon
			(pts
				(arc
					(start 313.53633 -394.552424)
					(mid 313.646301 -394.653478)
					(end 313.791092 -394.690092)
				)
				(arc
					(start 313.791092 -394.690092)
					(mid 314.006618 -394.600818)
					(end 314.095892 -394.385292)
				)
				(arc
					(start 314.095892 -394.385292)
					(mid 314.085555 -394.306553)
					(end 314.055252 -394.233146)
				)
				(arc
					(start 313.662822 -393.554204)
					(mid 313.550425 -393.432587)
					(end 313.391042 -393.38758)
				)
				(arc
					(start 313.391042 -393.38758)
					(mid 313.175516 -393.476854)
					(end 313.086242 -393.69238)
				)
				(arc
					(start 313.086242 -393.69238)
					(mid 313.09582 -393.768442)
					(end 313.124088 -393.8397)
				)
				(xy 313.521344 -394.527024) (xy 313.533536 -394.54836) (xy 313.536076 -394.552678)
			)
		)
	)
	(zone
		(layers "F.Cu" "B.Cu" "In1.Cu" "In2.Cu" "In3.Cu" "In4.Cu" "In5.Cu" "In6.Cu"
			"In7.Cu" "In8.Cu" "In9.Cu" "In10.Cu" "In11.Cu" "In12.Cu" "In13.Cu" "In14.Cu"
			"In15.Cu" "In16.Cu"
		)
		(hatch none 0.5)
		(connect_pads
			(clearance 0)
		)
		(min_thickness 0.25)
		(keepout
			(tracks not_allowed)
			(vias allowed)
			(pads allowed)
			(copperpour not_allowed)
			(footprints allowed)
		)
		(placement
			(enabled no)
			(sheetname "")
		)
		(fill
			(thermal_gap 0.5)
			(thermal_bridge_width 0.5)
			(island_removal_mode 0)
		)
		(polygon
			(pts
				(arc
					(start 409.184602 -418.031168)
					(mid 408.803602 -418.412168)
					(end 409.184602 -418.793168)
				)
				(arc
					(start 410.048202 -418.793168)
					(mid 410.429202 -418.412168)
					(end 410.048202 -418.031168)
				)
			)
		)
	)
	(zone
		(layers "F.Cu" "B.Cu" "In1.Cu" "In2.Cu" "In3.Cu" "In4.Cu" "In5.Cu" "In6.Cu"
			"In7.Cu" "In8.Cu" "In9.Cu" "In10.Cu" "In11.Cu" "In12.Cu" "In13.Cu" "In14.Cu"
			"In15.Cu" "In16.Cu"
		)
		(hatch none 0.5)
		(connect_pads
			(clearance 0)
		)
		(min_thickness 0.25)
		(keepout
			(tracks not_allowed)
			(vias allowed)
			(pads allowed)
			(copperpour not_allowed)
			(footprints allowed)
		)
		(placement
			(enabled no)
			(sheetname "")
		)
		(fill
			(thermal_gap 0.5)
			(thermal_bridge_width 0.5)
			(island_removal_mode 0)
		)
		(polygon
			(pts
				(arc
					(start 331.363066 -420.571168)
					(mid 330.982066 -420.952168)
					(end 331.363066 -421.333168)
				)
				(arc
					(start 332.226666 -421.333168)
					(mid 332.607666 -420.952168)
					(end 332.226666 -420.571168)
				)
			)
		)
	)
	(zone
		(layers "F.Cu" "B.Cu" "In1.Cu" "In2.Cu" "In3.Cu" "In4.Cu" "In5.Cu" "In6.Cu"
			"In7.Cu" "In8.Cu" "In9.Cu" "In10.Cu" "In11.Cu" "In12.Cu" "In13.Cu" "In14.Cu"
			"In15.Cu" "In16.Cu"
		)
		(hatch none 0.5)
		(connect_pads
			(clearance 0)
		)
		(min_thickness 0.25)
		(keepout
			(tracks not_allowed)
			(vias allowed)
			(pads allowed)
			(copperpour not_allowed)
			(footprints allowed)
		)
		(placement
			(enabled no)
			(sheetname "")
		)
		(fill yes
			(thermal_gap 0.5)
			(thermal_bridge_width 0.5)
			(island_removal_mode 0)
		)
		(polygon
			(pts
				(arc
					(start 342.464136 -394.552424)
					(mid 342.574107 -394.653478)
					(end 342.718898 -394.690092)
				)
				(arc
					(start 342.718898 -394.690092)
					(mid 342.934424 -394.600818)
					(end 343.023698 -394.385292)
				)
				(arc
					(start 343.023698 -394.385292)
					(mid 343.013361 -394.306553)
					(end 342.983058 -394.233146)
				)
				(arc
					(start 342.590628 -393.554204)
					(mid 342.478231 -393.432587)
					(end 342.318848 -393.38758)
				)
				(arc
					(start 342.318848 -393.38758)
					(mid 342.103322 -393.476854)
					(end 342.014048 -393.69238)
				)
				(arc
					(start 342.014048 -393.69238)
					(mid 342.023626 -393.768442)
					(end 342.051894 -393.8397)
				)
				(xy 342.44915 -394.527024) (xy 342.461342 -394.54836) (xy 342.463882 -394.552678)
			)
		)
	)
	(zone
		(layers "F.Cu" "B.Cu" "In1.Cu" "In2.Cu" "In3.Cu" "In4.Cu" "In5.Cu" "In6.Cu"
			"In7.Cu" "In8.Cu" "In9.Cu" "In10.Cu" "In11.Cu" "In12.Cu" "In13.Cu" "In14.Cu"
			"In15.Cu" "In16.Cu"
		)
		(hatch none 0.5)
		(connect_pads
			(clearance 0)
		)
		(min_thickness 0.25)
		(keepout
			(tracks not_allowed)
			(vias allowed)
			(pads allowed)
			(copperpour not_allowed)
			(footprints allowed)
		)
		(placement
			(enabled no)
			(sheetname "")
		)
		(fill
			(thermal_gap 0.5)
			(thermal_bridge_width 0.5)
			(island_removal_mode 0)
		)
		(polygon
			(pts
				(arc
					(start 384.834892 -381.96393)
					(mid 384.453892 -382.34493)
					(end 384.834892 -382.72593)
				)
				(arc
					(start 385.698492 -382.72593)
					(mid 386.079492 -382.34493)
					(end 385.698492 -381.96393)
				)
			)
		)
	)
	(zone
		(layers "F.Cu" "B.Cu" "In1.Cu" "In2.Cu" "In3.Cu" "In4.Cu" "In5.Cu" "In6.Cu"
			"In7.Cu" "In8.Cu" "In9.Cu" "In10.Cu" "In11.Cu" "In12.Cu" "In13.Cu" "In14.Cu"
			"In15.Cu" "In16.Cu"
		)
		(hatch none 0.5)
		(connect_pads
			(clearance 0)
		)
		(min_thickness 0.25)
		(keepout
			(tracks not_allowed)
			(vias allowed)
			(pads allowed)
			(copperpour not_allowed)
			(footprints allowed)
		)
		(placement
			(enabled no)
			(sheetname "")
		)
		(fill
			(thermal_gap 0.5)
			(thermal_bridge_width 0.5)
			(island_removal_mode 0)
		)
		(polygon
			(pts
				(arc
					(start 420.364158 -398.016476)
					(mid 420.474129 -398.11753)
					(end 420.61892 -398.154144)
				)
				(arc
					(start 420.61892 -398.154144)
					(mid 420.834446 -398.06487)
					(end 420.92372 -397.849344)
				)
				(arc
					(start 420.92372 -397.849344)
					(mid 420.913383 -397.770605)
					(end 420.88308 -397.697198)
				)
				(arc
					(start 420.49065 -397.018256)
					(mid 420.378253 -396.896639)
					(end 420.21887 -396.851632)
				)
				(arc
					(start 420.21887 -396.851632)
					(mid 420.003344 -396.940906)
					(end 419.91407 -397.156432)
				)
				(arc
					(start 419.91407 -397.156432)
					(mid 419.923648 -397.232494)
					(end 419.951916 -397.303752)
				)
				(xy 420.349172 -397.991076) (xy 420.361364 -398.012412) (xy 420.363904 -398.01673)
			)
		)
	)
	(zone
		(layers "F.Cu" "B.Cu" "In1.Cu" "In2.Cu" "In3.Cu" "In4.Cu" "In5.Cu" "In6.Cu"
			"In7.Cu" "In8.Cu" "In9.Cu" "In10.Cu" "In11.Cu" "In12.Cu" "In13.Cu" "In14.Cu"
			"In15.Cu" "In16.Cu"
		)
		(hatch none 0.5)
		(connect_pads
			(clearance 0)
		)
		(min_thickness 0.25)
		(keepout
			(tracks not_allowed)
			(vias allowed)
			(pads allowed)
			(copperpour not_allowed)
			(footprints allowed)
		)
		(placement
			(enabled no)
			(sheetname "")
		)
		(fill
			(thermal_gap 0.5)
			(thermal_bridge_width 0.5)
			(island_removal_mode 0)
		)
		(polygon
			(pts
				(arc
					(start 120.09755 -392.429238)
					(mid 119.71655 -392.048238)
					(end 119.33555 -392.429238)
				)
				(arc
					(start 119.33555 -393.292838)
					(mid 119.71655 -393.673838)
					(end 120.09755 -393.292838)
				)
			)
		)
	)
	(zone
		(layers "F.Cu" "B.Cu" "In1.Cu" "In2.Cu" "In3.Cu" "In4.Cu" "In5.Cu" "In6.Cu"
			"In7.Cu" "In8.Cu" "In9.Cu" "In10.Cu" "In11.Cu" "In12.Cu" "In13.Cu" "In14.Cu"
			"In15.Cu" "In16.Cu"
		)
		(hatch none 0.5)
		(connect_pads
			(clearance 0)
		)
		(min_thickness 0.25)
		(keepout
			(tracks not_allowed)
			(vias allowed)
			(pads allowed)
			(copperpour not_allowed)
			(footprints allowed)
		)
		(placement
			(enabled no)
			(sheetname "")
		)
		(fill yes
			(thermal_gap 0.5)
			(thermal_bridge_width 0.5)
			(island_removal_mode 0)
		)
		(polygon
			(pts
				(arc
					(start 409.564332 -394.552424)
					(mid 409.674303 -394.653478)
					(end 409.819094 -394.690092)
				)
				(arc
					(start 409.819094 -394.690092)
					(mid 410.03462 -394.600818)
					(end 410.123894 -394.385292)
				)
				(arc
					(start 410.123894 -394.385292)
					(mid 410.113557 -394.306553)
					(end 410.083254 -394.233146)
				)
				(arc
					(start 409.690824 -393.554204)
					(mid 409.578427 -393.432587)
					(end 409.419044 -393.38758)
				)
				(arc
					(start 409.419044 -393.38758)
					(mid 409.203518 -393.476854)
					(end 409.114244 -393.69238)
				)
				(arc
					(start 409.114244 -393.69238)
					(mid 409.123822 -393.768442)
					(end 409.15209 -393.8397)
				)
				(xy 409.549346 -394.527024) (xy 409.561538 -394.54836) (xy 409.564078 -394.552678)
			)
		)
	)
	(zone
		(layers "F.Cu" "B.Cu" "In1.Cu" "In2.Cu" "In3.Cu" "In4.Cu" "In5.Cu" "In6.Cu"
			"In7.Cu" "In8.Cu" "In9.Cu" "In10.Cu" "In11.Cu" "In12.Cu" "In13.Cu" "In14.Cu"
			"In15.Cu" "In16.Cu"
		)
		(hatch none 0.5)
		(connect_pads
			(clearance 0)
		)
		(min_thickness 0.25)
		(keepout
			(tracks not_allowed)
			(vias allowed)
			(pads allowed)
			(copperpour not_allowed)
			(footprints allowed)
		)
		(placement
			(enabled no)
			(sheetname "")
		)
		(fill
			(thermal_gap 0.5)
			(thermal_bridge_width 0.5)
			(island_removal_mode 0)
		)
		(polygon
			(pts
				(arc
					(start 349.742506 -420.571168)
					(mid 349.361506 -420.952168)
					(end 349.742506 -421.333168)
				)
				(arc
					(start 350.606106 -421.333168)
					(mid 350.987106 -420.952168)
					(end 350.606106 -420.571168)
				)
			)
		)
	)
	(zone
		(layers "F.Cu" "B.Cu" "In1.Cu" "In2.Cu" "In3.Cu" "In4.Cu" "In5.Cu" "In6.Cu"
			"In7.Cu" "In8.Cu" "In9.Cu" "In10.Cu" "In11.Cu" "In12.Cu" "In13.Cu" "In14.Cu"
			"In15.Cu" "In16.Cu"
		)
		(hatch none 0.5)
		(connect_pads
			(clearance 0)
		)
		(min_thickness 0.25)
		(keepout
			(tracks not_allowed)
			(vias allowed)
			(pads allowed)
			(copperpour not_allowed)
			(footprints allowed)
		)
		(placement
			(enabled no)
			(sheetname "")
		)
		(fill
			(thermal_gap 0.5)
			(thermal_bridge_width 0.5)
			(island_removal_mode 0)
		)
		(polygon
			(pts
				(arc
					(start 393.515596 -6.344158)
					(mid 393.134596 -6.725158)
					(end 393.515596 -7.106158)
				)
				(arc
					(start 394.379196 -7.106158)
					(mid 394.760196 -6.725158)
					(end 394.379196 -6.344158)
				)
			)
		)
	)
	(zone
		(layers "F.Cu" "B.Cu" "In1.Cu" "In2.Cu" "In3.Cu" "In4.Cu" "In5.Cu" "In6.Cu"
			"In7.Cu" "In8.Cu" "In9.Cu" "In10.Cu" "In11.Cu" "In12.Cu" "In13.Cu" "In14.Cu"
			"In15.Cu" "In16.Cu"
		)
		(hatch none 0.5)
		(connect_pads
			(clearance 0)
		)
		(min_thickness 0.25)
		(keepout
			(tracks not_allowed)
			(vias allowed)
			(pads allowed)
			(copperpour not_allowed)
			(footprints allowed)
		)
		(placement
			(enabled no)
			(sheetname "")
		)
		(fill
			(thermal_gap 0.5)
			(thermal_bridge_width 0.5)
			(island_removal_mode 0)
		)
		(polygon
			(pts
				(arc
					(start 117.957346 -404.08352)
					(mid 117.576346 -404.46452)
					(end 117.957346 -404.84552)
				)
				(arc
					(start 118.820946 -404.84552)
					(mid 119.201946 -404.46452)
					(end 118.820946 -404.08352)
				)
			)
		)
	)
	(zone
		(layers "F.Cu" "B.Cu" "In1.Cu" "In2.Cu" "In3.Cu" "In4.Cu" "In5.Cu" "In6.Cu"
			"In7.Cu" "In8.Cu" "In9.Cu" "In10.Cu" "In11.Cu" "In12.Cu" "In13.Cu" "In14.Cu"
			"In15.Cu" "In16.Cu"
		)
		(hatch none 0.5)
		(connect_pads
			(clearance 0)
		)
		(min_thickness 0.25)
		(keepout
			(tracks not_allowed)
			(vias allowed)
			(pads allowed)
			(copperpour not_allowed)
			(footprints allowed)
		)
		(placement
			(enabled no)
			(sheetname "")
		)
		(fill
			(thermal_gap 0.5)
			(thermal_bridge_width 0.5)
			(island_removal_mode 0)
		)
		(polygon
			(pts
				(arc
					(start 95.274384 -409.649168)
					(mid 94.893384 -410.030168)
					(end 95.274384 -410.411168)
				)
				(arc
					(start 96.137984 -410.411168)
					(mid 96.518984 -410.030168)
					(end 96.137984 -409.649168)
				)
			)
		)
	)
	(zone
		(layers "F.Cu" "B.Cu" "In1.Cu" "In2.Cu" "In3.Cu" "In4.Cu" "In5.Cu" "In6.Cu"
			"In7.Cu" "In8.Cu" "In9.Cu" "In10.Cu" "In11.Cu" "In12.Cu" "In13.Cu" "In14.Cu"
			"In15.Cu" "In16.Cu"
		)
		(hatch none 0.5)
		(connect_pads
			(clearance 0)
		)
		(min_thickness 0.25)
		(keepout
			(tracks not_allowed)
			(vias allowed)
			(pads allowed)
			(copperpour not_allowed)
			(footprints allowed)
		)
		(placement
			(enabled no)
			(sheetname "")
		)
		(fill
			(thermal_gap 0.5)
			(thermal_bridge_width 0.5)
			(island_removal_mode 0)
		)
		(polygon
			(pts
				(arc
					(start 135.55218 -29.24302)
					(mid 135.93318 -29.62402)
					(end 136.31418 -29.24302)
				)
				(arc
					(start 136.31418 -28.25242)
					(mid 135.93318 -27.87142)
					(end 135.55218 -28.25242)
				)
			)
		)
	)
	(zone
		(layers "F.Cu" "B.Cu" "In1.Cu" "In2.Cu" "In3.Cu" "In4.Cu" "In5.Cu" "In6.Cu"
			"In7.Cu" "In8.Cu" "In9.Cu" "In10.Cu" "In11.Cu" "In12.Cu" "In13.Cu" "In14.Cu"
			"In15.Cu" "In16.Cu"
		)
		(hatch none 0.5)
		(connect_pads
			(clearance 0)
		)
		(min_thickness 0.25)
		(keepout
			(tracks not_allowed)
			(vias allowed)
			(pads allowed)
			(copperpour not_allowed)
			(footprints allowed)
		)
		(placement
			(enabled no)
			(sheetname "")
		)
		(fill yes
			(thermal_gap 0.5)
			(thermal_bridge_width 0.5)
			(island_removal_mode 0)
		)
		(polygon
			(pts
				(arc
					(start 311.136284 -394.552424)
					(mid 311.246255 -394.653478)
					(end 311.391046 -394.690092)
				)
				(arc
					(start 311.391046 -394.690092)
					(mid 311.606572 -394.600818)
					(end 311.695846 -394.385292)
				)
				(arc
					(start 311.695846 -394.385292)
					(mid 311.685509 -394.306553)
					(end 311.655206 -394.233146)
				)
				(arc
					(start 311.262776 -393.554204)
					(mid 311.150379 -393.432587)
					(end 310.990996 -393.38758)
				)
				(arc
					(start 310.990996 -393.38758)
					(mid 310.77547 -393.476854)
					(end 310.686196 -393.69238)
				)
				(arc
					(start 310.686196 -393.69238)
					(mid 310.695774 -393.768442)
					(end 310.724042 -393.8397)
				)
				(xy 311.121298 -394.527024) (xy 311.13349 -394.54836) (xy 311.13603 -394.552678)
			)
		)
	)
	(zone
		(layers "F.Cu" "B.Cu" "In1.Cu" "In2.Cu" "In3.Cu" "In4.Cu" "In5.Cu" "In6.Cu"
			"In7.Cu" "In8.Cu" "In9.Cu" "In10.Cu" "In11.Cu" "In12.Cu" "In13.Cu" "In14.Cu"
			"In15.Cu" "In16.Cu"
		)
		(hatch none 0.5)
		(connect_pads
			(clearance 0)
		)
		(min_thickness 0.25)
		(keepout
			(tracks not_allowed)
			(vias allowed)
			(pads allowed)
			(copperpour not_allowed)
			(footprints allowed)
		)
		(placement
			(enabled no)
			(sheetname "")
		)
		(fill yes
			(thermal_gap 0.5)
			(thermal_bridge_width 0.5)
			(island_removal_mode 0)
		)
		(polygon
			(pts
				(arc
					(start 383.036572 -394.552424)
					(mid 383.146543 -394.653478)
					(end 383.291334 -394.690092)
				)
				(arc
					(start 383.291334 -394.690092)
					(mid 383.50686 -394.600818)
					(end 383.596134 -394.385292)
				)
				(arc
					(start 383.596134 -394.385292)
					(mid 383.585797 -394.306553)
					(end 383.555494 -394.233146)
				)
				(arc
					(start 383.163064 -393.554204)
					(mid 383.050667 -393.432587)
					(end 382.891284 -393.38758)
				)
				(arc
					(start 382.891284 -393.38758)
					(mid 382.675758 -393.476854)
					(end 382.586484 -393.69238)
				)
				(arc
					(start 382.586484 -393.69238)
					(mid 382.596062 -393.768442)
					(end 382.62433 -393.8397)
				)
				(xy 383.021586 -394.527024) (xy 383.033778 -394.54836) (xy 383.036318 -394.552678)
			)
		)
	)
	(zone
		(layers "F.Cu" "B.Cu" "In1.Cu" "In2.Cu" "In3.Cu" "In4.Cu" "In5.Cu" "In6.Cu"
			"In7.Cu" "In8.Cu" "In9.Cu" "In10.Cu" "In11.Cu" "In12.Cu" "In13.Cu" "In14.Cu"
			"In15.Cu" "In16.Cu"
		)
		(hatch none 0.5)
		(connect_pads
			(clearance 0)
		)
		(min_thickness 0.25)
		(keepout
			(tracks not_allowed)
			(vias allowed)
			(pads allowed)
			(copperpour not_allowed)
			(footprints allowed)
		)
		(placement
			(enabled no)
			(sheetname "")
		)
		(fill
			(thermal_gap 0.5)
			(thermal_bridge_width 0.5)
			(island_removal_mode 0)
		)
		(polygon
			(pts
				(arc
					(start 131.836414 -389.634476)
					(mid 131.946385 -389.73553)
					(end 132.091176 -389.772144)
				)
				(arc
					(start 132.091176 -389.772144)
					(mid 132.306702 -389.68287)
					(end 132.395976 -389.467344)
				)
				(arc
					(start 132.395976 -389.467344)
					(mid 132.385639 -389.388605)
					(end 132.355336 -389.315198)
				)
				(arc
					(start 131.962906 -388.636256)
					(mid 131.850509 -388.514639)
					(end 131.691126 -388.469632)
				)
				(arc
					(start 131.691126 -388.469632)
					(mid 131.4756 -388.558906)
					(end 131.386326 -388.774432)
				)
				(arc
					(start 131.386326 -388.774432)
					(mid 131.395904 -388.850494)
					(end 131.424172 -388.921752)
				)
				(xy 131.821428 -389.609076) (xy 131.83362 -389.630412) (xy 131.83616 -389.63473)
			)
		)
	)
	(zone
		(layers "F.Cu" "B.Cu" "In1.Cu" "In2.Cu" "In3.Cu" "In4.Cu" "In5.Cu" "In6.Cu"
			"In7.Cu" "In8.Cu" "In9.Cu" "In10.Cu" "In11.Cu" "In12.Cu" "In13.Cu" "In14.Cu"
			"In15.Cu" "In16.Cu"
		)
		(hatch none 0.5)
		(connect_pads
			(clearance 0)
		)
		(min_thickness 0.25)
		(keepout
			(tracks not_allowed)
			(vias allowed)
			(pads allowed)
			(copperpour not_allowed)
			(footprints allowed)
		)
		(placement
			(enabled no)
			(sheetname "")
		)
		(fill
			(thermal_gap 0.5)
			(thermal_bridge_width 0.5)
			(island_removal_mode 0)
		)
		(polygon
			(pts
				(arc
					(start 61.397642 -392.429238)
					(mid 61.016642 -392.048238)
					(end 60.635642 -392.429238)
				)
				(arc
					(start 60.635642 -393.292838)
					(mid 61.016642 -393.673838)
					(end 61.397642 -393.292838)
				)
			)
		)
	)
	(zone
		(layers "F.Cu" "B.Cu" "In1.Cu" "In2.Cu" "In3.Cu" "In4.Cu" "In5.Cu" "In6.Cu"
			"In7.Cu" "In8.Cu" "In9.Cu" "In10.Cu" "In11.Cu" "In12.Cu" "In13.Cu" "In14.Cu"
			"In15.Cu" "In16.Cu"
		)
		(hatch none 0.5)
		(connect_pads
			(clearance 0)
		)
		(min_thickness 0.25)
		(keepout
			(tracks not_allowed)
			(vias allowed)
			(pads allowed)
			(copperpour not_allowed)
			(footprints allowed)
		)
		(placement
			(enabled no)
			(sheetname "")
		)
		(fill
			(thermal_gap 0.5)
			(thermal_bridge_width 0.5)
			(island_removal_mode 0)
		)
		(polygon
			(pts
				(arc
					(start 306.336192 -398.016476)
					(mid 306.446163 -398.11753)
					(end 306.590954 -398.154144)
				)
				(arc
					(start 306.590954 -398.154144)
					(mid 306.80648 -398.06487)
					(end 306.895754 -397.849344)
				)
				(arc
					(start 306.895754 -397.849344)
					(mid 306.885417 -397.770605)
					(end 306.855114 -397.697198)
				)
				(arc
					(start 306.462684 -397.018256)
					(mid 306.350287 -396.896639)
					(end 306.190904 -396.851632)
				)
				(arc
					(start 306.190904 -396.851632)
					(mid 305.975378 -396.940906)
					(end 305.886104 -397.156432)
				)
				(arc
					(start 305.886104 -397.156432)
					(mid 305.895682 -397.232494)
					(end 305.92395 -397.303752)
				)
				(xy 306.321206 -397.991076) (xy 306.333398 -398.012412) (xy 306.335938 -398.01673)
			)
		)
	)
	(zone
		(layers "F.Cu" "B.Cu" "In1.Cu" "In2.Cu" "In3.Cu" "In4.Cu" "In5.Cu" "In6.Cu"
			"In7.Cu" "In8.Cu" "In9.Cu" "In10.Cu" "In11.Cu" "In12.Cu" "In13.Cu" "In14.Cu"
			"In15.Cu" "In16.Cu"
		)
		(hatch none 0.5)
		(connect_pads
			(clearance 0)
		)
		(min_thickness 0.25)
		(keepout
			(tracks not_allowed)
			(vias allowed)
			(pads allowed)
			(copperpour not_allowed)
			(footprints allowed)
		)
		(placement
			(enabled no)
			(sheetname "")
		)
		(fill
			(thermal_gap 0.5)
			(thermal_bridge_width 0.5)
			(island_removal_mode 0)
		)
		(polygon
			(pts
				(arc
					(start 162.225228 -392.429238)
					(mid 161.844228 -392.048238)
					(end 161.463228 -392.429238)
				)
				(arc
					(start 161.463228 -393.292838)
					(mid 161.844228 -393.673838)
					(end 162.225228 -393.292838)
				)
			)
		)
	)
	(zone
		(layers "F.Cu" "B.Cu" "In1.Cu" "In2.Cu" "In3.Cu" "In4.Cu" "In5.Cu" "In6.Cu"
			"In7.Cu" "In8.Cu" "In9.Cu" "In10.Cu" "In11.Cu" "In12.Cu" "In13.Cu" "In14.Cu"
			"In15.Cu" "In16.Cu"
		)
		(hatch none 0.5)
		(connect_pads
			(clearance 0)
		)
		(min_thickness 0.25)
		(keepout
			(tracks not_allowed)
			(vias allowed)
			(pads allowed)
			(copperpour not_allowed)
			(footprints allowed)
		)
		(placement
			(enabled no)
			(sheetname "")
		)
		(fill yes
			(thermal_gap 0.5)
			(thermal_bridge_width 0.5)
			(island_removal_mode 0)
		)
		(polygon
			(pts
				(arc
					(start 124.63653 -386.170424)
					(mid 124.746501 -386.271478)
					(end 124.891292 -386.308092)
				)
				(arc
					(start 124.891292 -386.308092)
					(mid 125.106818 -386.218818)
					(end 125.196092 -386.003292)
				)
				(arc
					(start 125.196092 -386.003292)
					(mid 125.185755 -385.924553)
					(end 125.155452 -385.851146)
				)
				(arc
					(start 124.763022 -385.172204)
					(mid 124.650625 -385.050587)
					(end 124.491242 -385.00558)
				)
				(arc
					(start 124.491242 -385.00558)
					(mid 124.275716 -385.094854)
					(end 124.186442 -385.31038)
				)
				(arc
					(start 124.186442 -385.31038)
					(mid 124.19602 -385.386442)
					(end 124.224288 -385.4577)
				)
				(xy 124.621544 -386.145024) (xy 124.633736 -386.16636) (xy 124.636276 -386.170678)
			)
		)
	)
	(zone
		(layers "F.Cu" "B.Cu" "In1.Cu" "In2.Cu" "In3.Cu" "In4.Cu" "In5.Cu" "In6.Cu"
			"In7.Cu" "In8.Cu" "In9.Cu" "In10.Cu" "In11.Cu" "In12.Cu" "In13.Cu" "In14.Cu"
			"In15.Cu" "In16.Cu"
		)
		(hatch none 0.5)
		(connect_pads
			(clearance 0)
		)
		(min_thickness 0.25)
		(keepout
			(tracks not_allowed)
			(vias allowed)
			(pads allowed)
			(copperpour not_allowed)
			(footprints allowed)
		)
		(placement
			(enabled no)
			(sheetname "")
		)
		(fill yes
			(thermal_gap 0.5)
			(thermal_bridge_width 0.5)
			(island_removal_mode 0)
		)
		(polygon
			(pts
				(arc
					(start 307.536342 -394.552424)
					(mid 307.646313 -394.653478)
					(end 307.791104 -394.690092)
				)
				(arc
					(start 307.791104 -394.690092)
					(mid 308.00663 -394.600818)
					(end 308.095904 -394.385292)
				)
				(arc
					(start 308.095904 -394.385292)
					(mid 308.085567 -394.306553)
					(end 308.055264 -394.233146)
				)
				(arc
					(start 307.662834 -393.554204)
					(mid 307.550437 -393.432587)
					(end 307.391054 -393.38758)
				)
				(arc
					(start 307.391054 -393.38758)
					(mid 307.175528 -393.476854)
					(end 307.086254 -393.69238)
				)
				(arc
					(start 307.086254 -393.69238)
					(mid 307.095832 -393.768442)
					(end 307.1241 -393.8397)
				)
				(xy 307.521356 -394.527024) (xy 307.533548 -394.54836) (xy 307.536088 -394.552678)
			)
		)
	)
	(zone
		(layers "F.Cu" "B.Cu" "In1.Cu" "In2.Cu" "In3.Cu" "In4.Cu" "In5.Cu" "In6.Cu"
			"In7.Cu" "In8.Cu" "In9.Cu" "In10.Cu" "In11.Cu" "In12.Cu" "In13.Cu" "In14.Cu"
			"In15.Cu" "In16.Cu"
		)
		(hatch none 0.5)
		(connect_pads
			(clearance 0)
		)
		(min_thickness 0.25)
		(keepout
			(tracks not_allowed)
			(vias allowed)
			(pads allowed)
			(copperpour not_allowed)
			(footprints allowed)
		)
		(placement
			(enabled no)
			(sheetname "")
		)
		(fill
			(thermal_gap 0.5)
			(thermal_bridge_width 0.5)
			(island_removal_mode 0)
		)
		(polygon
			(pts
				(arc
					(start 131.741926 -409.649168)
					(mid 131.360926 -410.030168)
					(end 131.741926 -410.411168)
				)
				(arc
					(start 132.605526 -410.411168)
					(mid 132.986526 -410.030168)
					(end 132.605526 -409.649168)
				)
			)
		)
	)
	(zone
		(layers "F.Cu" "B.Cu" "In1.Cu" "In2.Cu" "In3.Cu" "In4.Cu" "In5.Cu" "In6.Cu"
			"In7.Cu" "In8.Cu" "In9.Cu" "In10.Cu" "In11.Cu" "In12.Cu" "In13.Cu" "In14.Cu"
			"In15.Cu" "In16.Cu"
		)
		(hatch none 0.5)
		(connect_pads
			(clearance 0)
		)
		(min_thickness 0.25)
		(keepout
			(tracks not_allowed)
			(vias allowed)
			(pads allowed)
			(copperpour not_allowed)
			(footprints allowed)
		)
		(placement
			(enabled no)
			(sheetname "")
		)
		(fill
			(thermal_gap 0.5)
			(thermal_bridge_width 0.5)
			(island_removal_mode 0)
		)
		(polygon
			(pts
				(arc
					(start 395.621764 -17.23136)
					(mid 395.240764 -17.61236)
					(end 395.621764 -17.99336)
				)
				(arc
					(start 396.485364 -17.99336)
					(mid 396.866364 -17.61236)
					(end 396.485364 -17.23136)
				)
			)
		)
	)
	(zone
		(layers "F.Cu" "B.Cu" "In1.Cu" "In2.Cu" "In3.Cu" "In4.Cu" "In5.Cu" "In6.Cu"
			"In7.Cu" "In8.Cu" "In9.Cu" "In10.Cu" "In11.Cu" "In12.Cu" "In13.Cu" "In14.Cu"
			"In15.Cu" "In16.Cu"
		)
		(hatch none 0.5)
		(connect_pads
			(clearance 0)
		)
		(min_thickness 0.25)
		(keepout
			(tracks not_allowed)
			(vias allowed)
			(pads allowed)
			(copperpour not_allowed)
			(footprints allowed)
		)
		(placement
			(enabled no)
			(sheetname "")
		)
		(fill
			(thermal_gap 0.5)
			(thermal_bridge_width 0.5)
			(island_removal_mode 0)
		)
		(polygon
			(pts
				(arc
					(start 55.397654 -392.429238)
					(mid 55.016654 -392.048238)
					(end 54.635654 -392.429238)
				)
				(arc
					(start 54.635654 -393.292838)
					(mid 55.016654 -393.673838)
					(end 55.397654 -393.292838)
				)
			)
		)
	)
	(zone
		(layers "F.Cu" "B.Cu" "In1.Cu" "In2.Cu" "In3.Cu" "In4.Cu" "In5.Cu" "In6.Cu"
			"In7.Cu" "In8.Cu" "In9.Cu" "In10.Cu" "In11.Cu" "In12.Cu" "In13.Cu" "In14.Cu"
			"In15.Cu" "In16.Cu"
		)
		(hatch none 0.5)
		(connect_pads
			(clearance 0)
		)
		(min_thickness 0.25)
		(keepout
			(tracks not_allowed)
			(vias allowed)
			(pads allowed)
			(copperpour not_allowed)
			(footprints allowed)
		)
		(placement
			(enabled no)
			(sheetname "")
		)
		(fill
			(thermal_gap 0.5)
			(thermal_bridge_width 0.5)
			(island_removal_mode 0)
		)
		(polygon
			(pts
				(arc
					(start 413.425386 -400.811238)
					(mid 413.044386 -400.430238)
					(end 412.663386 -400.811238)
				)
				(arc
					(start 412.663386 -401.674838)
					(mid 413.044386 -402.055838)
					(end 413.425386 -401.674838)
				)
			)
		)
	)
	(zone
		(layers "F.Cu" "B.Cu" "In1.Cu" "In2.Cu" "In3.Cu" "In4.Cu" "In5.Cu" "In6.Cu"
			"In7.Cu" "In8.Cu" "In9.Cu" "In10.Cu" "In11.Cu" "In12.Cu" "In13.Cu" "In14.Cu"
			"In15.Cu" "In16.Cu"
		)
		(hatch none 0.5)
		(connect_pads
			(clearance 0)
		)
		(min_thickness 0.25)
		(keepout
			(tracks not_allowed)
			(vias allowed)
			(pads allowed)
			(copperpour not_allowed)
			(footprints allowed)
		)
		(placement
			(enabled no)
			(sheetname "")
		)
		(fill
			(thermal_gap 0.5)
			(thermal_bridge_width 0.5)
			(island_removal_mode 0)
		)
		(polygon
			(pts
				(arc
					(start 104.24795 -399.74647)
					(mid 103.48595 -399.74647)
					(end 104.24795 -399.74647)
				)
			)
		)
	)
	(zone
		(layers "F.Cu" "B.Cu" "In1.Cu" "In2.Cu" "In3.Cu" "In4.Cu" "In5.Cu" "In6.Cu"
			"In7.Cu" "In8.Cu" "In9.Cu" "In10.Cu" "In11.Cu" "In12.Cu" "In13.Cu" "In14.Cu"
			"In15.Cu" "In16.Cu"
		)
		(hatch none 0.5)
		(connect_pads
			(clearance 0)
		)
		(min_thickness 0.25)
		(keepout
			(tracks not_allowed)
			(vias allowed)
			(pads allowed)
			(copperpour not_allowed)
			(footprints allowed)
		)
		(placement
			(enabled no)
			(sheetname "")
		)
		(fill
			(thermal_gap 0.5)
			(thermal_bridge_width 0.5)
			(island_removal_mode 0)
		)
		(polygon
			(pts
				(arc
					(start 95.964502 -371.11813)
					(mid 95.583502 -371.49913)
					(end 95.964502 -371.88013)
				)
				(arc
					(start 96.828102 -371.88013)
					(mid 97.209102 -371.49913)
					(end 96.828102 -371.11813)
				)
			)
		)
	)
	(zone
		(layers "F.Cu" "B.Cu" "In1.Cu" "In2.Cu" "In3.Cu" "In4.Cu" "In5.Cu" "In6.Cu"
			"In7.Cu" "In8.Cu" "In9.Cu" "In10.Cu" "In11.Cu" "In12.Cu" "In13.Cu" "In14.Cu"
			"In15.Cu" "In16.Cu"
		)
		(hatch none 0.5)
		(connect_pads
			(clearance 0)
		)
		(min_thickness 0.25)
		(keepout
			(tracks not_allowed)
			(vias allowed)
			(pads allowed)
			(copperpour not_allowed)
			(footprints allowed)
		)
		(placement
			(enabled no)
			(sheetname "")
		)
		(fill
			(thermal_gap 0.5)
			(thermal_bridge_width 0.5)
			(island_removal_mode 0)
		)
		(polygon
			(pts
				(arc
					(start 383.147062 -412.46552)
					(mid 382.766062 -412.84652)
					(end 383.147062 -413.22752)
				)
				(arc
					(start 384.010662 -413.22752)
					(mid 384.391662 -412.84652)
					(end 384.010662 -412.46552)
				)
			)
		)
	)
	(zone
		(layers "F.Cu" "B.Cu" "In1.Cu" "In2.Cu" "In3.Cu" "In4.Cu" "In5.Cu" "In6.Cu"
			"In7.Cu" "In8.Cu" "In9.Cu" "In10.Cu" "In11.Cu" "In12.Cu" "In13.Cu" "In14.Cu"
			"In15.Cu" "In16.Cu"
		)
		(hatch none 0.5)
		(connect_pads
			(clearance 0)
		)
		(min_thickness 0.25)
		(keepout
			(tracks not_allowed)
			(vias allowed)
			(pads allowed)
			(copperpour not_allowed)
			(footprints allowed)
		)
		(placement
			(enabled no)
			(sheetname "")
		)
		(fill
			(thermal_gap 0.5)
			(thermal_bridge_width 0.5)
			(island_removal_mode 0)
		)
		(polygon
			(pts
				(arc
					(start 66.173604 -412.189168)
					(mid 65.792604 -412.570168)
					(end 66.173604 -412.951168)
				)
				(arc
					(start 67.037204 -412.951168)
					(mid 67.418204 -412.570168)
					(end 67.037204 -412.189168)
				)
			)
		)
	)
	(zone
		(layers "F.Cu" "B.Cu" "In1.Cu" "In2.Cu" "In3.Cu" "In4.Cu" "In5.Cu" "In6.Cu"
			"In7.Cu" "In8.Cu" "In9.Cu" "In10.Cu" "In11.Cu" "In12.Cu" "In13.Cu" "In14.Cu"
			"In15.Cu" "In16.Cu"
		)
		(hatch none 0.5)
		(connect_pads
			(clearance 0)
		)
		(min_thickness 0.25)
		(keepout
			(tracks not_allowed)
			(vias allowed)
			(pads allowed)
			(copperpour not_allowed)
			(footprints allowed)
		)
		(placement
			(enabled no)
			(sheetname "")
		)
		(fill
			(thermal_gap 0.5)
			(thermal_bridge_width 0.5)
			(island_removal_mode 0)
		)
		(polygon
			(pts
				(arc
					(start 305.822096 -379.50013)
					(mid 305.441096 -379.88113)
					(end 305.822096 -380.26213)
				)
				(arc
					(start 306.685696 -380.26213)
					(mid 307.066696 -379.88113)
					(end 306.685696 -379.50013)
				)
			)
		)
	)
	(zone
		(layers "F.Cu" "B.Cu" "In1.Cu" "In2.Cu" "In3.Cu" "In4.Cu" "In5.Cu" "In6.Cu"
			"In7.Cu" "In8.Cu" "In9.Cu" "In10.Cu" "In11.Cu" "In12.Cu" "In13.Cu" "In14.Cu"
			"In15.Cu" "In16.Cu"
		)
		(hatch none 0.5)
		(connect_pads
			(clearance 0)
		)
		(min_thickness 0.25)
		(keepout
			(tracks not_allowed)
			(vias allowed)
			(pads allowed)
			(copperpour not_allowed)
			(footprints allowed)
		)
		(placement
			(enabled no)
			(sheetname "")
		)
		(fill
			(thermal_gap 0.5)
			(thermal_bridge_width 0.5)
			(island_removal_mode 0)
		)
		(polygon
			(pts
				(arc
					(start 530.895306 7.400036)
					(mid 526.704306 7.400036)
					(end 530.895306 7.400036)
				)
			)
		)
	)
	(zone
		(layers "F.Cu" "B.Cu" "In1.Cu" "In2.Cu" "In3.Cu" "In4.Cu" "In5.Cu" "In6.Cu"
			"In7.Cu" "In8.Cu" "In9.Cu" "In10.Cu" "In11.Cu" "In12.Cu" "In13.Cu" "In14.Cu"
			"In15.Cu" "In16.Cu"
		)
		(hatch none 0.5)
		(connect_pads
			(clearance 0)
		)
		(min_thickness 0.25)
		(keepout
			(tracks not_allowed)
			(vias allowed)
			(pads allowed)
			(copperpour not_allowed)
			(footprints allowed)
		)
		(placement
			(enabled no)
			(sheetname "")
		)
		(fill
			(thermal_gap 0.5)
			(thermal_bridge_width 0.5)
			(island_removal_mode 0)
		)
		(polygon
			(pts
				(arc
					(start 89.147904 -409.649168)
					(mid 88.766904 -410.030168)
					(end 89.147904 -410.411168)
				)
				(arc
					(start 90.011504 -410.411168)
					(mid 90.392504 -410.030168)
					(end 90.011504 -409.649168)
				)
			)
		)
	)
	(zone
		(layers "F.Cu" "B.Cu" "In1.Cu" "In2.Cu" "In3.Cu" "In4.Cu" "In5.Cu" "In6.Cu"
			"In7.Cu" "In8.Cu" "In9.Cu" "In10.Cu" "In11.Cu" "In12.Cu" "In13.Cu" "In14.Cu"
			"In15.Cu" "In16.Cu"
		)
		(hatch none 0.5)
		(connect_pads
			(clearance 0)
		)
		(min_thickness 0.25)
		(keepout
			(tracks not_allowed)
			(vias allowed)
			(pads allowed)
			(copperpour not_allowed)
			(footprints allowed)
		)
		(placement
			(enabled no)
			(sheetname "")
		)
		(fill
			(thermal_gap 0.5)
			(thermal_bridge_width 0.5)
			(island_removal_mode 0)
		)
		(polygon
			(pts
				(arc
					(start 392.336782 -412.46552)
					(mid 391.955782 -412.84652)
					(end 392.336782 -413.22752)
				)
				(arc
					(start 393.200382 -413.22752)
					(mid 393.581382 -412.84652)
					(end 393.200382 -412.46552)
				)
			)
		)
	)
	(zone
		(layers "F.Cu" "B.Cu" "In1.Cu" "In2.Cu" "In3.Cu" "In4.Cu" "In5.Cu" "In6.Cu"
			"In7.Cu" "In8.Cu" "In9.Cu" "In10.Cu" "In11.Cu" "In12.Cu" "In13.Cu" "In14.Cu"
			"In15.Cu" "In16.Cu"
		)
		(hatch none 0.5)
		(connect_pads
			(clearance 0)
		)
		(min_thickness 0.25)
		(keepout
			(tracks not_allowed)
			(vias allowed)
			(pads allowed)
			(copperpour not_allowed)
			(footprints allowed)
		)
		(placement
			(enabled no)
			(sheetname "")
		)
		(fill
			(thermal_gap 0.5)
			(thermal_bridge_width 0.5)
			(island_removal_mode 0)
		)
		(polygon
			(pts
				(arc
					(start 40.985694 -18.75536)
					(mid 40.604694 -19.13636)
					(end 40.985694 -19.51736)
				)
				(arc
					(start 41.849294 -19.51736)
					(mid 42.230294 -19.13636)
					(end 41.849294 -18.75536)
				)
			)
		)
	)
	(zone
		(layers "F.Cu" "B.Cu" "In1.Cu" "In2.Cu" "In3.Cu" "In4.Cu" "In5.Cu" "In6.Cu"
			"In7.Cu" "In8.Cu" "In9.Cu" "In10.Cu" "In11.Cu" "In12.Cu" "In13.Cu" "In14.Cu"
			"In15.Cu" "In16.Cu"
		)
		(hatch none 0.5)
		(connect_pads
			(clearance 0)
		)
		(min_thickness 0.25)
		(keepout
			(tracks not_allowed)
			(vias allowed)
			(pads allowed)
			(copperpour not_allowed)
			(footprints allowed)
		)
		(placement
			(enabled no)
			(sheetname "")
		)
		(fill
			(thermal_gap 0.5)
			(thermal_bridge_width 0.5)
			(island_removal_mode 0)
		)
		(polygon
			(pts
				(arc
					(start 98.725228 -392.429238)
					(mid 98.344228 -392.048238)
					(end 97.963228 -392.429238)
				)
				(arc
					(start 97.963228 -393.292838)
					(mid 98.344228 -393.673838)
					(end 98.725228 -393.292838)
				)
			)
		)
	)
	(zone
		(layers "F.Cu" "B.Cu" "In1.Cu" "In2.Cu" "In3.Cu" "In4.Cu" "In5.Cu" "In6.Cu"
			"In7.Cu" "In8.Cu" "In9.Cu" "In10.Cu" "In11.Cu" "In12.Cu" "In13.Cu" "In14.Cu"
			"In15.Cu" "In16.Cu"
		)
		(hatch none 0.5)
		(connect_pads
			(clearance 0)
		)
		(min_thickness 0.25)
		(keepout
			(tracks not_allowed)
			(vias allowed)
			(pads allowed)
			(copperpour not_allowed)
			(footprints allowed)
		)
		(placement
			(enabled no)
			(sheetname "")
		)
		(fill
			(thermal_gap 0.5)
			(thermal_bridge_width 0.5)
			(island_removal_mode 0)
		)
		(polygon
			(pts
				(arc
					(start 73.831704 -406.62352)
					(mid 73.450704 -407.00452)
					(end 73.831704 -407.38552)
				)
				(arc
					(start 74.695304 -407.38552)
					(mid 75.076304 -407.00452)
					(end 74.695304 -406.62352)
				)
			)
		)
	)
	(zone
		(layers "F.Cu" "B.Cu" "In1.Cu" "In2.Cu" "In3.Cu" "In4.Cu" "In5.Cu" "In6.Cu"
			"In7.Cu" "In8.Cu" "In9.Cu" "In10.Cu" "In11.Cu" "In12.Cu" "In13.Cu" "In14.Cu"
			"In15.Cu" "In16.Cu"
		)
		(hatch none 0.5)
		(connect_pads
			(clearance 0)
		)
		(min_thickness 0.25)
		(keepout
			(tracks not_allowed)
			(vias allowed)
			(pads allowed)
			(copperpour not_allowed)
			(footprints allowed)
		)
		(placement
			(enabled no)
			(sheetname "")
		)
		(fill
			(thermal_gap 0.5)
			(thermal_bridge_width 0.5)
			(island_removal_mode 0)
		)
		(polygon
			(pts
				(arc
					(start 357.069644 -377.03633)
					(mid 356.688644 -377.41733)
					(end 357.069644 -377.79833)
				)
				(arc
					(start 357.933244 -377.79833)
					(mid 358.314244 -377.41733)
					(end 357.933244 -377.03633)
				)
			)
		)
	)
	(zone
		(layers "F.Cu" "B.Cu" "In1.Cu" "In2.Cu" "In3.Cu" "In4.Cu" "In5.Cu" "In6.Cu"
			"In7.Cu" "In8.Cu" "In9.Cu" "In10.Cu" "In11.Cu" "In12.Cu" "In13.Cu" "In14.Cu"
			"In15.Cu" "In16.Cu"
		)
		(hatch none 0.5)
		(connect_pads
			(clearance 0)
		)
		(min_thickness 0.25)
		(keepout
			(tracks not_allowed)
			(vias allowed)
			(pads allowed)
			(copperpour not_allowed)
			(footprints allowed)
		)
		(placement
			(enabled no)
			(sheetname "")
		)
		(fill
			(thermal_gap 0.5)
			(thermal_bridge_width 0.5)
			(island_removal_mode 0)
		)
		(polygon
			(pts
				(arc
					(start 47.794164 -412.189168)
					(mid 47.413164 -412.570168)
					(end 47.794164 -412.951168)
				)
				(arc
					(start 48.657764 -412.951168)
					(mid 49.038764 -412.570168)
					(end 48.657764 -412.189168)
				)
			)
		)
	)
	(zone
		(layers "F.Cu" "B.Cu" "In1.Cu" "In2.Cu" "In3.Cu" "In4.Cu" "In5.Cu" "In6.Cu"
			"In7.Cu" "In8.Cu" "In9.Cu" "In10.Cu" "In11.Cu" "In12.Cu" "In13.Cu" "In14.Cu"
			"In15.Cu" "In16.Cu"
		)
		(hatch none 0.5)
		(connect_pads
			(clearance 0)
		)
		(min_thickness 0.25)
		(keepout
			(tracks not_allowed)
			(vias allowed)
			(pads allowed)
			(copperpour not_allowed)
			(footprints allowed)
		)
		(placement
			(enabled no)
			(sheetname "")
		)
		(fill
			(thermal_gap 0.5)
			(thermal_bridge_width 0.5)
			(island_removal_mode 0)
		)
		(polygon
			(pts
				(arc
					(start 323.704966 -418.031168)
					(mid 323.323966 -418.412168)
					(end 323.704966 -418.793168)
				)
				(arc
					(start 324.568566 -418.793168)
					(mid 324.949566 -418.412168)
					(end 324.568566 -418.031168)
				)
			)
		)
	)
	(zone
		(layers "F.Cu" "B.Cu" "In1.Cu" "In2.Cu" "In3.Cu" "In4.Cu" "In5.Cu" "In6.Cu"
			"In7.Cu" "In8.Cu" "In9.Cu" "In10.Cu" "In11.Cu" "In12.Cu" "In13.Cu" "In14.Cu"
			"In15.Cu" "In16.Cu"
		)
		(hatch none 0.5)
		(connect_pads
			(clearance 0)
		)
		(min_thickness 0.25)
		(keepout
			(tracks not_allowed)
			(vias allowed)
			(pads allowed)
			(copperpour not_allowed)
			(footprints allowed)
		)
		(placement
			(enabled no)
			(sheetname "")
		)
		(fill
			(thermal_gap 0.5)
			(thermal_bridge_width 0.5)
			(island_removal_mode 0)
		)
		(polygon
			(pts
				(arc
					(start 392.336782 -420.571168)
					(mid 391.955782 -420.952168)
					(end 392.336782 -421.333168)
				)
				(arc
					(start 393.200382 -421.333168)
					(mid 393.581382 -420.952168)
					(end 393.200382 -420.571168)
				)
			)
		)
	)
	(zone
		(layers "F.Cu" "B.Cu" "In1.Cu" "In2.Cu" "In3.Cu" "In4.Cu" "In5.Cu" "In6.Cu"
			"In7.Cu" "In8.Cu" "In9.Cu" "In10.Cu" "In11.Cu" "In12.Cu" "In13.Cu" "In14.Cu"
			"In15.Cu" "In16.Cu"
		)
		(hatch none 0.5)
		(connect_pads
			(clearance 0)
		)
		(min_thickness 0.25)
		(keepout
			(tracks not_allowed)
			(vias allowed)
			(pads allowed)
			(copperpour not_allowed)
			(footprints allowed)
		)
		(placement
			(enabled no)
			(sheetname "")
		)
		(fill
			(thermal_gap 0.5)
			(thermal_bridge_width 0.5)
			(island_removal_mode 0)
		)
		(polygon
			(pts
				(arc
					(start 298.630086 2.111756)
					(mid 299.061886 1.679956)
					(end 299.493686 2.111756)
				)
				(arc
					(start 299.493686 2.975356)
					(mid 299.061886 3.407156)
					(end 298.630086 2.975356)
				)
			)
		)
	)
	(zone
		(layers "F.Cu" "B.Cu" "In1.Cu" "In2.Cu" "In3.Cu" "In4.Cu" "In5.Cu" "In6.Cu"
			"In7.Cu" "In8.Cu" "In9.Cu" "In10.Cu" "In11.Cu" "In12.Cu" "In13.Cu" "In14.Cu"
			"In15.Cu" "In16.Cu"
		)
		(hatch none 0.5)
		(connect_pads
			(clearance 0)
		)
		(min_thickness 0.25)
		(keepout
			(tracks not_allowed)
			(vias allowed)
			(pads allowed)
			(copperpour not_allowed)
			(footprints allowed)
		)
		(placement
			(enabled no)
			(sheetname "")
		)
		(fill
			(thermal_gap 0.5)
			(thermal_bridge_width 0.5)
			(island_removal_mode 0)
		)
		(polygon
			(pts
				(arc
					(start 132.097526 -392.429238)
					(mid 131.716526 -392.048238)
					(end 131.335526 -392.429238)
				)
				(arc
					(start 131.335526 -393.292838)
					(mid 131.716526 -393.673838)
					(end 132.097526 -393.292838)
				)
			)
		)
	)
	(zone
		(layers "F.Cu" "B.Cu" "In1.Cu" "In2.Cu" "In3.Cu" "In4.Cu" "In5.Cu" "In6.Cu"
			"In7.Cu" "In8.Cu" "In9.Cu" "In10.Cu" "In11.Cu" "In12.Cu" "In13.Cu" "In14.Cu"
			"In15.Cu" "In16.Cu"
		)
		(hatch none 0.5)
		(connect_pads
			(clearance 0)
		)
		(min_thickness 0.25)
		(keepout
			(tracks not_allowed)
			(vias allowed)
			(pads allowed)
			(copperpour not_allowed)
			(footprints allowed)
		)
		(placement
			(enabled no)
			(sheetname "")
		)
		(fill
			(thermal_gap 0.5)
			(thermal_bridge_width 0.5)
			(island_removal_mode 0)
		)
		(polygon
			(pts
				(arc
					(start 344.864182 -394.552424)
					(mid 344.974153 -394.653478)
					(end 345.118944 -394.690092)
				)
				(arc
					(start 345.118944 -394.690092)
					(mid 345.33447 -394.600818)
					(end 345.423744 -394.385292)
				)
				(arc
					(start 345.423744 -394.385292)
					(mid 345.413407 -394.306553)
					(end 345.383104 -394.233146)
				)
				(arc
					(start 344.990674 -393.554204)
					(mid 344.878277 -393.432587)
					(end 344.718894 -393.38758)
				)
				(arc
					(start 344.718894 -393.38758)
					(mid 344.503368 -393.476854)
					(end 344.414094 -393.69238)
				)
				(arc
					(start 344.414094 -393.69238)
					(mid 344.423672 -393.768442)
					(end 344.45194 -393.8397)
				)
				(xy 344.849196 -394.527024) (xy 344.861388 -394.54836) (xy 344.863928 -394.552678)
			)
		)
	)
	(zone
		(layers "F.Cu" "B.Cu" "In1.Cu" "In2.Cu" "In3.Cu" "In4.Cu" "In5.Cu" "In6.Cu"
			"In7.Cu" "In8.Cu" "In9.Cu" "In10.Cu" "In11.Cu" "In12.Cu" "In13.Cu" "In14.Cu"
			"In15.Cu" "In16.Cu"
		)
		(hatch none 0.5)
		(connect_pads
			(clearance 0)
		)
		(min_thickness 0.25)
		(keepout
			(tracks not_allowed)
			(vias allowed)
			(pads allowed)
			(copperpour not_allowed)
			(footprints allowed)
		)
		(placement
			(enabled no)
			(sheetname "")
		)
		(fill
			(thermal_gap 0.5)
			(thermal_bridge_width 0.5)
			(island_removal_mode 0)
		)
		(polygon
			(pts
				(arc
					(start 310.927496 -381.96393)
					(mid 310.546496 -382.34493)
					(end 310.927496 -382.72593)
				)
				(arc
					(start 311.791096 -382.72593)
					(mid 312.172096 -382.34493)
					(end 311.791096 -381.96393)
				)
			)
		)
	)
	(zone
		(layers "F.Cu" "B.Cu" "In1.Cu" "In2.Cu" "In3.Cu" "In4.Cu" "In5.Cu" "In6.Cu"
			"In7.Cu" "In8.Cu" "In9.Cu" "In10.Cu" "In11.Cu" "In12.Cu" "In13.Cu" "In14.Cu"
			"In15.Cu" "In16.Cu"
		)
		(hatch none 0.5)
		(connect_pads
			(clearance 0)
		)
		(min_thickness 0.25)
		(keepout
			(tracks not_allowed)
			(vias allowed)
			(pads allowed)
			(copperpour not_allowed)
			(footprints allowed)
		)
		(placement
			(enabled no)
			(sheetname "")
		)
		(fill
			(thermal_gap 0.5)
			(thermal_bridge_width 0.5)
			(island_removal_mode 0)
		)
		(polygon
			(pts
				(arc
					(start 348.725236 -400.811238)
					(mid 348.344236 -400.430238)
					(end 347.963236 -400.811238)
				)
				(arc
					(start 347.963236 -401.674838)
					(mid 348.344236 -402.055838)
					(end 348.725236 -401.674838)
				)
			)
		)
	)
	(zone
		(layers "F.Cu" "B.Cu" "In1.Cu" "In2.Cu" "In3.Cu" "In4.Cu" "In5.Cu" "In6.Cu"
			"In7.Cu" "In8.Cu" "In9.Cu" "In10.Cu" "In11.Cu" "In12.Cu" "In13.Cu" "In14.Cu"
			"In15.Cu" "In16.Cu"
		)
		(hatch none 0.5)
		(connect_pads
			(clearance 0)
		)
		(min_thickness 0.25)
		(keepout
			(tracks not_allowed)
			(vias allowed)
			(pads allowed)
			(copperpour not_allowed)
			(footprints allowed)
		)
		(placement
			(enabled no)
			(sheetname "")
		)
		(fill
			(thermal_gap 0.5)
			(thermal_bridge_width 0.5)
			(island_removal_mode 0)
		)
		(polygon
			(pts
				(arc
					(start 335.957926 -418.031168)
					(mid 335.576926 -418.412168)
					(end 335.957926 -418.793168)
				)
				(arc
					(start 336.821526 -418.793168)
					(mid 337.202526 -418.412168)
					(end 336.821526 -418.031168)
				)
			)
		)
	)
	(zone
		(layers "F.Cu" "B.Cu" "In1.Cu" "In2.Cu" "In3.Cu" "In4.Cu" "In5.Cu" "In6.Cu"
			"In7.Cu" "In8.Cu" "In9.Cu" "In10.Cu" "In11.Cu" "In12.Cu" "In13.Cu" "In14.Cu"
			"In15.Cu" "In16.Cu"
		)
		(hatch none 0.5)
		(connect_pads
			(clearance 0)
		)
		(min_thickness 0.25)
		(keepout
			(tracks not_allowed)
			(vias allowed)
			(pads allowed)
			(copperpour not_allowed)
			(footprints allowed)
		)
		(placement
			(enabled no)
			(sheetname "")
		)
		(fill
			(thermal_gap 0.5)
			(thermal_bridge_width 0.5)
			(island_removal_mode 0)
		)
		(polygon
			(pts
				(arc
					(start 108.069126 -405.620982)
					(mid 108.450126 -405.239982)
					(end 108.069126 -404.858982)
				)
				(arc
					(start 107.205526 -404.858982)
					(mid 106.824526 -405.239982)
					(end 107.205526 -405.620982)
				)
			)
		)
	)
	(zone
		(layers "F.Cu" "B.Cu" "In1.Cu" "In2.Cu" "In3.Cu" "In4.Cu" "In5.Cu" "In6.Cu"
			"In7.Cu" "In8.Cu" "In9.Cu" "In10.Cu" "In11.Cu" "In12.Cu" "In13.Cu" "In14.Cu"
			"In15.Cu" "In16.Cu"
		)
		(hatch none 0.5)
		(connect_pads
			(clearance 0)
		)
		(min_thickness 0.25)
		(keepout
			(tracks not_allowed)
			(vias allowed)
			(pads allowed)
			(copperpour not_allowed)
			(footprints allowed)
		)
		(placement
			(enabled no)
			(sheetname "")
		)
		(fill
			(thermal_gap 0.5)
			(thermal_bridge_width 0.5)
			(island_removal_mode 0)
		)
		(polygon
			(pts
				(arc
					(start 97.409254 -207.499458)
					(mid 97.790254 -207.880458)
					(end 98.171254 -207.499458)
				)
				(arc
					(start 98.171254 -206.635858)
					(mid 97.790254 -206.254858)
					(end 97.409254 -206.635858)
				)
			)
		)
	)
	(zone
		(layers "F.Cu" "B.Cu" "In1.Cu" "In2.Cu" "In3.Cu" "In4.Cu" "In5.Cu" "In6.Cu"
			"In7.Cu" "In8.Cu" "In9.Cu" "In10.Cu" "In11.Cu" "In12.Cu" "In13.Cu" "In14.Cu"
			"In15.Cu" "In16.Cu"
		)
		(hatch none 0.5)
		(connect_pads
			(clearance 0)
		)
		(min_thickness 0.25)
		(keepout
			(tracks not_allowed)
			(vias allowed)
			(pads allowed)
			(copperpour not_allowed)
			(footprints allowed)
		)
		(placement
			(enabled no)
			(sheetname "")
		)
		(fill
			(thermal_gap 0.5)
			(thermal_bridge_width 0.5)
			(island_removal_mode 0)
		)
		(polygon
			(pts
				(arc
					(start 390.782048 -5.169916)
					(mid 388.851648 -5.169916)
					(end 390.782048 -5.169916)
				)
			)
		)
	)
	(zone
		(layers "F.Cu" "B.Cu" "In1.Cu" "In2.Cu" "In3.Cu" "In4.Cu" "In5.Cu" "In6.Cu"
			"In7.Cu" "In8.Cu" "In9.Cu" "In10.Cu" "In11.Cu" "In12.Cu" "In13.Cu" "In14.Cu"
			"In15.Cu" "In16.Cu"
		)
		(hatch none 0.5)
		(connect_pads
			(clearance 0)
		)
		(min_thickness 0.25)
		(keepout
			(tracks not_allowed)
			(vias allowed)
			(pads allowed)
			(copperpour not_allowed)
			(footprints allowed)
		)
		(placement
			(enabled no)
			(sheetname "")
		)
		(fill
			(thermal_gap 0.5)
			(thermal_bridge_width 0.5)
			(island_removal_mode 0)
		)
		(polygon
			(pts
				(arc
					(start 93.92539 -392.429238)
					(mid 93.54439 -392.048238)
					(end 93.16339 -392.429238)
				)
				(arc
					(start 93.16339 -393.292838)
					(mid 93.54439 -393.673838)
					(end 93.92539 -393.292838)
				)
			)
		)
	)
	(zone
		(layers "F.Cu" "B.Cu" "In1.Cu" "In2.Cu" "In3.Cu" "In4.Cu" "In5.Cu" "In6.Cu"
			"In7.Cu" "In8.Cu" "In9.Cu" "In10.Cu" "In11.Cu" "In12.Cu" "In13.Cu" "In14.Cu"
			"In15.Cu" "In16.Cu"
		)
		(hatch none 0.5)
		(connect_pads
			(clearance 0)
		)
		(min_thickness 0.25)
		(keepout
			(tracks not_allowed)
			(vias allowed)
			(pads allowed)
			(copperpour not_allowed)
			(footprints allowed)
		)
		(placement
			(enabled no)
			(sheetname "")
		)
		(fill
			(thermal_gap 0.5)
			(thermal_bridge_width 0.5)
			(island_removal_mode 0)
		)
		(polygon
			(pts
				(arc
					(start 316.197488 -400.811238)
					(mid 315.816488 -400.430238)
					(end 315.435488 -400.811238)
				)
				(arc
					(start 315.435488 -401.674838)
					(mid 315.816488 -402.055838)
					(end 316.197488 -401.674838)
				)
			)
		)
	)
	(zone
		(layers "F.Cu" "B.Cu" "In1.Cu" "In2.Cu" "In3.Cu" "In4.Cu" "In5.Cu" "In6.Cu"
			"In7.Cu" "In8.Cu" "In9.Cu" "In10.Cu" "In11.Cu" "In12.Cu" "In13.Cu" "In14.Cu"
			"In15.Cu" "In16.Cu"
		)
		(hatch none 0.5)
		(connect_pads
			(clearance 0)
		)
		(min_thickness 0.25)
		(keepout
			(tracks not_allowed)
			(vias allowed)
			(pads allowed)
			(copperpour not_allowed)
			(footprints allowed)
		)
		(placement
			(enabled no)
			(sheetname "")
		)
		(fill
			(thermal_gap 0.5)
			(thermal_bridge_width 0.5)
			(island_removal_mode 0)
		)
		(polygon
			(pts
				(arc
					(start 58.515504 -409.649168)
					(mid 58.134504 -410.030168)
					(end 58.515504 -410.411168)
				)
				(arc
					(start 59.379104 -410.411168)
					(mid 59.760104 -410.030168)
					(end 59.379104 -409.649168)
				)
			)
		)
	)
	(zone
		(layers "F.Cu" "B.Cu" "In1.Cu" "In2.Cu" "In3.Cu" "In4.Cu" "In5.Cu" "In6.Cu"
			"In7.Cu" "In8.Cu" "In9.Cu" "In10.Cu" "In11.Cu" "In12.Cu" "In13.Cu" "In14.Cu"
			"In15.Cu" "In16.Cu"
		)
		(hatch none 0.5)
		(connect_pads
			(clearance 0)
		)
		(min_thickness 0.25)
		(keepout
			(tracks not_allowed)
			(vias allowed)
			(pads allowed)
			(copperpour not_allowed)
			(footprints allowed)
		)
		(placement
			(enabled no)
			(sheetname "")
		)
		(fill
			(thermal_gap 0.5)
			(thermal_bridge_width 0.5)
			(island_removal_mode 0)
		)
		(polygon
			(pts
				(arc
					(start 158.364174 -389.634476)
					(mid 158.474145 -389.73553)
					(end 158.618936 -389.772144)
				)
				(arc
					(start 158.618936 -389.772144)
					(mid 158.834462 -389.68287)
					(end 158.923736 -389.467344)
				)
				(arc
					(start 158.923736 -389.467344)
					(mid 158.913399 -389.388605)
					(end 158.883096 -389.315198)
				)
				(arc
					(start 158.490666 -388.636256)
					(mid 158.378269 -388.514639)
					(end 158.218886 -388.469632)
				)
				(arc
					(start 158.218886 -388.469632)
					(mid 158.00336 -388.558906)
					(end 157.914086 -388.774432)
				)
				(arc
					(start 157.914086 -388.774432)
					(mid 157.923664 -388.850494)
					(end 157.951932 -388.921752)
				)
				(xy 158.349188 -389.609076) (xy 158.36138 -389.630412) (xy 158.36392 -389.63473)
			)
		)
	)
	(zone
		(layers "F.Cu" "B.Cu" "In1.Cu" "In2.Cu" "In3.Cu" "In4.Cu" "In5.Cu" "In6.Cu"
			"In7.Cu" "In8.Cu" "In9.Cu" "In10.Cu" "In11.Cu" "In12.Cu" "In13.Cu" "In14.Cu"
			"In15.Cu" "In16.Cu"
		)
		(hatch none 0.5)
		(connect_pads
			(clearance 0)
		)
		(min_thickness 0.25)
		(keepout
			(tracks not_allowed)
			(vias allowed)
			(pads allowed)
			(copperpour not_allowed)
			(footprints allowed)
		)
		(placement
			(enabled no)
			(sheetname "")
		)
		(fill
			(thermal_gap 0.5)
			(thermal_bridge_width 0.5)
			(island_removal_mode 0)
		)
		(polygon
			(pts
				(arc
					(start 110.822486 -434.774086)
					(mid 112.024922 -438.585484)
					(end 113.227358 -434.774086)
				)
				(arc
					(start 113.227358 -434.774086)
					(mid 114.979042 -433.451607)
					(end 115.644422 -431.360072)
				)
				(arc
					(start 115.644422 -431.360072)
					(mid 112.024922 -427.740572)
					(end 108.405422 -431.360072)
				)
				(arc
					(start 108.405422 -431.360072)
					(mid 109.070865 -433.451562)
					(end 110.822486 -434.774086)
				)
			)
		)
	)
	(zone
		(layers "F.Cu" "B.Cu" "In1.Cu" "In2.Cu" "In3.Cu" "In4.Cu" "In5.Cu" "In6.Cu"
			"In7.Cu" "In8.Cu" "In9.Cu" "In10.Cu" "In11.Cu" "In12.Cu" "In13.Cu" "In14.Cu"
			"In15.Cu" "In16.Cu"
		)
		(hatch none 0.5)
		(connect_pads
			(clearance 0)
		)
		(min_thickness 0.25)
		(keepout
			(tracks not_allowed)
			(vias allowed)
			(pads allowed)
			(copperpour not_allowed)
			(footprints allowed)
		)
		(placement
			(enabled no)
			(sheetname "")
		)
		(fill
			(thermal_gap 0.5)
			(thermal_bridge_width 0.5)
			(island_removal_mode 0)
		)
		(polygon
			(pts
				(arc
					(start 381.836422 -398.016476)
					(mid 381.946393 -398.11753)
					(end 382.091184 -398.154144)
				)
				(arc
					(start 382.091184 -398.154144)
					(mid 382.30671 -398.06487)
					(end 382.395984 -397.849344)
				)
				(arc
					(start 382.395984 -397.849344)
					(mid 382.385647 -397.770605)
					(end 382.355344 -397.697198)
				)
				(arc
					(start 381.962914 -397.018256)
					(mid 381.850517 -396.896639)
					(end 381.691134 -396.851632)
				)
				(arc
					(start 381.691134 -396.851632)
					(mid 381.475608 -396.940906)
					(end 381.386334 -397.156432)
				)
				(arc
					(start 381.386334 -397.156432)
					(mid 381.395912 -397.232494)
					(end 381.42418 -397.303752)
				)
				(xy 381.821436 -397.991076) (xy 381.833628 -398.012412) (xy 381.836168 -398.01673)
			)
		)
	)
	(zone
		(layers "F.Cu" "B.Cu" "In1.Cu" "In2.Cu" "In3.Cu" "In4.Cu" "In5.Cu" "In6.Cu"
			"In7.Cu" "In8.Cu" "In9.Cu" "In10.Cu" "In11.Cu" "In12.Cu" "In13.Cu" "In14.Cu"
			"In15.Cu" "In16.Cu"
		)
		(hatch none 0.5)
		(connect_pads
			(clearance 0)
		)
		(min_thickness 0.25)
		(keepout
			(tracks not_allowed)
			(vias allowed)
			(pads allowed)
			(copperpour not_allowed)
			(footprints allowed)
		)
		(placement
			(enabled no)
			(sheetname "")
		)
		(fill
			(thermal_gap 0.5)
			(thermal_bridge_width 0.5)
			(island_removal_mode 0)
		)
		(polygon
			(pts
				(arc
					(start 143.994886 -409.649168)
					(mid 143.613886 -410.030168)
					(end 143.994886 -410.411168)
				)
				(arc
					(start 144.858486 -410.411168)
					(mid 145.239486 -410.030168)
					(end 144.858486 -409.649168)
				)
			)
		)
	)
	(zone
		(layers "F.Cu" "B.Cu" "In1.Cu" "In2.Cu" "In3.Cu" "In4.Cu" "In5.Cu" "In6.Cu"
			"In7.Cu" "In8.Cu" "In9.Cu" "In10.Cu" "In11.Cu" "In12.Cu" "In13.Cu" "In14.Cu"
			"In15.Cu" "In16.Cu"
		)
		(hatch none 0.5)
		(connect_pads
			(clearance 0)
		)
		(min_thickness 0.25)
		(keepout
			(tracks not_allowed)
			(vias allowed)
			(pads allowed)
			(copperpour not_allowed)
			(footprints allowed)
		)
		(placement
			(enabled no)
			(sheetname "")
		)
		(fill
			(thermal_gap 0.5)
			(thermal_bridge_width 0.5)
			(island_removal_mode 0)
		)
		(polygon
			(pts
				(arc
					(start 154.716226 -412.189168)
					(mid 154.335226 -412.570168)
					(end 154.716226 -412.951168)
				)
				(arc
					(start 155.579826 -412.951168)
					(mid 155.960826 -412.570168)
					(end 155.579826 -412.189168)
				)
			)
		)
	)
	(zone
		(layers "F.Cu" "B.Cu" "In1.Cu" "In2.Cu" "In3.Cu" "In4.Cu" "In5.Cu" "In6.Cu"
			"In7.Cu" "In8.Cu" "In9.Cu" "In10.Cu" "In11.Cu" "In12.Cu" "In13.Cu" "In14.Cu"
			"In15.Cu" "In16.Cu"
		)
		(hatch none 0.5)
		(connect_pads
			(clearance 0)
		)
		(min_thickness 0.25)
		(keepout
			(tracks not_allowed)
			(vias allowed)
			(pads allowed)
			(copperpour not_allowed)
			(footprints allowed)
		)
		(placement
			(enabled no)
			(sheetname "")
		)
		(fill
			(thermal_gap 0.5)
			(thermal_bridge_width 0.5)
			(island_removal_mode 0)
		)
		(polygon
			(pts
				(arc
					(start 75.901042 -420.058088)
					(mid 75.520042 -419.677088)
					(end 75.139042 -420.058088)
				)
				(arc
					(start 75.139042 -420.921688)
					(mid 75.520042 -421.302688)
					(end 75.901042 -420.921688)
				)
			)
		)
	)
	(zone
		(layers "F.Cu" "B.Cu" "In1.Cu" "In2.Cu" "In3.Cu" "In4.Cu" "In5.Cu" "In6.Cu"
			"In7.Cu" "In8.Cu" "In9.Cu" "In10.Cu" "In11.Cu" "In12.Cu" "In13.Cu" "In14.Cu"
			"In15.Cu" "In16.Cu"
		)
		(hatch none 0.5)
		(connect_pads
			(clearance 0)
		)
		(min_thickness 0.25)
		(keepout
			(tracks not_allowed)
			(vias allowed)
			(pads allowed)
			(copperpour not_allowed)
			(footprints allowed)
		)
		(placement
			(enabled no)
			(sheetname "")
		)
		(fill yes
			(thermal_gap 0.5)
			(thermal_bridge_width 0.5)
			(island_removal_mode 0)
		)
		(polygon
			(pts
				(arc
					(start 354.464112 -394.552424)
					(mid 354.574083 -394.653478)
					(end 354.718874 -394.690092)
				)
				(arc
					(start 354.718874 -394.690092)
					(mid 354.9344 -394.600818)
					(end 355.023674 -394.385292)
				)
				(arc
					(start 355.023674 -394.385292)
					(mid 355.013337 -394.306553)
					(end 354.983034 -394.233146)
				)
				(arc
					(start 354.590604 -393.554204)
					(mid 354.478207 -393.432587)
					(end 354.318824 -393.38758)
				)
				(arc
					(start 354.318824 -393.38758)
					(mid 354.103298 -393.476854)
					(end 354.014024 -393.69238)
				)
				(arc
					(start 354.014024 -393.69238)
					(mid 354.023602 -393.768442)
					(end 354.05187 -393.8397)
				)
				(xy 354.449126 -394.527024) (xy 354.461318 -394.54836) (xy 354.463858 -394.552678)
			)
		)
	)
	(zone
		(layers "F.Cu" "B.Cu" "In1.Cu" "In2.Cu" "In3.Cu" "In4.Cu" "In5.Cu" "In6.Cu"
			"In7.Cu" "In8.Cu" "In9.Cu" "In10.Cu" "In11.Cu" "In12.Cu" "In13.Cu" "In14.Cu"
			"In15.Cu" "In16.Cu"
		)
		(hatch none 0.5)
		(connect_pads
			(clearance 0)
		)
		(min_thickness 0.25)
		(keepout
			(tracks not_allowed)
			(vias allowed)
			(pads allowed)
			(copperpour not_allowed)
			(footprints allowed)
		)
		(placement
			(enabled no)
			(sheetname "")
		)
		(fill
			(thermal_gap 0.5)
			(thermal_bridge_width 0.5)
			(island_removal_mode 0)
		)
		(polygon
			(pts
				(arc
					(start 321.138296 -377.03633)
					(mid 320.757296 -377.41733)
					(end 321.138296 -377.79833)
				)
				(arc
					(start 322.001896 -377.79833)
					(mid 322.382896 -377.41733)
					(end 322.001896 -377.03633)
				)
			)
		)
	)
	(zone
		(layers "F.Cu" "B.Cu" "In1.Cu" "In2.Cu" "In3.Cu" "In4.Cu" "In5.Cu" "In6.Cu"
			"In7.Cu" "In8.Cu" "In9.Cu" "In10.Cu" "In11.Cu" "In12.Cu" "In13.Cu" "In14.Cu"
			"In15.Cu" "In16.Cu"
		)
		(hatch none 0.5)
		(connect_pads
			(clearance 0)
		)
		(min_thickness 0.25)
		(keepout
			(tracks not_allowed)
			(vias allowed)
			(pads allowed)
			(copperpour not_allowed)
			(footprints allowed)
		)
		(placement
			(enabled no)
			(sheetname "")
		)
		(fill
			(thermal_gap 0.5)
			(thermal_bridge_width 0.5)
			(island_removal_mode 0)
		)
		(polygon
			(pts
				(arc
					(start 341.525098 -400.811238)
					(mid 341.144098 -400.430238)
					(end 340.763098 -400.811238)
				)
				(arc
					(start 340.763098 -401.674838)
					(mid 341.144098 -402.055838)
					(end 341.525098 -401.674838)
				)
			)
		)
	)
	(zone
		(layers "F.Cu" "B.Cu" "In1.Cu" "In2.Cu" "In3.Cu" "In4.Cu" "In5.Cu" "In6.Cu"
			"In7.Cu" "In8.Cu" "In9.Cu" "In10.Cu" "In11.Cu" "In12.Cu" "In13.Cu" "In14.Cu"
			"In15.Cu" "In16.Cu"
		)
		(hatch none 0.5)
		(connect_pads
			(clearance 0)
		)
		(min_thickness 0.25)
		(keepout
			(tracks not_allowed)
			(vias allowed)
			(pads allowed)
			(copperpour not_allowed)
			(footprints allowed)
		)
		(placement
			(enabled no)
			(sheetname "")
		)
		(fill
			(thermal_gap 0.5)
			(thermal_bridge_width 0.5)
			(island_removal_mode 0)
		)
		(polygon
			(pts
				(arc
					(start 387.83641 -398.016476)
					(mid 387.946381 -398.11753)
					(end 388.091172 -398.154144)
				)
				(arc
					(start 388.091172 -398.154144)
					(mid 388.306698 -398.06487)
					(end 388.395972 -397.849344)
				)
				(arc
					(start 388.395972 -397.849344)
					(mid 388.385635 -397.770605)
					(end 388.355332 -397.697198)
				)
				(arc
					(start 387.962902 -397.018256)
					(mid 387.850505 -396.896639)
					(end 387.691122 -396.851632)
				)
				(arc
					(start 387.691122 -396.851632)
					(mid 387.475596 -396.940906)
					(end 387.386322 -397.156432)
				)
				(arc
					(start 387.386322 -397.156432)
					(mid 387.3959 -397.232494)
					(end 387.424168 -397.303752)
				)
				(xy 387.821424 -397.991076) (xy 387.833616 -398.012412) (xy 387.836156 -398.01673)
			)
		)
	)
	(zone
		(layers "F.Cu" "B.Cu" "In1.Cu" "In2.Cu" "In3.Cu" "In4.Cu" "In5.Cu" "In6.Cu"
			"In7.Cu" "In8.Cu" "In9.Cu" "In10.Cu" "In11.Cu" "In12.Cu" "In13.Cu" "In14.Cu"
			"In15.Cu" "In16.Cu"
		)
		(hatch none 0.5)
		(connect_pads
			(clearance 0)
		)
		(min_thickness 0.25)
		(keepout
			(tracks not_allowed)
			(vias allowed)
			(pads allowed)
			(copperpour not_allowed)
			(footprints allowed)
		)
		(placement
			(enabled no)
			(sheetname "")
		)
		(fill
			(thermal_gap 0.5)
			(thermal_bridge_width 0.5)
			(island_removal_mode 0)
		)
		(polygon
			(pts
				(arc
					(start 404.482554 -258.880102)
					(mid 399.453354 -258.880102)
					(end 404.482554 -258.880102)
				)
			)
		)
	)
	(zone
		(layers "F.Cu" "B.Cu" "In1.Cu" "In2.Cu" "In3.Cu" "In4.Cu" "In5.Cu" "In6.Cu"
			"In7.Cu" "In8.Cu" "In9.Cu" "In10.Cu" "In11.Cu" "In12.Cu" "In13.Cu" "In14.Cu"
			"In15.Cu" "In16.Cu"
		)
		(hatch none 0.5)
		(connect_pads
			(clearance 0)
		)
		(min_thickness 0.25)
		(keepout
			(tracks not_allowed)
			(vias allowed)
			(pads allowed)
			(copperpour not_allowed)
			(footprints allowed)
		)
		(placement
			(enabled no)
			(sheetname "")
		)
		(fill yes
			(thermal_gap 0.5)
			(thermal_bridge_width 0.5)
			(island_removal_mode 0)
		)
		(polygon
			(pts
				(arc
					(start 84.064348 -386.170424)
					(mid 84.174319 -386.271478)
					(end 84.31911 -386.308092)
				)
				(arc
					(start 84.31911 -386.308092)
					(mid 84.534636 -386.218818)
					(end 84.62391 -386.003292)
				)
				(arc
					(start 84.62391 -386.003292)
					(mid 84.613573 -385.924553)
					(end 84.58327 -385.851146)
				)
				(arc
					(start 84.19084 -385.172204)
					(mid 84.078443 -385.050587)
					(end 83.91906 -385.00558)
				)
				(arc
					(start 83.91906 -385.00558)
					(mid 83.703534 -385.094854)
					(end 83.61426 -385.31038)
				)
				(arc
					(start 83.61426 -385.31038)
					(mid 83.623838 -385.386442)
					(end 83.652106 -385.4577)
				)
				(xy 84.049362 -386.145024) (xy 84.061554 -386.16636) (xy 84.064094 -386.170678)
			)
		)
	)
	(zone
		(layers "F.Cu" "B.Cu" "In1.Cu" "In2.Cu" "In3.Cu" "In4.Cu" "In5.Cu" "In6.Cu"
			"In7.Cu" "In8.Cu" "In9.Cu" "In10.Cu" "In11.Cu" "In12.Cu" "In13.Cu" "In14.Cu"
			"In15.Cu" "In16.Cu"
		)
		(hatch none 0.5)
		(connect_pads
			(clearance 0)
		)
		(min_thickness 0.25)
		(keepout
			(tracks not_allowed)
			(vias allowed)
			(pads allowed)
			(copperpour not_allowed)
			(footprints allowed)
		)
		(placement
			(enabled no)
			(sheetname "")
		)
		(fill
			(thermal_gap 0.5)
			(thermal_bridge_width 0.5)
			(island_removal_mode 0)
		)
		(polygon
			(pts
				(arc
					(start 414.36417 -398.016476)
					(mid 414.474141 -398.11753)
					(end 414.618932 -398.154144)
				)
				(arc
					(start 414.618932 -398.154144)
					(mid 414.834458 -398.06487)
					(end 414.923732 -397.849344)
				)
				(arc
					(start 414.923732 -397.849344)
					(mid 414.913395 -397.770605)
					(end 414.883092 -397.697198)
				)
				(arc
					(start 414.490662 -397.018256)
					(mid 414.378265 -396.896639)
					(end 414.218882 -396.851632)
				)
				(arc
					(start 414.218882 -396.851632)
					(mid 414.003356 -396.940906)
					(end 413.914082 -397.156432)
				)
				(arc
					(start 413.914082 -397.156432)
					(mid 413.92366 -397.232494)
					(end 413.951928 -397.303752)
				)
				(xy 414.349184 -397.991076) (xy 414.361376 -398.012412) (xy 414.363916 -398.01673)
			)
		)
	)
	(zone
		(layers "F.Cu" "B.Cu" "In1.Cu" "In2.Cu" "In3.Cu" "In4.Cu" "In5.Cu" "In6.Cu"
			"In7.Cu" "In8.Cu" "In9.Cu" "In10.Cu" "In11.Cu" "In12.Cu" "In13.Cu" "In14.Cu"
			"In15.Cu" "In16.Cu"
		)
		(hatch none 0.5)
		(connect_pads
			(clearance 0)
		)
		(min_thickness 0.25)
		(keepout
			(tracks not_allowed)
			(vias allowed)
			(pads allowed)
			(copperpour not_allowed)
			(footprints allowed)
		)
		(placement
			(enabled no)
			(sheetname "")
		)
		(fill yes
			(thermal_gap 0.5)
			(thermal_bridge_width 0.5)
			(island_removal_mode 0)
		)
		(polygon
			(pts
				(arc
					(start 153.564336 -386.170424)
					(mid 153.674307 -386.271478)
					(end 153.819098 -386.308092)
				)
				(arc
					(start 153.819098 -386.308092)
					(mid 154.034624 -386.218818)
					(end 154.123898 -386.003292)
				)
				(arc
					(start 154.123898 -386.003292)
					(mid 154.113561 -385.924553)
					(end 154.083258 -385.851146)
				)
				(arc
					(start 153.690828 -385.172204)
					(mid 153.578431 -385.050587)
					(end 153.419048 -385.00558)
				)
				(arc
					(start 153.419048 -385.00558)
					(mid 153.203522 -385.094854)
					(end 153.114248 -385.31038)
				)
				(arc
					(start 153.114248 -385.31038)
					(mid 153.123826 -385.386442)
					(end 153.152094 -385.4577)
				)
				(xy 153.54935 -386.145024) (xy 153.561542 -386.16636) (xy 153.564082 -386.170678)
			)
		)
	)
	(zone
		(layers "F.Cu" "B.Cu" "In1.Cu" "In2.Cu" "In3.Cu" "In4.Cu" "In5.Cu" "In6.Cu"
			"In7.Cu" "In8.Cu" "In9.Cu" "In10.Cu" "In11.Cu" "In12.Cu" "In13.Cu" "In14.Cu"
			"In15.Cu" "In16.Cu"
		)
		(hatch none 0.5)
		(connect_pads
			(clearance 0)
		)
		(min_thickness 0.25)
		(keepout
			(tracks not_allowed)
			(vias allowed)
			(pads allowed)
			(copperpour not_allowed)
			(footprints allowed)
		)
		(placement
			(enabled no)
			(sheetname "")
		)
		(fill
			(thermal_gap 0.5)
			(thermal_bridge_width 0.5)
			(island_removal_mode 0)
		)
		(polygon
			(pts
				(arc
					(start 121.036588 -389.634476)
					(mid 121.146559 -389.73553)
					(end 121.29135 -389.772144)
				)
				(arc
					(start 121.29135 -389.772144)
					(mid 121.506876 -389.68287)
					(end 121.59615 -389.467344)
				)
				(arc
					(start 121.59615 -389.467344)
					(mid 121.585813 -389.388605)
					(end 121.55551 -389.315198)
				)
				(arc
					(start 121.16308 -388.636256)
					(mid 121.050683 -388.514639)
					(end 120.8913 -388.469632)
				)
				(arc
					(start 120.8913 -388.469632)
					(mid 120.675774 -388.558906)
					(end 120.5865 -388.774432)
				)
				(arc
					(start 120.5865 -388.774432)
					(mid 120.596078 -388.850494)
					(end 120.624346 -388.921752)
				)
				(xy 121.021602 -389.609076) (xy 121.033794 -389.630412) (xy 121.036334 -389.63473)
			)
		)
	)
	(zone
		(layers "F.Cu" "B.Cu" "In1.Cu" "In2.Cu" "In3.Cu" "In4.Cu" "In5.Cu" "In6.Cu"
			"In7.Cu" "In8.Cu" "In9.Cu" "In10.Cu" "In11.Cu" "In12.Cu" "In13.Cu" "In14.Cu"
			"In15.Cu" "In16.Cu"
		)
		(hatch none 0.5)
		(connect_pads
			(clearance 0)
		)
		(min_thickness 0.25)
		(keepout
			(tracks not_allowed)
			(vias allowed)
			(pads allowed)
			(copperpour not_allowed)
			(footprints allowed)
		)
		(placement
			(enabled no)
			(sheetname "")
		)
		(fill
			(thermal_gap 0.5)
			(thermal_bridge_width 0.5)
			(island_removal_mode 0)
		)
		(polygon
			(pts
				(arc
					(start 8.725408 -175.848264)
					(mid 9.106408 -176.229264)
					(end 9.487408 -175.848264)
				)
				(arc
					(start 9.487408 -174.984664)
					(mid 9.106408 -174.603664)
					(end 8.725408 -174.984664)
				)
			)
		)
	)
	(zone
		(layers "F.Cu" "B.Cu" "In1.Cu" "In2.Cu" "In3.Cu" "In4.Cu" "In5.Cu" "In6.Cu"
			"In7.Cu" "In8.Cu" "In9.Cu" "In10.Cu" "In11.Cu" "In12.Cu" "In13.Cu" "In14.Cu"
			"In15.Cu" "In16.Cu"
		)
		(hatch none 0.5)
		(connect_pads
			(clearance 0)
		)
		(min_thickness 0.25)
		(keepout
			(tracks not_allowed)
			(vias allowed)
			(pads allowed)
			(copperpour not_allowed)
			(footprints allowed)
		)
		(placement
			(enabled no)
			(sheetname "")
		)
		(fill yes
			(thermal_gap 0.5)
			(thermal_bridge_width 0.5)
			(island_removal_mode 0)
		)
		(polygon
			(pts
				(arc
					(start 348.464124 -394.552424)
					(mid 348.574095 -394.653478)
					(end 348.718886 -394.690092)
				)
				(arc
					(start 348.718886 -394.690092)
					(mid 348.934412 -394.600818)
					(end 349.023686 -394.385292)
				)
				(arc
					(start 349.023686 -394.385292)
					(mid 349.013349 -394.306553)
					(end 348.983046 -394.233146)
				)
				(arc
					(start 348.590616 -393.554204)
					(mid 348.478219 -393.432587)
					(end 348.318836 -393.38758)
				)
				(arc
					(start 348.318836 -393.38758)
					(mid 348.10331 -393.476854)
					(end 348.014036 -393.69238)
				)
				(arc
					(start 348.014036 -393.69238)
					(mid 348.023614 -393.768442)
					(end 348.051882 -393.8397)
				)
				(xy 348.449138 -394.527024) (xy 348.46133 -394.54836) (xy 348.46387 -394.552678)
			)
		)
	)
	(zone
		(layers "F.Cu" "B.Cu" "In1.Cu" "In2.Cu" "In3.Cu" "In4.Cu" "In5.Cu" "In6.Cu"
			"In7.Cu" "In8.Cu" "In9.Cu" "In10.Cu" "In11.Cu" "In12.Cu" "In13.Cu" "In14.Cu"
			"In15.Cu" "In16.Cu"
		)
		(hatch none 0.5)
		(connect_pads
			(clearance 0)
		)
		(min_thickness 0.25)
		(keepout
			(tracks not_allowed)
			(vias allowed)
			(pads allowed)
			(copperpour not_allowed)
			(footprints allowed)
		)
		(placement
			(enabled no)
			(sheetname "")
		)
		(fill
			(thermal_gap 0.5)
			(thermal_bridge_width 0.5)
			(island_removal_mode 0)
		)
		(polygon
			(pts
				(arc
					(start 386.210302 -412.46552)
					(mid 385.829302 -412.84652)
					(end 386.210302 -413.22752)
				)
				(arc
					(start 387.073902 -413.22752)
					(mid 387.454902 -412.84652)
					(end 387.073902 -412.46552)
				)
			)
		)
	)
	(zone
		(layers "F.Cu" "B.Cu" "In1.Cu" "In2.Cu" "In3.Cu" "In4.Cu" "In5.Cu" "In6.Cu"
			"In7.Cu" "In8.Cu" "In9.Cu" "In10.Cu" "In11.Cu" "In12.Cu" "In13.Cu" "In14.Cu"
			"In15.Cu" "In16.Cu"
		)
		(hatch none 0.5)
		(connect_pads
			(clearance 0)
		)
		(min_thickness 0.25)
		(keepout
			(tracks not_allowed)
			(vias allowed)
			(pads allowed)
			(copperpour not_allowed)
			(footprints allowed)
		)
		(placement
			(enabled no)
			(sheetname "")
		)
		(fill
			(thermal_gap 0.5)
			(thermal_bridge_width 0.5)
			(island_removal_mode 0)
		)
		(polygon
			(pts
				(arc
					(start 181.660546 -53.954934)
					(mid 182.041546 -54.335934)
					(end 182.422546 -53.954934)
				)
				(arc
					(start 182.422546 -53.091334)
					(mid 182.041546 -52.710334)
					(end 181.660546 -53.091334)
				)
			)
		)
	)
	(zone
		(layers "F.Cu" "B.Cu" "In1.Cu" "In2.Cu" "In3.Cu" "In4.Cu" "In5.Cu" "In6.Cu"
			"In7.Cu" "In8.Cu" "In9.Cu" "In10.Cu" "In11.Cu" "In12.Cu" "In13.Cu" "In14.Cu"
			"In15.Cu" "In16.Cu"
		)
		(hatch none 0.5)
		(connect_pads
			(clearance 0)
		)
		(min_thickness 0.25)
		(keepout
			(tracks not_allowed)
			(vias allowed)
			(pads allowed)
			(copperpour not_allowed)
			(footprints allowed)
		)
		(placement
			(enabled no)
			(sheetname "")
		)
		(fill
			(thermal_gap 0.5)
			(thermal_bridge_width 0.5)
			(island_removal_mode 0)
		)
		(polygon
			(pts
				(arc
					(start 56.983884 -404.08352)
					(mid 56.602884 -404.46452)
					(end 56.983884 -404.84552)
				)
				(arc
					(start 57.847484 -404.84552)
					(mid 58.228484 -404.46452)
					(end 57.847484 -404.08352)
				)
			)
		)
	)
	(zone
		(layers "F.Cu" "B.Cu" "In1.Cu" "In2.Cu" "In3.Cu" "In4.Cu" "In5.Cu" "In6.Cu"
			"In7.Cu" "In8.Cu" "In9.Cu" "In10.Cu" "In11.Cu" "In12.Cu" "In13.Cu" "In14.Cu"
			"In15.Cu" "In16.Cu"
		)
		(hatch none 0.5)
		(connect_pads
			(clearance 0)
		)
		(min_thickness 0.25)
		(keepout
			(tracks not_allowed)
			(vias allowed)
			(pads allowed)
			(copperpour not_allowed)
			(footprints allowed)
		)
		(placement
			(enabled no)
			(sheetname "")
		)
		(fill
			(thermal_gap 0.5)
			(thermal_bridge_width 0.5)
			(island_removal_mode 0)
		)
		(polygon
			(pts
				(arc
					(start 111.816896 -368.65433)
					(mid 111.435896 -369.03533)
					(end 111.816896 -369.41633)
				)
				(arc
					(start 112.680496 -369.41633)
					(mid 113.061496 -369.03533)
					(end 112.680496 -368.65433)
				)
			)
		)
	)
	(zone
		(layers "F.Cu" "B.Cu" "In1.Cu" "In2.Cu" "In3.Cu" "In4.Cu" "In5.Cu" "In6.Cu"
			"In7.Cu" "In8.Cu" "In9.Cu" "In10.Cu" "In11.Cu" "In12.Cu" "In13.Cu" "In14.Cu"
			"In15.Cu" "In16.Cu"
		)
		(hatch none 0.5)
		(connect_pads
			(clearance 0)
		)
		(min_thickness 0.25)
		(keepout
			(tracks not_allowed)
			(vias allowed)
			(pads allowed)
			(copperpour not_allowed)
			(footprints allowed)
		)
		(placement
			(enabled no)
			(sheetname "")
		)
		(fill
			(thermal_gap 0.5)
			(thermal_bridge_width 0.5)
			(island_removal_mode 0)
		)
		(polygon
			(pts
				(arc
					(start 156.22524 -392.429238)
					(mid 155.84424 -392.048238)
					(end 155.46324 -392.429238)
				)
				(arc
					(start 155.46324 -393.292838)
					(mid 155.84424 -393.673838)
					(end 156.22524 -393.292838)
				)
			)
		)
	)
	(zone
		(layers "F.Cu" "B.Cu" "In1.Cu" "In2.Cu" "In3.Cu" "In4.Cu" "In5.Cu" "In6.Cu"
			"In7.Cu" "In8.Cu" "In9.Cu" "In10.Cu" "In11.Cu" "In12.Cu" "In13.Cu" "In14.Cu"
			"In15.Cu" "In16.Cu"
		)
		(hatch none 0.5)
		(connect_pads
			(clearance 0)
		)
		(min_thickness 0.25)
		(keepout
			(tracks not_allowed)
			(vias allowed)
			(pads allowed)
			(copperpour not_allowed)
			(footprints allowed)
		)
		(placement
			(enabled no)
			(sheetname "")
		)
		(fill
			(thermal_gap 0.5)
			(thermal_bridge_width 0.5)
			(island_removal_mode 0)
		)
		(polygon
			(pts
				(arc
					(start 216.18702 -360.764074)
					(mid 211.1629 -360.764074)
					(end 216.18702 -360.764074)
				)
			)
		)
	)
	(zone
		(layers "F.Cu" "B.Cu" "In1.Cu" "In2.Cu" "In3.Cu" "In4.Cu" "In5.Cu" "In6.Cu"
			"In7.Cu" "In8.Cu" "In9.Cu" "In10.Cu" "In11.Cu" "In12.Cu" "In13.Cu" "In14.Cu"
			"In15.Cu" "In16.Cu"
		)
		(hatch none 0.5)
		(connect_pads
			(clearance 0)
		)
		(min_thickness 0.25)
		(keepout
			(tracks not_allowed)
			(vias allowed)
			(pads allowed)
			(copperpour not_allowed)
			(footprints allowed)
		)
		(placement
			(enabled no)
			(sheetname "")
		)
		(fill
			(thermal_gap 0.5)
			(thermal_bridge_width 0.5)
			(island_removal_mode 0)
		)
		(polygon
			(pts
				(arc
					(start 142.384526 -25.90419)
					(mid 142.003526 -25.52319)
					(end 141.622526 -25.90419)
				)
				(arc
					(start 141.622526 -26.76779)
					(mid 142.003526 -27.14879)
					(end 142.384526 -26.76779)
				)
			)
		)
	)
	(zone
		(layers "F.Cu" "B.Cu" "In1.Cu" "In2.Cu" "In3.Cu" "In4.Cu" "In5.Cu" "In6.Cu"
			"In7.Cu" "In8.Cu" "In9.Cu" "In10.Cu" "In11.Cu" "In12.Cu" "In13.Cu" "In14.Cu"
			"In15.Cu" "In16.Cu"
		)
		(hatch none 0.5)
		(connect_pads
			(clearance 0)
		)
		(min_thickness 0.25)
		(keepout
			(tracks not_allowed)
			(vias allowed)
			(pads allowed)
			(copperpour not_allowed)
			(footprints allowed)
		)
		(placement
			(enabled no)
			(sheetname "")
		)
		(fill
			(thermal_gap 0.5)
			(thermal_bridge_width 0.5)
			(island_removal_mode 0)
		)
		(polygon
			(pts
				(arc
					(start 391.642092 -377.03633)
					(mid 391.261092 -377.41733)
					(end 391.642092 -377.79833)
				)
				(arc
					(start 392.505692 -377.79833)
					(mid 392.886692 -377.41733)
					(end 392.505692 -377.03633)
				)
			)
		)
	)
	(zone
		(layers "F.Cu" "B.Cu" "In1.Cu" "In2.Cu" "In3.Cu" "In4.Cu" "In5.Cu" "In6.Cu"
			"In7.Cu" "In8.Cu" "In9.Cu" "In10.Cu" "In11.Cu" "In12.Cu" "In13.Cu" "In14.Cu"
			"In15.Cu" "In16.Cu"
		)
		(hatch none 0.5)
		(connect_pads
			(clearance 0)
		)
		(min_thickness 0.25)
		(keepout
			(tracks not_allowed)
			(vias allowed)
			(pads allowed)
			(copperpour not_allowed)
			(footprints allowed)
		)
		(placement
			(enabled no)
			(sheetname "")
		)
		(fill yes
			(thermal_gap 0.5)
			(thermal_bridge_width 0.5)
			(island_removal_mode 0)
		)
		(polygon
			(pts
				(arc
					(start 377.036584 -394.552424)
					(mid 377.146555 -394.653478)
					(end 377.291346 -394.690092)
				)
				(arc
					(start 377.291346 -394.690092)
					(mid 377.506872 -394.600818)
					(end 377.596146 -394.385292)
				)
				(arc
					(start 377.596146 -394.385292)
					(mid 377.585809 -394.306553)
					(end 377.555506 -394.233146)
				)
				(arc
					(start 377.163076 -393.554204)
					(mid 377.050679 -393.432587)
					(end 376.891296 -393.38758)
				)
				(arc
					(start 376.891296 -393.38758)
					(mid 376.67577 -393.476854)
					(end 376.586496 -393.69238)
				)
				(arc
					(start 376.586496 -393.69238)
					(mid 376.596074 -393.768442)
					(end 376.624342 -393.8397)
				)
				(xy 377.021598 -394.527024) (xy 377.03379 -394.54836) (xy 377.03633 -394.552678)
			)
		)
	)
	(zone
		(layers "F.Cu" "B.Cu" "In1.Cu" "In2.Cu" "In3.Cu" "In4.Cu" "In5.Cu" "In6.Cu"
			"In7.Cu" "In8.Cu" "In9.Cu" "In10.Cu" "In11.Cu" "In12.Cu" "In13.Cu" "In14.Cu"
			"In15.Cu" "In16.Cu"
		)
		(hatch none 0.5)
		(connect_pads
			(clearance 0)
		)
		(min_thickness 0.25)
		(keepout
			(tracks not_allowed)
			(vias allowed)
			(pads allowed)
			(copperpour not_allowed)
			(footprints allowed)
		)
		(placement
			(enabled no)
			(sheetname "")
		)
		(fill
			(thermal_gap 0.5)
			(thermal_bridge_width 0.5)
			(island_removal_mode 0)
		)
		(polygon
			(pts
				(arc
					(start 364.91164 -384.35026)
					(mid 364.53064 -383.96926)
					(end 364.14964 -384.35026)
				)
				(arc
					(start 364.14964 -385.21386)
					(mid 364.53064 -385.59486)
					(end 364.91164 -385.21386)
				)
			)
		)
	)
	(zone
		(layers "F.Cu" "B.Cu" "In1.Cu" "In2.Cu" "In3.Cu" "In4.Cu" "In5.Cu" "In6.Cu"
			"In7.Cu" "In8.Cu" "In9.Cu" "In10.Cu" "In11.Cu" "In12.Cu" "In13.Cu" "In14.Cu"
			"In15.Cu" "In16.Cu"
		)
		(hatch none 0.5)
		(connect_pads
			(clearance 0)
		)
		(min_thickness 0.25)
		(keepout
			(tracks not_allowed)
			(vias allowed)
			(pads allowed)
			(copperpour not_allowed)
			(footprints allowed)
		)
		(placement
			(enabled no)
			(sheetname "")
		)
		(fill
			(thermal_gap 0.5)
			(thermal_bridge_width 0.5)
			(island_removal_mode 0)
		)
		(polygon
			(pts
				(arc
					(start 410.55544 -381.96393)
					(mid 410.17444 -382.34493)
					(end 410.55544 -382.72593)
				)
				(arc
					(start 411.41904 -382.72593)
					(mid 411.80004 -382.34493)
					(end 411.41904 -381.96393)
				)
			)
		)
	)
	(zone
		(layers "F.Cu" "B.Cu" "In1.Cu" "In2.Cu" "In3.Cu" "In4.Cu" "In5.Cu" "In6.Cu"
			"In7.Cu" "In8.Cu" "In9.Cu" "In10.Cu" "In11.Cu" "In12.Cu" "In13.Cu" "In14.Cu"
			"In15.Cu" "In16.Cu"
		)
		(hatch none 0.5)
		(connect_pads
			(clearance 0)
		)
		(min_thickness 0.25)
		(keepout
			(tracks not_allowed)
			(vias allowed)
			(pads allowed)
			(copperpour not_allowed)
			(footprints allowed)
		)
		(placement
			(enabled no)
			(sheetname "")
		)
		(fill
			(thermal_gap 0.5)
			(thermal_bridge_width 0.5)
			(island_removal_mode 0)
		)
		(polygon
			(pts
				(arc
					(start 130.61696 -24.294084)
					(mid 130.23596 -24.675084)
					(end 130.61696 -25.056084)
				)
				(arc
					(start 131.48056 -25.056084)
					(mid 131.86156 -24.675084)
					(end 131.48056 -24.294084)
				)
			)
		)
	)
	(zone
		(layers "F.Cu" "B.Cu" "In1.Cu" "In2.Cu" "In3.Cu" "In4.Cu" "In5.Cu" "In6.Cu"
			"In7.Cu" "In8.Cu" "In9.Cu" "In10.Cu" "In11.Cu" "In12.Cu" "In13.Cu" "In14.Cu"
			"In15.Cu" "In16.Cu"
		)
		(hatch none 0.5)
		(connect_pads
			(clearance 0)
		)
		(min_thickness 0.25)
		(keepout
			(tracks not_allowed)
			(vias allowed)
			(pads allowed)
			(copperpour not_allowed)
			(footprints allowed)
		)
		(placement
			(enabled no)
			(sheetname "")
		)
		(fill
			(thermal_gap 0.5)
			(thermal_bridge_width 0.5)
			(island_removal_mode 0)
		)
		(polygon
			(pts
				(arc
					(start 40.007794 -423.019982)
					(mid 40.388794 -422.638982)
					(end 40.007794 -422.257982)
				)
				(arc
					(start 39.144194 -422.257982)
					(mid 38.763194 -422.638982)
					(end 39.144194 -423.019982)
				)
			)
		)
	)
	(zone
		(layers "F.Cu" "B.Cu" "In1.Cu" "In2.Cu" "In3.Cu" "In4.Cu" "In5.Cu" "In6.Cu"
			"In7.Cu" "In8.Cu" "In9.Cu" "In10.Cu" "In11.Cu" "In12.Cu" "In13.Cu" "In14.Cu"
			"In15.Cu" "In16.Cu"
		)
		(hatch none 0.5)
		(connect_pads
			(clearance 0)
		)
		(min_thickness 0.25)
		(keepout
			(tracks not_allowed)
			(vias allowed)
			(pads allowed)
			(copperpour not_allowed)
			(footprints allowed)
		)
		(placement
			(enabled no)
			(sheetname "")
		)
		(fill yes
			(thermal_gap 0.5)
			(thermal_bridge_width 0.5)
			(island_removal_mode 0)
		)
		(polygon
			(pts
				(arc
					(start 57.536588 -386.170424)
					(mid 57.646559 -386.271478)
					(end 57.79135 -386.308092)
				)
				(arc
					(start 57.79135 -386.308092)
					(mid 58.006876 -386.218818)
					(end 58.09615 -386.003292)
				)
				(arc
					(start 58.09615 -386.003292)
					(mid 58.085813 -385.924553)
					(end 58.05551 -385.851146)
				)
				(arc
					(start 57.66308 -385.172204)
					(mid 57.550683 -385.050587)
					(end 57.3913 -385.00558)
				)
				(arc
					(start 57.3913 -385.00558)
					(mid 57.175774 -385.094854)
					(end 57.0865 -385.31038)
				)
				(arc
					(start 57.0865 -385.31038)
					(mid 57.096078 -385.386442)
					(end 57.124346 -385.4577)
				)
				(xy 57.521602 -386.145024) (xy 57.533794 -386.16636) (xy 57.536334 -386.170678)
			)
		)
	)
	(zone
		(layers "F.Cu" "B.Cu" "In1.Cu" "In2.Cu" "In3.Cu" "In4.Cu" "In5.Cu" "In6.Cu"
			"In7.Cu" "In8.Cu" "In9.Cu" "In10.Cu" "In11.Cu" "In12.Cu" "In13.Cu" "In14.Cu"
			"In15.Cu" "In16.Cu"
		)
		(hatch none 0.5)
		(connect_pads
			(clearance 0)
		)
		(min_thickness 0.25)
		(keepout
			(tracks not_allowed)
			(vias allowed)
			(pads allowed)
			(copperpour not_allowed)
			(footprints allowed)
		)
		(placement
			(enabled no)
			(sheetname "")
		)
		(fill
			(thermal_gap 0.5)
			(thermal_bridge_width 0.5)
			(island_removal_mode 0)
		)
		(polygon
			(pts
				(arc
					(start 68.542154 -368.65433)
					(mid 68.161154 -369.03533)
					(end 68.542154 -369.41633)
				)
				(arc
					(start 69.405754 -369.41633)
					(mid 69.786754 -369.03533)
					(end 69.405754 -368.65433)
				)
			)
		)
	)
	(zone
		(layers "F.Cu" "B.Cu" "In1.Cu" "In2.Cu" "In3.Cu" "In4.Cu" "In5.Cu" "In6.Cu"
			"In7.Cu" "In8.Cu" "In9.Cu" "In10.Cu" "In11.Cu" "In12.Cu" "In13.Cu" "In14.Cu"
			"In15.Cu" "In16.Cu"
		)
		(hatch none 0.5)
		(connect_pads
			(clearance 0)
		)
		(min_thickness 0.25)
		(keepout
			(tracks not_allowed)
			(vias allowed)
			(pads allowed)
			(copperpour not_allowed)
			(footprints allowed)
		)
		(placement
			(enabled no)
			(sheetname "")
		)
		(fill
			(thermal_gap 0.5)
			(thermal_bridge_width 0.5)
			(island_removal_mode 0)
		)
		(polygon
			(pts
				(arc
					(start 72.141842 -421.760396)
					(mid 72.16416 -421.814278)
					(end 72.218042 -421.836596)
				)
				(arc
					(start 73.157842 -421.836596)
					(mid 73.211724 -421.814278)
					(end 73.234042 -421.760396)
				)
				(arc
					(start 73.234042 -419.218872)
					(mid 73.211724 -419.16499)
					(end 73.157842 -419.142672)
				)
				(arc
					(start 72.218042 -419.142672)
					(mid 72.16416 -419.16499)
					(end 72.141842 -419.218872)
				)
			)
		)
	)
	(zone
		(layers "F.Cu" "B.Cu" "In1.Cu" "In2.Cu" "In3.Cu" "In4.Cu" "In5.Cu" "In6.Cu"
			"In7.Cu" "In8.Cu" "In9.Cu" "In10.Cu" "In11.Cu" "In12.Cu" "In13.Cu" "In14.Cu"
			"In15.Cu" "In16.Cu"
		)
		(hatch none 0.5)
		(connect_pads
			(clearance 0)
		)
		(min_thickness 0.25)
		(keepout
			(tracks not_allowed)
			(vias allowed)
			(pads allowed)
			(copperpour not_allowed)
			(footprints allowed)
		)
		(placement
			(enabled no)
			(sheetname "")
		)
		(fill
			(thermal_gap 0.5)
			(thermal_bridge_width 0.5)
			(island_removal_mode 0)
		)
		(polygon
			(pts
				(arc
					(start 406.796748 -17.232122)
					(mid 406.415748 -17.613122)
					(end 406.796748 -17.994122)
				)
				(arc
					(start 407.660348 -17.994122)
					(mid 408.041348 -17.613122)
					(end 407.660348 -17.232122)
				)
			)
		)
	)
	(zone
		(layers "F.Cu" "B.Cu" "In1.Cu" "In2.Cu" "In3.Cu" "In4.Cu" "In5.Cu" "In6.Cu"
			"In7.Cu" "In8.Cu" "In9.Cu" "In10.Cu" "In11.Cu" "In12.Cu" "In13.Cu" "In14.Cu"
			"In15.Cu" "In16.Cu"
		)
		(hatch none 0.5)
		(connect_pads
			(clearance 0)
		)
		(min_thickness 0.25)
		(keepout
			(tracks not_allowed)
			(vias allowed)
			(pads allowed)
			(copperpour not_allowed)
			(footprints allowed)
		)
		(placement
			(enabled no)
			(sheetname "")
		)
		(fill
			(thermal_gap 0.5)
			(thermal_bridge_width 0.5)
			(island_removal_mode 0)
		)
		(polygon
			(pts
				(arc
					(start 331.78242 -304.780188)
					(mid 326.753728 -304.780188)
					(end 331.78242 -304.780188)
				)
			)
		)
	)
	(zone
		(layers "F.Cu" "B.Cu" "In1.Cu" "In2.Cu" "In3.Cu" "In4.Cu" "In5.Cu" "In6.Cu"
			"In7.Cu" "In8.Cu" "In9.Cu" "In10.Cu" "In11.Cu" "In12.Cu" "In13.Cu" "In14.Cu"
			"In15.Cu" "In16.Cu"
		)
		(hatch none 0.5)
		(connect_pads
			(clearance 0)
		)
		(min_thickness 0.25)
		(keepout
			(tracks not_allowed)
			(vias allowed)
			(pads allowed)
			(copperpour not_allowed)
			(footprints allowed)
		)
		(placement
			(enabled no)
			(sheetname "")
		)
		(fill
			(thermal_gap 0.5)
			(thermal_bridge_width 0.5)
			(island_removal_mode 0)
		)
		(polygon
			(pts
				(arc
					(start 318.59728 -400.811238)
					(mid 318.21628 -400.430238)
					(end 317.83528 -400.811238)
				)
				(arc
					(start 317.83528 -401.674838)
					(mid 318.21628 -402.055838)
					(end 318.59728 -401.674838)
				)
			)
		)
	)
	(zone
		(layers "F.Cu" "B.Cu" "In1.Cu" "In2.Cu" "In3.Cu" "In4.Cu" "In5.Cu" "In6.Cu"
			"In7.Cu" "In8.Cu" "In9.Cu" "In10.Cu" "In11.Cu" "In12.Cu" "In13.Cu" "In14.Cu"
			"In15.Cu" "In16.Cu"
		)
		(hatch none 0.5)
		(connect_pads
			(clearance 0)
		)
		(min_thickness 0.25)
		(keepout
			(tracks not_allowed)
			(vias allowed)
			(pads allowed)
			(copperpour not_allowed)
			(footprints allowed)
		)
		(placement
			(enabled no)
			(sheetname "")
		)
		(fill
			(thermal_gap 0.5)
			(thermal_bridge_width 0.5)
			(island_removal_mode 0)
		)
		(polygon
			(pts
				(arc
					(start 92.725494 -392.429238)
					(mid 92.344494 -392.048238)
					(end 91.963494 -392.429238)
				)
				(arc
					(start 91.963494 -393.292838)
					(mid 92.344494 -393.673838)
					(end 92.725494 -393.292838)
				)
			)
		)
	)
	(zone
		(layers "F.Cu" "B.Cu" "In1.Cu" "In2.Cu" "In3.Cu" "In4.Cu" "In5.Cu" "In6.Cu"
			"In7.Cu" "In8.Cu" "In9.Cu" "In10.Cu" "In11.Cu" "In12.Cu" "In13.Cu" "In14.Cu"
			"In15.Cu" "In16.Cu"
		)
		(hatch none 0.5)
		(connect_pads
			(clearance 0)
		)
		(min_thickness 0.25)
		(keepout
			(tracks not_allowed)
			(vias allowed)
			(pads allowed)
			(copperpour not_allowed)
			(footprints allowed)
		)
		(placement
			(enabled no)
			(sheetname "")
		)
		(fill
			(thermal_gap 0.5)
			(thermal_bridge_width 0.5)
			(island_removal_mode 0)
		)
		(polygon
			(pts
				(arc
					(start 312.597292 -400.811238)
					(mid 312.216292 -400.430238)
					(end 311.835292 -400.811238)
				)
				(arc
					(start 311.835292 -401.674838)
					(mid 312.216292 -402.055838)
					(end 312.597292 -401.674838)
				)
			)
		)
	)
	(zone
		(layers "F.Cu" "B.Cu" "In1.Cu" "In2.Cu" "In3.Cu" "In4.Cu" "In5.Cu" "In6.Cu"
			"In7.Cu" "In8.Cu" "In9.Cu" "In10.Cu" "In11.Cu" "In12.Cu" "In13.Cu" "In14.Cu"
			"In15.Cu" "In16.Cu"
		)
		(hatch none 0.5)
		(connect_pads
			(clearance 0)
		)
		(min_thickness 0.25)
		(keepout
			(tracks not_allowed)
			(vias allowed)
			(pads allowed)
			(copperpour not_allowed)
			(footprints allowed)
		)
		(placement
			(enabled no)
			(sheetname "")
		)
		(fill
			(thermal_gap 0.5)
			(thermal_bridge_width 0.5)
			(island_removal_mode 0)
		)
		(polygon
			(pts
				(arc
					(start 119.488966 -409.649168)
					(mid 119.107966 -410.030168)
					(end 119.488966 -410.411168)
				)
				(arc
					(start 120.352566 -410.411168)
					(mid 120.733566 -410.030168)
					(end 120.352566 -409.649168)
				)
			)
		)
	)
	(zone
		(layers "F.Cu" "B.Cu" "In1.Cu" "In2.Cu" "In3.Cu" "In4.Cu" "In5.Cu" "In6.Cu"
			"In7.Cu" "In8.Cu" "In9.Cu" "In10.Cu" "In11.Cu" "In12.Cu" "In13.Cu" "In14.Cu"
			"In15.Cu" "In16.Cu"
		)
		(hatch none 0.5)
		(connect_pads
			(clearance 0)
		)
		(min_thickness 0.25)
		(keepout
			(tracks not_allowed)
			(vias allowed)
			(pads allowed)
			(copperpour not_allowed)
			(footprints allowed)
		)
		(placement
			(enabled no)
			(sheetname "")
		)
		(fill yes
			(thermal_gap 0.5)
			(thermal_bridge_width 0.5)
			(island_removal_mode 0)
		)
		(polygon
			(pts
				(arc
					(start 92.464382 -386.170424)
					(mid 92.574353 -386.271478)
					(end 92.719144 -386.308092)
				)
				(arc
					(start 92.719144 -386.308092)
					(mid 92.93467 -386.218818)
					(end 93.023944 -386.003292)
				)
				(arc
					(start 93.023944 -386.003292)
					(mid 93.013607 -385.924553)
					(end 92.983304 -385.851146)
				)
				(arc
					(start 92.590874 -385.172204)
					(mid 92.478477 -385.050587)
					(end 92.319094 -385.00558)
				)
				(arc
					(start 92.319094 -385.00558)
					(mid 92.103568 -385.094854)
					(end 92.014294 -385.31038)
				)
				(arc
					(start 92.014294 -385.31038)
					(mid 92.023872 -385.386442)
					(end 92.05214 -385.4577)
				)
				(xy 92.449396 -386.145024) (xy 92.461588 -386.16636) (xy 92.464128 -386.170678)
			)
		)
	)
	(zone
		(layers "F.Cu" "B.Cu" "In1.Cu" "In2.Cu" "In3.Cu" "In4.Cu" "In5.Cu" "In6.Cu"
			"In7.Cu" "In8.Cu" "In9.Cu" "In10.Cu" "In11.Cu" "In12.Cu" "In13.Cu" "In14.Cu"
			"In15.Cu" "In16.Cu"
		)
		(hatch none 0.5)
		(connect_pads
			(clearance 0)
		)
		(min_thickness 0.25)
		(keepout
			(tracks not_allowed)
			(vias allowed)
			(pads allowed)
			(copperpour not_allowed)
			(footprints allowed)
		)
		(placement
			(enabled no)
			(sheetname "")
		)
		(fill
			(thermal_gap 0.5)
			(thermal_bridge_width 0.5)
			(island_removal_mode 0)
		)
		(polygon
			(pts
				(arc
					(start 364.380272 -2.968244)
					(mid 364.812072 -3.400044)
					(end 365.243872 -2.968244)
				)
				(arc
					(start 365.243872 -2.104644)
					(mid 364.812072 -1.672844)
					(end 364.380272 -2.104644)
				)
			)
		)
	)
	(zone
		(layers "F.Cu" "B.Cu" "In1.Cu" "In2.Cu" "In3.Cu" "In4.Cu" "In5.Cu" "In6.Cu"
			"In7.Cu" "In8.Cu" "In9.Cu" "In10.Cu" "In11.Cu" "In12.Cu" "In13.Cu" "In14.Cu"
			"In15.Cu" "In16.Cu"
		)
		(hatch none 0.5)
		(connect_pads
			(clearance 0)
		)
		(min_thickness 0.25)
		(keepout
			(tracks not_allowed)
			(vias allowed)
			(pads allowed)
			(copperpour not_allowed)
			(footprints allowed)
		)
		(placement
			(enabled no)
			(sheetname "")
		)
		(fill
			(thermal_gap 0.5)
			(thermal_bridge_width 0.5)
			(island_removal_mode 0)
		)
		(polygon
			(pts
				(arc
					(start 23.915878 -18.75536)
					(mid 23.534878 -19.13636)
					(end 23.915878 -19.51736)
				)
				(arc
					(start 24.779478 -19.51736)
					(mid 25.160478 -19.13636)
					(end 24.779478 -18.75536)
				)
			)
		)
	)
	(zone
		(layers "F.Cu" "B.Cu" "In1.Cu" "In2.Cu" "In3.Cu" "In4.Cu" "In5.Cu" "In6.Cu"
			"In7.Cu" "In8.Cu" "In9.Cu" "In10.Cu" "In11.Cu" "In12.Cu" "In13.Cu" "In14.Cu"
			"In15.Cu" "In16.Cu"
		)
		(hatch none 0.5)
		(connect_pads
			(clearance 0)
		)
		(min_thickness 0.25)
		(keepout
			(tracks not_allowed)
			(vias allowed)
			(pads allowed)
			(copperpour not_allowed)
			(footprints allowed)
		)
		(placement
			(enabled no)
			(sheetname "")
		)
		(fill
			(thermal_gap 0.5)
			(thermal_bridge_width 0.5)
			(island_removal_mode 0)
		)
		(polygon
			(pts
				(arc
					(start 372.236492 -398.016476)
					(mid 372.346463 -398.11753)
					(end 372.491254 -398.154144)
				)
				(arc
					(start 372.491254 -398.154144)
					(mid 372.70678 -398.06487)
					(end 372.796054 -397.849344)
				)
				(arc
					(start 372.796054 -397.849344)
					(mid 372.785717 -397.770605)
					(end 372.755414 -397.697198)
				)
				(arc
					(start 372.362984 -397.018256)
					(mid 372.250587 -396.896639)
					(end 372.091204 -396.851632)
				)
				(arc
					(start 372.091204 -396.851632)
					(mid 371.875678 -396.940906)
					(end 371.786404 -397.156432)
				)
				(arc
					(start 371.786404 -397.156432)
					(mid 371.795982 -397.232494)
					(end 371.82425 -397.303752)
				)
				(xy 372.221506 -397.991076) (xy 372.233698 -398.012412) (xy 372.236238 -398.01673)
			)
		)
	)
	(zone
		(layers "F.Cu" "B.Cu" "In1.Cu" "In2.Cu" "In3.Cu" "In4.Cu" "In5.Cu" "In6.Cu"
			"In7.Cu" "In8.Cu" "In9.Cu" "In10.Cu" "In11.Cu" "In12.Cu" "In13.Cu" "In14.Cu"
			"In15.Cu" "In16.Cu"
		)
		(hatch none 0.5)
		(connect_pads
			(clearance 0)
		)
		(min_thickness 0.25)
		(keepout
			(tracks not_allowed)
			(vias allowed)
			(pads allowed)
			(copperpour not_allowed)
			(footprints allowed)
		)
		(placement
			(enabled no)
			(sheetname "")
		)
		(fill
			(thermal_gap 0.5)
			(thermal_bridge_width 0.5)
			(island_removal_mode 0)
		)
		(polygon
			(pts
				(arc
					(start 104.24795 -400.50847)
					(mid 103.48595 -400.50847)
					(end 104.24795 -400.50847)
				)
			)
		)
	)
	(zone
		(layers "F.Cu" "B.Cu" "In1.Cu" "In2.Cu" "In3.Cu" "In4.Cu" "In5.Cu" "In6.Cu"
			"In7.Cu" "In8.Cu" "In9.Cu" "In10.Cu" "In11.Cu" "In12.Cu" "In13.Cu" "In14.Cu"
			"In15.Cu" "In16.Cu"
		)
		(name "Package Keepin")
		(hatch none 0.5)
		(connect_pads
			(clearance 0)
		)
		(min_thickness 0.25)
		(keepout
			(tracks allowed)
			(vias allowed)
			(pads allowed)
			(copperpour allowed)
			(footprints allowed)
		)
		(placement
			(enabled no)
			(sheetname "")
		)
		(fill
			(thermal_gap 0.5)
			(thermal_bridge_width 0.5)
			(island_removal_mode 0)
		)
		(polygon
			(pts
				(arc
					(start 474.815916 -461.028288)
					(mid 475.104122 -461.724078)
					(end 475.799912 -462.012284)
				)
				(arc
					(start 531.7998 -462.012284)
					(mid 532.49559 -461.724078)
					(end 532.783796 -461.028288)
				)
				(arc
					(start 532.783796 -455.0283)
					(mid 532.49559 -454.33251)
					(end 531.7998 -454.044304)
				)
				(arc
					(start 516.019796 -454.044304)
					(mid 513.887165 -453.160939)
					(end 513.0038 -451.028308)
				)
				(arc
					(start 513.0038 -312.408316)
					(mid 513.887165 -310.275685)
					(end 516.019796 -309.39232)
				)
				(arc
					(start 531.7998 -309.39232)
					(mid 532.49559 -309.104114)
					(end 532.783796 -308.408324)
				)
				(arc
					(start 532.783796 10.40003)
					(mid 532.49559 11.09582)
					(end 531.7998 11.384026)
				)
				(arc
					(start 475.799912 11.384026)
					(mid 475.104122 11.09582)
					(end 474.815916 10.40003)
				)
				(arc
					(start 474.815916 -77.67193)
					(mid 474.434052 -79.591219)
					(end 473.34678 -81.218278)
				)
				(arc
					(start 471.60434 -82.960972)
					(mid 471.390979 -83.28015)
					(end 471.31605 -83.656678)
				)
				(arc
					(start 471.31605 -404.871936)
					(mid 470.934186 -406.791225)
					(end 469.846914 -408.418284)
				)
				(arc
					(start 468.604092 -409.661106)
					(mid 468.390917 -409.980196)
					(end 468.316056 -410.356558)
				)
				(xy 468.316056 -418.46119) (xy 464.28406 -418.46119)
				(arc
					(start 464.28406 -409.528264)
					(mid 464.513688 -408.374229)
					(end 465.167472 -407.395934)
				)
				(arc
					(start 466.996018 -405.567388)
					(mid 467.209164 -405.248298)
					(end 467.284054 -404.871936)
				)
				(arc
					(start 467.284054 -82.82813)
					(mid 467.513682 -81.674095)
					(end 468.167466 -80.6958)
				)
				(arc
					(start 470.495884 -78.367382)
					(mid 470.70903 -78.048292)
					(end 470.78392 -77.67193)
				)
				(arc
					(start 470.78392 -13.780008)
					(mid 470.495714 -13.084218)
					(end 469.799924 -12.796012)
				)
				(xy 464.44408 -12.796012) (xy 464.44408 -8.764016)
				(arc
					(start 469.799924 -8.764016)
					(mid 470.495714 -8.47581)
					(end 470.78392 -7.78002)
				)
				(arc
					(start 470.78392 10.40003)
					(mid 470.495714 11.09582)
					(end 469.799924 11.384026)
				)
				(arc
					(start 1.999996 11.384026)
					(mid 1.304206 11.09582)
					(end 1.016 10.40003)
				)
				(arc
					(start 1.016 -7.78002)
					(mid 1.304206 -8.47581)
					(end 1.999996 -8.764016)
				)
				(arc
					(start 9.10209 -8.764016)
					(mid 9.79788 -8.47581)
					(end 10.086086 -7.78002)
				)
				(arc
					(start 10.086086 0.40005)
					(mid 10.969451 2.532681)
					(end 13.102082 3.416046)
				)
				(arc
					(start 81.701894 3.416046)
					(mid 83.834525 2.532681)
					(end 84.71789 0.40005)
				)
				(arc
					(start 84.71789 -7.78002)
					(mid 85.006096 -8.47581)
					(end 85.701886 -8.764016)
				)
				(arc
					(start 122.102118 -8.764016)
					(mid 122.797908 -8.47581)
					(end 123.086114 -7.78002)
				)
				(arc
					(start 123.086114 -4.879848)
					(mid 123.969479 -2.747217)
					(end 126.10211 -1.863852)
				)
				(arc
					(start 194.701922 -1.863852)
					(mid 196.834553 -2.747217)
					(end 197.717918 -4.879848)
				)
				(arc
					(start 197.717918 -7.78002)
					(mid 198.006124 -8.47581)
					(end 198.701914 -8.764016)
				)
				(arc
					(start 223.300036 -8.764016)
					(mid 225.432667 -9.647381)
					(end 226.316032 -11.780012)
				)
				(xy 226.316032 -33.104074) (xy 255.784096 -33.104074)
				(arc
					(start 255.784096 -11.780012)
					(mid 256.667461 -9.647381)
					(end 258.800092 -8.764016)
				)
				(arc
					(start 383.601976 -8.764016)
					(mid 384.297766 -8.47581)
					(end 384.585972 -7.78002)
				)
				(arc
					(start 384.585972 0.40005)
					(mid 385.469337 2.532681)
					(end 387.601968 3.416046)
				)
				(arc
					(start 456.202034 3.416046)
					(mid 458.334665 2.532681)
					(end 459.21803 0.40005)
				)
				(arc
					(start 459.21803 -7.78002)
					(mid 459.506236 -8.47581)
					(end 460.202026 -8.764016)
				)
				(xy 464.440016 -8.764016) (xy 464.440016 -12.796012)
				(arc
					(start 458.20203 -12.796012)
					(mid 456.069399 -11.912647)
					(end 455.186034 -9.780016)
				)
				(xy 455.186034 -1.016) (xy 388.617968 -1.016)
				(arc
					(start 388.617968 -9.780016)
					(mid 387.734603 -11.912647)
					(end 385.601972 -12.796012)
				)
				(arc
					(start 260.800088 -12.796012)
					(mid 260.104298 -13.084218)
					(end 259.816092 -13.780008)
				)
				(arc
					(start 259.816092 -34.120074)
					(mid 258.932727 -36.252705)
					(end 256.800096 -37.13607)
				)
				(arc
					(start 225.300032 -37.13607)
					(mid 223.167401 -36.252705)
					(end 222.284036 -34.120074)
				)
				(arc
					(start 222.284036 -13.780008)
					(mid 221.99583 -13.084218)
					(end 221.30004 -12.796012)
				)
				(arc
					(start 196.701918 -12.796012)
					(mid 194.569287 -11.912647)
					(end 193.685922 -9.780016)
				)
				(xy 193.685922 -6.295898) (xy 127.11811 -6.295898)
				(arc
					(start 127.11811 -9.780016)
					(mid 126.234745 -11.912647)
					(end 124.102114 -12.796012)
				)
				(arc
					(start 83.70189 -12.796012)
					(mid 81.569259 -11.912647)
					(end 80.685894 -9.780016)
				)
				(xy 80.685894 -1.016) (xy 14.118082 -1.016)
				(arc
					(start 14.118082 -9.780016)
					(mid 13.234717 -11.912647)
					(end 11.102086 -12.796012)
				)
				(arc
					(start 1.999996 -12.796012)
					(mid 1.304206 -13.084218)
					(end 1.016 -13.780008)
				)
				(arc
					(start 1.016 -77.67193)
					(mid 1.090849 -78.048309)
					(end 1.304036 -78.367382)
				)
				(arc
					(start 2.132584 -79.19593)
					(mid 2.786307 -80.174251)
					(end 3.015996 -81.32826)
				)
				(arc
					(start 3.015996 -403.371812)
					(mid 3.090981 -403.748317)
					(end 3.304286 -404.067518)
				)
				(arc
					(start 6.632448 -407.39568)
					(mid 7.286434 -408.374205)
					(end 7.516114 -409.528518)
				)
				(arc
					(start 7.516114 -439.989976)
					(mid 7.80432 -440.685766)
					(end 8.50011 -440.973972)
				)
				(arc
					(start 194.001644 -440.973972)
					(mid 194.50471 -440.030753)
					(end 195.50507 -439.653934)
				)
				(arc
					(start 276.314916 -439.653934)
					(mid 277.315254 -440.030778)
					(end 277.818342 -440.973972)
				)
				(arc
					(start 463.300064 -440.973972)
					(mid 463.995854 -440.685766)
					(end 464.28406 -439.989976)
				)
				(xy 464.28406 -418.467032) (xy 468.316056 -418.467032)
				(arc
					(start 468.316056 -439.989976)
					(mid 468.604262 -440.685766)
					(end 469.300052 -440.973972)
				)
				(arc
					(start 471.79992 -440.973972)
					(mid 473.932551 -441.857337)
					(end 474.815916 -443.989968)
				)
			)
		)
	)
	(zone
		(layers "F.Cu" "B.Cu" "In1.Cu" "In2.Cu" "In3.Cu" "In4.Cu" "In5.Cu" "In6.Cu"
			"In7.Cu" "In8.Cu" "In9.Cu" "In10.Cu" "In11.Cu" "In12.Cu" "In13.Cu" "In14.Cu"
			"In15.Cu" "In16.Cu"
		)
		(hatch none 0.5)
		(connect_pads
			(clearance 0)
		)
		(min_thickness 0.25)
		(keepout
			(tracks not_allowed)
			(vias allowed)
			(pads allowed)
			(copperpour not_allowed)
			(footprints allowed)
		)
		(placement
			(enabled no)
			(sheetname "")
		)
		(fill
			(thermal_gap 0.5)
			(thermal_bridge_width 0.5)
			(island_removal_mode 0)
		)
		(polygon
			(pts
				(arc
					(start 418.830252 -4.582414)
					(mid 418.449252 -4.963414)
					(end 418.830252 -5.344414)
				)
				(arc
					(start 419.693852 -5.344414)
					(mid 420.074852 -4.963414)
					(end 419.693852 -4.582414)
				)
			)
		)
	)
	(zone
		(layers "F.Cu" "B.Cu" "In1.Cu" "In2.Cu" "In3.Cu" "In4.Cu" "In5.Cu" "In6.Cu"
			"In7.Cu" "In8.Cu" "In9.Cu" "In10.Cu" "In11.Cu" "In12.Cu" "In13.Cu" "In14.Cu"
			"In15.Cu" "In16.Cu"
		)
		(hatch none 0.5)
		(connect_pads
			(clearance 0)
		)
		(min_thickness 0.25)
		(keepout
			(tracks not_allowed)
			(vias allowed)
			(pads allowed)
			(copperpour not_allowed)
			(footprints allowed)
		)
		(placement
			(enabled no)
			(sheetname "")
		)
		(fill
			(thermal_gap 0.5)
			(thermal_bridge_width 0.5)
			(island_removal_mode 0)
		)
		(polygon
			(pts
				(arc
					(start 218.679268 -83.656932)
					(mid 218.298268 -84.037932)
					(end 218.679268 -84.418932)
				)
				(arc
					(start 219.542868 -84.418932)
					(mid 219.923868 -84.037932)
					(end 219.542868 -83.656932)
				)
			)
		)
	)
	(zone
		(layers "F.Cu" "B.Cu" "In1.Cu" "In2.Cu" "In3.Cu" "In4.Cu" "In5.Cu" "In6.Cu"
			"In7.Cu" "In8.Cu" "In9.Cu" "In10.Cu" "In11.Cu" "In12.Cu" "In13.Cu" "In14.Cu"
			"In15.Cu" "In16.Cu"
		)
		(hatch none 0.5)
		(connect_pads
			(clearance 0)
		)
		(min_thickness 0.25)
		(keepout
			(tracks not_allowed)
			(vias allowed)
			(pads allowed)
			(copperpour not_allowed)
			(footprints allowed)
		)
		(placement
			(enabled no)
			(sheetname "")
		)
		(fill
			(thermal_gap 0.5)
			(thermal_bridge_width 0.5)
			(island_removal_mode 0)
		)
		(polygon
			(pts
				(arc
					(start 392.982704 -304.780188)
					(mid 387.952996 -304.780188)
					(end 392.982704 -304.780188)
				)
			)
		)
	)
	(zone
		(layers "F.Cu" "B.Cu" "In1.Cu" "In2.Cu" "In3.Cu" "In4.Cu" "In5.Cu" "In6.Cu"
			"In7.Cu" "In8.Cu" "In9.Cu" "In10.Cu" "In11.Cu" "In12.Cu" "In13.Cu" "In14.Cu"
			"In15.Cu" "In16.Cu"
		)
		(hatch none 0.5)
		(connect_pads
			(clearance 0)
		)
		(min_thickness 0.25)
		(keepout
			(tracks not_allowed)
			(vias allowed)
			(pads allowed)
			(copperpour not_allowed)
			(footprints allowed)
		)
		(placement
			(enabled no)
			(sheetname "")
		)
		(fill
			(thermal_gap 0.5)
			(thermal_bridge_width 0.5)
			(island_removal_mode 0)
		)
		(polygon
			(pts
				(arc
					(start 157.779466 -404.08352)
					(mid 157.398466 -404.46452)
					(end 157.779466 -404.84552)
				)
				(arc
					(start 158.643066 -404.84552)
					(mid 159.024066 -404.46452)
					(end 158.643066 -404.08352)
				)
			)
		)
	)
	(zone
		(layers "F.Cu" "B.Cu" "In1.Cu" "In2.Cu" "In3.Cu" "In4.Cu" "In5.Cu" "In6.Cu"
			"In7.Cu" "In8.Cu" "In9.Cu" "In10.Cu" "In11.Cu" "In12.Cu" "In13.Cu" "In14.Cu"
			"In15.Cu" "In16.Cu"
		)
		(hatch none 0.5)
		(connect_pads
			(clearance 0)
		)
		(min_thickness 0.25)
		(keepout
			(tracks not_allowed)
			(vias allowed)
			(pads allowed)
			(copperpour not_allowed)
			(footprints allowed)
		)
		(placement
			(enabled no)
			(sheetname "")
		)
		(fill
			(thermal_gap 0.5)
			(thermal_bridge_width 0.5)
			(island_removal_mode 0)
		)
		(polygon
			(pts
				(arc
					(start 416.764216 -398.016476)
					(mid 416.874187 -398.11753)
					(end 417.018978 -398.154144)
				)
				(arc
					(start 417.018978 -398.154144)
					(mid 417.234504 -398.06487)
					(end 417.323778 -397.849344)
				)
				(arc
					(start 417.323778 -397.849344)
					(mid 417.313441 -397.770605)
					(end 417.283138 -397.697198)
				)
				(arc
					(start 416.890708 -397.018256)
					(mid 416.778311 -396.896639)
					(end 416.618928 -396.851632)
				)
				(arc
					(start 416.618928 -396.851632)
					(mid 416.403402 -396.940906)
					(end 416.314128 -397.156432)
				)
				(arc
					(start 416.314128 -397.156432)
					(mid 416.323706 -397.232494)
					(end 416.351974 -397.303752)
				)
				(xy 416.74923 -397.991076) (xy 416.761422 -398.012412) (xy 416.763962 -398.01673)
			)
		)
	)
	(zone
		(layers "F.Cu" "B.Cu" "In1.Cu" "In2.Cu" "In3.Cu" "In4.Cu" "In5.Cu" "In6.Cu"
			"In7.Cu" "In8.Cu" "In9.Cu" "In10.Cu" "In11.Cu" "In12.Cu" "In13.Cu" "In14.Cu"
			"In15.Cu" "In16.Cu"
		)
		(hatch none 0.5)
		(connect_pads
			(clearance 0)
		)
		(min_thickness 0.25)
		(keepout
			(tracks not_allowed)
			(vias allowed)
			(pads allowed)
			(copperpour not_allowed)
			(footprints allowed)
		)
		(placement
			(enabled no)
			(sheetname "")
		)
		(fill
			(thermal_gap 0.5)
			(thermal_bridge_width 0.5)
			(island_removal_mode 0)
		)
		(polygon
			(pts
				(arc
					(start 299.014896 -379.50013)
					(mid 298.633896 -379.88113)
					(end 299.014896 -380.26213)
				)
				(arc
					(start 299.878496 -380.26213)
					(mid 300.259496 -379.88113)
					(end 299.878496 -379.50013)
				)
			)
		)
	)
	(zone
		(layers "F.Cu" "B.Cu" "In1.Cu" "In2.Cu" "In3.Cu" "In4.Cu" "In5.Cu" "In6.Cu"
			"In7.Cu" "In8.Cu" "In9.Cu" "In10.Cu" "In11.Cu" "In12.Cu" "In13.Cu" "In14.Cu"
			"In15.Cu" "In16.Cu"
		)
		(hatch none 0.5)
		(connect_pads
			(clearance 0)
		)
		(min_thickness 0.25)
		(keepout
			(tracks not_allowed)
			(vias allowed)
			(pads allowed)
			(copperpour not_allowed)
			(footprints allowed)
		)
		(placement
			(enabled no)
			(sheetname "")
		)
		(fill yes
			(thermal_gap 0.5)
			(thermal_bridge_width 0.5)
			(island_removal_mode 0)
		)
		(polygon
			(pts
				(arc
					(start 161.964116 -386.170424)
					(mid 162.074087 -386.271478)
					(end 162.218878 -386.308092)
				)
				(arc
					(start 162.218878 -386.308092)
					(mid 162.434404 -386.218818)
					(end 162.523678 -386.003292)
				)
				(arc
					(start 162.523678 -386.003292)
					(mid 162.513341 -385.924553)
					(end 162.483038 -385.851146)
				)
				(arc
					(start 162.090608 -385.172204)
					(mid 161.978211 -385.050587)
					(end 161.818828 -385.00558)
				)
				(arc
					(start 161.818828 -385.00558)
					(mid 161.603302 -385.094854)
					(end 161.514028 -385.31038)
				)
				(arc
					(start 161.514028 -385.31038)
					(mid 161.523606 -385.386442)
					(end 161.551874 -385.4577)
				)
				(xy 161.94913 -386.145024) (xy 161.961322 -386.16636) (xy 161.963862 -386.170678)
			)
		)
	)
	(zone
		(layers "F.Cu" "B.Cu" "In1.Cu" "In2.Cu" "In3.Cu" "In4.Cu" "In5.Cu" "In6.Cu"
			"In7.Cu" "In8.Cu" "In9.Cu" "In10.Cu" "In11.Cu" "In12.Cu" "In13.Cu" "In14.Cu"
			"In15.Cu" "In16.Cu"
		)
		(hatch none 0.5)
		(connect_pads
			(clearance 0)
		)
		(min_thickness 0.25)
		(keepout
			(tracks not_allowed)
			(vias allowed)
			(pads allowed)
			(copperpour not_allowed)
			(footprints allowed)
		)
		(placement
			(enabled no)
			(sheetname "")
		)
		(fill
			(thermal_gap 0.5)
			(thermal_bridge_width 0.5)
			(island_removal_mode 0)
		)
		(polygon
			(pts
				(arc
					(start 136.4361 -22.747478)
					(mid 136.436227 -23.286085)
					(end 136.974834 -23.286212)
				)
				(arc
					(start 137.585704 -22.675596)
					(mid 137.668238 -22.551936)
					(end 137.69721 -22.406102)
				)
				(arc
					(start 137.69721 -22.406102)
					(mid 137.585618 -22.136694)
					(end 137.31621 -22.025102)
				)
				(arc
					(start 137.31621 -22.025102)
					(mid 137.170354 -22.054021)
					(end 137.046716 -22.136608)
				)
			)
		)
	)
	(zone
		(layers "F.Cu" "B.Cu" "In1.Cu" "In2.Cu" "In3.Cu" "In4.Cu" "In5.Cu" "In6.Cu"
			"In7.Cu" "In8.Cu" "In9.Cu" "In10.Cu" "In11.Cu" "In12.Cu" "In13.Cu" "In14.Cu"
			"In15.Cu" "In16.Cu"
		)
		(hatch none 0.5)
		(connect_pads
			(clearance 0)
		)
		(min_thickness 0.25)
		(keepout
			(tracks not_allowed)
			(vias allowed)
			(pads allowed)
			(copperpour not_allowed)
			(footprints allowed)
		)
		(placement
			(enabled no)
			(sheetname "")
		)
		(fill
			(thermal_gap 0.5)
			(thermal_bridge_width 0.5)
			(island_removal_mode 0)
		)
		(polygon
			(pts
				(arc
					(start 118.8974 -392.429238)
					(mid 118.5164 -392.048238)
					(end 118.1354 -392.429238)
				)
				(arc
					(start 118.1354 -393.292838)
					(mid 118.5164 -393.673838)
					(end 118.8974 -393.292838)
				)
			)
		)
	)
	(zone
		(layers "F.Cu" "B.Cu" "In1.Cu" "In2.Cu" "In3.Cu" "In4.Cu" "In5.Cu" "In6.Cu"
			"In7.Cu" "In8.Cu" "In9.Cu" "In10.Cu" "In11.Cu" "In12.Cu" "In13.Cu" "In14.Cu"
			"In15.Cu" "In16.Cu"
		)
		(hatch none 0.5)
		(connect_pads
			(clearance 0)
		)
		(min_thickness 0.25)
		(keepout
			(tracks not_allowed)
			(vias allowed)
			(pads allowed)
			(copperpour not_allowed)
			(footprints allowed)
		)
		(placement
			(enabled no)
			(sheetname "")
		)
		(fill
			(thermal_gap 0.5)
			(thermal_bridge_width 0.5)
			(island_removal_mode 0)
		)
		(polygon
			(pts
				(arc
					(start 255.546098 -205.439772)
					(mid 255.927098 -205.820772)
					(end 256.308098 -205.439772)
				)
				(arc
					(start 256.308098 -204.576172)
					(mid 255.927098 -204.195172)
					(end 255.546098 -204.576172)
				)
			)
		)
	)
	(zone
		(layers "F.Cu" "B.Cu" "In1.Cu" "In2.Cu" "In3.Cu" "In4.Cu" "In5.Cu" "In6.Cu"
			"In7.Cu" "In8.Cu" "In9.Cu" "In10.Cu" "In11.Cu" "In12.Cu" "In13.Cu" "In14.Cu"
			"In15.Cu" "In16.Cu"
		)
		(hatch none 0.5)
		(connect_pads
			(clearance 0)
		)
		(min_thickness 0.25)
		(keepout
			(tracks not_allowed)
			(vias allowed)
			(pads allowed)
			(copperpour not_allowed)
			(footprints allowed)
		)
		(placement
			(enabled no)
			(sheetname "")
		)
		(fill
			(thermal_gap 0.5)
			(thermal_bridge_width 0.5)
			(island_removal_mode 0)
		)
		(polygon
			(pts
				(arc
					(start 13.2715 -39.1668)
					(mid 9.0805 -39.1668)
					(end 13.2715 -39.1668)
				)
			)
		)
	)
	(zone
		(layers "F.Cu" "B.Cu" "In1.Cu" "In2.Cu" "In3.Cu" "In4.Cu" "In5.Cu" "In6.Cu"
			"In7.Cu" "In8.Cu" "In9.Cu" "In10.Cu" "In11.Cu" "In12.Cu" "In13.Cu" "In14.Cu"
			"In15.Cu" "In16.Cu"
		)
		(hatch none 0.5)
		(connect_pads
			(clearance 0)
		)
		(min_thickness 0.25)
		(keepout
			(tracks not_allowed)
			(vias allowed)
			(pads allowed)
			(copperpour not_allowed)
			(footprints allowed)
		)
		(placement
			(enabled no)
			(sheetname "")
		)
		(fill
			(thermal_gap 0.5)
			(thermal_bridge_width 0.5)
			(island_removal_mode 0)
		)
		(polygon
			(pts
				(arc
					(start 386.636514 -398.016476)
					(mid 386.746485 -398.11753)
					(end 386.891276 -398.154144)
				)
				(arc
					(start 386.891276 -398.154144)
					(mid 387.106802 -398.06487)
					(end 387.196076 -397.849344)
				)
				(arc
					(start 387.196076 -397.849344)
					(mid 387.185739 -397.770605)
					(end 387.155436 -397.697198)
				)
				(arc
					(start 386.763006 -397.018256)
					(mid 386.650609 -396.896639)
					(end 386.491226 -396.851632)
				)
				(arc
					(start 386.491226 -396.851632)
					(mid 386.2757 -396.940906)
					(end 386.186426 -397.156432)
				)
				(arc
					(start 386.186426 -397.156432)
					(mid 386.196004 -397.232494)
					(end 386.224272 -397.303752)
				)
				(xy 386.621528 -397.991076) (xy 386.63372 -398.012412) (xy 386.63626 -398.01673)
			)
		)
	)
	(zone
		(layers "F.Cu" "B.Cu" "In1.Cu" "In2.Cu" "In3.Cu" "In4.Cu" "In5.Cu" "In6.Cu"
			"In7.Cu" "In8.Cu" "In9.Cu" "In10.Cu" "In11.Cu" "In12.Cu" "In13.Cu" "In14.Cu"
			"In15.Cu" "In16.Cu"
		)
		(hatch none 0.5)
		(connect_pads
			(clearance 0)
		)
		(min_thickness 0.25)
		(keepout
			(tracks not_allowed)
			(vias allowed)
			(pads allowed)
			(copperpour not_allowed)
			(footprints allowed)
		)
		(placement
			(enabled no)
			(sheetname "")
		)
		(fill
			(thermal_gap 0.5)
			(thermal_bridge_width 0.5)
			(island_removal_mode 0)
		)
		(polygon
			(pts
				(arc
					(start 403.058122 -415.00552)
					(mid 402.677122 -415.38652)
					(end 403.058122 -415.76752)
				)
				(arc
					(start 403.921722 -415.76752)
					(mid 404.302722 -415.38652)
					(end 403.921722 -415.00552)
				)
			)
		)
	)
	(zone
		(layers "F.Cu" "B.Cu" "In1.Cu" "In2.Cu" "In3.Cu" "In4.Cu" "In5.Cu" "In6.Cu"
			"In7.Cu" "In8.Cu" "In9.Cu" "In10.Cu" "In11.Cu" "In12.Cu" "In13.Cu" "In14.Cu"
			"In15.Cu" "In16.Cu"
		)
		(hatch none 0.5)
		(connect_pads
			(clearance 0)
		)
		(min_thickness 0.25)
		(keepout
			(tracks not_allowed)
			(vias allowed)
			(pads allowed)
			(copperpour not_allowed)
			(footprints allowed)
		)
		(placement
			(enabled no)
			(sheetname "")
		)
		(fill
			(thermal_gap 0.5)
			(thermal_bridge_width 0.5)
			(island_removal_mode 0)
		)
		(polygon
			(pts
				(arc
					(start 276.722332 -419.081712)
					(mid 277.103332 -419.462712)
					(end 277.484332 -419.081712)
				)
				(arc
					(start 277.484332 -418.218112)
					(mid 277.103332 -417.837112)
					(end 276.722332 -418.218112)
				)
			)
		)
	)
	(zone
		(layers "F.Cu" "B.Cu" "In1.Cu" "In2.Cu" "In3.Cu" "In4.Cu" "In5.Cu" "In6.Cu"
			"In7.Cu" "In8.Cu" "In9.Cu" "In10.Cu" "In11.Cu" "In12.Cu" "In13.Cu" "In14.Cu"
			"In15.Cu" "In16.Cu"
		)
		(hatch none 0.5)
		(connect_pads
			(clearance 0)
		)
		(min_thickness 0.25)
		(keepout
			(tracks not_allowed)
			(vias allowed)
			(pads allowed)
			(copperpour not_allowed)
			(footprints allowed)
		)
		(placement
			(enabled no)
			(sheetname "")
		)
		(fill
			(thermal_gap 0.5)
			(thermal_bridge_width 0.5)
			(island_removal_mode 0)
		)
		(polygon
			(pts
				(arc
					(start 117.436392 -389.634476)
					(mid 117.546363 -389.73553)
					(end 117.691154 -389.772144)
				)
				(arc
					(start 117.691154 -389.772144)
					(mid 117.90668 -389.68287)
					(end 117.995954 -389.467344)
				)
				(arc
					(start 117.995954 -389.467344)
					(mid 117.985617 -389.388605)
					(end 117.955314 -389.315198)
				)
				(arc
					(start 117.562884 -388.636256)
					(mid 117.450487 -388.514639)
					(end 117.291104 -388.469632)
				)
				(arc
					(start 117.291104 -388.469632)
					(mid 117.075578 -388.558906)
					(end 116.986304 -388.774432)
				)
				(arc
					(start 116.986304 -388.774432)
					(mid 116.995882 -388.850494)
					(end 117.02415 -388.921752)
				)
				(xy 117.421406 -389.609076) (xy 117.433598 -389.630412) (xy 117.436138 -389.63473)
			)
		)
	)
	(zone
		(layers "F.Cu" "B.Cu" "In1.Cu" "In2.Cu" "In3.Cu" "In4.Cu" "In5.Cu" "In6.Cu"
			"In7.Cu" "In8.Cu" "In9.Cu" "In10.Cu" "In11.Cu" "In12.Cu" "In13.Cu" "In14.Cu"
			"In15.Cu" "In16.Cu"
		)
		(hatch none 0.5)
		(connect_pads
			(clearance 0)
		)
		(min_thickness 0.25)
		(keepout
			(tracks not_allowed)
			(vias allowed)
			(pads allowed)
			(copperpour not_allowed)
			(footprints allowed)
		)
		(placement
			(enabled no)
			(sheetname "")
		)
		(fill
			(thermal_gap 0.5)
			(thermal_bridge_width 0.5)
			(island_removal_mode 0)
		)
		(polygon
			(pts
				(arc
					(start 398.463262 -412.46552)
					(mid 398.082262 -412.84652)
					(end 398.463262 -413.22752)
				)
				(arc
					(start 399.326862 -413.22752)
					(mid 399.707862 -412.84652)
					(end 399.326862 -412.46552)
				)
			)
		)
	)
	(zone
		(layers "F.Cu" "B.Cu" "In1.Cu" "In2.Cu" "In3.Cu" "In4.Cu" "In5.Cu" "In6.Cu"
			"In7.Cu" "In8.Cu" "In9.Cu" "In10.Cu" "In11.Cu" "In12.Cu" "In13.Cu" "In14.Cu"
			"In15.Cu" "In16.Cu"
		)
		(hatch none 0.5)
		(connect_pads
			(clearance 0)
		)
		(min_thickness 0.25)
		(keepout
			(tracks not_allowed)
			(vias allowed)
			(pads allowed)
			(copperpour not_allowed)
			(footprints allowed)
		)
		(placement
			(enabled no)
			(sheetname "")
		)
		(fill
			(thermal_gap 0.5)
			(thermal_bridge_width 0.5)
			(island_removal_mode 0)
		)
		(polygon
			(pts
				(arc
					(start 213.51875 4.651756)
					(mid 213.95055 4.219956)
					(end 214.38235 4.651756)
				)
				(arc
					(start 214.38235 5.515356)
					(mid 213.95055 5.947156)
					(end 213.51875 5.515356)
				)
			)
		)
	)
	(zone
		(layers "F.Cu" "B.Cu" "In1.Cu" "In2.Cu" "In3.Cu" "In4.Cu" "In5.Cu" "In6.Cu"
			"In7.Cu" "In8.Cu" "In9.Cu" "In10.Cu" "In11.Cu" "In12.Cu" "In13.Cu" "In14.Cu"
			"In15.Cu" "In16.Cu"
		)
		(hatch none 0.5)
		(connect_pads
			(clearance 0)
		)
		(min_thickness 0.25)
		(keepout
			(tracks not_allowed)
			(vias allowed)
			(pads allowed)
			(copperpour not_allowed)
			(footprints allowed)
		)
		(placement
			(enabled no)
			(sheetname "")
		)
		(fill
			(thermal_gap 0.5)
			(thermal_bridge_width 0.5)
			(island_removal_mode 0)
		)
		(polygon
			(pts
				(arc
					(start 36.595304 -416.601402)
					(mid 36.214304 -416.220402)
					(end 35.833304 -416.601402)
				)
				(arc
					(start 35.833304 -417.465002)
					(mid 36.214304 -417.846002)
					(end 36.595304 -417.465002)
				)
			)
		)
	)
	(zone
		(layers "F.Cu" "B.Cu" "In1.Cu" "In2.Cu" "In3.Cu" "In4.Cu" "In5.Cu" "In6.Cu"
			"In7.Cu" "In8.Cu" "In9.Cu" "In10.Cu" "In11.Cu" "In12.Cu" "In13.Cu" "In14.Cu"
			"In15.Cu" "In16.Cu"
		)
		(hatch none 0.5)
		(connect_pads
			(clearance 0)
		)
		(min_thickness 0.25)
		(keepout
			(tracks not_allowed)
			(vias allowed)
			(pads allowed)
			(copperpour not_allowed)
			(footprints allowed)
		)
		(placement
			(enabled no)
			(sheetname "")
		)
		(fill yes
			(thermal_gap 0.5)
			(thermal_bridge_width 0.5)
			(island_removal_mode 0)
		)
		(polygon
			(pts
				(arc
					(start 343.664032 -394.552424)
					(mid 343.774003 -394.653478)
					(end 343.918794 -394.690092)
				)
				(arc
					(start 343.918794 -394.690092)
					(mid 344.13432 -394.600818)
					(end 344.223594 -394.385292)
				)
				(arc
					(start 344.223594 -394.385292)
					(mid 344.213257 -394.306553)
					(end 344.182954 -394.233146)
				)
				(arc
					(start 343.790524 -393.554204)
					(mid 343.678127 -393.432587)
					(end 343.518744 -393.38758)
				)
				(arc
					(start 343.518744 -393.38758)
					(mid 343.303218 -393.476854)
					(end 343.213944 -393.69238)
				)
				(arc
					(start 343.213944 -393.69238)
					(mid 343.223522 -393.768442)
					(end 343.25179 -393.8397)
				)
				(xy 343.649046 -394.527024) (xy 343.661238 -394.54836) (xy 343.663778 -394.552678)
			)
		)
	)
	(zone
		(layers "F.Cu" "B.Cu" "In1.Cu" "In2.Cu" "In3.Cu" "In4.Cu" "In5.Cu" "In6.Cu"
			"In7.Cu" "In8.Cu" "In9.Cu" "In10.Cu" "In11.Cu" "In12.Cu" "In13.Cu" "In14.Cu"
			"In15.Cu" "In16.Cu"
		)
		(hatch none 0.5)
		(connect_pads
			(clearance 0)
		)
		(min_thickness 0.25)
		(keepout
			(tracks not_allowed)
			(vias allowed)
			(pads allowed)
			(copperpour not_allowed)
			(footprints allowed)
		)
		(placement
			(enabled no)
			(sheetname "")
		)
		(fill
			(thermal_gap 0.5)
			(thermal_bridge_width 0.5)
			(island_removal_mode 0)
		)
		(polygon
			(pts
				(arc
					(start 409.564332 -398.016476)
					(mid 409.674303 -398.11753)
					(end 409.819094 -398.154144)
				)
				(arc
					(start 409.819094 -398.154144)
					(mid 410.03462 -398.06487)
					(end 410.123894 -397.849344)
				)
				(arc
					(start 410.123894 -397.849344)
					(mid 410.113557 -397.770605)
					(end 410.083254 -397.697198)
				)
				(arc
					(start 409.690824 -397.018256)
					(mid 409.578427 -396.896639)
					(end 409.419044 -396.851632)
				)
				(arc
					(start 409.419044 -396.851632)
					(mid 409.203518 -396.940906)
					(end 409.114244 -397.156432)
				)
				(arc
					(start 409.114244 -397.156432)
					(mid 409.123822 -397.232494)
					(end 409.15209 -397.303752)
				)
				(xy 409.549346 -397.991076) (xy 409.561538 -398.012412) (xy 409.564078 -398.01673)
			)
		)
	)
	(zone
		(layers "F.Cu" "B.Cu" "In1.Cu" "In2.Cu" "In3.Cu" "In4.Cu" "In5.Cu" "In6.Cu"
			"In7.Cu" "In8.Cu" "In9.Cu" "In10.Cu" "In11.Cu" "In12.Cu" "In13.Cu" "In14.Cu"
			"In15.Cu" "In16.Cu"
		)
		(hatch none 0.5)
		(connect_pads
			(clearance 0)
		)
		(min_thickness 0.25)
		(keepout
			(tracks not_allowed)
			(vias allowed)
			(pads allowed)
			(copperpour not_allowed)
			(footprints allowed)
		)
		(placement
			(enabled no)
			(sheetname "")
		)
		(fill
			(thermal_gap 0.5)
			(thermal_bridge_width 0.5)
			(island_removal_mode 0)
		)
		(polygon
			(pts
				(arc
					(start 370.894102 -412.46552)
					(mid 370.513102 -412.84652)
					(end 370.894102 -413.22752)
				)
				(arc
					(start 371.757702 -413.22752)
					(mid 372.138702 -412.84652)
					(end 371.757702 -412.46552)
				)
			)
		)
	)
	(zone
		(layers "F.Cu" "B.Cu" "In1.Cu" "In2.Cu" "In3.Cu" "In4.Cu" "In5.Cu" "In6.Cu"
			"In7.Cu" "In8.Cu" "In9.Cu" "In10.Cu" "In11.Cu" "In12.Cu" "In13.Cu" "In14.Cu"
			"In15.Cu" "In16.Cu"
		)
		(hatch none 0.5)
		(connect_pads
			(clearance 0)
		)
		(min_thickness 0.25)
		(keepout
			(tracks not_allowed)
			(vias allowed)
			(pads allowed)
			(copperpour not_allowed)
			(footprints allowed)
		)
		(placement
			(enabled no)
			(sheetname "")
		)
		(fill
			(thermal_gap 0.5)
			(thermal_bridge_width 0.5)
			(island_removal_mode 0)
		)
		(polygon
			(pts
				(arc
					(start 260.094222 -194.492626)
					(mid 260.475222 -194.873626)
					(end 260.856222 -194.492626)
				)
				(arc
					(start 260.856222 -193.502026)
					(mid 260.475222 -193.121026)
					(end 260.094222 -193.502026)
				)
			)
		)
	)
	(zone
		(layers "F.Cu" "B.Cu" "In1.Cu" "In2.Cu" "In3.Cu" "In4.Cu" "In5.Cu" "In6.Cu"
			"In7.Cu" "In8.Cu" "In9.Cu" "In10.Cu" "In11.Cu" "In12.Cu" "In13.Cu" "In14.Cu"
			"In15.Cu" "In16.Cu"
		)
		(hatch none 0.5)
		(connect_pads
			(clearance 0)
		)
		(min_thickness 0.25)
		(keepout
			(tracks not_allowed)
			(vias allowed)
			(pads allowed)
			(copperpour not_allowed)
			(footprints allowed)
		)
		(placement
			(enabled no)
			(sheetname "")
		)
		(fill
			(thermal_gap 0.5)
			(thermal_bridge_width 0.5)
			(island_removal_mode 0)
		)
		(polygon
			(pts
				(arc
					(start 417.025582 -6.344158)
					(mid 416.644582 -6.725158)
					(end 417.025582 -7.106158)
				)
				(arc
					(start 417.889182 -7.106158)
					(mid 418.270182 -6.725158)
					(end 417.889182 -6.344158)
				)
			)
		)
	)
	(zone
		(layers "F.Cu" "B.Cu" "In1.Cu" "In2.Cu" "In3.Cu" "In4.Cu" "In5.Cu" "In6.Cu"
			"In7.Cu" "In8.Cu" "In9.Cu" "In10.Cu" "In11.Cu" "In12.Cu" "In13.Cu" "In14.Cu"
			"In15.Cu" "In16.Cu"
		)
		(hatch none 0.5)
		(connect_pads
			(clearance 0)
		)
		(min_thickness 0.25)
		(keepout
			(tracks not_allowed)
			(vias allowed)
			(pads allowed)
			(copperpour not_allowed)
			(footprints allowed)
		)
		(placement
			(enabled no)
			(sheetname "")
		)
		(fill
			(thermal_gap 0.5)
			(thermal_bridge_width 0.5)
			(island_removal_mode 0)
		)
		(polygon
			(pts
				(arc
					(start 178.630834 -46.481746)
					(mid 179.011834 -46.862746)
					(end 179.392834 -46.481746)
				)
				(arc
					(start 179.392834 -45.618146)
					(mid 179.011834 -45.237146)
					(end 178.630834 -45.618146)
				)
			)
		)
	)
	(zone
		(layers "F.Cu" "B.Cu" "In1.Cu" "In2.Cu" "In3.Cu" "In4.Cu" "In5.Cu" "In6.Cu"
			"In7.Cu" "In8.Cu" "In9.Cu" "In10.Cu" "In11.Cu" "In12.Cu" "In13.Cu" "In14.Cu"
			"In15.Cu" "In16.Cu"
		)
		(hatch none 0.5)
		(connect_pads
			(clearance 0)
		)
		(min_thickness 0.25)
		(keepout
			(tracks not_allowed)
			(vias allowed)
			(pads allowed)
			(copperpour not_allowed)
			(footprints allowed)
		)
		(placement
			(enabled no)
			(sheetname "")
		)
		(fill
			(thermal_gap 0.5)
			(thermal_bridge_width 0.5)
			(island_removal_mode 0)
		)
		(polygon
			(pts
				(arc
					(start 392.982704 -212.980016)
					(mid 387.952996 -212.980016)
					(end 392.982704 -212.980016)
				)
			)
		)
	)
	(zone
		(layers "F.Cu" "B.Cu" "In1.Cu" "In2.Cu" "In3.Cu" "In4.Cu" "In5.Cu" "In6.Cu"
			"In7.Cu" "In8.Cu" "In9.Cu" "In10.Cu" "In11.Cu" "In12.Cu" "In13.Cu" "In14.Cu"
			"In15.Cu" "In16.Cu"
		)
		(hatch none 0.5)
		(connect_pads
			(clearance 0)
		)
		(min_thickness 0.25)
		(keepout
			(tracks not_allowed)
			(vias allowed)
			(pads allowed)
			(copperpour not_allowed)
			(footprints allowed)
		)
		(placement
			(enabled no)
			(sheetname "")
		)
		(fill
			(thermal_gap 0.5)
			(thermal_bridge_width 0.5)
			(island_removal_mode 0)
		)
		(polygon
			(pts
				(arc
					(start 135.642096 -368.65433)
					(mid 135.261096 -369.03533)
					(end 135.642096 -369.41633)
				)
				(arc
					(start 136.505696 -369.41633)
					(mid 136.886696 -369.03533)
					(end 136.505696 -368.65433)
				)
			)
		)
	)
	(zone
		(layers "F.Cu" "B.Cu" "In1.Cu" "In2.Cu" "In3.Cu" "In4.Cu" "In5.Cu" "In6.Cu"
			"In7.Cu" "In8.Cu" "In9.Cu" "In10.Cu" "In11.Cu" "In12.Cu" "In13.Cu" "In14.Cu"
			"In15.Cu" "In16.Cu"
		)
		(hatch none 0.5)
		(connect_pads
			(clearance 0)
		)
		(min_thickness 0.25)
		(keepout
			(tracks not_allowed)
			(vias allowed)
			(pads allowed)
			(copperpour not_allowed)
			(footprints allowed)
		)
		(placement
			(enabled no)
			(sheetname "")
		)
		(fill
			(thermal_gap 0.5)
			(thermal_bridge_width 0.5)
			(island_removal_mode 0)
		)
		(polygon
			(pts
				(arc
					(start 237.015274 -40.744902)
					(mid 235.084874 -40.744902)
					(end 237.015274 -40.744902)
				)
			)
		)
	)
	(zone
		(layers "F.Cu" "B.Cu" "In1.Cu" "In2.Cu" "In3.Cu" "In4.Cu" "In5.Cu" "In6.Cu"
			"In7.Cu" "In8.Cu" "In9.Cu" "In10.Cu" "In11.Cu" "In12.Cu" "In13.Cu" "In14.Cu"
			"In15.Cu" "In16.Cu"
		)
		(hatch none 0.5)
		(connect_pads
			(clearance 0)
		)
		(min_thickness 0.25)
		(keepout
			(tracks not_allowed)
			(vias allowed)
			(pads allowed)
			(copperpour not_allowed)
			(footprints allowed)
		)
		(placement
			(enabled no)
			(sheetname "")
		)
		(fill
			(thermal_gap 0.5)
			(thermal_bridge_width 0.5)
			(island_removal_mode 0)
		)
		(polygon
			(pts
				(arc
					(start 132.014722 -17.763744)
					(mid 131.633722 -18.144744)
					(end 132.014722 -18.525744)
				)
				(arc
					(start 132.878322 -18.525744)
					(mid 133.259322 -18.144744)
					(end 132.878322 -17.763744)
				)
			)
		)
	)
	(zone
		(layers "F.Cu" "B.Cu" "In1.Cu" "In2.Cu" "In3.Cu" "In4.Cu" "In5.Cu" "In6.Cu"
			"In7.Cu" "In8.Cu" "In9.Cu" "In10.Cu" "In11.Cu" "In12.Cu" "In13.Cu" "In14.Cu"
			"In15.Cu" "In16.Cu"
		)
		(hatch none 0.5)
		(connect_pads
			(clearance 0)
		)
		(min_thickness 0.25)
		(keepout
			(tracks not_allowed)
			(vias allowed)
			(pads allowed)
			(copperpour not_allowed)
			(footprints allowed)
		)
		(placement
			(enabled no)
			(sheetname "")
		)
		(fill
			(thermal_gap 0.5)
			(thermal_bridge_width 0.5)
			(island_removal_mode 0)
		)
		(polygon
			(pts
				(arc
					(start 402.52015 -4.582414)
					(mid 402.13915 -4.963414)
					(end 402.52015 -5.344414)
				)
				(arc
					(start 403.38375 -5.344414)
					(mid 403.76475 -4.963414)
					(end 403.38375 -4.582414)
				)
			)
		)
	)
	(zone
		(layers "F.Cu" "B.Cu" "In1.Cu" "In2.Cu" "In3.Cu" "In4.Cu" "In5.Cu" "In6.Cu"
			"In7.Cu" "In8.Cu" "In9.Cu" "In10.Cu" "In11.Cu" "In12.Cu" "In13.Cu" "In14.Cu"
			"In15.Cu" "In16.Cu"
		)
		(hatch none 0.5)
		(connect_pads
			(clearance 0)
		)
		(min_thickness 0.25)
		(keepout
			(tracks not_allowed)
			(vias allowed)
			(pads allowed)
			(copperpour not_allowed)
			(footprints allowed)
		)
		(placement
			(enabled no)
			(sheetname "")
		)
		(fill
			(thermal_gap 0.5)
			(thermal_bridge_width 0.5)
			(island_removal_mode 0)
		)
		(polygon
			(pts
				(arc
					(start 159.311086 -406.62352)
					(mid 158.930086 -407.00452)
					(end 159.311086 -407.38552)
				)
				(arc
					(start 160.174686 -407.38552)
					(mid 160.555686 -407.00452)
					(end 160.174686 -406.62352)
				)
			)
		)
	)
	(zone
		(layers "F.Cu" "B.Cu" "In1.Cu" "In2.Cu" "In3.Cu" "In4.Cu" "In5.Cu" "In6.Cu"
			"In7.Cu" "In8.Cu" "In9.Cu" "In10.Cu" "In11.Cu" "In12.Cu" "In13.Cu" "In14.Cu"
			"In15.Cu" "In16.Cu"
		)
		(hatch none 0.5)
		(connect_pads
			(clearance 0)
		)
		(min_thickness 0.25)
		(keepout
			(tracks not_allowed)
			(vias allowed)
			(pads allowed)
			(copperpour not_allowed)
			(footprints allowed)
		)
		(placement
			(enabled no)
			(sheetname "")
		)
		(fill
			(thermal_gap 0.5)
			(thermal_bridge_width 0.5)
			(island_removal_mode 0)
		)
		(polygon
			(pts
				(arc
					(start 181.660546 -44.980098)
					(mid 182.041546 -45.361098)
					(end 182.422546 -44.980098)
				)
				(arc
					(start 182.422546 -44.116498)
					(mid 182.041546 -43.735498)
					(end 181.660546 -44.116498)
				)
			)
		)
	)
	(zone
		(layers "F.Cu" "B.Cu" "In1.Cu" "In2.Cu" "In3.Cu" "In4.Cu" "In5.Cu" "In6.Cu"
			"In7.Cu" "In8.Cu" "In9.Cu" "In10.Cu" "In11.Cu" "In12.Cu" "In13.Cu" "In14.Cu"
			"In15.Cu" "In16.Cu"
		)
		(hatch none 0.5)
		(connect_pads
			(clearance 0)
		)
		(min_thickness 0.25)
		(keepout
			(tracks not_allowed)
			(vias allowed)
			(pads allowed)
			(copperpour not_allowed)
			(footprints allowed)
		)
		(placement
			(enabled no)
			(sheetname "")
		)
		(fill
			(thermal_gap 0.5)
			(thermal_bridge_width 0.5)
			(island_removal_mode 0)
		)
		(polygon
			(pts
				(arc
					(start 65.936622 -389.634476)
					(mid 66.046593 -389.73553)
					(end 66.191384 -389.772144)
				)
				(arc
					(start 66.191384 -389.772144)
					(mid 66.40691 -389.68287)
					(end 66.496184 -389.467344)
				)
				(arc
					(start 66.496184 -389.467344)
					(mid 66.485847 -389.388605)
					(end 66.455544 -389.315198)
				)
				(arc
					(start 66.063114 -388.636256)
					(mid 65.950717 -388.514639)
					(end 65.791334 -388.469632)
				)
				(arc
					(start 65.791334 -388.469632)
					(mid 65.575808 -388.558906)
					(end 65.486534 -388.774432)
				)
				(arc
					(start 65.486534 -388.774432)
					(mid 65.496112 -388.850494)
					(end 65.52438 -388.921752)
				)
				(xy 65.921636 -389.609076) (xy 65.933828 -389.630412) (xy 65.936368 -389.63473)
			)
		)
	)
	(zone
		(layers "F.Cu" "B.Cu" "In1.Cu" "In2.Cu" "In3.Cu" "In4.Cu" "In5.Cu" "In6.Cu"
			"In7.Cu" "In8.Cu" "In9.Cu" "In10.Cu" "In11.Cu" "In12.Cu" "In13.Cu" "In14.Cu"
			"In15.Cu" "In16.Cu"
		)
		(hatch none 0.5)
		(connect_pads
			(clearance 0)
		)
		(min_thickness 0.25)
		(keepout
			(tracks not_allowed)
			(vias allowed)
			(pads allowed)
			(copperpour not_allowed)
			(footprints allowed)
		)
		(placement
			(enabled no)
			(sheetname "")
		)
		(fill
			(thermal_gap 0.5)
			(thermal_bridge_width 0.5)
			(island_removal_mode 0)
		)
		(polygon
			(pts
				(arc
					(start 374.624092 -377.03633)
					(mid 374.243092 -377.41733)
					(end 374.624092 -377.79833)
				)
				(arc
					(start 375.487692 -377.79833)
					(mid 375.868692 -377.41733)
					(end 375.487692 -377.03633)
				)
			)
		)
	)
	(zone
		(layers "F.Cu" "B.Cu" "In1.Cu" "In2.Cu" "In3.Cu" "In4.Cu" "In5.Cu" "In6.Cu"
			"In7.Cu" "In8.Cu" "In9.Cu" "In10.Cu" "In11.Cu" "In12.Cu" "In13.Cu" "In14.Cu"
			"In15.Cu" "In16.Cu"
		)
		(hatch none 0.5)
		(connect_pads
			(clearance 0)
		)
		(min_thickness 0.25)
		(keepout
			(tracks not_allowed)
			(vias allowed)
			(pads allowed)
			(copperpour not_allowed)
			(footprints allowed)
		)
		(placement
			(enabled no)
			(sheetname "")
		)
		(fill
			(thermal_gap 0.5)
			(thermal_bridge_width 0.5)
			(island_removal_mode 0)
		)
		(polygon
			(pts
				(arc
					(start 398.463262 -420.571168)
					(mid 398.082262 -420.952168)
					(end 398.463262 -421.333168)
				)
				(arc
					(start 399.326862 -421.333168)
					(mid 399.707862 -420.952168)
					(end 399.326862 -420.571168)
				)
			)
		)
	)
	(zone
		(layers "F.Cu" "B.Cu" "In1.Cu" "In2.Cu" "In3.Cu" "In4.Cu" "In5.Cu" "In6.Cu"
			"In7.Cu" "In8.Cu" "In9.Cu" "In10.Cu" "In11.Cu" "In12.Cu" "In13.Cu" "In14.Cu"
			"In15.Cu" "In16.Cu"
		)
		(hatch none 0.5)
		(connect_pads
			(clearance 0)
		)
		(min_thickness 0.25)
		(keepout
			(tracks not_allowed)
			(vias allowed)
			(pads allowed)
			(copperpour not_allowed)
			(footprints allowed)
		)
		(placement
			(enabled no)
			(sheetname "")
		)
		(fill
			(thermal_gap 0.5)
			(thermal_bridge_width 0.5)
			(island_removal_mode 0)
		)
		(polygon
			(pts
				(arc
					(start 123.43638 -389.634476)
					(mid 123.546351 -389.73553)
					(end 123.691142 -389.772144)
				)
				(arc
					(start 123.691142 -389.772144)
					(mid 123.906668 -389.68287)
					(end 123.995942 -389.467344)
				)
				(arc
					(start 123.995942 -389.467344)
					(mid 123.985605 -389.388605)
					(end 123.955302 -389.315198)
				)
				(arc
					(start 123.562872 -388.636256)
					(mid 123.450475 -388.514639)
					(end 123.291092 -388.469632)
				)
				(arc
					(start 123.291092 -388.469632)
					(mid 123.075566 -388.558906)
					(end 122.986292 -388.774432)
				)
				(arc
					(start 122.986292 -388.774432)
					(mid 122.99587 -388.850494)
					(end 123.024138 -388.921752)
				)
				(xy 123.421394 -389.609076) (xy 123.433586 -389.630412) (xy 123.436126 -389.63473)
			)
		)
	)
	(zone
		(layers "F.Cu" "B.Cu" "In1.Cu" "In2.Cu" "In3.Cu" "In4.Cu" "In5.Cu" "In6.Cu"
			"In7.Cu" "In8.Cu" "In9.Cu" "In10.Cu" "In11.Cu" "In12.Cu" "In13.Cu" "In14.Cu"
			"In15.Cu" "In16.Cu"
		)
		(hatch none 0.5)
		(connect_pads
			(clearance 0)
		)
		(min_thickness 0.25)
		(keepout
			(tracks not_allowed)
			(vias allowed)
			(pads allowed)
			(copperpour not_allowed)
			(footprints allowed)
		)
		(placement
			(enabled no)
			(sheetname "")
		)
		(fill
			(thermal_gap 0.5)
			(thermal_bridge_width 0.5)
			(island_removal_mode 0)
		)
		(polygon
			(pts
				(arc
					(start 68.14185 -421.760396)
					(mid 68.164168 -421.814278)
					(end 68.21805 -421.836596)
				)
				(arc
					(start 69.15785 -421.836596)
					(mid 69.211732 -421.814278)
					(end 69.23405 -421.760396)
				)
				(arc
					(start 69.23405 -419.218872)
					(mid 69.211732 -419.16499)
					(end 69.15785 -419.142672)
				)
				(arc
					(start 68.21805 -419.142672)
					(mid 68.164168 -419.16499)
					(end 68.14185 -419.218872)
				)
			)
		)
	)
	(zone
		(layers "F.Cu" "B.Cu" "In1.Cu" "In2.Cu" "In3.Cu" "In4.Cu" "In5.Cu" "In6.Cu"
			"In7.Cu" "In8.Cu" "In9.Cu" "In10.Cu" "In11.Cu" "In12.Cu" "In13.Cu" "In14.Cu"
			"In15.Cu" "In16.Cu"
		)
		(hatch none 0.5)
		(connect_pads
			(clearance 0)
		)
		(min_thickness 0.25)
		(keepout
			(tracks not_allowed)
			(vias allowed)
			(pads allowed)
			(copperpour not_allowed)
			(footprints allowed)
		)
		(placement
			(enabled no)
			(sheetname "")
		)
		(fill
			(thermal_gap 0.5)
			(thermal_bridge_width 0.5)
			(island_removal_mode 0)
		)
		(polygon
			(pts
				(arc
					(start 181.660546 -48.028098)
					(mid 182.041546 -48.409098)
					(end 182.422546 -48.028098)
				)
				(arc
					(start 182.422546 -47.164498)
					(mid 182.041546 -46.783498)
					(end 181.660546 -47.164498)
				)
			)
		)
	)
	(zone
		(layers "F.Cu" "B.Cu" "In1.Cu" "In2.Cu" "In3.Cu" "In4.Cu" "In5.Cu" "In6.Cu"
			"In7.Cu" "In8.Cu" "In9.Cu" "In10.Cu" "In11.Cu" "In12.Cu" "In13.Cu" "In14.Cu"
			"In15.Cu" "In16.Cu"
		)
		(hatch none 0.5)
		(connect_pads
			(clearance 0)
		)
		(min_thickness 0.25)
		(keepout
			(tracks not_allowed)
			(vias allowed)
			(pads allowed)
			(copperpour not_allowed)
			(footprints allowed)
		)
		(placement
			(enabled no)
			(sheetname "")
		)
		(fill
			(thermal_gap 0.5)
			(thermal_bridge_width 0.5)
			(island_removal_mode 0)
		)
		(polygon
			(pts
				(arc
					(start 134.805166 -406.62352)
					(mid 134.424166 -407.00452)
					(end 134.805166 -407.38552)
				)
				(arc
					(start 135.668766 -407.38552)
					(mid 136.049766 -407.00452)
					(end 135.668766 -406.62352)
				)
			)
		)
	)
	(zone
		(layers "F.Cu" "B.Cu" "In1.Cu" "In2.Cu" "In3.Cu" "In4.Cu" "In5.Cu" "In6.Cu"
			"In7.Cu" "In8.Cu" "In9.Cu" "In10.Cu" "In11.Cu" "In12.Cu" "In13.Cu" "In14.Cu"
			"In15.Cu" "In16.Cu"
		)
		(hatch none 0.5)
		(connect_pads
			(clearance 0)
		)
		(min_thickness 0.25)
		(keepout
			(tracks not_allowed)
			(vias allowed)
			(pads allowed)
			(copperpour not_allowed)
			(footprints allowed)
		)
		(placement
			(enabled no)
			(sheetname "")
		)
		(fill
			(thermal_gap 0.5)
			(thermal_bridge_width 0.5)
			(island_removal_mode 0)
		)
		(polygon
			(pts
				(arc
					(start 49.822354 -371.11813)
					(mid 49.441354 -371.49913)
					(end 49.822354 -371.88013)
				)
				(arc
					(start 50.685954 -371.88013)
					(mid 51.066954 -371.49913)
					(end 50.685954 -371.11813)
				)
			)
		)
	)
	(zone
		(layers "F.Cu" "B.Cu" "In1.Cu" "In2.Cu" "In3.Cu" "In4.Cu" "In5.Cu" "In6.Cu"
			"In7.Cu" "In8.Cu" "In9.Cu" "In10.Cu" "In11.Cu" "In12.Cu" "In13.Cu" "In14.Cu"
			"In15.Cu" "In16.Cu"
		)
		(hatch none 0.5)
		(connect_pads
			(clearance 0)
		)
		(min_thickness 0.25)
		(keepout
			(tracks not_allowed)
			(vias allowed)
			(pads allowed)
			(copperpour not_allowed)
			(footprints allowed)
		)
		(placement
			(enabled no)
			(sheetname "")
		)
		(fill
			(thermal_gap 0.5)
			(thermal_bridge_width 0.5)
			(island_removal_mode 0)
		)
		(polygon
			(pts
				(arc
					(start 75.363324 -412.189168)
					(mid 74.982324 -412.570168)
					(end 75.363324 -412.951168)
				)
				(arc
					(start 76.226924 -412.951168)
					(mid 76.607924 -412.570168)
					(end 76.226924 -412.189168)
				)
			)
		)
	)
	(zone
		(layers "F.Cu" "B.Cu" "In1.Cu" "In2.Cu" "In3.Cu" "In4.Cu" "In5.Cu" "In6.Cu"
			"In7.Cu" "In8.Cu" "In9.Cu" "In10.Cu" "In11.Cu" "In12.Cu" "In13.Cu" "In14.Cu"
			"In15.Cu" "In16.Cu"
		)
		(hatch none 0.5)
		(connect_pads
			(clearance 0)
		)
		(min_thickness 0.25)
		(keepout
			(tracks not_allowed)
			(vias allowed)
			(pads allowed)
			(copperpour not_allowed)
			(footprints allowed)
		)
		(placement
			(enabled no)
			(sheetname "")
		)
		(fill
			(thermal_gap 0.5)
			(thermal_bridge_width 0.5)
			(island_removal_mode 0)
		)
		(polygon
			(pts
				(arc
					(start 337.489546 -420.571168)
					(mid 337.108546 -420.952168)
					(end 337.489546 -421.333168)
				)
				(arc
					(start 338.353146 -421.333168)
					(mid 338.734146 -420.952168)
					(end 338.353146 -420.571168)
				)
			)
		)
	)
	(zone
		(layers "F.Cu" "B.Cu" "In1.Cu" "In2.Cu" "In3.Cu" "In4.Cu" "In5.Cu" "In6.Cu"
			"In7.Cu" "In8.Cu" "In9.Cu" "In10.Cu" "In11.Cu" "In12.Cu" "In13.Cu" "In14.Cu"
			"In15.Cu" "In16.Cu"
		)
		(hatch none 0.5)
		(connect_pads
			(clearance 0)
		)
		(min_thickness 0.25)
		(keepout
			(tracks not_allowed)
			(vias allowed)
			(pads allowed)
			(copperpour not_allowed)
			(footprints allowed)
		)
		(placement
			(enabled no)
			(sheetname "")
		)
		(fill
			(thermal_gap 0.5)
			(thermal_bridge_width 0.5)
			(island_removal_mode 0)
		)
		(polygon
			(pts
				(arc
					(start 420.76624 -377.03633)
					(mid 420.38524 -377.41733)
					(end 420.76624 -377.79833)
				)
				(arc
					(start 421.62984 -377.79833)
					(mid 422.01084 -377.41733)
					(end 421.62984 -377.03633)
				)
			)
		)
	)
	(zone
		(layers "F.Cu" "B.Cu" "In1.Cu" "In2.Cu" "In3.Cu" "In4.Cu" "In5.Cu" "In6.Cu"
			"In7.Cu" "In8.Cu" "In9.Cu" "In10.Cu" "In11.Cu" "In12.Cu" "In13.Cu" "In14.Cu"
			"In15.Cu" "In16.Cu"
		)
		(hatch none 0.5)
		(connect_pads
			(clearance 0)
		)
		(min_thickness 0.25)
		(keepout
			(tracks not_allowed)
			(vias allowed)
			(pads allowed)
			(copperpour not_allowed)
			(footprints allowed)
		)
		(placement
			(enabled no)
			(sheetname "")
		)
		(fill
			(thermal_gap 0.5)
			(thermal_bridge_width 0.5)
			(island_removal_mode 0)
		)
		(polygon
			(pts
				(arc
					(start 255.546098 -202.662536)
					(mid 255.927098 -203.043536)
					(end 256.308098 -202.662536)
				)
				(arc
					(start 256.308098 -201.798936)
					(mid 255.927098 -201.417936)
					(end 255.546098 -201.798936)
				)
			)
		)
	)
	(zone
		(layers "F.Cu" "B.Cu" "In1.Cu" "In2.Cu" "In3.Cu" "In4.Cu" "In5.Cu" "In6.Cu"
			"In7.Cu" "In8.Cu" "In9.Cu" "In10.Cu" "In11.Cu" "In12.Cu" "In13.Cu" "In14.Cu"
			"In15.Cu" "In16.Cu"
		)
		(hatch none 0.5)
		(connect_pads
			(clearance 0)
		)
		(min_thickness 0.25)
		(keepout
			(tracks not_allowed)
			(vias allowed)
			(pads allowed)
			(copperpour not_allowed)
			(footprints allowed)
		)
		(placement
			(enabled no)
			(sheetname "")
		)
		(fill
			(thermal_gap 0.5)
			(thermal_bridge_width 0.5)
			(island_removal_mode 0)
		)
		(polygon
			(pts
				(arc
					(start 328.299826 -412.46552)
					(mid 327.918826 -412.84652)
					(end 328.299826 -413.22752)
				)
				(arc
					(start 329.163426 -413.22752)
					(mid 329.544426 -412.84652)
					(end 329.163426 -412.46552)
				)
			)
		)
	)
	(zone
		(layers "F.Cu" "B.Cu" "In1.Cu" "In2.Cu" "In3.Cu" "In4.Cu" "In5.Cu" "In6.Cu"
			"In7.Cu" "In8.Cu" "In9.Cu" "In10.Cu" "In11.Cu" "In12.Cu" "In13.Cu" "In14.Cu"
			"In15.Cu" "In16.Cu"
		)
		(hatch none 0.5)
		(connect_pads
			(clearance 0)
		)
		(min_thickness 0.25)
		(keepout
			(tracks not_allowed)
			(vias allowed)
			(pads allowed)
			(copperpour not_allowed)
			(footprints allowed)
		)
		(placement
			(enabled no)
			(sheetname "")
		)
		(fill
			(thermal_gap 0.5)
			(thermal_bridge_width 0.5)
			(island_removal_mode 0)
		)
		(polygon
			(pts
				(arc
					(start 147.825206 -392.429238)
					(mid 147.444206 -392.048238)
					(end 147.063206 -392.429238)
				)
				(arc
					(start 147.063206 -393.292838)
					(mid 147.444206 -393.673838)
					(end 147.825206 -393.292838)
				)
			)
		)
	)
	(zone
		(layers "F.Cu" "B.Cu" "In1.Cu" "In2.Cu" "In3.Cu" "In4.Cu" "In5.Cu" "In6.Cu"
			"In7.Cu" "In8.Cu" "In9.Cu" "In10.Cu" "In11.Cu" "In12.Cu" "In13.Cu" "In14.Cu"
			"In15.Cu" "In16.Cu"
		)
		(hatch none 0.5)
		(connect_pads
			(clearance 0)
		)
		(min_thickness 0.25)
		(keepout
			(tracks not_allowed)
			(vias allowed)
			(pads allowed)
			(copperpour not_allowed)
			(footprints allowed)
		)
		(placement
			(enabled no)
			(sheetname "")
		)
		(fill
			(thermal_gap 0.5)
			(thermal_bridge_width 0.5)
			(island_removal_mode 0)
		)
		(polygon
			(pts
				(arc
					(start 309.920386 -412.46552)
					(mid 309.539386 -412.84652)
					(end 309.920386 -413.22752)
				)
				(arc
					(start 310.783986 -413.22752)
					(mid 311.164986 -412.84652)
					(end 310.783986 -412.46552)
				)
			)
		)
	)
	(zone
		(layers "F.Cu" "B.Cu" "In1.Cu" "In2.Cu" "In3.Cu" "In4.Cu" "In5.Cu" "In6.Cu"
			"In7.Cu" "In8.Cu" "In9.Cu" "In10.Cu" "In11.Cu" "In12.Cu" "In13.Cu" "In14.Cu"
			"In15.Cu" "In16.Cu"
		)
		(hatch none 0.5)
		(connect_pads
			(clearance 0)
		)
		(min_thickness 0.25)
		(keepout
			(tracks not_allowed)
			(vias allowed)
			(pads allowed)
			(copperpour not_allowed)
			(footprints allowed)
		)
		(placement
			(enabled no)
			(sheetname "")
		)
		(fill
			(thermal_gap 0.5)
			(thermal_bridge_width 0.5)
			(island_removal_mode 0)
		)
		(polygon
			(pts
				(arc
					(start 125.615446 -406.62352)
					(mid 125.234446 -407.00452)
					(end 125.615446 -407.38552)
				)
				(arc
					(start 126.479046 -407.38552)
					(mid 126.860046 -407.00452)
					(end 126.479046 -406.62352)
				)
			)
		)
	)
	(zone
		(layers "F.Cu" "B.Cu" "In1.Cu" "In2.Cu" "In3.Cu" "In4.Cu" "In5.Cu" "In6.Cu"
			"In7.Cu" "In8.Cu" "In9.Cu" "In10.Cu" "In11.Cu" "In12.Cu" "In13.Cu" "In14.Cu"
			"In15.Cu" "In16.Cu"
		)
		(hatch none 0.5)
		(connect_pads
			(clearance 0)
		)
		(min_thickness 0.25)
		(keepout
			(tracks not_allowed)
			(vias allowed)
			(pads allowed)
			(copperpour not_allowed)
			(footprints allowed)
		)
		(placement
			(enabled no)
			(sheetname "")
		)
		(fill
			(thermal_gap 0.5)
			(thermal_bridge_width 0.5)
			(island_removal_mode 0)
		)
		(polygon
			(pts
				(arc
					(start 401.526502 -420.571168)
					(mid 401.145502 -420.952168)
					(end 401.526502 -421.333168)
				)
				(arc
					(start 402.390102 -421.333168)
					(mid 402.771102 -420.952168)
					(end 402.390102 -420.571168)
				)
			)
		)
	)
	(zone
		(layers "F.Cu" "B.Cu" "In1.Cu" "In2.Cu" "In3.Cu" "In4.Cu" "In5.Cu" "In6.Cu"
			"In7.Cu" "In8.Cu" "In9.Cu" "In10.Cu" "In11.Cu" "In12.Cu" "In13.Cu" "In14.Cu"
			"In15.Cu" "In16.Cu"
		)
		(hatch none 0.5)
		(connect_pads
			(clearance 0)
		)
		(min_thickness 0.25)
		(keepout
			(tracks not_allowed)
			(vias allowed)
			(pads allowed)
			(copperpour not_allowed)
			(footprints allowed)
		)
		(placement
			(enabled no)
			(sheetname "")
		)
		(fill
			(thermal_gap 0.5)
			(thermal_bridge_width 0.5)
			(island_removal_mode 0)
		)
		(polygon
			(pts
				(arc
					(start 104.186482 -379.496828)
					(mid 103.805482 -379.115828)
					(end 103.424482 -379.496828)
				)
				(arc
					(start 103.424482 -380.360428)
					(mid 103.805482 -380.741428)
					(end 104.186482 -380.360428)
				)
			)
		)
	)
	(zone
		(layers "F.Cu" "B.Cu" "In1.Cu" "In2.Cu" "In3.Cu" "In4.Cu" "In5.Cu" "In6.Cu"
			"In7.Cu" "In8.Cu" "In9.Cu" "In10.Cu" "In11.Cu" "In12.Cu" "In13.Cu" "In14.Cu"
			"In15.Cu" "In16.Cu"
		)
		(hatch none 0.5)
		(connect_pads
			(clearance 0)
		)
		(min_thickness 0.25)
		(keepout
			(tracks not_allowed)
			(vias allowed)
			(pads allowed)
			(copperpour not_allowed)
			(footprints allowed)
		)
		(placement
			(enabled no)
			(sheetname "")
		)
		(fill
			(thermal_gap 0.5)
			(thermal_bridge_width 0.5)
			(island_removal_mode 0)
		)
		(polygon
			(pts
				(arc
					(start 407.15184 -377.03633)
					(mid 406.77084 -377.41733)
					(end 407.15184 -377.79833)
				)
				(arc
					(start 408.01544 -377.79833)
					(mid 408.39644 -377.41733)
					(end 408.01544 -377.03633)
				)
			)
		)
	)
	(zone
		(layers "F.Cu" "B.Cu" "In1.Cu" "In2.Cu" "In3.Cu" "In4.Cu" "In5.Cu" "In6.Cu"
			"In7.Cu" "In8.Cu" "In9.Cu" "In10.Cu" "In11.Cu" "In12.Cu" "In13.Cu" "In14.Cu"
			"In15.Cu" "In16.Cu"
		)
		(hatch none 0.5)
		(connect_pads
			(clearance 0)
		)
		(min_thickness 0.25)
		(keepout
			(tracks not_allowed)
			(vias allowed)
			(pads allowed)
			(copperpour not_allowed)
			(footprints allowed)
		)
		(placement
			(enabled no)
			(sheetname "")
		)
		(fill
			(thermal_gap 0.5)
			(thermal_bridge_width 0.5)
			(island_removal_mode 0)
		)
		(polygon
			(pts
				(arc
					(start 306.857146 -420.571168)
					(mid 306.476146 -420.952168)
					(end 306.857146 -421.333168)
				)
				(arc
					(start 307.720746 -421.333168)
					(mid 308.101746 -420.952168)
					(end 307.720746 -420.571168)
				)
			)
		)
	)
	(zone
		(layers "F.Cu" "B.Cu" "In1.Cu" "In2.Cu" "In3.Cu" "In4.Cu" "In5.Cu" "In6.Cu"
			"In7.Cu" "In8.Cu" "In9.Cu" "In10.Cu" "In11.Cu" "In12.Cu" "In13.Cu" "In14.Cu"
			"In15.Cu" "In16.Cu"
		)
		(hatch none 0.5)
		(connect_pads
			(clearance 0)
		)
		(min_thickness 0.25)
		(keepout
			(tracks not_allowed)
			(vias allowed)
			(pads allowed)
			(copperpour not_allowed)
			(footprints allowed)
		)
		(placement
			(enabled no)
			(sheetname "")
		)
		(fill
			(thermal_gap 0.5)
			(thermal_bridge_width 0.5)
			(island_removal_mode 0)
		)
		(polygon
			(pts
				(arc
					(start 316.046866 -420.571168)
					(mid 315.665866 -420.952168)
					(end 316.046866 -421.333168)
				)
				(arc
					(start 316.910466 -421.333168)
					(mid 317.291466 -420.952168)
					(end 316.910466 -420.571168)
				)
			)
		)
	)
	(zone
		(layers "F.Cu" "B.Cu" "In1.Cu" "In2.Cu" "In3.Cu" "In4.Cu" "In5.Cu" "In6.Cu"
			"In7.Cu" "In8.Cu" "In9.Cu" "In10.Cu" "In11.Cu" "In12.Cu" "In13.Cu" "In14.Cu"
			"In15.Cu" "In16.Cu"
		)
		(hatch none 0.5)
		(connect_pads
			(clearance 0)
		)
		(min_thickness 0.25)
		(keepout
			(tracks not_allowed)
			(vias allowed)
			(pads allowed)
			(copperpour not_allowed)
			(footprints allowed)
		)
		(placement
			(enabled no)
			(sheetname "")
		)
		(fill
			(thermal_gap 0.5)
			(thermal_bridge_width 0.5)
			(island_removal_mode 0)
		)
		(polygon
			(pts
				(arc
					(start 13.30452 -359.553002)
					(mid 12.92352 -359.172002)
					(end 12.54252 -359.553002)
				)
				(arc
					(start 12.54252 -360.416602)
					(mid 12.92352 -360.797602)
					(end 13.30452 -360.416602)
				)
			)
		)
	)
	(zone
		(layers "F.Cu" "B.Cu" "In1.Cu" "In2.Cu" "In3.Cu" "In4.Cu" "In5.Cu" "In6.Cu"
			"In7.Cu" "In8.Cu" "In9.Cu" "In10.Cu" "In11.Cu" "In12.Cu" "In13.Cu" "In14.Cu"
			"In15.Cu" "In16.Cu"
		)
		(hatch none 0.5)
		(connect_pads
			(clearance 0)
		)
		(min_thickness 0.25)
		(keepout
			(tracks not_allowed)
			(vias allowed)
			(pads allowed)
			(copperpour not_allowed)
			(footprints allowed)
		)
		(placement
			(enabled no)
			(sheetname "")
		)
		(fill
			(thermal_gap 0.5)
			(thermal_bridge_width 0.5)
			(island_removal_mode 0)
		)
		(polygon
			(pts
				(arc
					(start 379.697488 -400.811238)
					(mid 379.316488 -400.430238)
					(end 378.935488 -400.811238)
				)
				(arc
					(start 378.935488 -401.674838)
					(mid 379.316488 -402.055838)
					(end 379.697488 -401.674838)
				)
			)
		)
	)
	(zone
		(layers "F.Cu" "B.Cu" "In1.Cu" "In2.Cu" "In3.Cu" "In4.Cu" "In5.Cu" "In6.Cu"
			"In7.Cu" "In8.Cu" "In9.Cu" "In10.Cu" "In11.Cu" "In12.Cu" "In13.Cu" "In14.Cu"
			"In15.Cu" "In16.Cu"
		)
		(hatch none 0.5)
		(connect_pads
			(clearance 0)
		)
		(min_thickness 0.25)
		(keepout
			(tracks not_allowed)
			(vias allowed)
			(pads allowed)
			(copperpour not_allowed)
			(footprints allowed)
		)
		(placement
			(enabled no)
			(sheetname "")
		)
		(fill
			(thermal_gap 0.5)
			(thermal_bridge_width 0.5)
			(island_removal_mode 0)
		)
		(polygon
			(pts
				(arc
					(start 124.897642 -392.429238)
					(mid 124.516642 -392.048238)
					(end 124.135642 -392.429238)
				)
				(arc
					(start 124.135642 -393.292838)
					(mid 124.516642 -393.673838)
					(end 124.897642 -393.292838)
				)
			)
		)
	)
	(zone
		(layers "F.Cu" "B.Cu" "In1.Cu" "In2.Cu" "In3.Cu" "In4.Cu" "In5.Cu" "In6.Cu"
			"In7.Cu" "In8.Cu" "In9.Cu" "In10.Cu" "In11.Cu" "In12.Cu" "In13.Cu" "In14.Cu"
			"In15.Cu" "In16.Cu"
		)
		(hatch none 0.5)
		(connect_pads
			(clearance 0)
		)
		(min_thickness 0.25)
		(keepout
			(tracks not_allowed)
			(vias allowed)
			(pads allowed)
			(copperpour not_allowed)
			(footprints allowed)
		)
		(placement
			(enabled no)
			(sheetname "")
		)
		(fill
			(thermal_gap 0.5)
			(thermal_bridge_width 0.5)
			(island_removal_mode 0)
		)
		(polygon
			(pts
				(arc
					(start 122.11177 -33.838388)
					(mid 122.49277 -34.219388)
					(end 122.87377 -33.838388)
				)
				(arc
					(start 122.87377 -32.974788)
					(mid 122.49277 -32.593788)
					(end 122.11177 -32.974788)
				)
			)
		)
	)
	(zone
		(layers "F.Cu" "B.Cu" "In1.Cu" "In2.Cu" "In3.Cu" "In4.Cu" "In5.Cu" "In6.Cu"
			"In7.Cu" "In8.Cu" "In9.Cu" "In10.Cu" "In11.Cu" "In12.Cu" "In13.Cu" "In14.Cu"
			"In15.Cu" "In16.Cu"
		)
		(hatch none 0.5)
		(connect_pads
			(clearance 0)
		)
		(min_thickness 0.25)
		(keepout
			(tracks not_allowed)
			(vias allowed)
			(pads allowed)
			(copperpour not_allowed)
			(footprints allowed)
		)
		(placement
			(enabled no)
			(sheetname "")
		)
		(fill
			(thermal_gap 0.5)
			(thermal_bridge_width 0.5)
			(island_removal_mode 0)
		)
		(polygon
			(pts
				(arc
					(start 114.894106 -412.189168)
					(mid 114.513106 -412.570168)
					(end 114.894106 -412.951168)
				)
				(arc
					(start 115.757706 -412.951168)
					(mid 116.138706 -412.570168)
					(end 115.757706 -412.189168)
				)
			)
		)
	)
	(zone
		(layers "F.Cu" "B.Cu" "In1.Cu" "In2.Cu" "In3.Cu" "In4.Cu" "In5.Cu" "In6.Cu"
			"In7.Cu" "In8.Cu" "In9.Cu" "In10.Cu" "In11.Cu" "In12.Cu" "In13.Cu" "In14.Cu"
			"In15.Cu" "In16.Cu"
		)
		(hatch none 0.5)
		(connect_pads
			(clearance 0)
		)
		(min_thickness 0.25)
		(keepout
			(tracks not_allowed)
			(vias allowed)
			(pads allowed)
			(copperpour not_allowed)
			(footprints allowed)
		)
		(placement
			(enabled no)
			(sheetname "")
		)
		(fill
			(thermal_gap 0.5)
			(thermal_bridge_width 0.5)
			(island_removal_mode 0)
		)
		(polygon
			(pts
				(arc
					(start 47.936658 -389.634476)
					(mid 48.046629 -389.73553)
					(end 48.19142 -389.772144)
				)
				(arc
					(start 48.19142 -389.772144)
					(mid 48.406946 -389.68287)
					(end 48.49622 -389.467344)
				)
				(arc
					(start 48.49622 -389.467344)
					(mid 48.485883 -389.388605)
					(end 48.45558 -389.315198)
				)
				(arc
					(start 48.06315 -388.636256)
					(mid 47.950753 -388.514639)
					(end 47.79137 -388.469632)
				)
				(arc
					(start 47.79137 -388.469632)
					(mid 47.575844 -388.558906)
					(end 47.48657 -388.774432)
				)
				(arc
					(start 47.48657 -388.774432)
					(mid 47.496148 -388.850494)
					(end 47.524416 -388.921752)
				)
				(xy 47.921672 -389.609076) (xy 47.933864 -389.630412) (xy 47.936404 -389.63473)
			)
		)
	)
	(zone
		(layers "F.Cu" "B.Cu" "In1.Cu" "In2.Cu" "In3.Cu" "In4.Cu" "In5.Cu" "In6.Cu"
			"In7.Cu" "In8.Cu" "In9.Cu" "In10.Cu" "In11.Cu" "In12.Cu" "In13.Cu" "In14.Cu"
			"In15.Cu" "In16.Cu"
		)
		(hatch none 0.5)
		(connect_pads
			(clearance 0)
		)
		(min_thickness 0.25)
		(keepout
			(tracks not_allowed)
			(vias allowed)
			(pads allowed)
			(copperpour not_allowed)
			(footprints allowed)
		)
		(placement
			(enabled no)
			(sheetname "")
		)
		(fill
			(thermal_gap 0.5)
			(thermal_bridge_width 0.5)
			(island_removal_mode 0)
		)
		(polygon
			(pts
				(arc
					(start 361.870498 -424.74007)
					(mid 357.679498 -424.74007)
					(end 361.870498 -424.74007)
				)
			)
		)
	)
	(zone
		(layers "F.Cu" "B.Cu" "In1.Cu" "In2.Cu" "In3.Cu" "In4.Cu" "In5.Cu" "In6.Cu"
			"In7.Cu" "In8.Cu" "In9.Cu" "In10.Cu" "In11.Cu" "In12.Cu" "In13.Cu" "In14.Cu"
			"In15.Cu" "In16.Cu"
		)
		(hatch none 0.5)
		(connect_pads
			(clearance 0)
		)
		(min_thickness 0.25)
		(keepout
			(tracks not_allowed)
			(vias allowed)
			(pads allowed)
			(copperpour not_allowed)
			(footprints allowed)
		)
		(placement
			(enabled no)
			(sheetname "")
		)
		(fill
			(thermal_gap 0.5)
			(thermal_bridge_width 0.5)
			(island_removal_mode 0)
		)
		(polygon
			(pts
				(arc
					(start 75.542902 -371.11813)
					(mid 75.161902 -371.49913)
					(end 75.542902 -371.88013)
				)
				(arc
					(start 76.406502 -371.88013)
					(mid 76.787502 -371.49913)
					(end 76.406502 -371.11813)
				)
			)
		)
	)
	(zone
		(layers "F.Cu" "B.Cu" "In1.Cu" "In2.Cu" "In3.Cu" "In4.Cu" "In5.Cu" "In6.Cu"
			"In7.Cu" "In8.Cu" "In9.Cu" "In10.Cu" "In11.Cu" "In12.Cu" "In13.Cu" "In14.Cu"
			"In15.Cu" "In16.Cu"
		)
		(hatch none 0.5)
		(connect_pads
			(clearance 0)
		)
		(min_thickness 0.25)
		(keepout
			(tracks not_allowed)
			(vias allowed)
			(pads allowed)
			(copperpour not_allowed)
			(footprints allowed)
		)
		(placement
			(enabled no)
			(sheetname "")
		)
		(fill
			(thermal_gap 0.5)
			(thermal_bridge_width 0.5)
			(island_removal_mode 0)
		)
		(polygon
			(pts
				(arc
					(start 342.464136 -398.016476)
					(mid 342.574107 -398.11753)
					(end 342.718898 -398.154144)
				)
				(arc
					(start 342.718898 -398.154144)
					(mid 342.934424 -398.06487)
					(end 343.023698 -397.849344)
				)
				(arc
					(start 343.023698 -397.849344)
					(mid 343.013361 -397.770605)
					(end 342.983058 -397.697198)
				)
				(arc
					(start 342.590628 -397.018256)
					(mid 342.478231 -396.896639)
					(end 342.318848 -396.851632)
				)
				(arc
					(start 342.318848 -396.851632)
					(mid 342.103322 -396.940906)
					(end 342.014048 -397.156432)
				)
				(arc
					(start 342.014048 -397.156432)
					(mid 342.023626 -397.232494)
					(end 342.051894 -397.303752)
				)
				(xy 342.44915 -397.991076) (xy 342.461342 -398.012412) (xy 342.463882 -398.01673)
			)
		)
	)
	(zone
		(layers "F.Cu" "B.Cu" "In1.Cu" "In2.Cu" "In3.Cu" "In4.Cu" "In5.Cu" "In6.Cu"
			"In7.Cu" "In8.Cu" "In9.Cu" "In10.Cu" "In11.Cu" "In12.Cu" "In13.Cu" "In14.Cu"
			"In15.Cu" "In16.Cu"
		)
		(hatch none 0.5)
		(connect_pads
			(clearance 0)
		)
		(min_thickness 0.25)
		(keepout
			(tracks not_allowed)
			(vias allowed)
			(pads allowed)
			(copperpour not_allowed)
			(footprints allowed)
		)
		(placement
			(enabled no)
			(sheetname "")
		)
		(fill yes
			(thermal_gap 0.5)
			(thermal_bridge_width 0.5)
			(island_removal_mode 0)
		)
		(polygon
			(pts
				(arc
					(start 315.936376 -394.552424)
					(mid 316.046347 -394.653478)
					(end 316.191138 -394.690092)
				)
				(arc
					(start 316.191138 -394.690092)
					(mid 316.406664 -394.600818)
					(end 316.495938 -394.385292)
				)
				(arc
					(start 316.495938 -394.385292)
					(mid 316.485601 -394.306553)
					(end 316.455298 -394.233146)
				)
				(arc
					(start 316.062868 -393.554204)
					(mid 315.950471 -393.432587)
					(end 315.791088 -393.38758)
				)
				(arc
					(start 315.791088 -393.38758)
					(mid 315.575562 -393.476854)
					(end 315.486288 -393.69238)
				)
				(arc
					(start 315.486288 -393.69238)
					(mid 315.495866 -393.768442)
					(end 315.524134 -393.8397)
				)
				(xy 315.92139 -394.527024) (xy 315.933582 -394.54836) (xy 315.936122 -394.552678)
			)
		)
	)
	(zone
		(layers "F.Cu" "B.Cu" "In1.Cu" "In2.Cu" "In3.Cu" "In4.Cu" "In5.Cu" "In6.Cu"
			"In7.Cu" "In8.Cu" "In9.Cu" "In10.Cu" "In11.Cu" "In12.Cu" "In13.Cu" "In14.Cu"
			"In15.Cu" "In16.Cu"
		)
		(hatch none 0.5)
		(connect_pads
			(clearance 0)
		)
		(min_thickness 0.25)
		(keepout
			(tracks not_allowed)
			(vias allowed)
			(pads allowed)
			(copperpour not_allowed)
			(footprints allowed)
		)
		(placement
			(enabled no)
			(sheetname "")
		)
		(fill
			(thermal_gap 0.5)
			(thermal_bridge_width 0.5)
			(island_removal_mode 0)
		)
		(polygon
			(pts
				(arc
					(start 313.797442 -400.811238)
					(mid 313.416442 -400.430238)
					(end 313.035442 -400.811238)
				)
				(arc
					(start 313.035442 -401.674838)
					(mid 313.416442 -402.055838)
					(end 313.797442 -401.674838)
				)
			)
		)
	)
	(zone
		(layers "F.Cu" "B.Cu" "In1.Cu" "In2.Cu" "In3.Cu" "In4.Cu" "In5.Cu" "In6.Cu"
			"In7.Cu" "In8.Cu" "In9.Cu" "In10.Cu" "In11.Cu" "In12.Cu" "In13.Cu" "In14.Cu"
			"In15.Cu" "In16.Cu"
		)
		(hatch none 0.5)
		(connect_pads
			(clearance 0)
		)
		(min_thickness 0.25)
		(keepout
			(tracks not_allowed)
			(vias allowed)
			(pads allowed)
			(copperpour not_allowed)
			(footprints allowed)
		)
		(placement
			(enabled no)
			(sheetname "")
		)
		(fill
			(thermal_gap 0.5)
			(thermal_bridge_width 0.5)
			(island_removal_mode 0)
		)
		(polygon
			(pts
				(arc
					(start 71.329804 -12.483846)
					(mid 70.948804 -12.864846)
					(end 71.329804 -13.245846)
				)
				(arc
					(start 72.193404 -13.245846)
					(mid 72.574404 -12.864846)
					(end 72.193404 -12.483846)
				)
			)
		)
	)
	(zone
		(layers "F.Cu" "B.Cu" "In1.Cu" "In2.Cu" "In3.Cu" "In4.Cu" "In5.Cu" "In6.Cu"
			"In7.Cu" "In8.Cu" "In9.Cu" "In10.Cu" "In11.Cu" "In12.Cu" "In13.Cu" "In14.Cu"
			"In15.Cu" "In16.Cu"
		)
		(hatch none 0.5)
		(connect_pads
			(clearance 0)
		)
		(min_thickness 0.25)
		(keepout
			(tracks not_allowed)
			(vias allowed)
			(pads allowed)
			(copperpour not_allowed)
			(footprints allowed)
		)
		(placement
			(enabled no)
			(sheetname "")
		)
		(fill
			(thermal_gap 0.5)
			(thermal_bridge_width 0.5)
			(island_removal_mode 0)
		)
		(polygon
			(pts
				(arc
					(start 114.833908 -22.151594)
					(mid 114.452908 -22.532594)
					(end 114.833908 -22.913594)
				)
				(arc
					(start 115.697508 -22.913594)
					(mid 116.078508 -22.532594)
					(end 115.697508 -22.151594)
				)
			)
		)
	)
	(zone
		(layers "F.Cu" "B.Cu" "In1.Cu" "In2.Cu" "In3.Cu" "In4.Cu" "In5.Cu" "In6.Cu"
			"In7.Cu" "In8.Cu" "In9.Cu" "In10.Cu" "In11.Cu" "In12.Cu" "In13.Cu" "In14.Cu"
			"In15.Cu" "In16.Cu"
		)
		(hatch none 0.5)
		(connect_pads
			(clearance 0)
		)
		(min_thickness 0.25)
		(keepout
			(tracks not_allowed)
			(vias allowed)
			(pads allowed)
			(copperpour not_allowed)
			(footprints allowed)
		)
		(placement
			(enabled no)
			(sheetname "")
		)
		(fill
			(thermal_gap 0.5)
			(thermal_bridge_width 0.5)
			(island_removal_mode 0)
		)
		(polygon
			(pts
				(arc
					(start 290.681918 -402.161756)
					(mid 290.300918 -401.780756)
					(end 289.919918 -402.161756)
				)
				(arc
					(start 289.919918 -403.025356)
					(mid 290.300918 -403.406356)
					(end 290.681918 -403.025356)
				)
			)
		)
	)
	(zone
		(layers "F.Cu" "B.Cu" "In1.Cu" "In2.Cu" "In3.Cu" "In4.Cu" "In5.Cu" "In6.Cu"
			"In7.Cu" "In8.Cu" "In9.Cu" "In10.Cu" "In11.Cu" "In12.Cu" "In13.Cu" "In14.Cu"
			"In15.Cu" "In16.Cu"
		)
		(hatch none 0.5)
		(connect_pads
			(clearance 0)
		)
		(min_thickness 0.25)
		(keepout
			(tracks not_allowed)
			(vias allowed)
			(pads allowed)
			(copperpour not_allowed)
			(footprints allowed)
		)
		(placement
			(enabled no)
			(sheetname "")
		)
		(fill
			(thermal_gap 0.5)
			(thermal_bridge_width 0.5)
			(island_removal_mode 0)
		)
		(polygon
			(pts
				(arc
					(start 119.488966 -406.62352)
					(mid 119.107966 -407.00452)
					(end 119.488966 -407.38552)
				)
				(arc
					(start 120.352566 -407.38552)
					(mid 120.733566 -407.00452)
					(end 120.352566 -406.62352)
				)
			)
		)
	)
	(zone
		(layers "F.Cu" "B.Cu" "In1.Cu" "In2.Cu" "In3.Cu" "In4.Cu" "In5.Cu" "In6.Cu"
			"In7.Cu" "In8.Cu" "In9.Cu" "In10.Cu" "In11.Cu" "In12.Cu" "In13.Cu" "In14.Cu"
			"In15.Cu" "In16.Cu"
		)
		(hatch none 0.5)
		(connect_pads
			(clearance 0)
		)
		(min_thickness 0.25)
		(keepout
			(tracks not_allowed)
			(vias allowed)
			(pads allowed)
			(copperpour not_allowed)
			(footprints allowed)
		)
		(placement
			(enabled no)
			(sheetname "")
		)
		(fill
			(thermal_gap 0.5)
			(thermal_bridge_width 0.5)
			(island_removal_mode 0)
		)
		(polygon
			(pts
				(arc
					(start 139.400026 -404.08352)
					(mid 139.019026 -404.46452)
					(end 139.400026 -404.84552)
				)
				(arc
					(start 140.263626 -404.84552)
					(mid 140.644626 -404.46452)
					(end 140.263626 -404.08352)
				)
			)
		)
	)
	(zone
		(layers "F.Cu" "B.Cu" "In1.Cu" "In2.Cu" "In3.Cu" "In4.Cu" "In5.Cu" "In6.Cu"
			"In7.Cu" "In8.Cu" "In9.Cu" "In10.Cu" "In11.Cu" "In12.Cu" "In13.Cu" "In14.Cu"
			"In15.Cu" "In16.Cu"
		)
		(hatch none 0.5)
		(connect_pads
			(clearance 0)
		)
		(min_thickness 0.25)
		(keepout
			(tracks not_allowed)
			(vias allowed)
			(pads allowed)
			(copperpour not_allowed)
			(footprints allowed)
		)
		(placement
			(enabled no)
			(sheetname "")
		)
		(fill
			(thermal_gap 0.5)
			(thermal_bridge_width 0.5)
			(island_removal_mode 0)
		)
		(polygon
			(pts
				(arc
					(start 412.25724 -379.50013)
					(mid 411.87624 -379.88113)
					(end 412.25724 -380.26213)
				)
				(arc
					(start 413.12084 -380.26213)
					(mid 413.50184 -379.88113)
					(end 413.12084 -379.50013)
				)
			)
		)
	)
	(zone
		(layers "F.Cu" "B.Cu" "In1.Cu" "In2.Cu" "In3.Cu" "In4.Cu" "In5.Cu" "In6.Cu"
			"In7.Cu" "In8.Cu" "In9.Cu" "In10.Cu" "In11.Cu" "In12.Cu" "In13.Cu" "In14.Cu"
			"In15.Cu" "In16.Cu"
		)
		(hatch none 0.5)
		(connect_pads
			(clearance 0)
		)
		(min_thickness 0.25)
		(keepout
			(tracks not_allowed)
			(vias allowed)
			(pads allowed)
			(copperpour not_allowed)
			(footprints allowed)
		)
		(placement
			(enabled no)
			(sheetname "")
		)
		(fill yes
			(thermal_gap 0.5)
			(thermal_bridge_width 0.5)
			(island_removal_mode 0)
		)
		(polygon
			(pts
				(arc
					(start 321.936364 -394.552424)
					(mid 322.046335 -394.653478)
					(end 322.191126 -394.690092)
				)
				(arc
					(start 322.191126 -394.690092)
					(mid 322.406652 -394.600818)
					(end 322.495926 -394.385292)
				)
				(arc
					(start 322.495926 -394.385292)
					(mid 322.485589 -394.306553)
					(end 322.455286 -394.233146)
				)
				(arc
					(start 322.062856 -393.554204)
					(mid 321.950459 -393.432587)
					(end 321.791076 -393.38758)
				)
				(arc
					(start 321.791076 -393.38758)
					(mid 321.57555 -393.476854)
					(end 321.486276 -393.69238)
				)
				(arc
					(start 321.486276 -393.69238)
					(mid 321.495854 -393.768442)
					(end 321.524122 -393.8397)
				)
				(xy 321.921378 -394.527024) (xy 321.93357 -394.54836) (xy 321.93611 -394.552678)
			)
		)
	)
	(zone
		(layers "F.Cu" "B.Cu" "In1.Cu" "In2.Cu" "In3.Cu" "In4.Cu" "In5.Cu" "In6.Cu"
			"In7.Cu" "In8.Cu" "In9.Cu" "In10.Cu" "In11.Cu" "In12.Cu" "In13.Cu" "In14.Cu"
			"In15.Cu" "In16.Cu"
		)
		(hatch none 0.5)
		(connect_pads
			(clearance 0)
		)
		(min_thickness 0.25)
		(keepout
			(tracks not_allowed)
			(vias allowed)
			(pads allowed)
			(copperpour not_allowed)
			(footprints allowed)
		)
		(placement
			(enabled no)
			(sheetname "")
		)
		(fill
			(thermal_gap 0.5)
			(thermal_bridge_width 0.5)
			(island_removal_mode 0)
		)
		(polygon
			(pts
				(arc
					(start 63.536576 -389.634476)
					(mid 63.646547 -389.73553)
					(end 63.791338 -389.772144)
				)
				(arc
					(start 63.791338 -389.772144)
					(mid 64.006864 -389.68287)
					(end 64.096138 -389.467344)
				)
				(arc
					(start 64.096138 -389.467344)
					(mid 64.085801 -389.388605)
					(end 64.055498 -389.315198)
				)
				(arc
					(start 63.663068 -388.636256)
					(mid 63.550671 -388.514639)
					(end 63.391288 -388.469632)
				)
				(arc
					(start 63.391288 -388.469632)
					(mid 63.175762 -388.558906)
					(end 63.086488 -388.774432)
				)
				(arc
					(start 63.086488 -388.774432)
					(mid 63.096066 -388.850494)
					(end 63.124334 -388.921752)
				)
				(xy 63.52159 -389.609076) (xy 63.533782 -389.630412) (xy 63.536322 -389.63473)
			)
		)
	)
	(zone
		(layers "F.Cu" "B.Cu" "In1.Cu" "In2.Cu" "In3.Cu" "In4.Cu" "In5.Cu" "In6.Cu"
			"In7.Cu" "In8.Cu" "In9.Cu" "In10.Cu" "In11.Cu" "In12.Cu" "In13.Cu" "In14.Cu"
			"In15.Cu" "In16.Cu"
		)
		(hatch none 0.5)
		(connect_pads
			(clearance 0)
		)
		(min_thickness 0.25)
		(keepout
			(tracks not_allowed)
			(vias allowed)
			(pads allowed)
			(copperpour not_allowed)
			(footprints allowed)
		)
		(placement
			(enabled no)
			(sheetname "")
		)
		(fill
			(thermal_gap 0.5)
			(thermal_bridge_width 0.5)
			(island_removal_mode 0)
		)
		(polygon
			(pts
				(arc
					(start 350.262444 -381.96393)
					(mid 349.881444 -382.34493)
					(end 350.262444 -382.72593)
				)
				(arc
					(start 351.126044 -382.72593)
					(mid 351.507044 -382.34493)
					(end 351.126044 -381.96393)
				)
			)
		)
	)
	(zone
		(layers "F.Cu" "B.Cu" "In1.Cu" "In2.Cu" "In3.Cu" "In4.Cu" "In5.Cu" "In6.Cu"
			"In7.Cu" "In8.Cu" "In9.Cu" "In10.Cu" "In11.Cu" "In12.Cu" "In13.Cu" "In14.Cu"
			"In15.Cu" "In16.Cu"
		)
		(hatch none 0.5)
		(connect_pads
			(clearance 0)
		)
		(min_thickness 0.25)
		(keepout
			(tracks not_allowed)
			(vias allowed)
			(pads allowed)
			(copperpour not_allowed)
			(footprints allowed)
		)
		(placement
			(enabled no)
			(sheetname "")
		)
		(fill
			(thermal_gap 0.5)
			(thermal_bridge_width 0.5)
			(island_removal_mode 0)
		)
		(polygon
			(pts
				(arc
					(start 60.047124 -412.189168)
					(mid 59.666124 -412.570168)
					(end 60.047124 -412.951168)
				)
				(arc
					(start 60.910724 -412.951168)
					(mid 61.291724 -412.570168)
					(end 60.910724 -412.189168)
				)
			)
		)
	)
	(zone
		(layers "F.Cu" "B.Cu" "In1.Cu" "In2.Cu" "In3.Cu" "In4.Cu" "In5.Cu" "In6.Cu"
			"In7.Cu" "In8.Cu" "In9.Cu" "In10.Cu" "In11.Cu" "In12.Cu" "In13.Cu" "In14.Cu"
			"In15.Cu" "In16.Cu"
		)
		(hatch none 0.5)
		(connect_pads
			(clearance 0)
		)
		(min_thickness 0.25)
		(keepout
			(tracks not_allowed)
			(vias allowed)
			(pads allowed)
			(copperpour not_allowed)
			(footprints allowed)
		)
		(placement
			(enabled no)
			(sheetname "")
		)
		(fill
			(thermal_gap 0.5)
			(thermal_bridge_width 0.5)
			(island_removal_mode 0)
		)
		(polygon
			(pts
				(arc
					(start 21.121878 -17.23136)
					(mid 20.740878 -17.61236)
					(end 21.121878 -17.99336)
				)
				(arc
					(start 21.985478 -17.99336)
					(mid 22.366478 -17.61236)
					(end 21.985478 -17.23136)
				)
			)
		)
	)
	(zone
		(layers "F.Cu" "B.Cu" "In1.Cu" "In2.Cu" "In3.Cu" "In4.Cu" "In5.Cu" "In6.Cu"
			"In7.Cu" "In8.Cu" "In9.Cu" "In10.Cu" "In11.Cu" "In12.Cu" "In13.Cu" "In14.Cu"
			"In15.Cu" "In16.Cu"
		)
		(hatch none 0.5)
		(connect_pads
			(clearance 0)
		)
		(min_thickness 0.25)
		(keepout
			(tracks not_allowed)
			(vias allowed)
			(pads allowed)
			(copperpour not_allowed)
			(footprints allowed)
		)
		(placement
			(enabled no)
			(sheetname "")
		)
		(fill
			(thermal_gap 0.5)
			(thermal_bridge_width 0.5)
			(island_removal_mode 0)
		)
		(polygon
			(pts
				(arc
					(start 28.020264 -4.582414)
					(mid 27.639264 -4.963414)
					(end 28.020264 -5.344414)
				)
				(arc
					(start 28.883864 -5.344414)
					(mid 29.264864 -4.963414)
					(end 28.883864 -4.582414)
				)
			)
		)
	)
	(zone
		(layers "F.Cu" "B.Cu" "In1.Cu" "In2.Cu" "In3.Cu" "In4.Cu" "In5.Cu" "In6.Cu"
			"In7.Cu" "In8.Cu" "In9.Cu" "In10.Cu" "In11.Cu" "In12.Cu" "In13.Cu" "In14.Cu"
			"In15.Cu" "In16.Cu"
		)
		(hatch none 0.5)
		(connect_pads
			(clearance 0)
		)
		(min_thickness 0.25)
		(keepout
			(tracks not_allowed)
			(vias allowed)
			(pads allowed)
			(copperpour not_allowed)
			(footprints allowed)
		)
		(placement
			(enabled no)
			(sheetname "")
		)
		(fill
			(thermal_gap 0.5)
			(thermal_bridge_width 0.5)
			(island_removal_mode 0)
		)
		(polygon
			(pts
				(arc
					(start 151.16429 -389.634476)
					(mid 151.274261 -389.73553)
					(end 151.419052 -389.772144)
				)
				(arc
					(start 151.419052 -389.772144)
					(mid 151.634578 -389.68287)
					(end 151.723852 -389.467344)
				)
				(arc
					(start 151.723852 -389.467344)
					(mid 151.713515 -389.388605)
					(end 151.683212 -389.315198)
				)
				(arc
					(start 151.290782 -388.636256)
					(mid 151.178385 -388.514639)
					(end 151.019002 -388.469632)
				)
				(arc
					(start 151.019002 -388.469632)
					(mid 150.803476 -388.558906)
					(end 150.714202 -388.774432)
				)
				(arc
					(start 150.714202 -388.774432)
					(mid 150.72378 -388.850494)
					(end 150.752048 -388.921752)
				)
				(xy 151.149304 -389.609076) (xy 151.161496 -389.630412) (xy 151.164036 -389.63473)
			)
		)
	)
	(zone
		(layers "F.Cu" "B.Cu" "In1.Cu" "In2.Cu" "In3.Cu" "In4.Cu" "In5.Cu" "In6.Cu"
			"In7.Cu" "In8.Cu" "In9.Cu" "In10.Cu" "In11.Cu" "In12.Cu" "In13.Cu" "In14.Cu"
			"In15.Cu" "In16.Cu"
		)
		(hatch none 0.5)
		(connect_pads
			(clearance 0)
		)
		(min_thickness 0.25)
		(keepout
			(tracks not_allowed)
			(vias allowed)
			(pads allowed)
			(copperpour not_allowed)
			(footprints allowed)
		)
		(placement
			(enabled no)
			(sheetname "")
		)
		(fill
			(thermal_gap 0.5)
			(thermal_bridge_width 0.5)
			(island_removal_mode 0)
		)
		(polygon
			(pts
				(arc
					(start 147.748244 -373.58193)
					(mid 147.367244 -373.96293)
					(end 147.748244 -374.34393)
				)
				(arc
					(start 148.611844 -374.34393)
					(mid 148.992844 -373.96293)
					(end 148.611844 -373.58193)
				)
			)
		)
	)
	(zone
		(layers "F.Cu" "B.Cu" "In1.Cu" "In2.Cu" "In3.Cu" "In4.Cu" "In5.Cu" "In6.Cu"
			"In7.Cu" "In8.Cu" "In9.Cu" "In10.Cu" "In11.Cu" "In12.Cu" "In13.Cu" "In14.Cu"
			"In15.Cu" "In16.Cu"
		)
		(hatch none 0.5)
		(connect_pads
			(clearance 0)
		)
		(min_thickness 0.25)
		(keepout
			(tracks not_allowed)
			(vias allowed)
			(pads allowed)
			(copperpour not_allowed)
			(footprints allowed)
		)
		(placement
			(enabled no)
			(sheetname "")
		)
		(fill
			(thermal_gap 0.5)
			(thermal_bridge_width 0.5)
			(island_removal_mode 0)
		)
		(polygon
			(pts
				(arc
					(start 384.49758 -400.811238)
					(mid 384.11658 -400.430238)
					(end 383.73558 -400.811238)
				)
				(arc
					(start 383.73558 -401.674838)
					(mid 384.11658 -402.055838)
					(end 384.49758 -401.674838)
				)
			)
		)
	)
	(zone
		(layers "F.Cu" "B.Cu" "In1.Cu" "In2.Cu" "In3.Cu" "In4.Cu" "In5.Cu" "In6.Cu"
			"In7.Cu" "In8.Cu" "In9.Cu" "In10.Cu" "In11.Cu" "In12.Cu" "In13.Cu" "In14.Cu"
			"In15.Cu" "In16.Cu"
		)
		(hatch none 0.5)
		(connect_pads
			(clearance 0)
		)
		(min_thickness 0.25)
		(keepout
			(tracks not_allowed)
			(vias allowed)
			(pads allowed)
			(copperpour not_allowed)
			(footprints allowed)
		)
		(placement
			(enabled no)
			(sheetname "")
		)
		(fill
			(thermal_gap 0.5)
			(thermal_bridge_width 0.5)
			(island_removal_mode 0)
		)
		(polygon
			(pts
				(arc
					(start 44.330366 -4.582414)
					(mid 43.949366 -4.963414)
					(end 44.330366 -5.344414)
				)
				(arc
					(start 45.193966 -5.344414)
					(mid 45.574966 -4.963414)
					(end 45.193966 -4.582414)
				)
			)
		)
	)
	(zone
		(layers "F.Cu" "B.Cu" "In1.Cu" "In2.Cu" "In3.Cu" "In4.Cu" "In5.Cu" "In6.Cu"
			"In7.Cu" "In8.Cu" "In9.Cu" "In10.Cu" "In11.Cu" "In12.Cu" "In13.Cu" "In14.Cu"
			"In15.Cu" "In16.Cu"
		)
		(hatch none 0.5)
		(connect_pads
			(clearance 0)
		)
		(min_thickness 0.25)
		(keepout
			(tracks not_allowed)
			(vias allowed)
			(pads allowed)
			(copperpour not_allowed)
			(footprints allowed)
		)
		(placement
			(enabled no)
			(sheetname "")
		)
		(fill
			(thermal_gap 0.5)
			(thermal_bridge_width 0.5)
			(island_removal_mode 0)
		)
		(polygon
			(pts
				(arc
					(start 124.083826 -404.08352)
					(mid 123.702826 -404.46452)
					(end 124.083826 -404.84552)
				)
				(arc
					(start 124.947426 -404.84552)
					(mid 125.328426 -404.46452)
					(end 124.947426 -404.08352)
				)
			)
		)
	)
	(zone
		(layers "F.Cu" "B.Cu" "In1.Cu" "In2.Cu" "In3.Cu" "In4.Cu" "In5.Cu" "In6.Cu"
			"In7.Cu" "In8.Cu" "In9.Cu" "In10.Cu" "In11.Cu" "In12.Cu" "In13.Cu" "In14.Cu"
			"In15.Cu" "In16.Cu"
		)
		(hatch none 0.5)
		(connect_pads
			(clearance 0)
		)
		(min_thickness 0.25)
		(keepout
			(tracks not_allowed)
			(vias allowed)
			(pads allowed)
			(copperpour not_allowed)
			(footprints allowed)
		)
		(placement
			(enabled no)
			(sheetname "")
		)
		(fill
			(thermal_gap 0.5)
			(thermal_bridge_width 0.5)
			(island_removal_mode 0)
		)
		(polygon
			(pts
				(arc
					(start 42.525696 -6.344158)
					(mid 42.144696 -6.725158)
					(end 42.525696 -7.106158)
				)
				(arc
					(start 43.389296 -7.106158)
					(mid 43.770296 -6.725158)
					(end 43.389296 -6.344158)
				)
			)
		)
	)
	(zone
		(layers "F.Cu" "B.Cu" "In1.Cu" "In2.Cu" "In3.Cu" "In4.Cu" "In5.Cu" "In6.Cu"
			"In7.Cu" "In8.Cu" "In9.Cu" "In10.Cu" "In11.Cu" "In12.Cu" "In13.Cu" "In14.Cu"
			"In15.Cu" "In16.Cu"
		)
		(hatch none 0.5)
		(connect_pads
			(clearance 0)
		)
		(min_thickness 0.25)
		(keepout
			(tracks not_allowed)
			(vias allowed)
			(pads allowed)
			(copperpour not_allowed)
			(footprints allowed)
		)
		(placement
			(enabled no)
			(sheetname "")
		)
		(fill
			(thermal_gap 0.5)
			(thermal_bridge_width 0.5)
			(island_removal_mode 0)
		)
		(polygon
			(pts
				(arc
					(start 298.630086 4.651756)
					(mid 299.061886 4.219956)
					(end 299.493686 4.651756)
				)
				(arc
					(start 299.493686 5.515356)
					(mid 299.061886 5.947156)
					(end 298.630086 5.515356)
				)
			)
		)
	)
	(zone
		(layers "F.Cu" "B.Cu" "In1.Cu" "In2.Cu" "In3.Cu" "In4.Cu" "In5.Cu" "In6.Cu"
			"In7.Cu" "In8.Cu" "In9.Cu" "In10.Cu" "In11.Cu" "In12.Cu" "In13.Cu" "In14.Cu"
			"In15.Cu" "In16.Cu"
		)
		(hatch none 0.5)
		(connect_pads
			(clearance 0)
		)
		(min_thickness 0.25)
		(keepout
			(tracks not_allowed)
			(vias allowed)
			(pads allowed)
			(copperpour not_allowed)
			(footprints allowed)
		)
		(placement
			(enabled no)
			(sheetname "")
		)
		(fill
			(thermal_gap 0.5)
			(thermal_bridge_width 0.5)
			(island_removal_mode 0)
		)
		(polygon
			(pts
				(arc
					(start 73.831704 -409.649168)
					(mid 73.450704 -410.030168)
					(end 73.831704 -410.411168)
				)
				(arc
					(start 74.695304 -410.411168)
					(mid 75.076304 -410.030168)
					(end 74.695304 -409.649168)
				)
			)
		)
	)
	(zone
		(layers "F.Cu" "B.Cu" "In1.Cu" "In2.Cu" "In3.Cu" "In4.Cu" "In5.Cu" "In6.Cu"
			"In7.Cu" "In8.Cu" "In9.Cu" "In10.Cu" "In11.Cu" "In12.Cu" "In13.Cu" "In14.Cu"
			"In15.Cu" "In16.Cu"
		)
		(hatch none 0.5)
		(connect_pads
			(clearance 0)
		)
		(min_thickness 0.25)
		(keepout
			(tracks not_allowed)
			(vias allowed)
			(pads allowed)
			(copperpour not_allowed)
			(footprints allowed)
		)
		(placement
			(enabled no)
			(sheetname "")
		)
		(fill
			(thermal_gap 0.5)
			(thermal_bridge_width 0.5)
			(island_removal_mode 0)
		)
		(polygon
			(pts
				(arc
					(start 25.639522 -421.266874)
					(mid 25.258522 -420.885874)
					(end 24.877522 -421.266874)
				)
				(arc
					(start 24.877522 -422.130474)
					(mid 25.258522 -422.511474)
					(end 25.639522 -422.130474)
				)
			)
		)
	)
	(zone
		(layers "F.Cu" "B.Cu" "In1.Cu" "In2.Cu" "In3.Cu" "In4.Cu" "In5.Cu" "In6.Cu"
			"In7.Cu" "In8.Cu" "In9.Cu" "In10.Cu" "In11.Cu" "In12.Cu" "In13.Cu" "In14.Cu"
			"In15.Cu" "In16.Cu"
		)
		(hatch none 0.5)
		(connect_pads
			(clearance 0)
		)
		(min_thickness 0.25)
		(keepout
			(tracks not_allowed)
			(vias allowed)
			(pads allowed)
			(copperpour not_allowed)
			(footprints allowed)
		)
		(placement
			(enabled no)
			(sheetname "")
		)
		(fill
			(thermal_gap 0.5)
			(thermal_bridge_width 0.5)
			(island_removal_mode 0)
		)
		(polygon
			(pts
				(arc
					(start 11.636248 -114.325908)
					(mid 11.255248 -114.706908)
					(end 11.636248 -115.087908)
				)
				(arc
					(start 12.499848 -115.087908)
					(mid 12.880848 -114.706908)
					(end 12.499848 -114.325908)
				)
			)
		)
	)
	(zone
		(layers "F.Cu" "B.Cu" "In1.Cu" "In2.Cu" "In3.Cu" "In4.Cu" "In5.Cu" "In6.Cu"
			"In7.Cu" "In8.Cu" "In9.Cu" "In10.Cu" "In11.Cu" "In12.Cu" "In13.Cu" "In14.Cu"
			"In15.Cu" "In16.Cu"
		)
		(hatch none 0.5)
		(connect_pads
			(clearance 0)
		)
		(min_thickness 0.25)
		(keepout
			(tracks not_allowed)
			(vias allowed)
			(pads allowed)
			(copperpour not_allowed)
			(footprints allowed)
		)
		(placement
			(enabled no)
			(sheetname "")
		)
		(fill
			(thermal_gap 0.5)
			(thermal_bridge_width 0.5)
			(island_removal_mode 0)
		)
		(polygon
			(pts
				(arc
					(start 388.238492 -377.03633)
					(mid 387.857492 -377.41733)
					(end 388.238492 -377.79833)
				)
				(arc
					(start 389.102092 -377.79833)
					(mid 389.483092 -377.41733)
					(end 389.102092 -377.03633)
				)
			)
		)
	)
	(zone
		(layers "F.Cu" "B.Cu" "In1.Cu" "In2.Cu" "In3.Cu" "In4.Cu" "In5.Cu" "In6.Cu"
			"In7.Cu" "In8.Cu" "In9.Cu" "In10.Cu" "In11.Cu" "In12.Cu" "In13.Cu" "In14.Cu"
			"In15.Cu" "In16.Cu"
		)
		(hatch none 0.5)
		(connect_pads
			(clearance 0)
		)
		(min_thickness 0.25)
		(keepout
			(tracks not_allowed)
			(vias allowed)
			(pads allowed)
			(copperpour not_allowed)
			(footprints allowed)
		)
		(placement
			(enabled no)
			(sheetname "")
		)
		(fill
			(thermal_gap 0.5)
			(thermal_bridge_width 0.5)
			(island_removal_mode 0)
		)
		(polygon
			(pts
				(arc
					(start 424.635676 -6.344158)
					(mid 424.254676 -6.725158)
					(end 424.635676 -7.106158)
				)
				(arc
					(start 425.499276 -7.106158)
					(mid 425.880276 -6.725158)
					(end 425.499276 -6.344158)
				)
			)
		)
	)
	(zone
		(layers "F.Cu" "B.Cu" "In1.Cu" "In2.Cu" "In3.Cu" "In4.Cu" "In5.Cu" "In6.Cu"
			"In7.Cu" "In8.Cu" "In9.Cu" "In10.Cu" "In11.Cu" "In12.Cu" "In13.Cu" "In14.Cu"
			"In15.Cu" "In16.Cu"
		)
		(hatch none 0.5)
		(connect_pads
			(clearance 0)
		)
		(min_thickness 0.25)
		(keepout
			(tracks not_allowed)
			(vias allowed)
			(pads allowed)
			(copperpour not_allowed)
			(footprints allowed)
		)
		(placement
			(enabled no)
			(sheetname "")
		)
		(fill
			(thermal_gap 0.5)
			(thermal_bridge_width 0.5)
			(island_removal_mode 0)
		)
		(polygon
			(pts
				(arc
					(start 323.704966 -415.00552)
					(mid 323.323966 -415.38652)
					(end 323.704966 -415.76752)
				)
				(arc
					(start 324.568566 -415.76752)
					(mid 324.949566 -415.38652)
					(end 324.568566 -415.00552)
				)
			)
		)
	)
	(zone
		(layers "F.Cu" "B.Cu" "In1.Cu" "In2.Cu" "In3.Cu" "In4.Cu" "In5.Cu" "In6.Cu"
			"In7.Cu" "In8.Cu" "In9.Cu" "In10.Cu" "In11.Cu" "In12.Cu" "In13.Cu" "In14.Cu"
			"In15.Cu" "In16.Cu"
		)
		(hatch none 0.5)
		(connect_pads
			(clearance 0)
		)
		(min_thickness 0.25)
		(keepout
			(tracks not_allowed)
			(vias allowed)
			(pads allowed)
			(copperpour not_allowed)
			(footprints allowed)
		)
		(placement
			(enabled no)
			(sheetname "")
		)
		(fill
			(thermal_gap 0.5)
			(thermal_bridge_width 0.5)
			(island_removal_mode 0)
		)
		(polygon
			(pts
				(arc
					(start 297.811444 -384.35026)
					(mid 297.430444 -383.96926)
					(end 297.049444 -384.35026)
				)
				(arc
					(start 297.049444 -385.21386)
					(mid 297.430444 -385.59486)
					(end 297.811444 -385.21386)
				)
			)
		)
	)
	(zone
		(layers "F.Cu" "B.Cu" "In1.Cu" "In2.Cu" "In3.Cu" "In4.Cu" "In5.Cu" "In6.Cu"
			"In7.Cu" "In8.Cu" "In9.Cu" "In10.Cu" "In11.Cu" "In12.Cu" "In13.Cu" "In14.Cu"
			"In15.Cu" "In16.Cu"
		)
		(hatch none 0.5)
		(connect_pads
			(clearance 0)
		)
		(min_thickness 0.25)
		(keepout
			(tracks not_allowed)
			(vias allowed)
			(pads allowed)
			(copperpour not_allowed)
			(footprints allowed)
		)
		(placement
			(enabled no)
			(sheetname "")
		)
		(fill
			(thermal_gap 0.5)
			(thermal_bridge_width 0.5)
			(island_removal_mode 0)
		)
		(polygon
			(pts
				(arc
					(start 10.013188 -421.200326)
					(mid 10.394188 -421.581326)
					(end 10.775188 -421.200326)
				)
				(arc
					(start 10.775188 -420.336726)
					(mid 10.394188 -419.955726)
					(end 10.013188 -420.336726)
				)
			)
		)
	)
	(zone
		(layers "F.Cu" "B.Cu" "In1.Cu" "In2.Cu" "In3.Cu" "In4.Cu" "In5.Cu" "In6.Cu"
			"In7.Cu" "In8.Cu" "In9.Cu" "In10.Cu" "In11.Cu" "In12.Cu" "In13.Cu" "In14.Cu"
			"In15.Cu" "In16.Cu"
		)
		(hatch none 0.5)
		(connect_pads
			(clearance 0)
		)
		(min_thickness 0.25)
		(keepout
			(tracks not_allowed)
			(vias allowed)
			(pads allowed)
			(copperpour not_allowed)
			(footprints allowed)
		)
		(placement
			(enabled no)
			(sheetname "")
		)
		(fill
			(thermal_gap 0.5)
			(thermal_bridge_width 0.5)
			(island_removal_mode 0)
		)
		(polygon
			(pts
				(arc
					(start 400.71548 -6.344158)
					(mid 400.33448 -6.725158)
					(end 400.71548 -7.106158)
				)
				(arc
					(start 401.57908 -7.106158)
					(mid 401.96008 -6.725158)
					(end 401.57908 -6.344158)
				)
			)
		)
	)
	(zone
		(layers "F.Cu" "B.Cu" "In1.Cu" "In2.Cu" "In3.Cu" "In4.Cu" "In5.Cu" "In6.Cu"
			"In7.Cu" "In8.Cu" "In9.Cu" "In10.Cu" "In11.Cu" "In12.Cu" "In13.Cu" "In14.Cu"
			"In15.Cu" "In16.Cu"
		)
		(hatch none 0.5)
		(connect_pads
			(clearance 0)
		)
		(min_thickness 0.25)
		(keepout
			(tracks not_allowed)
			(vias allowed)
			(pads allowed)
			(copperpour not_allowed)
			(footprints allowed)
		)
		(placement
			(enabled no)
			(sheetname "")
		)
		(fill yes
			(thermal_gap 0.5)
			(thermal_bridge_width 0.5)
			(island_removal_mode 0)
		)
		(polygon
			(pts
				(arc
					(start 125.836426 -386.170424)
					(mid 125.946397 -386.271478)
					(end 126.091188 -386.308092)
				)
				(arc
					(start 126.091188 -386.308092)
					(mid 126.306714 -386.218818)
					(end 126.395988 -386.003292)
				)
				(arc
					(start 126.395988 -386.003292)
					(mid 126.385651 -385.924553)
					(end 126.355348 -385.851146)
				)
				(arc
					(start 125.962918 -385.172204)
					(mid 125.850521 -385.050587)
					(end 125.691138 -385.00558)
				)
				(arc
					(start 125.691138 -385.00558)
					(mid 125.475612 -385.094854)
					(end 125.386338 -385.31038)
				)
				(arc
					(start 125.386338 -385.31038)
					(mid 125.395916 -385.386442)
					(end 125.424184 -385.4577)
				)
				(xy 125.82144 -386.145024) (xy 125.833632 -386.16636) (xy 125.836172 -386.170678)
			)
		)
	)
	(zone
		(layers "F.Cu" "B.Cu" "In1.Cu" "In2.Cu" "In3.Cu" "In4.Cu" "In5.Cu" "In6.Cu"
			"In7.Cu" "In8.Cu" "In9.Cu" "In10.Cu" "In11.Cu" "In12.Cu" "In13.Cu" "In14.Cu"
			"In15.Cu" "In16.Cu"
		)
		(hatch none 0.5)
		(connect_pads
			(clearance 0)
		)
		(min_thickness 0.25)
		(keepout
			(tracks not_allowed)
			(vias allowed)
			(pads allowed)
			(copperpour not_allowed)
			(footprints allowed)
		)
		(placement
			(enabled no)
			(sheetname "")
		)
		(fill
			(thermal_gap 0.5)
			(thermal_bridge_width 0.5)
			(island_removal_mode 0)
		)
		(polygon
			(pts
				(arc
					(start 56.59755 -392.429238)
					(mid 56.21655 -392.048238)
					(end 55.83555 -392.429238)
				)
				(arc
					(start 55.83555 -393.292838)
					(mid 56.21655 -393.673838)
					(end 56.59755 -393.292838)
				)
			)
		)
	)
	(zone
		(layers "F.Cu" "B.Cu" "In1.Cu" "In2.Cu" "In3.Cu" "In4.Cu" "In5.Cu" "In6.Cu"
			"In7.Cu" "In8.Cu" "In9.Cu" "In10.Cu" "In11.Cu" "In12.Cu" "In13.Cu" "In14.Cu"
			"In15.Cu" "In16.Cu"
		)
		(hatch none 0.5)
		(connect_pads
			(clearance 0)
		)
		(min_thickness 0.25)
		(keepout
			(tracks not_allowed)
			(vias allowed)
			(pads allowed)
			(copperpour not_allowed)
			(footprints allowed)
		)
		(placement
			(enabled no)
			(sheetname "")
		)
		(fill
			(thermal_gap 0.5)
			(thermal_bridge_width 0.5)
			(island_removal_mode 0)
		)
		(polygon
			(pts
				(arc
					(start 60.197746 -392.429238)
					(mid 59.816746 -392.048238)
					(end 59.435746 -392.429238)
				)
				(arc
					(start 59.435746 -393.292838)
					(mid 59.816746 -393.673838)
					(end 60.197746 -393.292838)
				)
			)
		)
	)
	(zone
		(layers "F.Cu" "B.Cu" "In1.Cu" "In2.Cu" "In3.Cu" "In4.Cu" "In5.Cu" "In6.Cu"
			"In7.Cu" "In8.Cu" "In9.Cu" "In10.Cu" "In11.Cu" "In12.Cu" "In13.Cu" "In14.Cu"
			"In15.Cu" "In16.Cu"
		)
		(hatch none 0.5)
		(connect_pads
			(clearance 0)
		)
		(min_thickness 0.25)
		(keepout
			(tracks not_allowed)
			(vias allowed)
			(pads allowed)
			(copperpour not_allowed)
			(footprints allowed)
		)
		(placement
			(enabled no)
			(sheetname "")
		)
		(fill
			(thermal_gap 0.5)
			(thermal_bridge_width 0.5)
			(island_removal_mode 0)
		)
		(polygon
			(pts
				(arc
					(start 171.286424 -379.496828)
					(mid 170.905424 -379.115828)
					(end 170.524424 -379.496828)
				)
				(arc
					(start 170.524424 -380.360428)
					(mid 170.905424 -380.741428)
					(end 171.286424 -380.360428)
				)
			)
		)
	)
	(zone
		(layers "F.Cu" "B.Cu" "In1.Cu" "In2.Cu" "In3.Cu" "In4.Cu" "In5.Cu" "In6.Cu"
			"In7.Cu" "In8.Cu" "In9.Cu" "In10.Cu" "In11.Cu" "In12.Cu" "In13.Cu" "In14.Cu"
			"In15.Cu" "In16.Cu"
		)
		(hatch none 0.5)
		(connect_pads
			(clearance 0)
		)
		(min_thickness 0.25)
		(keepout
			(tracks not_allowed)
			(vias allowed)
			(pads allowed)
			(copperpour not_allowed)
			(footprints allowed)
		)
		(placement
			(enabled no)
			(sheetname "")
		)
		(fill
			(thermal_gap 0.5)
			(thermal_bridge_width 0.5)
			(island_removal_mode 0)
		)
		(polygon
			(pts
				(arc
					(start 123.729496 -371.11813)
					(mid 123.348496 -371.49913)
					(end 123.729496 -371.88013)
				)
				(arc
					(start 124.593096 -371.88013)
					(mid 124.974096 -371.49913)
					(end 124.593096 -371.11813)
				)
			)
		)
	)
	(zone
		(layers "F.Cu" "B.Cu" "In1.Cu" "In2.Cu" "In3.Cu" "In4.Cu" "In5.Cu" "In6.Cu"
			"In7.Cu" "In8.Cu" "In9.Cu" "In10.Cu" "In11.Cu" "In12.Cu" "In13.Cu" "In14.Cu"
			"In15.Cu" "In16.Cu"
		)
		(hatch none 0.5)
		(connect_pads
			(clearance 0)
		)
		(min_thickness 0.25)
		(keepout
			(tracks not_allowed)
			(vias allowed)
			(pads allowed)
			(copperpour not_allowed)
			(footprints allowed)
		)
		(placement
			(enabled no)
			(sheetname "")
		)
		(fill
			(thermal_gap 0.5)
			(thermal_bridge_width 0.5)
			(island_removal_mode 0)
		)
		(polygon
			(pts
				(arc
					(start 340.552786 -420.571168)
					(mid 340.171786 -420.952168)
					(end 340.552786 -421.333168)
				)
				(arc
					(start 341.416386 -421.333168)
					(mid 341.797386 -420.952168)
					(end 341.416386 -420.571168)
				)
			)
		)
	)
	(zone
		(layers "F.Cu" "B.Cu" "In1.Cu" "In2.Cu" "In3.Cu" "In4.Cu" "In5.Cu" "In6.Cu"
			"In7.Cu" "In8.Cu" "In9.Cu" "In10.Cu" "In11.Cu" "In12.Cu" "In13.Cu" "In14.Cu"
			"In15.Cu" "In16.Cu"
		)
		(hatch none 0.5)
		(connect_pads
			(clearance 0)
		)
		(min_thickness 0.25)
		(keepout
			(tracks not_allowed)
			(vias allowed)
			(pads allowed)
			(copperpour not_allowed)
			(footprints allowed)
		)
		(placement
			(enabled no)
			(sheetname "")
		)
		(fill
			(thermal_gap 0.5)
			(thermal_bridge_width 0.5)
			(island_removal_mode 0)
		)
		(polygon
			(pts
				(arc
					(start 154.555444 -373.58193)
					(mid 154.174444 -373.96293)
					(end 154.555444 -374.34393)
				)
				(arc
					(start 155.419044 -374.34393)
					(mid 155.800044 -373.96293)
					(end 155.419044 -373.58193)
				)
			)
		)
	)
	(zone
		(layers "F.Cu" "B.Cu" "In1.Cu" "In2.Cu" "In3.Cu" "In4.Cu" "In5.Cu" "In6.Cu"
			"In7.Cu" "In8.Cu" "In9.Cu" "In10.Cu" "In11.Cu" "In12.Cu" "In13.Cu" "In14.Cu"
			"In15.Cu" "In16.Cu"
		)
		(hatch none 0.5)
		(connect_pads
			(clearance 0)
		)
		(min_thickness 0.25)
		(keepout
			(tracks not_allowed)
			(vias allowed)
			(pads allowed)
			(copperpour not_allowed)
			(footprints allowed)
		)
		(placement
			(enabled no)
			(sheetname "")
		)
		(fill yes
			(thermal_gap 0.5)
			(thermal_bridge_width 0.5)
			(island_removal_mode 0)
		)
		(polygon
			(pts
				(arc
					(start 352.064066 -394.552424)
					(mid 352.174037 -394.653478)
					(end 352.318828 -394.690092)
				)
				(arc
					(start 352.318828 -394.690092)
					(mid 352.534354 -394.600818)
					(end 352.623628 -394.385292)
				)
				(arc
					(start 352.623628 -394.385292)
					(mid 352.613291 -394.306553)
					(end 352.582988 -394.233146)
				)
				(arc
					(start 352.190558 -393.554204)
					(mid 352.078161 -393.432587)
					(end 351.918778 -393.38758)
				)
				(arc
					(start 351.918778 -393.38758)
					(mid 351.703252 -393.476854)
					(end 351.613978 -393.69238)
				)
				(arc
					(start 351.613978 -393.69238)
					(mid 351.623556 -393.768442)
					(end 351.651824 -393.8397)
				)
				(xy 352.04908 -394.527024) (xy 352.061272 -394.54836) (xy 352.063812 -394.552678)
			)
		)
	)
	(zone
		(layers "F.Cu" "B.Cu" "In1.Cu" "In2.Cu" "In3.Cu" "In4.Cu" "In5.Cu" "In6.Cu"
			"In7.Cu" "In8.Cu" "In9.Cu" "In10.Cu" "In11.Cu" "In12.Cu" "In13.Cu" "In14.Cu"
			"In15.Cu" "In16.Cu"
		)
		(hatch none 0.5)
		(connect_pads
			(clearance 0)
		)
		(min_thickness 0.25)
		(keepout
			(tracks not_allowed)
			(vias allowed)
			(pads allowed)
			(copperpour not_allowed)
			(footprints allowed)
		)
		(placement
			(enabled no)
			(sheetname "")
		)
		(fill
			(thermal_gap 0.5)
			(thermal_bridge_width 0.5)
			(island_removal_mode 0)
		)
		(polygon
			(pts
				(arc
					(start 401.209764 -17.23136)
					(mid 400.828764 -17.61236)
					(end 401.209764 -17.99336)
				)
				(arc
					(start 402.073364 -17.99336)
					(mid 402.454364 -17.61236)
					(end 402.073364 -17.23136)
				)
			)
		)
	)
	(zone
		(layers "F.Cu" "B.Cu" "In1.Cu" "In2.Cu" "In3.Cu" "In4.Cu" "In5.Cu" "In6.Cu"
			"In7.Cu" "In8.Cu" "In9.Cu" "In10.Cu" "In11.Cu" "In12.Cu" "In13.Cu" "In14.Cu"
			"In15.Cu" "In16.Cu"
		)
		(hatch none 0.5)
		(connect_pads
			(clearance 0)
		)
		(min_thickness 0.25)
		(keepout
			(tracks not_allowed)
			(vias allowed)
			(pads allowed)
			(copperpour not_allowed)
			(footprints allowed)
		)
		(placement
			(enabled no)
			(sheetname "")
		)
		(fill
			(thermal_gap 0.5)
			(thermal_bridge_width 0.5)
			(island_removal_mode 0)
		)
		(polygon
			(pts
				(arc
					(start 354.464112 -398.016476)
					(mid 354.574083 -398.11753)
					(end 354.718874 -398.154144)
				)
				(arc
					(start 354.718874 -398.154144)
					(mid 354.9344 -398.06487)
					(end 355.023674 -397.849344)
				)
				(arc
					(start 355.023674 -397.849344)
					(mid 355.013337 -397.770605)
					(end 354.983034 -397.697198)
				)
				(arc
					(start 354.590604 -397.018256)
					(mid 354.478207 -396.896639)
					(end 354.318824 -396.851632)
				)
				(arc
					(start 354.318824 -396.851632)
					(mid 354.103298 -396.940906)
					(end 354.014024 -397.156432)
				)
				(arc
					(start 354.014024 -397.156432)
					(mid 354.023602 -397.232494)
					(end 354.05187 -397.303752)
				)
				(xy 354.449126 -397.991076) (xy 354.461318 -398.012412) (xy 354.463858 -398.01673)
			)
		)
	)
	(zone
		(layers "F.Cu" "B.Cu" "In1.Cu" "In2.Cu" "In3.Cu" "In4.Cu" "In5.Cu" "In6.Cu"
			"In7.Cu" "In8.Cu" "In9.Cu" "In10.Cu" "In11.Cu" "In12.Cu" "In13.Cu" "In14.Cu"
			"In15.Cu" "In16.Cu"
		)
		(hatch none 0.5)
		(connect_pads
			(clearance 0)
		)
		(min_thickness 0.25)
		(keepout
			(tracks not_allowed)
			(vias allowed)
			(pads allowed)
			(copperpour not_allowed)
			(footprints allowed)
		)
		(placement
			(enabled no)
			(sheetname "")
		)
		(fill
			(thermal_gap 0.5)
			(thermal_bridge_width 0.5)
			(island_removal_mode 0)
		)
		(polygon
			(pts
				(arc
					(start 57.7977 -392.429238)
					(mid 57.4167 -392.048238)
					(end 57.0357 -392.429238)
				)
				(arc
					(start 57.0357 -393.292838)
					(mid 57.4167 -393.673838)
					(end 57.7977 -393.292838)
				)
			)
		)
	)
	(zone
		(layers "F.Cu" "B.Cu" "In1.Cu" "In2.Cu" "In3.Cu" "In4.Cu" "In5.Cu" "In6.Cu"
			"In7.Cu" "In8.Cu" "In9.Cu" "In10.Cu" "In11.Cu" "In12.Cu" "In13.Cu" "In14.Cu"
			"In15.Cu" "In16.Cu"
		)
		(hatch none 0.5)
		(connect_pads
			(clearance 0)
		)
		(min_thickness 0.25)
		(keepout
			(tracks not_allowed)
			(vias allowed)
			(pads allowed)
			(copperpour not_allowed)
			(footprints allowed)
		)
		(placement
			(enabled no)
			(sheetname "")
		)
		(fill
			(thermal_gap 0.5)
			(thermal_bridge_width 0.5)
			(island_removal_mode 0)
		)
		(polygon
			(pts
				(arc
					(start 351.274126 -418.031168)
					(mid 350.893126 -418.412168)
					(end 351.274126 -418.793168)
				)
				(arc
					(start 352.137726 -418.793168)
					(mid 352.518726 -418.412168)
					(end 352.137726 -418.031168)
				)
			)
		)
	)
	(zone
		(layers "F.Cu" "B.Cu" "In1.Cu" "In2.Cu" "In3.Cu" "In4.Cu" "In5.Cu" "In6.Cu"
			"In7.Cu" "In8.Cu" "In9.Cu" "In10.Cu" "In11.Cu" "In12.Cu" "In13.Cu" "In14.Cu"
			"In15.Cu" "In16.Cu"
		)
		(hatch none 0.5)
		(connect_pads
			(clearance 0)
		)
		(min_thickness 0.25)
		(keepout
			(tracks not_allowed)
			(vias allowed)
			(pads allowed)
			(copperpour not_allowed)
			(footprints allowed)
		)
		(placement
			(enabled no)
			(sheetname "")
		)
		(fill
			(thermal_gap 0.5)
			(thermal_bridge_width 0.5)
			(island_removal_mode 0)
		)
		(polygon
			(pts
				(arc
					(start 54.927754 -373.58193)
					(mid 54.546754 -373.96293)
					(end 54.927754 -374.34393)
				)
				(arc
					(start 55.791354 -374.34393)
					(mid 56.172354 -373.96293)
					(end 55.791354 -373.58193)
				)
			)
		)
	)
	(zone
		(layers "F.Cu" "B.Cu" "In1.Cu" "In2.Cu" "In3.Cu" "In4.Cu" "In5.Cu" "In6.Cu"
			"In7.Cu" "In8.Cu" "In9.Cu" "In10.Cu" "In11.Cu" "In12.Cu" "In13.Cu" "In14.Cu"
			"In15.Cu" "In16.Cu"
		)
		(hatch none 0.5)
		(connect_pads
			(clearance 0)
		)
		(min_thickness 0.25)
		(keepout
			(tracks not_allowed)
			(vias allowed)
			(pads allowed)
			(copperpour not_allowed)
			(footprints allowed)
		)
		(placement
			(enabled no)
			(sheetname "")
		)
		(fill
			(thermal_gap 0.5)
			(thermal_bridge_width 0.5)
			(island_removal_mode 0)
		)
		(polygon
			(pts
				(arc
					(start 213.51875 2.111756)
					(mid 213.95055 1.679956)
					(end 214.38235 2.111756)
				)
				(arc
					(start 214.38235 2.975356)
					(mid 213.95055 3.407156)
					(end 213.51875 2.975356)
				)
			)
		)
	)
	(zone
		(layers "F.Cu" "B.Cu" "In1.Cu" "In2.Cu" "In3.Cu" "In4.Cu" "In5.Cu" "In6.Cu"
			"In7.Cu" "In8.Cu" "In9.Cu" "In10.Cu" "In11.Cu" "In12.Cu" "In13.Cu" "In14.Cu"
			"In15.Cu" "In16.Cu"
		)
		(hatch none 0.5)
		(connect_pads
			(clearance 0)
		)
		(min_thickness 0.25)
		(keepout
			(tracks not_allowed)
			(vias allowed)
			(pads allowed)
			(copperpour not_allowed)
			(footprints allowed)
		)
		(placement
			(enabled no)
			(sheetname "")
		)
		(fill yes
			(thermal_gap 0.5)
			(thermal_bridge_width 0.5)
			(island_removal_mode 0)
		)
		(polygon
			(pts
				(arc
					(start 375.836434 -394.552424)
					(mid 375.946405 -394.653478)
					(end 376.091196 -394.690092)
				)
				(arc
					(start 376.091196 -394.690092)
					(mid 376.306722 -394.600818)
					(end 376.395996 -394.385292)
				)
				(arc
					(start 376.395996 -394.385292)
					(mid 376.385659 -394.306553)
					(end 376.355356 -394.233146)
				)
				(arc
					(start 375.962926 -393.554204)
					(mid 375.850529 -393.432587)
					(end 375.691146 -393.38758)
				)
				(arc
					(start 375.691146 -393.38758)
					(mid 375.47562 -393.476854)
					(end 375.386346 -393.69238)
				)
				(arc
					(start 375.386346 -393.69238)
					(mid 375.395924 -393.768442)
					(end 375.424192 -393.8397)
				)
				(xy 375.821448 -394.527024) (xy 375.83364 -394.54836) (xy 375.83618 -394.552678)
			)
		)
	)
	(zone
		(layers "F.Cu" "B.Cu" "In1.Cu" "In2.Cu" "In3.Cu" "In4.Cu" "In5.Cu" "In6.Cu"
			"In7.Cu" "In8.Cu" "In9.Cu" "In10.Cu" "In11.Cu" "In12.Cu" "In13.Cu" "In14.Cu"
			"In15.Cu" "In16.Cu"
		)
		(hatch none 0.5)
		(connect_pads
			(clearance 0)
		)
		(min_thickness 0.25)
		(keepout
			(tracks not_allowed)
			(vias allowed)
			(pads allowed)
			(copperpour not_allowed)
			(footprints allowed)
		)
		(placement
			(enabled no)
			(sheetname "")
		)
		(fill
			(thermal_gap 0.5)
			(thermal_bridge_width 0.5)
			(island_removal_mode 0)
		)
		(polygon
			(pts
				(arc
					(start 79.955136 -308.640988)
					(mid 79.574136 -308.259988)
					(end 79.193136 -308.640988)
				)
				(arc
					(start 79.193136 -309.504588)
					(mid 79.574136 -309.885588)
					(end 79.955136 -309.504588)
				)
			)
		)
	)
	(zone
		(layers "F.Cu" "B.Cu" "In1.Cu" "In2.Cu" "In3.Cu" "In4.Cu" "In5.Cu" "In6.Cu"
			"In7.Cu" "In8.Cu" "In9.Cu" "In10.Cu" "In11.Cu" "In12.Cu" "In13.Cu" "In14.Cu"
			"In15.Cu" "In16.Cu"
		)
		(hatch none 0.5)
		(connect_pads
			(clearance 0)
		)
		(min_thickness 0.25)
		(keepout
			(tracks not_allowed)
			(vias allowed)
			(pads allowed)
			(copperpour not_allowed)
			(footprints allowed)
		)
		(placement
			(enabled no)
			(sheetname "")
		)
		(fill
			(thermal_gap 0.5)
			(thermal_bridge_width 0.5)
			(island_removal_mode 0)
		)
		(polygon
			(pts
				(arc
					(start 389.273542 -420.571168)
					(mid 388.892542 -420.952168)
					(end 389.273542 -421.333168)
				)
				(arc
					(start 390.137142 -421.333168)
					(mid 390.518142 -420.952168)
					(end 390.137142 -420.571168)
				)
			)
		)
	)
	(zone
		(layers "F.Cu" "B.Cu" "In1.Cu" "In2.Cu" "In3.Cu" "In4.Cu" "In5.Cu" "In6.Cu"
			"In7.Cu" "In8.Cu" "In9.Cu" "In10.Cu" "In11.Cu" "In12.Cu" "In13.Cu" "In14.Cu"
			"In15.Cu" "In16.Cu"
		)
		(hatch none 0.5)
		(connect_pads
			(clearance 0)
		)
		(min_thickness 0.25)
		(keepout
			(tracks not_allowed)
			(vias allowed)
			(pads allowed)
			(copperpour not_allowed)
			(footprints allowed)
		)
		(placement
			(enabled no)
			(sheetname "")
		)
		(fill
			(thermal_gap 0.5)
			(thermal_bridge_width 0.5)
			(island_removal_mode 0)
		)
		(polygon
			(pts
				(arc
					(start 405.025098 -400.811238)
					(mid 404.644098 -400.430238)
					(end 404.263098 -400.811238)
				)
				(arc
					(start 404.263098 -401.674838)
					(mid 404.644098 -402.055838)
					(end 405.025098 -401.674838)
				)
			)
		)
	)
	(zone
		(layers "F.Cu" "B.Cu" "In1.Cu" "In2.Cu" "In3.Cu" "In4.Cu" "In5.Cu" "In6.Cu"
			"In7.Cu" "In8.Cu" "In9.Cu" "In10.Cu" "In11.Cu" "In12.Cu" "In13.Cu" "In14.Cu"
			"In15.Cu" "In16.Cu"
		)
		(hatch none 0.5)
		(connect_pads
			(clearance 0)
		)
		(min_thickness 0.25)
		(keepout
			(tracks not_allowed)
			(vias allowed)
			(pads allowed)
			(copperpour not_allowed)
			(footprints allowed)
		)
		(placement
			(enabled no)
			(sheetname "")
		)
		(fill
			(thermal_gap 0.5)
			(thermal_bridge_width 0.5)
			(island_removal_mode 0)
		)
		(polygon
			(pts
				(arc
					(start 129.28219 -10.449814)
					(mid 127.35179 -10.449814)
					(end 129.28219 -10.449814)
				)
			)
		)
	)
	(zone
		(layers "F.Cu" "B.Cu" "In1.Cu" "In2.Cu" "In3.Cu" "In4.Cu" "In5.Cu" "In6.Cu"
			"In7.Cu" "In8.Cu" "In9.Cu" "In10.Cu" "In11.Cu" "In12.Cu" "In13.Cu" "In14.Cu"
			"In15.Cu" "In16.Cu"
		)
		(hatch none 0.5)
		(connect_pads
			(clearance 0)
		)
		(min_thickness 0.25)
		(keepout
			(tracks not_allowed)
			(vias allowed)
			(pads allowed)
			(copperpour not_allowed)
			(footprints allowed)
		)
		(placement
			(enabled no)
			(sheetname "")
		)
		(fill yes
			(thermal_gap 0.5)
			(thermal_bridge_width 0.5)
			(island_removal_mode 0)
		)
		(polygon
			(pts
				(arc
					(start 93.664278 -386.170424)
					(mid 93.774249 -386.271478)
					(end 93.91904 -386.308092)
				)
				(arc
					(start 93.91904 -386.308092)
					(mid 94.134566 -386.218818)
					(end 94.22384 -386.003292)
				)
				(arc
					(start 94.22384 -386.003292)
					(mid 94.213503 -385.924553)
					(end 94.1832 -385.851146)
				)
				(arc
					(start 93.79077 -385.172204)
					(mid 93.678373 -385.050587)
					(end 93.51899 -385.00558)
				)
				(arc
					(start 93.51899 -385.00558)
					(mid 93.303464 -385.094854)
					(end 93.21419 -385.31038)
				)
				(arc
					(start 93.21419 -385.31038)
					(mid 93.223768 -385.386442)
					(end 93.252036 -385.4577)
				)
				(xy 93.649292 -386.145024) (xy 93.661484 -386.16636) (xy 93.664024 -386.170678)
			)
		)
	)
	(zone
		(layers "F.Cu" "B.Cu" "In1.Cu" "In2.Cu" "In3.Cu" "In4.Cu" "In5.Cu" "In6.Cu"
			"In7.Cu" "In8.Cu" "In9.Cu" "In10.Cu" "In11.Cu" "In12.Cu" "In13.Cu" "In14.Cu"
			"In15.Cu" "In16.Cu"
		)
		(hatch none 0.5)
		(connect_pads
			(clearance 0)
		)
		(min_thickness 0.25)
		(keepout
			(tracks not_allowed)
			(vias allowed)
			(pads allowed)
			(copperpour not_allowed)
			(footprints allowed)
		)
		(placement
			(enabled no)
			(sheetname "")
		)
		(fill
			(thermal_gap 0.5)
			(thermal_bridge_width 0.5)
			(island_removal_mode 0)
		)
		(polygon
			(pts
				(arc
					(start 145.526506 -412.189168)
					(mid 145.145506 -412.570168)
					(end 145.526506 -412.951168)
				)
				(arc
					(start 146.390106 -412.951168)
					(mid 146.771106 -412.570168)
					(end 146.390106 -412.189168)
				)
			)
		)
	)
	(zone
		(layers "F.Cu" "B.Cu" "In1.Cu" "In2.Cu" "In3.Cu" "In4.Cu" "In5.Cu" "In6.Cu"
			"In7.Cu" "In8.Cu" "In9.Cu" "In10.Cu" "In11.Cu" "In12.Cu" "In13.Cu" "In14.Cu"
			"In15.Cu" "In16.Cu"
		)
		(hatch none 0.5)
		(connect_pads
			(clearance 0)
		)
		(min_thickness 0.25)
		(keepout
			(tracks not_allowed)
			(vias allowed)
			(pads allowed)
			(copperpour not_allowed)
			(footprints allowed)
		)
		(placement
			(enabled no)
			(sheetname "")
		)
		(fill
			(thermal_gap 0.5)
			(thermal_bridge_width 0.5)
			(island_removal_mode 0)
		)
		(polygon
			(pts
				(arc
					(start 163.425124 -392.429238)
					(mid 163.044124 -392.048238)
					(end 162.663124 -392.429238)
				)
				(arc
					(start 162.663124 -393.292838)
					(mid 163.044124 -393.673838)
					(end 163.425124 -393.292838)
				)
			)
		)
	)
	(zone
		(layers "F.Cu" "B.Cu" "In1.Cu" "In2.Cu" "In3.Cu" "In4.Cu" "In5.Cu" "In6.Cu"
			"In7.Cu" "In8.Cu" "In9.Cu" "In10.Cu" "In11.Cu" "In12.Cu" "In13.Cu" "In14.Cu"
			"In15.Cu" "In16.Cu"
		)
		(hatch none 0.5)
		(connect_pads
			(clearance 0)
		)
		(min_thickness 0.25)
		(keepout
			(tracks not_allowed)
			(vias allowed)
			(pads allowed)
			(copperpour not_allowed)
			(footprints allowed)
		)
		(placement
			(enabled no)
			(sheetname "")
		)
		(fill yes
			(thermal_gap 0.5)
			(thermal_bridge_width 0.5)
			(island_removal_mode 0)
		)
		(polygon
			(pts
				(arc
					(start 160.76422 -386.170424)
					(mid 160.874191 -386.271478)
					(end 161.018982 -386.308092)
				)
				(arc
					(start 161.018982 -386.308092)
					(mid 161.234508 -386.218818)
					(end 161.323782 -386.003292)
				)
				(arc
					(start 161.323782 -386.003292)
					(mid 161.313445 -385.924553)
					(end 161.283142 -385.851146)
				)
				(arc
					(start 160.890712 -385.172204)
					(mid 160.778315 -385.050587)
					(end 160.618932 -385.00558)
				)
				(arc
					(start 160.618932 -385.00558)
					(mid 160.403406 -385.094854)
					(end 160.314132 -385.31038)
				)
				(arc
					(start 160.314132 -385.31038)
					(mid 160.32371 -385.386442)
					(end 160.351978 -385.4577)
				)
				(xy 160.749234 -386.145024) (xy 160.761426 -386.16636) (xy 160.763966 -386.170678)
			)
		)
	)
	(zone
		(layers "F.Cu" "B.Cu" "In1.Cu" "In2.Cu" "In3.Cu" "In4.Cu" "In5.Cu" "In6.Cu"
			"In7.Cu" "In8.Cu" "In9.Cu" "In10.Cu" "In11.Cu" "In12.Cu" "In13.Cu" "In14.Cu"
			"In15.Cu" "In16.Cu"
		)
		(hatch none 0.5)
		(connect_pads
			(clearance 0)
		)
		(min_thickness 0.25)
		(keepout
			(tracks not_allowed)
			(vias allowed)
			(pads allowed)
			(copperpour not_allowed)
			(footprints allowed)
		)
		(placement
			(enabled no)
			(sheetname "")
		)
		(fill
			(thermal_gap 0.5)
			(thermal_bridge_width 0.5)
			(island_removal_mode 0)
		)
		(polygon
			(pts
				(arc
					(start 325.236586 -420.571168)
					(mid 324.855586 -420.952168)
					(end 325.236586 -421.333168)
				)
				(arc
					(start 326.100186 -421.333168)
					(mid 326.481186 -420.952168)
					(end 326.100186 -420.571168)
				)
			)
		)
	)
	(zone
		(layers "F.Cu" "B.Cu" "In1.Cu" "In2.Cu" "In3.Cu" "In4.Cu" "In5.Cu" "In6.Cu"
			"In7.Cu" "In8.Cu" "In9.Cu" "In10.Cu" "In11.Cu" "In12.Cu" "In13.Cu" "In14.Cu"
			"In15.Cu" "In16.Cu"
		)
		(hatch none 0.5)
		(connect_pads
			(clearance 0)
		)
		(min_thickness 0.25)
		(keepout
			(tracks not_allowed)
			(vias allowed)
			(pads allowed)
			(copperpour not_allowed)
			(footprints allowed)
		)
		(placement
			(enabled no)
			(sheetname "")
		)
		(fill
			(thermal_gap 0.5)
			(thermal_bridge_width 0.5)
			(island_removal_mode 0)
		)
		(polygon
			(pts
				(arc
					(start 13.095986 -32.447484)
					(mid 17.618841 -32.599253)
					(end 17.770348 -28.076398)
				)
				(arc
					(start 16.67764 -26.907744)
					(mid 12.154979 -26.756301)
					(end 12.003278 -31.279084)
				)
			)
		)
	)
	(zone
		(layers "F.Cu" "B.Cu" "In1.Cu" "In2.Cu" "In3.Cu" "In4.Cu" "In5.Cu" "In6.Cu"
			"In7.Cu" "In8.Cu" "In9.Cu" "In10.Cu" "In11.Cu" "In12.Cu" "In13.Cu" "In14.Cu"
			"In15.Cu" "In16.Cu"
		)
		(hatch none 0.5)
		(connect_pads
			(clearance 0)
		)
		(min_thickness 0.25)
		(keepout
			(tracks not_allowed)
			(vias allowed)
			(pads allowed)
			(copperpour not_allowed)
			(footprints allowed)
		)
		(placement
			(enabled no)
			(sheetname "")
		)
		(fill
			(thermal_gap 0.5)
			(thermal_bridge_width 0.5)
			(island_removal_mode 0)
		)
		(polygon
			(pts
				(arc
					(start 399.994882 -415.00552)
					(mid 399.613882 -415.38652)
					(end 399.994882 -415.76752)
				)
				(arc
					(start 400.858482 -415.76752)
					(mid 401.239482 -415.38652)
					(end 400.858482 -415.00552)
				)
			)
		)
	)
	(zone
		(layers "F.Cu" "B.Cu" "In1.Cu" "In2.Cu" "In3.Cu" "In4.Cu" "In5.Cu" "In6.Cu"
			"In7.Cu" "In8.Cu" "In9.Cu" "In10.Cu" "In11.Cu" "In12.Cu" "In13.Cu" "In14.Cu"
			"In15.Cu" "In16.Cu"
		)
		(hatch none 0.5)
		(connect_pads
			(clearance 0)
		)
		(min_thickness 0.25)
		(keepout
			(tracks not_allowed)
			(vias allowed)
			(pads allowed)
			(copperpour not_allowed)
			(footprints allowed)
		)
		(placement
			(enabled no)
			(sheetname "")
		)
		(fill
			(thermal_gap 0.5)
			(thermal_bridge_width 0.5)
			(island_removal_mode 0)
		)
		(polygon
			(pts
				(arc
					(start 377.036584 -398.016476)
					(mid 377.146555 -398.11753)
					(end 377.291346 -398.154144)
				)
				(arc
					(start 377.291346 -398.154144)
					(mid 377.506872 -398.06487)
					(end 377.596146 -397.849344)
				)
				(arc
					(start 377.596146 -397.849344)
					(mid 377.585809 -397.770605)
					(end 377.555506 -397.697198)
				)
				(arc
					(start 377.163076 -397.018256)
					(mid 377.050679 -396.896639)
					(end 376.891296 -396.851632)
				)
				(arc
					(start 376.891296 -396.851632)
					(mid 376.67577 -396.940906)
					(end 376.586496 -397.156432)
				)
				(arc
					(start 376.586496 -397.156432)
					(mid 376.596074 -397.232494)
					(end 376.624342 -397.303752)
				)
				(xy 377.021598 -397.991076) (xy 377.03379 -398.012412) (xy 377.03633 -398.01673)
			)
		)
	)
	(zone
		(layers "F.Cu" "B.Cu" "In1.Cu" "In2.Cu" "In3.Cu" "In4.Cu" "In5.Cu" "In6.Cu"
			"In7.Cu" "In8.Cu" "In9.Cu" "In10.Cu" "In11.Cu" "In12.Cu" "In13.Cu" "In14.Cu"
			"In15.Cu" "In16.Cu"
		)
		(hatch none 0.5)
		(connect_pads
			(clearance 0)
		)
		(min_thickness 0.25)
		(keepout
			(tracks not_allowed)
			(vias allowed)
			(pads allowed)
			(copperpour not_allowed)
			(footprints allowed)
		)
		(placement
			(enabled no)
			(sheetname "")
		)
		(fill
			(thermal_gap 0.5)
			(thermal_bridge_width 0.5)
			(island_removal_mode 0)
		)
		(polygon
			(pts
				(arc
					(start 28.568142 -422.08069)
					(mid 28.949142 -421.69969)
					(end 28.568142 -421.31869)
				)
				(arc
					(start 27.704542 -421.31869)
					(mid 27.323542 -421.69969)
					(end 27.704542 -422.08069)
				)
			)
		)
	)
	(zone
		(layers "F.Cu" "B.Cu" "In1.Cu" "In2.Cu" "In3.Cu" "In4.Cu" "In5.Cu" "In6.Cu"
			"In7.Cu" "In8.Cu" "In9.Cu" "In10.Cu" "In11.Cu" "In12.Cu" "In13.Cu" "In14.Cu"
			"In15.Cu" "In16.Cu"
		)
		(hatch none 0.5)
		(connect_pads
			(clearance 0)
		)
		(min_thickness 0.25)
		(keepout
			(tracks not_allowed)
			(vias allowed)
			(pads allowed)
			(copperpour not_allowed)
			(footprints allowed)
		)
		(placement
			(enabled no)
			(sheetname "")
		)
		(fill
			(thermal_gap 0.5)
			(thermal_bridge_width 0.5)
			(island_removal_mode 0)
		)
		(polygon
			(pts
				(arc
					(start 161.237676 -149.607016)
					(mid 160.856676 -149.988016)
					(end 161.237676 -150.369016)
				)
				(arc
					(start 162.228276 -150.369016)
					(mid 162.609276 -149.988016)
					(end 162.228276 -149.607016)
				)
			)
		)
	)
	(zone
		(layers "F.Cu" "B.Cu" "In1.Cu" "In2.Cu" "In3.Cu" "In4.Cu" "In5.Cu" "In6.Cu"
			"In7.Cu" "In8.Cu" "In9.Cu" "In10.Cu" "In11.Cu" "In12.Cu" "In13.Cu" "In14.Cu"
			"In15.Cu" "In16.Cu"
		)
		(hatch none 0.5)
		(connect_pads
			(clearance 0)
		)
		(min_thickness 0.25)
		(keepout
			(tracks not_allowed)
			(vias allowed)
			(pads allowed)
			(copperpour not_allowed)
			(footprints allowed)
		)
		(placement
			(enabled no)
			(sheetname "")
		)
		(fill
			(thermal_gap 0.5)
			(thermal_bridge_width 0.5)
			(island_removal_mode 0)
		)
		(polygon
			(pts
				(arc
					(start 317.136272 -398.016476)
					(mid 317.246243 -398.11753)
					(end 317.391034 -398.154144)
				)
				(arc
					(start 317.391034 -398.154144)
					(mid 317.60656 -398.06487)
					(end 317.695834 -397.849344)
				)
				(arc
					(start 317.695834 -397.849344)
					(mid 317.685497 -397.770605)
					(end 317.655194 -397.697198)
				)
				(arc
					(start 317.262764 -397.018256)
					(mid 317.150367 -396.896639)
					(end 316.990984 -396.851632)
				)
				(arc
					(start 316.990984 -396.851632)
					(mid 316.775458 -396.940906)
					(end 316.686184 -397.156432)
				)
				(arc
					(start 316.686184 -397.156432)
					(mid 316.695762 -397.232494)
					(end 316.72403 -397.303752)
				)
				(xy 317.121286 -397.991076) (xy 317.133478 -398.012412) (xy 317.136018 -398.01673)
			)
		)
	)
	(zone
		(layers "F.Cu" "B.Cu" "In1.Cu" "In2.Cu" "In3.Cu" "In4.Cu" "In5.Cu" "In6.Cu"
			"In7.Cu" "In8.Cu" "In9.Cu" "In10.Cu" "In11.Cu" "In12.Cu" "In13.Cu" "In14.Cu"
			"In15.Cu" "In16.Cu"
		)
		(hatch none 0.5)
		(connect_pads
			(clearance 0)
		)
		(min_thickness 0.25)
		(keepout
			(tracks not_allowed)
			(vias allowed)
			(pads allowed)
			(copperpour not_allowed)
			(footprints allowed)
		)
		(placement
			(enabled no)
			(sheetname "")
		)
		(fill
			(thermal_gap 0.5)
			(thermal_bridge_width 0.5)
			(island_removal_mode 0)
		)
		(polygon
			(pts
				(arc
					(start 213.51875 -2.968244)
					(mid 213.95055 -3.400044)
					(end 214.38235 -2.968244)
				)
				(arc
					(start 214.38235 -2.104644)
					(mid 213.95055 -1.672844)
					(end 213.51875 -2.104644)
				)
			)
		)
	)
	(zone
		(layers "F.Cu" "B.Cu" "In1.Cu" "In2.Cu" "In3.Cu" "In4.Cu" "In5.Cu" "In6.Cu"
			"In7.Cu" "In8.Cu" "In9.Cu" "In10.Cu" "In11.Cu" "In12.Cu" "In13.Cu" "In14.Cu"
			"In15.Cu" "In16.Cu"
		)
		(hatch none 0.5)
		(connect_pads
			(clearance 0)
		)
		(min_thickness 0.25)
		(keepout
			(tracks not_allowed)
			(vias allowed)
			(pads allowed)
			(copperpour not_allowed)
			(footprints allowed)
		)
		(placement
			(enabled no)
			(sheetname "")
		)
		(fill
			(thermal_gap 0.5)
			(thermal_bridge_width 0.5)
			(island_removal_mode 0)
		)
		(polygon
			(pts
				(arc
					(start 370.894102 -420.571168)
					(mid 370.513102 -420.952168)
					(end 370.894102 -421.333168)
				)
				(arc
					(start 371.757702 -421.333168)
					(mid 372.138702 -420.952168)
					(end 371.757702 -420.571168)
				)
			)
		)
	)
	(zone
		(layers "F.Cu" "B.Cu" "In1.Cu" "In2.Cu" "In3.Cu" "In4.Cu" "In5.Cu" "In6.Cu"
			"In7.Cu" "In8.Cu" "In9.Cu" "In10.Cu" "In11.Cu" "In12.Cu" "In13.Cu" "In14.Cu"
			"In15.Cu" "In16.Cu"
		)
		(hatch none 0.5)
		(connect_pads
			(clearance 0)
		)
		(min_thickness 0.25)
		(keepout
			(tracks not_allowed)
			(vias allowed)
			(pads allowed)
			(copperpour not_allowed)
			(footprints allowed)
		)
		(placement
			(enabled no)
			(sheetname "")
		)
		(fill
			(thermal_gap 0.5)
			(thermal_bridge_width 0.5)
			(island_removal_mode 0)
		)
		(polygon
			(pts
				(arc
					(start 419.164262 -398.016476)
					(mid 419.274233 -398.11753)
					(end 419.419024 -398.154144)
				)
				(arc
					(start 419.419024 -398.154144)
					(mid 419.63455 -398.06487)
					(end 419.723824 -397.849344)
				)
				(arc
					(start 419.723824 -397.849344)
					(mid 419.713487 -397.770605)
					(end 419.683184 -397.697198)
				)
				(arc
					(start 419.290754 -397.018256)
					(mid 419.178357 -396.896639)
					(end 419.018974 -396.851632)
				)
				(arc
					(start 419.018974 -396.851632)
					(mid 418.803448 -396.940906)
					(end 418.714174 -397.156432)
				)
				(arc
					(start 418.714174 -397.156432)
					(mid 418.723752 -397.232494)
					(end 418.75202 -397.303752)
				)
				(xy 419.149276 -397.991076) (xy 419.161468 -398.012412) (xy 419.164008 -398.01673)
			)
		)
	)
	(zone
		(layers "F.Cu" "B.Cu" "In1.Cu" "In2.Cu" "In3.Cu" "In4.Cu" "In5.Cu" "In6.Cu"
			"In7.Cu" "In8.Cu" "In9.Cu" "In10.Cu" "In11.Cu" "In12.Cu" "In13.Cu" "In14.Cu"
			"In15.Cu" "In16.Cu"
		)
		(hatch none 0.5)
		(connect_pads
			(clearance 0)
		)
		(min_thickness 0.25)
		(keepout
			(tracks not_allowed)
			(vias allowed)
			(pads allowed)
			(copperpour not_allowed)
			(footprints allowed)
		)
		(placement
			(enabled no)
			(sheetname "")
		)
		(fill yes
			(thermal_gap 0.5)
			(thermal_bridge_width 0.5)
			(island_removal_mode 0)
		)
		(polygon
			(pts
				(arc
					(start 131.836414 -386.170424)
					(mid 131.946385 -386.271478)
					(end 132.091176 -386.308092)
				)
				(arc
					(start 132.091176 -386.308092)
					(mid 132.306702 -386.218818)
					(end 132.395976 -386.003292)
				)
				(arc
					(start 132.395976 -386.003292)
					(mid 132.385639 -385.924553)
					(end 132.355336 -385.851146)
				)
				(arc
					(start 131.962906 -385.172204)
					(mid 131.850509 -385.050587)
					(end 131.691126 -385.00558)
				)
				(arc
					(start 131.691126 -385.00558)
					(mid 131.4756 -385.094854)
					(end 131.386326 -385.31038)
				)
				(arc
					(start 131.386326 -385.31038)
					(mid 131.395904 -385.386442)
					(end 131.424172 -385.4577)
				)
				(xy 131.821428 -386.145024) (xy 131.83362 -386.16636) (xy 131.83616 -386.170678)
			)
		)
	)
	(zone
		(layers "F.Cu" "B.Cu" "In1.Cu" "In2.Cu" "In3.Cu" "In4.Cu" "In5.Cu" "In6.Cu"
			"In7.Cu" "In8.Cu" "In9.Cu" "In10.Cu" "In11.Cu" "In12.Cu" "In13.Cu" "In14.Cu"
			"In15.Cu" "In16.Cu"
		)
		(hatch none 0.5)
		(connect_pads
			(clearance 0)
		)
		(min_thickness 0.25)
		(keepout
			(tracks not_allowed)
			(vias allowed)
			(pads allowed)
			(copperpour not_allowed)
			(footprints allowed)
		)
		(placement
			(enabled no)
			(sheetname "")
		)
		(fill
			(thermal_gap 0.5)
			(thermal_bridge_width 0.5)
			(island_removal_mode 0)
		)
		(polygon
			(pts
				(arc
					(start 383.147062 -420.571168)
					(mid 382.766062 -420.952168)
					(end 383.147062 -421.333168)
				)
				(arc
					(start 384.010662 -421.333168)
					(mid 384.391662 -420.952168)
					(end 384.010662 -420.571168)
				)
			)
		)
	)
	(zone
		(layers "F.Cu" "B.Cu" "In1.Cu" "In2.Cu" "In3.Cu" "In4.Cu" "In5.Cu" "In6.Cu"
			"In7.Cu" "In8.Cu" "In9.Cu" "In10.Cu" "In11.Cu" "In12.Cu" "In13.Cu" "In14.Cu"
			"In15.Cu" "In16.Cu"
		)
		(hatch none 0.5)
		(connect_pads
			(clearance 0)
		)
		(min_thickness 0.25)
		(keepout
			(tracks not_allowed)
			(vias allowed)
			(pads allowed)
			(copperpour not_allowed)
			(footprints allowed)
		)
		(placement
			(enabled no)
			(sheetname "")
		)
		(fill
			(thermal_gap 0.5)
			(thermal_bridge_width 0.5)
			(island_removal_mode 0)
		)
		(polygon
			(pts
				(arc
					(start 178.630834 -43.481752)
					(mid 179.011834 -43.862752)
					(end 179.392834 -43.481752)
				)
				(arc
					(start 179.392834 -42.618152)
					(mid 179.011834 -42.237152)
					(end 178.630834 -42.618152)
				)
			)
		)
	)
	(zone
		(layers "F.Cu" "B.Cu" "In1.Cu" "In2.Cu" "In3.Cu" "In4.Cu" "In5.Cu" "In6.Cu"
			"In7.Cu" "In8.Cu" "In9.Cu" "In10.Cu" "In11.Cu" "In12.Cu" "In13.Cu" "In14.Cu"
			"In15.Cu" "In16.Cu"
		)
		(hatch none 0.5)
		(connect_pads
			(clearance 0)
		)
		(min_thickness 0.25)
		(keepout
			(tracks not_allowed)
			(vias allowed)
			(pads allowed)
			(copperpour not_allowed)
			(footprints allowed)
		)
		(placement
			(enabled no)
			(sheetname "")
		)
		(fill
			(thermal_gap 0.5)
			(thermal_bridge_width 0.5)
			(island_removal_mode 0)
		)
		(polygon
			(pts
				(arc
					(start 85.525356 -392.429238)
					(mid 85.144356 -392.048238)
					(end 84.763356 -392.429238)
				)
				(arc
					(start 84.763356 -393.292838)
					(mid 85.144356 -393.673838)
					(end 85.525356 -393.292838)
				)
			)
		)
	)
	(zone
		(layers "F.Cu" "B.Cu" "In1.Cu" "In2.Cu" "In3.Cu" "In4.Cu" "In5.Cu" "In6.Cu"
			"In7.Cu" "In8.Cu" "In9.Cu" "In10.Cu" "In11.Cu" "In12.Cu" "In13.Cu" "In14.Cu"
			"In15.Cu" "In16.Cu"
		)
		(hatch none 0.5)
		(connect_pads
			(clearance 0)
		)
		(min_thickness 0.25)
		(keepout
			(tracks not_allowed)
			(vias allowed)
			(pads allowed)
			(copperpour not_allowed)
			(footprints allowed)
		)
		(placement
			(enabled no)
			(sheetname "")
		)
		(fill
			(thermal_gap 0.5)
			(thermal_bridge_width 0.5)
			(island_removal_mode 0)
		)
		(polygon
			(pts
				(arc
					(start 334.557878 -303.817528)
					(mid 334.176878 -303.436528)
					(end 333.795878 -303.817528)
				)
				(arc
					(start 333.795878 -304.681128)
					(mid 334.176878 -305.062128)
					(end 334.557878 -304.681128)
				)
			)
		)
	)
	(zone
		(layers "F.Cu" "B.Cu" "In1.Cu" "In2.Cu" "In3.Cu" "In4.Cu" "In5.Cu" "In6.Cu"
			"In7.Cu" "In8.Cu" "In9.Cu" "In10.Cu" "In11.Cu" "In12.Cu" "In13.Cu" "In14.Cu"
			"In15.Cu" "In16.Cu"
		)
		(hatch none 0.5)
		(connect_pads
			(clearance 0)
		)
		(min_thickness 0.25)
		(keepout
			(tracks not_allowed)
			(vias allowed)
			(pads allowed)
			(copperpour not_allowed)
			(footprints allowed)
		)
		(placement
			(enabled no)
			(sheetname "")
		)
		(fill
			(thermal_gap 0.5)
			(thermal_bridge_width 0.5)
			(island_removal_mode 0)
		)
		(polygon
			(pts
				(arc
					(start 377.297442 -400.811238)
					(mid 376.916442 -400.430238)
					(end 376.535442 -400.811238)
				)
				(arc
					(start 376.535442 -401.674838)
					(mid 376.916442 -402.055838)
					(end 377.297442 -401.674838)
				)
			)
		)
	)
	(zone
		(layers "F.Cu" "B.Cu" "In1.Cu" "In2.Cu" "In3.Cu" "In4.Cu" "In5.Cu" "In6.Cu"
			"In7.Cu" "In8.Cu" "In9.Cu" "In10.Cu" "In11.Cu" "In12.Cu" "In13.Cu" "In14.Cu"
			"In15.Cu" "In16.Cu"
		)
		(hatch none 0.5)
		(connect_pads
			(clearance 0)
		)
		(min_thickness 0.25)
		(keepout
			(tracks not_allowed)
			(vias allowed)
			(pads allowed)
			(copperpour not_allowed)
			(footprints allowed)
		)
		(placement
			(enabled no)
			(sheetname "")
		)
		(fill
			(thermal_gap 0.5)
			(thermal_bridge_width 0.5)
			(island_removal_mode 0)
		)
		(polygon
			(pts
				(arc
					(start 404.76424 -398.016476)
					(mid 404.874211 -398.11753)
					(end 405.019002 -398.154144)
				)
				(arc
					(start 405.019002 -398.154144)
					(mid 405.234528 -398.06487)
					(end 405.323802 -397.849344)
				)
				(arc
					(start 405.323802 -397.849344)
					(mid 405.313465 -397.770605)
					(end 405.283162 -397.697198)
				)
				(arc
					(start 404.890732 -397.018256)
					(mid 404.778335 -396.896639)
					(end 404.618952 -396.851632)
				)
				(arc
					(start 404.618952 -396.851632)
					(mid 404.403426 -396.940906)
					(end 404.314152 -397.156432)
				)
				(arc
					(start 404.314152 -397.156432)
					(mid 404.32373 -397.232494)
					(end 404.351998 -397.303752)
				)
				(xy 404.749254 -397.991076) (xy 404.761446 -398.012412) (xy 404.763986 -398.01673)
			)
		)
	)
	(zone
		(layers "F.Cu" "B.Cu" "In1.Cu" "In2.Cu" "In3.Cu" "In4.Cu" "In5.Cu" "In6.Cu"
			"In7.Cu" "In8.Cu" "In9.Cu" "In10.Cu" "In11.Cu" "In12.Cu" "In13.Cu" "In14.Cu"
			"In15.Cu" "In16.Cu"
		)
		(hatch none 0.5)
		(connect_pads
			(clearance 0)
		)
		(min_thickness 0.25)
		(keepout
			(tracks not_allowed)
			(vias allowed)
			(pads allowed)
			(copperpour not_allowed)
			(footprints allowed)
		)
		(placement
			(enabled no)
			(sheetname "")
		)
		(fill
			(thermal_gap 0.5)
			(thermal_bridge_width 0.5)
			(island_removal_mode 0)
		)
		(polygon
			(pts
				(arc
					(start 375.836434 -398.016476)
					(mid 375.946405 -398.11753)
					(end 376.091196 -398.154144)
				)
				(arc
					(start 376.091196 -398.154144)
					(mid 376.306722 -398.06487)
					(end 376.395996 -397.849344)
				)
				(arc
					(start 376.395996 -397.849344)
					(mid 376.385659 -397.770605)
					(end 376.355356 -397.697198)
				)
				(arc
					(start 375.962926 -397.018256)
					(mid 375.850529 -396.896639)
					(end 375.691146 -396.851632)
				)
				(arc
					(start 375.691146 -396.851632)
					(mid 375.47562 -396.940906)
					(end 375.386346 -397.156432)
				)
				(arc
					(start 375.386346 -397.156432)
					(mid 375.395924 -397.232494)
					(end 375.424192 -397.303752)
				)
				(xy 375.821448 -397.991076) (xy 375.83364 -398.012412) (xy 375.83618 -398.01673)
			)
		)
	)
	(zone
		(layers "F.Cu" "B.Cu" "In1.Cu" "In2.Cu" "In3.Cu" "In4.Cu" "In5.Cu" "In6.Cu"
			"In7.Cu" "In8.Cu" "In9.Cu" "In10.Cu" "In11.Cu" "In12.Cu" "In13.Cu" "In14.Cu"
			"In15.Cu" "In16.Cu"
		)
		(hatch none 0.5)
		(connect_pads
			(clearance 0)
		)
		(min_thickness 0.25)
		(keepout
			(tracks not_allowed)
			(vias allowed)
			(pads allowed)
			(copperpour not_allowed)
			(footprints allowed)
		)
		(placement
			(enabled no)
			(sheetname "")
		)
		(fill
			(thermal_gap 0.5)
			(thermal_bridge_width 0.5)
			(island_removal_mode 0)
		)
		(polygon
			(pts
				(arc
					(start 106.01071 -413.05353)
					(mid 105.62971 -413.43453)
					(end 106.01071 -413.81553)
				)
				(arc
					(start 106.87431 -413.81553)
					(mid 107.25531 -413.43453)
					(end 106.87431 -413.05353)
				)
			)
		)
	)
	(zone
		(layers "F.Cu" "B.Cu" "In1.Cu" "In2.Cu" "In3.Cu" "In4.Cu" "In5.Cu" "In6.Cu"
			"In7.Cu" "In8.Cu" "In9.Cu" "In10.Cu" "In11.Cu" "In12.Cu" "In13.Cu" "In14.Cu"
			"In15.Cu" "In16.Cu"
		)
		(hatch none 0.5)
		(connect_pads
			(clearance 0)
		)
		(min_thickness 0.25)
		(keepout
			(tracks not_allowed)
			(vias allowed)
			(pads allowed)
			(copperpour not_allowed)
			(footprints allowed)
		)
		(placement
			(enabled no)
			(sheetname "")
		)
		(fill
			(thermal_gap 0.5)
			(thermal_bridge_width 0.5)
			(island_removal_mode 0)
		)
		(polygon
			(pts
				(arc
					(start 80.648302 -373.58193)
					(mid 80.267302 -373.96293)
					(end 80.648302 -374.34393)
				)
				(arc
					(start 81.511902 -374.34393)
					(mid 81.892902 -373.96293)
					(end 81.511902 -373.58193)
				)
			)
		)
	)
	(zone
		(layers "F.Cu" "B.Cu" "In1.Cu" "In2.Cu" "In3.Cu" "In4.Cu" "In5.Cu" "In6.Cu"
			"In7.Cu" "In8.Cu" "In9.Cu" "In10.Cu" "In11.Cu" "In12.Cu" "In13.Cu" "In14.Cu"
			"In15.Cu" "In16.Cu"
		)
		(hatch none 0.5)
		(connect_pads
			(clearance 0)
		)
		(min_thickness 0.25)
		(keepout
			(tracks not_allowed)
			(vias allowed)
			(pads allowed)
			(copperpour not_allowed)
			(footprints allowed)
		)
		(placement
			(enabled no)
			(sheetname "")
		)
		(fill
			(thermal_gap 0.5)
			(thermal_bridge_width 0.5)
			(island_removal_mode 0)
		)
		(polygon
			(pts
				(arc
					(start 416.842702 -412.46552)
					(mid 416.461702 -412.84652)
					(end 416.842702 -413.22752)
				)
				(arc
					(start 417.706302 -413.22752)
					(mid 418.087302 -412.84652)
					(end 417.706302 -412.46552)
				)
			)
		)
	)
	(zone
		(layers "F.Cu" "B.Cu" "In1.Cu" "In2.Cu" "In3.Cu" "In4.Cu" "In5.Cu" "In6.Cu"
			"In7.Cu" "In8.Cu" "In9.Cu" "In10.Cu" "In11.Cu" "In12.Cu" "In13.Cu" "In14.Cu"
			"In15.Cu" "In16.Cu"
		)
		(hatch none 0.5)
		(connect_pads
			(clearance 0)
		)
		(min_thickness 0.25)
		(keepout
			(tracks not_allowed)
			(vias allowed)
			(pads allowed)
			(copperpour not_allowed)
			(footprints allowed)
		)
		(placement
			(enabled no)
			(sheetname "")
		)
		(fill
			(thermal_gap 0.5)
			(thermal_bridge_width 0.5)
			(island_removal_mode 0)
		)
		(polygon
			(pts
				(arc
					(start 147.564348 -389.634476)
					(mid 147.674319 -389.73553)
					(end 147.81911 -389.772144)
				)
				(arc
					(start 147.81911 -389.772144)
					(mid 148.034636 -389.68287)
					(end 148.12391 -389.467344)
				)
				(arc
					(start 148.12391 -389.467344)
					(mid 148.113573 -389.388605)
					(end 148.08327 -389.315198)
				)
				(arc
					(start 147.69084 -388.636256)
					(mid 147.578443 -388.514639)
					(end 147.41906 -388.469632)
				)
				(arc
					(start 147.41906 -388.469632)
					(mid 147.203534 -388.558906)
					(end 147.11426 -388.774432)
				)
				(arc
					(start 147.11426 -388.774432)
					(mid 147.123838 -388.850494)
					(end 147.152106 -388.921752)
				)
				(xy 147.549362 -389.609076) (xy 147.561554 -389.630412) (xy 147.564094 -389.63473)
			)
		)
	)
	(zone
		(layers "F.Cu" "B.Cu" "In1.Cu" "In2.Cu" "In3.Cu" "In4.Cu" "In5.Cu" "In6.Cu"
			"In7.Cu" "In8.Cu" "In9.Cu" "In10.Cu" "In11.Cu" "In12.Cu" "In13.Cu" "In14.Cu"
			"In15.Cu" "In16.Cu"
		)
		(hatch none 0.5)
		(connect_pads
			(clearance 0)
		)
		(min_thickness 0.25)
		(keepout
			(tracks not_allowed)
			(vias allowed)
			(pads allowed)
			(copperpour not_allowed)
			(footprints allowed)
		)
		(placement
			(enabled no)
			(sheetname "")
		)
		(fill
			(thermal_gap 0.5)
			(thermal_bridge_width 0.5)
			(island_removal_mode 0)
		)
		(polygon
			(pts
				(arc
					(start 316.01283 4.651756)
					(mid 316.44463 4.219956)
					(end 316.87643 4.651756)
				)
				(arc
					(start 316.87643 5.515356)
					(mid 316.44463 5.947156)
					(end 316.01283 5.515356)
				)
			)
		)
	)
	(zone
		(layers "F.Cu" "B.Cu" "In1.Cu" "In2.Cu" "In3.Cu" "In4.Cu" "In5.Cu" "In6.Cu"
			"In7.Cu" "In8.Cu" "In9.Cu" "In10.Cu" "In11.Cu" "In12.Cu" "In13.Cu" "In14.Cu"
			"In15.Cu" "In16.Cu"
		)
		(hatch none 0.5)
		(connect_pads
			(clearance 0)
		)
		(min_thickness 0.25)
		(keepout
			(tracks not_allowed)
			(vias allowed)
			(pads allowed)
			(copperpour not_allowed)
			(footprints allowed)
		)
		(placement
			(enabled no)
			(sheetname "")
		)
		(fill
			(thermal_gap 0.5)
			(thermal_bridge_width 0.5)
			(island_removal_mode 0)
		)
		(polygon
			(pts
				(arc
					(start 311.136284 -398.016476)
					(mid 311.246255 -398.11753)
					(end 311.391046 -398.154144)
				)
				(arc
					(start 311.391046 -398.154144)
					(mid 311.606572 -398.06487)
					(end 311.695846 -397.849344)
				)
				(arc
					(start 311.695846 -397.849344)
					(mid 311.685509 -397.770605)
					(end 311.655206 -397.697198)
				)
				(arc
					(start 311.262776 -397.018256)
					(mid 311.150379 -396.896639)
					(end 310.990996 -396.851632)
				)
				(arc
					(start 310.990996 -396.851632)
					(mid 310.77547 -396.940906)
					(end 310.686196 -397.156432)
				)
				(arc
					(start 310.686196 -397.156432)
					(mid 310.695774 -397.232494)
					(end 310.724042 -397.303752)
				)
				(xy 311.121298 -397.991076) (xy 311.13349 -398.012412) (xy 311.13603 -398.01673)
			)
		)
	)
	(zone
		(layers "F.Cu" "B.Cu" "In1.Cu" "In2.Cu" "In3.Cu" "In4.Cu" "In5.Cu" "In6.Cu"
			"In7.Cu" "In8.Cu" "In9.Cu" "In10.Cu" "In11.Cu" "In12.Cu" "In13.Cu" "In14.Cu"
			"In15.Cu" "In16.Cu"
		)
		(hatch none 0.5)
		(connect_pads
			(clearance 0)
		)
		(min_thickness 0.25)
		(keepout
			(tracks not_allowed)
			(vias allowed)
			(pads allowed)
			(copperpour not_allowed)
			(footprints allowed)
		)
		(placement
			(enabled no)
			(sheetname "")
		)
		(fill
			(thermal_gap 0.5)
			(thermal_bridge_width 0.5)
			(island_removal_mode 0)
		)
		(polygon
			(pts
				(arc
					(start 271.921986 -51.999896)
					(mid 265.368786 -51.999896)
					(end 271.921986 -51.999896)
				)
			)
		)
	)
	(zone
		(layers "F.Cu" "B.Cu" "In1.Cu" "In2.Cu" "In3.Cu" "In4.Cu" "In5.Cu" "In6.Cu"
			"In7.Cu" "In8.Cu" "In9.Cu" "In10.Cu" "In11.Cu" "In12.Cu" "In13.Cu" "In14.Cu"
			"In15.Cu" "In16.Cu"
		)
		(hatch none 0.5)
		(connect_pads
			(clearance 0)
		)
		(min_thickness 0.25)
		(keepout
			(tracks not_allowed)
			(vias allowed)
			(pads allowed)
			(copperpour not_allowed)
			(footprints allowed)
		)
		(placement
			(enabled no)
			(sheetname "")
		)
		(fill
			(thermal_gap 0.5)
			(thermal_bridge_width 0.5)
			(island_removal_mode 0)
		)
		(polygon
			(pts
				(arc
					(start 98.926396 -310.603646)
					(mid 99.307396 -310.984646)
					(end 99.688396 -310.603646)
				)
				(arc
					(start 99.688396 -309.740046)
					(mid 99.307396 -309.359046)
					(end 98.926396 -309.740046)
				)
			)
		)
	)
	(zone
		(layers "F.Cu" "B.Cu" "In1.Cu" "In2.Cu" "In3.Cu" "In4.Cu" "In5.Cu" "In6.Cu"
			"In7.Cu" "In8.Cu" "In9.Cu" "In10.Cu" "In11.Cu" "In12.Cu" "In13.Cu" "In14.Cu"
			"In15.Cu" "In16.Cu"
		)
		(hatch none 0.5)
		(connect_pads
			(clearance 0)
		)
		(min_thickness 0.25)
		(keepout
			(tracks not_allowed)
			(vias allowed)
			(pads allowed)
			(copperpour not_allowed)
			(footprints allowed)
		)
		(placement
			(enabled no)
			(sheetname "")
		)
		(fill
			(thermal_gap 0.5)
			(thermal_bridge_width 0.5)
			(island_removal_mode 0)
		)
		(polygon
			(pts
				(arc
					(start 110.115096 -371.11813)
					(mid 109.734096 -371.49913)
					(end 110.115096 -371.88013)
				)
				(arc
					(start 110.978696 -371.88013)
					(mid 111.359696 -371.49913)
					(end 110.978696 -371.11813)
				)
			)
		)
	)
	(zone
		(layers "F.Cu" "B.Cu" "In1.Cu" "In2.Cu" "In3.Cu" "In4.Cu" "In5.Cu" "In6.Cu"
			"In7.Cu" "In8.Cu" "In9.Cu" "In10.Cu" "In11.Cu" "In12.Cu" "In13.Cu" "In14.Cu"
			"In15.Cu" "In16.Cu"
		)
		(hatch none 0.5)
		(connect_pads
			(clearance 0)
		)
		(min_thickness 0.25)
		(keepout
			(tracks not_allowed)
			(vias allowed)
			(pads allowed)
			(copperpour not_allowed)
			(footprints allowed)
		)
		(placement
			(enabled no)
			(sheetname "")
		)
		(fill
			(thermal_gap 0.5)
			(thermal_bridge_width 0.5)
			(island_removal_mode 0)
		)
		(polygon
			(pts
				(arc
					(start 121.020586 -404.08352)
					(mid 120.639586 -404.46452)
					(end 121.020586 -404.84552)
				)
				(arc
					(start 121.884186 -404.84552)
					(mid 122.265186 -404.46452)
					(end 121.884186 -404.08352)
				)
			)
		)
	)
	(zone
		(layers "F.Cu" "B.Cu" "In1.Cu" "In2.Cu" "In3.Cu" "In4.Cu" "In5.Cu" "In6.Cu"
			"In7.Cu" "In8.Cu" "In9.Cu" "In10.Cu" "In11.Cu" "In12.Cu" "In13.Cu" "In14.Cu"
			"In15.Cu" "In16.Cu"
		)
		(hatch none 0.5)
		(connect_pads
			(clearance 0)
		)
		(min_thickness 0.25)
		(keepout
			(tracks not_allowed)
			(vias allowed)
			(pads allowed)
			(copperpour not_allowed)
			(footprints allowed)
		)
		(placement
			(enabled no)
			(sheetname "")
		)
		(fill
			(thermal_gap 0.5)
			(thermal_bridge_width 0.5)
			(island_removal_mode 0)
		)
		(polygon
			(pts
				(arc
					(start 340.219792 -300.146974)
					(mid 340.600792 -300.527974)
					(end 340.981792 -300.146974)
				)
				(arc
					(start 340.981792 -299.130974)
					(mid 340.600792 -298.749974)
					(end 340.219792 -299.130974)
				)
			)
		)
	)
	(zone
		(layers "F.Cu" "B.Cu" "In1.Cu" "In2.Cu" "In3.Cu" "In4.Cu" "In5.Cu" "In6.Cu"
			"In7.Cu" "In8.Cu" "In9.Cu" "In10.Cu" "In11.Cu" "In12.Cu" "In13.Cu" "In14.Cu"
			"In15.Cu" "In16.Cu"
		)
		(hatch none 0.5)
		(connect_pads
			(clearance 0)
		)
		(min_thickness 0.25)
		(keepout
			(tracks not_allowed)
			(vias allowed)
			(pads allowed)
			(copperpour not_allowed)
			(footprints allowed)
		)
		(placement
			(enabled no)
			(sheetname "")
		)
		(fill
			(thermal_gap 0.5)
			(thermal_bridge_width 0.5)
			(island_removal_mode 0)
		)
		(polygon
			(pts
				(arc
					(start 125.615446 -409.649168)
					(mid 125.234446 -410.030168)
					(end 125.615446 -410.411168)
				)
				(arc
					(start 126.479046 -410.411168)
					(mid 126.860046 -410.030168)
					(end 126.479046 -409.649168)
				)
			)
		)
	)
	(zone
		(layers "F.Cu" "B.Cu" "In1.Cu" "In2.Cu" "In3.Cu" "In4.Cu" "In5.Cu" "In6.Cu"
			"In7.Cu" "In8.Cu" "In9.Cu" "In10.Cu" "In11.Cu" "In12.Cu" "In13.Cu" "In14.Cu"
			"In15.Cu" "In16.Cu"
		)
		(hatch none 0.5)
		(connect_pads
			(clearance 0)
		)
		(min_thickness 0.25)
		(keepout
			(tracks not_allowed)
			(vias allowed)
			(pads allowed)
			(copperpour not_allowed)
			(footprints allowed)
		)
		(placement
			(enabled no)
			(sheetname "")
		)
		(fill
			(thermal_gap 0.5)
			(thermal_bridge_width 0.5)
			(island_removal_mode 0)
		)
		(polygon
			(pts
				(arc
					(start 124.63653 -389.634476)
					(mid 124.746501 -389.73553)
					(end 124.891292 -389.772144)
				)
				(arc
					(start 124.891292 -389.772144)
					(mid 125.106818 -389.68287)
					(end 125.196092 -389.467344)
				)
				(arc
					(start 125.196092 -389.467344)
					(mid 125.185755 -389.388605)
					(end 125.155452 -389.315198)
				)
				(arc
					(start 124.763022 -388.636256)
					(mid 124.650625 -388.514639)
					(end 124.491242 -388.469632)
				)
				(arc
					(start 124.491242 -388.469632)
					(mid 124.275716 -388.558906)
					(end 124.186442 -388.774432)
				)
				(arc
					(start 124.186442 -388.774432)
					(mid 124.19602 -388.850494)
					(end 124.224288 -388.921752)
				)
				(xy 124.621544 -389.609076) (xy 124.633736 -389.630412) (xy 124.636276 -389.63473)
			)
		)
	)
	(zone
		(layers "F.Cu" "B.Cu" "In1.Cu" "In2.Cu" "In3.Cu" "In4.Cu" "In5.Cu" "In6.Cu"
			"In7.Cu" "In8.Cu" "In9.Cu" "In10.Cu" "In11.Cu" "In12.Cu" "In13.Cu" "In14.Cu"
			"In15.Cu" "In16.Cu"
		)
		(hatch none 0.5)
		(connect_pads
			(clearance 0)
		)
		(min_thickness 0.25)
		(keepout
			(tracks not_allowed)
			(vias allowed)
			(pads allowed)
			(copperpour not_allowed)
			(footprints allowed)
		)
		(placement
			(enabled no)
			(sheetname "")
		)
		(fill
			(thermal_gap 0.5)
			(thermal_bridge_width 0.5)
			(island_removal_mode 0)
		)
		(polygon
			(pts
				(arc
					(start 314.515246 -415.00552)
					(mid 314.134246 -415.38652)
					(end 314.515246 -415.76752)
				)
				(arc
					(start 315.378846 -415.76752)
					(mid 315.759846 -415.38652)
					(end 315.378846 -415.00552)
				)
			)
		)
	)
	(zone
		(layers "F.Cu" "B.Cu" "In1.Cu" "In2.Cu" "In3.Cu" "In4.Cu" "In5.Cu" "In6.Cu"
			"In7.Cu" "In8.Cu" "In9.Cu" "In10.Cu" "In11.Cu" "In12.Cu" "In13.Cu" "In14.Cu"
			"In15.Cu" "In16.Cu"
		)
		(hatch none 0.5)
		(connect_pads
			(clearance 0)
		)
		(min_thickness 0.25)
		(keepout
			(tracks not_allowed)
			(vias allowed)
			(pads allowed)
			(copperpour not_allowed)
			(footprints allowed)
		)
		(placement
			(enabled no)
			(sheetname "")
		)
		(fill
			(thermal_gap 0.5)
			(thermal_bridge_width 0.5)
			(island_removal_mode 0)
		)
		(polygon
			(pts
				(arc
					(start 367.816892 -377.03633)
					(mid 367.435892 -377.41733)
					(end 367.816892 -377.79833)
				)
				(arc
					(start 368.680492 -377.79833)
					(mid 369.061492 -377.41733)
					(end 368.680492 -377.03633)
				)
			)
		)
	)
	(zone
		(layers "F.Cu" "B.Cu" "In1.Cu" "In2.Cu" "In3.Cu" "In4.Cu" "In5.Cu" "In6.Cu"
			"In7.Cu" "In8.Cu" "In9.Cu" "In10.Cu" "In11.Cu" "In12.Cu" "In13.Cu" "In14.Cu"
			"In15.Cu" "In16.Cu"
		)
		(hatch none 0.5)
		(connect_pads
			(clearance 0)
		)
		(min_thickness 0.25)
		(keepout
			(tracks not_allowed)
			(vias allowed)
			(pads allowed)
			(copperpour not_allowed)
			(footprints allowed)
		)
		(placement
			(enabled no)
			(sheetname "")
		)
		(fill
			(thermal_gap 0.5)
			(thermal_bridge_width 0.5)
			(island_removal_mode 0)
		)
		(polygon
			(pts
				(arc
					(start 307.523896 -377.03633)
					(mid 307.142896 -377.41733)
					(end 307.523896 -377.79833)
				)
				(arc
					(start 308.387496 -377.79833)
					(mid 308.768496 -377.41733)
					(end 308.387496 -377.03633)
				)
			)
		)
	)
	(zone
		(layers "F.Cu" "B.Cu" "In1.Cu" "In2.Cu" "In3.Cu" "In4.Cu" "In5.Cu" "In6.Cu"
			"In7.Cu" "In8.Cu" "In9.Cu" "In10.Cu" "In11.Cu" "In12.Cu" "In13.Cu" "In14.Cu"
			"In15.Cu" "In16.Cu"
		)
		(hatch none 0.5)
		(connect_pads
			(clearance 0)
		)
		(min_thickness 0.25)
		(keepout
			(tracks not_allowed)
			(vias allowed)
			(pads allowed)
			(copperpour not_allowed)
			(footprints allowed)
		)
		(placement
			(enabled no)
			(sheetname "")
		)
		(fill
			(thermal_gap 0.5)
			(thermal_bridge_width 0.5)
			(island_removal_mode 0)
		)
		(polygon
			(pts
				(arc
					(start 70.141846 -420.760398)
					(mid 70.164164 -420.81428)
					(end 70.218046 -420.836598)
				)
				(arc
					(start 71.157846 -420.836598)
					(mid 71.211728 -420.81428)
					(end 71.234046 -420.760398)
				)
				(arc
					(start 71.234046 -418.218874)
					(mid 71.211728 -418.164992)
					(end 71.157846 -418.142674)
				)
				(arc
					(start 70.218046 -418.142674)
					(mid 70.164164 -418.164992)
					(end 70.141846 -418.218874)
				)
			)
		)
	)
	(zone
		(layers "F.Cu" "B.Cu" "In1.Cu" "In2.Cu" "In3.Cu" "In4.Cu" "In5.Cu" "In6.Cu"
			"In7.Cu" "In8.Cu" "In9.Cu" "In10.Cu" "In11.Cu" "In12.Cu" "In13.Cu" "In14.Cu"
			"In15.Cu" "In16.Cu"
		)
		(hatch none 0.5)
		(connect_pads
			(clearance 0)
		)
		(min_thickness 0.25)
		(keepout
			(tracks not_allowed)
			(vias allowed)
			(pads allowed)
			(copperpour not_allowed)
			(footprints allowed)
		)
		(placement
			(enabled no)
			(sheetname "")
		)
		(fill
			(thermal_gap 0.5)
			(thermal_bridge_width 0.5)
			(island_removal_mode 0)
		)
		(polygon
			(pts
				(arc
					(start 335.957926 -415.00552)
					(mid 335.576926 -415.38652)
					(end 335.957926 -415.76752)
				)
				(arc
					(start 336.821526 -415.76752)
					(mid 337.202526 -415.38652)
					(end 336.821526 -415.00552)
				)
			)
		)
	)
	(zone
		(layers "F.Cu" "B.Cu" "In1.Cu" "In2.Cu" "In3.Cu" "In4.Cu" "In5.Cu" "In6.Cu"
			"In7.Cu" "In8.Cu" "In9.Cu" "In10.Cu" "In11.Cu" "In12.Cu" "In13.Cu" "In14.Cu"
			"In15.Cu" "In16.Cu"
		)
		(hatch none 0.5)
		(connect_pads
			(clearance 0)
		)
		(min_thickness 0.25)
		(keepout
			(tracks not_allowed)
			(vias allowed)
			(pads allowed)
			(copperpour not_allowed)
			(footprints allowed)
		)
		(placement
			(enabled no)
			(sheetname "")
		)
		(fill yes
			(thermal_gap 0.5)
			(thermal_bridge_width 0.5)
			(island_removal_mode 0)
		)
		(polygon
			(pts
				(arc
					(start 411.964124 -394.552424)
					(mid 412.074095 -394.653478)
					(end 412.218886 -394.690092)
				)
				(arc
					(start 412.218886 -394.690092)
					(mid 412.434412 -394.600818)
					(end 412.523686 -394.385292)
				)
				(arc
					(start 412.523686 -394.385292)
					(mid 412.513349 -394.306553)
					(end 412.483046 -394.233146)
				)
				(arc
					(start 412.090616 -393.554204)
					(mid 411.978219 -393.432587)
					(end 411.818836 -393.38758)
				)
				(arc
					(start 411.818836 -393.38758)
					(mid 411.60331 -393.476854)
					(end 411.514036 -393.69238)
				)
				(arc
					(start 411.514036 -393.69238)
					(mid 411.523614 -393.768442)
					(end 411.551882 -393.8397)
				)
				(xy 411.949138 -394.527024) (xy 411.96133 -394.54836) (xy 411.96387 -394.552678)
			)
		)
	)
	(zone
		(layers "F.Cu" "B.Cu" "In1.Cu" "In2.Cu" "In3.Cu" "In4.Cu" "In5.Cu" "In6.Cu"
			"In7.Cu" "In8.Cu" "In9.Cu" "In10.Cu" "In11.Cu" "In12.Cu" "In13.Cu" "In14.Cu"
			"In15.Cu" "In16.Cu"
		)
		(hatch none 0.5)
		(connect_pads
			(clearance 0)
		)
		(min_thickness 0.25)
		(keepout
			(tracks not_allowed)
			(vias allowed)
			(pads allowed)
			(copperpour not_allowed)
			(footprints allowed)
		)
		(placement
			(enabled no)
			(sheetname "")
		)
		(fill
			(thermal_gap 0.5)
			(thermal_bridge_width 0.5)
			(island_removal_mode 0)
		)
		(polygon
			(pts
				(arc
					(start 130.68808 -27.75458)
					(mid 131.06908 -28.13558)
					(end 131.45008 -27.75458)
				)
				(arc
					(start 131.45008 -26.76398)
					(mid 131.06908 -26.38298)
					(end 130.68808 -26.76398)
				)
			)
		)
	)
	(zone
		(layers "F.Cu" "B.Cu" "In1.Cu" "In2.Cu" "In3.Cu" "In4.Cu" "In5.Cu" "In6.Cu"
			"In7.Cu" "In8.Cu" "In9.Cu" "In10.Cu" "In11.Cu" "In12.Cu" "In13.Cu" "In14.Cu"
			"In15.Cu" "In16.Cu"
		)
		(hatch none 0.5)
		(connect_pads
			(clearance 0)
		)
		(min_thickness 0.25)
		(keepout
			(tracks not_allowed)
			(vias allowed)
			(pads allowed)
			(copperpour not_allowed)
			(footprints allowed)
		)
		(placement
			(enabled no)
			(sheetname "")
		)
		(fill
			(thermal_gap 0.5)
			(thermal_bridge_width 0.5)
			(island_removal_mode 0)
		)
		(polygon
			(pts
				(arc
					(start 421.825166 -400.811238)
					(mid 421.444166 -400.430238)
					(end 421.063166 -400.811238)
				)
				(arc
					(start 421.063166 -401.674838)
					(mid 421.444166 -402.055838)
					(end 421.825166 -401.674838)
				)
			)
		)
	)
	(zone
		(layers "F.Cu" "B.Cu" "In1.Cu" "In2.Cu" "In3.Cu" "In4.Cu" "In5.Cu" "In6.Cu"
			"In7.Cu" "In8.Cu" "In9.Cu" "In10.Cu" "In11.Cu" "In12.Cu" "In13.Cu" "In14.Cu"
			"In15.Cu" "In16.Cu"
		)
		(hatch none 0.5)
		(connect_pads
			(clearance 0)
		)
		(min_thickness 0.25)
		(keepout
			(tracks not_allowed)
			(vias allowed)
			(pads allowed)
			(copperpour not_allowed)
			(footprints allowed)
		)
		(placement
			(enabled no)
			(sheetname "")
		)
		(fill
			(thermal_gap 0.5)
			(thermal_bridge_width 0.5)
			(island_removal_mode 0)
		)
		(polygon
			(pts
				(arc
					(start 142.463266 -412.189168)
					(mid 142.082266 -412.570168)
					(end 142.463266 -412.951168)
				)
				(arc
					(start 143.326866 -412.951168)
					(mid 143.707866 -412.570168)
					(end 143.326866 -412.189168)
				)
			)
		)
	)
	(zone
		(layers "F.Cu" "B.Cu" "In1.Cu" "In2.Cu" "In3.Cu" "In4.Cu" "In5.Cu" "In6.Cu"
			"In7.Cu" "In8.Cu" "In9.Cu" "In10.Cu" "In11.Cu" "In12.Cu" "In13.Cu" "In14.Cu"
			"In15.Cu" "In16.Cu"
		)
		(hatch none 0.5)
		(connect_pads
			(clearance 0)
		)
		(min_thickness 0.25)
		(keepout
			(tracks not_allowed)
			(vias allowed)
			(pads allowed)
			(copperpour not_allowed)
			(footprints allowed)
		)
		(placement
			(enabled no)
			(sheetname "")
		)
		(fill
			(thermal_gap 0.5)
			(thermal_bridge_width 0.5)
			(island_removal_mode 0)
		)
		(polygon
			(pts
				(arc
					(start 76.894944 -406.62352)
					(mid 76.513944 -407.00452)
					(end 76.894944 -407.38552)
				)
				(arc
					(start 77.758544 -407.38552)
					(mid 78.139544 -407.00452)
					(end 77.758544 -406.62352)
				)
			)
		)
	)
	(zone
		(layers "F.Cu" "B.Cu" "In1.Cu" "In2.Cu" "In3.Cu" "In4.Cu" "In5.Cu" "In6.Cu"
			"In7.Cu" "In8.Cu" "In9.Cu" "In10.Cu" "In11.Cu" "In12.Cu" "In13.Cu" "In14.Cu"
			"In15.Cu" "In16.Cu"
		)
		(hatch none 0.5)
		(connect_pads
			(clearance 0)
		)
		(min_thickness 0.25)
		(keepout
			(tracks not_allowed)
			(vias allowed)
			(pads allowed)
			(copperpour not_allowed)
			(footprints allowed)
		)
		(placement
			(enabled no)
			(sheetname "")
		)
		(fill
			(thermal_gap 0.5)
			(thermal_bridge_width 0.5)
			(island_removal_mode 0)
		)
		(polygon
			(pts
				(arc
					(start 396.931642 -415.00552)
					(mid 396.550642 -415.38652)
					(end 396.931642 -415.76752)
				)
				(arc
					(start 397.795242 -415.76752)
					(mid 398.176242 -415.38652)
					(end 397.795242 -415.00552)
				)
			)
		)
	)
	(zone
		(layers "F.Cu" "B.Cu" "In1.Cu" "In2.Cu" "In3.Cu" "In4.Cu" "In5.Cu" "In6.Cu"
			"In7.Cu" "In8.Cu" "In9.Cu" "In10.Cu" "In11.Cu" "In12.Cu" "In13.Cu" "In14.Cu"
			"In15.Cu" "In16.Cu"
		)
		(hatch none 0.5)
		(connect_pads
			(clearance 0)
		)
		(min_thickness 0.25)
		(keepout
			(tracks not_allowed)
			(vias allowed)
			(pads allowed)
			(copperpour not_allowed)
			(footprints allowed)
		)
		(placement
			(enabled no)
			(sheetname "")
		)
		(fill
			(thermal_gap 0.5)
			(thermal_bridge_width 0.5)
			(island_removal_mode 0)
		)
		(polygon
			(pts
				(arc
					(start 417.025328 -400.811238)
					(mid 416.644328 -400.430238)
					(end 416.263328 -400.811238)
				)
				(arc
					(start 416.263328 -401.674838)
					(mid 416.644328 -402.055838)
					(end 417.025328 -401.674838)
				)
			)
		)
	)
	(zone
		(layers "F.Cu" "B.Cu" "In1.Cu" "In2.Cu" "In3.Cu" "In4.Cu" "In5.Cu" "In6.Cu"
			"In7.Cu" "In8.Cu" "In9.Cu" "In10.Cu" "In11.Cu" "In12.Cu" "In13.Cu" "In14.Cu"
			"In15.Cu" "In16.Cu"
		)
		(hatch none 0.5)
		(connect_pads
			(clearance 0)
		)
		(min_thickness 0.25)
		(keepout
			(tracks not_allowed)
			(vias allowed)
			(pads allowed)
			(copperpour not_allowed)
			(footprints allowed)
		)
		(placement
			(enabled no)
			(sheetname "")
		)
		(fill
			(thermal_gap 0.5)
			(thermal_bridge_width 0.5)
			(island_removal_mode 0)
		)
		(polygon
			(pts
				(arc
					(start 343.664032 -398.016476)
					(mid 343.774003 -398.11753)
					(end 343.918794 -398.154144)
				)
				(arc
					(start 343.918794 -398.154144)
					(mid 344.13432 -398.06487)
					(end 344.223594 -397.849344)
				)
				(arc
					(start 344.223594 -397.849344)
					(mid 344.213257 -397.770605)
					(end 344.182954 -397.697198)
				)
				(arc
					(start 343.790524 -397.018256)
					(mid 343.678127 -396.896639)
					(end 343.518744 -396.851632)
				)
				(arc
					(start 343.518744 -396.851632)
					(mid 343.303218 -396.940906)
					(end 343.213944 -397.156432)
				)
				(arc
					(start 343.213944 -397.156432)
					(mid 343.223522 -397.232494)
					(end 343.25179 -397.303752)
				)
				(xy 343.649046 -397.991076) (xy 343.661238 -398.012412) (xy 343.663778 -398.01673)
			)
		)
	)
	(zone
		(layers "F.Cu" "B.Cu" "In1.Cu" "In2.Cu" "In3.Cu" "In4.Cu" "In5.Cu" "In6.Cu"
			"In7.Cu" "In8.Cu" "In9.Cu" "In10.Cu" "In11.Cu" "In12.Cu" "In13.Cu" "In14.Cu"
			"In15.Cu" "In16.Cu"
		)
		(hatch none 0.5)
		(connect_pads
			(clearance 0)
		)
		(min_thickness 0.25)
		(keepout
			(tracks not_allowed)
			(vias allowed)
			(pads allowed)
			(copperpour not_allowed)
			(footprints allowed)
		)
		(placement
			(enabled no)
			(sheetname "")
		)
		(fill
			(thermal_gap 0.5)
			(thermal_bridge_width 0.5)
			(island_removal_mode 0)
		)
		(polygon
			(pts
				(arc
					(start 375.488962 -418.031168)
					(mid 375.107962 -418.412168)
					(end 375.488962 -418.793168)
				)
				(arc
					(start 376.352562 -418.793168)
					(mid 376.733562 -418.412168)
					(end 376.352562 -418.031168)
				)
			)
		)
	)
	(zone
		(layers "F.Cu" "B.Cu" "In1.Cu" "In2.Cu" "In3.Cu" "In4.Cu" "In5.Cu" "In6.Cu"
			"In7.Cu" "In8.Cu" "In9.Cu" "In10.Cu" "In11.Cu" "In12.Cu" "In13.Cu" "In14.Cu"
			"In15.Cu" "In16.Cu"
		)
		(hatch none 0.5)
		(connect_pads
			(clearance 0)
		)
		(min_thickness 0.25)
		(keepout
			(tracks not_allowed)
			(vias allowed)
			(pads allowed)
			(copperpour not_allowed)
			(footprints allowed)
		)
		(placement
			(enabled no)
			(sheetname "")
		)
		(fill
			(thermal_gap 0.5)
			(thermal_bridge_width 0.5)
			(island_removal_mode 0)
		)
		(polygon
			(pts
				(arc
					(start 153.184606 -409.649168)
					(mid 152.803606 -410.030168)
					(end 153.184606 -410.411168)
				)
				(arc
					(start 154.048206 -410.411168)
					(mid 154.429206 -410.030168)
					(end 154.048206 -409.649168)
				)
			)
		)
	)
	(zone
		(layers "F.Cu" "B.Cu" "In1.Cu" "In2.Cu" "In3.Cu" "In4.Cu" "In5.Cu" "In6.Cu"
			"In7.Cu" "In8.Cu" "In9.Cu" "In10.Cu" "In11.Cu" "In12.Cu" "In13.Cu" "In14.Cu"
			"In15.Cu" "In16.Cu"
		)
		(hatch none 0.5)
		(connect_pads
			(clearance 0)
		)
		(min_thickness 0.25)
		(keepout
			(tracks not_allowed)
			(vias allowed)
			(pads allowed)
			(copperpour not_allowed)
			(footprints allowed)
		)
		(placement
			(enabled no)
			(sheetname "")
		)
		(fill
			(thermal_gap 0.5)
			(thermal_bridge_width 0.5)
			(island_removal_mode 0)
		)
		(polygon
			(pts
				(arc
					(start 364.380272 4.651756)
					(mid 364.812072 4.219956)
					(end 365.243872 4.651756)
				)
				(arc
					(start 365.243872 5.515356)
					(mid 364.812072 5.947156)
					(end 364.380272 5.515356)
				)
			)
		)
	)
	(zone
		(layers "F.Cu" "B.Cu" "In1.Cu" "In2.Cu" "In3.Cu" "In4.Cu" "In5.Cu" "In6.Cu"
			"In7.Cu" "In8.Cu" "In9.Cu" "In10.Cu" "In11.Cu" "In12.Cu" "In13.Cu" "In14.Cu"
			"In15.Cu" "In16.Cu"
		)
		(hatch none 0.5)
		(connect_pads
			(clearance 0)
		)
		(min_thickness 0.25)
		(keepout
			(tracks not_allowed)
			(vias allowed)
			(pads allowed)
			(copperpour not_allowed)
			(footprints allowed)
		)
		(placement
			(enabled no)
			(sheetname "")
		)
		(fill
			(thermal_gap 0.5)
			(thermal_bridge_width 0.5)
			(island_removal_mode 0)
		)
		(polygon
			(pts
				(arc
					(start 419.42512 -400.811238)
					(mid 419.04412 -400.430238)
					(end 418.66312 -400.811238)
				)
				(arc
					(start 418.66312 -401.674838)
					(mid 419.04412 -402.055838)
					(end 419.42512 -401.674838)
				)
			)
		)
	)
	(zone
		(layers "F.Cu" "B.Cu" "In1.Cu" "In2.Cu" "In3.Cu" "In4.Cu" "In5.Cu" "In6.Cu"
			"In7.Cu" "In8.Cu" "In9.Cu" "In10.Cu" "In11.Cu" "In12.Cu" "In13.Cu" "In14.Cu"
			"In15.Cu" "In16.Cu"
		)
		(hatch none 0.5)
		(connect_pads
			(clearance 0)
		)
		(min_thickness 0.25)
		(keepout
			(tracks not_allowed)
			(vias allowed)
			(pads allowed)
			(copperpour not_allowed)
			(footprints allowed)
		)
		(placement
			(enabled no)
			(sheetname "")
		)
		(fill
			(thermal_gap 0.5)
			(thermal_bridge_width 0.5)
			(island_removal_mode 0)
		)
		(polygon
			(pts
				(arc
					(start 308.736238 -398.016476)
					(mid 308.846209 -398.11753)
					(end 308.991 -398.154144)
				)
				(arc
					(start 308.991 -398.154144)
					(mid 309.206526 -398.06487)
					(end 309.2958 -397.849344)
				)
				(arc
					(start 309.2958 -397.849344)
					(mid 309.285463 -397.770605)
					(end 309.25516 -397.697198)
				)
				(arc
					(start 308.86273 -397.018256)
					(mid 308.750333 -396.896639)
					(end 308.59095 -396.851632)
				)
				(arc
					(start 308.59095 -396.851632)
					(mid 308.375424 -396.940906)
					(end 308.28615 -397.156432)
				)
				(arc
					(start 308.28615 -397.156432)
					(mid 308.295728 -397.232494)
					(end 308.323996 -397.303752)
				)
				(xy 308.721252 -397.991076) (xy 308.733444 -398.012412) (xy 308.735984 -398.01673)
			)
		)
	)
	(zone
		(layers "F.Cu" "B.Cu" "In1.Cu" "In2.Cu" "In3.Cu" "In4.Cu" "In5.Cu" "In6.Cu"
			"In7.Cu" "In8.Cu" "In9.Cu" "In10.Cu" "In11.Cu" "In12.Cu" "In13.Cu" "In14.Cu"
			"In15.Cu" "In16.Cu"
		)
		(hatch none 0.5)
		(connect_pads
			(clearance 0)
		)
		(min_thickness 0.25)
		(keepout
			(tracks not_allowed)
			(vias allowed)
			(pads allowed)
			(copperpour not_allowed)
			(footprints allowed)
		)
		(placement
			(enabled no)
			(sheetname "")
		)
		(fill
			(thermal_gap 0.5)
			(thermal_bridge_width 0.5)
			(island_removal_mode 0)
		)
		(polygon
			(pts
				(arc
					(start 150.121366 -409.649168)
					(mid 149.740366 -410.030168)
					(end 150.121366 -410.411168)
				)
				(arc
					(start 150.984966 -410.411168)
					(mid 151.365966 -410.030168)
					(end 150.984966 -409.649168)
				)
			)
		)
	)
	(zone
		(layers "F.Cu" "B.Cu" "In1.Cu" "In2.Cu" "In3.Cu" "In4.Cu" "In5.Cu" "In6.Cu"
			"In7.Cu" "In8.Cu" "In9.Cu" "In10.Cu" "In11.Cu" "In12.Cu" "In13.Cu" "In14.Cu"
			"In15.Cu" "In16.Cu"
		)
		(hatch none 0.5)
		(connect_pads
			(clearance 0)
		)
		(min_thickness 0.25)
		(keepout
			(tracks not_allowed)
			(vias allowed)
			(pads allowed)
			(copperpour not_allowed)
			(footprints allowed)
		)
		(placement
			(enabled no)
			(sheetname "")
		)
		(fill
			(thermal_gap 0.5)
			(thermal_bridge_width 0.5)
			(island_removal_mode 0)
		)
		(polygon
			(pts
				(arc
					(start 116.497354 -392.429238)
					(mid 116.116354 -392.048238)
					(end 115.735354 -392.429238)
				)
				(arc
					(start 115.735354 -393.292838)
					(mid 116.116354 -393.673838)
					(end 116.497354 -393.292838)
				)
			)
		)
	)
	(zone
		(layers "F.Cu" "B.Cu" "In1.Cu" "In2.Cu" "In3.Cu" "In4.Cu" "In5.Cu" "In6.Cu"
			"In7.Cu" "In8.Cu" "In9.Cu" "In10.Cu" "In11.Cu" "In12.Cu" "In13.Cu" "In14.Cu"
			"In15.Cu" "In16.Cu"
		)
		(hatch none 0.5)
		(connect_pads
			(clearance 0)
		)
		(min_thickness 0.25)
		(keepout
			(tracks not_allowed)
			(vias allowed)
			(pads allowed)
			(copperpour not_allowed)
			(footprints allowed)
		)
		(placement
			(enabled no)
			(sheetname "")
		)
		(fill
			(thermal_gap 0.5)
			(thermal_bridge_width 0.5)
			(island_removal_mode 0)
		)
		(polygon
			(pts
				(arc
					(start 160.76422 -389.634476)
					(mid 160.874191 -389.73553)
					(end 161.018982 -389.772144)
				)
				(arc
					(start 161.018982 -389.772144)
					(mid 161.234508 -389.68287)
					(end 161.323782 -389.467344)
				)
				(arc
					(start 161.323782 -389.467344)
					(mid 161.313445 -389.388605)
					(end 161.283142 -389.315198)
				)
				(arc
					(start 160.890712 -388.636256)
					(mid 160.778315 -388.514639)
					(end 160.618932 -388.469632)
				)
				(arc
					(start 160.618932 -388.469632)
					(mid 160.403406 -388.558906)
					(end 160.314132 -388.774432)
				)
				(arc
					(start 160.314132 -388.774432)
					(mid 160.32371 -388.850494)
					(end 160.351978 -388.921752)
				)
				(xy 160.749234 -389.609076) (xy 160.761426 -389.630412) (xy 160.763966 -389.63473)
			)
		)
	)
	(zone
		(layers "F.Cu" "B.Cu" "In1.Cu" "In2.Cu" "In3.Cu" "In4.Cu" "In5.Cu" "In6.Cu"
			"In7.Cu" "In8.Cu" "In9.Cu" "In10.Cu" "In11.Cu" "In12.Cu" "In13.Cu" "In14.Cu"
			"In15.Cu" "In16.Cu"
		)
		(hatch none 0.5)
		(connect_pads
			(clearance 0)
		)
		(min_thickness 0.25)
		(keepout
			(tracks not_allowed)
			(vias allowed)
			(pads allowed)
			(copperpour not_allowed)
			(footprints allowed)
		)
		(placement
			(enabled no)
			(sheetname "")
		)
		(fill
			(thermal_gap 0.5)
			(thermal_bridge_width 0.5)
			(island_removal_mode 0)
		)
		(polygon
			(pts
				(arc
					(start 389.273542 -412.46552)
					(mid 388.892542 -412.84652)
					(end 389.273542 -413.22752)
				)
				(arc
					(start 390.137142 -413.22752)
					(mid 390.518142 -412.84652)
					(end 390.137142 -412.46552)
				)
			)
		)
	)
	(zone
		(layers "F.Cu" "B.Cu" "In1.Cu" "In2.Cu" "In3.Cu" "In4.Cu" "In5.Cu" "In6.Cu"
			"In7.Cu" "In8.Cu" "In9.Cu" "In10.Cu" "In11.Cu" "In12.Cu" "In13.Cu" "In14.Cu"
			"In15.Cu" "In16.Cu"
		)
		(hatch none 0.5)
		(connect_pads
			(clearance 0)
		)
		(min_thickness 0.25)
		(keepout
			(tracks not_allowed)
			(vias allowed)
			(pads allowed)
			(copperpour not_allowed)
			(footprints allowed)
		)
		(placement
			(enabled no)
			(sheetname "")
		)
		(fill
			(thermal_gap 0.5)
			(thermal_bridge_width 0.5)
			(island_removal_mode 0)
		)
		(polygon
			(pts
				(arc
					(start 140.931646 -406.62352)
					(mid 140.550646 -407.00452)
					(end 140.931646 -407.38552)
				)
				(arc
					(start 141.795246 -407.38552)
					(mid 142.176246 -407.00452)
					(end 141.795246 -406.62352)
				)
			)
		)
	)
	(zone
		(layers "F.Cu" "B.Cu" "In1.Cu" "In2.Cu" "In3.Cu" "In4.Cu" "In5.Cu" "In6.Cu"
			"In7.Cu" "In8.Cu" "In9.Cu" "In10.Cu" "In11.Cu" "In12.Cu" "In13.Cu" "In14.Cu"
			"In15.Cu" "In16.Cu"
		)
		(hatch none 0.5)
		(connect_pads
			(clearance 0)
		)
		(min_thickness 0.25)
		(keepout
			(tracks not_allowed)
			(vias allowed)
			(pads allowed)
			(copperpour not_allowed)
			(footprints allowed)
		)
		(placement
			(enabled no)
			(sheetname "")
		)
		(fill
			(thermal_gap 0.5)
			(thermal_bridge_width 0.5)
			(island_removal_mode 0)
		)
		(polygon
			(pts
				(arc
					(start 87.455502 -373.58193)
					(mid 87.074502 -373.96293)
					(end 87.455502 -374.34393)
				)
				(arc
					(start 88.319102 -374.34393)
					(mid 88.700102 -373.96293)
					(end 88.319102 -373.58193)
				)
			)
		)
	)
	(zone
		(layers "F.Cu" "B.Cu" "In1.Cu" "In2.Cu" "In3.Cu" "In4.Cu" "In5.Cu" "In6.Cu"
			"In7.Cu" "In8.Cu" "In9.Cu" "In10.Cu" "In11.Cu" "In12.Cu" "In13.Cu" "In14.Cu"
			"In15.Cu" "In16.Cu"
		)
		(hatch none 0.5)
		(connect_pads
			(clearance 0)
		)
		(min_thickness 0.25)
		(keepout
			(tracks not_allowed)
			(vias allowed)
			(pads allowed)
			(copperpour not_allowed)
			(footprints allowed)
		)
		(placement
			(enabled no)
			(sheetname "")
		)
		(fill
			(thermal_gap 0.5)
			(thermal_bridge_width 0.5)
			(island_removal_mode 0)
		)
		(polygon
			(pts
				(arc
					(start 86.084664 -406.62352)
					(mid 85.703664 -407.00452)
					(end 86.084664 -407.38552)
				)
				(arc
					(start 86.948264 -407.38552)
					(mid 87.329264 -407.00452)
					(end 86.948264 -406.62352)
				)
			)
		)
	)
	(zone
		(layers "F.Cu" "B.Cu" "In1.Cu" "In2.Cu" "In3.Cu" "In4.Cu" "In5.Cu" "In6.Cu"
			"In7.Cu" "In8.Cu" "In9.Cu" "In10.Cu" "In11.Cu" "In12.Cu" "In13.Cu" "In14.Cu"
			"In15.Cu" "In16.Cu"
		)
		(hatch none 0.5)
		(connect_pads
			(clearance 0)
		)
		(min_thickness 0.25)
		(keepout
			(tracks not_allowed)
			(vias allowed)
			(pads allowed)
			(copperpour not_allowed)
			(footprints allowed)
		)
		(placement
			(enabled no)
			(sheetname "")
		)
		(fill
			(thermal_gap 0.5)
			(thermal_bridge_width 0.5)
			(island_removal_mode 0)
		)
		(polygon
			(pts
				(arc
					(start 118.636542 -389.634476)
					(mid 118.746513 -389.73553)
					(end 118.891304 -389.772144)
				)
				(arc
					(start 118.891304 -389.772144)
					(mid 119.10683 -389.68287)
					(end 119.196104 -389.467344)
				)
				(arc
					(start 119.196104 -389.467344)
					(mid 119.185767 -389.388605)
					(end 119.155464 -389.315198)
				)
				(arc
					(start 118.763034 -388.636256)
					(mid 118.650637 -388.514639)
					(end 118.491254 -388.469632)
				)
				(arc
					(start 118.491254 -388.469632)
					(mid 118.275728 -388.558906)
					(end 118.186454 -388.774432)
				)
				(arc
					(start 118.186454 -388.774432)
					(mid 118.196032 -388.850494)
					(end 118.2243 -388.921752)
				)
				(xy 118.621556 -389.609076) (xy 118.633748 -389.630412) (xy 118.636288 -389.63473)
			)
		)
	)
	(zone
		(layers "F.Cu" "B.Cu" "In1.Cu" "In2.Cu" "In3.Cu" "In4.Cu" "In5.Cu" "In6.Cu"
			"In7.Cu" "In8.Cu" "In9.Cu" "In10.Cu" "In11.Cu" "In12.Cu" "In13.Cu" "In14.Cu"
			"In15.Cu" "In16.Cu"
		)
		(hatch none 0.5)
		(connect_pads
			(clearance 0)
		)
		(min_thickness 0.25)
		(keepout
			(tracks not_allowed)
			(vias allowed)
			(pads allowed)
			(copperpour not_allowed)
			(footprints allowed)
		)
		(placement
			(enabled no)
			(sheetname "")
		)
		(fill
			(thermal_gap 0.5)
			(thermal_bridge_width 0.5)
			(island_removal_mode 0)
		)
		(polygon
			(pts
				(arc
					(start 166.496746 -361.532678)
					(mid 166.115746 -361.151678)
					(end 165.734746 -361.532678)
				)
				(arc
					(start 165.734746 -362.396278)
					(mid 166.115746 -362.777278)
					(end 166.496746 -362.396278)
				)
			)
		)
	)
	(zone
		(layers "F.Cu" "B.Cu" "In1.Cu" "In2.Cu" "In3.Cu" "In4.Cu" "In5.Cu" "In6.Cu"
			"In7.Cu" "In8.Cu" "In9.Cu" "In10.Cu" "In11.Cu" "In12.Cu" "In13.Cu" "In14.Cu"
			"In15.Cu" "In16.Cu"
		)
		(hatch none 0.5)
		(connect_pads
			(clearance 0)
		)
		(min_thickness 0.25)
		(keepout
			(tracks not_allowed)
			(vias allowed)
			(pads allowed)
			(copperpour not_allowed)
			(footprints allowed)
		)
		(placement
			(enabled no)
			(sheetname "")
		)
		(fill
			(thermal_gap 0.5)
			(thermal_bridge_width 0.5)
			(island_removal_mode 0)
		)
		(polygon
			(pts
				(arc
					(start 306.857146 -412.46552)
					(mid 306.476146 -412.84652)
					(end 306.857146 -413.22752)
				)
				(arc
					(start 307.720746 -413.22752)
					(mid 308.101746 -412.84652)
					(end 307.720746 -412.46552)
				)
			)
		)
	)
	(zone
		(layers "F.Cu" "B.Cu" "In1.Cu" "In2.Cu" "In3.Cu" "In4.Cu" "In5.Cu" "In6.Cu"
			"In7.Cu" "In8.Cu" "In9.Cu" "In10.Cu" "In11.Cu" "In12.Cu" "In13.Cu" "In14.Cu"
			"In15.Cu" "In16.Cu"
		)
		(hatch none 0.5)
		(connect_pads
			(clearance 0)
		)
		(min_thickness 0.25)
		(keepout
			(tracks not_allowed)
			(vias allowed)
			(pads allowed)
			(copperpour not_allowed)
			(footprints allowed)
		)
		(placement
			(enabled no)
			(sheetname "")
		)
		(fill
			(thermal_gap 0.5)
			(thermal_bridge_width 0.5)
			(island_removal_mode 0)
		)
		(polygon
			(pts
				(arc
					(start 342.724994 -400.811238)
					(mid 342.343994 -400.430238)
					(end 341.962994 -400.811238)
				)
				(arc
					(start 341.962994 -401.674838)
					(mid 342.343994 -402.055838)
					(end 342.724994 -401.674838)
				)
			)
		)
	)
	(zone
		(layers "F.Cu" "B.Cu" "In2.Cu" "In4.Cu")
		(hatch none 0.5)
		(connect_pads
			(clearance 0)
		)
		(min_thickness 0.25)
		(keepout
			(tracks not_allowed)
			(vias allowed)
			(pads allowed)
			(copperpour not_allowed)
			(footprints allowed)
		)
		(placement
			(enabled no)
			(sheetname "")
		)
		(fill yes
			(thermal_gap 0.5)
			(thermal_bridge_width 0.5)
			(island_removal_mode 0)
		)
		(polygon
			(pts
				(arc
					(start 9.440418 -173.07814)
					(mid 8.772398 -173.07814)
					(end 9.440418 -173.07814)
				)
			)
		)
	)
	(zone
		(layers "F.Cu" "B.Cu" "In2.Cu" "In4.Cu")
		(hatch none 0.5)
		(connect_pads
			(clearance 0)
		)
		(min_thickness 0.25)
		(keepout
			(tracks not_allowed)
			(vias allowed)
			(pads allowed)
			(copperpour not_allowed)
			(footprints allowed)
		)
		(placement
			(enabled no)
			(sheetname "")
		)
		(fill yes
			(thermal_gap 0.5)
			(thermal_bridge_width 0.5)
			(island_removal_mode 0)
		)
		(polygon
			(pts
				(arc
					(start 9.440418 -177.754788)
					(mid 8.772398 -177.754788)
					(end 9.440418 -177.754788)
				)
			)
		)
	)
	(zone
		(layers "F.Cu" "B.Cu" "In2.Cu" "In4.Cu")
		(hatch none 0.5)
		(connect_pads
			(clearance 0)
		)
		(min_thickness 0.25)
		(keepout
			(tracks not_allowed)
			(vias allowed)
			(pads allowed)
			(copperpour not_allowed)
			(footprints allowed)
		)
		(placement
			(enabled no)
			(sheetname "")
		)
		(fill yes
			(thermal_gap 0.5)
			(thermal_bridge_width 0.5)
			(island_removal_mode 0)
		)
		(polygon
			(pts
				(arc
					(start 9.440418 -174.984664)
					(mid 8.772398 -174.984664)
					(end 9.440418 -174.984664)
				)
			)
		)
	)
	(zone
		(layers "F.Cu" "B.Cu" "In2.Cu" "In4.Cu")
		(hatch none 0.5)
		(connect_pads
			(clearance 0)
		)
		(min_thickness 0.25)
		(keepout
			(tracks not_allowed)
			(vias allowed)
			(pads allowed)
			(copperpour not_allowed)
			(footprints allowed)
		)
		(placement
			(enabled no)
			(sheetname "")
		)
		(fill yes
			(thermal_gap 0.5)
			(thermal_bridge_width 0.5)
			(island_removal_mode 0)
		)
		(polygon
			(pts
				(arc
					(start 9.440418 -172.21454)
					(mid 8.772398 -172.21454)
					(end 9.440418 -172.21454)
				)
			)
		)
	)
	(zone
		(layers "F.Cu" "B.Cu" "In2.Cu" "In4.Cu")
		(hatch none 0.5)
		(connect_pads
			(clearance 0)
		)
		(min_thickness 0.25)
		(keepout
			(tracks not_allowed)
			(vias allowed)
			(pads allowed)
			(copperpour not_allowed)
			(footprints allowed)
		)
		(placement
			(enabled no)
			(sheetname "")
		)
		(fill yes
			(thermal_gap 0.5)
			(thermal_bridge_width 0.5)
			(island_removal_mode 0)
		)
		(polygon
			(pts
				(arc
					(start 9.440418 -169.42943)
					(mid 8.772398 -169.42943)
					(end 9.440418 -169.42943)
				)
			)
		)
	)
	(zone
		(layers "F.Cu" "B.Cu" "In2.Cu" "In4.Cu")
		(hatch none 0.5)
		(connect_pads
			(clearance 0)
		)
		(min_thickness 0.25)
		(keepout
			(tracks not_allowed)
			(vias allowed)
			(pads allowed)
			(copperpour not_allowed)
			(footprints allowed)
		)
		(placement
			(enabled no)
			(sheetname "")
		)
		(fill yes
			(thermal_gap 0.5)
			(thermal_bridge_width 0.5)
			(island_removal_mode 0)
		)
		(polygon
			(pts
				(arc
					(start 9.440418 -170.29303)
					(mid 8.772398 -170.29303)
					(end 9.440418 -170.29303)
				)
			)
		)
	)
	(zone
		(layers "F.Cu" "B.Cu" "In2.Cu" "In4.Cu")
		(hatch none 0.5)
		(connect_pads
			(clearance 0)
		)
		(min_thickness 0.25)
		(keepout
			(tracks not_allowed)
			(vias allowed)
			(pads allowed)
			(copperpour not_allowed)
			(footprints allowed)
		)
		(placement
			(enabled no)
			(sheetname "")
		)
		(fill yes
			(thermal_gap 0.5)
			(thermal_bridge_width 0.5)
			(island_removal_mode 0)
		)
		(polygon
			(pts
				(arc
					(start 9.440418 -178.618388)
					(mid 8.772398 -178.618388)
					(end 9.440418 -178.618388)
				)
			)
		)
	)
	(zone
		(layers "F.Cu" "B.Cu" "In2.Cu" "In4.Cu")
		(hatch none 0.5)
		(connect_pads
			(clearance 0)
		)
		(min_thickness 0.25)
		(keepout
			(tracks not_allowed)
			(vias allowed)
			(pads allowed)
			(copperpour not_allowed)
			(footprints allowed)
		)
		(placement
			(enabled no)
			(sheetname "")
		)
		(fill yes
			(thermal_gap 0.5)
			(thermal_bridge_width 0.5)
			(island_removal_mode 0)
		)
		(polygon
			(pts
				(arc
					(start 9.440418 -175.848264)
					(mid 8.772398 -175.848264)
					(end 9.440418 -175.848264)
				)
			)
		)
	)
	(zone
		(layers "F.Cu" "B.Cu" "In2.Cu" "In4.Cu" "In6.Cu" "In8.Cu" "In9.Cu" "In11.Cu"
			"In13.Cu" "In15.Cu"
		)
		(hatch none 0.5)
		(connect_pads
			(clearance 0)
		)
		(min_thickness 0.25)
		(keepout
			(tracks not_allowed)
			(vias allowed)
			(pads allowed)
			(copperpour not_allowed)
			(footprints allowed)
		)
		(placement
			(enabled no)
			(sheetname "")
		)
		(fill yes
			(thermal_gap 0.5)
			(thermal_bridge_width 0.5)
			(island_removal_mode 0)
		)
		(polygon
			(pts
				(arc
					(start 297.567604 -417.213288)
					(mid 301.606204 -413.174688)
					(end 297.567604 -409.136088)
				)
				(arc
					(start 297.567604 -408.907488)
					(mid 301.834804 -413.174688)
					(end 297.567604 -417.441888)
				)
			)
		)
	)
	(zone
		(layers "F.Cu" "B.Cu" "In2.Cu" "In4.Cu" "In6.Cu" "In8.Cu" "In9.Cu" "In11.Cu"
			"In13.Cu" "In15.Cu"
		)
		(hatch none 0.5)
		(connect_pads
			(clearance 0)
		)
		(min_thickness 0.25)
		(keepout
			(tracks not_allowed)
			(vias allowed)
			(pads allowed)
			(copperpour not_allowed)
			(footprints allowed)
		)
		(placement
			(enabled no)
			(sheetname "")
		)
		(fill yes
			(thermal_gap 0.5)
			(thermal_bridge_width 0.5)
			(island_removal_mode 0)
		)
		(polygon
			(pts
				(arc
					(start 426.99559 -417.213288)
					(mid 431.03419 -413.174688)
					(end 426.99559 -409.136088)
				)
				(arc
					(start 426.99559 -408.907488)
					(mid 431.26279 -413.174688)
					(end 426.99559 -417.441888)
				)
			)
		)
	)
	(zone
		(layers "F.Cu" "B.Cu" "In2.Cu" "In4.Cu" "In6.Cu" "In8.Cu" "In9.Cu" "In11.Cu"
			"In13.Cu" "In15.Cu"
		)
		(hatch none 0.5)
		(connect_pads
			(clearance 0)
		)
		(min_thickness 0.25)
		(keepout
			(tracks not_allowed)
			(vias allowed)
			(pads allowed)
			(copperpour not_allowed)
			(footprints allowed)
		)
		(placement
			(enabled no)
			(sheetname "")
		)
		(fill yes
			(thermal_gap 0.5)
			(thermal_bridge_width 0.5)
			(island_removal_mode 0)
		)
		(polygon
			(pts
				(arc
					(start 177.495454 -380.53518)
					(mid 181.534054 -376.49658)
					(end 177.495454 -372.45798)
				)
				(arc
					(start 177.495454 -372.22938)
					(mid 181.762654 -376.49658)
					(end 177.495454 -380.76378)
				)
			)
		)
	)
	(zone
		(layers "F.Cu" "B.Cu" "In2.Cu" "In4.Cu" "In6.Cu" "In8.Cu" "In9.Cu" "In11.Cu"
			"In13.Cu" "In15.Cu"
		)
		(hatch none 0.5)
		(connect_pads
			(clearance 0)
		)
		(min_thickness 0.25)
		(keepout
			(tracks not_allowed)
			(vias allowed)
			(pads allowed)
			(copperpour not_allowed)
			(footprints allowed)
		)
		(placement
			(enabled no)
			(sheetname "")
		)
		(fill yes
			(thermal_gap 0.5)
			(thermal_bridge_width 0.5)
			(island_removal_mode 0)
		)
		(polygon
			(pts
				(arc
					(start 35.067748 -372.45798)
					(mid 31.029148 -376.49658)
					(end 35.067748 -380.53518)
				)
				(arc
					(start 35.067748 -380.76378)
					(mid 30.800548 -376.49658)
					(end 35.067748 -372.22938)
				)
			)
		)
	)
	(zone
		(layers "F.Cu" "B.Cu" "In2.Cu" "In4.Cu" "In6.Cu" "In8.Cu" "In9.Cu" "In11.Cu"
			"In13.Cu" "In15.Cu"
		)
		(hatch none 0.5)
		(connect_pads
			(clearance 0)
		)
		(min_thickness 0.25)
		(keepout
			(tracks not_allowed)
			(vias allowed)
			(pads allowed)
			(copperpour not_allowed)
			(footprints allowed)
		)
		(placement
			(enabled no)
			(sheetname "")
		)
		(fill yes
			(thermal_gap 0.5)
			(thermal_bridge_width 0.5)
			(island_removal_mode 0)
		)
		(polygon
			(pts
				(arc
					(start 291.06749 -380.83998)
					(mid 287.02889 -384.87858)
					(end 291.06749 -388.91718)
				)
				(arc
					(start 291.06749 -389.14578)
					(mid 286.80029 -384.87858)
					(end 291.06749 -380.61138)
				)
			)
		)
	)
	(zone
		(layers "F.Cu" "B.Cu" "In2.Cu" "In4.Cu" "In6.Cu" "In8.Cu" "In9.Cu" "In11.Cu"
			"In13.Cu" "In15.Cu"
		)
		(hatch none 0.5)
		(connect_pads
			(clearance 0)
		)
		(min_thickness 0.25)
		(keepout
			(tracks not_allowed)
			(vias allowed)
			(pads allowed)
			(copperpour not_allowed)
			(footprints allowed)
		)
		(placement
			(enabled no)
			(sheetname "")
		)
		(fill yes
			(thermal_gap 0.5)
			(thermal_bridge_width 0.5)
			(island_removal_mode 0)
		)
		(polygon
			(pts
				(arc
					(start 297.567604 -409.136088)
					(mid 293.529004 -413.174688)
					(end 297.567604 -417.213288)
				)
				(arc
					(start 297.567604 -417.441888)
					(mid 293.300404 -413.174688)
					(end 297.567604 -408.907488)
				)
			)
		)
	)
	(zone
		(layers "F.Cu" "B.Cu" "In2.Cu" "In4.Cu" "In6.Cu" "In8.Cu" "In9.Cu" "In11.Cu"
			"In13.Cu" "In15.Cu"
		)
		(hatch none 0.5)
		(connect_pads
			(clearance 0)
		)
		(min_thickness 0.25)
		(keepout
			(tracks not_allowed)
			(vias allowed)
			(pads allowed)
			(copperpour not_allowed)
			(footprints allowed)
		)
		(placement
			(enabled no)
			(sheetname "")
		)
		(fill yes
			(thermal_gap 0.5)
			(thermal_bridge_width 0.5)
			(island_removal_mode 0)
		)
		(polygon
			(pts
				(arc
					(start 291.06749 -388.91718)
					(mid 295.10609 -384.87858)
					(end 291.06749 -380.83998)
				)
				(arc
					(start 291.06749 -380.61138)
					(mid 295.33469 -384.87858)
					(end 291.06749 -389.14578)
				)
			)
		)
	)
	(zone
		(layers "F.Cu" "B.Cu" "In2.Cu" "In4.Cu" "In6.Cu" "In8.Cu" "In9.Cu" "In11.Cu"
			"In13.Cu" "In15.Cu"
		)
		(hatch none 0.5)
		(connect_pads
			(clearance 0)
		)
		(min_thickness 0.25)
		(keepout
			(tracks not_allowed)
			(vias allowed)
			(pads allowed)
			(copperpour not_allowed)
			(footprints allowed)
		)
		(placement
			(enabled no)
			(sheetname "")
		)
		(fill yes
			(thermal_gap 0.5)
			(thermal_bridge_width 0.5)
			(island_removal_mode 0)
		)
		(polygon
			(pts
				(arc
					(start 170.995594 -400.754088)
					(mid 166.956994 -404.792688)
					(end 170.995594 -408.831288)
				)
				(arc
					(start 170.995594 -409.059888)
					(mid 166.728394 -404.792688)
					(end 170.995594 -400.525488)
				)
			)
		)
	)
	(zone
		(layers "F.Cu" "B.Cu" "In2.Cu" "In4.Cu" "In6.Cu" "In8.Cu" "In9.Cu" "In11.Cu"
			"In13.Cu" "In15.Cu"
		)
		(hatch none 0.5)
		(connect_pads
			(clearance 0)
		)
		(min_thickness 0.25)
		(keepout
			(tracks not_allowed)
			(vias allowed)
			(pads allowed)
			(copperpour not_allowed)
			(footprints allowed)
		)
		(placement
			(enabled no)
			(sheetname "")
		)
		(fill yes
			(thermal_gap 0.5)
			(thermal_bridge_width 0.5)
			(island_removal_mode 0)
		)
		(polygon
			(pts
				(arc
					(start 433.49545 -388.91718)
					(mid 437.53405 -384.87858)
					(end 433.49545 -380.83998)
				)
				(arc
					(start 433.49545 -380.61138)
					(mid 437.76265 -384.87858)
					(end 433.49545 -389.14578)
				)
			)
		)
	)
	(zone
		(layers "F.Cu" "B.Cu" "In2.Cu" "In4.Cu" "In6.Cu" "In8.Cu" "In9.Cu" "In11.Cu"
			"In13.Cu" "In15.Cu"
		)
		(hatch none 0.5)
		(connect_pads
			(clearance 0)
		)
		(min_thickness 0.25)
		(keepout
			(tracks not_allowed)
			(vias allowed)
			(pads allowed)
			(copperpour not_allowed)
			(footprints allowed)
		)
		(placement
			(enabled no)
			(sheetname "")
		)
		(fill yes
			(thermal_gap 0.5)
			(thermal_bridge_width 0.5)
			(island_removal_mode 0)
		)
		(polygon
			(pts
				(arc
					(start 35.067748 -380.53518)
					(mid 39.106348 -376.49658)
					(end 35.067748 -372.45798)
				)
				(arc
					(start 35.067748 -372.22938)
					(mid 39.334948 -376.49658)
					(end 35.067748 -380.76378)
				)
			)
		)
	)
	(zone
		(layers "F.Cu" "B.Cu" "In2.Cu" "In4.Cu" "In6.Cu" "In8.Cu" "In9.Cu" "In11.Cu"
			"In13.Cu" "In15.Cu"
		)
		(hatch none 0.5)
		(connect_pads
			(clearance 0)
		)
		(min_thickness 0.25)
		(keepout
			(tracks not_allowed)
			(vias allowed)
			(pads allowed)
			(copperpour not_allowed)
			(footprints allowed)
		)
		(placement
			(enabled no)
			(sheetname "")
		)
		(fill yes
			(thermal_gap 0.5)
			(thermal_bridge_width 0.5)
			(island_removal_mode 0)
		)
		(polygon
			(pts
				(arc
					(start 41.567862 -400.754088)
					(mid 37.529262 -404.792688)
					(end 41.567862 -408.831288)
				)
				(arc
					(start 41.567862 -409.059888)
					(mid 37.300662 -404.792688)
					(end 41.567862 -400.525488)
				)
			)
		)
	)
	(zone
		(layers "F.Cu" "B.Cu" "In2.Cu" "In4.Cu" "In6.Cu" "In8.Cu" "In9.Cu" "In11.Cu"
			"In13.Cu" "In15.Cu"
		)
		(hatch none 0.5)
		(connect_pads
			(clearance 0)
		)
		(min_thickness 0.25)
		(keepout
			(tracks not_allowed)
			(vias allowed)
			(pads allowed)
			(copperpour not_allowed)
			(footprints allowed)
		)
		(placement
			(enabled no)
			(sheetname "")
		)
		(fill yes
			(thermal_gap 0.5)
			(thermal_bridge_width 0.5)
			(island_removal_mode 0)
		)
		(polygon
			(pts
				(arc
					(start 426.99559 -409.136088)
					(mid 422.95699 -413.174688)
					(end 426.99559 -417.213288)
				)
				(arc
					(start 426.99559 -417.441888)
					(mid 422.72839 -413.174688)
					(end 426.99559 -408.907488)
				)
			)
		)
	)
	(zone
		(layers "F.Cu" "B.Cu" "In2.Cu" "In4.Cu" "In6.Cu" "In8.Cu" "In9.Cu" "In11.Cu"
			"In13.Cu" "In15.Cu"
		)
		(hatch none 0.5)
		(connect_pads
			(clearance 0)
		)
		(min_thickness 0.25)
		(keepout
			(tracks not_allowed)
			(vias allowed)
			(pads allowed)
			(copperpour not_allowed)
			(footprints allowed)
		)
		(placement
			(enabled no)
			(sheetname "")
		)
		(fill yes
			(thermal_gap 0.5)
			(thermal_bridge_width 0.5)
			(island_removal_mode 0)
		)
		(polygon
			(pts
				(arc
					(start 41.567862 -408.831288)
					(mid 45.606462 -404.792688)
					(end 41.567862 -400.754088)
				)
				(arc
					(start 41.567862 -400.525488)
					(mid 45.835062 -404.792688)
					(end 41.567862 -409.059888)
				)
			)
		)
	)
	(zone
		(layers "F.Cu" "B.Cu" "In2.Cu" "In4.Cu" "In6.Cu" "In8.Cu" "In9.Cu" "In11.Cu"
			"In13.Cu" "In15.Cu"
		)
		(hatch none 0.5)
		(connect_pads
			(clearance 0)
		)
		(min_thickness 0.25)
		(keepout
			(tracks not_allowed)
			(vias allowed)
			(pads allowed)
			(copperpour not_allowed)
			(footprints allowed)
		)
		(placement
			(enabled no)
			(sheetname "")
		)
		(fill yes
			(thermal_gap 0.5)
			(thermal_bridge_width 0.5)
			(island_removal_mode 0)
		)
		(polygon
			(pts
				(arc
					(start 177.495454 -372.45798)
					(mid 173.456854 -376.49658)
					(end 177.495454 -380.53518)
				)
				(arc
					(start 177.495454 -380.76378)
					(mid 173.228254 -376.49658)
					(end 177.495454 -372.22938)
				)
			)
		)
	)
	(zone
		(layers "F.Cu" "B.Cu" "In2.Cu" "In4.Cu" "In6.Cu" "In8.Cu" "In9.Cu" "In11.Cu"
			"In13.Cu" "In15.Cu"
		)
		(hatch none 0.5)
		(connect_pads
			(clearance 0)
		)
		(min_thickness 0.25)
		(keepout
			(tracks not_allowed)
			(vias allowed)
			(pads allowed)
			(copperpour not_allowed)
			(footprints allowed)
		)
		(placement
			(enabled no)
			(sheetname "")
		)
		(fill yes
			(thermal_gap 0.5)
			(thermal_bridge_width 0.5)
			(island_removal_mode 0)
		)
		(polygon
			(pts
				(arc
					(start 433.49545 -380.83998)
					(mid 429.45685 -384.87858)
					(end 433.49545 -388.91718)
				)
				(arc
					(start 433.49545 -389.14578)
					(mid 429.22825 -384.87858)
					(end 433.49545 -380.61138)
				)
			)
		)
	)
	(zone
		(layers "F.Cu" "B.Cu" "In2.Cu" "In4.Cu" "In6.Cu" "In8.Cu" "In9.Cu" "In11.Cu"
			"In13.Cu" "In15.Cu"
		)
		(hatch none 0.5)
		(connect_pads
			(clearance 0)
		)
		(min_thickness 0.25)
		(keepout
			(tracks not_allowed)
			(vias allowed)
			(pads allowed)
			(copperpour not_allowed)
			(footprints allowed)
		)
		(placement
			(enabled no)
			(sheetname "")
		)
		(fill yes
			(thermal_gap 0.5)
			(thermal_bridge_width 0.5)
			(island_removal_mode 0)
		)
		(polygon
			(pts
				(arc
					(start 213.67496 -365.031274)
					(mid 209.40776 -360.764074)
					(end 213.67496 -356.496874)
				)
				(arc
					(start 213.67496 -356.725474)
					(mid 209.63636 -360.764074)
					(end 213.67496 -364.802674)
				)
			)
		)
	)
	(zone
		(layers "F.Cu" "B.Cu" "In2.Cu" "In4.Cu" "In6.Cu" "In8.Cu" "In9.Cu" "In11.Cu"
			"In13.Cu" "In15.Cu"
		)
		(hatch none 0.5)
		(connect_pads
			(clearance 0)
		)
		(min_thickness 0.25)
		(keepout
			(tracks not_allowed)
			(vias allowed)
			(pads allowed)
			(copperpour not_allowed)
			(footprints allowed)
		)
		(placement
			(enabled no)
			(sheetname "")
		)
		(fill yes
			(thermal_gap 0.5)
			(thermal_bridge_width 0.5)
			(island_removal_mode 0)
		)
		(polygon
			(pts
				(arc
					(start 213.67496 -365.031274)
					(mid 217.94216 -360.764074)
					(end 213.67496 -356.496874)
				)
				(arc
					(start 213.67496 -356.725474)
					(mid 217.71356 -360.764074)
					(end 213.67496 -364.802674)
				)
			)
		)
	)
	(zone
		(layers "F.Cu" "B.Cu" "In2.Cu" "In4.Cu" "In6.Cu" "In8.Cu" "In9.Cu" "In11.Cu"
			"In13.Cu" "In15.Cu"
		)
		(hatch none 0.5)
		(connect_pads
			(clearance 0)
		)
		(min_thickness 0.25)
		(keepout
			(tracks not_allowed)
			(vias allowed)
			(pads allowed)
			(copperpour not_allowed)
			(footprints allowed)
		)
		(placement
			(enabled no)
			(sheetname "")
		)
		(fill yes
			(thermal_gap 0.5)
			(thermal_bridge_width 0.5)
			(island_removal_mode 0)
		)
		(polygon
			(pts
				(arc
					(start 170.995594 -408.831288)
					(mid 175.034194 -404.792688)
					(end 170.995594 -400.754088)
				)
				(arc
					(start 170.995594 -400.525488)
					(mid 175.262794 -404.792688)
					(end 170.995594 -409.059888)
				)
			)
		)
	)
	(zone
		(layers "F.Cu" "B.Cu" "In2.Cu" "In4.Cu" "In6.Cu" "In11.Cu" "In13.Cu")
		(hatch none 0.5)
		(connect_pads
			(clearance 0)
		)
		(min_thickness 0.25)
		(keepout
			(tracks allowed)
			(vias allowed)
			(pads allowed)
			(copperpour allowed)
			(footprints allowed)
		)
		(placement
			(enabled no)
			(sheetname "")
		)
		(fill yes
			(thermal_gap 0.5)
			(thermal_bridge_width 0.5)
			(island_removal_mode 0)
		)
		(polygon
			(pts
				(xy 411.175708 -191.38519) (xy 411.175708 -319.66281) (xy 455.251058 -319.66281) (xy 455.251058 -191.38519)
			)
		)
	)
	(zone
		(layers "F.Cu" "B.Cu" "In2.Cu" "In4.Cu" "In6.Cu" "In11.Cu" "In13.Cu" "In15.Cu")
		(hatch none 0.5)
		(connect_pads
			(clearance 0)
		)
		(min_thickness 0.25)
		(keepout
			(tracks allowed)
			(vias allowed)
			(pads allowed)
			(copperpour allowed)
			(footprints allowed)
		)
		(placement
			(enabled no)
			(sheetname "")
		)
		(fill yes
			(thermal_gap 0.5)
			(thermal_bridge_width 0.5)
			(island_removal_mode 0)
		)
		(polygon
			(pts
				(xy -16.69415 -362.265722) (xy -16.69415 -359.053892) (xy -11.675618 -359.053892) (xy -11.675618 -362.265722)
			)
		)
	)
	(zone
		(layers "F.Cu" "B.Cu" "In2.Cu" "In4.Cu" "In11.Cu" "In13.Cu")
		(hatch none 0.5)
		(connect_pads
			(clearance 0)
		)
		(min_thickness 0.25)
		(keepout
			(tracks allowed)
			(vias allowed)
			(pads allowed)
			(copperpour allowed)
			(footprints allowed)
		)
		(placement
			(enabled no)
			(sheetname "")
		)
		(fill yes
			(thermal_gap 0.5)
			(thermal_bridge_width 0.5)
			(island_removal_mode 0)
		)
		(polygon
			(pts
				(xy 264.321798 -191.38519) (xy 264.321798 -319.66281) (xy 308.66588 -319.66281) (xy 308.66588 -191.38519)
			)
		)
	)
	(zone
		(layers "F.Cu" "B.Cu" "In11.Cu" "In13.Cu" "In15.Cu")
		(hatch none 0.5)
		(connect_pads
			(clearance 0)
		)
		(min_thickness 0.25)
		(keepout
			(tracks not_allowed)
			(vias allowed)
			(pads allowed)
			(copperpour not_allowed)
			(footprints allowed)
		)
		(placement
			(enabled no)
			(sheetname "")
		)
		(fill yes
			(thermal_gap 0.5)
			(thermal_bridge_width 0.5)
			(island_removal_mode 0)
		)
		(polygon
			(pts
				(arc
					(start 13.25753 -360.416602)
					(mid 12.58951 -360.416602)
					(end 13.25753 -360.416602)
				)
			)
		)
	)
	(zone
		(layers "F.Cu" "B.Cu" "In11.Cu" "In13.Cu" "In15.Cu")
		(hatch none 0.5)
		(connect_pads
			(clearance 0)
		)
		(min_thickness 0.25)
		(keepout
			(tracks not_allowed)
			(vias allowed)
			(pads allowed)
			(copperpour not_allowed)
			(footprints allowed)
		)
		(placement
			(enabled no)
			(sheetname "")
		)
		(fill yes
			(thermal_gap 0.5)
			(thermal_bridge_width 0.5)
			(island_removal_mode 0)
		)
		(polygon
			(pts
				(arc
					(start 13.25753 -359.553002)
					(mid 12.58951 -359.553002)
					(end 13.25753 -359.553002)
				)
			)
		)
	)
	(zone
		(layers "F.Cu" "B.Cu" "In11.Cu" "In13.Cu" "In15.Cu")
		(hatch none 0.5)
		(connect_pads
			(clearance 0)
		)
		(min_thickness 0.25)
		(keepout
			(tracks not_allowed)
			(vias allowed)
			(pads allowed)
			(copperpour not_allowed)
			(footprints allowed)
		)
		(placement
			(enabled no)
			(sheetname "")
		)
		(fill yes
			(thermal_gap 0.5)
			(thermal_bridge_width 0.5)
			(island_removal_mode 0)
		)
		(polygon
			(pts
				(arc
					(start 15.154656 -358.071674)
					(mid 14.486636 -358.071674)
					(end 15.154656 -358.071674)
				)
			)
		)
	)
	(zone
		(layers "F.Cu" "B.Cu" "In11.Cu" "In13.Cu" "In15.Cu")
		(hatch none 0.5)
		(connect_pads
			(clearance 0)
		)
		(min_thickness 0.25)
		(keepout
			(tracks not_allowed)
			(vias allowed)
			(pads allowed)
			(copperpour not_allowed)
			(footprints allowed)
		)
		(placement
			(enabled no)
			(sheetname "")
		)
		(fill yes
			(thermal_gap 0.5)
			(thermal_bridge_width 0.5)
			(island_removal_mode 0)
		)
		(polygon
			(pts
				(arc
					(start 15.154656 -357.208074)
					(mid 14.486636 -357.208074)
					(end 15.154656 -357.208074)
				)
			)
		)
	)
	(zone
		(layers "F.Cu" "In1.Cu" "In2.Cu" "In3.Cu" "In4.Cu" "In5.Cu" "In6.Cu" "In7.Cu"
			"In8.Cu" "In9.Cu" "In10.Cu" "In11.Cu" "In12.Cu" "In13.Cu" "In15.Cu"
		)
		(hatch none 0.5)
		(connect_pads
			(clearance 0)
		)
		(min_thickness 0.25)
		(keepout
			(tracks not_allowed)
			(vias allowed)
			(pads allowed)
			(copperpour not_allowed)
			(footprints allowed)
		)
		(placement
			(enabled no)
			(sheetname "")
		)
		(fill yes
			(thermal_gap 0.5)
			(thermal_bridge_width 0.5)
			(island_removal_mode 0)
		)
		(polygon
			(pts
				(arc
					(start 68.14185 -439.760614)
					(mid 68.164168 -439.814496)
					(end 68.21805 -439.836814)
				)
				(arc
					(start 69.15785 -439.836814)
					(mid 69.211732 -439.814496)
					(end 69.23405 -439.760614)
				)
				(arc
					(start 69.23405 -437.21909)
					(mid 69.211732 -437.165208)
					(end 69.15785 -437.14289)
				)
				(arc
					(start 68.21805 -437.14289)
					(mid 68.164168 -437.165208)
					(end 68.14185 -437.21909)
				)
			)
		)
	)
	(zone
		(layers "F.Cu" "In1.Cu" "In2.Cu" "In3.Cu" "In4.Cu" "In5.Cu" "In6.Cu" "In7.Cu"
			"In8.Cu" "In9.Cu" "In10.Cu" "In11.Cu" "In12.Cu" "In13.Cu" "In15.Cu"
		)
		(hatch none 0.5)
		(connect_pads
			(clearance 0)
		)
		(min_thickness 0.25)
		(keepout
			(tracks not_allowed)
			(vias allowed)
			(pads allowed)
			(copperpour not_allowed)
			(footprints allowed)
		)
		(placement
			(enabled no)
			(sheetname "")
		)
		(fill yes
			(thermal_gap 0.5)
			(thermal_bridge_width 0.5)
			(island_removal_mode 0)
		)
		(polygon
			(pts
				(arc
					(start 60.141866 -439.760614)
					(mid 60.164184 -439.814496)
					(end 60.218066 -439.836814)
				)
				(arc
					(start 61.157866 -439.836814)
					(mid 61.211748 -439.814496)
					(end 61.234066 -439.760614)
				)
				(arc
					(start 61.234066 -437.21909)
					(mid 61.211748 -437.165208)
					(end 61.157866 -437.14289)
				)
				(arc
					(start 60.218066 -437.14289)
					(mid 60.164184 -437.165208)
					(end 60.141866 -437.21909)
				)
			)
		)
	)
	(zone
		(layers "F.Cu" "In1.Cu" "In2.Cu" "In3.Cu" "In4.Cu" "In5.Cu" "In6.Cu" "In7.Cu"
			"In8.Cu" "In9.Cu" "In10.Cu" "In11.Cu" "In12.Cu" "In13.Cu" "In15.Cu"
		)
		(hatch none 0.5)
		(connect_pads
			(clearance 0)
		)
		(min_thickness 0.25)
		(keepout
			(tracks not_allowed)
			(vias allowed)
			(pads allowed)
			(copperpour not_allowed)
			(footprints allowed)
		)
		(placement
			(enabled no)
			(sheetname "")
		)
		(fill yes
			(thermal_gap 0.5)
			(thermal_bridge_width 0.5)
			(island_removal_mode 0)
		)
		(polygon
			(pts
				(arc
					(start 66.141854 -438.760616)
					(mid 66.164172 -438.814498)
					(end 66.218054 -438.836816)
				)
				(arc
					(start 67.157854 -438.836816)
					(mid 67.211736 -438.814498)
					(end 67.234054 -438.760616)
				)
				(arc
					(start 67.234054 -436.219092)
					(mid 67.211736 -436.16521)
					(end 67.157854 -436.142892)
				)
				(arc
					(start 66.218054 -436.142892)
					(mid 66.164172 -436.16521)
					(end 66.141854 -436.219092)
				)
			)
		)
	)
	(zone
		(layers "F.Cu" "In1.Cu" "In2.Cu" "In3.Cu" "In4.Cu" "In5.Cu" "In6.Cu" "In7.Cu"
			"In8.Cu" "In9.Cu" "In10.Cu" "In11.Cu" "In12.Cu" "In13.Cu" "In15.Cu"
		)
		(hatch none 0.5)
		(connect_pads
			(clearance 0)
		)
		(min_thickness 0.25)
		(keepout
			(tracks not_allowed)
			(vias allowed)
			(pads allowed)
			(copperpour not_allowed)
			(footprints allowed)
		)
		(placement
			(enabled no)
			(sheetname "")
		)
		(fill yes
			(thermal_gap 0.5)
			(thermal_bridge_width 0.5)
			(island_removal_mode 0)
		)
		(polygon
			(pts
				(arc
					(start 75.141836 -438.760616)
					(mid 75.164154 -438.814498)
					(end 75.218036 -438.836816)
				)
				(arc
					(start 76.157836 -438.836816)
					(mid 76.211718 -438.814498)
					(end 76.234036 -438.760616)
				)
				(arc
					(start 76.234036 -436.219092)
					(mid 76.211718 -436.16521)
					(end 76.157836 -436.142892)
				)
				(arc
					(start 75.218036 -436.142892)
					(mid 75.164154 -436.16521)
					(end 75.141836 -436.219092)
				)
			)
		)
	)
	(zone
		(layers "F.Cu" "In1.Cu" "In2.Cu" "In3.Cu" "In4.Cu" "In5.Cu" "In6.Cu" "In7.Cu"
			"In8.Cu" "In9.Cu" "In10.Cu" "In11.Cu" "In12.Cu" "In13.Cu" "In15.Cu"
		)
		(hatch none 0.5)
		(connect_pads
			(clearance 0)
		)
		(min_thickness 0.25)
		(keepout
			(tracks not_allowed)
			(vias allowed)
			(pads allowed)
			(copperpour not_allowed)
			(footprints allowed)
		)
		(placement
			(enabled no)
			(sheetname "")
		)
		(fill yes
			(thermal_gap 0.5)
			(thermal_bridge_width 0.5)
			(island_removal_mode 0)
		)
		(polygon
			(pts
				(arc
					(start 87.141812 -438.760616)
					(mid 87.16413 -438.814498)
					(end 87.218012 -438.836816)
				)
				(arc
					(start 88.157812 -438.836816)
					(mid 88.211694 -438.814498)
					(end 88.234012 -438.760616)
				)
				(arc
					(start 88.234012 -436.219092)
					(mid 88.211694 -436.16521)
					(end 88.157812 -436.142892)
				)
				(arc
					(start 87.218012 -436.142892)
					(mid 87.16413 -436.16521)
					(end 87.141812 -436.219092)
				)
			)
		)
	)
	(zone
		(layers "F.Cu" "In1.Cu" "In2.Cu" "In3.Cu" "In4.Cu" "In5.Cu" "In6.Cu" "In7.Cu"
			"In8.Cu" "In9.Cu" "In10.Cu" "In11.Cu" "In12.Cu" "In13.Cu" "In15.Cu"
		)
		(hatch none 0.5)
		(connect_pads
			(clearance 0)
		)
		(min_thickness 0.25)
		(keepout
			(tracks not_allowed)
			(vias allowed)
			(pads allowed)
			(copperpour not_allowed)
			(footprints allowed)
		)
		(placement
			(enabled no)
			(sheetname "")
		)
		(fill yes
			(thermal_gap 0.5)
			(thermal_bridge_width 0.5)
			(island_removal_mode 0)
		)
		(polygon
			(pts
				(arc
					(start 64.141858 -439.760614)
					(mid 64.164176 -439.814496)
					(end 64.218058 -439.836814)
				)
				(arc
					(start 65.157858 -439.836814)
					(mid 65.21174 -439.814496)
					(end 65.234058 -439.760614)
				)
				(arc
					(start 65.234058 -437.21909)
					(mid 65.21174 -437.165208)
					(end 65.157858 -437.14289)
				)
				(arc
					(start 64.218058 -437.14289)
					(mid 64.164176 -437.165208)
					(end 64.141858 -437.21909)
				)
			)
		)
	)
	(zone
		(layers "F.Cu" "In1.Cu" "In2.Cu" "In3.Cu" "In4.Cu" "In5.Cu" "In6.Cu" "In7.Cu"
			"In8.Cu" "In9.Cu" "In10.Cu" "In11.Cu" "In12.Cu" "In13.Cu" "In15.Cu"
		)
		(hatch none 0.5)
		(connect_pads
			(clearance 0)
		)
		(min_thickness 0.25)
		(keepout
			(tracks not_allowed)
			(vias allowed)
			(pads allowed)
			(copperpour not_allowed)
			(footprints allowed)
		)
		(placement
			(enabled no)
			(sheetname "")
		)
		(fill yes
			(thermal_gap 0.5)
			(thermal_bridge_width 0.5)
			(island_removal_mode 0)
		)
		(polygon
			(pts
				(arc
					(start 81.141824 -439.760614)
					(mid 81.164142 -439.814496)
					(end 81.218024 -439.836814)
				)
				(arc
					(start 82.157824 -439.836814)
					(mid 82.211706 -439.814496)
					(end 82.234024 -439.760614)
				)
				(arc
					(start 82.234024 -437.21909)
					(mid 82.211706 -437.165208)
					(end 82.157824 -437.14289)
				)
				(arc
					(start 81.218024 -437.14289)
					(mid 81.164142 -437.165208)
					(end 81.141824 -437.21909)
				)
			)
		)
	)
	(zone
		(layers "F.Cu" "In1.Cu" "In2.Cu" "In3.Cu" "In4.Cu" "In5.Cu" "In6.Cu" "In7.Cu"
			"In8.Cu" "In9.Cu" "In10.Cu" "In11.Cu" "In12.Cu" "In13.Cu" "In15.Cu"
		)
		(hatch none 0.5)
		(connect_pads
			(clearance 0)
		)
		(min_thickness 0.25)
		(keepout
			(tracks not_allowed)
			(vias allowed)
			(pads allowed)
			(copperpour not_allowed)
			(footprints allowed)
		)
		(placement
			(enabled no)
			(sheetname "")
		)
		(fill yes
			(thermal_gap 0.5)
			(thermal_bridge_width 0.5)
			(island_removal_mode 0)
		)
		(polygon
			(pts
				(arc
					(start 85.141816 -439.760614)
					(mid 85.164134 -439.814496)
					(end 85.218016 -439.836814)
				)
				(arc
					(start 86.157816 -439.836814)
					(mid 86.211698 -439.814496)
					(end 86.234016 -439.760614)
				)
				(arc
					(start 86.234016 -437.21909)
					(mid 86.211698 -437.165208)
					(end 86.157816 -437.14289)
				)
				(arc
					(start 85.218016 -437.14289)
					(mid 85.164134 -437.165208)
					(end 85.141816 -437.21909)
				)
			)
		)
	)
	(zone
		(layers "F.Cu" "In1.Cu" "In2.Cu" "In3.Cu" "In4.Cu" "In5.Cu" "In6.Cu" "In7.Cu"
			"In8.Cu" "In9.Cu" "In10.Cu" "In11.Cu" "In12.Cu" "In13.Cu" "In15.Cu"
		)
		(hatch none 0.5)
		(connect_pads
			(clearance 0)
		)
		(min_thickness 0.25)
		(keepout
			(tracks not_allowed)
			(vias allowed)
			(pads allowed)
			(copperpour not_allowed)
			(footprints allowed)
		)
		(placement
			(enabled no)
			(sheetname "")
		)
		(fill yes
			(thermal_gap 0.5)
			(thermal_bridge_width 0.5)
			(island_removal_mode 0)
		)
		(polygon
			(pts
				(arc
					(start 62.141862 -438.760616)
					(mid 62.16418 -438.814498)
					(end 62.218062 -438.836816)
				)
				(arc
					(start 63.157862 -438.836816)
					(mid 63.211744 -438.814498)
					(end 63.234062 -438.760616)
				)
				(arc
					(start 63.234062 -436.219092)
					(mid 63.211744 -436.16521)
					(end 63.157862 -436.142892)
				)
				(arc
					(start 62.218062 -436.142892)
					(mid 62.16418 -436.16521)
					(end 62.141862 -436.219092)
				)
			)
		)
	)
	(zone
		(layers "F.Cu" "In1.Cu" "In2.Cu" "In3.Cu" "In4.Cu" "In5.Cu" "In6.Cu" "In7.Cu"
			"In8.Cu" "In9.Cu" "In10.Cu" "In11.Cu" "In12.Cu" "In13.Cu" "In15.Cu"
		)
		(hatch none 0.5)
		(connect_pads
			(clearance 0)
		)
		(min_thickness 0.25)
		(keepout
			(tracks not_allowed)
			(vias allowed)
			(pads allowed)
			(copperpour not_allowed)
			(footprints allowed)
		)
		(placement
			(enabled no)
			(sheetname "")
		)
		(fill yes
			(thermal_gap 0.5)
			(thermal_bridge_width 0.5)
			(island_removal_mode 0)
		)
		(polygon
			(pts
				(arc
					(start 58.14187 -438.760616)
					(mid 58.164188 -438.814498)
					(end 58.21807 -438.836816)
				)
				(arc
					(start 59.15787 -438.836816)
					(mid 59.211752 -438.814498)
					(end 59.23407 -438.760616)
				)
				(arc
					(start 59.23407 -436.219092)
					(mid 59.211752 -436.16521)
					(end 59.15787 -436.142892)
				)
				(arc
					(start 58.21807 -436.142892)
					(mid 58.164188 -436.16521)
					(end 58.14187 -436.219092)
				)
			)
		)
	)
	(zone
		(layers "F.Cu" "In1.Cu" "In2.Cu" "In3.Cu" "In4.Cu" "In5.Cu" "In6.Cu" "In7.Cu"
			"In8.Cu" "In9.Cu" "In10.Cu" "In11.Cu" "In12.Cu" "In13.Cu" "In15.Cu"
		)
		(hatch none 0.5)
		(connect_pads
			(clearance 0)
		)
		(min_thickness 0.25)
		(keepout
			(tracks not_allowed)
			(vias allowed)
			(pads allowed)
			(copperpour not_allowed)
			(footprints allowed)
		)
		(placement
			(enabled no)
			(sheetname "")
		)
		(fill yes
			(thermal_gap 0.5)
			(thermal_bridge_width 0.5)
			(island_removal_mode 0)
		)
		(polygon
			(pts
				(arc
					(start 77.141832 -439.760614)
					(mid 77.16415 -439.814496)
					(end 77.218032 -439.836814)
				)
				(arc
					(start 78.157832 -439.836814)
					(mid 78.211714 -439.814496)
					(end 78.234032 -439.760614)
				)
				(arc
					(start 78.234032 -437.21909)
					(mid 78.211714 -437.165208)
					(end 78.157832 -437.14289)
				)
				(arc
					(start 77.218032 -437.14289)
					(mid 77.16415 -437.165208)
					(end 77.141832 -437.21909)
				)
			)
		)
	)
	(zone
		(layers "F.Cu" "In1.Cu" "In2.Cu" "In3.Cu" "In4.Cu" "In5.Cu" "In6.Cu" "In7.Cu"
			"In8.Cu" "In9.Cu" "In10.Cu" "In11.Cu" "In12.Cu" "In13.Cu" "In15.Cu"
		)
		(hatch none 0.5)
		(connect_pads
			(clearance 0)
		)
		(min_thickness 0.25)
		(keepout
			(tracks not_allowed)
			(vias allowed)
			(pads allowed)
			(copperpour not_allowed)
			(footprints allowed)
		)
		(placement
			(enabled no)
			(sheetname "")
		)
		(fill yes
			(thermal_gap 0.5)
			(thermal_bridge_width 0.5)
			(island_removal_mode 0)
		)
		(polygon
			(pts
				(arc
					(start 70.141846 -438.760616)
					(mid 70.164164 -438.814498)
					(end 70.218046 -438.836816)
				)
				(arc
					(start 71.157846 -438.836816)
					(mid 71.211728 -438.814498)
					(end 71.234046 -438.760616)
				)
				(arc
					(start 71.234046 -436.219092)
					(mid 71.211728 -436.16521)
					(end 71.157846 -436.142892)
				)
				(arc
					(start 70.218046 -436.142892)
					(mid 70.164164 -436.16521)
					(end 70.141846 -436.219092)
				)
			)
		)
	)
	(zone
		(layers "F.Cu" "In1.Cu" "In2.Cu" "In3.Cu" "In4.Cu" "In5.Cu" "In6.Cu" "In7.Cu"
			"In8.Cu" "In9.Cu" "In10.Cu" "In11.Cu" "In12.Cu" "In13.Cu" "In15.Cu"
		)
		(hatch none 0.5)
		(connect_pads
			(clearance 0)
		)
		(min_thickness 0.25)
		(keepout
			(tracks not_allowed)
			(vias allowed)
			(pads allowed)
			(copperpour not_allowed)
			(footprints allowed)
		)
		(placement
			(enabled no)
			(sheetname "")
		)
		(fill yes
			(thermal_gap 0.5)
			(thermal_bridge_width 0.5)
			(island_removal_mode 0)
		)
		(polygon
			(pts
				(arc
					(start 79.141828 -438.760616)
					(mid 79.164146 -438.814498)
					(end 79.218028 -438.836816)
				)
				(arc
					(start 80.157828 -438.836816)
					(mid 80.21171 -438.814498)
					(end 80.234028 -438.760616)
				)
				(arc
					(start 80.234028 -436.219092)
					(mid 80.21171 -436.16521)
					(end 80.157828 -436.142892)
				)
				(arc
					(start 79.218028 -436.142892)
					(mid 79.164146 -436.16521)
					(end 79.141828 -436.219092)
				)
			)
		)
	)
	(zone
		(layers "F.Cu" "In1.Cu" "In2.Cu" "In3.Cu" "In4.Cu" "In5.Cu" "In6.Cu" "In7.Cu"
			"In8.Cu" "In9.Cu" "In10.Cu" "In11.Cu" "In12.Cu" "In13.Cu" "In15.Cu"
		)
		(hatch none 0.5)
		(connect_pads
			(clearance 0)
		)
		(min_thickness 0.25)
		(keepout
			(tracks not_allowed)
			(vias allowed)
			(pads allowed)
			(copperpour not_allowed)
			(footprints allowed)
		)
		(placement
			(enabled no)
			(sheetname "")
		)
		(fill yes
			(thermal_gap 0.5)
			(thermal_bridge_width 0.5)
			(island_removal_mode 0)
		)
		(polygon
			(pts
				(arc
					(start 89.141808 -439.760614)
					(mid 89.164126 -439.814496)
					(end 89.218008 -439.836814)
				)
				(arc
					(start 90.157808 -439.836814)
					(mid 90.21169 -439.814496)
					(end 90.234008 -439.760614)
				)
				(arc
					(start 90.234008 -437.21909)
					(mid 90.21169 -437.165208)
					(end 90.157808 -437.14289)
				)
				(arc
					(start 89.218008 -437.14289)
					(mid 89.164126 -437.165208)
					(end 89.141808 -437.21909)
				)
			)
		)
	)
	(zone
		(layers "F.Cu" "In1.Cu" "In2.Cu" "In3.Cu" "In4.Cu" "In5.Cu" "In6.Cu" "In7.Cu"
			"In8.Cu" "In9.Cu" "In10.Cu" "In11.Cu" "In12.Cu" "In13.Cu" "In15.Cu"
		)
		(hatch none 0.5)
		(connect_pads
			(clearance 0)
		)
		(min_thickness 0.25)
		(keepout
			(tracks not_allowed)
			(vias allowed)
			(pads allowed)
			(copperpour not_allowed)
			(footprints allowed)
		)
		(placement
			(enabled no)
			(sheetname "")
		)
		(fill yes
			(thermal_gap 0.5)
			(thermal_bridge_width 0.5)
			(island_removal_mode 0)
		)
		(polygon
			(pts
				(arc
					(start 83.14182 -438.760616)
					(mid 83.164138 -438.814498)
					(end 83.21802 -438.836816)
				)
				(arc
					(start 84.15782 -438.836816)
					(mid 84.211702 -438.814498)
					(end 84.23402 -438.760616)
				)
				(arc
					(start 84.23402 -436.219092)
					(mid 84.211702 -436.16521)
					(end 84.15782 -436.142892)
				)
				(arc
					(start 83.21802 -436.142892)
					(mid 83.164138 -436.16521)
					(end 83.14182 -436.219092)
				)
			)
		)
	)
	(zone
		(layers "F.Cu" "In1.Cu" "In2.Cu" "In3.Cu" "In4.Cu" "In5.Cu" "In6.Cu" "In7.Cu"
			"In8.Cu" "In9.Cu" "In10.Cu" "In11.Cu" "In12.Cu" "In13.Cu" "In15.Cu"
		)
		(hatch none 0.5)
		(connect_pads
			(clearance 0)
		)
		(min_thickness 0.25)
		(keepout
			(tracks not_allowed)
			(vias allowed)
			(pads allowed)
			(copperpour not_allowed)
			(footprints allowed)
		)
		(placement
			(enabled no)
			(sheetname "")
		)
		(fill yes
			(thermal_gap 0.5)
			(thermal_bridge_width 0.5)
			(island_removal_mode 0)
		)
		(polygon
			(pts
				(arc
					(start 72.141842 -439.760614)
					(mid 72.16416 -439.814496)
					(end 72.218042 -439.836814)
				)
				(arc
					(start 73.157842 -439.836814)
					(mid 73.211724 -439.814496)
					(end 73.234042 -439.760614)
				)
				(arc
					(start 73.234042 -437.21909)
					(mid 73.211724 -437.165208)
					(end 73.157842 -437.14289)
				)
				(arc
					(start 72.218042 -437.14289)
					(mid 72.16416 -437.165208)
					(end 72.141842 -437.21909)
				)
			)
		)
	)
	(zone
		(layers "F.Cu" "In1.Cu" "In2.Cu" "In3.Cu" "In4.Cu" "In5.Cu" "In6.Cu" "In7.Cu"
			"In8.Cu" "In9.Cu" "In10.Cu" "In11.Cu" "In13.Cu" "In15.Cu"
		)
		(hatch none 0.5)
		(connect_pads
			(clearance 0)
		)
		(min_thickness 0.25)
		(keepout
			(tracks not_allowed)
			(vias allowed)
			(pads allowed)
			(copperpour not_allowed)
			(footprints allowed)
		)
		(placement
			(enabled no)
			(sheetname "")
		)
		(fill yes
			(thermal_gap 0.5)
			(thermal_bridge_width 0.5)
			(island_removal_mode 0)
		)
		(polygon
			(pts
				(arc
					(start 337.14182 -439.760614)
					(mid 337.164138 -439.814496)
					(end 337.21802 -439.836814)
				)
				(arc
					(start 338.15782 -439.836814)
					(mid 338.211702 -439.814496)
					(end 338.23402 -439.760614)
				)
				(arc
					(start 338.23402 -437.21909)
					(mid 338.211702 -437.165208)
					(end 338.15782 -437.14289)
				)
				(arc
					(start 337.21802 -437.14289)
					(mid 337.164138 -437.165208)
					(end 337.14182 -437.21909)
				)
			)
		)
	)
	(zone
		(layers "F.Cu" "In1.Cu" "In2.Cu" "In3.Cu" "In4.Cu" "In5.Cu" "In6.Cu" "In7.Cu"
			"In8.Cu" "In9.Cu" "In10.Cu" "In11.Cu" "In13.Cu" "In15.Cu"
		)
		(hatch none 0.5)
		(connect_pads
			(clearance 0)
		)
		(min_thickness 0.25)
		(keepout
			(tracks not_allowed)
			(vias allowed)
			(pads allowed)
			(copperpour not_allowed)
			(footprints allowed)
		)
		(placement
			(enabled no)
			(sheetname "")
		)
		(fill yes
			(thermal_gap 0.5)
			(thermal_bridge_width 0.5)
			(island_removal_mode 0)
		)
		(polygon
			(pts
				(arc
					(start 318.141858 -438.760616)
					(mid 318.164176 -438.814498)
					(end 318.218058 -438.836816)
				)
				(arc
					(start 319.157858 -438.836816)
					(mid 319.21174 -438.814498)
					(end 319.234058 -438.760616)
				)
				(arc
					(start 319.234058 -436.219092)
					(mid 319.21174 -436.16521)
					(end 319.157858 -436.142892)
				)
				(arc
					(start 318.218058 -436.142892)
					(mid 318.164176 -436.16521)
					(end 318.141858 -436.219092)
				)
			)
		)
	)
	(zone
		(layers "F.Cu" "In1.Cu" "In2.Cu" "In3.Cu" "In4.Cu" "In5.Cu" "In6.Cu" "In7.Cu"
			"In8.Cu" "In9.Cu" "In10.Cu" "In11.Cu" "In13.Cu" "In15.Cu"
		)
		(hatch none 0.5)
		(connect_pads
			(clearance 0)
		)
		(min_thickness 0.25)
		(keepout
			(tracks not_allowed)
			(vias allowed)
			(pads allowed)
			(copperpour not_allowed)
			(footprints allowed)
		)
		(placement
			(enabled no)
			(sheetname "")
		)
		(fill yes
			(thermal_gap 0.5)
			(thermal_bridge_width 0.5)
			(island_removal_mode 0)
		)
		(polygon
			(pts
				(arc
					(start 328.141838 -439.760614)
					(mid 328.164156 -439.814496)
					(end 328.218038 -439.836814)
				)
				(arc
					(start 329.157838 -439.836814)
					(mid 329.21172 -439.814496)
					(end 329.234038 -439.760614)
				)
				(arc
					(start 329.234038 -437.21909)
					(mid 329.21172 -437.165208)
					(end 329.157838 -437.14289)
				)
				(arc
					(start 328.218038 -437.14289)
					(mid 328.164156 -437.165208)
					(end 328.141838 -437.21909)
				)
			)
		)
	)
	(zone
		(layers "F.Cu" "In1.Cu" "In2.Cu" "In3.Cu" "In4.Cu" "In5.Cu" "In6.Cu" "In7.Cu"
			"In8.Cu" "In9.Cu" "In10.Cu" "In11.Cu" "In13.Cu" "In15.Cu"
		)
		(hatch none 0.5)
		(connect_pads
			(clearance 0)
		)
		(min_thickness 0.25)
		(keepout
			(tracks not_allowed)
			(vias allowed)
			(pads allowed)
			(copperpour not_allowed)
			(footprints allowed)
		)
		(placement
			(enabled no)
			(sheetname "")
		)
		(fill yes
			(thermal_gap 0.5)
			(thermal_bridge_width 0.5)
			(island_removal_mode 0)
		)
		(polygon
			(pts
				(arc
					(start 316.141862 -439.760614)
					(mid 316.16418 -439.814496)
					(end 316.218062 -439.836814)
				)
				(arc
					(start 317.157862 -439.836814)
					(mid 317.211744 -439.814496)
					(end 317.234062 -439.760614)
				)
				(arc
					(start 317.234062 -437.21909)
					(mid 317.211744 -437.165208)
					(end 317.157862 -437.14289)
				)
				(arc
					(start 316.218062 -437.14289)
					(mid 316.16418 -437.165208)
					(end 316.141862 -437.21909)
				)
			)
		)
	)
	(zone
		(layers "F.Cu" "In1.Cu" "In2.Cu" "In3.Cu" "In4.Cu" "In5.Cu" "In6.Cu" "In7.Cu"
			"In8.Cu" "In9.Cu" "In10.Cu" "In11.Cu" "In13.Cu" "In15.Cu"
		)
		(hatch none 0.5)
		(connect_pads
			(clearance 0)
		)
		(min_thickness 0.25)
		(keepout
			(tracks not_allowed)
			(vias allowed)
			(pads allowed)
			(copperpour not_allowed)
			(footprints allowed)
		)
		(placement
			(enabled no)
			(sheetname "")
		)
		(fill yes
			(thermal_gap 0.5)
			(thermal_bridge_width 0.5)
			(island_removal_mode 0)
		)
		(polygon
			(pts
				(arc
					(start 341.141812 -439.760614)
					(mid 341.16413 -439.814496)
					(end 341.218012 -439.836814)
				)
				(arc
					(start 342.157812 -439.836814)
					(mid 342.211694 -439.814496)
					(end 342.234012 -439.760614)
				)
				(arc
					(start 342.234012 -437.21909)
					(mid 342.211694 -437.165208)
					(end 342.157812 -437.14289)
				)
				(arc
					(start 341.218012 -437.14289)
					(mid 341.16413 -437.165208)
					(end 341.141812 -437.21909)
				)
			)
		)
	)
	(zone
		(layers "F.Cu" "In1.Cu" "In2.Cu" "In3.Cu" "In4.Cu" "In5.Cu" "In6.Cu" "In7.Cu"
			"In8.Cu" "In9.Cu" "In10.Cu" "In11.Cu" "In13.Cu" "In15.Cu"
		)
		(hatch none 0.5)
		(connect_pads
			(clearance 0)
		)
		(min_thickness 0.25)
		(keepout
			(tracks not_allowed)
			(vias allowed)
			(pads allowed)
			(copperpour not_allowed)
			(footprints allowed)
		)
		(placement
			(enabled no)
			(sheetname "")
		)
		(fill yes
			(thermal_gap 0.5)
			(thermal_bridge_width 0.5)
			(island_removal_mode 0)
		)
		(polygon
			(pts
				(arc
					(start 335.141824 -438.760616)
					(mid 335.164142 -438.814498)
					(end 335.218024 -438.836816)
				)
				(arc
					(start 336.157824 -438.836816)
					(mid 336.211706 -438.814498)
					(end 336.234024 -438.760616)
				)
				(arc
					(start 336.234024 -436.219092)
					(mid 336.211706 -436.16521)
					(end 336.157824 -436.142892)
				)
				(arc
					(start 335.218024 -436.142892)
					(mid 335.164142 -436.16521)
					(end 335.141824 -436.219092)
				)
			)
		)
	)
	(zone
		(layers "F.Cu" "In1.Cu" "In2.Cu" "In3.Cu" "In4.Cu" "In5.Cu" "In6.Cu" "In7.Cu"
			"In8.Cu" "In9.Cu" "In10.Cu" "In11.Cu" "In13.Cu" "In15.Cu"
		)
		(hatch none 0.5)
		(connect_pads
			(clearance 0)
		)
		(min_thickness 0.25)
		(keepout
			(tracks not_allowed)
			(vias allowed)
			(pads allowed)
			(copperpour not_allowed)
			(footprints allowed)
		)
		(placement
			(enabled no)
			(sheetname "")
		)
		(fill yes
			(thermal_gap 0.5)
			(thermal_bridge_width 0.5)
			(island_removal_mode 0)
		)
		(polygon
			(pts
				(arc
					(start 331.141832 -438.760616)
					(mid 331.16415 -438.814498)
					(end 331.218032 -438.836816)
				)
				(arc
					(start 332.157832 -438.836816)
					(mid 332.211714 -438.814498)
					(end 332.234032 -438.760616)
				)
				(arc
					(start 332.234032 -436.219092)
					(mid 332.211714 -436.16521)
					(end 332.157832 -436.142892)
				)
				(arc
					(start 331.218032 -436.142892)
					(mid 331.16415 -436.16521)
					(end 331.141832 -436.219092)
				)
			)
		)
	)
	(zone
		(layers "F.Cu" "In1.Cu" "In2.Cu" "In3.Cu" "In4.Cu" "In5.Cu" "In6.Cu" "In7.Cu"
			"In8.Cu" "In9.Cu" "In10.Cu" "In11.Cu" "In13.Cu" "In15.Cu"
		)
		(hatch none 0.5)
		(connect_pads
			(clearance 0)
		)
		(min_thickness 0.25)
		(keepout
			(tracks not_allowed)
			(vias allowed)
			(pads allowed)
			(copperpour not_allowed)
			(footprints allowed)
		)
		(placement
			(enabled no)
			(sheetname "")
		)
		(fill yes
			(thermal_gap 0.5)
			(thermal_bridge_width 0.5)
			(island_removal_mode 0)
		)
		(polygon
			(pts
				(arc
					(start 324.141846 -439.760614)
					(mid 324.164164 -439.814496)
					(end 324.218046 -439.836814)
				)
				(arc
					(start 325.157846 -439.836814)
					(mid 325.211728 -439.814496)
					(end 325.234046 -439.760614)
				)
				(arc
					(start 325.234046 -437.21909)
					(mid 325.211728 -437.165208)
					(end 325.157846 -437.14289)
				)
				(arc
					(start 324.218046 -437.14289)
					(mid 324.164164 -437.165208)
					(end 324.141846 -437.21909)
				)
			)
		)
	)
	(zone
		(layers "F.Cu" "In1.Cu" "In2.Cu" "In3.Cu" "In4.Cu" "In5.Cu" "In6.Cu" "In7.Cu"
			"In8.Cu" "In9.Cu" "In10.Cu" "In11.Cu" "In13.Cu" "In15.Cu"
		)
		(hatch none 0.5)
		(connect_pads
			(clearance 0)
		)
		(min_thickness 0.25)
		(keepout
			(tracks not_allowed)
			(vias allowed)
			(pads allowed)
			(copperpour not_allowed)
			(footprints allowed)
		)
		(placement
			(enabled no)
			(sheetname "")
		)
		(fill yes
			(thermal_gap 0.5)
			(thermal_bridge_width 0.5)
			(island_removal_mode 0)
		)
		(polygon
			(pts
				(arc
					(start 339.141816 -438.760616)
					(mid 339.164134 -438.814498)
					(end 339.218016 -438.836816)
				)
				(arc
					(start 340.157816 -438.836816)
					(mid 340.211698 -438.814498)
					(end 340.234016 -438.760616)
				)
				(arc
					(start 340.234016 -436.219092)
					(mid 340.211698 -436.16521)
					(end 340.157816 -436.142892)
				)
				(arc
					(start 339.218016 -436.142892)
					(mid 339.164134 -436.16521)
					(end 339.141816 -436.219092)
				)
			)
		)
	)
	(zone
		(layers "F.Cu" "In1.Cu" "In2.Cu" "In3.Cu" "In4.Cu" "In5.Cu" "In6.Cu" "In7.Cu"
			"In8.Cu" "In9.Cu" "In10.Cu" "In11.Cu" "In13.Cu" "In15.Cu"
		)
		(hatch none 0.5)
		(connect_pads
			(clearance 0)
		)
		(min_thickness 0.25)
		(keepout
			(tracks not_allowed)
			(vias allowed)
			(pads allowed)
			(copperpour not_allowed)
			(footprints allowed)
		)
		(placement
			(enabled no)
			(sheetname "")
		)
		(fill yes
			(thermal_gap 0.5)
			(thermal_bridge_width 0.5)
			(island_removal_mode 0)
		)
		(polygon
			(pts
				(arc
					(start 343.141808 -438.760616)
					(mid 343.164126 -438.814498)
					(end 343.218008 -438.836816)
				)
				(arc
					(start 344.157808 -438.836816)
					(mid 344.21169 -438.814498)
					(end 344.234008 -438.760616)
				)
				(arc
					(start 344.234008 -436.219092)
					(mid 344.21169 -436.16521)
					(end 344.157808 -436.142892)
				)
				(arc
					(start 343.218008 -436.142892)
					(mid 343.164126 -436.16521)
					(end 343.141808 -436.219092)
				)
			)
		)
	)
	(zone
		(layers "F.Cu" "In1.Cu" "In2.Cu" "In3.Cu" "In4.Cu" "In5.Cu" "In6.Cu" "In7.Cu"
			"In8.Cu" "In9.Cu" "In10.Cu" "In11.Cu" "In13.Cu" "In15.Cu"
		)
		(hatch none 0.5)
		(connect_pads
			(clearance 0)
		)
		(min_thickness 0.25)
		(keepout
			(tracks not_allowed)
			(vias allowed)
			(pads allowed)
			(copperpour not_allowed)
			(footprints allowed)
		)
		(placement
			(enabled no)
			(sheetname "")
		)
		(fill yes
			(thermal_gap 0.5)
			(thermal_bridge_width 0.5)
			(island_removal_mode 0)
		)
		(polygon
			(pts
				(arc
					(start 326.141842 -438.760616)
					(mid 326.16416 -438.814498)
					(end 326.218042 -438.836816)
				)
				(arc
					(start 327.157842 -438.836816)
					(mid 327.211724 -438.814498)
					(end 327.234042 -438.760616)
				)
				(arc
					(start 327.234042 -436.219092)
					(mid 327.211724 -436.16521)
					(end 327.157842 -436.142892)
				)
				(arc
					(start 326.218042 -436.142892)
					(mid 326.16416 -436.16521)
					(end 326.141842 -436.219092)
				)
			)
		)
	)
	(zone
		(layers "F.Cu" "In1.Cu" "In2.Cu" "In3.Cu" "In4.Cu" "In5.Cu" "In6.Cu" "In7.Cu"
			"In8.Cu" "In9.Cu" "In10.Cu" "In11.Cu" "In13.Cu" "In15.Cu"
		)
		(hatch none 0.5)
		(connect_pads
			(clearance 0)
		)
		(min_thickness 0.25)
		(keepout
			(tracks not_allowed)
			(vias allowed)
			(pads allowed)
			(copperpour not_allowed)
			(footprints allowed)
		)
		(placement
			(enabled no)
			(sheetname "")
		)
		(fill yes
			(thermal_gap 0.5)
			(thermal_bridge_width 0.5)
			(island_removal_mode 0)
		)
		(polygon
			(pts
				(arc
					(start 314.141866 -438.760616)
					(mid 314.164184 -438.814498)
					(end 314.218066 -438.836816)
				)
				(arc
					(start 315.157866 -438.836816)
					(mid 315.211748 -438.814498)
					(end 315.234066 -438.760616)
				)
				(arc
					(start 315.234066 -436.219092)
					(mid 315.211748 -436.16521)
					(end 315.157866 -436.142892)
				)
				(arc
					(start 314.218066 -436.142892)
					(mid 314.164184 -436.16521)
					(end 314.141866 -436.219092)
				)
			)
		)
	)
	(zone
		(layers "F.Cu" "In1.Cu" "In2.Cu" "In3.Cu" "In4.Cu" "In5.Cu" "In6.Cu" "In7.Cu"
			"In8.Cu" "In9.Cu" "In10.Cu" "In11.Cu" "In13.Cu" "In15.Cu"
		)
		(hatch none 0.5)
		(connect_pads
			(clearance 0)
		)
		(min_thickness 0.25)
		(keepout
			(tracks not_allowed)
			(vias allowed)
			(pads allowed)
			(copperpour not_allowed)
			(footprints allowed)
		)
		(placement
			(enabled no)
			(sheetname "")
		)
		(fill yes
			(thermal_gap 0.5)
			(thermal_bridge_width 0.5)
			(island_removal_mode 0)
		)
		(polygon
			(pts
				(arc
					(start 333.141828 -439.760614)
					(mid 333.164146 -439.814496)
					(end 333.218028 -439.836814)
				)
				(arc
					(start 334.157828 -439.836814)
					(mid 334.21171 -439.814496)
					(end 334.234028 -439.760614)
				)
				(arc
					(start 334.234028 -437.21909)
					(mid 334.21171 -437.165208)
					(end 334.157828 -437.14289)
				)
				(arc
					(start 333.218028 -437.14289)
					(mid 333.164146 -437.165208)
					(end 333.141828 -437.21909)
				)
			)
		)
	)
	(zone
		(layers "F.Cu" "In1.Cu" "In2.Cu" "In3.Cu" "In4.Cu" "In5.Cu" "In6.Cu" "In7.Cu"
			"In8.Cu" "In9.Cu" "In10.Cu" "In11.Cu" "In13.Cu" "In15.Cu"
		)
		(hatch none 0.5)
		(connect_pads
			(clearance 0)
		)
		(min_thickness 0.25)
		(keepout
			(tracks not_allowed)
			(vias allowed)
			(pads allowed)
			(copperpour not_allowed)
			(footprints allowed)
		)
		(placement
			(enabled no)
			(sheetname "")
		)
		(fill yes
			(thermal_gap 0.5)
			(thermal_bridge_width 0.5)
			(island_removal_mode 0)
		)
		(polygon
			(pts
				(arc
					(start 322.14185 -438.760616)
					(mid 322.164168 -438.814498)
					(end 322.21805 -438.836816)
				)
				(arc
					(start 323.15785 -438.836816)
					(mid 323.211732 -438.814498)
					(end 323.23405 -438.760616)
				)
				(arc
					(start 323.23405 -436.219092)
					(mid 323.211732 -436.16521)
					(end 323.15785 -436.142892)
				)
				(arc
					(start 322.21805 -436.142892)
					(mid 322.164168 -436.16521)
					(end 322.14185 -436.219092)
				)
			)
		)
	)
	(zone
		(layers "F.Cu" "In1.Cu" "In2.Cu" "In3.Cu" "In4.Cu" "In5.Cu" "In6.Cu" "In7.Cu"
			"In8.Cu" "In9.Cu" "In10.Cu" "In11.Cu" "In13.Cu" "In15.Cu"
		)
		(hatch none 0.5)
		(connect_pads
			(clearance 0)
		)
		(min_thickness 0.25)
		(keepout
			(tracks not_allowed)
			(vias allowed)
			(pads allowed)
			(copperpour not_allowed)
			(footprints allowed)
		)
		(placement
			(enabled no)
			(sheetname "")
		)
		(fill yes
			(thermal_gap 0.5)
			(thermal_bridge_width 0.5)
			(island_removal_mode 0)
		)
		(polygon
			(pts
				(arc
					(start 320.141854 -439.760614)
					(mid 320.164172 -439.814496)
					(end 320.218054 -439.836814)
				)
				(arc
					(start 321.157854 -439.836814)
					(mid 321.211736 -439.814496)
					(end 321.234054 -439.760614)
				)
				(arc
					(start 321.234054 -437.21909)
					(mid 321.211736 -437.165208)
					(end 321.157854 -437.14289)
				)
				(arc
					(start 320.218054 -437.14289)
					(mid 320.164172 -437.165208)
					(end 320.141854 -437.21909)
				)
			)
		)
	)
	(zone
		(layers "F.Cu" "In1.Cu" "In2.Cu" "In3.Cu" "In4.Cu" "In5.Cu" "In6.Cu" "In7.Cu"
			"In8.Cu" "In9.Cu" "In10.Cu" "In11.Cu" "In13.Cu" "In15.Cu"
		)
		(hatch none 0.5)
		(connect_pads
			(clearance 0)
		)
		(min_thickness 0.25)
		(keepout
			(tracks not_allowed)
			(vias allowed)
			(pads allowed)
			(copperpour not_allowed)
			(footprints allowed)
		)
		(placement
			(enabled no)
			(sheetname "")
		)
		(fill yes
			(thermal_gap 0.5)
			(thermal_bridge_width 0.5)
			(island_removal_mode 0)
		)
		(polygon
			(pts
				(arc
					(start 345.141804 -439.760614)
					(mid 345.164122 -439.814496)
					(end 345.218004 -439.836814)
				)
				(arc
					(start 346.157804 -439.836814)
					(mid 346.211686 -439.814496)
					(end 346.234004 -439.760614)
				)
				(arc
					(start 346.234004 -437.21909)
					(mid 346.211686 -437.165208)
					(end 346.157804 -437.14289)
				)
				(arc
					(start 345.218004 -437.14289)
					(mid 345.164122 -437.165208)
					(end 345.141804 -437.21909)
				)
			)
		)
	)
	(zone
		(layers "F.Cu" "In1.Cu" "In2.Cu" "In3.Cu" "In4.Cu" "In6.Cu" "In8.Cu" "In9.Cu"
			"In10.Cu" "In11.Cu" "In12.Cu" "In13.Cu" "In14.Cu" "In15.Cu" "In16.Cu"
		)
		(hatch none 0.5)
		(connect_pads
			(clearance 0)
		)
		(min_thickness 0.25)
		(keepout
			(tracks not_allowed)
			(vias allowed)
			(pads allowed)
			(copperpour not_allowed)
			(footprints allowed)
		)
		(placement
			(enabled no)
			(sheetname "")
		)
		(fill yes
			(thermal_gap 0.5)
			(thermal_bridge_width 0.5)
			(island_removal_mode 0)
		)
		(polygon
			(pts
				(arc
					(start 64.141858 -428.960534)
					(mid 64.164176 -429.014416)
					(end 64.218058 -429.036734)
				)
				(arc
					(start 65.157858 -429.036734)
					(mid 65.21174 -429.014416)
					(end 65.234058 -428.960534)
				)
				(arc
					(start 65.234058 -426.41901)
					(mid 65.21174 -426.365128)
					(end 65.157858 -426.34281)
				)
				(arc
					(start 64.218058 -426.34281)
					(mid 64.164176 -426.365128)
					(end 64.141858 -426.41901)
				)
			)
		)
	)
	(zone
		(layers "F.Cu" "In1.Cu" "In2.Cu" "In3.Cu" "In4.Cu" "In6.Cu" "In8.Cu" "In9.Cu"
			"In10.Cu" "In11.Cu" "In12.Cu" "In13.Cu" "In14.Cu" "In15.Cu" "In16.Cu"
		)
		(hatch none 0.5)
		(connect_pads
			(clearance 0)
		)
		(min_thickness 0.25)
		(keepout
			(tracks not_allowed)
			(vias allowed)
			(pads allowed)
			(copperpour not_allowed)
			(footprints allowed)
		)
		(placement
			(enabled no)
			(sheetname "")
		)
		(fill yes
			(thermal_gap 0.5)
			(thermal_bridge_width 0.5)
			(island_removal_mode 0)
		)
		(polygon
			(pts
				(arc
					(start 60.141866 -428.960534)
					(mid 60.164184 -429.014416)
					(end 60.218066 -429.036734)
				)
				(arc
					(start 61.157866 -429.036734)
					(mid 61.211748 -429.014416)
					(end 61.234066 -428.960534)
				)
				(arc
					(start 61.234066 -426.41901)
					(mid 61.211748 -426.365128)
					(end 61.157866 -426.34281)
				)
				(arc
					(start 60.218066 -426.34281)
					(mid 60.164184 -426.365128)
					(end 60.141866 -426.41901)
				)
			)
		)
	)
	(zone
		(layers "F.Cu" "In1.Cu" "In2.Cu" "In3.Cu" "In4.Cu" "In6.Cu" "In8.Cu" "In9.Cu"
			"In10.Cu" "In11.Cu" "In12.Cu" "In13.Cu" "In14.Cu" "In15.Cu" "In16.Cu"
		)
		(hatch none 0.5)
		(connect_pads
			(clearance 0)
		)
		(min_thickness 0.25)
		(keepout
			(tracks not_allowed)
			(vias allowed)
			(pads allowed)
			(copperpour not_allowed)
			(footprints allowed)
		)
		(placement
			(enabled no)
			(sheetname "")
		)
		(fill yes
			(thermal_gap 0.5)
			(thermal_bridge_width 0.5)
			(island_removal_mode 0)
		)
		(polygon
			(pts
				(arc
					(start 68.14185 -428.960534)
					(mid 68.164168 -429.014416)
					(end 68.21805 -429.036734)
				)
				(arc
					(start 69.15785 -429.036734)
					(mid 69.211732 -429.014416)
					(end 69.23405 -428.960534)
				)
				(arc
					(start 69.23405 -426.41901)
					(mid 69.211732 -426.365128)
					(end 69.15785 -426.34281)
				)
				(arc
					(start 68.21805 -426.34281)
					(mid 68.164168 -426.365128)
					(end 68.14185 -426.41901)
				)
			)
		)
	)
	(zone
		(layers "F.Cu" "In1.Cu" "In2.Cu" "In3.Cu" "In4.Cu" "In6.Cu" "In8.Cu" "In9.Cu"
			"In10.Cu" "In11.Cu" "In12.Cu" "In13.Cu" "In14.Cu" "In15.Cu" "In16.Cu"
		)
		(hatch none 0.5)
		(connect_pads
			(clearance 0)
		)
		(min_thickness 0.25)
		(keepout
			(tracks not_allowed)
			(vias allowed)
			(pads allowed)
			(copperpour not_allowed)
			(footprints allowed)
		)
		(placement
			(enabled no)
			(sheetname "")
		)
		(fill yes
			(thermal_gap 0.5)
			(thermal_bridge_width 0.5)
			(island_removal_mode 0)
		)
		(polygon
			(pts
				(arc
					(start 72.141842 -428.960534)
					(mid 72.16416 -429.014416)
					(end 72.218042 -429.036734)
				)
				(arc
					(start 73.157842 -429.036734)
					(mid 73.211724 -429.014416)
					(end 73.234042 -428.960534)
				)
				(arc
					(start 73.234042 -426.41901)
					(mid 73.211724 -426.365128)
					(end 73.157842 -426.34281)
				)
				(arc
					(start 72.218042 -426.34281)
					(mid 72.16416 -426.365128)
					(end 72.141842 -426.41901)
				)
			)
		)
	)
	(zone
		(layers "F.Cu" "In1.Cu" "In2.Cu" "In3.Cu" "In4.Cu" "In6.Cu" "In8.Cu" "In9.Cu"
			"In10.Cu" "In12.Cu" "In13.Cu" "In14.Cu" "In15.Cu" "In16.Cu"
		)
		(hatch none 0.5)
		(connect_pads
			(clearance 0)
		)
		(min_thickness 0.25)
		(keepout
			(tracks not_allowed)
			(vias allowed)
			(pads allowed)
			(copperpour not_allowed)
			(footprints allowed)
		)
		(placement
			(enabled no)
			(sheetname "")
		)
		(fill yes
			(thermal_gap 0.5)
			(thermal_bridge_width 0.5)
			(island_removal_mode 0)
		)
		(polygon
			(pts
				(arc
					(start 148.241766 -428.960534)
					(mid 148.264084 -429.014416)
					(end 148.317966 -429.036734)
				)
				(arc
					(start 149.257766 -429.036734)
					(mid 149.311648 -429.014416)
					(end 149.333966 -428.960534)
				)
				(arc
					(start 149.333966 -426.41901)
					(mid 149.311648 -426.365128)
					(end 149.257766 -426.34281)
				)
				(arc
					(start 148.317966 -426.34281)
					(mid 148.264084 -426.365128)
					(end 148.241766 -426.41901)
				)
			)
		)
	)
	(zone
		(layers "F.Cu" "In1.Cu" "In2.Cu" "In3.Cu" "In4.Cu" "In6.Cu" "In8.Cu" "In9.Cu"
			"In10.Cu" "In12.Cu" "In13.Cu" "In14.Cu" "In15.Cu" "In16.Cu"
		)
		(hatch none 0.5)
		(connect_pads
			(clearance 0)
		)
		(min_thickness 0.25)
		(keepout
			(tracks not_allowed)
			(vias allowed)
			(pads allowed)
			(copperpour not_allowed)
			(footprints allowed)
		)
		(placement
			(enabled no)
			(sheetname "")
		)
		(fill yes
			(thermal_gap 0.5)
			(thermal_bridge_width 0.5)
			(island_removal_mode 0)
		)
		(polygon
			(pts
				(arc
					(start 77.141832 -428.960534)
					(mid 77.16415 -429.014416)
					(end 77.218032 -429.036734)
				)
				(arc
					(start 78.157832 -429.036734)
					(mid 78.211714 -429.014416)
					(end 78.234032 -428.960534)
				)
				(arc
					(start 78.234032 -426.41901)
					(mid 78.211714 -426.365128)
					(end 78.157832 -426.34281)
				)
				(arc
					(start 77.218032 -426.34281)
					(mid 77.16415 -426.365128)
					(end 77.141832 -426.41901)
				)
			)
		)
	)
	(zone
		(layers "F.Cu" "In1.Cu" "In2.Cu" "In3.Cu" "In4.Cu" "In6.Cu" "In8.Cu" "In9.Cu"
			"In10.Cu" "In12.Cu" "In13.Cu" "In14.Cu" "In15.Cu" "In16.Cu"
		)
		(hatch none 0.5)
		(connect_pads
			(clearance 0)
		)
		(min_thickness 0.25)
		(keepout
			(tracks not_allowed)
			(vias allowed)
			(pads allowed)
			(copperpour not_allowed)
			(footprints allowed)
		)
		(placement
			(enabled no)
			(sheetname "")
		)
		(fill yes
			(thermal_gap 0.5)
			(thermal_bridge_width 0.5)
			(island_removal_mode 0)
		)
		(polygon
			(pts
				(arc
					(start 89.141808 -428.960534)
					(mid 89.164126 -429.014416)
					(end 89.218008 -429.036734)
				)
				(arc
					(start 90.157808 -429.036734)
					(mid 90.21169 -429.014416)
					(end 90.234008 -428.960534)
				)
				(arc
					(start 90.234008 -426.41901)
					(mid 90.21169 -426.365128)
					(end 90.157808 -426.34281)
				)
				(arc
					(start 89.218008 -426.34281)
					(mid 89.164126 -426.365128)
					(end 89.141808 -426.41901)
				)
			)
		)
	)
	(zone
		(layers "F.Cu" "In1.Cu" "In2.Cu" "In3.Cu" "In4.Cu" "In6.Cu" "In8.Cu" "In9.Cu"
			"In10.Cu" "In12.Cu" "In13.Cu" "In14.Cu" "In15.Cu" "In16.Cu"
		)
		(hatch none 0.5)
		(connect_pads
			(clearance 0)
		)
		(min_thickness 0.25)
		(keepout
			(tracks not_allowed)
			(vias allowed)
			(pads allowed)
			(copperpour not_allowed)
			(footprints allowed)
		)
		(placement
			(enabled no)
			(sheetname "")
		)
		(fill yes
			(thermal_gap 0.5)
			(thermal_bridge_width 0.5)
			(island_removal_mode 0)
		)
		(polygon
			(pts
				(arc
					(start 152.241758 -428.960534)
					(mid 152.264076 -429.014416)
					(end 152.317958 -429.036734)
				)
				(arc
					(start 153.257758 -429.036734)
					(mid 153.31164 -429.014416)
					(end 153.333958 -428.960534)
				)
				(arc
					(start 153.333958 -426.41901)
					(mid 153.31164 -426.365128)
					(end 153.257758 -426.34281)
				)
				(arc
					(start 152.317958 -426.34281)
					(mid 152.264076 -426.365128)
					(end 152.241758 -426.41901)
				)
			)
		)
	)
	(zone
		(layers "F.Cu" "In1.Cu" "In2.Cu" "In3.Cu" "In4.Cu" "In6.Cu" "In8.Cu" "In9.Cu"
			"In10.Cu" "In12.Cu" "In13.Cu" "In14.Cu" "In15.Cu" "In16.Cu"
		)
		(hatch none 0.5)
		(connect_pads
			(clearance 0)
		)
		(min_thickness 0.25)
		(keepout
			(tracks not_allowed)
			(vias allowed)
			(pads allowed)
			(copperpour not_allowed)
			(footprints allowed)
		)
		(placement
			(enabled no)
			(sheetname "")
		)
		(fill yes
			(thermal_gap 0.5)
			(thermal_bridge_width 0.5)
			(island_removal_mode 0)
		)
		(polygon
			(pts
				(arc
					(start 85.141816 -428.960534)
					(mid 85.164134 -429.014416)
					(end 85.218016 -429.036734)
				)
				(arc
					(start 86.157816 -429.036734)
					(mid 86.211698 -429.014416)
					(end 86.234016 -428.960534)
				)
				(arc
					(start 86.234016 -426.41901)
					(mid 86.211698 -426.365128)
					(end 86.157816 -426.34281)
				)
				(arc
					(start 85.218016 -426.34281)
					(mid 85.164134 -426.365128)
					(end 85.141816 -426.41901)
				)
			)
		)
	)
	(zone
		(layers "F.Cu" "In1.Cu" "In2.Cu" "In3.Cu" "In4.Cu" "In6.Cu" "In8.Cu" "In9.Cu"
			"In10.Cu" "In12.Cu" "In13.Cu" "In14.Cu" "In15.Cu" "In16.Cu"
		)
		(hatch none 0.5)
		(connect_pads
			(clearance 0)
		)
		(min_thickness 0.25)
		(keepout
			(tracks not_allowed)
			(vias allowed)
			(pads allowed)
			(copperpour not_allowed)
			(footprints allowed)
		)
		(placement
			(enabled no)
			(sheetname "")
		)
		(fill yes
			(thermal_gap 0.5)
			(thermal_bridge_width 0.5)
			(island_removal_mode 0)
		)
		(polygon
			(pts
				(arc
					(start 131.2418 -428.960534)
					(mid 131.264118 -429.014416)
					(end 131.318 -429.036734)
				)
				(arc
					(start 132.2578 -429.036734)
					(mid 132.311682 -429.014416)
					(end 132.334 -428.960534)
				)
				(arc
					(start 132.334 -426.41901)
					(mid 132.311682 -426.365128)
					(end 132.2578 -426.34281)
				)
				(arc
					(start 131.318 -426.34281)
					(mid 131.264118 -426.365128)
					(end 131.2418 -426.41901)
				)
			)
		)
	)
	(zone
		(layers "F.Cu" "In1.Cu" "In2.Cu" "In3.Cu" "In4.Cu" "In6.Cu" "In8.Cu" "In9.Cu"
			"In10.Cu" "In12.Cu" "In13.Cu" "In14.Cu" "In15.Cu" "In16.Cu"
		)
		(hatch none 0.5)
		(connect_pads
			(clearance 0)
		)
		(min_thickness 0.25)
		(keepout
			(tracks not_allowed)
			(vias allowed)
			(pads allowed)
			(copperpour not_allowed)
			(footprints allowed)
		)
		(placement
			(enabled no)
			(sheetname "")
		)
		(fill yes
			(thermal_gap 0.5)
			(thermal_bridge_width 0.5)
			(island_removal_mode 0)
		)
		(polygon
			(pts
				(arc
					(start 139.241784 -428.960534)
					(mid 139.264102 -429.014416)
					(end 139.317984 -429.036734)
				)
				(arc
					(start 140.257784 -429.036734)
					(mid 140.311666 -429.014416)
					(end 140.333984 -428.960534)
				)
				(arc
					(start 140.333984 -426.41901)
					(mid 140.311666 -426.365128)
					(end 140.257784 -426.34281)
				)
				(arc
					(start 139.317984 -426.34281)
					(mid 139.264102 -426.365128)
					(end 139.241784 -426.41901)
				)
			)
		)
	)
	(zone
		(layers "F.Cu" "In1.Cu" "In2.Cu" "In3.Cu" "In4.Cu" "In6.Cu" "In8.Cu" "In9.Cu"
			"In10.Cu" "In12.Cu" "In13.Cu" "In14.Cu" "In15.Cu" "In16.Cu"
		)
		(hatch none 0.5)
		(connect_pads
			(clearance 0)
		)
		(min_thickness 0.25)
		(keepout
			(tracks not_allowed)
			(vias allowed)
			(pads allowed)
			(copperpour not_allowed)
			(footprints allowed)
		)
		(placement
			(enabled no)
			(sheetname "")
		)
		(fill yes
			(thermal_gap 0.5)
			(thermal_bridge_width 0.5)
			(island_removal_mode 0)
		)
		(polygon
			(pts
				(arc
					(start 144.241774 -428.960534)
					(mid 144.264092 -429.014416)
					(end 144.317974 -429.036734)
				)
				(arc
					(start 145.257774 -429.036734)
					(mid 145.311656 -429.014416)
					(end 145.333974 -428.960534)
				)
				(arc
					(start 145.333974 -426.41901)
					(mid 145.311656 -426.365128)
					(end 145.257774 -426.34281)
				)
				(arc
					(start 144.317974 -426.34281)
					(mid 144.264092 -426.365128)
					(end 144.241774 -426.41901)
				)
			)
		)
	)
	(zone
		(layers "F.Cu" "In1.Cu" "In2.Cu" "In3.Cu" "In4.Cu" "In6.Cu" "In8.Cu" "In9.Cu"
			"In10.Cu" "In12.Cu" "In13.Cu" "In14.Cu" "In15.Cu" "In16.Cu"
		)
		(hatch none 0.5)
		(connect_pads
			(clearance 0)
		)
		(min_thickness 0.25)
		(keepout
			(tracks not_allowed)
			(vias allowed)
			(pads allowed)
			(copperpour not_allowed)
			(footprints allowed)
		)
		(placement
			(enabled no)
			(sheetname "")
		)
		(fill yes
			(thermal_gap 0.5)
			(thermal_bridge_width 0.5)
			(island_removal_mode 0)
		)
		(polygon
			(pts
				(arc
					(start 156.24175 -428.960534)
					(mid 156.264068 -429.014416)
					(end 156.31795 -429.036734)
				)
				(arc
					(start 157.25775 -429.036734)
					(mid 157.311632 -429.014416)
					(end 157.33395 -428.960534)
				)
				(arc
					(start 157.33395 -426.41901)
					(mid 157.311632 -426.365128)
					(end 157.25775 -426.34281)
				)
				(arc
					(start 156.31795 -426.34281)
					(mid 156.264068 -426.365128)
					(end 156.24175 -426.41901)
				)
			)
		)
	)
	(zone
		(layers "F.Cu" "In1.Cu" "In2.Cu" "In3.Cu" "In4.Cu" "In6.Cu" "In8.Cu" "In9.Cu"
			"In10.Cu" "In12.Cu" "In13.Cu" "In14.Cu" "In15.Cu" "In16.Cu"
		)
		(hatch none 0.5)
		(connect_pads
			(clearance 0)
		)
		(min_thickness 0.25)
		(keepout
			(tracks not_allowed)
			(vias allowed)
			(pads allowed)
			(copperpour not_allowed)
			(footprints allowed)
		)
		(placement
			(enabled no)
			(sheetname "")
		)
		(fill yes
			(thermal_gap 0.5)
			(thermal_bridge_width 0.5)
			(island_removal_mode 0)
		)
		(polygon
			(pts
				(arc
					(start 127.241808 -428.960534)
					(mid 127.264126 -429.014416)
					(end 127.318008 -429.036734)
				)
				(arc
					(start 128.257808 -429.036734)
					(mid 128.31169 -429.014416)
					(end 128.334008 -428.960534)
				)
				(arc
					(start 128.334008 -426.41901)
					(mid 128.31169 -426.365128)
					(end 128.257808 -426.34281)
				)
				(arc
					(start 127.318008 -426.34281)
					(mid 127.264126 -426.365128)
					(end 127.241808 -426.41901)
				)
			)
		)
	)
	(zone
		(layers "F.Cu" "In1.Cu" "In2.Cu" "In3.Cu" "In4.Cu" "In6.Cu" "In8.Cu" "In9.Cu"
			"In10.Cu" "In12.Cu" "In13.Cu" "In14.Cu" "In15.Cu" "In16.Cu"
		)
		(hatch none 0.5)
		(connect_pads
			(clearance 0)
		)
		(min_thickness 0.25)
		(keepout
			(tracks not_allowed)
			(vias allowed)
			(pads allowed)
			(copperpour not_allowed)
			(footprints allowed)
		)
		(placement
			(enabled no)
			(sheetname "")
		)
		(fill yes
			(thermal_gap 0.5)
			(thermal_bridge_width 0.5)
			(island_removal_mode 0)
		)
		(polygon
			(pts
				(arc
					(start 81.141824 -428.960534)
					(mid 81.164142 -429.014416)
					(end 81.218024 -429.036734)
				)
				(arc
					(start 82.157824 -429.036734)
					(mid 82.211706 -429.014416)
					(end 82.234024 -428.960534)
				)
				(arc
					(start 82.234024 -426.41901)
					(mid 82.211706 -426.365128)
					(end 82.157824 -426.34281)
				)
				(arc
					(start 81.218024 -426.34281)
					(mid 81.164142 -426.365128)
					(end 81.141824 -426.41901)
				)
			)
		)
	)
	(zone
		(layers "F.Cu" "In1.Cu" "In2.Cu" "In3.Cu" "In4.Cu" "In6.Cu" "In8.Cu" "In9.Cu"
			"In10.Cu" "In12.Cu" "In13.Cu" "In14.Cu" "In15.Cu" "In16.Cu"
		)
		(hatch none 0.5)
		(connect_pads
			(clearance 0)
		)
		(min_thickness 0.25)
		(keepout
			(tracks not_allowed)
			(vias allowed)
			(pads allowed)
			(copperpour not_allowed)
			(footprints allowed)
		)
		(placement
			(enabled no)
			(sheetname "")
		)
		(fill yes
			(thermal_gap 0.5)
			(thermal_bridge_width 0.5)
			(island_removal_mode 0)
		)
		(polygon
			(pts
				(arc
					(start 135.241792 -428.960534)
					(mid 135.26411 -429.014416)
					(end 135.317992 -429.036734)
				)
				(arc
					(start 136.257792 -429.036734)
					(mid 136.311674 -429.014416)
					(end 136.333992 -428.960534)
				)
				(arc
					(start 136.333992 -426.41901)
					(mid 136.311674 -426.365128)
					(end 136.257792 -426.34281)
				)
				(arc
					(start 135.317992 -426.34281)
					(mid 135.26411 -426.365128)
					(end 135.241792 -426.41901)
				)
			)
		)
	)
	(zone
		(layers "F.Cu" "In1.Cu" "In2.Cu" "In3.Cu" "In4.Cu" "In6.Cu" "In8.Cu" "In9.Cu"
			"In10.Cu" "In13.Cu" "In14.Cu" "In15.Cu" "In16.Cu"
		)
		(hatch none 0.5)
		(connect_pads
			(clearance 0)
		)
		(min_thickness 0.25)
		(keepout
			(tracks not_allowed)
			(vias allowed)
			(pads allowed)
			(copperpour not_allowed)
			(footprints allowed)
		)
		(placement
			(enabled no)
			(sheetname "")
		)
		(fill yes
			(thermal_gap 0.5)
			(thermal_bridge_width 0.5)
			(island_removal_mode 0)
		)
		(polygon
			(pts
				(arc
					(start 395.24178 -428.960534)
					(mid 395.264098 -429.014416)
					(end 395.31798 -429.036734)
				)
				(arc
					(start 396.25778 -429.036734)
					(mid 396.311662 -429.014416)
					(end 396.33398 -428.960534)
				)
				(arc
					(start 396.33398 -426.41901)
					(mid 396.311662 -426.365128)
					(end 396.25778 -426.34281)
				)
				(arc
					(start 395.31798 -426.34281)
					(mid 395.264098 -426.365128)
					(end 395.24178 -426.41901)
				)
			)
		)
	)
	(zone
		(layers "F.Cu" "In1.Cu" "In2.Cu" "In3.Cu" "In4.Cu" "In6.Cu" "In8.Cu" "In9.Cu"
			"In10.Cu" "In13.Cu" "In14.Cu" "In15.Cu" "In16.Cu"
		)
		(hatch none 0.5)
		(connect_pads
			(clearance 0)
		)
		(min_thickness 0.25)
		(keepout
			(tracks not_allowed)
			(vias allowed)
			(pads allowed)
			(copperpour not_allowed)
			(footprints allowed)
		)
		(placement
			(enabled no)
			(sheetname "")
		)
		(fill yes
			(thermal_gap 0.5)
			(thermal_bridge_width 0.5)
			(island_removal_mode 0)
		)
		(polygon
			(pts
				(arc
					(start 387.241796 -428.960534)
					(mid 387.264114 -429.014416)
					(end 387.317996 -429.036734)
				)
				(arc
					(start 388.257796 -429.036734)
					(mid 388.311678 -429.014416)
					(end 388.333996 -428.960534)
				)
				(arc
					(start 388.333996 -426.41901)
					(mid 388.311678 -426.365128)
					(end 388.257796 -426.34281)
				)
				(arc
					(start 387.317996 -426.34281)
					(mid 387.264114 -426.365128)
					(end 387.241796 -426.41901)
				)
			)
		)
	)
	(zone
		(layers "F.Cu" "In1.Cu" "In2.Cu" "In3.Cu" "In4.Cu" "In6.Cu" "In8.Cu" "In9.Cu"
			"In10.Cu" "In13.Cu" "In14.Cu" "In15.Cu" "In16.Cu"
		)
		(hatch none 0.5)
		(connect_pads
			(clearance 0)
		)
		(min_thickness 0.25)
		(keepout
			(tracks not_allowed)
			(vias allowed)
			(pads allowed)
			(copperpour not_allowed)
			(footprints allowed)
		)
		(placement
			(enabled no)
			(sheetname "")
		)
		(fill yes
			(thermal_gap 0.5)
			(thermal_bridge_width 0.5)
			(island_removal_mode 0)
		)
		(polygon
			(pts
				(arc
					(start 408.241754 -428.960534)
					(mid 408.264072 -429.014416)
					(end 408.317954 -429.036734)
				)
				(arc
					(start 409.257754 -429.036734)
					(mid 409.311636 -429.014416)
					(end 409.333954 -428.960534)
				)
				(arc
					(start 409.333954 -426.41901)
					(mid 409.311636 -426.365128)
					(end 409.257754 -426.34281)
				)
				(arc
					(start 408.317954 -426.34281)
					(mid 408.264072 -426.365128)
					(end 408.241754 -426.41901)
				)
			)
		)
	)
	(zone
		(layers "F.Cu" "In1.Cu" "In2.Cu" "In3.Cu" "In4.Cu" "In6.Cu" "In8.Cu" "In9.Cu"
			"In10.Cu" "In13.Cu" "In14.Cu" "In15.Cu" "In16.Cu"
		)
		(hatch none 0.5)
		(connect_pads
			(clearance 0)
		)
		(min_thickness 0.25)
		(keepout
			(tracks not_allowed)
			(vias allowed)
			(pads allowed)
			(copperpour not_allowed)
			(footprints allowed)
		)
		(placement
			(enabled no)
			(sheetname "")
		)
		(fill yes
			(thermal_gap 0.5)
			(thermal_bridge_width 0.5)
			(island_removal_mode 0)
		)
		(polygon
			(pts
				(arc
					(start 400.24177 -428.960534)
					(mid 400.264088 -429.014416)
					(end 400.31797 -429.036734)
				)
				(arc
					(start 401.25777 -429.036734)
					(mid 401.311652 -429.014416)
					(end 401.33397 -428.960534)
				)
				(arc
					(start 401.33397 -426.41901)
					(mid 401.311652 -426.365128)
					(end 401.25777 -426.34281)
				)
				(arc
					(start 400.31797 -426.34281)
					(mid 400.264088 -426.365128)
					(end 400.24177 -426.41901)
				)
			)
		)
	)
	(zone
		(layers "F.Cu" "In1.Cu" "In2.Cu" "In3.Cu" "In4.Cu" "In6.Cu" "In8.Cu" "In9.Cu"
			"In10.Cu" "In13.Cu" "In14.Cu" "In15.Cu" "In16.Cu"
		)
		(hatch none 0.5)
		(connect_pads
			(clearance 0)
		)
		(min_thickness 0.25)
		(keepout
			(tracks not_allowed)
			(vias allowed)
			(pads allowed)
			(copperpour not_allowed)
			(footprints allowed)
		)
		(placement
			(enabled no)
			(sheetname "")
		)
		(fill yes
			(thermal_gap 0.5)
			(thermal_bridge_width 0.5)
			(island_removal_mode 0)
		)
		(polygon
			(pts
				(arc
					(start 404.241762 -428.960534)
					(mid 404.26408 -429.014416)
					(end 404.317962 -429.036734)
				)
				(arc
					(start 405.257762 -429.036734)
					(mid 405.311644 -429.014416)
					(end 405.333962 -428.960534)
				)
				(arc
					(start 405.333962 -426.41901)
					(mid 405.311644 -426.365128)
					(end 405.257762 -426.34281)
				)
				(arc
					(start 404.317962 -426.34281)
					(mid 404.26408 -426.365128)
					(end 404.241762 -426.41901)
				)
			)
		)
	)
	(zone
		(layers "F.Cu" "In1.Cu" "In2.Cu" "In3.Cu" "In4.Cu" "In6.Cu" "In8.Cu" "In9.Cu"
			"In10.Cu" "In13.Cu" "In14.Cu" "In15.Cu" "In16.Cu"
		)
		(hatch none 0.5)
		(connect_pads
			(clearance 0)
		)
		(min_thickness 0.25)
		(keepout
			(tracks not_allowed)
			(vias allowed)
			(pads allowed)
			(copperpour not_allowed)
			(footprints allowed)
		)
		(placement
			(enabled no)
			(sheetname "")
		)
		(fill yes
			(thermal_gap 0.5)
			(thermal_bridge_width 0.5)
			(island_removal_mode 0)
		)
		(polygon
			(pts
				(arc
					(start 391.241788 -428.960534)
					(mid 391.264106 -429.014416)
					(end 391.317988 -429.036734)
				)
				(arc
					(start 392.257788 -429.036734)
					(mid 392.31167 -429.014416)
					(end 392.333988 -428.960534)
				)
				(arc
					(start 392.333988 -426.41901)
					(mid 392.31167 -426.365128)
					(end 392.257788 -426.34281)
				)
				(arc
					(start 391.317988 -426.34281)
					(mid 391.264106 -426.365128)
					(end 391.241788 -426.41901)
				)
			)
		)
	)
	(zone
		(layers "F.Cu" "In1.Cu" "In2.Cu" "In3.Cu" "In4.Cu" "In6.Cu" "In8.Cu" "In9.Cu"
			"In10.Cu" "In13.Cu" "In14.Cu" "In15.Cu" "In16.Cu"
		)
		(hatch none 0.5)
		(connect_pads
			(clearance 0)
		)
		(min_thickness 0.25)
		(keepout
			(tracks not_allowed)
			(vias allowed)
			(pads allowed)
			(copperpour not_allowed)
			(footprints allowed)
		)
		(placement
			(enabled no)
			(sheetname "")
		)
		(fill yes
			(thermal_gap 0.5)
			(thermal_bridge_width 0.5)
			(island_removal_mode 0)
		)
		(polygon
			(pts
				(arc
					(start 412.241746 -428.960534)
					(mid 412.264064 -429.014416)
					(end 412.317946 -429.036734)
				)
				(arc
					(start 413.257746 -429.036734)
					(mid 413.311628 -429.014416)
					(end 413.333946 -428.960534)
				)
				(arc
					(start 413.333946 -426.41901)
					(mid 413.311628 -426.365128)
					(end 413.257746 -426.34281)
				)
				(arc
					(start 412.317946 -426.34281)
					(mid 412.264064 -426.365128)
					(end 412.241746 -426.41901)
				)
			)
		)
	)
	(zone
		(layers "F.Cu" "In1.Cu" "In2.Cu" "In3.Cu" "In4.Cu" "In6.Cu" "In8.Cu" "In9.Cu"
			"In10.Cu" "In13.Cu" "In14.Cu" "In15.Cu" "In16.Cu"
		)
		(hatch none 0.5)
		(connect_pads
			(clearance 0)
		)
		(min_thickness 0.25)
		(keepout
			(tracks not_allowed)
			(vias allowed)
			(pads allowed)
			(copperpour not_allowed)
			(footprints allowed)
		)
		(placement
			(enabled no)
			(sheetname "")
		)
		(fill yes
			(thermal_gap 0.5)
			(thermal_bridge_width 0.5)
			(island_removal_mode 0)
		)
		(polygon
			(pts
				(arc
					(start 383.241804 -428.960534)
					(mid 383.264122 -429.014416)
					(end 383.318004 -429.036734)
				)
				(arc
					(start 384.257804 -429.036734)
					(mid 384.311686 -429.014416)
					(end 384.334004 -428.960534)
				)
				(arc
					(start 384.334004 -426.41901)
					(mid 384.311686 -426.365128)
					(end 384.257804 -426.34281)
				)
				(arc
					(start 383.318004 -426.34281)
					(mid 383.264122 -426.365128)
					(end 383.241804 -426.41901)
				)
			)
		)
	)
	(zone
		(layers "F.Cu" "In1.Cu" "In2.Cu" "In4.Cu" "In6.Cu" "In8.Cu" "In9.Cu" "In10.Cu"
			"In11.Cu" "In13.Cu" "In15.Cu"
		)
		(hatch none 0.5)
		(connect_pads
			(clearance 0)
		)
		(min_thickness 0.25)
		(keepout
			(tracks not_allowed)
			(vias allowed)
			(pads allowed)
			(copperpour not_allowed)
			(footprints allowed)
		)
		(placement
			(enabled no)
			(sheetname "")
		)
		(fill yes
			(thermal_gap 0.5)
			(thermal_bridge_width 0.5)
			(island_removal_mode 0)
		)
		(polygon
			(pts
				(arc
					(start 135.241792 -439.760614)
					(mid 135.26411 -439.814496)
					(end 135.317992 -439.836814)
				)
				(arc
					(start 136.257792 -439.836814)
					(mid 136.311674 -439.814496)
					(end 136.333992 -439.760614)
				)
				(arc
					(start 136.333992 -437.21909)
					(mid 136.311674 -437.165208)
					(end 136.257792 -437.14289)
				)
				(arc
					(start 135.317992 -437.14289)
					(mid 135.26411 -437.165208)
					(end 135.241792 -437.21909)
				)
			)
		)
	)
	(zone
		(layers "F.Cu" "In1.Cu" "In2.Cu" "In4.Cu" "In6.Cu" "In8.Cu" "In9.Cu" "In10.Cu"
			"In11.Cu" "In13.Cu" "In15.Cu"
		)
		(hatch none 0.5)
		(connect_pads
			(clearance 0)
		)
		(min_thickness 0.25)
		(keepout
			(tracks not_allowed)
			(vias allowed)
			(pads allowed)
			(copperpour not_allowed)
			(footprints allowed)
		)
		(placement
			(enabled no)
			(sheetname "")
		)
		(fill yes
			(thermal_gap 0.5)
			(thermal_bridge_width 0.5)
			(island_removal_mode 0)
		)
		(polygon
			(pts
				(arc
					(start 402.241766 -438.760616)
					(mid 402.264084 -438.814498)
					(end 402.317966 -438.836816)
				)
				(arc
					(start 403.257766 -438.836816)
					(mid 403.311648 -438.814498)
					(end 403.333966 -438.760616)
				)
				(arc
					(start 403.333966 -436.219092)
					(mid 403.311648 -436.16521)
					(end 403.257766 -436.142892)
				)
				(arc
					(start 402.317966 -436.142892)
					(mid 402.264084 -436.16521)
					(end 402.241766 -436.219092)
				)
			)
		)
	)
	(zone
		(layers "F.Cu" "In1.Cu" "In2.Cu" "In4.Cu" "In6.Cu" "In8.Cu" "In9.Cu" "In10.Cu"
			"In11.Cu" "In13.Cu" "In15.Cu"
		)
		(hatch none 0.5)
		(connect_pads
			(clearance 0)
		)
		(min_thickness 0.25)
		(keepout
			(tracks not_allowed)
			(vias allowed)
			(pads allowed)
			(copperpour not_allowed)
			(footprints allowed)
		)
		(placement
			(enabled no)
			(sheetname "")
		)
		(fill yes
			(thermal_gap 0.5)
			(thermal_bridge_width 0.5)
			(island_removal_mode 0)
		)
		(polygon
			(pts
				(arc
					(start 150.241762 -438.760616)
					(mid 150.26408 -438.814498)
					(end 150.317962 -438.836816)
				)
				(arc
					(start 151.257762 -438.836816)
					(mid 151.311644 -438.814498)
					(end 151.333962 -438.760616)
				)
				(arc
					(start 151.333962 -436.219092)
					(mid 151.311644 -436.16521)
					(end 151.257762 -436.142892)
				)
				(arc
					(start 150.317962 -436.142892)
					(mid 150.26408 -436.16521)
					(end 150.241762 -436.219092)
				)
			)
		)
	)
	(zone
		(layers "F.Cu" "In1.Cu" "In2.Cu" "In4.Cu" "In6.Cu" "In8.Cu" "In9.Cu" "In10.Cu"
			"In11.Cu" "In13.Cu" "In15.Cu"
		)
		(hatch none 0.5)
		(connect_pads
			(clearance 0)
		)
		(min_thickness 0.25)
		(keepout
			(tracks not_allowed)
			(vias allowed)
			(pads allowed)
			(copperpour not_allowed)
			(footprints allowed)
		)
		(placement
			(enabled no)
			(sheetname "")
		)
		(fill yes
			(thermal_gap 0.5)
			(thermal_bridge_width 0.5)
			(island_removal_mode 0)
		)
		(polygon
			(pts
				(arc
					(start 144.241774 -439.760614)
					(mid 144.264092 -439.814496)
					(end 144.317974 -439.836814)
				)
				(arc
					(start 145.257774 -439.836814)
					(mid 145.311656 -439.814496)
					(end 145.333974 -439.760614)
				)
				(arc
					(start 145.333974 -437.21909)
					(mid 145.311656 -437.165208)
					(end 145.257774 -437.14289)
				)
				(arc
					(start 144.317974 -437.14289)
					(mid 144.264092 -437.165208)
					(end 144.241774 -437.21909)
				)
			)
		)
	)
	(zone
		(layers "F.Cu" "In1.Cu" "In2.Cu" "In4.Cu" "In6.Cu" "In8.Cu" "In9.Cu" "In10.Cu"
			"In11.Cu" "In13.Cu" "In15.Cu"
		)
		(hatch none 0.5)
		(connect_pads
			(clearance 0)
		)
		(min_thickness 0.25)
		(keepout
			(tracks not_allowed)
			(vias allowed)
			(pads allowed)
			(copperpour not_allowed)
			(footprints allowed)
		)
		(placement
			(enabled no)
			(sheetname "")
		)
		(fill yes
			(thermal_gap 0.5)
			(thermal_bridge_width 0.5)
			(island_removal_mode 0)
		)
		(polygon
			(pts
				(arc
					(start 412.241746 -439.760614)
					(mid 412.264064 -439.814496)
					(end 412.317946 -439.836814)
				)
				(arc
					(start 413.257746 -439.836814)
					(mid 413.311628 -439.814496)
					(end 413.333946 -439.760614)
				)
				(arc
					(start 413.333946 -437.21909)
					(mid 413.311628 -437.165208)
					(end 413.257746 -437.14289)
				)
				(arc
					(start 412.317946 -437.14289)
					(mid 412.264064 -437.165208)
					(end 412.241746 -437.21909)
				)
			)
		)
	)
	(zone
		(layers "F.Cu" "In1.Cu" "In2.Cu" "In4.Cu" "In6.Cu" "In8.Cu" "In9.Cu" "In10.Cu"
			"In11.Cu" "In13.Cu" "In15.Cu"
		)
		(hatch none 0.5)
		(connect_pads
			(clearance 0)
		)
		(min_thickness 0.25)
		(keepout
			(tracks not_allowed)
			(vias allowed)
			(pads allowed)
			(copperpour not_allowed)
			(footprints allowed)
		)
		(placement
			(enabled no)
			(sheetname "")
		)
		(fill yes
			(thermal_gap 0.5)
			(thermal_bridge_width 0.5)
			(island_removal_mode 0)
		)
		(polygon
			(pts
				(arc
					(start 387.241796 -439.760614)
					(mid 387.264114 -439.814496)
					(end 387.317996 -439.836814)
				)
				(arc
					(start 388.257796 -439.836814)
					(mid 388.311678 -439.814496)
					(end 388.333996 -439.760614)
				)
				(arc
					(start 388.333996 -437.21909)
					(mid 388.311678 -437.165208)
					(end 388.257796 -437.14289)
				)
				(arc
					(start 387.317996 -437.14289)
					(mid 387.264114 -437.165208)
					(end 387.241796 -437.21909)
				)
			)
		)
	)
	(zone
		(layers "F.Cu" "In1.Cu" "In2.Cu" "In4.Cu" "In6.Cu" "In8.Cu" "In9.Cu" "In10.Cu"
			"In11.Cu" "In13.Cu" "In15.Cu"
		)
		(hatch none 0.5)
		(connect_pads
			(clearance 0)
		)
		(min_thickness 0.25)
		(keepout
			(tracks not_allowed)
			(vias allowed)
			(pads allowed)
			(copperpour not_allowed)
			(footprints allowed)
		)
		(placement
			(enabled no)
			(sheetname "")
		)
		(fill yes
			(thermal_gap 0.5)
			(thermal_bridge_width 0.5)
			(island_removal_mode 0)
		)
		(polygon
			(pts
				(arc
					(start 408.241754 -439.760614)
					(mid 408.264072 -439.814496)
					(end 408.317954 -439.836814)
				)
				(arc
					(start 409.257754 -439.836814)
					(mid 409.311636 -439.814496)
					(end 409.333954 -439.760614)
				)
				(arc
					(start 409.333954 -437.21909)
					(mid 409.311636 -437.165208)
					(end 409.257754 -437.14289)
				)
				(arc
					(start 408.317954 -437.14289)
					(mid 408.264072 -437.165208)
					(end 408.241754 -437.21909)
				)
			)
		)
	)
	(zone
		(layers "F.Cu" "In1.Cu" "In2.Cu" "In4.Cu" "In6.Cu" "In8.Cu" "In9.Cu" "In10.Cu"
			"In11.Cu" "In13.Cu" "In15.Cu"
		)
		(hatch none 0.5)
		(connect_pads
			(clearance 0)
		)
		(min_thickness 0.25)
		(keepout
			(tracks not_allowed)
			(vias allowed)
			(pads allowed)
			(copperpour not_allowed)
			(footprints allowed)
		)
		(placement
			(enabled no)
			(sheetname "")
		)
		(fill yes
			(thermal_gap 0.5)
			(thermal_bridge_width 0.5)
			(island_removal_mode 0)
		)
		(polygon
			(pts
				(arc
					(start 154.241754 -438.760616)
					(mid 154.264072 -438.814498)
					(end 154.317954 -438.836816)
				)
				(arc
					(start 155.257754 -438.836816)
					(mid 155.311636 -438.814498)
					(end 155.333954 -438.760616)
				)
				(arc
					(start 155.333954 -436.219092)
					(mid 155.311636 -436.16521)
					(end 155.257754 -436.142892)
				)
				(arc
					(start 154.317954 -436.142892)
					(mid 154.264072 -436.16521)
					(end 154.241754 -436.219092)
				)
			)
		)
	)
	(zone
		(layers "F.Cu" "In1.Cu" "In2.Cu" "In4.Cu" "In6.Cu" "In8.Cu" "In9.Cu" "In10.Cu"
			"In11.Cu" "In13.Cu" "In15.Cu"
		)
		(hatch none 0.5)
		(connect_pads
			(clearance 0)
		)
		(min_thickness 0.25)
		(keepout
			(tracks not_allowed)
			(vias allowed)
			(pads allowed)
			(copperpour not_allowed)
			(footprints allowed)
		)
		(placement
			(enabled no)
			(sheetname "")
		)
		(fill yes
			(thermal_gap 0.5)
			(thermal_bridge_width 0.5)
			(island_removal_mode 0)
		)
		(polygon
			(pts
				(arc
					(start 404.241762 -439.760614)
					(mid 404.26408 -439.814496)
					(end 404.317962 -439.836814)
				)
				(arc
					(start 405.257762 -439.836814)
					(mid 405.311644 -439.814496)
					(end 405.333962 -439.760614)
				)
				(arc
					(start 405.333962 -437.21909)
					(mid 405.311644 -437.165208)
					(end 405.257762 -437.14289)
				)
				(arc
					(start 404.317962 -437.14289)
					(mid 404.26408 -437.165208)
					(end 404.241762 -437.21909)
				)
			)
		)
	)
	(zone
		(layers "F.Cu" "In1.Cu" "In2.Cu" "In4.Cu" "In6.Cu" "In8.Cu" "In9.Cu" "In10.Cu"
			"In11.Cu" "In13.Cu" "In15.Cu"
		)
		(hatch none 0.5)
		(connect_pads
			(clearance 0)
		)
		(min_thickness 0.25)
		(keepout
			(tracks not_allowed)
			(vias allowed)
			(pads allowed)
			(copperpour not_allowed)
			(footprints allowed)
		)
		(placement
			(enabled no)
			(sheetname "")
		)
		(fill yes
			(thermal_gap 0.5)
			(thermal_bridge_width 0.5)
			(island_removal_mode 0)
		)
		(polygon
			(pts
				(arc
					(start 400.24177 -439.760614)
					(mid 400.264088 -439.814496)
					(end 400.31797 -439.836814)
				)
				(arc
					(start 401.25777 -439.836814)
					(mid 401.311652 -439.814496)
					(end 401.33397 -439.760614)
				)
				(arc
					(start 401.33397 -437.21909)
					(mid 401.311652 -437.165208)
					(end 401.25777 -437.14289)
				)
				(arc
					(start 400.31797 -437.14289)
					(mid 400.264088 -437.165208)
					(end 400.24177 -437.21909)
				)
			)
		)
	)
	(zone
		(layers "F.Cu" "In1.Cu" "In2.Cu" "In4.Cu" "In6.Cu" "In8.Cu" "In9.Cu" "In10.Cu"
			"In11.Cu" "In13.Cu" "In15.Cu"
		)
		(hatch none 0.5)
		(connect_pads
			(clearance 0)
		)
		(min_thickness 0.25)
		(keepout
			(tracks not_allowed)
			(vias allowed)
			(pads allowed)
			(copperpour not_allowed)
			(footprints allowed)
		)
		(placement
			(enabled no)
			(sheetname "")
		)
		(fill yes
			(thermal_gap 0.5)
			(thermal_bridge_width 0.5)
			(island_removal_mode 0)
		)
		(polygon
			(pts
				(arc
					(start 410.24175 -438.760616)
					(mid 410.264068 -438.814498)
					(end 410.31795 -438.836816)
				)
				(arc
					(start 411.25775 -438.836816)
					(mid 411.311632 -438.814498)
					(end 411.33395 -438.760616)
				)
				(arc
					(start 411.33395 -436.219092)
					(mid 411.311632 -436.16521)
					(end 411.25775 -436.142892)
				)
				(arc
					(start 410.31795 -436.142892)
					(mid 410.264068 -436.16521)
					(end 410.24175 -436.219092)
				)
			)
		)
	)
	(zone
		(layers "F.Cu" "In1.Cu" "In2.Cu" "In4.Cu" "In6.Cu" "In8.Cu" "In9.Cu" "In10.Cu"
			"In11.Cu" "In13.Cu" "In15.Cu"
		)
		(hatch none 0.5)
		(connect_pads
			(clearance 0)
		)
		(min_thickness 0.25)
		(keepout
			(tracks not_allowed)
			(vias allowed)
			(pads allowed)
			(copperpour not_allowed)
			(footprints allowed)
		)
		(placement
			(enabled no)
			(sheetname "")
		)
		(fill yes
			(thermal_gap 0.5)
			(thermal_bridge_width 0.5)
			(island_removal_mode 0)
		)
		(polygon
			(pts
				(arc
					(start 385.2418 -438.760616)
					(mid 385.264118 -438.814498)
					(end 385.318 -438.836816)
				)
				(arc
					(start 386.2578 -438.836816)
					(mid 386.311682 -438.814498)
					(end 386.334 -438.760616)
				)
				(arc
					(start 386.334 -436.219092)
					(mid 386.311682 -436.16521)
					(end 386.2578 -436.142892)
				)
				(arc
					(start 385.318 -436.142892)
					(mid 385.264118 -436.16521)
					(end 385.2418 -436.219092)
				)
			)
		)
	)
	(zone
		(layers "F.Cu" "In1.Cu" "In2.Cu" "In4.Cu" "In6.Cu" "In8.Cu" "In9.Cu" "In10.Cu"
			"In11.Cu" "In13.Cu" "In15.Cu"
		)
		(hatch none 0.5)
		(connect_pads
			(clearance 0)
		)
		(min_thickness 0.25)
		(keepout
			(tracks not_allowed)
			(vias allowed)
			(pads allowed)
			(copperpour not_allowed)
			(footprints allowed)
		)
		(placement
			(enabled no)
			(sheetname "")
		)
		(fill yes
			(thermal_gap 0.5)
			(thermal_bridge_width 0.5)
			(island_removal_mode 0)
		)
		(polygon
			(pts
				(arc
					(start 146.24177 -438.760616)
					(mid 146.264088 -438.814498)
					(end 146.31797 -438.836816)
				)
				(arc
					(start 147.25777 -438.836816)
					(mid 147.311652 -438.814498)
					(end 147.33397 -438.760616)
				)
				(arc
					(start 147.33397 -436.219092)
					(mid 147.311652 -436.16521)
					(end 147.25777 -436.142892)
				)
				(arc
					(start 146.31797 -436.142892)
					(mid 146.264088 -436.16521)
					(end 146.24177 -436.219092)
				)
			)
		)
	)
	(zone
		(layers "F.Cu" "In1.Cu" "In2.Cu" "In4.Cu" "In6.Cu" "In8.Cu" "In9.Cu" "In10.Cu"
			"In11.Cu" "In13.Cu" "In15.Cu"
		)
		(hatch none 0.5)
		(connect_pads
			(clearance 0)
		)
		(min_thickness 0.25)
		(keepout
			(tracks not_allowed)
			(vias allowed)
			(pads allowed)
			(copperpour not_allowed)
			(footprints allowed)
		)
		(placement
			(enabled no)
			(sheetname "")
		)
		(fill yes
			(thermal_gap 0.5)
			(thermal_bridge_width 0.5)
			(island_removal_mode 0)
		)
		(polygon
			(pts
				(arc
					(start 156.24175 -439.760614)
					(mid 156.264068 -439.814496)
					(end 156.31795 -439.836814)
				)
				(arc
					(start 157.25775 -439.836814)
					(mid 157.311632 -439.814496)
					(end 157.33395 -439.760614)
				)
				(arc
					(start 157.33395 -437.21909)
					(mid 157.311632 -437.165208)
					(end 157.25775 -437.14289)
				)
				(arc
					(start 156.31795 -437.14289)
					(mid 156.264068 -437.165208)
					(end 156.24175 -437.21909)
				)
			)
		)
	)
	(zone
		(layers "F.Cu" "In1.Cu" "In2.Cu" "In4.Cu" "In6.Cu" "In8.Cu" "In9.Cu" "In10.Cu"
			"In11.Cu" "In13.Cu" "In15.Cu"
		)
		(hatch none 0.5)
		(connect_pads
			(clearance 0)
		)
		(min_thickness 0.25)
		(keepout
			(tracks not_allowed)
			(vias allowed)
			(pads allowed)
			(copperpour not_allowed)
			(footprints allowed)
		)
		(placement
			(enabled no)
			(sheetname "")
		)
		(fill yes
			(thermal_gap 0.5)
			(thermal_bridge_width 0.5)
			(island_removal_mode 0)
		)
		(polygon
			(pts
				(arc
					(start 129.241804 -438.760616)
					(mid 129.264122 -438.814498)
					(end 129.318004 -438.836816)
				)
				(arc
					(start 130.257804 -438.836816)
					(mid 130.311686 -438.814498)
					(end 130.334004 -438.760616)
				)
				(arc
					(start 130.334004 -436.219092)
					(mid 130.311686 -436.16521)
					(end 130.257804 -436.142892)
				)
				(arc
					(start 129.318004 -436.142892)
					(mid 129.264122 -436.16521)
					(end 129.241804 -436.219092)
				)
			)
		)
	)
	(zone
		(layers "F.Cu" "In1.Cu" "In2.Cu" "In4.Cu" "In6.Cu" "In8.Cu" "In9.Cu" "In10.Cu"
			"In11.Cu" "In13.Cu" "In15.Cu"
		)
		(hatch none 0.5)
		(connect_pads
			(clearance 0)
		)
		(min_thickness 0.25)
		(keepout
			(tracks not_allowed)
			(vias allowed)
			(pads allowed)
			(copperpour not_allowed)
			(footprints allowed)
		)
		(placement
			(enabled no)
			(sheetname "")
		)
		(fill yes
			(thermal_gap 0.5)
			(thermal_bridge_width 0.5)
			(island_removal_mode 0)
		)
		(polygon
			(pts
				(arc
					(start 381.241808 -438.760616)
					(mid 381.264126 -438.814498)
					(end 381.318008 -438.836816)
				)
				(arc
					(start 382.257808 -438.836816)
					(mid 382.31169 -438.814498)
					(end 382.334008 -438.760616)
				)
				(arc
					(start 382.334008 -436.219092)
					(mid 382.31169 -436.16521)
					(end 382.257808 -436.142892)
				)
				(arc
					(start 381.318008 -436.142892)
					(mid 381.264126 -436.16521)
					(end 381.241808 -436.219092)
				)
			)
		)
	)
	(zone
		(layers "F.Cu" "In1.Cu" "In2.Cu" "In4.Cu" "In6.Cu" "In8.Cu" "In9.Cu" "In10.Cu"
			"In11.Cu" "In13.Cu" "In15.Cu"
		)
		(hatch none 0.5)
		(connect_pads
			(clearance 0)
		)
		(min_thickness 0.25)
		(keepout
			(tracks not_allowed)
			(vias allowed)
			(pads allowed)
			(copperpour not_allowed)
			(footprints allowed)
		)
		(placement
			(enabled no)
			(sheetname "")
		)
		(fill yes
			(thermal_gap 0.5)
			(thermal_bridge_width 0.5)
			(island_removal_mode 0)
		)
		(polygon
			(pts
				(arc
					(start 383.241804 -439.760614)
					(mid 383.264122 -439.814496)
					(end 383.318004 -439.836814)
				)
				(arc
					(start 384.257804 -439.836814)
					(mid 384.311686 -439.814496)
					(end 384.334004 -439.760614)
				)
				(arc
					(start 384.334004 -437.21909)
					(mid 384.311686 -437.165208)
					(end 384.257804 -437.14289)
				)
				(arc
					(start 383.318004 -437.14289)
					(mid 383.264122 -437.165208)
					(end 383.241804 -437.21909)
				)
			)
		)
	)
	(zone
		(layers "F.Cu" "In1.Cu" "In2.Cu" "In4.Cu" "In6.Cu" "In8.Cu" "In9.Cu" "In10.Cu"
			"In11.Cu" "In13.Cu" "In15.Cu"
		)
		(hatch none 0.5)
		(connect_pads
			(clearance 0)
		)
		(min_thickness 0.25)
		(keepout
			(tracks not_allowed)
			(vias allowed)
			(pads allowed)
			(copperpour not_allowed)
			(footprints allowed)
		)
		(placement
			(enabled no)
			(sheetname "")
		)
		(fill yes
			(thermal_gap 0.5)
			(thermal_bridge_width 0.5)
			(island_removal_mode 0)
		)
		(polygon
			(pts
				(arc
					(start 125.241812 -438.760616)
					(mid 125.26413 -438.814498)
					(end 125.318012 -438.836816)
				)
				(arc
					(start 126.257812 -438.836816)
					(mid 126.311694 -438.814498)
					(end 126.334012 -438.760616)
				)
				(arc
					(start 126.334012 -436.219092)
					(mid 126.311694 -436.16521)
					(end 126.257812 -436.142892)
				)
				(arc
					(start 125.318012 -436.142892)
					(mid 125.26413 -436.16521)
					(end 125.241812 -436.219092)
				)
			)
		)
	)
	(zone
		(layers "F.Cu" "In1.Cu" "In2.Cu" "In4.Cu" "In6.Cu" "In8.Cu" "In9.Cu" "In10.Cu"
			"In11.Cu" "In13.Cu" "In15.Cu"
		)
		(hatch none 0.5)
		(connect_pads
			(clearance 0)
		)
		(min_thickness 0.25)
		(keepout
			(tracks not_allowed)
			(vias allowed)
			(pads allowed)
			(copperpour not_allowed)
			(footprints allowed)
		)
		(placement
			(enabled no)
			(sheetname "")
		)
		(fill yes
			(thermal_gap 0.5)
			(thermal_bridge_width 0.5)
			(island_removal_mode 0)
		)
		(polygon
			(pts
				(arc
					(start 391.241788 -439.760614)
					(mid 391.264106 -439.814496)
					(end 391.317988 -439.836814)
				)
				(arc
					(start 392.257788 -439.836814)
					(mid 392.31167 -439.814496)
					(end 392.333988 -439.760614)
				)
				(arc
					(start 392.333988 -437.21909)
					(mid 392.31167 -437.165208)
					(end 392.257788 -437.14289)
				)
				(arc
					(start 391.317988 -437.14289)
					(mid 391.264106 -437.165208)
					(end 391.241788 -437.21909)
				)
			)
		)
	)
	(zone
		(layers "F.Cu" "In1.Cu" "In2.Cu" "In4.Cu" "In6.Cu" "In8.Cu" "In9.Cu" "In10.Cu"
			"In11.Cu" "In13.Cu" "In15.Cu"
		)
		(hatch none 0.5)
		(connect_pads
			(clearance 0)
		)
		(min_thickness 0.25)
		(keepout
			(tracks not_allowed)
			(vias allowed)
			(pads allowed)
			(copperpour not_allowed)
			(footprints allowed)
		)
		(placement
			(enabled no)
			(sheetname "")
		)
		(fill yes
			(thermal_gap 0.5)
			(thermal_bridge_width 0.5)
			(island_removal_mode 0)
		)
		(polygon
			(pts
				(arc
					(start 131.2418 -439.760614)
					(mid 131.264118 -439.814496)
					(end 131.318 -439.836814)
				)
				(arc
					(start 132.2578 -439.836814)
					(mid 132.311682 -439.814496)
					(end 132.334 -439.760614)
				)
				(arc
					(start 132.334 -437.21909)
					(mid 132.311682 -437.165208)
					(end 132.2578 -437.14289)
				)
				(arc
					(start 131.318 -437.14289)
					(mid 131.264118 -437.165208)
					(end 131.2418 -437.21909)
				)
			)
		)
	)
	(zone
		(layers "F.Cu" "In1.Cu" "In2.Cu" "In4.Cu" "In6.Cu" "In8.Cu" "In9.Cu" "In10.Cu"
			"In11.Cu" "In13.Cu" "In15.Cu"
		)
		(hatch none 0.5)
		(connect_pads
			(clearance 0)
		)
		(min_thickness 0.25)
		(keepout
			(tracks not_allowed)
			(vias allowed)
			(pads allowed)
			(copperpour not_allowed)
			(footprints allowed)
		)
		(placement
			(enabled no)
			(sheetname "")
		)
		(fill yes
			(thermal_gap 0.5)
			(thermal_bridge_width 0.5)
			(island_removal_mode 0)
		)
		(polygon
			(pts
				(arc
					(start 133.241796 -438.760616)
					(mid 133.264114 -438.814498)
					(end 133.317996 -438.836816)
				)
				(arc
					(start 134.257796 -438.836816)
					(mid 134.311678 -438.814498)
					(end 134.333996 -438.760616)
				)
				(arc
					(start 134.333996 -436.219092)
					(mid 134.311678 -436.16521)
					(end 134.257796 -436.142892)
				)
				(arc
					(start 133.317996 -436.142892)
					(mid 133.264114 -436.16521)
					(end 133.241796 -436.219092)
				)
			)
		)
	)
	(zone
		(layers "F.Cu" "In1.Cu" "In2.Cu" "In4.Cu" "In6.Cu" "In8.Cu" "In9.Cu" "In10.Cu"
			"In11.Cu" "In13.Cu" "In15.Cu"
		)
		(hatch none 0.5)
		(connect_pads
			(clearance 0)
		)
		(min_thickness 0.25)
		(keepout
			(tracks not_allowed)
			(vias allowed)
			(pads allowed)
			(copperpour not_allowed)
			(footprints allowed)
		)
		(placement
			(enabled no)
			(sheetname "")
		)
		(fill yes
			(thermal_gap 0.5)
			(thermal_bridge_width 0.5)
			(island_removal_mode 0)
		)
		(polygon
			(pts
				(arc
					(start 393.241784 -438.760616)
					(mid 393.264102 -438.814498)
					(end 393.317984 -438.836816)
				)
				(arc
					(start 394.257784 -438.836816)
					(mid 394.311666 -438.814498)
					(end 394.333984 -438.760616)
				)
				(arc
					(start 394.333984 -436.219092)
					(mid 394.311666 -436.16521)
					(end 394.257784 -436.142892)
				)
				(arc
					(start 393.317984 -436.142892)
					(mid 393.264102 -436.16521)
					(end 393.241784 -436.219092)
				)
			)
		)
	)
	(zone
		(layers "F.Cu" "In1.Cu" "In2.Cu" "In4.Cu" "In6.Cu" "In8.Cu" "In9.Cu" "In10.Cu"
			"In11.Cu" "In13.Cu" "In15.Cu"
		)
		(hatch none 0.5)
		(connect_pads
			(clearance 0)
		)
		(min_thickness 0.25)
		(keepout
			(tracks not_allowed)
			(vias allowed)
			(pads allowed)
			(copperpour not_allowed)
			(footprints allowed)
		)
		(placement
			(enabled no)
			(sheetname "")
		)
		(fill yes
			(thermal_gap 0.5)
			(thermal_bridge_width 0.5)
			(island_removal_mode 0)
		)
		(polygon
			(pts
				(arc
					(start 398.241774 -438.760616)
					(mid 398.264092 -438.814498)
					(end 398.317974 -438.836816)
				)
				(arc
					(start 399.257774 -438.836816)
					(mid 399.311656 -438.814498)
					(end 399.333974 -438.760616)
				)
				(arc
					(start 399.333974 -436.219092)
					(mid 399.311656 -436.16521)
					(end 399.257774 -436.142892)
				)
				(arc
					(start 398.317974 -436.142892)
					(mid 398.264092 -436.16521)
					(end 398.241774 -436.219092)
				)
			)
		)
	)
	(zone
		(layers "F.Cu" "In1.Cu" "In2.Cu" "In4.Cu" "In6.Cu" "In8.Cu" "In9.Cu" "In10.Cu"
			"In11.Cu" "In13.Cu" "In15.Cu"
		)
		(hatch none 0.5)
		(connect_pads
			(clearance 0)
		)
		(min_thickness 0.25)
		(keepout
			(tracks not_allowed)
			(vias allowed)
			(pads allowed)
			(copperpour not_allowed)
			(footprints allowed)
		)
		(placement
			(enabled no)
			(sheetname "")
		)
		(fill yes
			(thermal_gap 0.5)
			(thermal_bridge_width 0.5)
			(island_removal_mode 0)
		)
		(polygon
			(pts
				(arc
					(start 148.241766 -439.760614)
					(mid 148.264084 -439.814496)
					(end 148.317966 -439.836814)
				)
				(arc
					(start 149.257766 -439.836814)
					(mid 149.311648 -439.814496)
					(end 149.333966 -439.760614)
				)
				(arc
					(start 149.333966 -437.21909)
					(mid 149.311648 -437.165208)
					(end 149.257766 -437.14289)
				)
				(arc
					(start 148.317966 -437.14289)
					(mid 148.264084 -437.165208)
					(end 148.241766 -437.21909)
				)
			)
		)
	)
	(zone
		(layers "F.Cu" "In1.Cu" "In2.Cu" "In4.Cu" "In6.Cu" "In8.Cu" "In9.Cu" "In10.Cu"
			"In11.Cu" "In13.Cu" "In15.Cu"
		)
		(hatch none 0.5)
		(connect_pads
			(clearance 0)
		)
		(min_thickness 0.25)
		(keepout
			(tracks not_allowed)
			(vias allowed)
			(pads allowed)
			(copperpour not_allowed)
			(footprints allowed)
		)
		(placement
			(enabled no)
			(sheetname "")
		)
		(fill yes
			(thermal_gap 0.5)
			(thermal_bridge_width 0.5)
			(island_removal_mode 0)
		)
		(polygon
			(pts
				(arc
					(start 406.241758 -438.760616)
					(mid 406.264076 -438.814498)
					(end 406.317958 -438.836816)
				)
				(arc
					(start 407.257758 -438.836816)
					(mid 407.31164 -438.814498)
					(end 407.333958 -438.760616)
				)
				(arc
					(start 407.333958 -436.219092)
					(mid 407.31164 -436.16521)
					(end 407.257758 -436.142892)
				)
				(arc
					(start 406.317958 -436.142892)
					(mid 406.264076 -436.16521)
					(end 406.241758 -436.219092)
				)
			)
		)
	)
	(zone
		(layers "F.Cu" "In1.Cu" "In2.Cu" "In4.Cu" "In6.Cu" "In8.Cu" "In9.Cu" "In10.Cu"
			"In11.Cu" "In13.Cu" "In15.Cu"
		)
		(hatch none 0.5)
		(connect_pads
			(clearance 0)
		)
		(min_thickness 0.25)
		(keepout
			(tracks not_allowed)
			(vias allowed)
			(pads allowed)
			(copperpour not_allowed)
			(footprints allowed)
		)
		(placement
			(enabled no)
			(sheetname "")
		)
		(fill yes
			(thermal_gap 0.5)
			(thermal_bridge_width 0.5)
			(island_removal_mode 0)
		)
		(polygon
			(pts
				(arc
					(start 137.241788 -438.760616)
					(mid 137.264106 -438.814498)
					(end 137.317988 -438.836816)
				)
				(arc
					(start 138.257788 -438.836816)
					(mid 138.31167 -438.814498)
					(end 138.333988 -438.760616)
				)
				(arc
					(start 138.333988 -436.219092)
					(mid 138.31167 -436.16521)
					(end 138.257788 -436.142892)
				)
				(arc
					(start 137.317988 -436.142892)
					(mid 137.264106 -436.16521)
					(end 137.241788 -436.219092)
				)
			)
		)
	)
	(zone
		(layers "F.Cu" "In1.Cu" "In2.Cu" "In4.Cu" "In6.Cu" "In8.Cu" "In9.Cu" "In10.Cu"
			"In11.Cu" "In13.Cu" "In15.Cu"
		)
		(hatch none 0.5)
		(connect_pads
			(clearance 0)
		)
		(min_thickness 0.25)
		(keepout
			(tracks not_allowed)
			(vias allowed)
			(pads allowed)
			(copperpour not_allowed)
			(footprints allowed)
		)
		(placement
			(enabled no)
			(sheetname "")
		)
		(fill yes
			(thermal_gap 0.5)
			(thermal_bridge_width 0.5)
			(island_removal_mode 0)
		)
		(polygon
			(pts
				(arc
					(start 139.241784 -439.760614)
					(mid 139.264102 -439.814496)
					(end 139.317984 -439.836814)
				)
				(arc
					(start 140.257784 -439.836814)
					(mid 140.311666 -439.814496)
					(end 140.333984 -439.760614)
				)
				(arc
					(start 140.333984 -437.21909)
					(mid 140.311666 -437.165208)
					(end 140.257784 -437.14289)
				)
				(arc
					(start 139.317984 -437.14289)
					(mid 139.264102 -437.165208)
					(end 139.241784 -437.21909)
				)
			)
		)
	)
	(zone
		(layers "F.Cu" "In1.Cu" "In2.Cu" "In4.Cu" "In6.Cu" "In8.Cu" "In9.Cu" "In10.Cu"
			"In11.Cu" "In13.Cu" "In15.Cu"
		)
		(hatch none 0.5)
		(connect_pads
			(clearance 0)
		)
		(min_thickness 0.25)
		(keepout
			(tracks not_allowed)
			(vias allowed)
			(pads allowed)
			(copperpour not_allowed)
			(footprints allowed)
		)
		(placement
			(enabled no)
			(sheetname "")
		)
		(fill yes
			(thermal_gap 0.5)
			(thermal_bridge_width 0.5)
			(island_removal_mode 0)
		)
		(polygon
			(pts
				(arc
					(start 395.24178 -439.760614)
					(mid 395.264098 -439.814496)
					(end 395.31798 -439.836814)
				)
				(arc
					(start 396.25778 -439.836814)
					(mid 396.311662 -439.814496)
					(end 396.33398 -439.760614)
				)
				(arc
					(start 396.33398 -437.21909)
					(mid 396.311662 -437.165208)
					(end 396.25778 -437.14289)
				)
				(arc
					(start 395.31798 -437.14289)
					(mid 395.264098 -437.165208)
					(end 395.24178 -437.21909)
				)
			)
		)
	)
	(zone
		(layers "F.Cu" "In1.Cu" "In2.Cu" "In4.Cu" "In6.Cu" "In8.Cu" "In9.Cu" "In10.Cu"
			"In11.Cu" "In13.Cu" "In15.Cu"
		)
		(hatch none 0.5)
		(connect_pads
			(clearance 0)
		)
		(min_thickness 0.25)
		(keepout
			(tracks not_allowed)
			(vias allowed)
			(pads allowed)
			(copperpour not_allowed)
			(footprints allowed)
		)
		(placement
			(enabled no)
			(sheetname "")
		)
		(fill yes
			(thermal_gap 0.5)
			(thermal_bridge_width 0.5)
			(island_removal_mode 0)
		)
		(polygon
			(pts
				(arc
					(start 389.241792 -438.760616)
					(mid 389.26411 -438.814498)
					(end 389.317992 -438.836816)
				)
				(arc
					(start 390.257792 -438.836816)
					(mid 390.311674 -438.814498)
					(end 390.333992 -438.760616)
				)
				(arc
					(start 390.333992 -436.219092)
					(mid 390.311674 -436.16521)
					(end 390.257792 -436.142892)
				)
				(arc
					(start 389.317992 -436.142892)
					(mid 389.26411 -436.16521)
					(end 389.241792 -436.219092)
				)
			)
		)
	)
	(zone
		(layers "F.Cu" "In1.Cu" "In2.Cu" "In4.Cu" "In6.Cu" "In8.Cu" "In9.Cu" "In10.Cu"
			"In11.Cu" "In13.Cu" "In15.Cu"
		)
		(hatch none 0.5)
		(connect_pads
			(clearance 0)
		)
		(min_thickness 0.25)
		(keepout
			(tracks not_allowed)
			(vias allowed)
			(pads allowed)
			(copperpour not_allowed)
			(footprints allowed)
		)
		(placement
			(enabled no)
			(sheetname "")
		)
		(fill yes
			(thermal_gap 0.5)
			(thermal_bridge_width 0.5)
			(island_removal_mode 0)
		)
		(polygon
			(pts
				(arc
					(start 142.241778 -438.760616)
					(mid 142.264096 -438.814498)
					(end 142.317978 -438.836816)
				)
				(arc
					(start 143.257778 -438.836816)
					(mid 143.31166 -438.814498)
					(end 143.333978 -438.760616)
				)
				(arc
					(start 143.333978 -436.219092)
					(mid 143.31166 -436.16521)
					(end 143.257778 -436.142892)
				)
				(arc
					(start 142.317978 -436.142892)
					(mid 142.264096 -436.16521)
					(end 142.241778 -436.219092)
				)
			)
		)
	)
	(zone
		(layers "F.Cu" "In1.Cu" "In2.Cu" "In4.Cu" "In6.Cu" "In8.Cu" "In9.Cu" "In10.Cu"
			"In11.Cu" "In13.Cu" "In15.Cu"
		)
		(hatch none 0.5)
		(connect_pads
			(clearance 0)
		)
		(min_thickness 0.25)
		(keepout
			(tracks not_allowed)
			(vias allowed)
			(pads allowed)
			(copperpour not_allowed)
			(footprints allowed)
		)
		(placement
			(enabled no)
			(sheetname "")
		)
		(fill yes
			(thermal_gap 0.5)
			(thermal_bridge_width 0.5)
			(island_removal_mode 0)
		)
		(polygon
			(pts
				(arc
					(start 127.241808 -439.760614)
					(mid 127.264126 -439.814496)
					(end 127.318008 -439.836814)
				)
				(arc
					(start 128.257808 -439.836814)
					(mid 128.31169 -439.814496)
					(end 128.334008 -439.760614)
				)
				(arc
					(start 128.334008 -437.21909)
					(mid 128.31169 -437.165208)
					(end 128.257808 -437.14289)
				)
				(arc
					(start 127.318008 -437.14289)
					(mid 127.264126 -437.165208)
					(end 127.241808 -437.21909)
				)
			)
		)
	)
	(zone
		(layers "F.Cu" "In1.Cu" "In2.Cu" "In4.Cu" "In6.Cu" "In8.Cu" "In9.Cu" "In10.Cu"
			"In11.Cu" "In13.Cu" "In15.Cu"
		)
		(hatch none 0.5)
		(connect_pads
			(clearance 0)
		)
		(min_thickness 0.25)
		(keepout
			(tracks not_allowed)
			(vias allowed)
			(pads allowed)
			(copperpour not_allowed)
			(footprints allowed)
		)
		(placement
			(enabled no)
			(sheetname "")
		)
		(fill yes
			(thermal_gap 0.5)
			(thermal_bridge_width 0.5)
			(island_removal_mode 0)
		)
		(polygon
			(pts
				(arc
					(start 152.241758 -439.760614)
					(mid 152.264076 -439.814496)
					(end 152.317958 -439.836814)
				)
				(arc
					(start 153.257758 -439.836814)
					(mid 153.31164 -439.814496)
					(end 153.333958 -439.760614)
				)
				(arc
					(start 153.333958 -437.21909)
					(mid 153.31164 -437.165208)
					(end 153.257758 -437.14289)
				)
				(arc
					(start 152.317958 -437.14289)
					(mid 152.264076 -437.165208)
					(end 152.241758 -437.21909)
				)
			)
		)
	)
	(zone
		(layers "F.Cu" "In1.Cu" "In2.Cu" "In4.Cu" "In6.Cu" "In8.Cu" "In9.Cu" "In10.Cu"
			"In12.Cu" "In13.Cu" "In14.Cu" "In15.Cu" "In16.Cu"
		)
		(hatch none 0.5)
		(connect_pads
			(clearance 0)
		)
		(min_thickness 0.25)
		(keepout
			(tracks not_allowed)
			(vias allowed)
			(pads allowed)
			(copperpour not_allowed)
			(footprints allowed)
		)
		(placement
			(enabled no)
			(sheetname "")
		)
		(fill yes
			(thermal_gap 0.5)
			(thermal_bridge_width 0.5)
			(island_removal_mode 0)
		)
		(polygon
			(pts
				(arc
					(start 328.141838 -428.960534)
					(mid 328.164156 -429.014416)
					(end 328.218038 -429.036734)
				)
				(arc
					(start 329.157838 -429.036734)
					(mid 329.21172 -429.014416)
					(end 329.234038 -428.960534)
				)
				(arc
					(start 329.234038 -426.41901)
					(mid 329.21172 -426.365128)
					(end 329.157838 -426.34281)
				)
				(arc
					(start 328.218038 -426.34281)
					(mid 328.164156 -426.365128)
					(end 328.141838 -426.41901)
				)
			)
		)
	)
	(zone
		(layers "F.Cu" "In1.Cu" "In2.Cu" "In4.Cu" "In6.Cu" "In8.Cu" "In9.Cu" "In10.Cu"
			"In12.Cu" "In13.Cu" "In14.Cu" "In15.Cu" "In16.Cu"
		)
		(hatch none 0.5)
		(connect_pads
			(clearance 0)
		)
		(min_thickness 0.25)
		(keepout
			(tracks not_allowed)
			(vias allowed)
			(pads allowed)
			(copperpour not_allowed)
			(footprints allowed)
		)
		(placement
			(enabled no)
			(sheetname "")
		)
		(fill yes
			(thermal_gap 0.5)
			(thermal_bridge_width 0.5)
			(island_removal_mode 0)
		)
		(polygon
			(pts
				(arc
					(start 337.14182 -428.960534)
					(mid 337.164138 -429.014416)
					(end 337.21802 -429.036734)
				)
				(arc
					(start 338.15782 -429.036734)
					(mid 338.211702 -429.014416)
					(end 338.23402 -428.960534)
				)
				(arc
					(start 338.23402 -426.41901)
					(mid 338.211702 -426.365128)
					(end 338.15782 -426.34281)
				)
				(arc
					(start 337.21802 -426.34281)
					(mid 337.164138 -426.365128)
					(end 337.14182 -426.41901)
				)
			)
		)
	)
	(zone
		(layers "F.Cu" "In1.Cu" "In2.Cu" "In4.Cu" "In6.Cu" "In8.Cu" "In9.Cu" "In10.Cu"
			"In12.Cu" "In13.Cu" "In14.Cu" "In15.Cu" "In16.Cu"
		)
		(hatch none 0.5)
		(connect_pads
			(clearance 0)
		)
		(min_thickness 0.25)
		(keepout
			(tracks not_allowed)
			(vias allowed)
			(pads allowed)
			(copperpour not_allowed)
			(footprints allowed)
		)
		(placement
			(enabled no)
			(sheetname "")
		)
		(fill yes
			(thermal_gap 0.5)
			(thermal_bridge_width 0.5)
			(island_removal_mode 0)
		)
		(polygon
			(pts
				(arc
					(start 320.141854 -428.960534)
					(mid 320.164172 -429.014416)
					(end 320.218054 -429.036734)
				)
				(arc
					(start 321.157854 -429.036734)
					(mid 321.211736 -429.014416)
					(end 321.234054 -428.960534)
				)
				(arc
					(start 321.234054 -426.41901)
					(mid 321.211736 -426.365128)
					(end 321.157854 -426.34281)
				)
				(arc
					(start 320.218054 -426.34281)
					(mid 320.164172 -426.365128)
					(end 320.141854 -426.41901)
				)
			)
		)
	)
	(zone
		(layers "F.Cu" "In1.Cu" "In2.Cu" "In4.Cu" "In6.Cu" "In8.Cu" "In9.Cu" "In10.Cu"
			"In12.Cu" "In13.Cu" "In14.Cu" "In15.Cu" "In16.Cu"
		)
		(hatch none 0.5)
		(connect_pads
			(clearance 0)
		)
		(min_thickness 0.25)
		(keepout
			(tracks not_allowed)
			(vias allowed)
			(pads allowed)
			(copperpour not_allowed)
			(footprints allowed)
		)
		(placement
			(enabled no)
			(sheetname "")
		)
		(fill yes
			(thermal_gap 0.5)
			(thermal_bridge_width 0.5)
			(island_removal_mode 0)
		)
		(polygon
			(pts
				(arc
					(start 345.141804 -428.960534)
					(mid 345.164122 -429.014416)
					(end 345.218004 -429.036734)
				)
				(arc
					(start 346.157804 -429.036734)
					(mid 346.211686 -429.014416)
					(end 346.234004 -428.960534)
				)
				(arc
					(start 346.234004 -426.41901)
					(mid 346.211686 -426.365128)
					(end 346.157804 -426.34281)
				)
				(arc
					(start 345.218004 -426.34281)
					(mid 345.164122 -426.365128)
					(end 345.141804 -426.41901)
				)
			)
		)
	)
	(zone
		(layers "F.Cu" "In1.Cu" "In2.Cu" "In4.Cu" "In6.Cu" "In8.Cu" "In9.Cu" "In10.Cu"
			"In12.Cu" "In13.Cu" "In14.Cu" "In15.Cu" "In16.Cu"
		)
		(hatch none 0.5)
		(connect_pads
			(clearance 0)
		)
		(min_thickness 0.25)
		(keepout
			(tracks not_allowed)
			(vias allowed)
			(pads allowed)
			(copperpour not_allowed)
			(footprints allowed)
		)
		(placement
			(enabled no)
			(sheetname "")
		)
		(fill yes
			(thermal_gap 0.5)
			(thermal_bridge_width 0.5)
			(island_removal_mode 0)
		)
		(polygon
			(pts
				(arc
					(start 333.141828 -428.960534)
					(mid 333.164146 -429.014416)
					(end 333.218028 -429.036734)
				)
				(arc
					(start 334.157828 -429.036734)
					(mid 334.21171 -429.014416)
					(end 334.234028 -428.960534)
				)
				(arc
					(start 334.234028 -426.41901)
					(mid 334.21171 -426.365128)
					(end 334.157828 -426.34281)
				)
				(arc
					(start 333.218028 -426.34281)
					(mid 333.164146 -426.365128)
					(end 333.141828 -426.41901)
				)
			)
		)
	)
	(zone
		(layers "F.Cu" "In1.Cu" "In2.Cu" "In4.Cu" "In6.Cu" "In8.Cu" "In9.Cu" "In10.Cu"
			"In12.Cu" "In13.Cu" "In14.Cu" "In15.Cu" "In16.Cu"
		)
		(hatch none 0.5)
		(connect_pads
			(clearance 0)
		)
		(min_thickness 0.25)
		(keepout
			(tracks not_allowed)
			(vias allowed)
			(pads allowed)
			(copperpour not_allowed)
			(footprints allowed)
		)
		(placement
			(enabled no)
			(sheetname "")
		)
		(fill yes
			(thermal_gap 0.5)
			(thermal_bridge_width 0.5)
			(island_removal_mode 0)
		)
		(polygon
			(pts
				(arc
					(start 324.141846 -428.960534)
					(mid 324.164164 -429.014416)
					(end 324.218046 -429.036734)
				)
				(arc
					(start 325.157846 -429.036734)
					(mid 325.211728 -429.014416)
					(end 325.234046 -428.960534)
				)
				(arc
					(start 325.234046 -426.41901)
					(mid 325.211728 -426.365128)
					(end 325.157846 -426.34281)
				)
				(arc
					(start 324.218046 -426.34281)
					(mid 324.164164 -426.365128)
					(end 324.141846 -426.41901)
				)
			)
		)
	)
	(zone
		(layers "F.Cu" "In1.Cu" "In2.Cu" "In4.Cu" "In6.Cu" "In8.Cu" "In9.Cu" "In10.Cu"
			"In12.Cu" "In13.Cu" "In14.Cu" "In15.Cu" "In16.Cu"
		)
		(hatch none 0.5)
		(connect_pads
			(clearance 0)
		)
		(min_thickness 0.25)
		(keepout
			(tracks not_allowed)
			(vias allowed)
			(pads allowed)
			(copperpour not_allowed)
			(footprints allowed)
		)
		(placement
			(enabled no)
			(sheetname "")
		)
		(fill yes
			(thermal_gap 0.5)
			(thermal_bridge_width 0.5)
			(island_removal_mode 0)
		)
		(polygon
			(pts
				(arc
					(start 316.141862 -428.960534)
					(mid 316.16418 -429.014416)
					(end 316.218062 -429.036734)
				)
				(arc
					(start 317.157862 -429.036734)
					(mid 317.211744 -429.014416)
					(end 317.234062 -428.960534)
				)
				(arc
					(start 317.234062 -426.41901)
					(mid 317.211744 -426.365128)
					(end 317.157862 -426.34281)
				)
				(arc
					(start 316.218062 -426.34281)
					(mid 316.16418 -426.365128)
					(end 316.141862 -426.41901)
				)
			)
		)
	)
	(zone
		(layers "F.Cu" "In1.Cu" "In2.Cu" "In4.Cu" "In6.Cu" "In8.Cu" "In9.Cu" "In10.Cu"
			"In12.Cu" "In13.Cu" "In14.Cu" "In15.Cu" "In16.Cu"
		)
		(hatch none 0.5)
		(connect_pads
			(clearance 0)
		)
		(min_thickness 0.25)
		(keepout
			(tracks not_allowed)
			(vias allowed)
			(pads allowed)
			(copperpour not_allowed)
			(footprints allowed)
		)
		(placement
			(enabled no)
			(sheetname "")
		)
		(fill yes
			(thermal_gap 0.5)
			(thermal_bridge_width 0.5)
			(island_removal_mode 0)
		)
		(polygon
			(pts
				(arc
					(start 341.141812 -428.960534)
					(mid 341.16413 -429.014416)
					(end 341.218012 -429.036734)
				)
				(arc
					(start 342.157812 -429.036734)
					(mid 342.211694 -429.014416)
					(end 342.234012 -428.960534)
				)
				(arc
					(start 342.234012 -426.41901)
					(mid 342.211694 -426.365128)
					(end 342.157812 -426.34281)
				)
				(arc
					(start 341.218012 -426.34281)
					(mid 341.16413 -426.365128)
					(end 341.141812 -426.41901)
				)
			)
		)
	)
	(zone
		(layers "F.Cu" "In2.Cu")
		(hatch none 0.5)
		(connect_pads
			(clearance 0)
		)
		(min_thickness 0.25)
		(keepout
			(tracks not_allowed)
			(vias allowed)
			(pads allowed)
			(copperpour not_allowed)
			(footprints allowed)
		)
		(placement
			(enabled no)
			(sheetname "")
		)
		(fill yes
			(thermal_gap 0.5)
			(thermal_bridge_width 0.5)
			(island_removal_mode 0)
		)
		(polygon
			(pts
				(arc
					(start 78.37678 -418.3761)
					(mid 77.70876 -418.3761)
					(end 78.37678 -418.3761)
				)
			)
		)
	)
	(zone
		(layers "F.Cu" "In2.Cu")
		(hatch none 0.5)
		(connect_pads
			(clearance 0)
		)
		(min_thickness 0.25)
		(keepout
			(tracks not_allowed)
			(vias allowed)
			(pads allowed)
			(copperpour not_allowed)
			(footprints allowed)
		)
		(placement
			(enabled no)
			(sheetname "")
		)
		(fill yes
			(thermal_gap 0.5)
			(thermal_bridge_width 0.5)
			(island_removal_mode 0)
		)
		(polygon
			(pts
				(arc
					(start 75.854052 -420.058088)
					(mid 75.186032 -420.058088)
					(end 75.854052 -420.058088)
				)
			)
		)
	)
	(zone
		(layers "F.Cu" "In2.Cu")
		(hatch none 0.5)
		(connect_pads
			(clearance 0)
		)
		(min_thickness 0.25)
		(keepout
			(tracks not_allowed)
			(vias allowed)
			(pads allowed)
			(copperpour not_allowed)
			(footprints allowed)
		)
		(placement
			(enabled no)
			(sheetname "")
		)
		(fill yes
			(thermal_gap 0.5)
			(thermal_bridge_width 0.5)
			(island_removal_mode 0)
		)
		(polygon
			(pts
				(arc
					(start 438.037224 -244.08511)
					(mid 437.369204 -244.08511)
					(end 438.037224 -244.08511)
				)
			)
		)
	)
	(zone
		(layers "F.Cu" "In2.Cu")
		(hatch none 0.5)
		(connect_pads
			(clearance 0)
		)
		(min_thickness 0.25)
		(keepout
			(tracks not_allowed)
			(vias allowed)
			(pads allowed)
			(copperpour not_allowed)
			(footprints allowed)
		)
		(placement
			(enabled no)
			(sheetname "")
		)
		(fill yes
			(thermal_gap 0.5)
			(thermal_bridge_width 0.5)
			(island_removal_mode 0)
		)
		(polygon
			(pts
				(arc
					(start 38.526974 -244.085364)
					(mid 37.858954 -244.085364)
					(end 38.526974 -244.085364)
				)
			)
		)
	)
	(zone
		(layers "F.Cu" "In2.Cu")
		(hatch none 0.5)
		(connect_pads
			(clearance 0)
		)
		(min_thickness 0.25)
		(keepout
			(tracks not_allowed)
			(vias allowed)
			(pads allowed)
			(copperpour not_allowed)
			(footprints allowed)
		)
		(placement
			(enabled no)
			(sheetname "")
		)
		(fill yes
			(thermal_gap 0.5)
			(thermal_bridge_width 0.5)
			(island_removal_mode 0)
		)
		(polygon
			(pts
				(arc
					(start 78.37678 -417.5125)
					(mid 77.70876 -417.5125)
					(end 78.37678 -417.5125)
				)
			)
		)
	)
	(zone
		(layers "F.Cu" "In2.Cu")
		(hatch none 0.5)
		(connect_pads
			(clearance 0)
		)
		(min_thickness 0.25)
		(keepout
			(tracks not_allowed)
			(vias allowed)
			(pads allowed)
			(copperpour not_allowed)
			(footprints allowed)
		)
		(placement
			(enabled no)
			(sheetname "")
		)
		(fill yes
			(thermal_gap 0.5)
			(thermal_bridge_width 0.5)
			(island_removal_mode 0)
		)
		(polygon
			(pts
				(arc
					(start 190.097156 -244.085364)
					(mid 189.429136 -244.085364)
					(end 190.097156 -244.085364)
				)
			)
		)
	)
	(zone
		(layers "F.Cu" "In2.Cu")
		(hatch none 0.5)
		(connect_pads
			(clearance 0)
		)
		(min_thickness 0.25)
		(keepout
			(tracks not_allowed)
			(vias allowed)
			(pads allowed)
			(copperpour not_allowed)
			(footprints allowed)
		)
		(placement
			(enabled no)
			(sheetname "")
		)
		(fill yes
			(thermal_gap 0.5)
			(thermal_bridge_width 0.5)
			(island_removal_mode 0)
		)
		(polygon
			(pts
				(arc
					(start 286.467042 -244.08511)
					(mid 285.799022 -244.08511)
					(end 286.467042 -244.08511)
				)
			)
		)
	)
	(zone
		(layers "F.Cu" "In2.Cu")
		(hatch none 0.5)
		(connect_pads
			(clearance 0)
		)
		(min_thickness 0.25)
		(keepout
			(tracks not_allowed)
			(vias allowed)
			(pads allowed)
			(copperpour not_allowed)
			(footprints allowed)
		)
		(placement
			(enabled no)
			(sheetname "")
		)
		(fill yes
			(thermal_gap 0.5)
			(thermal_bridge_width 0.5)
			(island_removal_mode 0)
		)
		(polygon
			(pts
				(arc
					(start 75.854052 -420.921688)
					(mid 75.186032 -420.921688)
					(end 75.854052 -420.921688)
				)
			)
		)
	)
	(zone
		(layers "F.Cu" "In2.Cu" "In3.Cu" "In4.Cu" "In5.Cu" "In6.Cu" "In11.Cu" "In13.Cu"
			"In15.Cu"
		)
		(hatch none 0.5)
		(connect_pads
			(clearance 0)
		)
		(min_thickness 0.25)
		(keepout
			(tracks not_allowed)
			(vias allowed)
			(pads allowed)
			(copperpour not_allowed)
			(footprints allowed)
		)
		(placement
			(enabled no)
			(sheetname "")
		)
		(fill yes
			(thermal_gap 0.5)
			(thermal_bridge_width 0.5)
			(island_removal_mode 0)
		)
		(polygon
			(pts
				(arc
					(start 322.14185 -435.160674)
					(mid 322.164168 -435.214556)
					(end 322.21805 -435.236874)
				)
				(arc
					(start 323.15785 -435.236874)
					(mid 323.211732 -435.214556)
					(end 323.23405 -435.160674)
				)
				(arc
					(start 323.23405 -432.61915)
					(mid 323.211732 -432.565268)
					(end 323.15785 -432.54295)
				)
				(arc
					(start 322.21805 -432.54295)
					(mid 322.164168 -432.565268)
					(end 322.14185 -432.61915)
				)
			)
		)
	)
	(zone
		(layers "F.Cu" "In2.Cu" "In3.Cu" "In4.Cu" "In5.Cu" "In6.Cu" "In11.Cu" "In13.Cu"
			"In15.Cu"
		)
		(hatch none 0.5)
		(connect_pads
			(clearance 0)
		)
		(min_thickness 0.25)
		(keepout
			(tracks not_allowed)
			(vias allowed)
			(pads allowed)
			(copperpour not_allowed)
			(footprints allowed)
		)
		(placement
			(enabled no)
			(sheetname "")
		)
		(fill yes
			(thermal_gap 0.5)
			(thermal_bridge_width 0.5)
			(island_removal_mode 0)
		)
		(polygon
			(pts
				(arc
					(start 314.141866 -435.160674)
					(mid 314.164184 -435.214556)
					(end 314.218066 -435.236874)
				)
				(arc
					(start 315.157866 -435.236874)
					(mid 315.211748 -435.214556)
					(end 315.234066 -435.160674)
				)
				(arc
					(start 315.234066 -432.61915)
					(mid 315.211748 -432.565268)
					(end 315.157866 -432.54295)
				)
				(arc
					(start 314.218066 -432.54295)
					(mid 314.164184 -432.565268)
					(end 314.141866 -432.61915)
				)
			)
		)
	)
	(zone
		(layers "F.Cu" "In2.Cu" "In3.Cu" "In4.Cu" "In5.Cu" "In6.Cu" "In11.Cu" "In13.Cu"
			"In15.Cu"
		)
		(hatch none 0.5)
		(connect_pads
			(clearance 0)
		)
		(min_thickness 0.25)
		(keepout
			(tracks not_allowed)
			(vias allowed)
			(pads allowed)
			(copperpour not_allowed)
			(footprints allowed)
		)
		(placement
			(enabled no)
			(sheetname "")
		)
		(fill yes
			(thermal_gap 0.5)
			(thermal_bridge_width 0.5)
			(island_removal_mode 0)
		)
		(polygon
			(pts
				(arc
					(start 328.141838 -436.160672)
					(mid 328.164156 -436.214554)
					(end 328.218038 -436.236872)
				)
				(arc
					(start 329.157838 -436.236872)
					(mid 329.21172 -436.214554)
					(end 329.234038 -436.160672)
				)
				(arc
					(start 329.234038 -433.619148)
					(mid 329.21172 -433.565266)
					(end 329.157838 -433.542948)
				)
				(arc
					(start 328.218038 -433.542948)
					(mid 328.164156 -433.565266)
					(end 328.141838 -433.619148)
				)
			)
		)
	)
	(zone
		(layers "F.Cu" "In2.Cu" "In3.Cu" "In4.Cu" "In5.Cu" "In6.Cu" "In11.Cu" "In13.Cu"
			"In15.Cu"
		)
		(hatch none 0.5)
		(connect_pads
			(clearance 0)
		)
		(min_thickness 0.25)
		(keepout
			(tracks not_allowed)
			(vias allowed)
			(pads allowed)
			(copperpour not_allowed)
			(footprints allowed)
		)
		(placement
			(enabled no)
			(sheetname "")
		)
		(fill yes
			(thermal_gap 0.5)
			(thermal_bridge_width 0.5)
			(island_removal_mode 0)
		)
		(polygon
			(pts
				(arc
					(start 316.141862 -436.160672)
					(mid 316.16418 -436.214554)
					(end 316.218062 -436.236872)
				)
				(arc
					(start 317.157862 -436.236872)
					(mid 317.211744 -436.214554)
					(end 317.234062 -436.160672)
				)
				(arc
					(start 317.234062 -433.619148)
					(mid 317.211744 -433.565266)
					(end 317.157862 -433.542948)
				)
				(arc
					(start 316.218062 -433.542948)
					(mid 316.16418 -433.565266)
					(end 316.141862 -433.619148)
				)
			)
		)
	)
	(zone
		(layers "F.Cu" "In2.Cu" "In3.Cu" "In4.Cu" "In5.Cu" "In6.Cu" "In11.Cu" "In13.Cu"
			"In15.Cu"
		)
		(hatch none 0.5)
		(connect_pads
			(clearance 0)
		)
		(min_thickness 0.25)
		(keepout
			(tracks not_allowed)
			(vias allowed)
			(pads allowed)
			(copperpour not_allowed)
			(footprints allowed)
		)
		(placement
			(enabled no)
			(sheetname "")
		)
		(fill yes
			(thermal_gap 0.5)
			(thermal_bridge_width 0.5)
			(island_removal_mode 0)
		)
		(polygon
			(pts
				(arc
					(start 318.141858 -435.160674)
					(mid 318.164176 -435.214556)
					(end 318.218058 -435.236874)
				)
				(arc
					(start 319.157858 -435.236874)
					(mid 319.21174 -435.214556)
					(end 319.234058 -435.160674)
				)
				(arc
					(start 319.234058 -432.61915)
					(mid 319.21174 -432.565268)
					(end 319.157858 -432.54295)
				)
				(arc
					(start 318.218058 -432.54295)
					(mid 318.164176 -432.565268)
					(end 318.141858 -432.61915)
				)
			)
		)
	)
	(zone
		(layers "F.Cu" "In2.Cu" "In3.Cu" "In4.Cu" "In5.Cu" "In6.Cu" "In11.Cu" "In13.Cu"
			"In15.Cu"
		)
		(hatch none 0.5)
		(connect_pads
			(clearance 0)
		)
		(min_thickness 0.25)
		(keepout
			(tracks not_allowed)
			(vias allowed)
			(pads allowed)
			(copperpour not_allowed)
			(footprints allowed)
		)
		(placement
			(enabled no)
			(sheetname "")
		)
		(fill yes
			(thermal_gap 0.5)
			(thermal_bridge_width 0.5)
			(island_removal_mode 0)
		)
		(polygon
			(pts
				(arc
					(start 337.14182 -436.160672)
					(mid 337.164138 -436.214554)
					(end 337.21802 -436.236872)
				)
				(arc
					(start 338.15782 -436.236872)
					(mid 338.211702 -436.214554)
					(end 338.23402 -436.160672)
				)
				(arc
					(start 338.23402 -433.619148)
					(mid 338.211702 -433.565266)
					(end 338.15782 -433.542948)
				)
				(arc
					(start 337.21802 -433.542948)
					(mid 337.164138 -433.565266)
					(end 337.14182 -433.619148)
				)
			)
		)
	)
	(zone
		(layers "F.Cu" "In2.Cu" "In3.Cu" "In4.Cu" "In5.Cu" "In6.Cu" "In11.Cu" "In13.Cu"
			"In15.Cu"
		)
		(hatch none 0.5)
		(connect_pads
			(clearance 0)
		)
		(min_thickness 0.25)
		(keepout
			(tracks not_allowed)
			(vias allowed)
			(pads allowed)
			(copperpour not_allowed)
			(footprints allowed)
		)
		(placement
			(enabled no)
			(sheetname "")
		)
		(fill yes
			(thermal_gap 0.5)
			(thermal_bridge_width 0.5)
			(island_removal_mode 0)
		)
		(polygon
			(pts
				(arc
					(start 345.141804 -436.160672)
					(mid 345.164122 -436.214554)
					(end 345.218004 -436.236872)
				)
				(arc
					(start 346.157804 -436.236872)
					(mid 346.211686 -436.214554)
					(end 346.234004 -436.160672)
				)
				(arc
					(start 346.234004 -433.619148)
					(mid 346.211686 -433.565266)
					(end 346.157804 -433.542948)
				)
				(arc
					(start 345.218004 -433.542948)
					(mid 345.164122 -433.565266)
					(end 345.141804 -433.619148)
				)
			)
		)
	)
	(zone
		(layers "F.Cu" "In2.Cu" "In3.Cu" "In4.Cu" "In5.Cu" "In6.Cu" "In11.Cu" "In13.Cu"
			"In15.Cu"
		)
		(hatch none 0.5)
		(connect_pads
			(clearance 0)
		)
		(min_thickness 0.25)
		(keepout
			(tracks not_allowed)
			(vias allowed)
			(pads allowed)
			(copperpour not_allowed)
			(footprints allowed)
		)
		(placement
			(enabled no)
			(sheetname "")
		)
		(fill yes
			(thermal_gap 0.5)
			(thermal_bridge_width 0.5)
			(island_removal_mode 0)
		)
		(polygon
			(pts
				(arc
					(start 335.141824 -435.160674)
					(mid 335.164142 -435.214556)
					(end 335.218024 -435.236874)
				)
				(arc
					(start 336.157824 -435.236874)
					(mid 336.211706 -435.214556)
					(end 336.234024 -435.160674)
				)
				(arc
					(start 336.234024 -432.61915)
					(mid 336.211706 -432.565268)
					(end 336.157824 -432.54295)
				)
				(arc
					(start 335.218024 -432.54295)
					(mid 335.164142 -432.565268)
					(end 335.141824 -432.61915)
				)
			)
		)
	)
	(zone
		(layers "F.Cu" "In2.Cu" "In3.Cu" "In4.Cu" "In5.Cu" "In6.Cu" "In11.Cu" "In13.Cu"
			"In15.Cu"
		)
		(hatch none 0.5)
		(connect_pads
			(clearance 0)
		)
		(min_thickness 0.25)
		(keepout
			(tracks not_allowed)
			(vias allowed)
			(pads allowed)
			(copperpour not_allowed)
			(footprints allowed)
		)
		(placement
			(enabled no)
			(sheetname "")
		)
		(fill yes
			(thermal_gap 0.5)
			(thermal_bridge_width 0.5)
			(island_removal_mode 0)
		)
		(polygon
			(pts
				(arc
					(start 324.141846 -436.160672)
					(mid 324.164164 -436.214554)
					(end 324.218046 -436.236872)
				)
				(arc
					(start 325.157846 -436.236872)
					(mid 325.211728 -436.214554)
					(end 325.234046 -436.160672)
				)
				(arc
					(start 325.234046 -433.619148)
					(mid 325.211728 -433.565266)
					(end 325.157846 -433.542948)
				)
				(arc
					(start 324.218046 -433.542948)
					(mid 324.164164 -433.565266)
					(end 324.141846 -433.619148)
				)
			)
		)
	)
	(zone
		(layers "F.Cu" "In2.Cu" "In3.Cu" "In4.Cu" "In5.Cu" "In6.Cu" "In11.Cu" "In13.Cu"
			"In15.Cu"
		)
		(hatch none 0.5)
		(connect_pads
			(clearance 0)
		)
		(min_thickness 0.25)
		(keepout
			(tracks not_allowed)
			(vias allowed)
			(pads allowed)
			(copperpour not_allowed)
			(footprints allowed)
		)
		(placement
			(enabled no)
			(sheetname "")
		)
		(fill yes
			(thermal_gap 0.5)
			(thermal_bridge_width 0.5)
			(island_removal_mode 0)
		)
		(polygon
			(pts
				(arc
					(start 343.141808 -435.160674)
					(mid 343.164126 -435.214556)
					(end 343.218008 -435.236874)
				)
				(arc
					(start 344.157808 -435.236874)
					(mid 344.21169 -435.214556)
					(end 344.234008 -435.160674)
				)
				(arc
					(start 344.234008 -432.61915)
					(mid 344.21169 -432.565268)
					(end 344.157808 -432.54295)
				)
				(arc
					(start 343.218008 -432.54295)
					(mid 343.164126 -432.565268)
					(end 343.141808 -432.61915)
				)
			)
		)
	)
	(zone
		(layers "F.Cu" "In2.Cu" "In3.Cu" "In4.Cu" "In5.Cu" "In6.Cu" "In11.Cu" "In13.Cu"
			"In15.Cu"
		)
		(hatch none 0.5)
		(connect_pads
			(clearance 0)
		)
		(min_thickness 0.25)
		(keepout
			(tracks not_allowed)
			(vias allowed)
			(pads allowed)
			(copperpour not_allowed)
			(footprints allowed)
		)
		(placement
			(enabled no)
			(sheetname "")
		)
		(fill yes
			(thermal_gap 0.5)
			(thermal_bridge_width 0.5)
			(island_removal_mode 0)
		)
		(polygon
			(pts
				(arc
					(start 331.141832 -435.160674)
					(mid 331.16415 -435.214556)
					(end 331.218032 -435.236874)
				)
				(arc
					(start 332.157832 -435.236874)
					(mid 332.211714 -435.214556)
					(end 332.234032 -435.160674)
				)
				(arc
					(start 332.234032 -432.61915)
					(mid 332.211714 -432.565268)
					(end 332.157832 -432.54295)
				)
				(arc
					(start 331.218032 -432.54295)
					(mid 331.16415 -432.565268)
					(end 331.141832 -432.61915)
				)
			)
		)
	)
	(zone
		(layers "F.Cu" "In2.Cu" "In3.Cu" "In4.Cu" "In5.Cu" "In6.Cu" "In11.Cu" "In13.Cu"
			"In15.Cu"
		)
		(hatch none 0.5)
		(connect_pads
			(clearance 0)
		)
		(min_thickness 0.25)
		(keepout
			(tracks not_allowed)
			(vias allowed)
			(pads allowed)
			(copperpour not_allowed)
			(footprints allowed)
		)
		(placement
			(enabled no)
			(sheetname "")
		)
		(fill yes
			(thermal_gap 0.5)
			(thermal_bridge_width 0.5)
			(island_removal_mode 0)
		)
		(polygon
			(pts
				(arc
					(start 326.141842 -435.160674)
					(mid 326.16416 -435.214556)
					(end 326.218042 -435.236874)
				)
				(arc
					(start 327.157842 -435.236874)
					(mid 327.211724 -435.214556)
					(end 327.234042 -435.160674)
				)
				(arc
					(start 327.234042 -432.61915)
					(mid 327.211724 -432.565268)
					(end 327.157842 -432.54295)
				)
				(arc
					(start 326.218042 -432.54295)
					(mid 326.16416 -432.565268)
					(end 326.141842 -432.61915)
				)
			)
		)
	)
	(zone
		(layers "F.Cu" "In2.Cu" "In3.Cu" "In4.Cu" "In5.Cu" "In6.Cu" "In11.Cu" "In13.Cu"
			"In15.Cu"
		)
		(hatch none 0.5)
		(connect_pads
			(clearance 0)
		)
		(min_thickness 0.25)
		(keepout
			(tracks not_allowed)
			(vias allowed)
			(pads allowed)
			(copperpour not_allowed)
			(footprints allowed)
		)
		(placement
			(enabled no)
			(sheetname "")
		)
		(fill yes
			(thermal_gap 0.5)
			(thermal_bridge_width 0.5)
			(island_removal_mode 0)
		)
		(polygon
			(pts
				(arc
					(start 341.141812 -436.160672)
					(mid 341.16413 -436.214554)
					(end 341.218012 -436.236872)
				)
				(arc
					(start 342.157812 -436.236872)
					(mid 342.211694 -436.214554)
					(end 342.234012 -436.160672)
				)
				(arc
					(start 342.234012 -433.619148)
					(mid 342.211694 -433.565266)
					(end 342.157812 -433.542948)
				)
				(arc
					(start 341.218012 -433.542948)
					(mid 341.16413 -433.565266)
					(end 341.141812 -433.619148)
				)
			)
		)
	)
	(zone
		(layers "F.Cu" "In2.Cu" "In3.Cu" "In4.Cu" "In5.Cu" "In6.Cu" "In11.Cu" "In13.Cu"
			"In15.Cu"
		)
		(hatch none 0.5)
		(connect_pads
			(clearance 0)
		)
		(min_thickness 0.25)
		(keepout
			(tracks not_allowed)
			(vias allowed)
			(pads allowed)
			(copperpour not_allowed)
			(footprints allowed)
		)
		(placement
			(enabled no)
			(sheetname "")
		)
		(fill yes
			(thermal_gap 0.5)
			(thermal_bridge_width 0.5)
			(island_removal_mode 0)
		)
		(polygon
			(pts
				(arc
					(start 320.141854 -436.160672)
					(mid 320.164172 -436.214554)
					(end 320.218054 -436.236872)
				)
				(arc
					(start 321.157854 -436.236872)
					(mid 321.211736 -436.214554)
					(end 321.234054 -436.160672)
				)
				(arc
					(start 321.234054 -433.619148)
					(mid 321.211736 -433.565266)
					(end 321.157854 -433.542948)
				)
				(arc
					(start 320.218054 -433.542948)
					(mid 320.164172 -433.565266)
					(end 320.141854 -433.619148)
				)
			)
		)
	)
	(zone
		(layers "F.Cu" "In2.Cu" "In3.Cu" "In4.Cu" "In5.Cu" "In6.Cu" "In11.Cu" "In13.Cu"
			"In15.Cu"
		)
		(hatch none 0.5)
		(connect_pads
			(clearance 0)
		)
		(min_thickness 0.25)
		(keepout
			(tracks not_allowed)
			(vias allowed)
			(pads allowed)
			(copperpour not_allowed)
			(footprints allowed)
		)
		(placement
			(enabled no)
			(sheetname "")
		)
		(fill yes
			(thermal_gap 0.5)
			(thermal_bridge_width 0.5)
			(island_removal_mode 0)
		)
		(polygon
			(pts
				(arc
					(start 333.141828 -436.160672)
					(mid 333.164146 -436.214554)
					(end 333.218028 -436.236872)
				)
				(arc
					(start 334.157828 -436.236872)
					(mid 334.21171 -436.214554)
					(end 334.234028 -436.160672)
				)
				(arc
					(start 334.234028 -433.619148)
					(mid 334.21171 -433.565266)
					(end 334.157828 -433.542948)
				)
				(arc
					(start 333.218028 -433.542948)
					(mid 333.164146 -433.565266)
					(end 333.141828 -433.619148)
				)
			)
		)
	)
	(zone
		(layers "F.Cu" "In2.Cu" "In3.Cu" "In4.Cu" "In5.Cu" "In6.Cu" "In11.Cu" "In13.Cu"
			"In15.Cu"
		)
		(hatch none 0.5)
		(connect_pads
			(clearance 0)
		)
		(min_thickness 0.25)
		(keepout
			(tracks not_allowed)
			(vias allowed)
			(pads allowed)
			(copperpour not_allowed)
			(footprints allowed)
		)
		(placement
			(enabled no)
			(sheetname "")
		)
		(fill yes
			(thermal_gap 0.5)
			(thermal_bridge_width 0.5)
			(island_removal_mode 0)
		)
		(polygon
			(pts
				(arc
					(start 339.141816 -435.160674)
					(mid 339.164134 -435.214556)
					(end 339.218016 -435.236874)
				)
				(arc
					(start 340.157816 -435.236874)
					(mid 340.211698 -435.214556)
					(end 340.234016 -435.160674)
				)
				(arc
					(start 340.234016 -432.61915)
					(mid 340.211698 -432.565268)
					(end 340.157816 -432.54295)
				)
				(arc
					(start 339.218016 -432.54295)
					(mid 339.164134 -432.565268)
					(end 339.141816 -432.61915)
				)
			)
		)
	)
	(zone
		(layers "F.Cu" "In2.Cu" "In4.Cu")
		(hatch none 0.5)
		(connect_pads
			(clearance 0)
		)
		(min_thickness 0.25)
		(keepout
			(tracks not_allowed)
			(vias allowed)
			(pads allowed)
			(copperpour not_allowed)
			(footprints allowed)
		)
		(placement
			(enabled no)
			(sheetname "")
		)
		(fill yes
			(thermal_gap 0.5)
			(thermal_bridge_width 0.5)
			(island_removal_mode 0)
		)
		(polygon
			(pts
				(arc
					(start 381.949452 -415.38652)
					(mid 381.281432 -415.38652)
					(end 381.949452 -415.38652)
				)
			)
		)
	)
	(zone
		(layers "F.Cu" "In2.Cu" "In4.Cu")
		(hatch none 0.5)
		(connect_pads
			(clearance 0)
		)
		(min_thickness 0.25)
		(keepout
			(tracks not_allowed)
			(vias allowed)
			(pads allowed)
			(copperpour not_allowed)
			(footprints allowed)
		)
		(placement
			(enabled no)
			(sheetname "")
		)
		(fill yes
			(thermal_gap 0.5)
			(thermal_bridge_width 0.5)
			(island_removal_mode 0)
		)
		(polygon
			(pts
				(arc
					(start 80.292194 -410.030168)
					(mid 79.624174 -410.030168)
					(end 80.292194 -410.030168)
				)
			)
		)
	)
	(zone
		(layers "F.Cu" "In2.Cu" "In4.Cu")
		(hatch none 0.5)
		(connect_pads
			(clearance 0)
		)
		(min_thickness 0.25)
		(keepout
			(tracks not_allowed)
			(vias allowed)
			(pads allowed)
			(copperpour not_allowed)
			(footprints allowed)
		)
		(placement
			(enabled no)
			(sheetname "")
		)
		(fill yes
			(thermal_gap 0.5)
			(thermal_bridge_width 0.5)
			(island_removal_mode 0)
		)
		(polygon
			(pts
				(arc
					(start 415.645092 -418.412168)
					(mid 414.977072 -418.412168)
					(end 415.645092 -418.412168)
				)
			)
		)
	)
	(zone
		(layers "F.Cu" "In2.Cu" "In4.Cu")
		(hatch none 0.5)
		(connect_pads
			(clearance 0)
		)
		(min_thickness 0.25)
		(keepout
			(tracks not_allowed)
			(vias allowed)
			(pads allowed)
			(copperpour not_allowed)
			(footprints allowed)
		)
		(placement
			(enabled no)
			(sheetname "")
		)
		(fill yes
			(thermal_gap 0.5)
			(thermal_bridge_width 0.5)
			(island_removal_mode 0)
		)
		(polygon
			(pts
				(arc
					(start 340.218776 -418.412168)
					(mid 339.550756 -418.412168)
					(end 340.218776 -418.412168)
				)
			)
		)
	)
	(zone
		(layers "F.Cu" "In2.Cu" "In4.Cu")
		(hatch none 0.5)
		(connect_pads
			(clearance 0)
		)
		(min_thickness 0.25)
		(keepout
			(tracks not_allowed)
			(vias allowed)
			(pads allowed)
			(copperpour not_allowed)
			(footprints allowed)
		)
		(placement
			(enabled no)
			(sheetname "")
		)
		(fill yes
			(thermal_gap 0.5)
			(thermal_bridge_width 0.5)
			(island_removal_mode 0)
		)
		(polygon
			(pts
				(arc
					(start 59.713114 -410.030168)
					(mid 59.045094 -410.030168)
					(end 59.713114 -410.030168)
				)
			)
		)
	)
	(zone
		(layers "F.Cu" "In2.Cu" "In4.Cu")
		(hatch none 0.5)
		(connect_pads
			(clearance 0)
		)
		(min_thickness 0.25)
		(keepout
			(tracks not_allowed)
			(vias allowed)
			(pads allowed)
			(copperpour not_allowed)
			(footprints allowed)
		)
		(placement
			(enabled no)
			(sheetname "")
		)
		(fill yes
			(thermal_gap 0.5)
			(thermal_bridge_width 0.5)
			(island_removal_mode 0)
		)
		(polygon
			(pts
				(arc
					(start 305.659536 -415.38652)
					(mid 304.991516 -415.38652)
					(end 305.659536 -415.38652)
				)
			)
		)
	)
	(zone
		(layers "F.Cu" "In2.Cu" "In4.Cu")
		(hatch none 0.5)
		(connect_pads
			(clearance 0)
		)
		(min_thickness 0.25)
		(keepout
			(tracks not_allowed)
			(vias allowed)
			(pads allowed)
			(copperpour not_allowed)
			(footprints allowed)
		)
		(placement
			(enabled no)
			(sheetname "")
		)
		(fill yes
			(thermal_gap 0.5)
			(thermal_bridge_width 0.5)
			(island_removal_mode 0)
		)
		(polygon
			(pts
				(arc
					(start 388.939532 -415.38652)
					(mid 388.271512 -415.38652)
					(end 388.939532 -415.38652)
				)
			)
		)
	)
	(zone
		(layers "F.Cu" "In2.Cu" "In4.Cu")
		(hatch none 0.5)
		(connect_pads
			(clearance 0)
		)
		(min_thickness 0.25)
		(keepout
			(tracks not_allowed)
			(vias allowed)
			(pads allowed)
			(copperpour not_allowed)
			(footprints allowed)
		)
		(placement
			(enabled no)
			(sheetname "")
		)
		(fill yes
			(thermal_gap 0.5)
			(thermal_bridge_width 0.5)
			(island_removal_mode 0)
		)
		(polygon
			(pts
				(arc
					(start 309.586376 -415.38652)
					(mid 308.918356 -415.38652)
					(end 309.586376 -415.38652)
				)
			)
		)
	)
	(zone
		(layers "F.Cu" "In2.Cu" "In4.Cu")
		(hatch none 0.5)
		(connect_pads
			(clearance 0)
		)
		(min_thickness 0.25)
		(keepout
			(tracks not_allowed)
			(vias allowed)
			(pads allowed)
			(copperpour not_allowed)
			(footprints allowed)
		)
		(placement
			(enabled no)
			(sheetname "")
		)
		(fill yes
			(thermal_gap 0.5)
			(thermal_bridge_width 0.5)
			(island_removal_mode 0)
		)
		(polygon
			(pts
				(arc
					(start 157.445456 -410.030168)
					(mid 156.777436 -410.030168)
					(end 157.445456 -410.030168)
				)
			)
		)
	)
	(zone
		(layers "F.Cu" "In2.Cu" "In4.Cu")
		(hatch none 0.5)
		(connect_pads
			(clearance 0)
		)
		(min_thickness 0.25)
		(keepout
			(tracks not_allowed)
			(vias allowed)
			(pads allowed)
			(copperpour not_allowed)
			(footprints allowed)
		)
		(placement
			(enabled no)
			(sheetname "")
		)
		(fill yes
			(thermal_gap 0.5)
			(thermal_bridge_width 0.5)
			(island_removal_mode 0)
		)
		(polygon
			(pts
				(arc
					(start 391.139172 -418.412168)
					(mid 390.471152 -418.412168)
					(end 391.139172 -418.412168)
				)
			)
		)
	)
	(zone
		(layers "F.Cu" "In2.Cu" "In4.Cu")
		(hatch none 0.5)
		(connect_pads
			(clearance 0)
		)
		(min_thickness 0.25)
		(keepout
			(tracks not_allowed)
			(vias allowed)
			(pads allowed)
			(copperpour not_allowed)
			(footprints allowed)
		)
		(placement
			(enabled no)
			(sheetname "")
		)
		(fill yes
			(thermal_gap 0.5)
			(thermal_bridge_width 0.5)
			(island_removal_mode 0)
		)
		(polygon
			(pts
				(arc
					(start 398.129252 -418.412168)
					(mid 397.461232 -418.412168)
					(end 398.129252 -418.412168)
				)
			)
		)
	)
	(zone
		(layers "F.Cu" "In2.Cu" "In4.Cu")
		(hatch none 0.5)
		(connect_pads
			(clearance 0)
		)
		(min_thickness 0.25)
		(keepout
			(tracks not_allowed)
			(vias allowed)
			(pads allowed)
			(copperpour not_allowed)
			(footprints allowed)
		)
		(placement
			(enabled no)
			(sheetname "")
		)
		(fill yes
			(thermal_gap 0.5)
			(thermal_bridge_width 0.5)
			(island_removal_mode 0)
		)
		(polygon
			(pts
				(arc
					(start 385.876292 -418.412168)
					(mid 385.208272 -418.412168)
					(end 385.876292 -418.412168)
				)
			)
		)
	)
	(zone
		(layers "F.Cu" "In2.Cu" "In4.Cu")
		(hatch none 0.5)
		(connect_pads
			(clearance 0)
		)
		(min_thickness 0.25)
		(keepout
			(tracks not_allowed)
			(vias allowed)
			(pads allowed)
			(copperpour not_allowed)
			(footprints allowed)
		)
		(placement
			(enabled no)
			(sheetname "")
		)
		(fill yes
			(thermal_gap 0.5)
			(thermal_bridge_width 0.5)
			(island_removal_mode 0)
		)
		(polygon
			(pts
				(arc
					(start 312.649616 -418.412168)
					(mid 311.981596 -418.412168)
					(end 312.649616 -418.412168)
				)
			)
		)
	)
	(zone
		(layers "F.Cu" "In2.Cu" "In4.Cu")
		(hatch none 0.5)
		(connect_pads
			(clearance 0)
		)
		(min_thickness 0.25)
		(keepout
			(tracks not_allowed)
			(vias allowed)
			(pads allowed)
			(copperpour not_allowed)
			(footprints allowed)
		)
		(placement
			(enabled no)
			(sheetname "")
		)
		(fill yes
			(thermal_gap 0.5)
			(thermal_bridge_width 0.5)
			(island_removal_mode 0)
		)
		(polygon
			(pts
				(arc
					(start 77.228954 -410.030168)
					(mid 76.560934 -410.030168)
					(end 77.228954 -410.030168)
				)
			)
		)
	)
	(zone
		(layers "F.Cu" "In2.Cu" "In4.Cu")
		(hatch none 0.5)
		(connect_pads
			(clearance 0)
		)
		(min_thickness 0.25)
		(keepout
			(tracks not_allowed)
			(vias allowed)
			(pads allowed)
			(copperpour not_allowed)
			(footprints allowed)
		)
		(placement
			(enabled no)
			(sheetname "")
		)
		(fill yes
			(thermal_gap 0.5)
			(thermal_bridge_width 0.5)
			(island_removal_mode 0)
		)
		(polygon
			(pts
				(arc
					(start 351.608136 -418.412168)
					(mid 350.940116 -418.412168)
					(end 351.608136 -418.412168)
				)
			)
		)
	)
	(zone
		(layers "F.Cu" "In2.Cu" "In4.Cu")
		(hatch none 0.5)
		(connect_pads
			(clearance 0)
		)
		(min_thickness 0.25)
		(keepout
			(tracks not_allowed)
			(vias allowed)
			(pads allowed)
			(copperpour not_allowed)
			(footprints allowed)
		)
		(placement
			(enabled no)
			(sheetname "")
		)
		(fill yes
			(thermal_gap 0.5)
			(thermal_bridge_width 0.5)
			(island_removal_mode 0)
		)
		(polygon
			(pts
				(arc
					(start 308.722776 -418.412168)
					(mid 308.054756 -418.412168)
					(end 308.722776 -418.412168)
				)
			)
		)
	)
	(zone
		(layers "F.Cu" "In2.Cu" "In4.Cu")
		(hatch none 0.5)
		(connect_pads
			(clearance 0)
		)
		(min_thickness 0.25)
		(keepout
			(tracks not_allowed)
			(vias allowed)
			(pads allowed)
			(copperpour not_allowed)
			(footprints allowed)
		)
		(placement
			(enabled no)
			(sheetname "")
		)
		(fill yes
			(thermal_gap 0.5)
			(thermal_bridge_width 0.5)
			(island_removal_mode 0)
		)
		(polygon
			(pts
				(arc
					(start 327.102216 -418.412168)
					(mid 326.434196 -418.412168)
					(end 327.102216 -418.412168)
				)
			)
		)
	)
	(zone
		(layers "F.Cu" "In2.Cu" "In4.Cu")
		(hatch none 0.5)
		(connect_pads
			(clearance 0)
		)
		(min_thickness 0.25)
		(keepout
			(tracks not_allowed)
			(vias allowed)
			(pads allowed)
			(copperpour not_allowed)
			(footprints allowed)
		)
		(placement
			(enabled no)
			(sheetname "")
		)
		(fill yes
			(thermal_gap 0.5)
			(thermal_bridge_width 0.5)
			(island_removal_mode 0)
		)
		(polygon
			(pts
				(arc
					(start 119.822976 -410.030168)
					(mid 119.154956 -410.030168)
					(end 119.822976 -410.030168)
				)
			)
		)
	)
	(zone
		(layers "F.Cu" "In2.Cu" "In4.Cu")
		(hatch none 0.5)
		(connect_pads
			(clearance 0)
		)
		(min_thickness 0.25)
		(keepout
			(tracks not_allowed)
			(vias allowed)
			(pads allowed)
			(copperpour not_allowed)
			(footprints allowed)
		)
		(placement
			(enabled no)
			(sheetname "")
		)
		(fill yes
			(thermal_gap 0.5)
			(thermal_bridge_width 0.5)
			(island_removal_mode 0)
		)
		(polygon
			(pts
				(arc
					(start 345.481656 -418.412168)
					(mid 344.813636 -418.412168)
					(end 345.481656 -418.412168)
				)
			)
		)
	)
	(zone
		(layers "F.Cu" "In2.Cu" "In4.Cu")
		(hatch none 0.5)
		(connect_pads
			(clearance 0)
		)
		(min_thickness 0.25)
		(keepout
			(tracks not_allowed)
			(vias allowed)
			(pads allowed)
			(copperpour not_allowed)
			(footprints allowed)
		)
		(placement
			(enabled no)
			(sheetname "")
		)
		(fill yes
			(thermal_gap 0.5)
			(thermal_bridge_width 0.5)
			(island_removal_mode 0)
		)
		(polygon
			(pts
				(arc
					(start 162.708336 -407.00452)
					(mid 162.040316 -407.00452)
					(end 162.708336 -407.00452)
				)
			)
		)
	)
	(zone
		(layers "F.Cu" "In2.Cu" "In4.Cu")
		(hatch none 0.5)
		(connect_pads
			(clearance 0)
		)
		(min_thickness 0.25)
		(keepout
			(tracks not_allowed)
			(vias allowed)
			(pads allowed)
			(copperpour not_allowed)
			(footprints allowed)
		)
		(placement
			(enabled no)
			(sheetname "")
		)
		(fill yes
			(thermal_gap 0.5)
			(thermal_bridge_width 0.5)
			(island_removal_mode 0)
		)
		(polygon
			(pts
				(arc
					(start 339.355176 -415.38652)
					(mid 338.687156 -415.38652)
					(end 339.355176 -415.38652)
				)
			)
		)
	)
	(zone
		(layers "F.Cu" "In2.Cu" "In4.Cu")
		(hatch none 0.5)
		(connect_pads
			(clearance 0)
		)
		(min_thickness 0.25)
		(keepout
			(tracks not_allowed)
			(vias allowed)
			(pads allowed)
			(copperpour not_allowed)
			(footprints allowed)
		)
		(placement
			(enabled no)
			(sheetname "")
		)
		(fill yes
			(thermal_gap 0.5)
			(thermal_bridge_width 0.5)
			(island_removal_mode 0)
		)
		(polygon
			(pts
				(arc
					(start 385.012692 -415.38652)
					(mid 384.344672 -415.38652)
					(end 385.012692 -415.38652)
				)
			)
		)
	)
	(zone
		(layers "F.Cu" "In2.Cu" "In4.Cu")
		(hatch none 0.5)
		(connect_pads
			(clearance 0)
		)
		(min_thickness 0.25)
		(keepout
			(tracks not_allowed)
			(vias allowed)
			(pads allowed)
			(copperpour not_allowed)
			(footprints allowed)
		)
		(placement
			(enabled no)
			(sheetname "")
		)
		(fill yes
			(thermal_gap 0.5)
			(thermal_bridge_width 0.5)
			(island_removal_mode 0)
		)
		(polygon
			(pts
				(arc
					(start 418.708332 -415.38652)
					(mid 418.040312 -415.38652)
					(end 418.708332 -415.38652)
				)
			)
		)
	)
	(zone
		(layers "F.Cu" "In2.Cu" "In4.Cu")
		(hatch none 0.5)
		(connect_pads
			(clearance 0)
		)
		(min_thickness 0.25)
		(keepout
			(tracks not_allowed)
			(vias allowed)
			(pads allowed)
			(copperpour not_allowed)
			(footprints allowed)
		)
		(placement
			(enabled no)
			(sheetname "")
		)
		(fill yes
			(thermal_gap 0.5)
			(thermal_bridge_width 0.5)
			(island_removal_mode 0)
		)
		(polygon
			(pts
				(arc
					(start 346.345256 -418.412168)
					(mid 345.677236 -418.412168)
					(end 346.345256 -418.412168)
				)
			)
		)
	)
	(zone
		(layers "F.Cu" "In2.Cu" "In4.Cu")
		(hatch none 0.5)
		(connect_pads
			(clearance 0)
		)
		(min_thickness 0.25)
		(keepout
			(tracks not_allowed)
			(vias allowed)
			(pads allowed)
			(copperpour not_allowed)
			(footprints allowed)
		)
		(placement
			(enabled no)
			(sheetname "")
		)
		(fill yes
			(thermal_gap 0.5)
			(thermal_bridge_width 0.5)
			(island_removal_mode 0)
		)
		(polygon
			(pts
				(arc
					(start 150.455376 -407.00452)
					(mid 149.787356 -407.00452)
					(end 150.455376 -407.00452)
				)
			)
		)
	)
	(zone
		(layers "F.Cu" "In2.Cu" "In4.Cu")
		(hatch none 0.5)
		(connect_pads
			(clearance 0)
		)
		(min_thickness 0.25)
		(keepout
			(tracks not_allowed)
			(vias allowed)
			(pads allowed)
			(copperpour not_allowed)
			(footprints allowed)
		)
		(placement
			(enabled no)
			(sheetname "")
		)
		(fill yes
			(thermal_gap 0.5)
			(thermal_bridge_width 0.5)
			(island_removal_mode 0)
		)
		(polygon
			(pts
				(arc
					(start 39.69004 -412.5849)
					(mid 39.02202 -412.5849)
					(end 39.69004 -412.5849)
				)
			)
		)
	)
	(zone
		(layers "F.Cu" "In2.Cu" "In4.Cu")
		(hatch none 0.5)
		(connect_pads
			(clearance 0)
		)
		(min_thickness 0.25)
		(keepout
			(tracks not_allowed)
			(vias allowed)
			(pads allowed)
			(copperpour not_allowed)
			(footprints allowed)
		)
		(placement
			(enabled no)
			(sheetname "")
		)
		(fill yes
			(thermal_gap 0.5)
			(thermal_bridge_width 0.5)
			(island_removal_mode 0)
		)
		(polygon
			(pts
				(arc
					(start 148.255736 -407.00452)
					(mid 147.587716 -407.00452)
					(end 148.255736 -407.00452)
				)
			)
		)
	)
	(zone
		(layers "F.Cu" "In2.Cu" "In4.Cu")
		(hatch none 0.5)
		(connect_pads
			(clearance 0)
		)
		(min_thickness 0.25)
		(keepout
			(tracks not_allowed)
			(vias allowed)
			(pads allowed)
			(copperpour not_allowed)
			(footprints allowed)
		)
		(placement
			(enabled no)
			(sheetname "")
		)
		(fill yes
			(thermal_gap 0.5)
			(thermal_bridge_width 0.5)
			(island_removal_mode 0)
		)
		(polygon
			(pts
				(arc
					(start 348.544896 -418.412168)
					(mid 347.876876 -418.412168)
					(end 348.544896 -418.412168)
				)
			)
		)
	)
	(zone
		(layers "F.Cu" "In2.Cu" "In4.Cu")
		(hatch none 0.5)
		(connect_pads
			(clearance 0)
		)
		(min_thickness 0.25)
		(keepout
			(tracks not_allowed)
			(vias allowed)
			(pads allowed)
			(copperpour not_allowed)
			(footprints allowed)
		)
		(placement
			(enabled no)
			(sheetname "")
		)
		(fill yes
			(thermal_gap 0.5)
			(thermal_bridge_width 0.5)
			(island_removal_mode 0)
		)
		(polygon
			(pts
				(arc
					(start 151.318976 -407.00452)
					(mid 150.650956 -407.00452)
					(end 151.318976 -407.00452)
				)
			)
		)
	)
	(zone
		(layers "F.Cu" "In2.Cu" "In4.Cu")
		(hatch none 0.5)
		(connect_pads
			(clearance 0)
		)
		(min_thickness 0.25)
		(keepout
			(tracks not_allowed)
			(vias allowed)
			(pads allowed)
			(copperpour not_allowed)
			(footprints allowed)
		)
		(placement
			(enabled no)
			(sheetname "")
		)
		(fill yes
			(thermal_gap 0.5)
			(thermal_bridge_width 0.5)
			(island_removal_mode 0)
		)
		(polygon
			(pts
				(arc
					(start 278.923242 -244.08511)
					(mid 278.255222 -244.08511)
					(end 278.923242 -244.08511)
				)
			)
		)
	)
	(zone
		(layers "F.Cu" "In2.Cu" "In4.Cu")
		(hatch none 0.5)
		(connect_pads
			(clearance 0)
		)
		(min_thickness 0.25)
		(keepout
			(tracks not_allowed)
			(vias allowed)
			(pads allowed)
			(copperpour not_allowed)
			(footprints allowed)
		)
		(placement
			(enabled no)
			(sheetname "")
		)
		(fill yes
			(thermal_gap 0.5)
			(thermal_bridge_width 0.5)
			(island_removal_mode 0)
		)
		(polygon
			(pts
				(arc
					(start 342.418416 -418.412168)
					(mid 341.750396 -418.412168)
					(end 342.418416 -418.412168)
				)
			)
		)
	)
	(zone
		(layers "F.Cu" "In2.Cu" "In4.Cu")
		(hatch none 0.5)
		(connect_pads
			(clearance 0)
		)
		(min_thickness 0.25)
		(keepout
			(tracks not_allowed)
			(vias allowed)
			(pads allowed)
			(copperpour not_allowed)
			(footprints allowed)
		)
		(placement
			(enabled no)
			(sheetname "")
		)
		(fill yes
			(thermal_gap 0.5)
			(thermal_bridge_width 0.5)
			(island_removal_mode 0)
		)
		(polygon
			(pts
				(arc
					(start 153.518616 -407.00452)
					(mid 152.850596 -407.00452)
					(end 153.518616 -407.00452)
				)
			)
		)
	)
	(zone
		(layers "F.Cu" "In2.Cu" "In4.Cu")
		(hatch none 0.5)
		(connect_pads
			(clearance 0)
		)
		(min_thickness 0.25)
		(keepout
			(tracks not_allowed)
			(vias allowed)
			(pads allowed)
			(copperpour not_allowed)
			(footprints allowed)
		)
		(placement
			(enabled no)
			(sheetname "")
		)
		(fill yes
			(thermal_gap 0.5)
			(thermal_bridge_width 0.5)
			(island_removal_mode 0)
		)
		(polygon
			(pts
				(arc
					(start 331.029056 -418.412168)
					(mid 330.361036 -418.412168)
					(end 331.029056 -418.412168)
				)
			)
		)
	)
	(zone
		(layers "F.Cu" "In2.Cu" "In4.Cu")
		(hatch none 0.5)
		(connect_pads
			(clearance 0)
		)
		(min_thickness 0.25)
		(keepout
			(tracks not_allowed)
			(vias allowed)
			(pads allowed)
			(copperpour not_allowed)
			(footprints allowed)
		)
		(placement
			(enabled no)
			(sheetname "")
		)
		(fill yes
			(thermal_gap 0.5)
			(thermal_bridge_width 0.5)
			(island_removal_mode 0)
		)
		(polygon
			(pts
				(arc
					(start 324.902576 -418.412168)
					(mid 324.234556 -418.412168)
					(end 324.902576 -418.412168)
				)
			)
		)
	)
	(zone
		(layers "F.Cu" "In2.Cu" "In4.Cu")
		(hatch none 0.5)
		(connect_pads
			(clearance 0)
		)
		(min_thickness 0.25)
		(keepout
			(tracks not_allowed)
			(vias allowed)
			(pads allowed)
			(copperpour not_allowed)
			(footprints allowed)
		)
		(placement
			(enabled no)
			(sheetname "")
		)
		(fill yes
			(thermal_gap 0.5)
			(thermal_bridge_width 0.5)
			(island_removal_mode 0)
		)
		(polygon
			(pts
				(arc
					(start 394.202412 -418.412168)
					(mid 393.534392 -418.412168)
					(end 394.202412 -418.412168)
				)
			)
		)
	)
	(zone
		(layers "F.Cu" "In2.Cu" "In4.Cu")
		(hatch none 0.5)
		(connect_pads
			(clearance 0)
		)
		(min_thickness 0.25)
		(keepout
			(tracks not_allowed)
			(vias allowed)
			(pads allowed)
			(copperpour not_allowed)
			(footprints allowed)
		)
		(placement
			(enabled no)
			(sheetname "")
		)
		(fill yes
			(thermal_gap 0.5)
			(thermal_bridge_width 0.5)
			(island_removal_mode 0)
		)
		(polygon
			(pts
				(arc
					(start 126.813056 -410.030168)
					(mid 126.145036 -410.030168)
					(end 126.813056 -410.030168)
				)
			)
		)
	)
	(zone
		(layers "F.Cu" "In2.Cu" "In4.Cu")
		(hatch none 0.5)
		(connect_pads
			(clearance 0)
		)
		(min_thickness 0.25)
		(keepout
			(tracks not_allowed)
			(vias allowed)
			(pads allowed)
			(copperpour not_allowed)
			(footprints allowed)
		)
		(placement
			(enabled no)
			(sheetname "")
		)
		(fill yes
			(thermal_gap 0.5)
			(thermal_bridge_width 0.5)
			(island_removal_mode 0)
		)
		(polygon
			(pts
				(arc
					(start 395.066012 -418.412168)
					(mid 394.397992 -418.412168)
					(end 395.066012 -418.412168)
				)
			)
		)
	)
	(zone
		(layers "F.Cu" "In2.Cu" "In4.Cu")
		(hatch none 0.5)
		(connect_pads
			(clearance 0)
		)
		(min_thickness 0.25)
		(keepout
			(tracks not_allowed)
			(vias allowed)
			(pads allowed)
			(copperpour not_allowed)
			(footprints allowed)
		)
		(placement
			(enabled no)
			(sheetname "")
		)
		(fill yes
			(thermal_gap 0.5)
			(thermal_bridge_width 0.5)
			(island_removal_mode 0)
		)
		(polygon
			(pts
				(arc
					(start 136.002776 -410.030168)
					(mid 135.334756 -410.030168)
					(end 136.002776 -410.030168)
				)
			)
		)
	)
	(zone
		(layers "F.Cu" "In2.Cu" "In4.Cu")
		(hatch none 0.5)
		(connect_pads
			(clearance 0)
		)
		(min_thickness 0.25)
		(keepout
			(tracks not_allowed)
			(vias allowed)
			(pads allowed)
			(copperpour not_allowed)
			(footprints allowed)
		)
		(placement
			(enabled no)
			(sheetname "")
		)
		(fill yes
			(thermal_gap 0.5)
			(thermal_bridge_width 0.5)
			(island_removal_mode 0)
		)
		(polygon
			(pts
				(arc
					(start 373.623332 -415.38652)
					(mid 372.955312 -415.38652)
					(end 373.623332 -415.38652)
				)
			)
		)
	)
	(zone
		(layers "F.Cu" "In2.Cu" "In4.Cu")
		(hatch none 0.5)
		(connect_pads
			(clearance 0)
		)
		(min_thickness 0.25)
		(keepout
			(tracks not_allowed)
			(vias allowed)
			(pads allowed)
			(copperpour not_allowed)
			(footprints allowed)
		)
		(placement
			(enabled no)
			(sheetname "")
		)
		(fill yes
			(thermal_gap 0.5)
			(thermal_bridge_width 0.5)
			(island_removal_mode 0)
		)
		(polygon
			(pts
				(arc
					(start 139.066016 -410.030168)
					(mid 138.397996 -410.030168)
					(end 139.066016 -410.030168)
				)
			)
		)
	)
	(zone
		(layers "F.Cu" "In2.Cu" "In4.Cu")
		(hatch none 0.5)
		(connect_pads
			(clearance 0)
		)
		(min_thickness 0.25)
		(keepout
			(tracks not_allowed)
			(vias allowed)
			(pads allowed)
			(copperpour not_allowed)
			(footprints allowed)
		)
		(placement
			(enabled no)
			(sheetname "")
		)
		(fill yes
			(thermal_gap 0.5)
			(thermal_bridge_width 0.5)
			(island_removal_mode 0)
		)
		(polygon
			(pts
				(arc
					(start 340.218776 -415.38652)
					(mid 339.550756 -415.38652)
					(end 340.218776 -415.38652)
				)
			)
		)
	)
	(zone
		(layers "F.Cu" "In2.Cu" "In4.Cu")
		(hatch none 0.5)
		(connect_pads
			(clearance 0)
		)
		(min_thickness 0.25)
		(keepout
			(tracks not_allowed)
			(vias allowed)
			(pads allowed)
			(copperpour not_allowed)
			(footprints allowed)
		)
		(placement
			(enabled no)
			(sheetname "")
		)
		(fill yes
			(thermal_gap 0.5)
			(thermal_bridge_width 0.5)
			(island_removal_mode 0)
		)
		(polygon
			(pts
				(arc
					(start 404.255732 -418.412168)
					(mid 403.587712 -418.412168)
					(end 404.255732 -418.412168)
				)
			)
		)
	)
	(zone
		(layers "F.Cu" "In2.Cu" "In4.Cu")
		(hatch none 0.5)
		(connect_pads
			(clearance 0)
		)
		(min_thickness 0.25)
		(keepout
			(tracks not_allowed)
			(vias allowed)
			(pads allowed)
			(copperpour not_allowed)
			(footprints allowed)
		)
		(placement
			(enabled no)
			(sheetname "")
		)
		(fill yes
			(thermal_gap 0.5)
			(thermal_bridge_width 0.5)
			(island_removal_mode 0)
		)
		(polygon
			(pts
				(arc
					(start 410.382212 -418.412168)
					(mid 409.714192 -418.412168)
					(end 410.382212 -418.412168)
				)
			)
		)
	)
	(zone
		(layers "F.Cu" "In2.Cu" "In4.Cu")
		(hatch none 0.5)
		(connect_pads
			(clearance 0)
		)
		(min_thickness 0.25)
		(keepout
			(tracks not_allowed)
			(vias allowed)
			(pads allowed)
			(copperpour not_allowed)
			(footprints allowed)
		)
		(placement
			(enabled no)
			(sheetname "")
		)
		(fill yes
			(thermal_gap 0.5)
			(thermal_bridge_width 0.5)
			(island_removal_mode 0)
		)
		(polygon
			(pts
				(arc
					(start 379.749812 -418.412168)
					(mid 379.081792 -418.412168)
					(end 379.749812 -418.412168)
				)
			)
		)
	)
	(zone
		(layers "F.Cu" "In2.Cu" "In4.Cu")
		(hatch none 0.5)
		(connect_pads
			(clearance 0)
		)
		(min_thickness 0.25)
		(keepout
			(tracks not_allowed)
			(vias allowed)
			(pads allowed)
			(copperpour not_allowed)
			(footprints allowed)
		)
		(placement
			(enabled no)
			(sheetname "")
		)
		(fill yes
			(thermal_gap 0.5)
			(thermal_bridge_width 0.5)
			(island_removal_mode 0)
		)
		(polygon
			(pts
				(arc
					(start 407.318972 -418.412168)
					(mid 406.650952 -418.412168)
					(end 407.318972 -418.412168)
				)
			)
		)
	)
	(zone
		(layers "F.Cu" "In2.Cu" "In4.Cu")
		(hatch none 0.5)
		(connect_pads
			(clearance 0)
		)
		(min_thickness 0.25)
		(keepout
			(tracks not_allowed)
			(vias allowed)
			(pads allowed)
			(copperpour not_allowed)
			(footprints allowed)
		)
		(placement
			(enabled no)
			(sheetname "")
		)
		(fill yes
			(thermal_gap 0.5)
			(thermal_bridge_width 0.5)
			(island_removal_mode 0)
		)
		(polygon
			(pts
				(arc
					(start 314.849256 -418.412168)
					(mid 314.181236 -418.412168)
					(end 314.849256 -418.412168)
				)
			)
		)
	)
	(zone
		(layers "F.Cu" "In2.Cu" "In4.Cu")
		(hatch none 0.5)
		(connect_pads
			(clearance 0)
		)
		(min_thickness 0.25)
		(keepout
			(tracks not_allowed)
			(vias allowed)
			(pads allowed)
			(copperpour not_allowed)
			(footprints allowed)
		)
		(placement
			(enabled no)
			(sheetname "")
		)
		(fill yes
			(thermal_gap 0.5)
			(thermal_bridge_width 0.5)
			(island_removal_mode 0)
		)
		(polygon
			(pts
				(arc
					(start 314.849256 -415.38652)
					(mid 314.181236 -415.38652)
					(end 314.849256 -415.38652)
				)
			)
		)
	)
	(zone
		(layers "F.Cu" "In2.Cu" "In4.Cu")
		(hatch none 0.5)
		(connect_pads
			(clearance 0)
		)
		(min_thickness 0.25)
		(keepout
			(tracks not_allowed)
			(vias allowed)
			(pads allowed)
			(copperpour not_allowed)
			(footprints allowed)
		)
		(placement
			(enabled no)
			(sheetname "")
		)
		(fill yes
			(thermal_gap 0.5)
			(thermal_bridge_width 0.5)
			(island_removal_mode 0)
		)
		(polygon
			(pts
				(arc
					(start 339.355176 -418.412168)
					(mid 338.687156 -418.412168)
					(end 339.355176 -418.412168)
				)
			)
		)
	)
	(zone
		(layers "F.Cu" "In2.Cu" "In4.Cu")
		(hatch none 0.5)
		(connect_pads
			(clearance 0)
		)
		(min_thickness 0.25)
		(keepout
			(tracks not_allowed)
			(vias allowed)
			(pads allowed)
			(copperpour not_allowed)
			(footprints allowed)
		)
		(placement
			(enabled no)
			(sheetname "")
		)
		(fill yes
			(thermal_gap 0.5)
			(thermal_bridge_width 0.5)
			(island_removal_mode 0)
		)
		(polygon
			(pts
				(arc
					(start 336.291936 -415.38652)
					(mid 335.623916 -415.38652)
					(end 336.291936 -415.38652)
				)
			)
		)
	)
	(zone
		(layers "F.Cu" "In2.Cu" "In4.Cu")
		(hatch none 0.5)
		(connect_pads
			(clearance 0)
		)
		(min_thickness 0.25)
		(keepout
			(tracks not_allowed)
			(vias allowed)
			(pads allowed)
			(copperpour not_allowed)
			(footprints allowed)
		)
		(placement
			(enabled no)
			(sheetname "")
		)
		(fill yes
			(thermal_gap 0.5)
			(thermal_bridge_width 0.5)
			(island_removal_mode 0)
		)
		(polygon
			(pts
				(arc
					(start 123.749816 -407.00452)
					(mid 123.081796 -407.00452)
					(end 123.749816 -407.00452)
				)
			)
		)
	)
	(zone
		(layers "F.Cu" "In2.Cu" "In4.Cu")
		(hatch none 0.5)
		(connect_pads
			(clearance 0)
		)
		(min_thickness 0.25)
		(keepout
			(tracks not_allowed)
			(vias allowed)
			(pads allowed)
			(copperpour not_allowed)
			(footprints allowed)
		)
		(placement
			(enabled no)
			(sheetname "")
		)
		(fill yes
			(thermal_gap 0.5)
			(thermal_bridge_width 0.5)
			(island_removal_mode 0)
		)
		(polygon
			(pts
				(arc
					(start 375.822972 -415.38652)
					(mid 375.154952 -415.38652)
					(end 375.822972 -415.38652)
				)
			)
		)
	)
	(zone
		(layers "F.Cu" "In2.Cu" "In4.Cu")
		(hatch none 0.5)
		(connect_pads
			(clearance 0)
		)
		(min_thickness 0.25)
		(keepout
			(tracks not_allowed)
			(vias allowed)
			(pads allowed)
			(copperpour not_allowed)
			(footprints allowed)
		)
		(placement
			(enabled no)
			(sheetname "")
		)
		(fill yes
			(thermal_gap 0.5)
			(thermal_bridge_width 0.5)
			(island_removal_mode 0)
		)
		(polygon
			(pts
				(arc
					(start 71.102474 -410.030168)
					(mid 70.434454 -410.030168)
					(end 71.102474 -410.030168)
				)
			)
		)
	)
	(zone
		(layers "F.Cu" "In2.Cu" "In4.Cu")
		(hatch none 0.5)
		(connect_pads
			(clearance 0)
		)
		(min_thickness 0.25)
		(keepout
			(tracks not_allowed)
			(vias allowed)
			(pads allowed)
			(copperpour not_allowed)
			(footprints allowed)
		)
		(placement
			(enabled no)
			(sheetname "")
		)
		(fill yes
			(thermal_gap 0.5)
			(thermal_bridge_width 0.5)
			(island_removal_mode 0)
		)
		(polygon
			(pts
				(arc
					(start 409.518612 -415.38652)
					(mid 408.850592 -415.38652)
					(end 409.518612 -415.38652)
				)
			)
		)
	)
	(zone
		(layers "F.Cu" "In2.Cu" "In4.Cu")
		(hatch none 0.5)
		(connect_pads
			(clearance 0)
		)
		(min_thickness 0.25)
		(keepout
			(tracks not_allowed)
			(vias allowed)
			(pads allowed)
			(copperpour not_allowed)
			(footprints allowed)
		)
		(placement
			(enabled no)
			(sheetname "")
		)
		(fill yes
			(thermal_gap 0.5)
			(thermal_bridge_width 0.5)
			(island_removal_mode 0)
		)
		(polygon
			(pts
				(arc
					(start 372.759732 -415.38652)
					(mid 372.091712 -415.38652)
					(end 372.759732 -415.38652)
				)
			)
		)
	)
	(zone
		(layers "F.Cu" "In2.Cu" "In4.Cu")
		(hatch none 0.5)
		(connect_pads
			(clearance 0)
		)
		(min_thickness 0.25)
		(keepout
			(tracks not_allowed)
			(vias allowed)
			(pads allowed)
			(copperpour not_allowed)
			(footprints allowed)
		)
		(placement
			(enabled no)
			(sheetname "")
		)
		(fill yes
			(thermal_gap 0.5)
			(thermal_bridge_width 0.5)
			(island_removal_mode 0)
		)
		(polygon
			(pts
				(arc
					(start 410.382212 -415.38652)
					(mid 409.714192 -415.38652)
					(end 410.382212 -415.38652)
				)
			)
		)
	)
	(zone
		(layers "F.Cu" "In2.Cu" "In4.Cu")
		(hatch none 0.5)
		(connect_pads
			(clearance 0)
		)
		(min_thickness 0.25)
		(keepout
			(tracks not_allowed)
			(vias allowed)
			(pads allowed)
			(copperpour not_allowed)
			(footprints allowed)
		)
		(placement
			(enabled no)
			(sheetname "")
		)
		(fill yes
			(thermal_gap 0.5)
			(thermal_bridge_width 0.5)
			(island_removal_mode 0)
		)
		(polygon
			(pts
				(arc
					(start 117.623336 -407.00452)
					(mid 116.955316 -407.00452)
					(end 117.623336 -407.00452)
				)
			)
		)
	)
	(zone
		(layers "F.Cu" "In2.Cu" "In4.Cu")
		(hatch none 0.5)
		(connect_pads
			(clearance 0)
		)
		(min_thickness 0.25)
		(keepout
			(tracks not_allowed)
			(vias allowed)
			(pads allowed)
			(copperpour not_allowed)
			(footprints allowed)
		)
		(placement
			(enabled no)
			(sheetname "")
		)
		(fill yes
			(thermal_gap 0.5)
			(thermal_bridge_width 0.5)
			(island_removal_mode 0)
		)
		(polygon
			(pts
				(arc
					(start 321.839336 -415.38652)
					(mid 321.171316 -415.38652)
					(end 321.839336 -415.38652)
				)
			)
		)
	)
	(zone
		(layers "F.Cu" "In2.Cu" "In4.Cu")
		(hatch none 0.5)
		(connect_pads
			(clearance 0)
		)
		(min_thickness 0.25)
		(keepout
			(tracks not_allowed)
			(vias allowed)
			(pads allowed)
			(copperpour not_allowed)
			(footprints allowed)
		)
		(placement
			(enabled no)
			(sheetname "")
		)
		(fill yes
			(thermal_gap 0.5)
			(thermal_bridge_width 0.5)
			(island_removal_mode 0)
		)
		(polygon
			(pts
				(arc
					(start 119.822976 -407.00452)
					(mid 119.154956 -407.00452)
					(end 119.822976 -407.00452)
				)
			)
		)
	)
	(zone
		(layers "F.Cu" "In2.Cu" "In4.Cu")
		(hatch none 0.5)
		(connect_pads
			(clearance 0)
		)
		(min_thickness 0.25)
		(keepout
			(tracks not_allowed)
			(vias allowed)
			(pads allowed)
			(copperpour not_allowed)
			(footprints allowed)
		)
		(placement
			(enabled no)
			(sheetname "")
		)
		(fill yes
			(thermal_gap 0.5)
			(thermal_bridge_width 0.5)
			(island_removal_mode 0)
		)
		(polygon
			(pts
				(arc
					(start 126.813056 -407.00452)
					(mid 126.145036 -407.00452)
					(end 126.813056 -407.00452)
				)
			)
		)
	)
	(zone
		(layers "F.Cu" "In2.Cu" "In4.Cu")
		(hatch none 0.5)
		(connect_pads
			(clearance 0)
		)
		(min_thickness 0.25)
		(keepout
			(tracks not_allowed)
			(vias allowed)
			(pads allowed)
			(copperpour not_allowed)
			(footprints allowed)
		)
		(placement
			(enabled no)
			(sheetname "")
		)
		(fill yes
			(thermal_gap 0.5)
			(thermal_bridge_width 0.5)
			(island_removal_mode 0)
		)
		(polygon
			(pts
				(arc
					(start 305.659536 -418.412168)
					(mid 304.991516 -418.412168)
					(end 305.659536 -418.412168)
				)
			)
		)
	)
	(zone
		(layers "F.Cu" "In2.Cu" "In4.Cu")
		(hatch none 0.5)
		(connect_pads
			(clearance 0)
		)
		(min_thickness 0.25)
		(keepout
			(tracks not_allowed)
			(vias allowed)
			(pads allowed)
			(copperpour not_allowed)
			(footprints allowed)
		)
		(placement
			(enabled no)
			(sheetname "")
		)
		(fill yes
			(thermal_gap 0.5)
			(thermal_bridge_width 0.5)
			(island_removal_mode 0)
		)
		(polygon
			(pts
				(arc
					(start 132.939536 -407.00452)
					(mid 132.271516 -407.00452)
					(end 132.939536 -407.00452)
				)
			)
		)
	)
	(zone
		(layers "F.Cu" "In2.Cu" "In4.Cu")
		(hatch none 0.5)
		(connect_pads
			(clearance 0)
		)
		(min_thickness 0.25)
		(keepout
			(tracks not_allowed)
			(vias allowed)
			(pads allowed)
			(copperpour not_allowed)
			(footprints allowed)
		)
		(placement
			(enabled no)
			(sheetname "")
		)
		(fill yes
			(thermal_gap 0.5)
			(thermal_bridge_width 0.5)
			(island_removal_mode 0)
		)
		(polygon
			(pts
				(arc
					(start 156.581856 -410.030168)
					(mid 155.913836 -410.030168)
					(end 156.581856 -410.030168)
				)
			)
		)
	)
	(zone
		(layers "F.Cu" "In2.Cu" "In4.Cu")
		(hatch none 0.5)
		(connect_pads
			(clearance 0)
		)
		(min_thickness 0.25)
		(keepout
			(tracks not_allowed)
			(vias allowed)
			(pads allowed)
			(copperpour not_allowed)
			(footprints allowed)
		)
		(placement
			(enabled no)
			(sheetname "")
		)
		(fill yes
			(thermal_gap 0.5)
			(thermal_bridge_width 0.5)
			(island_removal_mode 0)
		)
		(polygon
			(pts
				(arc
					(start 330.165456 -415.38652)
					(mid 329.497436 -415.38652)
					(end 330.165456 -415.38652)
				)
			)
		)
	)
	(zone
		(layers "F.Cu" "In2.Cu" "In4.Cu")
		(hatch none 0.5)
		(connect_pads
			(clearance 0)
		)
		(min_thickness 0.25)
		(keepout
			(tracks not_allowed)
			(vias allowed)
			(pads allowed)
			(copperpour not_allowed)
			(footprints allowed)
		)
		(placement
			(enabled no)
			(sheetname "")
		)
		(fill yes
			(thermal_gap 0.5)
			(thermal_bridge_width 0.5)
			(island_removal_mode 0)
		)
		(polygon
			(pts
				(arc
					(start 90.345514 -410.030168)
					(mid 89.677494 -410.030168)
					(end 90.345514 -410.030168)
				)
			)
		)
	)
	(zone
		(layers "F.Cu" "In2.Cu" "In4.Cu")
		(hatch none 0.5)
		(connect_pads
			(clearance 0)
		)
		(min_thickness 0.25)
		(keepout
			(tracks not_allowed)
			(vias allowed)
			(pads allowed)
			(copperpour not_allowed)
			(footprints allowed)
		)
		(placement
			(enabled no)
			(sheetname "")
		)
		(fill yes
			(thermal_gap 0.5)
			(thermal_bridge_width 0.5)
			(island_removal_mode 0)
		)
		(polygon
			(pts
				(arc
					(start 345.481656 -415.38652)
					(mid 344.813636 -415.38652)
					(end 345.481656 -415.38652)
				)
			)
		)
	)
	(zone
		(layers "F.Cu" "In2.Cu" "In4.Cu")
		(hatch none 0.5)
		(connect_pads
			(clearance 0)
		)
		(min_thickness 0.25)
		(keepout
			(tracks not_allowed)
			(vias allowed)
			(pads allowed)
			(copperpour not_allowed)
			(footprints allowed)
		)
		(placement
			(enabled no)
			(sheetname "")
		)
		(fill yes
			(thermal_gap 0.5)
			(thermal_bridge_width 0.5)
			(island_removal_mode 0)
		)
		(polygon
			(pts
				(arc
					(start 135.139176 -407.00452)
					(mid 134.471156 -407.00452)
					(end 135.139176 -407.00452)
				)
			)
		)
	)
	(zone
		(layers "F.Cu" "In2.Cu" "In4.Cu")
		(hatch none 0.5)
		(connect_pads
			(clearance 0)
		)
		(min_thickness 0.25)
		(keepout
			(tracks not_allowed)
			(vias allowed)
			(pads allowed)
			(copperpour not_allowed)
			(footprints allowed)
		)
		(placement
			(enabled no)
			(sheetname "")
		)
		(fill yes
			(thermal_gap 0.5)
			(thermal_bridge_width 0.5)
			(island_removal_mode 0)
		)
		(polygon
			(pts
				(arc
					(start 50.523394 -410.030168)
					(mid 49.855374 -410.030168)
					(end 50.523394 -410.030168)
				)
			)
		)
	)
	(zone
		(layers "F.Cu" "In2.Cu" "In4.Cu")
		(hatch none 0.5)
		(connect_pads
			(clearance 0)
		)
		(min_thickness 0.25)
		(keepout
			(tracks not_allowed)
			(vias allowed)
			(pads allowed)
			(copperpour not_allowed)
			(footprints allowed)
		)
		(placement
			(enabled no)
			(sheetname "")
		)
		(fill yes
			(thermal_gap 0.5)
			(thermal_bridge_width 0.5)
			(island_removal_mode 0)
		)
		(polygon
			(pts
				(arc
					(start 148.255736 -410.030168)
					(mid 147.587716 -410.030168)
					(end 148.255736 -410.030168)
				)
			)
		)
	)
	(zone
		(layers "F.Cu" "In2.Cu" "In4.Cu")
		(hatch none 0.5)
		(connect_pads
			(clearance 0)
		)
		(min_thickness 0.25)
		(keepout
			(tracks not_allowed)
			(vias allowed)
			(pads allowed)
			(copperpour not_allowed)
			(footprints allowed)
		)
		(placement
			(enabled no)
			(sheetname "")
		)
		(fill yes
			(thermal_gap 0.5)
			(thermal_bridge_width 0.5)
			(island_removal_mode 0)
		)
		(polygon
			(pts
				(arc
					(start 144.328896 -407.00452)
					(mid 143.660876 -407.00452)
					(end 144.328896 -407.00452)
				)
			)
		)
	)
	(zone
		(layers "F.Cu" "In2.Cu" "In4.Cu")
		(hatch none 0.5)
		(connect_pads
			(clearance 0)
		)
		(min_thickness 0.25)
		(keepout
			(tracks not_allowed)
			(vias allowed)
			(pads allowed)
			(copperpour not_allowed)
			(footprints allowed)
		)
		(placement
			(enabled no)
			(sheetname "")
		)
		(fill yes
			(thermal_gap 0.5)
			(thermal_bridge_width 0.5)
			(island_removal_mode 0)
		)
		(polygon
			(pts
				(arc
					(start 330.165456 -418.412168)
					(mid 329.497436 -418.412168)
					(end 330.165456 -418.412168)
				)
			)
		)
	)
	(zone
		(layers "F.Cu" "In2.Cu" "In4.Cu")
		(hatch none 0.5)
		(connect_pads
			(clearance 0)
		)
		(min_thickness 0.25)
		(keepout
			(tracks not_allowed)
			(vias allowed)
			(pads allowed)
			(copperpour not_allowed)
			(footprints allowed)
		)
		(placement
			(enabled no)
			(sheetname "")
		)
		(fill yes
			(thermal_gap 0.5)
			(thermal_bridge_width 0.5)
			(island_removal_mode 0)
		)
		(polygon
			(pts
				(arc
					(start 412.581852 -415.38652)
					(mid 411.913832 -415.38652)
					(end 412.581852 -415.38652)
				)
			)
		)
	)
	(zone
		(layers "F.Cu" "In2.Cu" "In4.Cu")
		(hatch none 0.5)
		(connect_pads
			(clearance 0)
		)
		(min_thickness 0.25)
		(keepout
			(tracks not_allowed)
			(vias allowed)
			(pads allowed)
			(copperpour not_allowed)
			(footprints allowed)
		)
		(placement
			(enabled no)
			(sheetname "")
		)
		(fill yes
			(thermal_gap 0.5)
			(thermal_bridge_width 0.5)
			(island_removal_mode 0)
		)
		(polygon
			(pts
				(arc
					(start 382.813052 -418.412168)
					(mid 382.145032 -418.412168)
					(end 382.813052 -418.412168)
				)
			)
		)
	)
	(zone
		(layers "F.Cu" "In2.Cu" "In4.Cu")
		(hatch none 0.5)
		(connect_pads
			(clearance 0)
		)
		(min_thickness 0.25)
		(keepout
			(tracks not_allowed)
			(vias allowed)
			(pads allowed)
			(copperpour not_allowed)
			(footprints allowed)
		)
		(placement
			(enabled no)
			(sheetname "")
		)
		(fill yes
			(thermal_gap 0.5)
			(thermal_bridge_width 0.5)
			(island_removal_mode 0)
		)
		(polygon
			(pts
				(arc
					(start 129.876296 -410.030168)
					(mid 129.208276 -410.030168)
					(end 129.876296 -410.030168)
				)
			)
		)
	)
	(zone
		(layers "F.Cu" "In2.Cu" "In4.Cu")
		(hatch none 0.5)
		(connect_pads
			(clearance 0)
		)
		(min_thickness 0.25)
		(keepout
			(tracks not_allowed)
			(vias allowed)
			(pads allowed)
			(copperpour not_allowed)
			(footprints allowed)
		)
		(placement
			(enabled no)
			(sheetname "")
		)
		(fill yes
			(thermal_gap 0.5)
			(thermal_bridge_width 0.5)
			(island_removal_mode 0)
		)
		(polygon
			(pts
				(arc
					(start 142.129256 -407.00452)
					(mid 141.461236 -407.00452)
					(end 142.129256 -407.00452)
				)
			)
		)
	)
	(zone
		(layers "F.Cu" "In2.Cu" "In4.Cu")
		(hatch none 0.5)
		(connect_pads
			(clearance 0)
		)
		(min_thickness 0.25)
		(keepout
			(tracks not_allowed)
			(vias allowed)
			(pads allowed)
			(copperpour not_allowed)
			(footprints allowed)
		)
		(placement
			(enabled no)
			(sheetname "")
		)
		(fill yes
			(thermal_gap 0.5)
			(thermal_bridge_width 0.5)
			(island_removal_mode 0)
		)
		(polygon
			(pts
				(arc
					(start 318.776096 -418.412168)
					(mid 318.108076 -418.412168)
					(end 318.776096 -418.412168)
				)
			)
		)
	)
	(zone
		(layers "F.Cu" "In2.Cu" "In4.Cu")
		(hatch none 0.5)
		(connect_pads
			(clearance 0)
		)
		(min_thickness 0.25)
		(keepout
			(tracks not_allowed)
			(vias allowed)
			(pads allowed)
			(copperpour not_allowed)
			(footprints allowed)
		)
		(placement
			(enabled no)
			(sheetname "")
		)
		(fill yes
			(thermal_gap 0.5)
			(thermal_bridge_width 0.5)
			(island_removal_mode 0)
		)
		(polygon
			(pts
				(arc
					(start 68.902834 -410.030168)
					(mid 68.234814 -410.030168)
					(end 68.902834 -410.030168)
				)
			)
		)
	)
	(zone
		(layers "F.Cu" "In2.Cu" "In4.Cu")
		(hatch none 0.5)
		(connect_pads
			(clearance 0)
		)
		(min_thickness 0.25)
		(keepout
			(tracks not_allowed)
			(vias allowed)
			(pads allowed)
			(copperpour not_allowed)
			(footprints allowed)
		)
		(placement
			(enabled no)
			(sheetname "")
		)
		(fill yes
			(thermal_gap 0.5)
			(thermal_bridge_width 0.5)
			(island_removal_mode 0)
		)
		(polygon
			(pts
				(arc
					(start 334.092296 -415.38652)
					(mid 333.424276 -415.38652)
					(end 334.092296 -415.38652)
				)
			)
		)
	)
	(zone
		(layers "F.Cu" "In2.Cu" "In4.Cu")
		(hatch none 0.5)
		(connect_pads
			(clearance 0)
		)
		(min_thickness 0.25)
		(keepout
			(tracks not_allowed)
			(vias allowed)
			(pads allowed)
			(copperpour not_allowed)
			(footprints allowed)
		)
		(placement
			(enabled no)
			(sheetname "")
		)
		(fill yes
			(thermal_gap 0.5)
			(thermal_bridge_width 0.5)
			(island_removal_mode 0)
		)
		(polygon
			(pts
				(arc
					(start 125.949456 -410.030168)
					(mid 125.281436 -410.030168)
					(end 125.949456 -410.030168)
				)
			)
		)
	)
	(zone
		(layers "F.Cu" "In2.Cu" "In4.Cu")
		(hatch none 0.5)
		(connect_pads
			(clearance 0)
		)
		(min_thickness 0.25)
		(keepout
			(tracks not_allowed)
			(vias allowed)
			(pads allowed)
			(copperpour not_allowed)
			(footprints allowed)
		)
		(placement
			(enabled no)
			(sheetname "")
		)
		(fill yes
			(thermal_gap 0.5)
			(thermal_bridge_width 0.5)
			(island_removal_mode 0)
		)
		(polygon
			(pts
				(arc
					(start 129.012696 -407.00452)
					(mid 128.344676 -407.00452)
					(end 129.012696 -407.00452)
				)
			)
		)
	)
	(zone
		(layers "F.Cu" "In2.Cu" "In4.Cu")
		(hatch none 0.5)
		(connect_pads
			(clearance 0)
		)
		(min_thickness 0.25)
		(keepout
			(tracks not_allowed)
			(vias allowed)
			(pads allowed)
			(copperpour not_allowed)
			(footprints allowed)
		)
		(placement
			(enabled no)
			(sheetname "")
		)
		(fill yes
			(thermal_gap 0.5)
			(thermal_bridge_width 0.5)
			(island_removal_mode 0)
		)
		(polygon
			(pts
				(arc
					(start 318.776096 -415.38652)
					(mid 318.108076 -415.38652)
					(end 318.776096 -415.38652)
				)
			)
		)
	)
	(zone
		(layers "F.Cu" "In2.Cu" "In4.Cu")
		(hatch none 0.5)
		(connect_pads
			(clearance 0)
		)
		(min_thickness 0.25)
		(keepout
			(tracks not_allowed)
			(vias allowed)
			(pads allowed)
			(copperpour not_allowed)
			(footprints allowed)
		)
		(placement
			(enabled no)
			(sheetname "")
		)
		(fill yes
			(thermal_gap 0.5)
			(thermal_bridge_width 0.5)
			(island_removal_mode 0)
		)
		(polygon
			(pts
				(arc
					(start 336.291936 -418.412168)
					(mid 335.623916 -418.412168)
					(end 336.291936 -418.412168)
				)
			)
		)
	)
	(zone
		(layers "F.Cu" "In2.Cu" "In4.Cu")
		(hatch none 0.5)
		(connect_pads
			(clearance 0)
		)
		(min_thickness 0.25)
		(keepout
			(tracks not_allowed)
			(vias allowed)
			(pads allowed)
			(copperpour not_allowed)
			(footprints allowed)
		)
		(placement
			(enabled no)
			(sheetname "")
		)
		(fill yes
			(thermal_gap 0.5)
			(thermal_bridge_width 0.5)
			(island_removal_mode 0)
		)
		(polygon
			(pts
				(arc
					(start 337.155536 -418.412168)
					(mid 336.487516 -418.412168)
					(end 337.155536 -418.412168)
				)
			)
		)
	)
	(zone
		(layers "F.Cu" "In2.Cu" "In4.Cu")
		(hatch none 0.5)
		(connect_pads
			(clearance 0)
		)
		(min_thickness 0.25)
		(keepout
			(tracks not_allowed)
			(vias allowed)
			(pads allowed)
			(copperpour not_allowed)
			(footprints allowed)
		)
		(placement
			(enabled no)
			(sheetname "")
		)
		(fill yes
			(thermal_gap 0.5)
			(thermal_bridge_width 0.5)
			(island_removal_mode 0)
		)
		(polygon
			(pts
				(arc
					(start 41.9227 -414.520126)
					(mid 41.25468 -414.520126)
					(end 41.9227 -414.520126)
				)
			)
		)
	)
	(zone
		(layers "F.Cu" "In2.Cu" "In4.Cu")
		(hatch none 0.5)
		(connect_pads
			(clearance 0)
		)
		(min_thickness 0.25)
		(keepout
			(tracks not_allowed)
			(vias allowed)
			(pads allowed)
			(copperpour not_allowed)
			(footprints allowed)
		)
		(placement
			(enabled no)
			(sheetname "")
		)
		(fill yes
			(thermal_gap 0.5)
			(thermal_bridge_width 0.5)
			(island_removal_mode 0)
		)
		(polygon
			(pts
				(arc
					(start 160.508696 -410.030168)
					(mid 159.840676 -410.030168)
					(end 160.508696 -410.030168)
				)
			)
		)
	)
	(zone
		(layers "F.Cu" "In2.Cu" "In4.Cu")
		(hatch none 0.5)
		(connect_pads
			(clearance 0)
		)
		(min_thickness 0.25)
		(keepout
			(tracks not_allowed)
			(vias allowed)
			(pads allowed)
			(copperpour not_allowed)
			(footprints allowed)
		)
		(placement
			(enabled no)
			(sheetname "")
		)
		(fill yes
			(thermal_gap 0.5)
			(thermal_bridge_width 0.5)
			(island_removal_mode 0)
		)
		(polygon
			(pts
				(arc
					(start 157.445456 -407.00452)
					(mid 156.777436 -407.00452)
					(end 157.445456 -407.00452)
				)
			)
		)
	)
	(zone
		(layers "F.Cu" "In2.Cu" "In4.Cu")
		(hatch none 0.5)
		(connect_pads
			(clearance 0)
		)
		(min_thickness 0.25)
		(keepout
			(tracks not_allowed)
			(vias allowed)
			(pads allowed)
			(copperpour not_allowed)
			(footprints allowed)
		)
		(placement
			(enabled no)
			(sheetname "")
		)
		(fill yes
			(thermal_gap 0.5)
			(thermal_bridge_width 0.5)
			(island_removal_mode 0)
		)
		(polygon
			(pts
				(arc
					(start 309.586376 -418.412168)
					(mid 308.918356 -418.412168)
					(end 309.586376 -418.412168)
				)
			)
		)
	)
	(zone
		(layers "F.Cu" "In2.Cu" "In4.Cu")
		(hatch none 0.5)
		(connect_pads
			(clearance 0)
		)
		(min_thickness 0.25)
		(keepout
			(tracks not_allowed)
			(vias allowed)
			(pads allowed)
			(copperpour not_allowed)
			(footprints allowed)
		)
		(placement
			(enabled no)
			(sheetname "")
		)
		(fill yes
			(thermal_gap 0.5)
			(thermal_bridge_width 0.5)
			(island_removal_mode 0)
		)
		(polygon
			(pts
				(arc
					(start 382.813052 -415.38652)
					(mid 382.145032 -415.38652)
					(end 382.813052 -415.38652)
				)
			)
		)
	)
	(zone
		(layers "F.Cu" "In2.Cu" "In4.Cu")
		(hatch none 0.5)
		(connect_pads
			(clearance 0)
		)
		(min_thickness 0.25)
		(keepout
			(tracks not_allowed)
			(vias allowed)
			(pads allowed)
			(copperpour not_allowed)
			(footprints allowed)
		)
		(placement
			(enabled no)
			(sheetname "")
		)
		(fill yes
			(thermal_gap 0.5)
			(thermal_bridge_width 0.5)
			(island_removal_mode 0)
		)
		(polygon
			(pts
				(arc
					(start 306.523136 -415.38652)
					(mid 305.855116 -415.38652)
					(end 306.523136 -415.38652)
				)
			)
		)
	)
	(zone
		(layers "F.Cu" "In2.Cu" "In4.Cu")
		(hatch none 0.5)
		(connect_pads
			(clearance 0)
		)
		(min_thickness 0.25)
		(keepout
			(tracks not_allowed)
			(vias allowed)
			(pads allowed)
			(copperpour not_allowed)
			(footprints allowed)
		)
		(placement
			(enabled no)
			(sheetname "")
		)
		(fill yes
			(thermal_gap 0.5)
			(thermal_bridge_width 0.5)
			(island_removal_mode 0)
		)
		(polygon
			(pts
				(arc
					(start 376.686572 -418.412168)
					(mid 376.018552 -418.412168)
					(end 376.686572 -418.412168)
				)
			)
		)
	)
	(zone
		(layers "F.Cu" "In2.Cu" "In4.Cu")
		(hatch none 0.5)
		(connect_pads
			(clearance 0)
		)
		(min_thickness 0.25)
		(keepout
			(tracks not_allowed)
			(vias allowed)
			(pads allowed)
			(copperpour not_allowed)
			(footprints allowed)
		)
		(placement
			(enabled no)
			(sheetname "")
		)
		(fill yes
			(thermal_gap 0.5)
			(thermal_bridge_width 0.5)
			(island_removal_mode 0)
		)
		(polygon
			(pts
				(arc
					(start 83.355434 -410.030168)
					(mid 82.687414 -410.030168)
					(end 83.355434 -410.030168)
				)
			)
		)
	)
	(zone
		(layers "F.Cu" "In2.Cu" "In4.Cu")
		(hatch none 0.5)
		(connect_pads
			(clearance 0)
		)
		(min_thickness 0.25)
		(keepout
			(tracks not_allowed)
			(vias allowed)
			(pads allowed)
			(copperpour not_allowed)
			(footprints allowed)
		)
		(placement
			(enabled no)
			(sheetname "")
		)
		(fill yes
			(thermal_gap 0.5)
			(thermal_bridge_width 0.5)
			(island_removal_mode 0)
		)
		(polygon
			(pts
				(arc
					(start 398.129252 -415.38652)
					(mid 397.461232 -415.38652)
					(end 398.129252 -415.38652)
				)
			)
		)
	)
	(zone
		(layers "F.Cu" "In2.Cu" "In4.Cu")
		(hatch none 0.5)
		(connect_pads
			(clearance 0)
		)
		(min_thickness 0.25)
		(keepout
			(tracks not_allowed)
			(vias allowed)
			(pads allowed)
			(copperpour not_allowed)
			(footprints allowed)
		)
		(placement
			(enabled no)
			(sheetname "")
		)
		(fill yes
			(thermal_gap 0.5)
			(thermal_bridge_width 0.5)
			(island_removal_mode 0)
		)
		(polygon
			(pts
				(arc
					(start 391.139172 -415.38652)
					(mid 390.471152 -415.38652)
					(end 391.139172 -415.38652)
				)
			)
		)
	)
	(zone
		(layers "F.Cu" "In2.Cu" "In4.Cu")
		(hatch none 0.5)
		(connect_pads
			(clearance 0)
		)
		(min_thickness 0.25)
		(keepout
			(tracks not_allowed)
			(vias allowed)
			(pads allowed)
			(copperpour not_allowed)
			(footprints allowed)
		)
		(placement
			(enabled no)
			(sheetname "")
		)
		(fill yes
			(thermal_gap 0.5)
			(thermal_bridge_width 0.5)
			(island_removal_mode 0)
		)
		(polygon
			(pts
				(arc
					(start 142.129256 -410.030168)
					(mid 141.461236 -410.030168)
					(end 142.129256 -410.030168)
				)
			)
		)
	)
	(zone
		(layers "F.Cu" "In2.Cu" "In4.Cu")
		(hatch none 0.5)
		(connect_pads
			(clearance 0)
		)
		(min_thickness 0.25)
		(keepout
			(tracks not_allowed)
			(vias allowed)
			(pads allowed)
			(copperpour not_allowed)
			(footprints allowed)
		)
		(placement
			(enabled no)
			(sheetname "")
		)
		(fill yes
			(thermal_gap 0.5)
			(thermal_bridge_width 0.5)
			(island_removal_mode 0)
		)
		(polygon
			(pts
				(arc
					(start 392.002772 -418.412168)
					(mid 391.334752 -418.412168)
					(end 392.002772 -418.412168)
				)
			)
		)
	)
	(zone
		(layers "F.Cu" "In2.Cu" "In4.Cu")
		(hatch none 0.5)
		(connect_pads
			(clearance 0)
		)
		(min_thickness 0.25)
		(keepout
			(tracks not_allowed)
			(vias allowed)
			(pads allowed)
			(copperpour not_allowed)
			(footprints allowed)
		)
		(placement
			(enabled no)
			(sheetname "")
		)
		(fill yes
			(thermal_gap 0.5)
			(thermal_bridge_width 0.5)
			(island_removal_mode 0)
		)
		(polygon
			(pts
				(arc
					(start 144.328896 -410.030168)
					(mid 143.660876 -410.030168)
					(end 144.328896 -410.030168)
				)
			)
		)
	)
	(zone
		(layers "F.Cu" "In2.Cu" "In4.Cu")
		(hatch none 0.5)
		(connect_pads
			(clearance 0)
		)
		(min_thickness 0.25)
		(keepout
			(tracks not_allowed)
			(vias allowed)
			(pads allowed)
			(copperpour not_allowed)
			(footprints allowed)
		)
		(placement
			(enabled no)
			(sheetname "")
		)
		(fill yes
			(thermal_gap 0.5)
			(thermal_bridge_width 0.5)
			(island_removal_mode 0)
		)
		(polygon
			(pts
				(arc
					(start 419.571932 -418.412168)
					(mid 418.903912 -418.412168)
					(end 419.571932 -418.412168)
				)
			)
		)
	)
	(zone
		(layers "F.Cu" "In2.Cu" "In4.Cu")
		(hatch none 0.5)
		(connect_pads
			(clearance 0)
		)
		(min_thickness 0.25)
		(keepout
			(tracks not_allowed)
			(vias allowed)
			(pads allowed)
			(copperpour not_allowed)
			(footprints allowed)
		)
		(placement
			(enabled no)
			(sheetname "")
		)
		(fill yes
			(thermal_gap 0.5)
			(thermal_bridge_width 0.5)
			(island_removal_mode 0)
		)
		(polygon
			(pts
				(arc
					(start 84.219034 -410.030168)
					(mid 83.551014 -410.030168)
					(end 84.219034 -410.030168)
				)
			)
		)
	)
	(zone
		(layers "F.Cu" "In2.Cu" "In4.Cu")
		(hatch none 0.5)
		(connect_pads
			(clearance 0)
		)
		(min_thickness 0.25)
		(keepout
			(tracks not_allowed)
			(vias allowed)
			(pads allowed)
			(copperpour not_allowed)
			(footprints allowed)
		)
		(placement
			(enabled no)
			(sheetname "")
		)
		(fill yes
			(thermal_gap 0.5)
			(thermal_bridge_width 0.5)
			(island_removal_mode 0)
		)
		(polygon
			(pts
				(arc
					(start 351.608136 -415.38652)
					(mid 350.940116 -415.38652)
					(end 351.608136 -415.38652)
				)
			)
		)
	)
	(zone
		(layers "F.Cu" "In2.Cu" "In4.Cu")
		(hatch none 0.5)
		(connect_pads
			(clearance 0)
		)
		(min_thickness 0.25)
		(keepout
			(tracks not_allowed)
			(vias allowed)
			(pads allowed)
			(copperpour not_allowed)
			(footprints allowed)
		)
		(placement
			(enabled no)
			(sheetname "")
		)
		(fill yes
			(thermal_gap 0.5)
			(thermal_bridge_width 0.5)
			(island_removal_mode 0)
		)
		(polygon
			(pts
				(arc
					(start 62.776354 -410.030168)
					(mid 62.108334 -410.030168)
					(end 62.776354 -410.030168)
				)
			)
		)
	)
	(zone
		(layers "F.Cu" "In2.Cu" "In4.Cu")
		(hatch none 0.5)
		(connect_pads
			(clearance 0)
		)
		(min_thickness 0.25)
		(keepout
			(tracks not_allowed)
			(vias allowed)
			(pads allowed)
			(copperpour not_allowed)
			(footprints allowed)
		)
		(placement
			(enabled no)
			(sheetname "")
		)
		(fill yes
			(thermal_gap 0.5)
			(thermal_bridge_width 0.5)
			(island_removal_mode 0)
		)
		(polygon
			(pts
				(arc
					(start 394.202412 -415.38652)
					(mid 393.534392 -415.38652)
					(end 394.202412 -415.38652)
				)
			)
		)
	)
	(zone
		(layers "F.Cu" "In2.Cu" "In4.Cu")
		(hatch none 0.5)
		(connect_pads
			(clearance 0)
		)
		(min_thickness 0.25)
		(keepout
			(tracks not_allowed)
			(vias allowed)
			(pads allowed)
			(copperpour not_allowed)
			(footprints allowed)
		)
		(placement
			(enabled no)
			(sheetname "")
		)
		(fill yes
			(thermal_gap 0.5)
			(thermal_bridge_width 0.5)
			(island_removal_mode 0)
		)
		(polygon
			(pts
				(arc
					(start 132.075936 -410.030168)
					(mid 131.407916 -410.030168)
					(end 132.075936 -410.030168)
				)
			)
		)
	)
	(zone
		(layers "F.Cu" "In2.Cu" "In4.Cu")
		(hatch none 0.5)
		(connect_pads
			(clearance 0)
		)
		(min_thickness 0.25)
		(keepout
			(tracks not_allowed)
			(vias allowed)
			(pads allowed)
			(copperpour not_allowed)
			(footprints allowed)
		)
		(placement
			(enabled no)
			(sheetname "")
		)
		(fill yes
			(thermal_gap 0.5)
			(thermal_bridge_width 0.5)
			(island_removal_mode 0)
		)
		(polygon
			(pts
				(arc
					(start 162.708336 -410.030168)
					(mid 162.040316 -410.030168)
					(end 162.708336 -410.030168)
				)
			)
		)
	)
	(zone
		(layers "F.Cu" "In2.Cu" "In4.Cu")
		(hatch none 0.5)
		(connect_pads
			(clearance 0)
		)
		(min_thickness 0.25)
		(keepout
			(tracks not_allowed)
			(vias allowed)
			(pads allowed)
			(copperpour not_allowed)
			(footprints allowed)
		)
		(placement
			(enabled no)
			(sheetname "")
		)
		(fill yes
			(thermal_gap 0.5)
			(thermal_bridge_width 0.5)
			(island_removal_mode 0)
		)
		(polygon
			(pts
				(arc
					(start 378.886212 -415.38652)
					(mid 378.218192 -415.38652)
					(end 378.886212 -415.38652)
				)
			)
		)
	)
	(zone
		(layers "F.Cu" "In2.Cu" "In4.Cu")
		(hatch none 0.5)
		(connect_pads
			(clearance 0)
		)
		(min_thickness 0.25)
		(keepout
			(tracks not_allowed)
			(vias allowed)
			(pads allowed)
			(copperpour not_allowed)
			(footprints allowed)
		)
		(placement
			(enabled no)
			(sheetname "")
		)
		(fill yes
			(thermal_gap 0.5)
			(thermal_bridge_width 0.5)
			(island_removal_mode 0)
		)
		(polygon
			(pts
				(arc
					(start 385.876292 -415.38652)
					(mid 385.208272 -415.38652)
					(end 385.876292 -415.38652)
				)
			)
		)
	)
	(zone
		(layers "F.Cu" "In2.Cu" "In4.Cu")
		(hatch none 0.5)
		(connect_pads
			(clearance 0)
		)
		(min_thickness 0.25)
		(keepout
			(tracks not_allowed)
			(vias allowed)
			(pads allowed)
			(copperpour not_allowed)
			(footprints allowed)
		)
		(placement
			(enabled no)
			(sheetname "")
		)
		(fill yes
			(thermal_gap 0.5)
			(thermal_bridge_width 0.5)
			(island_removal_mode 0)
		)
		(polygon
			(pts
				(arc
					(start 39.69004 -413.4485)
					(mid 39.02202 -413.4485)
					(end 39.69004 -413.4485)
				)
			)
		)
	)
	(zone
		(layers "F.Cu" "In2.Cu" "In4.Cu")
		(hatch none 0.5)
		(connect_pads
			(clearance 0)
		)
		(min_thickness 0.25)
		(keepout
			(tracks not_allowed)
			(vias allowed)
			(pads allowed)
			(copperpour not_allowed)
			(footprints allowed)
		)
		(placement
			(enabled no)
			(sheetname "")
		)
		(fill yes
			(thermal_gap 0.5)
			(thermal_bridge_width 0.5)
			(island_removal_mode 0)
		)
		(polygon
			(pts
				(arc
					(start 337.155536 -415.38652)
					(mid 336.487516 -415.38652)
					(end 337.155536 -415.38652)
				)
			)
		)
	)
	(zone
		(layers "F.Cu" "In2.Cu" "In4.Cu")
		(hatch none 0.5)
		(connect_pads
			(clearance 0)
		)
		(min_thickness 0.25)
		(keepout
			(tracks not_allowed)
			(vias allowed)
			(pads allowed)
			(copperpour not_allowed)
			(footprints allowed)
		)
		(placement
			(enabled no)
			(sheetname "")
		)
		(fill yes
			(thermal_gap 0.5)
			(thermal_bridge_width 0.5)
			(island_removal_mode 0)
		)
		(polygon
			(pts
				(arc
					(start 397.265652 -415.38652)
					(mid 396.597632 -415.38652)
					(end 397.265652 -415.38652)
				)
			)
		)
	)
	(zone
		(layers "F.Cu" "In2.Cu" "In4.Cu")
		(hatch none 0.5)
		(connect_pads
			(clearance 0)
		)
		(min_thickness 0.25)
		(keepout
			(tracks not_allowed)
			(vias allowed)
			(pads allowed)
			(copperpour not_allowed)
			(footprints allowed)
		)
		(placement
			(enabled no)
			(sheetname "")
		)
		(fill yes
			(thermal_gap 0.5)
			(thermal_bridge_width 0.5)
			(island_removal_mode 0)
		)
		(polygon
			(pts
				(arc
					(start 117.623336 -410.030168)
					(mid 116.955316 -410.030168)
					(end 117.623336 -410.030168)
				)
			)
		)
	)
	(zone
		(layers "F.Cu" "In2.Cu" "In4.Cu")
		(hatch none 0.5)
		(connect_pads
			(clearance 0)
		)
		(min_thickness 0.25)
		(keepout
			(tracks not_allowed)
			(vias allowed)
			(pads allowed)
			(copperpour not_allowed)
			(footprints allowed)
		)
		(placement
			(enabled no)
			(sheetname "")
		)
		(fill yes
			(thermal_gap 0.5)
			(thermal_bridge_width 0.5)
			(island_removal_mode 0)
		)
		(polygon
			(pts
				(arc
					(start 343.282016 -415.38652)
					(mid 342.613996 -415.38652)
					(end 343.282016 -415.38652)
				)
			)
		)
	)
	(zone
		(layers "F.Cu" "In2.Cu" "In4.Cu")
		(hatch none 0.5)
		(connect_pads
			(clearance 0)
		)
		(min_thickness 0.25)
		(keepout
			(tracks not_allowed)
			(vias allowed)
			(pads allowed)
			(copperpour not_allowed)
			(footprints allowed)
		)
		(placement
			(enabled no)
			(sheetname "")
		)
		(fill yes
			(thermal_gap 0.5)
			(thermal_bridge_width 0.5)
			(island_removal_mode 0)
		)
		(polygon
			(pts
				(arc
					(start 145.192496 -407.00452)
					(mid 144.524476 -407.00452)
					(end 145.192496 -407.00452)
				)
			)
		)
	)
	(zone
		(layers "F.Cu" "In2.Cu" "In4.Cu")
		(hatch none 0.5)
		(connect_pads
			(clearance 0)
		)
		(min_thickness 0.25)
		(keepout
			(tracks not_allowed)
			(vias allowed)
			(pads allowed)
			(copperpour not_allowed)
			(footprints allowed)
		)
		(placement
			(enabled no)
			(sheetname "")
		)
		(fill yes
			(thermal_gap 0.5)
			(thermal_bridge_width 0.5)
			(island_removal_mode 0)
		)
		(polygon
			(pts
				(arc
					(start 401.192492 -415.38652)
					(mid 400.524472 -415.38652)
					(end 401.192492 -415.38652)
				)
			)
		)
	)
	(zone
		(layers "F.Cu" "In2.Cu" "In4.Cu")
		(hatch none 0.5)
		(connect_pads
			(clearance 0)
		)
		(min_thickness 0.25)
		(keepout
			(tracks not_allowed)
			(vias allowed)
			(pads allowed)
			(copperpour not_allowed)
			(footprints allowed)
		)
		(placement
			(enabled no)
			(sheetname "")
		)
		(fill yes
			(thermal_gap 0.5)
			(thermal_bridge_width 0.5)
			(island_removal_mode 0)
		)
		(polygon
			(pts
				(arc
					(start 311.786016 -418.412168)
					(mid 311.117996 -418.412168)
					(end 311.786016 -418.412168)
				)
			)
		)
	)
	(zone
		(layers "F.Cu" "In2.Cu" "In4.Cu")
		(hatch none 0.5)
		(connect_pads
			(clearance 0)
		)
		(min_thickness 0.25)
		(keepout
			(tracks not_allowed)
			(vias allowed)
			(pads allowed)
			(copperpour not_allowed)
			(footprints allowed)
		)
		(placement
			(enabled no)
			(sheetname "")
		)
		(fill yes
			(thermal_gap 0.5)
			(thermal_bridge_width 0.5)
			(island_removal_mode 0)
		)
		(polygon
			(pts
				(arc
					(start 49.659794 -410.030168)
					(mid 48.991774 -410.030168)
					(end 49.659794 -410.030168)
				)
			)
		)
	)
	(zone
		(layers "F.Cu" "In2.Cu" "In4.Cu")
		(hatch none 0.5)
		(connect_pads
			(clearance 0)
		)
		(min_thickness 0.25)
		(keepout
			(tracks not_allowed)
			(vias allowed)
			(pads allowed)
			(copperpour not_allowed)
			(footprints allowed)
		)
		(placement
			(enabled no)
			(sheetname "")
		)
		(fill yes
			(thermal_gap 0.5)
			(thermal_bridge_width 0.5)
			(island_removal_mode 0)
		)
		(polygon
			(pts
				(arc
					(start 197.64121 -244.085364)
					(mid 196.97319 -244.085364)
					(end 197.64121 -244.085364)
				)
			)
		)
	)
	(zone
		(layers "F.Cu" "In2.Cu" "In4.Cu")
		(hatch none 0.5)
		(connect_pads
			(clearance 0)
		)
		(min_thickness 0.25)
		(keepout
			(tracks not_allowed)
			(vias allowed)
			(pads allowed)
			(copperpour not_allowed)
			(footprints allowed)
		)
		(placement
			(enabled no)
			(sheetname "")
		)
		(fill yes
			(thermal_gap 0.5)
			(thermal_bridge_width 0.5)
			(island_removal_mode 0)
		)
		(polygon
			(pts
				(arc
					(start 160.508696 -407.00452)
					(mid 159.840676 -407.00452)
					(end 160.508696 -407.00452)
				)
			)
		)
	)
	(zone
		(layers "F.Cu" "In2.Cu" "In4.Cu")
		(hatch none 0.5)
		(connect_pads
			(clearance 0)
		)
		(min_thickness 0.25)
		(keepout
			(tracks not_allowed)
			(vias allowed)
			(pads allowed)
			(copperpour not_allowed)
			(footprints allowed)
		)
		(placement
			(enabled no)
			(sheetname "")
		)
		(fill yes
			(thermal_gap 0.5)
			(thermal_bridge_width 0.5)
			(island_removal_mode 0)
		)
		(polygon
			(pts
				(arc
					(start 348.544896 -415.38652)
					(mid 347.876876 -415.38652)
					(end 348.544896 -415.38652)
				)
			)
		)
	)
	(zone
		(layers "F.Cu" "In2.Cu" "In4.Cu")
		(hatch none 0.5)
		(connect_pads
			(clearance 0)
		)
		(min_thickness 0.25)
		(keepout
			(tracks not_allowed)
			(vias allowed)
			(pads allowed)
			(copperpour not_allowed)
			(footprints allowed)
		)
		(placement
			(enabled no)
			(sheetname "")
		)
		(fill yes
			(thermal_gap 0.5)
			(thermal_bridge_width 0.5)
			(island_removal_mode 0)
		)
		(polygon
			(pts
				(arc
					(start 61.912754 -410.030168)
					(mid 61.244734 -410.030168)
					(end 61.912754 -410.030168)
				)
			)
		)
	)
	(zone
		(layers "F.Cu" "In2.Cu" "In4.Cu")
		(hatch none 0.5)
		(connect_pads
			(clearance 0)
		)
		(min_thickness 0.25)
		(keepout
			(tracks not_allowed)
			(vias allowed)
			(pads allowed)
			(copperpour not_allowed)
			(footprints allowed)
		)
		(placement
			(enabled no)
			(sheetname "")
		)
		(fill yes
			(thermal_gap 0.5)
			(thermal_bridge_width 0.5)
			(island_removal_mode 0)
		)
		(polygon
			(pts
				(arc
					(start 315.712856 -418.412168)
					(mid 315.044836 -418.412168)
					(end 315.712856 -418.412168)
				)
			)
		)
	)
	(zone
		(layers "F.Cu" "In2.Cu" "In4.Cu")
		(hatch none 0.5)
		(connect_pads
			(clearance 0)
		)
		(min_thickness 0.25)
		(keepout
			(tracks not_allowed)
			(vias allowed)
			(pads allowed)
			(copperpour not_allowed)
			(footprints allowed)
		)
		(placement
			(enabled no)
			(sheetname "")
		)
		(fill yes
			(thermal_gap 0.5)
			(thermal_bridge_width 0.5)
			(island_removal_mode 0)
		)
		(polygon
			(pts
				(arc
					(start 58.849514 -410.030168)
					(mid 58.181494 -410.030168)
					(end 58.849514 -410.030168)
				)
			)
		)
	)
	(zone
		(layers "F.Cu" "In2.Cu" "In4.Cu")
		(hatch none 0.5)
		(connect_pads
			(clearance 0)
		)
		(min_thickness 0.25)
		(keepout
			(tracks not_allowed)
			(vias allowed)
			(pads allowed)
			(copperpour not_allowed)
			(footprints allowed)
		)
		(placement
			(enabled no)
			(sheetname "")
		)
		(fill yes
			(thermal_gap 0.5)
			(thermal_bridge_width 0.5)
			(island_removal_mode 0)
		)
		(polygon
			(pts
				(arc
					(start 375.822972 -418.412168)
					(mid 375.154952 -418.412168)
					(end 375.822972 -418.412168)
				)
			)
		)
	)
	(zone
		(layers "F.Cu" "In2.Cu" "In4.Cu")
		(hatch none 0.5)
		(connect_pads
			(clearance 0)
		)
		(min_thickness 0.25)
		(keepout
			(tracks not_allowed)
			(vias allowed)
			(pads allowed)
			(copperpour not_allowed)
			(footprints allowed)
		)
		(placement
			(enabled no)
			(sheetname "")
		)
		(fill yes
			(thermal_gap 0.5)
			(thermal_bridge_width 0.5)
			(island_removal_mode 0)
		)
		(polygon
			(pts
				(arc
					(start 93.408754 -410.030168)
					(mid 92.740734 -410.030168)
					(end 93.408754 -410.030168)
				)
			)
		)
	)
	(zone
		(layers "F.Cu" "In2.Cu" "In4.Cu")
		(hatch none 0.5)
		(connect_pads
			(clearance 0)
		)
		(min_thickness 0.25)
		(keepout
			(tracks not_allowed)
			(vias allowed)
			(pads allowed)
			(copperpour not_allowed)
			(footprints allowed)
		)
		(placement
			(enabled no)
			(sheetname "")
		)
		(fill yes
			(thermal_gap 0.5)
			(thermal_bridge_width 0.5)
			(island_removal_mode 0)
		)
		(polygon
			(pts
				(arc
					(start 418.708332 -418.412168)
					(mid 418.040312 -418.412168)
					(end 418.708332 -418.412168)
				)
			)
		)
	)
	(zone
		(layers "F.Cu" "In2.Cu" "In4.Cu")
		(hatch none 0.5)
		(connect_pads
			(clearance 0)
		)
		(min_thickness 0.25)
		(keepout
			(tracks not_allowed)
			(vias allowed)
			(pads allowed)
			(copperpour not_allowed)
			(footprints allowed)
		)
		(placement
			(enabled no)
			(sheetname "")
		)
		(fill yes
			(thermal_gap 0.5)
			(thermal_bridge_width 0.5)
			(island_removal_mode 0)
		)
		(polygon
			(pts
				(arc
					(start 404.255732 -415.38652)
					(mid 403.587712 -415.38652)
					(end 404.255732 -415.38652)
				)
			)
		)
	)
	(zone
		(layers "F.Cu" "In2.Cu" "In4.Cu")
		(hatch none 0.5)
		(connect_pads
			(clearance 0)
		)
		(min_thickness 0.25)
		(keepout
			(tracks not_allowed)
			(vias allowed)
			(pads allowed)
			(copperpour not_allowed)
			(footprints allowed)
		)
		(placement
			(enabled no)
			(sheetname "")
		)
		(fill yes
			(thermal_gap 0.5)
			(thermal_bridge_width 0.5)
			(island_removal_mode 0)
		)
		(polygon
			(pts
				(arc
					(start 400.328892 -418.412168)
					(mid 399.660872 -418.412168)
					(end 400.328892 -418.412168)
				)
			)
		)
	)
	(zone
		(layers "F.Cu" "In2.Cu" "In4.Cu")
		(hatch none 0.5)
		(connect_pads
			(clearance 0)
		)
		(min_thickness 0.25)
		(keepout
			(tracks not_allowed)
			(vias allowed)
			(pads allowed)
			(copperpour not_allowed)
			(footprints allowed)
		)
		(placement
			(enabled no)
			(sheetname "")
		)
		(fill yes
			(thermal_gap 0.5)
			(thermal_bridge_width 0.5)
			(island_removal_mode 0)
		)
		(polygon
			(pts
				(arc
					(start 123.749816 -410.030168)
					(mid 123.081796 -410.030168)
					(end 123.749816 -410.030168)
				)
			)
		)
	)
	(zone
		(layers "F.Cu" "In2.Cu" "In4.Cu")
		(hatch none 0.5)
		(connect_pads
			(clearance 0)
		)
		(min_thickness 0.25)
		(keepout
			(tracks not_allowed)
			(vias allowed)
			(pads allowed)
			(copperpour not_allowed)
			(footprints allowed)
		)
		(placement
			(enabled no)
			(sheetname "")
		)
		(fill yes
			(thermal_gap 0.5)
			(thermal_bridge_width 0.5)
			(island_removal_mode 0)
		)
		(polygon
			(pts
				(arc
					(start 132.939536 -410.030168)
					(mid 132.271516 -410.030168)
					(end 132.939536 -410.030168)
				)
			)
		)
	)
	(zone
		(layers "F.Cu" "In2.Cu" "In4.Cu")
		(hatch none 0.5)
		(connect_pads
			(clearance 0)
		)
		(min_thickness 0.25)
		(keepout
			(tracks not_allowed)
			(vias allowed)
			(pads allowed)
			(copperpour not_allowed)
			(footprints allowed)
		)
		(placement
			(enabled no)
			(sheetname "")
		)
		(fill yes
			(thermal_gap 0.5)
			(thermal_bridge_width 0.5)
			(island_removal_mode 0)
		)
		(polygon
			(pts
				(arc
					(start 154.382216 -410.030168)
					(mid 153.714196 -410.030168)
					(end 154.382216 -410.030168)
				)
			)
		)
	)
	(zone
		(layers "F.Cu" "In2.Cu" "In4.Cu")
		(hatch none 0.5)
		(connect_pads
			(clearance 0)
		)
		(min_thickness 0.25)
		(keepout
			(tracks not_allowed)
			(vias allowed)
			(pads allowed)
			(copperpour not_allowed)
			(footprints allowed)
		)
		(placement
			(enabled no)
			(sheetname "")
		)
		(fill yes
			(thermal_gap 0.5)
			(thermal_bridge_width 0.5)
			(island_removal_mode 0)
		)
		(polygon
			(pts
				(arc
					(start 138.202416 -410.030168)
					(mid 137.534396 -410.030168)
					(end 138.202416 -410.030168)
				)
			)
		)
	)
	(zone
		(layers "F.Cu" "In2.Cu" "In4.Cu")
		(hatch none 0.5)
		(connect_pads
			(clearance 0)
		)
		(min_thickness 0.25)
		(keepout
			(tracks not_allowed)
			(vias allowed)
			(pads allowed)
			(copperpour not_allowed)
			(footprints allowed)
		)
		(placement
			(enabled no)
			(sheetname "")
		)
		(fill yes
			(thermal_gap 0.5)
			(thermal_bridge_width 0.5)
			(island_removal_mode 0)
		)
		(polygon
			(pts
				(arc
					(start 86.418674 -410.030168)
					(mid 85.750654 -410.030168)
					(end 86.418674 -410.030168)
				)
			)
		)
	)
	(zone
		(layers "F.Cu" "In2.Cu" "In4.Cu")
		(hatch none 0.5)
		(connect_pads
			(clearance 0)
		)
		(min_thickness 0.25)
		(keepout
			(tracks not_allowed)
			(vias allowed)
			(pads allowed)
			(copperpour not_allowed)
			(footprints allowed)
		)
		(placement
			(enabled no)
			(sheetname "")
		)
		(fill yes
			(thermal_gap 0.5)
			(thermal_bridge_width 0.5)
			(island_removal_mode 0)
		)
		(polygon
			(pts
				(arc
					(start 159.645096 -410.030168)
					(mid 158.977076 -410.030168)
					(end 159.645096 -410.030168)
				)
			)
		)
	)
	(zone
		(layers "F.Cu" "In2.Cu" "In4.Cu")
		(hatch none 0.5)
		(connect_pads
			(clearance 0)
		)
		(min_thickness 0.25)
		(keepout
			(tracks not_allowed)
			(vias allowed)
			(pads allowed)
			(copperpour not_allowed)
			(footprints allowed)
		)
		(placement
			(enabled no)
			(sheetname "")
		)
		(fill yes
			(thermal_gap 0.5)
			(thermal_bridge_width 0.5)
			(island_removal_mode 0)
		)
		(polygon
			(pts
				(arc
					(start 150.455376 -410.030168)
					(mid 149.787356 -410.030168)
					(end 150.455376 -410.030168)
				)
			)
		)
	)
	(zone
		(layers "F.Cu" "In2.Cu" "In4.Cu")
		(hatch none 0.5)
		(connect_pads
			(clearance 0)
		)
		(min_thickness 0.25)
		(keepout
			(tracks not_allowed)
			(vias allowed)
			(pads allowed)
			(copperpour not_allowed)
			(footprints allowed)
		)
		(placement
			(enabled no)
			(sheetname "")
		)
		(fill yes
			(thermal_gap 0.5)
			(thermal_bridge_width 0.5)
			(island_removal_mode 0)
		)
		(polygon
			(pts
				(arc
					(start 334.092296 -418.412168)
					(mid 333.424276 -418.412168)
					(end 334.092296 -418.412168)
				)
			)
		)
	)
	(zone
		(layers "F.Cu" "In2.Cu" "In4.Cu")
		(hatch none 0.5)
		(connect_pads
			(clearance 0)
		)
		(min_thickness 0.25)
		(keepout
			(tracks not_allowed)
			(vias allowed)
			(pads allowed)
			(copperpour not_allowed)
			(footprints allowed)
		)
		(placement
			(enabled no)
			(sheetname "")
		)
		(fill yes
			(thermal_gap 0.5)
			(thermal_bridge_width 0.5)
			(island_removal_mode 0)
		)
		(polygon
			(pts
				(arc
					(start 129.876296 -407.00452)
					(mid 129.208276 -407.00452)
					(end 129.876296 -407.00452)
				)
			)
		)
	)
	(zone
		(layers "F.Cu" "In2.Cu" "In4.Cu")
		(hatch none 0.5)
		(connect_pads
			(clearance 0)
		)
		(min_thickness 0.25)
		(keepout
			(tracks not_allowed)
			(vias allowed)
			(pads allowed)
			(copperpour not_allowed)
			(footprints allowed)
		)
		(placement
			(enabled no)
			(sheetname "")
		)
		(fill yes
			(thermal_gap 0.5)
			(thermal_bridge_width 0.5)
			(island_removal_mode 0)
		)
		(polygon
			(pts
				(arc
					(start 75.029314 -410.030168)
					(mid 74.361294 -410.030168)
					(end 75.029314 -410.030168)
				)
			)
		)
	)
	(zone
		(layers "F.Cu" "In2.Cu" "In4.Cu")
		(hatch none 0.5)
		(connect_pads
			(clearance 0)
		)
		(min_thickness 0.25)
		(keepout
			(tracks not_allowed)
			(vias allowed)
			(pads allowed)
			(copperpour not_allowed)
			(footprints allowed)
		)
		(placement
			(enabled no)
			(sheetname "")
		)
		(fill yes
			(thermal_gap 0.5)
			(thermal_bridge_width 0.5)
			(island_removal_mode 0)
		)
		(polygon
			(pts
				(arc
					(start 95.608394 -410.030168)
					(mid 94.940374 -410.030168)
					(end 95.608394 -410.030168)
				)
			)
		)
	)
	(zone
		(layers "F.Cu" "In2.Cu" "In4.Cu")
		(hatch none 0.5)
		(connect_pads
			(clearance 0)
		)
		(min_thickness 0.25)
		(keepout
			(tracks not_allowed)
			(vias allowed)
			(pads allowed)
			(copperpour not_allowed)
			(footprints allowed)
		)
		(placement
			(enabled no)
			(sheetname "")
		)
		(fill yes
			(thermal_gap 0.5)
			(thermal_bridge_width 0.5)
			(island_removal_mode 0)
		)
		(polygon
			(pts
				(arc
					(start 116.759736 -407.00452)
					(mid 116.091716 -407.00452)
					(end 116.759736 -407.00452)
				)
			)
		)
	)
	(zone
		(layers "F.Cu" "In2.Cu" "In4.Cu")
		(hatch none 0.5)
		(connect_pads
			(clearance 0)
		)
		(min_thickness 0.25)
		(keepout
			(tracks not_allowed)
			(vias allowed)
			(pads allowed)
			(copperpour not_allowed)
			(footprints allowed)
		)
		(placement
			(enabled no)
			(sheetname "")
		)
		(fill yes
			(thermal_gap 0.5)
			(thermal_bridge_width 0.5)
			(island_removal_mode 0)
		)
		(polygon
			(pts
				(arc
					(start 327.965816 -418.412168)
					(mid 327.297796 -418.412168)
					(end 327.965816 -418.412168)
				)
			)
		)
	)
	(zone
		(layers "F.Cu" "In2.Cu" "In4.Cu")
		(hatch none 0.5)
		(connect_pads
			(clearance 0)
		)
		(min_thickness 0.25)
		(keepout
			(tracks not_allowed)
			(vias allowed)
			(pads allowed)
			(copperpour not_allowed)
			(footprints allowed)
		)
		(placement
			(enabled no)
			(sheetname "")
		)
		(fill yes
			(thermal_gap 0.5)
			(thermal_bridge_width 0.5)
			(island_removal_mode 0)
		)
		(polygon
			(pts
				(arc
					(start 306.523136 -418.412168)
					(mid 305.855116 -418.412168)
					(end 306.523136 -418.412168)
				)
			)
		)
	)
	(zone
		(layers "F.Cu" "In2.Cu" "In4.Cu")
		(hatch none 0.5)
		(connect_pads
			(clearance 0)
		)
		(min_thickness 0.25)
		(keepout
			(tracks not_allowed)
			(vias allowed)
			(pads allowed)
			(copperpour not_allowed)
			(footprints allowed)
		)
		(placement
			(enabled no)
			(sheetname "")
		)
		(fill yes
			(thermal_gap 0.5)
			(thermal_bridge_width 0.5)
			(island_removal_mode 0)
		)
		(polygon
			(pts
				(arc
					(start 68.039234 -410.030168)
					(mid 67.371214 -410.030168)
					(end 68.039234 -410.030168)
				)
			)
		)
	)
	(zone
		(layers "F.Cu" "In2.Cu" "In4.Cu")
		(hatch none 0.5)
		(connect_pads
			(clearance 0)
		)
		(min_thickness 0.25)
		(keepout
			(tracks not_allowed)
			(vias allowed)
			(pads allowed)
			(copperpour not_allowed)
			(footprints allowed)
		)
		(placement
			(enabled no)
			(sheetname "")
		)
		(fill yes
			(thermal_gap 0.5)
			(thermal_bridge_width 0.5)
			(island_removal_mode 0)
		)
		(polygon
			(pts
				(arc
					(start 403.392132 -418.412168)
					(mid 402.724112 -418.412168)
					(end 403.392132 -418.412168)
				)
			)
		)
	)
	(zone
		(layers "F.Cu" "In2.Cu" "In4.Cu")
		(hatch none 0.5)
		(connect_pads
			(clearance 0)
		)
		(min_thickness 0.25)
		(keepout
			(tracks not_allowed)
			(vias allowed)
			(pads allowed)
			(copperpour not_allowed)
			(footprints allowed)
		)
		(placement
			(enabled no)
			(sheetname "")
		)
		(fill yes
			(thermal_gap 0.5)
			(thermal_bridge_width 0.5)
			(island_removal_mode 0)
		)
		(polygon
			(pts
				(arc
					(start 379.749812 -415.38652)
					(mid 379.081792 -415.38652)
					(end 379.749812 -415.38652)
				)
			)
		)
	)
	(zone
		(layers "F.Cu" "In2.Cu" "In4.Cu")
		(hatch none 0.5)
		(connect_pads
			(clearance 0)
		)
		(min_thickness 0.25)
		(keepout
			(tracks not_allowed)
			(vias allowed)
			(pads allowed)
			(copperpour not_allowed)
			(footprints allowed)
		)
		(placement
			(enabled no)
			(sheetname "")
		)
		(fill yes
			(thermal_gap 0.5)
			(thermal_bridge_width 0.5)
			(island_removal_mode 0)
		)
		(polygon
			(pts
				(arc
					(start 71.966074 -410.030168)
					(mid 71.298054 -410.030168)
					(end 71.966074 -410.030168)
				)
			)
		)
	)
	(zone
		(layers "F.Cu" "In2.Cu" "In4.Cu")
		(hatch none 0.5)
		(connect_pads
			(clearance 0)
		)
		(min_thickness 0.25)
		(keepout
			(tracks not_allowed)
			(vias allowed)
			(pads allowed)
			(copperpour not_allowed)
			(footprints allowed)
		)
		(placement
			(enabled no)
			(sheetname "")
		)
		(fill yes
			(thermal_gap 0.5)
			(thermal_bridge_width 0.5)
			(island_removal_mode 0)
		)
		(polygon
			(pts
				(arc
					(start 312.649616 -415.38652)
					(mid 311.981596 -415.38652)
					(end 312.649616 -415.38652)
				)
			)
		)
	)
	(zone
		(layers "F.Cu" "In2.Cu" "In4.Cu")
		(hatch none 0.5)
		(connect_pads
			(clearance 0)
		)
		(min_thickness 0.25)
		(keepout
			(tracks not_allowed)
			(vias allowed)
			(pads allowed)
			(copperpour not_allowed)
			(footprints allowed)
		)
		(placement
			(enabled no)
			(sheetname "")
		)
		(fill yes
			(thermal_gap 0.5)
			(thermal_bridge_width 0.5)
			(island_removal_mode 0)
		)
		(polygon
			(pts
				(arc
					(start 138.202416 -407.00452)
					(mid 137.534396 -407.00452)
					(end 138.202416 -407.00452)
				)
			)
		)
	)
	(zone
		(layers "F.Cu" "In2.Cu" "In4.Cu")
		(hatch none 0.5)
		(connect_pads
			(clearance 0)
		)
		(min_thickness 0.25)
		(keepout
			(tracks not_allowed)
			(vias allowed)
			(pads allowed)
			(copperpour not_allowed)
			(footprints allowed)
		)
		(placement
			(enabled no)
			(sheetname "")
		)
		(fill yes
			(thermal_gap 0.5)
			(thermal_bridge_width 0.5)
			(island_removal_mode 0)
		)
		(polygon
			(pts
				(arc
					(start 156.581856 -407.00452)
					(mid 155.913836 -407.00452)
					(end 156.581856 -407.00452)
				)
			)
		)
	)
	(zone
		(layers "F.Cu" "In2.Cu" "In4.Cu")
		(hatch none 0.5)
		(connect_pads
			(clearance 0)
		)
		(min_thickness 0.25)
		(keepout
			(tracks not_allowed)
			(vias allowed)
			(pads allowed)
			(copperpour not_allowed)
			(footprints allowed)
		)
		(placement
			(enabled no)
			(sheetname "")
		)
		(fill yes
			(thermal_gap 0.5)
			(thermal_bridge_width 0.5)
			(island_removal_mode 0)
		)
		(polygon
			(pts
				(arc
					(start 400.328892 -415.38652)
					(mid 399.660872 -415.38652)
					(end 400.328892 -415.38652)
				)
			)
		)
	)
	(zone
		(layers "F.Cu" "In2.Cu" "In4.Cu")
		(hatch none 0.5)
		(connect_pads
			(clearance 0)
		)
		(min_thickness 0.25)
		(keepout
			(tracks not_allowed)
			(vias allowed)
			(pads allowed)
			(copperpour not_allowed)
			(footprints allowed)
		)
		(placement
			(enabled no)
			(sheetname "")
		)
		(fill yes
			(thermal_gap 0.5)
			(thermal_bridge_width 0.5)
			(island_removal_mode 0)
		)
		(polygon
			(pts
				(arc
					(start 129.012696 -410.030168)
					(mid 128.344676 -410.030168)
					(end 129.012696 -410.030168)
				)
			)
		)
	)
	(zone
		(layers "F.Cu" "In2.Cu" "In4.Cu")
		(hatch none 0.5)
		(connect_pads
			(clearance 0)
		)
		(min_thickness 0.25)
		(keepout
			(tracks not_allowed)
			(vias allowed)
			(pads allowed)
			(copperpour not_allowed)
			(footprints allowed)
		)
		(placement
			(enabled no)
			(sheetname "")
		)
		(fill yes
			(thermal_gap 0.5)
			(thermal_bridge_width 0.5)
			(island_removal_mode 0)
		)
		(polygon
			(pts
				(arc
					(start 64.975994 -410.030168)
					(mid 64.307974 -410.030168)
					(end 64.975994 -410.030168)
				)
			)
		)
	)
	(zone
		(layers "F.Cu" "In2.Cu" "In4.Cu")
		(hatch none 0.5)
		(connect_pads
			(clearance 0)
		)
		(min_thickness 0.25)
		(keepout
			(tracks not_allowed)
			(vias allowed)
			(pads allowed)
			(copperpour not_allowed)
			(footprints allowed)
		)
		(placement
			(enabled no)
			(sheetname "")
		)
		(fill yes
			(thermal_gap 0.5)
			(thermal_bridge_width 0.5)
			(island_removal_mode 0)
		)
		(polygon
			(pts
				(arc
					(start 320.975736 -415.38652)
					(mid 320.307716 -415.38652)
					(end 320.975736 -415.38652)
				)
			)
		)
	)
	(zone
		(layers "F.Cu" "In2.Cu" "In4.Cu")
		(hatch none 0.5)
		(connect_pads
			(clearance 0)
		)
		(min_thickness 0.25)
		(keepout
			(tracks not_allowed)
			(vias allowed)
			(pads allowed)
			(copperpour not_allowed)
			(footprints allowed)
		)
		(placement
			(enabled no)
			(sheetname "")
		)
		(fill yes
			(thermal_gap 0.5)
			(thermal_bridge_width 0.5)
			(island_removal_mode 0)
		)
		(polygon
			(pts
				(arc
					(start 412.581852 -418.412168)
					(mid 411.913832 -418.412168)
					(end 412.581852 -418.412168)
				)
			)
		)
	)
	(zone
		(layers "F.Cu" "In2.Cu" "In4.Cu")
		(hatch none 0.5)
		(connect_pads
			(clearance 0)
		)
		(min_thickness 0.25)
		(keepout
			(tracks not_allowed)
			(vias allowed)
			(pads allowed)
			(copperpour not_allowed)
			(footprints allowed)
		)
		(placement
			(enabled no)
			(sheetname "")
		)
		(fill yes
			(thermal_gap 0.5)
			(thermal_bridge_width 0.5)
			(island_removal_mode 0)
		)
		(polygon
			(pts
				(arc
					(start 139.066016 -407.00452)
					(mid 138.397996 -407.00452)
					(end 139.066016 -407.00452)
				)
			)
		)
	)
	(zone
		(layers "F.Cu" "In2.Cu" "In4.Cu")
		(hatch none 0.5)
		(connect_pads
			(clearance 0)
		)
		(min_thickness 0.25)
		(keepout
			(tracks not_allowed)
			(vias allowed)
			(pads allowed)
			(copperpour not_allowed)
			(footprints allowed)
		)
		(placement
			(enabled no)
			(sheetname "")
		)
		(fill yes
			(thermal_gap 0.5)
			(thermal_bridge_width 0.5)
			(island_removal_mode 0)
		)
		(polygon
			(pts
				(arc
					(start 120.686576 -407.00452)
					(mid 120.018556 -407.00452)
					(end 120.686576 -407.00452)
				)
			)
		)
	)
	(zone
		(layers "F.Cu" "In2.Cu" "In4.Cu")
		(hatch none 0.5)
		(connect_pads
			(clearance 0)
		)
		(min_thickness 0.25)
		(keepout
			(tracks not_allowed)
			(vias allowed)
			(pads allowed)
			(copperpour not_allowed)
			(footprints allowed)
		)
		(placement
			(enabled no)
			(sheetname "")
		)
		(fill yes
			(thermal_gap 0.5)
			(thermal_bridge_width 0.5)
			(island_removal_mode 0)
		)
		(polygon
			(pts
				(arc
					(start 445.581278 -244.08511)
					(mid 444.913258 -244.08511)
					(end 445.581278 -244.08511)
				)
			)
		)
	)
	(zone
		(layers "F.Cu" "In2.Cu" "In4.Cu")
		(hatch none 0.5)
		(connect_pads
			(clearance 0)
		)
		(min_thickness 0.25)
		(keepout
			(tracks not_allowed)
			(vias allowed)
			(pads allowed)
			(copperpour not_allowed)
			(footprints allowed)
		)
		(placement
			(enabled no)
			(sheetname "")
		)
		(fill yes
			(thermal_gap 0.5)
			(thermal_bridge_width 0.5)
			(island_removal_mode 0)
		)
		(polygon
			(pts
				(arc
					(start 122.886216 -407.00452)
					(mid 122.218196 -407.00452)
					(end 122.886216 -407.00452)
				)
			)
		)
	)
	(zone
		(layers "F.Cu" "In2.Cu" "In4.Cu")
		(hatch none 0.5)
		(connect_pads
			(clearance 0)
		)
		(min_thickness 0.25)
		(keepout
			(tracks not_allowed)
			(vias allowed)
			(pads allowed)
			(copperpour not_allowed)
			(footprints allowed)
		)
		(placement
			(enabled no)
			(sheetname "")
		)
		(fill yes
			(thermal_gap 0.5)
			(thermal_bridge_width 0.5)
			(island_removal_mode 0)
		)
		(polygon
			(pts
				(arc
					(start 381.949452 -418.412168)
					(mid 381.281432 -418.412168)
					(end 381.949452 -418.412168)
				)
			)
		)
	)
	(zone
		(layers "F.Cu" "In2.Cu" "In4.Cu")
		(hatch none 0.5)
		(connect_pads
			(clearance 0)
		)
		(min_thickness 0.25)
		(keepout
			(tracks not_allowed)
			(vias allowed)
			(pads allowed)
			(copperpour not_allowed)
			(footprints allowed)
		)
		(placement
			(enabled no)
			(sheetname "")
		)
		(fill yes
			(thermal_gap 0.5)
			(thermal_bridge_width 0.5)
			(island_removal_mode 0)
		)
		(polygon
			(pts
				(arc
					(start 392.002772 -415.38652)
					(mid 391.334752 -415.38652)
					(end 392.002772 -415.38652)
				)
			)
		)
	)
	(zone
		(layers "F.Cu" "In2.Cu" "In4.Cu")
		(hatch none 0.5)
		(connect_pads
			(clearance 0)
		)
		(min_thickness 0.25)
		(keepout
			(tracks not_allowed)
			(vias allowed)
			(pads allowed)
			(copperpour not_allowed)
			(footprints allowed)
		)
		(placement
			(enabled no)
			(sheetname "")
		)
		(fill yes
			(thermal_gap 0.5)
			(thermal_bridge_width 0.5)
			(island_removal_mode 0)
		)
		(polygon
			(pts
				(arc
					(start 419.571932 -415.38652)
					(mid 418.903912 -415.38652)
					(end 419.571932 -415.38652)
				)
			)
		)
	)
	(zone
		(layers "F.Cu" "In2.Cu" "In4.Cu")
		(hatch none 0.5)
		(connect_pads
			(clearance 0)
		)
		(min_thickness 0.25)
		(keepout
			(tracks not_allowed)
			(vias allowed)
			(pads allowed)
			(copperpour not_allowed)
			(footprints allowed)
		)
		(placement
			(enabled no)
			(sheetname "")
		)
		(fill yes
			(thermal_gap 0.5)
			(thermal_bridge_width 0.5)
			(island_removal_mode 0)
		)
		(polygon
			(pts
				(arc
					(start 388.939532 -418.412168)
					(mid 388.271512 -418.412168)
					(end 388.939532 -418.412168)
				)
			)
		)
	)
	(zone
		(layers "F.Cu" "In2.Cu" "In4.Cu")
		(hatch none 0.5)
		(connect_pads
			(clearance 0)
		)
		(min_thickness 0.25)
		(keepout
			(tracks not_allowed)
			(vias allowed)
			(pads allowed)
			(copperpour not_allowed)
			(footprints allowed)
		)
		(placement
			(enabled no)
			(sheetname "")
		)
		(fill yes
			(thermal_gap 0.5)
			(thermal_bridge_width 0.5)
			(island_removal_mode 0)
		)
		(polygon
			(pts
				(arc
					(start 349.408496 -415.38652)
					(mid 348.740476 -415.38652)
					(end 349.408496 -415.38652)
				)
			)
		)
	)
	(zone
		(layers "F.Cu" "In2.Cu" "In4.Cu")
		(hatch none 0.5)
		(connect_pads
			(clearance 0)
		)
		(min_thickness 0.25)
		(keepout
			(tracks not_allowed)
			(vias allowed)
			(pads allowed)
			(copperpour not_allowed)
			(footprints allowed)
		)
		(placement
			(enabled no)
			(sheetname "")
		)
		(fill yes
			(thermal_gap 0.5)
			(thermal_bridge_width 0.5)
			(island_removal_mode 0)
		)
		(polygon
			(pts
				(arc
					(start 352.471736 -415.38652)
					(mid 351.803716 -415.38652)
					(end 352.471736 -415.38652)
				)
			)
		)
	)
	(zone
		(layers "F.Cu" "In2.Cu" "In4.Cu")
		(hatch none 0.5)
		(connect_pads
			(clearance 0)
		)
		(min_thickness 0.25)
		(keepout
			(tracks not_allowed)
			(vias allowed)
			(pads allowed)
			(copperpour not_allowed)
			(footprints allowed)
		)
		(placement
			(enabled no)
			(sheetname "")
		)
		(fill yes
			(thermal_gap 0.5)
			(thermal_bridge_width 0.5)
			(island_removal_mode 0)
		)
		(polygon
			(pts
				(arc
					(start 81.155794 -410.030168)
					(mid 80.487774 -410.030168)
					(end 81.155794 -410.030168)
				)
			)
		)
	)
	(zone
		(layers "F.Cu" "In2.Cu" "In4.Cu")
		(hatch none 0.5)
		(connect_pads
			(clearance 0)
		)
		(min_thickness 0.25)
		(keepout
			(tracks not_allowed)
			(vias allowed)
			(pads allowed)
			(copperpour not_allowed)
			(footprints allowed)
		)
		(placement
			(enabled no)
			(sheetname "")
		)
		(fill yes
			(thermal_gap 0.5)
			(thermal_bridge_width 0.5)
			(island_removal_mode 0)
		)
		(polygon
			(pts
				(arc
					(start 409.518612 -418.412168)
					(mid 408.850592 -418.412168)
					(end 409.518612 -418.412168)
				)
			)
		)
	)
	(zone
		(layers "F.Cu" "In2.Cu" "In4.Cu")
		(hatch none 0.5)
		(connect_pads
			(clearance 0)
		)
		(min_thickness 0.25)
		(keepout
			(tracks not_allowed)
			(vias allowed)
			(pads allowed)
			(copperpour not_allowed)
			(footprints allowed)
		)
		(placement
			(enabled no)
			(sheetname "")
		)
		(fill yes
			(thermal_gap 0.5)
			(thermal_bridge_width 0.5)
			(island_removal_mode 0)
		)
		(polygon
			(pts
				(arc
					(start 153.518616 -410.030168)
					(mid 152.850596 -410.030168)
					(end 153.518616 -410.030168)
				)
			)
		)
	)
	(zone
		(layers "F.Cu" "In2.Cu" "In4.Cu")
		(hatch none 0.5)
		(connect_pads
			(clearance 0)
		)
		(min_thickness 0.25)
		(keepout
			(tracks not_allowed)
			(vias allowed)
			(pads allowed)
			(copperpour not_allowed)
			(footprints allowed)
		)
		(placement
			(enabled no)
			(sheetname "")
		)
		(fill yes
			(thermal_gap 0.5)
			(thermal_bridge_width 0.5)
			(island_removal_mode 0)
		)
		(polygon
			(pts
				(arc
					(start 413.445452 -418.412168)
					(mid 412.777432 -418.412168)
					(end 413.445452 -418.412168)
				)
			)
		)
	)
	(zone
		(layers "F.Cu" "In2.Cu" "In4.Cu")
		(hatch none 0.5)
		(connect_pads
			(clearance 0)
		)
		(min_thickness 0.25)
		(keepout
			(tracks not_allowed)
			(vias allowed)
			(pads allowed)
			(copperpour not_allowed)
			(footprints allowed)
		)
		(placement
			(enabled no)
			(sheetname "")
		)
		(fill yes
			(thermal_gap 0.5)
			(thermal_bridge_width 0.5)
			(island_removal_mode 0)
		)
		(polygon
			(pts
				(arc
					(start 343.282016 -418.412168)
					(mid 342.613996 -418.412168)
					(end 343.282016 -418.412168)
				)
			)
		)
	)
	(zone
		(layers "F.Cu" "In2.Cu" "In4.Cu")
		(hatch none 0.5)
		(connect_pads
			(clearance 0)
		)
		(min_thickness 0.25)
		(keepout
			(tracks not_allowed)
			(vias allowed)
			(pads allowed)
			(copperpour not_allowed)
			(footprints allowed)
		)
		(placement
			(enabled no)
			(sheetname "")
		)
		(fill yes
			(thermal_gap 0.5)
			(thermal_bridge_width 0.5)
			(island_removal_mode 0)
		)
		(polygon
			(pts
				(arc
					(start 147.392136 -407.00452)
					(mid 146.724116 -407.00452)
					(end 147.392136 -407.00452)
				)
			)
		)
	)
	(zone
		(layers "F.Cu" "In2.Cu" "In4.Cu")
		(hatch none 0.5)
		(connect_pads
			(clearance 0)
		)
		(min_thickness 0.25)
		(keepout
			(tracks not_allowed)
			(vias allowed)
			(pads allowed)
			(copperpour not_allowed)
			(footprints allowed)
		)
		(placement
			(enabled no)
			(sheetname "")
		)
		(fill yes
			(thermal_gap 0.5)
			(thermal_bridge_width 0.5)
			(island_removal_mode 0)
		)
		(polygon
			(pts
				(arc
					(start 151.318976 -410.030168)
					(mid 150.650956 -410.030168)
					(end 151.318976 -410.030168)
				)
			)
		)
	)
	(zone
		(layers "F.Cu" "In2.Cu" "In4.Cu")
		(hatch none 0.5)
		(connect_pads
			(clearance 0)
		)
		(min_thickness 0.25)
		(keepout
			(tracks not_allowed)
			(vias allowed)
			(pads allowed)
			(copperpour not_allowed)
			(footprints allowed)
		)
		(placement
			(enabled no)
			(sheetname "")
		)
		(fill yes
			(thermal_gap 0.5)
			(thermal_bridge_width 0.5)
			(island_removal_mode 0)
		)
		(polygon
			(pts
				(arc
					(start 135.139176 -410.030168)
					(mid 134.471156 -410.030168)
					(end 135.139176 -410.030168)
				)
			)
		)
	)
	(zone
		(layers "F.Cu" "In2.Cu" "In4.Cu")
		(hatch none 0.5)
		(connect_pads
			(clearance 0)
		)
		(min_thickness 0.25)
		(keepout
			(tracks not_allowed)
			(vias allowed)
			(pads allowed)
			(copperpour not_allowed)
			(footprints allowed)
		)
		(placement
			(enabled no)
			(sheetname "")
		)
		(fill yes
			(thermal_gap 0.5)
			(thermal_bridge_width 0.5)
			(island_removal_mode 0)
		)
		(polygon
			(pts
				(arc
					(start 122.886216 -410.030168)
					(mid 122.218196 -410.030168)
					(end 122.886216 -410.030168)
				)
			)
		)
	)
	(zone
		(layers "F.Cu" "In2.Cu" "In4.Cu")
		(hatch none 0.5)
		(connect_pads
			(clearance 0)
		)
		(min_thickness 0.25)
		(keepout
			(tracks not_allowed)
			(vias allowed)
			(pads allowed)
			(copperpour not_allowed)
			(footprints allowed)
		)
		(placement
			(enabled no)
			(sheetname "")
		)
		(fill yes
			(thermal_gap 0.5)
			(thermal_bridge_width 0.5)
			(island_removal_mode 0)
		)
		(polygon
			(pts
				(arc
					(start 120.686576 -410.030168)
					(mid 120.018556 -410.030168)
					(end 120.686576 -410.030168)
				)
			)
		)
	)
	(zone
		(layers "F.Cu" "In2.Cu" "In4.Cu")
		(hatch none 0.5)
		(connect_pads
			(clearance 0)
		)
		(min_thickness 0.25)
		(keepout
			(tracks not_allowed)
			(vias allowed)
			(pads allowed)
			(copperpour not_allowed)
			(footprints allowed)
		)
		(placement
			(enabled no)
			(sheetname "")
		)
		(fill yes
			(thermal_gap 0.5)
			(thermal_bridge_width 0.5)
			(island_removal_mode 0)
		)
		(polygon
			(pts
				(arc
					(start 403.392132 -415.38652)
					(mid 402.724112 -415.38652)
					(end 403.392132 -415.38652)
				)
			)
		)
	)
	(zone
		(layers "F.Cu" "In2.Cu" "In4.Cu")
		(hatch none 0.5)
		(connect_pads
			(clearance 0)
		)
		(min_thickness 0.25)
		(keepout
			(tracks not_allowed)
			(vias allowed)
			(pads allowed)
			(copperpour not_allowed)
			(footprints allowed)
		)
		(placement
			(enabled no)
			(sheetname "")
		)
		(fill yes
			(thermal_gap 0.5)
			(thermal_bridge_width 0.5)
			(island_removal_mode 0)
		)
		(polygon
			(pts
				(arc
					(start 415.645092 -415.38652)
					(mid 414.977072 -415.38652)
					(end 415.645092 -415.38652)
				)
			)
		)
	)
	(zone
		(layers "F.Cu" "In2.Cu" "In4.Cu")
		(hatch none 0.5)
		(connect_pads
			(clearance 0)
		)
		(min_thickness 0.25)
		(keepout
			(tracks not_allowed)
			(vias allowed)
			(pads allowed)
			(copperpour not_allowed)
			(footprints allowed)
		)
		(placement
			(enabled no)
			(sheetname "")
		)
		(fill yes
			(thermal_gap 0.5)
			(thermal_bridge_width 0.5)
			(island_removal_mode 0)
		)
		(polygon
			(pts
				(arc
					(start 407.318972 -415.38652)
					(mid 406.650952 -415.38652)
					(end 407.318972 -415.38652)
				)
			)
		)
	)
	(zone
		(layers "F.Cu" "In2.Cu" "In4.Cu")
		(hatch none 0.5)
		(connect_pads
			(clearance 0)
		)
		(min_thickness 0.25)
		(keepout
			(tracks not_allowed)
			(vias allowed)
			(pads allowed)
			(copperpour not_allowed)
			(footprints allowed)
		)
		(placement
			(enabled no)
			(sheetname "")
		)
		(fill yes
			(thermal_gap 0.5)
			(thermal_bridge_width 0.5)
			(island_removal_mode 0)
		)
		(polygon
			(pts
				(arc
					(start 56.649874 -410.030168)
					(mid 55.981854 -410.030168)
					(end 56.649874 -410.030168)
				)
			)
		)
	)
	(zone
		(layers "F.Cu" "In2.Cu" "In4.Cu")
		(hatch none 0.5)
		(connect_pads
			(clearance 0)
		)
		(min_thickness 0.25)
		(keepout
			(tracks not_allowed)
			(vias allowed)
			(pads allowed)
			(copperpour not_allowed)
			(footprints allowed)
		)
		(placement
			(enabled no)
			(sheetname "")
		)
		(fill yes
			(thermal_gap 0.5)
			(thermal_bridge_width 0.5)
			(island_removal_mode 0)
		)
		(polygon
			(pts
				(arc
					(start 320.975736 -418.412168)
					(mid 320.307716 -418.412168)
					(end 320.975736 -418.412168)
				)
			)
		)
	)
	(zone
		(layers "F.Cu" "In2.Cu" "In4.Cu")
		(hatch none 0.5)
		(connect_pads
			(clearance 0)
		)
		(min_thickness 0.25)
		(keepout
			(tracks not_allowed)
			(vias allowed)
			(pads allowed)
			(copperpour not_allowed)
			(footprints allowed)
		)
		(placement
			(enabled no)
			(sheetname "")
		)
		(fill yes
			(thermal_gap 0.5)
			(thermal_bridge_width 0.5)
			(island_removal_mode 0)
		)
		(polygon
			(pts
				(arc
					(start 92.545154 -410.030168)
					(mid 91.877134 -410.030168)
					(end 92.545154 -410.030168)
				)
			)
		)
	)
	(zone
		(layers "F.Cu" "In2.Cu" "In4.Cu")
		(hatch none 0.5)
		(connect_pads
			(clearance 0)
		)
		(min_thickness 0.25)
		(keepout
			(tracks not_allowed)
			(vias allowed)
			(pads allowed)
			(copperpour not_allowed)
			(footprints allowed)
		)
		(placement
			(enabled no)
			(sheetname "")
		)
		(fill yes
			(thermal_gap 0.5)
			(thermal_bridge_width 0.5)
			(island_removal_mode 0)
		)
		(polygon
			(pts
				(arc
					(start 385.012692 -418.412168)
					(mid 384.344672 -418.412168)
					(end 385.012692 -418.412168)
				)
			)
		)
	)
	(zone
		(layers "F.Cu" "In2.Cu" "In4.Cu")
		(hatch none 0.5)
		(connect_pads
			(clearance 0)
		)
		(min_thickness 0.25)
		(keepout
			(tracks not_allowed)
			(vias allowed)
			(pads allowed)
			(copperpour not_allowed)
			(footprints allowed)
		)
		(placement
			(enabled no)
			(sheetname "")
		)
		(fill yes
			(thermal_gap 0.5)
			(thermal_bridge_width 0.5)
			(island_removal_mode 0)
		)
		(polygon
			(pts
				(arc
					(start 147.392136 -410.030168)
					(mid 146.724116 -410.030168)
					(end 147.392136 -410.030168)
				)
			)
		)
	)
	(zone
		(layers "F.Cu" "In2.Cu" "In4.Cu")
		(hatch none 0.5)
		(connect_pads
			(clearance 0)
		)
		(min_thickness 0.25)
		(keepout
			(tracks not_allowed)
			(vias allowed)
			(pads allowed)
			(copperpour not_allowed)
			(footprints allowed)
		)
		(placement
			(enabled no)
			(sheetname "")
		)
		(fill yes
			(thermal_gap 0.5)
			(thermal_bridge_width 0.5)
			(island_removal_mode 0)
		)
		(polygon
			(pts
				(arc
					(start 395.066012 -415.38652)
					(mid 394.397992 -415.38652)
					(end 395.066012 -415.38652)
				)
			)
		)
	)
	(zone
		(layers "F.Cu" "In2.Cu" "In4.Cu")
		(hatch none 0.5)
		(connect_pads
			(clearance 0)
		)
		(min_thickness 0.25)
		(keepout
			(tracks not_allowed)
			(vias allowed)
			(pads allowed)
			(copperpour not_allowed)
			(footprints allowed)
		)
		(placement
			(enabled no)
			(sheetname "")
		)
		(fill yes
			(thermal_gap 0.5)
			(thermal_bridge_width 0.5)
			(island_removal_mode 0)
		)
		(polygon
			(pts
				(arc
					(start 163.571936 -407.00452)
					(mid 162.903916 -407.00452)
					(end 163.571936 -407.00452)
				)
			)
		)
	)
	(zone
		(layers "F.Cu" "In2.Cu" "In4.Cu")
		(hatch none 0.5)
		(connect_pads
			(clearance 0)
		)
		(min_thickness 0.25)
		(keepout
			(tracks not_allowed)
			(vias allowed)
			(pads allowed)
			(copperpour not_allowed)
			(footprints allowed)
		)
		(placement
			(enabled no)
			(sheetname "")
		)
		(fill yes
			(thermal_gap 0.5)
			(thermal_bridge_width 0.5)
			(island_removal_mode 0)
		)
		(polygon
			(pts
				(arc
					(start 378.886212 -418.412168)
					(mid 378.218192 -418.412168)
					(end 378.886212 -418.412168)
				)
			)
		)
	)
	(zone
		(layers "F.Cu" "In2.Cu" "In4.Cu")
		(hatch none 0.5)
		(connect_pads
			(clearance 0)
		)
		(min_thickness 0.25)
		(keepout
			(tracks not_allowed)
			(vias allowed)
			(pads allowed)
			(copperpour not_allowed)
			(footprints allowed)
		)
		(placement
			(enabled no)
			(sheetname "")
		)
		(fill yes
			(thermal_gap 0.5)
			(thermal_bridge_width 0.5)
			(island_removal_mode 0)
		)
		(polygon
			(pts
				(arc
					(start 74.165714 -410.030168)
					(mid 73.497694 -410.030168)
					(end 74.165714 -410.030168)
				)
			)
		)
	)
	(zone
		(layers "F.Cu" "In2.Cu" "In4.Cu")
		(hatch none 0.5)
		(connect_pads
			(clearance 0)
		)
		(min_thickness 0.25)
		(keepout
			(tracks not_allowed)
			(vias allowed)
			(pads allowed)
			(copperpour not_allowed)
			(footprints allowed)
		)
		(placement
			(enabled no)
			(sheetname "")
		)
		(fill yes
			(thermal_gap 0.5)
			(thermal_bridge_width 0.5)
			(island_removal_mode 0)
		)
		(polygon
			(pts
				(arc
					(start 324.902576 -415.38652)
					(mid 324.234556 -415.38652)
					(end 324.902576 -415.38652)
				)
			)
		)
	)
	(zone
		(layers "F.Cu" "In2.Cu" "In4.Cu")
		(hatch none 0.5)
		(connect_pads
			(clearance 0)
		)
		(min_thickness 0.25)
		(keepout
			(tracks not_allowed)
			(vias allowed)
			(pads allowed)
			(copperpour not_allowed)
			(footprints allowed)
		)
		(placement
			(enabled no)
			(sheetname "")
		)
		(fill yes
			(thermal_gap 0.5)
			(thermal_bridge_width 0.5)
			(island_removal_mode 0)
		)
		(polygon
			(pts
				(arc
					(start 52.723034 -410.030168)
					(mid 52.055014 -410.030168)
					(end 52.723034 -410.030168)
				)
			)
		)
	)
	(zone
		(layers "F.Cu" "In2.Cu" "In4.Cu")
		(hatch none 0.5)
		(connect_pads
			(clearance 0)
		)
		(min_thickness 0.25)
		(keepout
			(tracks not_allowed)
			(vias allowed)
			(pads allowed)
			(copperpour not_allowed)
			(footprints allowed)
		)
		(placement
			(enabled no)
			(sheetname "")
		)
		(fill yes
			(thermal_gap 0.5)
			(thermal_bridge_width 0.5)
			(island_removal_mode 0)
		)
		(polygon
			(pts
				(arc
					(start 317.912496 -418.412168)
					(mid 317.244476 -418.412168)
					(end 317.912496 -418.412168)
				)
			)
		)
	)
	(zone
		(layers "F.Cu" "In2.Cu" "In4.Cu")
		(hatch none 0.5)
		(connect_pads
			(clearance 0)
		)
		(min_thickness 0.25)
		(keepout
			(tracks not_allowed)
			(vias allowed)
			(pads allowed)
			(copperpour not_allowed)
			(footprints allowed)
		)
		(placement
			(enabled no)
			(sheetname "")
		)
		(fill yes
			(thermal_gap 0.5)
			(thermal_bridge_width 0.5)
			(island_removal_mode 0)
		)
		(polygon
			(pts
				(arc
					(start 324.038976 -415.38652)
					(mid 323.370956 -415.38652)
					(end 324.038976 -415.38652)
				)
			)
		)
	)
	(zone
		(layers "F.Cu" "In2.Cu" "In4.Cu")
		(hatch none 0.5)
		(connect_pads
			(clearance 0)
		)
		(min_thickness 0.25)
		(keepout
			(tracks not_allowed)
			(vias allowed)
			(pads allowed)
			(copperpour not_allowed)
			(footprints allowed)
		)
		(placement
			(enabled no)
			(sheetname "")
		)
		(fill yes
			(thermal_gap 0.5)
			(thermal_bridge_width 0.5)
			(island_removal_mode 0)
		)
		(polygon
			(pts
				(arc
					(start 159.645096 -407.00452)
					(mid 158.977076 -407.00452)
					(end 159.645096 -407.00452)
				)
			)
		)
	)
	(zone
		(layers "F.Cu" "In2.Cu" "In4.Cu")
		(hatch none 0.5)
		(connect_pads
			(clearance 0)
		)
		(min_thickness 0.25)
		(keepout
			(tracks not_allowed)
			(vias allowed)
			(pads allowed)
			(copperpour not_allowed)
			(footprints allowed)
		)
		(placement
			(enabled no)
			(sheetname "")
		)
		(fill yes
			(thermal_gap 0.5)
			(thermal_bridge_width 0.5)
			(island_removal_mode 0)
		)
		(polygon
			(pts
				(arc
					(start 342.418416 -415.38652)
					(mid 341.750396 -415.38652)
					(end 342.418416 -415.38652)
				)
			)
		)
	)
	(zone
		(layers "F.Cu" "In2.Cu" "In4.Cu")
		(hatch none 0.5)
		(connect_pads
			(clearance 0)
		)
		(min_thickness 0.25)
		(keepout
			(tracks not_allowed)
			(vias allowed)
			(pads allowed)
			(copperpour not_allowed)
			(footprints allowed)
		)
		(placement
			(enabled no)
			(sheetname "")
		)
		(fill yes
			(thermal_gap 0.5)
			(thermal_bridge_width 0.5)
			(island_removal_mode 0)
		)
		(polygon
			(pts
				(arc
					(start 333.228696 -415.38652)
					(mid 332.560676 -415.38652)
					(end 333.228696 -415.38652)
				)
			)
		)
	)
	(zone
		(layers "F.Cu" "In2.Cu" "In4.Cu")
		(hatch none 0.5)
		(connect_pads
			(clearance 0)
		)
		(min_thickness 0.25)
		(keepout
			(tracks not_allowed)
			(vias allowed)
			(pads allowed)
			(copperpour not_allowed)
			(footprints allowed)
		)
		(placement
			(enabled no)
			(sheetname "")
		)
		(fill yes
			(thermal_gap 0.5)
			(thermal_bridge_width 0.5)
			(island_removal_mode 0)
		)
		(polygon
			(pts
				(arc
					(start 349.408496 -418.412168)
					(mid 348.740476 -418.412168)
					(end 349.408496 -418.412168)
				)
			)
		)
	)
	(zone
		(layers "F.Cu" "In2.Cu" "In4.Cu")
		(hatch none 0.5)
		(connect_pads
			(clearance 0)
		)
		(min_thickness 0.25)
		(keepout
			(tracks not_allowed)
			(vias allowed)
			(pads allowed)
			(copperpour not_allowed)
			(footprints allowed)
		)
		(placement
			(enabled no)
			(sheetname "")
		)
		(fill yes
			(thermal_gap 0.5)
			(thermal_bridge_width 0.5)
			(island_removal_mode 0)
		)
		(polygon
			(pts
				(arc
					(start 30.983174 -244.085364)
					(mid 30.315154 -244.085364)
					(end 30.983174 -244.085364)
				)
			)
		)
	)
	(zone
		(layers "F.Cu" "In2.Cu" "In4.Cu")
		(hatch none 0.5)
		(connect_pads
			(clearance 0)
		)
		(min_thickness 0.25)
		(keepout
			(tracks not_allowed)
			(vias allowed)
			(pads allowed)
			(copperpour not_allowed)
			(footprints allowed)
		)
		(placement
			(enabled no)
			(sheetname "")
		)
		(fill yes
			(thermal_gap 0.5)
			(thermal_bridge_width 0.5)
			(island_removal_mode 0)
		)
		(polygon
			(pts
				(arc
					(start 308.722776 -415.38652)
					(mid 308.054756 -415.38652)
					(end 308.722776 -415.38652)
				)
			)
		)
	)
	(zone
		(layers "F.Cu" "In2.Cu" "In4.Cu")
		(hatch none 0.5)
		(connect_pads
			(clearance 0)
		)
		(min_thickness 0.25)
		(keepout
			(tracks not_allowed)
			(vias allowed)
			(pads allowed)
			(copperpour not_allowed)
			(footprints allowed)
		)
		(placement
			(enabled no)
			(sheetname "")
		)
		(fill yes
			(thermal_gap 0.5)
			(thermal_bridge_width 0.5)
			(island_removal_mode 0)
		)
		(polygon
			(pts
				(arc
					(start 125.949456 -407.00452)
					(mid 125.281436 -407.00452)
					(end 125.949456 -407.00452)
				)
			)
		)
	)
	(zone
		(layers "F.Cu" "In2.Cu" "In4.Cu")
		(hatch none 0.5)
		(connect_pads
			(clearance 0)
		)
		(min_thickness 0.25)
		(keepout
			(tracks not_allowed)
			(vias allowed)
			(pads allowed)
			(copperpour not_allowed)
			(footprints allowed)
		)
		(placement
			(enabled no)
			(sheetname "")
		)
		(fill yes
			(thermal_gap 0.5)
			(thermal_bridge_width 0.5)
			(island_removal_mode 0)
		)
		(polygon
			(pts
				(arc
					(start 154.382216 -407.00452)
					(mid 153.714196 -407.00452)
					(end 154.382216 -407.00452)
				)
			)
		)
	)
	(zone
		(layers "F.Cu" "In2.Cu" "In4.Cu")
		(hatch none 0.5)
		(connect_pads
			(clearance 0)
		)
		(min_thickness 0.25)
		(keepout
			(tracks not_allowed)
			(vias allowed)
			(pads allowed)
			(copperpour not_allowed)
			(footprints allowed)
		)
		(placement
			(enabled no)
			(sheetname "")
		)
		(fill yes
			(thermal_gap 0.5)
			(thermal_bridge_width 0.5)
			(island_removal_mode 0)
		)
		(polygon
			(pts
				(arc
					(start 327.965816 -415.38652)
					(mid 327.297796 -415.38652)
					(end 327.965816 -415.38652)
				)
			)
		)
	)
	(zone
		(layers "F.Cu" "In2.Cu" "In4.Cu")
		(hatch none 0.5)
		(connect_pads
			(clearance 0)
		)
		(min_thickness 0.25)
		(keepout
			(tracks not_allowed)
			(vias allowed)
			(pads allowed)
			(copperpour not_allowed)
			(footprints allowed)
		)
		(placement
			(enabled no)
			(sheetname "")
		)
		(fill yes
			(thermal_gap 0.5)
			(thermal_bridge_width 0.5)
			(island_removal_mode 0)
		)
		(polygon
			(pts
				(arc
					(start 324.038976 -418.412168)
					(mid 323.370956 -418.412168)
					(end 324.038976 -418.412168)
				)
			)
		)
	)
	(zone
		(layers "F.Cu" "In2.Cu" "In4.Cu")
		(hatch none 0.5)
		(connect_pads
			(clearance 0)
		)
		(min_thickness 0.25)
		(keepout
			(tracks not_allowed)
			(vias allowed)
			(pads allowed)
			(copperpour not_allowed)
			(footprints allowed)
		)
		(placement
			(enabled no)
			(sheetname "")
		)
		(fill yes
			(thermal_gap 0.5)
			(thermal_bridge_width 0.5)
			(island_removal_mode 0)
		)
		(polygon
			(pts
				(arc
					(start 132.075936 -407.00452)
					(mid 131.407916 -407.00452)
					(end 132.075936 -407.00452)
				)
			)
		)
	)
	(zone
		(layers "F.Cu" "In2.Cu" "In4.Cu")
		(hatch none 0.5)
		(connect_pads
			(clearance 0)
		)
		(min_thickness 0.25)
		(keepout
			(tracks not_allowed)
			(vias allowed)
			(pads allowed)
			(copperpour not_allowed)
			(footprints allowed)
		)
		(placement
			(enabled no)
			(sheetname "")
		)
		(fill yes
			(thermal_gap 0.5)
			(thermal_bridge_width 0.5)
			(island_removal_mode 0)
		)
		(polygon
			(pts
				(arc
					(start 333.228696 -418.412168)
					(mid 332.560676 -418.412168)
					(end 333.228696 -418.412168)
				)
			)
		)
	)
	(zone
		(layers "F.Cu" "In2.Cu" "In4.Cu")
		(hatch none 0.5)
		(connect_pads
			(clearance 0)
		)
		(min_thickness 0.25)
		(keepout
			(tracks not_allowed)
			(vias allowed)
			(pads allowed)
			(copperpour not_allowed)
			(footprints allowed)
		)
		(placement
			(enabled no)
			(sheetname "")
		)
		(fill yes
			(thermal_gap 0.5)
			(thermal_bridge_width 0.5)
			(island_removal_mode 0)
		)
		(polygon
			(pts
				(arc
					(start 376.686572 -415.38652)
					(mid 376.018552 -415.38652)
					(end 376.686572 -415.38652)
				)
			)
		)
	)
	(zone
		(layers "F.Cu" "In2.Cu" "In4.Cu")
		(hatch none 0.5)
		(connect_pads
			(clearance 0)
		)
		(min_thickness 0.25)
		(keepout
			(tracks not_allowed)
			(vias allowed)
			(pads allowed)
			(copperpour not_allowed)
			(footprints allowed)
		)
		(placement
			(enabled no)
			(sheetname "")
		)
		(fill yes
			(thermal_gap 0.5)
			(thermal_bridge_width 0.5)
			(island_removal_mode 0)
		)
		(polygon
			(pts
				(arc
					(start 413.445452 -415.38652)
					(mid 412.777432 -415.38652)
					(end 413.445452 -415.38652)
				)
			)
		)
	)
	(zone
		(layers "F.Cu" "In2.Cu" "In4.Cu")
		(hatch none 0.5)
		(connect_pads
			(clearance 0)
		)
		(min_thickness 0.25)
		(keepout
			(tracks not_allowed)
			(vias allowed)
			(pads allowed)
			(copperpour not_allowed)
			(footprints allowed)
		)
		(placement
			(enabled no)
			(sheetname "")
		)
		(fill yes
			(thermal_gap 0.5)
			(thermal_bridge_width 0.5)
			(island_removal_mode 0)
		)
		(polygon
			(pts
				(arc
					(start 78.092554 -410.030168)
					(mid 77.424534 -410.030168)
					(end 78.092554 -410.030168)
				)
			)
		)
	)
	(zone
		(layers "F.Cu" "In2.Cu" "In4.Cu")
		(hatch none 0.5)
		(connect_pads
			(clearance 0)
		)
		(min_thickness 0.25)
		(keepout
			(tracks not_allowed)
			(vias allowed)
			(pads allowed)
			(copperpour not_allowed)
			(footprints allowed)
		)
		(placement
			(enabled no)
			(sheetname "")
		)
		(fill yes
			(thermal_gap 0.5)
			(thermal_bridge_width 0.5)
			(island_removal_mode 0)
		)
		(polygon
			(pts
				(arc
					(start 406.455372 -418.412168)
					(mid 405.787352 -418.412168)
					(end 406.455372 -418.412168)
				)
			)
		)
	)
	(zone
		(layers "F.Cu" "In2.Cu" "In4.Cu")
		(hatch none 0.5)
		(connect_pads
			(clearance 0)
		)
		(min_thickness 0.25)
		(keepout
			(tracks not_allowed)
			(vias allowed)
			(pads allowed)
			(copperpour not_allowed)
			(footprints allowed)
		)
		(placement
			(enabled no)
			(sheetname "")
		)
		(fill yes
			(thermal_gap 0.5)
			(thermal_bridge_width 0.5)
			(island_removal_mode 0)
		)
		(polygon
			(pts
				(arc
					(start 331.029056 -415.38652)
					(mid 330.361036 -415.38652)
					(end 331.029056 -415.38652)
				)
			)
		)
	)
	(zone
		(layers "F.Cu" "In2.Cu" "In4.Cu")
		(hatch none 0.5)
		(connect_pads
			(clearance 0)
		)
		(min_thickness 0.25)
		(keepout
			(tracks not_allowed)
			(vias allowed)
			(pads allowed)
			(copperpour not_allowed)
			(footprints allowed)
		)
		(placement
			(enabled no)
			(sheetname "")
		)
		(fill yes
			(thermal_gap 0.5)
			(thermal_bridge_width 0.5)
			(island_removal_mode 0)
		)
		(polygon
			(pts
				(arc
					(start 321.839336 -418.412168)
					(mid 321.171316 -418.412168)
					(end 321.839336 -418.412168)
				)
			)
		)
	)
	(zone
		(layers "F.Cu" "In2.Cu" "In4.Cu")
		(hatch none 0.5)
		(connect_pads
			(clearance 0)
		)
		(min_thickness 0.25)
		(keepout
			(tracks not_allowed)
			(vias allowed)
			(pads allowed)
			(copperpour not_allowed)
			(footprints allowed)
		)
		(placement
			(enabled no)
			(sheetname "")
		)
		(fill yes
			(thermal_gap 0.5)
			(thermal_bridge_width 0.5)
			(island_removal_mode 0)
		)
		(polygon
			(pts
				(arc
					(start 346.345256 -415.38652)
					(mid 345.677236 -415.38652)
					(end 346.345256 -415.38652)
				)
			)
		)
	)
	(zone
		(layers "F.Cu" "In2.Cu" "In4.Cu")
		(hatch none 0.5)
		(connect_pads
			(clearance 0)
		)
		(min_thickness 0.25)
		(keepout
			(tracks not_allowed)
			(vias allowed)
			(pads allowed)
			(copperpour not_allowed)
			(footprints allowed)
		)
		(placement
			(enabled no)
			(sheetname "")
		)
		(fill yes
			(thermal_gap 0.5)
			(thermal_bridge_width 0.5)
			(island_removal_mode 0)
		)
		(polygon
			(pts
				(arc
					(start 141.265656 -410.030168)
					(mid 140.597636 -410.030168)
					(end 141.265656 -410.030168)
				)
			)
		)
	)
	(zone
		(layers "F.Cu" "In2.Cu" "In4.Cu")
		(hatch none 0.5)
		(connect_pads
			(clearance 0)
		)
		(min_thickness 0.25)
		(keepout
			(tracks not_allowed)
			(vias allowed)
			(pads allowed)
			(copperpour not_allowed)
			(footprints allowed)
		)
		(placement
			(enabled no)
			(sheetname "")
		)
		(fill yes
			(thermal_gap 0.5)
			(thermal_bridge_width 0.5)
			(island_removal_mode 0)
		)
		(polygon
			(pts
				(arc
					(start 87.282274 -410.030168)
					(mid 86.614254 -410.030168)
					(end 87.282274 -410.030168)
				)
			)
		)
	)
	(zone
		(layers "F.Cu" "In2.Cu" "In4.Cu")
		(hatch none 0.5)
		(connect_pads
			(clearance 0)
		)
		(min_thickness 0.25)
		(keepout
			(tracks not_allowed)
			(vias allowed)
			(pads allowed)
			(copperpour not_allowed)
			(footprints allowed)
		)
		(placement
			(enabled no)
			(sheetname "")
		)
		(fill yes
			(thermal_gap 0.5)
			(thermal_bridge_width 0.5)
			(island_removal_mode 0)
		)
		(polygon
			(pts
				(arc
					(start 388.075932 -415.38652)
					(mid 387.407912 -415.38652)
					(end 388.075932 -415.38652)
				)
			)
		)
	)
	(zone
		(layers "F.Cu" "In2.Cu" "In4.Cu")
		(hatch none 0.5)
		(connect_pads
			(clearance 0)
		)
		(min_thickness 0.25)
		(keepout
			(tracks not_allowed)
			(vias allowed)
			(pads allowed)
			(copperpour not_allowed)
			(footprints allowed)
		)
		(placement
			(enabled no)
			(sheetname "")
		)
		(fill yes
			(thermal_gap 0.5)
			(thermal_bridge_width 0.5)
			(island_removal_mode 0)
		)
		(polygon
			(pts
				(arc
					(start 352.471736 -418.412168)
					(mid 351.803716 -418.412168)
					(end 352.471736 -418.412168)
				)
			)
		)
	)
	(zone
		(layers "F.Cu" "In2.Cu" "In4.Cu")
		(hatch none 0.5)
		(connect_pads
			(clearance 0)
		)
		(min_thickness 0.25)
		(keepout
			(tracks not_allowed)
			(vias allowed)
			(pads allowed)
			(copperpour not_allowed)
			(footprints allowed)
		)
		(placement
			(enabled no)
			(sheetname "")
		)
		(fill yes
			(thermal_gap 0.5)
			(thermal_bridge_width 0.5)
			(island_removal_mode 0)
		)
		(polygon
			(pts
				(arc
					(start 41.9227 -415.383726)
					(mid 41.25468 -415.383726)
					(end 41.9227 -415.383726)
				)
			)
		)
	)
	(zone
		(layers "F.Cu" "In2.Cu" "In4.Cu")
		(hatch none 0.5)
		(connect_pads
			(clearance 0)
		)
		(min_thickness 0.25)
		(keepout
			(tracks not_allowed)
			(vias allowed)
			(pads allowed)
			(copperpour not_allowed)
			(footprints allowed)
		)
		(placement
			(enabled no)
			(sheetname "")
		)
		(fill yes
			(thermal_gap 0.5)
			(thermal_bridge_width 0.5)
			(island_removal_mode 0)
		)
		(polygon
			(pts
				(arc
					(start 65.839594 -410.030168)
					(mid 65.171574 -410.030168)
					(end 65.839594 -410.030168)
				)
			)
		)
	)
	(zone
		(layers "F.Cu" "In2.Cu" "In4.Cu")
		(hatch none 0.5)
		(connect_pads
			(clearance 0)
		)
		(min_thickness 0.25)
		(keepout
			(tracks not_allowed)
			(vias allowed)
			(pads allowed)
			(copperpour not_allowed)
			(footprints allowed)
		)
		(placement
			(enabled no)
			(sheetname "")
		)
		(fill yes
			(thermal_gap 0.5)
			(thermal_bridge_width 0.5)
			(island_removal_mode 0)
		)
		(polygon
			(pts
				(arc
					(start 141.265656 -407.00452)
					(mid 140.597636 -407.00452)
					(end 141.265656 -407.00452)
				)
			)
		)
	)
	(zone
		(layers "F.Cu" "In2.Cu" "In4.Cu")
		(hatch none 0.5)
		(connect_pads
			(clearance 0)
		)
		(min_thickness 0.25)
		(keepout
			(tracks not_allowed)
			(vias allowed)
			(pads allowed)
			(copperpour not_allowed)
			(footprints allowed)
		)
		(placement
			(enabled no)
			(sheetname "")
		)
		(fill yes
			(thermal_gap 0.5)
			(thermal_bridge_width 0.5)
			(island_removal_mode 0)
		)
		(polygon
			(pts
				(arc
					(start 55.786274 -410.030168)
					(mid 55.118254 -410.030168)
					(end 55.786274 -410.030168)
				)
			)
		)
	)
	(zone
		(layers "F.Cu" "In2.Cu" "In4.Cu")
		(hatch none 0.5)
		(connect_pads
			(clearance 0)
		)
		(min_thickness 0.25)
		(keepout
			(tracks not_allowed)
			(vias allowed)
			(pads allowed)
			(copperpour not_allowed)
			(footprints allowed)
		)
		(placement
			(enabled no)
			(sheetname "")
		)
		(fill yes
			(thermal_gap 0.5)
			(thermal_bridge_width 0.5)
			(island_removal_mode 0)
		)
		(polygon
			(pts
				(arc
					(start 315.712856 -415.38652)
					(mid 315.044836 -415.38652)
					(end 315.712856 -415.38652)
				)
			)
		)
	)
	(zone
		(layers "F.Cu" "In2.Cu" "In4.Cu")
		(hatch none 0.5)
		(connect_pads
			(clearance 0)
		)
		(min_thickness 0.25)
		(keepout
			(tracks not_allowed)
			(vias allowed)
			(pads allowed)
			(copperpour not_allowed)
			(footprints allowed)
		)
		(placement
			(enabled no)
			(sheetname "")
		)
		(fill yes
			(thermal_gap 0.5)
			(thermal_bridge_width 0.5)
			(island_removal_mode 0)
		)
		(polygon
			(pts
				(arc
					(start 388.075932 -418.412168)
					(mid 387.407912 -418.412168)
					(end 388.075932 -418.412168)
				)
			)
		)
	)
	(zone
		(layers "F.Cu" "In2.Cu" "In4.Cu")
		(hatch none 0.5)
		(connect_pads
			(clearance 0)
		)
		(min_thickness 0.25)
		(keepout
			(tracks not_allowed)
			(vias allowed)
			(pads allowed)
			(copperpour not_allowed)
			(footprints allowed)
		)
		(placement
			(enabled no)
			(sheetname "")
		)
		(fill yes
			(thermal_gap 0.5)
			(thermal_bridge_width 0.5)
			(island_removal_mode 0)
		)
		(polygon
			(pts
				(arc
					(start 145.192496 -410.030168)
					(mid 144.524476 -410.030168)
					(end 145.192496 -410.030168)
				)
			)
		)
	)
	(zone
		(layers "F.Cu" "In2.Cu" "In4.Cu")
		(hatch none 0.5)
		(connect_pads
			(clearance 0)
		)
		(min_thickness 0.25)
		(keepout
			(tracks not_allowed)
			(vias allowed)
			(pads allowed)
			(copperpour not_allowed)
			(footprints allowed)
		)
		(placement
			(enabled no)
			(sheetname "")
		)
		(fill yes
			(thermal_gap 0.5)
			(thermal_bridge_width 0.5)
			(island_removal_mode 0)
		)
		(polygon
			(pts
				(arc
					(start 416.508692 -418.412168)
					(mid 415.840672 -418.412168)
					(end 416.508692 -418.412168)
				)
			)
		)
	)
	(zone
		(layers "F.Cu" "In2.Cu" "In4.Cu")
		(hatch none 0.5)
		(connect_pads
			(clearance 0)
		)
		(min_thickness 0.25)
		(keepout
			(tracks not_allowed)
			(vias allowed)
			(pads allowed)
			(copperpour not_allowed)
			(footprints allowed)
		)
		(placement
			(enabled no)
			(sheetname "")
		)
		(fill yes
			(thermal_gap 0.5)
			(thermal_bridge_width 0.5)
			(island_removal_mode 0)
		)
		(polygon
			(pts
				(arc
					(start 96.471994 -410.030168)
					(mid 95.803974 -410.030168)
					(end 96.471994 -410.030168)
				)
			)
		)
	)
	(zone
		(layers "F.Cu" "In2.Cu" "In4.Cu")
		(hatch none 0.5)
		(connect_pads
			(clearance 0)
		)
		(min_thickness 0.25)
		(keepout
			(tracks not_allowed)
			(vias allowed)
			(pads allowed)
			(copperpour not_allowed)
			(footprints allowed)
		)
		(placement
			(enabled no)
			(sheetname "")
		)
		(fill yes
			(thermal_gap 0.5)
			(thermal_bridge_width 0.5)
			(island_removal_mode 0)
		)
		(polygon
			(pts
				(arc
					(start 372.759732 -418.412168)
					(mid 372.091712 -418.412168)
					(end 372.759732 -418.412168)
				)
			)
		)
	)
	(zone
		(layers "F.Cu" "In2.Cu" "In4.Cu")
		(hatch none 0.5)
		(connect_pads
			(clearance 0)
		)
		(min_thickness 0.25)
		(keepout
			(tracks not_allowed)
			(vias allowed)
			(pads allowed)
			(copperpour not_allowed)
			(footprints allowed)
		)
		(placement
			(enabled no)
			(sheetname "")
		)
		(fill yes
			(thermal_gap 0.5)
			(thermal_bridge_width 0.5)
			(island_removal_mode 0)
		)
		(polygon
			(pts
				(arc
					(start 401.192492 -418.412168)
					(mid 400.524472 -418.412168)
					(end 401.192492 -418.412168)
				)
			)
		)
	)
	(zone
		(layers "F.Cu" "In2.Cu" "In4.Cu")
		(hatch none 0.5)
		(connect_pads
			(clearance 0)
		)
		(min_thickness 0.25)
		(keepout
			(tracks not_allowed)
			(vias allowed)
			(pads allowed)
			(copperpour not_allowed)
			(footprints allowed)
		)
		(placement
			(enabled no)
			(sheetname "")
		)
		(fill yes
			(thermal_gap 0.5)
			(thermal_bridge_width 0.5)
			(island_removal_mode 0)
		)
		(polygon
			(pts
				(arc
					(start 163.571936 -410.030168)
					(mid 162.903916 -410.030168)
					(end 163.571936 -410.030168)
				)
			)
		)
	)
	(zone
		(layers "F.Cu" "In2.Cu" "In4.Cu")
		(hatch none 0.5)
		(connect_pads
			(clearance 0)
		)
		(min_thickness 0.25)
		(keepout
			(tracks not_allowed)
			(vias allowed)
			(pads allowed)
			(copperpour not_allowed)
			(footprints allowed)
		)
		(placement
			(enabled no)
			(sheetname "")
		)
		(fill yes
			(thermal_gap 0.5)
			(thermal_bridge_width 0.5)
			(island_removal_mode 0)
		)
		(polygon
			(pts
				(arc
					(start 397.265652 -418.412168)
					(mid 396.597632 -418.412168)
					(end 397.265652 -418.412168)
				)
			)
		)
	)
	(zone
		(layers "F.Cu" "In2.Cu" "In4.Cu")
		(hatch none 0.5)
		(connect_pads
			(clearance 0)
		)
		(min_thickness 0.25)
		(keepout
			(tracks not_allowed)
			(vias allowed)
			(pads allowed)
			(copperpour not_allowed)
			(footprints allowed)
		)
		(placement
			(enabled no)
			(sheetname "")
		)
		(fill yes
			(thermal_gap 0.5)
			(thermal_bridge_width 0.5)
			(island_removal_mode 0)
		)
		(polygon
			(pts
				(arc
					(start 116.759736 -410.030168)
					(mid 116.091716 -410.030168)
					(end 116.759736 -410.030168)
				)
			)
		)
	)
	(zone
		(layers "F.Cu" "In2.Cu" "In4.Cu")
		(hatch none 0.5)
		(connect_pads
			(clearance 0)
		)
		(min_thickness 0.25)
		(keepout
			(tracks not_allowed)
			(vias allowed)
			(pads allowed)
			(copperpour not_allowed)
			(footprints allowed)
		)
		(placement
			(enabled no)
			(sheetname "")
		)
		(fill yes
			(thermal_gap 0.5)
			(thermal_bridge_width 0.5)
			(island_removal_mode 0)
		)
		(polygon
			(pts
				(arc
					(start 89.481914 -410.030168)
					(mid 88.813894 -410.030168)
					(end 89.481914 -410.030168)
				)
			)
		)
	)
	(zone
		(layers "F.Cu" "In2.Cu" "In4.Cu")
		(hatch none 0.5)
		(connect_pads
			(clearance 0)
		)
		(min_thickness 0.25)
		(keepout
			(tracks not_allowed)
			(vias allowed)
			(pads allowed)
			(copperpour not_allowed)
			(footprints allowed)
		)
		(placement
			(enabled no)
			(sheetname "")
		)
		(fill yes
			(thermal_gap 0.5)
			(thermal_bridge_width 0.5)
			(island_removal_mode 0)
		)
		(polygon
			(pts
				(arc
					(start 53.586634 -410.030168)
					(mid 52.918614 -410.030168)
					(end 53.586634 -410.030168)
				)
			)
		)
	)
	(zone
		(layers "F.Cu" "In2.Cu" "In4.Cu")
		(hatch none 0.5)
		(connect_pads
			(clearance 0)
		)
		(min_thickness 0.25)
		(keepout
			(tracks not_allowed)
			(vias allowed)
			(pads allowed)
			(copperpour not_allowed)
			(footprints allowed)
		)
		(placement
			(enabled no)
			(sheetname "")
		)
		(fill yes
			(thermal_gap 0.5)
			(thermal_bridge_width 0.5)
			(island_removal_mode 0)
		)
		(polygon
			(pts
				(arc
					(start 327.102216 -415.38652)
					(mid 326.434196 -415.38652)
					(end 327.102216 -415.38652)
				)
			)
		)
	)
	(zone
		(layers "F.Cu" "In2.Cu" "In4.Cu")
		(hatch none 0.5)
		(connect_pads
			(clearance 0)
		)
		(min_thickness 0.25)
		(keepout
			(tracks not_allowed)
			(vias allowed)
			(pads allowed)
			(copperpour not_allowed)
			(footprints allowed)
		)
		(placement
			(enabled no)
			(sheetname "")
		)
		(fill yes
			(thermal_gap 0.5)
			(thermal_bridge_width 0.5)
			(island_removal_mode 0)
		)
		(polygon
			(pts
				(arc
					(start 317.912496 -415.38652)
					(mid 317.244476 -415.38652)
					(end 317.912496 -415.38652)
				)
			)
		)
	)
	(zone
		(layers "F.Cu" "In2.Cu" "In4.Cu")
		(hatch none 0.5)
		(connect_pads
			(clearance 0)
		)
		(min_thickness 0.25)
		(keepout
			(tracks not_allowed)
			(vias allowed)
			(pads allowed)
			(copperpour not_allowed)
			(footprints allowed)
		)
		(placement
			(enabled no)
			(sheetname "")
		)
		(fill yes
			(thermal_gap 0.5)
			(thermal_bridge_width 0.5)
			(island_removal_mode 0)
		)
		(polygon
			(pts
				(arc
					(start 136.002776 -407.00452)
					(mid 135.334756 -407.00452)
					(end 136.002776 -407.00452)
				)
			)
		)
	)
	(zone
		(layers "F.Cu" "In2.Cu" "In4.Cu")
		(hatch none 0.5)
		(connect_pads
			(clearance 0)
		)
		(min_thickness 0.25)
		(keepout
			(tracks not_allowed)
			(vias allowed)
			(pads allowed)
			(copperpour not_allowed)
			(footprints allowed)
		)
		(placement
			(enabled no)
			(sheetname "")
		)
		(fill yes
			(thermal_gap 0.5)
			(thermal_bridge_width 0.5)
			(island_removal_mode 0)
		)
		(polygon
			(pts
				(arc
					(start 416.508692 -415.38652)
					(mid 415.840672 -415.38652)
					(end 416.508692 -415.38652)
				)
			)
		)
	)
	(zone
		(layers "F.Cu" "In2.Cu" "In4.Cu")
		(hatch none 0.5)
		(connect_pads
			(clearance 0)
		)
		(min_thickness 0.25)
		(keepout
			(tracks not_allowed)
			(vias allowed)
			(pads allowed)
			(copperpour not_allowed)
			(footprints allowed)
		)
		(placement
			(enabled no)
			(sheetname "")
		)
		(fill yes
			(thermal_gap 0.5)
			(thermal_bridge_width 0.5)
			(island_removal_mode 0)
		)
		(polygon
			(pts
				(arc
					(start 373.623332 -418.412168)
					(mid 372.955312 -418.412168)
					(end 373.623332 -418.412168)
				)
			)
		)
	)
	(zone
		(layers "F.Cu" "In2.Cu" "In4.Cu")
		(hatch none 0.5)
		(connect_pads
			(clearance 0)
		)
		(min_thickness 0.25)
		(keepout
			(tracks not_allowed)
			(vias allowed)
			(pads allowed)
			(copperpour not_allowed)
			(footprints allowed)
		)
		(placement
			(enabled no)
			(sheetname "")
		)
		(fill yes
			(thermal_gap 0.5)
			(thermal_bridge_width 0.5)
			(island_removal_mode 0)
		)
		(polygon
			(pts
				(arc
					(start 406.455372 -415.38652)
					(mid 405.787352 -415.38652)
					(end 406.455372 -415.38652)
				)
			)
		)
	)
	(zone
		(layers "F.Cu" "In2.Cu" "In4.Cu")
		(hatch none 0.5)
		(connect_pads
			(clearance 0)
		)
		(min_thickness 0.25)
		(keepout
			(tracks not_allowed)
			(vias allowed)
			(pads allowed)
			(copperpour not_allowed)
			(footprints allowed)
		)
		(placement
			(enabled no)
			(sheetname "")
		)
		(fill yes
			(thermal_gap 0.5)
			(thermal_bridge_width 0.5)
			(island_removal_mode 0)
		)
		(polygon
			(pts
				(arc
					(start 311.786016 -415.38652)
					(mid 311.117996 -415.38652)
					(end 311.786016 -415.38652)
				)
			)
		)
	)
	(zone
		(layers "F.Cu" "In2.Cu" "In4.Cu" "In5.Cu" "In6.Cu" "In11.Cu" "In13.Cu"
			"In15.Cu"
		)
		(hatch none 0.5)
		(connect_pads
			(clearance 0)
		)
		(min_thickness 0.25)
		(keepout
			(tracks not_allowed)
			(vias allowed)
			(pads allowed)
			(copperpour not_allowed)
			(footprints allowed)
		)
		(placement
			(enabled no)
			(sheetname "")
		)
		(fill yes
			(thermal_gap 0.5)
			(thermal_bridge_width 0.5)
			(island_removal_mode 0)
		)
		(polygon
			(pts
				(arc
					(start 58.14187 -435.160674)
					(mid 58.164188 -435.214556)
					(end 58.21807 -435.236874)
				)
				(arc
					(start 59.15787 -435.236874)
					(mid 59.211752 -435.214556)
					(end 59.23407 -435.160674)
				)
				(arc
					(start 59.23407 -432.61915)
					(mid 59.211752 -432.565268)
					(end 59.15787 -432.54295)
				)
				(arc
					(start 58.21807 -432.54295)
					(mid 58.164188 -432.565268)
					(end 58.14187 -432.61915)
				)
			)
		)
	)
	(zone
		(layers "F.Cu" "In2.Cu" "In4.Cu" "In5.Cu" "In6.Cu" "In11.Cu" "In13.Cu"
			"In15.Cu"
		)
		(hatch none 0.5)
		(connect_pads
			(clearance 0)
		)
		(min_thickness 0.25)
		(keepout
			(tracks not_allowed)
			(vias allowed)
			(pads allowed)
			(copperpour not_allowed)
			(footprints allowed)
		)
		(placement
			(enabled no)
			(sheetname "")
		)
		(fill yes
			(thermal_gap 0.5)
			(thermal_bridge_width 0.5)
			(island_removal_mode 0)
		)
		(polygon
			(pts
				(arc
					(start 62.141862 -435.160674)
					(mid 62.16418 -435.214556)
					(end 62.218062 -435.236874)
				)
				(arc
					(start 63.157862 -435.236874)
					(mid 63.211744 -435.214556)
					(end 63.234062 -435.160674)
				)
				(arc
					(start 63.234062 -432.61915)
					(mid 63.211744 -432.565268)
					(end 63.157862 -432.54295)
				)
				(arc
					(start 62.218062 -432.54295)
					(mid 62.16418 -432.565268)
					(end 62.141862 -432.61915)
				)
			)
		)
	)
	(zone
		(layers "F.Cu" "In2.Cu" "In4.Cu" "In5.Cu" "In6.Cu" "In11.Cu" "In13.Cu"
			"In15.Cu"
		)
		(hatch none 0.5)
		(connect_pads
			(clearance 0)
		)
		(min_thickness 0.25)
		(keepout
			(tracks not_allowed)
			(vias allowed)
			(pads allowed)
			(copperpour not_allowed)
			(footprints allowed)
		)
		(placement
			(enabled no)
			(sheetname "")
		)
		(fill yes
			(thermal_gap 0.5)
			(thermal_bridge_width 0.5)
			(island_removal_mode 0)
		)
		(polygon
			(pts
				(arc
					(start 72.141842 -436.160672)
					(mid 72.16416 -436.214554)
					(end 72.218042 -436.236872)
				)
				(arc
					(start 73.157842 -436.236872)
					(mid 73.211724 -436.214554)
					(end 73.234042 -436.160672)
				)
				(arc
					(start 73.234042 -433.619148)
					(mid 73.211724 -433.565266)
					(end 73.157842 -433.542948)
				)
				(arc
					(start 72.218042 -433.542948)
					(mid 72.16416 -433.565266)
					(end 72.141842 -433.619148)
				)
			)
		)
	)
	(zone
		(layers "F.Cu" "In2.Cu" "In4.Cu" "In5.Cu" "In6.Cu" "In11.Cu" "In13.Cu"
			"In15.Cu"
		)
		(hatch none 0.5)
		(connect_pads
			(clearance 0)
		)
		(min_thickness 0.25)
		(keepout
			(tracks not_allowed)
			(vias allowed)
			(pads allowed)
			(copperpour not_allowed)
			(footprints allowed)
		)
		(placement
			(enabled no)
			(sheetname "")
		)
		(fill yes
			(thermal_gap 0.5)
			(thermal_bridge_width 0.5)
			(island_removal_mode 0)
		)
		(polygon
			(pts
				(arc
					(start 89.141808 -436.160672)
					(mid 89.164126 -436.214554)
					(end 89.218008 -436.236872)
				)
				(arc
					(start 90.157808 -436.236872)
					(mid 90.21169 -436.214554)
					(end 90.234008 -436.160672)
				)
				(arc
					(start 90.234008 -433.619148)
					(mid 90.21169 -433.565266)
					(end 90.157808 -433.542948)
				)
				(arc
					(start 89.218008 -433.542948)
					(mid 89.164126 -433.565266)
					(end 89.141808 -433.619148)
				)
			)
		)
	)
	(zone
		(layers "F.Cu" "In2.Cu" "In4.Cu" "In5.Cu" "In6.Cu" "In11.Cu" "In13.Cu"
			"In15.Cu"
		)
		(hatch none 0.5)
		(connect_pads
			(clearance 0)
		)
		(min_thickness 0.25)
		(keepout
			(tracks not_allowed)
			(vias allowed)
			(pads allowed)
			(copperpour not_allowed)
			(footprints allowed)
		)
		(placement
			(enabled no)
			(sheetname "")
		)
		(fill yes
			(thermal_gap 0.5)
			(thermal_bridge_width 0.5)
			(island_removal_mode 0)
		)
		(polygon
			(pts
				(arc
					(start 70.141846 -435.160674)
					(mid 70.164164 -435.214556)
					(end 70.218046 -435.236874)
				)
				(arc
					(start 71.157846 -435.236874)
					(mid 71.211728 -435.214556)
					(end 71.234046 -435.160674)
				)
				(arc
					(start 71.234046 -432.61915)
					(mid 71.211728 -432.565268)
					(end 71.157846 -432.54295)
				)
				(arc
					(start 70.218046 -432.54295)
					(mid 70.164164 -432.565268)
					(end 70.141846 -432.61915)
				)
			)
		)
	)
	(zone
		(layers "F.Cu" "In2.Cu" "In4.Cu" "In5.Cu" "In6.Cu" "In11.Cu" "In13.Cu"
			"In15.Cu"
		)
		(hatch none 0.5)
		(connect_pads
			(clearance 0)
		)
		(min_thickness 0.25)
		(keepout
			(tracks not_allowed)
			(vias allowed)
			(pads allowed)
			(copperpour not_allowed)
			(footprints allowed)
		)
		(placement
			(enabled no)
			(sheetname "")
		)
		(fill yes
			(thermal_gap 0.5)
			(thermal_bridge_width 0.5)
			(island_removal_mode 0)
		)
		(polygon
			(pts
				(arc
					(start 324.141846 -432.56073)
					(mid 324.164164 -432.614612)
					(end 324.218046 -432.63693)
				)
				(arc
					(start 325.157846 -432.63693)
					(mid 325.211728 -432.614612)
					(end 325.234046 -432.56073)
				)
				(arc
					(start 325.234046 -430.019206)
					(mid 325.211728 -429.965324)
					(end 325.157846 -429.943006)
				)
				(arc
					(start 324.218046 -429.943006)
					(mid 324.164164 -429.965324)
					(end 324.141846 -430.019206)
				)
			)
		)
	)
	(zone
		(layers "F.Cu" "In2.Cu" "In4.Cu" "In5.Cu" "In6.Cu" "In11.Cu" "In13.Cu"
			"In15.Cu"
		)
		(hatch none 0.5)
		(connect_pads
			(clearance 0)
		)
		(min_thickness 0.25)
		(keepout
			(tracks not_allowed)
			(vias allowed)
			(pads allowed)
			(copperpour not_allowed)
			(footprints allowed)
		)
		(placement
			(enabled no)
			(sheetname "")
		)
		(fill yes
			(thermal_gap 0.5)
			(thermal_bridge_width 0.5)
			(island_removal_mode 0)
		)
		(polygon
			(pts
				(arc
					(start 83.14182 -435.160674)
					(mid 83.164138 -435.214556)
					(end 83.21802 -435.236874)
				)
				(arc
					(start 84.15782 -435.236874)
					(mid 84.211702 -435.214556)
					(end 84.23402 -435.160674)
				)
				(arc
					(start 84.23402 -432.61915)
					(mid 84.211702 -432.565268)
					(end 84.15782 -432.54295)
				)
				(arc
					(start 83.21802 -432.54295)
					(mid 83.164138 -432.565268)
					(end 83.14182 -432.61915)
				)
			)
		)
	)
	(zone
		(layers "F.Cu" "In2.Cu" "In4.Cu" "In5.Cu" "In6.Cu" "In11.Cu" "In13.Cu"
			"In15.Cu"
		)
		(hatch none 0.5)
		(connect_pads
			(clearance 0)
		)
		(min_thickness 0.25)
		(keepout
			(tracks not_allowed)
			(vias allowed)
			(pads allowed)
			(copperpour not_allowed)
			(footprints allowed)
		)
		(placement
			(enabled no)
			(sheetname "")
		)
		(fill yes
			(thermal_gap 0.5)
			(thermal_bridge_width 0.5)
			(island_removal_mode 0)
		)
		(polygon
			(pts
				(arc
					(start 320.141854 -432.56073)
					(mid 320.164172 -432.614612)
					(end 320.218054 -432.63693)
				)
				(arc
					(start 321.157854 -432.63693)
					(mid 321.211736 -432.614612)
					(end 321.234054 -432.56073)
				)
				(arc
					(start 321.234054 -430.019206)
					(mid 321.211736 -429.965324)
					(end 321.157854 -429.943006)
				)
				(arc
					(start 320.218054 -429.943006)
					(mid 320.164172 -429.965324)
					(end 320.141854 -430.019206)
				)
			)
		)
	)
	(zone
		(layers "F.Cu" "In2.Cu" "In4.Cu" "In5.Cu" "In6.Cu" "In11.Cu" "In13.Cu"
			"In15.Cu"
		)
		(hatch none 0.5)
		(connect_pads
			(clearance 0)
		)
		(min_thickness 0.25)
		(keepout
			(tracks not_allowed)
			(vias allowed)
			(pads allowed)
			(copperpour not_allowed)
			(footprints allowed)
		)
		(placement
			(enabled no)
			(sheetname "")
		)
		(fill yes
			(thermal_gap 0.5)
			(thermal_bridge_width 0.5)
			(island_removal_mode 0)
		)
		(polygon
			(pts
				(arc
					(start 87.141812 -435.160674)
					(mid 87.16413 -435.214556)
					(end 87.218012 -435.236874)
				)
				(arc
					(start 88.157812 -435.236874)
					(mid 88.211694 -435.214556)
					(end 88.234012 -435.160674)
				)
				(arc
					(start 88.234012 -432.61915)
					(mid 88.211694 -432.565268)
					(end 88.157812 -432.54295)
				)
				(arc
					(start 87.218012 -432.54295)
					(mid 87.16413 -432.565268)
					(end 87.141812 -432.61915)
				)
			)
		)
	)
	(zone
		(layers "F.Cu" "In2.Cu" "In4.Cu" "In5.Cu" "In6.Cu" "In11.Cu" "In13.Cu"
			"In15.Cu"
		)
		(hatch none 0.5)
		(connect_pads
			(clearance 0)
		)
		(min_thickness 0.25)
		(keepout
			(tracks not_allowed)
			(vias allowed)
			(pads allowed)
			(copperpour not_allowed)
			(footprints allowed)
		)
		(placement
			(enabled no)
			(sheetname "")
		)
		(fill yes
			(thermal_gap 0.5)
			(thermal_bridge_width 0.5)
			(island_removal_mode 0)
		)
		(polygon
			(pts
				(arc
					(start 316.141862 -432.56073)
					(mid 316.16418 -432.614612)
					(end 316.218062 -432.63693)
				)
				(arc
					(start 317.157862 -432.63693)
					(mid 317.211744 -432.614612)
					(end 317.234062 -432.56073)
				)
				(arc
					(start 317.234062 -430.019206)
					(mid 317.211744 -429.965324)
					(end 317.157862 -429.943006)
				)
				(arc
					(start 316.218062 -429.943006)
					(mid 316.16418 -429.965324)
					(end 316.141862 -430.019206)
				)
			)
		)
	)
	(zone
		(layers "F.Cu" "In2.Cu" "In4.Cu" "In5.Cu" "In6.Cu" "In11.Cu" "In13.Cu"
			"In15.Cu"
		)
		(hatch none 0.5)
		(connect_pads
			(clearance 0)
		)
		(min_thickness 0.25)
		(keepout
			(tracks not_allowed)
			(vias allowed)
			(pads allowed)
			(copperpour not_allowed)
			(footprints allowed)
		)
		(placement
			(enabled no)
			(sheetname "")
		)
		(fill yes
			(thermal_gap 0.5)
			(thermal_bridge_width 0.5)
			(island_removal_mode 0)
		)
		(polygon
			(pts
				(arc
					(start 60.141866 -436.160672)
					(mid 60.164184 -436.214554)
					(end 60.218066 -436.236872)
				)
				(arc
					(start 61.157866 -436.236872)
					(mid 61.211748 -436.214554)
					(end 61.234066 -436.160672)
				)
				(arc
					(start 61.234066 -433.619148)
					(mid 61.211748 -433.565266)
					(end 61.157866 -433.542948)
				)
				(arc
					(start 60.218066 -433.542948)
					(mid 60.164184 -433.565266)
					(end 60.141866 -433.619148)
				)
			)
		)
	)
	(zone
		(layers "F.Cu" "In2.Cu" "In4.Cu" "In5.Cu" "In6.Cu" "In11.Cu" "In13.Cu"
			"In15.Cu"
		)
		(hatch none 0.5)
		(connect_pads
			(clearance 0)
		)
		(min_thickness 0.25)
		(keepout
			(tracks not_allowed)
			(vias allowed)
			(pads allowed)
			(copperpour not_allowed)
			(footprints allowed)
		)
		(placement
			(enabled no)
			(sheetname "")
		)
		(fill yes
			(thermal_gap 0.5)
			(thermal_bridge_width 0.5)
			(island_removal_mode 0)
		)
		(polygon
			(pts
				(arc
					(start 66.141854 -435.160674)
					(mid 66.164172 -435.214556)
					(end 66.218054 -435.236874)
				)
				(arc
					(start 67.157854 -435.236874)
					(mid 67.211736 -435.214556)
					(end 67.234054 -435.160674)
				)
				(arc
					(start 67.234054 -432.61915)
					(mid 67.211736 -432.565268)
					(end 67.157854 -432.54295)
				)
				(arc
					(start 66.218054 -432.54295)
					(mid 66.164172 -432.565268)
					(end 66.141854 -432.61915)
				)
			)
		)
	)
	(zone
		(layers "F.Cu" "In2.Cu" "In4.Cu" "In5.Cu" "In6.Cu" "In11.Cu" "In13.Cu"
			"In15.Cu"
		)
		(hatch none 0.5)
		(connect_pads
			(clearance 0)
		)
		(min_thickness 0.25)
		(keepout
			(tracks not_allowed)
			(vias allowed)
			(pads allowed)
			(copperpour not_allowed)
			(footprints allowed)
		)
		(placement
			(enabled no)
			(sheetname "")
		)
		(fill yes
			(thermal_gap 0.5)
			(thermal_bridge_width 0.5)
			(island_removal_mode 0)
		)
		(polygon
			(pts
				(arc
					(start 322.14185 -431.560732)
					(mid 322.164168 -431.614614)
					(end 322.21805 -431.636932)
				)
				(arc
					(start 323.15785 -431.636932)
					(mid 323.211732 -431.614614)
					(end 323.23405 -431.560732)
				)
				(arc
					(start 323.23405 -429.019208)
					(mid 323.211732 -428.965326)
					(end 323.15785 -428.943008)
				)
				(arc
					(start 322.21805 -428.943008)
					(mid 322.164168 -428.965326)
					(end 322.14185 -429.019208)
				)
			)
		)
	)
	(zone
		(layers "F.Cu" "In2.Cu" "In4.Cu" "In5.Cu" "In6.Cu" "In11.Cu" "In13.Cu"
			"In15.Cu"
		)
		(hatch none 0.5)
		(connect_pads
			(clearance 0)
		)
		(min_thickness 0.25)
		(keepout
			(tracks not_allowed)
			(vias allowed)
			(pads allowed)
			(copperpour not_allowed)
			(footprints allowed)
		)
		(placement
			(enabled no)
			(sheetname "")
		)
		(fill yes
			(thermal_gap 0.5)
			(thermal_bridge_width 0.5)
			(island_removal_mode 0)
		)
		(polygon
			(pts
				(arc
					(start 318.141858 -431.560732)
					(mid 318.164176 -431.614614)
					(end 318.218058 -431.636932)
				)
				(arc
					(start 319.157858 -431.636932)
					(mid 319.21174 -431.614614)
					(end 319.234058 -431.560732)
				)
				(arc
					(start 319.234058 -429.019208)
					(mid 319.21174 -428.965326)
					(end 319.157858 -428.943008)
				)
				(arc
					(start 318.218058 -428.943008)
					(mid 318.164176 -428.965326)
					(end 318.141858 -429.019208)
				)
			)
		)
	)
	(zone
		(layers "F.Cu" "In2.Cu" "In4.Cu" "In5.Cu" "In6.Cu" "In11.Cu" "In13.Cu"
			"In15.Cu"
		)
		(hatch none 0.5)
		(connect_pads
			(clearance 0)
		)
		(min_thickness 0.25)
		(keepout
			(tracks not_allowed)
			(vias allowed)
			(pads allowed)
			(copperpour not_allowed)
			(footprints allowed)
		)
		(placement
			(enabled no)
			(sheetname "")
		)
		(fill yes
			(thermal_gap 0.5)
			(thermal_bridge_width 0.5)
			(island_removal_mode 0)
		)
		(polygon
			(pts
				(arc
					(start 326.141842 -431.560732)
					(mid 326.16416 -431.614614)
					(end 326.218042 -431.636932)
				)
				(arc
					(start 327.157842 -431.636932)
					(mid 327.211724 -431.614614)
					(end 327.234042 -431.560732)
				)
				(arc
					(start 327.234042 -429.019208)
					(mid 327.211724 -428.965326)
					(end 327.157842 -428.943008)
				)
				(arc
					(start 326.218042 -428.943008)
					(mid 326.16416 -428.965326)
					(end 326.141842 -429.019208)
				)
			)
		)
	)
	(zone
		(layers "F.Cu" "In2.Cu" "In4.Cu" "In5.Cu" "In6.Cu" "In11.Cu" "In13.Cu"
			"In15.Cu"
		)
		(hatch none 0.5)
		(connect_pads
			(clearance 0)
		)
		(min_thickness 0.25)
		(keepout
			(tracks not_allowed)
			(vias allowed)
			(pads allowed)
			(copperpour not_allowed)
			(footprints allowed)
		)
		(placement
			(enabled no)
			(sheetname "")
		)
		(fill yes
			(thermal_gap 0.5)
			(thermal_bridge_width 0.5)
			(island_removal_mode 0)
		)
		(polygon
			(pts
				(arc
					(start 75.141836 -435.160674)
					(mid 75.164154 -435.214556)
					(end 75.218036 -435.236874)
				)
				(arc
					(start 76.157836 -435.236874)
					(mid 76.211718 -435.214556)
					(end 76.234036 -435.160674)
				)
				(arc
					(start 76.234036 -432.61915)
					(mid 76.211718 -432.565268)
					(end 76.157836 -432.54295)
				)
				(arc
					(start 75.218036 -432.54295)
					(mid 75.164154 -432.565268)
					(end 75.141836 -432.61915)
				)
			)
		)
	)
	(zone
		(layers "F.Cu" "In2.Cu" "In4.Cu" "In5.Cu" "In6.Cu" "In11.Cu" "In13.Cu"
			"In15.Cu"
		)
		(hatch none 0.5)
		(connect_pads
			(clearance 0)
		)
		(min_thickness 0.25)
		(keepout
			(tracks not_allowed)
			(vias allowed)
			(pads allowed)
			(copperpour not_allowed)
			(footprints allowed)
		)
		(placement
			(enabled no)
			(sheetname "")
		)
		(fill yes
			(thermal_gap 0.5)
			(thermal_bridge_width 0.5)
			(island_removal_mode 0)
		)
		(polygon
			(pts
				(arc
					(start 77.141832 -436.160672)
					(mid 77.16415 -436.214554)
					(end 77.218032 -436.236872)
				)
				(arc
					(start 78.157832 -436.236872)
					(mid 78.211714 -436.214554)
					(end 78.234032 -436.160672)
				)
				(arc
					(start 78.234032 -433.619148)
					(mid 78.211714 -433.565266)
					(end 78.157832 -433.542948)
				)
				(arc
					(start 77.218032 -433.542948)
					(mid 77.16415 -433.565266)
					(end 77.141832 -433.619148)
				)
			)
		)
	)
	(zone
		(layers "F.Cu" "In2.Cu" "In4.Cu" "In5.Cu" "In6.Cu" "In11.Cu" "In13.Cu"
			"In15.Cu"
		)
		(hatch none 0.5)
		(connect_pads
			(clearance 0)
		)
		(min_thickness 0.25)
		(keepout
			(tracks not_allowed)
			(vias allowed)
			(pads allowed)
			(copperpour not_allowed)
			(footprints allowed)
		)
		(placement
			(enabled no)
			(sheetname "")
		)
		(fill yes
			(thermal_gap 0.5)
			(thermal_bridge_width 0.5)
			(island_removal_mode 0)
		)
		(polygon
			(pts
				(arc
					(start 64.141858 -436.160672)
					(mid 64.164176 -436.214554)
					(end 64.218058 -436.236872)
				)
				(arc
					(start 65.157858 -436.236872)
					(mid 65.21174 -436.214554)
					(end 65.234058 -436.160672)
				)
				(arc
					(start 65.234058 -433.619148)
					(mid 65.21174 -433.565266)
					(end 65.157858 -433.542948)
				)
				(arc
					(start 64.218058 -433.542948)
					(mid 64.164176 -433.565266)
					(end 64.141858 -433.619148)
				)
			)
		)
	)
	(zone
		(layers "F.Cu" "In2.Cu" "In4.Cu" "In5.Cu" "In6.Cu" "In11.Cu" "In13.Cu"
			"In15.Cu"
		)
		(hatch none 0.5)
		(connect_pads
			(clearance 0)
		)
		(min_thickness 0.25)
		(keepout
			(tracks not_allowed)
			(vias allowed)
			(pads allowed)
			(copperpour not_allowed)
			(footprints allowed)
		)
		(placement
			(enabled no)
			(sheetname "")
		)
		(fill yes
			(thermal_gap 0.5)
			(thermal_bridge_width 0.5)
			(island_removal_mode 0)
		)
		(polygon
			(pts
				(arc
					(start 68.14185 -436.160672)
					(mid 68.164168 -436.214554)
					(end 68.21805 -436.236872)
				)
				(arc
					(start 69.15785 -436.236872)
					(mid 69.211732 -436.214554)
					(end 69.23405 -436.160672)
				)
				(arc
					(start 69.23405 -433.619148)
					(mid 69.211732 -433.565266)
					(end 69.15785 -433.542948)
				)
				(arc
					(start 68.21805 -433.542948)
					(mid 68.164168 -433.565266)
					(end 68.14185 -433.619148)
				)
			)
		)
	)
	(zone
		(layers "F.Cu" "In2.Cu" "In4.Cu" "In5.Cu" "In6.Cu" "In11.Cu" "In13.Cu"
			"In15.Cu"
		)
		(hatch none 0.5)
		(connect_pads
			(clearance 0)
		)
		(min_thickness 0.25)
		(keepout
			(tracks not_allowed)
			(vias allowed)
			(pads allowed)
			(copperpour not_allowed)
			(footprints allowed)
		)
		(placement
			(enabled no)
			(sheetname "")
		)
		(fill yes
			(thermal_gap 0.5)
			(thermal_bridge_width 0.5)
			(island_removal_mode 0)
		)
		(polygon
			(pts
				(arc
					(start 81.141824 -436.160672)
					(mid 81.164142 -436.214554)
					(end 81.218024 -436.236872)
				)
				(arc
					(start 82.157824 -436.236872)
					(mid 82.211706 -436.214554)
					(end 82.234024 -436.160672)
				)
				(arc
					(start 82.234024 -433.619148)
					(mid 82.211706 -433.565266)
					(end 82.157824 -433.542948)
				)
				(arc
					(start 81.218024 -433.542948)
					(mid 81.164142 -433.565266)
					(end 81.141824 -433.619148)
				)
			)
		)
	)
	(zone
		(layers "F.Cu" "In2.Cu" "In4.Cu" "In5.Cu" "In6.Cu" "In11.Cu" "In13.Cu"
			"In15.Cu"
		)
		(hatch none 0.5)
		(connect_pads
			(clearance 0)
		)
		(min_thickness 0.25)
		(keepout
			(tracks not_allowed)
			(vias allowed)
			(pads allowed)
			(copperpour not_allowed)
			(footprints allowed)
		)
		(placement
			(enabled no)
			(sheetname "")
		)
		(fill yes
			(thermal_gap 0.5)
			(thermal_bridge_width 0.5)
			(island_removal_mode 0)
		)
		(polygon
			(pts
				(arc
					(start 79.141828 -435.160674)
					(mid 79.164146 -435.214556)
					(end 79.218028 -435.236874)
				)
				(arc
					(start 80.157828 -435.236874)
					(mid 80.21171 -435.214556)
					(end 80.234028 -435.160674)
				)
				(arc
					(start 80.234028 -432.61915)
					(mid 80.21171 -432.565268)
					(end 80.157828 -432.54295)
				)
				(arc
					(start 79.218028 -432.54295)
					(mid 79.164146 -432.565268)
					(end 79.141828 -432.61915)
				)
			)
		)
	)
	(zone
		(layers "F.Cu" "In2.Cu" "In4.Cu" "In5.Cu" "In6.Cu" "In11.Cu" "In13.Cu"
			"In15.Cu"
		)
		(hatch none 0.5)
		(connect_pads
			(clearance 0)
		)
		(min_thickness 0.25)
		(keepout
			(tracks not_allowed)
			(vias allowed)
			(pads allowed)
			(copperpour not_allowed)
			(footprints allowed)
		)
		(placement
			(enabled no)
			(sheetname "")
		)
		(fill yes
			(thermal_gap 0.5)
			(thermal_bridge_width 0.5)
			(island_removal_mode 0)
		)
		(polygon
			(pts
				(arc
					(start 328.141838 -432.56073)
					(mid 328.164156 -432.614612)
					(end 328.218038 -432.63693)
				)
				(arc
					(start 329.157838 -432.63693)
					(mid 329.21172 -432.614612)
					(end 329.234038 -432.56073)
				)
				(arc
					(start 329.234038 -430.019206)
					(mid 329.21172 -429.965324)
					(end 329.157838 -429.943006)
				)
				(arc
					(start 328.218038 -429.943006)
					(mid 328.164156 -429.965324)
					(end 328.141838 -430.019206)
				)
			)
		)
	)
	(zone
		(layers "F.Cu" "In2.Cu" "In4.Cu" "In5.Cu" "In6.Cu" "In11.Cu" "In13.Cu"
			"In15.Cu"
		)
		(hatch none 0.5)
		(connect_pads
			(clearance 0)
		)
		(min_thickness 0.25)
		(keepout
			(tracks not_allowed)
			(vias allowed)
			(pads allowed)
			(copperpour not_allowed)
			(footprints allowed)
		)
		(placement
			(enabled no)
			(sheetname "")
		)
		(fill yes
			(thermal_gap 0.5)
			(thermal_bridge_width 0.5)
			(island_removal_mode 0)
		)
		(polygon
			(pts
				(arc
					(start 85.141816 -436.160672)
					(mid 85.164134 -436.214554)
					(end 85.218016 -436.236872)
				)
				(arc
					(start 86.157816 -436.236872)
					(mid 86.211698 -436.214554)
					(end 86.234016 -436.160672)
				)
				(arc
					(start 86.234016 -433.619148)
					(mid 86.211698 -433.565266)
					(end 86.157816 -433.542948)
				)
				(arc
					(start 85.218016 -433.542948)
					(mid 85.164134 -433.565266)
					(end 85.141816 -433.619148)
				)
			)
		)
	)
	(zone
		(layers "F.Cu" "In2.Cu" "In4.Cu" "In5.Cu" "In6.Cu" "In11.Cu" "In13.Cu"
			"In15.Cu"
		)
		(hatch none 0.5)
		(connect_pads
			(clearance 0)
		)
		(min_thickness 0.25)
		(keepout
			(tracks not_allowed)
			(vias allowed)
			(pads allowed)
			(copperpour not_allowed)
			(footprints allowed)
		)
		(placement
			(enabled no)
			(sheetname "")
		)
		(fill yes
			(thermal_gap 0.5)
			(thermal_bridge_width 0.5)
			(island_removal_mode 0)
		)
		(polygon
			(pts
				(arc
					(start 314.141866 -431.560732)
					(mid 314.164184 -431.614614)
					(end 314.218066 -431.636932)
				)
				(arc
					(start 315.157866 -431.636932)
					(mid 315.211748 -431.614614)
					(end 315.234066 -431.560732)
				)
				(arc
					(start 315.234066 -429.019208)
					(mid 315.211748 -428.965326)
					(end 315.157866 -428.943008)
				)
				(arc
					(start 314.218066 -428.943008)
					(mid 314.164184 -428.965326)
					(end 314.141866 -429.019208)
				)
			)
		)
	)
	(zone
		(layers "F.Cu" "In2.Cu" "In4.Cu" "In6.Cu")
		(hatch none 0.5)
		(connect_pads
			(clearance 0)
		)
		(min_thickness 0.25)
		(keepout
			(tracks not_allowed)
			(vias allowed)
			(pads allowed)
			(copperpour not_allowed)
			(footprints allowed)
		)
		(placement
			(enabled no)
			(sheetname "")
		)
		(fill yes
			(thermal_gap 0.5)
			(thermal_bridge_width 0.5)
			(island_removal_mode 0)
		)
		(polygon
			(pts
				(arc
					(start 439.641488 8.258048)
					(mid 438.973468 8.258048)
					(end 439.641488 8.258048)
				)
			)
		)
	)
	(zone
		(layers "F.Cu" "In2.Cu" "In4.Cu" "In6.Cu")
		(hatch none 0.5)
		(connect_pads
			(clearance 0)
		)
		(min_thickness 0.25)
		(keepout
			(tracks not_allowed)
			(vias allowed)
			(pads allowed)
			(copperpour not_allowed)
			(footprints allowed)
		)
		(placement
			(enabled no)
			(sheetname "")
		)
		(fill yes
			(thermal_gap 0.5)
			(thermal_bridge_width 0.5)
			(island_removal_mode 0)
		)
		(polygon
			(pts
				(arc
					(start 90.345514 -407.00452)
					(mid 89.677494 -407.00452)
					(end 90.345514 -407.00452)
				)
			)
		)
	)
	(zone
		(layers "F.Cu" "In2.Cu" "In4.Cu" "In6.Cu")
		(hatch none 0.5)
		(connect_pads
			(clearance 0)
		)
		(min_thickness 0.25)
		(keepout
			(tracks not_allowed)
			(vias allowed)
			(pads allowed)
			(copperpour not_allowed)
			(footprints allowed)
		)
		(placement
			(enabled no)
			(sheetname "")
		)
		(fill yes
			(thermal_gap 0.5)
			(thermal_bridge_width 0.5)
			(island_removal_mode 0)
		)
		(polygon
			(pts
				(arc
					(start 65.839594 -407.00452)
					(mid 65.171574 -407.00452)
					(end 65.839594 -407.00452)
				)
			)
		)
	)
	(zone
		(layers "F.Cu" "In2.Cu" "In4.Cu" "In6.Cu")
		(hatch none 0.5)
		(connect_pads
			(clearance 0)
		)
		(min_thickness 0.25)
		(keepout
			(tracks not_allowed)
			(vias allowed)
			(pads allowed)
			(copperpour not_allowed)
			(footprints allowed)
		)
		(placement
			(enabled no)
			(sheetname "")
		)
		(fill yes
			(thermal_gap 0.5)
			(thermal_bridge_width 0.5)
			(island_removal_mode 0)
		)
		(polygon
			(pts
				(arc
					(start 87.282274 -407.00452)
					(mid 86.614254 -407.00452)
					(end 87.282274 -407.00452)
				)
			)
		)
	)
	(zone
		(layers "F.Cu" "In2.Cu" "In4.Cu" "In6.Cu")
		(hatch none 0.5)
		(connect_pads
			(clearance 0)
		)
		(min_thickness 0.25)
		(keepout
			(tracks not_allowed)
			(vias allowed)
			(pads allowed)
			(copperpour not_allowed)
			(footprints allowed)
		)
		(placement
			(enabled no)
			(sheetname "")
		)
		(fill yes
			(thermal_gap 0.5)
			(thermal_bridge_width 0.5)
			(island_removal_mode 0)
		)
		(polygon
			(pts
				(arc
					(start 59.713114 -407.00452)
					(mid 59.045094 -407.00452)
					(end 59.713114 -407.00452)
				)
			)
		)
	)
	(zone
		(layers "F.Cu" "In2.Cu" "In4.Cu" "In6.Cu")
		(hatch none 0.5)
		(connect_pads
			(clearance 0)
		)
		(min_thickness 0.25)
		(keepout
			(tracks not_allowed)
			(vias allowed)
			(pads allowed)
			(copperpour not_allowed)
			(footprints allowed)
		)
		(placement
			(enabled no)
			(sheetname "")
		)
		(fill yes
			(thermal_gap 0.5)
			(thermal_bridge_width 0.5)
			(island_removal_mode 0)
		)
		(polygon
			(pts
				(arc
					(start 95.608394 -407.00452)
					(mid 94.940374 -407.00452)
					(end 95.608394 -407.00452)
				)
			)
		)
	)
	(zone
		(layers "F.Cu" "In2.Cu" "In4.Cu" "In6.Cu")
		(hatch none 0.5)
		(connect_pads
			(clearance 0)
		)
		(min_thickness 0.25)
		(keepout
			(tracks not_allowed)
			(vias allowed)
			(pads allowed)
			(copperpour not_allowed)
			(footprints allowed)
		)
		(placement
			(enabled no)
			(sheetname "")
		)
		(fill yes
			(thermal_gap 0.5)
			(thermal_bridge_width 0.5)
			(island_removal_mode 0)
		)
		(polygon
			(pts
				(arc
					(start 23.43912 -244.085364)
					(mid 22.7711 -244.085364)
					(end 23.43912 -244.085364)
				)
			)
		)
	)
	(zone
		(layers "F.Cu" "In2.Cu" "In4.Cu" "In6.Cu")
		(hatch none 0.5)
		(connect_pads
			(clearance 0)
		)
		(min_thickness 0.25)
		(keepout
			(tracks not_allowed)
			(vias allowed)
			(pads allowed)
			(copperpour not_allowed)
			(footprints allowed)
		)
		(placement
			(enabled no)
			(sheetname "")
		)
		(fill yes
			(thermal_gap 0.5)
			(thermal_bridge_width 0.5)
			(island_removal_mode 0)
		)
		(polygon
			(pts
				(arc
					(start 68.902834 -407.00452)
					(mid 68.234814 -407.00452)
					(end 68.902834 -407.00452)
				)
			)
		)
	)
	(zone
		(layers "F.Cu" "In2.Cu" "In4.Cu" "In6.Cu")
		(hatch none 0.5)
		(connect_pads
			(clearance 0)
		)
		(min_thickness 0.25)
		(keepout
			(tracks not_allowed)
			(vias allowed)
			(pads allowed)
			(copperpour not_allowed)
			(footprints allowed)
		)
		(placement
			(enabled no)
			(sheetname "")
		)
		(fill yes
			(thermal_gap 0.5)
			(thermal_bridge_width 0.5)
			(island_removal_mode 0)
		)
		(polygon
			(pts
				(arc
					(start 83.355434 -407.00452)
					(mid 82.687414 -407.00452)
					(end 83.355434 -407.00452)
				)
			)
		)
	)
	(zone
		(layers "F.Cu" "In2.Cu" "In4.Cu" "In6.Cu")
		(hatch none 0.5)
		(connect_pads
			(clearance 0)
		)
		(min_thickness 0.25)
		(keepout
			(tracks not_allowed)
			(vias allowed)
			(pads allowed)
			(copperpour not_allowed)
			(footprints allowed)
		)
		(placement
			(enabled no)
			(sheetname "")
		)
		(fill yes
			(thermal_gap 0.5)
			(thermal_bridge_width 0.5)
			(island_removal_mode 0)
		)
		(polygon
			(pts
				(arc
					(start 214.28329 -2.969006)
					(mid 213.61527 -2.969006)
					(end 214.28329 -2.969006)
				)
			)
		)
	)
	(zone
		(layers "F.Cu" "In2.Cu" "In4.Cu" "In6.Cu")
		(hatch none 0.5)
		(connect_pads
			(clearance 0)
		)
		(min_thickness 0.25)
		(keepout
			(tracks not_allowed)
			(vias allowed)
			(pads allowed)
			(copperpour not_allowed)
			(footprints allowed)
		)
		(placement
			(enabled no)
			(sheetname "")
		)
		(fill yes
			(thermal_gap 0.5)
			(thermal_bridge_width 0.5)
			(island_removal_mode 0)
		)
		(polygon
			(pts
				(arc
					(start 439.641488 9.121648)
					(mid 438.973468 9.121648)
					(end 439.641488 9.121648)
				)
			)
		)
	)
	(zone
		(layers "F.Cu" "In2.Cu" "In4.Cu" "In6.Cu")
		(hatch none 0.5)
		(connect_pads
			(clearance 0)
		)
		(min_thickness 0.25)
		(keepout
			(tracks not_allowed)
			(vias allowed)
			(pads allowed)
			(copperpour not_allowed)
			(footprints allowed)
		)
		(placement
			(enabled no)
			(sheetname "")
		)
		(fill yes
			(thermal_gap 0.5)
			(thermal_bridge_width 0.5)
			(island_removal_mode 0)
		)
		(polygon
			(pts
				(arc
					(start 49.659794 -407.00452)
					(mid 48.991774 -407.00452)
					(end 49.659794 -407.00452)
				)
			)
		)
	)
	(zone
		(layers "F.Cu" "In2.Cu" "In4.Cu" "In6.Cu")
		(hatch none 0.5)
		(connect_pads
			(clearance 0)
		)
		(min_thickness 0.25)
		(keepout
			(tracks not_allowed)
			(vias allowed)
			(pads allowed)
			(copperpour not_allowed)
			(footprints allowed)
		)
		(placement
			(enabled no)
			(sheetname "")
		)
		(fill yes
			(thermal_gap 0.5)
			(thermal_bridge_width 0.5)
			(island_removal_mode 0)
		)
		(polygon
			(pts
				(arc
					(start 80.292194 -407.00452)
					(mid 79.624174 -407.00452)
					(end 80.292194 -407.00452)
				)
			)
		)
	)
	(zone
		(layers "F.Cu" "In2.Cu" "In4.Cu" "In6.Cu")
		(hatch none 0.5)
		(connect_pads
			(clearance 0)
		)
		(min_thickness 0.25)
		(keepout
			(tracks not_allowed)
			(vias allowed)
			(pads allowed)
			(copperpour not_allowed)
			(footprints allowed)
		)
		(placement
			(enabled no)
			(sheetname "")
		)
		(fill yes
			(thermal_gap 0.5)
			(thermal_bridge_width 0.5)
			(island_removal_mode 0)
		)
		(polygon
			(pts
				(arc
					(start 50.523394 -407.00452)
					(mid 49.855374 -407.00452)
					(end 50.523394 -407.00452)
				)
			)
		)
	)
	(zone
		(layers "F.Cu" "In2.Cu" "In4.Cu" "In6.Cu")
		(hatch none 0.5)
		(connect_pads
			(clearance 0)
		)
		(min_thickness 0.25)
		(keepout
			(tracks not_allowed)
			(vias allowed)
			(pads allowed)
			(copperpour not_allowed)
			(footprints allowed)
		)
		(placement
			(enabled no)
			(sheetname "")
		)
		(fill yes
			(thermal_gap 0.5)
			(thermal_bridge_width 0.5)
			(island_removal_mode 0)
		)
		(polygon
			(pts
				(arc
					(start 86.418674 -407.00452)
					(mid 85.750654 -407.00452)
					(end 86.418674 -407.00452)
				)
			)
		)
	)
	(zone
		(layers "F.Cu" "In2.Cu" "In4.Cu" "In6.Cu")
		(hatch none 0.5)
		(connect_pads
			(clearance 0)
		)
		(min_thickness 0.25)
		(keepout
			(tracks not_allowed)
			(vias allowed)
			(pads allowed)
			(copperpour not_allowed)
			(footprints allowed)
		)
		(placement
			(enabled no)
			(sheetname "")
		)
		(fill yes
			(thermal_gap 0.5)
			(thermal_bridge_width 0.5)
			(island_removal_mode 0)
		)
		(polygon
			(pts
				(arc
					(start 214.28329 -2.105406)
					(mid 213.61527 -2.105406)
					(end 214.28329 -2.105406)
				)
			)
		)
	)
	(zone
		(layers "F.Cu" "In2.Cu" "In4.Cu" "In6.Cu")
		(hatch none 0.5)
		(connect_pads
			(clearance 0)
		)
		(min_thickness 0.25)
		(keepout
			(tracks not_allowed)
			(vias allowed)
			(pads allowed)
			(copperpour not_allowed)
			(footprints allowed)
		)
		(placement
			(enabled no)
			(sheetname "")
		)
		(fill yes
			(thermal_gap 0.5)
			(thermal_bridge_width 0.5)
			(island_removal_mode 0)
		)
		(polygon
			(pts
				(arc
					(start 74.165714 -407.00452)
					(mid 73.497694 -407.00452)
					(end 74.165714 -407.00452)
				)
			)
		)
	)
	(zone
		(layers "F.Cu" "In2.Cu" "In4.Cu" "In6.Cu")
		(hatch none 0.5)
		(connect_pads
			(clearance 0)
		)
		(min_thickness 0.25)
		(keepout
			(tracks not_allowed)
			(vias allowed)
			(pads allowed)
			(copperpour not_allowed)
			(footprints allowed)
		)
		(placement
			(enabled no)
			(sheetname "")
		)
		(fill yes
			(thermal_gap 0.5)
			(thermal_bridge_width 0.5)
			(island_removal_mode 0)
		)
		(polygon
			(pts
				(arc
					(start 58.849514 -407.00452)
					(mid 58.181494 -407.00452)
					(end 58.849514 -407.00452)
				)
			)
		)
	)
	(zone
		(layers "F.Cu" "In2.Cu" "In4.Cu" "In6.Cu")
		(hatch none 0.5)
		(connect_pads
			(clearance 0)
		)
		(min_thickness 0.25)
		(keepout
			(tracks not_allowed)
			(vias allowed)
			(pads allowed)
			(copperpour not_allowed)
			(footprints allowed)
		)
		(placement
			(enabled no)
			(sheetname "")
		)
		(fill yes
			(thermal_gap 0.5)
			(thermal_bridge_width 0.5)
			(island_removal_mode 0)
		)
		(polygon
			(pts
				(arc
					(start 61.912754 -407.00452)
					(mid 61.244734 -407.00452)
					(end 61.912754 -407.00452)
				)
			)
		)
	)
	(zone
		(layers "F.Cu" "In2.Cu" "In4.Cu" "In6.Cu")
		(hatch none 0.5)
		(connect_pads
			(clearance 0)
		)
		(min_thickness 0.25)
		(keepout
			(tracks not_allowed)
			(vias allowed)
			(pads allowed)
			(copperpour not_allowed)
			(footprints allowed)
		)
		(placement
			(enabled no)
			(sheetname "")
		)
		(fill yes
			(thermal_gap 0.5)
			(thermal_bridge_width 0.5)
			(island_removal_mode 0)
		)
		(polygon
			(pts
				(arc
					(start 299.394626 -2.969006)
					(mid 298.726606 -2.969006)
					(end 299.394626 -2.969006)
				)
			)
		)
	)
	(zone
		(layers "F.Cu" "In2.Cu" "In4.Cu" "In6.Cu")
		(hatch none 0.5)
		(connect_pads
			(clearance 0)
		)
		(min_thickness 0.25)
		(keepout
			(tracks not_allowed)
			(vias allowed)
			(pads allowed)
			(copperpour not_allowed)
			(footprints allowed)
		)
		(placement
			(enabled no)
			(sheetname "")
		)
		(fill yes
			(thermal_gap 0.5)
			(thermal_bridge_width 0.5)
			(island_removal_mode 0)
		)
		(polygon
			(pts
				(arc
					(start 84.219034 -407.00452)
					(mid 83.551014 -407.00452)
					(end 84.219034 -407.00452)
				)
			)
		)
	)
	(zone
		(layers "F.Cu" "In2.Cu" "In4.Cu" "In6.Cu")
		(hatch none 0.5)
		(connect_pads
			(clearance 0)
		)
		(min_thickness 0.25)
		(keepout
			(tracks not_allowed)
			(vias allowed)
			(pads allowed)
			(copperpour not_allowed)
			(footprints allowed)
		)
		(placement
			(enabled no)
			(sheetname "")
		)
		(fill yes
			(thermal_gap 0.5)
			(thermal_bridge_width 0.5)
			(island_removal_mode 0)
		)
		(polygon
			(pts
				(arc
					(start 53.586634 -407.00452)
					(mid 52.918614 -407.00452)
					(end 53.586634 -407.00452)
				)
			)
		)
	)
	(zone
		(layers "F.Cu" "In2.Cu" "In4.Cu" "In6.Cu")
		(hatch none 0.5)
		(connect_pads
			(clearance 0)
		)
		(min_thickness 0.25)
		(keepout
			(tracks not_allowed)
			(vias allowed)
			(pads allowed)
			(copperpour not_allowed)
			(footprints allowed)
		)
		(placement
			(enabled no)
			(sheetname "")
		)
		(fill yes
			(thermal_gap 0.5)
			(thermal_bridge_width 0.5)
			(island_removal_mode 0)
		)
		(polygon
			(pts
				(arc
					(start 391.274046 8.258048)
					(mid 390.606026 8.258048)
					(end 391.274046 8.258048)
				)
			)
		)
	)
	(zone
		(layers "F.Cu" "In2.Cu" "In4.Cu" "In6.Cu")
		(hatch none 0.5)
		(connect_pads
			(clearance 0)
		)
		(min_thickness 0.25)
		(keepout
			(tracks not_allowed)
			(vias allowed)
			(pads allowed)
			(copperpour not_allowed)
			(footprints allowed)
		)
		(placement
			(enabled no)
			(sheetname "")
		)
		(fill yes
			(thermal_gap 0.5)
			(thermal_bridge_width 0.5)
			(island_removal_mode 0)
		)
		(polygon
			(pts
				(arc
					(start 205.18501 -244.085364)
					(mid 204.51699 -244.085364)
					(end 205.18501 -244.085364)
				)
			)
		)
	)
	(zone
		(layers "F.Cu" "In2.Cu" "In4.Cu" "In6.Cu")
		(hatch none 0.5)
		(connect_pads
			(clearance 0)
		)
		(min_thickness 0.25)
		(keepout
			(tracks not_allowed)
			(vias allowed)
			(pads allowed)
			(copperpour not_allowed)
			(footprints allowed)
		)
		(placement
			(enabled no)
			(sheetname "")
		)
		(fill yes
			(thermal_gap 0.5)
			(thermal_bridge_width 0.5)
			(island_removal_mode 0)
		)
		(polygon
			(pts
				(arc
					(start 96.471994 -407.00452)
					(mid 95.803974 -407.00452)
					(end 96.471994 -407.00452)
				)
			)
		)
	)
	(zone
		(layers "F.Cu" "In2.Cu" "In4.Cu" "In6.Cu")
		(hatch none 0.5)
		(connect_pads
			(clearance 0)
		)
		(min_thickness 0.25)
		(keepout
			(tracks not_allowed)
			(vias allowed)
			(pads allowed)
			(copperpour not_allowed)
			(footprints allowed)
		)
		(placement
			(enabled no)
			(sheetname "")
		)
		(fill yes
			(thermal_gap 0.5)
			(thermal_bridge_width 0.5)
			(island_removal_mode 0)
		)
		(polygon
			(pts
				(arc
					(start 55.786274 -407.00452)
					(mid 55.118254 -407.00452)
					(end 55.786274 -407.00452)
				)
			)
		)
	)
	(zone
		(layers "F.Cu" "In2.Cu" "In4.Cu" "In6.Cu")
		(hatch none 0.5)
		(connect_pads
			(clearance 0)
		)
		(min_thickness 0.25)
		(keepout
			(tracks not_allowed)
			(vias allowed)
			(pads allowed)
			(copperpour not_allowed)
			(footprints allowed)
		)
		(placement
			(enabled no)
			(sheetname "")
		)
		(fill yes
			(thermal_gap 0.5)
			(thermal_bridge_width 0.5)
			(island_removal_mode 0)
		)
		(polygon
			(pts
				(arc
					(start 75.029314 -407.00452)
					(mid 74.361294 -407.00452)
					(end 75.029314 -407.00452)
				)
			)
		)
	)
	(zone
		(layers "F.Cu" "In2.Cu" "In4.Cu" "In6.Cu")
		(hatch none 0.5)
		(connect_pads
			(clearance 0)
		)
		(min_thickness 0.25)
		(keepout
			(tracks not_allowed)
			(vias allowed)
			(pads allowed)
			(copperpour not_allowed)
			(footprints allowed)
		)
		(placement
			(enabled no)
			(sheetname "")
		)
		(fill yes
			(thermal_gap 0.5)
			(thermal_bridge_width 0.5)
			(island_removal_mode 0)
		)
		(polygon
			(pts
				(arc
					(start 78.092554 -407.00452)
					(mid 77.424534 -407.00452)
					(end 78.092554 -407.00452)
				)
			)
		)
	)
	(zone
		(layers "F.Cu" "In2.Cu" "In4.Cu" "In6.Cu")
		(hatch none 0.5)
		(connect_pads
			(clearance 0)
		)
		(min_thickness 0.25)
		(keepout
			(tracks not_allowed)
			(vias allowed)
			(pads allowed)
			(copperpour not_allowed)
			(footprints allowed)
		)
		(placement
			(enabled no)
			(sheetname "")
		)
		(fill yes
			(thermal_gap 0.5)
			(thermal_bridge_width 0.5)
			(island_removal_mode 0)
		)
		(polygon
			(pts
				(arc
					(start 299.394626 -2.105406)
					(mid 298.726606 -2.105406)
					(end 299.394626 -2.105406)
				)
			)
		)
	)
	(zone
		(layers "F.Cu" "In2.Cu" "In4.Cu" "In6.Cu")
		(hatch none 0.5)
		(connect_pads
			(clearance 0)
		)
		(min_thickness 0.25)
		(keepout
			(tracks not_allowed)
			(vias allowed)
			(pads allowed)
			(copperpour not_allowed)
			(footprints allowed)
		)
		(placement
			(enabled no)
			(sheetname "")
		)
		(fill yes
			(thermal_gap 0.5)
			(thermal_bridge_width 0.5)
			(island_removal_mode 0)
		)
		(polygon
			(pts
				(arc
					(start 71.102474 -407.00452)
					(mid 70.434454 -407.00452)
					(end 71.102474 -407.00452)
				)
			)
		)
	)
	(zone
		(layers "F.Cu" "In2.Cu" "In4.Cu" "In6.Cu")
		(hatch none 0.5)
		(connect_pads
			(clearance 0)
		)
		(min_thickness 0.25)
		(keepout
			(tracks not_allowed)
			(vias allowed)
			(pads allowed)
			(copperpour not_allowed)
			(footprints allowed)
		)
		(placement
			(enabled no)
			(sheetname "")
		)
		(fill yes
			(thermal_gap 0.5)
			(thermal_bridge_width 0.5)
			(island_removal_mode 0)
		)
		(polygon
			(pts
				(arc
					(start 92.545154 -407.00452)
					(mid 91.877134 -407.00452)
					(end 92.545154 -407.00452)
				)
			)
		)
	)
	(zone
		(layers "F.Cu" "In2.Cu" "In4.Cu" "In6.Cu")
		(hatch none 0.5)
		(connect_pads
			(clearance 0)
		)
		(min_thickness 0.25)
		(keepout
			(tracks not_allowed)
			(vias allowed)
			(pads allowed)
			(copperpour not_allowed)
			(footprints allowed)
		)
		(placement
			(enabled no)
			(sheetname "")
		)
		(fill yes
			(thermal_gap 0.5)
			(thermal_bridge_width 0.5)
			(island_removal_mode 0)
		)
		(polygon
			(pts
				(arc
					(start 62.776354 -407.00452)
					(mid 62.108334 -407.00452)
					(end 62.776354 -407.00452)
				)
			)
		)
	)
	(zone
		(layers "F.Cu" "In2.Cu" "In4.Cu" "In6.Cu")
		(hatch none 0.5)
		(connect_pads
			(clearance 0)
		)
		(min_thickness 0.25)
		(keepout
			(tracks not_allowed)
			(vias allowed)
			(pads allowed)
			(copperpour not_allowed)
			(footprints allowed)
		)
		(placement
			(enabled no)
			(sheetname "")
		)
		(fill yes
			(thermal_gap 0.5)
			(thermal_bridge_width 0.5)
			(island_removal_mode 0)
		)
		(polygon
			(pts
				(arc
					(start 271.379188 -244.08511)
					(mid 270.711168 -244.08511)
					(end 271.379188 -244.08511)
				)
			)
		)
	)
	(zone
		(layers "F.Cu" "In2.Cu" "In4.Cu" "In6.Cu")
		(hatch none 0.5)
		(connect_pads
			(clearance 0)
		)
		(min_thickness 0.25)
		(keepout
			(tracks not_allowed)
			(vias allowed)
			(pads allowed)
			(copperpour not_allowed)
			(footprints allowed)
		)
		(placement
			(enabled no)
			(sheetname "")
		)
		(fill yes
			(thermal_gap 0.5)
			(thermal_bridge_width 0.5)
			(island_removal_mode 0)
		)
		(polygon
			(pts
				(arc
					(start 52.723034 -407.00452)
					(mid 52.055014 -407.00452)
					(end 52.723034 -407.00452)
				)
			)
		)
	)
	(zone
		(layers "F.Cu" "In2.Cu" "In4.Cu" "In6.Cu")
		(hatch none 0.5)
		(connect_pads
			(clearance 0)
		)
		(min_thickness 0.25)
		(keepout
			(tracks not_allowed)
			(vias allowed)
			(pads allowed)
			(copperpour not_allowed)
			(footprints allowed)
		)
		(placement
			(enabled no)
			(sheetname "")
		)
		(fill yes
			(thermal_gap 0.5)
			(thermal_bridge_width 0.5)
			(island_removal_mode 0)
		)
		(polygon
			(pts
				(arc
					(start 81.155794 -407.00452)
					(mid 80.487774 -407.00452)
					(end 81.155794 -407.00452)
				)
			)
		)
	)
	(zone
		(layers "F.Cu" "In2.Cu" "In4.Cu" "In6.Cu")
		(hatch none 0.5)
		(connect_pads
			(clearance 0)
		)
		(min_thickness 0.25)
		(keepout
			(tracks not_allowed)
			(vias allowed)
			(pads allowed)
			(copperpour not_allowed)
			(footprints allowed)
		)
		(placement
			(enabled no)
			(sheetname "")
		)
		(fill yes
			(thermal_gap 0.5)
			(thermal_bridge_width 0.5)
			(island_removal_mode 0)
		)
		(polygon
			(pts
				(arc
					(start 453.125078 -244.08511)
					(mid 452.457058 -244.08511)
					(end 453.125078 -244.08511)
				)
			)
		)
	)
	(zone
		(layers "F.Cu" "In2.Cu" "In4.Cu" "In6.Cu")
		(hatch none 0.5)
		(connect_pads
			(clearance 0)
		)
		(min_thickness 0.25)
		(keepout
			(tracks not_allowed)
			(vias allowed)
			(pads allowed)
			(copperpour not_allowed)
			(footprints allowed)
		)
		(placement
			(enabled no)
			(sheetname "")
		)
		(fill yes
			(thermal_gap 0.5)
			(thermal_bridge_width 0.5)
			(island_removal_mode 0)
		)
		(polygon
			(pts
				(arc
					(start 68.039234 -407.00452)
					(mid 67.371214 -407.00452)
					(end 68.039234 -407.00452)
				)
			)
		)
	)
	(zone
		(layers "F.Cu" "In2.Cu" "In4.Cu" "In6.Cu")
		(hatch none 0.5)
		(connect_pads
			(clearance 0)
		)
		(min_thickness 0.25)
		(keepout
			(tracks not_allowed)
			(vias allowed)
			(pads allowed)
			(copperpour not_allowed)
			(footprints allowed)
		)
		(placement
			(enabled no)
			(sheetname "")
		)
		(fill yes
			(thermal_gap 0.5)
			(thermal_bridge_width 0.5)
			(island_removal_mode 0)
		)
		(polygon
			(pts
				(arc
					(start 71.966074 -407.00452)
					(mid 71.298054 -407.00452)
					(end 71.966074 -407.00452)
				)
			)
		)
	)
	(zone
		(layers "F.Cu" "In2.Cu" "In4.Cu" "In6.Cu")
		(hatch none 0.5)
		(connect_pads
			(clearance 0)
		)
		(min_thickness 0.25)
		(keepout
			(tracks not_allowed)
			(vias allowed)
			(pads allowed)
			(copperpour not_allowed)
			(footprints allowed)
		)
		(placement
			(enabled no)
			(sheetname "")
		)
		(fill yes
			(thermal_gap 0.5)
			(thermal_bridge_width 0.5)
			(island_removal_mode 0)
		)
		(polygon
			(pts
				(arc
					(start 77.228954 -407.00452)
					(mid 76.560934 -407.00452)
					(end 77.228954 -407.00452)
				)
			)
		)
	)
	(zone
		(layers "F.Cu" "In2.Cu" "In4.Cu" "In6.Cu")
		(hatch none 0.5)
		(connect_pads
			(clearance 0)
		)
		(min_thickness 0.25)
		(keepout
			(tracks not_allowed)
			(vias allowed)
			(pads allowed)
			(copperpour not_allowed)
			(footprints allowed)
		)
		(placement
			(enabled no)
			(sheetname "")
		)
		(fill yes
			(thermal_gap 0.5)
			(thermal_bridge_width 0.5)
			(island_removal_mode 0)
		)
		(polygon
			(pts
				(arc
					(start 89.481914 -407.00452)
					(mid 88.813894 -407.00452)
					(end 89.481914 -407.00452)
				)
			)
		)
	)
	(zone
		(layers "F.Cu" "In2.Cu" "In4.Cu" "In6.Cu")
		(hatch none 0.5)
		(connect_pads
			(clearance 0)
		)
		(min_thickness 0.25)
		(keepout
			(tracks not_allowed)
			(vias allowed)
			(pads allowed)
			(copperpour not_allowed)
			(footprints allowed)
		)
		(placement
			(enabled no)
			(sheetname "")
		)
		(fill yes
			(thermal_gap 0.5)
			(thermal_bridge_width 0.5)
			(island_removal_mode 0)
		)
		(polygon
			(pts
				(arc
					(start 93.408754 -407.00452)
					(mid 92.740734 -407.00452)
					(end 93.408754 -407.00452)
				)
			)
		)
	)
	(zone
		(layers "F.Cu" "In2.Cu" "In4.Cu" "In6.Cu")
		(hatch none 0.5)
		(connect_pads
			(clearance 0)
		)
		(min_thickness 0.25)
		(keepout
			(tracks not_allowed)
			(vias allowed)
			(pads allowed)
			(copperpour not_allowed)
			(footprints allowed)
		)
		(placement
			(enabled no)
			(sheetname "")
		)
		(fill yes
			(thermal_gap 0.5)
			(thermal_bridge_width 0.5)
			(island_removal_mode 0)
		)
		(polygon
			(pts
				(arc
					(start 391.274046 9.121648)
					(mid 390.606026 9.121648)
					(end 391.274046 9.121648)
				)
			)
		)
	)
	(zone
		(layers "F.Cu" "In2.Cu" "In4.Cu" "In6.Cu")
		(hatch none 0.5)
		(connect_pads
			(clearance 0)
		)
		(min_thickness 0.25)
		(keepout
			(tracks not_allowed)
			(vias allowed)
			(pads allowed)
			(copperpour not_allowed)
			(footprints allowed)
		)
		(placement
			(enabled no)
			(sheetname "")
		)
		(fill yes
			(thermal_gap 0.5)
			(thermal_bridge_width 0.5)
			(island_removal_mode 0)
		)
		(polygon
			(pts
				(arc
					(start 64.975994 -407.00452)
					(mid 64.307974 -407.00452)
					(end 64.975994 -407.00452)
				)
			)
		)
	)
	(zone
		(layers "F.Cu" "In2.Cu" "In4.Cu" "In6.Cu")
		(hatch none 0.5)
		(connect_pads
			(clearance 0)
		)
		(min_thickness 0.25)
		(keepout
			(tracks not_allowed)
			(vias allowed)
			(pads allowed)
			(copperpour not_allowed)
			(footprints allowed)
		)
		(placement
			(enabled no)
			(sheetname "")
		)
		(fill yes
			(thermal_gap 0.5)
			(thermal_bridge_width 0.5)
			(island_removal_mode 0)
		)
		(polygon
			(pts
				(arc
					(start 56.649874 -407.00452)
					(mid 55.981854 -407.00452)
					(end 56.649874 -407.00452)
				)
			)
		)
	)
	(zone
		(layers "F.Cu" "In2.Cu" "In4.Cu" "In6.Cu" "In10.Cu" "In11.Cu" "In13.Cu"
			"In15.Cu"
		)
		(hatch none 0.5)
		(connect_pads
			(clearance 0)
		)
		(min_thickness 0.25)
		(keepout
			(tracks not_allowed)
			(vias allowed)
			(pads allowed)
			(copperpour not_allowed)
			(footprints allowed)
		)
		(placement
			(enabled no)
			(sheetname "")
		)
		(fill yes
			(thermal_gap 0.5)
			(thermal_bridge_width 0.5)
			(island_removal_mode 0)
		)
		(polygon
			(pts
				(arc
					(start 152.241758 -436.160672)
					(mid 152.264076 -436.214554)
					(end 152.317958 -436.236872)
				)
				(arc
					(start 153.257758 -436.236872)
					(mid 153.31164 -436.214554)
					(end 153.333958 -436.160672)
				)
				(arc
					(start 153.333958 -433.619148)
					(mid 153.31164 -433.565266)
					(end 153.257758 -433.542948)
				)
				(arc
					(start 152.317958 -433.542948)
					(mid 152.264076 -433.565266)
					(end 152.241758 -433.619148)
				)
			)
		)
	)
	(zone
		(layers "F.Cu" "In2.Cu" "In4.Cu" "In6.Cu" "In10.Cu" "In11.Cu" "In13.Cu"
			"In15.Cu"
		)
		(hatch none 0.5)
		(connect_pads
			(clearance 0)
		)
		(min_thickness 0.25)
		(keepout
			(tracks not_allowed)
			(vias allowed)
			(pads allowed)
			(copperpour not_allowed)
			(footprints allowed)
		)
		(placement
			(enabled no)
			(sheetname "")
		)
		(fill yes
			(thermal_gap 0.5)
			(thermal_bridge_width 0.5)
			(island_removal_mode 0)
		)
		(polygon
			(pts
				(arc
					(start 144.241774 -436.160672)
					(mid 144.264092 -436.214554)
					(end 144.317974 -436.236872)
				)
				(arc
					(start 145.257774 -436.236872)
					(mid 145.311656 -436.214554)
					(end 145.333974 -436.160672)
				)
				(arc
					(start 145.333974 -433.619148)
					(mid 145.311656 -433.565266)
					(end 145.257774 -433.542948)
				)
				(arc
					(start 144.317974 -433.542948)
					(mid 144.264092 -433.565266)
					(end 144.241774 -433.619148)
				)
			)
		)
	)
	(zone
		(layers "F.Cu" "In2.Cu" "In4.Cu" "In6.Cu" "In10.Cu" "In11.Cu" "In13.Cu"
			"In15.Cu"
		)
		(hatch none 0.5)
		(connect_pads
			(clearance 0)
		)
		(min_thickness 0.25)
		(keepout
			(tracks not_allowed)
			(vias allowed)
			(pads allowed)
			(copperpour not_allowed)
			(footprints allowed)
		)
		(placement
			(enabled no)
			(sheetname "")
		)
		(fill yes
			(thermal_gap 0.5)
			(thermal_bridge_width 0.5)
			(island_removal_mode 0)
		)
		(polygon
			(pts
				(arc
					(start 400.24177 -436.160672)
					(mid 400.264088 -436.214554)
					(end 400.31797 -436.236872)
				)
				(arc
					(start 401.25777 -436.236872)
					(mid 401.311652 -436.214554)
					(end 401.33397 -436.160672)
				)
				(arc
					(start 401.33397 -433.619148)
					(mid 401.311652 -433.565266)
					(end 401.25777 -433.542948)
				)
				(arc
					(start 400.31797 -433.542948)
					(mid 400.264088 -433.565266)
					(end 400.24177 -433.619148)
				)
			)
		)
	)
	(zone
		(layers "F.Cu" "In2.Cu" "In4.Cu" "In6.Cu" "In10.Cu" "In11.Cu" "In13.Cu"
			"In15.Cu"
		)
		(hatch none 0.5)
		(connect_pads
			(clearance 0)
		)
		(min_thickness 0.25)
		(keepout
			(tracks not_allowed)
			(vias allowed)
			(pads allowed)
			(copperpour not_allowed)
			(footprints allowed)
		)
		(placement
			(enabled no)
			(sheetname "")
		)
		(fill yes
			(thermal_gap 0.5)
			(thermal_bridge_width 0.5)
			(island_removal_mode 0)
		)
		(polygon
			(pts
				(arc
					(start 404.241762 -436.160672)
					(mid 404.26408 -436.214554)
					(end 404.317962 -436.236872)
				)
				(arc
					(start 405.257762 -436.236872)
					(mid 405.311644 -436.214554)
					(end 405.333962 -436.160672)
				)
				(arc
					(start 405.333962 -433.619148)
					(mid 405.311644 -433.565266)
					(end 405.257762 -433.542948)
				)
				(arc
					(start 404.317962 -433.542948)
					(mid 404.26408 -433.565266)
					(end 404.241762 -433.619148)
				)
			)
		)
	)
	(zone
		(layers "F.Cu" "In2.Cu" "In4.Cu" "In6.Cu" "In10.Cu" "In11.Cu" "In13.Cu"
			"In15.Cu"
		)
		(hatch none 0.5)
		(connect_pads
			(clearance 0)
		)
		(min_thickness 0.25)
		(keepout
			(tracks not_allowed)
			(vias allowed)
			(pads allowed)
			(copperpour not_allowed)
			(footprints allowed)
		)
		(placement
			(enabled no)
			(sheetname "")
		)
		(fill yes
			(thermal_gap 0.5)
			(thermal_bridge_width 0.5)
			(island_removal_mode 0)
		)
		(polygon
			(pts
				(arc
					(start 146.24177 -435.160674)
					(mid 146.264088 -435.214556)
					(end 146.31797 -435.236874)
				)
				(arc
					(start 147.25777 -435.236874)
					(mid 147.311652 -435.214556)
					(end 147.33397 -435.160674)
				)
				(arc
					(start 147.33397 -432.61915)
					(mid 147.311652 -432.565268)
					(end 147.25777 -432.54295)
				)
				(arc
					(start 146.31797 -432.54295)
					(mid 146.264088 -432.565268)
					(end 146.24177 -432.61915)
				)
			)
		)
	)
	(zone
		(layers "F.Cu" "In2.Cu" "In4.Cu" "In6.Cu" "In10.Cu" "In11.Cu" "In13.Cu"
			"In15.Cu"
		)
		(hatch none 0.5)
		(connect_pads
			(clearance 0)
		)
		(min_thickness 0.25)
		(keepout
			(tracks not_allowed)
			(vias allowed)
			(pads allowed)
			(copperpour not_allowed)
			(footprints allowed)
		)
		(placement
			(enabled no)
			(sheetname "")
		)
		(fill yes
			(thermal_gap 0.5)
			(thermal_bridge_width 0.5)
			(island_removal_mode 0)
		)
		(polygon
			(pts
				(arc
					(start 402.241766 -435.160674)
					(mid 402.264084 -435.214556)
					(end 402.317966 -435.236874)
				)
				(arc
					(start 403.257766 -435.236874)
					(mid 403.311648 -435.214556)
					(end 403.333966 -435.160674)
				)
				(arc
					(start 403.333966 -432.61915)
					(mid 403.311648 -432.565268)
					(end 403.257766 -432.54295)
				)
				(arc
					(start 402.317966 -432.54295)
					(mid 402.264084 -432.565268)
					(end 402.241766 -432.61915)
				)
			)
		)
	)
	(zone
		(layers "F.Cu" "In2.Cu" "In4.Cu" "In6.Cu" "In10.Cu" "In11.Cu" "In13.Cu"
			"In15.Cu"
		)
		(hatch none 0.5)
		(connect_pads
			(clearance 0)
		)
		(min_thickness 0.25)
		(keepout
			(tracks not_allowed)
			(vias allowed)
			(pads allowed)
			(copperpour not_allowed)
			(footprints allowed)
		)
		(placement
			(enabled no)
			(sheetname "")
		)
		(fill yes
			(thermal_gap 0.5)
			(thermal_bridge_width 0.5)
			(island_removal_mode 0)
		)
		(polygon
			(pts
				(arc
					(start 412.241746 -436.160672)
					(mid 412.264064 -436.214554)
					(end 412.317946 -436.236872)
				)
				(arc
					(start 413.257746 -436.236872)
					(mid 413.311628 -436.214554)
					(end 413.333946 -436.160672)
				)
				(arc
					(start 413.333946 -433.619148)
					(mid 413.311628 -433.565266)
					(end 413.257746 -433.542948)
				)
				(arc
					(start 412.317946 -433.542948)
					(mid 412.264064 -433.565266)
					(end 412.241746 -433.619148)
				)
			)
		)
	)
	(zone
		(layers "F.Cu" "In2.Cu" "In4.Cu" "In6.Cu" "In10.Cu" "In11.Cu" "In13.Cu"
			"In15.Cu"
		)
		(hatch none 0.5)
		(connect_pads
			(clearance 0)
		)
		(min_thickness 0.25)
		(keepout
			(tracks not_allowed)
			(vias allowed)
			(pads allowed)
			(copperpour not_allowed)
			(footprints allowed)
		)
		(placement
			(enabled no)
			(sheetname "")
		)
		(fill yes
			(thermal_gap 0.5)
			(thermal_bridge_width 0.5)
			(island_removal_mode 0)
		)
		(polygon
			(pts
				(arc
					(start 408.241754 -436.160672)
					(mid 408.264072 -436.214554)
					(end 408.317954 -436.236872)
				)
				(arc
					(start 409.257754 -436.236872)
					(mid 409.311636 -436.214554)
					(end 409.333954 -436.160672)
				)
				(arc
					(start 409.333954 -433.619148)
					(mid 409.311636 -433.565266)
					(end 409.257754 -433.542948)
				)
				(arc
					(start 408.317954 -433.542948)
					(mid 408.264072 -433.565266)
					(end 408.241754 -433.619148)
				)
			)
		)
	)
	(zone
		(layers "F.Cu" "In2.Cu" "In4.Cu" "In6.Cu" "In10.Cu" "In11.Cu" "In13.Cu"
			"In15.Cu"
		)
		(hatch none 0.5)
		(connect_pads
			(clearance 0)
		)
		(min_thickness 0.25)
		(keepout
			(tracks not_allowed)
			(vias allowed)
			(pads allowed)
			(copperpour not_allowed)
			(footprints allowed)
		)
		(placement
			(enabled no)
			(sheetname "")
		)
		(fill yes
			(thermal_gap 0.5)
			(thermal_bridge_width 0.5)
			(island_removal_mode 0)
		)
		(polygon
			(pts
				(arc
					(start 410.24175 -435.160674)
					(mid 410.264068 -435.214556)
					(end 410.31795 -435.236874)
				)
				(arc
					(start 411.25775 -435.236874)
					(mid 411.311632 -435.214556)
					(end 411.33395 -435.160674)
				)
				(arc
					(start 411.33395 -432.61915)
					(mid 411.311632 -432.565268)
					(end 411.25775 -432.54295)
				)
				(arc
					(start 410.31795 -432.54295)
					(mid 410.264068 -432.565268)
					(end 410.24175 -432.61915)
				)
			)
		)
	)
	(zone
		(layers "F.Cu" "In2.Cu" "In4.Cu" "In6.Cu" "In10.Cu" "In11.Cu" "In13.Cu"
			"In15.Cu"
		)
		(hatch none 0.5)
		(connect_pads
			(clearance 0)
		)
		(min_thickness 0.25)
		(keepout
			(tracks not_allowed)
			(vias allowed)
			(pads allowed)
			(copperpour not_allowed)
			(footprints allowed)
		)
		(placement
			(enabled no)
			(sheetname "")
		)
		(fill yes
			(thermal_gap 0.5)
			(thermal_bridge_width 0.5)
			(island_removal_mode 0)
		)
		(polygon
			(pts
				(arc
					(start 150.241762 -435.160674)
					(mid 150.26408 -435.214556)
					(end 150.317962 -435.236874)
				)
				(arc
					(start 151.257762 -435.236874)
					(mid 151.311644 -435.214556)
					(end 151.333962 -435.160674)
				)
				(arc
					(start 151.333962 -432.61915)
					(mid 151.311644 -432.565268)
					(end 151.257762 -432.54295)
				)
				(arc
					(start 150.317962 -432.54295)
					(mid 150.26408 -432.565268)
					(end 150.241762 -432.61915)
				)
			)
		)
	)
	(zone
		(layers "F.Cu" "In2.Cu" "In4.Cu" "In6.Cu" "In10.Cu" "In11.Cu" "In13.Cu"
			"In15.Cu"
		)
		(hatch none 0.5)
		(connect_pads
			(clearance 0)
		)
		(min_thickness 0.25)
		(keepout
			(tracks not_allowed)
			(vias allowed)
			(pads allowed)
			(copperpour not_allowed)
			(footprints allowed)
		)
		(placement
			(enabled no)
			(sheetname "")
		)
		(fill yes
			(thermal_gap 0.5)
			(thermal_bridge_width 0.5)
			(island_removal_mode 0)
		)
		(polygon
			(pts
				(arc
					(start 142.241778 -435.160674)
					(mid 142.264096 -435.214556)
					(end 142.317978 -435.236874)
				)
				(arc
					(start 143.257778 -435.236874)
					(mid 143.31166 -435.214556)
					(end 143.333978 -435.160674)
				)
				(arc
					(start 143.333978 -432.61915)
					(mid 143.31166 -432.565268)
					(end 143.257778 -432.54295)
				)
				(arc
					(start 142.317978 -432.54295)
					(mid 142.264096 -432.565268)
					(end 142.241778 -432.61915)
				)
			)
		)
	)
	(zone
		(layers "F.Cu" "In2.Cu" "In4.Cu" "In6.Cu" "In10.Cu" "In11.Cu" "In13.Cu"
			"In15.Cu"
		)
		(hatch none 0.5)
		(connect_pads
			(clearance 0)
		)
		(min_thickness 0.25)
		(keepout
			(tracks not_allowed)
			(vias allowed)
			(pads allowed)
			(copperpour not_allowed)
			(footprints allowed)
		)
		(placement
			(enabled no)
			(sheetname "")
		)
		(fill yes
			(thermal_gap 0.5)
			(thermal_bridge_width 0.5)
			(island_removal_mode 0)
		)
		(polygon
			(pts
				(arc
					(start 398.241774 -435.160674)
					(mid 398.264092 -435.214556)
					(end 398.317974 -435.236874)
				)
				(arc
					(start 399.257774 -435.236874)
					(mid 399.311656 -435.214556)
					(end 399.333974 -435.160674)
				)
				(arc
					(start 399.333974 -432.61915)
					(mid 399.311656 -432.565268)
					(end 399.257774 -432.54295)
				)
				(arc
					(start 398.317974 -432.54295)
					(mid 398.264092 -432.565268)
					(end 398.241774 -432.61915)
				)
			)
		)
	)
	(zone
		(layers "F.Cu" "In2.Cu" "In4.Cu" "In6.Cu" "In10.Cu" "In11.Cu" "In13.Cu"
			"In15.Cu"
		)
		(hatch none 0.5)
		(connect_pads
			(clearance 0)
		)
		(min_thickness 0.25)
		(keepout
			(tracks not_allowed)
			(vias allowed)
			(pads allowed)
			(copperpour not_allowed)
			(footprints allowed)
		)
		(placement
			(enabled no)
			(sheetname "")
		)
		(fill yes
			(thermal_gap 0.5)
			(thermal_bridge_width 0.5)
			(island_removal_mode 0)
		)
		(polygon
			(pts
				(arc
					(start 148.241766 -436.160672)
					(mid 148.264084 -436.214554)
					(end 148.317966 -436.236872)
				)
				(arc
					(start 149.257766 -436.236872)
					(mid 149.311648 -436.214554)
					(end 149.333966 -436.160672)
				)
				(arc
					(start 149.333966 -433.619148)
					(mid 149.311648 -433.565266)
					(end 149.257766 -433.542948)
				)
				(arc
					(start 148.317966 -433.542948)
					(mid 148.264084 -433.565266)
					(end 148.241766 -433.619148)
				)
			)
		)
	)
	(zone
		(layers "F.Cu" "In2.Cu" "In4.Cu" "In6.Cu" "In10.Cu" "In11.Cu" "In13.Cu"
			"In15.Cu"
		)
		(hatch none 0.5)
		(connect_pads
			(clearance 0)
		)
		(min_thickness 0.25)
		(keepout
			(tracks not_allowed)
			(vias allowed)
			(pads allowed)
			(copperpour not_allowed)
			(footprints allowed)
		)
		(placement
			(enabled no)
			(sheetname "")
		)
		(fill yes
			(thermal_gap 0.5)
			(thermal_bridge_width 0.5)
			(island_removal_mode 0)
		)
		(polygon
			(pts
				(arc
					(start 406.241758 -435.160674)
					(mid 406.264076 -435.214556)
					(end 406.317958 -435.236874)
				)
				(arc
					(start 407.257758 -435.236874)
					(mid 407.31164 -435.214556)
					(end 407.333958 -435.160674)
				)
				(arc
					(start 407.333958 -432.61915)
					(mid 407.31164 -432.565268)
					(end 407.257758 -432.54295)
				)
				(arc
					(start 406.317958 -432.54295)
					(mid 406.264076 -432.565268)
					(end 406.241758 -432.61915)
				)
			)
		)
	)
	(zone
		(layers "F.Cu" "In2.Cu" "In4.Cu" "In6.Cu" "In11.Cu")
		(hatch none 0.5)
		(connect_pads
			(clearance 0)
		)
		(min_thickness 0.25)
		(keepout
			(tracks not_allowed)
			(vias allowed)
			(pads allowed)
			(copperpour not_allowed)
			(footprints allowed)
		)
		(placement
			(enabled no)
			(sheetname "")
		)
		(fill yes
			(thermal_gap 0.5)
			(thermal_bridge_width 0.5)
			(island_removal_mode 0)
		)
		(polygon
			(pts
				(arc
					(start 175.009048 -244.085364)
					(mid 174.341028 -244.085364)
					(end 175.009048 -244.085364)
				)
			)
		)
	)
	(zone
		(layers "F.Cu" "In2.Cu" "In4.Cu" "In6.Cu" "In11.Cu")
		(hatch none 0.5)
		(connect_pads
			(clearance 0)
		)
		(min_thickness 0.25)
		(keepout
			(tracks not_allowed)
			(vias allowed)
			(pads allowed)
			(copperpour not_allowed)
			(footprints allowed)
		)
		(placement
			(enabled no)
			(sheetname "")
		)
		(fill yes
			(thermal_gap 0.5)
			(thermal_bridge_width 0.5)
			(island_removal_mode 0)
		)
		(polygon
			(pts
				(arc
					(start 365.144812 7.190994)
					(mid 364.476792 7.190994)
					(end 365.144812 7.190994)
				)
			)
		)
	)
	(zone
		(layers "F.Cu" "In2.Cu" "In4.Cu" "In6.Cu" "In11.Cu")
		(hatch none 0.5)
		(connect_pads
			(clearance 0)
		)
		(min_thickness 0.25)
		(keepout
			(tracks not_allowed)
			(vias allowed)
			(pads allowed)
			(copperpour not_allowed)
			(footprints allowed)
		)
		(placement
			(enabled no)
			(sheetname "")
		)
		(fill yes
			(thermal_gap 0.5)
			(thermal_bridge_width 0.5)
			(island_removal_mode 0)
		)
		(polygon
			(pts
				(arc
					(start 316.77737 8.054594)
					(mid 316.10935 8.054594)
					(end 316.77737 8.054594)
				)
			)
		)
	)
	(zone
		(layers "F.Cu" "In2.Cu" "In4.Cu" "In6.Cu" "In11.Cu")
		(hatch none 0.5)
		(connect_pads
			(clearance 0)
		)
		(min_thickness 0.25)
		(keepout
			(tracks not_allowed)
			(vias allowed)
			(pads allowed)
			(copperpour not_allowed)
			(footprints allowed)
		)
		(placement
			(enabled no)
			(sheetname "")
		)
		(fill yes
			(thermal_gap 0.5)
			(thermal_bridge_width 0.5)
			(island_removal_mode 0)
		)
		(polygon
			(pts
				(arc
					(start 53.615082 -244.085364)
					(mid 52.947062 -244.085364)
					(end 53.615082 -244.085364)
				)
			)
		)
	)
	(zone
		(layers "F.Cu" "In2.Cu" "In4.Cu" "In6.Cu" "In11.Cu")
		(hatch none 0.5)
		(connect_pads
			(clearance 0)
		)
		(min_thickness 0.25)
		(keepout
			(tracks not_allowed)
			(vias allowed)
			(pads allowed)
			(copperpour not_allowed)
			(footprints allowed)
		)
		(placement
			(enabled no)
			(sheetname "")
		)
		(fill yes
			(thermal_gap 0.5)
			(thermal_bridge_width 0.5)
			(island_removal_mode 0)
		)
		(polygon
			(pts
				(arc
					(start 316.77737 7.190994)
					(mid 316.10935 7.190994)
					(end 316.77737 7.190994)
				)
			)
		)
	)
	(zone
		(layers "F.Cu" "In2.Cu" "In4.Cu" "In6.Cu" "In11.Cu")
		(hatch none 0.5)
		(connect_pads
			(clearance 0)
		)
		(min_thickness 0.25)
		(keepout
			(tracks not_allowed)
			(vias allowed)
			(pads allowed)
			(copperpour not_allowed)
			(footprints allowed)
		)
		(placement
			(enabled no)
			(sheetname "")
		)
		(fill yes
			(thermal_gap 0.5)
			(thermal_bridge_width 0.5)
			(island_removal_mode 0)
		)
		(polygon
			(pts
				(arc
					(start 99.607624 3.091434)
					(mid 98.939604 3.091434)
					(end 99.607624 3.091434)
				)
			)
		)
	)
	(zone
		(layers "F.Cu" "In2.Cu" "In4.Cu" "In6.Cu" "In11.Cu")
		(hatch none 0.5)
		(connect_pads
			(clearance 0)
		)
		(min_thickness 0.25)
		(keepout
			(tracks not_allowed)
			(vias allowed)
			(pads allowed)
			(copperpour not_allowed)
			(footprints allowed)
		)
		(placement
			(enabled no)
			(sheetname "")
		)
		(fill yes
			(thermal_gap 0.5)
			(thermal_bridge_width 0.5)
			(island_removal_mode 0)
		)
		(polygon
			(pts
				(arc
					(start 422.949116 -244.08511)
					(mid 422.281096 -244.08511)
					(end 422.949116 -244.08511)
				)
			)
		)
	)
	(zone
		(layers "F.Cu" "In2.Cu" "In4.Cu" "In6.Cu" "In11.Cu")
		(hatch none 0.5)
		(connect_pads
			(clearance 0)
		)
		(min_thickness 0.25)
		(keepout
			(tracks not_allowed)
			(vias allowed)
			(pads allowed)
			(copperpour not_allowed)
			(footprints allowed)
		)
		(placement
			(enabled no)
			(sheetname "")
		)
		(fill yes
			(thermal_gap 0.5)
			(thermal_bridge_width 0.5)
			(island_removal_mode 0)
		)
		(polygon
			(pts
				(arc
					(start 184.71896 3.091434)
					(mid 184.05094 3.091434)
					(end 184.71896 3.091434)
				)
			)
		)
	)
	(zone
		(layers "F.Cu" "In2.Cu" "In4.Cu" "In6.Cu" "In11.Cu")
		(hatch none 0.5)
		(connect_pads
			(clearance 0)
		)
		(min_thickness 0.25)
		(keepout
			(tracks not_allowed)
			(vias allowed)
			(pads allowed)
			(copperpour not_allowed)
			(footprints allowed)
		)
		(placement
			(enabled no)
			(sheetname "")
		)
		(fill yes
			(thermal_gap 0.5)
			(thermal_bridge_width 0.5)
			(island_removal_mode 0)
		)
		(polygon
			(pts
				(arc
					(start 365.144812 8.054594)
					(mid 364.476792 8.054594)
					(end 365.144812 8.054594)
				)
			)
		)
	)
	(zone
		(layers "F.Cu" "In2.Cu" "In4.Cu" "In6.Cu" "In11.Cu")
		(hatch none 0.5)
		(connect_pads
			(clearance 0)
		)
		(min_thickness 0.25)
		(keepout
			(tracks not_allowed)
			(vias allowed)
			(pads allowed)
			(copperpour not_allowed)
			(footprints allowed)
		)
		(placement
			(enabled no)
			(sheetname "")
		)
		(fill yes
			(thermal_gap 0.5)
			(thermal_bridge_width 0.5)
			(island_removal_mode 0)
		)
		(polygon
			(pts
				(arc
					(start 99.607624 3.955034)
					(mid 98.939604 3.955034)
					(end 99.607624 3.955034)
				)
			)
		)
	)
	(zone
		(layers "F.Cu" "In2.Cu" "In4.Cu" "In6.Cu" "In11.Cu")
		(hatch none 0.5)
		(connect_pads
			(clearance 0)
		)
		(min_thickness 0.25)
		(keepout
			(tracks not_allowed)
			(vias allowed)
			(pads allowed)
			(copperpour not_allowed)
			(footprints allowed)
		)
		(placement
			(enabled no)
			(sheetname "")
		)
		(fill yes
			(thermal_gap 0.5)
			(thermal_bridge_width 0.5)
			(island_removal_mode 0)
		)
		(polygon
			(pts
				(arc
					(start 184.71896 3.955034)
					(mid 184.05094 3.955034)
					(end 184.71896 3.955034)
				)
			)
		)
	)
	(zone
		(layers "F.Cu" "In2.Cu" "In4.Cu" "In6.Cu" "In11.Cu")
		(hatch none 0.5)
		(connect_pads
			(clearance 0)
		)
		(min_thickness 0.25)
		(keepout
			(tracks not_allowed)
			(vias allowed)
			(pads allowed)
			(copperpour not_allowed)
			(footprints allowed)
		)
		(placement
			(enabled no)
			(sheetname "")
		)
		(fill yes
			(thermal_gap 0.5)
			(thermal_bridge_width 0.5)
			(island_removal_mode 0)
		)
		(polygon
			(pts
				(arc
					(start 301.55515 -244.08511)
					(mid 300.88713 -244.08511)
					(end 301.55515 -244.08511)
				)
			)
		)
	)
	(zone
		(layers "F.Cu" "In2.Cu" "In4.Cu" "In6.Cu" "In11.Cu" "In12.Cu" "In15.Cu")
		(hatch none 0.5)
		(connect_pads
			(clearance 0)
		)
		(min_thickness 0.25)
		(keepout
			(tracks not_allowed)
			(vias allowed)
			(pads allowed)
			(copperpour not_allowed)
			(footprints allowed)
		)
		(placement
			(enabled no)
			(sheetname "")
		)
		(fill yes
			(thermal_gap 0.5)
			(thermal_bridge_width 0.5)
			(island_removal_mode 0)
		)
		(polygon
			(pts
				(arc
					(start 410.24175 -427.96079)
					(mid 410.264068 -428.014672)
					(end 410.31795 -428.03699)
				)
				(arc
					(start 411.25775 -428.03699)
					(mid 411.311632 -428.014672)
					(end 411.33395 -427.96079)
				)
				(arc
					(start 411.33395 -425.419266)
					(mid 411.311632 -425.365384)
					(end 411.25775 -425.343066)
				)
				(arc
					(start 410.31795 -425.343066)
					(mid 410.264068 -425.365384)
					(end 410.24175 -425.419266)
				)
			)
		)
	)
	(zone
		(layers "F.Cu" "In2.Cu" "In4.Cu" "In6.Cu" "In11.Cu" "In12.Cu" "In15.Cu")
		(hatch none 0.5)
		(connect_pads
			(clearance 0)
		)
		(min_thickness 0.25)
		(keepout
			(tracks not_allowed)
			(vias allowed)
			(pads allowed)
			(copperpour not_allowed)
			(footprints allowed)
		)
		(placement
			(enabled no)
			(sheetname "")
		)
		(fill yes
			(thermal_gap 0.5)
			(thermal_bridge_width 0.5)
			(island_removal_mode 0)
		)
		(polygon
			(pts
				(arc
					(start 385.2418 -427.96079)
					(mid 385.264118 -428.014672)
					(end 385.318 -428.03699)
				)
				(arc
					(start 386.2578 -428.03699)
					(mid 386.311682 -428.014672)
					(end 386.334 -427.96079)
				)
				(arc
					(start 386.334 -425.419266)
					(mid 386.311682 -425.365384)
					(end 386.2578 -425.343066)
				)
				(arc
					(start 385.318 -425.343066)
					(mid 385.264118 -425.365384)
					(end 385.2418 -425.419266)
				)
			)
		)
	)
	(zone
		(layers "F.Cu" "In2.Cu" "In4.Cu" "In6.Cu" "In11.Cu" "In12.Cu" "In15.Cu")
		(hatch none 0.5)
		(connect_pads
			(clearance 0)
		)
		(min_thickness 0.25)
		(keepout
			(tracks not_allowed)
			(vias allowed)
			(pads allowed)
			(copperpour not_allowed)
			(footprints allowed)
		)
		(placement
			(enabled no)
			(sheetname "")
		)
		(fill yes
			(thermal_gap 0.5)
			(thermal_bridge_width 0.5)
			(island_removal_mode 0)
		)
		(polygon
			(pts
				(arc
					(start 398.241774 -427.96079)
					(mid 398.264092 -428.014672)
					(end 398.317974 -428.03699)
				)
				(arc
					(start 399.257774 -428.03699)
					(mid 399.311656 -428.014672)
					(end 399.333974 -427.96079)
				)
				(arc
					(start 399.333974 -425.419266)
					(mid 399.311656 -425.365384)
					(end 399.257774 -425.343066)
				)
				(arc
					(start 398.317974 -425.343066)
					(mid 398.264092 -425.365384)
					(end 398.241774 -425.419266)
				)
			)
		)
	)
	(zone
		(layers "F.Cu" "In2.Cu" "In4.Cu" "In6.Cu" "In11.Cu" "In12.Cu" "In15.Cu")
		(hatch none 0.5)
		(connect_pads
			(clearance 0)
		)
		(min_thickness 0.25)
		(keepout
			(tracks not_allowed)
			(vias allowed)
			(pads allowed)
			(copperpour not_allowed)
			(footprints allowed)
		)
		(placement
			(enabled no)
			(sheetname "")
		)
		(fill yes
			(thermal_gap 0.5)
			(thermal_bridge_width 0.5)
			(island_removal_mode 0)
		)
		(polygon
			(pts
				(arc
					(start 381.241808 -427.96079)
					(mid 381.264126 -428.014672)
					(end 381.318008 -428.03699)
				)
				(arc
					(start 382.257808 -428.03699)
					(mid 382.31169 -428.014672)
					(end 382.334008 -427.96079)
				)
				(arc
					(start 382.334008 -425.419266)
					(mid 382.31169 -425.365384)
					(end 382.257808 -425.343066)
				)
				(arc
					(start 381.318008 -425.343066)
					(mid 381.264126 -425.365384)
					(end 381.241808 -425.419266)
				)
			)
		)
	)
	(zone
		(layers "F.Cu" "In2.Cu" "In4.Cu" "In6.Cu" "In11.Cu" "In12.Cu" "In15.Cu")
		(hatch none 0.5)
		(connect_pads
			(clearance 0)
		)
		(min_thickness 0.25)
		(keepout
			(tracks not_allowed)
			(vias allowed)
			(pads allowed)
			(copperpour not_allowed)
			(footprints allowed)
		)
		(placement
			(enabled no)
			(sheetname "")
		)
		(fill yes
			(thermal_gap 0.5)
			(thermal_bridge_width 0.5)
			(island_removal_mode 0)
		)
		(polygon
			(pts
				(arc
					(start 402.241766 -427.96079)
					(mid 402.264084 -428.014672)
					(end 402.317966 -428.03699)
				)
				(arc
					(start 403.257766 -428.03699)
					(mid 403.311648 -428.014672)
					(end 403.333966 -427.96079)
				)
				(arc
					(start 403.333966 -425.419266)
					(mid 403.311648 -425.365384)
					(end 403.257766 -425.343066)
				)
				(arc
					(start 402.317966 -425.343066)
					(mid 402.264084 -425.365384)
					(end 402.241766 -425.419266)
				)
			)
		)
	)
	(zone
		(layers "F.Cu" "In2.Cu" "In4.Cu" "In6.Cu" "In11.Cu" "In12.Cu" "In15.Cu")
		(hatch none 0.5)
		(connect_pads
			(clearance 0)
		)
		(min_thickness 0.25)
		(keepout
			(tracks not_allowed)
			(vias allowed)
			(pads allowed)
			(copperpour not_allowed)
			(footprints allowed)
		)
		(placement
			(enabled no)
			(sheetname "")
		)
		(fill yes
			(thermal_gap 0.5)
			(thermal_bridge_width 0.5)
			(island_removal_mode 0)
		)
		(polygon
			(pts
				(arc
					(start 389.241792 -427.96079)
					(mid 389.26411 -428.014672)
					(end 389.317992 -428.03699)
				)
				(arc
					(start 390.257792 -428.03699)
					(mid 390.311674 -428.014672)
					(end 390.333992 -427.96079)
				)
				(arc
					(start 390.333992 -425.419266)
					(mid 390.311674 -425.365384)
					(end 390.257792 -425.343066)
				)
				(arc
					(start 389.317992 -425.343066)
					(mid 389.26411 -425.365384)
					(end 389.241792 -425.419266)
				)
			)
		)
	)
	(zone
		(layers "F.Cu" "In2.Cu" "In4.Cu" "In6.Cu" "In11.Cu" "In12.Cu" "In15.Cu")
		(hatch none 0.5)
		(connect_pads
			(clearance 0)
		)
		(min_thickness 0.25)
		(keepout
			(tracks not_allowed)
			(vias allowed)
			(pads allowed)
			(copperpour not_allowed)
			(footprints allowed)
		)
		(placement
			(enabled no)
			(sheetname "")
		)
		(fill yes
			(thermal_gap 0.5)
			(thermal_bridge_width 0.5)
			(island_removal_mode 0)
		)
		(polygon
			(pts
				(arc
					(start 406.241758 -427.96079)
					(mid 406.264076 -428.014672)
					(end 406.317958 -428.03699)
				)
				(arc
					(start 407.257758 -428.03699)
					(mid 407.31164 -428.014672)
					(end 407.333958 -427.96079)
				)
				(arc
					(start 407.333958 -425.419266)
					(mid 407.31164 -425.365384)
					(end 407.257758 -425.343066)
				)
				(arc
					(start 406.317958 -425.343066)
					(mid 406.264076 -425.365384)
					(end 406.241758 -425.419266)
				)
			)
		)
	)
	(zone
		(layers "F.Cu" "In2.Cu" "In4.Cu" "In6.Cu" "In11.Cu" "In12.Cu" "In15.Cu")
		(hatch none 0.5)
		(connect_pads
			(clearance 0)
		)
		(min_thickness 0.25)
		(keepout
			(tracks not_allowed)
			(vias allowed)
			(pads allowed)
			(copperpour not_allowed)
			(footprints allowed)
		)
		(placement
			(enabled no)
			(sheetname "")
		)
		(fill yes
			(thermal_gap 0.5)
			(thermal_bridge_width 0.5)
			(island_removal_mode 0)
		)
		(polygon
			(pts
				(arc
					(start 393.241784 -427.96079)
					(mid 393.264102 -428.014672)
					(end 393.317984 -428.03699)
				)
				(arc
					(start 394.257784 -428.03699)
					(mid 394.311666 -428.014672)
					(end 394.333984 -427.96079)
				)
				(arc
					(start 394.333984 -425.419266)
					(mid 394.311666 -425.365384)
					(end 394.257784 -425.343066)
				)
				(arc
					(start 393.317984 -425.343066)
					(mid 393.264102 -425.365384)
					(end 393.241784 -425.419266)
				)
			)
		)
	)
	(zone
		(layers "F.Cu" "In2.Cu" "In4.Cu" "In6.Cu" "In11.Cu" "In13.Cu")
		(hatch none 0.5)
		(connect_pads
			(clearance 0)
		)
		(min_thickness 0.25)
		(keepout
			(tracks not_allowed)
			(vias allowed)
			(pads allowed)
			(copperpour not_allowed)
			(footprints allowed)
		)
		(placement
			(enabled no)
			(sheetname "")
		)
		(fill yes
			(thermal_gap 0.5)
			(thermal_bridge_width 0.5)
			(island_removal_mode 0)
		)
		(polygon
			(pts
				(arc
					(start 316.77737 -2.105406)
					(mid 316.10935 -2.105406)
					(end 316.77737 -2.105406)
				)
			)
		)
	)
	(zone
		(layers "F.Cu" "In2.Cu" "In4.Cu" "In6.Cu" "In11.Cu" "In13.Cu")
		(hatch none 0.5)
		(connect_pads
			(clearance 0)
		)
		(min_thickness 0.25)
		(keepout
			(tracks not_allowed)
			(vias allowed)
			(pads allowed)
			(copperpour not_allowed)
			(footprints allowed)
		)
		(placement
			(enabled no)
			(sheetname "")
		)
		(fill yes
			(thermal_gap 0.5)
			(thermal_bridge_width 0.5)
			(island_removal_mode 0)
		)
		(polygon
			(pts
				(arc
					(start 365.144812 -2.105406)
					(mid 364.476792 -2.105406)
					(end 365.144812 -2.105406)
				)
			)
		)
	)
	(zone
		(layers "F.Cu" "In2.Cu" "In4.Cu" "In6.Cu" "In11.Cu" "In13.Cu")
		(hatch none 0.5)
		(connect_pads
			(clearance 0)
		)
		(min_thickness 0.25)
		(keepout
			(tracks not_allowed)
			(vias allowed)
			(pads allowed)
			(copperpour not_allowed)
			(footprints allowed)
		)
		(placement
			(enabled no)
			(sheetname "")
		)
		(fill yes
			(thermal_gap 0.5)
			(thermal_bridge_width 0.5)
			(island_removal_mode 0)
		)
		(polygon
			(pts
				(arc
					(start 214.28329 2.110994)
					(mid 213.61527 2.110994)
					(end 214.28329 2.110994)
				)
			)
		)
	)
	(zone
		(layers "F.Cu" "In2.Cu" "In4.Cu" "In6.Cu" "In11.Cu" "In13.Cu")
		(hatch none 0.5)
		(connect_pads
			(clearance 0)
		)
		(min_thickness 0.25)
		(keepout
			(tracks not_allowed)
			(vias allowed)
			(pads allowed)
			(copperpour not_allowed)
			(footprints allowed)
		)
		(placement
			(enabled no)
			(sheetname "")
		)
		(fill yes
			(thermal_gap 0.5)
			(thermal_bridge_width 0.5)
			(island_removal_mode 0)
		)
		(polygon
			(pts
				(arc
					(start 316.77737 -2.969006)
					(mid 316.10935 -2.969006)
					(end 316.77737 -2.969006)
				)
			)
		)
	)
	(zone
		(layers "F.Cu" "In2.Cu" "In4.Cu" "In6.Cu" "In11.Cu" "In13.Cu")
		(hatch none 0.5)
		(connect_pads
			(clearance 0)
		)
		(min_thickness 0.25)
		(keepout
			(tracks not_allowed)
			(vias allowed)
			(pads allowed)
			(copperpour not_allowed)
			(footprints allowed)
		)
		(placement
			(enabled no)
			(sheetname "")
		)
		(fill yes
			(thermal_gap 0.5)
			(thermal_bridge_width 0.5)
			(island_removal_mode 0)
		)
		(polygon
			(pts
				(arc
					(start 214.28329 2.974594)
					(mid 213.61527 2.974594)
					(end 214.28329 2.974594)
				)
			)
		)
	)
	(zone
		(layers "F.Cu" "In2.Cu" "In4.Cu" "In6.Cu" "In11.Cu" "In13.Cu")
		(hatch none 0.5)
		(connect_pads
			(clearance 0)
		)
		(min_thickness 0.25)
		(keepout
			(tracks not_allowed)
			(vias allowed)
			(pads allowed)
			(copperpour not_allowed)
			(footprints allowed)
		)
		(placement
			(enabled no)
			(sheetname "")
		)
		(fill yes
			(thermal_gap 0.5)
			(thermal_bridge_width 0.5)
			(island_removal_mode 0)
		)
		(polygon
			(pts
				(arc
					(start 365.144812 -2.969006)
					(mid 364.476792 -2.969006)
					(end 365.144812 -2.969006)
				)
			)
		)
	)
	(zone
		(layers "F.Cu" "In2.Cu" "In4.Cu" "In6.Cu" "In11.Cu" "In13.Cu")
		(hatch none 0.5)
		(connect_pads
			(clearance 0)
		)
		(min_thickness 0.25)
		(keepout
			(tracks not_allowed)
			(vias allowed)
			(pads allowed)
			(copperpour not_allowed)
			(footprints allowed)
		)
		(placement
			(enabled no)
			(sheetname "")
		)
		(fill yes
			(thermal_gap 0.5)
			(thermal_bridge_width 0.5)
			(island_removal_mode 0)
		)
		(polygon
			(pts
				(arc
					(start 299.394626 2.110994)
					(mid 298.726606 2.110994)
					(end 299.394626 2.110994)
				)
			)
		)
	)
	(zone
		(layers "F.Cu" "In2.Cu" "In4.Cu" "In6.Cu" "In11.Cu" "In13.Cu")
		(hatch none 0.5)
		(connect_pads
			(clearance 0)
		)
		(min_thickness 0.25)
		(keepout
			(tracks not_allowed)
			(vias allowed)
			(pads allowed)
			(copperpour not_allowed)
			(footprints allowed)
		)
		(placement
			(enabled no)
			(sheetname "")
		)
		(fill yes
			(thermal_gap 0.5)
			(thermal_bridge_width 0.5)
			(island_removal_mode 0)
		)
		(polygon
			(pts
				(arc
					(start 299.394626 2.974594)
					(mid 298.726606 2.974594)
					(end 299.394626 2.974594)
				)
			)
		)
	)
	(zone
		(layers "F.Cu" "In2.Cu" "In4.Cu" "In6.Cu" "In11.Cu" "In13.Cu" "In14.Cu"
			"In15.Cu"
		)
		(hatch none 0.5)
		(connect_pads
			(clearance 0)
		)
		(min_thickness 0.25)
		(keepout
			(tracks not_allowed)
			(vias allowed)
			(pads allowed)
			(copperpour not_allowed)
			(footprints allowed)
		)
		(placement
			(enabled no)
			(sheetname "")
		)
		(fill yes
			(thermal_gap 0.5)
			(thermal_bridge_width 0.5)
			(island_removal_mode 0)
		)
		(polygon
			(pts
				(arc
					(start 139.241784 -432.56073)
					(mid 139.264102 -432.614612)
					(end 139.317984 -432.63693)
				)
				(arc
					(start 140.257784 -432.63693)
					(mid 140.311666 -432.614612)
					(end 140.333984 -432.56073)
				)
				(arc
					(start 140.333984 -430.019206)
					(mid 140.311666 -429.965324)
					(end 140.257784 -429.943006)
				)
				(arc
					(start 139.317984 -429.943006)
					(mid 139.264102 -429.965324)
					(end 139.241784 -430.019206)
				)
			)
		)
	)
	(zone
		(layers "F.Cu" "In2.Cu" "In4.Cu" "In6.Cu" "In11.Cu" "In13.Cu" "In14.Cu"
			"In15.Cu"
		)
		(hatch none 0.5)
		(connect_pads
			(clearance 0)
		)
		(min_thickness 0.25)
		(keepout
			(tracks not_allowed)
			(vias allowed)
			(pads allowed)
			(copperpour not_allowed)
			(footprints allowed)
		)
		(placement
			(enabled no)
			(sheetname "")
		)
		(fill yes
			(thermal_gap 0.5)
			(thermal_bridge_width 0.5)
			(island_removal_mode 0)
		)
		(polygon
			(pts
				(arc
					(start 148.241766 -432.56073)
					(mid 148.264084 -432.614612)
					(end 148.317966 -432.63693)
				)
				(arc
					(start 149.257766 -432.63693)
					(mid 149.311648 -432.614612)
					(end 149.333966 -432.56073)
				)
				(arc
					(start 149.333966 -430.019206)
					(mid 149.311648 -429.965324)
					(end 149.257766 -429.943006)
				)
				(arc
					(start 148.317966 -429.943006)
					(mid 148.264084 -429.965324)
					(end 148.241766 -430.019206)
				)
			)
		)
	)
	(zone
		(layers "F.Cu" "In2.Cu" "In4.Cu" "In6.Cu" "In11.Cu" "In13.Cu" "In14.Cu"
			"In15.Cu"
		)
		(hatch none 0.5)
		(connect_pads
			(clearance 0)
		)
		(min_thickness 0.25)
		(keepout
			(tracks not_allowed)
			(vias allowed)
			(pads allowed)
			(copperpour not_allowed)
			(footprints allowed)
		)
		(placement
			(enabled no)
			(sheetname "")
		)
		(fill yes
			(thermal_gap 0.5)
			(thermal_bridge_width 0.5)
			(island_removal_mode 0)
		)
		(polygon
			(pts
				(arc
					(start 152.241758 -432.56073)
					(mid 152.264076 -432.614612)
					(end 152.317958 -432.63693)
				)
				(arc
					(start 153.257758 -432.63693)
					(mid 153.31164 -432.614612)
					(end 153.333958 -432.56073)
				)
				(arc
					(start 153.333958 -430.019206)
					(mid 153.31164 -429.965324)
					(end 153.257758 -429.943006)
				)
				(arc
					(start 152.317958 -429.943006)
					(mid 152.264076 -429.965324)
					(end 152.241758 -430.019206)
				)
			)
		)
	)
	(zone
		(layers "F.Cu" "In2.Cu" "In4.Cu" "In6.Cu" "In11.Cu" "In13.Cu" "In14.Cu"
			"In15.Cu"
		)
		(hatch none 0.5)
		(connect_pads
			(clearance 0)
		)
		(min_thickness 0.25)
		(keepout
			(tracks not_allowed)
			(vias allowed)
			(pads allowed)
			(copperpour not_allowed)
			(footprints allowed)
		)
		(placement
			(enabled no)
			(sheetname "")
		)
		(fill yes
			(thermal_gap 0.5)
			(thermal_bridge_width 0.5)
			(island_removal_mode 0)
		)
		(polygon
			(pts
				(arc
					(start 131.2418 -432.56073)
					(mid 131.264118 -432.614612)
					(end 131.318 -432.63693)
				)
				(arc
					(start 132.2578 -432.63693)
					(mid 132.311682 -432.614612)
					(end 132.334 -432.56073)
				)
				(arc
					(start 132.334 -430.019206)
					(mid 132.311682 -429.965324)
					(end 132.2578 -429.943006)
				)
				(arc
					(start 131.318 -429.943006)
					(mid 131.264118 -429.965324)
					(end 131.2418 -430.019206)
				)
			)
		)
	)
	(zone
		(layers "F.Cu" "In2.Cu" "In4.Cu" "In6.Cu" "In11.Cu" "In13.Cu" "In14.Cu"
			"In15.Cu"
		)
		(hatch none 0.5)
		(connect_pads
			(clearance 0)
		)
		(min_thickness 0.25)
		(keepout
			(tracks not_allowed)
			(vias allowed)
			(pads allowed)
			(copperpour not_allowed)
			(footprints allowed)
		)
		(placement
			(enabled no)
			(sheetname "")
		)
		(fill yes
			(thermal_gap 0.5)
			(thermal_bridge_width 0.5)
			(island_removal_mode 0)
		)
		(polygon
			(pts
				(arc
					(start 146.24177 -431.560732)
					(mid 146.264088 -431.614614)
					(end 146.31797 -431.636932)
				)
				(arc
					(start 147.25777 -431.636932)
					(mid 147.311652 -431.614614)
					(end 147.33397 -431.560732)
				)
				(arc
					(start 147.33397 -429.019208)
					(mid 147.311652 -428.965326)
					(end 147.25777 -428.943008)
				)
				(arc
					(start 146.31797 -428.943008)
					(mid 146.264088 -428.965326)
					(end 146.24177 -429.019208)
				)
			)
		)
	)
	(zone
		(layers "F.Cu" "In2.Cu" "In4.Cu" "In6.Cu" "In11.Cu" "In13.Cu" "In14.Cu"
			"In15.Cu"
		)
		(hatch none 0.5)
		(connect_pads
			(clearance 0)
		)
		(min_thickness 0.25)
		(keepout
			(tracks not_allowed)
			(vias allowed)
			(pads allowed)
			(copperpour not_allowed)
			(footprints allowed)
		)
		(placement
			(enabled no)
			(sheetname "")
		)
		(fill yes
			(thermal_gap 0.5)
			(thermal_bridge_width 0.5)
			(island_removal_mode 0)
		)
		(polygon
			(pts
				(arc
					(start 144.241774 -432.56073)
					(mid 144.264092 -432.614612)
					(end 144.317974 -432.63693)
				)
				(arc
					(start 145.257774 -432.63693)
					(mid 145.311656 -432.614612)
					(end 145.333974 -432.56073)
				)
				(arc
					(start 145.333974 -430.019206)
					(mid 145.311656 -429.965324)
					(end 145.257774 -429.943006)
				)
				(arc
					(start 144.317974 -429.943006)
					(mid 144.264092 -429.965324)
					(end 144.241774 -430.019206)
				)
			)
		)
	)
	(zone
		(layers "F.Cu" "In2.Cu" "In4.Cu" "In6.Cu" "In11.Cu" "In13.Cu" "In14.Cu"
			"In15.Cu"
		)
		(hatch none 0.5)
		(connect_pads
			(clearance 0)
		)
		(min_thickness 0.25)
		(keepout
			(tracks not_allowed)
			(vias allowed)
			(pads allowed)
			(copperpour not_allowed)
			(footprints allowed)
		)
		(placement
			(enabled no)
			(sheetname "")
		)
		(fill yes
			(thermal_gap 0.5)
			(thermal_bridge_width 0.5)
			(island_removal_mode 0)
		)
		(polygon
			(pts
				(arc
					(start 142.241778 -431.560732)
					(mid 142.264096 -431.614614)
					(end 142.317978 -431.636932)
				)
				(arc
					(start 143.257778 -431.636932)
					(mid 143.31166 -431.614614)
					(end 143.333978 -431.560732)
				)
				(arc
					(start 143.333978 -429.019208)
					(mid 143.31166 -428.965326)
					(end 143.257778 -428.943008)
				)
				(arc
					(start 142.317978 -428.943008)
					(mid 142.264096 -428.965326)
					(end 142.241778 -429.019208)
				)
			)
		)
	)
	(zone
		(layers "F.Cu" "In2.Cu" "In4.Cu" "In6.Cu" "In11.Cu" "In13.Cu" "In14.Cu"
			"In15.Cu"
		)
		(hatch none 0.5)
		(connect_pads
			(clearance 0)
		)
		(min_thickness 0.25)
		(keepout
			(tracks not_allowed)
			(vias allowed)
			(pads allowed)
			(copperpour not_allowed)
			(footprints allowed)
		)
		(placement
			(enabled no)
			(sheetname "")
		)
		(fill yes
			(thermal_gap 0.5)
			(thermal_bridge_width 0.5)
			(island_removal_mode 0)
		)
		(polygon
			(pts
				(arc
					(start 129.241804 -431.560732)
					(mid 129.264122 -431.614614)
					(end 129.318004 -431.636932)
				)
				(arc
					(start 130.257804 -431.636932)
					(mid 130.311686 -431.614614)
					(end 130.334004 -431.560732)
				)
				(arc
					(start 130.334004 -429.019208)
					(mid 130.311686 -428.965326)
					(end 130.257804 -428.943008)
				)
				(arc
					(start 129.318004 -428.943008)
					(mid 129.264122 -428.965326)
					(end 129.241804 -429.019208)
				)
			)
		)
	)
	(zone
		(layers "F.Cu" "In2.Cu" "In4.Cu" "In6.Cu" "In11.Cu" "In13.Cu" "In14.Cu"
			"In15.Cu"
		)
		(hatch none 0.5)
		(connect_pads
			(clearance 0)
		)
		(min_thickness 0.25)
		(keepout
			(tracks not_allowed)
			(vias allowed)
			(pads allowed)
			(copperpour not_allowed)
			(footprints allowed)
		)
		(placement
			(enabled no)
			(sheetname "")
		)
		(fill yes
			(thermal_gap 0.5)
			(thermal_bridge_width 0.5)
			(island_removal_mode 0)
		)
		(polygon
			(pts
				(arc
					(start 127.241808 -432.56073)
					(mid 127.264126 -432.614612)
					(end 127.318008 -432.63693)
				)
				(arc
					(start 128.257808 -432.63693)
					(mid 128.31169 -432.614612)
					(end 128.334008 -432.56073)
				)
				(arc
					(start 128.334008 -430.019206)
					(mid 128.31169 -429.965324)
					(end 128.257808 -429.943006)
				)
				(arc
					(start 127.318008 -429.943006)
					(mid 127.264126 -429.965324)
					(end 127.241808 -430.019206)
				)
			)
		)
	)
	(zone
		(layers "F.Cu" "In2.Cu" "In4.Cu" "In6.Cu" "In11.Cu" "In13.Cu" "In14.Cu"
			"In15.Cu"
		)
		(hatch none 0.5)
		(connect_pads
			(clearance 0)
		)
		(min_thickness 0.25)
		(keepout
			(tracks not_allowed)
			(vias allowed)
			(pads allowed)
			(copperpour not_allowed)
			(footprints allowed)
		)
		(placement
			(enabled no)
			(sheetname "")
		)
		(fill yes
			(thermal_gap 0.5)
			(thermal_bridge_width 0.5)
			(island_removal_mode 0)
		)
		(polygon
			(pts
				(arc
					(start 150.241762 -431.560732)
					(mid 150.26408 -431.614614)
					(end 150.317962 -431.636932)
				)
				(arc
					(start 151.257762 -431.636932)
					(mid 151.311644 -431.614614)
					(end 151.333962 -431.560732)
				)
				(arc
					(start 151.333962 -429.019208)
					(mid 151.311644 -428.965326)
					(end 151.257762 -428.943008)
				)
				(arc
					(start 150.317962 -428.943008)
					(mid 150.26408 -428.965326)
					(end 150.241762 -429.019208)
				)
			)
		)
	)
	(zone
		(layers "F.Cu" "In2.Cu" "In4.Cu" "In6.Cu" "In11.Cu" "In13.Cu" "In14.Cu"
			"In15.Cu"
		)
		(hatch none 0.5)
		(connect_pads
			(clearance 0)
		)
		(min_thickness 0.25)
		(keepout
			(tracks not_allowed)
			(vias allowed)
			(pads allowed)
			(copperpour not_allowed)
			(footprints allowed)
		)
		(placement
			(enabled no)
			(sheetname "")
		)
		(fill yes
			(thermal_gap 0.5)
			(thermal_bridge_width 0.5)
			(island_removal_mode 0)
		)
		(polygon
			(pts
				(arc
					(start 135.241792 -432.56073)
					(mid 135.26411 -432.614612)
					(end 135.317992 -432.63693)
				)
				(arc
					(start 136.257792 -432.63693)
					(mid 136.311674 -432.614612)
					(end 136.333992 -432.56073)
				)
				(arc
					(start 136.333992 -430.019206)
					(mid 136.311674 -429.965324)
					(end 136.257792 -429.943006)
				)
				(arc
					(start 135.317992 -429.943006)
					(mid 135.26411 -429.965324)
					(end 135.241792 -430.019206)
				)
			)
		)
	)
	(zone
		(layers "F.Cu" "In2.Cu" "In4.Cu" "In6.Cu" "In11.Cu" "In13.Cu" "In14.Cu"
			"In15.Cu"
		)
		(hatch none 0.5)
		(connect_pads
			(clearance 0)
		)
		(min_thickness 0.25)
		(keepout
			(tracks not_allowed)
			(vias allowed)
			(pads allowed)
			(copperpour not_allowed)
			(footprints allowed)
		)
		(placement
			(enabled no)
			(sheetname "")
		)
		(fill yes
			(thermal_gap 0.5)
			(thermal_bridge_width 0.5)
			(island_removal_mode 0)
		)
		(polygon
			(pts
				(arc
					(start 137.241788 -431.560732)
					(mid 137.264106 -431.614614)
					(end 137.317988 -431.636932)
				)
				(arc
					(start 138.257788 -431.636932)
					(mid 138.31167 -431.614614)
					(end 138.333988 -431.560732)
				)
				(arc
					(start 138.333988 -429.019208)
					(mid 138.31167 -428.965326)
					(end 138.257788 -428.943008)
				)
				(arc
					(start 137.317988 -428.943008)
					(mid 137.264106 -428.965326)
					(end 137.241788 -429.019208)
				)
			)
		)
	)
	(zone
		(layers "F.Cu" "In2.Cu" "In4.Cu" "In6.Cu" "In11.Cu" "In13.Cu" "In14.Cu"
			"In15.Cu"
		)
		(hatch none 0.5)
		(connect_pads
			(clearance 0)
		)
		(min_thickness 0.25)
		(keepout
			(tracks not_allowed)
			(vias allowed)
			(pads allowed)
			(copperpour not_allowed)
			(footprints allowed)
		)
		(placement
			(enabled no)
			(sheetname "")
		)
		(fill yes
			(thermal_gap 0.5)
			(thermal_bridge_width 0.5)
			(island_removal_mode 0)
		)
		(polygon
			(pts
				(arc
					(start 125.241812 -431.560732)
					(mid 125.26413 -431.614614)
					(end 125.318012 -431.636932)
				)
				(arc
					(start 126.257812 -431.636932)
					(mid 126.311694 -431.614614)
					(end 126.334012 -431.560732)
				)
				(arc
					(start 126.334012 -429.019208)
					(mid 126.311694 -428.965326)
					(end 126.257812 -428.943008)
				)
				(arc
					(start 125.318012 -428.943008)
					(mid 125.26413 -428.965326)
					(end 125.241812 -429.019208)
				)
			)
		)
	)
	(zone
		(layers "F.Cu" "In2.Cu" "In4.Cu" "In6.Cu" "In11.Cu" "In13.Cu" "In14.Cu"
			"In15.Cu"
		)
		(hatch none 0.5)
		(connect_pads
			(clearance 0)
		)
		(min_thickness 0.25)
		(keepout
			(tracks not_allowed)
			(vias allowed)
			(pads allowed)
			(copperpour not_allowed)
			(footprints allowed)
		)
		(placement
			(enabled no)
			(sheetname "")
		)
		(fill yes
			(thermal_gap 0.5)
			(thermal_bridge_width 0.5)
			(island_removal_mode 0)
		)
		(polygon
			(pts
				(arc
					(start 133.241796 -431.560732)
					(mid 133.264114 -431.614614)
					(end 133.317996 -431.636932)
				)
				(arc
					(start 134.257796 -431.636932)
					(mid 134.311678 -431.614614)
					(end 134.333996 -431.560732)
				)
				(arc
					(start 134.333996 -429.019208)
					(mid 134.311678 -428.965326)
					(end 134.257796 -428.943008)
				)
				(arc
					(start 133.317996 -428.943008)
					(mid 133.264114 -428.965326)
					(end 133.241796 -429.019208)
				)
			)
		)
	)
	(zone
		(layers "F.Cu" "In2.Cu" "In4.Cu" "In6.Cu" "In11.Cu" "In13.Cu" "In15.Cu")
		(hatch none 0.5)
		(connect_pads
			(clearance 0)
		)
		(min_thickness 0.25)
		(keepout
			(tracks not_allowed)
			(vias allowed)
			(pads allowed)
			(copperpour not_allowed)
			(footprints allowed)
		)
		(placement
			(enabled no)
			(sheetname "")
		)
		(fill yes
			(thermal_gap 0.5)
			(thermal_bridge_width 0.5)
			(island_removal_mode 0)
		)
		(polygon
			(pts
				(arc
					(start 337.14182 -432.56073)
					(mid 337.164138 -432.614612)
					(end 337.21802 -432.63693)
				)
				(arc
					(start 338.15782 -432.63693)
					(mid 338.211702 -432.614612)
					(end 338.23402 -432.56073)
				)
				(arc
					(start 338.23402 -430.019206)
					(mid 338.211702 -429.965324)
					(end 338.15782 -429.943006)
				)
				(arc
					(start 337.21802 -429.943006)
					(mid 337.164138 -429.965324)
					(end 337.14182 -430.019206)
				)
			)
		)
	)
	(zone
		(layers "F.Cu" "In2.Cu" "In4.Cu" "In6.Cu" "In11.Cu" "In13.Cu" "In15.Cu")
		(hatch none 0.5)
		(connect_pads
			(clearance 0)
		)
		(min_thickness 0.25)
		(keepout
			(tracks not_allowed)
			(vias allowed)
			(pads allowed)
			(copperpour not_allowed)
			(footprints allowed)
		)
		(placement
			(enabled no)
			(sheetname "")
		)
		(fill yes
			(thermal_gap 0.5)
			(thermal_bridge_width 0.5)
			(island_removal_mode 0)
		)
		(polygon
			(pts
				(arc
					(start 70.141846 -431.560732)
					(mid 70.164164 -431.614614)
					(end 70.218046 -431.636932)
				)
				(arc
					(start 71.157846 -431.636932)
					(mid 71.211728 -431.614614)
					(end 71.234046 -431.560732)
				)
				(arc
					(start 71.234046 -429.019208)
					(mid 71.211728 -428.965326)
					(end 71.157846 -428.943008)
				)
				(arc
					(start 70.218046 -428.943008)
					(mid 70.164164 -428.965326)
					(end 70.141846 -429.019208)
				)
			)
		)
	)
	(zone
		(layers "F.Cu" "In2.Cu" "In4.Cu" "In6.Cu" "In11.Cu" "In13.Cu" "In15.Cu")
		(hatch none 0.5)
		(connect_pads
			(clearance 0)
		)
		(min_thickness 0.25)
		(keepout
			(tracks not_allowed)
			(vias allowed)
			(pads allowed)
			(copperpour not_allowed)
			(footprints allowed)
		)
		(placement
			(enabled no)
			(sheetname "")
		)
		(fill yes
			(thermal_gap 0.5)
			(thermal_bridge_width 0.5)
			(island_removal_mode 0)
		)
		(polygon
			(pts
				(arc
					(start 339.141816 -431.560732)
					(mid 339.164134 -431.614614)
					(end 339.218016 -431.636932)
				)
				(arc
					(start 340.157816 -431.636932)
					(mid 340.211698 -431.614614)
					(end 340.234016 -431.560732)
				)
				(arc
					(start 340.234016 -429.019208)
					(mid 340.211698 -428.965326)
					(end 340.157816 -428.943008)
				)
				(arc
					(start 339.218016 -428.943008)
					(mid 339.164134 -428.965326)
					(end 339.141816 -429.019208)
				)
			)
		)
	)
	(zone
		(layers "F.Cu" "In2.Cu" "In4.Cu" "In6.Cu" "In11.Cu" "In13.Cu" "In15.Cu")
		(hatch none 0.5)
		(connect_pads
			(clearance 0)
		)
		(min_thickness 0.25)
		(keepout
			(tracks not_allowed)
			(vias allowed)
			(pads allowed)
			(copperpour not_allowed)
			(footprints allowed)
		)
		(placement
			(enabled no)
			(sheetname "")
		)
		(fill yes
			(thermal_gap 0.5)
			(thermal_bridge_width 0.5)
			(island_removal_mode 0)
		)
		(polygon
			(pts
				(arc
					(start 389.241792 -431.560732)
					(mid 389.26411 -431.614614)
					(end 389.317992 -431.636932)
				)
				(arc
					(start 390.257792 -431.636932)
					(mid 390.311674 -431.614614)
					(end 390.333992 -431.560732)
				)
				(arc
					(start 390.333992 -429.019208)
					(mid 390.311674 -428.965326)
					(end 390.257792 -428.943008)
				)
				(arc
					(start 389.317992 -428.943008)
					(mid 389.26411 -428.965326)
					(end 389.241792 -429.019208)
				)
			)
		)
	)
	(zone
		(layers "F.Cu" "In2.Cu" "In4.Cu" "In6.Cu" "In11.Cu" "In13.Cu" "In15.Cu")
		(hatch none 0.5)
		(connect_pads
			(clearance 0)
		)
		(min_thickness 0.25)
		(keepout
			(tracks not_allowed)
			(vias allowed)
			(pads allowed)
			(copperpour not_allowed)
			(footprints allowed)
		)
		(placement
			(enabled no)
			(sheetname "")
		)
		(fill yes
			(thermal_gap 0.5)
			(thermal_bridge_width 0.5)
			(island_removal_mode 0)
		)
		(polygon
			(pts
				(arc
					(start 381.241808 -435.160674)
					(mid 381.264126 -435.214556)
					(end 381.318008 -435.236874)
				)
				(arc
					(start 382.257808 -435.236874)
					(mid 382.31169 -435.214556)
					(end 382.334008 -435.160674)
				)
				(arc
					(start 382.334008 -432.61915)
					(mid 382.31169 -432.565268)
					(end 382.257808 -432.54295)
				)
				(arc
					(start 381.318008 -432.54295)
					(mid 381.264126 -432.565268)
					(end 381.241808 -432.61915)
				)
			)
		)
	)
	(zone
		(layers "F.Cu" "In2.Cu" "In4.Cu" "In6.Cu" "In11.Cu" "In13.Cu" "In15.Cu")
		(hatch none 0.5)
		(connect_pads
			(clearance 0)
		)
		(min_thickness 0.25)
		(keepout
			(tracks not_allowed)
			(vias allowed)
			(pads allowed)
			(copperpour not_allowed)
			(footprints allowed)
		)
		(placement
			(enabled no)
			(sheetname "")
		)
		(fill yes
			(thermal_gap 0.5)
			(thermal_bridge_width 0.5)
			(island_removal_mode 0)
		)
		(polygon
			(pts
				(arc
					(start 129.241804 -435.160674)
					(mid 129.264122 -435.214556)
					(end 129.318004 -435.236874)
				)
				(arc
					(start 130.257804 -435.236874)
					(mid 130.311686 -435.214556)
					(end 130.334004 -435.160674)
				)
				(arc
					(start 130.334004 -432.61915)
					(mid 130.311686 -432.565268)
					(end 130.257804 -432.54295)
				)
				(arc
					(start 129.318004 -432.54295)
					(mid 129.264122 -432.565268)
					(end 129.241804 -432.61915)
				)
			)
		)
	)
	(zone
		(layers "F.Cu" "In2.Cu" "In4.Cu" "In6.Cu" "In11.Cu" "In13.Cu" "In15.Cu")
		(hatch none 0.5)
		(connect_pads
			(clearance 0)
		)
		(min_thickness 0.25)
		(keepout
			(tracks not_allowed)
			(vias allowed)
			(pads allowed)
			(copperpour not_allowed)
			(footprints allowed)
		)
		(placement
			(enabled no)
			(sheetname "")
		)
		(fill yes
			(thermal_gap 0.5)
			(thermal_bridge_width 0.5)
			(island_removal_mode 0)
		)
		(polygon
			(pts
				(arc
					(start 404.241762 -432.56073)
					(mid 404.26408 -432.614612)
					(end 404.317962 -432.63693)
				)
				(arc
					(start 405.257762 -432.63693)
					(mid 405.311644 -432.614612)
					(end 405.333962 -432.56073)
				)
				(arc
					(start 405.333962 -430.019206)
					(mid 405.311644 -429.965324)
					(end 405.257762 -429.943006)
				)
				(arc
					(start 404.317962 -429.943006)
					(mid 404.26408 -429.965324)
					(end 404.241762 -430.019206)
				)
			)
		)
	)
	(zone
		(layers "F.Cu" "In2.Cu" "In4.Cu" "In6.Cu" "In11.Cu" "In13.Cu" "In15.Cu")
		(hatch none 0.5)
		(connect_pads
			(clearance 0)
		)
		(min_thickness 0.25)
		(keepout
			(tracks not_allowed)
			(vias allowed)
			(pads allowed)
			(copperpour not_allowed)
			(footprints allowed)
		)
		(placement
			(enabled no)
			(sheetname "")
		)
		(fill yes
			(thermal_gap 0.5)
			(thermal_bridge_width 0.5)
			(island_removal_mode 0)
		)
		(polygon
			(pts
				(arc
					(start 85.141816 -432.56073)
					(mid 85.164134 -432.614612)
					(end 85.218016 -432.63693)
				)
				(arc
					(start 86.157816 -432.63693)
					(mid 86.211698 -432.614612)
					(end 86.234016 -432.56073)
				)
				(arc
					(start 86.234016 -430.019206)
					(mid 86.211698 -429.965324)
					(end 86.157816 -429.943006)
				)
				(arc
					(start 85.218016 -429.943006)
					(mid 85.164134 -429.965324)
					(end 85.141816 -430.019206)
				)
			)
		)
	)
	(zone
		(layers "F.Cu" "In2.Cu" "In4.Cu" "In6.Cu" "In11.Cu" "In13.Cu" "In15.Cu")
		(hatch none 0.5)
		(connect_pads
			(clearance 0)
		)
		(min_thickness 0.25)
		(keepout
			(tracks not_allowed)
			(vias allowed)
			(pads allowed)
			(copperpour not_allowed)
			(footprints allowed)
		)
		(placement
			(enabled no)
			(sheetname "")
		)
		(fill yes
			(thermal_gap 0.5)
			(thermal_bridge_width 0.5)
			(island_removal_mode 0)
		)
		(polygon
			(pts
				(arc
					(start 68.14185 -432.56073)
					(mid 68.164168 -432.614612)
					(end 68.21805 -432.63693)
				)
				(arc
					(start 69.15785 -432.63693)
					(mid 69.211732 -432.614612)
					(end 69.23405 -432.56073)
				)
				(arc
					(start 69.23405 -430.019206)
					(mid 69.211732 -429.965324)
					(end 69.15785 -429.943006)
				)
				(arc
					(start 68.21805 -429.943006)
					(mid 68.164168 -429.965324)
					(end 68.14185 -430.019206)
				)
			)
		)
	)
	(zone
		(layers "F.Cu" "In2.Cu" "In4.Cu" "In6.Cu" "In11.Cu" "In13.Cu" "In15.Cu")
		(hatch none 0.5)
		(connect_pads
			(clearance 0)
		)
		(min_thickness 0.25)
		(keepout
			(tracks not_allowed)
			(vias allowed)
			(pads allowed)
			(copperpour not_allowed)
			(footprints allowed)
		)
		(placement
			(enabled no)
			(sheetname "")
		)
		(fill yes
			(thermal_gap 0.5)
			(thermal_bridge_width 0.5)
			(island_removal_mode 0)
		)
		(polygon
			(pts
				(arc
					(start 133.241796 -435.160674)
					(mid 133.264114 -435.214556)
					(end 133.317996 -435.236874)
				)
				(arc
					(start 134.257796 -435.236874)
					(mid 134.311678 -435.214556)
					(end 134.333996 -435.160674)
				)
				(arc
					(start 134.333996 -432.61915)
					(mid 134.311678 -432.565268)
					(end 134.257796 -432.54295)
				)
				(arc
					(start 133.317996 -432.54295)
					(mid 133.264114 -432.565268)
					(end 133.241796 -432.61915)
				)
			)
		)
	)
	(zone
		(layers "F.Cu" "In2.Cu" "In4.Cu" "In6.Cu" "In11.Cu" "In13.Cu" "In15.Cu")
		(hatch none 0.5)
		(connect_pads
			(clearance 0)
		)
		(min_thickness 0.25)
		(keepout
			(tracks not_allowed)
			(vias allowed)
			(pads allowed)
			(copperpour not_allowed)
			(footprints allowed)
		)
		(placement
			(enabled no)
			(sheetname "")
		)
		(fill yes
			(thermal_gap 0.5)
			(thermal_bridge_width 0.5)
			(island_removal_mode 0)
		)
		(polygon
			(pts
				(arc
					(start 79.141828 -431.560732)
					(mid 79.164146 -431.614614)
					(end 79.218028 -431.636932)
				)
				(arc
					(start 80.157828 -431.636932)
					(mid 80.21171 -431.614614)
					(end 80.234028 -431.560732)
				)
				(arc
					(start 80.234028 -429.019208)
					(mid 80.21171 -428.965326)
					(end 80.157828 -428.943008)
				)
				(arc
					(start 79.218028 -428.943008)
					(mid 79.164146 -428.965326)
					(end 79.141828 -429.019208)
				)
			)
		)
	)
	(zone
		(layers "F.Cu" "In2.Cu" "In4.Cu" "In6.Cu" "In11.Cu" "In13.Cu" "In15.Cu")
		(hatch none 0.5)
		(connect_pads
			(clearance 0)
		)
		(min_thickness 0.25)
		(keepout
			(tracks not_allowed)
			(vias allowed)
			(pads allowed)
			(copperpour not_allowed)
			(footprints allowed)
		)
		(placement
			(enabled no)
			(sheetname "")
		)
		(fill yes
			(thermal_gap 0.5)
			(thermal_bridge_width 0.5)
			(island_removal_mode 0)
		)
		(polygon
			(pts
				(arc
					(start 410.24175 -431.560732)
					(mid 410.264068 -431.614614)
					(end 410.31795 -431.636932)
				)
				(arc
					(start 411.25775 -431.636932)
					(mid 411.311632 -431.614614)
					(end 411.33395 -431.560732)
				)
				(arc
					(start 411.33395 -429.019208)
					(mid 411.311632 -428.965326)
					(end 411.25775 -428.943008)
				)
				(arc
					(start 410.31795 -428.943008)
					(mid 410.264068 -428.965326)
					(end 410.24175 -429.019208)
				)
			)
		)
	)
	(zone
		(layers "F.Cu" "In2.Cu" "In4.Cu" "In6.Cu" "In11.Cu" "In13.Cu" "In15.Cu")
		(hatch none 0.5)
		(connect_pads
			(clearance 0)
		)
		(min_thickness 0.25)
		(keepout
			(tracks not_allowed)
			(vias allowed)
			(pads allowed)
			(copperpour not_allowed)
			(footprints allowed)
		)
		(placement
			(enabled no)
			(sheetname "")
		)
		(fill yes
			(thermal_gap 0.5)
			(thermal_bridge_width 0.5)
			(island_removal_mode 0)
		)
		(polygon
			(pts
				(arc
					(start 389.241792 -435.160674)
					(mid 389.26411 -435.214556)
					(end 389.317992 -435.236874)
				)
				(arc
					(start 390.257792 -435.236874)
					(mid 390.311674 -435.214556)
					(end 390.333992 -435.160674)
				)
				(arc
					(start 390.333992 -432.61915)
					(mid 390.311674 -432.565268)
					(end 390.257792 -432.54295)
				)
				(arc
					(start 389.317992 -432.54295)
					(mid 389.26411 -432.565268)
					(end 389.241792 -432.61915)
				)
			)
		)
	)
	(zone
		(layers "F.Cu" "In2.Cu" "In4.Cu" "In6.Cu" "In11.Cu" "In13.Cu" "In15.Cu")
		(hatch none 0.5)
		(connect_pads
			(clearance 0)
		)
		(min_thickness 0.25)
		(keepout
			(tracks not_allowed)
			(vias allowed)
			(pads allowed)
			(copperpour not_allowed)
			(footprints allowed)
		)
		(placement
			(enabled no)
			(sheetname "")
		)
		(fill yes
			(thermal_gap 0.5)
			(thermal_bridge_width 0.5)
			(island_removal_mode 0)
		)
		(polygon
			(pts
				(arc
					(start 412.241746 -432.56073)
					(mid 412.264064 -432.614612)
					(end 412.317946 -432.63693)
				)
				(arc
					(start 413.257746 -432.63693)
					(mid 413.311628 -432.614612)
					(end 413.333946 -432.56073)
				)
				(arc
					(start 413.333946 -430.019206)
					(mid 413.311628 -429.965324)
					(end 413.257746 -429.943006)
				)
				(arc
					(start 412.317946 -429.943006)
					(mid 412.264064 -429.965324)
					(end 412.241746 -430.019206)
				)
			)
		)
	)
	(zone
		(layers "F.Cu" "In2.Cu" "In4.Cu" "In6.Cu" "In11.Cu" "In13.Cu" "In15.Cu")
		(hatch none 0.5)
		(connect_pads
			(clearance 0)
		)
		(min_thickness 0.25)
		(keepout
			(tracks not_allowed)
			(vias allowed)
			(pads allowed)
			(copperpour not_allowed)
			(footprints allowed)
		)
		(placement
			(enabled no)
			(sheetname "")
		)
		(fill yes
			(thermal_gap 0.5)
			(thermal_bridge_width 0.5)
			(island_removal_mode 0)
		)
		(polygon
			(pts
				(arc
					(start 391.241788 -432.56073)
					(mid 391.264106 -432.614612)
					(end 391.317988 -432.63693)
				)
				(arc
					(start 392.257788 -432.63693)
					(mid 392.31167 -432.614612)
					(end 392.333988 -432.56073)
				)
				(arc
					(start 392.333988 -430.019206)
					(mid 392.31167 -429.965324)
					(end 392.257788 -429.943006)
				)
				(arc
					(start 391.317988 -429.943006)
					(mid 391.264106 -429.965324)
					(end 391.241788 -430.019206)
				)
			)
		)
	)
	(zone
		(layers "F.Cu" "In2.Cu" "In4.Cu" "In6.Cu" "In11.Cu" "In13.Cu" "In15.Cu")
		(hatch none 0.5)
		(connect_pads
			(clearance 0)
		)
		(min_thickness 0.25)
		(keepout
			(tracks not_allowed)
			(vias allowed)
			(pads allowed)
			(copperpour not_allowed)
			(footprints allowed)
		)
		(placement
			(enabled no)
			(sheetname "")
		)
		(fill yes
			(thermal_gap 0.5)
			(thermal_bridge_width 0.5)
			(island_removal_mode 0)
		)
		(polygon
			(pts
				(arc
					(start 400.24177 -432.56073)
					(mid 400.264088 -432.614612)
					(end 400.31797 -432.63693)
				)
				(arc
					(start 401.25777 -432.63693)
					(mid 401.311652 -432.614612)
					(end 401.33397 -432.56073)
				)
				(arc
					(start 401.33397 -430.019206)
					(mid 401.311652 -429.965324)
					(end 401.25777 -429.943006)
				)
				(arc
					(start 400.31797 -429.943006)
					(mid 400.264088 -429.965324)
					(end 400.24177 -430.019206)
				)
			)
		)
	)
	(zone
		(layers "F.Cu" "In2.Cu" "In4.Cu" "In6.Cu" "In11.Cu" "In13.Cu" "In15.Cu")
		(hatch none 0.5)
		(connect_pads
			(clearance 0)
		)
		(min_thickness 0.25)
		(keepout
			(tracks not_allowed)
			(vias allowed)
			(pads allowed)
			(copperpour not_allowed)
			(footprints allowed)
		)
		(placement
			(enabled no)
			(sheetname "")
		)
		(fill yes
			(thermal_gap 0.5)
			(thermal_bridge_width 0.5)
			(island_removal_mode 0)
		)
		(polygon
			(pts
				(arc
					(start 72.141842 -432.56073)
					(mid 72.16416 -432.614612)
					(end 72.218042 -432.63693)
				)
				(arc
					(start 73.157842 -432.63693)
					(mid 73.211724 -432.614612)
					(end 73.234042 -432.56073)
				)
				(arc
					(start 73.234042 -430.019206)
					(mid 73.211724 -429.965324)
					(end 73.157842 -429.943006)
				)
				(arc
					(start 72.218042 -429.943006)
					(mid 72.16416 -429.965324)
					(end 72.141842 -430.019206)
				)
			)
		)
	)
	(zone
		(layers "F.Cu" "In2.Cu" "In4.Cu" "In6.Cu" "In11.Cu" "In13.Cu" "In15.Cu")
		(hatch none 0.5)
		(connect_pads
			(clearance 0)
		)
		(min_thickness 0.25)
		(keepout
			(tracks not_allowed)
			(vias allowed)
			(pads allowed)
			(copperpour not_allowed)
			(footprints allowed)
		)
		(placement
			(enabled no)
			(sheetname "")
		)
		(fill yes
			(thermal_gap 0.5)
			(thermal_bridge_width 0.5)
			(island_removal_mode 0)
		)
		(polygon
			(pts
				(arc
					(start 395.24178 -436.160672)
					(mid 395.264098 -436.214554)
					(end 395.31798 -436.236872)
				)
				(arc
					(start 396.25778 -436.236872)
					(mid 396.311662 -436.214554)
					(end 396.33398 -436.160672)
				)
				(arc
					(start 396.33398 -433.619148)
					(mid 396.311662 -433.565266)
					(end 396.25778 -433.542948)
				)
				(arc
					(start 395.31798 -433.542948)
					(mid 395.264098 -433.565266)
					(end 395.24178 -433.619148)
				)
			)
		)
	)
	(zone
		(layers "F.Cu" "In2.Cu" "In4.Cu" "In6.Cu" "In11.Cu" "In13.Cu" "In15.Cu")
		(hatch none 0.5)
		(connect_pads
			(clearance 0)
		)
		(min_thickness 0.25)
		(keepout
			(tracks not_allowed)
			(vias allowed)
			(pads allowed)
			(copperpour not_allowed)
			(footprints allowed)
		)
		(placement
			(enabled no)
			(sheetname "")
		)
		(fill yes
			(thermal_gap 0.5)
			(thermal_bridge_width 0.5)
			(island_removal_mode 0)
		)
		(polygon
			(pts
				(arc
					(start 345.141804 -432.56073)
					(mid 345.164122 -432.614612)
					(end 345.218004 -432.63693)
				)
				(arc
					(start 346.157804 -432.63693)
					(mid 346.211686 -432.614612)
					(end 346.234004 -432.56073)
				)
				(arc
					(start 346.234004 -430.019206)
					(mid 346.211686 -429.965324)
					(end 346.157804 -429.943006)
				)
				(arc
					(start 345.218004 -429.943006)
					(mid 345.164122 -429.965324)
					(end 345.141804 -430.019206)
				)
			)
		)
	)
	(zone
		(layers "F.Cu" "In2.Cu" "In4.Cu" "In6.Cu" "In11.Cu" "In13.Cu" "In15.Cu")
		(hatch none 0.5)
		(connect_pads
			(clearance 0)
		)
		(min_thickness 0.25)
		(keepout
			(tracks not_allowed)
			(vias allowed)
			(pads allowed)
			(copperpour not_allowed)
			(footprints allowed)
		)
		(placement
			(enabled no)
			(sheetname "")
		)
		(fill yes
			(thermal_gap 0.5)
			(thermal_bridge_width 0.5)
			(island_removal_mode 0)
		)
		(polygon
			(pts
				(arc
					(start 395.24178 -432.56073)
					(mid 395.264098 -432.614612)
					(end 395.31798 -432.63693)
				)
				(arc
					(start 396.25778 -432.63693)
					(mid 396.311662 -432.614612)
					(end 396.33398 -432.56073)
				)
				(arc
					(start 396.33398 -430.019206)
					(mid 396.311662 -429.965324)
					(end 396.25778 -429.943006)
				)
				(arc
					(start 395.31798 -429.943006)
					(mid 395.264098 -429.965324)
					(end 395.24178 -430.019206)
				)
			)
		)
	)
	(zone
		(layers "F.Cu" "In2.Cu" "In4.Cu" "In6.Cu" "In11.Cu" "In13.Cu" "In15.Cu")
		(hatch none 0.5)
		(connect_pads
			(clearance 0)
		)
		(min_thickness 0.25)
		(keepout
			(tracks not_allowed)
			(vias allowed)
			(pads allowed)
			(copperpour not_allowed)
			(footprints allowed)
		)
		(placement
			(enabled no)
			(sheetname "")
		)
		(fill yes
			(thermal_gap 0.5)
			(thermal_bridge_width 0.5)
			(island_removal_mode 0)
		)
		(polygon
			(pts
				(arc
					(start 393.241784 -435.160674)
					(mid 393.264102 -435.214556)
					(end 393.317984 -435.236874)
				)
				(arc
					(start 394.257784 -435.236874)
					(mid 394.311666 -435.214556)
					(end 394.333984 -435.160674)
				)
				(arc
					(start 394.333984 -432.61915)
					(mid 394.311666 -432.565268)
					(end 394.257784 -432.54295)
				)
				(arc
					(start 393.317984 -432.54295)
					(mid 393.264102 -432.565268)
					(end 393.241784 -432.61915)
				)
			)
		)
	)
	(zone
		(layers "F.Cu" "In2.Cu" "In4.Cu" "In6.Cu" "In11.Cu" "In13.Cu" "In15.Cu")
		(hatch none 0.5)
		(connect_pads
			(clearance 0)
		)
		(min_thickness 0.25)
		(keepout
			(tracks not_allowed)
			(vias allowed)
			(pads allowed)
			(copperpour not_allowed)
			(footprints allowed)
		)
		(placement
			(enabled no)
			(sheetname "")
		)
		(fill yes
			(thermal_gap 0.5)
			(thermal_bridge_width 0.5)
			(island_removal_mode 0)
		)
		(polygon
			(pts
				(arc
					(start 387.241796 -436.160672)
					(mid 387.264114 -436.214554)
					(end 387.317996 -436.236872)
				)
				(arc
					(start 388.257796 -436.236872)
					(mid 388.311678 -436.214554)
					(end 388.333996 -436.160672)
				)
				(arc
					(start 388.333996 -433.619148)
					(mid 388.311678 -433.565266)
					(end 388.257796 -433.542948)
				)
				(arc
					(start 387.317996 -433.542948)
					(mid 387.264114 -433.565266)
					(end 387.241796 -433.619148)
				)
			)
		)
	)
	(zone
		(layers "F.Cu" "In2.Cu" "In4.Cu" "In6.Cu" "In11.Cu" "In13.Cu" "In15.Cu")
		(hatch none 0.5)
		(connect_pads
			(clearance 0)
		)
		(min_thickness 0.25)
		(keepout
			(tracks not_allowed)
			(vias allowed)
			(pads allowed)
			(copperpour not_allowed)
			(footprints allowed)
		)
		(placement
			(enabled no)
			(sheetname "")
		)
		(fill yes
			(thermal_gap 0.5)
			(thermal_bridge_width 0.5)
			(island_removal_mode 0)
		)
		(polygon
			(pts
				(arc
					(start 333.141828 -432.56073)
					(mid 333.164146 -432.614612)
					(end 333.218028 -432.63693)
				)
				(arc
					(start 334.157828 -432.63693)
					(mid 334.21171 -432.614612)
					(end 334.234028 -432.56073)
				)
				(arc
					(start 334.234028 -430.019206)
					(mid 334.21171 -429.965324)
					(end 334.157828 -429.943006)
				)
				(arc
					(start 333.218028 -429.943006)
					(mid 333.164146 -429.965324)
					(end 333.141828 -430.019206)
				)
			)
		)
	)
	(zone
		(layers "F.Cu" "In2.Cu" "In4.Cu" "In6.Cu" "In11.Cu" "In13.Cu" "In15.Cu")
		(hatch none 0.5)
		(connect_pads
			(clearance 0)
		)
		(min_thickness 0.25)
		(keepout
			(tracks not_allowed)
			(vias allowed)
			(pads allowed)
			(copperpour not_allowed)
			(footprints allowed)
		)
		(placement
			(enabled no)
			(sheetname "")
		)
		(fill yes
			(thermal_gap 0.5)
			(thermal_bridge_width 0.5)
			(island_removal_mode 0)
		)
		(polygon
			(pts
				(arc
					(start 385.2418 -435.160674)
					(mid 385.264118 -435.214556)
					(end 385.318 -435.236874)
				)
				(arc
					(start 386.2578 -435.236874)
					(mid 386.311682 -435.214556)
					(end 386.334 -435.160674)
				)
				(arc
					(start 386.334 -432.61915)
					(mid 386.311682 -432.565268)
					(end 386.2578 -432.54295)
				)
				(arc
					(start 385.318 -432.54295)
					(mid 385.264118 -432.565268)
					(end 385.2418 -432.61915)
				)
			)
		)
	)
	(zone
		(layers "F.Cu" "In2.Cu" "In4.Cu" "In6.Cu" "In11.Cu" "In13.Cu" "In15.Cu")
		(hatch none 0.5)
		(connect_pads
			(clearance 0)
		)
		(min_thickness 0.25)
		(keepout
			(tracks not_allowed)
			(vias allowed)
			(pads allowed)
			(copperpour not_allowed)
			(footprints allowed)
		)
		(placement
			(enabled no)
			(sheetname "")
		)
		(fill yes
			(thermal_gap 0.5)
			(thermal_bridge_width 0.5)
			(island_removal_mode 0)
		)
		(polygon
			(pts
				(arc
					(start 64.141858 -432.56073)
					(mid 64.164176 -432.614612)
					(end 64.218058 -432.63693)
				)
				(arc
					(start 65.157858 -432.63693)
					(mid 65.21174 -432.614612)
					(end 65.234058 -432.56073)
				)
				(arc
					(start 65.234058 -430.019206)
					(mid 65.21174 -429.965324)
					(end 65.157858 -429.943006)
				)
				(arc
					(start 64.218058 -429.943006)
					(mid 64.164176 -429.965324)
					(end 64.141858 -430.019206)
				)
			)
		)
	)
	(zone
		(layers "F.Cu" "In2.Cu" "In4.Cu" "In6.Cu" "In11.Cu" "In13.Cu" "In15.Cu")
		(hatch none 0.5)
		(connect_pads
			(clearance 0)
		)
		(min_thickness 0.25)
		(keepout
			(tracks not_allowed)
			(vias allowed)
			(pads allowed)
			(copperpour not_allowed)
			(footprints allowed)
		)
		(placement
			(enabled no)
			(sheetname "")
		)
		(fill yes
			(thermal_gap 0.5)
			(thermal_bridge_width 0.5)
			(island_removal_mode 0)
		)
		(polygon
			(pts
				(arc
					(start 58.14187 -431.560732)
					(mid 58.164188 -431.614614)
					(end 58.21807 -431.636932)
				)
				(arc
					(start 59.15787 -431.636932)
					(mid 59.211752 -431.614614)
					(end 59.23407 -431.560732)
				)
				(arc
					(start 59.23407 -429.019208)
					(mid 59.211752 -428.965326)
					(end 59.15787 -428.943008)
				)
				(arc
					(start 58.21807 -428.943008)
					(mid 58.164188 -428.965326)
					(end 58.14187 -429.019208)
				)
			)
		)
	)
	(zone
		(layers "F.Cu" "In2.Cu" "In4.Cu" "In6.Cu" "In11.Cu" "In13.Cu" "In15.Cu")
		(hatch none 0.5)
		(connect_pads
			(clearance 0)
		)
		(min_thickness 0.25)
		(keepout
			(tracks not_allowed)
			(vias allowed)
			(pads allowed)
			(copperpour not_allowed)
			(footprints allowed)
		)
		(placement
			(enabled no)
			(sheetname "")
		)
		(fill yes
			(thermal_gap 0.5)
			(thermal_bridge_width 0.5)
			(island_removal_mode 0)
		)
		(polygon
			(pts
				(arc
					(start 383.241804 -436.160672)
					(mid 383.264122 -436.214554)
					(end 383.318004 -436.236872)
				)
				(arc
					(start 384.257804 -436.236872)
					(mid 384.311686 -436.214554)
					(end 384.334004 -436.160672)
				)
				(arc
					(start 384.334004 -433.619148)
					(mid 384.311686 -433.565266)
					(end 384.257804 -433.542948)
				)
				(arc
					(start 383.318004 -433.542948)
					(mid 383.264122 -433.565266)
					(end 383.241804 -433.619148)
				)
			)
		)
	)
	(zone
		(layers "F.Cu" "In2.Cu" "In4.Cu" "In6.Cu" "In11.Cu" "In13.Cu" "In15.Cu")
		(hatch none 0.5)
		(connect_pads
			(clearance 0)
		)
		(min_thickness 0.25)
		(keepout
			(tracks not_allowed)
			(vias allowed)
			(pads allowed)
			(copperpour not_allowed)
			(footprints allowed)
		)
		(placement
			(enabled no)
			(sheetname "")
		)
		(fill yes
			(thermal_gap 0.5)
			(thermal_bridge_width 0.5)
			(island_removal_mode 0)
		)
		(polygon
			(pts
				(arc
					(start 81.141824 -432.56073)
					(mid 81.164142 -432.614612)
					(end 81.218024 -432.63693)
				)
				(arc
					(start 82.157824 -432.63693)
					(mid 82.211706 -432.614612)
					(end 82.234024 -432.56073)
				)
				(arc
					(start 82.234024 -430.019206)
					(mid 82.211706 -429.965324)
					(end 82.157824 -429.943006)
				)
				(arc
					(start 81.218024 -429.943006)
					(mid 81.164142 -429.965324)
					(end 81.141824 -430.019206)
				)
			)
		)
	)
	(zone
		(layers "F.Cu" "In2.Cu" "In4.Cu" "In6.Cu" "In11.Cu" "In13.Cu" "In15.Cu")
		(hatch none 0.5)
		(connect_pads
			(clearance 0)
		)
		(min_thickness 0.25)
		(keepout
			(tracks not_allowed)
			(vias allowed)
			(pads allowed)
			(copperpour not_allowed)
			(footprints allowed)
		)
		(placement
			(enabled no)
			(sheetname "")
		)
		(fill yes
			(thermal_gap 0.5)
			(thermal_bridge_width 0.5)
			(island_removal_mode 0)
		)
		(polygon
			(pts
				(arc
					(start 381.241808 -431.560732)
					(mid 381.264126 -431.614614)
					(end 381.318008 -431.636932)
				)
				(arc
					(start 382.257808 -431.636932)
					(mid 382.31169 -431.614614)
					(end 382.334008 -431.560732)
				)
				(arc
					(start 382.334008 -429.019208)
					(mid 382.31169 -428.965326)
					(end 382.257808 -428.943008)
				)
				(arc
					(start 381.318008 -428.943008)
					(mid 381.264126 -428.965326)
					(end 381.241808 -429.019208)
				)
			)
		)
	)
	(zone
		(layers "F.Cu" "In2.Cu" "In4.Cu" "In6.Cu" "In11.Cu" "In13.Cu" "In15.Cu")
		(hatch none 0.5)
		(connect_pads
			(clearance 0)
		)
		(min_thickness 0.25)
		(keepout
			(tracks not_allowed)
			(vias allowed)
			(pads allowed)
			(copperpour not_allowed)
			(footprints allowed)
		)
		(placement
			(enabled no)
			(sheetname "")
		)
		(fill yes
			(thermal_gap 0.5)
			(thermal_bridge_width 0.5)
			(island_removal_mode 0)
		)
		(polygon
			(pts
				(arc
					(start 89.141808 -432.56073)
					(mid 89.164126 -432.614612)
					(end 89.218008 -432.63693)
				)
				(arc
					(start 90.157808 -432.63693)
					(mid 90.21169 -432.614612)
					(end 90.234008 -432.56073)
				)
				(arc
					(start 90.234008 -430.019206)
					(mid 90.21169 -429.965324)
					(end 90.157808 -429.943006)
				)
				(arc
					(start 89.218008 -429.943006)
					(mid 89.164126 -429.965324)
					(end 89.141808 -430.019206)
				)
			)
		)
	)
	(zone
		(layers "F.Cu" "In2.Cu" "In4.Cu" "In6.Cu" "In11.Cu" "In13.Cu" "In15.Cu")
		(hatch none 0.5)
		(connect_pads
			(clearance 0)
		)
		(min_thickness 0.25)
		(keepout
			(tracks not_allowed)
			(vias allowed)
			(pads allowed)
			(copperpour not_allowed)
			(footprints allowed)
		)
		(placement
			(enabled no)
			(sheetname "")
		)
		(fill yes
			(thermal_gap 0.5)
			(thermal_bridge_width 0.5)
			(island_removal_mode 0)
		)
		(polygon
			(pts
				(arc
					(start 341.141812 -432.56073)
					(mid 341.16413 -432.614612)
					(end 341.218012 -432.63693)
				)
				(arc
					(start 342.157812 -432.63693)
					(mid 342.211694 -432.614612)
					(end 342.234012 -432.56073)
				)
				(arc
					(start 342.234012 -430.019206)
					(mid 342.211694 -429.965324)
					(end 342.157812 -429.943006)
				)
				(arc
					(start 341.218012 -429.943006)
					(mid 341.16413 -429.965324)
					(end 341.141812 -430.019206)
				)
			)
		)
	)
	(zone
		(layers "F.Cu" "In2.Cu" "In4.Cu" "In6.Cu" "In11.Cu" "In13.Cu" "In15.Cu")
		(hatch none 0.5)
		(connect_pads
			(clearance 0)
		)
		(min_thickness 0.25)
		(keepout
			(tracks not_allowed)
			(vias allowed)
			(pads allowed)
			(copperpour not_allowed)
			(footprints allowed)
		)
		(placement
			(enabled no)
			(sheetname "")
		)
		(fill yes
			(thermal_gap 0.5)
			(thermal_bridge_width 0.5)
			(island_removal_mode 0)
		)
		(polygon
			(pts
				(arc
					(start 139.241784 -436.160672)
					(mid 139.264102 -436.214554)
					(end 139.317984 -436.236872)
				)
				(arc
					(start 140.257784 -436.236872)
					(mid 140.311666 -436.214554)
					(end 140.333984 -436.160672)
				)
				(arc
					(start 140.333984 -433.619148)
					(mid 140.311666 -433.565266)
					(end 140.257784 -433.542948)
				)
				(arc
					(start 139.317984 -433.542948)
					(mid 139.264102 -433.565266)
					(end 139.241784 -433.619148)
				)
			)
		)
	)
	(zone
		(layers "F.Cu" "In2.Cu" "In4.Cu" "In6.Cu" "In11.Cu" "In13.Cu" "In15.Cu")
		(hatch none 0.5)
		(connect_pads
			(clearance 0)
		)
		(min_thickness 0.25)
		(keepout
			(tracks not_allowed)
			(vias allowed)
			(pads allowed)
			(copperpour not_allowed)
			(footprints allowed)
		)
		(placement
			(enabled no)
			(sheetname "")
		)
		(fill yes
			(thermal_gap 0.5)
			(thermal_bridge_width 0.5)
			(island_removal_mode 0)
		)
		(polygon
			(pts
				(arc
					(start 135.241792 -436.160672)
					(mid 135.26411 -436.214554)
					(end 135.317992 -436.236872)
				)
				(arc
					(start 136.257792 -436.236872)
					(mid 136.311674 -436.214554)
					(end 136.333992 -436.160672)
				)
				(arc
					(start 136.333992 -433.619148)
					(mid 136.311674 -433.565266)
					(end 136.257792 -433.542948)
				)
				(arc
					(start 135.317992 -433.542948)
					(mid 135.26411 -433.565266)
					(end 135.241792 -433.619148)
				)
			)
		)
	)
	(zone
		(layers "F.Cu" "In2.Cu" "In4.Cu" "In6.Cu" "In11.Cu" "In13.Cu" "In15.Cu")
		(hatch none 0.5)
		(connect_pads
			(clearance 0)
		)
		(min_thickness 0.25)
		(keepout
			(tracks not_allowed)
			(vias allowed)
			(pads allowed)
			(copperpour not_allowed)
			(footprints allowed)
		)
		(placement
			(enabled no)
			(sheetname "")
		)
		(fill yes
			(thermal_gap 0.5)
			(thermal_bridge_width 0.5)
			(island_removal_mode 0)
		)
		(polygon
			(pts
				(arc
					(start 62.141862 -431.560732)
					(mid 62.16418 -431.614614)
					(end 62.218062 -431.636932)
				)
				(arc
					(start 63.157862 -431.636932)
					(mid 63.211744 -431.614614)
					(end 63.234062 -431.560732)
				)
				(arc
					(start 63.234062 -429.019208)
					(mid 63.211744 -428.965326)
					(end 63.157862 -428.943008)
				)
				(arc
					(start 62.218062 -428.943008)
					(mid 62.16418 -428.965326)
					(end 62.141862 -429.019208)
				)
			)
		)
	)
	(zone
		(layers "F.Cu" "In2.Cu" "In4.Cu" "In6.Cu" "In11.Cu" "In13.Cu" "In15.Cu")
		(hatch none 0.5)
		(connect_pads
			(clearance 0)
		)
		(min_thickness 0.25)
		(keepout
			(tracks not_allowed)
			(vias allowed)
			(pads allowed)
			(copperpour not_allowed)
			(footprints allowed)
		)
		(placement
			(enabled no)
			(sheetname "")
		)
		(fill yes
			(thermal_gap 0.5)
			(thermal_bridge_width 0.5)
			(island_removal_mode 0)
		)
		(polygon
			(pts
				(arc
					(start 127.241808 -436.160672)
					(mid 127.264126 -436.214554)
					(end 127.318008 -436.236872)
				)
				(arc
					(start 128.257808 -436.236872)
					(mid 128.31169 -436.214554)
					(end 128.334008 -436.160672)
				)
				(arc
					(start 128.334008 -433.619148)
					(mid 128.31169 -433.565266)
					(end 128.257808 -433.542948)
				)
				(arc
					(start 127.318008 -433.542948)
					(mid 127.264126 -433.565266)
					(end 127.241808 -433.619148)
				)
			)
		)
	)
	(zone
		(layers "F.Cu" "In2.Cu" "In4.Cu" "In6.Cu" "In11.Cu" "In13.Cu" "In15.Cu")
		(hatch none 0.5)
		(connect_pads
			(clearance 0)
		)
		(min_thickness 0.25)
		(keepout
			(tracks not_allowed)
			(vias allowed)
			(pads allowed)
			(copperpour not_allowed)
			(footprints allowed)
		)
		(placement
			(enabled no)
			(sheetname "")
		)
		(fill yes
			(thermal_gap 0.5)
			(thermal_bridge_width 0.5)
			(island_removal_mode 0)
		)
		(polygon
			(pts
				(arc
					(start 66.141854 -431.560732)
					(mid 66.164172 -431.614614)
					(end 66.218054 -431.636932)
				)
				(arc
					(start 67.157854 -431.636932)
					(mid 67.211736 -431.614614)
					(end 67.234054 -431.560732)
				)
				(arc
					(start 67.234054 -429.019208)
					(mid 67.211736 -428.965326)
					(end 67.157854 -428.943008)
				)
				(arc
					(start 66.218054 -428.943008)
					(mid 66.164172 -428.965326)
					(end 66.141854 -429.019208)
				)
			)
		)
	)
	(zone
		(layers "F.Cu" "In2.Cu" "In4.Cu" "In6.Cu" "In11.Cu" "In13.Cu" "In15.Cu")
		(hatch none 0.5)
		(connect_pads
			(clearance 0)
		)
		(min_thickness 0.25)
		(keepout
			(tracks not_allowed)
			(vias allowed)
			(pads allowed)
			(copperpour not_allowed)
			(footprints allowed)
		)
		(placement
			(enabled no)
			(sheetname "")
		)
		(fill yes
			(thermal_gap 0.5)
			(thermal_bridge_width 0.5)
			(island_removal_mode 0)
		)
		(polygon
			(pts
				(arc
					(start 385.2418 -431.560732)
					(mid 385.264118 -431.614614)
					(end 385.318 -431.636932)
				)
				(arc
					(start 386.2578 -431.636932)
					(mid 386.311682 -431.614614)
					(end 386.334 -431.560732)
				)
				(arc
					(start 386.334 -429.019208)
					(mid 386.311682 -428.965326)
					(end 386.2578 -428.943008)
				)
				(arc
					(start 385.318 -428.943008)
					(mid 385.264118 -428.965326)
					(end 385.2418 -429.019208)
				)
			)
		)
	)
	(zone
		(layers "F.Cu" "In2.Cu" "In4.Cu" "In6.Cu" "In11.Cu" "In13.Cu" "In15.Cu")
		(hatch none 0.5)
		(connect_pads
			(clearance 0)
		)
		(min_thickness 0.25)
		(keepout
			(tracks not_allowed)
			(vias allowed)
			(pads allowed)
			(copperpour not_allowed)
			(footprints allowed)
		)
		(placement
			(enabled no)
			(sheetname "")
		)
		(fill yes
			(thermal_gap 0.5)
			(thermal_bridge_width 0.5)
			(island_removal_mode 0)
		)
		(polygon
			(pts
				(arc
					(start 331.141832 -431.560732)
					(mid 331.16415 -431.614614)
					(end 331.218032 -431.636932)
				)
				(arc
					(start 332.157832 -431.636932)
					(mid 332.211714 -431.614614)
					(end 332.234032 -431.560732)
				)
				(arc
					(start 332.234032 -429.019208)
					(mid 332.211714 -428.965326)
					(end 332.157832 -428.943008)
				)
				(arc
					(start 331.218032 -428.943008)
					(mid 331.16415 -428.965326)
					(end 331.141832 -429.019208)
				)
			)
		)
	)
	(zone
		(layers "F.Cu" "In2.Cu" "In4.Cu" "In6.Cu" "In11.Cu" "In13.Cu" "In15.Cu")
		(hatch none 0.5)
		(connect_pads
			(clearance 0)
		)
		(min_thickness 0.25)
		(keepout
			(tracks not_allowed)
			(vias allowed)
			(pads allowed)
			(copperpour not_allowed)
			(footprints allowed)
		)
		(placement
			(enabled no)
			(sheetname "")
		)
		(fill yes
			(thermal_gap 0.5)
			(thermal_bridge_width 0.5)
			(island_removal_mode 0)
		)
		(polygon
			(pts
				(arc
					(start 75.141836 -431.560732)
					(mid 75.164154 -431.614614)
					(end 75.218036 -431.636932)
				)
				(arc
					(start 76.157836 -431.636932)
					(mid 76.211718 -431.614614)
					(end 76.234036 -431.560732)
				)
				(arc
					(start 76.234036 -429.019208)
					(mid 76.211718 -428.965326)
					(end 76.157836 -428.943008)
				)
				(arc
					(start 75.218036 -428.943008)
					(mid 75.164154 -428.965326)
					(end 75.141836 -429.019208)
				)
			)
		)
	)
	(zone
		(layers "F.Cu" "In2.Cu" "In4.Cu" "In6.Cu" "In11.Cu" "In13.Cu" "In15.Cu")
		(hatch none 0.5)
		(connect_pads
			(clearance 0)
		)
		(min_thickness 0.25)
		(keepout
			(tracks not_allowed)
			(vias allowed)
			(pads allowed)
			(copperpour not_allowed)
			(footprints allowed)
		)
		(placement
			(enabled no)
			(sheetname "")
		)
		(fill yes
			(thermal_gap 0.5)
			(thermal_bridge_width 0.5)
			(island_removal_mode 0)
		)
		(polygon
			(pts
				(arc
					(start 83.14182 -431.560732)
					(mid 83.164138 -431.614614)
					(end 83.21802 -431.636932)
				)
				(arc
					(start 84.15782 -431.636932)
					(mid 84.211702 -431.614614)
					(end 84.23402 -431.560732)
				)
				(arc
					(start 84.23402 -429.019208)
					(mid 84.211702 -428.965326)
					(end 84.15782 -428.943008)
				)
				(arc
					(start 83.21802 -428.943008)
					(mid 83.164138 -428.965326)
					(end 83.14182 -429.019208)
				)
			)
		)
	)
	(zone
		(layers "F.Cu" "In2.Cu" "In4.Cu" "In6.Cu" "In11.Cu" "In13.Cu" "In15.Cu")
		(hatch none 0.5)
		(connect_pads
			(clearance 0)
		)
		(min_thickness 0.25)
		(keepout
			(tracks not_allowed)
			(vias allowed)
			(pads allowed)
			(copperpour not_allowed)
			(footprints allowed)
		)
		(placement
			(enabled no)
			(sheetname "")
		)
		(fill yes
			(thermal_gap 0.5)
			(thermal_bridge_width 0.5)
			(island_removal_mode 0)
		)
		(polygon
			(pts
				(arc
					(start 335.141824 -431.560732)
					(mid 335.164142 -431.614614)
					(end 335.218024 -431.636932)
				)
				(arc
					(start 336.157824 -431.636932)
					(mid 336.211706 -431.614614)
					(end 336.234024 -431.560732)
				)
				(arc
					(start 336.234024 -429.019208)
					(mid 336.211706 -428.965326)
					(end 336.157824 -428.943008)
				)
				(arc
					(start 335.218024 -428.943008)
					(mid 335.164142 -428.965326)
					(end 335.141824 -429.019208)
				)
			)
		)
	)
	(zone
		(layers "F.Cu" "In2.Cu" "In4.Cu" "In6.Cu" "In11.Cu" "In13.Cu" "In15.Cu")
		(hatch none 0.5)
		(connect_pads
			(clearance 0)
		)
		(min_thickness 0.25)
		(keepout
			(tracks not_allowed)
			(vias allowed)
			(pads allowed)
			(copperpour not_allowed)
			(footprints allowed)
		)
		(placement
			(enabled no)
			(sheetname "")
		)
		(fill yes
			(thermal_gap 0.5)
			(thermal_bridge_width 0.5)
			(island_removal_mode 0)
		)
		(polygon
			(pts
				(arc
					(start 406.241758 -431.560732)
					(mid 406.264076 -431.614614)
					(end 406.317958 -431.636932)
				)
				(arc
					(start 407.257758 -431.636932)
					(mid 407.31164 -431.614614)
					(end 407.333958 -431.560732)
				)
				(arc
					(start 407.333958 -429.019208)
					(mid 407.31164 -428.965326)
					(end 407.257758 -428.943008)
				)
				(arc
					(start 406.317958 -428.943008)
					(mid 406.264076 -428.965326)
					(end 406.241758 -429.019208)
				)
			)
		)
	)
	(zone
		(layers "F.Cu" "In2.Cu" "In4.Cu" "In6.Cu" "In11.Cu" "In13.Cu" "In15.Cu")
		(hatch none 0.5)
		(connect_pads
			(clearance 0)
		)
		(min_thickness 0.25)
		(keepout
			(tracks not_allowed)
			(vias allowed)
			(pads allowed)
			(copperpour not_allowed)
			(footprints allowed)
		)
		(placement
			(enabled no)
			(sheetname "")
		)
		(fill yes
			(thermal_gap 0.5)
			(thermal_bridge_width 0.5)
			(island_removal_mode 0)
		)
		(polygon
			(pts
				(arc
					(start 343.141808 -431.560732)
					(mid 343.164126 -431.614614)
					(end 343.218008 -431.636932)
				)
				(arc
					(start 344.157808 -431.636932)
					(mid 344.21169 -431.614614)
					(end 344.234008 -431.560732)
				)
				(arc
					(start 344.234008 -429.019208)
					(mid 344.21169 -428.965326)
					(end 344.157808 -428.943008)
				)
				(arc
					(start 343.218008 -428.943008)
					(mid 343.164126 -428.965326)
					(end 343.141808 -429.019208)
				)
			)
		)
	)
	(zone
		(layers "F.Cu" "In2.Cu" "In4.Cu" "In6.Cu" "In11.Cu" "In13.Cu" "In15.Cu")
		(hatch none 0.5)
		(connect_pads
			(clearance 0)
		)
		(min_thickness 0.25)
		(keepout
			(tracks not_allowed)
			(vias allowed)
			(pads allowed)
			(copperpour not_allowed)
			(footprints allowed)
		)
		(placement
			(enabled no)
			(sheetname "")
		)
		(fill yes
			(thermal_gap 0.5)
			(thermal_bridge_width 0.5)
			(island_removal_mode 0)
		)
		(polygon
			(pts
				(arc
					(start 60.141866 -432.56073)
					(mid 60.164184 -432.614612)
					(end 60.218066 -432.63693)
				)
				(arc
					(start 61.157866 -432.63693)
					(mid 61.211748 -432.614612)
					(end 61.234066 -432.56073)
				)
				(arc
					(start 61.234066 -430.019206)
					(mid 61.211748 -429.965324)
					(end 61.157866 -429.943006)
				)
				(arc
					(start 60.218066 -429.943006)
					(mid 60.164184 -429.965324)
					(end 60.141866 -430.019206)
				)
			)
		)
	)
	(zone
		(layers "F.Cu" "In2.Cu" "In4.Cu" "In6.Cu" "In11.Cu" "In13.Cu" "In15.Cu")
		(hatch none 0.5)
		(connect_pads
			(clearance 0)
		)
		(min_thickness 0.25)
		(keepout
			(tracks not_allowed)
			(vias allowed)
			(pads allowed)
			(copperpour not_allowed)
			(footprints allowed)
		)
		(placement
			(enabled no)
			(sheetname "")
		)
		(fill yes
			(thermal_gap 0.5)
			(thermal_bridge_width 0.5)
			(island_removal_mode 0)
		)
		(polygon
			(pts
				(arc
					(start 393.241784 -431.560732)
					(mid 393.264102 -431.614614)
					(end 393.317984 -431.636932)
				)
				(arc
					(start 394.257784 -431.636932)
					(mid 394.311666 -431.614614)
					(end 394.333984 -431.560732)
				)
				(arc
					(start 394.333984 -429.019208)
					(mid 394.311666 -428.965326)
					(end 394.257784 -428.943008)
				)
				(arc
					(start 393.317984 -428.943008)
					(mid 393.264102 -428.965326)
					(end 393.241784 -429.019208)
				)
			)
		)
	)
	(zone
		(layers "F.Cu" "In2.Cu" "In4.Cu" "In6.Cu" "In11.Cu" "In13.Cu" "In15.Cu")
		(hatch none 0.5)
		(connect_pads
			(clearance 0)
		)
		(min_thickness 0.25)
		(keepout
			(tracks not_allowed)
			(vias allowed)
			(pads allowed)
			(copperpour not_allowed)
			(footprints allowed)
		)
		(placement
			(enabled no)
			(sheetname "")
		)
		(fill yes
			(thermal_gap 0.5)
			(thermal_bridge_width 0.5)
			(island_removal_mode 0)
		)
		(polygon
			(pts
				(arc
					(start 131.2418 -436.160672)
					(mid 131.264118 -436.214554)
					(end 131.318 -436.236872)
				)
				(arc
					(start 132.2578 -436.236872)
					(mid 132.311682 -436.214554)
					(end 132.334 -436.160672)
				)
				(arc
					(start 132.334 -433.619148)
					(mid 132.311682 -433.565266)
					(end 132.2578 -433.542948)
				)
				(arc
					(start 131.318 -433.542948)
					(mid 131.264118 -433.565266)
					(end 131.2418 -433.619148)
				)
			)
		)
	)
	(zone
		(layers "F.Cu" "In2.Cu" "In4.Cu" "In6.Cu" "In11.Cu" "In13.Cu" "In15.Cu")
		(hatch none 0.5)
		(connect_pads
			(clearance 0)
		)
		(min_thickness 0.25)
		(keepout
			(tracks not_allowed)
			(vias allowed)
			(pads allowed)
			(copperpour not_allowed)
			(footprints allowed)
		)
		(placement
			(enabled no)
			(sheetname "")
		)
		(fill yes
			(thermal_gap 0.5)
			(thermal_bridge_width 0.5)
			(island_removal_mode 0)
		)
		(polygon
			(pts
				(arc
					(start 87.141812 -431.560732)
					(mid 87.16413 -431.614614)
					(end 87.218012 -431.636932)
				)
				(arc
					(start 88.157812 -431.636932)
					(mid 88.211694 -431.614614)
					(end 88.234012 -431.560732)
				)
				(arc
					(start 88.234012 -429.019208)
					(mid 88.211694 -428.965326)
					(end 88.157812 -428.943008)
				)
				(arc
					(start 87.218012 -428.943008)
					(mid 87.16413 -428.965326)
					(end 87.141812 -429.019208)
				)
			)
		)
	)
	(zone
		(layers "F.Cu" "In2.Cu" "In4.Cu" "In6.Cu" "In11.Cu" "In13.Cu" "In15.Cu")
		(hatch none 0.5)
		(connect_pads
			(clearance 0)
		)
		(min_thickness 0.25)
		(keepout
			(tracks not_allowed)
			(vias allowed)
			(pads allowed)
			(copperpour not_allowed)
			(footprints allowed)
		)
		(placement
			(enabled no)
			(sheetname "")
		)
		(fill yes
			(thermal_gap 0.5)
			(thermal_bridge_width 0.5)
			(island_removal_mode 0)
		)
		(polygon
			(pts
				(arc
					(start 387.241796 -432.56073)
					(mid 387.264114 -432.614612)
					(end 387.317996 -432.63693)
				)
				(arc
					(start 388.257796 -432.63693)
					(mid 388.311678 -432.614612)
					(end 388.333996 -432.56073)
				)
				(arc
					(start 388.333996 -430.019206)
					(mid 388.311678 -429.965324)
					(end 388.257796 -429.943006)
				)
				(arc
					(start 387.317996 -429.943006)
					(mid 387.264114 -429.965324)
					(end 387.241796 -430.019206)
				)
			)
		)
	)
	(zone
		(layers "F.Cu" "In2.Cu" "In4.Cu" "In6.Cu" "In11.Cu" "In13.Cu" "In15.Cu")
		(hatch none 0.5)
		(connect_pads
			(clearance 0)
		)
		(min_thickness 0.25)
		(keepout
			(tracks not_allowed)
			(vias allowed)
			(pads allowed)
			(copperpour not_allowed)
			(footprints allowed)
		)
		(placement
			(enabled no)
			(sheetname "")
		)
		(fill yes
			(thermal_gap 0.5)
			(thermal_bridge_width 0.5)
			(island_removal_mode 0)
		)
		(polygon
			(pts
				(arc
					(start 402.241766 -431.560732)
					(mid 402.264084 -431.614614)
					(end 402.317966 -431.636932)
				)
				(arc
					(start 403.257766 -431.636932)
					(mid 403.311648 -431.614614)
					(end 403.333966 -431.560732)
				)
				(arc
					(start 403.333966 -429.019208)
					(mid 403.311648 -428.965326)
					(end 403.257766 -428.943008)
				)
				(arc
					(start 402.317966 -428.943008)
					(mid 402.264084 -428.965326)
					(end 402.241766 -429.019208)
				)
			)
		)
	)
	(zone
		(layers "F.Cu" "In2.Cu" "In4.Cu" "In6.Cu" "In11.Cu" "In13.Cu" "In15.Cu")
		(hatch none 0.5)
		(connect_pads
			(clearance 0)
		)
		(min_thickness 0.25)
		(keepout
			(tracks not_allowed)
			(vias allowed)
			(pads allowed)
			(copperpour not_allowed)
			(footprints allowed)
		)
		(placement
			(enabled no)
			(sheetname "")
		)
		(fill yes
			(thermal_gap 0.5)
			(thermal_bridge_width 0.5)
			(island_removal_mode 0)
		)
		(polygon
			(pts
				(arc
					(start 391.241788 -436.160672)
					(mid 391.264106 -436.214554)
					(end 391.317988 -436.236872)
				)
				(arc
					(start 392.257788 -436.236872)
					(mid 392.31167 -436.214554)
					(end 392.333988 -436.160672)
				)
				(arc
					(start 392.333988 -433.619148)
					(mid 392.31167 -433.565266)
					(end 392.257788 -433.542948)
				)
				(arc
					(start 391.317988 -433.542948)
					(mid 391.264106 -433.565266)
					(end 391.241788 -433.619148)
				)
			)
		)
	)
	(zone
		(layers "F.Cu" "In2.Cu" "In4.Cu" "In6.Cu" "In11.Cu" "In13.Cu" "In15.Cu")
		(hatch none 0.5)
		(connect_pads
			(clearance 0)
		)
		(min_thickness 0.25)
		(keepout
			(tracks not_allowed)
			(vias allowed)
			(pads allowed)
			(copperpour not_allowed)
			(footprints allowed)
		)
		(placement
			(enabled no)
			(sheetname "")
		)
		(fill yes
			(thermal_gap 0.5)
			(thermal_bridge_width 0.5)
			(island_removal_mode 0)
		)
		(polygon
			(pts
				(arc
					(start 383.241804 -432.56073)
					(mid 383.264122 -432.614612)
					(end 383.318004 -432.63693)
				)
				(arc
					(start 384.257804 -432.63693)
					(mid 384.311686 -432.614612)
					(end 384.334004 -432.56073)
				)
				(arc
					(start 384.334004 -430.019206)
					(mid 384.311686 -429.965324)
					(end 384.257804 -429.943006)
				)
				(arc
					(start 383.318004 -429.943006)
					(mid 383.264122 -429.965324)
					(end 383.241804 -430.019206)
				)
			)
		)
	)
	(zone
		(layers "F.Cu" "In2.Cu" "In4.Cu" "In6.Cu" "In11.Cu" "In13.Cu" "In15.Cu")
		(hatch none 0.5)
		(connect_pads
			(clearance 0)
		)
		(min_thickness 0.25)
		(keepout
			(tracks not_allowed)
			(vias allowed)
			(pads allowed)
			(copperpour not_allowed)
			(footprints allowed)
		)
		(placement
			(enabled no)
			(sheetname "")
		)
		(fill yes
			(thermal_gap 0.5)
			(thermal_bridge_width 0.5)
			(island_removal_mode 0)
		)
		(polygon
			(pts
				(arc
					(start 125.241812 -435.160674)
					(mid 125.26413 -435.214556)
					(end 125.318012 -435.236874)
				)
				(arc
					(start 126.257812 -435.236874)
					(mid 126.311694 -435.214556)
					(end 126.334012 -435.160674)
				)
				(arc
					(start 126.334012 -432.61915)
					(mid 126.311694 -432.565268)
					(end 126.257812 -432.54295)
				)
				(arc
					(start 125.318012 -432.54295)
					(mid 125.26413 -432.565268)
					(end 125.241812 -432.61915)
				)
			)
		)
	)
	(zone
		(layers "F.Cu" "In2.Cu" "In4.Cu" "In6.Cu" "In11.Cu" "In13.Cu" "In15.Cu")
		(hatch none 0.5)
		(connect_pads
			(clearance 0)
		)
		(min_thickness 0.25)
		(keepout
			(tracks not_allowed)
			(vias allowed)
			(pads allowed)
			(copperpour not_allowed)
			(footprints allowed)
		)
		(placement
			(enabled no)
			(sheetname "")
		)
		(fill yes
			(thermal_gap 0.5)
			(thermal_bridge_width 0.5)
			(island_removal_mode 0)
		)
		(polygon
			(pts
				(arc
					(start 77.141832 -432.56073)
					(mid 77.16415 -432.614612)
					(end 77.218032 -432.63693)
				)
				(arc
					(start 78.157832 -432.63693)
					(mid 78.211714 -432.614612)
					(end 78.234032 -432.56073)
				)
				(arc
					(start 78.234032 -430.019206)
					(mid 78.211714 -429.965324)
					(end 78.157832 -429.943006)
				)
				(arc
					(start 77.218032 -429.943006)
					(mid 77.16415 -429.965324)
					(end 77.141832 -430.019206)
				)
			)
		)
	)
	(zone
		(layers "F.Cu" "In2.Cu" "In4.Cu" "In6.Cu" "In11.Cu" "In13.Cu" "In15.Cu")
		(hatch none 0.5)
		(connect_pads
			(clearance 0)
		)
		(min_thickness 0.25)
		(keepout
			(tracks not_allowed)
			(vias allowed)
			(pads allowed)
			(copperpour not_allowed)
			(footprints allowed)
		)
		(placement
			(enabled no)
			(sheetname "")
		)
		(fill yes
			(thermal_gap 0.5)
			(thermal_bridge_width 0.5)
			(island_removal_mode 0)
		)
		(polygon
			(pts
				(arc
					(start 408.241754 -432.56073)
					(mid 408.264072 -432.614612)
					(end 408.317954 -432.63693)
				)
				(arc
					(start 409.257754 -432.63693)
					(mid 409.311636 -432.614612)
					(end 409.333954 -432.56073)
				)
				(arc
					(start 409.333954 -430.019206)
					(mid 409.311636 -429.965324)
					(end 409.257754 -429.943006)
				)
				(arc
					(start 408.317954 -429.943006)
					(mid 408.264072 -429.965324)
					(end 408.241754 -430.019206)
				)
			)
		)
	)
	(zone
		(layers "F.Cu" "In2.Cu" "In4.Cu" "In6.Cu" "In11.Cu" "In13.Cu" "In15.Cu")
		(hatch none 0.5)
		(connect_pads
			(clearance 0)
		)
		(min_thickness 0.25)
		(keepout
			(tracks not_allowed)
			(vias allowed)
			(pads allowed)
			(copperpour not_allowed)
			(footprints allowed)
		)
		(placement
			(enabled no)
			(sheetname "")
		)
		(fill yes
			(thermal_gap 0.5)
			(thermal_bridge_width 0.5)
			(island_removal_mode 0)
		)
		(polygon
			(pts
				(arc
					(start 137.241788 -435.160674)
					(mid 137.264106 -435.214556)
					(end 137.317988 -435.236874)
				)
				(arc
					(start 138.257788 -435.236874)
					(mid 138.31167 -435.214556)
					(end 138.333988 -435.160674)
				)
				(arc
					(start 138.333988 -432.61915)
					(mid 138.31167 -432.565268)
					(end 138.257788 -432.54295)
				)
				(arc
					(start 137.317988 -432.54295)
					(mid 137.264106 -432.565268)
					(end 137.241788 -432.61915)
				)
			)
		)
	)
	(zone
		(layers "F.Cu" "In2.Cu" "In4.Cu" "In6.Cu" "In11.Cu" "In13.Cu" "In15.Cu")
		(hatch none 0.5)
		(connect_pads
			(clearance 0)
		)
		(min_thickness 0.25)
		(keepout
			(tracks not_allowed)
			(vias allowed)
			(pads allowed)
			(copperpour not_allowed)
			(footprints allowed)
		)
		(placement
			(enabled no)
			(sheetname "")
		)
		(fill yes
			(thermal_gap 0.5)
			(thermal_bridge_width 0.5)
			(island_removal_mode 0)
		)
		(polygon
			(pts
				(arc
					(start 398.241774 -431.560732)
					(mid 398.264092 -431.614614)
					(end 398.317974 -431.636932)
				)
				(arc
					(start 399.257774 -431.636932)
					(mid 399.311656 -431.614614)
					(end 399.333974 -431.560732)
				)
				(arc
					(start 399.333974 -429.019208)
					(mid 399.311656 -428.965326)
					(end 399.257774 -428.943008)
				)
				(arc
					(start 398.317974 -428.943008)
					(mid 398.264092 -428.965326)
					(end 398.241774 -429.019208)
				)
			)
		)
	)
	(zone
		(layers "F.Cu" "In2.Cu" "In4.Cu" "In6.Cu" "In11.Cu" "In15.Cu")
		(hatch none 0.5)
		(connect_pads
			(clearance 0)
		)
		(min_thickness 0.25)
		(keepout
			(tracks not_allowed)
			(vias allowed)
			(pads allowed)
			(copperpour not_allowed)
			(footprints allowed)
		)
		(placement
			(enabled no)
			(sheetname "")
		)
		(fill yes
			(thermal_gap 0.5)
			(thermal_bridge_width 0.5)
			(island_removal_mode 0)
		)
		(polygon
			(pts
				(arc
					(start 339.141816 -427.96079)
					(mid 339.164134 -428.014672)
					(end 339.218016 -428.03699)
				)
				(arc
					(start 340.157816 -428.03699)
					(mid 340.211698 -428.014672)
					(end 340.234016 -427.96079)
				)
				(arc
					(start 340.234016 -425.419266)
					(mid 340.211698 -425.365384)
					(end 340.157816 -425.343066)
				)
				(arc
					(start 339.218016 -425.343066)
					(mid 339.164134 -425.365384)
					(end 339.141816 -425.419266)
				)
			)
		)
	)
	(zone
		(layers "F.Cu" "In2.Cu" "In4.Cu" "In6.Cu" "In11.Cu" "In15.Cu")
		(hatch none 0.5)
		(connect_pads
			(clearance 0)
		)
		(min_thickness 0.25)
		(keepout
			(tracks not_allowed)
			(vias allowed)
			(pads allowed)
			(copperpour not_allowed)
			(footprints allowed)
		)
		(placement
			(enabled no)
			(sheetname "")
		)
		(fill yes
			(thermal_gap 0.5)
			(thermal_bridge_width 0.5)
			(island_removal_mode 0)
		)
		(polygon
			(pts
				(arc
					(start 314.141866 -427.96079)
					(mid 314.164184 -428.014672)
					(end 314.218066 -428.03699)
				)
				(arc
					(start 315.157866 -428.03699)
					(mid 315.211748 -428.014672)
					(end 315.234066 -427.96079)
				)
				(arc
					(start 315.234066 -425.419266)
					(mid 315.211748 -425.365384)
					(end 315.157866 -425.343066)
				)
				(arc
					(start 314.218066 -425.343066)
					(mid 314.164184 -425.365384)
					(end 314.141866 -425.419266)
				)
			)
		)
	)
	(zone
		(layers "F.Cu" "In2.Cu" "In4.Cu" "In6.Cu" "In11.Cu" "In15.Cu")
		(hatch none 0.5)
		(connect_pads
			(clearance 0)
		)
		(min_thickness 0.25)
		(keepout
			(tracks not_allowed)
			(vias allowed)
			(pads allowed)
			(copperpour not_allowed)
			(footprints allowed)
		)
		(placement
			(enabled no)
			(sheetname "")
		)
		(fill yes
			(thermal_gap 0.5)
			(thermal_bridge_width 0.5)
			(island_removal_mode 0)
		)
		(polygon
			(pts
				(arc
					(start 129.241804 -427.96079)
					(mid 129.264122 -428.014672)
					(end 129.318004 -428.03699)
				)
				(arc
					(start 130.257804 -428.03699)
					(mid 130.311686 -428.014672)
					(end 130.334004 -427.96079)
				)
				(arc
					(start 130.334004 -425.419266)
					(mid 130.311686 -425.365384)
					(end 130.257804 -425.343066)
				)
				(arc
					(start 129.318004 -425.343066)
					(mid 129.264122 -425.365384)
					(end 129.241804 -425.419266)
				)
			)
		)
	)
	(zone
		(layers "F.Cu" "In2.Cu" "In4.Cu" "In6.Cu" "In11.Cu" "In15.Cu")
		(hatch none 0.5)
		(connect_pads
			(clearance 0)
		)
		(min_thickness 0.25)
		(keepout
			(tracks not_allowed)
			(vias allowed)
			(pads allowed)
			(copperpour not_allowed)
			(footprints allowed)
		)
		(placement
			(enabled no)
			(sheetname "")
		)
		(fill yes
			(thermal_gap 0.5)
			(thermal_bridge_width 0.5)
			(island_removal_mode 0)
		)
		(polygon
			(pts
				(arc
					(start 335.141824 -427.96079)
					(mid 335.164142 -428.014672)
					(end 335.218024 -428.03699)
				)
				(arc
					(start 336.157824 -428.03699)
					(mid 336.211706 -428.014672)
					(end 336.234024 -427.96079)
				)
				(arc
					(start 336.234024 -425.419266)
					(mid 336.211706 -425.365384)
					(end 336.157824 -425.343066)
				)
				(arc
					(start 335.218024 -425.343066)
					(mid 335.164142 -425.365384)
					(end 335.141824 -425.419266)
				)
			)
		)
	)
	(zone
		(layers "F.Cu" "In2.Cu" "In4.Cu" "In6.Cu" "In11.Cu" "In15.Cu")
		(hatch none 0.5)
		(connect_pads
			(clearance 0)
		)
		(min_thickness 0.25)
		(keepout
			(tracks not_allowed)
			(vias allowed)
			(pads allowed)
			(copperpour not_allowed)
			(footprints allowed)
		)
		(placement
			(enabled no)
			(sheetname "")
		)
		(fill yes
			(thermal_gap 0.5)
			(thermal_bridge_width 0.5)
			(island_removal_mode 0)
		)
		(polygon
			(pts
				(arc
					(start 87.141812 -427.96079)
					(mid 87.16413 -428.014672)
					(end 87.218012 -428.03699)
				)
				(arc
					(start 88.157812 -428.03699)
					(mid 88.211694 -428.014672)
					(end 88.234012 -427.96079)
				)
				(arc
					(start 88.234012 -425.419266)
					(mid 88.211694 -425.365384)
					(end 88.157812 -425.343066)
				)
				(arc
					(start 87.218012 -425.343066)
					(mid 87.16413 -425.365384)
					(end 87.141812 -425.419266)
				)
			)
		)
	)
	(zone
		(layers "F.Cu" "In2.Cu" "In4.Cu" "In6.Cu" "In11.Cu" "In15.Cu")
		(hatch none 0.5)
		(connect_pads
			(clearance 0)
		)
		(min_thickness 0.25)
		(keepout
			(tracks not_allowed)
			(vias allowed)
			(pads allowed)
			(copperpour not_allowed)
			(footprints allowed)
		)
		(placement
			(enabled no)
			(sheetname "")
		)
		(fill yes
			(thermal_gap 0.5)
			(thermal_bridge_width 0.5)
			(island_removal_mode 0)
		)
		(polygon
			(pts
				(arc
					(start 70.141846 -427.96079)
					(mid 70.164164 -428.014672)
					(end 70.218046 -428.03699)
				)
				(arc
					(start 71.157846 -428.03699)
					(mid 71.211728 -428.014672)
					(end 71.234046 -427.96079)
				)
				(arc
					(start 71.234046 -425.419266)
					(mid 71.211728 -425.365384)
					(end 71.157846 -425.343066)
				)
				(arc
					(start 70.218046 -425.343066)
					(mid 70.164164 -425.365384)
					(end 70.141846 -425.419266)
				)
			)
		)
	)
	(zone
		(layers "F.Cu" "In2.Cu" "In4.Cu" "In6.Cu" "In11.Cu" "In15.Cu")
		(hatch none 0.5)
		(connect_pads
			(clearance 0)
		)
		(min_thickness 0.25)
		(keepout
			(tracks not_allowed)
			(vias allowed)
			(pads allowed)
			(copperpour not_allowed)
			(footprints allowed)
		)
		(placement
			(enabled no)
			(sheetname "")
		)
		(fill yes
			(thermal_gap 0.5)
			(thermal_bridge_width 0.5)
			(island_removal_mode 0)
		)
		(polygon
			(pts
				(arc
					(start 75.141836 -427.96079)
					(mid 75.164154 -428.014672)
					(end 75.218036 -428.03699)
				)
				(arc
					(start 76.157836 -428.03699)
					(mid 76.211718 -428.014672)
					(end 76.234036 -427.96079)
				)
				(arc
					(start 76.234036 -425.419266)
					(mid 76.211718 -425.365384)
					(end 76.157836 -425.343066)
				)
				(arc
					(start 75.218036 -425.343066)
					(mid 75.164154 -425.365384)
					(end 75.141836 -425.419266)
				)
			)
		)
	)
	(zone
		(layers "F.Cu" "In2.Cu" "In4.Cu" "In6.Cu" "In11.Cu" "In15.Cu")
		(hatch none 0.5)
		(connect_pads
			(clearance 0)
		)
		(min_thickness 0.25)
		(keepout
			(tracks not_allowed)
			(vias allowed)
			(pads allowed)
			(copperpour not_allowed)
			(footprints allowed)
		)
		(placement
			(enabled no)
			(sheetname "")
		)
		(fill yes
			(thermal_gap 0.5)
			(thermal_bridge_width 0.5)
			(island_removal_mode 0)
		)
		(polygon
			(pts
				(arc
					(start 343.141808 -427.96079)
					(mid 343.164126 -428.014672)
					(end 343.218008 -428.03699)
				)
				(arc
					(start 344.157808 -428.03699)
					(mid 344.21169 -428.014672)
					(end 344.234008 -427.96079)
				)
				(arc
					(start 344.234008 -425.419266)
					(mid 344.21169 -425.365384)
					(end 344.157808 -425.343066)
				)
				(arc
					(start 343.218008 -425.343066)
					(mid 343.164126 -425.365384)
					(end 343.141808 -425.419266)
				)
			)
		)
	)
	(zone
		(layers "F.Cu" "In2.Cu" "In4.Cu" "In6.Cu" "In11.Cu" "In15.Cu")
		(hatch none 0.5)
		(connect_pads
			(clearance 0)
		)
		(min_thickness 0.25)
		(keepout
			(tracks not_allowed)
			(vias allowed)
			(pads allowed)
			(copperpour not_allowed)
			(footprints allowed)
		)
		(placement
			(enabled no)
			(sheetname "")
		)
		(fill yes
			(thermal_gap 0.5)
			(thermal_bridge_width 0.5)
			(island_removal_mode 0)
		)
		(polygon
			(pts
				(arc
					(start 331.141832 -427.96079)
					(mid 331.16415 -428.014672)
					(end 331.218032 -428.03699)
				)
				(arc
					(start 332.157832 -428.03699)
					(mid 332.211714 -428.014672)
					(end 332.234032 -427.96079)
				)
				(arc
					(start 332.234032 -425.419266)
					(mid 332.211714 -425.365384)
					(end 332.157832 -425.343066)
				)
				(arc
					(start 331.218032 -425.343066)
					(mid 331.16415 -425.365384)
					(end 331.141832 -425.419266)
				)
			)
		)
	)
	(zone
		(layers "F.Cu" "In2.Cu" "In4.Cu" "In6.Cu" "In11.Cu" "In15.Cu")
		(hatch none 0.5)
		(connect_pads
			(clearance 0)
		)
		(min_thickness 0.25)
		(keepout
			(tracks not_allowed)
			(vias allowed)
			(pads allowed)
			(copperpour not_allowed)
			(footprints allowed)
		)
		(placement
			(enabled no)
			(sheetname "")
		)
		(fill yes
			(thermal_gap 0.5)
			(thermal_bridge_width 0.5)
			(island_removal_mode 0)
		)
		(polygon
			(pts
				(arc
					(start 146.24177 -427.96079)
					(mid 146.264088 -428.014672)
					(end 146.31797 -428.03699)
				)
				(arc
					(start 147.25777 -428.03699)
					(mid 147.311652 -428.014672)
					(end 147.33397 -427.96079)
				)
				(arc
					(start 147.33397 -425.419266)
					(mid 147.311652 -425.365384)
					(end 147.25777 -425.343066)
				)
				(arc
					(start 146.31797 -425.343066)
					(mid 146.264088 -425.365384)
					(end 146.24177 -425.419266)
				)
			)
		)
	)
	(zone
		(layers "F.Cu" "In2.Cu" "In4.Cu" "In6.Cu" "In11.Cu" "In15.Cu")
		(hatch none 0.5)
		(connect_pads
			(clearance 0)
		)
		(min_thickness 0.25)
		(keepout
			(tracks not_allowed)
			(vias allowed)
			(pads allowed)
			(copperpour not_allowed)
			(footprints allowed)
		)
		(placement
			(enabled no)
			(sheetname "")
		)
		(fill yes
			(thermal_gap 0.5)
			(thermal_bridge_width 0.5)
			(island_removal_mode 0)
		)
		(polygon
			(pts
				(arc
					(start 322.14185 -427.96079)
					(mid 322.164168 -428.014672)
					(end 322.21805 -428.03699)
				)
				(arc
					(start 323.15785 -428.03699)
					(mid 323.211732 -428.014672)
					(end 323.23405 -427.96079)
				)
				(arc
					(start 323.23405 -425.419266)
					(mid 323.211732 -425.365384)
					(end 323.15785 -425.343066)
				)
				(arc
					(start 322.21805 -425.343066)
					(mid 322.164168 -425.365384)
					(end 322.14185 -425.419266)
				)
			)
		)
	)
	(zone
		(layers "F.Cu" "In2.Cu" "In4.Cu" "In6.Cu" "In11.Cu" "In15.Cu")
		(hatch none 0.5)
		(connect_pads
			(clearance 0)
		)
		(min_thickness 0.25)
		(keepout
			(tracks not_allowed)
			(vias allowed)
			(pads allowed)
			(copperpour not_allowed)
			(footprints allowed)
		)
		(placement
			(enabled no)
			(sheetname "")
		)
		(fill yes
			(thermal_gap 0.5)
			(thermal_bridge_width 0.5)
			(island_removal_mode 0)
		)
		(polygon
			(pts
				(arc
					(start 142.241778 -427.96079)
					(mid 142.264096 -428.014672)
					(end 142.317978 -428.03699)
				)
				(arc
					(start 143.257778 -428.03699)
					(mid 143.31166 -428.014672)
					(end 143.333978 -427.96079)
				)
				(arc
					(start 143.333978 -425.419266)
					(mid 143.31166 -425.365384)
					(end 143.257778 -425.343066)
				)
				(arc
					(start 142.317978 -425.343066)
					(mid 142.264096 -425.365384)
					(end 142.241778 -425.419266)
				)
			)
		)
	)
	(zone
		(layers "F.Cu" "In2.Cu" "In4.Cu" "In6.Cu" "In11.Cu" "In15.Cu")
		(hatch none 0.5)
		(connect_pads
			(clearance 0)
		)
		(min_thickness 0.25)
		(keepout
			(tracks not_allowed)
			(vias allowed)
			(pads allowed)
			(copperpour not_allowed)
			(footprints allowed)
		)
		(placement
			(enabled no)
			(sheetname "")
		)
		(fill yes
			(thermal_gap 0.5)
			(thermal_bridge_width 0.5)
			(island_removal_mode 0)
		)
		(polygon
			(pts
				(arc
					(start 125.241812 -427.96079)
					(mid 125.26413 -428.014672)
					(end 125.318012 -428.03699)
				)
				(arc
					(start 126.257812 -428.03699)
					(mid 126.311694 -428.014672)
					(end 126.334012 -427.96079)
				)
				(arc
					(start 126.334012 -425.419266)
					(mid 126.311694 -425.365384)
					(end 126.257812 -425.343066)
				)
				(arc
					(start 125.318012 -425.343066)
					(mid 125.26413 -425.365384)
					(end 125.241812 -425.419266)
				)
			)
		)
	)
	(zone
		(layers "F.Cu" "In2.Cu" "In4.Cu" "In6.Cu" "In11.Cu" "In15.Cu")
		(hatch none 0.5)
		(connect_pads
			(clearance 0)
		)
		(min_thickness 0.25)
		(keepout
			(tracks not_allowed)
			(vias allowed)
			(pads allowed)
			(copperpour not_allowed)
			(footprints allowed)
		)
		(placement
			(enabled no)
			(sheetname "")
		)
		(fill yes
			(thermal_gap 0.5)
			(thermal_bridge_width 0.5)
			(island_removal_mode 0)
		)
		(polygon
			(pts
				(arc
					(start 83.14182 -427.96079)
					(mid 83.164138 -428.014672)
					(end 83.21802 -428.03699)
				)
				(arc
					(start 84.15782 -428.03699)
					(mid 84.211702 -428.014672)
					(end 84.23402 -427.96079)
				)
				(arc
					(start 84.23402 -425.419266)
					(mid 84.211702 -425.365384)
					(end 84.15782 -425.343066)
				)
				(arc
					(start 83.21802 -425.343066)
					(mid 83.164138 -425.365384)
					(end 83.14182 -425.419266)
				)
			)
		)
	)
	(zone
		(layers "F.Cu" "In2.Cu" "In4.Cu" "In6.Cu" "In11.Cu" "In15.Cu")
		(hatch none 0.5)
		(connect_pads
			(clearance 0)
		)
		(min_thickness 0.25)
		(keepout
			(tracks not_allowed)
			(vias allowed)
			(pads allowed)
			(copperpour not_allowed)
			(footprints allowed)
		)
		(placement
			(enabled no)
			(sheetname "")
		)
		(fill yes
			(thermal_gap 0.5)
			(thermal_bridge_width 0.5)
			(island_removal_mode 0)
		)
		(polygon
			(pts
				(arc
					(start 79.141828 -427.96079)
					(mid 79.164146 -428.014672)
					(end 79.218028 -428.03699)
				)
				(arc
					(start 80.157828 -428.03699)
					(mid 80.21171 -428.014672)
					(end 80.234028 -427.96079)
				)
				(arc
					(start 80.234028 -425.419266)
					(mid 80.21171 -425.365384)
					(end 80.157828 -425.343066)
				)
				(arc
					(start 79.218028 -425.343066)
					(mid 79.164146 -425.365384)
					(end 79.141828 -425.419266)
				)
			)
		)
	)
	(zone
		(layers "F.Cu" "In2.Cu" "In4.Cu" "In6.Cu" "In11.Cu" "In15.Cu")
		(hatch none 0.5)
		(connect_pads
			(clearance 0)
		)
		(min_thickness 0.25)
		(keepout
			(tracks not_allowed)
			(vias allowed)
			(pads allowed)
			(copperpour not_allowed)
			(footprints allowed)
		)
		(placement
			(enabled no)
			(sheetname "")
		)
		(fill yes
			(thermal_gap 0.5)
			(thermal_bridge_width 0.5)
			(island_removal_mode 0)
		)
		(polygon
			(pts
				(arc
					(start 66.141854 -427.96079)
					(mid 66.164172 -428.014672)
					(end 66.218054 -428.03699)
				)
				(arc
					(start 67.157854 -428.03699)
					(mid 67.211736 -428.014672)
					(end 67.234054 -427.96079)
				)
				(arc
					(start 67.234054 -425.419266)
					(mid 67.211736 -425.365384)
					(end 67.157854 -425.343066)
				)
				(arc
					(start 66.218054 -425.343066)
					(mid 66.164172 -425.365384)
					(end 66.141854 -425.419266)
				)
			)
		)
	)
	(zone
		(layers "F.Cu" "In2.Cu" "In4.Cu" "In6.Cu" "In11.Cu" "In15.Cu")
		(hatch none 0.5)
		(connect_pads
			(clearance 0)
		)
		(min_thickness 0.25)
		(keepout
			(tracks not_allowed)
			(vias allowed)
			(pads allowed)
			(copperpour not_allowed)
			(footprints allowed)
		)
		(placement
			(enabled no)
			(sheetname "")
		)
		(fill yes
			(thermal_gap 0.5)
			(thermal_bridge_width 0.5)
			(island_removal_mode 0)
		)
		(polygon
			(pts
				(arc
					(start 150.241762 -427.96079)
					(mid 150.26408 -428.014672)
					(end 150.317962 -428.03699)
				)
				(arc
					(start 151.257762 -428.03699)
					(mid 151.311644 -428.014672)
					(end 151.333962 -427.96079)
				)
				(arc
					(start 151.333962 -425.419266)
					(mid 151.311644 -425.365384)
					(end 151.257762 -425.343066)
				)
				(arc
					(start 150.317962 -425.343066)
					(mid 150.26408 -425.365384)
					(end 150.241762 -425.419266)
				)
			)
		)
	)
	(zone
		(layers "F.Cu" "In2.Cu" "In4.Cu" "In6.Cu" "In11.Cu" "In15.Cu")
		(hatch none 0.5)
		(connect_pads
			(clearance 0)
		)
		(min_thickness 0.25)
		(keepout
			(tracks not_allowed)
			(vias allowed)
			(pads allowed)
			(copperpour not_allowed)
			(footprints allowed)
		)
		(placement
			(enabled no)
			(sheetname "")
		)
		(fill yes
			(thermal_gap 0.5)
			(thermal_bridge_width 0.5)
			(island_removal_mode 0)
		)
		(polygon
			(pts
				(arc
					(start 62.141862 -427.96079)
					(mid 62.16418 -428.014672)
					(end 62.218062 -428.03699)
				)
				(arc
					(start 63.157862 -428.03699)
					(mid 63.211744 -428.014672)
					(end 63.234062 -427.96079)
				)
				(arc
					(start 63.234062 -425.419266)
					(mid 63.211744 -425.365384)
					(end 63.157862 -425.343066)
				)
				(arc
					(start 62.218062 -425.343066)
					(mid 62.16418 -425.365384)
					(end 62.141862 -425.419266)
				)
			)
		)
	)
	(zone
		(layers "F.Cu" "In2.Cu" "In4.Cu" "In6.Cu" "In11.Cu" "In15.Cu")
		(hatch none 0.5)
		(connect_pads
			(clearance 0)
		)
		(min_thickness 0.25)
		(keepout
			(tracks not_allowed)
			(vias allowed)
			(pads allowed)
			(copperpour not_allowed)
			(footprints allowed)
		)
		(placement
			(enabled no)
			(sheetname "")
		)
		(fill yes
			(thermal_gap 0.5)
			(thermal_bridge_width 0.5)
			(island_removal_mode 0)
		)
		(polygon
			(pts
				(arc
					(start 326.141842 -427.96079)
					(mid 326.16416 -428.014672)
					(end 326.218042 -428.03699)
				)
				(arc
					(start 327.157842 -428.03699)
					(mid 327.211724 -428.014672)
					(end 327.234042 -427.96079)
				)
				(arc
					(start 327.234042 -425.419266)
					(mid 327.211724 -425.365384)
					(end 327.157842 -425.343066)
				)
				(arc
					(start 326.218042 -425.343066)
					(mid 326.16416 -425.365384)
					(end 326.141842 -425.419266)
				)
			)
		)
	)
	(zone
		(layers "F.Cu" "In2.Cu" "In4.Cu" "In6.Cu" "In11.Cu" "In15.Cu")
		(hatch none 0.5)
		(connect_pads
			(clearance 0)
		)
		(min_thickness 0.25)
		(keepout
			(tracks not_allowed)
			(vias allowed)
			(pads allowed)
			(copperpour not_allowed)
			(footprints allowed)
		)
		(placement
			(enabled no)
			(sheetname "")
		)
		(fill yes
			(thermal_gap 0.5)
			(thermal_bridge_width 0.5)
			(island_removal_mode 0)
		)
		(polygon
			(pts
				(arc
					(start 58.14187 -427.96079)
					(mid 58.164188 -428.014672)
					(end 58.21807 -428.03699)
				)
				(arc
					(start 59.15787 -428.03699)
					(mid 59.211752 -428.014672)
					(end 59.23407 -427.96079)
				)
				(arc
					(start 59.23407 -425.419266)
					(mid 59.211752 -425.365384)
					(end 59.15787 -425.343066)
				)
				(arc
					(start 58.21807 -425.343066)
					(mid 58.164188 -425.365384)
					(end 58.14187 -425.419266)
				)
			)
		)
	)
	(zone
		(layers "F.Cu" "In2.Cu" "In4.Cu" "In6.Cu" "In11.Cu" "In15.Cu")
		(hatch none 0.5)
		(connect_pads
			(clearance 0)
		)
		(min_thickness 0.25)
		(keepout
			(tracks not_allowed)
			(vias allowed)
			(pads allowed)
			(copperpour not_allowed)
			(footprints allowed)
		)
		(placement
			(enabled no)
			(sheetname "")
		)
		(fill yes
			(thermal_gap 0.5)
			(thermal_bridge_width 0.5)
			(island_removal_mode 0)
		)
		(polygon
			(pts
				(arc
					(start 137.241788 -427.96079)
					(mid 137.264106 -428.014672)
					(end 137.317988 -428.03699)
				)
				(arc
					(start 138.257788 -428.03699)
					(mid 138.31167 -428.014672)
					(end 138.333988 -427.96079)
				)
				(arc
					(start 138.333988 -425.419266)
					(mid 138.31167 -425.365384)
					(end 138.257788 -425.343066)
				)
				(arc
					(start 137.317988 -425.343066)
					(mid 137.264106 -425.365384)
					(end 137.241788 -425.419266)
				)
			)
		)
	)
	(zone
		(layers "F.Cu" "In2.Cu" "In4.Cu" "In6.Cu" "In11.Cu" "In15.Cu")
		(hatch none 0.5)
		(connect_pads
			(clearance 0)
		)
		(min_thickness 0.25)
		(keepout
			(tracks not_allowed)
			(vias allowed)
			(pads allowed)
			(copperpour not_allowed)
			(footprints allowed)
		)
		(placement
			(enabled no)
			(sheetname "")
		)
		(fill yes
			(thermal_gap 0.5)
			(thermal_bridge_width 0.5)
			(island_removal_mode 0)
		)
		(polygon
			(pts
				(arc
					(start 133.241796 -427.96079)
					(mid 133.264114 -428.014672)
					(end 133.317996 -428.03699)
				)
				(arc
					(start 134.257796 -428.03699)
					(mid 134.311678 -428.014672)
					(end 134.333996 -427.96079)
				)
				(arc
					(start 134.333996 -425.419266)
					(mid 134.311678 -425.365384)
					(end 134.257796 -425.343066)
				)
				(arc
					(start 133.317996 -425.343066)
					(mid 133.264114 -425.365384)
					(end 133.241796 -425.419266)
				)
			)
		)
	)
	(zone
		(layers "F.Cu" "In2.Cu" "In4.Cu" "In6.Cu" "In11.Cu" "In15.Cu")
		(hatch none 0.5)
		(connect_pads
			(clearance 0)
		)
		(min_thickness 0.25)
		(keepout
			(tracks not_allowed)
			(vias allowed)
			(pads allowed)
			(copperpour not_allowed)
			(footprints allowed)
		)
		(placement
			(enabled no)
			(sheetname "")
		)
		(fill yes
			(thermal_gap 0.5)
			(thermal_bridge_width 0.5)
			(island_removal_mode 0)
		)
		(polygon
			(pts
				(arc
					(start 318.141858 -427.96079)
					(mid 318.164176 -428.014672)
					(end 318.218058 -428.03699)
				)
				(arc
					(start 319.157858 -428.03699)
					(mid 319.21174 -428.014672)
					(end 319.234058 -427.96079)
				)
				(arc
					(start 319.234058 -425.419266)
					(mid 319.21174 -425.365384)
					(end 319.157858 -425.343066)
				)
				(arc
					(start 318.218058 -425.343066)
					(mid 318.164176 -425.365384)
					(end 318.141858 -425.419266)
				)
			)
		)
	)
	(zone
		(layers "F.Cu" "In4.Cu" "In6.Cu" "In10.Cu" "In11.Cu" "In13.Cu" "In15.Cu")
		(hatch none 0.5)
		(connect_pads
			(clearance 0)
		)
		(min_thickness 0.25)
		(keepout
			(tracks not_allowed)
			(vias allowed)
			(pads allowed)
			(copperpour not_allowed)
			(footprints allowed)
		)
		(placement
			(enabled no)
			(sheetname "")
		)
		(fill yes
			(thermal_gap 0.5)
			(thermal_bridge_width 0.5)
			(island_removal_mode 0)
		)
		(polygon
			(pts
				(arc
					(start 154.241754 -435.160674)
					(mid 154.264072 -435.214556)
					(end 154.317954 -435.236874)
				)
				(arc
					(start 155.257754 -435.236874)
					(mid 155.311636 -435.214556)
					(end 155.333954 -435.160674)
				)
				(arc
					(start 155.333954 -432.61915)
					(mid 155.311636 -432.565268)
					(end 155.257754 -432.54295)
				)
				(arc
					(start 154.317954 -432.54295)
					(mid 154.264072 -432.565268)
					(end 154.241754 -432.61915)
				)
			)
		)
	)
	(zone
		(layers "F.Cu" "In4.Cu" "In6.Cu" "In10.Cu" "In11.Cu" "In13.Cu" "In15.Cu")
		(hatch none 0.5)
		(connect_pads
			(clearance 0)
		)
		(min_thickness 0.25)
		(keepout
			(tracks not_allowed)
			(vias allowed)
			(pads allowed)
			(copperpour not_allowed)
			(footprints allowed)
		)
		(placement
			(enabled no)
			(sheetname "")
		)
		(fill yes
			(thermal_gap 0.5)
			(thermal_bridge_width 0.5)
			(island_removal_mode 0)
		)
		(polygon
			(pts
				(arc
					(start 156.24175 -436.160672)
					(mid 156.264068 -436.214554)
					(end 156.31795 -436.236872)
				)
				(arc
					(start 157.25775 -436.236872)
					(mid 157.311632 -436.214554)
					(end 157.33395 -436.160672)
				)
				(arc
					(start 157.33395 -433.619148)
					(mid 157.311632 -433.565266)
					(end 157.25775 -433.542948)
				)
				(arc
					(start 156.31795 -433.542948)
					(mid 156.264068 -433.565266)
					(end 156.24175 -433.619148)
				)
			)
		)
	)
	(zone
		(layers "F.Cu" "In4.Cu" "In6.Cu" "In11.Cu" "In13.Cu" "In14.Cu" "In15.Cu")
		(hatch none 0.5)
		(connect_pads
			(clearance 0)
		)
		(min_thickness 0.25)
		(keepout
			(tracks not_allowed)
			(vias allowed)
			(pads allowed)
			(copperpour not_allowed)
			(footprints allowed)
		)
		(placement
			(enabled no)
			(sheetname "")
		)
		(fill yes
			(thermal_gap 0.5)
			(thermal_bridge_width 0.5)
			(island_removal_mode 0)
		)
		(polygon
			(pts
				(arc
					(start 156.24175 -432.56073)
					(mid 156.264068 -432.614612)
					(end 156.31795 -432.63693)
				)
				(arc
					(start 157.25775 -432.63693)
					(mid 157.311632 -432.614612)
					(end 157.33395 -432.56073)
				)
				(arc
					(start 157.33395 -430.019206)
					(mid 157.311632 -429.965324)
					(end 157.25775 -429.943006)
				)
				(arc
					(start 156.31795 -429.943006)
					(mid 156.264068 -429.965324)
					(end 156.24175 -430.019206)
				)
			)
		)
	)
	(zone
		(layers "F.Cu" "In4.Cu" "In6.Cu" "In11.Cu" "In13.Cu" "In14.Cu" "In15.Cu")
		(hatch none 0.5)
		(connect_pads
			(clearance 0)
		)
		(min_thickness 0.25)
		(keepout
			(tracks not_allowed)
			(vias allowed)
			(pads allowed)
			(copperpour not_allowed)
			(footprints allowed)
		)
		(placement
			(enabled no)
			(sheetname "")
		)
		(fill yes
			(thermal_gap 0.5)
			(thermal_bridge_width 0.5)
			(island_removal_mode 0)
		)
		(polygon
			(pts
				(arc
					(start 154.241754 -431.560732)
					(mid 154.264072 -431.614614)
					(end 154.317954 -431.636932)
				)
				(arc
					(start 155.257754 -431.636932)
					(mid 155.311636 -431.614614)
					(end 155.333954 -431.560732)
				)
				(arc
					(start 155.333954 -429.019208)
					(mid 155.311636 -428.965326)
					(end 155.257754 -428.943008)
				)
				(arc
					(start 154.317954 -428.943008)
					(mid 154.264072 -428.965326)
					(end 154.241754 -429.019208)
				)
			)
		)
	)
	(zone
		(layers "F.Cu" "In4.Cu" "In6.Cu" "In11.Cu" "In15.Cu")
		(hatch none 0.5)
		(connect_pads
			(clearance 0)
		)
		(min_thickness 0.25)
		(keepout
			(tracks not_allowed)
			(vias allowed)
			(pads allowed)
			(copperpour not_allowed)
			(footprints allowed)
		)
		(placement
			(enabled no)
			(sheetname "")
		)
		(fill yes
			(thermal_gap 0.5)
			(thermal_bridge_width 0.5)
			(island_removal_mode 0)
		)
		(polygon
			(pts
				(arc
					(start 154.241754 -427.96079)
					(mid 154.264072 -428.014672)
					(end 154.317954 -428.03699)
				)
				(arc
					(start 155.257754 -428.03699)
					(mid 155.311636 -428.014672)
					(end 155.333954 -427.96079)
				)
				(arc
					(start 155.333954 -425.419266)
					(mid 155.311636 -425.365384)
					(end 155.257754 -425.343066)
				)
				(arc
					(start 154.317954 -425.343066)
					(mid 154.264072 -425.365384)
					(end 154.241754 -425.419266)
				)
			)
		)
	)
	(zone
		(layer "B.Cu")
		(hatch none 0.5)
		(connect_pads
			(clearance 0)
		)
		(min_thickness 0.25)
		(keepout
			(tracks allowed)
			(vias allowed)
			(pads allowed)
			(copperpour allowed)
			(footprints allowed)
		)
		(placement
			(enabled no)
			(sheetname "")
		)
		(fill
			(thermal_gap 0.5)
			(thermal_bridge_width 0.5)
			(island_removal_mode 0)
		)
		(polygon
			(pts
				(xy 67.438778 -409.046426) (xy 67.438778 -408.04211) (xy 68.815712 -408.04211) (xy 68.815712 -409.046426)
			)
		)
	)
	(zone
		(layer "B.Cu")
		(hatch none 0.5)
		(connect_pads
			(clearance 0)
		)
		(min_thickness 0.25)
		(keepout
			(tracks allowed)
			(vias allowed)
			(pads allowed)
			(copperpour allowed)
			(footprints not_allowed)
		)
		(placement
			(enabled no)
			(sheetname "")
		)
		(fill
			(thermal_gap 0.5)
			(thermal_bridge_width 0.5)
			(island_removal_mode 0)
		)
		(polygon
			(pts
				(arc
					(start 438.852056 -351.415096)
					(mid 441.952126 -354.515166)
					(end 445.051942 -351.415096)
				)
				(arc
					(start 445.051942 -351.415096)
					(mid 441.952126 -348.31528)
					(end 438.852056 -351.415096)
				)
			)
		)
	)
	(zone
		(layer "B.Cu")
		(hatch none 0.5)
		(connect_pads
			(clearance 0)
		)
		(min_thickness 0.25)
		(keepout
			(tracks not_allowed)
			(vias allowed)
			(pads allowed)
			(copperpour not_allowed)
			(footprints allowed)
		)
		(placement
			(enabled no)
			(sheetname "")
		)
		(fill
			(thermal_gap 0.5)
			(thermal_bridge_width 0.5)
			(island_removal_mode 0)
		)
		(polygon
			(pts
				(arc
					(start 313.750452 -400.811238)
					(mid 313.082432 -400.811238)
					(end 313.750452 -400.811238)
				)
			)
		)
	)
	(zone
		(layer "B.Cu")
		(hatch none 0.5)
		(connect_pads
			(clearance 0)
		)
		(min_thickness 0.25)
		(keepout
			(tracks not_allowed)
			(vias allowed)
			(pads allowed)
			(copperpour not_allowed)
			(footprints allowed)
		)
		(placement
			(enabled no)
			(sheetname "")
		)
		(fill
			(thermal_gap 0.5)
			(thermal_bridge_width 0.5)
			(island_removal_mode 0)
		)
		(polygon
			(pts
				(arc
					(start 61.306202 -385.31038)
					(mid 60.676282 -385.31038)
					(end 61.306202 -385.31038)
				)
			)
		)
	)
	(zone
		(layer "B.Cu")
		(hatch none 0.5)
		(connect_pads
			(clearance 0)
		)
		(min_thickness 0.25)
		(keepout
			(tracks allowed)
			(vias allowed)
			(pads allowed)
			(copperpour allowed)
			(footprints not_allowed)
		)
		(placement
			(enabled no)
			(sheetname "")
		)
		(fill
			(thermal_gap 0.5)
			(thermal_bridge_width 0.5)
			(island_removal_mode 0)
		)
		(polygon
			(pts
				(arc
					(start 231.650032 -272.50009)
					(mid 236.650022 -277.50008)
					(end 241.650012 -272.50009)
				)
				(arc
					(start 241.650012 -272.50009)
					(mid 236.650022 -267.5001)
					(end 231.650032 -272.50009)
				)
			)
		)
	)
	(zone
		(layer "B.Cu")
		(hatch none 0.5)
		(connect_pads
			(clearance 0)
		)
		(min_thickness 0.25)
		(keepout
			(tracks allowed)
			(vias allowed)
			(pads allowed)
			(copperpour allowed)
			(footprints not_allowed)
		)
		(placement
			(enabled no)
			(sheetname "")
		)
		(fill
			(thermal_gap 0.5)
			(thermal_bridge_width 0.5)
			(island_removal_mode 0)
		)
		(polygon
			(pts
				(arc
					(start 150.530052 -258.890008)
					(mid 154.030172 -262.390128)
					(end 157.530038 -258.890008)
				)
				(arc
					(start 157.530038 -258.890008)
					(mid 154.030172 -255.390142)
					(end 150.530052 -258.890008)
				)
			)
		)
	)
	(zone
		(layer "B.Cu")
		(hatch none 0.5)
		(connect_pads
			(clearance 0)
		)
		(min_thickness 0.25)
		(keepout
			(tracks allowed)
			(vias allowed)
			(pads allowed)
			(copperpour allowed)
			(footprints not_allowed)
		)
		(placement
			(enabled no)
			(sheetname "")
		)
		(fill
			(thermal_gap 0.5)
			(thermal_bridge_width 0.5)
			(island_removal_mode 0)
		)
		(polygon
			(pts
				(arc
					(start 429.50003 -384.869944)
					(mid 433.500022 -388.869936)
					(end 437.500014 -384.869944)
				)
				(arc
					(start 437.500014 -384.869944)
					(mid 433.500022 -380.869952)
					(end 429.50003 -384.869944)
				)
			)
		)
	)
	(zone
		(layer "B.Cu")
		(hatch none 0.5)
		(connect_pads
			(clearance 0)
		)
		(min_thickness 0.25)
		(keepout
			(tracks not_allowed)
			(vias allowed)
			(pads allowed)
			(copperpour not_allowed)
			(footprints allowed)
		)
		(placement
			(enabled no)
			(sheetname "")
		)
		(fill
			(thermal_gap 0.5)
			(thermal_bridge_width 0.5)
			(island_removal_mode 0)
		)
		(polygon
			(pts
				(arc
					(start 332.069948 -212.989922)
					(mid 329.270106 -210.19008)
					(end 326.47001 -212.989922)
				)
				(arc
					(start 326.47001 -212.989922)
					(mid 329.270106 -215.790018)
					(end 332.069948 -212.989922)
				)
			)
		)
	)
	(zone
		(layer "B.Cu")
		(hatch none 0.5)
		(connect_pads
			(clearance 0)
		)
		(min_thickness 0.25)
		(keepout
			(tracks not_allowed)
			(vias allowed)
			(pads allowed)
			(copperpour not_allowed)
			(footprints allowed)
		)
		(placement
			(enabled no)
			(sheetname "")
		)
		(fill
			(thermal_gap 0.5)
			(thermal_bridge_width 0.5)
			(island_removal_mode 0)
		)
		(polygon
			(pts
				(arc
					(start 256.261108 -201.798936)
					(mid 255.593088 -201.798936)
					(end 256.261108 -201.798936)
				)
			)
		)
	)
	(zone
		(layer "B.Cu")
		(hatch none 0.5)
		(connect_pads
			(clearance 0)
		)
		(min_thickness 0.25)
		(keepout
			(tracks not_allowed)
			(vias allowed)
			(pads allowed)
			(copperpour not_allowed)
			(footprints allowed)
		)
		(placement
			(enabled no)
			(sheetname "")
		)
		(fill
			(thermal_gap 0.5)
			(thermal_bridge_width 0.5)
			(island_removal_mode 0)
		)
		(polygon
			(pts
				(arc
					(start 357.686102 -248.534174)
					(mid 357.056182 -248.534174)
					(end 357.686102 -248.534174)
				)
			)
		)
	)
	(zone
		(layer "B.Cu")
		(hatch none 0.5)
		(connect_pads
			(clearance 0)
		)
		(min_thickness 0.25)
		(keepout
			(tracks not_allowed)
			(vias allowed)
			(pads allowed)
			(copperpour not_allowed)
			(footprints allowed)
		)
		(placement
			(enabled no)
			(sheetname "")
		)
		(fill
			(thermal_gap 0.5)
			(thermal_bridge_width 0.5)
			(island_removal_mode 0)
		)
		(polygon
			(pts
				(arc
					(start 103.300276 -435.600094)
					(mid 100.500434 -432.800252)
					(end 97.700338 -435.600094)
				)
				(arc
					(start 97.700338 -435.600094)
					(mid 100.500434 -438.40019)
					(end 103.300276 -435.600094)
				)
			)
		)
	)
	(zone
		(layer "B.Cu")
		(hatch none 0.5)
		(connect_pads
			(clearance 0)
		)
		(min_thickness 0.25)
		(keepout
			(tracks not_allowed)
			(vias allowed)
			(pads allowed)
			(copperpour not_allowed)
			(footprints allowed)
		)
		(placement
			(enabled no)
			(sheetname "")
		)
		(fill
			(thermal_gap 0.5)
			(thermal_bridge_width 0.5)
			(island_removal_mode 0)
		)
		(polygon
			(pts
				(arc
					(start 61.036962 -437.889904)
					(mid 60.26277 -437.889904)
					(end 61.036962 -437.889904)
				)
			)
		)
	)
	(zone
		(layer "B.Cu")
		(hatch none 0.5)
		(connect_pads
			(clearance 0)
		)
		(min_thickness 0.25)
		(keepout
			(tracks not_allowed)
			(vias allowed)
			(pads allowed)
			(copperpour not_allowed)
			(footprints allowed)
		)
		(placement
			(enabled no)
			(sheetname "")
		)
		(fill
			(thermal_gap 0.5)
			(thermal_bridge_width 0.5)
			(island_removal_mode 0)
		)
		(polygon
			(pts
				(arc
					(start 25.592532 -422.130474)
					(mid 24.924512 -422.130474)
					(end 25.592532 -422.130474)
				)
			)
		)
	)
	(zone
		(layer "B.Cu")
		(hatch none 0.5)
		(connect_pads
			(clearance 0)
		)
		(min_thickness 0.25)
		(keepout
			(tracks not_allowed)
			(vias allowed)
			(pads allowed)
			(copperpour not_allowed)
			(footprints allowed)
		)
		(placement
			(enabled no)
			(sheetname "")
		)
		(fill
			(thermal_gap 0.5)
			(thermal_bridge_width 0.5)
			(island_removal_mode 0)
		)
		(polygon
			(pts
				(arc
					(start 392.136884 -439.0898)
					(mid 391.362692 -439.0898)
					(end 392.136884 -439.0898)
				)
			)
		)
	)
	(zone
		(layer "B.Cu")
		(hatch none 0.5)
		(connect_pads
			(clearance 0)
		)
		(min_thickness 0.25)
		(keepout
			(tracks not_allowed)
			(vias allowed)
			(pads allowed)
			(copperpour not_allowed)
			(footprints allowed)
		)
		(placement
			(enabled no)
			(sheetname "")
		)
		(fill
			(thermal_gap 0.5)
			(thermal_bridge_width 0.5)
			(island_removal_mode 0)
		)
		(polygon
			(pts
				(arc
					(start 25.846532 -428.615602)
					(mid 25.178512 -428.615602)
					(end 25.846532 -428.615602)
				)
			)
		)
	)
	(zone
		(layer "B.Cu")
		(hatch none 0.5)
		(connect_pads
			(clearance 0)
		)
		(min_thickness 0.25)
		(keepout
			(tracks not_allowed)
			(vias allowed)
			(pads allowed)
			(copperpour not_allowed)
			(footprints allowed)
		)
		(placement
			(enabled no)
			(sheetname "")
		)
		(fill
			(thermal_gap 0.5)
			(thermal_bridge_width 0.5)
			(island_removal_mode 0)
		)
		(polygon
			(pts
				(arc
					(start 72.080882 -344.814906)
					(mid 70.216014 -342.950038)
					(end 68.350892 -344.814906)
				)
				(arc
					(start 68.350892 -344.814906)
					(mid 70.216014 -346.680028)
					(end 72.080882 -344.814906)
				)
			)
		)
	)
	(zone
		(layer "B.Cu")
		(hatch none 0.5)
		(connect_pads
			(clearance 0)
		)
		(min_thickness 0.25)
		(keepout
			(tracks allowed)
			(vias allowed)
			(pads allowed)
			(copperpour allowed)
			(footprints allowed)
		)
		(placement
			(enabled no)
			(sheetname "")
		)
		(fill
			(thermal_gap 0.5)
			(thermal_bridge_width 0.5)
			(island_removal_mode 0)
		)
		(polygon
			(pts
				(xy 423.916348 -353.39147) (xy 423.916348 -355.55047) (xy 423.535348 -355.93147) (xy 420.741348 -355.93147)
				(xy 419.598348 -354.78847) (xy 419.598348 -351.86747) (xy 420.106348 -351.35947) (xy 421.884348 -351.35947)
			)
		)
	)
	(zone
		(layer "B.Cu")
		(hatch none 0.5)
		(connect_pads
			(clearance 0)
		)
		(min_thickness 0.25)
		(keepout
			(tracks not_allowed)
			(vias allowed)
			(pads allowed)
			(copperpour not_allowed)
			(footprints allowed)
		)
		(placement
			(enabled no)
			(sheetname "")
		)
		(fill
			(thermal_gap 0.5)
			(thermal_bridge_width 0.5)
			(island_removal_mode 0)
		)
		(polygon
			(pts
				(arc
					(start 134.751064 -146.84502)
					(mid 132.886196 -144.980152)
					(end 131.021074 -146.84502)
				)
				(arc
					(start 131.021074 -146.84502)
					(mid 132.886196 -148.710142)
					(end 134.751064 -146.84502)
				)
			)
		)
	)
	(zone
		(layer "B.Cu")
		(hatch none 0.5)
		(connect_pads
			(clearance 0)
		)
		(min_thickness 0.25)
		(keepout
			(tracks not_allowed)
			(vias allowed)
			(pads allowed)
			(copperpour not_allowed)
			(footprints allowed)
		)
		(placement
			(enabled no)
			(sheetname "")
		)
		(fill
			(thermal_gap 0.5)
			(thermal_bridge_width 0.5)
			(island_removal_mode 0)
		)
		(polygon
			(pts
				(arc
					(start 264.352024 -347.8149)
					(mid 267.452094 -350.91497)
					(end 270.55191 -347.8149)
				)
				(arc
					(start 270.55191 -347.8149)
					(mid 267.452094 -344.715084)
					(end 264.352024 -347.8149)
				)
			)
		)
	)
	(zone
		(layer "B.Cu")
		(hatch none 0.5)
		(connect_pads
			(clearance 0)
		)
		(min_thickness 0.25)
		(keepout
			(tracks allowed)
			(vias allowed)
			(pads allowed)
			(copperpour allowed)
			(footprints not_allowed)
		)
		(placement
			(enabled no)
			(sheetname "")
		)
		(fill
			(thermal_gap 0.5)
			(thermal_bridge_width 0.5)
			(island_removal_mode 0)
		)
		(polygon
			(pts
				(arc
					(start 463.79003 -51.289966)
					(mid 466.8901 -54.390036)
					(end 469.989916 -51.289966)
				)
				(arc
					(start 469.989916 -51.289966)
					(mid 466.8901 -48.19015)
					(end 463.79003 -51.289966)
				)
			)
		)
	)
	(zone
		(layer "B.Cu")
		(hatch none 0.5)
		(connect_pads
			(clearance 0)
		)
		(min_thickness 0.25)
		(keepout
			(tracks allowed)
			(vias allowed)
			(pads allowed)
			(copperpour allowed)
			(footprints allowed)
		)
		(placement
			(enabled no)
			(sheetname "")
		)
		(fill
			(thermal_gap 0.5)
			(thermal_bridge_width 0.5)
			(island_removal_mode 0)
		)
		(polygon
			(pts
				(xy 78.37805 -394.180568) (xy 78.37805 -391.48639) (xy 78.37805 -385.965954) (xy 80.125316 -385.965954)
				(xy 80.125316 -384.911854) (xy 99.720146 -384.911854) (xy 99.720146 -385.965954) (xy 99.720146 -394.180568)
			)
		)
	)
	(zone
		(layer "B.Cu")
		(hatch none 0.5)
		(connect_pads
			(clearance 0)
		)
		(min_thickness 0.25)
		(keepout
			(tracks allowed)
			(vias allowed)
			(pads allowed)
			(copperpour allowed)
			(footprints not_allowed)
		)
		(placement
			(enabled no)
			(sheetname "")
		)
		(fill
			(thermal_gap 0.5)
			(thermal_bridge_width 0.5)
			(island_removal_mode 0)
		)
		(polygon
			(pts
				(arc
					(start 366.298734 -435.600094)
					(mid 371.298724 -440.600084)
					(end 376.298714 -435.600094)
				)
				(arc
					(start 376.298714 -435.600094)
					(mid 371.298724 -430.600104)
					(end 366.298734 -435.600094)
				)
			)
		)
	)
	(zone
		(layer "B.Cu")
		(hatch none 0.5)
		(connect_pads
			(clearance 0)
		)
		(min_thickness 0.25)
		(keepout
			(tracks allowed)
			(vias allowed)
			(pads allowed)
			(copperpour allowed)
			(footprints not_allowed)
		)
		(placement
			(enabled no)
			(sheetname "")
		)
		(fill
			(thermal_gap 0.5)
			(thermal_bridge_width 0.5)
			(island_removal_mode 0)
		)
		(polygon
			(pts
				(arc
					(start 108.580936 -166.61511)
					(mid 106.716068 -164.750242)
					(end 104.850946 -166.61511)
				)
				(arc
					(start 104.850946 -166.61511)
					(mid 106.716068 -168.480232)
					(end 108.580936 -166.61511)
				)
			)
		)
	)
	(zone
		(layer "B.Cu")
		(hatch none 0.5)
		(connect_pads
			(clearance 0)
		)
		(min_thickness 0.25)
		(keepout
			(tracks not_allowed)
			(vias allowed)
			(pads allowed)
			(copperpour not_allowed)
			(footprints allowed)
		)
		(placement
			(enabled no)
			(sheetname "")
		)
		(fill
			(thermal_gap 0.5)
			(thermal_bridge_width 0.5)
			(island_removal_mode 0)
		)
		(polygon
			(pts
				(arc
					(start 77.829918 -212.989922)
					(mid 81.330038 -216.490042)
					(end 84.829904 -212.989922)
				)
				(arc
					(start 84.829904 -212.989922)
					(mid 81.330038 -209.490056)
					(end 77.829918 -212.989922)
				)
			)
		)
	)
	(zone
		(layer "B.Cu")
		(hatch none 0.5)
		(connect_pads
			(clearance 0)
		)
		(min_thickness 0.25)
		(keepout
			(tracks allowed)
			(vias allowed)
			(pads allowed)
			(copperpour allowed)
			(footprints allowed)
		)
		(placement
			(enabled no)
			(sheetname "")
		)
		(fill
			(thermal_gap 0.5)
			(thermal_bridge_width 0.5)
			(island_removal_mode 0)
		)
		(polygon
			(pts
				(xy 192.629536 -99.57562) (xy 192.629536 -99.002596) (xy 195.236846 -99.002596) (xy 195.236846 -99.57562)
			)
		)
	)
	(zone
		(layer "B.Cu")
		(hatch none 0.5)
		(connect_pads
			(clearance 0)
		)
		(min_thickness 0.25)
		(keepout
			(tracks not_allowed)
			(vias allowed)
			(pads allowed)
			(copperpour not_allowed)
			(footprints allowed)
		)
		(placement
			(enabled no)
			(sheetname "")
		)
		(fill
			(thermal_gap 0.5)
			(thermal_bridge_width 0.5)
			(island_removal_mode 0)
		)
		(polygon
			(pts
				(arc
					(start 82.037174 -439.0898)
					(mid 81.262982 -439.0898)
					(end 82.037174 -439.0898)
				)
			)
		)
	)
	(zone
		(layer "B.Cu")
		(hatch none 0.5)
		(connect_pads
			(clearance 0)
		)
		(min_thickness 0.25)
		(keepout
			(tracks allowed)
			(vias allowed)
			(pads allowed)
			(copperpour allowed)
			(footprints not_allowed)
		)
		(placement
			(enabled no)
			(sheetname "")
		)
		(fill
			(thermal_gap 0.5)
			(thermal_bridge_width 0.5)
			(island_removal_mode 0)
		)
		(polygon
			(pts
				(arc
					(start 461.600042 -435.600094)
					(mid 458.8002 -432.800252)
					(end 456.000104 -435.600094)
				)
				(arc
					(start 456.000104 -435.600094)
					(mid 458.8002 -438.40019)
					(end 461.600042 -435.600094)
				)
			)
		)
	)
	(zone
		(layer "B.Cu")
		(hatch none 0.5)
		(connect_pads
			(clearance 0)
		)
		(min_thickness 0.25)
		(keepout
			(tracks allowed)
			(vias allowed)
			(pads allowed)
			(copperpour allowed)
			(footprints allowed)
		)
		(placement
			(enabled no)
			(sheetname "")
		)
		(fill
			(thermal_gap 0.5)
			(thermal_bridge_width 0.5)
			(island_removal_mode 0)
		)
		(polygon
			(pts
				(xy 99.701858 -139.989052) (xy 93.540834 -139.989052) (xy 91.000834 -142.529052) (xy 91.000834 -149.514052)
				(xy 91.862402 -150.37562) (xy 98.902266 -150.37562) (xy 100.017834 -149.260052) (xy 100.017834 -147.609052)
				(xy 101.033834 -146.593052) (xy 101.033834 -141.321028)
			)
		)
	)
	(zone
		(layer "B.Cu")
		(hatch none 0.5)
		(connect_pads
			(clearance 0)
		)
		(min_thickness 0.25)
		(keepout
			(tracks not_allowed)
			(vias allowed)
			(pads allowed)
			(copperpour not_allowed)
			(footprints allowed)
		)
		(placement
			(enabled no)
			(sheetname "")
		)
		(fill
			(thermal_gap 0.5)
			(thermal_bridge_width 0.5)
			(island_removal_mode 0)
		)
		(polygon
			(pts
				(arc
					(start 421.778176 -400.811238)
					(mid 421.110156 -400.811238)
					(end 421.778176 -400.811238)
				)
			)
		)
	)
	(zone
		(layer "B.Cu")
		(hatch none 0.5)
		(connect_pads
			(clearance 0)
		)
		(min_thickness 0.25)
		(keepout
			(tracks not_allowed)
			(vias allowed)
			(pads allowed)
			(copperpour not_allowed)
			(footprints allowed)
		)
		(placement
			(enabled no)
			(sheetname "")
		)
		(fill
			(thermal_gap 0.5)
			(thermal_bridge_width 0.5)
			(island_removal_mode 0)
		)
		(polygon
			(pts
				(arc
					(start 413.378396 -401.674838)
					(mid 412.710376 -401.674838)
					(end 413.378396 -401.674838)
				)
			)
		)
	)
	(zone
		(layer "B.Cu")
		(hatch none 0.5)
		(connect_pads
			(clearance 0)
		)
		(min_thickness 0.25)
		(keepout
			(tracks not_allowed)
			(vias allowed)
			(pads allowed)
			(copperpour not_allowed)
			(footprints allowed)
		)
		(placement
			(enabled no)
			(sheetname "")
		)
		(fill
			(thermal_gap 0.5)
			(thermal_bridge_width 0.5)
			(island_removal_mode 0)
		)
		(polygon
			(pts
				(arc
					(start 117.729762 -247.724422)
					(mid 117.099842 -247.724422)
					(end 117.729762 -247.724422)
				)
			)
		)
	)
	(zone
		(layer "B.Cu")
		(hatch none 0.5)
		(connect_pads
			(clearance 0)
		)
		(min_thickness 0.25)
		(keepout
			(tracks not_allowed)
			(vias allowed)
			(pads allowed)
			(copperpour not_allowed)
			(footprints allowed)
		)
		(placement
			(enabled no)
			(sheetname "")
		)
		(fill
			(thermal_gap 0.5)
			(thermal_bridge_width 0.5)
			(island_removal_mode 0)
		)
		(polygon
			(pts
				(arc
					(start 316.506098 -394.385292)
					(mid 315.876178 -394.385292)
					(end 316.506098 -394.385292)
				)
			)
		)
	)
	(zone
		(layer "B.Cu")
		(hatch none 0.5)
		(connect_pads
			(clearance 0)
		)
		(min_thickness 0.25)
		(keepout
			(tracks not_allowed)
			(vias allowed)
			(pads allowed)
			(copperpour not_allowed)
			(footprints allowed)
		)
		(placement
			(enabled no)
			(sheetname "")
		)
		(fill
			(thermal_gap 0.5)
			(thermal_bridge_width 0.5)
			(island_removal_mode 0)
		)
		(polygon
			(pts
				(arc
					(start 172.900086 -160.50006)
					(mid 167.900096 -155.50007)
					(end 162.900106 -160.50006)
				)
				(arc
					(start 162.900106 -160.50006)
					(mid 167.900096 -165.50005)
					(end 172.900086 -160.50006)
				)
			)
		)
	)
	(zone
		(layer "B.Cu")
		(hatch none 0.5)
		(connect_pads
			(clearance 0)
		)
		(min_thickness 0.25)
		(keepout
			(tracks allowed)
			(vias allowed)
			(pads allowed)
			(copperpour allowed)
			(footprints not_allowed)
		)
		(placement
			(enabled no)
			(sheetname "")
		)
		(fill
			(thermal_gap 0.5)
			(thermal_bridge_width 0.5)
			(island_removal_mode 0)
		)
		(polygon
			(pts
				(arc
					(start 265.8999 -51.999896)
					(mid 268.649958 -54.749954)
					(end 271.400016 -51.999896)
				)
				(arc
					(start 271.400016 -51.999896)
					(mid 268.649958 -49.249838)
					(end 265.8999 -51.999896)
				)
			)
		)
	)
	(zone
		(layer "B.Cu")
		(hatch none 0.5)
		(connect_pads
			(clearance 0)
		)
		(min_thickness 0.25)
		(keepout
			(tracks not_allowed)
			(vias allowed)
			(pads allowed)
			(copperpour not_allowed)
			(footprints allowed)
		)
		(placement
			(enabled no)
			(sheetname "")
		)
		(fill
			(thermal_gap 0.5)
			(thermal_bridge_width 0.5)
			(island_removal_mode 0)
		)
		(polygon
			(pts
				(arc
					(start 467.60003 -22.29993)
					(mid 464.800188 -19.500088)
					(end 462.000092 -22.29993)
				)
				(arc
					(start 462.000092 -22.29993)
					(mid 464.800188 -25.100026)
					(end 467.60003 -22.29993)
				)
			)
		)
	)
	(zone
		(layer "B.Cu")
		(hatch none 0.5)
		(connect_pads
			(clearance 0)
		)
		(min_thickness 0.25)
		(keepout
			(tracks not_allowed)
			(vias allowed)
			(pads allowed)
			(copperpour not_allowed)
			(footprints allowed)
		)
		(placement
			(enabled no)
			(sheetname "")
		)
		(fill
			(thermal_gap 0.5)
			(thermal_bridge_width 0.5)
			(island_removal_mode 0)
		)
		(polygon
			(pts
				(arc
					(start 393.269978 -212.989922)
					(mid 390.470136 -210.19008)
					(end 387.67004 -212.989922)
				)
				(arc
					(start 387.67004 -212.989922)
					(mid 390.470136 -215.790018)
					(end 393.269978 -212.989922)
				)
			)
		)
	)
	(zone
		(layer "B.Cu")
		(hatch none 0.5)
		(connect_pads
			(clearance 0)
		)
		(min_thickness 0.25)
		(keepout
			(tracks allowed)
			(vias allowed)
			(pads allowed)
			(copperpour allowed)
			(footprints not_allowed)
		)
		(placement
			(enabled no)
			(sheetname "")
		)
		(fill
			(thermal_gap 0.5)
			(thermal_bridge_width 0.5)
			(island_removal_mode 0)
		)
		(polygon
			(pts
				(arc
					(start 173.500034 -376.489976)
					(mid 177.500026 -380.489968)
					(end 181.500018 -376.489976)
				)
				(arc
					(start 181.500018 -376.489976)
					(mid 177.500026 -372.489984)
					(end 173.500034 -376.489976)
				)
			)
		)
	)
	(zone
		(layer "B.Cu")
		(hatch none 0.5)
		(connect_pads
			(clearance 0)
		)
		(min_thickness 0.25)
		(keepout
			(tracks not_allowed)
			(vias allowed)
			(pads allowed)
			(copperpour not_allowed)
			(footprints allowed)
		)
		(placement
			(enabled no)
			(sheetname "")
		)
		(fill
			(thermal_gap 0.5)
			(thermal_bridge_width 0.5)
			(island_removal_mode 0)
		)
		(polygon
			(pts
				(arc
					(start 256.261108 -199.004428)
					(mid 255.593088 -199.004428)
					(end 256.261108 -199.004428)
				)
			)
		)
	)
	(zone
		(layer "B.Cu")
		(hatch none 0.5)
		(connect_pads
			(clearance 0)
		)
		(min_thickness 0.25)
		(keepout
			(tracks allowed)
			(vias allowed)
			(pads allowed)
			(copperpour allowed)
			(footprints not_allowed)
		)
		(placement
			(enabled no)
			(sheetname "")
		)
		(fill
			(thermal_gap 0.5)
			(thermal_bridge_width 0.5)
			(island_removal_mode 0)
		)
		(polygon
			(pts
				(arc
					(start 109.815884 -166.61511)
					(mid 106.716068 -163.515294)
					(end 103.615998 -166.61511)
				)
				(arc
					(start 103.615998 -166.61511)
					(mid 106.716068 -169.71518)
					(end 109.815884 -166.61511)
				)
			)
		)
	)
	(zone
		(layer "B.Cu")
		(hatch none 0.5)
		(connect_pads
			(clearance 0)
		)
		(min_thickness 0.25)
		(keepout
			(tracks not_allowed)
			(vias allowed)
			(pads allowed)
			(copperpour not_allowed)
			(footprints allowed)
		)
		(placement
			(enabled no)
			(sheetname "")
		)
		(fill
			(thermal_gap 0.5)
			(thermal_bridge_width 0.5)
			(island_removal_mode 0)
		)
		(polygon
			(pts
				(arc
					(start 82.037174 -437.889904)
					(mid 81.262982 -437.889904)
					(end 82.037174 -437.889904)
				)
			)
		)
	)
	(zone
		(layer "B.Cu")
		(hatch none 0.5)
		(connect_pads
			(clearance 0)
		)
		(min_thickness 0.25)
		(keepout
			(tracks not_allowed)
			(vias allowed)
			(pads allowed)
			(copperpour not_allowed)
			(footprints allowed)
		)
		(placement
			(enabled no)
			(sheetname "")
		)
		(fill
			(thermal_gap 0.5)
			(thermal_bridge_width 0.5)
			(island_removal_mode 0)
		)
		(polygon
			(pts
				(arc
					(start 158.578296 -392.429238)
					(mid 157.910276 -392.429238)
					(end 158.578296 -392.429238)
				)
			)
		)
	)
	(zone
		(layer "B.Cu")
		(hatch none 0.5)
		(connect_pads
			(clearance 0)
		)
		(min_thickness 0.25)
		(keepout
			(tracks allowed)
			(vias allowed)
			(pads allowed)
			(copperpour allowed)
			(footprints not_allowed)
		)
		(placement
			(enabled no)
			(sheetname "")
		)
		(fill
			(thermal_gap 0.5)
			(thermal_bridge_width 0.5)
			(island_removal_mode 0)
		)
		(polygon
			(pts
				(arc
					(start 176.186084 -351.825052)
					(mid 173.086014 -348.724982)
					(end 169.985944 -351.825052)
				)
				(arc
					(start 169.985944 -351.825052)
					(mid 173.086014 -354.925122)
					(end 176.186084 -351.825052)
				)
			)
		)
	)
	(zone
		(layer "B.Cu")
		(hatch none 0.5)
		(connect_pads
			(clearance 0)
		)
		(min_thickness 0.25)
		(keepout
			(tracks allowed)
			(vias allowed)
			(pads allowed)
			(copperpour allowed)
			(footprints not_allowed)
		)
		(placement
			(enabled no)
			(sheetname "")
		)
		(fill
			(thermal_gap 0.5)
			(thermal_bridge_width 0.5)
			(island_removal_mode 0)
		)
		(polygon
			(pts
				(arc
					(start 361.362498 -431.360072)
					(mid 359.774998 -429.772572)
					(end 358.187498 -431.360072)
				)
				(arc
					(start 358.187498 -431.360072)
					(mid 359.774998 -432.947572)
					(end 361.362498 -431.360072)
				)
			)
		)
	)
	(zone
		(layer "B.Cu")
		(hatch none 0.5)
		(connect_pads
			(clearance 0)
		)
		(min_thickness 0.25)
		(keepout
			(tracks not_allowed)
			(vias allowed)
			(pads allowed)
			(copperpour not_allowed)
			(footprints allowed)
		)
		(placement
			(enabled no)
			(sheetname "")
		)
		(fill
			(thermal_gap 0.5)
			(thermal_bridge_width 0.5)
			(island_removal_mode 0)
		)
		(polygon
			(pts
				(arc
					(start 67.03695 -436.889906)
					(mid 66.262758 -436.889906)
					(end 67.03695 -436.889906)
				)
			)
		)
	)
	(zone
		(layer "B.Cu")
		(hatch none 0.5)
		(connect_pads
			(clearance 0)
		)
		(min_thickness 0.25)
		(keepout
			(tracks not_allowed)
			(vias allowed)
			(pads allowed)
			(copperpour not_allowed)
			(footprints allowed)
		)
		(placement
			(enabled no)
			(sheetname "")
		)
		(fill
			(thermal_gap 0.5)
			(thermal_bridge_width 0.5)
			(island_removal_mode 0)
		)
		(polygon
			(pts
				(arc
					(start 67.115944 -344.814906)
					(mid 70.216014 -347.914976)
					(end 73.316084 -344.814906)
				)
				(arc
					(start 73.316084 -344.814906)
					(mid 70.216014 -341.714836)
					(end 67.115944 -344.814906)
				)
			)
		)
	)
	(zone
		(layer "B.Cu")
		(hatch none 0.5)
		(connect_pads
			(clearance 0)
		)
		(min_thickness 0.25)
		(keepout
			(tracks not_allowed)
			(vias allowed)
			(pads allowed)
			(copperpour not_allowed)
			(footprints allowed)
		)
		(placement
			(enabled no)
			(sheetname "")
		)
		(fill
			(thermal_gap 0.5)
			(thermal_bridge_width 0.5)
			(island_removal_mode 0)
		)
		(polygon
			(pts
				(arc
					(start 103.615998 -166.61511)
					(mid 106.716068 -169.71518)
					(end 109.815884 -166.61511)
				)
				(arc
					(start 109.815884 -166.61511)
					(mid 106.716068 -163.515294)
					(end 103.615998 -166.61511)
				)
			)
		)
	)
	(zone
		(layer "B.Cu")
		(hatch none 0.5)
		(connect_pads
			(clearance 0)
		)
		(min_thickness 0.25)
		(keepout
			(tracks not_allowed)
			(vias allowed)
			(pads allowed)
			(copperpour not_allowed)
			(footprints allowed)
		)
		(placement
			(enabled no)
			(sheetname "")
		)
		(fill
			(thermal_gap 0.5)
			(thermal_bridge_width 0.5)
			(island_removal_mode 0)
		)
		(polygon
			(pts
				(arc
					(start 388.136892 -439.0898)
					(mid 387.3627 -439.0898)
					(end 388.136892 -439.0898)
				)
			)
		)
	)
	(zone
		(layer "B.Cu")
		(hatch none 0.5)
		(connect_pads
			(clearance 0)
		)
		(min_thickness 0.25)
		(keepout
			(tracks allowed)
			(vias allowed)
			(pads allowed)
			(copperpour allowed)
			(footprints not_allowed)
		)
		(placement
			(enabled no)
			(sheetname "")
		)
		(fill
			(thermal_gap 0.5)
			(thermal_bridge_width 0.5)
			(island_removal_mode 0)
		)
		(polygon
			(pts
				(arc
					(start 169.985944 -351.825052)
					(mid 173.086014 -354.925122)
					(end 176.186084 -351.825052)
				)
				(arc
					(start 176.186084 -351.825052)
					(mid 173.086014 -348.724982)
					(end 169.985944 -351.825052)
				)
			)
		)
	)
	(zone
		(layer "B.Cu")
		(hatch none 0.5)
		(connect_pads
			(clearance 0)
		)
		(min_thickness 0.25)
		(keepout
			(tracks allowed)
			(vias allowed)
			(pads allowed)
			(copperpour allowed)
			(footprints not_allowed)
		)
		(placement
			(enabled no)
			(sheetname "")
		)
		(fill
			(thermal_gap 0.5)
			(thermal_bridge_width 0.5)
			(island_removal_mode 0)
		)
		(polygon
			(pts
				(arc
					(start 139.029948 -304.790094)
					(mid 142.530068 -308.290214)
					(end 146.029934 -304.790094)
				)
				(arc
					(start 146.029934 -304.790094)
					(mid 142.530068 -301.290228)
					(end 139.029948 -304.790094)
				)
			)
		)
	)
	(zone
		(layer "B.Cu")
		(hatch none 0.5)
		(connect_pads
			(clearance 0)
		)
		(min_thickness 0.25)
		(keepout
			(tracks not_allowed)
			(vias allowed)
			(pads allowed)
			(copperpour not_allowed)
			(footprints allowed)
		)
		(placement
			(enabled no)
			(sheetname "")
		)
		(fill
			(thermal_gap 0.5)
			(thermal_bridge_width 0.5)
			(island_removal_mode 0)
		)
		(polygon
			(pts
				(arc
					(start 312.550302 -400.811238)
					(mid 311.882282 -400.811238)
					(end 312.550302 -400.811238)
				)
			)
		)
	)
	(zone
		(layer "B.Cu")
		(hatch none 0.5)
		(connect_pads
			(clearance 0)
		)
		(min_thickness 0.25)
		(keepout
			(tracks not_allowed)
			(vias allowed)
			(pads allowed)
			(copperpour not_allowed)
			(footprints allowed)
		)
		(placement
			(enabled no)
			(sheetname "")
		)
		(fill
			(thermal_gap 0.5)
			(thermal_bridge_width 0.5)
			(island_removal_mode 0)
		)
		(polygon
			(pts
				(arc
					(start 109.105954 -270.846296)
					(mid 108.476034 -270.846296)
					(end 109.105954 -270.846296)
				)
			)
		)
	)
	(zone
		(layer "B.Cu")
		(hatch none 0.5)
		(connect_pads
			(clearance 0)
		)
		(min_thickness 0.25)
		(keepout
			(tracks not_allowed)
			(vias allowed)
			(pads allowed)
			(copperpour not_allowed)
			(footprints allowed)
		)
		(placement
			(enabled no)
			(sheetname "")
		)
		(fill
			(thermal_gap 0.5)
			(thermal_bridge_width 0.5)
			(island_removal_mode 0)
		)
		(polygon
			(pts
				(arc
					(start 415.778442 -400.811238)
					(mid 415.110422 -400.811238)
					(end 415.778442 -400.811238)
				)
			)
		)
	)
	(zone
		(layer "B.Cu")
		(hatch none 0.5)
		(connect_pads
			(clearance 0)
		)
		(min_thickness 0.25)
		(keepout
			(tracks not_allowed)
			(vias allowed)
			(pads allowed)
			(copperpour not_allowed)
			(footprints allowed)
		)
		(placement
			(enabled no)
			(sheetname "")
		)
		(fill
			(thermal_gap 0.5)
			(thermal_bridge_width 0.5)
			(island_removal_mode 0)
		)
		(polygon
			(pts
				(arc
					(start 162.178238 -392.429238)
					(mid 161.510218 -392.429238)
					(end 162.178238 -392.429238)
				)
			)
		)
	)
	(zone
		(layer "B.Cu")
		(hatch none 0.5)
		(connect_pads
			(clearance 0)
		)
		(min_thickness 0.25)
		(keepout
			(tracks allowed)
			(vias allowed)
			(pads allowed)
			(copperpour allowed)
			(footprints allowed)
		)
		(placement
			(enabled no)
			(sheetname "")
		)
		(fill
			(thermal_gap 0.5)
			(thermal_bridge_width 0.5)
			(island_removal_mode 0)
		)
		(polygon
			(pts
				(xy 24.322024 -392.23823) (xy 25.689052 -392.23823) (xy 25.689052 -393.07516) (xy 24.322024 -393.07516)
			)
		)
	)
	(zone
		(layer "B.Cu")
		(hatch none 0.5)
		(connect_pads
			(clearance 0)
		)
		(min_thickness 0.25)
		(keepout
			(tracks allowed)
			(vias allowed)
			(pads allowed)
			(copperpour allowed)
			(footprints not_allowed)
		)
		(placement
			(enabled no)
			(sheetname "")
		)
		(fill
			(thermal_gap 0.5)
			(thermal_bridge_width 0.5)
			(island_removal_mode 0)
		)
		(polygon
			(pts
				(xy 462.639918 -310.522112)
				(arc
					(start 462.639918 -339.787484)
					(mid 457.352089 -340.835314)
					(end 453.929496 -345.000072)
				)
				(arc
					(start 446.731898 -345.000072)
					(mid 441.952024 -343.415174)
					(end 437.1721 -345.000072)
				)
				(arc
					(start 418.731954 -345.000072)
					(mid 413.95208 -343.415174)
					(end 409.172156 -345.000072)
				)
				(arc
					(start 366.436656 -345.000072)
					(mid 367.56376 -342.777046)
					(end 367.95202 -340.315042)
				)
				(arc
					(start 367.95202 -340.315042)
					(mid 359.952036 -332.315058)
					(end 351.952052 -340.315042)
				)
				(arc
					(start 351.952052 -340.315042)
					(mid 352.340316 -342.777044)
					(end 353.467416 -345.000072)
				)
				(arc
					(start 325.449946 -345.000072)
					(mid 325.451496 -344.907495)
					(end 325.451978 -344.814906)
				)
				(arc
					(start 325.451978 -344.814906)
					(mid 317.451994 -336.814922)
					(end 309.45201 -344.814906)
				)
				(arc
					(start 309.45201 -344.814906)
					(mid 309.45249 -344.907495)
					(end 309.454042 -345.000072)
				)
				(arc
					(start 274.940268 -345.000072)
					(mid 267.452049 -339.815314)
					(end 259.963666 -345.000072)
				)
				(arc
					(start 239.445546 -345.000072)
					(mid 236.650022 -344.495732)
					(end 233.854498 -345.000072)
				)
				(arc
					(start 205.259686 -345.000072)
					(mid 201.085958 -343.825067)
					(end 196.91223 -345.000072)
				)
				(arc
					(start 177.259742 -345.000072)
					(mid 173.086014 -343.825067)
					(end 168.912286 -345.000072)
				)
				(arc
					(start 73.310496 -345.000072)
					(mid 70.216014 -341.715158)
					(end 67.121532 -345.000072)
				)
				(arc
					(start 27.704288 -345.000072)
					(mid 22.417421 -340.123966)
					(end 15.351252 -341.464138)
				)
				(arc
					(start 15.351252 -341.464138)
					(mid 11.591008 -339.798513)
					(end 7.500112 -340.221062)
				)
				(xy 7.500112 -273.121882) (xy 8.839962 -273.121882) (xy 8.839962 -310.522112) (xy 63.840106 -310.522112)
				(xy 63.840106 -273.121882) (xy 65.227962 -273.121882)
				(arc
					(start 65.227962 -309.38089)
					(mid 65.960231 -311.148743)
					(end 67.728084 -311.881012)
				)
				(arc
					(start 85.471 -311.881012)
					(mid 87.111214 -311.267768)
					(end 87.946738 -309.72887)
				)
				(arc
					(start 89.028016 -302.033178)
					(mid 89.863572 -300.494316)
					(end 91.503754 -299.881036)
				)
				(xy 111.828072 -299.881036) (xy 111.828072 -272.880074)
				(arc
					(start 99.927918 -272.880074)
					(mid 98.160319 -272.1477)
					(end 97.42805 -270.379952)
				)
				(arc
					(start 97.42805 -247.379744)
					(mid 98.160244 -245.61207)
					(end 99.927918 -244.879876)
				)
				(arc
					(start 123.928124 -244.879876)
					(mid 125.695977 -245.612145)
					(end 126.427992 -247.379998)
				)
				(arc
					(start 126.427992 -270.380206)
					(mid 125.695798 -272.14788)
					(end 123.928124 -272.880074)
				)
				(xy 111.927894 -272.880074) (xy 111.927894 -299.881036)
				(arc
					(start 132.252466 -299.881036)
					(mid 133.892594 -300.494288)
					(end 134.72795 -302.033178)
				)
				(arc
					(start 135.809228 -309.72887)
					(mid 136.644688 -311.267649)
					(end 138.284712 -311.881012)
				)
				(arc
					(start 156.127704 -311.883044)
					(mid 157.89644 -311.150146)
					(end 158.62808 -309.38089)
				)
				(xy 158.62808 -273.121882) (xy 159.740092 -273.121882) (xy 159.740092 -310.522112) (xy 214.739982 -310.522112)
				(xy 214.739982 -273.02206) (xy 159.740092 -273.02206) (xy 158.62808 -273.02206) (xy 158.62808 -267.380974)
				(xy 161.727896 -264.38098) (xy 161.727896 -253.381002) (xy 158.62808 -250.381008) (xy 158.62808 -239.862106)
				(xy 159.770064 -239.862106) (xy 214.769954 -239.862106) (xy 214.769954 -202.362054) (xy 159.770064 -202.362054)
				(xy 159.770064 -239.76203) (xy 158.62808 -239.76203)
				(arc
					(start 158.62808 -208.381092)
					(mid 157.895811 -206.613239)
					(end 156.127958 -205.88097)
				)
				(arc
					(start 138.385042 -205.88097)
					(mid 136.744828 -206.494214)
					(end 135.909304 -208.033112)
				)
				(arc
					(start 134.828026 -215.728804)
					(mid 133.99247 -217.267666)
					(end 132.352288 -217.880946)
				)
				(arc
					(start 91.503754 -217.880946)
					(mid 89.86354 -217.267702)
					(end 89.028016 -215.728804)
				)
				(arc
					(start 87.946738 -208.033112)
					(mid 87.111182 -206.49425)
					(end 85.471 -205.88097)
				)
				(arc
					(start 67.728084 -205.88097)
					(mid 65.960231 -206.613239)
					(end 65.227962 -208.381092)
				)
				(xy 65.227962 -239.76203) (xy 63.840106 -239.76203) (xy 63.840106 -202.362054) (xy 8.839962 -202.362054)
				(xy 8.839962 -239.862106) (xy 63.840106 -239.862106) (xy 65.227962 -239.862106) (xy 65.227962 -250.381008)
				(xy 62.127892 -253.381002) (xy 62.127892 -264.38098) (xy 65.227962 -267.380974) (xy 65.227962 -273.02206)
				(xy 63.840106 -273.02206) (xy 8.839962 -273.02206) (xy 7.500112 -273.02206)
				(arc
					(start 7.500112 -172.67301)
					(mid 16.765603 -171.221949)
					(end 22.413976 -163.735258)
				)
				(arc
					(start 22.413976 -163.735258)
					(mid 32.598358 -165.983426)
					(end 40.942514 -159.726376)
				)
				(xy 105.350564 -159.726376)
				(arc
					(start 130.606546 -154.51328)
					(mid 132.738329 -154.843602)
					(end 134.880858 -154.592274)
				)
				(arc
					(start 156.677614 -154.99461)
					(mid 155.723561 -157.67418)
					(end 155.399994 -160.50006)
				)
				(arc
					(start 155.399994 -160.50006)
					(mid 167.900096 -173.000162)
					(end 180.399944 -160.50006)
				)
				(arc
					(start 180.399944 -160.50006)
					(mid 180.126434 -157.899482)
					(end 179.317904 -155.412694)
				)
				(arc
					(start 186.151774 -155.538932)
					(mid 193.807273 -161.773584)
					(end 201.687684 -155.825698)
				)
				(arc
					(start 265.830812 -157.0101)
					(mid 277.671779 -166.263793)
					(end 289.846258 -157.45333)
				)
				(arc
					(start 310.686704 -157.83814)
					(mid 310.471853 -159.161401)
					(end 310.399938 -160.50006)
				)
				(arc
					(start 310.399938 -160.50006)
					(mid 322.90004 -173.000162)
					(end 335.399888 -160.50006)
				)
				(arc
					(start 335.399888 -160.50006)
					(mid 335.064753 -157.624496)
					(end 334.077056 -154.90317)
				)
				(arc
					(start 345.280234 -149.293072)
					(mid 346.423043 -150.542461)
					(end 348.051882 -151.005032)
				)
				(xy 348.051882 -163.314888)
				(arc
					(start 419.78199 -163.314888)
					(mid 422.88206 -166.414958)
					(end 425.981876 -163.314888)
				)
				(arc
					(start 433.81803 -163.314888)
					(mid 441.526896 -166.269417)
					(end 449.396358 -163.773866)
				)
				(arc
					(start 449.396358 -163.773866)
					(mid 454.343975 -170.776845)
					(end 462.639918 -172.944282)
				)
				(xy 462.639918 -202.362054) (xy 407.640028 -202.362054) (xy 407.640028 -239.76203) (xy 406.567894 -239.76203)
				(arc
					(start 406.567894 -208.381092)
					(mid 405.8357 -206.613418)
					(end 404.068026 -205.88097)
				)
				(arc
					(start 386.32511 -205.88097)
					(mid 384.684896 -206.494214)
					(end 383.849372 -208.033112)
				)
				(arc
					(start 382.768094 -215.728804)
					(mid 381.932538 -217.267666)
					(end 380.292356 -217.880946)
				)
				(arc
					(start 339.443568 -217.880946)
					(mid 337.80344 -217.267694)
					(end 336.968084 -215.728804)
				)
				(arc
					(start 335.886806 -208.033112)
					(mid 335.05125 -206.49425)
					(end 333.411068 -205.88097)
				)
				(arc
					(start 315.667898 -205.88097)
					(mid 313.900209 -206.613329)
					(end 313.16803 -208.381092)
				)
				(xy 313.16803 -239.76203) (xy 312.040016 -239.76203) (xy 312.040016 -202.362054) (xy 257.040126 -202.362054)
				(xy 257.040126 -239.862106) (xy 312.040016 -239.862106) (xy 313.16803 -239.862106) (xy 313.16803 -250.381008)
				(xy 310.06796 -253.381002) (xy 310.06796 -264.38098) (xy 313.16803 -267.380974) (xy 313.16803 -273.02206)
				(xy 312.040016 -273.02206) (xy 257.040126 -273.02206) (xy 257.040126 -310.522112) (xy 312.040016 -310.522112)
				(xy 312.040016 -273.121882) (xy 313.16803 -273.121882)
				(arc
					(start 313.16803 -309.38089)
					(mid 313.900119 -311.148818)
					(end 315.667898 -311.881012)
				)
				(arc
					(start 333.411068 -311.881012)
					(mid 335.051282 -311.267768)
					(end 335.886806 -309.72887)
				)
				(arc
					(start 336.968084 -302.033178)
					(mid 337.803493 -300.49435)
					(end 339.443568 -299.881036)
				)
				(xy 359.767886 -299.881036) (xy 359.767886 -272.880074)
				(arc
					(start 347.867986 -272.880074)
					(mid 346.100387 -272.1477)
					(end 345.368118 -270.379952)
				)
				(arc
					(start 345.368118 -247.379744)
					(mid 346.100312 -245.61207)
					(end 347.867986 -244.879876)
				)
				(arc
					(start 371.867938 -244.879876)
					(mid 373.635791 -245.612145)
					(end 374.36806 -247.379998)
				)
				(arc
					(start 374.36806 -270.380206)
					(mid 373.635701 -272.147895)
					(end 371.867938 -272.880074)
				)
				(xy 359.867962 -272.880074) (xy 359.867962 -299.881036)
				(arc
					(start 380.19228 -299.881036)
					(mid 381.832494 -300.49428)
					(end 382.668018 -302.033178)
				)
				(arc
					(start 383.749296 -309.72887)
					(mid 384.584852 -311.267732)
					(end 386.225034 -311.881012)
				)
				(arc
					(start 403.96795 -311.881012)
					(mid 405.800679 -311.184991)
					(end 406.567894 -309.38089)
				)
				(xy 406.567894 -273.121882) (xy 407.640028 -273.121882) (xy 407.640028 -310.522112)
			)
		)
	)
	(zone
		(layer "B.Cu")
		(hatch none 0.5)
		(connect_pads
			(clearance 0)
		)
		(min_thickness 0.25)
		(keepout
			(tracks not_allowed)
			(vias allowed)
			(pads allowed)
			(copperpour not_allowed)
			(footprints allowed)
		)
		(placement
			(enabled no)
			(sheetname "")
		)
		(fill
			(thermal_gap 0.5)
			(thermal_bridge_width 0.5)
			(island_removal_mode 0)
		)
		(polygon
			(pts
				(arc
					(start 299.820076 -413.170116)
					(mid 297.570144 -410.920184)
					(end 295.319958 -413.170116)
				)
				(arc
					(start 295.319958 -413.170116)
					(mid 297.570144 -415.420302)
					(end 299.820076 -413.170116)
				)
			)
		)
	)
	(zone
		(layer "B.Cu")
		(hatch none 0.5)
		(connect_pads
			(clearance 0)
		)
		(min_thickness 0.25)
		(keepout
			(tracks not_allowed)
			(vias allowed)
			(pads allowed)
			(copperpour not_allowed)
			(footprints allowed)
		)
		(placement
			(enabled no)
			(sheetname "")
		)
		(fill
			(thermal_gap 0.5)
			(thermal_bridge_width 0.5)
			(island_removal_mode 0)
		)
		(polygon
			(pts
				(arc
					(start 314.905898 -393.69238)
					(mid 314.275978 -393.69238)
					(end 314.905898 -393.69238)
				)
			)
		)
	)
	(zone
		(layer "B.Cu")
		(hatch none 0.5)
		(connect_pads
			(clearance 0)
		)
		(min_thickness 0.25)
		(keepout
			(tracks not_allowed)
			(vias allowed)
			(pads allowed)
			(copperpour not_allowed)
			(footprints allowed)
		)
		(placement
			(enabled no)
			(sheetname "")
		)
		(fill
			(thermal_gap 0.5)
			(thermal_bridge_width 0.5)
			(island_removal_mode 0)
		)
		(polygon
			(pts
				(arc
					(start 72.63003 -258.890008)
					(mid 69.830188 -256.090166)
					(end 67.030092 -258.890008)
				)
				(arc
					(start 67.030092 -258.890008)
					(mid 69.830188 -261.690104)
					(end 72.63003 -258.890008)
				)
			)
		)
	)
	(zone
		(layer "B.Cu")
		(hatch none 0.5)
		(connect_pads
			(clearance 0)
		)
		(min_thickness 0.25)
		(keepout
			(tracks allowed)
			(vias allowed)
			(pads allowed)
			(copperpour allowed)
			(footprints allowed)
		)
		(placement
			(enabled no)
			(sheetname "")
		)
		(fill
			(thermal_gap 0.5)
			(thermal_bridge_width 0.5)
			(island_removal_mode 0)
		)
		(polygon
			(pts
				(xy 384.25374 -139.54506) (xy 384.25374 -138.63066) (xy 385.7625 -138.63066) (xy 385.7625 -139.54506)
			)
		)
	)
	(zone
		(layer "B.Cu")
		(hatch none 0.5)
		(connect_pads
			(clearance 0)
		)
		(min_thickness 0.25)
		(keepout
			(tracks not_allowed)
			(vias allowed)
			(pads allowed)
			(copperpour not_allowed)
			(footprints allowed)
		)
		(placement
			(enabled no)
			(sheetname "")
		)
		(fill
			(thermal_gap 0.5)
			(thermal_bridge_width 0.5)
			(island_removal_mode 0)
		)
		(polygon
			(pts
				(arc
					(start 446.300098 -435.600094)
					(mid 448.80022 -438.100216)
					(end 451.300088 -435.600094)
				)
				(arc
					(start 451.300088 -435.600094)
					(mid 448.80022 -433.100226)
					(end 446.300098 -435.600094)
				)
			)
		)
	)
	(zone
		(layer "B.Cu")
		(hatch none 0.5)
		(connect_pads
			(clearance 0)
		)
		(min_thickness 0.25)
		(keepout
			(tracks allowed)
			(vias allowed)
			(pads allowed)
			(copperpour allowed)
			(footprints not_allowed)
		)
		(placement
			(enabled no)
			(sheetname "")
		)
		(fill
			(thermal_gap 0.5)
			(thermal_bridge_width 0.5)
			(island_removal_mode 0)
		)
		(polygon
			(pts
				(arc
					(start 17.116044 -347.8149)
					(mid 20.216114 -350.91497)
					(end 23.31593 -347.8149)
				)
				(arc
					(start 23.31593 -347.8149)
					(mid 20.216114 -344.715084)
					(end 17.116044 -347.8149)
				)
			)
		)
	)
	(zone
		(layer "B.Cu")
		(hatch none 0.5)
		(connect_pads
			(clearance 0)
		)
		(min_thickness 0.25)
		(keepout
			(tracks not_allowed)
			(vias allowed)
			(pads allowed)
			(copperpour not_allowed)
			(footprints allowed)
		)
		(placement
			(enabled no)
			(sheetname "")
		)
		(fill
			(thermal_gap 0.5)
			(thermal_bridge_width 0.5)
			(island_removal_mode 0)
		)
		(polygon
			(pts
				(arc
					(start 269.316962 -347.8149)
					(mid 267.452094 -345.950032)
					(end 265.586972 -347.8149)
				)
				(arc
					(start 265.586972 -347.8149)
					(mid 267.452094 -349.680022)
					(end 269.316962 -347.8149)
				)
			)
		)
	)
	(zone
		(layer "B.Cu")
		(hatch none 0.5)
		(connect_pads
			(clearance 0)
		)
		(min_thickness 0.25)
		(keepout
			(tracks not_allowed)
			(vias allowed)
			(pads allowed)
			(copperpour not_allowed)
			(footprints allowed)
		)
		(placement
			(enabled no)
			(sheetname "")
		)
		(fill
			(thermal_gap 0.5)
			(thermal_bridge_width 0.5)
			(island_removal_mode 0)
		)
		(polygon
			(pts
				(arc
					(start 421.778176 -401.674838)
					(mid 421.110156 -401.674838)
					(end 421.778176 -401.674838)
				)
			)
		)
	)
	(zone
		(layer "B.Cu")
		(hatch none 0.5)
		(connect_pads
			(clearance 0)
		)
		(min_thickness 0.25)
		(keepout
			(tracks not_allowed)
			(vias allowed)
			(pads allowed)
			(copperpour not_allowed)
			(footprints allowed)
		)
		(placement
			(enabled no)
			(sheetname "")
		)
		(fill
			(thermal_gap 0.5)
			(thermal_bridge_width 0.5)
			(island_removal_mode 0)
		)
		(polygon
			(pts
				(arc
					(start 453.799956 -435.600094)
					(mid 458.799946 -440.600084)
					(end 463.799936 -435.600094)
				)
				(arc
					(start 463.799936 -435.600094)
					(mid 458.799946 -430.600104)
					(end 453.799956 -435.600094)
				)
			)
		)
	)
	(zone
		(layer "B.Cu")
		(hatch none 0.5)
		(connect_pads
			(clearance 0)
		)
		(min_thickness 0.25)
		(keepout
			(tracks allowed)
			(vias allowed)
			(pads allowed)
			(copperpour allowed)
			(footprints allowed)
		)
		(placement
			(enabled no)
			(sheetname "")
		)
		(fill
			(thermal_gap 0.5)
			(thermal_bridge_width 0.5)
			(island_removal_mode 0)
		)
		(polygon
			(pts
				(xy 76.628498 -409.046426) (xy 76.628498 -408.04211) (xy 78.005432 -408.04211) (xy 78.005432 -409.046426)
			)
		)
	)
	(zone
		(layer "B.Cu")
		(hatch none 0.5)
		(connect_pads
			(clearance 0)
		)
		(min_thickness 0.25)
		(keepout
			(tracks not_allowed)
			(vias allowed)
			(pads allowed)
			(copperpour not_allowed)
			(footprints allowed)
		)
		(placement
			(enabled no)
			(sheetname "")
		)
		(fill
			(thermal_gap 0.5)
			(thermal_bridge_width 0.5)
			(island_removal_mode 0)
		)
		(polygon
			(pts
				(arc
					(start 435.749954 -384.869944)
					(mid 433.500022 -382.620012)
					(end 431.25009 -384.869944)
				)
				(arc
					(start 431.25009 -384.869944)
					(mid 433.500022 -387.119876)
					(end 435.749954 -384.869944)
				)
			)
		)
	)
	(zone
		(layer "B.Cu")
		(hatch none 0.5)
		(connect_pads
			(clearance 0)
		)
		(min_thickness 0.25)
		(keepout
			(tracks not_allowed)
			(vias allowed)
			(pads allowed)
			(copperpour not_allowed)
			(footprints allowed)
		)
		(placement
			(enabled no)
			(sheetname "")
		)
		(fill
			(thermal_gap 0.5)
			(thermal_bridge_width 0.5)
			(island_removal_mode 0)
		)
		(polygon
			(pts
				(arc
					(start 317.350394 -400.811238)
					(mid 316.682374 -400.811238)
					(end 317.350394 -400.811238)
				)
			)
		)
	)
	(zone
		(layer "B.Cu")
		(hatch none 0.5)
		(connect_pads
			(clearance 0)
		)
		(min_thickness 0.25)
		(keepout
			(tracks allowed)
			(vias allowed)
			(pads allowed)
			(copperpour allowed)
			(footprints not_allowed)
		)
		(placement
			(enabled no)
			(sheetname "")
		)
		(fill
			(thermal_gap 0.5)
			(thermal_bridge_width 0.5)
			(island_removal_mode 0)
		)
		(polygon
			(pts
				(arc
					(start 57.815988 -167.135048)
					(mid 54.716172 -164.035232)
					(end 51.616102 -167.135048)
				)
				(arc
					(start 51.616102 -167.135048)
					(mid 54.716172 -170.235118)
					(end 57.815988 -167.135048)
				)
			)
		)
	)
	(zone
		(layer "B.Cu")
		(hatch none 0.5)
		(connect_pads
			(clearance 0)
		)
		(min_thickness 0.25)
		(keepout
			(tracks allowed)
			(vias allowed)
			(pads allowed)
			(copperpour allowed)
			(footprints not_allowed)
		)
		(placement
			(enabled no)
			(sheetname "")
		)
		(fill
			(thermal_gap 0.5)
			(thermal_bridge_width 0.5)
			(island_removal_mode 0)
		)
		(polygon
			(pts
				(arc
					(start 270.55191 -347.8149)
					(mid 267.452094 -344.715084)
					(end 264.352024 -347.8149)
				)
				(arc
					(start 264.352024 -347.8149)
					(mid 267.452094 -350.91497)
					(end 270.55191 -347.8149)
				)
			)
		)
	)
	(zone
		(layer "B.Cu")
		(hatch none 0.5)
		(connect_pads
			(clearance 0)
		)
		(min_thickness 0.25)
		(keepout
			(tracks not_allowed)
			(vias allowed)
			(pads allowed)
			(copperpour not_allowed)
			(footprints allowed)
		)
		(placement
			(enabled no)
			(sheetname "")
		)
		(fill
			(thermal_gap 0.5)
			(thermal_bridge_width 0.5)
			(island_removal_mode 0)
		)
		(polygon
			(pts
				(arc
					(start 464.25993 -160.50006)
					(mid 461.460088 -157.700218)
					(end 458.659992 -160.50006)
				)
				(arc
					(start 458.659992 -160.50006)
					(mid 461.460088 -163.300156)
					(end 464.25993 -160.50006)
				)
			)
		)
	)
	(zone
		(layer "B.Cu")
		(hatch none 0.5)
		(connect_pads
			(clearance 0)
		)
		(min_thickness 0.25)
		(keepout
			(tracks allowed)
			(vias allowed)
			(pads allowed)
			(copperpour allowed)
			(footprints not_allowed)
		)
		(placement
			(enabled no)
			(sheetname "")
		)
		(fill
			(thermal_gap 0.5)
			(thermal_bridge_width 0.5)
			(island_removal_mode 0)
		)
		(polygon
			(pts
				(arc
					(start 102.024942 -431.360072)
					(mid 112.024922 -441.360052)
					(end 122.024902 -431.360072)
				)
				(arc
					(start 122.024902 -431.360072)
					(mid 112.024922 -421.360092)
					(end 102.024942 -431.360072)
				)
			)
		)
	)
	(zone
		(layer "B.Cu")
		(hatch none 0.5)
		(connect_pads
			(clearance 0)
		)
		(min_thickness 0.25)
		(keepout
			(tracks allowed)
			(vias allowed)
			(pads allowed)
			(copperpour allowed)
			(footprints not_allowed)
		)
		(placement
			(enabled no)
			(sheetname "")
		)
		(fill
			(thermal_gap 0.5)
			(thermal_bridge_width 0.5)
			(island_removal_mode 0)
		)
		(polygon
			(pts
				(arc
					(start 449.396358 -163.773866)
					(mid 456.478086 -171.964398)
					(end 467.29777 -171.553124)
				)
				(arc
					(start 467.29777 -149.446996)
					(mid 460.475328 -148.03896)
					(end 453.958706 -150.501096)
				)
				(arc
					(start 453.958706 -150.501096)
					(mid 430.07429 -149.711573)
					(end 449.396358 -163.773866)
				)
			)
		)
	)
	(zone
		(layer "B.Cu")
		(hatch none 0.5)
		(connect_pads
			(clearance 0)
		)
		(min_thickness 0.25)
		(keepout
			(tracks not_allowed)
			(vias allowed)
			(pads allowed)
			(copperpour not_allowed)
			(footprints allowed)
		)
		(placement
			(enabled no)
			(sheetname "")
		)
		(fill
			(thermal_gap 0.5)
			(thermal_bridge_width 0.5)
			(island_removal_mode 0)
		)
		(polygon
			(pts
				(arc
					(start 354.696014 -271.656048)
					(mid 354.066094 -271.656048)
					(end 354.696014 -271.656048)
				)
			)
		)
	)
	(zone
		(layer "B.Cu")
		(hatch none 0.5)
		(connect_pads
			(clearance 0)
		)
		(min_thickness 0.25)
		(keepout
			(tracks not_allowed)
			(vias allowed)
			(pads allowed)
			(copperpour not_allowed)
			(footprints allowed)
		)
		(placement
			(enabled no)
			(sheetname "")
		)
		(fill
			(thermal_gap 0.5)
			(thermal_bridge_width 0.5)
			(island_removal_mode 0)
		)
		(polygon
			(pts
				(arc
					(start 51.616102 -167.135048)
					(mid 54.716172 -170.235118)
					(end 57.815988 -167.135048)
				)
				(arc
					(start 57.815988 -167.135048)
					(mid 54.716172 -164.035232)
					(end 51.616102 -167.135048)
				)
			)
		)
	)
	(zone
		(layer "B.Cu")
		(hatch none 0.5)
		(connect_pads
			(clearance 0)
		)
		(min_thickness 0.25)
		(keepout
			(tracks not_allowed)
			(vias allowed)
			(pads allowed)
			(copperpour not_allowed)
			(footprints allowed)
		)
		(placement
			(enabled no)
			(sheetname "")
		)
		(fill
			(thermal_gap 0.5)
			(thermal_bridge_width 0.5)
			(island_removal_mode 0)
		)
		(polygon
			(pts
				(arc
					(start 114.580924 -340.315042)
					(mid 112.716056 -338.450174)
					(end 110.850934 -340.315042)
				)
				(arc
					(start 110.850934 -340.315042)
					(mid 112.716056 -342.180164)
					(end 114.580924 -340.315042)
				)
			)
		)
	)
	(zone
		(layer "B.Cu")
		(hatch none 0.5)
		(connect_pads
			(clearance 0)
		)
		(min_thickness 0.25)
		(keepout
			(tracks not_allowed)
			(vias allowed)
			(pads allowed)
			(copperpour not_allowed)
			(footprints allowed)
		)
		(placement
			(enabled no)
			(sheetname "")
		)
		(fill
			(thermal_gap 0.5)
			(thermal_bridge_width 0.5)
			(island_removal_mode 0)
		)
		(polygon
			(pts
				(arc
					(start 3.770122 -389.439912)
					(mid 6.870192 -392.539982)
					(end 9.970008 -389.439912)
				)
				(arc
					(start 9.970008 -389.439912)
					(mid 6.870192 -386.340096)
					(end 3.770122 -389.439912)
				)
			)
		)
	)
	(zone
		(layer "B.Cu")
		(hatch none 0.5)
		(connect_pads
			(clearance 0)
		)
		(min_thickness 0.25)
		(keepout
			(tracks not_allowed)
			(vias allowed)
			(pads allowed)
			(copperpour not_allowed)
			(footprints allowed)
		)
		(placement
			(enabled no)
			(sheetname "")
		)
		(fill
			(thermal_gap 0.5)
			(thermal_bridge_width 0.5)
			(island_removal_mode 0)
		)
		(polygon
			(pts
				(arc
					(start 356.525068 -431.360072)
					(mid 359.774998 -434.610002)
					(end 363.024928 -431.360072)
				)
				(arc
					(start 363.024928 -431.360072)
					(mid 359.774998 -428.110142)
					(end 356.525068 -431.360072)
				)
			)
		)
	)
	(zone
		(layer "B.Cu")
		(hatch none 0.5)
		(connect_pads
			(clearance 0)
		)
		(min_thickness 0.25)
		(keepout
			(tracks not_allowed)
			(vias allowed)
			(pads allowed)
			(copperpour not_allowed)
			(footprints allowed)
		)
		(placement
			(enabled no)
			(sheetname "")
		)
		(fill
			(thermal_gap 0.5)
			(thermal_bridge_width 0.5)
			(island_removal_mode 0)
		)
		(polygon
			(pts
				(arc
					(start 348.75597 -244.484144)
					(mid 348.12605 -244.484144)
					(end 348.75597 -244.484144)
				)
			)
		)
	)
	(zone
		(layer "B.Cu")
		(hatch none 0.5)
		(connect_pads
			(clearance 0)
		)
		(min_thickness 0.25)
		(keepout
			(tracks not_allowed)
			(vias allowed)
			(pads allowed)
			(copperpour not_allowed)
			(footprints allowed)
		)
		(placement
			(enabled no)
			(sheetname "")
		)
		(fill
			(thermal_gap 0.5)
			(thermal_bridge_width 0.5)
			(island_removal_mode 0)
		)
		(polygon
			(pts
				(arc
					(start 338.036916 -437.889904)
					(mid 337.262724 -437.889904)
					(end 338.036916 -437.889904)
				)
			)
		)
	)
	(zone
		(layer "B.Cu")
		(hatch none 0.5)
		(connect_pads
			(clearance 0)
		)
		(min_thickness 0.25)
		(keepout
			(tracks not_allowed)
			(vias allowed)
			(pads allowed)
			(copperpour not_allowed)
			(footprints allowed)
		)
		(placement
			(enabled no)
			(sheetname "")
		)
		(fill
			(thermal_gap 0.5)
			(thermal_bridge_width 0.5)
			(island_removal_mode 0)
		)
		(polygon
			(pts
				(arc
					(start 147.13712 -436.889906)
					(mid 146.362928 -436.889906)
					(end 147.13712 -436.889906)
				)
			)
		)
	)
	(zone
		(layer "B.Cu")
		(hatch none 0.5)
		(connect_pads
			(clearance 0)
		)
		(min_thickness 0.25)
		(keepout
			(tracks allowed)
			(vias allowed)
			(pads allowed)
			(copperpour allowed)
			(footprints not_allowed)
		)
		(placement
			(enabled no)
			(sheetname "")
		)
		(fill
			(thermal_gap 0.5)
			(thermal_bridge_width 0.5)
			(island_removal_mode 0)
		)
		(polygon
			(pts
				(arc
					(start 209.674968 -360.764074)
					(mid 213.67496 -364.764066)
					(end 217.674952 -360.764074)
				)
				(arc
					(start 217.674952 -360.764074)
					(mid 213.67496 -356.764082)
					(end 209.674968 -360.764074)
				)
			)
		)
	)
	(zone
		(layer "B.Cu")
		(hatch none 0.5)
		(connect_pads
			(clearance 0)
		)
		(min_thickness 0.25)
		(keepout
			(tracks allowed)
			(vias allowed)
			(pads allowed)
			(copperpour allowed)
			(footprints not_allowed)
		)
		(placement
			(enabled no)
			(sheetname "")
		)
		(fill
			(thermal_gap 0.5)
			(thermal_bridge_width 0.5)
			(island_removal_mode 0)
		)
		(polygon
			(pts
				(arc
					(start 449.33997 -40.420036)
					(mid 447.44005 -38.520116)
					(end 445.539876 -40.420036)
				)
				(arc
					(start 445.539876 -40.420036)
					(mid 447.44005 -42.32021)
					(end 449.33997 -40.420036)
				)
			)
		)
	)
	(zone
		(layer "B.Cu")
		(hatch none 0.5)
		(connect_pads
			(clearance 0)
		)
		(min_thickness 0.25)
		(keepout
			(tracks allowed)
			(vias allowed)
			(pads allowed)
			(copperpour allowed)
			(footprints not_allowed)
		)
		(placement
			(enabled no)
			(sheetname "")
		)
		(fill
			(thermal_gap 0.5)
			(thermal_bridge_width 0.5)
			(island_removal_mode 0)
		)
		(polygon
			(pts
				(arc
					(start 375.899934 -22.29993)
					(mid 380.899924 -27.29992)
					(end 385.899914 -22.29993)
				)
				(arc
					(start 385.899914 -22.29993)
					(mid 380.899924 -17.29994)
					(end 375.899934 -22.29993)
				)
			)
		)
	)
	(zone
		(layer "B.Cu")
		(hatch none 0.5)
		(connect_pads
			(clearance 0)
		)
		(min_thickness 0.25)
		(keepout
			(tracks allowed)
			(vias allowed)
			(pads allowed)
			(copperpour allowed)
			(footprints allowed)
		)
		(placement
			(enabled no)
			(sheetname "")
		)
		(fill
			(thermal_gap 0.5)
			(thermal_bridge_width 0.5)
			(island_removal_mode 0)
		)
		(polygon
			(pts
				(xy 454.978008 -46.784768) (xy 454.978008 -44.895008) (xy 457.657454 -44.895008) (xy 457.657454 -46.784768)
			)
		)
	)
	(zone
		(layer "B.Cu")
		(hatch none 0.5)
		(connect_pads
			(clearance 0)
		)
		(min_thickness 0.25)
		(keepout
			(tracks allowed)
			(vias allowed)
			(pads allowed)
			(copperpour allowed)
			(footprints allowed)
		)
		(placement
			(enabled no)
			(sheetname "")
		)
		(fill
			(thermal_gap 0.5)
			(thermal_bridge_width 0.5)
			(island_removal_mode 0)
		)
		(polygon
			(pts
				(xy 338.03844 1.75768) (xy 338.03844 3.76174) (xy 340.08568 3.76174) (xy 340.08568 1.75768)
			)
		)
	)
	(zone
		(layer "B.Cu")
		(hatch none 0.5)
		(connect_pads
			(clearance 0)
		)
		(min_thickness 0.25)
		(keepout
			(tracks not_allowed)
			(vias allowed)
			(pads allowed)
			(copperpour not_allowed)
			(footprints allowed)
		)
		(placement
			(enabled no)
			(sheetname "")
		)
		(fill
			(thermal_gap 0.5)
			(thermal_bridge_width 0.5)
			(island_removal_mode 0)
		)
		(polygon
			(pts
				(arc
					(start 152.578308 -392.429238)
					(mid 151.910288 -392.429238)
					(end 152.578308 -392.429238)
				)
			)
		)
	)
	(zone
		(layer "B.Cu")
		(hatch none 0.5)
		(connect_pads
			(clearance 0)
		)
		(min_thickness 0.25)
		(keepout
			(tracks not_allowed)
			(vias allowed)
			(pads allowed)
			(copperpour not_allowed)
			(footprints allowed)
		)
		(placement
			(enabled no)
			(sheetname "")
		)
		(fill
			(thermal_gap 0.5)
			(thermal_bridge_width 0.5)
			(island_removal_mode 0)
		)
		(polygon
			(pts
				(arc
					(start 149.137116 -439.0898)
					(mid 148.362924 -439.0898)
					(end 149.137116 -439.0898)
				)
			)
		)
	)
	(zone
		(layer "B.Cu")
		(hatch none 0.5)
		(connect_pads
			(clearance 0)
		)
		(min_thickness 0.25)
		(keepout
			(tracks not_allowed)
			(vias allowed)
			(pads allowed)
			(copperpour not_allowed)
			(footprints allowed)
		)
		(placement
			(enabled no)
			(sheetname "")
		)
		(fill
			(thermal_gap 0.5)
			(thermal_bridge_width 0.5)
			(island_removal_mode 0)
		)
		(polygon
			(pts
				(arc
					(start 13.139928 -347.700092)
					(mid 10.340086 -344.90025)
					(end 7.53999 -347.700092)
				)
				(arc
					(start 7.53999 -347.700092)
					(mid 10.340086 -350.500188)
					(end 13.139928 -347.700092)
				)
			)
		)
	)
	(zone
		(layer "B.Cu")
		(hatch none 0.5)
		(connect_pads
			(clearance 0)
		)
		(min_thickness 0.25)
		(keepout
			(tracks not_allowed)
			(vias allowed)
			(pads allowed)
			(copperpour not_allowed)
			(footprints allowed)
		)
		(placement
			(enabled no)
			(sheetname "")
		)
		(fill
			(thermal_gap 0.5)
			(thermal_bridge_width 0.5)
			(island_removal_mode 0)
		)
		(polygon
			(pts
				(arc
					(start 349.696024 -246.104156)
					(mid 349.066104 -246.104156)
					(end 349.696024 -246.104156)
				)
			)
		)
	)
	(zone
		(layer "B.Cu")
		(hatch none 0.5)
		(connect_pads
			(clearance 0)
		)
		(min_thickness 0.25)
		(keepout
			(tracks allowed)
			(vias allowed)
			(pads allowed)
			(copperpour allowed)
			(footprints allowed)
		)
		(placement
			(enabled no)
			(sheetname "")
		)
		(fill
			(thermal_gap 0.5)
			(thermal_bridge_width 0.5)
			(island_removal_mode 0)
		)
		(polygon
			(pts
				(xy 34.849308 -361.09021) (xy 35.853624 -361.09021) (xy 35.853624 -362.467144) (xy 34.849308 -362.467144)
			)
		)
	)
	(zone
		(layer "B.Cu")
		(hatch none 0.5)
		(connect_pads
			(clearance 0)
		)
		(min_thickness 0.25)
		(keepout
			(tracks allowed)
			(vias allowed)
			(pads allowed)
			(copperpour allowed)
			(footprints allowed)
		)
		(placement
			(enabled no)
			(sheetname "")
		)
		(fill
			(thermal_gap 0.5)
			(thermal_bridge_width 0.5)
			(island_removal_mode 0)
		)
		(polygon
			(pts
				(xy 335.311496 -337.250278) (xy 335.311496 -339.409278) (xy 334.930496 -339.790278) (xy 332.136496 -339.790278)
				(xy 330.993496 -338.647278) (xy 330.993496 -335.726278) (xy 331.501496 -335.218278) (xy 333.279496 -335.218278)
			)
		)
	)
	(zone
		(layer "B.Cu")
		(hatch none 0.5)
		(connect_pads
			(clearance 0)
		)
		(min_thickness 0.25)
		(keepout
			(tracks allowed)
			(vias allowed)
			(pads allowed)
			(copperpour allowed)
			(footprints allowed)
		)
		(placement
			(enabled no)
			(sheetname "")
		)
		(fill
			(thermal_gap 0.5)
			(thermal_bridge_width 0.5)
			(island_removal_mode 0)
		)
		(polygon
			(pts
				(xy 131.47548 -409.046426) (xy 131.47548 -408.04211) (xy 132.852414 -408.04211) (xy 132.852414 -409.046426)
			)
		)
	)
	(zone
		(layer "B.Cu")
		(hatch none 0.5)
		(connect_pads
			(clearance 0)
		)
		(min_thickness 0.25)
		(keepout
			(tracks allowed)
			(vias allowed)
			(pads allowed)
			(copperpour allowed)
			(footprints allowed)
		)
		(placement
			(enabled no)
			(sheetname "")
		)
		(fill
			(thermal_gap 0.5)
			(thermal_bridge_width 0.5)
			(island_removal_mode 0)
		)
		(polygon
			(pts
				(xy 326.50176 -417.428426) (xy 326.50176 -416.42411) (xy 327.878694 -416.42411) (xy 327.878694 -417.428426)
			)
		)
	)
	(zone
		(layer "B.Cu")
		(hatch none 0.5)
		(connect_pads
			(clearance 0)
		)
		(min_thickness 0.25)
		(keepout
			(tracks not_allowed)
			(vias allowed)
			(pads allowed)
			(copperpour not_allowed)
			(footprints allowed)
		)
		(placement
			(enabled no)
			(sheetname "")
		)
		(fill
			(thermal_gap 0.5)
			(thermal_bridge_width 0.5)
			(island_removal_mode 0)
		)
		(polygon
			(pts
				(arc
					(start 173.500034 -376.489976)
					(mid 177.500026 -380.489968)
					(end 181.500018 -376.489976)
				)
				(arc
					(start 181.500018 -376.489976)
					(mid 177.500026 -372.489984)
					(end 173.500034 -376.489976)
				)
			)
		)
	)
	(zone
		(layer "B.Cu")
		(hatch none 0.5)
		(connect_pads
			(clearance 0)
		)
		(min_thickness 0.25)
		(keepout
			(tracks not_allowed)
			(vias allowed)
			(pads allowed)
			(copperpour not_allowed)
			(footprints allowed)
		)
		(placement
			(enabled no)
			(sheetname "")
		)
		(fill
			(thermal_gap 0.5)
			(thermal_bridge_width 0.5)
			(island_removal_mode 0)
		)
		(polygon
			(pts
				(arc
					(start 150.178262 -393.292838)
					(mid 149.510242 -393.292838)
					(end 150.178262 -393.292838)
				)
			)
		)
	)
	(zone
		(layer "B.Cu")
		(hatch none 0.5)
		(connect_pads
			(clearance 0)
		)
		(min_thickness 0.25)
		(keepout
			(tracks not_allowed)
			(vias allowed)
			(pads allowed)
			(copperpour not_allowed)
			(footprints allowed)
		)
		(placement
			(enabled no)
			(sheetname "")
		)
		(fill
			(thermal_gap 0.5)
			(thermal_bridge_width 0.5)
			(island_removal_mode 0)
		)
		(polygon
			(pts
				(arc
					(start 411.1371 -436.889906)
					(mid 410.362908 -436.889906)
					(end 411.1371 -436.889906)
				)
			)
		)
	)
	(zone
		(layer "B.Cu")
		(hatch none 0.5)
		(connect_pads
			(clearance 0)
		)
		(min_thickness 0.25)
		(keepout
			(tracks not_allowed)
			(vias allowed)
			(pads allowed)
			(copperpour not_allowed)
			(footprints allowed)
		)
		(placement
			(enabled no)
			(sheetname "")
		)
		(fill
			(thermal_gap 0.5)
			(thermal_bridge_width 0.5)
			(island_removal_mode 0)
		)
		(polygon
			(pts
				(arc
					(start 361.362498 -431.360072)
					(mid 359.774998 -429.772572)
					(end 358.187498 -431.360072)
				)
				(arc
					(start 358.187498 -431.360072)
					(mid 359.774998 -432.947572)
					(end 361.362498 -431.360072)
				)
			)
		)
	)
	(zone
		(layer "B.Cu")
		(hatch none 0.5)
		(connect_pads
			(clearance 0)
		)
		(min_thickness 0.25)
		(keepout
			(tracks not_allowed)
			(vias allowed)
			(pads allowed)
			(copperpour not_allowed)
			(footprints allowed)
		)
		(placement
			(enabled no)
			(sheetname "")
		)
		(fill
			(thermal_gap 0.5)
			(thermal_bridge_width 0.5)
			(island_removal_mode 0)
		)
		(polygon
			(pts
				(arc
					(start 357.686102 -243.674138)
					(mid 357.056182 -243.674138)
					(end 357.686102 -243.674138)
				)
			)
		)
	)
	(zone
		(layer "B.Cu")
		(hatch none 0.5)
		(connect_pads
			(clearance 0)
		)
		(min_thickness 0.25)
		(keepout
			(tracks allowed)
			(vias allowed)
			(pads allowed)
			(copperpour allowed)
			(footprints not_allowed)
		)
		(placement
			(enabled no)
			(sheetname "")
		)
		(fill
			(thermal_gap 0.5)
			(thermal_bridge_width 0.5)
			(island_removal_mode 0)
		)
		(polygon
			(pts
				(arc
					(start 464.300062 -439.989976)
					(mid 464.007169 -440.697081)
					(end 463.300064 -440.989974)
				)
				(arc
					(start 442.88837 -440.989974)
					(mid 441.562076 -432.192643)
					(end 449.18757 -427.609508)
				)
				(arc
					(start 449.18757 -427.609508)
					(mid 456.184065 -423.376839)
					(end 464.300062 -424.375072)
				)
			)
		)
	)
	(zone
		(layer "B.Cu")
		(hatch none 0.5)
		(connect_pads
			(clearance 0)
		)
		(min_thickness 0.25)
		(keepout
			(tracks allowed)
			(vias allowed)
			(pads allowed)
			(copperpour allowed)
			(footprints not_allowed)
		)
		(placement
			(enabled no)
			(sheetname "")
		)
		(fill
			(thermal_gap 0.5)
			(thermal_bridge_width 0.5)
			(island_removal_mode 0)
		)
		(polygon
			(pts
				(arc
					(start 66.580004 -258.890008)
					(mid 69.830188 -262.140192)
					(end 73.080118 -258.890008)
				)
				(arc
					(start 73.080118 -258.890008)
					(mid 69.830188 -255.640078)
					(end 66.580004 -258.890008)
				)
			)
		)
	)
	(zone
		(layer "B.Cu")
		(hatch none 0.5)
		(connect_pads
			(clearance 0)
		)
		(min_thickness 0.25)
		(keepout
			(tracks not_allowed)
			(vias allowed)
			(pads allowed)
			(copperpour not_allowed)
			(footprints allowed)
		)
		(placement
			(enabled no)
			(sheetname "")
		)
		(fill
			(thermal_gap 0.5)
			(thermal_bridge_width 0.5)
			(island_removal_mode 0)
		)
		(polygon
			(pts
				(arc
					(start 158.578296 -393.292838)
					(mid 157.910276 -393.292838)
					(end 158.578296 -393.292838)
				)
			)
		)
	)
	(zone
		(layer "B.Cu")
		(hatch none 0.5)
		(connect_pads
			(clearance 0)
		)
		(min_thickness 0.25)
		(keepout
			(tracks allowed)
			(vias allowed)
			(pads allowed)
			(copperpour allowed)
			(footprints not_allowed)
		)
		(placement
			(enabled no)
			(sheetname "")
		)
		(fill
			(thermal_gap 0.5)
			(thermal_bridge_width 0.5)
			(island_removal_mode 0)
		)
		(polygon
			(pts
				(arc
					(start 17.45488 -153.766012)
					(mid 29.954982 -166.266114)
					(end 42.455084 -153.766012)
				)
				(arc
					(start 42.455084 -153.766012)
					(mid 29.954982 -141.26591)
					(end 17.45488 -153.766012)
				)
			)
		)
	)
	(zone
		(layer "B.Cu")
		(hatch none 0.5)
		(connect_pads
			(clearance 0)
		)
		(min_thickness 0.25)
		(keepout
			(tracks allowed)
			(vias allowed)
			(pads allowed)
			(copperpour allowed)
			(footprints not_allowed)
		)
		(placement
			(enabled no)
			(sheetname "")
		)
		(fill
			(thermal_gap 0.5)
			(thermal_bridge_width 0.5)
			(island_removal_mode 0)
		)
		(polygon
			(pts
				(arc
					(start 103.300276 -435.600094)
					(mid 100.500434 -432.800252)
					(end 97.700338 -435.600094)
				)
				(arc
					(start 97.700338 -435.600094)
					(mid 100.500434 -438.40019)
					(end 103.300276 -435.600094)
				)
			)
		)
	)
	(zone
		(layer "B.Cu")
		(hatch none 0.5)
		(connect_pads
			(clearance 0)
		)
		(min_thickness 0.25)
		(keepout
			(tracks allowed)
			(vias allowed)
			(pads allowed)
			(copperpour allowed)
			(footprints not_allowed)
		)
		(placement
			(enabled no)
			(sheetname "")
		)
		(fill
			(thermal_gap 0.5)
			(thermal_bridge_width 0.5)
			(island_removal_mode 0)
		)
		(polygon
			(pts
				(xy 8.839962 -310.522112) (xy 8.839962 -273.02206) (xy 63.840106 -273.02206) (xy 63.840106 -310.522112)
			)
		)
	)
	(zone
		(layer "B.Cu")
		(hatch none 0.5)
		(connect_pads
			(clearance 0)
		)
		(min_thickness 0.25)
		(keepout
			(tracks allowed)
			(vias allowed)
			(pads allowed)
			(copperpour allowed)
			(footprints allowed)
		)
		(placement
			(enabled no)
			(sheetname "")
		)
		(fill
			(thermal_gap 0.5)
			(thermal_bridge_width 0.5)
			(island_removal_mode 0)
		)
		(polygon
			(pts
				(xy 377.97486 -3.2512) (xy 377.97486 -1.15824) (xy 380.20244 -1.15824) (xy 380.20244 -3.2512)
			)
		)
	)
	(zone
		(layer "B.Cu")
		(hatch none 0.5)
		(connect_pads
			(clearance 0)
		)
		(min_thickness 0.25)
		(keepout
			(tracks allowed)
			(vias allowed)
			(pads allowed)
			(copperpour allowed)
			(footprints not_allowed)
		)
		(placement
			(enabled no)
			(sheetname "")
		)
		(fill
			(thermal_gap 0.5)
			(thermal_bridge_width 0.5)
			(island_removal_mode 0)
		)
		(polygon
			(pts
				(arc
					(start 374.098566 -435.600094)
					(mid 371.298724 -432.800252)
					(end 368.498628 -435.600094)
				)
				(arc
					(start 368.498628 -435.600094)
					(mid 371.298724 -438.40019)
					(end 374.098566 -435.600094)
				)
			)
		)
	)
	(zone
		(layer "B.Cu")
		(hatch none 0.5)
		(connect_pads
			(clearance 0)
		)
		(min_thickness 0.25)
		(keepout
			(tracks not_allowed)
			(vias allowed)
			(pads allowed)
			(copperpour not_allowed)
			(footprints allowed)
		)
		(placement
			(enabled no)
			(sheetname "")
		)
		(fill
			(thermal_gap 0.5)
			(thermal_bridge_width 0.5)
			(island_removal_mode 0)
		)
		(polygon
			(pts
				(arc
					(start 357.046022 -274.086066)
					(mid 356.416102 -274.086066)
					(end 357.046022 -274.086066)
				)
			)
		)
	)
	(zone
		(layer "B.Cu")
		(hatch none 0.5)
		(connect_pads
			(clearance 0)
		)
		(min_thickness 0.25)
		(keepout
			(tracks not_allowed)
			(vias allowed)
			(pads allowed)
			(copperpour not_allowed)
			(footprints allowed)
		)
		(placement
			(enabled no)
			(sheetname "")
		)
		(fill
			(thermal_gap 0.5)
			(thermal_bridge_width 0.5)
			(island_removal_mode 0)
		)
		(polygon
			(pts
				(arc
					(start 461.600042 -435.600094)
					(mid 458.8002 -432.800252)
					(end 456.000104 -435.600094)
				)
				(arc
					(start 456.000104 -435.600094)
					(mid 458.8002 -438.40019)
					(end 461.600042 -435.600094)
				)
			)
		)
	)
	(zone
		(layer "B.Cu")
		(hatch none 0.5)
		(connect_pads
			(clearance 0)
		)
		(min_thickness 0.25)
		(keepout
			(tracks allowed)
			(vias allowed)
			(pads allowed)
			(copperpour allowed)
			(footprints allowed)
		)
		(placement
			(enabled no)
			(sheetname "")
		)
		(fill
			(thermal_gap 0.5)
			(thermal_bridge_width 0.5)
			(island_removal_mode 0)
		)
		(polygon
			(pts
				(xy 128.41224 -409.046426) (xy 128.41224 -408.04211) (xy 129.789174 -408.04211) (xy 129.789174 -409.046426)
			)
		)
	)
	(zone
		(layer "B.Cu")
		(hatch none 0.5)
		(connect_pads
			(clearance 0)
		)
		(min_thickness 0.25)
		(keepout
			(tracks allowed)
			(vias allowed)
			(pads allowed)
			(copperpour allowed)
			(footprints allowed)
		)
		(placement
			(enabled no)
			(sheetname "")
		)
		(fill
			(thermal_gap 0.5)
			(thermal_bridge_width 0.5)
			(island_removal_mode 0)
		)
		(polygon
			(pts
				(xy 132.341366 -154.455876) (xy 132.341366 -152.296876) (xy 132.722366 -151.915876) (xy 135.516366 -151.915876)
				(xy 136.659366 -153.058876) (xy 136.659366 -155.979876) (xy 136.151366 -156.487876) (xy 134.373366 -156.487876)
			)
		)
	)
	(zone
		(layer "B.Cu")
		(hatch none 0.5)
		(connect_pads
			(clearance 0)
		)
		(min_thickness 0.25)
		(keepout
			(tracks allowed)
			(vias allowed)
			(pads allowed)
			(copperpour allowed)
			(footprints allowed)
		)
		(placement
			(enabled no)
			(sheetname "")
		)
		(fill
			(thermal_gap 0.5)
			(thermal_bridge_width 0.5)
			(island_removal_mode 0)
		)
		(polygon
			(pts
				(xy 432.242976 -353.41687) (xy 432.242976 -355.57587) (xy 431.861976 -355.95687) (xy 429.067976 -355.95687)
				(xy 427.924976 -354.81387) (xy 427.924976 -351.89287) (xy 428.432976 -351.38487) (xy 430.210976 -351.38487)
			)
		)
	)
	(zone
		(layer "B.Cu")
		(hatch none 0.5)
		(connect_pads
			(clearance 0)
		)
		(min_thickness 0.25)
		(keepout
			(tracks allowed)
			(vias allowed)
			(pads allowed)
			(copperpour allowed)
			(footprints not_allowed)
		)
		(placement
			(enabled no)
			(sheetname "")
		)
		(fill
			(thermal_gap 0.5)
			(thermal_bridge_width 0.5)
			(island_removal_mode 0)
		)
		(polygon
			(pts
				(arc
					(start 230.650034 -44.494958)
					(mid 228.650038 -42.494962)
					(end 226.650042 -44.494958)
				)
				(arc
					(start 226.650042 -44.494958)
					(mid 228.650038 -46.494954)
					(end 230.650034 -44.494958)
				)
			)
		)
	)
	(zone
		(layer "B.Cu")
		(hatch none 0.5)
		(connect_pads
			(clearance 0)
		)
		(min_thickness 0.25)
		(keepout
			(tracks not_allowed)
			(vias allowed)
			(pads allowed)
			(copperpour not_allowed)
			(footprints allowed)
		)
		(placement
			(enabled no)
			(sheetname "")
		)
		(fill
			(thermal_gap 0.5)
			(thermal_bridge_width 0.5)
			(island_removal_mode 0)
		)
		(polygon
			(pts
				(arc
					(start 323.036692 -438.089802)
					(mid 322.2625 -438.089802)
					(end 323.036692 -438.089802)
				)
			)
		)
	)
	(zone
		(layer "B.Cu")
		(hatch none 0.5)
		(connect_pads
			(clearance 0)
		)
		(min_thickness 0.25)
		(keepout
			(tracks allowed)
			(vias allowed)
			(pads allowed)
			(copperpour allowed)
			(footprints allowed)
		)
		(placement
			(enabled no)
			(sheetname "")
		)
		(fill
			(thermal_gap 0.5)
			(thermal_bridge_width 0.5)
			(island_removal_mode 0)
		)
		(polygon
			(pts
				(xy 355.76129 -167.219376) (xy 355.76129 -165.060376) (xy 356.14229 -164.679376) (xy 358.93629 -164.679376)
				(xy 360.07929 -165.822376) (xy 360.07929 -168.743376) (xy 359.57129 -169.251376) (xy 357.79329 -169.251376)
			)
		)
	)
	(zone
		(layer "B.Cu")
		(hatch none 0.5)
		(connect_pads
			(clearance 0)
		)
		(min_thickness 0.25)
		(keepout
			(tracks not_allowed)
			(vias allowed)
			(pads allowed)
			(copperpour not_allowed)
			(footprints allowed)
		)
		(placement
			(enabled no)
			(sheetname "")
		)
		(fill
			(thermal_gap 0.5)
			(thermal_bridge_width 0.5)
			(island_removal_mode 0)
		)
		(polygon
			(pts
				(arc
					(start 313.750452 -401.674838)
					(mid 313.082432 -401.674838)
					(end 313.750452 -401.674838)
				)
			)
		)
	)
	(zone
		(layer "B.Cu")
		(hatch none 0.5)
		(connect_pads
			(clearance 0)
		)
		(min_thickness 0.25)
		(keepout
			(tracks allowed)
			(vias allowed)
			(pads allowed)
			(copperpour allowed)
			(footprints allowed)
		)
		(placement
			(enabled no)
			(sheetname "")
		)
		(fill
			(thermal_gap 0.5)
			(thermal_bridge_width 0.5)
			(island_removal_mode 0)
		)
		(polygon
			(pts
				(xy 389.751062 -315.587888) (xy 389.751062 -314.234576) (xy 392.62177 -314.234576) (xy 392.62177 -315.587888)
			)
		)
	)
	(zone
		(layer "B.Cu")
		(hatch none 0.5)
		(connect_pads
			(clearance 0)
		)
		(min_thickness 0.25)
		(keepout
			(tracks not_allowed)
			(vias allowed)
			(pads allowed)
			(copperpour not_allowed)
			(footprints allowed)
		)
		(placement
			(enabled no)
			(sheetname "")
		)
		(fill
			(thermal_gap 0.5)
			(thermal_bridge_width 0.5)
			(island_removal_mode 0)
		)
		(polygon
			(pts
				(arc
					(start 251.765054 -290.900104)
					(mid 249.900186 -289.035236)
					(end 248.035064 -290.900104)
				)
				(arc
					(start 248.035064 -290.900104)
					(mid 249.900186 -292.765226)
					(end 251.765054 -290.900104)
				)
			)
		)
	)
	(zone
		(layer "B.Cu")
		(hatch none 0.5)
		(connect_pads
			(clearance 0)
		)
		(min_thickness 0.25)
		(keepout
			(tracks not_allowed)
			(vias allowed)
			(pads allowed)
			(copperpour not_allowed)
			(footprints allowed)
		)
		(placement
			(enabled no)
			(sheetname "")
		)
		(fill
			(thermal_gap 0.5)
			(thermal_bridge_width 0.5)
			(island_removal_mode 0)
		)
		(polygon
			(pts
				(arc
					(start 383.70002 -22.29993)
					(mid 380.900178 -19.500088)
					(end 378.100082 -22.29993)
				)
				(arc
					(start 378.100082 -22.29993)
					(mid 380.900178 -25.100026)
					(end 383.70002 -22.29993)
				)
			)
		)
	)
	(zone
		(layer "B.Cu")
		(hatch none 0.5)
		(connect_pads
			(clearance 0)
		)
		(min_thickness 0.25)
		(keepout
			(tracks allowed)
			(vias allowed)
			(pads allowed)
			(copperpour allowed)
			(footprints not_allowed)
		)
		(placement
			(enabled no)
			(sheetname "")
		)
		(fill
			(thermal_gap 0.5)
			(thermal_bridge_width 0.5)
			(island_removal_mode 0)
		)
		(polygon
			(pts
				(arc
					(start 250.124976 -360.764074)
					(mid 258.12496 -368.764058)
					(end 266.124944 -360.764074)
				)
				(arc
					(start 266.124944 -360.764074)
					(mid 258.12496 -352.76409)
					(end 250.124976 -360.764074)
				)
			)
		)
	)
	(zone
		(layer "B.Cu")
		(hatch none 0.5)
		(connect_pads
			(clearance 0)
		)
		(min_thickness 0.25)
		(keepout
			(tracks allowed)
			(vias allowed)
			(pads allowed)
			(copperpour allowed)
			(footprints not_allowed)
		)
		(placement
			(enabled no)
			(sheetname "")
		)
		(fill
			(thermal_gap 0.5)
			(thermal_bridge_width 0.5)
			(island_removal_mode 0)
		)
		(polygon
			(pts
				(arc
					(start 139.029948 -212.989922)
					(mid 142.530068 -216.490042)
					(end 146.029934 -212.989922)
				)
				(arc
					(start 146.029934 -212.989922)
					(mid 142.530068 -209.490056)
					(end 139.029948 -212.989922)
				)
			)
		)
	)
	(zone
		(layer "B.Cu")
		(hatch none 0.5)
		(connect_pads
			(clearance 0)
		)
		(min_thickness 0.25)
		(keepout
			(tracks allowed)
			(vias allowed)
			(pads allowed)
			(copperpour allowed)
			(footprints not_allowed)
		)
		(placement
			(enabled no)
			(sheetname "")
		)
		(fill
			(thermal_gap 0.5)
			(thermal_bridge_width 0.5)
			(island_removal_mode 0)
		)
		(polygon
			(pts
				(arc
					(start 419.78199 -163.314888)
					(mid 422.88206 -166.414958)
					(end 425.981876 -163.314888)
				)
				(arc
					(start 425.981876 -163.314888)
					(mid 422.88206 -160.215072)
					(end 419.78199 -163.314888)
				)
			)
		)
	)
	(zone
		(layer "B.Cu")
		(hatch none 0.5)
		(connect_pads
			(clearance 0)
		)
		(min_thickness 0.25)
		(keepout
			(tracks not_allowed)
			(vias allowed)
			(pads allowed)
			(copperpour not_allowed)
			(footprints allowed)
		)
		(placement
			(enabled no)
			(sheetname "")
		)
		(fill
			(thermal_gap 0.5)
			(thermal_bridge_width 0.5)
			(island_removal_mode 0)
		)
		(polygon
			(pts
				(arc
					(start 8.73506 -389.439912)
					(mid 6.870192 -387.575044)
					(end 5.00507 -389.439912)
				)
				(arc
					(start 5.00507 -389.439912)
					(mid 6.870192 -391.305034)
					(end 8.73506 -389.439912)
				)
			)
		)
	)
	(zone
		(layer "B.Cu")
		(hatch none 0.5)
		(connect_pads
			(clearance 0)
		)
		(min_thickness 0.25)
		(keepout
			(tracks allowed)
			(vias allowed)
			(pads allowed)
			(copperpour allowed)
			(footprints not_allowed)
		)
		(placement
			(enabled no)
			(sheetname "")
		)
		(fill
			(thermal_gap 0.5)
			(thermal_bridge_width 0.5)
			(island_removal_mode 0)
		)
		(polygon
			(pts
				(arc
					(start 62.782958 -45.449998)
					(mid 61.183012 -47.049944)
					(end 62.782958 -48.64989)
				)
				(arc
					(start 64.382904 -48.64989)
					(mid 65.98285 -47.049944)
					(end 64.382904 -45.449998)
				)
			)
		)
	)
	(zone
		(layer "B.Cu")
		(hatch none 0.5)
		(connect_pads
			(clearance 0)
		)
		(min_thickness 0.25)
		(keepout
			(tracks not_allowed)
			(vias allowed)
			(pads allowed)
			(copperpour not_allowed)
			(footprints allowed)
		)
		(placement
			(enabled no)
			(sheetname "")
		)
		(fill
			(thermal_gap 0.5)
			(thermal_bridge_width 0.5)
			(island_removal_mode 0)
		)
		(polygon
			(pts
				(arc
					(start 138.136884 -438.089802)
					(mid 137.362692 -438.089802)
					(end 138.136884 -438.089802)
				)
			)
		)
	)
	(zone
		(layer "B.Cu")
		(hatch none 0.5)
		(connect_pads
			(clearance 0)
		)
		(min_thickness 0.25)
		(keepout
			(tracks not_allowed)
			(vias allowed)
			(pads allowed)
			(copperpour not_allowed)
			(footprints allowed)
		)
		(placement
			(enabled no)
			(sheetname "")
		)
		(fill
			(thermal_gap 0.5)
			(thermal_bridge_width 0.5)
			(island_removal_mode 0)
		)
		(polygon
			(pts
				(arc
					(start 391.387076 -173.315122)
					(mid 389.522208 -171.450254)
					(end 387.657086 -173.315122)
				)
				(arc
					(start 387.657086 -173.315122)
					(mid 389.522208 -175.180244)
					(end 391.387076 -173.315122)
				)
			)
		)
	)
	(zone
		(layer "B.Cu")
		(hatch none 0.5)
		(connect_pads
			(clearance 0)
		)
		(min_thickness 0.25)
		(keepout
			(tracks not_allowed)
			(vias allowed)
			(pads allowed)
			(copperpour not_allowed)
			(footprints allowed)
		)
		(placement
			(enabled no)
			(sheetname "")
		)
		(fill
			(thermal_gap 0.5)
			(thermal_bridge_width 0.5)
			(island_removal_mode 0)
		)
		(polygon
			(pts
				(arc
					(start 88.037162 -438.089802)
					(mid 87.26297 -438.089802)
					(end 88.037162 -438.089802)
				)
			)
		)
	)
	(zone
		(layer "B.Cu")
		(hatch none 0.5)
		(connect_pads
			(clearance 0)
		)
		(min_thickness 0.25)
		(keepout
			(tracks allowed)
			(vias allowed)
			(pads allowed)
			(copperpour allowed)
			(footprints allowed)
		)
		(placement
			(enabled no)
			(sheetname "")
		)
		(fill
			(thermal_gap 0.5)
			(thermal_bridge_width 0.5)
			(island_removal_mode 0)
		)
		(polygon
			(pts
				(xy 12.95908 -115.16868) (xy 11.30808 -115.16868) (xy 11.30808 -114.20348) (xy 12.95908 -114.20348)
			)
		)
	)
	(zone
		(layer "B.Cu")
		(hatch none 0.5)
		(connect_pads
			(clearance 0)
		)
		(min_thickness 0.25)
		(keepout
			(tracks not_allowed)
			(vias allowed)
			(pads allowed)
			(copperpour not_allowed)
			(footprints allowed)
		)
		(placement
			(enabled no)
			(sheetname "")
		)
		(fill
			(thermal_gap 0.5)
			(thermal_bridge_width 0.5)
			(island_removal_mode 0)
		)
		(polygon
			(pts
				(arc
					(start 413.378396 -400.811238)
					(mid 412.710376 -400.811238)
					(end 413.378396 -400.811238)
				)
			)
		)
	)
	(zone
		(layer "B.Cu")
		(hatch none 0.5)
		(connect_pads
			(clearance 0)
		)
		(min_thickness 0.25)
		(keepout
			(tracks allowed)
			(vias allowed)
			(pads allowed)
			(copperpour allowed)
			(footprints not_allowed)
		)
		(placement
			(enabled no)
			(sheetname "")
		)
		(fill
			(thermal_gap 0.5)
			(thermal_bridge_width 0.5)
			(island_removal_mode 0)
		)
		(polygon
			(pts
				(arc
					(start 174.749968 -435.600094)
					(mid 179.749958 -440.600084)
					(end 184.749948 -435.600094)
				)
				(arc
					(start 184.749948 -435.600094)
					(mid 179.749958 -430.600104)
					(end 174.749968 -435.600094)
				)
			)
		)
	)
	(zone
		(layer "B.Cu")
		(hatch none 0.5)
		(connect_pads
			(clearance 0)
		)
		(min_thickness 0.25)
		(keepout
			(tracks not_allowed)
			(vias allowed)
			(pads allowed)
			(copperpour not_allowed)
			(footprints allowed)
		)
		(placement
			(enabled no)
			(sheetname "")
		)
		(fill
			(thermal_gap 0.5)
			(thermal_bridge_width 0.5)
			(island_removal_mode 0)
		)
		(polygon
			(pts
				(arc
					(start 39.45255 -425.909994)
					(mid 38.78453 -425.909994)
					(end 39.45255 -425.909994)
				)
			)
		)
	)
	(zone
		(layer "B.Cu")
		(hatch none 0.5)
		(connect_pads
			(clearance 0)
		)
		(min_thickness 0.25)
		(keepout
			(tracks allowed)
			(vias allowed)
			(pads allowed)
			(copperpour allowed)
			(footprints allowed)
		)
		(placement
			(enabled no)
			(sheetname "")
		)
		(fill
			(thermal_gap 0.5)
			(thermal_bridge_width 0.5)
			(island_removal_mode 0)
		)
		(polygon
			(pts
				(xy 35.294062 -362.753402) (xy 35.294062 -363.757718) (xy 33.917128 -363.757718) (xy 33.917128 -362.753402)
			)
		)
	)
	(zone
		(layer "B.Cu")
		(hatch none 0.5)
		(connect_pads
			(clearance 0)
		)
		(min_thickness 0.25)
		(keepout
			(tracks allowed)
			(vias allowed)
			(pads allowed)
			(copperpour allowed)
			(footprints allowed)
		)
		(placement
			(enabled no)
			(sheetname "")
		)
		(fill
			(thermal_gap 0.5)
			(thermal_bridge_width 0.5)
			(island_removal_mode 0)
		)
		(polygon
			(pts
				(xy 249.638312 -42.39006) (xy 252.850142 -42.39006) (xy 252.850142 -47.408592) (xy 249.638312 -47.408592)
			)
		)
	)
	(zone
		(layer "B.Cu")
		(hatch none 0.5)
		(connect_pads
			(clearance 0)
		)
		(min_thickness 0.25)
		(keepout
			(tracks not_allowed)
			(vias allowed)
			(pads allowed)
			(copperpour not_allowed)
			(footprints allowed)
		)
		(placement
			(enabled no)
			(sheetname "")
		)
		(fill
			(thermal_gap 0.5)
			(thermal_bridge_width 0.5)
			(island_removal_mode 0)
		)
		(polygon
			(pts
				(arc
					(start 78.037182 -437.889904)
					(mid 77.26299 -437.889904)
					(end 78.037182 -437.889904)
				)
			)
		)
	)
	(zone
		(layer "B.Cu")
		(hatch none 0.5)
		(connect_pads
			(clearance 0)
		)
		(min_thickness 0.25)
		(keepout
			(tracks not_allowed)
			(vias allowed)
			(pads allowed)
			(copperpour not_allowed)
			(footprints allowed)
		)
		(placement
			(enabled no)
			(sheetname "")
		)
		(fill
			(thermal_gap 0.5)
			(thermal_bridge_width 0.5)
			(island_removal_mode 0)
		)
		(polygon
			(pts
				(arc
					(start 412.178246 -401.674838)
					(mid 411.510226 -401.674838)
					(end 412.178246 -401.674838)
				)
			)
		)
	)
	(zone
		(layer "B.Cu")
		(hatch none 0.5)
		(connect_pads
			(clearance 0)
		)
		(min_thickness 0.25)
		(keepout
			(tracks allowed)
			(vias allowed)
			(pads allowed)
			(copperpour allowed)
			(footprints not_allowed)
		)
		(placement
			(enabled no)
			(sheetname "")
		)
		(fill
			(thermal_gap 0.5)
			(thermal_bridge_width 0.5)
			(island_removal_mode 0)
		)
		(polygon
			(pts
				(arc
					(start 459.799944 -22.29993)
					(mid 464.799934 -27.29992)
					(end 469.799924 -22.29993)
				)
				(arc
					(start 469.799924 -22.29993)
					(mid 464.799934 -17.29994)
					(end 459.799944 -22.29993)
				)
			)
		)
	)
	(zone
		(layer "B.Cu")
		(hatch none 0.5)
		(connect_pads
			(clearance 0)
		)
		(min_thickness 0.25)
		(keepout
			(tracks allowed)
			(vias allowed)
			(pads allowed)
			(copperpour allowed)
			(footprints allowed)
		)
		(placement
			(enabled no)
			(sheetname "")
		)
		(fill
			(thermal_gap 0.5)
			(thermal_bridge_width 0.5)
			(island_removal_mode 0)
		)
		(polygon
			(pts
				(xy 259.12318 6.99008) (xy 259.12318 8.9027) (xy 261.70382 8.9027) (xy 261.70382 6.99008)
			)
		)
	)
	(zone
		(layer "B.Cu")
		(hatch none 0.5)
		(connect_pads
			(clearance 0)
		)
		(min_thickness 0.25)
		(keepout
			(tracks allowed)
			(vias allowed)
			(pads allowed)
			(copperpour allowed)
			(footprints allowed)
		)
		(placement
			(enabled no)
			(sheetname "")
		)
		(fill
			(thermal_gap 0.5)
			(thermal_bridge_width 0.5)
			(island_removal_mode 0)
		)
		(polygon
			(pts
				(xy 242.903248 -383.73558) (xy 242.066318 -383.73558) (xy 242.066318 -382.368552) (xy 242.066318 -381.17145)
				(xy 242.28044 -380.957328) (xy 243.583714 -380.957328) (xy 243.74983 -381.123444) (xy 243.74983 -382.888998)
			)
		)
	)
	(zone
		(layer "B.Cu")
		(hatch none 0.5)
		(connect_pads
			(clearance 0)
		)
		(min_thickness 0.25)
		(keepout
			(tracks allowed)
			(vias allowed)
			(pads allowed)
			(copperpour allowed)
			(footprints not_allowed)
		)
		(placement
			(enabled no)
			(sheetname "")
		)
		(fill
			(thermal_gap 0.5)
			(thermal_bridge_width 0.5)
			(island_removal_mode 0)
		)
		(polygon
			(pts
				(arc
					(start 207.39989 -51.999896)
					(mid 204.650086 -49.250092)
					(end 201.900028 -51.999896)
				)
				(arc
					(start 201.900028 -51.999896)
					(mid 204.650086 -54.749954)
					(end 207.39989 -51.999896)
				)
			)
		)
	)
	(zone
		(layer "B.Cu")
		(hatch none 0.5)
		(connect_pads
			(clearance 0)
		)
		(min_thickness 0.25)
		(keepout
			(tracks not_allowed)
			(vias allowed)
			(pads allowed)
			(copperpour not_allowed)
			(footprints allowed)
		)
		(placement
			(enabled no)
			(sheetname "")
		)
		(fill
			(thermal_gap 0.5)
			(thermal_bridge_width 0.5)
			(island_removal_mode 0)
		)
		(polygon
			(pts
				(arc
					(start 314.269882 -258.890008)
					(mid 317.770002 -262.390128)
					(end 321.270122 -258.890008)
				)
				(arc
					(start 321.270122 -258.890008)
					(mid 317.770002 -255.389888)
					(end 314.269882 -258.890008)
				)
			)
		)
	)
	(zone
		(layer "B.Cu")
		(hatch none 0.5)
		(connect_pads
			(clearance 0)
		)
		(min_thickness 0.25)
		(keepout
			(tracks allowed)
			(vias allowed)
			(pads allowed)
			(copperpour allowed)
			(footprints allowed)
		)
		(placement
			(enabled no)
			(sheetname "")
		)
		(fill
			(thermal_gap 0.5)
			(thermal_bridge_width 0.5)
			(island_removal_mode 0)
		)
		(polygon
			(pts
				(xy 308.956456 -348.970092) (xy 308.956456 -351.129092) (xy 308.575456 -351.510092) (xy 305.781456 -351.510092)
				(xy 304.638456 -350.367092) (xy 304.638456 -347.446092) (xy 305.146456 -346.938092) (xy 306.924456 -346.938092)
			)
		)
	)
	(zone
		(layer "B.Cu")
		(hatch none 0.5)
		(connect_pads
			(clearance 0)
		)
		(min_thickness 0.25)
		(keepout
			(tracks not_allowed)
			(vias allowed)
			(pads allowed)
			(copperpour not_allowed)
			(footprints allowed)
		)
		(placement
			(enabled no)
			(sheetname "")
		)
		(fill
			(thermal_gap 0.5)
			(thermal_bridge_width 0.5)
			(island_removal_mode 0)
		)
		(polygon
			(pts
				(arc
					(start 152.578308 -393.292838)
					(mid 151.910288 -393.292838)
					(end 152.578308 -393.292838)
				)
			)
		)
	)
	(zone
		(layer "B.Cu")
		(hatch none 0.5)
		(connect_pads
			(clearance 0)
		)
		(min_thickness 0.25)
		(keepout
			(tracks not_allowed)
			(vias allowed)
			(pads allowed)
			(copperpour not_allowed)
			(footprints allowed)
		)
		(placement
			(enabled no)
			(sheetname "")
		)
		(fill
			(thermal_gap 0.5)
			(thermal_bridge_width 0.5)
			(island_removal_mode 0)
		)
		(polygon
			(pts
				(arc
					(start 351.576132 -244.484144)
					(mid 350.946212 -244.484144)
					(end 351.576132 -244.484144)
				)
			)
		)
	)
	(zone
		(layer "B.Cu")
		(hatch none 0.5)
		(connect_pads
			(clearance 0)
		)
		(min_thickness 0.25)
		(keepout
			(tracks allowed)
			(vias allowed)
			(pads allowed)
			(copperpour allowed)
			(footprints allowed)
		)
		(placement
			(enabled no)
			(sheetname "")
		)
		(fill
			(thermal_gap 0.5)
			(thermal_bridge_width 0.5)
			(island_removal_mode 0)
		)
		(polygon
			(pts
				(xy 61.940694 -348.898972) (xy 61.940694 -351.057972) (xy 61.559694 -351.438972) (xy 58.765694 -351.438972)
				(xy 57.622694 -350.295972) (xy 57.622694 -347.374972) (xy 58.130694 -346.866972) (xy 59.908694 -346.866972)
			)
		)
	)
	(zone
		(layer "B.Cu")
		(hatch none 0.5)
		(connect_pads
			(clearance 0)
		)
		(min_thickness 0.25)
		(keepout
			(tracks not_allowed)
			(vias allowed)
			(pads allowed)
			(copperpour not_allowed)
			(footprints allowed)
		)
		(placement
			(enabled no)
			(sheetname "")
		)
		(fill
			(thermal_gap 0.5)
			(thermal_bridge_width 0.5)
			(island_removal_mode 0)
		)
		(polygon
			(pts
				(arc
					(start 169.985944 -351.825052)
					(mid 173.086014 -354.925122)
					(end 176.186084 -351.825052)
				)
				(arc
					(start 176.186084 -351.825052)
					(mid 173.086014 -348.724982)
					(end 169.985944 -351.825052)
				)
			)
		)
	)
	(zone
		(layer "B.Cu")
		(hatch none 0.5)
		(connect_pads
			(clearance 0)
		)
		(min_thickness 0.25)
		(keepout
			(tracks allowed)
			(vias allowed)
			(pads allowed)
			(copperpour allowed)
			(footprints allowed)
		)
		(placement
			(enabled no)
			(sheetname "")
		)
		(fill
			(thermal_gap 0.5)
			(thermal_bridge_width 0.5)
			(island_removal_mode 0)
		)
		(polygon
			(pts
				(xy 414.25749 -161.491168) (xy 414.25749 -159.332168) (xy 414.63849 -158.951168) (xy 417.43249 -158.951168)
				(xy 418.57549 -160.094168) (xy 418.57549 -163.015168) (xy 418.06749 -163.523168) (xy 416.28949 -163.523168)
			)
		)
	)
	(zone
		(layer "B.Cu")
		(hatch none 0.5)
		(connect_pads
			(clearance 0)
		)
		(min_thickness 0.25)
		(keepout
			(tracks not_allowed)
			(vias allowed)
			(pads allowed)
			(copperpour not_allowed)
			(footprints allowed)
		)
		(placement
			(enabled no)
			(sheetname "")
		)
		(fill
			(thermal_gap 0.5)
			(thermal_bridge_width 0.5)
			(island_removal_mode 0)
		)
		(polygon
			(pts
				(arc
					(start 115.379754 -246.914416)
					(mid 114.749834 -246.914416)
					(end 115.379754 -246.914416)
				)
			)
		)
	)
	(zone
		(layer "B.Cu")
		(hatch none 0.5)
		(connect_pads
			(clearance 0)
		)
		(min_thickness 0.25)
		(keepout
			(tracks allowed)
			(vias allowed)
			(pads allowed)
			(copperpour allowed)
			(footprints allowed)
		)
		(placement
			(enabled no)
			(sheetname "")
		)
		(fill
			(thermal_gap 0.5)
			(thermal_bridge_width 0.5)
			(island_removal_mode 0)
		)
		(polygon
			(pts
				(xy 292.268656 -348.970092) (xy 292.268656 -351.129092) (xy 291.887656 -351.510092) (xy 289.093656 -351.510092)
				(xy 287.950656 -350.367092) (xy 287.950656 -347.446092) (xy 288.458656 -346.938092) (xy 290.236656 -346.938092)
			)
		)
	)
	(zone
		(layer "B.Cu")
		(hatch none 0.5)
		(connect_pads
			(clearance 0)
		)
		(min_thickness 0.25)
		(keepout
			(tracks not_allowed)
			(vias allowed)
			(pads allowed)
			(copperpour not_allowed)
			(footprints allowed)
		)
		(placement
			(enabled no)
			(sheetname "")
		)
		(fill
			(thermal_gap 0.5)
			(thermal_bridge_width 0.5)
			(island_removal_mode 0)
		)
		(polygon
			(pts
				(arc
					(start 388.136892 -437.889904)
					(mid 387.3627 -437.889904)
					(end 388.136892 -437.889904)
				)
			)
		)
	)
	(zone
		(layer "B.Cu")
		(hatch none 0.5)
		(connect_pads
			(clearance 0)
		)
		(min_thickness 0.25)
		(keepout
			(tracks not_allowed)
			(vias allowed)
			(pads allowed)
			(copperpour not_allowed)
			(footprints allowed)
		)
		(placement
			(enabled no)
			(sheetname "")
		)
		(fill
			(thermal_gap 0.5)
			(thermal_bridge_width 0.5)
			(island_removal_mode 0)
		)
		(polygon
			(pts
				(arc
					(start 132.348732 -18.144744)
					(mid 131.680712 -18.144744)
					(end 132.348732 -18.144744)
				)
			)
		)
	)
	(zone
		(layer "B.Cu")
		(hatch none 0.5)
		(connect_pads
			(clearance 0)
		)
		(min_thickness 0.25)
		(keepout
			(tracks allowed)
			(vias allowed)
			(pads allowed)
			(copperpour allowed)
			(footprints allowed)
		)
		(placement
			(enabled no)
			(sheetname "")
		)
		(fill
			(thermal_gap 0.5)
			(thermal_bridge_width 0.5)
			(island_removal_mode 0)
		)
		(polygon
			(pts
				(xy 214.06104 -408.604212) (xy 214.06104 -407.599896) (xy 214.754206 -407.599896) (xy 214.754206 -408.604212)
			)
		)
	)
	(zone
		(layer "B.Cu")
		(hatch none 0.5)
		(connect_pads
			(clearance 0)
		)
		(min_thickness 0.25)
		(keepout
			(tracks allowed)
			(vias allowed)
			(pads allowed)
			(copperpour allowed)
			(footprints not_allowed)
		)
		(placement
			(enabled no)
			(sheetname "")
		)
		(fill
			(thermal_gap 0.5)
			(thermal_bridge_width 0.5)
			(island_removal_mode 0)
		)
		(polygon
			(pts
				(arc
					(start 197.985888 -351.825052)
					(mid 201.085958 -354.925122)
					(end 204.186028 -351.825052)
				)
				(arc
					(start 204.186028 -351.825052)
					(mid 201.085958 -348.724982)
					(end 197.985888 -351.825052)
				)
			)
		)
	)
	(zone
		(layer "B.Cu")
		(hatch none 0.5)
		(connect_pads
			(clearance 0)
		)
		(min_thickness 0.25)
		(keepout
			(tracks allowed)
			(vias allowed)
			(pads allowed)
			(copperpour allowed)
			(footprints not_allowed)
		)
		(placement
			(enabled no)
			(sheetname "")
		)
		(fill
			(thermal_gap 0.5)
			(thermal_bridge_width 0.5)
			(island_removal_mode 0)
		)
		(polygon
			(pts
				(arc
					(start 417.051998 -351.415096)
					(mid 413.952182 -348.31528)
					(end 410.852112 -351.415096)
				)
				(arc
					(start 410.852112 -351.415096)
					(mid 413.952182 -354.515166)
					(end 417.051998 -351.415096)
				)
			)
		)
	)
	(zone
		(layer "B.Cu")
		(hatch none 0.5)
		(connect_pads
			(clearance 0)
		)
		(min_thickness 0.25)
		(keepout
			(tracks not_allowed)
			(vias allowed)
			(pads allowed)
			(copperpour not_allowed)
			(footprints allowed)
		)
		(placement
			(enabled no)
			(sheetname "")
		)
		(fill
			(thermal_gap 0.5)
			(thermal_bridge_width 0.5)
			(island_removal_mode 0)
		)
		(polygon
			(pts
				(arc
					(start 117.729762 -246.10441)
					(mid 117.099842 -246.10441)
					(end 117.729762 -246.10441)
				)
			)
		)
	)
	(zone
		(layer "B.Cu")
		(hatch none 0.5)
		(connect_pads
			(clearance 0)
		)
		(min_thickness 0.25)
		(keepout
			(tracks allowed)
			(vias allowed)
			(pads allowed)
			(copperpour allowed)
			(footprints not_allowed)
		)
		(placement
			(enabled no)
			(sheetname "")
		)
		(fill
			(thermal_gap 0.5)
			(thermal_bridge_width 0.5)
			(island_removal_mode 0)
		)
		(polygon
			(pts
				(arc
					(start 320.570098 -258.890008)
					(mid 317.770002 -256.089912)
					(end 314.969906 -258.890008)
				)
				(arc
					(start 314.969906 -258.890008)
					(mid 317.770002 -261.690104)
					(end 320.570098 -258.890008)
				)
			)
		)
	)
	(zone
		(layer "B.Cu")
		(hatch none 0.5)
		(connect_pads
			(clearance 0)
		)
		(min_thickness 0.25)
		(keepout
			(tracks not_allowed)
			(vias allowed)
			(pads allowed)
			(copperpour not_allowed)
			(footprints allowed)
		)
		(placement
			(enabled no)
			(sheetname "")
		)
		(fill
			(thermal_gap 0.5)
			(thermal_bridge_width 0.5)
			(island_removal_mode 0)
		)
		(polygon
			(pts
				(arc
					(start 148.978112 -392.429238)
					(mid 148.310092 -392.429238)
					(end 148.978112 -392.429238)
				)
			)
		)
	)
	(zone
		(layer "B.Cu")
		(hatch none 0.5)
		(connect_pads
			(clearance 0)
		)
		(min_thickness 0.25)
		(keepout
			(tracks allowed)
			(vias allowed)
			(pads allowed)
			(copperpour allowed)
			(footprints not_allowed)
		)
		(placement
			(enabled no)
			(sheetname "")
		)
		(fill
			(thermal_gap 0.5)
			(thermal_bridge_width 0.5)
			(island_removal_mode 0)
		)
		(polygon
			(pts
				(arc
					(start 99.927918 -244.879876)
					(mid 98.160244 -245.61207)
					(end 97.42805 -247.379744)
				)
				(arc
					(start 97.42805 -270.379952)
					(mid 98.160139 -272.14788)
					(end 99.927918 -272.880074)
				)
				(arc
					(start 123.928124 -272.880074)
					(mid 125.695798 -272.14788)
					(end 126.427992 -270.380206)
				)
				(arc
					(start 126.427992 -247.379998)
					(mid 125.695798 -245.612324)
					(end 123.928124 -244.879876)
				)
			)
		)
	)
	(zone
		(layer "B.Cu")
		(hatch none 0.5)
		(connect_pads
			(clearance 0)
		)
		(min_thickness 0.25)
		(keepout
			(tracks not_allowed)
			(vias allowed)
			(pads allowed)
			(copperpour not_allowed)
			(footprints allowed)
		)
		(placement
			(enabled no)
			(sheetname "")
		)
		(fill
			(thermal_gap 0.5)
			(thermal_bridge_width 0.5)
			(island_removal_mode 0)
		)
		(polygon
			(pts
				(arc
					(start 306.550314 -401.674838)
					(mid 305.882294 -401.674838)
					(end 306.550314 -401.674838)
				)
			)
		)
	)
	(zone
		(layer "B.Cu")
		(hatch none 0.5)
		(connect_pads
			(clearance 0)
		)
		(min_thickness 0.25)
		(keepout
			(tracks not_allowed)
			(vias allowed)
			(pads allowed)
			(copperpour not_allowed)
			(footprints allowed)
		)
		(placement
			(enabled no)
			(sheetname "")
		)
		(fill
			(thermal_gap 0.5)
			(thermal_bridge_width 0.5)
			(island_removal_mode 0)
		)
		(polygon
			(pts
				(arc
					(start 54.150514 -392.429238)
					(mid 53.482494 -392.429238)
					(end 54.150514 -392.429238)
				)
			)
		)
	)
	(zone
		(layer "B.Cu")
		(hatch none 0.5)
		(connect_pads
			(clearance 0)
		)
		(min_thickness 0.25)
		(keepout
			(tracks allowed)
			(vias allowed)
			(pads allowed)
			(copperpour allowed)
			(footprints not_allowed)
		)
		(placement
			(enabled no)
			(sheetname "")
		)
		(fill
			(thermal_gap 0.5)
			(thermal_bridge_width 0.5)
			(island_removal_mode 0)
		)
		(polygon
			(pts
				(arc
					(start 3.770122 -389.439912)
					(mid 6.870192 -392.539982)
					(end 9.970008 -389.439912)
				)
				(arc
					(start 9.970008 -389.439912)
					(mid 6.870192 -386.340096)
					(end 3.770122 -389.439912)
				)
			)
		)
	)
	(zone
		(layer "B.Cu")
		(hatch none 0.5)
		(connect_pads
			(clearance 0)
		)
		(min_thickness 0.25)
		(keepout
			(tracks allowed)
			(vias allowed)
			(pads allowed)
			(copperpour allowed)
			(footprints allowed)
		)
		(placement
			(enabled no)
			(sheetname "")
		)
		(fill
			(thermal_gap 0.5)
			(thermal_bridge_width 0.5)
			(island_removal_mode 0)
		)
		(polygon
			(pts
				(xy 249.54992 -3.29438) (xy 249.54992 -1.22428) (xy 252.0442 -1.22428) (xy 252.0442 -3.29438)
			)
		)
	)
	(zone
		(layer "B.Cu")
		(hatch none 0.5)
		(connect_pads
			(clearance 0)
		)
		(min_thickness 0.25)
		(keepout
			(tracks not_allowed)
			(vias allowed)
			(pads allowed)
			(copperpour not_allowed)
			(footprints allowed)
		)
		(placement
			(enabled no)
			(sheetname "")
		)
		(fill
			(thermal_gap 0.5)
			(thermal_bridge_width 0.5)
			(island_removal_mode 0)
		)
		(polygon
			(pts
				(arc
					(start 89.899998 -22.29993)
					(mid 94.899988 -27.29992)
					(end 99.899978 -22.29993)
				)
				(arc
					(start 99.899978 -22.29993)
					(mid 94.899988 -17.29994)
					(end 89.899998 -22.29993)
				)
			)
		)
	)
	(zone
		(layer "B.Cu")
		(hatch none 0.5)
		(connect_pads
			(clearance 0)
		)
		(min_thickness 0.25)
		(keepout
			(tracks not_allowed)
			(vias allowed)
			(pads allowed)
			(copperpour not_allowed)
			(footprints allowed)
		)
		(placement
			(enabled no)
			(sheetname "")
		)
		(fill
			(thermal_gap 0.5)
			(thermal_bridge_width 0.5)
			(island_removal_mode 0)
		)
		(polygon
			(pts
				(arc
					(start 150.178262 -392.429238)
					(mid 149.510242 -392.429238)
					(end 150.178262 -392.429238)
				)
			)
		)
	)
	(zone
		(layer "B.Cu")
		(hatch none 0.5)
		(connect_pads
			(clearance 0)
		)
		(min_thickness 0.25)
		(keepout
			(tracks not_allowed)
			(vias allowed)
			(pads allowed)
			(copperpour not_allowed)
			(footprints allowed)
		)
		(placement
			(enabled no)
			(sheetname "")
		)
		(fill
			(thermal_gap 0.5)
			(thermal_bridge_width 0.5)
			(island_removal_mode 0)
		)
		(polygon
			(pts
				(arc
					(start 307.75021 -401.674838)
					(mid 307.08219 -401.674838)
					(end 307.75021 -401.674838)
				)
			)
		)
	)
	(zone
		(layer "B.Cu")
		(hatch none 0.5)
		(connect_pads
			(clearance 0)
		)
		(min_thickness 0.25)
		(keepout
			(tracks not_allowed)
			(vias allowed)
			(pads allowed)
			(copperpour not_allowed)
			(footprints allowed)
		)
		(placement
			(enabled no)
			(sheetname "")
		)
		(fill
			(thermal_gap 0.5)
			(thermal_bridge_width 0.5)
			(island_removal_mode 0)
		)
		(polygon
			(pts
				(arc
					(start 63.750444 -393.292838)
					(mid 63.082424 -393.292838)
					(end 63.750444 -393.292838)
				)
			)
		)
	)
	(zone
		(layer "B.Cu")
		(hatch none 0.5)
		(connect_pads
			(clearance 0)
		)
		(min_thickness 0.25)
		(keepout
			(tracks not_allowed)
			(vias allowed)
			(pads allowed)
			(copperpour not_allowed)
			(footprints allowed)
		)
		(placement
			(enabled no)
			(sheetname "")
		)
		(fill
			(thermal_gap 0.5)
			(thermal_bridge_width 0.5)
			(island_removal_mode 0)
		)
		(polygon
			(pts
				(arc
					(start 71.036942 -436.889906)
					(mid 70.26275 -436.889906)
					(end 71.036942 -436.889906)
				)
			)
		)
	)
	(zone
		(layer "B.Cu")
		(hatch none 0.5)
		(connect_pads
			(clearance 0)
		)
		(min_thickness 0.25)
		(keepout
			(tracks not_allowed)
			(vias allowed)
			(pads allowed)
			(copperpour not_allowed)
			(footprints allowed)
		)
		(placement
			(enabled no)
			(sheetname "")
		)
		(fill
			(thermal_gap 0.5)
			(thermal_bridge_width 0.5)
			(island_removal_mode 0)
		)
		(polygon
			(pts
				(arc
					(start 156.17825 -392.429238)
					(mid 155.51023 -392.429238)
					(end 156.17825 -392.429238)
				)
			)
		)
	)
	(zone
		(layer "B.Cu")
		(hatch none 0.5)
		(connect_pads
			(clearance 0)
		)
		(min_thickness 0.25)
		(keepout
			(tracks not_allowed)
			(vias allowed)
			(pads allowed)
			(copperpour not_allowed)
			(footprints allowed)
		)
		(placement
			(enabled no)
			(sheetname "")
		)
		(fill
			(thermal_gap 0.5)
			(thermal_bridge_width 0.5)
			(island_removal_mode 0)
		)
		(polygon
			(pts
				(arc
					(start 126.18974 -246.10441)
					(mid 125.55982 -246.10441)
					(end 126.18974 -246.10441)
				)
			)
		)
	)
	(zone
		(layer "B.Cu")
		(hatch none 0.5)
		(connect_pads
			(clearance 0)
		)
		(min_thickness 0.25)
		(keepout
			(tracks allowed)
			(vias allowed)
			(pads allowed)
			(copperpour allowed)
			(footprints allowed)
		)
		(placement
			(enabled no)
			(sheetname "")
		)
		(fill
			(thermal_gap 0.5)
			(thermal_bridge_width 0.5)
			(island_removal_mode 0)
		)
		(polygon
			(pts
				(xy 343.642696 -337.301078) (xy 343.642696 -339.460078) (xy 343.261696 -339.841078) (xy 340.467696 -339.841078)
				(xy 339.324696 -338.698078) (xy 339.324696 -335.777078) (xy 339.832696 -335.269078) (xy 341.610696 -335.269078)
			)
		)
	)
	(zone
		(layer "B.Cu")
		(hatch none 0.5)
		(connect_pads
			(clearance 0)
		)
		(min_thickness 0.25)
		(keepout
			(tracks allowed)
			(vias allowed)
			(pads allowed)
			(copperpour allowed)
			(footprints allowed)
		)
		(placement
			(enabled no)
			(sheetname "")
		)
		(fill
			(thermal_gap 0.5)
			(thermal_bridge_width 0.5)
			(island_removal_mode 0)
		)
		(polygon
			(pts
				(xy 95.735394 -337.346798) (xy 95.735394 -339.505798) (xy 95.354394 -339.886798) (xy 92.560394 -339.886798)
				(xy 91.417394 -338.743798) (xy 91.417394 -335.822798) (xy 91.925394 -335.314798) (xy 93.703394 -335.314798)
			)
		)
	)
	(zone
		(layer "B.Cu")
		(hatch none 0.5)
		(connect_pads
			(clearance 0)
		)
		(min_thickness 0.25)
		(keepout
			(tracks allowed)
			(vias allowed)
			(pads allowed)
			(copperpour allowed)
			(footprints not_allowed)
		)
		(placement
			(enabled no)
			(sheetname "")
		)
		(fill
			(thermal_gap 0.5)
			(thermal_bridge_width 0.5)
			(island_removal_mode 0)
		)
		(polygon
			(pts
				(arc
					(start 467.60003 -22.29993)
					(mid 464.800188 -19.500088)
					(end 462.000092 -22.29993)
				)
				(arc
					(start 462.000092 -22.29993)
					(mid 464.800188 -25.100026)
					(end 467.60003 -22.29993)
				)
			)
		)
	)
	(zone
		(layer "B.Cu")
		(hatch none 0.5)
		(connect_pads
			(clearance 0)
		)
		(min_thickness 0.25)
		(keepout
			(tracks not_allowed)
			(vias allowed)
			(pads allowed)
			(copperpour not_allowed)
			(footprints allowed)
		)
		(placement
			(enabled no)
			(sheetname "")
		)
		(fill
			(thermal_gap 0.5)
			(thermal_bridge_width 0.5)
			(island_removal_mode 0)
		)
		(polygon
			(pts
				(arc
					(start 66.506344 -386.003292)
					(mid 65.876424 -386.003292)
					(end 66.506344 -386.003292)
				)
			)
		)
	)
	(zone
		(layer "B.Cu")
		(hatch none 0.5)
		(connect_pads
			(clearance 0)
		)
		(min_thickness 0.25)
		(keepout
			(tracks not_allowed)
			(vias allowed)
			(pads allowed)
			(copperpour not_allowed)
			(footprints allowed)
		)
		(placement
			(enabled no)
			(sheetname "")
		)
		(fill
			(thermal_gap 0.5)
			(thermal_bridge_width 0.5)
			(island_removal_mode 0)
		)
		(polygon
			(pts
				(arc
					(start 116.789708 -244.484398)
					(mid 116.159788 -244.484398)
					(end 116.789708 -244.484398)
				)
			)
		)
	)
	(zone
		(layer "B.Cu")
		(hatch none 0.5)
		(connect_pads
			(clearance 0)
		)
		(min_thickness 0.25)
		(keepout
			(tracks allowed)
			(vias allowed)
			(pads allowed)
			(copperpour allowed)
			(footprints not_allowed)
		)
		(placement
			(enabled no)
			(sheetname "")
		)
		(fill
			(thermal_gap 0.5)
			(thermal_bridge_width 0.5)
			(island_removal_mode 0)
		)
		(polygon
			(pts
				(arc
					(start 299.461682 -440.989974)
					(mid 293.550172 -427.599808)
					(end 287.638236 -440.989974)
				)
			)
		)
	)
	(zone
		(layer "B.Cu")
		(hatch none 0.5)
		(connect_pads
			(clearance 0)
		)
		(min_thickness 0.25)
		(keepout
			(tracks allowed)
			(vias allowed)
			(pads allowed)
			(copperpour allowed)
			(footprints allowed)
		)
		(placement
			(enabled no)
			(sheetname "")
		)
		(fill
			(thermal_gap 0.5)
			(thermal_bridge_width 0.5)
			(island_removal_mode 0)
		)
		(polygon
			(pts
				(xy 203.39304 -408.604212) (xy 203.39304 -407.599896) (xy 204.086206 -407.599896) (xy 204.086206 -408.604212)
			)
		)
	)
	(zone
		(layer "B.Cu")
		(hatch none 0.5)
		(connect_pads
			(clearance 0)
		)
		(min_thickness 0.25)
		(keepout
			(tracks not_allowed)
			(vias allowed)
			(pads allowed)
			(copperpour not_allowed)
			(footprints allowed)
		)
		(placement
			(enabled no)
			(sheetname "")
		)
		(fill
			(thermal_gap 0.5)
			(thermal_bridge_width 0.5)
			(island_removal_mode 0)
		)
		(polygon
			(pts
				(arc
					(start 58.950606 -393.292838)
					(mid 58.282586 -393.292838)
					(end 58.950606 -393.292838)
				)
			)
		)
	)
	(zone
		(layer "B.Cu")
		(hatch none 0.5)
		(connect_pads
			(clearance 0)
		)
		(min_thickness 0.25)
		(keepout
			(tracks not_allowed)
			(vias allowed)
			(pads allowed)
			(copperpour not_allowed)
			(footprints allowed)
		)
		(placement
			(enabled no)
			(sheetname "")
		)
		(fill
			(thermal_gap 0.5)
			(thermal_bridge_width 0.5)
			(island_removal_mode 0)
		)
		(polygon
			(pts
				(arc
					(start 375.899934 -22.29993)
					(mid 380.899924 -27.29992)
					(end 385.899914 -22.29993)
				)
				(arc
					(start 385.899914 -22.29993)
					(mid 380.899924 -17.29994)
					(end 375.899934 -22.29993)
				)
			)
		)
	)
	(zone
		(layer "B.Cu")
		(hatch none 0.5)
		(connect_pads
			(clearance 0)
		)
		(min_thickness 0.25)
		(keepout
			(tracks not_allowed)
			(vias allowed)
			(pads allowed)
			(copperpour not_allowed)
			(footprints allowed)
		)
		(placement
			(enabled no)
			(sheetname "")
		)
		(fill
			(thermal_gap 0.5)
			(thermal_bridge_width 0.5)
			(island_removal_mode 0)
		)
		(polygon
			(pts
				(arc
					(start 403.137116 -438.089802)
					(mid 402.362924 -438.089802)
					(end 403.137116 -438.089802)
				)
			)
		)
	)
	(zone
		(layer "B.Cu")
		(hatch none 0.5)
		(connect_pads
			(clearance 0)
		)
		(min_thickness 0.25)
		(keepout
			(tracks allowed)
			(vias allowed)
			(pads allowed)
			(copperpour allowed)
			(footprints not_allowed)
		)
		(placement
			(enabled no)
			(sheetname "")
		)
		(fill
			(thermal_gap 0.5)
			(thermal_bridge_width 0.5)
			(island_removal_mode 0)
		)
		(polygon
			(pts
				(arc
					(start 166.362888 -74.767948)
					(mid 178.86299 -87.26805)
					(end 191.363092 -74.767948)
				)
				(arc
					(start 191.363092 -66.06794)
					(mid 178.86299 -53.567838)
					(end 166.362888 -66.06794)
				)
			)
		)
	)
	(zone
		(layer "B.Cu")
		(hatch none 0.5)
		(connect_pads
			(clearance 0)
		)
		(min_thickness 0.25)
		(keepout
			(tracks allowed)
			(vias allowed)
			(pads allowed)
			(copperpour allowed)
			(footprints allowed)
		)
		(placement
			(enabled no)
			(sheetname "")
		)
		(fill
			(thermal_gap 0.5)
			(thermal_bridge_width 0.5)
			(island_removal_mode 0)
		)
		(polygon
			(pts
				(xy 187.50788 -130.9878) (xy 187.50788 -129.90068) (xy 189.7761 -129.90068) (xy 189.7761 -130.9878)
			)
		)
	)
	(zone
		(layer "B.Cu")
		(hatch none 0.5)
		(connect_pads
			(clearance 0)
		)
		(min_thickness 0.25)
		(keepout
			(tracks not_allowed)
			(vias allowed)
			(pads allowed)
			(copperpour not_allowed)
			(footprints allowed)
		)
		(placement
			(enabled no)
			(sheetname "")
		)
		(fill
			(thermal_gap 0.5)
			(thermal_bridge_width 0.5)
			(island_removal_mode 0)
		)
		(polygon
			(pts
				(arc
					(start 40.31615 -425.909994)
					(mid 39.64813 -425.909994)
					(end 40.31615 -425.909994)
				)
			)
		)
	)
	(zone
		(layer "B.Cu")
		(hatch none 0.5)
		(connect_pads
			(clearance 0)
		)
		(min_thickness 0.25)
		(keepout
			(tracks allowed)
			(vias allowed)
			(pads allowed)
			(copperpour allowed)
			(footprints not_allowed)
		)
		(placement
			(enabled no)
			(sheetname "")
		)
		(fill
			(thermal_gap 0.5)
			(thermal_bridge_width 0.5)
			(island_removal_mode 0)
		)
		(polygon
			(pts
				(arc
					(start 468.754968 -51.289966)
					(mid 466.8901 -49.425098)
					(end 465.024978 -51.289966)
				)
				(arc
					(start 465.024978 -51.289966)
					(mid 466.8901 -53.155088)
					(end 468.754968 -51.289966)
				)
			)
		)
	)
	(zone
		(layer "B.Cu")
		(hatch none 0.5)
		(connect_pads
			(clearance 0)
		)
		(min_thickness 0.25)
		(keepout
			(tracks not_allowed)
			(vias allowed)
			(pads allowed)
			(copperpour not_allowed)
			(footprints allowed)
		)
		(placement
			(enabled no)
			(sheetname "")
		)
		(fill
			(thermal_gap 0.5)
			(thermal_bridge_width 0.5)
			(island_removal_mode 0)
		)
		(polygon
			(pts
				(arc
					(start 151.137112 -438.089802)
					(mid 150.36292 -438.089802)
					(end 151.137112 -438.089802)
				)
			)
		)
	)
	(zone
		(layer "B.Cu")
		(hatch none 0.5)
		(connect_pads
			(clearance 0)
		)
		(min_thickness 0.25)
		(keepout
			(tracks allowed)
			(vias allowed)
			(pads allowed)
			(copperpour allowed)
			(footprints not_allowed)
		)
		(placement
			(enabled no)
			(sheetname "")
		)
		(fill
			(thermal_gap 0.5)
			(thermal_bridge_width 0.5)
			(island_removal_mode 0)
		)
		(polygon
			(pts
				(arc
					(start 410.852112 -351.415096)
					(mid 413.952182 -354.515166)
					(end 417.051998 -351.415096)
				)
				(arc
					(start 417.051998 -351.415096)
					(mid 413.952182 -348.31528)
					(end 410.852112 -351.415096)
				)
			)
		)
	)
	(zone
		(layer "B.Cu")
		(hatch none 0.5)
		(connect_pads
			(clearance 0)
		)
		(min_thickness 0.25)
		(keepout
			(tracks not_allowed)
			(vias allowed)
			(pads allowed)
			(copperpour not_allowed)
			(footprints allowed)
		)
		(placement
			(enabled no)
			(sheetname "")
		)
		(fill
			(thermal_gap 0.5)
			(thermal_bridge_width 0.5)
			(island_removal_mode 0)
		)
		(polygon
			(pts
				(arc
					(start 92.782898 -45.449998)
					(mid 91.182952 -47.049944)
					(end 92.782898 -48.64989)
				)
				(arc
					(start 94.383098 -48.64989)
					(mid 95.983044 -47.049944)
					(end 94.383098 -45.449998)
				)
			)
		)
	)
	(zone
		(layer "B.Cu")
		(hatch none 0.5)
		(connect_pads
			(clearance 0)
		)
		(min_thickness 0.25)
		(keepout
			(tracks not_allowed)
			(vias allowed)
			(pads allowed)
			(copperpour not_allowed)
			(footprints allowed)
		)
		(placement
			(enabled no)
			(sheetname "")
		)
		(fill
			(thermal_gap 0.5)
			(thermal_bridge_width 0.5)
			(island_removal_mode 0)
		)
		(polygon
			(pts
				(arc
					(start 357.046022 -269.22603)
					(mid 356.416102 -269.22603)
					(end 357.046022 -269.22603)
				)
			)
		)
	)
	(zone
		(layer "B.Cu")
		(hatch none 0.5)
		(connect_pads
			(clearance 0)
		)
		(min_thickness 0.25)
		(keepout
			(tracks not_allowed)
			(vias allowed)
			(pads allowed)
			(copperpour not_allowed)
			(footprints allowed)
		)
		(placement
			(enabled no)
			(sheetname "")
		)
		(fill
			(thermal_gap 0.5)
			(thermal_bridge_width 0.5)
			(island_removal_mode 0)
		)
		(polygon
			(pts
				(arc
					(start 174.950882 -351.825052)
					(mid 173.086014 -349.960184)
					(end 171.220892 -351.825052)
				)
				(arc
					(start 171.220892 -351.825052)
					(mid 173.086014 -353.690174)
					(end 174.950882 -351.825052)
				)
			)
		)
	)
	(zone
		(layer "B.Cu")
		(hatch none 0.5)
		(connect_pads
			(clearance 0)
		)
		(min_thickness 0.25)
		(keepout
			(tracks not_allowed)
			(vias allowed)
			(pads allowed)
			(copperpour not_allowed)
			(footprints allowed)
		)
		(placement
			(enabled no)
			(sheetname "")
		)
		(fill
			(thermal_gap 0.5)
			(thermal_bridge_width 0.5)
			(island_removal_mode 0)
		)
		(polygon
			(pts
				(arc
					(start 265.8999 -51.999896)
					(mid 268.649958 -54.749954)
					(end 271.400016 -51.999896)
				)
				(arc
					(start 271.400016 -51.999896)
					(mid 268.649958 -49.249838)
					(end 265.8999 -51.999896)
				)
			)
		)
	)
	(zone
		(layer "B.Cu")
		(hatch none 0.5)
		(connect_pads
			(clearance 0)
		)
		(min_thickness 0.25)
		(keepout
			(tracks allowed)
			(vias allowed)
			(pads allowed)
			(copperpour allowed)
			(footprints not_allowed)
		)
		(placement
			(enabled no)
			(sheetname "")
		)
		(fill
			(thermal_gap 0.5)
			(thermal_bridge_width 0.5)
			(island_removal_mode 0)
		)
		(polygon
			(pts
				(arc
					(start 386.970016 -212.989922)
					(mid 390.470136 -216.490042)
					(end 393.970002 -212.989922)
				)
				(arc
					(start 393.970002 -212.989922)
					(mid 390.470136 -209.490056)
					(end 386.970016 -212.989922)
				)
			)
		)
	)
	(zone
		(layer "B.Cu")
		(hatch none 0.5)
		(connect_pads
			(clearance 0)
		)
		(min_thickness 0.25)
		(keepout
			(tracks not_allowed)
			(vias allowed)
			(pads allowed)
			(copperpour not_allowed)
			(footprints allowed)
		)
		(placement
			(enabled no)
			(sheetname "")
		)
		(fill
			(thermal_gap 0.5)
			(thermal_bridge_width 0.5)
			(island_removal_mode 0)
		)
		(polygon
			(pts
				(arc
					(start 145.137124 -437.889904)
					(mid 144.362932 -437.889904)
					(end 145.137124 -437.889904)
				)
			)
		)
	)
	(zone
		(layer "B.Cu")
		(hatch none 0.5)
		(connect_pads
			(clearance 0)
		)
		(min_thickness 0.25)
		(keepout
			(tracks allowed)
			(vias allowed)
			(pads allowed)
			(copperpour allowed)
			(footprints allowed)
		)
		(placement
			(enabled no)
			(sheetname "")
		)
		(fill
			(thermal_gap 0.5)
			(thermal_bridge_width 0.5)
			(island_removal_mode 0)
		)
		(polygon
			(pts
				(xy 396.665196 -417.428426) (xy 396.665196 -416.42411) (xy 398.04213 -416.42411) (xy 398.04213 -417.428426)
			)
		)
	)
	(zone
		(layer "B.Cu")
		(hatch none 0.5)
		(connect_pads
			(clearance 0)
		)
		(min_thickness 0.25)
		(keepout
			(tracks not_allowed)
			(vias allowed)
			(pads allowed)
			(copperpour not_allowed)
			(footprints allowed)
		)
		(placement
			(enabled no)
			(sheetname "")
		)
		(fill
			(thermal_gap 0.5)
			(thermal_bridge_width 0.5)
			(island_removal_mode 0)
		)
		(polygon
			(pts
				(arc
					(start 36.735004 -389.439912)
					(mid 34.870136 -387.575044)
					(end 33.005014 -389.439912)
				)
				(arc
					(start 33.005014 -389.439912)
					(mid 34.870136 -391.305034)
					(end 36.735004 -389.439912)
				)
			)
		)
	)
	(zone
		(layer "B.Cu")
		(hatch none 0.5)
		(connect_pads
			(clearance 0)
		)
		(min_thickness 0.25)
		(keepout
			(tracks allowed)
			(vias allowed)
			(pads allowed)
			(copperpour allowed)
			(footprints not_allowed)
		)
		(placement
			(enabled no)
			(sheetname "")
		)
		(fill
			(thermal_gap 0.5)
			(thermal_bridge_width 0.5)
			(island_removal_mode 0)
		)
		(polygon
			(pts
				(arc
					(start 174.950882 -351.825052)
					(mid 173.086014 -349.960184)
					(end 171.220892 -351.825052)
				)
				(arc
					(start 171.220892 -351.825052)
					(mid 173.086014 -353.690174)
					(end 174.950882 -351.825052)
				)
			)
		)
	)
	(zone
		(layer "B.Cu")
		(hatch none 0.5)
		(connect_pads
			(clearance 0)
		)
		(min_thickness 0.25)
		(keepout
			(tracks allowed)
			(vias allowed)
			(pads allowed)
			(copperpour allowed)
			(footprints allowed)
		)
		(placement
			(enabled no)
			(sheetname "")
		)
		(fill
			(thermal_gap 0.5)
			(thermal_bridge_width 0.5)
			(island_removal_mode 0)
		)
		(polygon
			(pts
				(xy 104.011222 -342.256872) (xy 104.011222 -344.415872) (xy 103.630222 -344.796872) (xy 100.836222 -344.796872)
				(xy 99.693222 -343.653872) (xy 99.693222 -340.732872) (xy 100.201222 -340.224872) (xy 101.979222 -340.224872)
			)
		)
	)
	(zone
		(layer "B.Cu")
		(hatch none 0.5)
		(connect_pads
			(clearance 0)
		)
		(min_thickness 0.25)
		(keepout
			(tracks allowed)
			(vias allowed)
			(pads allowed)
			(copperpour allowed)
			(footprints allowed)
		)
		(placement
			(enabled no)
			(sheetname "")
		)
		(fill
			(thermal_gap 0.5)
			(thermal_bridge_width 0.5)
			(island_removal_mode 0)
		)
		(polygon
			(pts
				(xy 79.046578 -337.310476) (xy 79.046578 -339.469476) (xy 78.665578 -339.850476) (xy 75.871578 -339.850476)
				(xy 74.728578 -338.707476) (xy 74.728578 -335.786476) (xy 75.236578 -335.278476) (xy 77.014578 -335.278476)
			)
		)
	)
	(zone
		(layer "B.Cu")
		(hatch none 0.5)
		(connect_pads
			(clearance 0)
		)
		(min_thickness 0.25)
		(keepout
			(tracks allowed)
			(vias allowed)
			(pads allowed)
			(copperpour allowed)
			(footprints allowed)
		)
		(placement
			(enabled no)
			(sheetname "")
		)
		(fill
			(thermal_gap 0.5)
			(thermal_bridge_width 0.5)
			(island_removal_mode 0)
		)
		(polygon
			(pts
				(xy 418.107876 -417.428426) (xy 418.107876 -416.42411) (xy 419.48481 -416.42411) (xy 419.48481 -417.428426)
			)
		)
	)
	(zone
		(layer "B.Cu")
		(hatch none 0.5)
		(connect_pads
			(clearance 0)
		)
		(min_thickness 0.25)
		(keepout
			(tracks allowed)
			(vias allowed)
			(pads allowed)
			(copperpour allowed)
			(footprints allowed)
		)
		(placement
			(enabled no)
			(sheetname "")
		)
		(fill
			(thermal_gap 0.5)
			(thermal_bridge_width 0.5)
			(island_removal_mode 0)
		)
		(polygon
			(pts
				(xy 107.195366 -175.791876) (xy 107.195366 -173.632876) (xy 107.576366 -173.251876) (xy 110.370366 -173.251876)
				(xy 111.513366 -174.394876) (xy 111.513366 -177.315876) (xy 111.005366 -177.823876) (xy 109.227366 -177.823876)
			)
		)
	)
	(zone
		(layer "B.Cu")
		(hatch none 0.5)
		(connect_pads
			(clearance 0)
		)
		(min_thickness 0.25)
		(keepout
			(tracks allowed)
			(vias allowed)
			(pads allowed)
			(copperpour allowed)
			(footprints allowed)
		)
		(placement
			(enabled no)
			(sheetname "")
		)
		(fill
			(thermal_gap 0.5)
			(thermal_bridge_width 0.5)
			(island_removal_mode 0)
		)
		(polygon
			(pts
				(xy 364.04169 -175.494696) (xy 364.04169 -173.335696) (xy 364.42269 -172.954696) (xy 367.21669 -172.954696)
				(xy 368.35969 -174.097696) (xy 368.35969 -177.018696) (xy 367.85169 -177.526696) (xy 366.07369 -177.526696)
			)
		)
	)
	(zone
		(layer "B.Cu")
		(hatch none 0.5)
		(connect_pads
			(clearance 0)
		)
		(min_thickness 0.25)
		(keepout
			(tracks allowed)
			(vias allowed)
			(pads allowed)
			(copperpour allowed)
			(footprints not_allowed)
		)
		(placement
			(enabled no)
			(sheetname "")
		)
		(fill
			(thermal_gap 0.5)
			(thermal_bridge_width 0.5)
			(island_removal_mode 0)
		)
		(polygon
			(pts
				(arc
					(start 13.139928 -347.700092)
					(mid 10.340086 -344.90025)
					(end 7.53999 -347.700092)
				)
				(arc
					(start 7.53999 -347.700092)
					(mid 10.340086 -350.500188)
					(end 13.139928 -347.700092)
				)
			)
		)
	)
	(zone
		(layer "B.Cu")
		(hatch none 0.5)
		(connect_pads
			(clearance 0)
		)
		(min_thickness 0.25)
		(keepout
			(tracks allowed)
			(vias allowed)
			(pads allowed)
			(copperpour allowed)
			(footprints not_allowed)
		)
		(placement
			(enabled no)
			(sheetname "")
		)
		(fill
			(thermal_gap 0.5)
			(thermal_bridge_width 0.5)
			(island_removal_mode 0)
		)
		(polygon
			(pts
				(arc
					(start 332.069948 -304.790094)
					(mid 329.270106 -301.990252)
					(end 326.47001 -304.790094)
				)
				(arc
					(start 326.47001 -304.790094)
					(mid 329.270106 -307.59019)
					(end 332.069948 -304.790094)
				)
			)
		)
	)
	(zone
		(layer "B.Cu")
		(hatch none 0.5)
		(connect_pads
			(clearance 0)
		)
		(min_thickness 0.25)
		(keepout
			(tracks not_allowed)
			(vias allowed)
			(pads allowed)
			(copperpour not_allowed)
			(footprints allowed)
		)
		(placement
			(enabled no)
			(sheetname "")
		)
		(fill
			(thermal_gap 0.5)
			(thermal_bridge_width 0.5)
			(island_removal_mode 0)
		)
		(polygon
			(pts
				(arc
					(start 202.95108 -351.825052)
					(mid 201.086212 -349.960184)
					(end 199.22109 -351.825052)
				)
				(arc
					(start 199.22109 -351.825052)
					(mid 201.086212 -353.690174)
					(end 202.95108 -351.825052)
				)
			)
		)
	)
	(zone
		(layer "B.Cu")
		(hatch none 0.5)
		(connect_pads
			(clearance 0)
		)
		(min_thickness 0.25)
		(keepout
			(tracks allowed)
			(vias allowed)
			(pads allowed)
			(copperpour allowed)
			(footprints not_allowed)
		)
		(placement
			(enabled no)
			(sheetname "")
		)
		(fill
			(thermal_gap 0.5)
			(thermal_bridge_width 0.5)
			(island_removal_mode 0)
		)
		(polygon
			(pts
				(arc
					(start 393.269978 -304.790094)
					(mid 390.470136 -301.990252)
					(end 387.67004 -304.790094)
				)
				(arc
					(start 387.67004 -304.790094)
					(mid 390.470136 -307.59019)
					(end 393.269978 -304.790094)
				)
			)
		)
	)
	(zone
		(layer "B.Cu")
		(hatch none 0.5)
		(connect_pads
			(clearance 0)
		)
		(min_thickness 0.25)
		(keepout
			(tracks not_allowed)
			(vias allowed)
			(pads allowed)
			(copperpour not_allowed)
			(footprints allowed)
		)
		(placement
			(enabled no)
			(sheetname "")
		)
		(fill
			(thermal_gap 0.5)
			(thermal_bridge_width 0.5)
			(island_removal_mode 0)
		)
		(polygon
			(pts
				(arc
					(start 357.986076 -269.22603)
					(mid 357.356156 -269.22603)
					(end 357.986076 -269.22603)
				)
			)
		)
	)
	(zone
		(layer "B.Cu")
		(hatch none 0.5)
		(connect_pads
			(clearance 0)
		)
		(min_thickness 0.25)
		(keepout
			(tracks not_allowed)
			(vias allowed)
			(pads allowed)
			(copperpour not_allowed)
			(footprints allowed)
		)
		(placement
			(enabled no)
			(sheetname "")
		)
		(fill
			(thermal_gap 0.5)
			(thermal_bridge_width 0.5)
			(island_removal_mode 0)
		)
		(polygon
			(pts
				(arc
					(start 464.25993 -347.700092)
					(mid 461.460088 -344.90025)
					(end 458.659992 -347.700092)
				)
				(arc
					(start 458.659992 -347.700092)
					(mid 461.460088 -350.500188)
					(end 464.25993 -347.700092)
				)
			)
		)
	)
	(zone
		(layer "B.Cu")
		(hatch none 0.5)
		(connect_pads
			(clearance 0)
		)
		(min_thickness 0.25)
		(keepout
			(tracks not_allowed)
			(vias allowed)
			(pads allowed)
			(copperpour not_allowed)
			(footprints allowed)
		)
		(placement
			(enabled no)
			(sheetname "")
		)
		(fill
			(thermal_gap 0.5)
			(thermal_bridge_width 0.5)
			(island_removal_mode 0)
		)
		(polygon
			(pts
				(arc
					(start 116.789708 -246.10441)
					(mid 116.159788 -246.10441)
					(end 116.789708 -246.10441)
				)
			)
		)
	)
	(zone
		(layer "B.Cu")
		(hatch none 0.5)
		(connect_pads
			(clearance 0)
		)
		(min_thickness 0.25)
		(keepout
			(tracks not_allowed)
			(vias allowed)
			(pads allowed)
			(copperpour not_allowed)
			(footprints allowed)
		)
		(placement
			(enabled no)
			(sheetname "")
		)
		(fill
			(thermal_gap 0.5)
			(thermal_bridge_width 0.5)
			(island_removal_mode 0)
		)
		(polygon
			(pts
				(arc
					(start 317.90005 -160.50006)
					(mid 322.90004 -165.50005)
					(end 327.90003 -160.50006)
				)
				(arc
					(start 327.90003 -160.50006)
					(mid 322.90004 -155.50007)
					(end 317.90005 -160.50006)
				)
			)
		)
	)
	(zone
		(layer "B.Cu")
		(hatch none 0.5)
		(connect_pads
			(clearance 0)
		)
		(min_thickness 0.25)
		(keepout
			(tracks allowed)
			(vias allowed)
			(pads allowed)
			(copperpour allowed)
			(footprints not_allowed)
		)
		(placement
			(enabled no)
			(sheetname "")
		)
		(fill
			(thermal_gap 0.5)
			(thermal_bridge_width 0.5)
			(island_removal_mode 0)
		)
		(polygon
			(pts
				(arc
					(start 218.799918 -290.900104)
					(mid 221.899988 -294.000174)
					(end 225.000058 -290.900104)
				)
				(arc
					(start 225.000058 -290.900104)
					(mid 221.899988 -287.800034)
					(end 218.799918 -290.900104)
				)
			)
		)
	)
	(zone
		(layer "B.Cu")
		(hatch none 0.5)
		(connect_pads
			(clearance 0)
		)
		(min_thickness 0.25)
		(keepout
			(tracks allowed)
			(vias allowed)
			(pads allowed)
			(copperpour allowed)
			(footprints not_allowed)
		)
		(placement
			(enabled no)
			(sheetname "")
		)
		(fill
			(thermal_gap 0.5)
			(thermal_bridge_width 0.5)
			(island_removal_mode 0)
		)
		(polygon
			(pts
				(arc
					(start 14.999716 -22.238462)
					(mid 9.799573 -14.805814)
					(end 0.999998 -17.008602)
				)
				(arc
					(start 0.999998 -27.591512)
					(mid 3.92484 -29.685433)
					(end 7.47141 -30.286198)
				)
				(arc
					(start 7.47141 -30.286198)
					(mid 21.313293 -35.689957)
					(end 14.999716 -22.238462)
				)
			)
		)
	)
	(zone
		(layer "B.Cu")
		(hatch none 0.5)
		(connect_pads
			(clearance 0)
		)
		(min_thickness 0.25)
		(keepout
			(tracks allowed)
			(vias allowed)
			(pads allowed)
			(copperpour allowed)
			(footprints allowed)
		)
		(placement
			(enabled no)
			(sheetname "")
		)
		(fill
			(thermal_gap 0.5)
			(thermal_bridge_width 0.5)
			(island_removal_mode 0)
		)
		(polygon
			(pts
				(xy 230.366316 -233.595926) (xy 231.370632 -233.595926) (xy 231.370632 -234.97286) (xy 230.366316 -234.97286)
			)
		)
	)
	(zone
		(layer "B.Cu")
		(hatch none 0.5)
		(connect_pads
			(clearance 0)
		)
		(min_thickness 0.25)
		(keepout
			(tracks not_allowed)
			(vias allowed)
			(pads allowed)
			(copperpour not_allowed)
			(footprints allowed)
		)
		(placement
			(enabled no)
			(sheetname "")
		)
		(fill
			(thermal_gap 0.5)
			(thermal_bridge_width 0.5)
			(island_removal_mode 0)
		)
		(polygon
			(pts
				(arc
					(start 307.75021 -400.811238)
					(mid 307.08219 -400.811238)
					(end 307.75021 -400.811238)
				)
			)
		)
	)
	(zone
		(layer "B.Cu")
		(hatch none 0.5)
		(connect_pads
			(clearance 0)
		)
		(min_thickness 0.25)
		(keepout
			(tracks allowed)
			(vias allowed)
			(pads allowed)
			(copperpour allowed)
			(footprints allowed)
		)
		(placement
			(enabled no)
			(sheetname "")
		)
		(fill
			(thermal_gap 0.5)
			(thermal_bridge_width 0.5)
			(island_removal_mode 0)
		)
		(polygon
			(pts
				(xy 82.754978 -409.046426) (xy 82.754978 -408.04211) (xy 84.131912 -408.04211) (xy 84.131912 -409.046426)
			)
		)
	)
	(zone
		(layer "B.Cu")
		(hatch none 0.5)
		(connect_pads
			(clearance 0)
		)
		(min_thickness 0.25)
		(keepout
			(tracks allowed)
			(vias allowed)
			(pads allowed)
			(copperpour allowed)
			(footprints not_allowed)
		)
		(placement
			(enabled no)
			(sheetname "")
		)
		(fill
			(thermal_gap 0.5)
			(thermal_bridge_width 0.5)
			(island_removal_mode 0)
		)
		(polygon
			(pts
				(arc
					(start 22.413976 -163.735258)
					(mid 41.777773 -149.707164)
					(end 17.880838 -150.530814)
				)
				(arc
					(start 17.880838 -150.530814)
					(mid 10.464956 -148.000581)
					(end 2.999994 -150.38197)
				)
				(arc
					(start 2.999994 -170.617896)
					(mid 14.516809 -172.281509)
					(end 22.413976 -163.735258)
				)
			)
		)
	)
	(zone
		(layer "B.Cu")
		(hatch none 0.5)
		(connect_pads
			(clearance 0)
		)
		(min_thickness 0.25)
		(keepout
			(tracks not_allowed)
			(vias allowed)
			(pads allowed)
			(copperpour not_allowed)
			(footprints allowed)
		)
		(placement
			(enabled no)
			(sheetname "")
		)
		(fill
			(thermal_gap 0.5)
			(thermal_bridge_width 0.5)
			(island_removal_mode 0)
		)
		(polygon
			(pts
				(arc
					(start 154.978354 -392.429238)
					(mid 154.310334 -392.429238)
					(end 154.978354 -392.429238)
				)
			)
		)
	)
	(zone
		(layer "B.Cu")
		(hatch none 0.5)
		(connect_pads
			(clearance 0)
		)
		(min_thickness 0.25)
		(keepout
			(tracks not_allowed)
			(vias allowed)
			(pads allowed)
			(copperpour not_allowed)
			(footprints allowed)
		)
		(placement
			(enabled no)
			(sheetname "")
		)
		(fill
			(thermal_gap 0.5)
			(thermal_bridge_width 0.5)
			(island_removal_mode 0)
		)
		(polygon
			(pts
				(arc
					(start 63.036958 -436.889906)
					(mid 62.262766 -436.889906)
					(end 63.036958 -436.889906)
				)
			)
		)
	)
	(zone
		(layer "B.Cu")
		(hatch none 0.5)
		(connect_pads
			(clearance 0)
		)
		(min_thickness 0.25)
		(keepout
			(tracks allowed)
			(vias allowed)
			(pads allowed)
			(copperpour allowed)
			(footprints allowed)
		)
		(placement
			(enabled no)
			(sheetname "")
		)
		(fill
			(thermal_gap 0.5)
			(thermal_bridge_width 0.5)
			(island_removal_mode 0)
		)
		(polygon
			(pts
				(xy 454.7743 -192.83172) (xy 454.7743 -191.72428) (xy 456.38974 -191.72428) (xy 456.38974 -192.83172)
			)
		)
	)
	(zone
		(layer "B.Cu")
		(hatch none 0.5)
		(connect_pads
			(clearance 0)
		)
		(min_thickness 0.25)
		(keepout
			(tracks allowed)
			(vias allowed)
			(pads allowed)
			(copperpour allowed)
			(footprints not_allowed)
		)
		(placement
			(enabled no)
			(sheetname "")
		)
		(fill
			(thermal_gap 0.5)
			(thermal_bridge_width 0.5)
			(island_removal_mode 0)
		)
		(polygon
			(pts
				(arc
					(start 129.786126 -146.84502)
					(mid 132.886196 -149.94509)
					(end 135.986012 -146.84502)
				)
				(arc
					(start 135.986012 -146.84502)
					(mid 132.886196 -143.745204)
					(end 129.786126 -146.84502)
				)
			)
		)
	)
	(zone
		(layer "B.Cu")
		(hatch none 0.5)
		(connect_pads
			(clearance 0)
		)
		(min_thickness 0.25)
		(keepout
			(tracks allowed)
			(vias allowed)
			(pads allowed)
			(copperpour allowed)
			(footprints allowed)
		)
		(placement
			(enabled no)
			(sheetname "")
		)
		(fill
			(thermal_gap 0.5)
			(thermal_bridge_width 0.5)
			(island_removal_mode 0)
		)
		(polygon
			(pts
				(xy 189.5856 -138.99642) (xy 189.5856 -136.11352) (xy 191.24168 -136.11352) (xy 191.24168 -138.99642)
			)
		)
	)
	(zone
		(layer "B.Cu")
		(hatch none 0.5)
		(connect_pads
			(clearance 0)
		)
		(min_thickness 0.25)
		(keepout
			(tracks not_allowed)
			(vias allowed)
			(pads allowed)
			(copperpour not_allowed)
			(footprints allowed)
		)
		(placement
			(enabled no)
			(sheetname "")
		)
		(fill
			(thermal_gap 0.5)
			(thermal_bridge_width 0.5)
			(island_removal_mode 0)
		)
		(polygon
			(pts
				(arc
					(start 348.75597 -246.104156)
					(mid 348.12605 -246.104156)
					(end 348.75597 -246.104156)
				)
			)
		)
	)
	(zone
		(layer "B.Cu")
		(hatch none 0.5)
		(connect_pads
			(clearance 0)
		)
		(min_thickness 0.25)
		(keepout
			(tracks not_allowed)
			(vias allowed)
			(pads allowed)
			(copperpour not_allowed)
			(footprints allowed)
		)
		(placement
			(enabled no)
			(sheetname "")
		)
		(fill
			(thermal_gap 0.5)
			(thermal_bridge_width 0.5)
			(island_removal_mode 0)
		)
		(polygon
			(pts
				(arc
					(start 94.383098 -50.25009)
					(mid 95.784681 -49.926806)
					(end 96.903032 -49.022254)
				)
				(arc
					(start 96.903032 -49.022254)
					(mid 101.402945 -50.917846)
					(end 104.383078 -47.049944)
				)
				(arc
					(start 104.383078 -47.049944)
					(mid 101.402812 -43.182116)
					(end 96.903032 -45.077888)
				)
				(arc
					(start 96.903032 -45.077888)
					(mid 95.784665 -44.173369)
					(end 94.383098 -43.850052)
				)
				(arc
					(start 92.782898 -43.850052)
					(mid 89.582752 -47.050198)
					(end 92.782898 -50.25009)
				)
			)
		)
	)
	(zone
		(layer "B.Cu")
		(hatch none 0.5)
		(connect_pads
			(clearance 0)
		)
		(min_thickness 0.25)
		(keepout
			(tracks not_allowed)
			(vias allowed)
			(pads allowed)
			(copperpour not_allowed)
			(footprints allowed)
		)
		(placement
			(enabled no)
			(sheetname "")
		)
		(fill
			(thermal_gap 0.5)
			(thermal_bridge_width 0.5)
			(island_removal_mode 0)
		)
		(polygon
			(pts
				(arc
					(start 123.369578 -247.724422)
					(mid 122.739658 -247.724422)
					(end 123.369578 -247.724422)
				)
			)
		)
	)
	(zone
		(layer "B.Cu")
		(hatch none 0.5)
		(connect_pads
			(clearance 0)
		)
		(min_thickness 0.25)
		(keepout
			(tracks allowed)
			(vias allowed)
			(pads allowed)
			(copperpour allowed)
			(footprints allowed)
		)
		(placement
			(enabled no)
			(sheetname "")
		)
		(fill
			(thermal_gap 0.5)
			(thermal_bridge_width 0.5)
			(island_removal_mode 0)
		)
		(polygon
			(pts
				(xy 447.591942 -419.22065) (xy 447.591942 -419.49878) (xy 447.591942 -420.485824) (xy 446.92443 -420.485824)
				(xy 446.92443 -419.22065)
			)
		)
	)
	(zone
		(layer "B.Cu")
		(hatch none 0.5)
		(connect_pads
			(clearance 0)
		)
		(min_thickness 0.25)
		(keepout
			(tracks not_allowed)
			(vias allowed)
			(pads allowed)
			(copperpour not_allowed)
			(footprints allowed)
		)
		(placement
			(enabled no)
			(sheetname "")
		)
		(fill
			(thermal_gap 0.5)
			(thermal_bridge_width 0.5)
			(island_removal_mode 0)
		)
		(polygon
			(pts
				(arc
					(start 68.482972 -47.049944)
					(mid 70.383146 -48.950118)
					(end 72.283066 -47.049944)
				)
				(arc
					(start 72.283066 -47.049944)
					(mid 70.383146 -45.150024)
					(end 68.482972 -47.049944)
				)
			)
		)
	)
	(zone
		(layer "B.Cu")
		(hatch none 0.5)
		(connect_pads
			(clearance 0)
		)
		(min_thickness 0.25)
		(keepout
			(tracks allowed)
			(vias allowed)
			(pads allowed)
			(copperpour allowed)
			(footprints allowed)
		)
		(placement
			(enabled no)
			(sheetname "")
		)
		(fill
			(thermal_gap 0.5)
			(thermal_bridge_width 0.5)
			(island_removal_mode 0)
		)
		(polygon
			(pts
				(xy 10.795 -113.2586) (xy 10.795 -111.506) (xy 11.6586 -111.506) (xy 11.6586 -113.2586)
			)
		)
	)
	(zone
		(layer "B.Cu")
		(hatch none 0.5)
		(connect_pads
			(clearance 0)
		)
		(min_thickness 0.25)
		(keepout
			(tracks allowed)
			(vias allowed)
			(pads allowed)
			(copperpour allowed)
			(footprints allowed)
		)
		(placement
			(enabled no)
			(sheetname "")
		)
		(fill
			(thermal_gap 0.5)
			(thermal_bridge_width 0.5)
			(island_removal_mode 0)
		)
		(polygon
			(pts
				(xy 220.65234 -190.88862) (xy 220.65234 -190.30188) (xy 221.92996 -190.30188) (xy 221.92996 -190.88862)
			)
		)
	)
	(zone
		(layer "B.Cu")
		(hatch none 0.5)
		(connect_pads
			(clearance 0)
		)
		(min_thickness 0.25)
		(keepout
			(tracks allowed)
			(vias allowed)
			(pads allowed)
			(copperpour allowed)
			(footprints allowed)
		)
		(placement
			(enabled no)
			(sheetname "")
		)
		(fill
			(thermal_gap 0.5)
			(thermal_bridge_width 0.5)
			(island_removal_mode 0)
		)
		(polygon
			(pts
				(xy 206.96936 -192.58788) (xy 206.96936 -191.74714) (xy 209.20456 -191.74714) (xy 209.20456 -192.58788)
			)
		)
	)
	(zone
		(layer "B.Cu")
		(hatch none 0.5)
		(connect_pads
			(clearance 0)
		)
		(min_thickness 0.25)
		(keepout
			(tracks allowed)
			(vias allowed)
			(pads allowed)
			(copperpour allowed)
			(footprints allowed)
		)
		(placement
			(enabled no)
			(sheetname "")
		)
		(fill
			(thermal_gap 0.5)
			(thermal_bridge_width 0.5)
			(island_removal_mode 0)
		)
		(polygon
			(pts
				(xy 125.349 -409.046426) (xy 125.349 -408.04211) (xy 126.725934 -408.04211) (xy 126.725934 -409.046426)
			)
		)
	)
	(zone
		(layer "B.Cu")
		(hatch none 0.5)
		(connect_pads
			(clearance 0)
		)
		(min_thickness 0.25)
		(keepout
			(tracks not_allowed)
			(vias allowed)
			(pads allowed)
			(copperpour not_allowed)
			(footprints allowed)
		)
		(placement
			(enabled no)
			(sheetname "")
		)
		(fill
			(thermal_gap 0.5)
			(thermal_bridge_width 0.5)
			(island_removal_mode 0)
		)
		(polygon
			(pts
				(arc
					(start 346.876116 -244.484144)
					(mid 346.246196 -244.484144)
					(end 346.876116 -244.484144)
				)
			)
		)
	)
	(zone
		(layer "B.Cu")
		(hatch none 0.5)
		(connect_pads
			(clearance 0)
		)
		(min_thickness 0.25)
		(keepout
			(tracks allowed)
			(vias allowed)
			(pads allowed)
			(copperpour allowed)
			(footprints not_allowed)
		)
		(placement
			(enabled no)
			(sheetname "")
		)
		(fill
			(thermal_gap 0.5)
			(thermal_bridge_width 0.5)
			(island_removal_mode 0)
		)
		(polygon
			(pts
				(arc
					(start 444.33998 -40.420036)
					(mid 447.44005 -43.520106)
					(end 450.54012 -40.420036)
				)
				(arc
					(start 450.54012 -40.420036)
					(mid 447.44005 -37.319966)
					(end 444.33998 -40.420036)
				)
			)
		)
	)
	(zone
		(layer "B.Cu")
		(hatch none 0.5)
		(connect_pads
			(clearance 0)
		)
		(min_thickness 0.25)
		(keepout
			(tracks allowed)
			(vias allowed)
			(pads allowed)
			(copperpour allowed)
			(footprints allowed)
		)
		(placement
			(enabled no)
			(sheetname "")
		)
		(fill
			(thermal_gap 0.5)
			(thermal_bridge_width 0.5)
			(island_removal_mode 0)
		)
		(polygon
			(pts
				(xy 302.727614 -355.06279) (xy 302.449484 -355.06279) (xy 301.46244 -355.06279) (xy 301.46244 -354.395278)
				(xy 302.727614 -354.395278) (xy 303.50079 -354.395278) (xy 303.629822 -354.52431) (xy 303.629822 -354.965254)
				(xy 303.532286 -355.06279)
			)
		)
	)
	(zone
		(layer "B.Cu")
		(hatch none 0.5)
		(connect_pads
			(clearance 0)
		)
		(min_thickness 0.25)
		(keepout
			(tracks allowed)
			(vias allowed)
			(pads allowed)
			(copperpour allowed)
			(footprints allowed)
		)
		(placement
			(enabled no)
			(sheetname "")
		)
		(fill
			(thermal_gap 0.5)
			(thermal_bridge_width 0.5)
			(island_removal_mode 0)
		)
		(polygon
			(pts
				(xy 45.1866 -194.22618) (xy 45.1866 -193.15176) (xy 47.0789 -193.15176) (xy 47.0789 -194.22618)
			)
		)
	)
	(zone
		(layer "B.Cu")
		(hatch none 0.5)
		(connect_pads
			(clearance 0)
		)
		(min_thickness 0.25)
		(keepout
			(tracks not_allowed)
			(vias allowed)
			(pads allowed)
			(copperpour not_allowed)
			(footprints allowed)
		)
		(placement
			(enabled no)
			(sheetname "")
		)
		(fill
			(thermal_gap 0.5)
			(thermal_bridge_width 0.5)
			(island_removal_mode 0)
		)
		(polygon
			(pts
				(arc
					(start 5.340096 -160.50006)
					(mid 10.340086 -165.50005)
					(end 15.340076 -160.50006)
				)
				(arc
					(start 15.340076 -160.50006)
					(mid 10.340086 -155.50007)
					(end 5.340096 -160.50006)
				)
			)
		)
	)
	(zone
		(layer "B.Cu")
		(hatch none 0.5)
		(connect_pads
			(clearance 0)
		)
		(min_thickness 0.25)
		(keepout
			(tracks allowed)
			(vias allowed)
			(pads allowed)
			(copperpour allowed)
			(footprints allowed)
		)
		(placement
			(enabled no)
			(sheetname "")
		)
		(fill
			(thermal_gap 0.5)
			(thermal_bridge_width 0.5)
			(island_removal_mode 0)
		)
		(polygon
			(pts
				(xy 167.296338 -351.117154) (xy 167.296338 -350.112838) (xy 167.296338 -349.554038) (xy 167.455596 -349.39478)
				(xy 169.097706 -349.39478) (xy 169.193464 -349.490538) (xy 169.193464 -350.940878) (xy 169.017188 -351.117154)
				(xy 168.673272 -351.117154)
			)
		)
	)
	(zone
		(layer "B.Cu")
		(hatch none 0.5)
		(connect_pads
			(clearance 0)
		)
		(min_thickness 0.25)
		(keepout
			(tracks not_allowed)
			(vias allowed)
			(pads allowed)
			(copperpour not_allowed)
			(footprints allowed)
		)
		(placement
			(enabled no)
			(sheetname "")
		)
		(fill
			(thermal_gap 0.5)
			(thermal_bridge_width 0.5)
			(island_removal_mode 0)
		)
		(polygon
			(pts
				(arc
					(start 56.55056 -393.292838)
					(mid 55.88254 -393.292838)
					(end 56.55056 -393.292838)
				)
			)
		)
	)
	(zone
		(layer "B.Cu")
		(hatch none 0.5)
		(connect_pads
			(clearance 0)
		)
		(min_thickness 0.25)
		(keepout
			(tracks allowed)
			(vias allowed)
			(pads allowed)
			(copperpour allowed)
			(footprints allowed)
		)
		(placement
			(enabled no)
			(sheetname "")
		)
		(fill
			(thermal_gap 0.5)
			(thermal_bridge_width 0.5)
			(island_removal_mode 0)
		)
		(polygon
			(pts
				(xy 28.666694 -348.898972) (xy 28.666694 -351.057972) (xy 28.285694 -351.438972) (xy 25.491694 -351.438972)
				(xy 24.348694 -350.295972) (xy 24.348694 -347.374972) (xy 24.856694 -346.866972) (xy 26.634694 -346.866972)
			)
		)
	)
	(zone
		(layer "B.Cu")
		(hatch none 0.5)
		(connect_pads
			(clearance 0)
		)
		(min_thickness 0.25)
		(keepout
			(tracks allowed)
			(vias allowed)
			(pads allowed)
			(copperpour allowed)
			(footprints allowed)
		)
		(placement
			(enabled no)
			(sheetname "")
		)
		(fill
			(thermal_gap 0.5)
			(thermal_bridge_width 0.5)
			(island_removal_mode 0)
		)
		(polygon
			(pts
				(xy 102.17785 -221.174564) (xy 102.17785 -223.561402) (xy 102.90556 -224.289112) (xy 102.90556 -225.40722)
				(xy 104.731058 -225.40722) (xy 104.731058 -224.234502) (xy 105.666286 -224.234502) (xy 105.671112 -224.239328)
				(xy 105.671112 -221.174564)
			)
		)
	)
	(zone
		(layer "B.Cu")
		(hatch none 0.5)
		(connect_pads
			(clearance 0)
		)
		(min_thickness 0.25)
		(keepout
			(tracks not_allowed)
			(vias allowed)
			(pads allowed)
			(copperpour not_allowed)
			(footprints allowed)
		)
		(placement
			(enabled no)
			(sheetname "")
		)
		(fill
			(thermal_gap 0.5)
			(thermal_bridge_width 0.5)
			(island_removal_mode 0)
		)
		(polygon
			(pts
				(arc
					(start 157.1371 -439.0898)
					(mid 156.362908 -439.0898)
					(end 157.1371 -439.0898)
				)
			)
		)
	)
	(zone
		(layer "B.Cu")
		(hatch none 0.5)
		(connect_pads
			(clearance 0)
		)
		(min_thickness 0.25)
		(keepout
			(tracks not_allowed)
			(vias allowed)
			(pads allowed)
			(copperpour not_allowed)
			(footprints allowed)
		)
		(placement
			(enabled no)
			(sheetname "")
		)
		(fill
			(thermal_gap 0.5)
			(thermal_bridge_width 0.5)
			(island_removal_mode 0)
		)
		(polygon
			(pts
				(arc
					(start 382.136904 -438.089802)
					(mid 381.362712 -438.089802)
					(end 382.136904 -438.089802)
				)
			)
		)
	)
	(zone
		(layer "B.Cu")
		(hatch none 0.5)
		(connect_pads
			(clearance 0)
		)
		(min_thickness 0.25)
		(keepout
			(tracks not_allowed)
			(vias allowed)
			(pads allowed)
			(copperpour not_allowed)
			(footprints allowed)
		)
		(placement
			(enabled no)
			(sheetname "")
		)
		(fill
			(thermal_gap 0.5)
			(thermal_bridge_width 0.5)
			(island_removal_mode 0)
		)
		(polygon
			(pts
				(arc
					(start 355.636068 -270.036036)
					(mid 355.006148 -270.036036)
					(end 355.636068 -270.036036)
				)
			)
		)
	)
	(zone
		(layer "B.Cu")
		(hatch none 0.5)
		(connect_pads
			(clearance 0)
		)
		(min_thickness 0.25)
		(keepout
			(tracks not_allowed)
			(vias allowed)
			(pads allowed)
			(copperpour not_allowed)
			(footprints allowed)
		)
		(placement
			(enabled no)
			(sheetname "")
		)
		(fill
			(thermal_gap 0.5)
			(thermal_bridge_width 0.5)
			(island_removal_mode 0)
		)
		(polygon
			(pts
				(arc
					(start 48.150526 -393.292838)
					(mid 47.482506 -393.292838)
					(end 48.150526 -393.292838)
				)
			)
		)
	)
	(zone
		(layer "B.Cu")
		(hatch none 0.5)
		(connect_pads
			(clearance 0)
		)
		(min_thickness 0.25)
		(keepout
			(tracks not_allowed)
			(vias allowed)
			(pads allowed)
			(copperpour not_allowed)
			(footprints allowed)
		)
		(placement
			(enabled no)
			(sheetname "")
		)
		(fill
			(thermal_gap 0.5)
			(thermal_bridge_width 0.5)
			(island_removal_mode 0)
		)
		(polygon
			(pts
				(arc
					(start 403.778212 -400.811238)
					(mid 403.110192 -400.811238)
					(end 403.778212 -400.811238)
				)
			)
		)
	)
	(zone
		(layer "B.Cu")
		(hatch none 0.5)
		(connect_pads
			(clearance 0)
		)
		(min_thickness 0.25)
		(keepout
			(tracks not_allowed)
			(vias allowed)
			(pads allowed)
			(copperpour not_allowed)
			(footprints allowed)
		)
		(placement
			(enabled no)
			(sheetname "")
		)
		(fill
			(thermal_gap 0.5)
			(thermal_bridge_width 0.5)
			(island_removal_mode 0)
		)
		(polygon
			(pts
				(arc
					(start 357.046022 -272.466054)
					(mid 356.416102 -272.466054)
					(end 357.046022 -272.466054)
				)
			)
		)
	)
	(zone
		(layer "B.Cu")
		(hatch none 0.5)
		(connect_pads
			(clearance 0)
		)
		(min_thickness 0.25)
		(keepout
			(tracks not_allowed)
			(vias allowed)
			(pads allowed)
			(copperpour not_allowed)
			(footprints allowed)
		)
		(placement
			(enabled no)
			(sheetname "")
		)
		(fill
			(thermal_gap 0.5)
			(thermal_bridge_width 0.5)
			(island_removal_mode 0)
		)
		(polygon
			(pts
				(arc
					(start 308.95036 -401.674838)
					(mid 308.28234 -401.674838)
					(end 308.95036 -401.674838)
				)
			)
		)
	)
	(zone
		(layer "B.Cu")
		(hatch none 0.5)
		(connect_pads
			(clearance 0)
		)
		(min_thickness 0.25)
		(keepout
			(tracks not_allowed)
			(vias allowed)
			(pads allowed)
			(copperpour not_allowed)
			(footprints allowed)
		)
		(placement
			(enabled no)
			(sheetname "")
		)
		(fill
			(thermal_gap 0.5)
			(thermal_bridge_width 0.5)
			(island_removal_mode 0)
		)
		(polygon
			(pts
				(arc
					(start 256.261108 -193.432684)
					(mid 255.593088 -193.432684)
					(end 256.261108 -193.432684)
				)
			)
		)
	)
	(zone
		(layer "B.Cu")
		(hatch none 0.5)
		(connect_pads
			(clearance 0)
		)
		(min_thickness 0.25)
		(keepout
			(tracks not_allowed)
			(vias allowed)
			(pads allowed)
			(copperpour not_allowed)
			(footprints allowed)
		)
		(placement
			(enabled no)
			(sheetname "")
		)
		(fill
			(thermal_gap 0.5)
			(thermal_bridge_width 0.5)
			(island_removal_mode 0)
		)
		(polygon
			(pts
				(arc
					(start 308.95036 -400.811238)
					(mid 308.28234 -400.811238)
					(end 308.95036 -400.811238)
				)
			)
		)
	)
	(zone
		(layer "B.Cu")
		(hatch none 0.5)
		(connect_pads
			(clearance 0)
		)
		(min_thickness 0.25)
		(keepout
			(tracks not_allowed)
			(vias allowed)
			(pads allowed)
			(copperpour not_allowed)
			(footprints allowed)
		)
		(placement
			(enabled no)
			(sheetname "")
		)
		(fill
			(thermal_gap 0.5)
			(thermal_bridge_width 0.5)
			(island_removal_mode 0)
		)
		(polygon
			(pts
				(arc
					(start 336.03692 -438.089802)
					(mid 335.262728 -438.089802)
					(end 336.03692 -438.089802)
				)
			)
		)
	)
	(zone
		(layer "B.Cu")
		(hatch none 0.5)
		(connect_pads
			(clearance 0)
		)
		(min_thickness 0.25)
		(keepout
			(tracks not_allowed)
			(vias allowed)
			(pads allowed)
			(copperpour not_allowed)
			(footprints allowed)
		)
		(placement
			(enabled no)
			(sheetname "")
		)
		(fill
			(thermal_gap 0.5)
			(thermal_bridge_width 0.5)
			(island_removal_mode 0)
		)
		(polygon
			(pts
				(arc
					(start 399.137124 -438.089802)
					(mid 398.362932 -438.089802)
					(end 399.137124 -438.089802)
				)
			)
		)
	)
	(zone
		(layer "B.Cu")
		(hatch none 0.5)
		(connect_pads
			(clearance 0)
		)
		(min_thickness 0.25)
		(keepout
			(tracks allowed)
			(vias allowed)
			(pads allowed)
			(copperpour allowed)
			(footprints not_allowed)
		)
		(placement
			(enabled no)
			(sheetname "")
		)
		(fill
			(thermal_gap 0.5)
			(thermal_bridge_width 0.5)
			(island_removal_mode 0)
		)
		(polygon
			(pts
				(arc
					(start 102.283006 -47.049944)
					(mid 100.383086 -45.150024)
					(end 98.482912 -47.049944)
				)
				(arc
					(start 98.482912 -47.049944)
					(mid 100.383086 -48.950118)
					(end 102.283006 -47.049944)
				)
			)
		)
	)
	(zone
		(layer "B.Cu")
		(hatch none 0.5)
		(connect_pads
			(clearance 0)
		)
		(min_thickness 0.25)
		(keepout
			(tracks not_allowed)
			(vias allowed)
			(pads allowed)
			(copperpour not_allowed)
			(footprints allowed)
		)
		(placement
			(enabled no)
			(sheetname "")
		)
		(fill
			(thermal_gap 0.5)
			(thermal_bridge_width 0.5)
			(island_removal_mode 0)
		)
		(polygon
			(pts
				(arc
					(start 109.615986 -340.315042)
					(mid 112.716056 -343.415112)
					(end 115.816126 -340.315042)
				)
				(arc
					(start 115.816126 -340.315042)
					(mid 112.716056 -337.214972)
					(end 109.615986 -340.315042)
				)
			)
		)
	)
	(zone
		(layer "B.Cu")
		(hatch none 0.5)
		(connect_pads
			(clearance 0)
		)
		(min_thickness 0.25)
		(keepout
			(tracks not_allowed)
			(vias allowed)
			(pads allowed)
			(copperpour not_allowed)
			(footprints allowed)
		)
		(placement
			(enabled no)
			(sheetname "")
		)
		(fill
			(thermal_gap 0.5)
			(thermal_bridge_width 0.5)
			(island_removal_mode 0)
		)
		(polygon
			(pts
				(arc
					(start 325.036688 -439.0898)
					(mid 324.262496 -439.0898)
					(end 325.036688 -439.0898)
				)
			)
		)
	)
	(zone
		(layer "B.Cu")
		(hatch none 0.5)
		(connect_pads
			(clearance 0)
		)
		(min_thickness 0.25)
		(keepout
			(tracks allowed)
			(vias allowed)
			(pads allowed)
			(copperpour allowed)
			(footprints not_allowed)
		)
		(placement
			(enabled no)
			(sheetname "")
		)
		(fill
			(thermal_gap 0.5)
			(thermal_bridge_width 0.5)
			(island_removal_mode 0)
		)
		(polygon
			(pts
				(arc
					(start 107.10418 -19.596354)
					(mid 105.609166 -15.852974)
					(end 103.000556 -12.78001)
				)
				(arc
					(start 86.79942 -12.78001)
					(mid 82.798992 -25.432657)
					(end 92.436442 -34.554922)
				)
				(arc
					(start 92.436442 -34.554922)
					(mid 86.046001 -36.520897)
					(end 81.583022 -41.499282)
				)
				(arc
					(start 81.583022 -41.499282)
					(mid 75.261052 -35.541117)
					(end 66.583052 -35.141662)
				)
				(arc
					(start 66.583052 -35.141662)
					(mid 50.2828 -47.050237)
					(end 66.583052 -58.95848)
				)
				(arc
					(start 66.583052 -58.95848)
					(mid 75.261074 -58.558869)
					(end 81.583022 -52.600606)
				)
				(arc
					(start 81.583022 -52.600606)
					(mid 87.904959 -58.558897)
					(end 96.582992 -58.95848)
				)
				(arc
					(start 96.582992 -58.95848)
					(mid 108.811167 -56.281151)
					(end 112.587024 -44.346368)
				)
			)
		)
	)
	(zone
		(layer "B.Cu")
		(hatch none 0.5)
		(connect_pads
			(clearance 0)
		)
		(min_thickness 0.25)
		(keepout
			(tracks not_allowed)
			(vias allowed)
			(pads allowed)
			(copperpour not_allowed)
			(footprints allowed)
		)
		(placement
			(enabled no)
			(sheetname "")
		)
		(fill
			(thermal_gap 0.5)
			(thermal_bridge_width 0.5)
			(island_removal_mode 0)
		)
		(polygon
			(pts
				(arc
					(start 120.54967 -247.724422)
					(mid 119.91975 -247.724422)
					(end 120.54967 -247.724422)
				)
			)
		)
	)
	(zone
		(layer "B.Cu")
		(hatch none 0.5)
		(connect_pads
			(clearance 0)
		)
		(min_thickness 0.25)
		(keepout
			(tracks allowed)
			(vias allowed)
			(pads allowed)
			(copperpour allowed)
			(footprints allowed)
		)
		(placement
			(enabled no)
			(sheetname "")
		)
		(fill
			(thermal_gap 0.5)
			(thermal_bridge_width 0.5)
			(island_removal_mode 0)
		)
		(polygon
			(pts
				(xy 206.66456 -37.67836) (xy 206.66456 -35.23996) (xy 208.9912 -35.23996) (xy 208.9912 -37.67836)
			)
		)
	)
	(zone
		(layer "B.Cu")
		(hatch none 0.5)
		(connect_pads
			(clearance 0)
		)
		(min_thickness 0.25)
		(keepout
			(tracks allowed)
			(vias allowed)
			(pads allowed)
			(copperpour allowed)
			(footprints allowed)
		)
		(placement
			(enabled no)
			(sheetname "")
		)
		(fill
			(thermal_gap 0.5)
			(thermal_bridge_width 0.5)
			(island_removal_mode 0)
		)
		(polygon
			(pts
				(xy 190.72098 -134.83844) (xy 190.72098 -134.0358) (xy 192.70472 -134.0358) (xy 192.70472 -134.83844)
			)
		)
	)
	(zone
		(layer "B.Cu")
		(hatch none 0.5)
		(connect_pads
			(clearance 0)
		)
		(min_thickness 0.25)
		(keepout
			(tracks not_allowed)
			(vias allowed)
			(pads allowed)
			(copperpour not_allowed)
			(footprints allowed)
		)
		(placement
			(enabled no)
			(sheetname "")
		)
		(fill
			(thermal_gap 0.5)
			(thermal_bridge_width 0.5)
			(island_removal_mode 0)
		)
		(polygon
			(pts
				(arc
					(start 151.137112 -436.889906)
					(mid 150.36292 -436.889906)
					(end 151.137112 -436.889906)
				)
			)
		)
	)
	(zone
		(layer "B.Cu")
		(hatch none 0.5)
		(connect_pads
			(clearance 0)
		)
		(min_thickness 0.25)
		(keepout
			(tracks not_allowed)
			(vias allowed)
			(pads allowed)
			(copperpour not_allowed)
			(footprints allowed)
		)
		(placement
			(enabled no)
			(sheetname "")
		)
		(fill
			(thermal_gap 0.5)
			(thermal_bridge_width 0.5)
			(island_removal_mode 0)
		)
		(polygon
			(pts
				(arc
					(start 102.283006 -47.049944)
					(mid 100.383086 -45.150024)
					(end 98.482912 -47.049944)
				)
				(arc
					(start 98.482912 -47.049944)
					(mid 100.383086 -48.950118)
					(end 102.283006 -47.049944)
				)
			)
		)
	)
	(zone
		(layer "B.Cu")
		(hatch none 0.5)
		(connect_pads
			(clearance 0)
		)
		(min_thickness 0.25)
		(keepout
			(tracks allowed)
			(vias allowed)
			(pads allowed)
			(copperpour allowed)
			(footprints allowed)
		)
		(placement
			(enabled no)
			(sheetname "")
		)
		(fill
			(thermal_gap 0.5)
			(thermal_bridge_width 0.5)
			(island_removal_mode 0)
		)
		(polygon
			(pts
				(xy 190.81496 -133.04266) (xy 190.81496 -130.02006) (xy 192.4685 -130.02006) (xy 192.4685 -133.04266)
			)
		)
	)
	(zone
		(layer "B.Cu")
		(hatch none 0.5)
		(connect_pads
			(clearance 0)
		)
		(min_thickness 0.25)
		(keepout
			(tracks not_allowed)
			(vias allowed)
			(pads allowed)
			(copperpour not_allowed)
			(footprints allowed)
		)
		(placement
			(enabled no)
			(sheetname "")
		)
		(fill
			(thermal_gap 0.5)
			(thermal_bridge_width 0.5)
			(island_removal_mode 0)
		)
		(polygon
			(pts
				(arc
					(start 145.32991 -304.790094)
					(mid 142.530068 -301.990252)
					(end 139.729972 -304.790094)
				)
				(arc
					(start 139.729972 -304.790094)
					(mid 142.530068 -307.59019)
					(end 145.32991 -304.790094)
				)
			)
		)
	)
	(zone
		(layer "B.Cu")
		(hatch none 0.5)
		(connect_pads
			(clearance 0)
		)
		(min_thickness 0.25)
		(keepout
			(tracks not_allowed)
			(vias allowed)
			(pads allowed)
			(copperpour not_allowed)
			(footprints allowed)
		)
		(placement
			(enabled no)
			(sheetname "")
		)
		(fill
			(thermal_gap 0.5)
			(thermal_bridge_width 0.5)
			(island_removal_mode 0)
		)
		(polygon
			(pts
				(arc
					(start 316.150498 -400.811238)
					(mid 315.482478 -400.811238)
					(end 316.150498 -400.811238)
				)
			)
		)
	)
	(zone
		(layer "B.Cu")
		(hatch none 0.5)
		(connect_pads
			(clearance 0)
		)
		(min_thickness 0.25)
		(keepout
			(tracks not_allowed)
			(vias allowed)
			(pads allowed)
			(copperpour not_allowed)
			(footprints allowed)
		)
		(placement
			(enabled no)
			(sheetname "")
		)
		(fill
			(thermal_gap 0.5)
			(thermal_bridge_width 0.5)
			(island_removal_mode 0)
		)
		(polygon
			(pts
				(arc
					(start 125.249686 -246.10441)
					(mid 124.619766 -246.10441)
					(end 125.249686 -246.10441)
				)
			)
		)
	)
	(zone
		(layer "B.Cu")
		(hatch none 0.5)
		(connect_pads
			(clearance 0)
		)
		(min_thickness 0.25)
		(keepout
			(tracks not_allowed)
			(vias allowed)
			(pads allowed)
			(copperpour not_allowed)
			(footprints allowed)
		)
		(placement
			(enabled no)
			(sheetname "")
		)
		(fill
			(thermal_gap 0.5)
			(thermal_bridge_width 0.5)
			(island_removal_mode 0)
		)
		(polygon
			(pts
				(arc
					(start 314.950348 -400.811238)
					(mid 314.282328 -400.811238)
					(end 314.950348 -400.811238)
				)
			)
		)
	)
	(zone
		(layer "B.Cu")
		(hatch none 0.5)
		(connect_pads
			(clearance 0)
		)
		(min_thickness 0.25)
		(keepout
			(tracks not_allowed)
			(vias allowed)
			(pads allowed)
			(copperpour not_allowed)
			(footprints allowed)
		)
		(placement
			(enabled no)
			(sheetname "")
		)
		(fill
			(thermal_gap 0.5)
			(thermal_bridge_width 0.5)
			(island_removal_mode 0)
		)
		(polygon
			(pts
				(arc
					(start 133.21792 -10.243312)
					(mid 132.5499 -10.243312)
					(end 133.21792 -10.243312)
				)
			)
		)
	)
	(zone
		(layer "B.Cu")
		(hatch none 0.5)
		(connect_pads
			(clearance 0)
		)
		(min_thickness 0.25)
		(keepout
			(tracks not_allowed)
			(vias allowed)
			(pads allowed)
			(copperpour not_allowed)
			(footprints allowed)
		)
		(placement
			(enabled no)
			(sheetname "")
		)
		(fill
			(thermal_gap 0.5)
			(thermal_bridge_width 0.5)
			(island_removal_mode 0)
		)
		(polygon
			(pts
				(arc
					(start 62.550548 -392.429238)
					(mid 61.882528 -392.429238)
					(end 62.550548 -392.429238)
				)
			)
		)
	)
	(zone
		(layer "B.Cu")
		(hatch none 0.5)
		(connect_pads
			(clearance 0)
		)
		(min_thickness 0.25)
		(keepout
			(tracks allowed)
			(vias allowed)
			(pads allowed)
			(copperpour allowed)
			(footprints allowed)
		)
		(placement
			(enabled no)
			(sheetname "")
		)
		(fill
			(thermal_gap 0.5)
			(thermal_bridge_width 0.5)
			(island_removal_mode 0)
		)
		(polygon
			(pts
				(xy 259.34416 1.8034) (xy 259.34416 3.6957) (xy 261.5057 3.6957) (xy 261.5057 1.8034)
			)
		)
	)
	(zone
		(layer "B.Cu")
		(hatch none 0.5)
		(connect_pads
			(clearance 0)
		)
		(min_thickness 0.25)
		(keepout
			(tracks not_allowed)
			(vias allowed)
			(pads allowed)
			(copperpour not_allowed)
			(footprints allowed)
		)
		(placement
			(enabled no)
			(sheetname "")
		)
		(fill
			(thermal_gap 0.5)
			(thermal_bridge_width 0.5)
			(island_removal_mode 0)
		)
		(polygon
			(pts
				(arc
					(start 86.037166 -437.889904)
					(mid 85.262974 -437.889904)
					(end 86.037166 -437.889904)
				)
			)
		)
	)
	(zone
		(layer "B.Cu")
		(hatch none 0.5)
		(connect_pads
			(clearance 0)
		)
		(min_thickness 0.25)
		(keepout
			(tracks allowed)
			(vias allowed)
			(pads allowed)
			(copperpour allowed)
			(footprints not_allowed)
		)
		(placement
			(enabled no)
			(sheetname "")
		)
		(fill
			(thermal_gap 0.5)
			(thermal_bridge_width 0.5)
			(island_removal_mode 0)
		)
		(polygon
			(pts
				(arc
					(start 228.650038 -352.495612)
					(mid 236.650022 -360.495596)
					(end 244.650006 -352.495612)
				)
				(arc
					(start 244.650006 -352.495612)
					(mid 236.650022 -344.495628)
					(end 228.650038 -352.495612)
				)
			)
		)
	)
	(zone
		(layer "B.Cu")
		(hatch none 0.5)
		(connect_pads
			(clearance 0)
		)
		(min_thickness 0.25)
		(keepout
			(tracks allowed)
			(vias allowed)
			(pads allowed)
			(copperpour allowed)
			(footprints allowed)
		)
		(placement
			(enabled no)
			(sheetname "")
		)
		(fill
			(thermal_gap 0.5)
			(thermal_bridge_width 0.5)
			(island_removal_mode 0)
		)
		(polygon
			(pts
				(xy 176.88052 -193.69278) (xy 176.88052 -190.57366) (xy 178.9938 -190.57366) (xy 178.9938 -193.69278)
			)
		)
	)
	(zone
		(layer "B.Cu")
		(hatch none 0.5)
		(connect_pads
			(clearance 0)
		)
		(min_thickness 0.25)
		(keepout
			(tracks allowed)
			(vias allowed)
			(pads allowed)
			(copperpour allowed)
			(footprints not_allowed)
		)
		(placement
			(enabled no)
			(sheetname "")
		)
		(fill
			(thermal_gap 0.5)
			(thermal_bridge_width 0.5)
			(island_removal_mode 0)
		)
		(polygon
			(pts
				(arc
					(start 281.15006 -51.999896)
					(mid 268.650212 -39.500048)
					(end 256.15011 -51.999896)
				)
				(arc
					(start 256.15011 -51.999896)
					(mid 268.650212 -64.499998)
					(end 281.15006 -51.999896)
				)
			)
		)
	)
	(zone
		(layer "B.Cu")
		(hatch none 0.5)
		(connect_pads
			(clearance 0)
		)
		(min_thickness 0.25)
		(keepout
			(tracks not_allowed)
			(vias allowed)
			(pads allowed)
			(copperpour not_allowed)
			(footprints allowed)
		)
		(placement
			(enabled no)
			(sheetname "")
		)
		(fill
			(thermal_gap 0.5)
			(thermal_bridge_width 0.5)
			(island_removal_mode 0)
		)
		(polygon
			(pts
				(arc
					(start 60.150756 -393.292838)
					(mid 59.482736 -393.292838)
					(end 60.150756 -393.292838)
				)
			)
		)
	)
	(zone
		(layer "B.Cu")
		(hatch none 0.5)
		(connect_pads
			(clearance 0)
		)
		(min_thickness 0.25)
		(keepout
			(tracks allowed)
			(vias allowed)
			(pads allowed)
			(copperpour allowed)
			(footprints allowed)
		)
		(placement
			(enabled no)
			(sheetname "")
		)
		(fill
			(thermal_gap 0.5)
			(thermal_bridge_width 0.5)
			(island_removal_mode 0)
		)
		(polygon
			(pts
				(xy 312.008774 -355.694742) (xy 312.008774 -355.972872) (xy 312.008774 -356.959916) (xy 311.341262 -356.959916)
				(xy 311.341262 -355.694742)
			)
		)
	)
	(zone
		(layer "B.Cu")
		(hatch none 0.5)
		(connect_pads
			(clearance 0)
		)
		(min_thickness 0.25)
		(keepout
			(tracks not_allowed)
			(vias allowed)
			(pads allowed)
			(copperpour not_allowed)
			(footprints allowed)
		)
		(placement
			(enabled no)
			(sheetname "")
		)
		(fill
			(thermal_gap 0.5)
			(thermal_bridge_width 0.5)
			(island_removal_mode 0)
		)
		(polygon
			(pts
				(arc
					(start 80.037178 -438.089802)
					(mid 79.262986 -438.089802)
					(end 80.037178 -438.089802)
				)
			)
		)
	)
	(zone
		(layer "B.Cu")
		(hatch none 0.5)
		(connect_pads
			(clearance 0)
		)
		(min_thickness 0.25)
		(keepout
			(tracks not_allowed)
			(vias allowed)
			(pads allowed)
			(copperpour not_allowed)
			(footprints allowed)
		)
		(placement
			(enabled no)
			(sheetname "")
		)
		(fill
			(thermal_gap 0.5)
			(thermal_bridge_width 0.5)
			(island_removal_mode 0)
		)
		(polygon
			(pts
				(arc
					(start 61.706252 -386.003292)
					(mid 61.076332 -386.003292)
					(end 61.706252 -386.003292)
				)
			)
		)
	)
	(zone
		(layer "B.Cu")
		(hatch none 0.5)
		(connect_pads
			(clearance 0)
		)
		(min_thickness 0.25)
		(keepout
			(tracks allowed)
			(vias allowed)
			(pads allowed)
			(copperpour allowed)
			(footprints not_allowed)
		)
		(placement
			(enabled no)
			(sheetname "")
		)
		(fill
			(thermal_gap 0.5)
			(thermal_bridge_width 0.5)
			(island_removal_mode 0)
		)
		(polygon
			(pts
				(arc
					(start 466.460078 -160.50006)
					(mid 461.460088 -155.50007)
					(end 456.460098 -160.50006)
				)
				(arc
					(start 456.460098 -160.50006)
					(mid 461.460088 -165.50005)
					(end 466.460078 -160.50006)
				)
			)
		)
	)
	(zone
		(layer "B.Cu")
		(hatch none 0.5)
		(connect_pads
			(clearance 0)
		)
		(min_thickness 0.25)
		(keepout
			(tracks not_allowed)
			(vias allowed)
			(pads allowed)
			(copperpour not_allowed)
			(footprints allowed)
		)
		(placement
			(enabled no)
			(sheetname "")
		)
		(fill
			(thermal_gap 0.5)
			(thermal_bridge_width 0.5)
			(island_removal_mode 0)
		)
		(polygon
			(pts
				(arc
					(start 136.136888 -439.0898)
					(mid 135.362696 -439.0898)
					(end 136.136888 -439.0898)
				)
			)
		)
	)
	(zone
		(layer "B.Cu")
		(hatch none 0.5)
		(connect_pads
			(clearance 0)
		)
		(min_thickness 0.25)
		(keepout
			(tracks not_allowed)
			(vias allowed)
			(pads allowed)
			(copperpour not_allowed)
			(footprints allowed)
		)
		(placement
			(enabled no)
			(sheetname "")
		)
		(fill
			(thermal_gap 0.5)
			(thermal_bridge_width 0.5)
			(island_removal_mode 0)
		)
		(polygon
			(pts
				(arc
					(start 105.500424 -435.600094)
					(mid 100.500434 -430.600104)
					(end 95.500444 -435.600094)
				)
				(arc
					(start 95.500444 -435.600094)
					(mid 100.500434 -440.600084)
					(end 105.500424 -435.600094)
				)
			)
		)
	)
	(zone
		(layer "B.Cu")
		(hatch none 0.5)
		(connect_pads
			(clearance 0)
		)
		(min_thickness 0.25)
		(keepout
			(tracks allowed)
			(vias allowed)
			(pads allowed)
			(copperpour allowed)
			(footprints not_allowed)
		)
		(placement
			(enabled no)
			(sheetname "")
		)
		(fill
			(thermal_gap 0.5)
			(thermal_bridge_width 0.5)
			(island_removal_mode 0)
		)
		(polygon
			(pts
				(arc
					(start 221.430342 -388.161784)
					(mid 225.430334 -392.161776)
					(end 229.430326 -388.161784)
				)
				(arc
					(start 229.430326 -388.161784)
					(mid 225.430334 -384.161792)
					(end 221.430342 -388.161784)
				)
			)
		)
	)
	(zone
		(layer "B.Cu")
		(hatch none 0.5)
		(connect_pads
			(clearance 0)
		)
		(min_thickness 0.25)
		(keepout
			(tracks not_allowed)
			(vias allowed)
			(pads allowed)
			(copperpour not_allowed)
			(footprints allowed)
		)
		(placement
			(enabled no)
			(sheetname "")
		)
		(fill
			(thermal_gap 0.5)
			(thermal_bridge_width 0.5)
			(island_removal_mode 0)
		)
		(polygon
			(pts
				(arc
					(start 13.139928 -160.50006)
					(mid 10.340086 -157.700218)
					(end 7.53999 -160.50006)
				)
				(arc
					(start 7.53999 -160.50006)
					(mid 10.340086 -163.300156)
					(end 13.139928 -160.50006)
				)
			)
		)
	)
	(zone
		(layer "B.Cu")
		(hatch none 0.5)
		(connect_pads
			(clearance 0)
		)
		(min_thickness 0.25)
		(keepout
			(tracks not_allowed)
			(vias allowed)
			(pads allowed)
			(copperpour not_allowed)
			(footprints allowed)
		)
		(placement
			(enabled no)
			(sheetname "")
		)
		(fill
			(thermal_gap 0.5)
			(thermal_bridge_width 0.5)
			(island_removal_mode 0)
		)
		(polygon
			(pts
				(arc
					(start 59.306206 -386.003292)
					(mid 58.676286 -386.003292)
					(end 59.306206 -386.003292)
				)
			)
		)
	)
	(zone
		(layer "B.Cu")
		(hatch none 0.5)
		(connect_pads
			(clearance 0)
		)
		(min_thickness 0.25)
		(keepout
			(tracks allowed)
			(vias allowed)
			(pads allowed)
			(copperpour allowed)
			(footprints not_allowed)
		)
		(placement
			(enabled no)
			(sheetname "")
		)
		(fill
			(thermal_gap 0.5)
			(thermal_bridge_width 0.5)
			(island_removal_mode 0)
		)
		(polygon
			(pts
				(arc
					(start 415.81705 -351.415096)
					(mid 413.952182 -349.550228)
					(end 412.08706 -351.415096)
				)
				(arc
					(start 412.08706 -351.415096)
					(mid 413.952182 -353.280218)
					(end 415.81705 -351.415096)
				)
			)
		)
	)
	(zone
		(layer "B.Cu")
		(hatch none 0.5)
		(connect_pads
			(clearance 0)
		)
		(min_thickness 0.25)
		(keepout
			(tracks allowed)
			(vias allowed)
			(pads allowed)
			(copperpour allowed)
			(footprints allowed)
		)
		(placement
			(enabled no)
			(sheetname "")
		)
		(fill
			(thermal_gap 0.5)
			(thermal_bridge_width 0.5)
			(island_removal_mode 0)
		)
		(polygon
			(pts
				(xy 347.94444 -417.428426) (xy 347.94444 -416.42411) (xy 349.321374 -416.42411) (xy 349.321374 -417.428426)
			)
		)
	)
	(zone
		(layer "B.Cu")
		(hatch none 0.5)
		(connect_pads
			(clearance 0)
		)
		(min_thickness 0.25)
		(keepout
			(tracks not_allowed)
			(vias allowed)
			(pads allowed)
			(copperpour not_allowed)
			(footprints allowed)
		)
		(placement
			(enabled no)
			(sheetname "")
		)
		(fill
			(thermal_gap 0.5)
			(thermal_bridge_width 0.5)
			(island_removal_mode 0)
		)
		(polygon
			(pts
				(arc
					(start 317.036704 -439.0898)
					(mid 316.262512 -439.0898)
					(end 317.036704 -439.0898)
				)
			)
		)
	)
	(zone
		(layer "B.Cu")
		(hatch none 0.5)
		(connect_pads
			(clearance 0)
		)
		(min_thickness 0.25)
		(keepout
			(tracks not_allowed)
			(vias allowed)
			(pads allowed)
			(copperpour not_allowed)
			(footprints allowed)
		)
		(placement
			(enabled no)
			(sheetname "")
		)
		(fill
			(thermal_gap 0.5)
			(thermal_bridge_width 0.5)
			(island_removal_mode 0)
		)
		(polygon
			(pts
				(arc
					(start 419.37813 -400.811238)
					(mid 418.71011 -400.811238)
					(end 419.37813 -400.811238)
				)
			)
		)
	)
	(zone
		(layer "B.Cu")
		(hatch none 0.5)
		(connect_pads
			(clearance 0)
		)
		(min_thickness 0.25)
		(keepout
			(tracks not_allowed)
			(vias allowed)
			(pads allowed)
			(copperpour not_allowed)
			(footprints allowed)
		)
		(placement
			(enabled no)
			(sheetname "")
		)
		(fill
			(thermal_gap 0.5)
			(thermal_bridge_width 0.5)
			(island_removal_mode 0)
		)
		(polygon
			(pts
				(arc
					(start 399.137124 -436.889906)
					(mid 398.362932 -436.889906)
					(end 399.137124 -436.889906)
				)
			)
		)
	)
	(zone
		(layer "B.Cu")
		(hatch none 0.5)
		(connect_pads
			(clearance 0)
		)
		(min_thickness 0.25)
		(keepout
			(tracks allowed)
			(vias allowed)
			(pads allowed)
			(copperpour allowed)
			(footprints not_allowed)
		)
		(placement
			(enabled no)
			(sheetname "")
		)
		(fill
			(thermal_gap 0.5)
			(thermal_bridge_width 0.5)
			(island_removal_mode 0)
		)
		(polygon
			(pts
				(arc
					(start 238.748316 -51.861974)
					(mid 249.172176 -47.857874)
					(end 252.236478 -37.120068)
				)
				(arc
					(start 225.300032 -37.120068)
					(mid 223.178716 -36.24139)
					(end 222.300038 -34.120074)
				)
				(arc
					(start 222.300038 -33.728152)
					(mid 219.391482 -52.89292)
					(end 238.748316 -51.861974)
				)
			)
		)
	)
	(zone
		(layer "B.Cu")
		(hatch none 0.5)
		(connect_pads
			(clearance 0)
		)
		(min_thickness 0.25)
		(keepout
			(tracks not_allowed)
			(vias allowed)
			(pads allowed)
			(copperpour not_allowed)
			(footprints allowed)
		)
		(placement
			(enabled no)
			(sheetname "")
		)
		(fill
			(thermal_gap 0.5)
			(thermal_bridge_width 0.5)
			(island_removal_mode 0)
		)
		(polygon
			(pts
				(arc
					(start 108.774992 -431.360072)
					(mid 112.025176 -434.610256)
					(end 115.275106 -431.360072)
				)
				(arc
					(start 115.275106 -431.360072)
					(mid 112.025176 -428.110142)
					(end 108.774992 -431.360072)
				)
			)
		)
	)
	(zone
		(layer "B.Cu")
		(hatch none 0.5)
		(connect_pads
			(clearance 0)
		)
		(min_thickness 0.25)
		(keepout
			(tracks allowed)
			(vias allowed)
			(pads allowed)
			(copperpour allowed)
			(footprints not_allowed)
		)
		(placement
			(enabled no)
			(sheetname "")
		)
		(fill
			(thermal_gap 0.5)
			(thermal_bridge_width 0.5)
			(island_removal_mode 0)
		)
		(polygon
			(pts
				(arc
					(start 195.568316 -12.557506)
					(mid 203.225355 -34.799103)
					(end 211.500466 -12.78001)
				)
				(arc
					(start 196.702426 -12.78001)
					(mid 196.124556 -12.723883)
					(end 195.568316 -12.557506)
				)
			)
		)
	)
	(zone
		(layer "B.Cu")
		(hatch none 0.5)
		(connect_pads
			(clearance 0)
		)
		(min_thickness 0.25)
		(keepout
			(tracks allowed)
			(vias allowed)
			(pads allowed)
			(copperpour allowed)
			(footprints not_allowed)
		)
		(placement
			(enabled no)
			(sheetname "")
		)
		(fill
			(thermal_gap 0.5)
			(thermal_bridge_width 0.5)
			(island_removal_mode 0)
		)
		(polygon
			(pts
				(arc
					(start 169.809922 -371.089936)
					(mid 169.37062 -370.029368)
					(end 168.310052 -369.590066)
				)
				(arc
					(start 49.018444 -369.590066)
					(mid 48.444566 -369.704217)
					(end 47.957994 -370.029232)
				)
				(arc
					(start 42.41927 -375.567956)
					(mid 42.09418 -376.054626)
					(end 41.980104 -376.62866)
				)
				(arc
					(start 41.980104 -391.78992)
					(mid 42.419301 -392.850742)
					(end 43.479974 -393.290044)
				)
				(arc
					(start 62.771782 -393.290044)
					(mid 63.805659 -393.410365)
					(end 64.784224 -393.765024)
				)
				(arc
					(start 65.517268 -394.131546)
					(mid 65.84345 -394.249833)
					(end 66.188082 -394.290042)
				)
				(arc
					(start 145.60169 -394.290042)
					(mid 145.946328 -394.249857)
					(end 146.272504 -394.131546)
				)
				(arc
					(start 147.005802 -393.765024)
					(mid 147.984372 -393.410385)
					(end 149.018244 -393.290044)
				)
				(arc
					(start 168.310052 -393.290044)
					(mid 169.37071 -392.850652)
					(end 169.809922 -391.78992)
				)
			)
		)
	)
	(zone
		(layer "B.Cu")
		(hatch none 0.5)
		(connect_pads
			(clearance 0)
		)
		(min_thickness 0.25)
		(keepout
			(tracks not_allowed)
			(vias allowed)
			(pads allowed)
			(copperpour not_allowed)
			(footprints allowed)
		)
		(placement
			(enabled no)
			(sheetname "")
		)
		(fill
			(thermal_gap 0.5)
			(thermal_bridge_width 0.5)
			(island_removal_mode 0)
		)
		(polygon
			(pts
				(arc
					(start 165.77818 -393.292838)
					(mid 165.11016 -393.292838)
					(end 165.77818 -393.292838)
				)
			)
		)
	)
	(zone
		(layer "B.Cu")
		(hatch none 0.5)
		(connect_pads
			(clearance 0)
		)
		(min_thickness 0.25)
		(keepout
			(tracks allowed)
			(vias allowed)
			(pads allowed)
			(copperpour allowed)
			(footprints allowed)
		)
		(placement
			(enabled no)
			(sheetname "")
		)
		(fill
			(thermal_gap 0.5)
			(thermal_bridge_width 0.5)
			(island_removal_mode 0)
		)
		(polygon
			(pts
				(xy 378.285756 -417.428426) (xy 378.285756 -416.42411) (xy 379.66269 -416.42411) (xy 379.66269 -417.428426)
			)
		)
	)
	(zone
		(layer "B.Cu")
		(hatch none 0.5)
		(connect_pads
			(clearance 0)
		)
		(min_thickness 0.25)
		(keepout
			(tracks not_allowed)
			(vias allowed)
			(pads allowed)
			(copperpour not_allowed)
			(footprints allowed)
		)
		(placement
			(enabled no)
			(sheetname "")
		)
		(fill
			(thermal_gap 0.5)
			(thermal_bridge_width 0.5)
			(island_removal_mode 0)
		)
		(polygon
			(pts
				(arc
					(start 223.76511 -290.900104)
					(mid 221.900242 -289.035236)
					(end 220.03512 -290.900104)
				)
				(arc
					(start 220.03512 -290.900104)
					(mid 221.900242 -292.765226)
					(end 223.76511 -290.900104)
				)
			)
		)
	)
	(zone
		(layer "B.Cu")
		(hatch none 0.5)
		(connect_pads
			(clearance 0)
		)
		(min_thickness 0.25)
		(keepout
			(tracks allowed)
			(vias allowed)
			(pads allowed)
			(copperpour allowed)
			(footprints allowed)
		)
		(placement
			(enabled no)
			(sheetname "")
		)
		(fill
			(thermal_gap 0.5)
			(thermal_bridge_width 0.5)
			(island_removal_mode 0)
		)
		(polygon
			(pts
				(xy 82.049366 -180.490876) (xy 82.049366 -178.331876) (xy 82.430366 -177.950876) (xy 85.224366 -177.950876)
				(xy 86.367366 -179.093876) (xy 86.367366 -182.014876) (xy 85.859366 -182.522876) (xy 84.081366 -182.522876)
			)
		)
	)
	(zone
		(layer "B.Cu")
		(hatch none 0.5)
		(connect_pads
			(clearance 0)
		)
		(min_thickness 0.25)
		(keepout
			(tracks allowed)
			(vias allowed)
			(pads allowed)
			(copperpour allowed)
			(footprints allowed)
		)
		(placement
			(enabled no)
			(sheetname "")
		)
		(fill
			(thermal_gap 0.5)
			(thermal_bridge_width 0.5)
			(island_removal_mode 0)
		)
		(polygon
			(pts
				(xy 217.61704 -403.689566) (xy 217.61704 -402.68525) (xy 218.310206 -402.68525) (xy 218.310206 -403.689566)
			)
		)
	)
	(zone
		(layer "B.Cu")
		(hatch none 0.5)
		(connect_pads
			(clearance 0)
		)
		(min_thickness 0.25)
		(keepout
			(tracks not_allowed)
			(vias allowed)
			(pads allowed)
			(copperpour not_allowed)
			(footprints allowed)
		)
		(placement
			(enabled no)
			(sheetname "")
		)
		(fill
			(thermal_gap 0.5)
			(thermal_bridge_width 0.5)
			(island_removal_mode 0)
		)
		(polygon
			(pts
				(arc
					(start 429.50003 -384.869944)
					(mid 433.500022 -388.869936)
					(end 437.500014 -384.869944)
				)
				(arc
					(start 437.500014 -384.869944)
					(mid 433.500022 -380.869952)
					(end 429.50003 -384.869944)
				)
			)
		)
	)
	(zone
		(layer "B.Cu")
		(hatch none 0.5)
		(connect_pads
			(clearance 0)
		)
		(min_thickness 0.25)
		(keepout
			(tracks not_allowed)
			(vias allowed)
			(pads allowed)
			(copperpour not_allowed)
			(footprints allowed)
		)
		(placement
			(enabled no)
			(sheetname "")
		)
		(fill
			(thermal_gap 0.5)
			(thermal_bridge_width 0.5)
			(island_removal_mode 0)
		)
		(polygon
			(pts
				(arc
					(start 396.136876 -439.0898)
					(mid 395.362684 -439.0898)
					(end 396.136876 -439.0898)
				)
			)
		)
	)
	(zone
		(layer "B.Cu")
		(hatch none 0.5)
		(connect_pads
			(clearance 0)
		)
		(min_thickness 0.25)
		(keepout
			(tracks allowed)
			(vias allowed)
			(pads allowed)
			(copperpour allowed)
			(footprints allowed)
		)
		(placement
			(enabled no)
			(sheetname "")
		)
		(fill
			(thermal_gap 0.5)
			(thermal_bridge_width 0.5)
			(island_removal_mode 0)
		)
		(polygon
			(pts
				(xy 143.362934 -199.191372) (xy 143.362934 -199.877172) (xy 142.623794 -199.877172) (xy 142.623794 -199.191372)
			)
		)
	)
	(zone
		(layer "B.Cu")
		(hatch none 0.5)
		(connect_pads
			(clearance 0)
		)
		(min_thickness 0.25)
		(keepout
			(tracks allowed)
			(vias allowed)
			(pads allowed)
			(copperpour allowed)
			(footprints allowed)
		)
		(placement
			(enabled no)
			(sheetname "")
		)
		(fill
			(thermal_gap 0.5)
			(thermal_bridge_width 0.5)
			(island_removal_mode 0)
		)
		(polygon
			(pts
				(xy 88.881458 -409.046426) (xy 88.881458 -408.04211) (xy 90.258392 -408.04211) (xy 90.258392 -409.046426)
			)
		)
	)
	(zone
		(layer "B.Cu")
		(hatch none 0.5)
		(connect_pads
			(clearance 0)
		)
		(min_thickness 0.25)
		(keepout
			(tracks allowed)
			(vias allowed)
			(pads allowed)
			(copperpour allowed)
			(footprints not_allowed)
		)
		(placement
			(enabled no)
			(sheetname "")
		)
		(fill
			(thermal_gap 0.5)
			(thermal_bridge_width 0.5)
			(island_removal_mode 0)
		)
		(polygon
			(pts
				(arc
					(start 349.775018 -431.360072)
					(mid 359.774998 -441.360052)
					(end 369.774978 -431.360072)
				)
				(arc
					(start 369.774978 -431.360072)
					(mid 359.774998 -421.360092)
					(end 349.775018 -431.360072)
				)
			)
		)
	)
	(zone
		(layer "B.Cu")
		(hatch none 0.5)
		(connect_pads
			(clearance 0)
		)
		(min_thickness 0.25)
		(keepout
			(tracks not_allowed)
			(vias allowed)
			(pads allowed)
			(copperpour not_allowed)
			(footprints allowed)
		)
		(placement
			(enabled no)
			(sheetname "")
		)
		(fill
			(thermal_gap 0.5)
			(thermal_bridge_width 0.5)
			(island_removal_mode 0)
		)
		(polygon
			(pts
				(arc
					(start 107.696 -273.276314)
					(mid 107.06608 -273.276314)
					(end 107.696 -273.276314)
				)
			)
		)
	)
	(zone
		(layer "B.Cu")
		(hatch none 0.5)
		(connect_pads
			(clearance 0)
		)
		(min_thickness 0.25)
		(keepout
			(tracks not_allowed)
			(vias allowed)
			(pads allowed)
			(copperpour not_allowed)
			(footprints allowed)
		)
		(placement
			(enabled no)
			(sheetname "")
		)
		(fill
			(thermal_gap 0.5)
			(thermal_bridge_width 0.5)
			(island_removal_mode 0)
		)
		(polygon
			(pts
				(arc
					(start 71.036942 -438.089802)
					(mid 70.26275 -438.089802)
					(end 71.036942 -438.089802)
				)
			)
		)
	)
	(zone
		(layer "B.Cu")
		(hatch none 0.5)
		(connect_pads
			(clearance 0)
		)
		(min_thickness 0.25)
		(keepout
			(tracks not_allowed)
			(vias allowed)
			(pads allowed)
			(copperpour not_allowed)
			(footprints allowed)
		)
		(placement
			(enabled no)
			(sheetname "")
		)
		(fill
			(thermal_gap 0.5)
			(thermal_bridge_width 0.5)
			(island_removal_mode 0)
		)
		(polygon
			(pts
				(arc
					(start 317.350394 -401.674838)
					(mid 316.682374 -401.674838)
					(end 317.350394 -401.674838)
				)
			)
		)
	)
	(zone
		(layer "B.Cu")
		(hatch none 0.5)
		(connect_pads
			(clearance 0)
		)
		(min_thickness 0.25)
		(keepout
			(tracks allowed)
			(vias allowed)
			(pads allowed)
			(copperpour allowed)
			(footprints allowed)
		)
		(placement
			(enabled no)
			(sheetname "")
		)
		(fill
			(thermal_gap 0.5)
			(thermal_bridge_width 0.5)
			(island_removal_mode 0)
		)
		(polygon
			(pts
				(xy 267.420852 -394.410438) (xy 267.420852 -393.406122) (xy 268.797786 -393.406122) (xy 268.797786 -394.410438)
			)
		)
	)
	(zone
		(layer "B.Cu")
		(hatch none 0.5)
		(connect_pads
			(clearance 0)
		)
		(min_thickness 0.25)
		(keepout
			(tracks not_allowed)
			(vias allowed)
			(pads allowed)
			(copperpour not_allowed)
			(footprints allowed)
		)
		(placement
			(enabled no)
			(sheetname "")
		)
		(fill
			(thermal_gap 0.5)
			(thermal_bridge_width 0.5)
			(island_removal_mode 0)
		)
		(polygon
			(pts
				(arc
					(start 349.696024 -244.484144)
					(mid 349.066104 -244.484144)
					(end 349.696024 -244.484144)
				)
			)
		)
	)
	(zone
		(layer "B.Cu")
		(hatch none 0.5)
		(connect_pads
			(clearance 0)
		)
		(min_thickness 0.25)
		(keepout
			(tracks not_allowed)
			(vias allowed)
			(pads allowed)
			(copperpour not_allowed)
			(footprints allowed)
		)
		(placement
			(enabled no)
			(sheetname "")
		)
		(fill
			(thermal_gap 0.5)
			(thermal_bridge_width 0.5)
			(island_removal_mode 0)
		)
		(polygon
			(pts
				(arc
					(start 1.999996 -22.29993)
					(mid 6.999986 -27.29992)
					(end 11.999976 -22.29993)
				)
				(arc
					(start 11.999976 -22.29993)
					(mid 6.999986 -17.29994)
					(end 1.999996 -22.29993)
				)
			)
		)
	)
	(zone
		(layer "B.Cu")
		(hatch none 0.5)
		(connect_pads
			(clearance 0)
		)
		(min_thickness 0.25)
		(keepout
			(tracks allowed)
			(vias allowed)
			(pads allowed)
			(copperpour allowed)
			(footprints allowed)
		)
		(placement
			(enabled no)
			(sheetname "")
		)
		(fill
			(thermal_gap 0.5)
			(thermal_bridge_width 0.5)
			(island_removal_mode 0)
		)
		(polygon
			(pts
				(xy 372.402862 -180.467254) (xy 372.402862 -178.308254) (xy 372.783862 -177.927254) (xy 375.577862 -177.927254)
				(xy 376.720862 -179.070254) (xy 376.720862 -181.991254) (xy 376.212862 -182.499254) (xy 374.434862 -182.499254)
			)
		)
	)
	(zone
		(layer "B.Cu")
		(hatch none 0.5)
		(connect_pads
			(clearance 0)
		)
		(min_thickness 0.25)
		(keepout
			(tracks allowed)
			(vias allowed)
			(pads allowed)
			(copperpour allowed)
			(footprints allowed)
		)
		(placement
			(enabled no)
			(sheetname "")
		)
		(fill
			(thermal_gap 0.5)
			(thermal_bridge_width 0.5)
			(island_removal_mode 0)
		)
		(polygon
			(pts
				(xy 276.585172 -394.401802) (xy 276.585172 -393.397486) (xy 277.962106 -393.397486) (xy 277.962106 -394.401802)
			)
		)
	)
	(zone
		(layer "B.Cu")
		(hatch none 0.5)
		(connect_pads
			(clearance 0)
		)
		(min_thickness 0.25)
		(keepout
			(tracks not_allowed)
			(vias allowed)
			(pads allowed)
			(copperpour not_allowed)
			(footprints allowed)
		)
		(placement
			(enabled no)
			(sheetname "")
		)
		(fill
			(thermal_gap 0.5)
			(thermal_bridge_width 0.5)
			(island_removal_mode 0)
		)
		(polygon
			(pts
				(arc
					(start 314.351924 -344.814906)
					(mid 317.451994 -347.914976)
					(end 320.552064 -344.814906)
				)
				(arc
					(start 320.552064 -344.814906)
					(mid 317.451994 -341.714836)
					(end 314.351924 -344.814906)
				)
			)
		)
	)
	(zone
		(layer "B.Cu")
		(hatch none 0.5)
		(connect_pads
			(clearance 0)
		)
		(min_thickness 0.25)
		(keepout
			(tracks not_allowed)
			(vias allowed)
			(pads allowed)
			(copperpour not_allowed)
			(footprints allowed)
		)
		(placement
			(enabled no)
			(sheetname "")
		)
		(fill
			(thermal_gap 0.5)
			(thermal_bridge_width 0.5)
			(island_removal_mode 0)
		)
		(polygon
			(pts
				(arc
					(start 322.150232 -400.811238)
					(mid 321.482212 -400.811238)
					(end 322.150232 -400.811238)
				)
			)
		)
	)
	(zone
		(layer "B.Cu")
		(hatch none 0.5)
		(connect_pads
			(clearance 0)
		)
		(min_thickness 0.25)
		(keepout
			(tracks allowed)
			(vias allowed)
			(pads allowed)
			(copperpour allowed)
			(footprints not_allowed)
		)
		(placement
			(enabled no)
			(sheetname "")
		)
		(fill
			(thermal_gap 0.5)
			(thermal_bridge_width 0.5)
			(island_removal_mode 0)
		)
		(polygon
			(pts
				(xy 407.640028 -239.862106) (xy 407.640028 -202.362054) (xy 462.639918 -202.362054) (xy 462.639918 -239.862106)
			)
		)
	)
	(zone
		(layer "B.Cu")
		(hatch none 0.5)
		(connect_pads
			(clearance 0)
		)
		(min_thickness 0.25)
		(keepout
			(tracks allowed)
			(vias allowed)
			(pads allowed)
			(copperpour allowed)
			(footprints not_allowed)
		)
		(placement
			(enabled no)
			(sheetname "")
		)
		(fill
			(thermal_gap 0.5)
			(thermal_bridge_width 0.5)
			(island_removal_mode 0)
		)
		(polygon
			(pts
				(arc
					(start 230.89997 -81.700116)
					(mid 235.89996 -86.700106)
					(end 240.89995 -81.700116)
				)
				(arc
					(start 240.89995 -81.700116)
					(mid 235.89996 -76.700126)
					(end 230.89997 -81.700116)
				)
			)
		)
	)
	(zone
		(layer "B.Cu")
		(hatch none 0.5)
		(connect_pads
			(clearance 0)
		)
		(min_thickness 0.25)
		(keepout
			(tracks not_allowed)
			(vias allowed)
			(pads allowed)
			(copperpour not_allowed)
			(footprints allowed)
		)
		(placement
			(enabled no)
			(sheetname "")
		)
		(fill
			(thermal_gap 0.5)
			(thermal_bridge_width 0.5)
			(island_removal_mode 0)
		)
		(polygon
			(pts
				(arc
					(start 396.136876 -437.889904)
					(mid 395.362684 -437.889904)
					(end 396.136876 -437.889904)
				)
			)
		)
	)
	(zone
		(layer "B.Cu")
		(hatch none 0.5)
		(connect_pads
			(clearance 0)
		)
		(min_thickness 0.25)
		(keepout
			(tracks allowed)
			(vias allowed)
			(pads allowed)
			(copperpour allowed)
			(footprints allowed)
		)
		(placement
			(enabled no)
			(sheetname "")
		)
		(fill
			(thermal_gap 0.5)
			(thermal_bridge_width 0.5)
			(island_removal_mode 0)
		)
		(polygon
			(pts
				(xy 377.97486 1.8923) (xy 377.97486 3.8735) (xy 380.11354 3.8735) (xy 380.11354 1.8923)
			)
		)
	)
	(zone
		(layer "B.Cu")
		(hatch none 0.5)
		(connect_pads
			(clearance 0)
		)
		(min_thickness 0.25)
		(keepout
			(tracks allowed)
			(vias allowed)
			(pads allowed)
			(copperpour allowed)
			(footprints not_allowed)
		)
		(placement
			(enabled no)
			(sheetname "")
		)
		(fill
			(thermal_gap 0.5)
			(thermal_bridge_width 0.5)
			(island_removal_mode 0)
		)
		(polygon
			(pts
				(arc
					(start 201.954892 -153.774902)
					(mid 193.954908 -145.774918)
					(end 185.954924 -153.774902)
				)
				(arc
					(start 185.954924 -153.774902)
					(mid 193.954908 -161.774886)
					(end 201.954892 -153.774902)
				)
			)
		)
	)
	(zone
		(layer "B.Cu")
		(hatch none 0.5)
		(connect_pads
			(clearance 0)
		)
		(min_thickness 0.25)
		(keepout
			(tracks not_allowed)
			(vias allowed)
			(pads allowed)
			(copperpour not_allowed)
			(footprints allowed)
		)
		(placement
			(enabled no)
			(sheetname "")
		)
		(fill
			(thermal_gap 0.5)
			(thermal_bridge_width 0.5)
			(island_removal_mode 0)
		)
		(polygon
			(pts
				(arc
					(start 334.036924 -437.889904)
					(mid 333.262732 -437.889904)
					(end 334.036924 -437.889904)
				)
			)
		)
	)
	(zone
		(layer "B.Cu")
		(hatch none 0.5)
		(connect_pads
			(clearance 0)
		)
		(min_thickness 0.25)
		(keepout
			(tracks allowed)
			(vias allowed)
			(pads allowed)
			(copperpour allowed)
			(footprints not_allowed)
		)
		(placement
			(enabled no)
			(sheetname "")
		)
		(fill
			(thermal_gap 0.5)
			(thermal_bridge_width 0.5)
			(island_removal_mode 0)
		)
		(polygon
			(pts
				(arc
					(start 202.996546 -354.266246)
					(mid 223.866854 -368.001655)
					(end 204.020674 -352.824034)
				)
				(arc
					(start 204.020674 -352.824034)
					(mid 198.558263 -350.029864)
					(end 202.996546 -354.266246)
				)
			)
		)
	)
	(zone
		(layer "B.Cu")
		(hatch none 0.5)
		(connect_pads
			(clearance 0)
		)
		(min_thickness 0.25)
		(keepout
			(tracks not_allowed)
			(vias allowed)
			(pads allowed)
			(copperpour not_allowed)
			(footprints allowed)
		)
		(placement
			(enabled no)
			(sheetname "")
		)
		(fill
			(thermal_gap 0.5)
			(thermal_bridge_width 0.5)
			(island_removal_mode 0)
		)
		(polygon
			(pts
				(arc
					(start 65.306194 -386.003292)
					(mid 64.676274 -386.003292)
					(end 65.306194 -386.003292)
				)
			)
		)
	)
	(zone
		(layer "B.Cu")
		(hatch none 0.5)
		(connect_pads
			(clearance 0)
		)
		(min_thickness 0.25)
		(keepout
			(tracks not_allowed)
			(vias allowed)
			(pads allowed)
			(copperpour not_allowed)
			(footprints allowed)
		)
		(placement
			(enabled no)
			(sheetname "")
		)
		(fill
			(thermal_gap 0.5)
			(thermal_bridge_width 0.5)
			(island_removal_mode 0)
		)
		(polygon
			(pts
				(arc
					(start 384.1369 -437.889904)
					(mid 383.362708 -437.889904)
					(end 384.1369 -437.889904)
				)
			)
		)
	)
	(zone
		(layer "B.Cu")
		(hatch none 0.5)
		(connect_pads
			(clearance 0)
		)
		(min_thickness 0.25)
		(keepout
			(tracks allowed)
			(vias allowed)
			(pads allowed)
			(copperpour allowed)
			(footprints allowed)
		)
		(placement
			(enabled no)
			(sheetname "")
		)
		(fill
			(thermal_gap 0.5)
			(thermal_bridge_width 0.5)
			(island_removal_mode 0)
		)
		(polygon
			(pts
				(xy 70.690994 -337.317588) (xy 70.690994 -339.476588) (xy 70.309994 -339.857588) (xy 67.515994 -339.857588)
				(xy 66.372994 -338.714588) (xy 66.372994 -335.793588) (xy 66.880994 -335.285588) (xy 68.658994 -335.285588)
			)
		)
	)
	(zone
		(layer "B.Cu")
		(hatch none 0.5)
		(connect_pads
			(clearance 0)
		)
		(min_thickness 0.25)
		(keepout
			(tracks not_allowed)
			(vias allowed)
			(pads allowed)
			(copperpour not_allowed)
			(footprints allowed)
		)
		(placement
			(enabled no)
			(sheetname "")
		)
		(fill
			(thermal_gap 0.5)
			(thermal_bridge_width 0.5)
			(island_removal_mode 0)
		)
		(polygon
			(pts
				(arc
					(start 239.450118 -192.499996)
					(mid 236.650022 -189.6999)
					(end 233.849926 -192.499996)
				)
				(arc
					(start 233.849926 -192.499996)
					(mid 236.650022 -195.300092)
					(end 239.450118 -192.499996)
				)
			)
		)
	)
	(zone
		(layer "B.Cu")
		(hatch none 0.5)
		(connect_pads
			(clearance 0)
		)
		(min_thickness 0.25)
		(keepout
			(tracks allowed)
			(vias allowed)
			(pads allowed)
			(copperpour allowed)
			(footprints allowed)
		)
		(placement
			(enabled no)
			(sheetname "")
		)
		(fill
			(thermal_gap 0.5)
			(thermal_bridge_width 0.5)
			(island_removal_mode 0)
		)
		(polygon
			(pts
				(xy 449.667122 -398.96034) (xy 449.667122 -398.68221) (xy 449.667122 -397.695166) (xy 450.334634 -397.695166)
				(xy 450.334634 -398.96034)
			)
		)
	)
	(zone
		(layer "B.Cu")
		(hatch none 0.5)
		(connect_pads
			(clearance 0)
		)
		(min_thickness 0.25)
		(keepout
			(tracks not_allowed)
			(vias allowed)
			(pads allowed)
			(copperpour not_allowed)
			(footprints allowed)
		)
		(placement
			(enabled no)
			(sheetname "")
		)
		(fill
			(thermal_gap 0.5)
			(thermal_bridge_width 0.5)
			(island_removal_mode 0)
		)
		(polygon
			(pts
				(arc
					(start 468.754968 -51.289966)
					(mid 466.8901 -49.425098)
					(end 465.024978 -51.289966)
				)
				(arc
					(start 465.024978 -51.289966)
					(mid 466.8901 -53.155088)
					(end 468.754968 -51.289966)
				)
			)
		)
	)
	(zone
		(layer "B.Cu")
		(hatch none 0.5)
		(connect_pads
			(clearance 0)
		)
		(min_thickness 0.25)
		(keepout
			(tracks allowed)
			(vias allowed)
			(pads allowed)
			(copperpour allowed)
			(footprints allowed)
		)
		(placement
			(enabled no)
			(sheetname "")
		)
		(fill
			(thermal_gap 0.5)
			(thermal_bridge_width 0.5)
			(island_removal_mode 0)
		)
		(polygon
			(pts
				(xy 301.850044 -402.562568) (xy 301.850044 -399.86839) (xy 301.850044 -394.347954) (xy 303.59731 -394.347954)
				(xy 303.59731 -393.293854) (xy 323.19214 -393.293854) (xy 323.19214 -394.347954) (xy 323.19214 -402.562568)
			)
		)
	)
	(zone
		(layer "B.Cu")
		(hatch none 0.5)
		(connect_pads
			(clearance 0)
		)
		(min_thickness 0.25)
		(keepout
			(tracks not_allowed)
			(vias allowed)
			(pads allowed)
			(copperpour not_allowed)
			(footprints allowed)
		)
		(placement
			(enabled no)
			(sheetname "")
		)
		(fill
			(thermal_gap 0.5)
			(thermal_bridge_width 0.5)
			(island_removal_mode 0)
		)
		(polygon
			(pts
				(arc
					(start 254.124968 -360.764074)
					(mid 258.12496 -364.764066)
					(end 262.124952 -360.764074)
				)
				(arc
					(start 262.124952 -360.764074)
					(mid 258.12496 -356.764082)
					(end 254.124968 -360.764074)
				)
			)
		)
	)
	(zone
		(layer "B.Cu")
		(hatch none 0.5)
		(connect_pads
			(clearance 0)
		)
		(min_thickness 0.25)
		(keepout
			(tracks not_allowed)
			(vias allowed)
			(pads allowed)
			(copperpour not_allowed)
			(footprints allowed)
		)
		(placement
			(enabled no)
			(sheetname "")
		)
		(fill
			(thermal_gap 0.5)
			(thermal_bridge_width 0.5)
			(island_removal_mode 0)
		)
		(polygon
			(pts
				(arc
					(start 55.350664 -393.292838)
					(mid 54.682644 -393.292838)
					(end 55.350664 -393.292838)
				)
			)
		)
	)
	(zone
		(layer "B.Cu")
		(hatch none 0.5)
		(connect_pads
			(clearance 0)
		)
		(min_thickness 0.25)
		(keepout
			(tracks not_allowed)
			(vias allowed)
			(pads allowed)
			(copperpour not_allowed)
			(footprints allowed)
		)
		(placement
			(enabled no)
			(sheetname "")
		)
		(fill
			(thermal_gap 0.5)
			(thermal_bridge_width 0.5)
			(island_removal_mode 0)
		)
		(polygon
			(pts
				(arc
					(start 123.369578 -246.10441)
					(mid 122.739658 -246.10441)
					(end 123.369578 -246.10441)
				)
			)
		)
	)
	(zone
		(layer "B.Cu")
		(hatch none 0.5)
		(connect_pads
			(clearance 0)
		)
		(min_thickness 0.25)
		(keepout
			(tracks not_allowed)
			(vias allowed)
			(pads allowed)
			(copperpour not_allowed)
			(footprints allowed)
		)
		(placement
			(enabled no)
			(sheetname "")
		)
		(fill
			(thermal_gap 0.5)
			(thermal_bridge_width 0.5)
			(island_removal_mode 0)
		)
		(polygon
			(pts
				(arc
					(start 207.39989 -51.999896)
					(mid 204.650086 -49.250092)
					(end 201.900028 -51.999896)
				)
				(arc
					(start 201.900028 -51.999896)
					(mid 204.650086 -54.749954)
					(end 207.39989 -51.999896)
				)
			)
		)
	)
	(zone
		(layer "B.Cu")
		(hatch none 0.5)
		(connect_pads
			(clearance 0)
		)
		(min_thickness 0.25)
		(keepout
			(tracks not_allowed)
			(vias allowed)
			(pads allowed)
			(copperpour not_allowed)
			(footprints allowed)
		)
		(placement
			(enabled no)
			(sheetname "")
		)
		(fill
			(thermal_gap 0.5)
			(thermal_bridge_width 0.5)
			(island_removal_mode 0)
		)
		(polygon
			(pts
				(arc
					(start 153.778204 -393.292838)
					(mid 153.110184 -393.292838)
					(end 153.778204 -393.292838)
				)
			)
		)
	)
	(zone
		(layer "B.Cu")
		(hatch none 0.5)
		(connect_pads
			(clearance 0)
		)
		(min_thickness 0.25)
		(keepout
			(tracks not_allowed)
			(vias allowed)
			(pads allowed)
			(copperpour not_allowed)
			(footprints allowed)
		)
		(placement
			(enabled no)
			(sheetname "")
		)
		(fill
			(thermal_gap 0.5)
			(thermal_bridge_width 0.5)
			(island_removal_mode 0)
		)
		(polygon
			(pts
				(arc
					(start 429.250094 -413.170116)
					(mid 427.000162 -410.920184)
					(end 424.749976 -413.170116)
				)
				(arc
					(start 424.749976 -413.170116)
					(mid 427.000162 -415.420302)
					(end 429.250094 -413.170116)
				)
			)
		)
	)
	(zone
		(layer "B.Cu")
		(hatch none 0.5)
		(connect_pads
			(clearance 0)
		)
		(min_thickness 0.25)
		(keepout
			(tracks not_allowed)
			(vias allowed)
			(pads allowed)
			(copperpour not_allowed)
			(footprints allowed)
		)
		(placement
			(enabled no)
			(sheetname "")
		)
		(fill
			(thermal_gap 0.5)
			(thermal_bridge_width 0.5)
			(island_removal_mode 0)
		)
		(polygon
			(pts
				(arc
					(start 110.046008 -270.846296)
					(mid 109.416088 -270.846296)
					(end 110.046008 -270.846296)
				)
			)
		)
	)
	(zone
		(layer "B.Cu")
		(hatch none 0.5)
		(connect_pads
			(clearance 0)
		)
		(min_thickness 0.25)
		(keepout
			(tracks not_allowed)
			(vias allowed)
			(pads allowed)
			(copperpour not_allowed)
			(footprints allowed)
		)
		(placement
			(enabled no)
			(sheetname "")
		)
		(fill
			(thermal_gap 0.5)
			(thermal_bridge_width 0.5)
			(island_removal_mode 0)
		)
		(polygon
			(pts
				(arc
					(start 57.70626 -385.31038)
					(mid 57.07634 -385.31038)
					(end 57.70626 -385.31038)
				)
			)
		)
	)
	(zone
		(layer "B.Cu")
		(hatch none 0.5)
		(connect_pads
			(clearance 0)
		)
		(min_thickness 0.25)
		(keepout
			(tracks not_allowed)
			(vias allowed)
			(pads allowed)
			(copperpour not_allowed)
			(footprints allowed)
		)
		(placement
			(enabled no)
			(sheetname "")
		)
		(fill
			(thermal_gap 0.5)
			(thermal_bridge_width 0.5)
			(island_removal_mode 0)
		)
		(polygon
			(pts
				(arc
					(start 414.578292 -401.674838)
					(mid 413.910272 -401.674838)
					(end 414.578292 -401.674838)
				)
			)
		)
	)
	(zone
		(layer "B.Cu")
		(hatch none 0.5)
		(connect_pads
			(clearance 0)
		)
		(min_thickness 0.25)
		(keepout
			(tracks allowed)
			(vias allowed)
			(pads allowed)
			(copperpour allowed)
			(footprints not_allowed)
		)
		(placement
			(enabled no)
			(sheetname "")
		)
		(fill
			(thermal_gap 0.5)
			(thermal_bridge_width 0.5)
			(island_removal_mode 0)
		)
		(polygon
			(pts
				(arc
					(start 132.352288 -217.880946)
					(mid 133.992502 -217.267702)
					(end 134.828026 -215.728804)
				)
				(arc
					(start 135.909304 -208.033112)
					(mid 136.74486 -206.49425)
					(end 138.385042 -205.88097)
				)
				(arc
					(start 156.127958 -205.88097)
					(mid 157.895811 -206.613239)
					(end 158.62808 -208.381092)
				)
				(xy 158.62808 -250.381008) (xy 161.727896 -253.381002) (xy 161.727896 -264.38098) (xy 158.62808 -267.380974)
				(arc
					(start 158.62808 -309.38089)
					(mid 157.8608 -311.185107)
					(end 156.027882 -311.881012)
				)
				(arc
					(start 138.284966 -311.881012)
					(mid 136.644752 -311.267768)
					(end 135.809228 -309.72887)
				)
				(arc
					(start 134.72795 -302.033178)
					(mid 133.892541 -300.49435)
					(end 132.252466 -299.881036)
				)
				(xy 111.927894 -299.881036) (xy 111.927894 -272.880074)
				(arc
					(start 123.928124 -272.880074)
					(mid 125.695798 -272.14788)
					(end 126.427992 -270.380206)
				)
				(arc
					(start 126.427992 -247.379998)
					(mid 125.695798 -245.612324)
					(end 123.928124 -244.879876)
				)
				(arc
					(start 99.927918 -244.879876)
					(mid 98.160244 -245.61207)
					(end 97.42805 -247.379744)
				)
				(arc
					(start 97.42805 -270.379952)
					(mid 98.160139 -272.14788)
					(end 99.927918 -272.880074)
				)
				(xy 111.828072 -272.880074) (xy 111.828072 -299.881036)
				(arc
					(start 91.503754 -299.881036)
					(mid 89.86354 -300.49428)
					(end 89.028016 -302.033178)
				)
				(arc
					(start 87.946738 -309.72887)
					(mid 87.111182 -311.267732)
					(end 85.471 -311.881012)
				)
				(arc
					(start 67.728084 -311.881012)
					(mid 65.960231 -311.148743)
					(end 65.227962 -309.38089)
				)
				(xy 65.227962 -267.380974) (xy 62.127892 -264.38098) (xy 62.127892 -253.381002) (xy 65.227962 -250.381008)
				(arc
					(start 65.227962 -208.381092)
					(mid 65.960231 -206.613239)
					(end 67.728084 -205.88097)
				)
				(arc
					(start 85.471 -205.88097)
					(mid 87.111214 -206.494214)
					(end 87.946738 -208.033112)
				)
				(arc
					(start 89.028016 -215.728804)
					(mid 89.863572 -217.267666)
					(end 91.503754 -217.880946)
				)
			)
		)
	)
	(zone
		(layer "B.Cu")
		(hatch none 0.5)
		(connect_pads
			(clearance 0)
		)
		(min_thickness 0.25)
		(keepout
			(tracks allowed)
			(vias allowed)
			(pads allowed)
			(copperpour allowed)
			(footprints not_allowed)
		)
		(placement
			(enabled no)
			(sheetname "")
		)
		(fill
			(thermal_gap 0.5)
			(thermal_bridge_width 0.5)
			(island_removal_mode 0)
		)
		(polygon
			(pts
				(arc
					(start 446.300098 -435.600094)
					(mid 448.80022 -438.100216)
					(end 451.300088 -435.600094)
				)
				(arc
					(start 451.300088 -435.600094)
					(mid 448.80022 -433.100226)
					(end 446.300098 -435.600094)
				)
			)
		)
	)
	(zone
		(layer "B.Cu")
		(hatch none 0.5)
		(connect_pads
			(clearance 0)
		)
		(min_thickness 0.25)
		(keepout
			(tracks not_allowed)
			(vias allowed)
			(pads allowed)
			(copperpour not_allowed)
			(footprints allowed)
		)
		(placement
			(enabled no)
			(sheetname "")
		)
		(fill
			(thermal_gap 0.5)
			(thermal_bridge_width 0.5)
			(island_removal_mode 0)
		)
		(polygon
			(pts
				(arc
					(start 419.37813 -401.674838)
					(mid 418.71011 -401.674838)
					(end 419.37813 -401.674838)
				)
			)
		)
	)
	(zone
		(layer "B.Cu")
		(hatch none 0.5)
		(connect_pads
			(clearance 0)
		)
		(min_thickness 0.25)
		(keepout
			(tracks allowed)
			(vias allowed)
			(pads allowed)
			(copperpour allowed)
			(footprints allowed)
		)
		(placement
			(enabled no)
			(sheetname "")
		)
		(fill
			(thermal_gap 0.5)
			(thermal_bridge_width 0.5)
			(island_removal_mode 0)
		)
		(polygon
			(pts
				(xy 399.728436 -417.428426) (xy 399.728436 -416.42411) (xy 401.10537 -416.42411) (xy 401.10537 -417.428426)
			)
		)
	)
	(zone
		(layer "B.Cu")
		(hatch none 0.5)
		(connect_pads
			(clearance 0)
		)
		(min_thickness 0.25)
		(keepout
			(tracks not_allowed)
			(vias allowed)
			(pads allowed)
			(copperpour not_allowed)
			(footprints allowed)
		)
		(placement
			(enabled no)
			(sheetname "")
		)
		(fill
			(thermal_gap 0.5)
			(thermal_bridge_width 0.5)
			(island_removal_mode 0)
		)
		(polygon
			(pts
				(arc
					(start 153.137108 -437.889904)
					(mid 152.362916 -437.889904)
					(end 153.137108 -437.889904)
				)
			)
		)
	)
	(zone
		(layer "B.Cu")
		(hatch none 0.5)
		(connect_pads
			(clearance 0)
		)
		(min_thickness 0.25)
		(keepout
			(tracks allowed)
			(vias allowed)
			(pads allowed)
			(copperpour allowed)
			(footprints not_allowed)
		)
		(placement
			(enabled no)
			(sheetname "")
		)
		(fill
			(thermal_gap 0.5)
			(thermal_bridge_width 0.5)
			(island_removal_mode 0)
		)
		(polygon
			(pts
				(arc
					(start 269.316962 -347.8149)
					(mid 267.452094 -345.950032)
					(end 265.586972 -347.8149)
				)
				(arc
					(start 265.586972 -347.8149)
					(mid 267.452094 -349.680022)
					(end 269.316962 -347.8149)
				)
			)
		)
	)
	(zone
		(layer "B.Cu")
		(hatch none 0.5)
		(connect_pads
			(clearance 0)
		)
		(min_thickness 0.25)
		(keepout
			(tracks allowed)
			(vias allowed)
			(pads allowed)
			(copperpour allowed)
			(footprints allowed)
		)
		(placement
			(enabled no)
			(sheetname "")
		)
		(fill
			(thermal_gap 0.5)
			(thermal_bridge_width 0.5)
			(island_removal_mode 0)
		)
		(polygon
			(pts
				(xy 99.175824 -384.911854) (xy 99.175824 -383.394966) (xy 99.168458 -383.3876) (xy 99.168458 -382.876806)
				(xy 98.622104 -382.330452) (xy 97.34169 -382.330452) (xy 97.123758 -382.548384) (xy 81.123282 -382.548384)
				(xy 80.572864 -383.098802) (xy 80.572864 -384.911854)
			)
		)
	)
	(zone
		(layer "B.Cu")
		(hatch none 0.5)
		(connect_pads
			(clearance 0)
		)
		(min_thickness 0.25)
		(keepout
			(tracks not_allowed)
			(vias allowed)
			(pads allowed)
			(copperpour not_allowed)
			(footprints allowed)
		)
		(placement
			(enabled no)
			(sheetname "")
		)
		(fill
			(thermal_gap 0.5)
			(thermal_bridge_width 0.5)
			(island_removal_mode 0)
		)
		(polygon
			(pts
				(arc
					(start 63.706248 -385.31038)
					(mid 63.076328 -385.31038)
					(end 63.706248 -385.31038)
				)
			)
		)
	)
	(zone
		(layer "B.Cu")
		(hatch none 0.5)
		(connect_pads
			(clearance 0)
		)
		(min_thickness 0.25)
		(keepout
			(tracks not_allowed)
			(vias allowed)
			(pads allowed)
			(copperpour not_allowed)
			(footprints allowed)
		)
		(placement
			(enabled no)
			(sheetname "")
		)
		(fill
			(thermal_gap 0.5)
			(thermal_bridge_width 0.5)
			(island_removal_mode 0)
		)
		(polygon
			(pts
				(arc
					(start 374.098566 -435.600094)
					(mid 371.298724 -432.800252)
					(end 368.498628 -435.600094)
				)
				(arc
					(start 368.498628 -435.600094)
					(mid 371.298724 -438.40019)
					(end 374.098566 -435.600094)
				)
			)
		)
	)
	(zone
		(layer "B.Cu")
		(hatch none 0.5)
		(connect_pads
			(clearance 0)
		)
		(min_thickness 0.25)
		(keepout
			(tracks not_allowed)
			(vias allowed)
			(pads allowed)
			(copperpour not_allowed)
			(footprints allowed)
		)
		(placement
			(enabled no)
			(sheetname "")
		)
		(fill
			(thermal_gap 0.5)
			(thermal_bridge_width 0.5)
			(island_removal_mode 0)
		)
		(polygon
			(pts
				(arc
					(start 134.136892 -438.089802)
					(mid 133.3627 -438.089802)
					(end 134.136892 -438.089802)
				)
			)
		)
	)
	(zone
		(layer "B.Cu")
		(hatch none 0.5)
		(connect_pads
			(clearance 0)
		)
		(min_thickness 0.25)
		(keepout
			(tracks allowed)
			(vias allowed)
			(pads allowed)
			(copperpour allowed)
			(footprints not_allowed)
		)
		(placement
			(enabled no)
			(sheetname "")
		)
		(fill
			(thermal_gap 0.5)
			(thermal_bridge_width 0.5)
			(island_removal_mode 0)
		)
		(polygon
			(pts
				(arc
					(start 380.292356 -217.880946)
					(mid 381.93257 -217.267702)
					(end 382.768094 -215.728804)
				)
				(arc
					(start 383.849372 -208.033112)
					(mid 384.684928 -206.49425)
					(end 386.32511 -205.88097)
				)
				(arc
					(start 404.068026 -205.88097)
					(mid 405.835879 -206.613239)
					(end 406.567894 -208.381092)
				)
				(xy 406.567894 -250.381008) (xy 409.667964 -253.381002) (xy 409.667964 -264.38098) (xy 406.567894 -267.380974)
				(arc
					(start 406.567894 -309.38089)
					(mid 405.800706 -311.185019)
					(end 403.96795 -311.881012)
				)
				(arc
					(start 386.225034 -311.881012)
					(mid 384.58482 -311.267768)
					(end 383.749296 -309.72887)
				)
				(arc
					(start 382.668018 -302.033178)
					(mid 381.832462 -300.494316)
					(end 380.19228 -299.881036)
				)
				(xy 359.867962 -299.881036) (xy 359.867962 -272.880074)
				(arc
					(start 371.867938 -272.880074)
					(mid 373.635701 -272.147895)
					(end 374.36806 -270.380206)
				)
				(arc
					(start 374.36806 -247.379998)
					(mid 373.635791 -245.612145)
					(end 371.867938 -244.879876)
				)
				(arc
					(start 347.867986 -244.879876)
					(mid 346.100312 -245.61207)
					(end 345.368118 -247.379744)
				)
				(arc
					(start 345.368118 -270.379952)
					(mid 346.100207 -272.14788)
					(end 347.867986 -272.880074)
				)
				(xy 359.767886 -272.880074) (xy 359.767886 -299.881036)
				(arc
					(start 339.443568 -299.881036)
					(mid 337.80344 -300.494288)
					(end 336.968084 -302.033178)
				)
				(arc
					(start 335.886806 -309.72887)
					(mid 335.05125 -311.267732)
					(end 333.411068 -311.881012)
				)
				(arc
					(start 315.667898 -311.881012)
					(mid 313.900299 -311.148638)
					(end 313.16803 -309.38089)
				)
				(xy 313.16803 -267.380974) (xy 310.06796 -264.38098) (xy 310.06796 -253.381002) (xy 313.16803 -250.381008)
				(arc
					(start 313.16803 -208.381092)
					(mid 313.900209 -206.613329)
					(end 315.667898 -205.88097)
				)
				(arc
					(start 333.411068 -205.88097)
					(mid 335.051282 -206.494214)
					(end 335.886806 -208.033112)
				)
				(arc
					(start 336.968084 -215.728804)
					(mid 337.803493 -217.267632)
					(end 339.443568 -217.880946)
				)
			)
		)
	)
	(zone
		(layer "B.Cu")
		(hatch none 0.5)
		(connect_pads
			(clearance 0)
		)
		(min_thickness 0.25)
		(keepout
			(tracks allowed)
			(vias allowed)
			(pads allowed)
			(copperpour allowed)
			(footprints allowed)
		)
		(placement
			(enabled no)
			(sheetname "")
		)
		(fill
			(thermal_gap 0.5)
			(thermal_bridge_width 0.5)
			(island_removal_mode 0)
		)
		(polygon
			(pts
				(xy 73.565258 -409.046426) (xy 73.565258 -408.04211) (xy 74.942192 -408.04211) (xy 74.942192 -409.046426)
			)
		)
	)
	(zone
		(layer "B.Cu")
		(hatch none 0.5)
		(connect_pads
			(clearance 0)
		)
		(min_thickness 0.25)
		(keepout
			(tracks allowed)
			(vias allowed)
			(pads allowed)
			(copperpour allowed)
			(footprints allowed)
		)
		(placement
			(enabled no)
			(sheetname "")
		)
		(fill
			(thermal_gap 0.5)
			(thermal_bridge_width 0.5)
			(island_removal_mode 0)
		)
		(polygon
			(pts
				(xy 11.2776 -109.347) (xy 11.2776 -108.5596) (xy 12.8778 -108.5596) (xy 12.8778 -109.347)
			)
		)
	)
	(zone
		(layer "B.Cu")
		(hatch none 0.5)
		(connect_pads
			(clearance 0)
		)
		(min_thickness 0.25)
		(keepout
			(tracks allowed)
			(vias allowed)
			(pads allowed)
			(copperpour allowed)
			(footprints not_allowed)
		)
		(placement
			(enabled no)
			(sheetname "")
		)
		(fill
			(thermal_gap 0.5)
			(thermal_bridge_width 0.5)
			(island_removal_mode 0)
		)
		(polygon
			(pts
				(arc
					(start 5.340096 -347.700092)
					(mid 10.340086 -352.700082)
					(end 15.340076 -347.700092)
				)
				(arc
					(start 15.340076 -347.700092)
					(mid 10.340086 -342.700102)
					(end 5.340096 -347.700092)
				)
			)
		)
	)
	(zone
		(layer "B.Cu")
		(hatch none 0.5)
		(connect_pads
			(clearance 0)
		)
		(min_thickness 0.25)
		(keepout
			(tracks allowed)
			(vias allowed)
			(pads allowed)
			(copperpour allowed)
			(footprints not_allowed)
		)
		(placement
			(enabled no)
			(sheetname "")
		)
		(fill
			(thermal_gap 0.5)
			(thermal_bridge_width 0.5)
			(island_removal_mode 0)
		)
		(polygon
			(pts
				(arc
					(start 205.674976 -360.764074)
					(mid 213.67496 -368.764058)
					(end 221.674944 -360.764074)
				)
				(arc
					(start 221.674944 -360.764074)
					(mid 213.67496 -352.76409)
					(end 205.674976 -360.764074)
				)
			)
		)
	)
	(zone
		(layer "B.Cu")
		(hatch none 0.5)
		(connect_pads
			(clearance 0)
		)
		(min_thickness 0.25)
		(keepout
			(tracks allowed)
			(vias allowed)
			(pads allowed)
			(copperpour allowed)
			(footprints allowed)
		)
		(placement
			(enabled no)
			(sheetname "")
		)
		(fill
			(thermal_gap 0.5)
			(thermal_bridge_width 0.5)
			(island_removal_mode 0)
		)
		(polygon
			(pts
				(xy 405.854916 -417.428426) (xy 405.854916 -416.42411) (xy 407.23185 -416.42411) (xy 407.23185 -417.428426)
			)
		)
	)
	(zone
		(layer "B.Cu")
		(hatch none 0.5)
		(connect_pads
			(clearance 0)
		)
		(min_thickness 0.25)
		(keepout
			(tracks not_allowed)
			(vias allowed)
			(pads allowed)
			(copperpour not_allowed)
			(footprints allowed)
		)
		(placement
			(enabled no)
			(sheetname "")
		)
		(fill
			(thermal_gap 0.5)
			(thermal_bridge_width 0.5)
			(island_removal_mode 0)
		)
		(polygon
			(pts
				(arc
					(start 163.378134 -393.292838)
					(mid 162.710114 -393.292838)
					(end 163.378134 -393.292838)
				)
			)
		)
	)
	(zone
		(layer "B.Cu")
		(hatch none 0.5)
		(connect_pads
			(clearance 0)
		)
		(min_thickness 0.25)
		(keepout
			(tracks allowed)
			(vias allowed)
			(pads allowed)
			(copperpour allowed)
			(footprints not_allowed)
		)
		(placement
			(enabled no)
			(sheetname "")
		)
		(fill
			(thermal_gap 0.5)
			(thermal_bridge_width 0.5)
			(island_removal_mode 0)
		)
		(polygon
			(pts
				(arc
					(start 453.799956 -435.600094)
					(mid 458.799946 -440.600084)
					(end 463.799936 -435.600094)
				)
				(arc
					(start 463.799936 -435.600094)
					(mid 458.799946 -430.600104)
					(end 453.799956 -435.600094)
				)
			)
		)
	)
	(zone
		(layer "B.Cu")
		(hatch none 0.5)
		(connect_pads
			(clearance 0)
		)
		(min_thickness 0.25)
		(keepout
			(tracks not_allowed)
			(vias allowed)
			(pads allowed)
			(copperpour not_allowed)
			(footprints allowed)
		)
		(placement
			(enabled no)
			(sheetname "")
		)
		(fill
			(thermal_gap 0.5)
			(thermal_bridge_width 0.5)
			(island_removal_mode 0)
		)
		(polygon
			(pts
				(arc
					(start 332.036928 -436.889906)
					(mid 331.262736 -436.889906)
					(end 332.036928 -436.889906)
				)
			)
		)
	)
	(zone
		(layer "B.Cu")
		(hatch none 0.5)
		(connect_pads
			(clearance 0)
		)
		(min_thickness 0.25)
		(keepout
			(tracks not_allowed)
			(vias allowed)
			(pads allowed)
			(copperpour not_allowed)
			(footprints allowed)
		)
		(placement
			(enabled no)
			(sheetname "")
		)
		(fill
			(thermal_gap 0.5)
			(thermal_bridge_width 0.5)
			(island_removal_mode 0)
		)
		(polygon
			(pts
				(arc
					(start 155.137104 -436.889906)
					(mid 154.362912 -436.889906)
					(end 155.137104 -436.889906)
				)
			)
		)
	)
	(zone
		(layer "B.Cu")
		(hatch none 0.5)
		(connect_pads
			(clearance 0)
		)
		(min_thickness 0.25)
		(keepout
			(tracks allowed)
			(vias allowed)
			(pads allowed)
			(copperpour allowed)
			(footprints not_allowed)
		)
		(placement
			(enabled no)
			(sheetname "")
		)
		(fill
			(thermal_gap 0.5)
			(thermal_bridge_width 0.5)
			(island_removal_mode 0)
		)
		(polygon
			(pts
				(arc
					(start 135.986012 -146.84502)
					(mid 132.886196 -143.745204)
					(end 129.786126 -146.84502)
				)
				(arc
					(start 129.786126 -146.84502)
					(mid 132.886196 -149.94509)
					(end 135.986012 -146.84502)
				)
			)
		)
	)
	(zone
		(layer "B.Cu")
		(hatch none 0.5)
		(connect_pads
			(clearance 0)
		)
		(min_thickness 0.25)
		(keepout
			(tracks not_allowed)
			(vias allowed)
			(pads allowed)
			(copperpour not_allowed)
			(footprints allowed)
		)
		(placement
			(enabled no)
			(sheetname "")
		)
		(fill
			(thermal_gap 0.5)
			(thermal_bridge_width 0.5)
			(island_removal_mode 0)
		)
		(polygon
			(pts
				(arc
					(start 338.036916 -439.0898)
					(mid 337.262724 -439.0898)
					(end 338.036916 -439.0898)
				)
			)
		)
	)
	(zone
		(layer "B.Cu")
		(hatch none 0.5)
		(connect_pads
			(clearance 0)
		)
		(min_thickness 0.25)
		(keepout
			(tracks not_allowed)
			(vias allowed)
			(pads allowed)
			(copperpour not_allowed)
			(footprints allowed)
		)
		(placement
			(enabled no)
			(sheetname "")
		)
		(fill
			(thermal_gap 0.5)
			(thermal_bridge_width 0.5)
			(island_removal_mode 0)
		)
		(polygon
			(pts
				(arc
					(start 159.778446 -393.292838)
					(mid 159.110426 -393.292838)
					(end 159.778446 -393.292838)
				)
			)
		)
	)
	(zone
		(layer "B.Cu")
		(hatch none 0.5)
		(connect_pads
			(clearance 0)
		)
		(min_thickness 0.25)
		(keepout
			(tracks not_allowed)
			(vias allowed)
			(pads allowed)
			(copperpour not_allowed)
			(footprints allowed)
		)
		(placement
			(enabled no)
			(sheetname "")
		)
		(fill
			(thermal_gap 0.5)
			(thermal_bridge_width 0.5)
			(island_removal_mode 0)
		)
		(polygon
			(pts
				(arc
					(start 317.305944 -393.69238)
					(mid 316.676024 -393.69238)
					(end 317.305944 -393.69238)
				)
			)
		)
	)
	(zone
		(layer "B.Cu")
		(hatch none 0.5)
		(connect_pads
			(clearance 0)
		)
		(min_thickness 0.25)
		(keepout
			(tracks allowed)
			(vias allowed)
			(pads allowed)
			(copperpour allowed)
			(footprints not_allowed)
		)
		(placement
			(enabled no)
			(sheetname "")
		)
		(fill
			(thermal_gap 0.5)
			(thermal_bridge_width 0.5)
			(island_removal_mode 0)
		)
		(polygon
			(pts
				(arc
					(start 114.580924 -340.315042)
					(mid 112.716056 -338.450174)
					(end 110.850934 -340.315042)
				)
				(arc
					(start 110.850934 -340.315042)
					(mid 112.716056 -342.180164)
					(end 114.580924 -340.315042)
				)
			)
		)
	)
	(zone
		(layer "B.Cu")
		(hatch none 0.5)
		(connect_pads
			(clearance 0)
		)
		(min_thickness 0.25)
		(keepout
			(tracks not_allowed)
			(vias allowed)
			(pads allowed)
			(copperpour not_allowed)
			(footprints allowed)
		)
		(placement
			(enabled no)
			(sheetname "")
		)
		(fill
			(thermal_gap 0.5)
			(thermal_bridge_width 0.5)
			(island_removal_mode 0)
		)
		(polygon
			(pts
				(arc
					(start 401.13712 -439.0898)
					(mid 400.362928 -439.0898)
					(end 401.13712 -439.0898)
				)
			)
		)
	)
	(zone
		(layer "B.Cu")
		(hatch none 0.5)
		(connect_pads
			(clearance 0)
		)
		(min_thickness 0.25)
		(keepout
			(tracks allowed)
			(vias allowed)
			(pads allowed)
			(copperpour allowed)
			(footprints not_allowed)
		)
		(placement
			(enabled no)
			(sheetname "")
		)
		(fill
			(thermal_gap 0.5)
			(thermal_bridge_width 0.5)
			(island_removal_mode 0)
		)
		(polygon
			(pts
				(arc
					(start 42.330624 -356.307898)
					(mid 43.790589 -355.33238)
					(end 45.512736 -354.989892)
				)
				(arc
					(start 170.25747 -354.989892)
					(mid 171.979493 -355.332424)
					(end 173.439328 -356.307898)
				)
				(arc
					(start 184.182004 -367.050574)
					(mid 185.157522 -368.510539)
					(end 185.50001 -370.232686)
				)
				(arc
					(start 185.50001 -389.770366)
					(mid 185.434024 -390.538431)
					(end 185.237882 -391.283952)
				)
				(arc
					(start 178.623722 -409.8036)
					(mid 176.977968 -411.968312)
					(end 174.385732 -412.789878)
				)
				(arc
					(start 170.25747 -412.789878)
					(mid 168.535349 -412.447327)
					(end 167.075358 -411.471872)
				)
				(arc
					(start 163.582858 -407.979372)
					(mid 163.096203 -407.654199)
					(end 162.522154 -407.539952)
				)
				(arc
					(start 50.047906 -407.539952)
					(mid 49.473833 -407.654142)
					(end 48.987202 -407.979372)
				)
				(arc
					(start 45.494702 -411.471872)
					(mid 44.034737 -412.44739)
					(end 42.31259 -412.789878)
				)
				(arc
					(start 37.176202 -412.789878)
					(mid 34.590512 -411.972809)
					(end 32.9438 -409.818332)
				)
				(arc
					(start 29.68752 -400.801078)
					(mid 29.487411 -400.048407)
					(end 29.420058 -399.272506)
				)
				(arc
					(start 29.420058 -386.732526)
					(mid 29.305804 -386.158604)
					(end 28.980638 -385.672076)
				)
				(arc
					(start 28.388056 -385.07924)
					(mid 27.412616 -383.619391)
					(end 27.07005 -381.897382)
				)
				(arc
					(start 27.07005 -373.432578)
					(mid 27.412582 -371.710555)
					(end 28.388056 -370.25072)
				)
			)
		)
	)
	(zone
		(layer "B.Cu")
		(hatch none 0.5)
		(connect_pads
			(clearance 0)
		)
		(min_thickness 0.25)
		(keepout
			(tracks not_allowed)
			(vias allowed)
			(pads allowed)
			(copperpour not_allowed)
			(footprints allowed)
		)
		(placement
			(enabled no)
			(sheetname "")
		)
		(fill
			(thermal_gap 0.5)
			(thermal_bridge_width 0.5)
			(island_removal_mode 0)
		)
		(polygon
			(pts
				(arc
					(start 346.876116 -247.724168)
					(mid 346.246196 -247.724168)
					(end 346.876116 -247.724168)
				)
			)
		)
	)
	(zone
		(layer "B.Cu")
		(hatch none 0.5)
		(connect_pads
			(clearance 0)
		)
		(min_thickness 0.25)
		(keepout
			(tracks allowed)
			(vias allowed)
			(pads allowed)
			(copperpour allowed)
			(footprints not_allowed)
		)
		(placement
			(enabled no)
			(sheetname "")
		)
		(fill
			(thermal_gap 0.5)
			(thermal_bridge_width 0.5)
			(island_removal_mode 0)
		)
		(polygon
			(pts
				(arc
					(start 320.552064 -344.814906)
					(mid 317.451994 -341.714836)
					(end 314.351924 -344.814906)
				)
				(arc
					(start 314.351924 -344.814906)
					(mid 317.451994 -347.914976)
					(end 320.552064 -344.814906)
				)
			)
		)
	)
	(zone
		(layer "B.Cu")
		(hatch none 0.5)
		(connect_pads
			(clearance 0)
		)
		(min_thickness 0.25)
		(keepout
			(tracks not_allowed)
			(vias allowed)
			(pads allowed)
			(copperpour not_allowed)
			(footprints allowed)
		)
		(placement
			(enabled no)
			(sheetname "")
		)
		(fill
			(thermal_gap 0.5)
			(thermal_bridge_width 0.5)
			(island_removal_mode 0)
		)
		(polygon
			(pts
				(arc
					(start 408.578304 -401.674838)
					(mid 407.910284 -401.674838)
					(end 408.578304 -401.674838)
				)
			)
		)
	)
	(zone
		(layer "B.Cu")
		(hatch none 0.5)
		(connect_pads
			(clearance 0)
		)
		(min_thickness 0.25)
		(keepout
			(tracks allowed)
			(vias allowed)
			(pads allowed)
			(copperpour allowed)
			(footprints not_allowed)
		)
		(placement
			(enabled no)
			(sheetname "")
		)
		(fill
			(thermal_gap 0.5)
			(thermal_bridge_width 0.5)
			(island_removal_mode 0)
		)
		(polygon
			(pts
				(arc
					(start 393.269978 -212.989922)
					(mid 390.470136 -210.19008)
					(end 387.67004 -212.989922)
				)
				(arc
					(start 387.67004 -212.989922)
					(mid 390.470136 -215.790018)
					(end 393.269978 -212.989922)
				)
			)
		)
	)
	(zone
		(layer "B.Cu")
		(hatch none 0.5)
		(connect_pads
			(clearance 0)
		)
		(min_thickness 0.25)
		(keepout
			(tracks not_allowed)
			(vias allowed)
			(pads allowed)
			(copperpour not_allowed)
			(footprints allowed)
		)
		(placement
			(enabled no)
			(sheetname "")
		)
		(fill
			(thermal_gap 0.5)
			(thermal_bridge_width 0.5)
			(island_removal_mode 0)
		)
		(polygon
			(pts
				(arc
					(start 321.036696 -437.889904)
					(mid 320.262504 -437.889904)
					(end 321.036696 -437.889904)
				)
			)
		)
	)
	(zone
		(layer "B.Cu")
		(hatch none 0.5)
		(connect_pads
			(clearance 0)
		)
		(min_thickness 0.25)
		(keepout
			(tracks not_allowed)
			(vias allowed)
			(pads allowed)
			(copperpour not_allowed)
			(footprints allowed)
		)
		(placement
			(enabled no)
			(sheetname "")
		)
		(fill
			(thermal_gap 0.5)
			(thermal_bridge_width 0.5)
			(island_removal_mode 0)
		)
		(polygon
			(pts
				(arc
					(start 106.755946 -271.656302)
					(mid 106.126026 -271.656302)
					(end 106.755946 -271.656302)
				)
			)
		)
	)
	(zone
		(layer "B.Cu")
		(hatch none 0.5)
		(connect_pads
			(clearance 0)
		)
		(min_thickness 0.25)
		(keepout
			(tracks not_allowed)
			(vias allowed)
			(pads allowed)
			(copperpour not_allowed)
			(footprints allowed)
		)
		(placement
			(enabled no)
			(sheetname "")
		)
		(fill
			(thermal_gap 0.5)
			(thermal_bridge_width 0.5)
			(island_removal_mode 0)
		)
		(polygon
			(pts
				(arc
					(start 370.369846 -225.044254)
					(mid 369.739926 -225.044254)
					(end 370.369846 -225.044254)
				)
			)
		)
	)
	(zone
		(layer "B.Cu")
		(hatch none 0.5)
		(connect_pads
			(clearance 0)
		)
		(min_thickness 0.25)
		(keepout
			(tracks not_allowed)
			(vias allowed)
			(pads allowed)
			(copperpour not_allowed)
			(footprints allowed)
		)
		(placement
			(enabled no)
			(sheetname "")
		)
		(fill
			(thermal_gap 0.5)
			(thermal_bridge_width 0.5)
			(island_removal_mode 0)
		)
		(polygon
			(pts
				(arc
					(start 139.029948 -212.989922)
					(mid 142.530068 -216.490042)
					(end 146.029934 -212.989922)
				)
				(arc
					(start 146.029934 -212.989922)
					(mid 142.530068 -209.490056)
					(end 139.029948 -212.989922)
				)
			)
		)
	)
	(zone
		(layer "B.Cu")
		(hatch none 0.5)
		(connect_pads
			(clearance 0)
		)
		(min_thickness 0.25)
		(keepout
			(tracks allowed)
			(vias allowed)
			(pads allowed)
			(copperpour allowed)
			(footprints not_allowed)
		)
		(placement
			(enabled no)
			(sheetname "")
		)
		(fill
			(thermal_gap 0.5)
			(thermal_bridge_width 0.5)
			(island_removal_mode 0)
		)
		(polygon
			(pts
				(arc
					(start 155.399994 -160.50006)
					(mid 167.900096 -173.000162)
					(end 180.399944 -160.50006)
				)
				(arc
					(start 180.399944 -160.50006)
					(mid 167.900096 -148.000212)
					(end 155.399994 -160.50006)
				)
			)
		)
	)
	(zone
		(layer "B.Cu")
		(hatch none 0.5)
		(connect_pads
			(clearance 0)
		)
		(min_thickness 0.25)
		(keepout
			(tracks not_allowed)
			(vias allowed)
			(pads allowed)
			(copperpour not_allowed)
			(footprints allowed)
		)
		(placement
			(enabled no)
			(sheetname "")
		)
		(fill
			(thermal_gap 0.5)
			(thermal_bridge_width 0.5)
			(island_removal_mode 0)
		)
		(polygon
			(pts
				(arc
					(start 404.770082 -258.890008)
					(mid 401.969986 -256.089912)
					(end 399.16989 -258.890008)
				)
				(arc
					(start 399.16989 -258.890008)
					(mid 401.969986 -261.690104)
					(end 404.770082 -258.890008)
				)
			)
		)
	)
	(zone
		(layer "B.Cu")
		(hatch none 0.5)
		(connect_pads
			(clearance 0)
		)
		(min_thickness 0.25)
		(keepout
			(tracks not_allowed)
			(vias allowed)
			(pads allowed)
			(copperpour not_allowed)
			(footprints allowed)
		)
		(placement
			(enabled no)
			(sheetname "")
		)
		(fill
			(thermal_gap 0.5)
			(thermal_bridge_width 0.5)
			(island_removal_mode 0)
		)
		(polygon
			(pts
				(arc
					(start 296.349928 -435.600094)
					(mid 293.550086 -432.800252)
					(end 290.74999 -435.600094)
				)
				(arc
					(start 290.74999 -435.600094)
					(mid 293.550086 -438.40019)
					(end 296.349928 -435.600094)
				)
			)
		)
	)
	(zone
		(layer "B.Cu")
		(hatch none 0.5)
		(connect_pads
			(clearance 0)
		)
		(min_thickness 0.25)
		(keepout
			(tracks allowed)
			(vias allowed)
			(pads allowed)
			(copperpour allowed)
			(footprints not_allowed)
		)
		(placement
			(enabled no)
			(sheetname "")
		)
		(fill
			(thermal_gap 0.5)
			(thermal_bridge_width 0.5)
			(island_removal_mode 0)
		)
		(polygon
			(pts
				(arc
					(start 392.622024 -173.315122)
					(mid 389.521954 -170.215052)
					(end 386.421884 -173.315122)
				)
				(arc
					(start 386.421884 -173.315122)
					(mid 389.521954 -176.415192)
					(end 392.622024 -173.315122)
				)
			)
		)
	)
	(zone
		(layer "B.Cu")
		(hatch none 0.5)
		(connect_pads
			(clearance 0)
		)
		(min_thickness 0.25)
		(keepout
			(tracks allowed)
			(vias allowed)
			(pads allowed)
			(copperpour allowed)
			(footprints not_allowed)
		)
		(placement
			(enabled no)
			(sheetname "")
		)
		(fill
			(thermal_gap 0.5)
			(thermal_bridge_width 0.5)
			(island_removal_mode 0)
		)
		(polygon
			(pts
				(arc
					(start 134.751064 -146.84502)
					(mid 132.886196 -144.980152)
					(end 131.021074 -146.84502)
				)
				(arc
					(start 131.021074 -146.84502)
					(mid 132.886196 -148.710142)
					(end 134.751064 -146.84502)
				)
			)
		)
	)
	(zone
		(layer "B.Cu")
		(hatch none 0.5)
		(connect_pads
			(clearance 0)
		)
		(min_thickness 0.25)
		(keepout
			(tracks not_allowed)
			(vias allowed)
			(pads allowed)
			(copperpour not_allowed)
			(footprints allowed)
		)
		(placement
			(enabled no)
			(sheetname "")
		)
		(fill
			(thermal_gap 0.5)
			(thermal_bridge_width 0.5)
			(island_removal_mode 0)
		)
		(polygon
			(pts
				(arc
					(start 80.037178 -436.889906)
					(mid 79.262986 -436.889906)
					(end 80.037178 -436.889906)
				)
			)
		)
	)
	(zone
		(layer "B.Cu")
		(hatch none 0.5)
		(connect_pads
			(clearance 0)
		)
		(min_thickness 0.25)
		(keepout
			(tracks allowed)
			(vias allowed)
			(pads allowed)
			(copperpour allowed)
			(footprints not_allowed)
		)
		(placement
			(enabled no)
			(sheetname "")
		)
		(fill
			(thermal_gap 0.5)
			(thermal_bridge_width 0.5)
			(island_removal_mode 0)
		)
		(polygon
			(pts
				(arc
					(start 344.952066 -147.904962)
					(mid 348.052136 -151.005032)
					(end 351.151952 -147.904962)
				)
				(arc
					(start 351.151952 -147.904962)
					(mid 348.052136 -144.805146)
					(end 344.952066 -147.904962)
				)
			)
		)
	)
	(zone
		(layer "B.Cu")
		(hatch none 0.5)
		(connect_pads
			(clearance 0)
		)
		(min_thickness 0.25)
		(keepout
			(tracks not_allowed)
			(vias allowed)
			(pads allowed)
			(copperpour not_allowed)
			(footprints allowed)
		)
		(placement
			(enabled no)
			(sheetname "")
		)
		(fill
			(thermal_gap 0.5)
			(thermal_bridge_width 0.5)
			(island_removal_mode 0)
		)
		(polygon
			(pts
				(arc
					(start 115.379754 -243.674392)
					(mid 114.749834 -243.674392)
					(end 115.379754 -243.674392)
				)
			)
		)
	)
	(zone
		(layer "B.Cu")
		(hatch none 0.5)
		(connect_pads
			(clearance 0)
		)
		(min_thickness 0.25)
		(keepout
			(tracks not_allowed)
			(vias allowed)
			(pads allowed)
			(copperpour not_allowed)
			(footprints allowed)
		)
		(placement
			(enabled no)
			(sheetname "")
		)
		(fill
			(thermal_gap 0.5)
			(thermal_bridge_width 0.5)
			(island_removal_mode 0)
		)
		(polygon
			(pts
				(arc
					(start 126.136908 -436.889906)
					(mid 125.362716 -436.889906)
					(end 126.136908 -436.889906)
				)
			)
		)
	)
	(zone
		(layer "B.Cu")
		(hatch none 0.5)
		(connect_pads
			(clearance 0)
		)
		(min_thickness 0.25)
		(keepout
			(tracks allowed)
			(vias allowed)
			(pads allowed)
			(copperpour allowed)
			(footprints allowed)
		)
		(placement
			(enabled no)
			(sheetname "")
		)
		(fill
			(thermal_gap 0.5)
			(thermal_bridge_width 0.5)
			(island_removal_mode 0)
		)
		(polygon
			(pts
				(xy 180.71846 1.84658) (xy 180.71846 3.85064) (xy 183.0324 3.85064) (xy 183.0324 1.84658)
			)
		)
	)
	(zone
		(layer "B.Cu")
		(hatch none 0.5)
		(connect_pads
			(clearance 0)
		)
		(min_thickness 0.25)
		(keepout
			(tracks allowed)
			(vias allowed)
			(pads allowed)
			(copperpour allowed)
			(footprints allowed)
		)
		(placement
			(enabled no)
			(sheetname "")
		)
		(fill
			(thermal_gap 0.5)
			(thermal_bridge_width 0.5)
			(island_removal_mode 0)
		)
		(polygon
			(pts
				(xy 314.885832 -360.729784) (xy 314.607702 -360.729784) (xy 313.620658 -360.729784) (xy 313.620658 -360.062272)
				(xy 314.885832 -360.062272)
			)
		)
	)
	(zone
		(layer "B.Cu")
		(hatch none 0.5)
		(connect_pads
			(clearance 0)
		)
		(min_thickness 0.25)
		(keepout
			(tracks allowed)
			(vias allowed)
			(pads allowed)
			(copperpour allowed)
			(footprints allowed)
		)
		(placement
			(enabled no)
			(sheetname "")
		)
		(fill
			(thermal_gap 0.5)
			(thermal_bridge_width 0.5)
			(island_removal_mode 0)
		)
		(polygon
			(pts
				(xy 90.558366 -180.236876) (xy 90.558366 -178.077876) (xy 90.939366 -177.696876) (xy 93.733366 -177.696876)
				(xy 94.876366 -178.839876) (xy 94.876366 -181.760876) (xy 94.368366 -182.268876) (xy 92.590366 -182.268876)
			)
		)
	)
	(zone
		(layer "B.Cu")
		(hatch none 0.5)
		(connect_pads
			(clearance 0)
		)
		(min_thickness 0.25)
		(keepout
			(tracks allowed)
			(vias allowed)
			(pads allowed)
			(copperpour allowed)
			(footprints allowed)
		)
		(placement
			(enabled no)
			(sheetname "")
		)
		(fill
			(thermal_gap 0.5)
			(thermal_bridge_width 0.5)
			(island_removal_mode 0)
		)
		(polygon
			(pts
				(xy 162.10788 -409.046426) (xy 162.10788 -408.04211) (xy 163.484814 -408.04211) (xy 163.484814 -409.046426)
			)
		)
	)
	(zone
		(layer "B.Cu")
		(hatch none 0.5)
		(connect_pads
			(clearance 0)
		)
		(min_thickness 0.25)
		(keepout
			(tracks not_allowed)
			(vias allowed)
			(pads allowed)
			(copperpour not_allowed)
			(footprints allowed)
		)
		(placement
			(enabled no)
			(sheetname "")
		)
		(fill
			(thermal_gap 0.5)
			(thermal_bridge_width 0.5)
			(island_removal_mode 0)
		)
		(polygon
			(pts
				(arc
					(start 340.036912 -438.089802)
					(mid 339.26272 -438.089802)
					(end 340.036912 -438.089802)
				)
			)
		)
	)
	(zone
		(layer "B.Cu")
		(hatch none 0.5)
		(connect_pads
			(clearance 0)
		)
		(min_thickness 0.25)
		(keepout
			(tracks allowed)
			(vias allowed)
			(pads allowed)
			(copperpour allowed)
			(footprints allowed)
		)
		(placement
			(enabled no)
			(sheetname "")
		)
		(fill
			(thermal_gap 0.5)
			(thermal_bridge_width 0.5)
			(island_removal_mode 0)
		)
		(polygon
			(pts
				(xy 145.800826 -317.48476) (xy 145.800826 -318.171068) (xy 145.800826 -318.500506) (xy 144.26184 -318.500506)
				(xy 144.26184 -317.924434) (xy 143.993108 -317.655702) (xy 143.993108 -316.735968) (xy 144.51076 -316.218316)
				(xy 145.584164 -316.218316) (xy 145.800826 -316.434978)
			)
		)
	)
	(zone
		(layer "B.Cu")
		(hatch none 0.5)
		(connect_pads
			(clearance 0)
		)
		(min_thickness 0.25)
		(keepout
			(tracks not_allowed)
			(vias allowed)
			(pads allowed)
			(copperpour not_allowed)
			(footprints allowed)
		)
		(placement
			(enabled no)
			(sheetname "")
		)
		(fill
			(thermal_gap 0.5)
			(thermal_bridge_width 0.5)
			(island_removal_mode 0)
		)
		(polygon
			(pts
				(arc
					(start 404.978108 -400.811238)
					(mid 404.310088 -400.811238)
					(end 404.978108 -400.811238)
				)
			)
		)
	)
	(zone
		(layer "B.Cu")
		(hatch none 0.5)
		(connect_pads
			(clearance 0)
		)
		(min_thickness 0.25)
		(keepout
			(tracks allowed)
			(vias allowed)
			(pads allowed)
			(copperpour allowed)
			(footprints allowed)
		)
		(placement
			(enabled no)
			(sheetname "")
		)
		(fill
			(thermal_gap 0.5)
			(thermal_bridge_width 0.5)
			(island_removal_mode 0)
		)
		(polygon
			(pts
				(xy 119.22252 -409.046426) (xy 119.22252 -408.04211) (xy 120.599454 -408.04211) (xy 120.599454 -409.046426)
			)
		)
	)
	(zone
		(layer "B.Cu")
		(hatch none 0.5)
		(connect_pads
			(clearance 0)
		)
		(min_thickness 0.25)
		(keepout
			(tracks not_allowed)
			(vias allowed)
			(pads allowed)
			(copperpour not_allowed)
			(footprints allowed)
		)
		(placement
			(enabled no)
			(sheetname "")
		)
		(fill
			(thermal_gap 0.5)
			(thermal_bridge_width 0.5)
			(island_removal_mode 0)
		)
		(polygon
			(pts
				(arc
					(start 312.550302 -401.674838)
					(mid 311.882282 -401.674838)
					(end 312.550302 -401.674838)
				)
			)
		)
	)
	(zone
		(layer "B.Cu")
		(hatch none 0.5)
		(connect_pads
			(clearance 0)
		)
		(min_thickness 0.25)
		(keepout
			(tracks not_allowed)
			(vias allowed)
			(pads allowed)
			(copperpour not_allowed)
			(footprints allowed)
		)
		(placement
			(enabled no)
			(sheetname "")
		)
		(fill
			(thermal_gap 0.5)
			(thermal_bridge_width 0.5)
			(island_removal_mode 0)
		)
		(polygon
			(pts
				(arc
					(start 115.379754 -245.294404)
					(mid 114.749834 -245.294404)
					(end 115.379754 -245.294404)
				)
			)
		)
	)
	(zone
		(layer "B.Cu")
		(hatch none 0.5)
		(connect_pads
			(clearance 0)
		)
		(min_thickness 0.25)
		(keepout
			(tracks allowed)
			(vias allowed)
			(pads allowed)
			(copperpour allowed)
			(footprints not_allowed)
		)
		(placement
			(enabled no)
			(sheetname "")
		)
		(fill
			(thermal_gap 0.5)
			(thermal_bridge_width 0.5)
			(island_removal_mode 0)
		)
		(polygon
			(pts
				(arc
					(start 77.829918 -212.989922)
					(mid 81.330038 -216.490042)
					(end 84.829904 -212.989922)
				)
				(arc
					(start 84.829904 -212.989922)
					(mid 81.330038 -209.490056)
					(end 77.829918 -212.989922)
				)
			)
		)
	)
	(zone
		(layer "B.Cu")
		(hatch none 0.5)
		(connect_pads
			(clearance 0)
		)
		(min_thickness 0.25)
		(keepout
			(tracks not_allowed)
			(vias allowed)
			(pads allowed)
			(copperpour not_allowed)
			(footprints allowed)
		)
		(placement
			(enabled no)
			(sheetname "")
		)
		(fill
			(thermal_gap 0.5)
			(thermal_bridge_width 0.5)
			(island_removal_mode 0)
		)
		(polygon
			(pts
				(arc
					(start 444.33998 -40.420036)
					(mid 447.44005 -43.520106)
					(end 450.54012 -40.420036)
				)
				(arc
					(start 450.54012 -40.420036)
					(mid 447.44005 -37.319966)
					(end 444.33998 -40.420036)
				)
			)
		)
	)
	(zone
		(layer "B.Cu")
		(hatch none 0.5)
		(connect_pads
			(clearance 0)
		)
		(min_thickness 0.25)
		(keepout
			(tracks allowed)
			(vias allowed)
			(pads allowed)
			(copperpour allowed)
			(footprints not_allowed)
		)
		(placement
			(enabled no)
			(sheetname "")
		)
		(fill
			(thermal_gap 0.5)
			(thermal_bridge_width 0.5)
			(island_removal_mode 0)
		)
		(polygon
			(pts
				(arc
					(start 224.14992 -272.50009)
					(mid 236.650022 -285.000192)
					(end 249.150124 -272.50009)
				)
				(arc
					(start 249.150124 -272.50009)
					(mid 236.650022 -259.999988)
					(end 224.14992 -272.50009)
				)
			)
		)
	)
	(zone
		(layer "B.Cu")
		(hatch none 0.5)
		(connect_pads
			(clearance 0)
		)
		(min_thickness 0.25)
		(keepout
			(tracks allowed)
			(vias allowed)
			(pads allowed)
			(copperpour allowed)
			(footprints allowed)
		)
		(placement
			(enabled no)
			(sheetname "")
		)
		(fill
			(thermal_gap 0.5)
			(thermal_bridge_width 0.5)
			(island_removal_mode 0)
		)
		(polygon
			(pts
				(xy 145.477992 -394.180568) (xy 145.477992 -391.48639) (xy 145.477992 -385.965954) (xy 147.225258 -385.965954)
				(xy 147.225258 -384.911854) (xy 166.820088 -384.911854) (xy 166.820088 -385.965954) (xy 166.820088 -394.180568)
			)
		)
	)
	(zone
		(layer "B.Cu")
		(hatch none 0.5)
		(connect_pads
			(clearance 0)
		)
		(min_thickness 0.25)
		(keepout
			(tracks not_allowed)
			(vias allowed)
			(pads allowed)
			(copperpour not_allowed)
			(footprints allowed)
		)
		(placement
			(enabled no)
			(sheetname "")
		)
		(fill
			(thermal_gap 0.5)
			(thermal_bridge_width 0.5)
			(island_removal_mode 0)
		)
		(polygon
			(pts
				(arc
					(start 64.106298 -386.003292)
					(mid 63.476378 -386.003292)
					(end 64.106298 -386.003292)
				)
			)
		)
	)
	(zone
		(layer "B.Cu")
		(hatch none 0.5)
		(connect_pads
			(clearance 0)
		)
		(min_thickness 0.25)
		(keepout
			(tracks allowed)
			(vias allowed)
			(pads allowed)
			(copperpour allowed)
			(footprints allowed)
		)
		(placement
			(enabled no)
			(sheetname "")
		)
		(fill
			(thermal_gap 0.5)
			(thermal_bridge_width 0.5)
			(island_removal_mode 0)
		)
		(polygon
			(pts
				(xy 66.30543 -18.223992) (xy 67.219068 -18.223992) (xy 67.219068 -18.935192) (xy 66.30543 -18.935192)
			)
		)
	)
	(zone
		(layer "B.Cu")
		(hatch none 0.5)
		(connect_pads
			(clearance 0)
		)
		(min_thickness 0.25)
		(keepout
			(tracks allowed)
			(vias allowed)
			(pads allowed)
			(copperpour allowed)
			(footprints allowed)
		)
		(placement
			(enabled no)
			(sheetname "")
		)
		(fill
			(thermal_gap 0.5)
			(thermal_bridge_width 0.5)
			(island_removal_mode 0)
		)
		(polygon
			(pts
				(xy 401.477988 -402.562568) (xy 401.477988 -399.86839) (xy 401.477988 -394.347954) (xy 403.225254 -394.347954)
				(xy 403.225254 -393.293854) (xy 422.820084 -393.293854) (xy 422.820084 -394.347954) (xy 422.820084 -402.562568)
			)
		)
	)
	(zone
		(layer "B.Cu")
		(hatch none 0.5)
		(connect_pads
			(clearance 0)
		)
		(min_thickness 0.25)
		(keepout
			(tracks not_allowed)
			(vias allowed)
			(pads allowed)
			(copperpour not_allowed)
			(footprints allowed)
		)
		(placement
			(enabled no)
			(sheetname "")
		)
		(fill
			(thermal_gap 0.5)
			(thermal_bridge_width 0.5)
			(island_removal_mode 0)
		)
		(polygon
			(pts
				(arc
					(start 130.1369 -436.889906)
					(mid 129.362708 -436.889906)
					(end 130.1369 -436.889906)
				)
			)
		)
	)
	(zone
		(layer "B.Cu")
		(hatch none 0.5)
		(connect_pads
			(clearance 0)
		)
		(min_thickness 0.25)
		(keepout
			(tracks allowed)
			(vias allowed)
			(pads allowed)
			(copperpour allowed)
			(footprints not_allowed)
		)
		(placement
			(enabled no)
			(sheetname "")
		)
		(fill
			(thermal_gap 0.5)
			(thermal_bridge_width 0.5)
			(island_removal_mode 0)
		)
		(polygon
			(pts
				(arc
					(start 398.47012 -258.890008)
					(mid 401.97024 -262.390128)
					(end 405.470106 -258.890008)
				)
				(arc
					(start 405.470106 -258.890008)
					(mid 401.97024 -255.390142)
					(end 398.47012 -258.890008)
				)
			)
		)
	)
	(zone
		(layer "B.Cu")
		(hatch none 0.5)
		(connect_pads
			(clearance 0)
		)
		(min_thickness 0.25)
		(keepout
			(tracks allowed)
			(vias allowed)
			(pads allowed)
			(copperpour allowed)
			(footprints not_allowed)
		)
		(placement
			(enabled no)
			(sheetname "")
		)
		(fill
			(thermal_gap 0.5)
			(thermal_bridge_width 0.5)
			(island_removal_mode 0)
		)
		(polygon
			(pts
				(arc
					(start 231.650032 -352.49993)
					(mid 236.650022 -357.49992)
					(end 241.650012 -352.49993)
				)
				(arc
					(start 241.650012 -352.49993)
					(mid 236.650022 -347.49994)
					(end 231.650032 -352.49993)
				)
			)
		)
	)
	(zone
		(layer "B.Cu")
		(hatch none 0.5)
		(connect_pads
			(clearance 0)
		)
		(min_thickness 0.25)
		(keepout
			(tracks not_allowed)
			(vias allowed)
			(pads allowed)
			(copperpour not_allowed)
			(footprints allowed)
		)
		(placement
			(enabled no)
			(sheetname "")
		)
		(fill
			(thermal_gap 0.5)
			(thermal_bridge_width 0.5)
			(island_removal_mode 0)
		)
		(polygon
			(pts
				(arc
					(start 322.106036 -393.69238)
					(mid 321.476116 -393.69238)
					(end 322.106036 -393.69238)
				)
			)
		)
	)
	(zone
		(layer "B.Cu")
		(hatch none 0.5)
		(connect_pads
			(clearance 0)
		)
		(min_thickness 0.25)
		(keepout
			(tracks not_allowed)
			(vias allowed)
			(pads allowed)
			(copperpour not_allowed)
			(footprints allowed)
		)
		(placement
			(enabled no)
			(sheetname "")
		)
		(fill
			(thermal_gap 0.5)
			(thermal_bridge_width 0.5)
			(island_removal_mode 0)
		)
		(polygon
			(pts
				(arc
					(start 199.650096 -51.999896)
					(mid 204.650086 -56.999886)
					(end 209.650076 -51.999896)
				)
				(arc
					(start 209.650076 -51.999896)
					(mid 204.650086 -46.999906)
					(end 199.650096 -51.999896)
				)
			)
		)
	)
	(zone
		(layer "B.Cu")
		(hatch none 0.5)
		(connect_pads
			(clearance 0)
		)
		(min_thickness 0.25)
		(keepout
			(tracks allowed)
			(vias allowed)
			(pads allowed)
			(copperpour allowed)
			(footprints not_allowed)
		)
		(placement
			(enabled no)
			(sheetname "")
		)
		(fill
			(thermal_gap 0.5)
			(thermal_bridge_width 0.5)
			(island_removal_mode 0)
		)
		(polygon
			(pts
				(xy 280.47696 -425.990004)
				(arc
					(start 280.47696 -417.770056)
					(mid 281.034986 -414.077158)
					(end 282.659074 -410.713936)
				)
				(xy 282.659074 -405.99995) (xy 189.15888 -405.99995)
				(arc
					(start 189.15888 -410.71673)
					(mid 190.781469 -414.078785)
					(end 191.338962 -417.770056)
				)
				(xy 191.338962 -425.990004)
			)
		)
	)
	(zone
		(layer "B.Cu")
		(hatch none 0.5)
		(connect_pads
			(clearance 0)
		)
		(min_thickness 0.25)
		(keepout
			(tracks not_allowed)
			(vias allowed)
			(pads allowed)
			(copperpour not_allowed)
			(footprints allowed)
		)
		(placement
			(enabled no)
			(sheetname "")
		)
		(fill
			(thermal_gap 0.5)
			(thermal_bridge_width 0.5)
			(island_removal_mode 0)
		)
		(polygon
			(pts
				(arc
					(start 352.516186 -246.104156)
					(mid 351.886266 -246.104156)
					(end 352.516186 -246.104156)
				)
			)
		)
	)
	(zone
		(layer "B.Cu")
		(hatch none 0.5)
		(connect_pads
			(clearance 0)
		)
		(min_thickness 0.25)
		(keepout
			(tracks not_allowed)
			(vias allowed)
			(pads allowed)
			(copperpour not_allowed)
			(footprints allowed)
		)
		(placement
			(enabled no)
			(sheetname "")
		)
		(fill
			(thermal_gap 0.5)
			(thermal_bridge_width 0.5)
			(island_removal_mode 0)
		)
		(polygon
			(pts
				(arc
					(start 316.106048 -393.69238)
					(mid 315.476128 -393.69238)
					(end 316.106048 -393.69238)
				)
			)
		)
	)
	(zone
		(layer "B.Cu")
		(hatch none 0.5)
		(connect_pads
			(clearance 0)
		)
		(min_thickness 0.25)
		(keepout
			(tracks not_allowed)
			(vias allowed)
			(pads allowed)
			(copperpour not_allowed)
			(footprints allowed)
		)
		(placement
			(enabled no)
			(sheetname "")
		)
		(fill
			(thermal_gap 0.5)
			(thermal_bridge_width 0.5)
			(island_removal_mode 0)
		)
		(polygon
			(pts
				(arc
					(start 61.036962 -439.0898)
					(mid 60.26277 -439.0898)
					(end 61.036962 -439.0898)
				)
			)
		)
	)
	(zone
		(layer "B.Cu")
		(hatch none 0.5)
		(connect_pads
			(clearance 0)
		)
		(min_thickness 0.25)
		(keepout
			(tracks allowed)
			(vias allowed)
			(pads allowed)
			(copperpour allowed)
			(footprints not_allowed)
		)
		(placement
			(enabled no)
			(sheetname "")
		)
		(fill
			(thermal_gap 0.5)
			(thermal_bridge_width 0.5)
			(island_removal_mode 0)
		)
		(polygon
			(pts
				(arc
					(start 32.563054 -74.76109)
					(mid 45.063156 -87.261192)
					(end 57.563004 -74.76109)
				)
				(arc
					(start 57.563004 -66.061082)
					(mid 45.063156 -53.561234)
					(end 32.563054 -66.061082)
				)
			)
		)
	)
	(zone
		(layer "B.Cu")
		(hatch none 0.5)
		(connect_pads
			(clearance 0)
		)
		(min_thickness 0.25)
		(keepout
			(tracks not_allowed)
			(vias allowed)
			(pads allowed)
			(copperpour not_allowed)
			(footprints allowed)
		)
		(placement
			(enabled no)
			(sheetname "")
		)
		(fill
			(thermal_gap 0.5)
			(thermal_bridge_width 0.5)
			(island_removal_mode 0)
		)
		(polygon
			(pts
				(arc
					(start 256.261108 -197.07352)
					(mid 255.593088 -197.07352)
					(end 256.261108 -197.07352)
				)
			)
		)
	)
	(zone
		(layer "B.Cu")
		(hatch none 0.5)
		(connect_pads
			(clearance 0)
		)
		(min_thickness 0.25)
		(keepout
			(tracks allowed)
			(vias allowed)
			(pads allowed)
			(copperpour allowed)
			(footprints allowed)
		)
		(placement
			(enabled no)
			(sheetname "")
		)
		(fill
			(thermal_gap 0.5)
			(thermal_bridge_width 0.5)
			(island_removal_mode 0)
		)
		(polygon
			(pts
				(xy 384.412236 -417.428426) (xy 384.412236 -416.42411) (xy 385.78917 -416.42411) (xy 385.78917 -417.428426)
			)
		)
	)
	(zone
		(layer "B.Cu")
		(hatch none 0.5)
		(connect_pads
			(clearance 0)
		)
		(min_thickness 0.25)
		(keepout
			(tracks not_allowed)
			(vias allowed)
			(pads allowed)
			(copperpour not_allowed)
			(footprints allowed)
		)
		(placement
			(enabled no)
			(sheetname "")
		)
		(fill
			(thermal_gap 0.5)
			(thermal_bridge_width 0.5)
			(island_removal_mode 0)
		)
		(polygon
			(pts
				(arc
					(start 157.1371 -437.889904)
					(mid 156.362908 -437.889904)
					(end 157.1371 -437.889904)
				)
			)
		)
	)
	(zone
		(layer "B.Cu")
		(hatch none 0.5)
		(connect_pads
			(clearance 0)
		)
		(min_thickness 0.25)
		(keepout
			(tracks not_allowed)
			(vias allowed)
			(pads allowed)
			(copperpour not_allowed)
			(footprints allowed)
		)
		(placement
			(enabled no)
			(sheetname "")
		)
		(fill
			(thermal_gap 0.5)
			(thermal_bridge_width 0.5)
			(island_removal_mode 0)
		)
		(polygon
			(pts
				(arc
					(start 344.952066 -147.904962)
					(mid 348.052136 -151.005032)
					(end 351.151952 -147.904962)
				)
				(arc
					(start 351.151952 -147.904962)
					(mid 348.052136 -144.805146)
					(end 344.952066 -147.904962)
				)
			)
		)
	)
	(zone
		(layer "B.Cu")
		(hatch none 0.5)
		(connect_pads
			(clearance 0)
		)
		(min_thickness 0.25)
		(keepout
			(tracks not_allowed)
			(vias allowed)
			(pads allowed)
			(copperpour not_allowed)
			(footprints allowed)
		)
		(placement
			(enabled no)
			(sheetname "")
		)
		(fill
			(thermal_gap 0.5)
			(thermal_bridge_width 0.5)
			(island_removal_mode 0)
		)
		(polygon
			(pts
				(arc
					(start 64.906398 -385.31038)
					(mid 64.276478 -385.31038)
					(end 64.906398 -385.31038)
				)
			)
		)
	)
	(zone
		(layer "B.Cu")
		(hatch none 0.5)
		(connect_pads
			(clearance 0)
		)
		(min_thickness 0.25)
		(keepout
			(tracks allowed)
			(vias allowed)
			(pads allowed)
			(copperpour allowed)
			(footprints allowed)
		)
		(placement
			(enabled no)
			(sheetname "")
		)
		(fill
			(thermal_gap 0.5)
			(thermal_bridge_width 0.5)
			(island_removal_mode 0)
		)
		(polygon
			(pts
				(xy 61.312298 -409.046426) (xy 61.312298 -408.04211) (xy 62.689232 -408.04211) (xy 62.689232 -409.046426)
			)
		)
	)
	(zone
		(layer "B.Cu")
		(hatch none 0.5)
		(connect_pads
			(clearance 0)
		)
		(min_thickness 0.25)
		(keepout
			(tracks allowed)
			(vias allowed)
			(pads allowed)
			(copperpour allowed)
			(footprints not_allowed)
		)
		(placement
			(enabled no)
			(sheetname "")
		)
		(fill
			(thermal_gap 0.5)
			(thermal_bridge_width 0.5)
			(island_removal_mode 0)
		)
		(polygon
			(pts
				(arc
					(start 467.29777 -342.229948)
					(mid 453.460025 -347.700185)
					(end 467.29777 -353.169982)
				)
			)
		)
	)
	(zone
		(layer "B.Cu")
		(hatch none 0.5)
		(connect_pads
			(clearance 0)
		)
		(min_thickness 0.25)
		(keepout
			(tracks allowed)
			(vias allowed)
			(pads allowed)
			(copperpour allowed)
			(footprints not_allowed)
		)
		(placement
			(enabled no)
			(sheetname "")
		)
		(fill
			(thermal_gap 0.5)
			(thermal_bridge_width 0.5)
			(island_removal_mode 0)
		)
		(polygon
			(pts
				(arc
					(start 251.765054 -290.900104)
					(mid 249.900186 -289.035236)
					(end 248.035064 -290.900104)
				)
				(arc
					(start 248.035064 -290.900104)
					(mid 249.900186 -292.765226)
					(end 251.765054 -290.900104)
				)
			)
		)
	)
	(zone
		(layer "B.Cu")
		(hatch none 0.5)
		(connect_pads
			(clearance 0)
		)
		(min_thickness 0.25)
		(keepout
			(tracks not_allowed)
			(vias allowed)
			(pads allowed)
			(copperpour not_allowed)
			(footprints allowed)
		)
		(placement
			(enabled no)
			(sheetname "")
		)
		(fill
			(thermal_gap 0.5)
			(thermal_bridge_width 0.5)
			(island_removal_mode 0)
		)
		(polygon
			(pts
				(arc
					(start 320.10604 -394.385292)
					(mid 319.47612 -394.385292)
					(end 320.10604 -394.385292)
				)
			)
		)
	)
	(zone
		(layer "B.Cu")
		(hatch none 0.5)
		(connect_pads
			(clearance 0)
		)
		(min_thickness 0.25)
		(keepout
			(tracks allowed)
			(vias allowed)
			(pads allowed)
			(copperpour allowed)
			(footprints allowed)
		)
		(placement
			(enabled no)
			(sheetname "")
		)
		(fill
			(thermal_gap 0.5)
			(thermal_bridge_width 0.5)
			(island_removal_mode 0)
		)
		(polygon
			(pts
				(xy 12.5222 -113.0808) (xy 12.5222 -111.5568) (xy 13.2334 -111.5568) (xy 13.2334 -113.0808)
			)
		)
	)
	(zone
		(layer "B.Cu")
		(hatch none 0.5)
		(connect_pads
			(clearance 0)
		)
		(min_thickness 0.25)
		(keepout
			(tracks not_allowed)
			(vias allowed)
			(pads allowed)
			(copperpour not_allowed)
			(footprints allowed)
		)
		(placement
			(enabled no)
			(sheetname "")
		)
		(fill
			(thermal_gap 0.5)
			(thermal_bridge_width 0.5)
			(island_removal_mode 0)
		)
		(polygon
			(pts
				(arc
					(start 66.580004 -258.890008)
					(mid 69.830188 -262.140192)
					(end 73.080118 -258.890008)
				)
				(arc
					(start 73.080118 -258.890008)
					(mid 69.830188 -255.640078)
					(end 66.580004 -258.890008)
				)
			)
		)
	)
	(zone
		(layer "B.Cu")
		(hatch none 0.5)
		(connect_pads
			(clearance 0)
		)
		(min_thickness 0.25)
		(keepout
			(tracks not_allowed)
			(vias allowed)
			(pads allowed)
			(copperpour not_allowed)
			(footprints allowed)
		)
		(placement
			(enabled no)
			(sheetname "")
		)
		(fill
			(thermal_gap 0.5)
			(thermal_bridge_width 0.5)
			(island_removal_mode 0)
		)
		(polygon
			(pts
				(arc
					(start 60.150756 -392.429238)
					(mid 59.482736 -392.429238)
					(end 60.150756 -392.429238)
				)
			)
		)
	)
	(zone
		(layer "B.Cu")
		(hatch none 0.5)
		(connect_pads
			(clearance 0)
		)
		(min_thickness 0.25)
		(keepout
			(tracks allowed)
			(vias allowed)
			(pads allowed)
			(copperpour allowed)
			(footprints allowed)
		)
		(placement
			(enabled no)
			(sheetname "")
		)
		(fill
			(thermal_gap 0.5)
			(thermal_bridge_width 0.5)
			(island_removal_mode 0)
		)
		(polygon
			(pts
				(xy 329.565 -417.428426) (xy 329.565 -416.42411) (xy 330.941934 -416.42411) (xy 330.941934 -417.428426)
			)
		)
	)
	(zone
		(layer "B.Cu")
		(hatch none 0.5)
		(connect_pads
			(clearance 0)
		)
		(min_thickness 0.25)
		(keepout
			(tracks not_allowed)
			(vias allowed)
			(pads allowed)
			(copperpour not_allowed)
			(footprints allowed)
		)
		(placement
			(enabled no)
			(sheetname "")
		)
		(fill
			(thermal_gap 0.5)
			(thermal_bridge_width 0.5)
			(island_removal_mode 0)
		)
		(polygon
			(pts
				(arc
					(start 106.755946 -270.03629)
					(mid 106.126026 -270.03629)
					(end 106.755946 -270.03629)
				)
			)
		)
	)
	(zone
		(layer "B.Cu")
		(hatch none 0.5)
		(connect_pads
			(clearance 0)
		)
		(min_thickness 0.25)
		(keepout
			(tracks not_allowed)
			(vias allowed)
			(pads allowed)
			(copperpour not_allowed)
			(footprints allowed)
		)
		(placement
			(enabled no)
			(sheetname "")
		)
		(fill
			(thermal_gap 0.5)
			(thermal_bridge_width 0.5)
			(island_removal_mode 0)
		)
		(polygon
			(pts
				(arc
					(start 318.55029 -401.674838)
					(mid 317.88227 -401.674838)
					(end 318.55029 -401.674838)
				)
			)
		)
	)
	(zone
		(layer "B.Cu")
		(hatch none 0.5)
		(connect_pads
			(clearance 0)
		)
		(min_thickness 0.25)
		(keepout
			(tracks not_allowed)
			(vias allowed)
			(pads allowed)
			(copperpour not_allowed)
			(footprints allowed)
		)
		(placement
			(enabled no)
			(sheetname "")
		)
		(fill
			(thermal_gap 0.5)
			(thermal_bridge_width 0.5)
			(island_removal_mode 0)
		)
		(polygon
			(pts
				(arc
					(start 65.036954 -439.0898)
					(mid 64.262762 -439.0898)
					(end 65.036954 -439.0898)
				)
			)
		)
	)
	(zone
		(layer "B.Cu")
		(hatch none 0.5)
		(connect_pads
			(clearance 0)
		)
		(min_thickness 0.25)
		(keepout
			(tracks allowed)
			(vias allowed)
			(pads allowed)
			(copperpour allowed)
			(footprints allowed)
		)
		(placement
			(enabled no)
			(sheetname "")
		)
		(fill
			(thermal_gap 0.5)
			(thermal_bridge_width 0.5)
			(island_removal_mode 0)
		)
		(polygon
			(pts
				(xy 167.57142 -109.15904) (xy 167.57142 -108.177076) (xy 170.18 -108.177076) (xy 170.18 -109.15904)
			)
		)
	)
	(zone
		(layer "B.Cu")
		(hatch none 0.5)
		(connect_pads
			(clearance 0)
		)
		(min_thickness 0.25)
		(keepout
			(tracks not_allowed)
			(vias allowed)
			(pads allowed)
			(copperpour not_allowed)
			(footprints allowed)
		)
		(placement
			(enabled no)
			(sheetname "")
		)
		(fill
			(thermal_gap 0.5)
			(thermal_bridge_width 0.5)
			(island_removal_mode 0)
		)
		(polygon
			(pts
				(arc
					(start 349.917004 -147.904962)
					(mid 348.052136 -146.040094)
					(end 346.187014 -147.904962)
				)
				(arc
					(start 346.187014 -147.904962)
					(mid 348.052136 -149.770084)
					(end 349.917004 -147.904962)
				)
			)
		)
	)
	(zone
		(layer "B.Cu")
		(hatch none 0.5)
		(connect_pads
			(clearance 0)
		)
		(min_thickness 0.25)
		(keepout
			(tracks allowed)
			(vias allowed)
			(pads allowed)
			(copperpour allowed)
			(footprints not_allowed)
		)
		(placement
			(enabled no)
			(sheetname "")
		)
		(fill
			(thermal_gap 0.5)
			(thermal_bridge_width 0.5)
			(island_removal_mode 0)
		)
		(polygon
			(pts
				(arc
					(start 94.383098 -50.25009)
					(mid 95.784681 -49.926806)
					(end 96.903032 -49.022254)
				)
				(arc
					(start 96.903032 -49.022254)
					(mid 101.402945 -50.917846)
					(end 104.383078 -47.049944)
				)
				(arc
					(start 104.383078 -47.049944)
					(mid 101.402812 -43.182116)
					(end 96.903032 -45.077888)
				)
				(arc
					(start 96.903032 -45.077888)
					(mid 95.784665 -44.173369)
					(end 94.383098 -43.850052)
				)
				(arc
					(start 92.782898 -43.850052)
					(mid 89.582752 -47.050198)
					(end 92.782898 -50.25009)
				)
			)
		)
	)
	(zone
		(layer "B.Cu")
		(hatch none 0.5)
		(connect_pads
			(clearance 0)
		)
		(min_thickness 0.25)
		(keepout
			(tracks allowed)
			(vias allowed)
			(pads allowed)
			(copperpour allowed)
			(footprints not_allowed)
		)
		(placement
			(enabled no)
			(sheetname "")
		)
		(fill
			(thermal_gap 0.5)
			(thermal_bridge_width 0.5)
			(island_removal_mode 0)
		)
		(polygon
			(pts
				(arc
					(start 325.699882 -160.50006)
					(mid 322.90004 -157.700218)
					(end 320.099944 -160.50006)
				)
				(arc
					(start 320.099944 -160.50006)
					(mid 322.90004 -163.300156)
					(end 325.699882 -160.50006)
				)
			)
		)
	)
	(zone
		(layer "B.Cu")
		(hatch none 0.5)
		(connect_pads
			(clearance 0)
		)
		(min_thickness 0.25)
		(keepout
			(tracks allowed)
			(vias allowed)
			(pads allowed)
			(copperpour allowed)
			(footprints allowed)
		)
		(placement
			(enabled no)
			(sheetname "")
		)
		(fill
			(thermal_gap 0.5)
			(thermal_bridge_width 0.5)
			(island_removal_mode 0)
		)
		(polygon
			(pts
				(xy 337.81492 -3.31724) (xy 337.81492 -1.22428) (xy 340.35492 -1.22428) (xy 340.35492 -3.31724)
			)
		)
	)
	(zone
		(layer "B.Cu")
		(hatch none 0.5)
		(connect_pads
			(clearance 0)
		)
		(min_thickness 0.25)
		(keepout
			(tracks allowed)
			(vias allowed)
			(pads allowed)
			(copperpour allowed)
			(footprints allowed)
		)
		(placement
			(enabled no)
			(sheetname "")
		)
		(fill
			(thermal_gap 0.5)
			(thermal_bridge_width 0.5)
			(island_removal_mode 0)
		)
		(polygon
			(pts
				(xy 184.69356 -194.01536) (xy 184.69356 -190.70574) (xy 186.46394 -190.70574) (xy 186.46394 -194.01536)
			)
		)
	)
	(zone
		(layer "B.Cu")
		(hatch none 0.5)
		(connect_pads
			(clearance 0)
		)
		(min_thickness 0.25)
		(keepout
			(tracks allowed)
			(vias allowed)
			(pads allowed)
			(copperpour allowed)
			(footprints not_allowed)
		)
		(placement
			(enabled no)
			(sheetname "")
		)
		(fill
			(thermal_gap 0.5)
			(thermal_bridge_width 0.5)
			(island_removal_mode 0)
		)
		(polygon
			(pts
				(arc
					(start 450.54012 -40.420036)
					(mid 447.44005 -37.319966)
					(end 444.33998 -40.420036)
				)
				(arc
					(start 444.33998 -40.420036)
					(mid 447.44005 -43.520106)
					(end 450.54012 -40.420036)
				)
			)
		)
	)
	(zone
		(layer "B.Cu")
		(hatch none 0.5)
		(connect_pads
			(clearance 0)
		)
		(min_thickness 0.25)
		(keepout
			(tracks allowed)
			(vias allowed)
			(pads allowed)
			(copperpour allowed)
			(footprints allowed)
		)
		(placement
			(enabled no)
			(sheetname "")
		)
		(fill
			(thermal_gap 0.5)
			(thermal_bridge_width 0.5)
			(island_removal_mode 0)
		)
		(polygon
			(pts
				(xy 389.748014 -393.293854) (xy 389.748014 -391.776966) (xy 389.740648 -391.7696) (xy 389.740648 -391.258806)
				(xy 389.194294 -390.712452) (xy 387.91388 -390.712452) (xy 387.695948 -390.930384) (xy 371.695472 -390.930384)
				(xy 371.145054 -391.480802) (xy 371.145054 -393.293854)
			)
		)
	)
	(zone
		(layer "B.Cu")
		(hatch none 0.5)
		(connect_pads
			(clearance 0)
		)
		(min_thickness 0.25)
		(keepout
			(tracks allowed)
			(vias allowed)
			(pads allowed)
			(copperpour allowed)
			(footprints not_allowed)
		)
		(placement
			(enabled no)
			(sheetname "")
		)
		(fill
			(thermal_gap 0.5)
			(thermal_bridge_width 0.5)
			(island_removal_mode 0)
		)
		(polygon
			(pts
				(xy 282.659074 -405.99995)
				(arc
					(start 282.659074 -410.713936)
					(mid 281.034958 -414.077149)
					(end 280.47696 -417.770056)
				)
				(xy 280.47696 -425.990004) (xy 191.338962 -425.990004)
				(arc
					(start 191.338962 -417.770056)
					(mid 190.781524 -414.078768)
					(end 189.15888 -410.71673)
				)
				(xy 189.15888 -405.99995)
			)
		)
	)
	(zone
		(layer "B.Cu")
		(hatch none 0.5)
		(connect_pads
			(clearance 0)
		)
		(min_thickness 0.25)
		(keepout
			(tracks not_allowed)
			(vias allowed)
			(pads allowed)
			(copperpour not_allowed)
			(footprints allowed)
		)
		(placement
			(enabled no)
			(sheetname "")
		)
		(fill
			(thermal_gap 0.5)
			(thermal_bridge_width 0.5)
			(island_removal_mode 0)
		)
		(polygon
			(pts
				(arc
					(start 382.136904 -436.889906)
					(mid 381.362712 -436.889906)
					(end 382.136904 -436.889906)
				)
			)
		)
	)
	(zone
		(layer "B.Cu")
		(hatch none 0.5)
		(connect_pads
			(clearance 0)
		)
		(min_thickness 0.25)
		(keepout
			(tracks not_allowed)
			(vias allowed)
			(pads allowed)
			(copperpour not_allowed)
			(footprints allowed)
		)
		(placement
			(enabled no)
			(sheetname "")
		)
		(fill
			(thermal_gap 0.5)
			(thermal_bridge_width 0.5)
			(island_removal_mode 0)
		)
		(polygon
			(pts
				(arc
					(start 104.876092 -270.03629)
					(mid 104.246172 -270.03629)
					(end 104.876092 -270.03629)
				)
			)
		)
	)
	(zone
		(layer "B.Cu")
		(hatch none 0.5)
		(connect_pads
			(clearance 0)
		)
		(min_thickness 0.25)
		(keepout
			(tracks not_allowed)
			(vias allowed)
			(pads allowed)
			(copperpour not_allowed)
			(footprints allowed)
		)
		(placement
			(enabled no)
			(sheetname "")
		)
		(fill
			(thermal_gap 0.5)
			(thermal_bridge_width 0.5)
			(island_removal_mode 0)
		)
		(polygon
			(pts
				(arc
					(start 84.12988 -212.989922)
					(mid 81.330038 -210.19008)
					(end 78.529942 -212.989922)
				)
				(arc
					(start 78.529942 -212.989922)
					(mid 81.330038 -215.790018)
					(end 84.12988 -212.989922)
				)
			)
		)
	)
	(zone
		(layer "B.Cu")
		(hatch none 0.5)
		(connect_pads
			(clearance 0)
		)
		(min_thickness 0.25)
		(keepout
			(tracks allowed)
			(vias allowed)
			(pads allowed)
			(copperpour allowed)
			(footprints allowed)
		)
		(placement
			(enabled no)
			(sheetname "")
		)
		(fill
			(thermal_gap 0.5)
			(thermal_bridge_width 0.5)
			(island_removal_mode 0)
		)
		(polygon
			(pts
				(xy 37.66058 -194.22364) (xy 37.66058 -193.13906) (xy 39.66464 -193.13906) (xy 39.66464 -194.22364)
			)
		)
	)
	(zone
		(layer "B.Cu")
		(hatch none 0.5)
		(connect_pads
			(clearance 0)
		)
		(min_thickness 0.25)
		(keepout
			(tracks not_allowed)
			(vias allowed)
			(pads allowed)
			(copperpour not_allowed)
			(footprints allowed)
		)
		(placement
			(enabled no)
			(sheetname "")
		)
		(fill
			(thermal_gap 0.5)
			(thermal_bridge_width 0.5)
			(island_removal_mode 0)
		)
		(polygon
			(pts
				(arc
					(start 342.036908 -437.889904)
					(mid 341.262716 -437.889904)
					(end 342.036908 -437.889904)
				)
			)
		)
	)
	(zone
		(layer "B.Cu")
		(hatch none 0.5)
		(connect_pads
			(clearance 0)
		)
		(min_thickness 0.25)
		(keepout
			(tracks allowed)
			(vias allowed)
			(pads allowed)
			(copperpour allowed)
			(footprints not_allowed)
		)
		(placement
			(enabled no)
			(sheetname "")
		)
		(fill
			(thermal_gap 0.5)
			(thermal_bridge_width 0.5)
			(island_removal_mode 0)
		)
		(polygon
			(pts
				(arc
					(start 13.139928 -160.50006)
					(mid 10.340086 -157.700218)
					(end 7.53999 -160.50006)
				)
				(arc
					(start 7.53999 -160.50006)
					(mid 10.340086 -163.300156)
					(end 13.139928 -160.50006)
				)
			)
		)
	)
	(zone
		(layer "B.Cu")
		(hatch none 0.5)
		(connect_pads
			(clearance 0)
		)
		(min_thickness 0.25)
		(keepout
			(tracks allowed)
			(vias allowed)
			(pads allowed)
			(copperpour allowed)
			(footprints not_allowed)
		)
		(placement
			(enabled no)
			(sheetname "")
		)
		(fill
			(thermal_gap 0.5)
			(thermal_bridge_width 0.5)
			(island_removal_mode 0)
		)
		(polygon
			(pts
				(arc
					(start 470.799922 -13.780008)
					(mid 470.507029 -13.072903)
					(end 469.799924 -12.78001)
				)
				(arc
					(start 458.242924 -12.78001)
					(mid 457.616318 -12.713792)
					(end 457.017374 -12.518136)
				)
				(arc
					(start 457.017374 -12.518136)
					(mid 452.556954 -19.778243)
					(end 453.785478 -28.210002)
				)
				(arc
					(start 460.893922 -45.994066)
					(mid 460.664291 -56.313921)
					(end 470.799922 -58.269378)
				)
			)
		)
	)
	(zone
		(layer "B.Cu")
		(hatch none 0.5)
		(connect_pads
			(clearance 0)
		)
		(min_thickness 0.25)
		(keepout
			(tracks allowed)
			(vias allowed)
			(pads allowed)
			(copperpour allowed)
			(footprints not_allowed)
		)
		(placement
			(enabled no)
			(sheetname "")
		)
		(fill
			(thermal_gap 0.5)
			(thermal_bridge_width 0.5)
			(island_removal_mode 0)
		)
		(polygon
			(pts
				(arc
					(start 280.50109 -74.767948)
					(mid 293.001192 -87.265256)
					(end 305.50104 -74.767948)
				)
				(arc
					(start 305.503072 -66.06794)
					(mid 293.00805 -53.561233)
					(end 280.503122 -66.058288)
				)
			)
		)
	)
	(zone
		(layer "B.Cu")
		(hatch none 0.5)
		(connect_pads
			(clearance 0)
		)
		(min_thickness 0.25)
		(keepout
			(tracks not_allowed)
			(vias allowed)
			(pads allowed)
			(copperpour not_allowed)
			(footprints allowed)
		)
		(placement
			(enabled no)
			(sheetname "")
		)
		(fill
			(thermal_gap 0.5)
			(thermal_bridge_width 0.5)
			(island_removal_mode 0)
		)
		(polygon
			(pts
				(arc
					(start 128.136904 -437.889904)
					(mid 127.362712 -437.889904)
					(end 128.136904 -437.889904)
				)
			)
		)
	)
	(zone
		(layer "B.Cu")
		(hatch none 0.5)
		(connect_pads
			(clearance 0)
		)
		(min_thickness 0.25)
		(keepout
			(tracks allowed)
			(vias allowed)
			(pads allowed)
			(copperpour allowed)
			(footprints allowed)
		)
		(placement
			(enabled no)
			(sheetname "")
		)
		(fill
			(thermal_gap 0.5)
			(thermal_bridge_width 0.5)
			(island_removal_mode 0)
		)
		(polygon
			(pts
				(xy 98.940366 -180.363876) (xy 98.940366 -178.204876) (xy 99.321366 -177.823876) (xy 102.115366 -177.823876)
				(xy 103.258366 -178.966876) (xy 103.258366 -181.887876) (xy 102.750366 -182.395876) (xy 100.972366 -182.395876)
			)
		)
	)
	(zone
		(layer "B.Cu")
		(hatch none 0.5)
		(connect_pads
			(clearance 0)
		)
		(min_thickness 0.25)
		(keepout
			(tracks not_allowed)
			(vias allowed)
			(pads allowed)
			(copperpour not_allowed)
			(footprints allowed)
		)
		(placement
			(enabled no)
			(sheetname "")
		)
		(fill
			(thermal_gap 0.5)
			(thermal_bridge_width 0.5)
			(island_removal_mode 0)
		)
		(polygon
			(pts
				(arc
					(start 310.150256 -401.674838)
					(mid 309.482236 -401.674838)
					(end 310.150256 -401.674838)
				)
			)
		)
	)
	(zone
		(layer "B.Cu")
		(hatch none 0.5)
		(connect_pads
			(clearance 0)
		)
		(min_thickness 0.25)
		(keepout
			(tracks not_allowed)
			(vias allowed)
			(pads allowed)
			(copperpour not_allowed)
			(footprints allowed)
		)
		(placement
			(enabled no)
			(sheetname "")
		)
		(fill
			(thermal_gap 0.5)
			(thermal_bridge_width 0.5)
			(island_removal_mode 0)
		)
		(polygon
			(pts
				(arc
					(start 97.700084 -22.29993)
					(mid 94.899988 -19.499834)
					(end 92.099892 -22.29993)
				)
				(arc
					(start 92.099892 -22.29993)
					(mid 94.899988 -25.100026)
					(end 97.700084 -22.29993)
				)
			)
		)
	)
	(zone
		(layer "B.Cu")
		(hatch none 0.5)
		(connect_pads
			(clearance 0)
		)
		(min_thickness 0.25)
		(keepout
			(tracks not_allowed)
			(vias allowed)
			(pads allowed)
			(copperpour not_allowed)
			(footprints allowed)
		)
		(placement
			(enabled no)
			(sheetname "")
		)
		(fill
			(thermal_gap 0.5)
			(thermal_bridge_width 0.5)
			(island_removal_mode 0)
		)
		(polygon
			(pts
				(arc
					(start 66.15049 -393.292838)
					(mid 65.48247 -393.292838)
					(end 66.15049 -393.292838)
				)
			)
		)
	)
	(zone
		(layer "B.Cu")
		(hatch none 0.5)
		(connect_pads
			(clearance 0)
		)
		(min_thickness 0.25)
		(keepout
			(tracks not_allowed)
			(vias allowed)
			(pads allowed)
			(copperpour not_allowed)
			(footprints allowed)
		)
		(placement
			(enabled no)
			(sheetname "")
		)
		(fill
			(thermal_gap 0.5)
			(thermal_bridge_width 0.5)
			(island_removal_mode 0)
		)
		(polygon
			(pts
				(arc
					(start 424.746928 -163.314888)
					(mid 422.88206 -161.45002)
					(end 421.016938 -163.314888)
				)
				(arc
					(start 421.016938 -163.314888)
					(mid 422.88206 -165.18001)
					(end 424.746928 -163.314888)
				)
			)
		)
	)
	(zone
		(layer "B.Cu")
		(hatch none 0.5)
		(connect_pads
			(clearance 0)
		)
		(min_thickness 0.25)
		(keepout
			(tracks not_allowed)
			(vias allowed)
			(pads allowed)
			(copperpour not_allowed)
			(footprints allowed)
		)
		(placement
			(enabled no)
			(sheetname "")
		)
		(fill
			(thermal_gap 0.5)
			(thermal_bridge_width 0.5)
			(island_removal_mode 0)
		)
		(polygon
			(pts
				(arc
					(start 460.339948 -399.029936)
					(mid 463.440018 -402.130006)
					(end 466.540088 -399.029936)
				)
				(arc
					(start 466.540088 -399.029936)
					(mid 463.440018 -395.929866)
					(end 460.339948 -399.029936)
				)
			)
		)
	)
	(zone
		(layer "B.Cu")
		(hatch none 0.5)
		(connect_pads
			(clearance 0)
		)
		(min_thickness 0.25)
		(keepout
			(tracks not_allowed)
			(vias allowed)
			(pads allowed)
			(copperpour not_allowed)
			(footprints allowed)
		)
		(placement
			(enabled no)
			(sheetname "")
		)
		(fill
			(thermal_gap 0.5)
			(thermal_bridge_width 0.5)
			(island_removal_mode 0)
		)
		(polygon
			(pts
				(arc
					(start 133.212332 -18.144744)
					(mid 132.544312 -18.144744)
					(end 133.212332 -18.144744)
				)
			)
		)
	)
	(zone
		(layer "B.Cu")
		(hatch none 0.5)
		(connect_pads
			(clearance 0)
		)
		(min_thickness 0.25)
		(keepout
			(tracks allowed)
			(vias allowed)
			(pads allowed)
			(copperpour allowed)
			(footprints not_allowed)
		)
		(placement
			(enabled no)
			(sheetname "")
		)
		(fill
			(thermal_gap 0.5)
			(thermal_bridge_width 0.5)
			(island_removal_mode 0)
		)
		(polygon
			(pts
				(arc
					(start 260.124956 -360.764074)
					(mid 258.12496 -358.764078)
					(end 256.124964 -360.764074)
				)
				(arc
					(start 256.124964 -360.764074)
					(mid 258.12496 -362.76407)
					(end 260.124956 -360.764074)
				)
			)
		)
	)
	(zone
		(layer "B.Cu")
		(hatch none 0.5)
		(connect_pads
			(clearance 0)
		)
		(min_thickness 0.25)
		(keepout
			(tracks not_allowed)
			(vias allowed)
			(pads allowed)
			(copperpour not_allowed)
			(footprints allowed)
		)
		(placement
			(enabled no)
			(sheetname "")
		)
		(fill
			(thermal_gap 0.5)
			(thermal_bridge_width 0.5)
			(island_removal_mode 0)
		)
		(polygon
			(pts
				(arc
					(start 64.950594 -393.292838)
					(mid 64.282574 -393.292838)
					(end 64.950594 -393.292838)
				)
			)
		)
	)
	(zone
		(layer "B.Cu")
		(hatch none 0.5)
		(connect_pads
			(clearance 0)
		)
		(min_thickness 0.25)
		(keepout
			(tracks allowed)
			(vias allowed)
			(pads allowed)
			(copperpour allowed)
			(footprints not_allowed)
		)
		(placement
			(enabled no)
			(sheetname "")
		)
		(fill
			(thermal_gap 0.5)
			(thermal_bridge_width 0.5)
			(island_removal_mode 0)
		)
		(polygon
			(pts
				(arc
					(start 264.352024 -347.8149)
					(mid 267.452094 -350.91497)
					(end 270.55191 -347.8149)
				)
				(arc
					(start 270.55191 -347.8149)
					(mid 267.452094 -344.715084)
					(end 264.352024 -347.8149)
				)
			)
		)
	)
	(zone
		(layer "B.Cu")
		(hatch none 0.5)
		(connect_pads
			(clearance 0)
		)
		(min_thickness 0.25)
		(keepout
			(tracks not_allowed)
			(vias allowed)
			(pads allowed)
			(copperpour not_allowed)
			(footprints allowed)
		)
		(placement
			(enabled no)
			(sheetname "")
		)
		(fill
			(thermal_gap 0.5)
			(thermal_bridge_width 0.5)
			(island_removal_mode 0)
		)
		(polygon
			(pts
				(arc
					(start 256.261108 -199.868028)
					(mid 255.593088 -199.868028)
					(end 256.261108 -199.868028)
				)
			)
		)
	)
	(zone
		(layer "B.Cu")
		(hatch none 0.5)
		(connect_pads
			(clearance 0)
		)
		(min_thickness 0.25)
		(keepout
			(tracks allowed)
			(vias allowed)
			(pads allowed)
			(copperpour allowed)
			(footprints allowed)
		)
		(placement
			(enabled no)
			(sheetname "")
		)
		(fill
			(thermal_gap 0.5)
			(thermal_bridge_width 0.5)
			(island_removal_mode 0)
		)
		(polygon
			(pts
				(xy 347.45549 -158.862776) (xy 347.45549 -156.703776) (xy 347.83649 -156.322776) (xy 350.63049 -156.322776)
				(xy 351.77349 -157.465776) (xy 351.77349 -160.386776) (xy 351.26549 -160.894776) (xy 349.48749 -160.894776)
			)
		)
	)
	(zone
		(layer "B.Cu")
		(hatch none 0.5)
		(connect_pads
			(clearance 0)
		)
		(min_thickness 0.25)
		(keepout
			(tracks not_allowed)
			(vias allowed)
			(pads allowed)
			(copperpour not_allowed)
			(footprints allowed)
		)
		(placement
			(enabled no)
			(sheetname "")
		)
		(fill
			(thermal_gap 0.5)
			(thermal_bridge_width 0.5)
			(island_removal_mode 0)
		)
		(polygon
			(pts
				(arc
					(start 137.65022 -22.406102)
					(mid 136.9822 -22.406102)
					(end 137.65022 -22.406102)
				)
			)
		)
	)
	(zone
		(layer "B.Cu")
		(hatch none 0.5)
		(connect_pads
			(clearance 0)
		)
		(min_thickness 0.25)
		(keepout
			(tracks not_allowed)
			(vias allowed)
			(pads allowed)
			(copperpour not_allowed)
			(footprints allowed)
		)
		(placement
			(enabled no)
			(sheetname "")
		)
		(fill
			(thermal_gap 0.5)
			(thermal_bridge_width 0.5)
			(island_removal_mode 0)
		)
		(polygon
			(pts
				(arc
					(start 390.136888 -436.889906)
					(mid 389.362696 -436.889906)
					(end 390.136888 -436.889906)
				)
			)
		)
	)
	(zone
		(layer "B.Cu")
		(hatch none 0.5)
		(connect_pads
			(clearance 0)
		)
		(min_thickness 0.25)
		(keepout
			(tracks not_allowed)
			(vias allowed)
			(pads allowed)
			(copperpour not_allowed)
			(footprints allowed)
		)
		(placement
			(enabled no)
			(sheetname "")
		)
		(fill
			(thermal_gap 0.5)
			(thermal_bridge_width 0.5)
			(island_removal_mode 0)
		)
		(polygon
			(pts
				(arc
					(start 173.250098 -404.789894)
					(mid 171.000166 -402.539962)
					(end 168.74998 -404.789894)
				)
				(arc
					(start 168.74998 -404.789894)
					(mid 171.000166 -407.04008)
					(end 173.250098 -404.789894)
				)
			)
		)
	)
	(zone
		(layer "B.Cu")
		(hatch none 0.5)
		(connect_pads
			(clearance 0)
		)
		(min_thickness 0.25)
		(keepout
			(tracks allowed)
			(vias allowed)
			(pads allowed)
			(copperpour allowed)
			(footprints allowed)
		)
		(placement
			(enabled no)
			(sheetname "")
		)
		(fill
			(thermal_gap 0.5)
			(thermal_bridge_width 0.5)
			(island_removal_mode 0)
		)
		(polygon
			(pts
				(xy 380.80569 -180.509926) (xy 380.80569 -178.350926) (xy 381.18669 -177.969926) (xy 383.98069 -177.969926)
				(xy 385.12369 -179.112926) (xy 385.12369 -182.033926) (xy 384.61569 -182.541926) (xy 382.83769 -182.541926)
			)
		)
	)
	(zone
		(layer "B.Cu")
		(hatch none 0.5)
		(connect_pads
			(clearance 0)
		)
		(min_thickness 0.25)
		(keepout
			(tracks not_allowed)
			(vias allowed)
			(pads allowed)
			(copperpour not_allowed)
			(footprints allowed)
		)
		(placement
			(enabled no)
			(sheetname "")
		)
		(fill
			(thermal_gap 0.5)
			(thermal_bridge_width 0.5)
			(island_removal_mode 0)
		)
		(polygon
			(pts
				(arc
					(start 162.178238 -393.292838)
					(mid 161.510218 -393.292838)
					(end 162.178238 -393.292838)
				)
			)
		)
	)
	(zone
		(layer "B.Cu")
		(hatch none 0.5)
		(connect_pads
			(clearance 0)
		)
		(min_thickness 0.25)
		(keepout
			(tracks not_allowed)
			(vias allowed)
			(pads allowed)
			(copperpour not_allowed)
			(footprints allowed)
		)
		(placement
			(enabled no)
			(sheetname "")
		)
		(fill
			(thermal_gap 0.5)
			(thermal_bridge_width 0.5)
			(island_removal_mode 0)
		)
		(polygon
			(pts
				(arc
					(start 313.706002 -393.69238)
					(mid 313.076082 -393.69238)
					(end 313.706002 -393.69238)
				)
			)
		)
	)
	(zone
		(layer "B.Cu")
		(hatch none 0.5)
		(connect_pads
			(clearance 0)
		)
		(min_thickness 0.25)
		(keepout
			(tracks allowed)
			(vias allowed)
			(pads allowed)
			(copperpour allowed)
			(footprints not_allowed)
		)
		(placement
			(enabled no)
			(sheetname "")
		)
		(fill
			(thermal_gap 0.5)
			(thermal_bridge_width 0.5)
			(island_removal_mode 0)
		)
		(polygon
			(pts
				(arc
					(start 37.319966 -376.489976)
					(mid 35.070034 -374.240044)
					(end 32.820102 -376.489976)
				)
				(arc
					(start 32.820102 -376.489976)
					(mid 35.070034 -378.739908)
					(end 37.319966 -376.489976)
				)
			)
		)
	)
	(zone
		(layer "B.Cu")
		(hatch none 0.5)
		(connect_pads
			(clearance 0)
		)
		(min_thickness 0.25)
		(keepout
			(tracks not_allowed)
			(vias allowed)
			(pads allowed)
			(copperpour not_allowed)
			(footprints allowed)
		)
		(placement
			(enabled no)
			(sheetname "")
		)
		(fill
			(thermal_gap 0.5)
			(thermal_bridge_width 0.5)
			(island_removal_mode 0)
		)
		(polygon
			(pts
				(arc
					(start 420.57828 -400.811238)
					(mid 419.91026 -400.811238)
					(end 420.57828 -400.811238)
				)
			)
		)
	)
	(zone
		(layer "B.Cu")
		(hatch none 0.5)
		(connect_pads
			(clearance 0)
		)
		(min_thickness 0.25)
		(keepout
			(tracks allowed)
			(vias allowed)
			(pads allowed)
			(copperpour allowed)
			(footprints not_allowed)
		)
		(placement
			(enabled no)
			(sheetname "")
		)
		(fill
			(thermal_gap 0.5)
			(thermal_bridge_width 0.5)
			(island_removal_mode 0)
		)
		(polygon
			(pts
				(arc
					(start 105.500424 -435.600094)
					(mid 100.500434 -430.600104)
					(end 95.500444 -435.600094)
				)
				(arc
					(start 95.500444 -435.600094)
					(mid 100.500434 -440.600084)
					(end 105.500424 -435.600094)
				)
			)
		)
	)
	(zone
		(layer "B.Cu")
		(hatch none 0.5)
		(connect_pads
			(clearance 0)
		)
		(min_thickness 0.25)
		(keepout
			(tracks not_allowed)
			(vias allowed)
			(pads allowed)
			(copperpour not_allowed)
			(footprints allowed)
		)
		(placement
			(enabled no)
			(sheetname "")
		)
		(fill
			(thermal_gap 0.5)
			(thermal_bridge_width 0.5)
			(island_removal_mode 0)
		)
		(polygon
			(pts
				(arc
					(start 386.970016 -212.989922)
					(mid 390.470136 -216.490042)
					(end 393.970002 -212.989922)
				)
				(arc
					(start 393.970002 -212.989922)
					(mid 390.470136 -209.490056)
					(end 386.970016 -212.989922)
				)
			)
		)
	)
	(zone
		(layer "B.Cu")
		(hatch none 0.5)
		(connect_pads
			(clearance 0)
		)
		(min_thickness 0.25)
		(keepout
			(tracks allowed)
			(vias allowed)
			(pads allowed)
			(copperpour allowed)
			(footprints allowed)
		)
		(placement
			(enabled no)
			(sheetname "")
		)
		(fill
			(thermal_gap 0.5)
			(thermal_bridge_width 0.5)
			(island_removal_mode 0)
		)
		(polygon
			(pts
				(xy 252.981206 -47.484538) (xy 256.193036 -47.484538) (xy 256.897886 -47.484538) (xy 257.32359 -47.910242)
				(xy 257.32359 -54.649878) (xy 256.492248 -55.48122) (xy 253.214886 -55.48122) (xy 252.981206 -55.48122)
				(xy 252.981206 -49.174908)
			)
		)
	)
	(zone
		(layer "B.Cu")
		(hatch none 0.5)
		(connect_pads
			(clearance 0)
		)
		(min_thickness 0.25)
		(keepout
			(tracks allowed)
			(vias allowed)
			(pads allowed)
			(copperpour allowed)
			(footprints not_allowed)
		)
		(placement
			(enabled no)
			(sheetname "")
		)
		(fill
			(thermal_gap 0.5)
			(thermal_bridge_width 0.5)
			(island_removal_mode 0)
		)
		(polygon
			(pts
				(arc
					(start 306.047902 -415.91992)
					(mid 305.473829 -416.03411)
					(end 304.987198 -416.35934)
				)
				(arc
					(start 301.494698 -419.852094)
					(mid 300.034733 -420.827612)
					(end 298.312586 -421.1701)
				)
				(arc
					(start 293.176198 -421.1701)
					(mid 290.590477 -420.352888)
					(end 288.943796 -418.1983)
				)
				(arc
					(start 285.687516 -409.181046)
					(mid 285.487407 -408.428502)
					(end 285.420054 -407.652728)
				)
				(arc
					(start 285.420054 -395.112748)
					(mid 285.305864 -394.538675)
					(end 284.980634 -394.052044)
				)
				(arc
					(start 284.388052 -393.459462)
					(mid 283.412534 -391.999497)
					(end 283.070046 -390.27735)
				)
				(arc
					(start 283.070046 -381.812546)
					(mid 283.412578 -380.090523)
					(end 284.388052 -378.630688)
				)
				(arc
					(start 298.33062 -364.68812)
					(mid 299.790585 -363.712602)
					(end 301.512732 -363.370114)
				)
				(arc
					(start 426.257466 -363.370114)
					(mid 427.979489 -363.712646)
					(end 429.439324 -364.68812)
				)
				(arc
					(start 440.182 -375.430542)
					(mid 441.157518 -376.890507)
					(end 441.500006 -378.612654)
				)
				(arc
					(start 441.500006 -398.150334)
					(mid 441.43402 -398.918399)
					(end 441.237878 -399.66392)
				)
				(arc
					(start 434.623718 -418.183568)
					(mid 432.978035 -420.348493)
					(end 430.385728 -421.1701)
				)
				(arc
					(start 426.257466 -421.1701)
					(mid 424.535345 -420.827549)
					(end 423.075354 -419.852094)
				)
				(arc
					(start 419.582854 -416.35934)
					(mid 419.096199 -416.034167)
					(end 418.52215 -415.91992)
				)
			)
		)
	)
	(zone
		(layer "B.Cu")
		(hatch none 0.5)
		(connect_pads
			(clearance 0)
		)
		(min_thickness 0.25)
		(keepout
			(tracks not_allowed)
			(vias allowed)
			(pads allowed)
			(copperpour not_allowed)
			(footprints allowed)
		)
		(placement
			(enabled no)
			(sheetname "")
		)
		(fill
			(thermal_gap 0.5)
			(thermal_bridge_width 0.5)
			(island_removal_mode 0)
		)
		(polygon
			(pts
				(arc
					(start 325.769986 -212.989922)
					(mid 329.270106 -216.490042)
					(end 332.769972 -212.989922)
				)
				(arc
					(start 332.769972 -212.989922)
					(mid 329.270106 -209.490056)
					(end 325.769986 -212.989922)
				)
			)
		)
	)
	(zone
		(layer "B.Cu")
		(hatch none 0.5)
		(connect_pads
			(clearance 0)
		)
		(min_thickness 0.25)
		(keepout
			(tracks not_allowed)
			(vias allowed)
			(pads allowed)
			(copperpour not_allowed)
			(footprints allowed)
		)
		(placement
			(enabled no)
			(sheetname "")
		)
		(fill
			(thermal_gap 0.5)
			(thermal_bridge_width 0.5)
			(island_removal_mode 0)
		)
		(polygon
			(pts
				(arc
					(start 153.137108 -439.0898)
					(mid 152.362916 -439.0898)
					(end 153.137108 -439.0898)
				)
			)
		)
	)
	(zone
		(layer "B.Cu")
		(hatch none 0.5)
		(connect_pads
			(clearance 0)
		)
		(min_thickness 0.25)
		(keepout
			(tracks not_allowed)
			(vias allowed)
			(pads allowed)
			(copperpour not_allowed)
			(footprints allowed)
		)
		(placement
			(enabled no)
			(sheetname "")
		)
		(fill
			(thermal_gap 0.5)
			(thermal_bridge_width 0.5)
			(island_removal_mode 0)
		)
		(polygon
			(pts
				(arc
					(start 143.137128 -438.089802)
					(mid 142.362936 -438.089802)
					(end 143.137128 -438.089802)
				)
			)
		)
	)
	(zone
		(layer "B.Cu")
		(hatch none 0.5)
		(connect_pads
			(clearance 0)
		)
		(min_thickness 0.25)
		(keepout
			(tracks not_allowed)
			(vias allowed)
			(pads allowed)
			(copperpour not_allowed)
			(footprints allowed)
		)
		(placement
			(enabled no)
			(sheetname "")
		)
		(fill
			(thermal_gap 0.5)
			(thermal_bridge_width 0.5)
			(island_removal_mode 0)
		)
		(polygon
			(pts
				(arc
					(start 354.39604 -246.104156)
					(mid 353.76612 -246.104156)
					(end 354.39604 -246.104156)
				)
			)
		)
	)
	(zone
		(layer "B.Cu")
		(hatch none 0.5)
		(connect_pads
			(clearance 0)
		)
		(min_thickness 0.25)
		(keepout
			(tracks allowed)
			(vias allowed)
			(pads allowed)
			(copperpour allowed)
			(footprints allowed)
		)
		(placement
			(enabled no)
			(sheetname "")
		)
		(fill
			(thermal_gap 0.5)
			(thermal_bridge_width 0.5)
			(island_removal_mode 0)
		)
		(polygon
			(pts
				(xy 300.68266 -194.6021) (xy 300.68266 -190.68288) (xy 302.63084 -190.68288) (xy 302.63084 -194.6021)
			)
		)
	)
	(zone
		(layer "B.Cu")
		(hatch none 0.5)
		(connect_pads
			(clearance 0)
		)
		(min_thickness 0.25)
		(keepout
			(tracks not_allowed)
			(vias allowed)
			(pads allowed)
			(copperpour not_allowed)
			(footprints allowed)
		)
		(placement
			(enabled no)
			(sheetname "")
		)
		(fill
			(thermal_gap 0.5)
			(thermal_bridge_width 0.5)
			(island_removal_mode 0)
		)
		(polygon
			(pts
				(arc
					(start 410.97835 -401.674838)
					(mid 410.31033 -401.674838)
					(end 410.97835 -401.674838)
				)
			)
		)
	)
	(zone
		(layer "B.Cu")
		(hatch none 0.5)
		(connect_pads
			(clearance 0)
		)
		(min_thickness 0.25)
		(keepout
			(tracks not_allowed)
			(vias allowed)
			(pads allowed)
			(copperpour not_allowed)
			(footprints allowed)
		)
		(placement
			(enabled no)
			(sheetname "")
		)
		(fill
			(thermal_gap 0.5)
			(thermal_bridge_width 0.5)
			(island_removal_mode 0)
		)
		(polygon
			(pts
				(arc
					(start 256.261108 -202.662536)
					(mid 255.593088 -202.662536)
					(end 256.261108 -202.662536)
				)
			)
		)
	)
	(zone
		(layer "B.Cu")
		(hatch none 0.5)
		(connect_pads
			(clearance 0)
		)
		(min_thickness 0.25)
		(keepout
			(tracks allowed)
			(vias allowed)
			(pads allowed)
			(copperpour allowed)
			(footprints allowed)
		)
		(placement
			(enabled no)
			(sheetname "")
		)
		(fill
			(thermal_gap 0.5)
			(thermal_bridge_width 0.5)
			(island_removal_mode 0)
		)
		(polygon
			(pts
				(xy 305.05908 -417.428426) (xy 305.05908 -416.42411) (xy 306.436014 -416.42411) (xy 306.436014 -417.428426)
			)
		)
	)
	(zone
		(layer "B.Cu")
		(hatch none 0.5)
		(connect_pads
			(clearance 0)
		)
		(min_thickness 0.25)
		(keepout
			(tracks allowed)
			(vias allowed)
			(pads allowed)
			(copperpour allowed)
			(footprints not_allowed)
		)
		(placement
			(enabled no)
			(sheetname "")
		)
		(fill
			(thermal_gap 0.5)
			(thermal_bridge_width 0.5)
			(island_removal_mode 0)
		)
		(polygon
			(pts
				(arc
					(start 15.80007 -435.600094)
					(mid 12.999974 -432.799998)
					(end 10.199878 -435.600094)
				)
				(arc
					(start 10.199878 -435.600094)
					(mid 12.999974 -438.40019)
					(end 15.80007 -435.600094)
				)
			)
		)
	)
	(zone
		(layer "B.Cu")
		(hatch none 0.5)
		(connect_pads
			(clearance 0)
		)
		(min_thickness 0.25)
		(keepout
			(tracks not_allowed)
			(vias allowed)
			(pads allowed)
			(copperpour not_allowed)
			(footprints allowed)
		)
		(placement
			(enabled no)
			(sheetname "")
		)
		(fill
			(thermal_gap 0.5)
			(thermal_bridge_width 0.5)
			(island_removal_mode 0)
		)
		(polygon
			(pts
				(arc
					(start 325.769986 -304.790094)
					(mid 329.270106 -308.290214)
					(end 332.769972 -304.790094)
				)
				(arc
					(start 332.769972 -304.790094)
					(mid 329.270106 -301.290228)
					(end 325.769986 -304.790094)
				)
			)
		)
	)
	(zone
		(layer "B.Cu")
		(hatch none 0.5)
		(connect_pads
			(clearance 0)
		)
		(min_thickness 0.25)
		(keepout
			(tracks allowed)
			(vias allowed)
			(pads allowed)
			(copperpour allowed)
			(footprints not_allowed)
		)
		(placement
			(enabled no)
			(sheetname "")
		)
		(fill
			(thermal_gap 0.5)
			(thermal_bridge_width 0.5)
			(island_removal_mode 0)
		)
		(polygon
			(pts
				(arc
					(start 185.50001 -370.232686)
					(mid 185.157459 -368.510565)
					(end 184.182004 -367.050574)
				)
				(arc
					(start 173.439328 -356.307898)
					(mid 171.979479 -355.332458)
					(end 170.25747 -354.989892)
				)
				(arc
					(start 45.512736 -354.989892)
					(mid 43.790615 -355.332443)
					(end 42.330624 -356.307898)
				)
				(arc
					(start 28.388056 -370.25072)
					(mid 27.412616 -371.710569)
					(end 27.07005 -373.432578)
				)
				(arc
					(start 27.07005 -381.897382)
					(mid 27.412582 -383.619405)
					(end 28.388056 -385.07924)
				)
				(arc
					(start 28.980638 -385.672076)
					(mid 29.305816 -386.1586)
					(end 29.420058 -386.732526)
				)
				(arc
					(start 29.420058 -399.272506)
					(mid 29.487404 -400.048408)
					(end 29.68752 -400.801078)
				)
				(arc
					(start 32.9438 -409.818332)
					(mid 34.590499 -411.972828)
					(end 37.176202 -412.789878)
				)
				(arc
					(start 42.31259 -412.789878)
					(mid 44.034711 -412.447327)
					(end 45.494702 -411.471872)
				)
				(arc
					(start 48.987202 -407.979372)
					(mid 49.473857 -407.654199)
					(end 50.047906 -407.539952)
				)
				(arc
					(start 162.522154 -407.539952)
					(mid 163.096227 -407.654142)
					(end 163.582858 -407.979372)
				)
				(arc
					(start 167.075358 -411.471872)
					(mid 168.535323 -412.44739)
					(end 170.25747 -412.789878)
				)
				(arc
					(start 174.385732 -412.789878)
					(mid 176.978028 -411.968398)
					(end 178.623722 -409.8036)
				)
				(arc
					(start 185.237882 -391.283952)
					(mid 185.433988 -390.538425)
					(end 185.50001 -389.770366)
				)
			)
		)
	)
	(zone
		(layer "B.Cu")
		(hatch none 0.5)
		(connect_pads
			(clearance 0)
		)
		(min_thickness 0.25)
		(keepout
			(tracks not_allowed)
			(vias allowed)
			(pads allowed)
			(copperpour not_allowed)
			(footprints allowed)
		)
		(placement
			(enabled no)
			(sheetname "")
		)
		(fill
			(thermal_gap 0.5)
			(thermal_bridge_width 0.5)
			(island_removal_mode 0)
		)
		(polygon
			(pts
				(arc
					(start 319.0367 -436.889906)
					(mid 318.262508 -436.889906)
					(end 319.0367 -436.889906)
				)
			)
		)
	)
	(zone
		(layer "B.Cu")
		(hatch none 0.5)
		(connect_pads
			(clearance 0)
		)
		(min_thickness 0.25)
		(keepout
			(tracks allowed)
			(vias allowed)
			(pads allowed)
			(copperpour allowed)
			(footprints allowed)
		)
		(placement
			(enabled no)
			(sheetname "")
		)
		(fill
			(thermal_gap 0.5)
			(thermal_bridge_width 0.5)
			(island_removal_mode 0)
		)
		(polygon
			(pts
				(xy 251.44857 -394.410438) (xy 251.44857 -393.406122) (xy 252.825504 -393.406122) (xy 252.825504 -394.410438)
			)
		)
	)
	(zone
		(layer "B.Cu")
		(hatch none 0.5)
		(connect_pads
			(clearance 0)
		)
		(min_thickness 0.25)
		(keepout
			(tracks allowed)
			(vias allowed)
			(pads allowed)
			(copperpour allowed)
			(footprints allowed)
		)
		(placement
			(enabled no)
			(sheetname "")
		)
		(fill
			(thermal_gap 0.5)
			(thermal_bridge_width 0.5)
			(island_removal_mode 0)
		)
		(polygon
			(pts
				(xy 263.65454 -194.03568) (xy 263.65454 -190.5508) (xy 265.34618 -190.5508) (xy 265.34618 -194.03568)
			)
		)
	)
	(zone
		(layer "B.Cu")
		(hatch none 0.5)
		(connect_pads
			(clearance 0)
		)
		(min_thickness 0.25)
		(keepout
			(tracks allowed)
			(vias allowed)
			(pads allowed)
			(copperpour allowed)
			(footprints allowed)
		)
		(placement
			(enabled no)
			(sheetname "")
		)
		(fill
			(thermal_gap 0.5)
			(thermal_bridge_width 0.5)
			(island_removal_mode 0)
		)
		(polygon
			(pts
				(xy 259.524246 -394.410184) (xy 259.524246 -393.405868) (xy 260.90118 -393.405868) (xy 260.90118 -394.410184)
			)
		)
	)
	(zone
		(layer "B.Cu")
		(hatch none 0.5)
		(connect_pads
			(clearance 0)
		)
		(min_thickness 0.25)
		(keepout
			(tracks not_allowed)
			(vias allowed)
			(pads allowed)
			(copperpour not_allowed)
			(footprints allowed)
		)
		(placement
			(enabled no)
			(sheetname "")
		)
		(fill
			(thermal_gap 0.5)
			(thermal_bridge_width 0.5)
			(island_removal_mode 0)
		)
		(polygon
			(pts
				(arc
					(start 86.037166 -439.0898)
					(mid 85.262974 -439.0898)
					(end 86.037166 -439.0898)
				)
			)
		)
	)
	(zone
		(layer "B.Cu")
		(hatch none 0.5)
		(connect_pads
			(clearance 0)
		)
		(min_thickness 0.25)
		(keepout
			(tracks not_allowed)
			(vias allowed)
			(pads allowed)
			(copperpour not_allowed)
			(footprints allowed)
		)
		(placement
			(enabled no)
			(sheetname "")
		)
		(fill
			(thermal_gap 0.5)
			(thermal_bridge_width 0.5)
			(island_removal_mode 0)
		)
		(polygon
			(pts
				(arc
					(start 156.17825 -393.292838)
					(mid 155.51023 -393.292838)
					(end 156.17825 -393.292838)
				)
			)
		)
	)
	(zone
		(layer "B.Cu")
		(hatch none 0.5)
		(connect_pads
			(clearance 0)
		)
		(min_thickness 0.25)
		(keepout
			(tracks allowed)
			(vias allowed)
			(pads allowed)
			(copperpour allowed)
			(footprints allowed)
		)
		(placement
			(enabled no)
			(sheetname "")
		)
		(fill
			(thermal_gap 0.5)
			(thermal_bridge_width 0.5)
			(island_removal_mode 0)
		)
		(polygon
			(pts
				(xy 283.962856 -348.970092) (xy 283.962856 -351.129092) (xy 283.581856 -351.510092) (xy 280.787856 -351.510092)
				(xy 279.644856 -350.367092) (xy 279.644856 -347.446092) (xy 280.152856 -346.938092) (xy 281.930856 -346.938092)
			)
		)
	)
	(zone
		(layer "B.Cu")
		(hatch none 0.5)
		(connect_pads
			(clearance 0)
		)
		(min_thickness 0.25)
		(keepout
			(tracks allowed)
			(vias allowed)
			(pads allowed)
			(copperpour allowed)
			(footprints allowed)
		)
		(placement
			(enabled no)
			(sheetname "")
		)
		(fill
			(thermal_gap 0.5)
			(thermal_bridge_width 0.5)
			(island_removal_mode 0)
		)
		(polygon
			(pts
				(xy 159.04464 -409.046426) (xy 159.04464 -408.04211) (xy 160.421574 -408.04211) (xy 160.421574 -409.046426)
			)
		)
	)
	(zone
		(layer "B.Cu")
		(hatch none 0.5)
		(connect_pads
			(clearance 0)
		)
		(min_thickness 0.25)
		(keepout
			(tracks not_allowed)
			(vias allowed)
			(pads allowed)
			(copperpour not_allowed)
			(footprints allowed)
		)
		(placement
			(enabled no)
			(sheetname "")
		)
		(fill
			(thermal_gap 0.5)
			(thermal_bridge_width 0.5)
			(island_removal_mode 0)
		)
		(polygon
			(pts
				(arc
					(start 410.852112 -351.415096)
					(mid 413.952182 -354.515166)
					(end 417.051998 -351.415096)
				)
				(arc
					(start 417.051998 -351.415096)
					(mid 413.952182 -348.31528)
					(end 410.852112 -351.415096)
				)
			)
		)
	)
	(zone
		(layer "B.Cu")
		(hatch none 0.5)
		(connect_pads
			(clearance 0)
		)
		(min_thickness 0.25)
		(keepout
			(tracks not_allowed)
			(vias allowed)
			(pads allowed)
			(copperpour not_allowed)
			(footprints allowed)
		)
		(placement
			(enabled no)
			(sheetname "")
		)
		(fill
			(thermal_gap 0.5)
			(thermal_bridge_width 0.5)
			(island_removal_mode 0)
		)
		(polygon
			(pts
				(arc
					(start 394.13688 -438.089802)
					(mid 393.362688 -438.089802)
					(end 394.13688 -438.089802)
				)
			)
		)
	)
	(zone
		(layer "B.Cu")
		(hatch none 0.5)
		(connect_pads
			(clearance 0)
		)
		(min_thickness 0.25)
		(keepout
			(tracks allowed)
			(vias allowed)
			(pads allowed)
			(copperpour allowed)
			(footprints allowed)
		)
		(placement
			(enabled no)
			(sheetname "")
		)
		(fill
			(thermal_gap 0.5)
			(thermal_bridge_width 0.5)
			(island_removal_mode 0)
		)
		(polygon
			(pts
				(xy 307.50002 -194.20332) (xy 307.50002 -192.3669) (xy 308.96052 -192.3669) (xy 308.96052 -194.20332)
			)
		)
	)
	(zone
		(layer "B.Cu")
		(hatch none 0.5)
		(connect_pads
			(clearance 0)
		)
		(min_thickness 0.25)
		(keepout
			(tracks not_allowed)
			(vias allowed)
			(pads allowed)
			(copperpour not_allowed)
			(footprints allowed)
		)
		(placement
			(enabled no)
			(sheetname "")
		)
		(fill
			(thermal_gap 0.5)
			(thermal_bridge_width 0.5)
			(island_removal_mode 0)
		)
		(polygon
			(pts
				(arc
					(start 315.305948 -394.385292)
					(mid 314.676028 -394.385292)
					(end 315.305948 -394.385292)
				)
			)
		)
	)
	(zone
		(layer "B.Cu")
		(hatch none 0.5)
		(connect_pads
			(clearance 0)
		)
		(min_thickness 0.25)
		(keepout
			(tracks not_allowed)
			(vias allowed)
			(pads allowed)
			(copperpour not_allowed)
			(footprints allowed)
		)
		(placement
			(enabled no)
			(sheetname "")
		)
		(fill
			(thermal_gap 0.5)
			(thermal_bridge_width 0.5)
			(island_removal_mode 0)
		)
		(polygon
			(pts
				(arc
					(start 344.036904 -438.089802)
					(mid 343.262712 -438.089802)
					(end 344.036904 -438.089802)
				)
			)
		)
	)
	(zone
		(layer "B.Cu")
		(hatch none 0.5)
		(connect_pads
			(clearance 0)
		)
		(min_thickness 0.25)
		(keepout
			(tracks allowed)
			(vias allowed)
			(pads allowed)
			(copperpour allowed)
			(footprints allowed)
		)
		(placement
			(enabled no)
			(sheetname "")
		)
		(fill
			(thermal_gap 0.5)
			(thermal_bridge_width 0.5)
			(island_removal_mode 0)
		)
		(polygon
			(pts
				(xy 190.2206 -126.31928) (xy 190.2206 -125.3617) (xy 191.7446 -125.3617) (xy 191.7446 -126.31928)
			)
		)
	)
	(zone
		(layer "B.Cu")
		(hatch none 0.5)
		(connect_pads
			(clearance 0)
		)
		(min_thickness 0.25)
		(keepout
			(tracks allowed)
			(vias allowed)
			(pads allowed)
			(copperpour allowed)
			(footprints allowed)
		)
		(placement
			(enabled no)
			(sheetname "")
		)
		(fill
			(thermal_gap 0.5)
			(thermal_bridge_width 0.5)
			(island_removal_mode 0)
		)
		(polygon
			(pts
				(xy 143.72844 -409.046426) (xy 143.72844 -408.04211) (xy 145.105374 -408.04211) (xy 145.105374 -409.046426)
			)
		)
	)
	(zone
		(layer "B.Cu")
		(hatch none 0.5)
		(connect_pads
			(clearance 0)
		)
		(min_thickness 0.25)
		(keepout
			(tracks not_allowed)
			(vias allowed)
			(pads allowed)
			(copperpour not_allowed)
			(footprints allowed)
		)
		(placement
			(enabled no)
			(sheetname "")
		)
		(fill
			(thermal_gap 0.5)
			(thermal_bridge_width 0.5)
			(island_removal_mode 0)
		)
		(polygon
			(pts
				(arc
					(start 143.137128 -436.889906)
					(mid 142.362936 -436.889906)
					(end 143.137128 -436.889906)
				)
			)
		)
	)
	(zone
		(layer "B.Cu")
		(hatch none 0.5)
		(connect_pads
			(clearance 0)
		)
		(min_thickness 0.25)
		(keepout
			(tracks not_allowed)
			(vias allowed)
			(pads allowed)
			(copperpour not_allowed)
			(footprints allowed)
		)
		(placement
			(enabled no)
			(sheetname "")
		)
		(fill
			(thermal_gap 0.5)
			(thermal_bridge_width 0.5)
			(island_removal_mode 0)
		)
		(polygon
			(pts
				(arc
					(start 355.336094 -244.484144)
					(mid 354.706174 -244.484144)
					(end 355.336094 -244.484144)
				)
			)
		)
	)
	(zone
		(layer "B.Cu")
		(hatch none 0.5)
		(connect_pads
			(clearance 0)
		)
		(min_thickness 0.25)
		(keepout
			(tracks not_allowed)
			(vias allowed)
			(pads allowed)
			(copperpour not_allowed)
			(footprints allowed)
		)
		(placement
			(enabled no)
			(sheetname "")
		)
		(fill
			(thermal_gap 0.5)
			(thermal_bridge_width 0.5)
			(island_removal_mode 0)
		)
		(polygon
			(pts
				(arc
					(start 311.350406 -401.674838)
					(mid 310.682386 -401.674838)
					(end 311.350406 -401.674838)
				)
			)
		)
	)
	(zone
		(layer "B.Cu")
		(hatch none 0.5)
		(connect_pads
			(clearance 0)
		)
		(min_thickness 0.25)
		(keepout
			(tracks allowed)
			(vias allowed)
			(pads allowed)
			(copperpour allowed)
			(footprints not_allowed)
		)
		(placement
			(enabled no)
			(sheetname "")
		)
		(fill
			(thermal_gap 0.5)
			(thermal_bridge_width 0.5)
			(island_removal_mode 0)
		)
		(polygon
			(pts
				(arc
					(start 202.95108 -351.825052)
					(mid 201.086212 -349.960184)
					(end 199.22109 -351.825052)
				)
				(arc
					(start 199.22109 -351.825052)
					(mid 201.086212 -353.690174)
					(end 202.95108 -351.825052)
				)
			)
		)
	)
	(zone
		(layer "B.Cu")
		(hatch none 0.5)
		(connect_pads
			(clearance 0)
		)
		(min_thickness 0.25)
		(keepout
			(tracks allowed)
			(vias allowed)
			(pads allowed)
			(copperpour allowed)
			(footprints not_allowed)
		)
		(placement
			(enabled no)
			(sheetname "")
		)
		(fill
			(thermal_gap 0.5)
			(thermal_bridge_width 0.5)
			(island_removal_mode 0)
		)
		(polygon
			(pts
				(arc
					(start 172.900086 -160.50006)
					(mid 167.900096 -155.50007)
					(end 162.900106 -160.50006)
				)
				(arc
					(start 162.900106 -160.50006)
					(mid 167.900096 -165.50005)
					(end 172.900086 -160.50006)
				)
			)
		)
	)
	(zone
		(layer "B.Cu")
		(hatch none 0.5)
		(connect_pads
			(clearance 0)
		)
		(min_thickness 0.25)
		(keepout
			(tracks not_allowed)
			(vias allowed)
			(pads allowed)
			(copperpour not_allowed)
			(footprints allowed)
		)
		(placement
			(enabled no)
			(sheetname "")
		)
		(fill
			(thermal_gap 0.5)
			(thermal_bridge_width 0.5)
			(island_removal_mode 0)
		)
		(polygon
			(pts
				(arc
					(start 329.03668 -437.889904)
					(mid 328.262488 -437.889904)
					(end 329.03668 -437.889904)
				)
			)
		)
	)
	(zone
		(layer "B.Cu")
		(hatch none 0.5)
		(connect_pads
			(clearance 0)
		)
		(min_thickness 0.25)
		(keepout
			(tracks allowed)
			(vias allowed)
			(pads allowed)
			(copperpour allowed)
			(footprints allowed)
		)
		(placement
			(enabled no)
			(sheetname "")
		)
		(fill
			(thermal_gap 0.5)
			(thermal_bridge_width 0.5)
			(island_removal_mode 0)
		)
		(polygon
			(pts
				(xy 183.484774 -99.542092) (xy 183.484774 -99.002342) (xy 184.486296 -99.002342) (xy 184.486296 -99.542092)
			)
		)
	)
	(zone
		(layer "B.Cu")
		(hatch none 0.5)
		(connect_pads
			(clearance 0)
		)
		(min_thickness 0.25)
		(keepout
			(tracks allowed)
			(vias allowed)
			(pads allowed)
			(copperpour allowed)
			(footprints allowed)
		)
		(placement
			(enabled no)
			(sheetname "")
		)
		(fill
			(thermal_gap 0.5)
			(thermal_bridge_width 0.5)
			(island_removal_mode 0)
		)
		(polygon
			(pts
				(xy 15.3924 -109.347) (xy 15.3924 -108.5088) (xy 16.7894 -108.5088) (xy 16.7894 -109.347)
			)
		)
	)
	(zone
		(layer "B.Cu")
		(hatch none 0.5)
		(connect_pads
			(clearance 0)
		)
		(min_thickness 0.25)
		(keepout
			(tracks not_allowed)
			(vias allowed)
			(pads allowed)
			(copperpour not_allowed)
			(footprints allowed)
		)
		(placement
			(enabled no)
			(sheetname "")
		)
		(fill
			(thermal_gap 0.5)
			(thermal_bridge_width 0.5)
			(island_removal_mode 0)
		)
		(polygon
			(pts
				(arc
					(start 355.636068 -271.656048)
					(mid 355.006148 -271.656048)
					(end 355.636068 -271.656048)
				)
			)
		)
	)
	(zone
		(layer "B.Cu")
		(hatch none 0.5)
		(connect_pads
			(clearance 0)
		)
		(min_thickness 0.25)
		(keepout
			(tracks allowed)
			(vias allowed)
			(pads allowed)
			(copperpour allowed)
			(footprints allowed)
		)
		(placement
			(enabled no)
			(sheetname "")
		)
		(fill
			(thermal_gap 0.5)
			(thermal_bridge_width 0.5)
			(island_removal_mode 0)
		)
		(polygon
			(pts
				(xy 259.52196 -3.13944) (xy 259.52196 -1.33604) (xy 261.57174 -1.33604) (xy 261.57174 -3.13944)
			)
		)
	)
	(zone
		(layer "B.Cu")
		(hatch none 0.5)
		(connect_pads
			(clearance 0)
		)
		(min_thickness 0.25)
		(keepout
			(tracks allowed)
			(vias allowed)
			(pads allowed)
			(copperpour allowed)
			(footprints allowed)
		)
		(placement
			(enabled no)
			(sheetname "")
		)
		(fill
			(thermal_gap 0.5)
			(thermal_bridge_width 0.5)
			(island_removal_mode 0)
		)
		(polygon
			(pts
				(xy 85.818218 -409.046426) (xy 85.818218 -408.04211) (xy 87.195152 -408.04211) (xy 87.195152 -409.046426)
			)
		)
	)
	(zone
		(layer "B.Cu")
		(hatch none 0.5)
		(connect_pads
			(clearance 0)
		)
		(min_thickness 0.25)
		(keepout
			(tracks allowed)
			(vias allowed)
			(pads allowed)
			(copperpour allowed)
			(footprints not_allowed)
		)
		(placement
			(enabled no)
			(sheetname "")
		)
		(fill
			(thermal_gap 0.5)
			(thermal_bridge_width 0.5)
			(island_removal_mode 0)
		)
		(polygon
			(pts
				(arc
					(start 7.999984 -435.600094)
					(mid 12.999974 -440.600084)
					(end 17.999964 -435.600094)
				)
				(arc
					(start 17.999964 -435.600094)
					(mid 12.999974 -430.600104)
					(end 7.999984 -435.600094)
				)
			)
		)
	)
	(zone
		(layer "B.Cu")
		(hatch none 0.5)
		(connect_pads
			(clearance 0)
		)
		(min_thickness 0.25)
		(keepout
			(tracks allowed)
			(vias allowed)
			(pads allowed)
			(copperpour allowed)
			(footprints not_allowed)
		)
		(placement
			(enabled no)
			(sheetname "")
		)
		(fill
			(thermal_gap 0.5)
			(thermal_bridge_width 0.5)
			(island_removal_mode 0)
		)
		(polygon
			(pts
				(arc
					(start 260.649974 -22.29993)
					(mid 265.649964 -27.29992)
					(end 270.649954 -22.29993)
				)
				(arc
					(start 270.649954 -22.29993)
					(mid 265.649964 -17.29994)
					(end 260.649974 -22.29993)
				)
			)
		)
	)
	(zone
		(layer "B.Cu")
		(hatch none 0.5)
		(connect_pads
			(clearance 0)
		)
		(min_thickness 0.25)
		(keepout
			(tracks not_allowed)
			(vias allowed)
			(pads allowed)
			(copperpour not_allowed)
			(footprints allowed)
		)
		(placement
			(enabled no)
			(sheetname "")
		)
		(fill
			(thermal_gap 0.5)
			(thermal_bridge_width 0.5)
			(island_removal_mode 0)
		)
		(polygon
			(pts
				(arc
					(start 10.728198 -420.336726)
					(mid 10.060178 -420.336726)
					(end 10.728198 -420.336726)
				)
			)
		)
	)
	(zone
		(layer "B.Cu")
		(hatch none 0.5)
		(connect_pads
			(clearance 0)
		)
		(min_thickness 0.25)
		(keepout
			(tracks allowed)
			(vias allowed)
			(pads allowed)
			(copperpour allowed)
			(footprints not_allowed)
		)
		(placement
			(enabled no)
			(sheetname "")
		)
		(fill
			(thermal_gap 0.5)
			(thermal_bridge_width 0.5)
			(island_removal_mode 0)
		)
		(polygon
			(pts
				(arc
					(start 290.402518 -153.766012)
					(mid 277.90267 -141.266164)
					(end 265.402568 -153.766012)
				)
				(arc
					(start 265.402568 -153.766012)
					(mid 277.90267 -166.266114)
					(end 290.402518 -153.766012)
				)
			)
		)
	)
	(zone
		(layer "B.Cu")
		(hatch none 0.5)
		(connect_pads
			(clearance 0)
		)
		(min_thickness 0.25)
		(keepout
			(tracks not_allowed)
			(vias allowed)
			(pads allowed)
			(copperpour not_allowed)
			(footprints allowed)
		)
		(placement
			(enabled no)
			(sheetname "")
		)
		(fill
			(thermal_gap 0.5)
			(thermal_bridge_width 0.5)
			(island_removal_mode 0)
		)
		(polygon
			(pts
				(arc
					(start 246.800116 -290.900104)
					(mid 249.900186 -294.000174)
					(end 253.000002 -290.900104)
				)
				(arc
					(start 253.000002 -290.900104)
					(mid 249.900186 -287.800288)
					(end 246.800116 -290.900104)
				)
			)
		)
	)
	(zone
		(layer "B.Cu")
		(hatch none 0.5)
		(connect_pads
			(clearance 0)
		)
		(min_thickness 0.25)
		(keepout
			(tracks not_allowed)
			(vias allowed)
			(pads allowed)
			(copperpour not_allowed)
			(footprints allowed)
		)
		(placement
			(enabled no)
			(sheetname "")
		)
		(fill
			(thermal_gap 0.5)
			(thermal_bridge_width 0.5)
			(island_removal_mode 0)
		)
		(polygon
			(pts
				(arc
					(start 62.782958 -45.449998)
					(mid 61.183012 -47.049944)
					(end 62.782958 -48.64989)
				)
				(arc
					(start 64.382904 -48.64989)
					(mid 65.98285 -47.049944)
					(end 64.382904 -45.449998)
				)
			)
		)
	)
	(zone
		(layer "B.Cu")
		(hatch none 0.5)
		(connect_pads
			(clearance 0)
		)
		(min_thickness 0.25)
		(keepout
			(tracks not_allowed)
			(vias allowed)
			(pads allowed)
			(copperpour not_allowed)
			(footprints allowed)
		)
		(placement
			(enabled no)
			(sheetname "")
		)
		(fill
			(thermal_gap 0.5)
			(thermal_bridge_width 0.5)
			(island_removal_mode 0)
		)
		(polygon
			(pts
				(arc
					(start 110.046008 -269.226284)
					(mid 109.416088 -269.226284)
					(end 110.046008 -269.226284)
				)
			)
		)
	)
	(zone
		(layer "B.Cu")
		(hatch none 0.5)
		(connect_pads
			(clearance 0)
		)
		(min_thickness 0.25)
		(keepout
			(tracks not_allowed)
			(vias allowed)
			(pads allowed)
			(copperpour not_allowed)
			(footprints allowed)
		)
		(placement
			(enabled no)
			(sheetname "")
		)
		(fill
			(thermal_gap 0.5)
			(thermal_bridge_width 0.5)
			(island_removal_mode 0)
		)
		(polygon
			(pts
				(arc
					(start 141.348714 -18.144744)
					(mid 140.680694 -18.144744)
					(end 141.348714 -18.144744)
				)
			)
		)
	)
	(zone
		(layer "B.Cu")
		(hatch none 0.5)
		(connect_pads
			(clearance 0)
		)
		(min_thickness 0.25)
		(keepout
			(tracks not_allowed)
			(vias allowed)
			(pads allowed)
			(copperpour not_allowed)
			(footprints allowed)
		)
		(placement
			(enabled no)
			(sheetname "")
		)
		(fill
			(thermal_gap 0.5)
			(thermal_bridge_width 0.5)
			(island_removal_mode 0)
		)
		(polygon
			(pts
				(arc
					(start 147.13712 -438.089802)
					(mid 146.362928 -438.089802)
					(end 147.13712 -438.089802)
				)
			)
		)
	)
	(zone
		(layer "B.Cu")
		(hatch none 0.5)
		(connect_pads
			(clearance 0)
		)
		(min_thickness 0.25)
		(keepout
			(tracks not_allowed)
			(vias allowed)
			(pads allowed)
			(copperpour not_allowed)
			(footprints allowed)
		)
		(placement
			(enabled no)
			(sheetname "")
		)
		(fill
			(thermal_gap 0.5)
			(thermal_bridge_width 0.5)
			(island_removal_mode 0)
		)
		(polygon
			(pts
				(arc
					(start 316.150498 -401.674838)
					(mid 315.482478 -401.674838)
					(end 316.150498 -401.674838)
				)
			)
		)
	)
	(zone
		(layer "B.Cu")
		(hatch none 0.5)
		(connect_pads
			(clearance 0)
		)
		(min_thickness 0.25)
		(keepout
			(tracks not_allowed)
			(vias allowed)
			(pads allowed)
			(copperpour not_allowed)
			(footprints allowed)
		)
		(placement
			(enabled no)
			(sheetname "")
		)
		(fill
			(thermal_gap 0.5)
			(thermal_bridge_width 0.5)
			(island_removal_mode 0)
		)
		(polygon
			(pts
				(arc
					(start 49.350422 -393.292838)
					(mid 48.682402 -393.292838)
					(end 49.350422 -393.292838)
				)
			)
		)
	)
	(zone
		(layer "B.Cu")
		(hatch none 0.5)
		(connect_pads
			(clearance 0)
		)
		(min_thickness 0.25)
		(keepout
			(tracks allowed)
			(vias allowed)
			(pads allowed)
			(copperpour allowed)
			(footprints allowed)
		)
		(placement
			(enabled no)
			(sheetname "")
		)
		(fill
			(thermal_gap 0.5)
			(thermal_bridge_width 0.5)
			(island_removal_mode 0)
		)
		(polygon
			(pts
				(xy 175.276256 -97.395538) (xy 175.276256 -96.822514) (xy 176.976278 -96.822514) (xy 176.976278 -97.395538)
			)
		)
	)
	(zone
		(layer "B.Cu")
		(hatch none 0.5)
		(connect_pads
			(clearance 0)
		)
		(min_thickness 0.25)
		(keepout
			(tracks not_allowed)
			(vias allowed)
			(pads allowed)
			(copperpour not_allowed)
			(footprints allowed)
		)
		(placement
			(enabled no)
			(sheetname "")
		)
		(fill
			(thermal_gap 0.5)
			(thermal_bridge_width 0.5)
			(island_removal_mode 0)
		)
		(polygon
			(pts
				(arc
					(start 416.978338 -401.674838)
					(mid 416.310318 -401.674838)
					(end 416.978338 -401.674838)
				)
			)
		)
	)
	(zone
		(layer "B.Cu")
		(hatch none 0.5)
		(connect_pads
			(clearance 0)
		)
		(min_thickness 0.25)
		(keepout
			(tracks not_allowed)
			(vias allowed)
			(pads allowed)
			(copperpour not_allowed)
			(footprints allowed)
		)
		(placement
			(enabled no)
			(sheetname "")
		)
		(fill
			(thermal_gap 0.5)
			(thermal_bridge_width 0.5)
			(island_removal_mode 0)
		)
		(polygon
			(pts
				(arc
					(start 346.0369 -437.889904)
					(mid 345.262708 -437.889904)
					(end 346.0369 -437.889904)
				)
			)
		)
	)
	(zone
		(layer "B.Cu")
		(hatch none 0.5)
		(connect_pads
			(clearance 0)
		)
		(min_thickness 0.25)
		(keepout
			(tracks not_allowed)
			(vias allowed)
			(pads allowed)
			(copperpour not_allowed)
			(footprints allowed)
		)
		(placement
			(enabled no)
			(sheetname "")
		)
		(fill
			(thermal_gap 0.5)
			(thermal_bridge_width 0.5)
			(island_removal_mode 0)
		)
		(polygon
			(pts
				(arc
					(start 107.696 -271.656302)
					(mid 107.06608 -271.656302)
					(end 107.696 -271.656302)
				)
			)
		)
	)
	(zone
		(layer "B.Cu")
		(hatch none 0.5)
		(connect_pads
			(clearance 0)
		)
		(min_thickness 0.25)
		(keepout
			(tracks not_allowed)
			(vias allowed)
			(pads allowed)
			(copperpour not_allowed)
			(footprints allowed)
		)
		(placement
			(enabled no)
			(sheetname "")
		)
		(fill
			(thermal_gap 0.5)
			(thermal_bridge_width 0.5)
			(island_removal_mode 0)
		)
		(polygon
			(pts
				(arc
					(start 357.986076 -274.086066)
					(mid 357.356156 -274.086066)
					(end 357.986076 -274.086066)
				)
			)
		)
	)
	(zone
		(layer "B.Cu")
		(hatch none 0.5)
		(connect_pads
			(clearance 0)
		)
		(min_thickness 0.25)
		(keepout
			(tracks allowed)
			(vias allowed)
			(pads allowed)
			(copperpour allowed)
			(footprints not_allowed)
		)
		(placement
			(enabled no)
			(sheetname "")
		)
		(fill
			(thermal_gap 0.5)
			(thermal_bridge_width 0.5)
			(island_removal_mode 0)
		)
		(polygon
			(pts
				(arc
					(start 170.699938 -160.50006)
					(mid 167.900096 -157.700218)
					(end 165.1 -160.50006)
				)
				(arc
					(start 165.1 -160.50006)
					(mid 167.900096 -163.300156)
					(end 170.699938 -160.50006)
				)
			)
		)
	)
	(zone
		(layer "B.Cu")
		(hatch none 0.5)
		(connect_pads
			(clearance 0)
		)
		(min_thickness 0.25)
		(keepout
			(tracks allowed)
			(vias allowed)
			(pads allowed)
			(copperpour allowed)
			(footprints not_allowed)
		)
		(placement
			(enabled no)
			(sheetname "")
		)
		(fill
			(thermal_gap 0.5)
			(thermal_bridge_width 0.5)
			(island_removal_mode 0)
		)
		(polygon
			(pts
				(arc
					(start 72.080882 -344.814906)
					(mid 70.216014 -342.950038)
					(end 68.350892 -344.814906)
				)
				(arc
					(start 68.350892 -344.814906)
					(mid 70.216014 -346.680028)
					(end 72.080882 -344.814906)
				)
			)
		)
	)
	(zone
		(layer "B.Cu")
		(hatch none 0.5)
		(connect_pads
			(clearance 0)
		)
		(min_thickness 0.25)
		(keepout
			(tracks not_allowed)
			(vias allowed)
			(pads allowed)
			(copperpour not_allowed)
			(footprints allowed)
		)
		(placement
			(enabled no)
			(sheetname "")
		)
		(fill
			(thermal_gap 0.5)
			(thermal_bridge_width 0.5)
			(island_removal_mode 0)
		)
		(polygon
			(pts
				(arc
					(start 314.950348 -401.674838)
					(mid 314.282328 -401.674838)
					(end 314.950348 -401.674838)
				)
			)
		)
	)
	(zone
		(layer "B.Cu")
		(hatch none 0.5)
		(connect_pads
			(clearance 0)
		)
		(min_thickness 0.25)
		(keepout
			(tracks allowed)
			(vias allowed)
			(pads allowed)
			(copperpour allowed)
			(footprints allowed)
		)
		(placement
			(enabled no)
			(sheetname "")
		)
		(fill
			(thermal_gap 0.5)
			(thermal_bridge_width 0.5)
			(island_removal_mode 0)
		)
		(polygon
			(pts
				(xy 443.481968 -21.146008) (xy 443.481968 -21.487384) (xy 444.546228 -22.551644) (xy 444.546228 -26.680414)
				(xy 444.354966 -26.871676) (xy 442.774832 -26.871676) (xy 440.503818 -29.14269) (xy 438.173622 -29.14269)
				(xy 436.917846 -30.398466) (xy 434.742082 -30.398466) (xy 434.38826 -30.044644) (xy 434.38826 -26.4541)
				(xy 437.466232 -23.376128) (xy 438.904888 -23.376128) (xy 439.280046 -23.00097) (xy 439.280046 -15.723616)
				(xy 440.357006 -14.646656) (xy 443.101222 -14.646656) (xy 443.481968 -15.027402)
			)
		)
	)
	(zone
		(layer "B.Cu")
		(hatch none 0.5)
		(connect_pads
			(clearance 0)
		)
		(min_thickness 0.25)
		(keepout
			(tracks not_allowed)
			(vias allowed)
			(pads allowed)
			(copperpour not_allowed)
			(footprints allowed)
		)
		(placement
			(enabled no)
			(sheetname "")
		)
		(fill
			(thermal_gap 0.5)
			(thermal_bridge_width 0.5)
			(island_removal_mode 0)
		)
		(polygon
			(pts
				(arc
					(start 122.429778 -247.724422)
					(mid 121.799858 -247.724422)
					(end 122.429778 -247.724422)
				)
			)
		)
	)
	(zone
		(layer "B.Cu")
		(hatch none 0.5)
		(connect_pads
			(clearance 0)
		)
		(min_thickness 0.25)
		(keepout
			(tracks not_allowed)
			(vias allowed)
			(pads allowed)
			(copperpour not_allowed)
			(footprints allowed)
		)
		(placement
			(enabled no)
			(sheetname "")
		)
		(fill
			(thermal_gap 0.5)
			(thermal_bridge_width 0.5)
			(island_removal_mode 0)
		)
		(polygon
			(pts
				(arc
					(start 134.136892 -436.889906)
					(mid 133.3627 -436.889906)
					(end 134.136892 -436.889906)
				)
			)
		)
	)
	(zone
		(layer "B.Cu")
		(hatch none 0.5)
		(connect_pads
			(clearance 0)
		)
		(min_thickness 0.25)
		(keepout
			(tracks not_allowed)
			(vias allowed)
			(pads allowed)
			(copperpour not_allowed)
			(footprints allowed)
		)
		(placement
			(enabled no)
			(sheetname "")
		)
		(fill
			(thermal_gap 0.5)
			(thermal_bridge_width 0.5)
			(island_removal_mode 0)
		)
		(polygon
			(pts
				(arc
					(start 119.609616 -247.724422)
					(mid 118.979696 -247.724422)
					(end 119.609616 -247.724422)
				)
			)
		)
	)
	(zone
		(layer "B.Cu")
		(hatch none 0.5)
		(connect_pads
			(clearance 0)
		)
		(min_thickness 0.25)
		(keepout
			(tracks not_allowed)
			(vias allowed)
			(pads allowed)
			(copperpour not_allowed)
			(footprints allowed)
		)
		(placement
			(enabled no)
			(sheetname "")
		)
		(fill
			(thermal_gap 0.5)
			(thermal_bridge_width 0.5)
			(island_removal_mode 0)
		)
		(polygon
			(pts
				(arc
					(start 58.950606 -392.429238)
					(mid 58.282586 -392.429238)
					(end 58.950606 -392.429238)
				)
			)
		)
	)
	(zone
		(layer "B.Cu")
		(hatch none 0.5)
		(connect_pads
			(clearance 0)
		)
		(min_thickness 0.25)
		(keepout
			(tracks allowed)
			(vias allowed)
			(pads allowed)
			(copperpour allowed)
			(footprints not_allowed)
		)
		(placement
			(enabled no)
			(sheetname "")
		)
		(fill
			(thermal_gap 0.5)
			(thermal_bridge_width 0.5)
			(island_removal_mode 0)
		)
		(polygon
			(pts
				(arc
					(start 103.615998 -166.61511)
					(mid 106.716068 -169.71518)
					(end 109.815884 -166.61511)
				)
				(arc
					(start 109.815884 -166.61511)
					(mid 106.716068 -163.515294)
					(end 103.615998 -166.61511)
				)
			)
		)
	)
	(zone
		(layer "B.Cu")
		(hatch none 0.5)
		(connect_pads
			(clearance 0)
		)
		(min_thickness 0.25)
		(keepout
			(tracks allowed)
			(vias allowed)
			(pads allowed)
			(copperpour allowed)
			(footprints allowed)
		)
		(placement
			(enabled no)
			(sheetname "")
		)
		(fill
			(thermal_gap 0.5)
			(thermal_bridge_width 0.5)
			(island_removal_mode 0)
		)
		(polygon
			(pts
				(xy 116.15928 -409.046426) (xy 116.15928 -408.04211) (xy 117.536214 -408.04211) (xy 117.536214 -409.046426)
			)
		)
	)
	(zone
		(layer "B.Cu")
		(hatch none 0.5)
		(connect_pads
			(clearance 0)
		)
		(min_thickness 0.25)
		(keepout
			(tracks allowed)
			(vias allowed)
			(pads allowed)
			(copperpour allowed)
			(footprints allowed)
		)
		(placement
			(enabled no)
			(sheetname "")
		)
		(fill
			(thermal_gap 0.5)
			(thermal_bridge_width 0.5)
			(island_removal_mode 0)
		)
		(polygon
			(pts
				(xy 402.791676 -417.428426) (xy 402.791676 -416.42411) (xy 404.16861 -416.42411) (xy 404.16861 -417.428426)
			)
		)
	)
	(zone
		(layer "B.Cu")
		(hatch none 0.5)
		(connect_pads
			(clearance 0)
		)
		(min_thickness 0.25)
		(keepout
			(tracks not_allowed)
			(vias allowed)
			(pads allowed)
			(copperpour not_allowed)
			(footprints allowed)
		)
		(placement
			(enabled no)
			(sheetname "")
		)
		(fill
			(thermal_gap 0.5)
			(thermal_bridge_width 0.5)
			(island_removal_mode 0)
		)
		(polygon
			(pts
				(arc
					(start 413.137096 -437.889904)
					(mid 412.362904 -437.889904)
					(end 413.137096 -437.889904)
				)
			)
		)
	)
	(zone
		(layer "B.Cu")
		(hatch none 0.5)
		(connect_pads
			(clearance 0)
		)
		(min_thickness 0.25)
		(keepout
			(tracks not_allowed)
			(vias allowed)
			(pads allowed)
			(copperpour not_allowed)
			(footprints allowed)
		)
		(placement
			(enabled no)
			(sheetname "")
		)
		(fill
			(thermal_gap 0.5)
			(thermal_bridge_width 0.5)
			(island_removal_mode 0)
		)
		(polygon
			(pts
				(arc
					(start 179.749958 -376.489976)
					(mid 177.500026 -374.240044)
					(end 175.250094 -376.489976)
				)
				(arc
					(start 175.250094 -376.489976)
					(mid 177.500026 -378.739908)
					(end 179.749958 -376.489976)
				)
			)
		)
	)
	(zone
		(layer "B.Cu")
		(hatch none 0.5)
		(connect_pads
			(clearance 0)
		)
		(min_thickness 0.25)
		(keepout
			(tracks not_allowed)
			(vias allowed)
			(pads allowed)
			(copperpour not_allowed)
			(footprints allowed)
		)
		(placement
			(enabled no)
			(sheetname "")
		)
		(fill
			(thermal_gap 0.5)
			(thermal_bridge_width 0.5)
			(island_removal_mode 0)
		)
		(polygon
			(pts
				(arc
					(start 293.569898 -413.170116)
					(mid 297.56989 -417.170108)
					(end 301.569882 -413.170116)
				)
				(arc
					(start 301.569882 -413.170116)
					(mid 297.56989 -409.170124)
					(end 293.569898 -413.170116)
				)
			)
		)
	)
	(zone
		(layer "B.Cu")
		(hatch none 0.5)
		(connect_pads
			(clearance 0)
		)
		(min_thickness 0.25)
		(keepout
			(tracks allowed)
			(vias allowed)
			(pads allowed)
			(copperpour allowed)
			(footprints not_allowed)
		)
		(placement
			(enabled no)
			(sheetname "")
		)
		(fill
			(thermal_gap 0.5)
			(thermal_bridge_width 0.5)
			(island_removal_mode 0)
		)
		(polygon
			(pts
				(arc
					(start 287.070038 -384.869944)
					(mid 291.07003 -388.869936)
					(end 295.070022 -384.869944)
				)
				(arc
					(start 295.070022 -384.869944)
					(mid 291.07003 -380.869952)
					(end 287.070038 -384.869944)
				)
			)
		)
	)
	(zone
		(layer "B.Cu")
		(hatch none 0.5)
		(connect_pads
			(clearance 0)
		)
		(min_thickness 0.25)
		(keepout
			(tracks not_allowed)
			(vias allowed)
			(pads allowed)
			(copperpour not_allowed)
			(footprints allowed)
		)
		(placement
			(enabled no)
			(sheetname "")
		)
		(fill
			(thermal_gap 0.5)
			(thermal_bridge_width 0.5)
			(island_removal_mode 0)
		)
		(polygon
			(pts
				(arc
					(start 145.32991 -212.989922)
					(mid 142.530068 -210.19008)
					(end 139.729972 -212.989922)
				)
				(arc
					(start 139.729972 -212.989922)
					(mid 142.530068 -215.790018)
					(end 145.32991 -212.989922)
				)
			)
		)
	)
	(zone
		(layer "B.Cu")
		(hatch none 0.5)
		(connect_pads
			(clearance 0)
		)
		(min_thickness 0.25)
		(keepout
			(tracks not_allowed)
			(vias allowed)
			(pads allowed)
			(copperpour not_allowed)
			(footprints allowed)
		)
		(placement
			(enabled no)
			(sheetname "")
		)
		(fill
			(thermal_gap 0.5)
			(thermal_bridge_width 0.5)
			(island_removal_mode 0)
		)
		(polygon
			(pts
				(arc
					(start 420.57828 -401.674838)
					(mid 419.91026 -401.674838)
					(end 420.57828 -401.674838)
				)
			)
		)
	)
	(zone
		(layer "B.Cu")
		(hatch none 0.5)
		(connect_pads
			(clearance 0)
		)
		(min_thickness 0.25)
		(keepout
			(tracks allowed)
			(vias allowed)
			(pads allowed)
			(copperpour allowed)
			(footprints not_allowed)
		)
		(placement
			(enabled no)
			(sheetname "")
		)
		(fill
			(thermal_gap 0.5)
			(thermal_bridge_width 0.5)
			(island_removal_mode 0)
		)
		(polygon
			(pts
				(arc
					(start 223.400366 -81.700116)
					(mid 235.900468 -94.200218)
					(end 248.400316 -81.700116)
				)
				(arc
					(start 248.400316 -81.700116)
					(mid 235.900468 -69.200268)
					(end 223.400366 -81.700116)
				)
			)
		)
	)
	(zone
		(layer "B.Cu")
		(hatch none 0.5)
		(connect_pads
			(clearance 0)
		)
		(min_thickness 0.25)
		(keepout
			(tracks not_allowed)
			(vias allowed)
			(pads allowed)
			(copperpour not_allowed)
			(footprints allowed)
		)
		(placement
			(enabled no)
			(sheetname "")
		)
		(fill
			(thermal_gap 0.5)
			(thermal_bridge_width 0.5)
			(island_removal_mode 0)
		)
		(polygon
			(pts
				(arc
					(start 117.729762 -244.484398)
					(mid 117.099842 -244.484398)
					(end 117.729762 -244.484398)
				)
			)
		)
	)
	(zone
		(layer "B.Cu")
		(hatch none 0.5)
		(connect_pads
			(clearance 0)
		)
		(min_thickness 0.25)
		(keepout
			(tracks not_allowed)
			(vias allowed)
			(pads allowed)
			(copperpour not_allowed)
			(footprints allowed)
		)
		(placement
			(enabled no)
			(sheetname "")
		)
		(fill
			(thermal_gap 0.5)
			(thermal_bridge_width 0.5)
			(island_removal_mode 0)
		)
		(polygon
			(pts
				(arc
					(start 273.649948 -51.999896)
					(mid 268.649958 -46.999906)
					(end 263.649968 -51.999896)
				)
				(arc
					(start 263.649968 -51.999896)
					(mid 268.649958 -56.999886)
					(end 273.649948 -51.999896)
				)
			)
		)
	)
	(zone
		(layer "B.Cu")
		(hatch none 0.5)
		(connect_pads
			(clearance 0)
		)
		(min_thickness 0.25)
		(keepout
			(tracks allowed)
			(vias allowed)
			(pads allowed)
			(copperpour allowed)
			(footprints not_allowed)
		)
		(placement
			(enabled no)
			(sheetname "")
		)
		(fill
			(thermal_gap 0.5)
			(thermal_bridge_width 0.5)
			(island_removal_mode 0)
		)
		(polygon
			(pts
				(arc
					(start 179.749958 -376.489976)
					(mid 177.500026 -374.240044)
					(end 175.250094 -376.489976)
				)
				(arc
					(start 175.250094 -376.489976)
					(mid 177.500026 -378.739908)
					(end 179.749958 -376.489976)
				)
			)
		)
	)
	(zone
		(layer "B.Cu")
		(hatch none 0.5)
		(connect_pads
			(clearance 0)
		)
		(min_thickness 0.25)
		(keepout
			(tracks not_allowed)
			(vias allowed)
			(pads allowed)
			(copperpour not_allowed)
			(footprints allowed)
		)
		(placement
			(enabled no)
			(sheetname "")
		)
		(fill
			(thermal_gap 0.5)
			(thermal_bridge_width 0.5)
			(island_removal_mode 0)
		)
		(polygon
			(pts
				(arc
					(start 332.069948 -304.790094)
					(mid 329.270106 -301.990252)
					(end 326.47001 -304.790094)
				)
				(arc
					(start 326.47001 -304.790094)
					(mid 329.270106 -307.59019)
					(end 332.069948 -304.790094)
				)
			)
		)
	)
	(zone
		(layer "B.Cu")
		(hatch none 0.5)
		(connect_pads
			(clearance 0)
		)
		(min_thickness 0.25)
		(keepout
			(tracks not_allowed)
			(vias allowed)
			(pads allowed)
			(copperpour not_allowed)
			(footprints allowed)
		)
		(placement
			(enabled no)
			(sheetname "")
		)
		(fill
			(thermal_gap 0.5)
			(thermal_bridge_width 0.5)
			(island_removal_mode 0)
		)
		(polygon
			(pts
				(arc
					(start 465.304886 -399.029936)
					(mid 463.440018 -397.165068)
					(end 461.574896 -399.029936)
				)
				(arc
					(start 461.574896 -399.029936)
					(mid 463.440018 -400.895058)
					(end 465.304886 -399.029936)
				)
			)
		)
	)
	(zone
		(layer "B.Cu")
		(hatch none 0.5)
		(connect_pads
			(clearance 0)
		)
		(min_thickness 0.25)
		(keepout
			(tracks allowed)
			(vias allowed)
			(pads allowed)
			(copperpour allowed)
			(footprints not_allowed)
		)
		(placement
			(enabled no)
			(sheetname "")
		)
		(fill
			(thermal_gap 0.5)
			(thermal_bridge_width 0.5)
			(island_removal_mode 0)
		)
		(polygon
			(pts
				(xy 7.500112 -96.19996) (xy 462.639918 -96.19996)
				(arc
					(start 462.639918 -148.055838)
					(mid 458.07109 -148.468221)
					(end 453.958706 -150.501096)
				)
				(arc
					(start 453.958706 -150.501096)
					(mid 435.185106 -143.228385)
					(end 433.81803 -163.314888)
				)
				(arc
					(start 425.981876 -163.314888)
					(mid 422.88206 -160.215072)
					(end 419.78199 -163.314888)
				)
				(xy 348.051882 -163.314888)
				(arc
					(start 348.051882 -151.005032)
					(mid 349.680779 -145.267877)
					(end 345.280234 -149.293072)
				)
				(arc
					(start 334.077056 -154.90317)
					(mid 321.343763 -148.097283)
					(end 310.686704 -157.83814)
				)
				(arc
					(start 289.846258 -157.45333)
					(mid 290.262661 -155.630531)
					(end 290.402518 -153.766012)
				)
				(arc
					(start 290.402518 -153.766012)
					(mid 277.90267 -141.266164)
					(end 265.402568 -153.766012)
				)
				(arc
					(start 265.402568 -153.766012)
					(mid 265.510069 -155.402131)
					(end 265.830812 -157.0101)
				)
				(arc
					(start 201.687684 -155.825698)
					(mid 201.887824 -154.80897)
					(end 201.954892 -153.774902)
				)
				(arc
					(start 201.954892 -153.774902)
					(mid 193.954908 -145.774918)
					(end 185.954924 -153.774902)
				)
				(arc
					(start 185.954924 -153.774902)
					(mid 186.004273 -154.662394)
					(end 186.151774 -155.538932)
				)
				(arc
					(start 179.317904 -155.412694)
					(mid 168.130682 -148.001904)
					(end 156.677614 -154.99461)
				)
				(arc
					(start 134.880858 -154.592274)
					(mid 132.73833 -154.843575)
					(end 130.606546 -154.51328)
				)
				(xy 105.350564 -159.726376)
				(arc
					(start 40.942514 -159.726376)
					(mid 42.07102 -156.840655)
					(end 42.455084 -153.766012)
				)
				(arc
					(start 42.455084 -153.766012)
					(mid 31.586544 -141.372846)
					(end 17.880838 -150.530814)
				)
				(arc
					(start 17.880838 -150.530814)
					(mid 12.935974 -148.272578)
					(end 7.500112 -148.326856)
				)
			)
		)
	)
	(zone
		(layer "B.Cu")
		(hatch none 0.5)
		(connect_pads
			(clearance 0)
		)
		(min_thickness 0.25)
		(keepout
			(tracks allowed)
			(vias allowed)
			(pads allowed)
			(copperpour allowed)
			(footprints not_allowed)
		)
		(placement
			(enabled no)
			(sheetname "")
		)
		(fill
			(thermal_gap 0.5)
			(thermal_bridge_width 0.5)
			(island_removal_mode 0)
		)
		(polygon
			(pts
				(arc
					(start 466.540088 -399.029936)
					(mid 463.440018 -395.929866)
					(end 460.339948 -399.029936)
				)
				(arc
					(start 460.339948 -399.029936)
					(mid 463.440018 -402.130006)
					(end 466.540088 -399.029936)
				)
			)
		)
	)
	(zone
		(layer "B.Cu")
		(hatch none 0.5)
		(connect_pads
			(clearance 0)
		)
		(min_thickness 0.25)
		(keepout
			(tracks not_allowed)
			(vias allowed)
			(pads allowed)
			(copperpour not_allowed)
			(footprints allowed)
		)
		(placement
			(enabled no)
			(sheetname "")
		)
		(fill
			(thermal_gap 0.5)
			(thermal_bridge_width 0.5)
			(island_removal_mode 0)
		)
		(polygon
			(pts
				(arc
					(start 227.530406 -388.161784)
					(mid 225.430588 -386.061966)
					(end 223.330516 -388.161784)
				)
				(arc
					(start 223.330516 -388.161784)
					(mid 225.430588 -390.261856)
					(end 227.530406 -388.161784)
				)
			)
		)
	)
	(zone
		(layer "B.Cu")
		(hatch none 0.5)
		(connect_pads
			(clearance 0)
		)
		(min_thickness 0.25)
		(keepout
			(tracks not_allowed)
			(vias allowed)
			(pads allowed)
			(copperpour not_allowed)
			(footprints allowed)
		)
		(placement
			(enabled no)
			(sheetname "")
		)
		(fill
			(thermal_gap 0.5)
			(thermal_bridge_width 0.5)
			(island_removal_mode 0)
		)
		(polygon
			(pts
				(arc
					(start 164.578284 -392.429238)
					(mid 163.910264 -392.429238)
					(end 164.578284 -392.429238)
				)
			)
		)
	)
	(zone
		(layer "B.Cu")
		(hatch none 0.5)
		(connect_pads
			(clearance 0)
		)
		(min_thickness 0.25)
		(keepout
			(tracks allowed)
			(vias allowed)
			(pads allowed)
			(copperpour allowed)
			(footprints not_allowed)
		)
		(placement
			(enabled no)
			(sheetname "")
		)
		(fill
			(thermal_gap 0.5)
			(thermal_bridge_width 0.5)
			(island_removal_mode 0)
		)
		(polygon
			(pts
				(arc
					(start 89.899998 -22.29993)
					(mid 94.899988 -27.29992)
					(end 99.899978 -22.29993)
				)
				(arc
					(start 99.899978 -22.29993)
					(mid 94.899988 -17.29994)
					(end 89.899998 -22.29993)
				)
			)
		)
	)
	(zone
		(layer "B.Cu")
		(hatch none 0.5)
		(connect_pads
			(clearance 0)
		)
		(min_thickness 0.25)
		(keepout
			(tracks not_allowed)
			(vias allowed)
			(pads allowed)
			(copperpour not_allowed)
			(footprints allowed)
		)
		(placement
			(enabled no)
			(sheetname "")
		)
		(fill
			(thermal_gap 0.5)
			(thermal_bridge_width 0.5)
			(island_removal_mode 0)
		)
		(polygon
			(pts
				(arc
					(start 366.298734 -435.600094)
					(mid 371.298724 -440.600084)
					(end 376.298714 -435.600094)
				)
				(arc
					(start 376.298714 -435.600094)
					(mid 371.298724 -430.600104)
					(end 366.298734 -435.600094)
				)
			)
		)
	)
	(zone
		(layer "B.Cu")
		(hatch none 0.5)
		(connect_pads
			(clearance 0)
		)
		(min_thickness 0.25)
		(keepout
			(tracks not_allowed)
			(vias allowed)
			(pads allowed)
			(copperpour not_allowed)
			(footprints allowed)
		)
		(placement
			(enabled no)
			(sheetname "")
		)
		(fill
			(thermal_gap 0.5)
			(thermal_bridge_width 0.5)
			(island_removal_mode 0)
		)
		(polygon
			(pts
				(arc
					(start 354.39604 -244.484144)
					(mid 353.76612 -244.484144)
					(end 354.39604 -244.484144)
				)
			)
		)
	)
	(zone
		(layer "B.Cu")
		(hatch none 0.5)
		(connect_pads
			(clearance 0)
		)
		(min_thickness 0.25)
		(keepout
			(tracks allowed)
			(vias allowed)
			(pads allowed)
			(copperpour allowed)
			(footprints allowed)
		)
		(placement
			(enabled no)
			(sheetname "")
		)
		(fill
			(thermal_gap 0.5)
			(thermal_bridge_width 0.5)
			(island_removal_mode 0)
		)
		(polygon
			(pts
				(xy 169.6974 -193.8274) (xy 169.6974 -190.51778) (xy 171.23664 -190.51778) (xy 171.23664 -193.8274)
			)
		)
	)
	(zone
		(layer "B.Cu")
		(hatch none 0.5)
		(connect_pads
			(clearance 0)
		)
		(min_thickness 0.25)
		(keepout
			(tracks not_allowed)
			(vias allowed)
			(pads allowed)
			(copperpour not_allowed)
			(footprints allowed)
		)
		(placement
			(enabled no)
			(sheetname "")
		)
		(fill
			(thermal_gap 0.5)
			(thermal_bridge_width 0.5)
			(island_removal_mode 0)
		)
		(polygon
			(pts
				(arc
					(start 415.778442 -401.674838)
					(mid 415.110422 -401.674838)
					(end 415.778442 -401.674838)
				)
			)
		)
	)
	(zone
		(layer "B.Cu")
		(hatch none 0.5)
		(connect_pads
			(clearance 0)
		)
		(min_thickness 0.25)
		(keepout
			(tracks not_allowed)
			(vias allowed)
			(pads allowed)
			(copperpour not_allowed)
			(footprints allowed)
		)
		(placement
			(enabled no)
			(sheetname "")
		)
		(fill
			(thermal_gap 0.5)
			(thermal_bridge_width 0.5)
			(island_removal_mode 0)
		)
		(polygon
			(pts
				(arc
					(start 346.0369 -439.0898)
					(mid 345.262708 -439.0898)
					(end 346.0369 -439.0898)
				)
			)
		)
	)
	(zone
		(layer "B.Cu")
		(hatch none 0.5)
		(connect_pads
			(clearance 0)
		)
		(min_thickness 0.25)
		(keepout
			(tracks not_allowed)
			(vias allowed)
			(pads allowed)
			(copperpour not_allowed)
			(footprints allowed)
		)
		(placement
			(enabled no)
			(sheetname "")
		)
		(fill
			(thermal_gap 0.5)
			(thermal_bridge_width 0.5)
			(island_removal_mode 0)
		)
		(polygon
			(pts
				(arc
					(start 88.037162 -436.889906)
					(mid 87.26297 -436.889906)
					(end 88.037162 -436.889906)
				)
			)
		)
	)
	(zone
		(layer "B.Cu")
		(hatch none 0.5)
		(connect_pads
			(clearance 0)
		)
		(min_thickness 0.25)
		(keepout
			(tracks allowed)
			(vias allowed)
			(pads allowed)
			(copperpour allowed)
			(footprints not_allowed)
		)
		(placement
			(enabled no)
			(sheetname "")
		)
		(fill
			(thermal_gap 0.5)
			(thermal_bridge_width 0.5)
			(island_removal_mode 0)
		)
		(polygon
			(pts
				(arc
					(start 64.382904 -50.25009)
					(mid 65.784579 -49.92679)
					(end 66.903092 -49.022254)
				)
				(arc
					(start 66.903092 -49.022254)
					(mid 71.402756 -50.917617)
					(end 74.382884 -47.049944)
				)
				(arc
					(start 74.382884 -47.049944)
					(mid 71.402678 -43.182132)
					(end 66.903092 -45.077888)
				)
				(arc
					(start 66.903092 -45.077888)
					(mid 65.784607 -44.173293)
					(end 64.382904 -43.850052)
				)
				(arc
					(start 62.782958 -43.850052)
					(mid 59.582812 -47.050198)
					(end 62.782958 -50.25009)
				)
			)
		)
	)
	(zone
		(layer "B.Cu")
		(hatch none 0.5)
		(connect_pads
			(clearance 0)
		)
		(min_thickness 0.25)
		(keepout
			(tracks allowed)
			(vias allowed)
			(pads allowed)
			(copperpour allowed)
			(footprints allowed)
		)
		(placement
			(enabled no)
			(sheetname "")
		)
		(fill
			(thermal_gap 0.5)
			(thermal_bridge_width 0.5)
			(island_removal_mode 0)
		)
		(polygon
			(pts
				(xy 133.748018 -384.911854) (xy 133.748018 -383.394966) (xy 133.740652 -383.3876) (xy 133.740652 -382.876806)
				(xy 133.194298 -382.330452) (xy 131.913884 -382.330452) (xy 131.695952 -382.548384) (xy 115.695476 -382.548384)
				(xy 115.145058 -383.098802) (xy 115.145058 -384.911854)
			)
		)
	)
	(zone
		(layer "B.Cu")
		(hatch none 0.5)
		(connect_pads
			(clearance 0)
		)
		(min_thickness 0.25)
		(keepout
			(tracks allowed)
			(vias allowed)
			(pads allowed)
			(copperpour allowed)
			(footprints allowed)
		)
		(placement
			(enabled no)
			(sheetname "")
		)
		(fill
			(thermal_gap 0.5)
			(thermal_bridge_width 0.5)
			(island_removal_mode 0)
		)
		(polygon
			(pts
				(xy 322.647818 -393.293854) (xy 322.647818 -391.776966) (xy 322.640452 -391.7696) (xy 322.640452 -391.258806)
				(xy 322.094098 -390.712452) (xy 320.813684 -390.712452) (xy 320.595752 -390.930384) (xy 304.595276 -390.930384)
				(xy 304.044858 -391.480802) (xy 304.044858 -393.293854)
			)
		)
	)
	(zone
		(layer "B.Cu")
		(hatch none 0.5)
		(connect_pads
			(clearance 0)
		)
		(min_thickness 0.25)
		(keepout
			(tracks allowed)
			(vias allowed)
			(pads allowed)
			(copperpour allowed)
			(footprints not_allowed)
		)
		(placement
			(enabled no)
			(sheetname "")
		)
		(fill
			(thermal_gap 0.5)
			(thermal_bridge_width 0.5)
			(island_removal_mode 0)
		)
		(polygon
			(pts
				(arc
					(start 429.394874 -153.774902)
					(mid 441.894976 -166.275004)
					(end 454.395078 -153.774902)
				)
				(arc
					(start 454.395078 -153.774902)
					(mid 441.894976 -141.2748)
					(end 429.394874 -153.774902)
				)
			)
		)
	)
	(zone
		(layer "B.Cu")
		(hatch none 0.5)
		(connect_pads
			(clearance 0)
		)
		(min_thickness 0.25)
		(keepout
			(tracks not_allowed)
			(vias allowed)
			(pads allowed)
			(copperpour not_allowed)
			(footprints allowed)
		)
		(placement
			(enabled no)
			(sheetname "")
		)
		(fill
			(thermal_gap 0.5)
			(thermal_bridge_width 0.5)
			(island_removal_mode 0)
		)
		(polygon
			(pts
				(arc
					(start 371.309646 -223.424242)
					(mid 370.679726 -223.424242)
					(end 371.309646 -223.424242)
				)
			)
		)
	)
	(zone
		(layer "B.Cu")
		(hatch none 0.5)
		(connect_pads
			(clearance 0)
		)
		(min_thickness 0.25)
		(keepout
			(tracks not_allowed)
			(vias allowed)
			(pads allowed)
			(copperpour not_allowed)
			(footprints allowed)
		)
		(placement
			(enabled no)
			(sheetname "")
		)
		(fill
			(thermal_gap 0.5)
			(thermal_bridge_width 0.5)
			(island_removal_mode 0)
		)
		(polygon
			(pts
				(arc
					(start 114.4397 -243.674392)
					(mid 113.80978 -243.674392)
					(end 114.4397 -243.674392)
				)
			)
		)
	)
	(zone
		(layer "B.Cu")
		(hatch none 0.5)
		(connect_pads
			(clearance 0)
		)
		(min_thickness 0.25)
		(keepout
			(tracks not_allowed)
			(vias allowed)
			(pads allowed)
			(copperpour not_allowed)
			(footprints allowed)
		)
		(placement
			(enabled no)
			(sheetname "")
		)
		(fill
			(thermal_gap 0.5)
			(thermal_bridge_width 0.5)
			(island_removal_mode 0)
		)
		(polygon
			(pts
				(arc
					(start 129.786126 -146.84502)
					(mid 132.886196 -149.94509)
					(end 135.986012 -146.84502)
				)
				(arc
					(start 135.986012 -146.84502)
					(mid 132.886196 -143.745204)
					(end 129.786126 -146.84502)
				)
			)
		)
	)
	(zone
		(layer "B.Cu")
		(hatch none 0.5)
		(connect_pads
			(clearance 0)
		)
		(min_thickness 0.25)
		(keepout
			(tracks allowed)
			(vias allowed)
			(pads allowed)
			(copperpour allowed)
			(footprints not_allowed)
		)
		(placement
			(enabled no)
			(sheetname "")
		)
		(fill
			(thermal_gap 0.5)
			(thermal_bridge_width 0.5)
			(island_removal_mode 0)
		)
		(polygon
			(pts
				(xy 2.999994 -87.199978)
				(arc
					(start 224.674938 -87.199978)
					(mid 235.89996 -94.199958)
					(end 247.124982 -87.199978)
				)
				(xy 467.300056 -87.199978) (xy 467.300056 -96.19996) (xy 2.999994 -96.19996)
			)
		)
	)
	(zone
		(layer "B.Cu")
		(hatch none 0.5)
		(connect_pads
			(clearance 0)
		)
		(min_thickness 0.25)
		(keepout
			(tracks not_allowed)
			(vias allowed)
			(pads allowed)
			(copperpour not_allowed)
			(footprints allowed)
		)
		(placement
			(enabled no)
			(sheetname "")
		)
		(fill
			(thermal_gap 0.5)
			(thermal_bridge_width 0.5)
			(island_removal_mode 0)
		)
		(polygon
			(pts
				(arc
					(start 392.136884 -437.889904)
					(mid 391.362692 -437.889904)
					(end 392.136884 -437.889904)
				)
			)
		)
	)
	(zone
		(layer "B.Cu")
		(hatch none 0.5)
		(connect_pads
			(clearance 0)
		)
		(min_thickness 0.25)
		(keepout
			(tracks allowed)
			(vias allowed)
			(pads allowed)
			(copperpour allowed)
			(footprints allowed)
		)
		(placement
			(enabled no)
			(sheetname "")
		)
		(fill
			(thermal_gap 0.5)
			(thermal_bridge_width 0.5)
			(island_removal_mode 0)
		)
		(polygon
			(pts
				(xy 45.850302 -394.180568) (xy 45.850302 -391.48639) (xy 45.850302 -385.965954) (xy 47.597568 -385.965954)
				(xy 47.597568 -384.911854) (xy 67.192398 -384.911854) (xy 67.192398 -385.965954) (xy 67.192398 -394.180568)
			)
		)
	)
	(zone
		(layer "B.Cu")
		(hatch none 0.5)
		(connect_pads
			(clearance 0)
		)
		(min_thickness 0.25)
		(keepout
			(tracks allowed)
			(vias allowed)
			(pads allowed)
			(copperpour allowed)
			(footprints allowed)
		)
		(placement
			(enabled no)
			(sheetname "")
		)
		(fill
			(thermal_gap 0.5)
			(thermal_bridge_width 0.5)
			(island_removal_mode 0)
		)
		(polygon
			(pts
				(xy 334.377792 -402.562568) (xy 334.377792 -399.86839) (xy 334.377792 -394.347954) (xy 336.125058 -394.347954)
				(xy 336.125058 -393.293854) (xy 355.719888 -393.293854) (xy 355.719888 -394.347954) (xy 355.719888 -402.562568)
			)
		)
	)
	(zone
		(layer "B.Cu")
		(hatch none 0.5)
		(connect_pads
			(clearance 0)
		)
		(min_thickness 0.25)
		(keepout
			(tracks allowed)
			(vias allowed)
			(pads allowed)
			(copperpour allowed)
			(footprints not_allowed)
		)
		(placement
			(enabled no)
			(sheetname "")
		)
		(fill
			(thermal_gap 0.5)
			(thermal_bridge_width 0.5)
			(island_removal_mode 0)
		)
		(polygon
			(pts
				(arc
					(start 404.770082 -258.890008)
					(mid 401.969986 -256.089912)
					(end 399.16989 -258.890008)
				)
				(arc
					(start 399.16989 -258.890008)
					(mid 401.969986 -261.690104)
					(end 404.770082 -258.890008)
				)
			)
		)
	)
	(zone
		(layer "B.Cu")
		(hatch none 0.5)
		(connect_pads
			(clearance 0)
		)
		(min_thickness 0.25)
		(keepout
			(tracks not_allowed)
			(vias allowed)
			(pads allowed)
			(copperpour not_allowed)
			(footprints allowed)
		)
		(placement
			(enabled no)
			(sheetname "")
		)
		(fill
			(thermal_gap 0.5)
			(thermal_bridge_width 0.5)
			(island_removal_mode 0)
		)
		(polygon
			(pts
				(arc
					(start 346.876116 -246.104156)
					(mid 346.246196 -246.104156)
					(end 346.876116 -246.104156)
				)
			)
		)
	)
	(zone
		(layer "B.Cu")
		(hatch none 0.5)
		(connect_pads
			(clearance 0)
		)
		(min_thickness 0.25)
		(keepout
			(tracks allowed)
			(vias allowed)
			(pads allowed)
			(copperpour allowed)
			(footprints allowed)
		)
		(placement
			(enabled no)
			(sheetname "")
		)
		(fill
			(thermal_gap 0.5)
			(thermal_bridge_width 0.5)
			(island_removal_mode 0)
		)
		(polygon
			(pts
				(xy 186.40552 -126.01194) (xy 186.40552 -124.75464) (xy 187.73394 -124.75464) (xy 187.73394 -126.01194)
			)
		)
	)
	(zone
		(layer "B.Cu")
		(hatch none 0.5)
		(connect_pads
			(clearance 0)
		)
		(min_thickness 0.25)
		(keepout
			(tracks allowed)
			(vias allowed)
			(pads allowed)
			(copperpour allowed)
			(footprints allowed)
		)
		(placement
			(enabled no)
			(sheetname "")
		)
		(fill
			(thermal_gap 0.5)
			(thermal_bridge_width 0.5)
			(island_removal_mode 0)
		)
		(polygon
			(pts
				(xy 317.31204 -417.428426) (xy 317.31204 -416.42411) (xy 318.688974 -416.42411) (xy 318.688974 -417.428426)
			)
		)
	)
	(zone
		(layer "B.Cu")
		(hatch none 0.5)
		(connect_pads
			(clearance 0)
		)
		(min_thickness 0.25)
		(keepout
			(tracks allowed)
			(vias allowed)
			(pads allowed)
			(copperpour allowed)
			(footprints allowed)
		)
		(placement
			(enabled no)
			(sheetname "")
		)
		(fill
			(thermal_gap 0.5)
			(thermal_bridge_width 0.5)
			(island_removal_mode 0)
		)
		(polygon
			(pts
				(xy 112.950244 -394.180568) (xy 112.950244 -391.48639) (xy 112.950244 -385.965954) (xy 114.69751 -385.965954)
				(xy 114.69751 -384.911854) (xy 134.29234 -384.911854) (xy 134.29234 -385.965954) (xy 134.29234 -394.180568)
			)
		)
	)
	(zone
		(layer "B.Cu")
		(hatch none 0.5)
		(connect_pads
			(clearance 0)
		)
		(min_thickness 0.25)
		(keepout
			(tracks not_allowed)
			(vias allowed)
			(pads allowed)
			(copperpour not_allowed)
			(footprints allowed)
		)
		(placement
			(enabled no)
			(sheetname "")
		)
		(fill
			(thermal_gap 0.5)
			(thermal_bridge_width 0.5)
			(island_removal_mode 0)
		)
		(polygon
			(pts
				(arc
					(start 181.631082 -376.489976)
					(mid 173.36897 -376.489976)
					(end 181.631082 -376.489976)
				)
			)
		)
	)
	(zone
		(layer "B.Cu")
		(hatch none 0.5)
		(connect_pads
			(clearance 0)
		)
		(min_thickness 0.25)
		(keepout
			(tracks allowed)
			(vias allowed)
			(pads allowed)
			(copperpour allowed)
			(footprints allowed)
		)
		(placement
			(enabled no)
			(sheetname "")
		)
		(fill
			(thermal_gap 0.5)
			(thermal_bridge_width 0.5)
			(island_removal_mode 0)
		)
		(polygon
			(pts
				(xy 13.250926 -413.92221) (xy 13.250926 -415.289238) (xy 12.413996 -415.289238) (xy 12.06119 -415.289238)
				(xy 11.99134 -415.219388) (xy 11.99134 -413.70504) (xy 12.074398 -413.621982) (xy 13.109448 -413.621982)
				(xy 13.250926 -413.76346)
			)
		)
	)
	(zone
		(layer "B.Cu")
		(hatch none 0.5)
		(connect_pads
			(clearance 0)
		)
		(min_thickness 0.25)
		(keepout
			(tracks allowed)
			(vias allowed)
			(pads allowed)
			(copperpour allowed)
			(footprints not_allowed)
		)
		(placement
			(enabled no)
			(sheetname "")
		)
		(fill
			(thermal_gap 0.5)
			(thermal_bridge_width 0.5)
			(island_removal_mode 0)
		)
		(polygon
			(pts
				(arc
					(start 347.867986 -244.879876)
					(mid 346.100297 -245.612235)
					(end 345.368118 -247.379998)
				)
				(arc
					(start 345.368118 -270.380206)
					(mid 346.100312 -272.14788)
					(end 347.867986 -272.880074)
				)
				(arc
					(start 371.867938 -272.880074)
					(mid 373.635776 -272.147969)
					(end 374.36806 -270.380206)
				)
				(arc
					(start 374.36806 -247.379998)
					(mid 373.635791 -245.612145)
					(end 371.867938 -244.879876)
				)
			)
		)
	)
	(zone
		(layer "B.Cu")
		(hatch none 0.5)
		(connect_pads
			(clearance 0)
		)
		(min_thickness 0.25)
		(keepout
			(tracks allowed)
			(vias allowed)
			(pads allowed)
			(copperpour allowed)
			(footprints not_allowed)
		)
		(placement
			(enabled no)
			(sheetname "")
		)
		(fill
			(thermal_gap 0.5)
			(thermal_bridge_width 0.5)
			(island_removal_mode 0)
		)
		(polygon
			(pts
				(arc
					(start 363.052106 -340.315042)
					(mid 359.952036 -337.214972)
					(end 356.851966 -340.315042)
				)
				(arc
					(start 356.851966 -340.315042)
					(mid 359.952036 -343.415112)
					(end 363.052106 -340.315042)
				)
			)
		)
	)
	(zone
		(layer "B.Cu")
		(hatch none 0.5)
		(connect_pads
			(clearance 0)
		)
		(min_thickness 0.25)
		(keepout
			(tracks allowed)
			(vias allowed)
			(pads allowed)
			(copperpour allowed)
			(footprints not_allowed)
		)
		(placement
			(enabled no)
			(sheetname "")
		)
		(fill
			(thermal_gap 0.5)
			(thermal_bridge_width 0.5)
			(island_removal_mode 0)
		)
		(polygon
			(pts
				(arc
					(start 241.949986 -39.420038)
					(mid 239.94999 -37.420042)
					(end 237.949994 -39.420038)
				)
				(arc
					(start 237.949994 -39.420038)
					(mid 239.94999 -41.420034)
					(end 241.949986 -39.420038)
				)
			)
		)
	)
	(zone
		(layer "B.Cu")
		(hatch none 0.5)
		(connect_pads
			(clearance 0)
		)
		(min_thickness 0.25)
		(keepout
			(tracks not_allowed)
			(vias allowed)
			(pads allowed)
			(copperpour not_allowed)
			(footprints allowed)
		)
		(placement
			(enabled no)
			(sheetname "")
		)
		(fill
			(thermal_gap 0.5)
			(thermal_bridge_width 0.5)
			(island_removal_mode 0)
		)
		(polygon
			(pts
				(arc
					(start 355.336094 -247.724168)
					(mid 354.706174 -247.724168)
					(end 355.336094 -247.724168)
				)
			)
		)
	)
	(zone
		(layer "B.Cu")
		(hatch none 0.5)
		(connect_pads
			(clearance 0)
		)
		(min_thickness 0.25)
		(keepout
			(tracks not_allowed)
			(vias allowed)
			(pads allowed)
			(copperpour not_allowed)
			(footprints allowed)
		)
		(placement
			(enabled no)
			(sheetname "")
		)
		(fill
			(thermal_gap 0.5)
			(thermal_bridge_width 0.5)
			(island_removal_mode 0)
		)
		(polygon
			(pts
				(arc
					(start 239.450118 -352.49993)
					(mid 236.650022 -349.699834)
					(end 233.849926 -352.49993)
				)
				(arc
					(start 233.849926 -352.49993)
					(mid 236.650022 -355.300026)
					(end 239.450118 -352.49993)
				)
			)
		)
	)
	(zone
		(layer "B.Cu")
		(hatch none 0.5)
		(connect_pads
			(clearance 0)
		)
		(min_thickness 0.25)
		(keepout
			(tracks not_allowed)
			(vias allowed)
			(pads allowed)
			(copperpour not_allowed)
			(footprints allowed)
		)
		(placement
			(enabled no)
			(sheetname "")
		)
		(fill
			(thermal_gap 0.5)
			(thermal_bridge_width 0.5)
			(island_removal_mode 0)
		)
		(polygon
			(pts
				(arc
					(start 151.378158 -393.292838)
					(mid 150.710138 -393.292838)
					(end 151.378158 -393.292838)
				)
			)
		)
	)
	(zone
		(layer "B.Cu")
		(hatch none 0.5)
		(connect_pads
			(clearance 0)
		)
		(min_thickness 0.25)
		(keepout
			(tracks allowed)
			(vias allowed)
			(pads allowed)
			(copperpour allowed)
			(footprints allowed)
		)
		(placement
			(enabled no)
			(sheetname "")
		)
		(fill
			(thermal_gap 0.5)
			(thermal_bridge_width 0.5)
			(island_removal_mode 0)
		)
		(polygon
			(pts
				(xy 249.77344 1.84658) (xy 249.77344 3.67284) (xy 251.93244 3.67284) (xy 251.93244 1.84658)
			)
		)
	)
	(zone
		(layer "B.Cu")
		(hatch none 0.5)
		(connect_pads
			(clearance 0)
		)
		(min_thickness 0.25)
		(keepout
			(tracks allowed)
			(vias allowed)
			(pads allowed)
			(copperpour allowed)
			(footprints not_allowed)
		)
		(placement
			(enabled no)
			(sheetname "")
		)
		(fill
			(thermal_gap 0.5)
			(thermal_bridge_width 0.5)
			(island_removal_mode 0)
		)
		(polygon
			(pts
				(arc
					(start 185.661554 -440.989974)
					(mid 179.749958 -427.600233)
					(end 173.838362 -440.989974)
				)
			)
		)
	)
	(zone
		(layer "B.Cu")
		(hatch none 0.5)
		(connect_pads
			(clearance 0)
		)
		(min_thickness 0.25)
		(keepout
			(tracks allowed)
			(vias allowed)
			(pads allowed)
			(copperpour allowed)
			(footprints allowed)
		)
		(placement
			(enabled no)
			(sheetname "")
		)
		(fill
			(thermal_gap 0.5)
			(thermal_bridge_width 0.5)
			(island_removal_mode 0)
		)
		(polygon
			(pts
				(xy 55.185818 -409.046426) (xy 55.185818 -408.04211) (xy 56.562752 -408.04211) (xy 56.562752 -409.046426)
			)
		)
	)
	(zone
		(layer "B.Cu")
		(hatch none 0.5)
		(connect_pads
			(clearance 0)
		)
		(min_thickness 0.25)
		(keepout
			(tracks allowed)
			(vias allowed)
			(pads allowed)
			(copperpour allowed)
			(footprints not_allowed)
		)
		(placement
			(enabled no)
			(sheetname "")
		)
		(fill
			(thermal_gap 0.5)
			(thermal_bridge_width 0.5)
			(island_removal_mode 0)
		)
		(polygon
			(pts
				(arc
					(start 231.650032 -192.499996)
					(mid 236.650022 -197.499986)
					(end 241.650012 -192.499996)
				)
				(arc
					(start 241.650012 -192.499996)
					(mid 236.650022 -187.500006)
					(end 231.650032 -192.499996)
				)
			)
		)
	)
	(zone
		(layer "B.Cu")
		(hatch none 0.5)
		(connect_pads
			(clearance 0)
		)
		(min_thickness 0.25)
		(keepout
			(tracks allowed)
			(vias allowed)
			(pads allowed)
			(copperpour allowed)
			(footprints not_allowed)
		)
		(placement
			(enabled no)
			(sheetname "")
		)
		(fill
			(thermal_gap 0.5)
			(thermal_bridge_width 0.5)
			(island_removal_mode 0)
		)
		(polygon
			(pts
				(arc
					(start 145.32991 -212.989922)
					(mid 142.530068 -210.19008)
					(end 139.729972 -212.989922)
				)
				(arc
					(start 139.729972 -212.989922)
					(mid 142.530068 -215.790018)
					(end 145.32991 -212.989922)
				)
			)
		)
	)
	(zone
		(layer "B.Cu")
		(hatch none 0.5)
		(connect_pads
			(clearance 0)
		)
		(min_thickness 0.25)
		(keepout
			(tracks not_allowed)
			(vias allowed)
			(pads allowed)
			(copperpour not_allowed)
			(footprints allowed)
		)
		(placement
			(enabled no)
			(sheetname "")
		)
		(fill
			(thermal_gap 0.5)
			(thermal_bridge_width 0.5)
			(island_removal_mode 0)
		)
		(polygon
			(pts
				(arc
					(start 449.33997 -40.420036)
					(mid 447.44005 -38.520116)
					(end 445.539876 -40.420036)
				)
				(arc
					(start 445.539876 -40.420036)
					(mid 447.44005 -42.32021)
					(end 449.33997 -40.420036)
				)
			)
		)
	)
	(zone
		(layer "B.Cu")
		(hatch none 0.5)
		(connect_pads
			(clearance 0)
		)
		(min_thickness 0.25)
		(keepout
			(tracks allowed)
			(vias allowed)
			(pads allowed)
			(copperpour allowed)
			(footprints allowed)
		)
		(placement
			(enabled no)
			(sheetname "")
		)
		(fill
			(thermal_gap 0.5)
			(thermal_bridge_width 0.5)
			(island_removal_mode 0)
		)
		(polygon
			(pts
				(xy 70.502018 -409.046426) (xy 70.502018 -408.04211) (xy 71.878952 -408.04211) (xy 71.878952 -409.046426)
			)
		)
	)
	(zone
		(layer "B.Cu")
		(hatch none 0.5)
		(connect_pads
			(clearance 0)
		)
		(min_thickness 0.25)
		(keepout
			(tracks not_allowed)
			(vias allowed)
			(pads allowed)
			(copperpour not_allowed)
			(footprints allowed)
		)
		(placement
			(enabled no)
			(sheetname "")
		)
		(fill
			(thermal_gap 0.5)
			(thermal_bridge_width 0.5)
			(island_removal_mode 0)
		)
		(polygon
			(pts
				(arc
					(start 126.18974 -244.484398)
					(mid 125.55982 -244.484398)
					(end 126.18974 -244.484398)
				)
			)
		)
	)
	(zone
		(layer "B.Cu")
		(hatch none 0.5)
		(connect_pads
			(clearance 0)
		)
		(min_thickness 0.25)
		(keepout
			(tracks allowed)
			(vias allowed)
			(pads allowed)
			(copperpour allowed)
			(footprints not_allowed)
		)
		(placement
			(enabled no)
			(sheetname "")
		)
		(fill
			(thermal_gap 0.5)
			(thermal_bridge_width 0.5)
			(island_removal_mode 0)
		)
		(polygon
			(pts
				(arc
					(start 18.91157 -440.989974)
					(mid 18.603422 -429.890528)
					(end 7.500112 -429.790606)
				)
				(arc
					(start 7.500112 -439.989976)
					(mid 7.793005 -440.697081)
					(end 8.50011 -440.989974)
				)
			)
		)
	)
	(zone
		(layer "B.Cu")
		(hatch none 0.5)
		(connect_pads
			(clearance 0)
		)
		(min_thickness 0.25)
		(keepout
			(tracks allowed)
			(vias allowed)
			(pads allowed)
			(copperpour allowed)
			(footprints not_allowed)
		)
		(placement
			(enabled no)
			(sheetname "")
		)
		(fill
			(thermal_gap 0.5)
			(thermal_bridge_width 0.5)
			(island_removal_mode 0)
		)
		(polygon
			(pts
				(arc
					(start 32.563054 -74.767948)
					(mid 45.063156 -87.26094)
					(end 57.563004 -74.767948)
				)
				(arc
					(start 57.563004 -66.061082)
					(mid 45.063156 -53.561234)
					(end 32.563054 -66.061082)
				)
			)
		)
	)
	(zone
		(layer "B.Cu")
		(hatch none 0.5)
		(connect_pads
			(clearance 0)
		)
		(min_thickness 0.25)
		(keepout
			(tracks not_allowed)
			(vias allowed)
			(pads allowed)
			(copperpour not_allowed)
			(footprints allowed)
		)
		(placement
			(enabled no)
			(sheetname "")
		)
		(fill
			(thermal_gap 0.5)
			(thermal_bridge_width 0.5)
			(island_removal_mode 0)
		)
		(polygon
			(pts
				(arc
					(start 407.378154 -401.674838)
					(mid 406.710134 -401.674838)
					(end 407.378154 -401.674838)
				)
			)
		)
	)
	(zone
		(layer "B.Cu")
		(hatch none 0.5)
		(connect_pads
			(clearance 0)
		)
		(min_thickness 0.25)
		(keepout
			(tracks not_allowed)
			(vias allowed)
			(pads allowed)
			(copperpour not_allowed)
			(footprints allowed)
		)
		(placement
			(enabled no)
			(sheetname "")
		)
		(fill
			(thermal_gap 0.5)
			(thermal_bridge_width 0.5)
			(island_removal_mode 0)
		)
		(polygon
			(pts
				(arc
					(start 304.150268 -400.811238)
					(mid 303.482248 -400.811238)
					(end 304.150268 -400.811238)
				)
			)
		)
	)
	(zone
		(layer "B.Cu")
		(hatch none 0.5)
		(connect_pads
			(clearance 0)
		)
		(min_thickness 0.25)
		(keepout
			(tracks not_allowed)
			(vias allowed)
			(pads allowed)
			(copperpour not_allowed)
			(footprints allowed)
		)
		(placement
			(enabled no)
			(sheetname "")
		)
		(fill
			(thermal_gap 0.5)
			(thermal_bridge_width 0.5)
			(island_removal_mode 0)
		)
		(polygon
			(pts
				(arc
					(start 403.137116 -436.889906)
					(mid 402.362924 -436.889906)
					(end 403.137116 -436.889906)
				)
			)
		)
	)
	(zone
		(layer "B.Cu")
		(hatch none 0.5)
		(connect_pads
			(clearance 0)
		)
		(min_thickness 0.25)
		(keepout
			(tracks allowed)
			(vias allowed)
			(pads allowed)
			(copperpour allowed)
			(footprints allowed)
		)
		(placement
			(enabled no)
			(sheetname "")
		)
		(fill
			(thermal_gap 0.5)
			(thermal_bridge_width 0.5)
			(island_removal_mode 0)
		)
		(polygon
			(pts
				(xy 422.275762 -393.293854) (xy 422.275762 -391.776966) (xy 422.268396 -391.7696) (xy 422.268396 -391.258806)
				(xy 421.722042 -390.712452) (xy 420.441628 -390.712452) (xy 420.223696 -390.930384) (xy 404.22322 -390.930384)
				(xy 403.672802 -391.480802) (xy 403.672802 -393.293854)
			)
		)
	)
	(zone
		(layer "B.Cu")
		(hatch none 0.5)
		(connect_pads
			(clearance 0)
		)
		(min_thickness 0.25)
		(keepout
			(tracks allowed)
			(vias allowed)
			(pads allowed)
			(copperpour allowed)
			(footprints not_allowed)
		)
		(placement
			(enabled no)
			(sheetname "")
		)
		(fill
			(thermal_gap 0.5)
			(thermal_bridge_width 0.5)
			(island_removal_mode 0)
		)
		(polygon
			(pts
				(arc
					(start 18.05686 -345.590622)
					(mid 10.90839 -339.720399)
					(end 2.999994 -344.518234)
				)
				(arc
					(start 2.999994 -350.88195)
					(mid 10.815277 -355.685791)
					(end 18.005552 -349.988632)
				)
				(arc
					(start 18.005552 -349.988632)
					(mid 23.315563 -347.851344)
					(end 18.05686 -345.590622)
				)
			)
		)
	)
	(zone
		(layer "B.Cu")
		(hatch none 0.5)
		(connect_pads
			(clearance 0)
		)
		(min_thickness 0.25)
		(keepout
			(tracks not_allowed)
			(vias allowed)
			(pads allowed)
			(copperpour not_allowed)
			(footprints allowed)
		)
		(placement
			(enabled no)
			(sheetname "")
		)
		(fill
			(thermal_gap 0.5)
			(thermal_bridge_width 0.5)
			(island_removal_mode 0)
		)
		(polygon
			(pts
				(arc
					(start 332.036928 -438.089802)
					(mid 331.262736 -438.089802)
					(end 332.036928 -438.089802)
				)
			)
		)
	)
	(zone
		(layer "B.Cu")
		(hatch none 0.5)
		(connect_pads
			(clearance 0)
		)
		(min_thickness 0.25)
		(keepout
			(tracks allowed)
			(vias allowed)
			(pads allowed)
			(copperpour allowed)
			(footprints not_allowed)
		)
		(placement
			(enabled no)
			(sheetname "")
		)
		(fill
			(thermal_gap 0.5)
			(thermal_bridge_width 0.5)
			(island_removal_mode 0)
		)
		(polygon
			(pts
				(arc
					(start 254.124968 -360.764074)
					(mid 258.12496 -364.764066)
					(end 262.124952 -360.764074)
				)
				(arc
					(start 262.124952 -360.764074)
					(mid 258.12496 -356.764082)
					(end 254.124968 -360.764074)
				)
			)
		)
	)
	(zone
		(layer "B.Cu")
		(hatch none 0.5)
		(connect_pads
			(clearance 0)
		)
		(min_thickness 0.25)
		(keepout
			(tracks allowed)
			(vias allowed)
			(pads allowed)
			(copperpour allowed)
			(footprints allowed)
		)
		(placement
			(enabled no)
			(sheetname "")
		)
		(fill
			(thermal_gap 0.5)
			(thermal_bridge_width 0.5)
			(island_removal_mode 0)
		)
		(polygon
			(pts
				(xy 52.677314 -418.542978) (xy 52.677314 -419.910006) (xy 51.840384 -419.910006) (xy 51.840384 -418.542978)
			)
		)
	)
	(zone
		(layer "B.Cu")
		(hatch none 0.5)
		(connect_pads
			(clearance 0)
		)
		(min_thickness 0.25)
		(keepout
			(tracks allowed)
			(vias allowed)
			(pads allowed)
			(copperpour allowed)
			(footprints allowed)
		)
		(placement
			(enabled no)
			(sheetname "")
		)
		(fill
			(thermal_gap 0.5)
			(thermal_bridge_width 0.5)
			(island_removal_mode 0)
		)
		(polygon
			(pts
				(xy 152.91816 -409.046426) (xy 152.91816 -408.04211) (xy 154.295094 -408.04211) (xy 154.295094 -409.046426)
			)
		)
	)
	(zone
		(layer "B.Cu")
		(hatch none 0.5)
		(connect_pads
			(clearance 0)
		)
		(min_thickness 0.25)
		(keepout
			(tracks not_allowed)
			(vias allowed)
			(pads allowed)
			(copperpour not_allowed)
			(footprints allowed)
		)
		(placement
			(enabled no)
			(sheetname "")
		)
		(fill
			(thermal_gap 0.5)
			(thermal_bridge_width 0.5)
			(island_removal_mode 0)
		)
		(polygon
			(pts
				(arc
					(start 351.576132 -246.104156)
					(mid 350.946212 -246.104156)
					(end 351.576132 -246.104156)
				)
			)
		)
	)
	(zone
		(layer "B.Cu")
		(hatch none 0.5)
		(connect_pads
			(clearance 0)
		)
		(min_thickness 0.25)
		(keepout
			(tracks allowed)
			(vias allowed)
			(pads allowed)
			(copperpour allowed)
			(footprints allowed)
		)
		(placement
			(enabled no)
			(sheetname "")
		)
		(fill
			(thermal_gap 0.5)
			(thermal_bridge_width 0.5)
			(island_removal_mode 0)
		)
		(polygon
			(pts
				(xy 335.69148 -417.428426) (xy 335.69148 -416.42411) (xy 337.068414 -416.42411) (xy 337.068414 -417.428426)
			)
		)
	)
	(zone
		(layer "B.Cu")
		(hatch none 0.5)
		(connect_pads
			(clearance 0)
		)
		(min_thickness 0.25)
		(keepout
			(tracks allowed)
			(vias allowed)
			(pads allowed)
			(copperpour allowed)
			(footprints not_allowed)
		)
		(placement
			(enabled no)
			(sheetname "")
		)
		(fill
			(thermal_gap 0.5)
			(thermal_bridge_width 0.5)
			(island_removal_mode 0)
		)
		(polygon
			(pts
				(arc
					(start 9.970008 -389.439912)
					(mid 6.870192 -386.340096)
					(end 3.770122 -389.439912)
				)
				(arc
					(start 3.770122 -389.439912)
					(mid 6.870192 -392.539982)
					(end 9.970008 -389.439912)
				)
			)
		)
	)
	(zone
		(layer "B.Cu")
		(hatch none 0.5)
		(connect_pads
			(clearance 0)
		)
		(min_thickness 0.25)
		(keepout
			(tracks allowed)
			(vias allowed)
			(pads allowed)
			(copperpour allowed)
			(footprints allowed)
		)
		(placement
			(enabled no)
			(sheetname "")
		)
		(fill
			(thermal_gap 0.5)
			(thermal_bridge_width 0.5)
			(island_removal_mode 0)
		)
		(polygon
			(pts
				(xy 122.28576 -409.046426) (xy 122.28576 -408.04211) (xy 123.662694 -408.04211) (xy 123.662694 -409.046426)
			)
		)
	)
	(zone
		(layer "B.Cu")
		(hatch none 0.5)
		(connect_pads
			(clearance 0)
		)
		(min_thickness 0.25)
		(keepout
			(tracks not_allowed)
			(vias allowed)
			(pads allowed)
			(copperpour not_allowed)
			(footprints allowed)
		)
		(placement
			(enabled no)
			(sheetname "")
		)
		(fill
			(thermal_gap 0.5)
			(thermal_bridge_width 0.5)
			(island_removal_mode 0)
		)
		(polygon
			(pts
				(arc
					(start 393.269978 -304.790094)
					(mid 390.470136 -301.990252)
					(end 387.67004 -304.790094)
				)
				(arc
					(start 387.67004 -304.790094)
					(mid 390.470136 -307.59019)
					(end 393.269978 -304.790094)
				)
			)
		)
	)
	(zone
		(layer "B.Cu")
		(hatch none 0.5)
		(connect_pads
			(clearance 0)
		)
		(min_thickness 0.25)
		(keepout
			(tracks allowed)
			(vias allowed)
			(pads allowed)
			(copperpour allowed)
			(footprints not_allowed)
		)
		(placement
			(enabled no)
			(sheetname "")
		)
		(fill
			(thermal_gap 0.5)
			(thermal_bridge_width 0.5)
			(island_removal_mode 0)
		)
		(polygon
			(pts
				(arc
					(start 115.816126 -340.315042)
					(mid 112.716056 -337.214972)
					(end 109.615986 -340.315042)
				)
				(arc
					(start 109.615986 -340.315042)
					(mid 112.716056 -343.415112)
					(end 115.816126 -340.315042)
				)
			)
		)
	)
	(zone
		(layer "B.Cu")
		(hatch none 0.5)
		(connect_pads
			(clearance 0)
		)
		(min_thickness 0.25)
		(keepout
			(tracks allowed)
			(vias allowed)
			(pads allowed)
			(copperpour allowed)
			(footprints allowed)
		)
		(placement
			(enabled no)
			(sheetname "")
		)
		(fill
			(thermal_gap 0.5)
			(thermal_bridge_width 0.5)
			(island_removal_mode 0)
		)
		(polygon
			(pts
				(xy 79.691738 -409.046426) (xy 79.691738 -408.04211) (xy 81.068672 -408.04211) (xy 81.068672 -409.046426)
			)
		)
	)
	(zone
		(layer "B.Cu")
		(hatch none 0.5)
		(connect_pads
			(clearance 0)
		)
		(min_thickness 0.25)
		(keepout
			(tracks not_allowed)
			(vias allowed)
			(pads allowed)
			(copperpour not_allowed)
			(footprints allowed)
		)
		(placement
			(enabled no)
			(sheetname "")
		)
		(fill
			(thermal_gap 0.5)
			(thermal_bridge_width 0.5)
			(island_removal_mode 0)
		)
		(polygon
			(pts
				(arc
					(start 408.578304 -400.811238)
					(mid 407.910284 -400.811238)
					(end 408.578304 -400.811238)
				)
			)
		)
	)
	(zone
		(layer "B.Cu")
		(hatch none 0.5)
		(connect_pads
			(clearance 0)
		)
		(min_thickness 0.25)
		(keepout
			(tracks not_allowed)
			(vias allowed)
			(pads allowed)
			(copperpour not_allowed)
			(footprints allowed)
		)
		(placement
			(enabled no)
			(sheetname "")
		)
		(fill
			(thermal_gap 0.5)
			(thermal_bridge_width 0.5)
			(island_removal_mode 0)
		)
		(polygon
			(pts
				(arc
					(start 147.778216 -393.292838)
					(mid 147.110196 -393.292838)
					(end 147.778216 -393.292838)
				)
			)
		)
	)
	(zone
		(layer "B.Cu")
		(hatch none 0.5)
		(connect_pads
			(clearance 0)
		)
		(min_thickness 0.25)
		(keepout
			(tracks not_allowed)
			(vias allowed)
			(pads allowed)
			(copperpour not_allowed)
			(footprints allowed)
		)
		(placement
			(enabled no)
			(sheetname "")
		)
		(fill
			(thermal_gap 0.5)
			(thermal_bridge_width 0.5)
			(island_removal_mode 0)
		)
		(polygon
			(pts
				(arc
					(start 15.80007 -435.600094)
					(mid 12.999974 -432.799998)
					(end 10.199878 -435.600094)
				)
				(arc
					(start 10.199878 -435.600094)
					(mid 12.999974 -438.40019)
					(end 15.80007 -435.600094)
				)
			)
		)
	)
	(zone
		(layer "B.Cu")
		(hatch none 0.5)
		(connect_pads
			(clearance 0)
		)
		(min_thickness 0.25)
		(keepout
			(tracks allowed)
			(vias allowed)
			(pads allowed)
			(copperpour allowed)
			(footprints not_allowed)
		)
		(placement
			(enabled no)
			(sheetname "")
		)
		(fill
			(thermal_gap 0.5)
			(thermal_bridge_width 0.5)
			(island_removal_mode 0)
		)
		(polygon
			(pts
				(arc
					(start 206.199994 -22.29993)
					(mid 203.400152 -19.500088)
					(end 200.600056 -22.29993)
				)
				(arc
					(start 200.600056 -22.29993)
					(mid 203.400152 -25.100026)
					(end 206.199994 -22.29993)
				)
			)
		)
	)
	(zone
		(layer "B.Cu")
		(hatch none 0.5)
		(connect_pads
			(clearance 0)
		)
		(min_thickness 0.25)
		(keepout
			(tracks allowed)
			(vias allowed)
			(pads allowed)
			(copperpour allowed)
			(footprints not_allowed)
		)
		(placement
			(enabled no)
			(sheetname "")
		)
		(fill
			(thermal_gap 0.5)
			(thermal_bridge_width 0.5)
			(island_removal_mode 0)
		)
		(polygon
			(pts
				(arc
					(start 68.482972 -47.049944)
					(mid 70.383146 -48.950118)
					(end 72.283066 -47.049944)
				)
				(arc
					(start 72.283066 -47.049944)
					(mid 70.383146 -45.150024)
					(end 68.482972 -47.049944)
				)
			)
		)
	)
	(zone
		(layer "B.Cu")
		(hatch none 0.5)
		(connect_pads
			(clearance 0)
		)
		(min_thickness 0.25)
		(keepout
			(tracks not_allowed)
			(vias allowed)
			(pads allowed)
			(copperpour not_allowed)
			(footprints allowed)
		)
		(placement
			(enabled no)
			(sheetname "")
		)
		(fill
			(thermal_gap 0.5)
			(thermal_bridge_width 0.5)
			(island_removal_mode 0)
		)
		(polygon
			(pts
				(arc
					(start 231.650032 -272.50009)
					(mid 236.650022 -277.50008)
					(end 241.650012 -272.50009)
				)
				(arc
					(start 241.650012 -272.50009)
					(mid 236.650022 -267.5001)
					(end 231.650032 -272.50009)
				)
			)
		)
	)
	(zone
		(layer "B.Cu")
		(hatch none 0.5)
		(connect_pads
			(clearance 0)
		)
		(min_thickness 0.25)
		(keepout
			(tracks allowed)
			(vias allowed)
			(pads allowed)
			(copperpour allowed)
			(footprints not_allowed)
		)
		(placement
			(enabled no)
			(sheetname "")
		)
		(fill
			(thermal_gap 0.5)
			(thermal_bridge_width 0.5)
			(island_removal_mode 0)
		)
		(polygon
			(pts
				(arc
					(start 434.623718 -418.183568)
					(mid 432.978035 -420.348493)
					(end 430.385728 -421.1701)
				)
				(arc
					(start 426.257466 -421.1701)
					(mid 424.535345 -420.827549)
					(end 423.075354 -419.852094)
				)
				(arc
					(start 419.582854 -416.35934)
					(mid 419.096199 -416.034167)
					(end 418.52215 -415.91992)
				)
				(arc
					(start 306.047902 -415.91992)
					(mid 305.473829 -416.03411)
					(end 304.987198 -416.35934)
				)
				(arc
					(start 301.494698 -419.852094)
					(mid 300.034733 -420.827612)
					(end 298.312586 -421.1701)
				)
				(arc
					(start 293.176198 -421.1701)
					(mid 290.590477 -420.352888)
					(end 288.943796 -418.1983)
				)
				(arc
					(start 285.687516 -409.181046)
					(mid 285.487407 -408.428502)
					(end 285.420054 -407.652728)
				)
				(arc
					(start 285.420054 -395.112748)
					(mid 285.305864 -394.538675)
					(end 284.980634 -394.052044)
				)
				(arc
					(start 284.388052 -393.459462)
					(mid 283.412534 -391.999497)
					(end 283.070046 -390.27735)
				)
				(arc
					(start 283.070046 -381.812546)
					(mid 283.412578 -380.090523)
					(end 284.388052 -378.630688)
				)
				(arc
					(start 298.33062 -364.68812)
					(mid 299.790585 -363.712602)
					(end 301.512732 -363.370114)
				)
				(arc
					(start 426.257466 -363.370114)
					(mid 427.979489 -363.712646)
					(end 429.439324 -364.68812)
				)
				(arc
					(start 440.182 -375.430542)
					(mid 441.157518 -376.890507)
					(end 441.500006 -378.612654)
				)
				(arc
					(start 441.500006 -398.150334)
					(mid 441.43402 -398.918399)
					(end 441.237878 -399.66392)
				)
			)
		)
	)
	(zone
		(layer "B.Cu")
		(hatch none 0.5)
		(connect_pads
			(clearance 0)
		)
		(min_thickness 0.25)
		(keepout
			(tracks allowed)
			(vias allowed)
			(pads allowed)
			(copperpour allowed)
			(footprints not_allowed)
		)
		(placement
			(enabled no)
			(sheetname "")
		)
		(fill
			(thermal_gap 0.5)
			(thermal_bridge_width 0.5)
			(island_removal_mode 0)
		)
		(polygon
			(pts
				(arc
					(start 51.616102 -167.135048)
					(mid 54.716172 -170.235118)
					(end 57.815988 -167.135048)
				)
				(arc
					(start 57.815988 -167.135048)
					(mid 54.716172 -164.035232)
					(end 51.616102 -167.135048)
				)
			)
		)
	)
	(zone
		(layer "B.Cu")
		(hatch none 0.5)
		(connect_pads
			(clearance 0)
		)
		(min_thickness 0.25)
		(keepout
			(tracks allowed)
			(vias allowed)
			(pads allowed)
			(copperpour allowed)
			(footprints allowed)
		)
		(placement
			(enabled no)
			(sheetname "")
		)
		(fill
			(thermal_gap 0.5)
			(thermal_bridge_width 0.5)
			(island_removal_mode 0)
		)
		(polygon
			(pts
				(xy 162.85972 -193.92646) (xy 162.85972 -192.6082) (xy 163.8427 -192.6082) (xy 163.8427 -193.92646)
			)
		)
	)
	(zone
		(layer "B.Cu")
		(hatch none 0.5)
		(connect_pads
			(clearance 0)
		)
		(min_thickness 0.25)
		(keepout
			(tracks not_allowed)
			(vias allowed)
			(pads allowed)
			(copperpour not_allowed)
			(footprints allowed)
		)
		(placement
			(enabled no)
			(sheetname "")
		)
		(fill
			(thermal_gap 0.5)
			(thermal_bridge_width 0.5)
			(island_removal_mode 0)
		)
		(polygon
			(pts
				(arc
					(start 107.696 -270.03629)
					(mid 107.06608 -270.03629)
					(end 107.696 -270.03629)
				)
			)
		)
	)
	(zone
		(layer "B.Cu")
		(hatch none 0.5)
		(connect_pads
			(clearance 0)
		)
		(min_thickness 0.25)
		(keepout
			(tracks allowed)
			(vias allowed)
			(pads allowed)
			(copperpour allowed)
			(footprints not_allowed)
		)
		(placement
			(enabled no)
			(sheetname "")
		)
		(fill
			(thermal_gap 0.5)
			(thermal_bridge_width 0.5)
			(island_removal_mode 0)
		)
		(polygon
			(pts
				(arc
					(start 246.800116 -290.900104)
					(mid 249.900186 -294.000174)
					(end 253.000002 -290.900104)
				)
				(arc
					(start 253.000002 -290.900104)
					(mid 249.900186 -287.800288)
					(end 246.800116 -290.900104)
				)
			)
		)
	)
	(zone
		(layer "B.Cu")
		(hatch none 0.5)
		(connect_pads
			(clearance 0)
		)
		(min_thickness 0.25)
		(keepout
			(tracks allowed)
			(vias allowed)
			(pads allowed)
			(copperpour allowed)
			(footprints allowed)
		)
		(placement
			(enabled no)
			(sheetname "")
		)
		(fill
			(thermal_gap 0.5)
			(thermal_bridge_width 0.5)
			(island_removal_mode 0)
		)
		(polygon
			(pts
				(xy 320.37528 -417.428426) (xy 320.37528 -416.42411) (xy 321.752214 -416.42411) (xy 321.752214 -417.428426)
			)
		)
	)
	(zone
		(layer "B.Cu")
		(hatch none 0.5)
		(connect_pads
			(clearance 0)
		)
		(min_thickness 0.25)
		(keepout
			(tracks allowed)
			(vias allowed)
			(pads allowed)
			(copperpour allowed)
			(footprints allowed)
		)
		(placement
			(enabled no)
			(sheetname "")
		)
		(fill
			(thermal_gap 0.5)
			(thermal_bridge_width 0.5)
			(island_removal_mode 0)
		)
		(polygon
			(pts
				(xy 390.538716 -417.428426) (xy 390.538716 -416.42411) (xy 391.91565 -416.42411) (xy 391.91565 -417.428426)
			)
		)
	)
	(zone
		(layer "B.Cu")
		(hatch none 0.5)
		(connect_pads
			(clearance 0)
		)
		(min_thickness 0.25)
		(keepout
			(tracks allowed)
			(vias allowed)
			(pads allowed)
			(copperpour allowed)
			(footprints not_allowed)
		)
		(placement
			(enabled no)
			(sheetname "")
		)
		(fill
			(thermal_gap 0.5)
			(thermal_bridge_width 0.5)
			(island_removal_mode 0)
		)
		(polygon
			(pts
				(arc
					(start 37.569902 -404.789894)
					(mid 41.569894 -408.789886)
					(end 45.569886 -404.789894)
				)
				(arc
					(start 45.569886 -404.789894)
					(mid 41.569894 -400.789902)
					(end 37.569902 -404.789894)
				)
			)
		)
	)
	(zone
		(layer "B.Cu")
		(hatch none 0.5)
		(connect_pads
			(clearance 0)
		)
		(min_thickness 0.25)
		(keepout
			(tracks not_allowed)
			(vias allowed)
			(pads allowed)
			(copperpour not_allowed)
			(footprints allowed)
		)
		(placement
			(enabled no)
			(sheetname "")
		)
		(fill
			(thermal_gap 0.5)
			(thermal_bridge_width 0.5)
			(island_removal_mode 0)
		)
		(polygon
			(pts
				(arc
					(start 140.13688 -439.0898)
					(mid 139.362688 -439.0898)
					(end 140.13688 -439.0898)
				)
			)
		)
	)
	(zone
		(layer "B.Cu")
		(hatch none 0.5)
		(connect_pads
			(clearance 0)
		)
		(min_thickness 0.25)
		(keepout
			(tracks not_allowed)
			(vias allowed)
			(pads allowed)
			(copperpour not_allowed)
			(footprints allowed)
		)
		(placement
			(enabled no)
			(sheetname "")
		)
		(fill
			(thermal_gap 0.5)
			(thermal_bridge_width 0.5)
			(island_removal_mode 0)
		)
		(polygon
			(pts
				(arc
					(start 352.516186 -247.724168)
					(mid 351.886266 -247.724168)
					(end 352.516186 -247.724168)
				)
			)
		)
	)
	(zone
		(layer "B.Cu")
		(hatch none 0.5)
		(connect_pads
			(clearance 0)
		)
		(min_thickness 0.25)
		(keepout
			(tracks allowed)
			(vias allowed)
			(pads allowed)
			(copperpour allowed)
			(footprints not_allowed)
		)
		(placement
			(enabled no)
			(sheetname "")
		)
		(fill
			(thermal_gap 0.5)
			(thermal_bridge_width 0.5)
			(island_removal_mode 0)
		)
		(polygon
			(pts
				(xy 159.770064 -239.862106) (xy 159.770064 -202.362054) (xy 214.769954 -202.362054) (xy 214.769954 -239.862106)
			)
		)
	)
	(zone
		(layer "B.Cu")
		(hatch none 0.5)
		(connect_pads
			(clearance 0)
		)
		(min_thickness 0.25)
		(keepout
			(tracks allowed)
			(vias allowed)
			(pads allowed)
			(copperpour allowed)
			(footprints allowed)
		)
		(placement
			(enabled no)
			(sheetname "")
		)
		(fill
			(thermal_gap 0.5)
			(thermal_bridge_width 0.5)
			(island_removal_mode 0)
		)
		(polygon
			(pts
				(xy 332.62824 -417.428426) (xy 332.62824 -416.42411) (xy 334.005174 -416.42411) (xy 334.005174 -417.428426)
			)
		)
	)
	(zone
		(layer "B.Cu")
		(hatch none 0.5)
		(connect_pads
			(clearance 0)
		)
		(min_thickness 0.25)
		(keepout
			(tracks allowed)
			(vias allowed)
			(pads allowed)
			(copperpour allowed)
			(footprints allowed)
		)
		(placement
			(enabled no)
			(sheetname "")
		)
		(fill
			(thermal_gap 0.5)
			(thermal_bridge_width 0.5)
			(island_removal_mode 0)
		)
		(polygon
			(pts
				(xy 328.46518 6.78942) (xy 328.46518 9.06018) (xy 330.60386 9.06018) (xy 330.60386 6.78942)
			)
		)
	)
	(zone
		(layer "B.Cu")
		(hatch none 0.5)
		(connect_pads
			(clearance 0)
		)
		(min_thickness 0.25)
		(keepout
			(tracks not_allowed)
			(vias allowed)
			(pads allowed)
			(copperpour not_allowed)
			(footprints allowed)
		)
		(placement
			(enabled no)
			(sheetname "")
		)
		(fill
			(thermal_gap 0.5)
			(thermal_bridge_width 0.5)
			(island_removal_mode 0)
		)
		(polygon
			(pts
				(arc
					(start 361.816904 -340.315042)
					(mid 359.952036 -338.450174)
					(end 358.086914 -340.315042)
				)
				(arc
					(start 358.086914 -340.315042)
					(mid 359.952036 -342.180164)
					(end 361.816904 -340.315042)
				)
			)
		)
	)
	(zone
		(layer "B.Cu")
		(hatch none 0.5)
		(connect_pads
			(clearance 0)
		)
		(min_thickness 0.25)
		(keepout
			(tracks not_allowed)
			(vias allowed)
			(pads allowed)
			(copperpour not_allowed)
			(footprints allowed)
		)
		(placement
			(enabled no)
			(sheetname "")
		)
		(fill
			(thermal_gap 0.5)
			(thermal_bridge_width 0.5)
			(island_removal_mode 0)
		)
		(polygon
			(pts
				(arc
					(start 77.829918 -304.790094)
					(mid 81.330038 -308.290214)
					(end 84.829904 -304.790094)
				)
				(arc
					(start 84.829904 -304.790094)
					(mid 81.330038 -301.290228)
					(end 77.829918 -304.790094)
				)
			)
		)
	)
	(zone
		(layer "B.Cu")
		(hatch none 0.5)
		(connect_pads
			(clearance 0)
		)
		(min_thickness 0.25)
		(keepout
			(tracks allowed)
			(vias allowed)
			(pads allowed)
			(copperpour allowed)
			(footprints not_allowed)
		)
		(placement
			(enabled no)
			(sheetname "")
		)
		(fill
			(thermal_gap 0.5)
			(thermal_bridge_width 0.5)
			(island_removal_mode 0)
		)
		(polygon
			(pts
				(arc
					(start 450.349874 -435.600094)
					(mid 448.799966 -434.050186)
					(end 447.250058 -435.600094)
				)
				(arc
					(start 447.250058 -435.600094)
					(mid 448.799966 -437.150002)
					(end 450.349874 -435.600094)
				)
			)
		)
	)
	(zone
		(layer "B.Cu")
		(hatch none 0.5)
		(connect_pads
			(clearance 0)
		)
		(min_thickness 0.25)
		(keepout
			(tracks allowed)
			(vias allowed)
			(pads allowed)
			(copperpour allowed)
			(footprints allowed)
		)
		(placement
			(enabled no)
			(sheetname "")
		)
		(fill
			(thermal_gap 0.5)
			(thermal_bridge_width 0.5)
			(island_removal_mode 0)
		)
		(polygon
			(pts
				(xy 439.70194 -194.0687) (xy 439.70194 -190.70574) (xy 441.84824 -190.70574) (xy 441.84824 -194.0687)
			)
		)
	)
	(zone
		(layer "B.Cu")
		(hatch none 0.5)
		(connect_pads
			(clearance 0)
		)
		(min_thickness 0.25)
		(keepout
			(tracks allowed)
			(vias allowed)
			(pads allowed)
			(copperpour allowed)
			(footprints not_allowed)
		)
		(placement
			(enabled no)
			(sheetname "")
		)
		(fill
			(thermal_gap 0.5)
			(thermal_bridge_width 0.5)
			(island_removal_mode 0)
		)
		(polygon
			(pts
				(arc
					(start 256.15011 -51.999896)
					(mid 268.650212 -64.499998)
					(end 281.15006 -51.999896)
				)
				(arc
					(start 281.15006 -51.999896)
					(mid 268.650212 -39.500048)
					(end 256.15011 -51.999896)
				)
			)
		)
	)
	(zone
		(layer "B.Cu")
		(hatch none 0.5)
		(connect_pads
			(clearance 0)
		)
		(min_thickness 0.25)
		(keepout
			(tracks not_allowed)
			(vias allowed)
			(pads allowed)
			(copperpour not_allowed)
			(footprints allowed)
		)
		(placement
			(enabled no)
			(sheetname "")
		)
		(fill
			(thermal_gap 0.5)
			(thermal_bridge_width 0.5)
			(island_removal_mode 0)
		)
		(polygon
			(pts
				(arc
					(start 327.036684 -436.889906)
					(mid 326.262492 -436.889906)
					(end 327.036684 -436.889906)
				)
			)
		)
	)
	(zone
		(layer "B.Cu")
		(hatch none 0.5)
		(connect_pads
			(clearance 0)
		)
		(min_thickness 0.25)
		(keepout
			(tracks not_allowed)
			(vias allowed)
			(pads allowed)
			(copperpour not_allowed)
			(footprints allowed)
		)
		(placement
			(enabled no)
			(sheetname "")
		)
		(fill
			(thermal_gap 0.5)
			(thermal_bridge_width 0.5)
			(island_removal_mode 0)
		)
		(polygon
			(pts
				(arc
					(start 406.178258 -401.674838)
					(mid 405.510238 -401.674838)
					(end 406.178258 -401.674838)
				)
			)
		)
	)
	(zone
		(layer "B.Cu")
		(hatch none 0.5)
		(connect_pads
			(clearance 0)
		)
		(min_thickness 0.25)
		(keepout
			(tracks allowed)
			(vias allowed)
			(pads allowed)
			(copperpour allowed)
			(footprints allowed)
		)
		(placement
			(enabled no)
			(sheetname "")
		)
		(fill
			(thermal_gap 0.5)
			(thermal_bridge_width 0.5)
			(island_removal_mode 0)
		)
		(polygon
			(pts
				(xy 75.955906 -296.612564) (xy 75.955906 -226.666044) (xy 76.494386 -226.127564) (xy 76.494386 -223.333564)
				(xy 78.653386 -221.174564) (xy 147.919186 -221.174564) (xy 147.919186 -296.612564) (xy 135.336534 -296.612564)
				(xy 135.184134 -296.460164) (xy 131.271772 -296.460164) (xy 131.119372 -296.612564)
			)
		)
	)
	(zone
		(layer "B.Cu")
		(hatch none 0.5)
		(connect_pads
			(clearance 0)
		)
		(min_thickness 0.25)
		(keepout
			(tracks not_allowed)
			(vias allowed)
			(pads allowed)
			(copperpour not_allowed)
			(footprints allowed)
		)
		(placement
			(enabled no)
			(sheetname "")
		)
		(fill
			(thermal_gap 0.5)
			(thermal_bridge_width 0.5)
			(island_removal_mode 0)
		)
		(polygon
			(pts
				(arc
					(start 122.429778 -244.484398)
					(mid 121.799858 -244.484398)
					(end 122.429778 -244.484398)
				)
			)
		)
	)
	(zone
		(layer "B.Cu")
		(hatch none 0.5)
		(connect_pads
			(clearance 0)
		)
		(min_thickness 0.25)
		(keepout
			(tracks allowed)
			(vias allowed)
			(pads allowed)
			(copperpour allowed)
			(footprints not_allowed)
		)
		(placement
			(enabled no)
			(sheetname "")
		)
		(fill
			(thermal_gap 0.5)
			(thermal_bridge_width 0.5)
			(island_removal_mode 0)
		)
		(polygon
			(pts
				(arc
					(start 156.830014 -258.890008)
					(mid 154.030172 -256.090166)
					(end 151.230076 -258.890008)
				)
				(arc
					(start 151.230076 -258.890008)
					(mid 154.030172 -261.690104)
					(end 156.830014 -258.890008)
				)
			)
		)
	)
	(zone
		(layer "B.Cu")
		(hatch none 0.5)
		(connect_pads
			(clearance 0)
		)
		(min_thickness 0.25)
		(keepout
			(tracks allowed)
			(vias allowed)
			(pads allowed)
			(copperpour allowed)
			(footprints allowed)
		)
		(placement
			(enabled no)
			(sheetname "")
		)
		(fill
			(thermal_gap 0.5)
			(thermal_bridge_width 0.5)
			(island_removal_mode 0)
		)
		(polygon
			(pts
				(xy 376.439176 -137.799318) (xy 381.193802 -137.799318) (xy 383.031746 -137.799318) (xy 383.95656 -138.724132)
				(xy 383.95656 -144.89557) (xy 380.807976 -148.044154) (xy 376.56516 -148.044154) (xy 375.939558 -147.418552)
				(xy 373.678958 -145.157952) (xy 373.678958 -140.559536)
			)
		)
	)
	(zone
		(layer "B.Cu")
		(hatch none 0.5)
		(connect_pads
			(clearance 0)
		)
		(min_thickness 0.25)
		(keepout
			(tracks not_allowed)
			(vias allowed)
			(pads allowed)
			(copperpour not_allowed)
			(footprints allowed)
		)
		(placement
			(enabled no)
			(sheetname "")
		)
		(fill
			(thermal_gap 0.5)
			(thermal_bridge_width 0.5)
			(island_removal_mode 0)
		)
		(polygon
			(pts
				(arc
					(start 37.319966 -376.489976)
					(mid 35.070034 -374.240044)
					(end 32.820102 -376.489976)
				)
				(arc
					(start 32.820102 -376.489976)
					(mid 35.070034 -378.739908)
					(end 37.319966 -376.489976)
				)
			)
		)
	)
	(zone
		(layer "B.Cu")
		(hatch none 0.5)
		(connect_pads
			(clearance 0)
		)
		(min_thickness 0.25)
		(keepout
			(tracks not_allowed)
			(vias allowed)
			(pads allowed)
			(copperpour not_allowed)
			(footprints allowed)
		)
		(placement
			(enabled no)
			(sheetname "")
		)
		(fill
			(thermal_gap 0.5)
			(thermal_bridge_width 0.5)
			(island_removal_mode 0)
		)
		(polygon
			(pts
				(arc
					(start 83.330034 -304.790094)
					(mid 81.330038 -302.790098)
					(end 79.330042 -304.790094)
				)
				(arc
					(start 79.330042 -304.790094)
					(mid 81.330038 -306.79009)
					(end 83.330034 -304.790094)
				)
			)
		)
	)
	(zone
		(layer "B.Cu")
		(hatch none 0.5)
		(connect_pads
			(clearance 0)
		)
		(min_thickness 0.25)
		(keepout
			(tracks allowed)
			(vias allowed)
			(pads allowed)
			(copperpour allowed)
			(footprints allowed)
		)
		(placement
			(enabled no)
			(sheetname "")
		)
		(fill
			(thermal_gap 0.5)
			(thermal_bridge_width 0.5)
			(island_removal_mode 0)
		)
		(polygon
			(pts
				(xy 277.97506 -194.32524) (xy 277.97506 -190.51778) (xy 280.2763 -190.51778) (xy 280.2763 -194.32524)
			)
		)
	)
	(zone
		(layer "B.Cu")
		(hatch none 0.5)
		(connect_pads
			(clearance 0)
		)
		(min_thickness 0.25)
		(keepout
			(tracks not_allowed)
			(vias allowed)
			(pads allowed)
			(copperpour not_allowed)
			(footprints allowed)
		)
		(placement
			(enabled no)
			(sheetname "")
		)
		(fill
			(thermal_gap 0.5)
			(thermal_bridge_width 0.5)
			(island_removal_mode 0)
		)
		(polygon
			(pts
				(arc
					(start 125.249686 -244.484398)
					(mid 124.619766 -244.484398)
					(end 125.249686 -244.484398)
				)
			)
		)
	)
	(zone
		(layer "B.Cu")
		(hatch none 0.5)
		(connect_pads
			(clearance 0)
		)
		(min_thickness 0.25)
		(keepout
			(tracks allowed)
			(vias allowed)
			(pads allowed)
			(copperpour allowed)
			(footprints allowed)
		)
		(placement
			(enabled no)
			(sheetname "")
		)
		(fill
			(thermal_gap 0.5)
			(thermal_bridge_width 0.5)
			(island_removal_mode 0)
		)
		(polygon
			(pts
				(xy 137.60196 -409.046426) (xy 137.60196 -408.04211) (xy 138.978894 -408.04211) (xy 138.978894 -409.046426)
			)
		)
	)
	(zone
		(layer "B.Cu")
		(hatch none 0.5)
		(connect_pads
			(clearance 0)
		)
		(min_thickness 0.25)
		(keepout
			(tracks allowed)
			(vias allowed)
			(pads allowed)
			(copperpour allowed)
			(footprints allowed)
		)
		(placement
			(enabled no)
			(sheetname "")
		)
		(fill
			(thermal_gap 0.5)
			(thermal_bridge_width 0.5)
			(island_removal_mode 0)
		)
		(polygon
			(pts
				(xy 104.602026 -24.197056) (xy 107.142026 -24.197056) (xy 107.142026 -24.908256) (xy 104.602026 -24.908256)
			)
		)
	)
	(zone
		(layer "B.Cu")
		(hatch none 0.5)
		(connect_pads
			(clearance 0)
		)
		(min_thickness 0.25)
		(keepout
			(tracks allowed)
			(vias allowed)
			(pads allowed)
			(copperpour allowed)
			(footprints allowed)
		)
		(placement
			(enabled no)
			(sheetname "")
		)
		(fill
			(thermal_gap 0.5)
			(thermal_bridge_width 0.5)
			(island_removal_mode 0)
		)
		(polygon
			(pts
				(xy 187.549028 -95.435674) (xy 187.549028 -94.767146) (xy 189.153546 -94.767146) (xy 189.153546 -95.435674)
			)
		)
	)
	(zone
		(layer "B.Cu")
		(hatch none 0.5)
		(connect_pads
			(clearance 0)
		)
		(min_thickness 0.25)
		(keepout
			(tracks not_allowed)
			(vias allowed)
			(pads allowed)
			(copperpour not_allowed)
			(footprints allowed)
		)
		(placement
			(enabled no)
			(sheetname "")
		)
		(fill
			(thermal_gap 0.5)
			(thermal_bridge_width 0.5)
			(island_removal_mode 0)
		)
		(polygon
			(pts
				(arc
					(start 157.3784 -392.429238)
					(mid 156.71038 -392.429238)
					(end 157.3784 -392.429238)
				)
			)
		)
	)
	(zone
		(layer "B.Cu")
		(hatch none 0.5)
		(connect_pads
			(clearance 0)
		)
		(min_thickness 0.25)
		(keepout
			(tracks not_allowed)
			(vias allowed)
			(pads allowed)
			(copperpour not_allowed)
			(footprints allowed)
		)
		(placement
			(enabled no)
			(sheetname "")
		)
		(fill
			(thermal_gap 0.5)
			(thermal_bridge_width 0.5)
			(island_removal_mode 0)
		)
		(polygon
			(pts
				(arc
					(start 16.288512 -105.664)
					(mid 15.620492 -105.664)
					(end 16.288512 -105.664)
				)
			)
		)
	)
	(zone
		(layer "B.Cu")
		(hatch none 0.5)
		(connect_pads
			(clearance 0)
		)
		(min_thickness 0.25)
		(keepout
			(tracks allowed)
			(vias allowed)
			(pads allowed)
			(copperpour allowed)
			(footprints allowed)
		)
		(placement
			(enabled no)
			(sheetname "")
		)
		(fill
			(thermal_gap 0.5)
			(thermal_bridge_width 0.5)
			(island_removal_mode 0)
		)
		(polygon
			(pts
				(xy 145.920714 -196.938392) (xy 145.920714 -197.674992) (xy 144.907254 -197.674992) (xy 144.907254 -196.938392)
			)
		)
	)
	(zone
		(layer "B.Cu")
		(hatch none 0.5)
		(connect_pads
			(clearance 0)
		)
		(min_thickness 0.25)
		(keepout
			(tracks not_allowed)
			(vias allowed)
			(pads allowed)
			(copperpour not_allowed)
			(footprints allowed)
		)
		(placement
			(enabled no)
			(sheetname "")
		)
		(fill
			(thermal_gap 0.5)
			(thermal_bridge_width 0.5)
			(island_removal_mode 0)
		)
		(polygon
			(pts
				(arc
					(start 398.47012 -258.890008)
					(mid 401.97024 -262.390128)
					(end 405.470106 -258.890008)
				)
				(arc
					(start 405.470106 -258.890008)
					(mid 401.97024 -255.390142)
					(end 398.47012 -258.890008)
				)
			)
		)
	)
	(zone
		(layer "B.Cu")
		(hatch none 0.5)
		(connect_pads
			(clearance 0)
		)
		(min_thickness 0.25)
		(keepout
			(tracks not_allowed)
			(vias allowed)
			(pads allowed)
			(copperpour not_allowed)
			(footprints allowed)
		)
		(placement
			(enabled no)
			(sheetname "")
		)
		(fill
			(thermal_gap 0.5)
			(thermal_bridge_width 0.5)
			(island_removal_mode 0)
		)
		(polygon
			(pts
				(arc
					(start 165.77818 -392.429238)
					(mid 165.11016 -392.429238)
					(end 165.77818 -392.429238)
				)
			)
		)
	)
	(zone
		(layer "B.Cu")
		(hatch none 0.5)
		(connect_pads
			(clearance 0)
		)
		(min_thickness 0.25)
		(keepout
			(tracks not_allowed)
			(vias allowed)
			(pads allowed)
			(copperpour not_allowed)
			(footprints allowed)
		)
		(placement
			(enabled no)
			(sheetname "")
		)
		(fill
			(thermal_gap 0.5)
			(thermal_bridge_width 0.5)
			(island_removal_mode 0)
		)
		(polygon
			(pts
				(arc
					(start 456.460098 -347.700092)
					(mid 461.460088 -352.700082)
					(end 466.460078 -347.700092)
				)
				(arc
					(start 466.460078 -347.700092)
					(mid 461.460088 -342.700102)
					(end 456.460098 -347.700092)
				)
			)
		)
	)
	(zone
		(layer "B.Cu")
		(hatch none 0.5)
		(connect_pads
			(clearance 0)
		)
		(min_thickness 0.25)
		(keepout
			(tracks allowed)
			(vias allowed)
			(pads allowed)
			(copperpour allowed)
			(footprints not_allowed)
		)
		(placement
			(enabled no)
			(sheetname "")
		)
		(fill
			(thermal_gap 0.5)
			(thermal_bridge_width 0.5)
			(island_removal_mode 0)
		)
		(polygon
			(pts
				(arc
					(start 217.149934 -51.999896)
					(mid 204.650086 -39.500048)
					(end 192.149984 -51.999896)
				)
				(arc
					(start 192.149984 -51.999896)
					(mid 204.650086 -64.499998)
					(end 217.149934 -51.999896)
				)
			)
		)
	)
	(zone
		(layer "B.Cu")
		(hatch none 0.5)
		(connect_pads
			(clearance 0)
		)
		(min_thickness 0.25)
		(keepout
			(tracks allowed)
			(vias allowed)
			(pads allowed)
			(copperpour allowed)
			(footprints allowed)
		)
		(placement
			(enabled no)
			(sheetname "")
		)
		(fill
			(thermal_gap 0.5)
			(thermal_bridge_width 0.5)
			(island_removal_mode 0)
		)
		(polygon
			(pts
				(xy 270.2941 -194.34556) (xy 270.2941 -190.2968) (xy 273.23796 -190.2968) (xy 273.23796 -194.34556)
			)
		)
	)
	(zone
		(layer "B.Cu")
		(hatch none 0.5)
		(connect_pads
			(clearance 0)
		)
		(min_thickness 0.25)
		(keepout
			(tracks not_allowed)
			(vias allowed)
			(pads allowed)
			(copperpour not_allowed)
			(footprints allowed)
		)
		(placement
			(enabled no)
			(sheetname "")
		)
		(fill
			(thermal_gap 0.5)
			(thermal_bridge_width 0.5)
			(island_removal_mode 0)
		)
		(polygon
			(pts
				(arc
					(start 352.81616 -270.036036)
					(mid 352.18624 -270.036036)
					(end 352.81616 -270.036036)
				)
			)
		)
	)
	(zone
		(layer "B.Cu")
		(hatch none 0.5)
		(connect_pads
			(clearance 0)
		)
		(min_thickness 0.25)
		(keepout
			(tracks not_allowed)
			(vias allowed)
			(pads allowed)
			(copperpour not_allowed)
			(footprints allowed)
		)
		(placement
			(enabled no)
			(sheetname "")
		)
		(fill
			(thermal_gap 0.5)
			(thermal_bridge_width 0.5)
			(island_removal_mode 0)
		)
		(polygon
			(pts
				(arc
					(start 356.746048 -243.674138)
					(mid 356.116128 -243.674138)
					(end 356.746048 -243.674138)
				)
			)
		)
	)
	(zone
		(layer "B.Cu")
		(hatch none 0.5)
		(connect_pads
			(clearance 0)
		)
		(min_thickness 0.25)
		(keepout
			(tracks not_allowed)
			(vias allowed)
			(pads allowed)
			(copperpour not_allowed)
			(footprints allowed)
		)
		(placement
			(enabled no)
			(sheetname "")
		)
		(fill
			(thermal_gap 0.5)
			(thermal_bridge_width 0.5)
			(island_removal_mode 0)
		)
		(polygon
			(pts
				(arc
					(start 320.950336 -401.674838)
					(mid 320.282316 -401.674838)
					(end 320.950336 -401.674838)
				)
			)
		)
	)
	(zone
		(layer "B.Cu")
		(hatch none 0.5)
		(connect_pads
			(clearance 0)
		)
		(min_thickness 0.25)
		(keepout
			(tracks not_allowed)
			(vias allowed)
			(pads allowed)
			(copperpour not_allowed)
			(footprints allowed)
		)
		(placement
			(enabled no)
			(sheetname "")
		)
		(fill
			(thermal_gap 0.5)
			(thermal_bridge_width 0.5)
			(island_removal_mode 0)
		)
		(polygon
			(pts
				(arc
					(start 322.150232 -401.674838)
					(mid 321.482212 -401.674838)
					(end 322.150232 -401.674838)
				)
			)
		)
	)
	(zone
		(layer "B.Cu")
		(hatch none 0.5)
		(connect_pads
			(clearance 0)
		)
		(min_thickness 0.25)
		(keepout
			(tracks not_allowed)
			(vias allowed)
			(pads allowed)
			(copperpour not_allowed)
			(footprints allowed)
		)
		(placement
			(enabled no)
			(sheetname "")
		)
		(fill
			(thermal_gap 0.5)
			(thermal_bridge_width 0.5)
			(island_removal_mode 0)
		)
		(polygon
			(pts
				(arc
					(start 320.570098 -258.890008)
					(mid 317.770002 -256.089912)
					(end 314.969906 -258.890008)
				)
				(arc
					(start 314.969906 -258.890008)
					(mid 317.770002 -261.690104)
					(end 320.570098 -258.890008)
				)
			)
		)
	)
	(zone
		(layer "B.Cu")
		(hatch none 0.5)
		(connect_pads
			(clearance 0)
		)
		(min_thickness 0.25)
		(keepout
			(tracks not_allowed)
			(vias allowed)
			(pads allowed)
			(copperpour not_allowed)
			(footprints allowed)
		)
		(placement
			(enabled no)
			(sheetname "")
		)
		(fill
			(thermal_gap 0.5)
			(thermal_bridge_width 0.5)
			(island_removal_mode 0)
		)
		(polygon
			(pts
				(arc
					(start 345.936062 -247.724168)
					(mid 345.306142 -247.724168)
					(end 345.936062 -247.724168)
				)
			)
		)
	)
	(zone
		(layer "B.Cu")
		(hatch none 0.5)
		(connect_pads
			(clearance 0)
		)
		(min_thickness 0.25)
		(keepout
			(tracks allowed)
			(vias allowed)
			(pads allowed)
			(copperpour allowed)
			(footprints allowed)
		)
		(placement
			(enabled no)
			(sheetname "")
		)
		(fill
			(thermal_gap 0.5)
			(thermal_bridge_width 0.5)
			(island_removal_mode 0)
		)
		(polygon
			(pts
				(xy 410.24302 -194.4243) (xy 410.24302 -190.48476) (xy 412.56712 -190.48476) (xy 412.56712 -194.4243)
			)
		)
	)
	(zone
		(layer "B.Cu")
		(hatch none 0.5)
		(connect_pads
			(clearance 0)
		)
		(min_thickness 0.25)
		(keepout
			(tracks allowed)
			(vias allowed)
			(pads allowed)
			(copperpour allowed)
			(footprints allowed)
		)
		(placement
			(enabled no)
			(sheetname "")
		)
		(fill
			(thermal_gap 0.5)
			(thermal_bridge_width 0.5)
			(island_removal_mode 0)
		)
		(polygon
			(pts
				(xy 65.412366 -166.647876) (xy 65.412366 -164.488876) (xy 65.793366 -164.107876) (xy 68.587366 -164.107876)
				(xy 69.730366 -165.250876) (xy 69.730366 -168.171876) (xy 69.222366 -168.679876) (xy 67.444366 -168.679876)
			)
		)
	)
	(zone
		(layer "B.Cu")
		(hatch none 0.5)
		(connect_pads
			(clearance 0)
		)
		(min_thickness 0.25)
		(keepout
			(tracks allowed)
			(vias allowed)
			(pads allowed)
			(copperpour allowed)
			(footprints not_allowed)
		)
		(placement
			(enabled no)
			(sheetname "")
		)
		(fill
			(thermal_gap 0.5)
			(thermal_bridge_width 0.5)
			(island_removal_mode 0)
		)
		(polygon
			(pts
				(arc
					(start 468.178642 -80.70723)
					(mid 467.528375 -81.680424)
					(end 467.300056 -82.828384)
				)
				(xy 467.300056 -87.199978)
				(arc
					(start 428.105062 -87.199978)
					(mid 436.090837 -83.133816)
					(end 439.302906 -74.767948)
				)
				(arc
					(start 439.302906 -66.06794)
					(mid 426.803058 -53.568092)
					(end 414.302956 -66.06794)
				)
				(arc
					(start 414.302956 -74.767948)
					(mid 417.515221 -83.133869)
					(end 425.501054 -87.199978)
				)
				(arc
					(start 294.23614 -87.199978)
					(mid 302.267297 -83.152443)
					(end 305.502818 -74.76109)
				)
				(arc
					(start 305.502818 -66.061082)
					(mid 293.00297 -53.561234)
					(end 280.502868 -66.061082)
				)
				(arc
					(start 280.502868 -74.76109)
					(mid 283.738166 -83.152414)
					(end 291.769292 -87.199978)
				)
				(arc
					(start 247.124982 -87.199978)
					(mid 248.077106 -84.522979)
					(end 248.400062 -81.700116)
				)
				(arc
					(start 248.400062 -81.700116)
					(mid 235.900214 -69.200268)
					(end 223.400112 -81.700116)
				)
				(arc
					(start 223.400112 -81.700116)
					(mid 223.722971 -84.522955)
					(end 224.674938 -87.199978)
				)
				(arc
					(start 180.165502 -87.199978)
					(mid 188.151277 -83.133816)
					(end 191.363346 -74.767948)
				)
				(arc
					(start 191.363346 -66.06794)
					(mid 178.863498 -53.568092)
					(end 166.363396 -66.06794)
				)
				(arc
					(start 166.363396 -74.767948)
					(mid 169.575596 -83.133699)
					(end 177.56124 -87.199978)
				)
				(arc
					(start 46.296326 -87.199978)
					(mid 54.327483 -83.152443)
					(end 57.563004 -74.76109)
				)
				(arc
					(start 57.563004 -66.061082)
					(mid 45.063156 -53.561234)
					(end 32.563054 -66.061082)
				)
				(arc
					(start 32.563054 -74.76109)
					(mid 35.798352 -83.152414)
					(end 43.829478 -87.199978)
				)
				(xy 2.999994 -87.199978)
				(arc
					(start 2.999994 -81.328514)
					(mid 2.771716 -80.180412)
					(end 2.121408 -79.207106)
				)
				(arc
					(start 1.29286 -78.378812)
					(mid 1.076078 -78.054375)
					(end 0.999998 -77.671676)
				)
				(arc
					(start 0.999998 -27.591512)
					(mid 3.92484 -29.685433)
					(end 7.47141 -30.286198)
				)
				(arc
					(start 7.47141 -30.286198)
					(mid 21.313293 -35.689957)
					(end 14.999716 -22.238462)
				)
				(arc
					(start 14.999716 -22.238462)
					(mid 9.799573 -14.805814)
					(end 0.999998 -17.008602)
				)
				(arc
					(start 0.999998 -13.780008)
					(mid 1.292891 -13.072903)
					(end 1.999996 -12.78001)
				)
				(arc
					(start 11.102086 -12.78001)
					(mid 13.223402 -11.901332)
					(end 14.10208 -9.780016)
				)
				(xy 14.10208 -0.999998) (xy 80.701896 -0.999998)
				(arc
					(start 80.701896 -9.780016)
					(mid 81.580574 -11.901332)
					(end 83.70189 -12.78001)
				)
				(arc
					(start 86.79942 -12.78001)
					(mid 82.798992 -25.432657)
					(end 92.436442 -34.554922)
				)
				(arc
					(start 92.436442 -34.554922)
					(mid 86.046001 -36.520897)
					(end 81.583022 -41.499282)
				)
				(arc
					(start 81.583022 -41.499282)
					(mid 75.261052 -35.541117)
					(end 66.583052 -35.141662)
				)
				(arc
					(start 66.583052 -35.141662)
					(mid 50.2828 -47.050237)
					(end 66.583052 -58.95848)
				)
				(arc
					(start 66.583052 -58.95848)
					(mid 75.261074 -58.558869)
					(end 81.583022 -52.600606)
				)
				(arc
					(start 81.583022 -52.600606)
					(mid 87.904959 -58.558897)
					(end 96.582992 -58.95848)
				)
				(arc
					(start 96.582992 -58.95848)
					(mid 108.811167 -56.281151)
					(end 112.587024 -44.346368)
				)
				(arc
					(start 107.10418 -19.596354)
					(mid 105.609166 -15.852974)
					(end 103.000556 -12.78001)
				)
				(arc
					(start 124.102114 -12.78001)
					(mid 126.22343 -11.901332)
					(end 127.102108 -9.780016)
				)
				(xy 127.102108 -6.279896) (xy 193.701924 -6.279896)
				(arc
					(start 193.701924 -9.780016)
					(mid 194.211722 -11.453003)
					(end 195.567808 -12.557506)
				)
				(arc
					(start 195.567808 -12.557506)
					(mid 203.224847 -34.799103)
					(end 211.499958 -12.78001)
				)
				(arc
					(start 221.30004 -12.78001)
					(mid 222.007145 -13.072903)
					(end 222.300038 -13.780008)
				)
				(arc
					(start 222.300038 -33.728152)
					(mid 219.391482 -52.89292)
					(end 238.748316 -51.861974)
				)
				(arc
					(start 238.748316 -51.861974)
					(mid 249.172176 -47.857874)
					(end 252.236478 -37.120068)
				)
				(arc
					(start 256.800096 -37.120068)
					(mid 259.199302 -35.921123)
					(end 259.68071 -33.282636)
				)
				(arc
					(start 259.68071 -33.282636)
					(mid 275.956579 -29.372801)
					(end 273.750532 -12.78001)
				)
				(arc
					(start 372.799356 -12.78001)
					(mid 381.670278 -34.776093)
					(end 387.76783 -11.855704)
				)
				(arc
					(start 387.76783 -11.855704)
					(mid 388.385566 -10.89851)
					(end 388.601966 -9.780016)
				)
				(xy 388.601966 -0.999998) (xy 455.202036 -0.999998)
				(arc
					(start 455.202036 -9.780016)
					(mid 455.692301 -11.423556)
					(end 457.002896 -12.52982)
				)
				(arc
					(start 457.002896 -12.52982)
					(mid 452.555193 -19.787378)
					(end 453.785478 -28.210002)
				)
				(xy 459.373478 -42.189908) (xy 466.8901 -42.189908)
				(arc
					(start 466.8901 -48.189896)
					(mid 464.698019 -53.482047)
					(end 469.989916 -51.289966)
				)
				(xy 470.799922 -51.289966)
				(arc
					(start 470.799922 -77.671676)
					(mid 470.723802 -78.054359)
					(end 470.50706 -78.378812)
				)
			)
		)
	)
	(zone
		(layer "B.Cu")
		(hatch none 0.5)
		(connect_pads
			(clearance 0)
		)
		(min_thickness 0.25)
		(keepout
			(tracks allowed)
			(vias allowed)
			(pads allowed)
			(copperpour allowed)
			(footprints allowed)
		)
		(placement
			(enabled no)
			(sheetname "")
		)
		(fill
			(thermal_gap 0.5)
			(thermal_bridge_width 0.5)
			(island_removal_mode 0)
		)
		(polygon
			(pts
				(xy 243.413788 -394.401548) (xy 243.413788 -393.397232) (xy 244.790722 -393.397232) (xy 244.790722 -394.401548)
			)
		)
	)
	(zone
		(layer "B.Cu")
		(hatch none 0.5)
		(connect_pads
			(clearance 0)
		)
		(min_thickness 0.25)
		(keepout
			(tracks allowed)
			(vias allowed)
			(pads allowed)
			(copperpour allowed)
			(footprints not_allowed)
		)
		(placement
			(enabled no)
			(sheetname "")
		)
		(fill
			(thermal_gap 0.5)
			(thermal_bridge_width 0.5)
			(island_removal_mode 0)
		)
		(polygon
			(pts
				(arc
					(start 260.649974 -51.999896)
					(mid 268.649958 -59.99988)
					(end 276.649942 -51.999896)
				)
				(arc
					(start 276.649942 -51.999896)
					(mid 268.649958 -43.999912)
					(end 260.649974 -51.999896)
				)
			)
		)
	)
	(zone
		(layer "B.Cu")
		(hatch none 0.5)
		(connect_pads
			(clearance 0)
		)
		(min_thickness 0.25)
		(keepout
			(tracks not_allowed)
			(vias allowed)
			(pads allowed)
			(copperpour not_allowed)
			(footprints allowed)
		)
		(placement
			(enabled no)
			(sheetname "")
		)
		(fill
			(thermal_gap 0.5)
			(thermal_bridge_width 0.5)
			(island_removal_mode 0)
		)
		(polygon
			(pts
				(arc
					(start 50.550572 -392.429238)
					(mid 49.882552 -392.429238)
					(end 50.550572 -392.429238)
				)
			)
		)
	)
	(zone
		(layer "B.Cu")
		(hatch none 0.5)
		(connect_pads
			(clearance 0)
		)
		(min_thickness 0.25)
		(keepout
			(tracks allowed)
			(vias allowed)
			(pads allowed)
			(copperpour allowed)
			(footprints not_allowed)
		)
		(placement
			(enabled no)
			(sheetname "")
		)
		(fill
			(thermal_gap 0.5)
			(thermal_bridge_width 0.5)
			(island_removal_mode 0)
		)
		(polygon
			(pts
				(arc
					(start 437.304942 -399.029936)
					(mid 435.440074 -397.165068)
					(end 433.574952 -399.029936)
				)
				(arc
					(start 433.574952 -399.029936)
					(mid 435.440074 -400.895058)
					(end 437.304942 -399.029936)
				)
			)
		)
	)
	(zone
		(layer "B.Cu")
		(hatch none 0.5)
		(connect_pads
			(clearance 0)
		)
		(min_thickness 0.25)
		(keepout
			(tracks not_allowed)
			(vias allowed)
			(pads allowed)
			(copperpour not_allowed)
			(footprints allowed)
		)
		(placement
			(enabled no)
			(sheetname "")
		)
		(fill
			(thermal_gap 0.5)
			(thermal_bridge_width 0.5)
			(island_removal_mode 0)
		)
		(polygon
			(pts
				(arc
					(start 57.75071 -392.429238)
					(mid 57.08269 -392.429238)
					(end 57.75071 -392.429238)
				)
			)
		)
	)
	(zone
		(layer "B.Cu")
		(hatch none 0.5)
		(connect_pads
			(clearance 0)
		)
		(min_thickness 0.25)
		(keepout
			(tracks not_allowed)
			(vias allowed)
			(pads allowed)
			(copperpour not_allowed)
			(footprints allowed)
		)
		(placement
			(enabled no)
			(sheetname "")
		)
		(fill
			(thermal_gap 0.5)
			(thermal_bridge_width 0.5)
			(island_removal_mode 0)
		)
		(polygon
			(pts
				(arc
					(start 84.03717 -436.889906)
					(mid 83.262978 -436.889906)
					(end 84.03717 -436.889906)
				)
			)
		)
	)
	(zone
		(layer "B.Cu")
		(hatch none 0.5)
		(connect_pads
			(clearance 0)
		)
		(min_thickness 0.25)
		(keepout
			(tracks not_allowed)
			(vias allowed)
			(pads allowed)
			(copperpour not_allowed)
			(footprints allowed)
		)
		(placement
			(enabled no)
			(sheetname "")
		)
		(fill
			(thermal_gap 0.5)
			(thermal_bridge_width 0.5)
			(island_removal_mode 0)
		)
		(polygon
			(pts
				(arc
					(start 140.13688 -437.889904)
					(mid 139.362688 -437.889904)
					(end 140.13688 -437.889904)
				)
			)
		)
	)
	(zone
		(layer "B.Cu")
		(hatch none 0.5)
		(connect_pads
			(clearance 0)
		)
		(min_thickness 0.25)
		(keepout
			(tracks not_allowed)
			(vias allowed)
			(pads allowed)
			(copperpour not_allowed)
			(footprints allowed)
		)
		(placement
			(enabled no)
			(sheetname "")
		)
		(fill
			(thermal_gap 0.5)
			(thermal_bridge_width 0.5)
			(island_removal_mode 0)
		)
		(polygon
			(pts
				(arc
					(start 221.430342 -388.161784)
					(mid 225.430334 -392.161776)
					(end 229.430326 -388.161784)
				)
				(arc
					(start 229.430326 -388.161784)
					(mid 225.430334 -384.161792)
					(end 221.430342 -388.161784)
				)
			)
		)
	)
	(zone
		(layer "B.Cu")
		(hatch none 0.5)
		(connect_pads
			(clearance 0)
		)
		(min_thickness 0.25)
		(keepout
			(tracks allowed)
			(vias allowed)
			(pads allowed)
			(copperpour allowed)
			(footprints allowed)
		)
		(placement
			(enabled no)
			(sheetname "")
		)
		(fill
			(thermal_gap 0.5)
			(thermal_bridge_width 0.5)
			(island_removal_mode 0)
		)
		(polygon
			(pts
				(xy 212.66404 -402.689568) (xy 212.66404 -401.685252) (xy 213.357206 -401.685252) (xy 213.357206 -402.689568)
			)
		)
	)
	(zone
		(layer "B.Cu")
		(hatch none 0.5)
		(connect_pads
			(clearance 0)
		)
		(min_thickness 0.25)
		(keepout
			(tracks allowed)
			(vias allowed)
			(pads allowed)
			(copperpour allowed)
			(footprints allowed)
		)
		(placement
			(enabled no)
			(sheetname "")
		)
		(fill
			(thermal_gap 0.5)
			(thermal_bridge_width 0.5)
			(island_removal_mode 0)
		)
		(polygon
			(pts
				(xy 191.518794 -353.597464) (xy 191.518794 -355.756464) (xy 191.137794 -356.137464) (xy 188.343794 -356.137464)
				(xy 187.200794 -354.994464) (xy 187.200794 -352.073464) (xy 187.708794 -351.565464) (xy 189.486794 -351.565464)
			)
		)
	)
	(zone
		(layer "B.Cu")
		(hatch none 0.5)
		(connect_pads
			(clearance 0)
		)
		(min_thickness 0.25)
		(keepout
			(tracks not_allowed)
			(vias allowed)
			(pads allowed)
			(copperpour not_allowed)
			(footprints allowed)
		)
		(placement
			(enabled no)
			(sheetname "")
		)
		(fill
			(thermal_gap 0.5)
			(thermal_bridge_width 0.5)
			(island_removal_mode 0)
		)
		(polygon
			(pts
				(arc
					(start 55.350664 -392.429238)
					(mid 54.682644 -392.429238)
					(end 55.350664 -392.429238)
				)
			)
		)
	)
	(zone
		(layer "B.Cu")
		(hatch none 0.5)
		(connect_pads
			(clearance 0)
		)
		(min_thickness 0.25)
		(keepout
			(tracks not_allowed)
			(vias allowed)
			(pads allowed)
			(copperpour not_allowed)
			(footprints allowed)
		)
		(placement
			(enabled no)
			(sheetname "")
		)
		(fill
			(thermal_gap 0.5)
			(thermal_bridge_width 0.5)
			(island_removal_mode 0)
		)
		(polygon
			(pts
				(arc
					(start 409.137104 -437.889904)
					(mid 408.362912 -437.889904)
					(end 409.137104 -437.889904)
				)
			)
		)
	)
	(zone
		(layer "B.Cu")
		(hatch none 0.5)
		(connect_pads
			(clearance 0)
		)
		(min_thickness 0.25)
		(keepout
			(tracks allowed)
			(vias allowed)
			(pads allowed)
			(copperpour allowed)
			(footprints not_allowed)
		)
		(placement
			(enabled no)
			(sheetname "")
		)
		(fill
			(thermal_gap 0.5)
			(thermal_bridge_width 0.5)
			(island_removal_mode 0)
		)
		(polygon
			(pts
				(xy 257.040126 -310.522112) (xy 257.040126 -273.02206) (xy 312.040016 -273.02206) (xy 312.040016 -310.522112)
			)
		)
	)
	(zone
		(layer "B.Cu")
		(hatch none 0.5)
		(connect_pads
			(clearance 0)
		)
		(min_thickness 0.25)
		(keepout
			(tracks allowed)
			(vias allowed)
			(pads allowed)
			(copperpour allowed)
			(footprints allowed)
		)
		(placement
			(enabled no)
			(sheetname "")
		)
		(fill
			(thermal_gap 0.5)
			(thermal_bridge_width 0.5)
			(island_removal_mode 0)
		)
		(polygon
			(pts
				(xy 21.868892 -389.256524) (xy 21.868892 -390.623552) (xy 21.031962 -390.623552) (xy 21.031962 -389.256524)
			)
		)
	)
	(zone
		(layer "B.Cu")
		(hatch none 0.5)
		(connect_pads
			(clearance 0)
		)
		(min_thickness 0.25)
		(keepout
			(tracks allowed)
			(vias allowed)
			(pads allowed)
			(copperpour allowed)
			(footprints allowed)
		)
		(placement
			(enabled no)
			(sheetname "")
		)
		(fill
			(thermal_gap 0.5)
			(thermal_bridge_width 0.5)
			(island_removal_mode 0)
		)
		(polygon
			(pts
				(xy 165.313106 -345.697556) (xy 165.999414 -345.697556) (xy 166.328852 -345.697556) (xy 166.328852 -347.236542)
				(xy 165.313106 -347.236542)
			)
		)
	)
	(zone
		(layer "B.Cu")
		(hatch none 0.5)
		(connect_pads
			(clearance 0)
		)
		(min_thickness 0.25)
		(keepout
			(tracks not_allowed)
			(vias allowed)
			(pads allowed)
			(copperpour not_allowed)
			(footprints allowed)
		)
		(placement
			(enabled no)
			(sheetname "")
		)
		(fill
			(thermal_gap 0.5)
			(thermal_bridge_width 0.5)
			(island_removal_mode 0)
		)
		(polygon
			(pts
				(arc
					(start 386.136896 -438.089802)
					(mid 385.362704 -438.089802)
					(end 386.136896 -438.089802)
				)
			)
		)
	)
	(zone
		(layer "B.Cu")
		(hatch none 0.5)
		(connect_pads
			(clearance 0)
		)
		(min_thickness 0.25)
		(keepout
			(tracks not_allowed)
			(vias allowed)
			(pads allowed)
			(copperpour not_allowed)
			(footprints allowed)
		)
		(placement
			(enabled no)
			(sheetname "")
		)
		(fill
			(thermal_gap 0.5)
			(thermal_bridge_width 0.5)
			(island_removal_mode 0)
		)
		(polygon
			(pts
				(arc
					(start 164.578284 -393.292838)
					(mid 163.910264 -393.292838)
					(end 164.578284 -393.292838)
				)
			)
		)
	)
	(zone
		(layer "B.Cu")
		(hatch none 0.5)
		(connect_pads
			(clearance 0)
		)
		(min_thickness 0.25)
		(keepout
			(tracks not_allowed)
			(vias allowed)
			(pads allowed)
			(copperpour not_allowed)
			(footprints allowed)
		)
		(placement
			(enabled no)
			(sheetname "")
		)
		(fill
			(thermal_gap 0.5)
			(thermal_bridge_width 0.5)
			(island_removal_mode 0)
		)
		(polygon
			(pts
				(arc
					(start 356.851966 -340.315042)
					(mid 359.952036 -343.415112)
					(end 363.052106 -340.315042)
				)
				(arc
					(start 363.052106 -340.315042)
					(mid 359.952036 -337.214972)
					(end 356.851966 -340.315042)
				)
			)
		)
	)
	(zone
		(layer "B.Cu")
		(hatch none 0.5)
		(connect_pads
			(clearance 0)
		)
		(min_thickness 0.25)
		(keepout
			(tracks not_allowed)
			(vias allowed)
			(pads allowed)
			(copperpour not_allowed)
			(footprints allowed)
		)
		(placement
			(enabled no)
			(sheetname "")
		)
		(fill
			(thermal_gap 0.5)
			(thermal_bridge_width 0.5)
			(island_removal_mode 0)
		)
		(polygon
			(pts
				(arc
					(start 340.036912 -436.889906)
					(mid 339.26272 -436.889906)
					(end 340.036912 -436.889906)
				)
			)
		)
	)
	(zone
		(layer "B.Cu")
		(hatch none 0.5)
		(connect_pads
			(clearance 0)
		)
		(min_thickness 0.25)
		(keepout
			(tracks allowed)
			(vias allowed)
			(pads allowed)
			(copperpour allowed)
			(footprints allowed)
		)
		(placement
			(enabled no)
			(sheetname "")
		)
		(fill
			(thermal_gap 0.5)
			(thermal_bridge_width 0.5)
			(island_removal_mode 0)
		)
		(polygon
			(pts
				(xy 452.987664 -400.760184) (xy 453.265794 -400.760184) (xy 454.252838 -400.760184) (xy 454.252838 -401.427696)
				(xy 452.987664 -401.427696)
			)
		)
	)
	(zone
		(layer "B.Cu")
		(hatch none 0.5)
		(connect_pads
			(clearance 0)
		)
		(min_thickness 0.25)
		(keepout
			(tracks not_allowed)
			(vias allowed)
			(pads allowed)
			(copperpour not_allowed)
			(footprints allowed)
		)
		(placement
			(enabled no)
			(sheetname "")
		)
		(fill
			(thermal_gap 0.5)
			(thermal_bridge_width 0.5)
			(island_removal_mode 0)
		)
		(polygon
			(pts
				(arc
					(start 156.830014 -258.890008)
					(mid 154.030172 -256.090166)
					(end 151.230076 -258.890008)
				)
				(arc
					(start 151.230076 -258.890008)
					(mid 154.030172 -261.690104)
					(end 156.830014 -258.890008)
				)
			)
		)
	)
	(zone
		(layer "B.Cu")
		(hatch none 0.5)
		(connect_pads
			(clearance 0)
		)
		(min_thickness 0.25)
		(keepout
			(tracks not_allowed)
			(vias allowed)
			(pads allowed)
			(copperpour not_allowed)
			(footprints allowed)
		)
		(placement
			(enabled no)
			(sheetname "")
		)
		(fill
			(thermal_gap 0.5)
			(thermal_bridge_width 0.5)
			(island_removal_mode 0)
		)
		(polygon
			(pts
				(arc
					(start 327.036684 -438.089802)
					(mid 326.262492 -438.089802)
					(end 327.036684 -438.089802)
				)
			)
		)
	)
	(zone
		(layer "B.Cu")
		(hatch none 0.5)
		(connect_pads
			(clearance 0)
		)
		(min_thickness 0.25)
		(keepout
			(tracks not_allowed)
			(vias allowed)
			(pads allowed)
			(copperpour not_allowed)
			(footprints allowed)
		)
		(placement
			(enabled no)
			(sheetname "")
		)
		(fill
			(thermal_gap 0.5)
			(thermal_bridge_width 0.5)
			(island_removal_mode 0)
		)
		(polygon
			(pts
				(arc
					(start 109.105954 -272.466308)
					(mid 108.476034 -272.466308)
					(end 109.105954 -272.466308)
				)
			)
		)
	)
	(zone
		(layer "B.Cu")
		(hatch none 0.5)
		(connect_pads
			(clearance 0)
		)
		(min_thickness 0.25)
		(keepout
			(tracks not_allowed)
			(vias allowed)
			(pads allowed)
			(copperpour not_allowed)
			(footprints allowed)
		)
		(placement
			(enabled no)
			(sheetname "")
		)
		(fill
			(thermal_gap 0.5)
			(thermal_bridge_width 0.5)
			(island_removal_mode 0)
		)
		(polygon
			(pts
				(arc
					(start 356.746048 -246.914162)
					(mid 356.116128 -246.914162)
					(end 356.746048 -246.914162)
				)
			)
		)
	)
	(zone
		(layer "B.Cu")
		(hatch none 0.5)
		(connect_pads
			(clearance 0)
		)
		(min_thickness 0.25)
		(keepout
			(tracks allowed)
			(vias allowed)
			(pads allowed)
			(copperpour allowed)
			(footprints not_allowed)
		)
		(placement
			(enabled no)
			(sheetname "")
		)
		(fill
			(thermal_gap 0.5)
			(thermal_bridge_width 0.5)
			(island_removal_mode 0)
		)
		(polygon
			(pts
				(arc
					(start 109.615986 -340.315042)
					(mid 112.716056 -343.415112)
					(end 115.816126 -340.315042)
				)
				(arc
					(start 115.816126 -340.315042)
					(mid 112.716056 -337.214972)
					(end 109.615986 -340.315042)
				)
			)
		)
	)
	(zone
		(layer "B.Cu")
		(hatch none 0.5)
		(connect_pads
			(clearance 0)
		)
		(min_thickness 0.25)
		(keepout
			(tracks not_allowed)
			(vias allowed)
			(pads allowed)
			(copperpour not_allowed)
			(footprints allowed)
		)
		(placement
			(enabled no)
			(sheetname "")
		)
		(fill
			(thermal_gap 0.5)
			(thermal_bridge_width 0.5)
			(island_removal_mode 0)
		)
		(polygon
			(pts
				(arc
					(start 411.1371 -438.089802)
					(mid 410.362908 -438.089802)
					(end 411.1371 -438.089802)
				)
			)
		)
	)
	(zone
		(layer "B.Cu")
		(hatch none 0.5)
		(connect_pads
			(clearance 0)
		)
		(min_thickness 0.25)
		(keepout
			(tracks not_allowed)
			(vias allowed)
			(pads allowed)
			(copperpour not_allowed)
			(footprints allowed)
		)
		(placement
			(enabled no)
			(sheetname "")
		)
		(fill
			(thermal_gap 0.5)
			(thermal_bridge_width 0.5)
			(island_removal_mode 0)
		)
		(polygon
			(pts
				(arc
					(start 354.696014 -270.036036)
					(mid 354.066094 -270.036036)
					(end 354.696014 -270.036036)
				)
			)
		)
	)
	(zone
		(layer "B.Cu")
		(hatch none 0.5)
		(connect_pads
			(clearance 0)
		)
		(min_thickness 0.25)
		(keepout
			(tracks not_allowed)
			(vias allowed)
			(pads allowed)
			(copperpour not_allowed)
			(footprints allowed)
		)
		(placement
			(enabled no)
			(sheetname "")
		)
		(fill
			(thermal_gap 0.5)
			(thermal_bridge_width 0.5)
			(island_removal_mode 0)
		)
		(polygon
			(pts
				(arc
					(start 450.349874 -435.600094)
					(mid 448.799966 -434.050186)
					(end 447.250058 -435.600094)
				)
				(arc
					(start 447.250058 -435.600094)
					(mid 448.799966 -437.150002)
					(end 450.349874 -435.600094)
				)
			)
		)
	)
	(zone
		(layer "B.Cu")
		(hatch none 0.5)
		(connect_pads
			(clearance 0)
		)
		(min_thickness 0.25)
		(keepout
			(tracks not_allowed)
			(vias allowed)
			(pads allowed)
			(copperpour not_allowed)
			(footprints allowed)
		)
		(placement
			(enabled no)
			(sheetname "")
		)
		(fill
			(thermal_gap 0.5)
			(thermal_bridge_width 0.5)
			(island_removal_mode 0)
		)
		(polygon
			(pts
				(arc
					(start 90.037158 -439.0898)
					(mid 89.262966 -439.0898)
					(end 90.037158 -439.0898)
				)
			)
		)
	)
	(zone
		(layer "B.Cu")
		(hatch none 0.5)
		(connect_pads
			(clearance 0)
		)
		(min_thickness 0.25)
		(keepout
			(tracks not_allowed)
			(vias allowed)
			(pads allowed)
			(copperpour not_allowed)
			(footprints allowed)
		)
		(placement
			(enabled no)
			(sheetname "")
		)
		(fill
			(thermal_gap 0.5)
			(thermal_bridge_width 0.5)
			(island_removal_mode 0)
		)
		(polygon
			(pts
				(arc
					(start 160.978342 -393.292838)
					(mid 160.310322 -393.292838)
					(end 160.978342 -393.292838)
				)
			)
		)
	)
	(zone
		(layer "B.Cu")
		(hatch none 0.5)
		(connect_pads
			(clearance 0)
		)
		(min_thickness 0.25)
		(keepout
			(tracks not_allowed)
			(vias allowed)
			(pads allowed)
			(copperpour not_allowed)
			(footprints allowed)
		)
		(placement
			(enabled no)
			(sheetname "")
		)
		(fill
			(thermal_gap 0.5)
			(thermal_bridge_width 0.5)
			(island_removal_mode 0)
		)
		(polygon
			(pts
				(arc
					(start 51.750468 -393.292838)
					(mid 51.082448 -393.292838)
					(end 51.750468 -393.292838)
				)
			)
		)
	)
	(zone
		(layer "B.Cu")
		(hatch none 0.5)
		(connect_pads
			(clearance 0)
		)
		(min_thickness 0.25)
		(keepout
			(tracks not_allowed)
			(vias allowed)
			(pads allowed)
			(copperpour not_allowed)
			(footprints allowed)
		)
		(placement
			(enabled no)
			(sheetname "")
		)
		(fill
			(thermal_gap 0.5)
			(thermal_bridge_width 0.5)
			(island_removal_mode 0)
		)
		(polygon
			(pts
				(arc
					(start 62.906148 -386.003292)
					(mid 62.276228 -386.003292)
					(end 62.906148 -386.003292)
				)
			)
		)
	)
	(zone
		(layer "B.Cu")
		(hatch none 0.5)
		(connect_pads
			(clearance 0)
		)
		(min_thickness 0.25)
		(keepout
			(tracks not_allowed)
			(vias allowed)
			(pads allowed)
			(copperpour not_allowed)
			(footprints allowed)
		)
		(placement
			(enabled no)
			(sheetname "")
		)
		(fill
			(thermal_gap 0.5)
			(thermal_bridge_width 0.5)
			(island_removal_mode 0)
		)
		(polygon
			(pts
				(arc
					(start 136.136888 -437.889904)
					(mid 135.362696 -437.889904)
					(end 136.136888 -437.889904)
				)
			)
		)
	)
	(zone
		(layer "B.Cu")
		(hatch none 0.5)
		(connect_pads
			(clearance 0)
		)
		(min_thickness 0.25)
		(keepout
			(tracks not_allowed)
			(vias allowed)
			(pads allowed)
			(copperpour not_allowed)
			(footprints allowed)
		)
		(placement
			(enabled no)
			(sheetname "")
		)
		(fill
			(thermal_gap 0.5)
			(thermal_bridge_width 0.5)
			(island_removal_mode 0)
		)
		(polygon
			(pts
				(arc
					(start 415.81705 -351.415096)
					(mid 413.952182 -349.550228)
					(end 412.08706 -351.415096)
				)
				(arc
					(start 412.08706 -351.415096)
					(mid 413.952182 -353.280218)
					(end 415.81705 -351.415096)
				)
			)
		)
	)
	(zone
		(layer "B.Cu")
		(hatch none 0.5)
		(connect_pads
			(clearance 0)
		)
		(min_thickness 0.25)
		(keepout
			(tracks allowed)
			(vias allowed)
			(pads allowed)
			(copperpour allowed)
			(footprints allowed)
		)
		(placement
			(enabled no)
			(sheetname "")
		)
		(fill
			(thermal_gap 0.5)
			(thermal_bridge_width 0.5)
			(island_removal_mode 0)
		)
		(polygon
			(pts
				(xy 224.72904 -408.604212) (xy 224.72904 -407.599896) (xy 225.422206 -407.599896) (xy 225.422206 -408.604212)
			)
		)
	)
	(zone
		(layer "B.Cu")
		(hatch none 0.5)
		(connect_pads
			(clearance 0)
		)
		(min_thickness 0.25)
		(keepout
			(tracks not_allowed)
			(vias allowed)
			(pads allowed)
			(copperpour not_allowed)
			(footprints allowed)
		)
		(placement
			(enabled no)
			(sheetname "")
		)
		(fill
			(thermal_gap 0.5)
			(thermal_bridge_width 0.5)
			(island_removal_mode 0)
		)
		(polygon
			(pts
				(arc
					(start 31.770066 -389.439912)
					(mid 34.870136 -392.539982)
					(end 37.969952 -389.439912)
				)
				(arc
					(start 37.969952 -389.439912)
					(mid 34.870136 -386.340096)
					(end 31.770066 -389.439912)
				)
			)
		)
	)
	(zone
		(layer "B.Cu")
		(hatch none 0.5)
		(connect_pads
			(clearance 0)
		)
		(min_thickness 0.25)
		(keepout
			(tracks allowed)
			(vias allowed)
			(pads allowed)
			(copperpour allowed)
			(footprints allowed)
		)
		(placement
			(enabled no)
			(sheetname "")
		)
		(fill
			(thermal_gap 0.5)
			(thermal_bridge_width 0.5)
			(island_removal_mode 0)
		)
		(polygon
			(pts
				(xy 341.81796 -417.428426) (xy 341.81796 -416.42411) (xy 343.194894 -416.42411) (xy 343.194894 -417.428426)
			)
		)
	)
	(zone
		(layer "B.Cu")
		(hatch none 0.5)
		(connect_pads
			(clearance 0)
		)
		(min_thickness 0.25)
		(keepout
			(tracks not_allowed)
			(vias allowed)
			(pads allowed)
			(copperpour not_allowed)
			(footprints allowed)
		)
		(placement
			(enabled no)
			(sheetname "")
		)
		(fill
			(thermal_gap 0.5)
			(thermal_bridge_width 0.5)
			(island_removal_mode 0)
		)
		(polygon
			(pts
				(arc
					(start 51.750468 -392.429238)
					(mid 51.082448 -392.429238)
					(end 51.750468 -392.429238)
				)
			)
		)
	)
	(zone
		(layer "B.Cu")
		(hatch none 0.5)
		(connect_pads
			(clearance 0)
		)
		(min_thickness 0.25)
		(keepout
			(tracks allowed)
			(vias allowed)
			(pads allowed)
			(copperpour allowed)
			(footprints allowed)
		)
		(placement
			(enabled no)
			(sheetname "")
		)
		(fill
			(thermal_gap 0.5)
			(thermal_bridge_width 0.5)
			(island_removal_mode 0)
		)
		(polygon
			(pts
				(xy 387.475476 -417.428426) (xy 387.475476 -416.42411) (xy 388.85241 -416.42411) (xy 388.85241 -417.428426)
			)
		)
	)
	(zone
		(layer "B.Cu")
		(hatch none 0.5)
		(connect_pads
			(clearance 0)
		)
		(min_thickness 0.25)
		(keepout
			(tracks allowed)
			(vias allowed)
			(pads allowed)
			(copperpour allowed)
			(footprints not_allowed)
		)
		(placement
			(enabled no)
			(sheetname "")
		)
		(fill
			(thermal_gap 0.5)
			(thermal_bridge_width 0.5)
			(island_removal_mode 0)
		)
		(polygon
			(pts
				(arc
					(start 325.769986 -304.790094)
					(mid 329.270106 -308.290214)
					(end 332.769972 -304.790094)
				)
				(arc
					(start 332.769972 -304.790094)
					(mid 329.270106 -301.290228)
					(end 325.769986 -304.790094)
				)
			)
		)
	)
	(zone
		(layer "B.Cu")
		(hatch none 0.5)
		(connect_pads
			(clearance 0)
		)
		(min_thickness 0.25)
		(keepout
			(tracks allowed)
			(vias allowed)
			(pads allowed)
			(copperpour allowed)
			(footprints not_allowed)
		)
		(placement
			(enabled no)
			(sheetname "")
		)
		(fill
			(thermal_gap 0.5)
			(thermal_bridge_width 0.5)
			(island_removal_mode 0)
		)
		(polygon
			(pts
				(arc
					(start 229.430326 -388.161784)
					(mid 225.430334 -384.161792)
					(end 221.430342 -388.161784)
				)
				(arc
					(start 221.430342 -388.161784)
					(mid 225.430334 -392.161776)
					(end 229.430326 -388.161784)
				)
			)
		)
	)
	(zone
		(layer "B.Cu")
		(hatch none 0.5)
		(connect_pads
			(clearance 0)
		)
		(min_thickness 0.25)
		(keepout
			(tracks not_allowed)
			(vias allowed)
			(pads allowed)
			(copperpour not_allowed)
			(footprints allowed)
		)
		(placement
			(enabled no)
			(sheetname "")
		)
		(fill
			(thermal_gap 0.5)
			(thermal_bridge_width 0.5)
			(island_removal_mode 0)
		)
		(polygon
			(pts
				(arc
					(start 73.036938 -437.889904)
					(mid 72.262746 -437.889904)
					(end 73.036938 -437.889904)
				)
			)
		)
	)
	(zone
		(layer "B.Cu")
		(hatch none 0.5)
		(connect_pads
			(clearance 0)
		)
		(min_thickness 0.25)
		(keepout
			(tracks not_allowed)
			(vias allowed)
			(pads allowed)
			(copperpour not_allowed)
			(footprints allowed)
		)
		(placement
			(enabled no)
			(sheetname "")
		)
		(fill
			(thermal_gap 0.5)
			(thermal_bridge_width 0.5)
			(island_removal_mode 0)
		)
		(polygon
			(pts
				(arc
					(start 459.799944 -22.29993)
					(mid 464.799934 -27.29992)
					(end 469.799924 -22.29993)
				)
				(arc
					(start 469.799924 -22.29993)
					(mid 464.799934 -17.29994)
					(end 459.799944 -22.29993)
				)
			)
		)
	)
	(zone
		(layer "B.Cu")
		(hatch none 0.5)
		(connect_pads
			(clearance 0)
		)
		(min_thickness 0.25)
		(keepout
			(tracks allowed)
			(vias allowed)
			(pads allowed)
			(copperpour allowed)
			(footprints allowed)
		)
		(placement
			(enabled no)
			(sheetname "")
		)
		(fill
			(thermal_gap 0.5)
			(thermal_bridge_width 0.5)
			(island_removal_mode 0)
		)
		(polygon
			(pts
				(xy 52.68976 -194.23634) (xy 52.68976 -193.19494) (xy 54.59222 -193.19494) (xy 54.59222 -194.23634)
			)
		)
	)
	(zone
		(layer "B.Cu")
		(hatch none 0.5)
		(connect_pads
			(clearance 0)
		)
		(min_thickness 0.25)
		(keepout
			(tracks not_allowed)
			(vias allowed)
			(pads allowed)
			(copperpour not_allowed)
			(footprints allowed)
		)
		(placement
			(enabled no)
			(sheetname "")
		)
		(fill
			(thermal_gap 0.5)
			(thermal_bridge_width 0.5)
			(island_removal_mode 0)
		)
		(polygon
			(pts
				(arc
					(start 372.2497 -223.424242)
					(mid 371.61978 -223.424242)
					(end 372.2497 -223.424242)
				)
			)
		)
	)
	(zone
		(layer "B.Cu")
		(hatch none 0.5)
		(connect_pads
			(clearance 0)
		)
		(min_thickness 0.25)
		(keepout
			(tracks allowed)
			(vias allowed)
			(pads allowed)
			(copperpour allowed)
			(footprints not_allowed)
		)
		(placement
			(enabled no)
			(sheetname "")
		)
		(fill
			(thermal_gap 0.5)
			(thermal_bridge_width 0.5)
			(island_removal_mode 0)
		)
		(polygon
			(pts
				(arc
					(start 386.421884 -173.315122)
					(mid 389.521954 -176.415192)
					(end 392.622024 -173.315122)
				)
				(arc
					(start 392.622024 -173.315122)
					(mid 389.521954 -170.215052)
					(end 386.421884 -173.315122)
				)
			)
		)
	)
	(zone
		(layer "B.Cu")
		(hatch none 0.5)
		(connect_pads
			(clearance 0)
		)
		(min_thickness 0.25)
		(keepout
			(tracks not_allowed)
			(vias allowed)
			(pads allowed)
			(copperpour not_allowed)
			(footprints allowed)
		)
		(placement
			(enabled no)
			(sheetname "")
		)
		(fill
			(thermal_gap 0.5)
			(thermal_bridge_width 0.5)
			(island_removal_mode 0)
		)
		(polygon
			(pts
				(arc
					(start 20.734782 -138.001502)
					(mid 20.066762 -138.001502)
					(end 20.734782 -138.001502)
				)
			)
		)
	)
	(zone
		(layer "B.Cu")
		(hatch none 0.5)
		(connect_pads
			(clearance 0)
		)
		(min_thickness 0.25)
		(keepout
			(tracks allowed)
			(vias allowed)
			(pads allowed)
			(copperpour allowed)
			(footprints allowed)
		)
		(placement
			(enabled no)
			(sheetname "")
		)
		(fill
			(thermal_gap 0.5)
			(thermal_bridge_width 0.5)
			(island_removal_mode 0)
		)
		(polygon
			(pts
				(xy 326.95388 -337.264756) (xy 326.95388 -339.423756) (xy 326.57288 -339.804756) (xy 323.77888 -339.804756)
				(xy 322.63588 -338.661756) (xy 322.63588 -335.740756) (xy 323.14388 -335.232756) (xy 324.92188 -335.232756)
			)
		)
	)
	(zone
		(layer "B.Cu")
		(hatch none 0.5)
		(connect_pads
			(clearance 0)
		)
		(min_thickness 0.25)
		(keepout
			(tracks not_allowed)
			(vias allowed)
			(pads allowed)
			(copperpour not_allowed)
			(footprints allowed)
		)
		(placement
			(enabled no)
			(sheetname "")
		)
		(fill
			(thermal_gap 0.5)
			(thermal_bridge_width 0.5)
			(island_removal_mode 0)
		)
		(polygon
			(pts
				(arc
					(start 413.137096 -439.0898)
					(mid 412.362904 -439.0898)
					(end 413.137096 -439.0898)
				)
			)
		)
	)
	(zone
		(layer "B.Cu")
		(hatch none 0.5)
		(connect_pads
			(clearance 0)
		)
		(min_thickness 0.25)
		(keepout
			(tracks not_allowed)
			(vias allowed)
			(pads allowed)
			(copperpour not_allowed)
			(footprints allowed)
		)
		(placement
			(enabled no)
			(sheetname "")
		)
		(fill
			(thermal_gap 0.5)
			(thermal_bridge_width 0.5)
			(island_removal_mode 0)
		)
		(polygon
			(pts
				(arc
					(start 342.036908 -439.0898)
					(mid 341.262716 -439.0898)
					(end 342.036908 -439.0898)
				)
			)
		)
	)
	(zone
		(layer "B.Cu")
		(hatch none 0.5)
		(connect_pads
			(clearance 0)
		)
		(min_thickness 0.25)
		(keepout
			(tracks not_allowed)
			(vias allowed)
			(pads allowed)
			(copperpour not_allowed)
			(footprints allowed)
		)
		(placement
			(enabled no)
			(sheetname "")
		)
		(fill
			(thermal_gap 0.5)
			(thermal_bridge_width 0.5)
			(island_removal_mode 0)
		)
		(polygon
			(pts
				(arc
					(start 357.986076 -272.466054)
					(mid 357.356156 -272.466054)
					(end 357.986076 -272.466054)
				)
			)
		)
	)
	(zone
		(layer "B.Cu")
		(hatch none 0.5)
		(connect_pads
			(clearance 0)
		)
		(min_thickness 0.25)
		(keepout
			(tracks not_allowed)
			(vias allowed)
			(pads allowed)
			(copperpour not_allowed)
			(footprints allowed)
		)
		(placement
			(enabled no)
			(sheetname "")
		)
		(fill
			(thermal_gap 0.5)
			(thermal_bridge_width 0.5)
			(island_removal_mode 0)
		)
		(polygon
			(pts
				(arc
					(start 320.950336 -400.811238)
					(mid 320.282316 -400.811238)
					(end 320.950336 -400.811238)
				)
			)
		)
	)
	(zone
		(layer "B.Cu")
		(hatch none 0.5)
		(connect_pads
			(clearance 0)
		)
		(min_thickness 0.25)
		(keepout
			(tracks not_allowed)
			(vias allowed)
			(pads allowed)
			(copperpour not_allowed)
			(footprints allowed)
		)
		(placement
			(enabled no)
			(sheetname "")
		)
		(fill
			(thermal_gap 0.5)
			(thermal_bridge_width 0.5)
			(island_removal_mode 0)
		)
		(polygon
			(pts
				(arc
					(start 288.550096 -435.600094)
					(mid 293.550086 -440.600084)
					(end 298.550076 -435.600094)
				)
				(arc
					(start 298.550076 -435.600094)
					(mid 293.550086 -430.600104)
					(end 288.550096 -435.600094)
				)
			)
		)
	)
	(zone
		(layer "B.Cu")
		(hatch none 0.5)
		(connect_pads
			(clearance 0)
		)
		(min_thickness 0.25)
		(keepout
			(tracks not_allowed)
			(vias allowed)
			(pads allowed)
			(copperpour not_allowed)
			(footprints allowed)
		)
		(placement
			(enabled no)
			(sheetname "")
		)
		(fill
			(thermal_gap 0.5)
			(thermal_bridge_width 0.5)
			(island_removal_mode 0)
		)
		(polygon
			(pts
				(arc
					(start 123.369578 -244.484398)
					(mid 122.739658 -244.484398)
					(end 123.369578 -244.484398)
				)
			)
		)
	)
	(zone
		(layer "B.Cu")
		(hatch none 0.5)
		(connect_pads
			(clearance 0)
		)
		(min_thickness 0.25)
		(keepout
			(tracks allowed)
			(vias allowed)
			(pads allowed)
			(copperpour allowed)
			(footprints not_allowed)
		)
		(placement
			(enabled no)
			(sheetname "")
		)
		(fill
			(thermal_gap 0.5)
			(thermal_bridge_width 0.5)
			(island_removal_mode 0)
		)
		(polygon
			(pts
				(arc
					(start 36.735004 -389.439912)
					(mid 34.870136 -387.575044)
					(end 33.005014 -389.439912)
				)
				(arc
					(start 33.005014 -389.439912)
					(mid 34.870136 -391.305034)
					(end 36.735004 -389.439912)
				)
			)
		)
	)
	(zone
		(layer "B.Cu")
		(hatch none 0.5)
		(connect_pads
			(clearance 0)
		)
		(min_thickness 0.25)
		(keepout
			(tracks not_allowed)
			(vias allowed)
			(pads allowed)
			(copperpour not_allowed)
			(footprints allowed)
		)
		(placement
			(enabled no)
			(sheetname "")
		)
		(fill
			(thermal_gap 0.5)
			(thermal_bridge_width 0.5)
			(island_removal_mode 0)
		)
		(polygon
			(pts
				(arc
					(start 145.137124 -439.0898)
					(mid 144.362932 -439.0898)
					(end 145.137124 -439.0898)
				)
			)
		)
	)
	(zone
		(layer "B.Cu")
		(hatch none 0.5)
		(connect_pads
			(clearance 0)
		)
		(min_thickness 0.25)
		(keepout
			(tracks not_allowed)
			(vias allowed)
			(pads allowed)
			(copperpour not_allowed)
			(footprints allowed)
		)
		(placement
			(enabled no)
			(sheetname "")
		)
		(fill
			(thermal_gap 0.5)
			(thermal_bridge_width 0.5)
			(island_removal_mode 0)
		)
		(polygon
			(pts
				(arc
					(start 231.650032 -352.49993)
					(mid 236.650022 -357.49992)
					(end 241.650012 -352.49993)
				)
				(arc
					(start 241.650012 -352.49993)
					(mid 236.650022 -347.49994)
					(end 231.650032 -352.49993)
				)
			)
		)
	)
	(zone
		(layer "B.Cu")
		(hatch none 0.5)
		(connect_pads
			(clearance 0)
		)
		(min_thickness 0.25)
		(keepout
			(tracks not_allowed)
			(vias allowed)
			(pads allowed)
			(copperpour not_allowed)
			(footprints allowed)
		)
		(placement
			(enabled no)
			(sheetname "")
		)
		(fill
			(thermal_gap 0.5)
			(thermal_bridge_width 0.5)
			(island_removal_mode 0)
		)
		(polygon
			(pts
				(arc
					(start 355.336094 -246.104156)
					(mid 354.706174 -246.104156)
					(end 355.336094 -246.104156)
				)
			)
		)
	)
	(zone
		(layer "B.Cu")
		(hatch none 0.5)
		(connect_pads
			(clearance 0)
		)
		(min_thickness 0.25)
		(keepout
			(tracks allowed)
			(vias allowed)
			(pads allowed)
			(copperpour allowed)
			(footprints not_allowed)
		)
		(placement
			(enabled no)
			(sheetname "")
		)
		(fill
			(thermal_gap 0.5)
			(thermal_bridge_width 0.5)
			(island_removal_mode 0)
		)
		(polygon
			(pts
				(arc
					(start 198.399908 -22.29993)
					(mid 203.399898 -27.29992)
					(end 208.399888 -22.29993)
				)
				(arc
					(start 208.399888 -22.29993)
					(mid 203.399898 -17.29994)
					(end 198.399908 -22.29993)
				)
			)
		)
	)
	(zone
		(layer "B.Cu")
		(hatch none 0.5)
		(connect_pads
			(clearance 0)
		)
		(min_thickness 0.25)
		(keepout
			(tracks not_allowed)
			(vias allowed)
			(pads allowed)
			(copperpour not_allowed)
			(footprints allowed)
		)
		(placement
			(enabled no)
			(sheetname "")
		)
		(fill
			(thermal_gap 0.5)
			(thermal_bridge_width 0.5)
			(island_removal_mode 0)
		)
		(polygon
			(pts
				(arc
					(start 128.136904 -439.0898)
					(mid 127.362712 -439.0898)
					(end 128.136904 -439.0898)
				)
			)
		)
	)
	(zone
		(layer "B.Cu")
		(hatch none 0.5)
		(connect_pads
			(clearance 0)
		)
		(min_thickness 0.25)
		(keepout
			(tracks not_allowed)
			(vias allowed)
			(pads allowed)
			(copperpour not_allowed)
			(footprints allowed)
		)
		(placement
			(enabled no)
			(sheetname "")
		)
		(fill
			(thermal_gap 0.5)
			(thermal_bridge_width 0.5)
			(island_removal_mode 0)
		)
		(polygon
			(pts
				(arc
					(start 321.036696 -439.0898)
					(mid 320.262504 -439.0898)
					(end 321.036696 -439.0898)
				)
			)
		)
	)
	(zone
		(layer "B.Cu")
		(hatch none 0.5)
		(connect_pads
			(clearance 0)
		)
		(min_thickness 0.25)
		(keepout
			(tracks allowed)
			(vias allowed)
			(pads allowed)
			(copperpour allowed)
			(footprints not_allowed)
		)
		(placement
			(enabled no)
			(sheetname "")
		)
		(fill
			(thermal_gap 0.5)
			(thermal_bridge_width 0.5)
			(island_removal_mode 0)
		)
		(polygon
			(pts
				(arc
					(start 325.769986 -212.989922)
					(mid 329.270106 -216.490042)
					(end 332.769972 -212.989922)
				)
				(arc
					(start 332.769972 -212.989922)
					(mid 329.270106 -209.490056)
					(end 325.769986 -212.989922)
				)
			)
		)
	)
	(zone
		(layer "B.Cu")
		(hatch none 0.5)
		(connect_pads
			(clearance 0)
		)
		(min_thickness 0.25)
		(keepout
			(tracks not_allowed)
			(vias allowed)
			(pads allowed)
			(copperpour not_allowed)
			(footprints allowed)
		)
		(placement
			(enabled no)
			(sheetname "")
		)
		(fill
			(thermal_gap 0.5)
			(thermal_bridge_width 0.5)
			(island_removal_mode 0)
		)
		(polygon
			(pts
				(arc
					(start 306.550314 -400.811238)
					(mid 305.882294 -400.811238)
					(end 306.550314 -400.811238)
				)
			)
		)
	)
	(zone
		(layer "B.Cu")
		(hatch none 0.5)
		(connect_pads
			(clearance 0)
		)
		(min_thickness 0.25)
		(keepout
			(tracks allowed)
			(vias allowed)
			(pads allowed)
			(copperpour allowed)
			(footprints not_allowed)
		)
		(placement
			(enabled no)
			(sheetname "")
		)
		(fill
			(thermal_gap 0.5)
			(thermal_bridge_width 0.5)
			(island_removal_mode 0)
		)
		(polygon
			(pts
				(arc
					(start 299.820076 -413.170116)
					(mid 297.570144 -410.920184)
					(end 295.319958 -413.170116)
				)
				(arc
					(start 295.319958 -413.170116)
					(mid 297.570144 -415.420302)
					(end 299.820076 -413.170116)
				)
			)
		)
	)
	(zone
		(layer "B.Cu")
		(hatch none 0.5)
		(connect_pads
			(clearance 0)
		)
		(min_thickness 0.25)
		(keepout
			(tracks not_allowed)
			(vias allowed)
			(pads allowed)
			(copperpour not_allowed)
			(footprints allowed)
		)
		(placement
			(enabled no)
			(sheetname "")
		)
		(fill
			(thermal_gap 0.5)
			(thermal_bridge_width 0.5)
			(island_removal_mode 0)
		)
		(polygon
			(pts
				(arc
					(start 321.305936 -394.385292)
					(mid 320.676016 -394.385292)
					(end 321.305936 -394.385292)
				)
			)
		)
	)
	(zone
		(layer "B.Cu")
		(hatch none 0.5)
		(connect_pads
			(clearance 0)
		)
		(min_thickness 0.25)
		(keepout
			(tracks allowed)
			(vias allowed)
			(pads allowed)
			(copperpour allowed)
			(footprints allowed)
		)
		(placement
			(enabled no)
			(sheetname "")
		)
		(fill
			(thermal_gap 0.5)
			(thermal_bridge_width 0.5)
			(island_removal_mode 0)
		)
		(polygon
			(pts
				(xy 11.5062 -106.7308) (xy 11.5062 -105.0798) (xy 12.4714 -105.0798) (xy 12.4714 -106.7308)
			)
		)
	)
	(zone
		(layer "B.Cu")
		(hatch none 0.5)
		(connect_pads
			(clearance 0)
		)
		(min_thickness 0.25)
		(keepout
			(tracks allowed)
			(vias allowed)
			(pads allowed)
			(copperpour allowed)
			(footprints not_allowed)
		)
		(placement
			(enabled no)
			(sheetname "")
		)
		(fill
			(thermal_gap 0.5)
			(thermal_bridge_width 0.5)
			(island_removal_mode 0)
		)
		(polygon
			(pts
				(arc
					(start 196.650102 -51.999896)
					(mid 204.650086 -59.99988)
					(end 212.65007 -51.999896)
				)
				(arc
					(start 212.65007 -51.999896)
					(mid 204.650086 -43.999912)
					(end 196.650102 -51.999896)
				)
			)
		)
	)
	(zone
		(layer "B.Cu")
		(hatch none 0.5)
		(connect_pads
			(clearance 0)
		)
		(min_thickness 0.25)
		(keepout
			(tracks not_allowed)
			(vias allowed)
			(pads allowed)
			(copperpour not_allowed)
			(footprints allowed)
		)
		(placement
			(enabled no)
			(sheetname "")
		)
		(fill
			(thermal_gap 0.5)
			(thermal_bridge_width 0.5)
			(island_removal_mode 0)
		)
		(polygon
			(pts
				(arc
					(start 409.137104 -439.0898)
					(mid 408.362912 -439.0898)
					(end 409.137104 -439.0898)
				)
			)
		)
	)
	(zone
		(layer "B.Cu")
		(hatch none 0.5)
		(connect_pads
			(clearance 0)
		)
		(min_thickness 0.25)
		(keepout
			(tracks allowed)
			(vias allowed)
			(pads allowed)
			(copperpour allowed)
			(footprints allowed)
		)
		(placement
			(enabled no)
			(sheetname "")
		)
		(fill
			(thermal_gap 0.5)
			(thermal_bridge_width 0.5)
			(island_removal_mode 0)
		)
		(polygon
			(pts
				(xy 191.94272 -193.8274) (xy 191.94272 -190.7159) (xy 193.97726 -190.7159) (xy 193.97726 -193.8274)
			)
		)
	)
	(zone
		(layer "B.Cu")
		(hatch none 0.5)
		(connect_pads
			(clearance 0)
		)
		(min_thickness 0.25)
		(keepout
			(tracks not_allowed)
			(vias allowed)
			(pads allowed)
			(copperpour not_allowed)
			(footprints allowed)
		)
		(placement
			(enabled no)
			(sheetname "")
		)
		(fill
			(thermal_gap 0.5)
			(thermal_bridge_width 0.5)
			(island_removal_mode 0)
		)
		(polygon
			(pts
				(arc
					(start 110.046008 -274.08632)
					(mid 109.416088 -274.08632)
					(end 110.046008 -274.08632)
				)
			)
		)
	)
	(zone
		(layer "B.Cu")
		(hatch none 0.5)
		(connect_pads
			(clearance 0)
		)
		(min_thickness 0.25)
		(keepout
			(tracks allowed)
			(vias allowed)
			(pads allowed)
			(copperpour allowed)
			(footprints allowed)
		)
		(placement
			(enabled no)
			(sheetname "")
		)
		(fill
			(thermal_gap 0.5)
			(thermal_bridge_width 0.5)
			(island_removal_mode 0)
		)
		(polygon
			(pts
				(xy 31.6738 -358.95153) (xy 32.678116 -358.95153) (xy 32.678116 -360.328464) (xy 31.6738 -360.328464)
			)
		)
	)
	(zone
		(layer "B.Cu")
		(hatch none 0.5)
		(connect_pads
			(clearance 0)
		)
		(min_thickness 0.25)
		(keepout
			(tracks allowed)
			(vias allowed)
			(pads allowed)
			(copperpour allowed)
			(footprints allowed)
		)
		(placement
			(enabled no)
			(sheetname "")
		)
		(fill
			(thermal_gap 0.5)
			(thermal_bridge_width 0.5)
			(island_removal_mode 0)
		)
		(polygon
			(pts
				(xy 171.303188 -99.57308) (xy 171.303188 -98.971354) (xy 178.981862 -98.971354) (xy 178.981862 -99.57308)
			)
		)
	)
	(zone
		(layer "B.Cu")
		(hatch none 0.5)
		(connect_pads
			(clearance 0)
		)
		(min_thickness 0.25)
		(keepout
			(tracks allowed)
			(vias allowed)
			(pads allowed)
			(copperpour allowed)
			(footprints not_allowed)
		)
		(placement
			(enabled no)
			(sheetname "")
		)
		(fill
			(thermal_gap 0.5)
			(thermal_bridge_width 0.5)
			(island_removal_mode 0)
		)
		(polygon
			(pts
				(arc
					(start 445.051942 -351.415096)
					(mid 441.952126 -348.31528)
					(end 438.852056 -351.415096)
				)
				(arc
					(start 438.852056 -351.415096)
					(mid 441.952126 -354.515166)
					(end 445.051942 -351.415096)
				)
			)
		)
	)
	(zone
		(layer "B.Cu")
		(hatch none 0.5)
		(connect_pads
			(clearance 0)
		)
		(min_thickness 0.25)
		(keepout
			(tracks allowed)
			(vias allowed)
			(pads allowed)
			(copperpour allowed)
			(footprints not_allowed)
		)
		(placement
			(enabled no)
			(sheetname "")
		)
		(fill
			(thermal_gap 0.5)
			(thermal_bridge_width 0.5)
			(island_removal_mode 0)
		)
		(polygon
			(pts
				(arc
					(start 424.746928 -163.314888)
					(mid 422.88206 -161.45002)
					(end 421.016938 -163.314888)
				)
				(arc
					(start 421.016938 -163.314888)
					(mid 422.88206 -165.18001)
					(end 424.746928 -163.314888)
				)
			)
		)
	)
	(zone
		(layer "B.Cu")
		(hatch none 0.5)
		(connect_pads
			(clearance 0)
		)
		(min_thickness 0.25)
		(keepout
			(tracks not_allowed)
			(vias allowed)
			(pads allowed)
			(copperpour not_allowed)
			(footprints allowed)
		)
		(placement
			(enabled no)
			(sheetname "")
		)
		(fill
			(thermal_gap 0.5)
			(thermal_bridge_width 0.5)
			(island_removal_mode 0)
		)
		(polygon
			(pts
				(arc
					(start 40.341804 -422.638982)
					(mid 39.673784 -422.638982)
					(end 40.341804 -422.638982)
				)
			)
		)
	)
	(zone
		(layer "B.Cu")
		(hatch none 0.5)
		(connect_pads
			(clearance 0)
		)
		(min_thickness 0.25)
		(keepout
			(tracks allowed)
			(vias allowed)
			(pads allowed)
			(copperpour allowed)
			(footprints not_allowed)
		)
		(placement
			(enabled no)
			(sheetname "")
		)
		(fill
			(thermal_gap 0.5)
			(thermal_bridge_width 0.5)
			(island_removal_mode 0)
		)
		(polygon
			(pts
				(arc
					(start 22.080982 -347.8149)
					(mid 20.216114 -345.950032)
					(end 18.350992 -347.8149)
				)
				(arc
					(start 18.350992 -347.8149)
					(mid 20.216114 -349.680022)
					(end 22.080982 -347.8149)
				)
			)
		)
	)
	(zone
		(layer "B.Cu")
		(hatch none 0.5)
		(connect_pads
			(clearance 0)
		)
		(min_thickness 0.25)
		(keepout
			(tracks not_allowed)
			(vias allowed)
			(pads allowed)
			(copperpour not_allowed)
			(footprints allowed)
		)
		(placement
			(enabled no)
			(sheetname "")
		)
		(fill
			(thermal_gap 0.5)
			(thermal_bridge_width 0.5)
			(island_removal_mode 0)
		)
		(polygon
			(pts
				(arc
					(start 256.261108 -196.20992)
					(mid 255.593088 -196.20992)
					(end 256.261108 -196.20992)
				)
			)
		)
	)
	(zone
		(layer "B.Cu")
		(hatch none 0.5)
		(connect_pads
			(clearance 0)
		)
		(min_thickness 0.25)
		(keepout
			(tracks allowed)
			(vias allowed)
			(pads allowed)
			(copperpour allowed)
			(footprints allowed)
		)
		(placement
			(enabled no)
			(sheetname "")
		)
		(fill
			(thermal_gap 0.5)
			(thermal_bridge_width 0.5)
			(island_removal_mode 0)
		)
		(polygon
			(pts
				(xy 193.651632 -98.596704) (xy 193.651632 -97.994978) (xy 195.241672 -97.994978) (xy 195.241672 -98.596704)
			)
		)
	)
	(zone
		(layer "B.Cu")
		(hatch none 0.5)
		(connect_pads
			(clearance 0)
		)
		(min_thickness 0.25)
		(keepout
			(tracks not_allowed)
			(vias allowed)
			(pads allowed)
			(copperpour not_allowed)
			(footprints allowed)
		)
		(placement
			(enabled no)
			(sheetname "")
		)
		(fill
			(thermal_gap 0.5)
			(thermal_bridge_width 0.5)
			(island_removal_mode 0)
		)
		(polygon
			(pts
				(arc
					(start 163.378134 -392.429238)
					(mid 162.710114 -392.429238)
					(end 163.378134 -392.429238)
				)
			)
		)
	)
	(zone
		(layer "B.Cu")
		(hatch none 0.5)
		(connect_pads
			(clearance 0)
		)
		(min_thickness 0.25)
		(keepout
			(tracks allowed)
			(vias allowed)
			(pads allowed)
			(copperpour allowed)
			(footprints not_allowed)
		)
		(placement
			(enabled no)
			(sheetname "")
		)
		(fill
			(thermal_gap 0.5)
			(thermal_bridge_width 0.5)
			(island_removal_mode 0)
		)
		(polygon
			(pts
				(arc
					(start 43.82008 -404.789894)
					(mid 41.570148 -402.539962)
					(end 39.319962 -404.789894)
				)
				(arc
					(start 39.319962 -404.789894)
					(mid 41.570148 -407.04008)
					(end 43.82008 -404.789894)
				)
			)
		)
	)
	(zone
		(layer "B.Cu")
		(hatch none 0.5)
		(connect_pads
			(clearance 0)
		)
		(min_thickness 0.25)
		(keepout
			(tracks not_allowed)
			(vias allowed)
			(pads allowed)
			(copperpour not_allowed)
			(footprints allowed)
		)
		(placement
			(enabled no)
			(sheetname "")
		)
		(fill
			(thermal_gap 0.5)
			(thermal_bridge_width 0.5)
			(island_removal_mode 0)
		)
		(polygon
			(pts
				(arc
					(start 147.778216 -392.429238)
					(mid 147.110196 -392.429238)
					(end 147.778216 -392.429238)
				)
			)
		)
	)
	(zone
		(layer "B.Cu")
		(hatch none 0.5)
		(connect_pads
			(clearance 0)
		)
		(min_thickness 0.25)
		(keepout
			(tracks allowed)
			(vias allowed)
			(pads allowed)
			(copperpour allowed)
			(footprints not_allowed)
		)
		(placement
			(enabled no)
			(sheetname "")
		)
		(fill
			(thermal_gap 0.5)
			(thermal_bridge_width 0.5)
			(island_removal_mode 0)
		)
		(polygon
			(pts
				(arc
					(start 245.625112 -360.764074)
					(mid 258.125214 -373.264176)
					(end 270.625062 -360.764074)
				)
				(arc
					(start 270.625062 -360.764074)
					(mid 258.125214 -348.264226)
					(end 245.625112 -360.764074)
				)
			)
		)
	)
	(zone
		(layer "B.Cu")
		(hatch none 0.5)
		(connect_pads
			(clearance 0)
		)
		(min_thickness 0.25)
		(keepout
			(tracks allowed)
			(vias allowed)
			(pads allowed)
			(copperpour allowed)
			(footprints allowed)
		)
		(placement
			(enabled no)
			(sheetname "")
		)
		(fill
			(thermal_gap 0.5)
			(thermal_bridge_width 0.5)
			(island_removal_mode 0)
		)
		(polygon
			(pts
				(xy 292.78072 -194.35826) (xy 292.78072 -190.66256) (xy 295.10482 -190.66256) (xy 295.10482 -194.35826)
			)
		)
	)
	(zone
		(layer "B.Cu")
		(hatch none 0.5)
		(connect_pads
			(clearance 0)
		)
		(min_thickness 0.25)
		(keepout
			(tracks allowed)
			(vias allowed)
			(pads allowed)
			(copperpour allowed)
			(footprints allowed)
		)
		(placement
			(enabled no)
			(sheetname "")
		)
		(fill
			(thermal_gap 0.5)
			(thermal_bridge_width 0.5)
			(island_removal_mode 0)
		)
		(polygon
			(pts
				(xy 397.55191 -174.894494) (xy 397.55191 -172.735494) (xy 397.93291 -172.354494) (xy 400.72691 -172.354494)
				(xy 401.86991 -173.497494) (xy 401.86991 -176.418494) (xy 401.36191 -176.926494) (xy 399.58391 -176.926494)
			)
		)
	)
	(zone
		(layer "B.Cu")
		(hatch none 0.5)
		(connect_pads
			(clearance 0)
		)
		(min_thickness 0.25)
		(keepout
			(tracks not_allowed)
			(vias allowed)
			(pads allowed)
			(copperpour not_allowed)
			(footprints allowed)
		)
		(placement
			(enabled no)
			(sheetname "")
		)
		(fill
			(thermal_gap 0.5)
			(thermal_bridge_width 0.5)
			(island_removal_mode 0)
		)
		(polygon
			(pts
				(arc
					(start 405.137112 -439.0898)
					(mid 404.36292 -439.0898)
					(end 405.137112 -439.0898)
				)
			)
		)
	)
	(zone
		(layer "B.Cu")
		(hatch none 0.5)
		(connect_pads
			(clearance 0)
		)
		(min_thickness 0.25)
		(keepout
			(tracks allowed)
			(vias allowed)
			(pads allowed)
			(copperpour allowed)
			(footprints not_allowed)
		)
		(placement
			(enabled no)
			(sheetname "")
		)
		(fill
			(thermal_gap 0.5)
			(thermal_bridge_width 0.5)
			(island_removal_mode 0)
		)
		(polygon
			(pts
				(arc
					(start 460.339948 -399.029936)
					(mid 463.440018 -402.130006)
					(end 466.540088 -399.029936)
				)
				(arc
					(start 466.540088 -399.029936)
					(mid 463.440018 -395.929866)
					(end 460.339948 -399.029936)
				)
			)
		)
	)
	(zone
		(layer "B.Cu")
		(hatch none 0.5)
		(connect_pads
			(clearance 0)
		)
		(min_thickness 0.25)
		(keepout
			(tracks not_allowed)
			(vias allowed)
			(pads allowed)
			(copperpour not_allowed)
			(footprints allowed)
		)
		(placement
			(enabled no)
			(sheetname "")
		)
		(fill
			(thermal_gap 0.5)
			(thermal_bridge_width 0.5)
			(island_removal_mode 0)
		)
		(polygon
			(pts
				(arc
					(start 304.150268 -401.674838)
					(mid 303.482248 -401.674838)
					(end 304.150268 -401.674838)
				)
			)
		)
	)
	(zone
		(layer "B.Cu")
		(hatch none 0.5)
		(connect_pads
			(clearance 0)
		)
		(min_thickness 0.25)
		(keepout
			(tracks not_allowed)
			(vias allowed)
			(pads allowed)
			(copperpour not_allowed)
			(footprints allowed)
		)
		(placement
			(enabled no)
			(sheetname "")
		)
		(fill
			(thermal_gap 0.5)
			(thermal_bridge_width 0.5)
			(island_removal_mode 0)
		)
		(polygon
			(pts
				(arc
					(start 52.950618 -393.292838)
					(mid 52.282598 -393.292838)
					(end 52.950618 -393.292838)
				)
			)
		)
	)
	(zone
		(layer "B.Cu")
		(hatch none 0.5)
		(connect_pads
			(clearance 0)
		)
		(min_thickness 0.25)
		(keepout
			(tracks allowed)
			(vias allowed)
			(pads allowed)
			(copperpour allowed)
			(footprints allowed)
		)
		(placement
			(enabled no)
			(sheetname "")
		)
		(fill
			(thermal_gap 0.5)
			(thermal_bridge_width 0.5)
			(island_removal_mode 0)
		)
		(polygon
			(pts
				(xy 393.601956 -417.428426) (xy 393.601956 -416.42411) (xy 394.97889 -416.42411) (xy 394.97889 -417.428426)
			)
		)
	)
	(zone
		(layer "B.Cu")
		(hatch none 0.5)
		(connect_pads
			(clearance 0)
		)
		(min_thickness 0.25)
		(keepout
			(tracks not_allowed)
			(vias allowed)
			(pads allowed)
			(copperpour not_allowed)
			(footprints allowed)
		)
		(placement
			(enabled no)
			(sheetname "")
		)
		(fill
			(thermal_gap 0.5)
			(thermal_bridge_width 0.5)
			(island_removal_mode 0)
		)
		(polygon
			(pts
				(arc
					(start 122.429778 -246.10441)
					(mid 121.799858 -246.10441)
					(end 122.429778 -246.10441)
				)
			)
		)
	)
	(zone
		(layer "B.Cu")
		(hatch none 0.5)
		(connect_pads
			(clearance 0)
		)
		(min_thickness 0.25)
		(keepout
			(tracks not_allowed)
			(vias allowed)
			(pads allowed)
			(copperpour not_allowed)
			(footprints allowed)
		)
		(placement
			(enabled no)
			(sheetname "")
		)
		(fill
			(thermal_gap 0.5)
			(thermal_bridge_width 0.5)
			(island_removal_mode 0)
		)
		(polygon
			(pts
				(arc
					(start 132.35432 -10.243312)
					(mid 131.6863 -10.243312)
					(end 132.35432 -10.243312)
				)
			)
		)
	)
	(zone
		(layer "B.Cu")
		(hatch none 0.5)
		(connect_pads
			(clearance 0)
		)
		(min_thickness 0.25)
		(keepout
			(tracks allowed)
			(vias allowed)
			(pads allowed)
			(copperpour allowed)
			(footprints not_allowed)
		)
		(placement
			(enabled no)
			(sheetname "")
		)
		(fill
			(thermal_gap 0.5)
			(thermal_bridge_width 0.5)
			(island_removal_mode 0)
		)
		(polygon
			(pts
				(arc
					(start 293.569898 -413.170116)
					(mid 297.56989 -417.170108)
					(end 301.569882 -413.170116)
				)
				(arc
					(start 301.569882 -413.170116)
					(mid 297.56989 -409.170124)
					(end 293.569898 -413.170116)
				)
			)
		)
	)
	(zone
		(layer "B.Cu")
		(hatch none 0.5)
		(connect_pads
			(clearance 0)
		)
		(min_thickness 0.25)
		(keepout
			(tracks not_allowed)
			(vias allowed)
			(pads allowed)
			(copperpour not_allowed)
			(footprints allowed)
		)
		(placement
			(enabled no)
			(sheetname "")
		)
		(fill
			(thermal_gap 0.5)
			(thermal_bridge_width 0.5)
			(island_removal_mode 0)
		)
		(polygon
			(pts
				(arc
					(start 149.137116 -437.889904)
					(mid 148.362924 -437.889904)
					(end 149.137116 -437.889904)
				)
			)
		)
	)
	(zone
		(layer "B.Cu")
		(hatch none 0.5)
		(connect_pads
			(clearance 0)
		)
		(min_thickness 0.25)
		(keepout
			(tracks not_allowed)
			(vias allowed)
			(pads allowed)
			(copperpour not_allowed)
			(footprints allowed)
		)
		(placement
			(enabled no)
			(sheetname "")
		)
		(fill
			(thermal_gap 0.5)
			(thermal_bridge_width 0.5)
			(island_removal_mode 0)
		)
		(polygon
			(pts
				(arc
					(start 115.379754 -248.534428)
					(mid 114.749834 -248.534428)
					(end 115.379754 -248.534428)
				)
			)
		)
	)
	(zone
		(layer "B.Cu")
		(hatch none 0.5)
		(connect_pads
			(clearance 0)
		)
		(min_thickness 0.25)
		(keepout
			(tracks not_allowed)
			(vias allowed)
			(pads allowed)
			(copperpour not_allowed)
			(footprints allowed)
		)
		(placement
			(enabled no)
			(sheetname "")
		)
		(fill
			(thermal_gap 0.5)
			(thermal_bridge_width 0.5)
			(island_removal_mode 0)
		)
		(polygon
			(pts
				(arc
					(start 405.137112 -437.889904)
					(mid 404.36292 -437.889904)
					(end 405.137112 -437.889904)
				)
			)
		)
	)
	(zone
		(layer "B.Cu")
		(hatch none 0.5)
		(connect_pads
			(clearance 0)
		)
		(min_thickness 0.25)
		(keepout
			(tracks not_allowed)
			(vias allowed)
			(pads allowed)
			(copperpour not_allowed)
			(footprints allowed)
		)
		(placement
			(enabled no)
			(sheetname "")
		)
		(fill
			(thermal_gap 0.5)
			(thermal_bridge_width 0.5)
			(island_removal_mode 0)
		)
		(polygon
			(pts
				(arc
					(start 66.106294 -385.31038)
					(mid 65.476374 -385.31038)
					(end 66.106294 -385.31038)
				)
			)
		)
	)
	(zone
		(layer "B.Cu")
		(hatch none 0.5)
		(connect_pads
			(clearance 0)
		)
		(min_thickness 0.25)
		(keepout
			(tracks allowed)
			(vias allowed)
			(pads allowed)
			(copperpour allowed)
			(footprints allowed)
		)
		(placement
			(enabled no)
			(sheetname "")
		)
		(fill
			(thermal_gap 0.5)
			(thermal_bridge_width 0.5)
			(island_removal_mode 0)
		)
		(polygon
			(pts
				(xy 95.007938 -409.046426) (xy 95.007938 -408.04211) (xy 96.384872 -408.04211) (xy 96.384872 -409.046426)
			)
		)
	)
	(zone
		(layer "B.Cu")
		(hatch none 0.5)
		(connect_pads
			(clearance 0)
		)
		(min_thickness 0.25)
		(keepout
			(tracks not_allowed)
			(vias allowed)
			(pads allowed)
			(copperpour not_allowed)
			(footprints allowed)
		)
		(placement
			(enabled no)
			(sheetname "")
		)
		(fill
			(thermal_gap 0.5)
			(thermal_bridge_width 0.5)
			(island_removal_mode 0)
		)
		(polygon
			(pts
				(arc
					(start 150.530052 -258.890008)
					(mid 154.030172 -262.390128)
					(end 157.530038 -258.890008)
				)
				(arc
					(start 157.530038 -258.890008)
					(mid 154.030172 -255.390142)
					(end 150.530052 -258.890008)
				)
			)
		)
	)
	(zone
		(layer "B.Cu")
		(hatch none 0.5)
		(connect_pads
			(clearance 0)
		)
		(min_thickness 0.25)
		(keepout
			(tracks allowed)
			(vias allowed)
			(pads allowed)
			(copperpour allowed)
			(footprints allowed)
		)
		(placement
			(enabled no)
			(sheetname "")
		)
		(fill
			(thermal_gap 0.5)
			(thermal_bridge_width 0.5)
			(island_removal_mode 0)
		)
		(polygon
			(pts
				(xy 166.275766 -384.911854) (xy 166.275766 -383.394966) (xy 166.2684 -383.3876) (xy 166.2684 -382.876806)
				(xy 165.722046 -382.330452) (xy 164.441632 -382.330452) (xy 164.2237 -382.548384) (xy 148.223224 -382.548384)
				(xy 147.672806 -383.098802) (xy 147.672806 -384.911854)
			)
		)
	)
	(zone
		(layer "B.Cu")
		(hatch none 0.5)
		(connect_pads
			(clearance 0)
		)
		(min_thickness 0.25)
		(keepout
			(tracks not_allowed)
			(vias allowed)
			(pads allowed)
			(copperpour not_allowed)
			(footprints allowed)
		)
		(placement
			(enabled no)
			(sheetname "")
		)
		(fill
			(thermal_gap 0.5)
			(thermal_bridge_width 0.5)
			(island_removal_mode 0)
		)
		(polygon
			(pts
				(arc
					(start 418.178234 -401.674838)
					(mid 417.510214 -401.674838)
					(end 418.178234 -401.674838)
				)
			)
		)
	)
	(zone
		(layer "B.Cu")
		(hatch none 0.5)
		(connect_pads
			(clearance 0)
		)
		(min_thickness 0.25)
		(keepout
			(tracks allowed)
			(vias allowed)
			(pads allowed)
			(copperpour allowed)
			(footprints allowed)
		)
		(placement
			(enabled no)
			(sheetname "")
		)
		(fill
			(thermal_gap 0.5)
			(thermal_bridge_width 0.5)
			(island_removal_mode 0)
		)
		(polygon
			(pts
				(xy 87.404194 -337.295998) (xy 87.404194 -339.454998) (xy 87.023194 -339.835998) (xy 84.229194 -339.835998)
				(xy 83.086194 -338.692998) (xy 83.086194 -335.771998) (xy 83.594194 -335.263998) (xy 85.372194 -335.263998)
			)
		)
	)
	(zone
		(layer "B.Cu")
		(hatch none 0.5)
		(connect_pads
			(clearance 0)
		)
		(min_thickness 0.25)
		(keepout
			(tracks allowed)
			(vias allowed)
			(pads allowed)
			(copperpour allowed)
			(footprints allowed)
		)
		(placement
			(enabled no)
			(sheetname "")
		)
		(fill
			(thermal_gap 0.5)
			(thermal_bridge_width 0.5)
			(island_removal_mode 0)
		)
		(polygon
			(pts
				(xy 351.00768 -417.428426) (xy 351.00768 -416.42411) (xy 352.384614 -416.42411) (xy 352.384614 -417.428426)
			)
		)
	)
	(zone
		(layer "B.Cu")
		(hatch none 0.5)
		(connect_pads
			(clearance 0)
		)
		(min_thickness 0.25)
		(keepout
			(tracks not_allowed)
			(vias allowed)
			(pads allowed)
			(copperpour not_allowed)
			(footprints allowed)
		)
		(placement
			(enabled no)
			(sheetname "")
		)
		(fill
			(thermal_gap 0.5)
			(thermal_bridge_width 0.5)
			(island_removal_mode 0)
		)
		(polygon
			(pts
				(arc
					(start 110.046008 -272.466308)
					(mid 109.416088 -272.466308)
					(end 110.046008 -272.466308)
				)
			)
		)
	)
	(zone
		(layer "B.Cu")
		(hatch none 0.5)
		(connect_pads
			(clearance 0)
		)
		(min_thickness 0.25)
		(keepout
			(tracks allowed)
			(vias allowed)
			(pads allowed)
			(copperpour allowed)
			(footprints allowed)
		)
		(placement
			(enabled no)
			(sheetname "")
		)
		(fill
			(thermal_gap 0.5)
			(thermal_bridge_width 0.5)
			(island_removal_mode 0)
		)
		(polygon
			(pts
				(xy 432.26482 -193.98234) (xy 432.26482 -190.6397) (xy 434.52288 -190.6397) (xy 434.52288 -193.98234)
			)
		)
	)
	(zone
		(layer "B.Cu")
		(hatch none 0.5)
		(connect_pads
			(clearance 0)
		)
		(min_thickness 0.25)
		(keepout
			(tracks allowed)
			(vias allowed)
			(pads allowed)
			(copperpour allowed)
			(footprints not_allowed)
		)
		(placement
			(enabled no)
			(sheetname "")
		)
		(fill
			(thermal_gap 0.5)
			(thermal_bridge_width 0.5)
			(island_removal_mode 0)
		)
		(polygon
			(pts
				(arc
					(start 102.64521 -427.892972)
					(mid 119.377047 -424.581722)
					(end 114.720116 -440.989974)
				)
				(arc
					(start 94.588584 -440.989974)
					(mid 93.686334 -431.408521)
					(end 102.64521 -427.892972)
				)
			)
		)
	)
	(zone
		(layer "B.Cu")
		(hatch none 0.5)
		(connect_pads
			(clearance 0)
		)
		(min_thickness 0.25)
		(keepout
			(tracks allowed)
			(vias allowed)
			(pads allowed)
			(copperpour allowed)
			(footprints allowed)
		)
		(placement
			(enabled no)
			(sheetname "")
		)
		(fill
			(thermal_gap 0.5)
			(thermal_bridge_width 0.5)
			(island_removal_mode 0)
		)
		(polygon
			(pts
				(xy 209.5246 -3.2512) (xy 209.5246 -1.27) (xy 211.88426 -1.27) (xy 211.88426 -3.2512)
			)
		)
	)
	(zone
		(layer "B.Cu")
		(hatch none 0.5)
		(connect_pads
			(clearance 0)
		)
		(min_thickness 0.25)
		(keepout
			(tracks allowed)
			(vias allowed)
			(pads allowed)
			(copperpour allowed)
			(footprints allowed)
		)
		(placement
			(enabled no)
			(sheetname "")
		)
		(fill
			(thermal_gap 0.5)
			(thermal_bridge_width 0.5)
			(island_removal_mode 0)
		)
		(polygon
			(pts
				(xy 415.044636 -417.428426) (xy 415.044636 -416.42411) (xy 416.42157 -416.42411) (xy 416.42157 -417.428426)
			)
		)
	)
	(zone
		(layer "B.Cu")
		(hatch none 0.5)
		(connect_pads
			(clearance 0)
		)
		(min_thickness 0.25)
		(keepout
			(tracks not_allowed)
			(vias allowed)
			(pads allowed)
			(copperpour not_allowed)
			(footprints allowed)
		)
		(placement
			(enabled no)
			(sheetname "")
		)
		(fill
			(thermal_gap 0.5)
			(thermal_bridge_width 0.5)
			(island_removal_mode 0)
		)
		(polygon
			(pts
				(arc
					(start 17.116044 -347.8149)
					(mid 20.216114 -350.91497)
					(end 23.31593 -347.8149)
				)
				(arc
					(start 23.31593 -347.8149)
					(mid 20.216114 -344.715084)
					(end 17.116044 -347.8149)
				)
			)
		)
	)
	(zone
		(layer "B.Cu")
		(hatch none 0.5)
		(connect_pads
			(clearance 0)
		)
		(min_thickness 0.25)
		(keepout
			(tracks not_allowed)
			(vias allowed)
			(pads allowed)
			(copperpour not_allowed)
			(footprints allowed)
		)
		(placement
			(enabled no)
			(sheetname "")
		)
		(fill
			(thermal_gap 0.5)
			(thermal_bridge_width 0.5)
			(island_removal_mode 0)
		)
		(polygon
			(pts
				(arc
					(start 356.746048 -245.29415)
					(mid 356.116128 -245.29415)
					(end 356.746048 -245.29415)
				)
			)
		)
	)
	(zone
		(layer "B.Cu")
		(hatch none 0.5)
		(connect_pads
			(clearance 0)
		)
		(min_thickness 0.25)
		(keepout
			(tracks not_allowed)
			(vias allowed)
			(pads allowed)
			(copperpour not_allowed)
			(footprints allowed)
		)
		(placement
			(enabled no)
			(sheetname "")
		)
		(fill
			(thermal_gap 0.5)
			(thermal_bridge_width 0.5)
			(island_removal_mode 0)
		)
		(polygon
			(pts
				(arc
					(start 239.450118 -272.50009)
					(mid 236.650022 -269.699994)
					(end 233.849926 -272.50009)
				)
				(arc
					(start 233.849926 -272.50009)
					(mid 236.650022 -275.300186)
					(end 239.450118 -272.50009)
				)
			)
		)
	)
	(zone
		(layer "B.Cu")
		(hatch none 0.5)
		(connect_pads
			(clearance 0)
		)
		(min_thickness 0.25)
		(keepout
			(tracks allowed)
			(vias allowed)
			(pads allowed)
			(copperpour allowed)
			(footprints allowed)
		)
		(placement
			(enabled no)
			(sheetname "")
		)
		(fill
			(thermal_gap 0.5)
			(thermal_bridge_width 0.5)
			(island_removal_mode 0)
		)
		(polygon
			(pts
				(xy 424.69562 -194.11442) (xy 424.69562 -190.59398) (xy 426.93082 -190.59398) (xy 426.93082 -194.11442)
			)
		)
	)
	(zone
		(layer "B.Cu")
		(hatch none 0.5)
		(connect_pads
			(clearance 0)
		)
		(min_thickness 0.25)
		(keepout
			(tracks allowed)
			(vias allowed)
			(pads allowed)
			(copperpour allowed)
			(footprints allowed)
		)
		(placement
			(enabled no)
			(sheetname "")
		)
		(fill
			(thermal_gap 0.5)
			(thermal_bridge_width 0.5)
			(island_removal_mode 0)
		)
		(polygon
			(pts
				(xy 53.609494 -348.898972) (xy 53.609494 -351.057972) (xy 53.228494 -351.438972) (xy 50.434494 -351.438972)
				(xy 49.291494 -350.295972) (xy 49.291494 -347.374972) (xy 49.799494 -346.866972) (xy 51.577494 -346.866972)
			)
		)
	)
	(zone
		(layer "B.Cu")
		(hatch none 0.5)
		(connect_pads
			(clearance 0)
		)
		(min_thickness 0.25)
		(keepout
			(tracks not_allowed)
			(vias allowed)
			(pads allowed)
			(copperpour not_allowed)
			(footprints allowed)
		)
		(placement
			(enabled no)
			(sheetname "")
		)
		(fill
			(thermal_gap 0.5)
			(thermal_bridge_width 0.5)
			(island_removal_mode 0)
		)
		(polygon
			(pts
				(arc
					(start 357.046022 -270.846042)
					(mid 356.416102 -270.846042)
					(end 357.046022 -270.846042)
				)
			)
		)
	)
	(zone
		(layer "B.Cu")
		(hatch none 0.5)
		(connect_pads
			(clearance 0)
		)
		(min_thickness 0.25)
		(keepout
			(tracks allowed)
			(vias allowed)
			(pads allowed)
			(copperpour allowed)
			(footprints allowed)
		)
		(placement
			(enabled no)
			(sheetname "")
		)
		(fill
			(thermal_gap 0.5)
			(thermal_bridge_width 0.5)
			(island_removal_mode 0)
		)
		(polygon
			(pts
				(xy 368.95024 -402.562568) (xy 368.95024 -399.86839) (xy 368.95024 -394.347954) (xy 370.697506 -394.347954)
				(xy 370.697506 -393.293854) (xy 390.292336 -393.293854) (xy 390.292336 -394.347954) (xy 390.292336 -402.562568)
			)
		)
	)
	(zone
		(layer "B.Cu")
		(hatch none 0.5)
		(connect_pads
			(clearance 0)
		)
		(min_thickness 0.25)
		(keepout
			(tracks not_allowed)
			(vias allowed)
			(pads allowed)
			(copperpour not_allowed)
			(footprints allowed)
		)
		(placement
			(enabled no)
			(sheetname "")
		)
		(fill
			(thermal_gap 0.5)
			(thermal_bridge_width 0.5)
			(island_removal_mode 0)
		)
		(polygon
			(pts
				(arc
					(start 37.569902 -404.789894)
					(mid 41.569894 -408.789886)
					(end 45.569886 -404.789894)
				)
				(arc
					(start 45.569886 -404.789894)
					(mid 41.569894 -400.789902)
					(end 37.569902 -404.789894)
				)
			)
		)
	)
	(zone
		(layer "B.Cu")
		(hatch none 0.5)
		(connect_pads
			(clearance 0)
		)
		(min_thickness 0.25)
		(keepout
			(tracks allowed)
			(vias allowed)
			(pads allowed)
			(copperpour allowed)
			(footprints allowed)
		)
		(placement
			(enabled no)
			(sheetname "")
		)
		(fill
			(thermal_gap 0.5)
			(thermal_bridge_width 0.5)
			(island_removal_mode 0)
		)
		(polygon
			(pts
				(xy 408.918156 -417.428426) (xy 408.918156 -416.42411) (xy 410.29509 -416.42411) (xy 410.29509 -417.428426)
			)
		)
	)
	(zone
		(layer "B.Cu")
		(hatch none 0.5)
		(connect_pads
			(clearance 0)
		)
		(min_thickness 0.25)
		(keepout
			(tracks allowed)
			(vias allowed)
			(pads allowed)
			(copperpour allowed)
			(footprints not_allowed)
		)
		(placement
			(enabled no)
			(sheetname "")
		)
		(fill
			(thermal_gap 0.5)
			(thermal_bridge_width 0.5)
			(island_removal_mode 0)
		)
		(polygon
			(pts
				(arc
					(start 349.917004 -147.904962)
					(mid 348.052136 -146.040094)
					(end 346.187014 -147.904962)
				)
				(arc
					(start 346.187014 -147.904962)
					(mid 348.052136 -149.770084)
					(end 349.917004 -147.904962)
				)
			)
		)
	)
	(zone
		(layer "B.Cu")
		(hatch none 0.5)
		(connect_pads
			(clearance 0)
		)
		(min_thickness 0.25)
		(keepout
			(tracks allowed)
			(vias allowed)
			(pads allowed)
			(copperpour allowed)
			(footprints not_allowed)
		)
		(placement
			(enabled no)
			(sheetname "")
		)
		(fill
			(thermal_gap 0.5)
			(thermal_bridge_width 0.5)
			(island_removal_mode 0)
		)
		(polygon
			(pts
				(arc
					(start 97.700084 -22.29993)
					(mid 94.899988 -19.499834)
					(end 92.099892 -22.29993)
				)
				(arc
					(start 92.099892 -22.29993)
					(mid 94.899988 -25.100026)
					(end 97.700084 -22.29993)
				)
			)
		)
	)
	(zone
		(layer "B.Cu")
		(hatch none 0.5)
		(connect_pads
			(clearance 0)
		)
		(min_thickness 0.25)
		(keepout
			(tracks allowed)
			(vias allowed)
			(pads allowed)
			(copperpour allowed)
			(footprints allowed)
		)
		(placement
			(enabled no)
			(sheetname "")
		)
		(fill
			(thermal_gap 0.5)
			(thermal_bridge_width 0.5)
			(island_removal_mode 0)
		)
		(polygon
			(pts
				(xy 135.6106 -29.6672) (xy 135.6106 -27.305) (xy 136.2202 -27.305) (xy 136.2202 -29.6672)
			)
		)
	)
	(zone
		(layer "B.Cu")
		(hatch none 0.5)
		(connect_pads
			(clearance 0)
		)
		(min_thickness 0.25)
		(keepout
			(tracks allowed)
			(vias allowed)
			(pads allowed)
			(copperpour allowed)
			(footprints allowed)
		)
		(placement
			(enabled no)
			(sheetname "")
		)
		(fill
			(thermal_gap 0.5)
			(thermal_bridge_width 0.5)
			(island_removal_mode 0)
		)
		(polygon
			(pts
				(xy 311.18556 -417.428426) (xy 311.18556 -416.42411) (xy 312.562494 -416.42411) (xy 312.562494 -417.428426)
			)
		)
	)
	(zone
		(layer "B.Cu")
		(hatch none 0.5)
		(connect_pads
			(clearance 0)
		)
		(min_thickness 0.25)
		(keepout
			(tracks allowed)
			(vias allowed)
			(pads allowed)
			(copperpour allowed)
			(footprints not_allowed)
		)
		(placement
			(enabled no)
			(sheetname "")
		)
		(fill
			(thermal_gap 0.5)
			(thermal_bridge_width 0.5)
			(island_removal_mode 0)
		)
		(polygon
			(pts
				(arc
					(start 432.340004 -399.029936)
					(mid 435.440074 -402.130006)
					(end 438.53989 -399.029936)
				)
				(arc
					(start 438.53989 -399.029936)
					(mid 435.440074 -395.93012)
					(end 432.340004 -399.029936)
				)
			)
		)
	)
	(zone
		(layer "B.Cu")
		(hatch none 0.5)
		(connect_pads
			(clearance 0)
		)
		(min_thickness 0.25)
		(keepout
			(tracks allowed)
			(vias allowed)
			(pads allowed)
			(copperpour allowed)
			(footprints not_allowed)
		)
		(placement
			(enabled no)
			(sheetname "")
		)
		(fill
			(thermal_gap 0.5)
			(thermal_bridge_width 0.5)
			(island_removal_mode 0)
		)
		(polygon
			(pts
				(arc
					(start 268.45006 -22.29993)
					(mid 265.650218 -19.500088)
					(end 262.850122 -22.29993)
				)
				(arc
					(start 262.850122 -22.29993)
					(mid 265.650218 -25.100026)
					(end 268.45006 -22.29993)
				)
			)
		)
	)
	(zone
		(layer "B.Cu")
		(hatch none 0.5)
		(connect_pads
			(clearance 0)
		)
		(min_thickness 0.25)
		(keepout
			(tracks not_allowed)
			(vias allowed)
			(pads allowed)
			(copperpour not_allowed)
			(footprints allowed)
		)
		(placement
			(enabled no)
			(sheetname "")
		)
		(fill
			(thermal_gap 0.5)
			(thermal_bridge_width 0.5)
			(island_removal_mode 0)
		)
		(polygon
			(pts
				(arc
					(start 62.506352 -385.31038)
					(mid 61.876432 -385.31038)
					(end 62.506352 -385.31038)
				)
			)
		)
	)
	(zone
		(layer "B.Cu")
		(hatch none 0.5)
		(connect_pads
			(clearance 0)
		)
		(min_thickness 0.25)
		(keepout
			(tracks not_allowed)
			(vias allowed)
			(pads allowed)
			(copperpour not_allowed)
			(footprints allowed)
		)
		(placement
			(enabled no)
			(sheetname "")
		)
		(fill
			(thermal_gap 0.5)
			(thermal_bridge_width 0.5)
			(island_removal_mode 0)
		)
		(polygon
			(pts
				(arc
					(start 73.036938 -439.0898)
					(mid 72.262746 -439.0898)
					(end 73.036938 -439.0898)
				)
			)
		)
	)
	(zone
		(layer "B.Cu")
		(hatch none 0.5)
		(connect_pads
			(clearance 0)
		)
		(min_thickness 0.25)
		(keepout
			(tracks allowed)
			(vias allowed)
			(pads allowed)
			(copperpour allowed)
			(footprints allowed)
		)
		(placement
			(enabled no)
			(sheetname "")
		)
		(fill
			(thermal_gap 0.5)
			(thermal_bridge_width 0.5)
			(island_removal_mode 0)
		)
		(polygon
			(pts
				(xy 347.29801 -221.17431) (xy 347.29801 -223.561148) (xy 348.02572 -224.288858) (xy 348.02572 -225.85426)
				(xy 349.851218 -225.85426) (xy 350.791018 -224.914206) (xy 350.791018 -221.17431)
			)
		)
	)
	(zone
		(layer "B.Cu")
		(hatch none 0.5)
		(connect_pads
			(clearance 0)
		)
		(min_thickness 0.25)
		(keepout
			(tracks not_allowed)
			(vias allowed)
			(pads allowed)
			(copperpour not_allowed)
			(footprints allowed)
		)
		(placement
			(enabled no)
			(sheetname "")
		)
		(fill
			(thermal_gap 0.5)
			(thermal_bridge_width 0.5)
			(island_removal_mode 0)
		)
		(polygon
			(pts
				(arc
					(start 231.650032 -192.499996)
					(mid 236.650022 -197.499986)
					(end 241.650012 -192.499996)
				)
				(arc
					(start 241.650012 -192.499996)
					(mid 236.650022 -187.500006)
					(end 231.650032 -192.499996)
				)
			)
		)
	)
	(zone
		(layer "B.Cu")
		(hatch none 0.5)
		(connect_pads
			(clearance 0)
		)
		(min_thickness 0.25)
		(keepout
			(tracks not_allowed)
			(vias allowed)
			(pads allowed)
			(copperpour not_allowed)
			(footprints allowed)
		)
		(placement
			(enabled no)
			(sheetname "")
		)
		(fill
			(thermal_gap 0.5)
			(thermal_bridge_width 0.5)
			(island_removal_mode 0)
		)
		(polygon
			(pts
				(arc
					(start 323.036692 -436.889906)
					(mid 322.2625 -436.889906)
					(end 323.036692 -436.889906)
				)
			)
		)
	)
	(zone
		(layer "B.Cu")
		(hatch none 0.5)
		(connect_pads
			(clearance 0)
		)
		(min_thickness 0.25)
		(keepout
			(tracks not_allowed)
			(vias allowed)
			(pads allowed)
			(copperpour not_allowed)
			(footprints allowed)
		)
		(placement
			(enabled no)
			(sheetname "")
		)
		(fill
			(thermal_gap 0.5)
			(thermal_bridge_width 0.5)
			(island_removal_mode 0)
		)
		(polygon
			(pts
				(arc
					(start 160.978342 -392.429238)
					(mid 160.310322 -392.429238)
					(end 160.978342 -392.429238)
				)
			)
		)
	)
	(zone
		(layer "B.Cu")
		(hatch none 0.5)
		(connect_pads
			(clearance 0)
		)
		(min_thickness 0.25)
		(keepout
			(tracks not_allowed)
			(vias allowed)
			(pads allowed)
			(copperpour not_allowed)
			(footprints allowed)
		)
		(placement
			(enabled no)
			(sheetname "")
		)
		(fill
			(thermal_gap 0.5)
			(thermal_bridge_width 0.5)
			(island_removal_mode 0)
		)
		(polygon
			(pts
				(arc
					(start 10.920476 -425.024042)
					(mid 10.252456 -425.024042)
					(end 10.920476 -425.024042)
				)
			)
		)
	)
	(zone
		(layer "B.Cu")
		(hatch none 0.5)
		(connect_pads
			(clearance 0)
		)
		(min_thickness 0.25)
		(keepout
			(tracks not_allowed)
			(vias allowed)
			(pads allowed)
			(copperpour not_allowed)
			(footprints allowed)
		)
		(placement
			(enabled no)
			(sheetname "")
		)
		(fill
			(thermal_gap 0.5)
			(thermal_bridge_width 0.5)
			(island_removal_mode 0)
		)
		(polygon
			(pts
				(arc
					(start 463.79003 -51.289966)
					(mid 466.8901 -54.390036)
					(end 469.989916 -51.289966)
				)
				(arc
					(start 469.989916 -51.289966)
					(mid 466.8901 -48.19015)
					(end 463.79003 -51.289966)
				)
			)
		)
	)
	(zone
		(layer "B.Cu")
		(hatch none 0.5)
		(connect_pads
			(clearance 0)
		)
		(min_thickness 0.25)
		(keepout
			(tracks not_allowed)
			(vias allowed)
			(pads allowed)
			(copperpour not_allowed)
			(footprints allowed)
		)
		(placement
			(enabled no)
			(sheetname "")
		)
		(fill
			(thermal_gap 0.5)
			(thermal_bridge_width 0.5)
			(island_removal_mode 0)
		)
		(polygon
			(pts
				(arc
					(start 325.036688 -437.889904)
					(mid 324.262496 -437.889904)
					(end 325.036688 -437.889904)
				)
			)
		)
	)
	(zone
		(layer "B.Cu")
		(hatch none 0.5)
		(connect_pads
			(clearance 0)
		)
		(min_thickness 0.25)
		(keepout
			(tracks allowed)
			(vias allowed)
			(pads allowed)
			(copperpour allowed)
			(footprints not_allowed)
		)
		(placement
			(enabled no)
			(sheetname "")
		)
		(fill
			(thermal_gap 0.5)
			(thermal_bridge_width 0.5)
			(island_removal_mode 0)
		)
		(polygon
			(pts
				(arc
					(start 277.804118 -440.989974)
					(mid 277.309907 -440.047498)
					(end 276.314916 -439.669936)
				)
				(arc
					(start 195.50507 -439.669936)
					(mid 194.51003 -440.047443)
					(end 194.015868 -440.989974)
				)
				(arc
					(start 185.661554 -440.989974)
					(mid 179.749958 -427.600233)
					(end 173.838362 -440.989974)
				)
				(arc
					(start 114.720116 -440.989974)
					(mid 119.377022 -424.581745)
					(end 102.64521 -427.892972)
				)
				(arc
					(start 102.64521 -427.892972)
					(mid 93.686169 -431.40842)
					(end 94.588584 -440.989974)
				)
				(arc
					(start 18.91157 -440.989974)
					(mid 18.603422 -429.890528)
					(end 7.500112 -429.790606)
				)
				(arc
					(start 7.500112 -409.528518)
					(mid 7.271649 -408.380426)
					(end 6.621272 -407.40711)
				)
				(arc
					(start 3.292856 -404.078694)
					(mid 3.076074 -403.754257)
					(end 2.999994 -403.371558)
				)
				(arc
					(start 2.999994 -350.88195)
					(mid 10.815277 -355.685791)
					(end 18.005552 -349.988632)
				)
				(arc
					(start 18.005552 -349.988632)
					(mid 23.315563 -347.851344)
					(end 18.05686 -345.590622)
				)
				(arc
					(start 18.05686 -345.590622)
					(mid 17.030148 -343.313574)
					(end 15.351252 -341.464138)
				)
				(arc
					(start 15.351252 -341.464138)
					(mid 22.417396 -340.124052)
					(end 27.704288 -345.000072)
				)
				(arc
					(start 67.121532 -345.000072)
					(mid 70.216014 -347.915162)
					(end 73.310496 -345.000072)
				)
				(arc
					(start 168.912286 -345.000072)
					(mid 173.086014 -343.825067)
					(end 177.259742 -345.000072)
				)
				(arc
					(start 196.91223 -345.000072)
					(mid 201.085958 -343.825067)
					(end 205.259686 -345.000072)
				)
				(arc
					(start 233.854498 -345.000072)
					(mid 230.0788 -347.933035)
					(end 228.650038 -352.495612)
				)
				(arc
					(start 228.650038 -352.495612)
					(mid 236.650022 -360.495596)
					(end 244.650006 -352.495612)
				)
				(arc
					(start 244.650006 -352.495612)
					(mid 243.22133 -347.932975)
					(end 239.445546 -345.000072)
				)
				(arc
					(start 259.963666 -345.000072)
					(mid 267.452049 -339.815076)
					(end 274.940268 -345.000072)
				)
				(arc
					(start 309.454042 -345.000072)
					(mid 309.452492 -344.907495)
					(end 309.45201 -344.814906)
				)
				(arc
					(start 309.45201 -344.814906)
					(mid 317.451994 -336.814922)
					(end 325.451978 -344.814906)
				)
				(arc
					(start 325.451978 -344.814906)
					(mid 325.451498 -344.907495)
					(end 325.449946 -345.000072)
				)
				(arc
					(start 353.467416 -345.000072)
					(mid 359.952036 -332.315054)
					(end 366.436656 -345.000072)
				)
				(arc
					(start 409.172156 -345.000072)
					(mid 413.95208 -343.415022)
					(end 418.731954 -345.000072)
				)
				(arc
					(start 437.1721 -345.000072)
					(mid 441.952024 -343.415022)
					(end 446.731898 -345.000072)
				)
				(arc
					(start 453.929496 -345.000072)
					(mid 457.288329 -354.526244)
					(end 467.29777 -353.169982)
				)
				(arc
					(start 467.300056 -404.871682)
					(mid 467.223955 -405.254267)
					(end 467.007194 -405.578564)
				)
				(arc
					(start 465.178648 -407.40711)
					(mid 464.528386 -408.380435)
					(end 464.300062 -409.528518)
				)
				(arc
					(start 464.300062 -424.375072)
					(mid 456.184086 -423.376938)
					(end 449.18757 -427.609508)
				)
				(arc
					(start 449.18757 -427.609508)
					(mid 441.561967 -432.192592)
					(end 442.88837 -440.989974)
				)
				(arc
					(start 377.21032 -440.989974)
					(mid 378.112844 -431.408967)
					(end 369.15471 -427.892718)
				)
				(arc
					(start 369.15471 -427.892718)
					(mid 352.422644 -424.58184)
					(end 357.080058 -440.989974)
				)
				(arc
					(start 299.461682 -440.989974)
					(mid 293.550172 -427.599808)
					(end 287.638236 -440.989974)
				)
			)
		)
	)
	(zone
		(layer "B.Cu")
		(hatch none 0.5)
		(connect_pads
			(clearance 0)
		)
		(min_thickness 0.25)
		(keepout
			(tracks allowed)
			(vias allowed)
			(pads allowed)
			(copperpour allowed)
			(footprints allowed)
		)
		(placement
			(enabled no)
			(sheetname "")
		)
		(fill
			(thermal_gap 0.5)
			(thermal_bridge_width 0.5)
			(island_removal_mode 0)
		)
		(polygon
			(pts
				(xy 300.625256 -348.970092) (xy 300.625256 -351.129092) (xy 300.244256 -351.510092) (xy 297.450256 -351.510092)
				(xy 296.307256 -350.367092) (xy 296.307256 -347.446092) (xy 296.815256 -346.938092) (xy 298.593256 -346.938092)
			)
		)
	)
	(zone
		(layer "B.Cu")
		(hatch none 0.5)
		(connect_pads
			(clearance 0)
		)
		(min_thickness 0.25)
		(keepout
			(tracks not_allowed)
			(vias allowed)
			(pads allowed)
			(copperpour not_allowed)
			(footprints allowed)
		)
		(placement
			(enabled no)
			(sheetname "")
		)
		(fill
			(thermal_gap 0.5)
			(thermal_bridge_width 0.5)
			(island_removal_mode 0)
		)
		(polygon
			(pts
				(arc
					(start 39.478204 -422.638982)
					(mid 38.810184 -422.638982)
					(end 39.478204 -422.638982)
				)
			)
		)
	)
	(zone
		(layer "B.Cu")
		(hatch none 0.5)
		(connect_pads
			(clearance 0)
		)
		(min_thickness 0.25)
		(keepout
			(tracks allowed)
			(vias allowed)
			(pads allowed)
			(copperpour allowed)
			(footprints allowed)
		)
		(placement
			(enabled no)
			(sheetname "")
		)
		(fill
			(thermal_gap 0.5)
			(thermal_bridge_width 0.5)
			(island_removal_mode 0)
		)
		(polygon
			(pts
				(xy 432.00955 -164.032946) (xy 432.00955 -163.456366) (xy 433.438808 -163.456366) (xy 433.438808 -164.032946)
			)
		)
	)
	(zone
		(layer "B.Cu")
		(hatch none 0.5)
		(connect_pads
			(clearance 0)
		)
		(min_thickness 0.25)
		(keepout
			(tracks not_allowed)
			(vias allowed)
			(pads allowed)
			(copperpour not_allowed)
			(footprints allowed)
		)
		(placement
			(enabled no)
			(sheetname "")
		)
		(fill
			(thermal_gap 0.5)
			(thermal_bridge_width 0.5)
			(island_removal_mode 0)
		)
		(polygon
			(pts
				(arc
					(start 351.876106 -270.036036)
					(mid 351.246186 -270.036036)
					(end 351.876106 -270.036036)
				)
			)
		)
	)
	(zone
		(layer "B.Cu")
		(hatch none 0.5)
		(connect_pads
			(clearance 0)
		)
		(min_thickness 0.25)
		(keepout
			(tracks allowed)
			(vias allowed)
			(pads allowed)
			(copperpour allowed)
			(footprints allowed)
		)
		(placement
			(enabled no)
			(sheetname "")
		)
		(fill
			(thermal_gap 0.5)
			(thermal_bridge_width 0.5)
			(island_removal_mode 0)
		)
		(polygon
			(pts
				(xy 389.13689 -180.509926) (xy 389.13689 -178.350926) (xy 389.51789 -177.969926) (xy 392.31189 -177.969926)
				(xy 393.45489 -179.112926) (xy 393.45489 -182.033926) (xy 392.94689 -182.541926) (xy 391.16889 -182.541926)
			)
		)
	)
	(zone
		(layer "B.Cu")
		(hatch none 0.5)
		(connect_pads
			(clearance 0)
		)
		(min_thickness 0.25)
		(keepout
			(tracks not_allowed)
			(vias allowed)
			(pads allowed)
			(copperpour not_allowed)
			(footprints allowed)
		)
		(placement
			(enabled no)
			(sheetname "")
		)
		(fill
			(thermal_gap 0.5)
			(thermal_bridge_width 0.5)
			(island_removal_mode 0)
		)
		(polygon
			(pts
				(xy 95.696278 -142.353284) (xy 98.164904 -142.353284) (xy 98.164904 -147.341336) (xy 93.176852 -147.341336)
				(xy 93.176852 -142.353284) (xy 95.670878 -142.353284) (xy 95.670878 -142.58671) (xy 93.410278 -142.58671)
				(xy 93.410278 -147.10791) (xy 97.931478 -147.10791) (xy 97.931478 -142.58671) (xy 95.696278 -142.58671)
			)
		)
	)
	(zone
		(layer "B.Cu")
		(hatch none 0.5)
		(connect_pads
			(clearance 0)
		)
		(min_thickness 0.25)
		(keepout
			(tracks not_allowed)
			(vias allowed)
			(pads allowed)
			(copperpour not_allowed)
			(footprints allowed)
		)
		(placement
			(enabled no)
			(sheetname "")
		)
		(fill
			(thermal_gap 0.5)
			(thermal_bridge_width 0.5)
			(island_removal_mode 0)
		)
		(polygon
			(pts
				(arc
					(start 416.978338 -400.811238)
					(mid 416.310318 -400.811238)
					(end 416.978338 -400.811238)
				)
			)
		)
	)
	(zone
		(layer "B.Cu")
		(hatch none 0.5)
		(connect_pads
			(clearance 0)
		)
		(min_thickness 0.25)
		(keepout
			(tracks not_allowed)
			(vias allowed)
			(pads allowed)
			(copperpour not_allowed)
			(footprints allowed)
		)
		(placement
			(enabled no)
			(sheetname "")
		)
		(fill
			(thermal_gap 0.5)
			(thermal_bridge_width 0.5)
			(island_removal_mode 0)
		)
		(polygon
			(pts
				(arc
					(start 119.609616 -244.484398)
					(mid 118.979696 -244.484398)
					(end 119.609616 -244.484398)
				)
			)
		)
	)
	(zone
		(layer "B.Cu")
		(hatch none 0.5)
		(connect_pads
			(clearance 0)
		)
		(min_thickness 0.25)
		(keepout
			(tracks allowed)
			(vias allowed)
			(pads allowed)
			(copperpour allowed)
			(footprints allowed)
		)
		(placement
			(enabled no)
			(sheetname "")
		)
		(fill
			(thermal_gap 0.5)
			(thermal_bridge_width 0.5)
			(island_removal_mode 0)
		)
		(polygon
			(pts
				(xy 338.75472 -417.428426) (xy 338.75472 -416.42411) (xy 340.131654 -416.42411) (xy 340.131654 -417.428426)
			)
		)
	)
	(zone
		(layer "B.Cu")
		(hatch none 0.5)
		(connect_pads
			(clearance 0)
		)
		(min_thickness 0.25)
		(keepout
			(tracks not_allowed)
			(vias allowed)
			(pads allowed)
			(copperpour not_allowed)
			(footprints allowed)
		)
		(placement
			(enabled no)
			(sheetname "")
		)
		(fill
			(thermal_gap 0.5)
			(thermal_bridge_width 0.5)
			(island_removal_mode 0)
		)
		(polygon
			(pts
				(arc
					(start 352.516186 -244.484144)
					(mid 351.886266 -244.484144)
					(end 352.516186 -244.484144)
				)
			)
		)
	)
	(zone
		(layer "B.Cu")
		(hatch none 0.5)
		(connect_pads
			(clearance 0)
		)
		(min_thickness 0.25)
		(keepout
			(tracks not_allowed)
			(vias allowed)
			(pads allowed)
			(copperpour not_allowed)
			(footprints allowed)
		)
		(placement
			(enabled no)
			(sheetname "")
		)
		(fill
			(thermal_gap 0.5)
			(thermal_bridge_width 0.5)
			(island_removal_mode 0)
		)
		(polygon
			(pts
				(arc
					(start 69.036946 -439.0898)
					(mid 68.262754 -439.0898)
					(end 69.036946 -439.0898)
				)
			)
		)
	)
	(zone
		(layer "B.Cu")
		(hatch none 0.5)
		(connect_pads
			(clearance 0)
		)
		(min_thickness 0.25)
		(keepout
			(tracks not_allowed)
			(vias allowed)
			(pads allowed)
			(copperpour not_allowed)
			(footprints allowed)
		)
		(placement
			(enabled no)
			(sheetname "")
		)
		(fill
			(thermal_gap 0.5)
			(thermal_bridge_width 0.5)
			(island_removal_mode 0)
		)
		(polygon
			(pts
				(arc
					(start 60.506356 -386.003292)
					(mid 59.876436 -386.003292)
					(end 60.506356 -386.003292)
				)
			)
		)
	)
	(zone
		(layer "B.Cu")
		(hatch none 0.5)
		(connect_pads
			(clearance 0)
		)
		(min_thickness 0.25)
		(keepout
			(tracks not_allowed)
			(vias allowed)
			(pads allowed)
			(copperpour not_allowed)
			(footprints allowed)
		)
		(placement
			(enabled no)
			(sheetname "")
		)
		(fill
			(thermal_gap 0.5)
			(thermal_bridge_width 0.5)
			(island_removal_mode 0)
		)
		(polygon
			(pts
				(arc
					(start 69.036946 -437.889904)
					(mid 68.262754 -437.889904)
					(end 69.036946 -437.889904)
				)
			)
		)
	)
	(zone
		(layer "B.Cu")
		(hatch none 0.5)
		(connect_pads
			(clearance 0)
		)
		(min_thickness 0.25)
		(keepout
			(tracks allowed)
			(vias allowed)
			(pads allowed)
			(copperpour allowed)
			(footprints not_allowed)
		)
		(placement
			(enabled no)
			(sheetname "")
		)
		(fill
			(thermal_gap 0.5)
			(thermal_bridge_width 0.5)
			(island_removal_mode 0)
		)
		(polygon
			(pts
				(arc
					(start 56.58104 -167.135048)
					(mid 54.716172 -165.27018)
					(end 52.85105 -167.135048)
				)
				(arc
					(start 52.85105 -167.135048)
					(mid 54.716172 -169.00017)
					(end 56.58104 -167.135048)
				)
			)
		)
	)
	(zone
		(layer "B.Cu")
		(hatch none 0.5)
		(connect_pads
			(clearance 0)
		)
		(min_thickness 0.25)
		(keepout
			(tracks not_allowed)
			(vias allowed)
			(pads allowed)
			(copperpour not_allowed)
			(footprints allowed)
		)
		(placement
			(enabled no)
			(sheetname "")
		)
		(fill
			(thermal_gap 0.5)
			(thermal_bridge_width 0.5)
			(island_removal_mode 0)
		)
		(polygon
			(pts
				(arc
					(start 354.696014 -273.27606)
					(mid 354.066094 -273.27606)
					(end 354.696014 -273.27606)
				)
			)
		)
	)
	(zone
		(layer "B.Cu")
		(hatch none 0.5)
		(connect_pads
			(clearance 0)
		)
		(min_thickness 0.25)
		(keepout
			(tracks allowed)
			(vias allowed)
			(pads allowed)
			(copperpour allowed)
			(footprints not_allowed)
		)
		(placement
			(enabled no)
			(sheetname "")
		)
		(fill
			(thermal_gap 0.5)
			(thermal_bridge_width 0.5)
			(island_removal_mode 0)
		)
		(polygon
			(pts
				(arc
					(start 31.770066 -389.439912)
					(mid 34.870136 -392.539982)
					(end 37.969952 -389.439912)
				)
				(arc
					(start 37.969952 -389.439912)
					(mid 34.870136 -386.340096)
					(end 31.770066 -389.439912)
				)
			)
		)
	)
	(zone
		(layer "B.Cu")
		(hatch none 0.5)
		(connect_pads
			(clearance 0)
		)
		(min_thickness 0.25)
		(keepout
			(tracks allowed)
			(vias allowed)
			(pads allowed)
			(copperpour allowed)
			(footprints not_allowed)
		)
		(placement
			(enabled no)
			(sheetname "")
		)
		(fill
			(thermal_gap 0.5)
			(thermal_bridge_width 0.5)
			(island_removal_mode 0)
		)
		(polygon
			(pts
				(arc
					(start 465.304886 -399.029936)
					(mid 463.440018 -397.165068)
					(end 461.574896 -399.029936)
				)
				(arc
					(start 461.574896 -399.029936)
					(mid 463.440018 -400.895058)
					(end 465.304886 -399.029936)
				)
			)
		)
	)
	(zone
		(layer "B.Cu")
		(hatch none 0.5)
		(connect_pads
			(clearance 0)
		)
		(min_thickness 0.25)
		(keepout
			(tracks not_allowed)
			(vias allowed)
			(pads allowed)
			(copperpour not_allowed)
			(footprints allowed)
		)
		(placement
			(enabled no)
			(sheetname "")
		)
		(fill
			(thermal_gap 0.5)
			(thermal_bridge_width 0.5)
			(island_removal_mode 0)
		)
		(polygon
			(pts
				(arc
					(start 9.800082 -22.29993)
					(mid 6.999986 -19.499834)
					(end 4.19989 -22.29993)
				)
				(arc
					(start 4.19989 -22.29993)
					(mid 6.999986 -25.100026)
					(end 9.800082 -22.29993)
				)
			)
		)
	)
	(zone
		(layer "B.Cu")
		(hatch none 0.5)
		(connect_pads
			(clearance 0)
		)
		(min_thickness 0.25)
		(keepout
			(tracks not_allowed)
			(vias allowed)
			(pads allowed)
			(copperpour not_allowed)
			(footprints allowed)
		)
		(placement
			(enabled no)
			(sheetname "")
		)
		(fill
			(thermal_gap 0.5)
			(thermal_bridge_width 0.5)
			(island_removal_mode 0)
		)
		(polygon
			(pts
				(arc
					(start 125.249686 -247.724422)
					(mid 124.619766 -247.724422)
					(end 125.249686 -247.724422)
				)
			)
		)
	)
	(zone
		(layer "B.Cu")
		(hatch none 0.5)
		(connect_pads
			(clearance 0)
		)
		(min_thickness 0.25)
		(keepout
			(tracks allowed)
			(vias allowed)
			(pads allowed)
			(copperpour allowed)
			(footprints not_allowed)
		)
		(placement
			(enabled no)
			(sheetname "")
		)
		(fill
			(thermal_gap 0.5)
			(thermal_bridge_width 0.5)
			(island_removal_mode 0)
		)
		(polygon
			(pts
				(arc
					(start 239.450118 -192.499996)
					(mid 236.650022 -189.6999)
					(end 233.849926 -192.499996)
				)
				(arc
					(start 233.849926 -192.499996)
					(mid 236.650022 -195.300092)
					(end 239.450118 -192.499996)
				)
			)
		)
	)
	(zone
		(layer "B.Cu")
		(hatch none 0.5)
		(connect_pads
			(clearance 0)
		)
		(min_thickness 0.25)
		(keepout
			(tracks not_allowed)
			(vias allowed)
			(pads allowed)
			(copperpour not_allowed)
			(footprints allowed)
		)
		(placement
			(enabled no)
			(sheetname "")
		)
		(fill
			(thermal_gap 0.5)
			(thermal_bridge_width 0.5)
			(island_removal_mode 0)
		)
		(polygon
			(pts
				(arc
					(start 310.150256 -400.811238)
					(mid 309.482236 -400.811238)
					(end 310.150256 -400.811238)
				)
			)
		)
	)
	(zone
		(layer "B.Cu")
		(hatch none 0.5)
		(connect_pads
			(clearance 0)
		)
		(min_thickness 0.25)
		(keepout
			(tracks not_allowed)
			(vias allowed)
			(pads allowed)
			(copperpour not_allowed)
			(footprints allowed)
		)
		(placement
			(enabled no)
			(sheetname "")
		)
		(fill
			(thermal_gap 0.5)
			(thermal_bridge_width 0.5)
			(island_removal_mode 0)
		)
		(polygon
			(pts
				(arc
					(start 260.649974 -22.29993)
					(mid 265.649964 -27.29992)
					(end 270.649954 -22.29993)
				)
				(arc
					(start 270.649954 -22.29993)
					(mid 265.649964 -17.29994)
					(end 260.649974 -22.29993)
				)
			)
		)
	)
	(zone
		(layer "B.Cu")
		(hatch none 0.5)
		(connect_pads
			(clearance 0)
		)
		(min_thickness 0.25)
		(keepout
			(tracks not_allowed)
			(vias allowed)
			(pads allowed)
			(copperpour not_allowed)
			(footprints allowed)
		)
		(placement
			(enabled no)
			(sheetname "")
		)
		(fill
			(thermal_gap 0.5)
			(thermal_bridge_width 0.5)
			(island_removal_mode 0)
		)
		(polygon
			(pts
				(arc
					(start 357.686102 -245.29415)
					(mid 357.056182 -245.29415)
					(end 357.686102 -245.29415)
				)
			)
		)
	)
	(zone
		(layer "B.Cu")
		(hatch none 0.5)
		(connect_pads
			(clearance 0)
		)
		(min_thickness 0.25)
		(keepout
			(tracks allowed)
			(vias allowed)
			(pads allowed)
			(copperpour allowed)
			(footprints not_allowed)
		)
		(placement
			(enabled no)
			(sheetname "")
		)
		(fill
			(thermal_gap 0.5)
			(thermal_bridge_width 0.5)
			(island_removal_mode 0)
		)
		(polygon
			(pts
				(xy 2.999994 -96.19996) (xy 7.500112 -96.19996)
				(arc
					(start 7.500112 -148.326856)
					(mid 5.147363 -149.129555)
					(end 2.999994 -150.38197)
				)
			)
		)
	)
	(zone
		(layer "B.Cu")
		(hatch none 0.5)
		(connect_pads
			(clearance 0)
		)
		(min_thickness 0.25)
		(keepout
			(tracks not_allowed)
			(vias allowed)
			(pads allowed)
			(copperpour not_allowed)
			(footprints allowed)
		)
		(placement
			(enabled no)
			(sheetname "")
		)
		(fill
			(thermal_gap 0.5)
			(thermal_bridge_width 0.5)
			(island_removal_mode 0)
		)
		(polygon
			(pts
				(arc
					(start 61.350652 -393.292838)
					(mid 60.682632 -393.292838)
					(end 61.350652 -393.292838)
				)
			)
		)
	)
	(zone
		(layer "B.Cu")
		(hatch none 0.5)
		(connect_pads
			(clearance 0)
		)
		(min_thickness 0.25)
		(keepout
			(tracks allowed)
			(vias allowed)
			(pads allowed)
			(copperpour allowed)
			(footprints allowed)
		)
		(placement
			(enabled no)
			(sheetname "")
		)
		(fill
			(thermal_gap 0.5)
			(thermal_bridge_width 0.5)
			(island_removal_mode 0)
		)
		(polygon
			(pts
				(xy 130.7338 -28.3718) (xy 130.7338 -25.8318) (xy 131.445 -25.8318) (xy 131.445 -28.3718)
			)
		)
	)
	(zone
		(layer "B.Cu")
		(hatch none 0.5)
		(connect_pads
			(clearance 0)
		)
		(min_thickness 0.25)
		(keepout
			(tracks not_allowed)
			(vias allowed)
			(pads allowed)
			(copperpour not_allowed)
			(footprints allowed)
		)
		(placement
			(enabled no)
			(sheetname "")
		)
		(fill
			(thermal_gap 0.5)
			(thermal_bridge_width 0.5)
			(island_removal_mode 0)
		)
		(polygon
			(pts
				(arc
					(start 5.340096 -347.700092)
					(mid 10.340086 -352.700082)
					(end 15.340076 -347.700092)
				)
				(arc
					(start 15.340076 -347.700092)
					(mid 10.340086 -342.700102)
					(end 5.340096 -347.700092)
				)
			)
		)
	)
	(zone
		(layer "B.Cu")
		(hatch none 0.5)
		(connect_pads
			(clearance 0)
		)
		(min_thickness 0.25)
		(keepout
			(tracks not_allowed)
			(vias allowed)
			(pads allowed)
			(copperpour not_allowed)
			(footprints allowed)
		)
		(placement
			(enabled no)
			(sheetname "")
		)
		(fill
			(thermal_gap 0.5)
			(thermal_bridge_width 0.5)
			(island_removal_mode 0)
		)
		(polygon
			(pts
				(arc
					(start 318.55029 -400.811238)
					(mid 317.88227 -400.811238)
					(end 318.55029 -400.811238)
				)
			)
		)
	)
	(zone
		(layer "B.Cu")
		(hatch none 0.5)
		(connect_pads
			(clearance 0)
		)
		(min_thickness 0.25)
		(keepout
			(tracks not_allowed)
			(vias allowed)
			(pads allowed)
			(copperpour not_allowed)
			(footprints allowed)
		)
		(placement
			(enabled no)
			(sheetname "")
		)
		(fill
			(thermal_gap 0.5)
			(thermal_bridge_width 0.5)
			(island_removal_mode 0)
		)
		(polygon
			(pts
				(arc
					(start 293.319962 -384.869944)
					(mid 291.07003 -382.620012)
					(end 288.820098 -384.869944)
				)
				(arc
					(start 288.820098 -384.869944)
					(mid 291.07003 -387.119876)
					(end 293.319962 -384.869944)
				)
			)
		)
	)
	(zone
		(layer "B.Cu")
		(hatch none 0.5)
		(connect_pads
			(clearance 0)
		)
		(min_thickness 0.25)
		(keepout
			(tracks not_allowed)
			(vias allowed)
			(pads allowed)
			(copperpour not_allowed)
			(footprints allowed)
		)
		(placement
			(enabled no)
			(sheetname "")
		)
		(fill
			(thermal_gap 0.5)
			(thermal_bridge_width 0.5)
			(island_removal_mode 0)
		)
		(polygon
			(pts
				(arc
					(start 116.789708 -247.724422)
					(mid 116.159788 -247.724422)
					(end 116.789708 -247.724422)
				)
			)
		)
	)
	(zone
		(layer "B.Cu")
		(hatch none 0.5)
		(connect_pads
			(clearance 0)
		)
		(min_thickness 0.25)
		(keepout
			(tracks not_allowed)
			(vias allowed)
			(pads allowed)
			(copperpour not_allowed)
			(footprints allowed)
		)
		(placement
			(enabled no)
			(sheetname "")
		)
		(fill
			(thermal_gap 0.5)
			(thermal_bridge_width 0.5)
			(island_removal_mode 0)
		)
		(polygon
			(pts
				(arc
					(start 407.378154 -400.811238)
					(mid 406.710134 -400.811238)
					(end 407.378154 -400.811238)
				)
			)
		)
	)
	(zone
		(layer "B.Cu")
		(hatch none 0.5)
		(connect_pads
			(clearance 0)
		)
		(min_thickness 0.25)
		(keepout
			(tracks allowed)
			(vias allowed)
			(pads allowed)
			(copperpour allowed)
			(footprints allowed)
		)
		(placement
			(enabled no)
			(sheetname "")
		)
		(fill
			(thermal_gap 0.5)
			(thermal_bridge_width 0.5)
			(island_removal_mode 0)
		)
		(polygon
			(pts
				(xy 36.487354 -416.343846) (xy 36.487354 -417.710874) (xy 35.650424 -417.710874) (xy 35.650424 -416.343846)
			)
		)
	)
	(zone
		(layer "B.Cu")
		(hatch none 0.5)
		(connect_pads
			(clearance 0)
		)
		(min_thickness 0.25)
		(keepout
			(tracks allowed)
			(vias allowed)
			(pads allowed)
			(copperpour allowed)
			(footprints not_allowed)
		)
		(placement
			(enabled no)
			(sheetname "")
		)
		(fill
			(thermal_gap 0.5)
			(thermal_bridge_width 0.5)
			(island_removal_mode 0)
		)
		(polygon
			(pts
				(arc
					(start 199.650096 -51.999896)
					(mid 204.650086 -56.999886)
					(end 209.650076 -51.999896)
				)
				(arc
					(start 209.650076 -51.999896)
					(mid 204.650086 -46.999906)
					(end 199.650096 -51.999896)
				)
			)
		)
	)
	(zone
		(layer "B.Cu")
		(hatch none 0.5)
		(connect_pads
			(clearance 0)
		)
		(min_thickness 0.25)
		(keepout
			(tracks allowed)
			(vias allowed)
			(pads allowed)
			(copperpour allowed)
			(footprints not_allowed)
		)
		(placement
			(enabled no)
			(sheetname "")
		)
		(fill
			(thermal_gap 0.5)
			(thermal_bridge_width 0.5)
			(island_removal_mode 0)
		)
		(polygon
			(pts
				(arc
					(start 383.70002 -22.29993)
					(mid 380.900178 -19.500088)
					(end 378.100082 -22.29993)
				)
				(arc
					(start 378.100082 -22.29993)
					(mid 380.900178 -25.100026)
					(end 383.70002 -22.29993)
				)
			)
		)
	)
	(zone
		(layer "B.Cu")
		(hatch none 0.5)
		(connect_pads
			(clearance 0)
		)
		(min_thickness 0.25)
		(keepout
			(tracks allowed)
			(vias allowed)
			(pads allowed)
			(copperpour allowed)
			(footprints not_allowed)
		)
		(placement
			(enabled no)
			(sheetname "")
		)
		(fill
			(thermal_gap 0.5)
			(thermal_bridge_width 0.5)
			(island_removal_mode 0)
		)
		(polygon
			(pts
				(arc
					(start 467.29777 -149.446996)
					(mid 465.037119 -148.52282)
					(end 462.639918 -148.055838)
				)
				(xy 462.639918 -96.19996) (xy 467.299802 -96.19996)
			)
		)
	)
	(zone
		(layer "B.Cu")
		(hatch none 0.5)
		(connect_pads
			(clearance 0)
		)
		(min_thickness 0.25)
		(keepout
			(tracks allowed)
			(vias allowed)
			(pads allowed)
			(copperpour allowed)
			(footprints allowed)
		)
		(placement
			(enabled no)
			(sheetname "")
		)
		(fill
			(thermal_gap 0.5)
			(thermal_bridge_width 0.5)
			(island_removal_mode 0)
		)
		(polygon
			(pts
				(xy 318.598296 -337.271868) (xy 318.598296 -339.430868) (xy 318.217296 -339.811868) (xy 315.423296 -339.811868)
				(xy 314.280296 -338.668868) (xy 314.280296 -335.747868) (xy 314.788296 -335.239868) (xy 316.566296 -335.239868)
			)
		)
	)
	(zone
		(layer "B.Cu")
		(hatch none 0.5)
		(connect_pads
			(clearance 0)
		)
		(min_thickness 0.25)
		(keepout
			(tracks not_allowed)
			(vias allowed)
			(pads allowed)
			(copperpour not_allowed)
			(footprints allowed)
		)
		(placement
			(enabled no)
			(sheetname "")
		)
		(fill
			(thermal_gap 0.5)
			(thermal_bridge_width 0.5)
			(island_removal_mode 0)
		)
		(polygon
			(pts
				(arc
					(start 305.350164 -401.674838)
					(mid 304.682144 -401.674838)
					(end 305.350164 -401.674838)
				)
			)
		)
	)
	(zone
		(layer "B.Cu")
		(hatch none 0.5)
		(connect_pads
			(clearance 0)
		)
		(min_thickness 0.25)
		(keepout
			(tracks not_allowed)
			(vias allowed)
			(pads allowed)
			(copperpour not_allowed)
			(footprints allowed)
		)
		(placement
			(enabled no)
			(sheetname "")
		)
		(fill
			(thermal_gap 0.5)
			(thermal_bridge_width 0.5)
			(island_removal_mode 0)
		)
		(polygon
			(pts
				(arc
					(start 406.178258 -400.811238)
					(mid 405.510238 -400.811238)
					(end 406.178258 -400.811238)
				)
			)
		)
	)
	(zone
		(layer "B.Cu")
		(hatch none 0.5)
		(connect_pads
			(clearance 0)
		)
		(min_thickness 0.25)
		(keepout
			(tracks allowed)
			(vias allowed)
			(pads allowed)
			(copperpour allowed)
			(footprints allowed)
		)
		(placement
			(enabled no)
			(sheetname "")
		)
		(fill
			(thermal_gap 0.5)
			(thermal_bridge_width 0.5)
			(island_removal_mode 0)
		)
		(polygon
			(pts
				(xy 66.648076 -384.911854) (xy 66.648076 -383.394966) (xy 66.64071 -383.3876) (xy 66.64071 -382.876806)
				(xy 66.094356 -382.330452) (xy 64.813942 -382.330452) (xy 64.59601 -382.548384) (xy 48.595534 -382.548384)
				(xy 48.045116 -383.098802) (xy 48.045116 -384.911854)
			)
		)
	)
	(zone
		(layer "B.Cu")
		(hatch none 0.5)
		(connect_pads
			(clearance 0)
		)
		(min_thickness 0.25)
		(keepout
			(tracks not_allowed)
			(vias allowed)
			(pads allowed)
			(copperpour not_allowed)
			(footprints allowed)
		)
		(placement
			(enabled no)
			(sheetname "")
		)
		(fill
			(thermal_gap 0.5)
			(thermal_bridge_width 0.5)
			(island_removal_mode 0)
		)
		(polygon
			(pts
				(arc
					(start 230.89997 -81.700116)
					(mid 235.89996 -86.700106)
					(end 240.89995 -81.700116)
				)
				(arc
					(start 240.89995 -81.700116)
					(mid 235.89996 -76.700126)
					(end 230.89997 -81.700116)
				)
			)
		)
	)
	(zone
		(layer "B.Cu")
		(hatch none 0.5)
		(connect_pads
			(clearance 0)
		)
		(min_thickness 0.25)
		(keepout
			(tracks not_allowed)
			(vias allowed)
			(pads allowed)
			(copperpour not_allowed)
			(footprints allowed)
		)
		(placement
			(enabled no)
			(sheetname "")
		)
		(fill
			(thermal_gap 0.5)
			(thermal_bridge_width 0.5)
			(island_removal_mode 0)
		)
		(polygon
			(pts
				(arc
					(start 138.136884 -436.889906)
					(mid 137.362692 -436.889906)
					(end 138.136884 -436.889906)
				)
			)
		)
	)
	(zone
		(layer "B.Cu")
		(hatch none 0.5)
		(connect_pads
			(clearance 0)
		)
		(min_thickness 0.25)
		(keepout
			(tracks not_allowed)
			(vias allowed)
			(pads allowed)
			(copperpour not_allowed)
			(footprints allowed)
		)
		(placement
			(enabled no)
			(sheetname "")
		)
		(fill
			(thermal_gap 0.5)
			(thermal_bridge_width 0.5)
			(island_removal_mode 0)
		)
		(polygon
			(pts
				(arc
					(start 10.728198 -421.200326)
					(mid 10.060178 -421.200326)
					(end 10.728198 -421.200326)
				)
			)
		)
	)
	(zone
		(layer "B.Cu")
		(hatch none 0.5)
		(connect_pads
			(clearance 0)
		)
		(min_thickness 0.25)
		(keepout
			(tracks allowed)
			(vias allowed)
			(pads allowed)
			(copperpour allowed)
			(footprints allowed)
		)
		(placement
			(enabled no)
			(sheetname "")
		)
		(fill
			(thermal_gap 0.5)
			(thermal_bridge_width 0.5)
			(island_removal_mode 0)
		)
		(polygon
			(pts
				(xy 189.68212 -141.8082) (xy 189.68212 -140.6271) (xy 191.38138 -140.6271) (xy 191.38138 -141.8082)
			)
		)
	)
	(zone
		(layer "B.Cu")
		(hatch none 0.5)
		(connect_pads
			(clearance 0)
		)
		(min_thickness 0.25)
		(keepout
			(tracks allowed)
			(vias allowed)
			(pads allowed)
			(copperpour allowed)
			(footprints allowed)
		)
		(placement
			(enabled no)
			(sheetname "")
		)
		(fill
			(thermal_gap 0.5)
			(thermal_bridge_width 0.5)
			(island_removal_mode 0)
		)
		(polygon
			(pts
				(xy 199.85482 -193.8274) (xy 199.85482 -190.64986) (xy 201.76998 -190.64986) (xy 201.76998 -193.8274)
			)
		)
	)
	(zone
		(layer "B.Cu")
		(hatch none 0.5)
		(connect_pads
			(clearance 0)
		)
		(min_thickness 0.25)
		(keepout
			(tracks allowed)
			(vias allowed)
			(pads allowed)
			(copperpour allowed)
			(footprints allowed)
		)
		(placement
			(enabled no)
			(sheetname "")
		)
		(fill
			(thermal_gap 0.5)
			(thermal_bridge_width 0.5)
			(island_removal_mode 0)
		)
		(polygon
			(pts
				(xy 449.420234 -426.261022) (xy 448.752722 -426.261022) (xy 448.752722 -424.995848) (xy 449.05295 -424.69562)
				(xy 450.088254 -424.69562) (xy 450.177662 -424.785028) (xy 450.177662 -426.16501) (xy 450.08165 -426.261022)
			)
		)
	)
	(zone
		(layer "B.Cu")
		(hatch none 0.5)
		(connect_pads
			(clearance 0)
		)
		(min_thickness 0.25)
		(keepout
			(tracks allowed)
			(vias allowed)
			(pads allowed)
			(copperpour allowed)
			(footprints not_allowed)
		)
		(placement
			(enabled no)
			(sheetname "")
		)
		(fill
			(thermal_gap 0.5)
			(thermal_bridge_width 0.5)
			(island_removal_mode 0)
		)
		(polygon
			(pts
				(arc
					(start 297.9801 -400.169888)
					(mid 298.419297 -401.23071)
					(end 299.47997 -401.670012)
				)
				(arc
					(start 318.771778 -401.670012)
					(mid 319.805655 -401.790333)
					(end 320.78422 -402.144992)
				)
				(arc
					(start 321.517264 -402.511514)
					(mid 321.843446 -402.629801)
					(end 322.188078 -402.67001)
				)
				(arc
					(start 401.601686 -402.67001)
					(mid 401.946324 -402.629825)
					(end 402.2725 -402.511514)
				)
				(arc
					(start 403.005798 -402.144992)
					(mid 403.984368 -401.790353)
					(end 405.01824 -401.670012)
				)
				(arc
					(start 424.310048 -401.670012)
					(mid 425.370706 -401.23062)
					(end 425.809918 -400.169888)
				)
				(arc
					(start 425.809918 -379.469904)
					(mid 425.370616 -378.409336)
					(end 424.310048 -377.970034)
				)
				(arc
					(start 305.01844 -377.970034)
					(mid 304.444518 -378.084288)
					(end 303.95799 -378.409454)
				)
				(arc
					(start 298.419266 -383.947924)
					(mid 298.094176 -384.434594)
					(end 297.9801 -385.008628)
				)
			)
		)
	)
	(zone
		(layer "B.Cu")
		(hatch none 0.5)
		(connect_pads
			(clearance 0)
		)
		(min_thickness 0.25)
		(keepout
			(tracks not_allowed)
			(vias allowed)
			(pads allowed)
			(copperpour not_allowed)
			(footprints allowed)
		)
		(placement
			(enabled no)
			(sheetname "")
		)
		(fill
			(thermal_gap 0.5)
			(thermal_bridge_width 0.5)
			(island_removal_mode 0)
		)
		(polygon
			(pts
				(arc
					(start 66.15049 -392.429238)
					(mid 65.48247 -392.429238)
					(end 66.15049 -392.429238)
				)
			)
		)
	)
	(zone
		(layer "B.Cu")
		(hatch none 0.5)
		(connect_pads
			(clearance 0)
		)
		(min_thickness 0.25)
		(keepout
			(tracks not_allowed)
			(vias allowed)
			(pads allowed)
			(copperpour not_allowed)
			(footprints allowed)
		)
		(placement
			(enabled no)
			(sheetname "")
		)
		(fill
			(thermal_gap 0.5)
			(thermal_bridge_width 0.5)
			(island_removal_mode 0)
		)
		(polygon
			(pts
				(arc
					(start 151.378158 -392.429238)
					(mid 150.710138 -392.429238)
					(end 151.378158 -392.429238)
				)
			)
		)
	)
	(zone
		(layer "B.Cu")
		(hatch none 0.5)
		(connect_pads
			(clearance 0)
		)
		(min_thickness 0.25)
		(keepout
			(tracks not_allowed)
			(vias allowed)
			(pads allowed)
			(copperpour not_allowed)
			(footprints allowed)
		)
		(placement
			(enabled no)
			(sheetname "")
		)
		(fill
			(thermal_gap 0.5)
			(thermal_bridge_width 0.5)
			(island_removal_mode 0)
		)
		(polygon
			(pts
				(arc
					(start 438.852056 -351.415096)
					(mid 441.952126 -354.515166)
					(end 445.051942 -351.415096)
				)
				(arc
					(start 445.051942 -351.415096)
					(mid 441.952126 -348.31528)
					(end 438.852056 -351.415096)
				)
			)
		)
	)
	(zone
		(layer "B.Cu")
		(hatch none 0.5)
		(connect_pads
			(clearance 0)
		)
		(min_thickness 0.25)
		(keepout
			(tracks not_allowed)
			(vias allowed)
			(pads allowed)
			(copperpour not_allowed)
			(footprints allowed)
		)
		(placement
			(enabled no)
			(sheetname "")
		)
		(fill
			(thermal_gap 0.5)
			(thermal_bridge_width 0.5)
			(island_removal_mode 0)
		)
		(polygon
			(pts
				(arc
					(start 319.750186 -401.674838)
					(mid 319.082166 -401.674838)
					(end 319.750186 -401.674838)
				)
			)
		)
	)
	(zone
		(layer "B.Cu")
		(hatch none 0.5)
		(connect_pads
			(clearance 0)
		)
		(min_thickness 0.25)
		(keepout
			(tracks not_allowed)
			(vias allowed)
			(pads allowed)
			(copperpour not_allowed)
			(footprints allowed)
		)
		(placement
			(enabled no)
			(sheetname "")
		)
		(fill
			(thermal_gap 0.5)
			(thermal_bridge_width 0.5)
			(island_removal_mode 0)
		)
		(polygon
			(pts
				(arc
					(start 329.03668 -439.0898)
					(mid 328.262488 -439.0898)
					(end 329.03668 -439.0898)
				)
			)
		)
	)
	(zone
		(layer "B.Cu")
		(hatch none 0.5)
		(connect_pads
			(clearance 0)
		)
		(min_thickness 0.25)
		(keepout
			(tracks allowed)
			(vias allowed)
			(pads allowed)
			(copperpour allowed)
			(footprints allowed)
		)
		(placement
			(enabled no)
			(sheetname "")
		)
		(fill
			(thermal_gap 0.5)
			(thermal_bridge_width 0.5)
			(island_removal_mode 0)
		)
		(polygon
			(pts
				(xy 378.02058 1.75768) (xy 378.02058 3.76174) (xy 380.31166 3.76174) (xy 380.31166 1.75768)
			)
		)
	)
	(zone
		(layer "B.Cu")
		(hatch none 0.5)
		(connect_pads
			(clearance 0)
		)
		(min_thickness 0.25)
		(keepout
			(tracks allowed)
			(vias allowed)
			(pads allowed)
			(copperpour allowed)
			(footprints not_allowed)
		)
		(placement
			(enabled no)
			(sheetname "")
		)
		(fill
			(thermal_gap 0.5)
			(thermal_bridge_width 0.5)
			(island_removal_mode 0)
		)
		(polygon
			(pts
				(arc
					(start 456.460098 -347.700092)
					(mid 461.460088 -352.700082)
					(end 466.460078 -347.700092)
				)
				(arc
					(start 466.460078 -347.700092)
					(mid 461.460088 -342.700102)
					(end 456.460098 -347.700092)
				)
			)
		)
	)
	(zone
		(layer "B.Cu")
		(hatch none 0.5)
		(connect_pads
			(clearance 0)
		)
		(min_thickness 0.25)
		(keepout
			(tracks allowed)
			(vias allowed)
			(pads allowed)
			(copperpour allowed)
			(footprints allowed)
		)
		(placement
			(enabled no)
			(sheetname "")
		)
		(fill
			(thermal_gap 0.5)
			(thermal_bridge_width 0.5)
			(island_removal_mode 0)
		)
		(polygon
			(pts
				(xy 36.947094 -348.898972) (xy 36.947094 -351.057972) (xy 36.566094 -351.438972) (xy 33.772094 -351.438972)
				(xy 32.629094 -350.295972) (xy 32.629094 -347.374972) (xy 33.137094 -346.866972) (xy 34.915094 -346.866972)
			)
		)
	)
	(zone
		(layer "B.Cu")
		(hatch none 0.5)
		(connect_pads
			(clearance 0)
		)
		(min_thickness 0.25)
		(keepout
			(tracks not_allowed)
			(vias allowed)
			(pads allowed)
			(copperpour not_allowed)
			(footprints allowed)
		)
		(placement
			(enabled no)
			(sheetname "")
		)
		(fill
			(thermal_gap 0.5)
			(thermal_bridge_width 0.5)
			(island_removal_mode 0)
		)
		(polygon
			(pts
				(arc
					(start 120.54967 -244.484398)
					(mid 119.91975 -244.484398)
					(end 120.54967 -244.484398)
				)
			)
		)
	)
	(zone
		(layer "B.Cu")
		(hatch none 0.5)
		(connect_pads
			(clearance 0)
		)
		(min_thickness 0.25)
		(keepout
			(tracks allowed)
			(vias allowed)
			(pads allowed)
			(copperpour allowed)
			(footprints allowed)
		)
		(placement
			(enabled no)
			(sheetname "")
		)
		(fill
			(thermal_gap 0.5)
			(thermal_bridge_width 0.5)
			(island_removal_mode 0)
		)
		(polygon
			(pts
				(xy 411.981396 -417.428426) (xy 411.981396 -416.42411) (xy 413.35833 -416.42411) (xy 413.35833 -417.428426)
			)
		)
	)
	(zone
		(layer "B.Cu")
		(hatch none 0.5)
		(connect_pads
			(clearance 0)
		)
		(min_thickness 0.25)
		(keepout
			(tracks not_allowed)
			(vias allowed)
			(pads allowed)
			(copperpour not_allowed)
			(footprints allowed)
		)
		(placement
			(enabled no)
			(sheetname "")
		)
		(fill
			(thermal_gap 0.5)
			(thermal_bridge_width 0.5)
			(island_removal_mode 0)
		)
		(polygon
			(pts
				(arc
					(start 410.97835 -400.811238)
					(mid 410.31033 -400.811238)
					(end 410.97835 -400.811238)
				)
			)
		)
	)
	(zone
		(layer "B.Cu")
		(hatch none 0.5)
		(connect_pads
			(clearance 0)
		)
		(min_thickness 0.25)
		(keepout
			(tracks allowed)
			(vias allowed)
			(pads allowed)
			(copperpour allowed)
			(footprints not_allowed)
		)
		(placement
			(enabled no)
			(sheetname "")
		)
		(fill
			(thermal_gap 0.5)
			(thermal_bridge_width 0.5)
			(island_removal_mode 0)
		)
		(polygon
			(pts
				(arc
					(start 259.80009 -33.346644)
					(mid 275.99472 -29.316833)
					(end 273.750532 -12.78001)
				)
				(arc
					(start 260.800088 -12.78001)
					(mid 260.092983 -13.072903)
					(end 259.80009 -13.780008)
				)
			)
		)
	)
	(zone
		(layer "B.Cu")
		(hatch none 0.5)
		(connect_pads
			(clearance 0)
		)
		(min_thickness 0.25)
		(keepout
			(tracks not_allowed)
			(vias allowed)
			(pads allowed)
			(copperpour not_allowed)
			(footprints allowed)
		)
		(placement
			(enabled no)
			(sheetname "")
		)
		(fill
			(thermal_gap 0.5)
			(thermal_bridge_width 0.5)
			(island_removal_mode 0)
		)
		(polygon
			(pts
				(arc
					(start 31.070042 -376.489976)
					(mid 35.070034 -380.489968)
					(end 39.070026 -376.489976)
				)
				(arc
					(start 39.070026 -376.489976)
					(mid 35.070034 -372.489984)
					(end 31.070042 -376.489976)
				)
			)
		)
	)
	(zone
		(layer "B.Cu")
		(hatch none 0.5)
		(connect_pads
			(clearance 0)
		)
		(min_thickness 0.25)
		(keepout
			(tracks not_allowed)
			(vias allowed)
			(pads allowed)
			(copperpour not_allowed)
			(footprints allowed)
		)
		(placement
			(enabled no)
			(sheetname "")
		)
		(fill
			(thermal_gap 0.5)
			(thermal_bridge_width 0.5)
			(island_removal_mode 0)
		)
		(polygon
			(pts
				(arc
					(start 268.45006 -22.29993)
					(mid 265.650218 -19.500088)
					(end 262.850122 -22.29993)
				)
				(arc
					(start 262.850122 -22.29993)
					(mid 265.650218 -25.100026)
					(end 268.45006 -22.29993)
				)
			)
		)
	)
	(zone
		(layer "B.Cu")
		(hatch none 0.5)
		(connect_pads
			(clearance 0)
		)
		(min_thickness 0.25)
		(keepout
			(tracks not_allowed)
			(vias allowed)
			(pads allowed)
			(copperpour not_allowed)
			(footprints allowed)
		)
		(placement
			(enabled no)
			(sheetname "")
		)
		(fill
			(thermal_gap 0.5)
			(thermal_bridge_width 0.5)
			(island_removal_mode 0)
		)
		(polygon
			(pts
				(arc
					(start 345.936062 -246.104156)
					(mid 345.306142 -246.104156)
					(end 345.936062 -246.104156)
				)
			)
		)
	)
	(zone
		(layer "B.Cu")
		(hatch none 0.5)
		(connect_pads
			(clearance 0)
		)
		(min_thickness 0.25)
		(keepout
			(tracks not_allowed)
			(vias allowed)
			(pads allowed)
			(copperpour not_allowed)
			(footprints allowed)
		)
		(placement
			(enabled no)
			(sheetname "")
		)
		(fill
			(thermal_gap 0.5)
			(thermal_bridge_width 0.5)
			(island_removal_mode 0)
		)
		(polygon
			(pts
				(arc
					(start 126.136908 -438.089802)
					(mid 125.362716 -438.089802)
					(end 126.136908 -438.089802)
				)
			)
		)
	)
	(zone
		(layer "B.Cu")
		(hatch none 0.5)
		(connect_pads
			(clearance 0)
		)
		(min_thickness 0.25)
		(keepout
			(tracks not_allowed)
			(vias allowed)
			(pads allowed)
			(copperpour not_allowed)
			(footprints allowed)
		)
		(placement
			(enabled no)
			(sheetname "")
		)
		(fill
			(thermal_gap 0.5)
			(thermal_bridge_width 0.5)
			(island_removal_mode 0)
		)
		(polygon
			(pts
				(arc
					(start 422.999916 -413.170116)
					(mid 426.999908 -417.170108)
					(end 430.9999 -413.170116)
				)
				(arc
					(start 430.9999 -413.170116)
					(mid 426.999908 -409.170124)
					(end 422.999916 -413.170116)
				)
			)
		)
	)
	(zone
		(layer "B.Cu")
		(hatch none 0.5)
		(connect_pads
			(clearance 0)
		)
		(min_thickness 0.25)
		(keepout
			(tracks not_allowed)
			(vias allowed)
			(pads allowed)
			(copperpour not_allowed)
			(footprints allowed)
		)
		(placement
			(enabled no)
			(sheetname "")
		)
		(fill
			(thermal_gap 0.5)
			(thermal_bridge_width 0.5)
			(island_removal_mode 0)
		)
		(polygon
			(pts
				(arc
					(start 390.136888 -438.089802)
					(mid 389.362696 -438.089802)
					(end 390.136888 -438.089802)
				)
			)
		)
	)
	(zone
		(layer "B.Cu")
		(hatch none 0.5)
		(connect_pads
			(clearance 0)
		)
		(min_thickness 0.25)
		(keepout
			(tracks not_allowed)
			(vias allowed)
			(pads allowed)
			(copperpour not_allowed)
			(footprints allowed)
		)
		(placement
			(enabled no)
			(sheetname "")
		)
		(fill
			(thermal_gap 0.5)
			(thermal_bridge_width 0.5)
			(island_removal_mode 0)
		)
		(polygon
			(pts
				(arc
					(start 114.4397 -246.914416)
					(mid 113.80978 -246.914416)
					(end 114.4397 -246.914416)
				)
			)
		)
	)
	(zone
		(layer "B.Cu")
		(hatch none 0.5)
		(connect_pads
			(clearance 0)
		)
		(min_thickness 0.25)
		(keepout
			(tracks allowed)
			(vias allowed)
			(pads allowed)
			(copperpour allowed)
			(footprints not_allowed)
		)
		(placement
			(enabled no)
			(sheetname "")
		)
		(fill
			(thermal_gap 0.5)
			(thermal_bridge_width 0.5)
			(island_removal_mode 0)
		)
		(polygon
			(pts
				(arc
					(start 332.069948 -212.989922)
					(mid 329.270106 -210.19008)
					(end 326.47001 -212.989922)
				)
				(arc
					(start 326.47001 -212.989922)
					(mid 329.270106 -215.790018)
					(end 332.069948 -212.989922)
				)
			)
		)
	)
	(zone
		(layer "B.Cu")
		(hatch none 0.5)
		(connect_pads
			(clearance 0)
		)
		(min_thickness 0.25)
		(keepout
			(tracks allowed)
			(vias allowed)
			(pads allowed)
			(copperpour allowed)
			(footprints allowed)
		)
		(placement
			(enabled no)
			(sheetname "")
		)
		(fill
			(thermal_gap 0.5)
			(thermal_bridge_width 0.5)
			(island_removal_mode 0)
		)
		(polygon
			(pts
				(xy 206.94904 -403.689566) (xy 206.94904 -402.68525) (xy 207.642206 -402.68525) (xy 207.642206 -403.689566)
			)
		)
	)
	(zone
		(layer "B.Cu")
		(hatch none 0.5)
		(connect_pads
			(clearance 0)
		)
		(min_thickness 0.25)
		(keepout
			(tracks not_allowed)
			(vias allowed)
			(pads allowed)
			(copperpour not_allowed)
			(footprints allowed)
		)
		(placement
			(enabled no)
			(sheetname "")
		)
		(fill
			(thermal_gap 0.5)
			(thermal_bridge_width 0.5)
			(island_removal_mode 0)
		)
		(polygon
			(pts
				(arc
					(start 108.580936 -166.61511)
					(mid 106.716068 -164.750242)
					(end 104.850946 -166.61511)
				)
				(arc
					(start 104.850946 -166.61511)
					(mid 106.716068 -168.480232)
					(end 108.580936 -166.61511)
				)
			)
		)
	)
	(zone
		(layer "B.Cu")
		(hatch none 0.5)
		(connect_pads
			(clearance 0)
		)
		(min_thickness 0.25)
		(keepout
			(tracks not_allowed)
			(vias allowed)
			(pads allowed)
			(copperpour not_allowed)
			(footprints allowed)
		)
		(placement
			(enabled no)
			(sheetname "")
		)
		(fill
			(thermal_gap 0.5)
			(thermal_bridge_width 0.5)
			(island_removal_mode 0)
		)
		(polygon
			(pts
				(arc
					(start 57.75071 -393.292838)
					(mid 57.08269 -393.292838)
					(end 57.75071 -393.292838)
				)
			)
		)
	)
	(zone
		(layer "B.Cu")
		(hatch none 0.5)
		(connect_pads
			(clearance 0)
		)
		(min_thickness 0.25)
		(keepout
			(tracks not_allowed)
			(vias allowed)
			(pads allowed)
			(copperpour not_allowed)
			(footprints allowed)
		)
		(placement
			(enabled no)
			(sheetname "")
		)
		(fill
			(thermal_gap 0.5)
			(thermal_bridge_width 0.5)
			(island_removal_mode 0)
		)
		(polygon
			(pts
				(arc
					(start 64.950594 -392.429238)
					(mid 64.282574 -392.429238)
					(end 64.950594 -392.429238)
				)
			)
		)
	)
	(zone
		(layer "B.Cu")
		(hatch none 0.5)
		(connect_pads
			(clearance 0)
		)
		(min_thickness 0.25)
		(keepout
			(tracks allowed)
			(vias allowed)
			(pads allowed)
			(copperpour allowed)
			(footprints not_allowed)
		)
		(placement
			(enabled no)
			(sheetname "")
		)
		(fill
			(thermal_gap 0.5)
			(thermal_bridge_width 0.5)
			(island_removal_mode 0)
		)
		(polygon
			(pts
				(arc
					(start 7.500112 -340.221062)
					(mid 4.815152 -341.914209)
					(end 2.999994 -344.518234)
				)
				(arc
					(start 2.999994 -170.617896)
					(mid 5.147375 -171.870286)
					(end 7.500112 -172.67301)
				)
			)
		)
	)
	(zone
		(layer "B.Cu")
		(hatch none 0.5)
		(connect_pads
			(clearance 0)
		)
		(min_thickness 0.25)
		(keepout
			(tracks not_allowed)
			(vias allowed)
			(pads allowed)
			(copperpour not_allowed)
			(footprints allowed)
		)
		(placement
			(enabled no)
			(sheetname "")
		)
		(fill
			(thermal_gap 0.5)
			(thermal_bridge_width 0.5)
			(island_removal_mode 0)
		)
		(polygon
			(pts
				(arc
					(start 345.936062 -244.484144)
					(mid 345.306142 -244.484144)
					(end 345.936062 -244.484144)
				)
			)
		)
	)
	(zone
		(layer "B.Cu")
		(hatch none 0.5)
		(connect_pads
			(clearance 0)
		)
		(min_thickness 0.25)
		(keepout
			(tracks not_allowed)
			(vias allowed)
			(pads allowed)
			(copperpour not_allowed)
			(footprints allowed)
		)
		(placement
			(enabled no)
			(sheetname "")
		)
		(fill
			(thermal_gap 0.5)
			(thermal_bridge_width 0.5)
			(island_removal_mode 0)
		)
		(polygon
			(pts
				(arc
					(start 466.460078 -160.50006)
					(mid 461.460088 -155.50007)
					(end 456.460098 -160.50006)
				)
				(arc
					(start 456.460098 -160.50006)
					(mid 461.460088 -165.50005)
					(end 466.460078 -160.50006)
				)
			)
		)
	)
	(zone
		(layer "B.Cu")
		(hatch none 0.5)
		(connect_pads
			(clearance 0)
		)
		(min_thickness 0.25)
		(keepout
			(tracks allowed)
			(vias allowed)
			(pads allowed)
			(copperpour allowed)
			(footprints not_allowed)
		)
		(placement
			(enabled no)
			(sheetname "")
		)
		(fill
			(thermal_gap 0.5)
			(thermal_bridge_width 0.5)
			(island_removal_mode 0)
		)
		(polygon
			(pts
				(arc
					(start 67.115944 -344.814906)
					(mid 70.216014 -347.914976)
					(end 73.316084 -344.814906)
				)
				(arc
					(start 73.316084 -344.814906)
					(mid 70.216014 -341.714836)
					(end 67.115944 -344.814906)
				)
			)
		)
	)
	(zone
		(layer "B.Cu")
		(hatch none 0.5)
		(connect_pads
			(clearance 0)
		)
		(min_thickness 0.25)
		(keepout
			(tracks allowed)
			(vias allowed)
			(pads allowed)
			(copperpour allowed)
			(footprints not_allowed)
		)
		(placement
			(enabled no)
			(sheetname "")
		)
		(fill
			(thermal_gap 0.5)
			(thermal_bridge_width 0.5)
			(island_removal_mode 0)
		)
		(polygon
			(pts
				(arc
					(start 317.90005 -160.50006)
					(mid 322.90004 -165.50005)
					(end 327.90003 -160.50006)
				)
				(arc
					(start 327.90003 -160.50006)
					(mid 322.90004 -155.50007)
					(end 317.90005 -160.50006)
				)
			)
		)
	)
	(zone
		(layer "B.Cu")
		(hatch none 0.5)
		(connect_pads
			(clearance 0)
		)
		(min_thickness 0.25)
		(keepout
			(tracks not_allowed)
			(vias allowed)
			(pads allowed)
			(copperpour not_allowed)
			(footprints allowed)
		)
		(placement
			(enabled no)
			(sheetname "")
		)
		(fill
			(thermal_gap 0.5)
			(thermal_bridge_width 0.5)
			(island_removal_mode 0)
		)
		(polygon
			(pts
				(arc
					(start 174.749968 -435.600094)
					(mid 179.749958 -440.600084)
					(end 184.749948 -435.600094)
				)
				(arc
					(start 184.749948 -435.600094)
					(mid 179.749958 -430.600104)
					(end 174.749968 -435.600094)
				)
			)
		)
	)
	(zone
		(layer "B.Cu")
		(hatch none 0.5)
		(connect_pads
			(clearance 0)
		)
		(min_thickness 0.25)
		(keepout
			(tracks not_allowed)
			(vias allowed)
			(pads allowed)
			(copperpour not_allowed)
			(footprints allowed)
		)
		(placement
			(enabled no)
			(sheetname "")
		)
		(fill
			(thermal_gap 0.5)
			(thermal_bridge_width 0.5)
			(island_removal_mode 0)
		)
		(polygon
			(pts
				(arc
					(start 63.750444 -392.429238)
					(mid 63.082424 -392.429238)
					(end 63.750444 -392.429238)
				)
			)
		)
	)
	(zone
		(layer "B.Cu")
		(hatch none 0.5)
		(connect_pads
			(clearance 0)
		)
		(min_thickness 0.25)
		(keepout
			(tracks not_allowed)
			(vias allowed)
			(pads allowed)
			(copperpour not_allowed)
			(footprints allowed)
		)
		(placement
			(enabled no)
			(sheetname "")
		)
		(fill
			(thermal_gap 0.5)
			(thermal_bridge_width 0.5)
			(island_removal_mode 0)
		)
		(polygon
			(pts
				(arc
					(start 132.136896 -439.0898)
					(mid 131.362704 -439.0898)
					(end 132.136896 -439.0898)
				)
			)
		)
	)
	(zone
		(layer "B.Cu")
		(hatch none 0.5)
		(connect_pads
			(clearance 0)
		)
		(min_thickness 0.25)
		(keepout
			(tracks not_allowed)
			(vias allowed)
			(pads allowed)
			(copperpour not_allowed)
			(footprints allowed)
		)
		(placement
			(enabled no)
			(sheetname "")
		)
		(fill
			(thermal_gap 0.5)
			(thermal_bridge_width 0.5)
			(island_removal_mode 0)
		)
		(polygon
			(pts
				(arc
					(start 109.105954 -269.226284)
					(mid 108.476034 -269.226284)
					(end 109.105954 -269.226284)
				)
			)
		)
	)
	(zone
		(layer "B.Cu")
		(hatch none 0.5)
		(connect_pads
			(clearance 0)
		)
		(min_thickness 0.25)
		(keepout
			(tracks allowed)
			(vias allowed)
			(pads allowed)
			(copperpour allowed)
			(footprints not_allowed)
		)
		(placement
			(enabled no)
			(sheetname "")
		)
		(fill
			(thermal_gap 0.5)
			(thermal_bridge_width 0.5)
			(island_removal_mode 0)
		)
		(polygon
			(pts
				(arc
					(start 361.816904 -340.315042)
					(mid 359.952036 -338.450174)
					(end 358.086914 -340.315042)
				)
				(arc
					(start 358.086914 -340.315042)
					(mid 359.952036 -342.180164)
					(end 361.816904 -340.315042)
				)
			)
		)
	)
	(zone
		(layer "B.Cu")
		(hatch none 0.5)
		(connect_pads
			(clearance 0)
		)
		(min_thickness 0.25)
		(keepout
			(tracks not_allowed)
			(vias allowed)
			(pads allowed)
			(copperpour not_allowed)
			(footprints allowed)
		)
		(placement
			(enabled no)
			(sheetname "")
		)
		(fill
			(thermal_gap 0.5)
			(thermal_bridge_width 0.5)
			(island_removal_mode 0)
		)
		(polygon
			(pts
				(arc
					(start 351.576132 -247.724168)
					(mid 350.946212 -247.724168)
					(end 351.576132 -247.724168)
				)
			)
		)
	)
	(zone
		(layer "B.Cu")
		(hatch none 0.5)
		(connect_pads
			(clearance 0)
		)
		(min_thickness 0.25)
		(keepout
			(tracks allowed)
			(vias allowed)
			(pads allowed)
			(copperpour allowed)
			(footprints allowed)
		)
		(placement
			(enabled no)
			(sheetname "")
		)
		(fill
			(thermal_gap 0.5)
			(thermal_bridge_width 0.5)
			(island_removal_mode 0)
		)
		(polygon
			(pts
				(xy 195.54698 -125.41504) (xy 195.54698 -124.41682) (xy 196.88048 -124.41682) (xy 196.88048 -125.41504)
			)
		)
	)
	(zone
		(layer "B.Cu")
		(hatch none 0.5)
		(connect_pads
			(clearance 0)
		)
		(min_thickness 0.25)
		(keepout
			(tracks not_allowed)
			(vias allowed)
			(pads allowed)
			(copperpour not_allowed)
			(footprints allowed)
		)
		(placement
			(enabled no)
			(sheetname "")
		)
		(fill
			(thermal_gap 0.5)
			(thermal_bridge_width 0.5)
			(island_removal_mode 0)
		)
		(polygon
			(pts
				(arc
					(start 64.382904 -50.25009)
					(mid 65.784579 -49.92679)
					(end 66.903092 -49.022254)
				)
				(arc
					(start 66.903092 -49.022254)
					(mid 71.402756 -50.917617)
					(end 74.382884 -47.049944)
				)
				(arc
					(start 74.382884 -47.049944)
					(mid 71.402678 -43.182132)
					(end 66.903092 -45.077888)
				)
				(arc
					(start 66.903092 -45.077888)
					(mid 65.784607 -44.173293)
					(end 64.382904 -43.850052)
				)
				(arc
					(start 62.782958 -43.850052)
					(mid 59.582812 -47.050198)
					(end 62.782958 -50.25009)
				)
			)
		)
	)
	(zone
		(layer "B.Cu")
		(hatch none 0.5)
		(connect_pads
			(clearance 0)
		)
		(min_thickness 0.25)
		(keepout
			(tracks allowed)
			(vias allowed)
			(pads allowed)
			(copperpour allowed)
			(footprints not_allowed)
		)
		(placement
			(enabled no)
			(sheetname "")
		)
		(fill
			(thermal_gap 0.5)
			(thermal_bridge_width 0.5)
			(island_removal_mode 0)
		)
		(polygon
			(pts
				(arc
					(start 41.980104 -391.78992)
					(mid 42.419301 -392.850742)
					(end 43.479974 -393.290044)
				)
				(arc
					(start 62.771782 -393.290044)
					(mid 63.805659 -393.410365)
					(end 64.784224 -393.765024)
				)
				(arc
					(start 65.517268 -394.131546)
					(mid 65.84345 -394.249833)
					(end 66.188082 -394.290042)
				)
				(arc
					(start 145.60169 -394.290042)
					(mid 145.946328 -394.249857)
					(end 146.272504 -394.131546)
				)
				(arc
					(start 147.005802 -393.765024)
					(mid 147.984372 -393.410385)
					(end 149.018244 -393.290044)
				)
				(arc
					(start 168.310052 -393.290044)
					(mid 169.37071 -392.850652)
					(end 169.809922 -391.78992)
				)
				(arc
					(start 169.809922 -371.089936)
					(mid 169.37062 -370.029368)
					(end 168.310052 -369.590066)
				)
				(arc
					(start 49.018444 -369.590066)
					(mid 48.444566 -369.704217)
					(end 47.957994 -370.029232)
				)
				(arc
					(start 42.41927 -375.567956)
					(mid 42.09418 -376.054626)
					(end 41.980104 -376.62866)
				)
			)
		)
	)
	(zone
		(layer "B.Cu")
		(hatch none 0.5)
		(connect_pads
			(clearance 0)
		)
		(min_thickness 0.25)
		(keepout
			(tracks not_allowed)
			(vias allowed)
			(pads allowed)
			(copperpour not_allowed)
			(footprints allowed)
		)
		(placement
			(enabled no)
			(sheetname "")
		)
		(fill
			(thermal_gap 0.5)
			(thermal_bridge_width 0.5)
			(island_removal_mode 0)
		)
		(polygon
			(pts
				(arc
					(start 404.978108 -401.674838)
					(mid 404.310088 -401.674838)
					(end 404.978108 -401.674838)
				)
			)
		)
	)
	(zone
		(layer "B.Cu")
		(hatch none 0.5)
		(connect_pads
			(clearance 0)
		)
		(min_thickness 0.25)
		(keepout
			(tracks not_allowed)
			(vias allowed)
			(pads allowed)
			(copperpour not_allowed)
			(footprints allowed)
		)
		(placement
			(enabled no)
			(sheetname "")
		)
		(fill
			(thermal_gap 0.5)
			(thermal_bridge_width 0.5)
			(island_removal_mode 0)
		)
		(polygon
			(pts
				(arc
					(start 67.03695 -438.089802)
					(mid 66.262758 -438.089802)
					(end 67.03695 -438.089802)
				)
			)
		)
	)
	(zone
		(layer "B.Cu")
		(hatch none 0.5)
		(connect_pads
			(clearance 0)
		)
		(min_thickness 0.25)
		(keepout
			(tracks not_allowed)
			(vias allowed)
			(pads allowed)
			(copperpour not_allowed)
			(footprints allowed)
		)
		(placement
			(enabled no)
			(sheetname "")
		)
		(fill
			(thermal_gap 0.5)
			(thermal_bridge_width 0.5)
			(island_removal_mode 0)
		)
		(polygon
			(pts
				(arc
					(start 114.4397 -245.294404)
					(mid 113.80978 -245.294404)
					(end 114.4397 -245.294404)
				)
			)
		)
	)
	(zone
		(layer "B.Cu")
		(hatch none 0.5)
		(connect_pads
			(clearance 0)
		)
		(min_thickness 0.25)
		(keepout
			(tracks not_allowed)
			(vias allowed)
			(pads allowed)
			(copperpour not_allowed)
			(footprints allowed)
		)
		(placement
			(enabled no)
			(sheetname "")
		)
		(fill
			(thermal_gap 0.5)
			(thermal_bridge_width 0.5)
			(island_removal_mode 0)
		)
		(polygon
			(pts
				(arc
					(start 153.778204 -392.429238)
					(mid 153.110184 -392.429238)
					(end 153.778204 -392.429238)
				)
			)
		)
	)
	(zone
		(layer "B.Cu")
		(hatch none 0.5)
		(connect_pads
			(clearance 0)
		)
		(min_thickness 0.25)
		(keepout
			(tracks allowed)
			(vias allowed)
			(pads allowed)
			(copperpour allowed)
			(footprints not_allowed)
		)
		(placement
			(enabled no)
			(sheetname "")
		)
		(fill
			(thermal_gap 0.5)
			(thermal_bridge_width 0.5)
			(island_removal_mode 0)
		)
		(polygon
			(pts
				(xy 8.839962 -239.862106) (xy 8.839962 -202.362054) (xy 63.840106 -202.362054) (xy 63.840106 -239.862106)
			)
		)
	)
	(zone
		(layer "B.Cu")
		(hatch none 0.5)
		(connect_pads
			(clearance 0)
		)
		(min_thickness 0.25)
		(keepout
			(tracks not_allowed)
			(vias allowed)
			(pads allowed)
			(copperpour not_allowed)
			(footprints allowed)
		)
		(placement
			(enabled no)
			(sheetname "")
		)
		(fill
			(thermal_gap 0.5)
			(thermal_bridge_width 0.5)
			(island_removal_mode 0)
		)
		(polygon
			(pts
				(arc
					(start 78.037182 -439.0898)
					(mid 77.26299 -439.0898)
					(end 78.037182 -439.0898)
				)
			)
		)
	)
	(zone
		(layer "B.Cu")
		(hatch none 0.5)
		(connect_pads
			(clearance 0)
		)
		(min_thickness 0.25)
		(keepout
			(tracks not_allowed)
			(vias allowed)
			(pads allowed)
			(copperpour not_allowed)
			(footprints allowed)
		)
		(placement
			(enabled no)
			(sheetname "")
		)
		(fill
			(thermal_gap 0.5)
			(thermal_bridge_width 0.5)
			(island_removal_mode 0)
		)
		(polygon
			(pts
				(arc
					(start 349.696024 -247.724168)
					(mid 349.066104 -247.724168)
					(end 349.696024 -247.724168)
				)
			)
		)
	)
	(zone
		(layer "B.Cu")
		(hatch none 0.5)
		(connect_pads
			(clearance 0)
		)
		(min_thickness 0.25)
		(keepout
			(tracks not_allowed)
			(vias allowed)
			(pads allowed)
			(copperpour not_allowed)
			(footprints allowed)
		)
		(placement
			(enabled no)
			(sheetname "")
		)
		(fill
			(thermal_gap 0.5)
			(thermal_bridge_width 0.5)
			(island_removal_mode 0)
		)
		(polygon
			(pts
				(arc
					(start 103.936038 -270.03629)
					(mid 103.306118 -270.03629)
					(end 103.936038 -270.03629)
				)
			)
		)
	)
	(zone
		(layer "B.Cu")
		(hatch none 0.5)
		(connect_pads
			(clearance 0)
		)
		(min_thickness 0.25)
		(keepout
			(tracks allowed)
			(vias allowed)
			(pads allowed)
			(copperpour allowed)
			(footprints not_allowed)
		)
		(placement
			(enabled no)
			(sheetname "")
		)
		(fill
			(thermal_gap 0.5)
			(thermal_bridge_width 0.5)
			(island_removal_mode 0)
		)
		(polygon
			(pts
				(arc
					(start 314.269882 -258.890008)
					(mid 317.770002 -262.390128)
					(end 321.270122 -258.890008)
				)
				(arc
					(start 321.270122 -258.890008)
					(mid 317.770002 -255.389888)
					(end 314.269882 -258.890008)
				)
			)
		)
	)
	(zone
		(layer "B.Cu")
		(hatch none 0.5)
		(connect_pads
			(clearance 0)
		)
		(min_thickness 0.25)
		(keepout
			(tracks not_allowed)
			(vias allowed)
			(pads allowed)
			(copperpour not_allowed)
			(footprints allowed)
		)
		(placement
			(enabled no)
			(sheetname "")
		)
		(fill
			(thermal_gap 0.5)
			(thermal_bridge_width 0.5)
			(island_removal_mode 0)
		)
		(polygon
			(pts
				(arc
					(start 155.137104 -438.089802)
					(mid 154.362912 -438.089802)
					(end 155.137104 -438.089802)
				)
			)
		)
	)
	(zone
		(layer "B.Cu")
		(hatch none 0.5)
		(connect_pads
			(clearance 0)
		)
		(min_thickness 0.25)
		(keepout
			(tracks not_allowed)
			(vias allowed)
			(pads allowed)
			(copperpour not_allowed)
			(footprints allowed)
		)
		(placement
			(enabled no)
			(sheetname "")
		)
		(fill
			(thermal_gap 0.5)
			(thermal_bridge_width 0.5)
			(island_removal_mode 0)
		)
		(polygon
			(pts
				(arc
					(start 334.036924 -439.0898)
					(mid 333.262732 -439.0898)
					(end 334.036924 -439.0898)
				)
			)
		)
	)
	(zone
		(layer "B.Cu")
		(hatch none 0.5)
		(connect_pads
			(clearance 0)
		)
		(min_thickness 0.25)
		(keepout
			(tracks allowed)
			(vias allowed)
			(pads allowed)
			(copperpour allowed)
			(footprints allowed)
		)
		(placement
			(enabled no)
			(sheetname "")
		)
		(fill
			(thermal_gap 0.5)
			(thermal_bridge_width 0.5)
			(island_removal_mode 0)
		)
		(polygon
			(pts
				(xy 10.669778 -406.140412) (xy 10.669778 -407.50744) (xy 9.832848 -407.50744) (xy 9.480042 -407.50744)
				(xy 9.410192 -407.43759) (xy 9.410192 -405.923242) (xy 9.49325 -405.840184) (xy 10.5283 -405.840184)
				(xy 10.669778 -405.981662)
			)
		)
	)
	(zone
		(layer "B.Cu")
		(hatch none 0.5)
		(connect_pads
			(clearance 0)
		)
		(min_thickness 0.25)
		(keepout
			(tracks allowed)
			(vias allowed)
			(pads allowed)
			(copperpour allowed)
			(footprints not_allowed)
		)
		(placement
			(enabled no)
			(sheetname "")
		)
		(fill
			(thermal_gap 0.5)
			(thermal_bridge_width 0.5)
			(island_removal_mode 0)
		)
		(polygon
			(pts
				(arc
					(start 108.774992 -431.360072)
					(mid 112.025176 -434.610256)
					(end 115.275106 -431.360072)
				)
				(arc
					(start 115.275106 -431.360072)
					(mid 112.025176 -428.110142)
					(end 108.774992 -431.360072)
				)
			)
		)
	)
	(zone
		(layer "B.Cu")
		(hatch none 0.5)
		(connect_pads
			(clearance 0)
		)
		(min_thickness 0.25)
		(keepout
			(tracks allowed)
			(vias allowed)
			(pads allowed)
			(copperpour allowed)
			(footprints not_allowed)
		)
		(placement
			(enabled no)
			(sheetname "")
		)
		(fill
			(thermal_gap 0.5)
			(thermal_bridge_width 0.5)
			(island_removal_mode 0)
		)
		(polygon
			(pts
				(arc
					(start 429.250094 -413.170116)
					(mid 427.000162 -410.920184)
					(end 424.749976 -413.170116)
				)
				(arc
					(start 424.749976 -413.170116)
					(mid 427.000162 -415.420302)
					(end 429.250094 -413.170116)
				)
			)
		)
	)
	(zone
		(layer "B.Cu")
		(hatch none 0.5)
		(connect_pads
			(clearance 0)
		)
		(min_thickness 0.25)
		(keepout
			(tracks allowed)
			(vias allowed)
			(pads allowed)
			(copperpour allowed)
			(footprints not_allowed)
		)
		(placement
			(enabled no)
			(sheetname "")
		)
		(fill
			(thermal_gap 0.5)
			(thermal_bridge_width 0.5)
			(island_removal_mode 0)
		)
		(polygon
			(pts
				(arc
					(start 356.525068 -431.360072)
					(mid 359.774998 -434.610002)
					(end 363.024928 -431.360072)
				)
				(arc
					(start 363.024928 -431.360072)
					(mid 359.774998 -428.110142)
					(end 356.525068 -431.360072)
				)
			)
		)
	)
	(zone
		(layer "B.Cu")
		(hatch none 0.5)
		(connect_pads
			(clearance 0)
		)
		(min_thickness 0.25)
		(keepout
			(tracks allowed)
			(vias allowed)
			(pads allowed)
			(copperpour allowed)
			(footprints allowed)
		)
		(placement
			(enabled no)
			(sheetname "")
		)
		(fill
			(thermal_gap 0.5)
			(thermal_bridge_width 0.5)
			(island_removal_mode 0)
		)
		(polygon
			(pts
				(xy 378.02058 4.318) (xy 378.02058 6.3881) (xy 380.31166 6.3881) (xy 380.31166 4.318)
			)
		)
	)
	(zone
		(layer "B.Cu")
		(hatch none 0.5)
		(connect_pads
			(clearance 0)
		)
		(min_thickness 0.25)
		(keepout
			(tracks allowed)
			(vias allowed)
			(pads allowed)
			(copperpour allowed)
			(footprints allowed)
		)
		(placement
			(enabled no)
			(sheetname "")
		)
		(fill
			(thermal_gap 0.5)
			(thermal_bridge_width 0.5)
			(island_removal_mode 0)
		)
		(polygon
			(pts
				(xy 314.2488 -417.428426) (xy 314.2488 -416.42411) (xy 315.625734 -416.42411) (xy 315.625734 -417.428426)
			)
		)
	)
	(zone
		(layer "B.Cu")
		(hatch none 0.5)
		(connect_pads
			(clearance 0)
		)
		(min_thickness 0.25)
		(keepout
			(tracks allowed)
			(vias allowed)
			(pads allowed)
			(copperpour allowed)
			(footprints not_allowed)
		)
		(placement
			(enabled no)
			(sheetname "")
		)
		(fill
			(thermal_gap 0.5)
			(thermal_bridge_width 0.5)
			(island_removal_mode 0)
		)
		(polygon
			(pts
				(arc
					(start 113.612422 -431.360072)
					(mid 112.024922 -429.772572)
					(end 110.437422 -431.360072)
				)
				(arc
					(start 110.437422 -431.360072)
					(mid 112.024922 -432.947572)
					(end 113.612422 -431.360072)
				)
			)
		)
	)
	(zone
		(layer "B.Cu")
		(hatch none 0.5)
		(connect_pads
			(clearance 0)
		)
		(min_thickness 0.25)
		(keepout
			(tracks not_allowed)
			(vias allowed)
			(pads allowed)
			(copperpour not_allowed)
			(footprints allowed)
		)
		(placement
			(enabled no)
			(sheetname "")
		)
		(fill
			(thermal_gap 0.5)
			(thermal_bridge_width 0.5)
			(island_removal_mode 0)
		)
		(polygon
			(pts
				(arc
					(start 409.7782 -400.811238)
					(mid 409.11018 -400.811238)
					(end 409.7782 -400.811238)
				)
			)
		)
	)
	(zone
		(layer "B.Cu")
		(hatch none 0.5)
		(connect_pads
			(clearance 0)
		)
		(min_thickness 0.25)
		(keepout
			(tracks not_allowed)
			(vias allowed)
			(pads allowed)
			(copperpour not_allowed)
			(footprints allowed)
		)
		(placement
			(enabled no)
			(sheetname "")
		)
		(fill
			(thermal_gap 0.5)
			(thermal_bridge_width 0.5)
			(island_removal_mode 0)
		)
		(polygon
			(pts
				(arc
					(start 319.750186 -400.811238)
					(mid 319.082166 -400.811238)
					(end 319.750186 -400.811238)
				)
			)
		)
	)
	(zone
		(layer "B.Cu")
		(hatch none 0.5)
		(connect_pads
			(clearance 0)
		)
		(min_thickness 0.25)
		(keepout
			(tracks not_allowed)
			(vias allowed)
			(pads allowed)
			(copperpour not_allowed)
			(footprints allowed)
		)
		(placement
			(enabled no)
			(sheetname "")
		)
		(fill
			(thermal_gap 0.5)
			(thermal_bridge_width 0.5)
			(island_removal_mode 0)
		)
		(polygon
			(pts
				(arc
					(start 371.309646 -225.044254)
					(mid 370.679726 -225.044254)
					(end 371.309646 -225.044254)
				)
			)
		)
	)
	(zone
		(layer "B.Cu")
		(hatch none 0.5)
		(connect_pads
			(clearance 0)
		)
		(min_thickness 0.25)
		(keepout
			(tracks allowed)
			(vias allowed)
			(pads allowed)
			(copperpour allowed)
			(footprints allowed)
		)
		(placement
			(enabled no)
			(sheetname "")
		)
		(fill
			(thermal_gap 0.5)
			(thermal_bridge_width 0.5)
			(island_removal_mode 0)
		)
		(polygon
			(pts
				(xy 323.43852 -417.428426) (xy 323.43852 -416.42411) (xy 324.815454 -416.42411) (xy 324.815454 -417.428426)
			)
		)
	)
	(zone
		(layer "B.Cu")
		(hatch none 0.5)
		(connect_pads
			(clearance 0)
		)
		(min_thickness 0.25)
		(keepout
			(tracks allowed)
			(vias allowed)
			(pads allowed)
			(copperpour allowed)
			(footprints allowed)
		)
		(placement
			(enabled no)
			(sheetname "")
		)
		(fill
			(thermal_gap 0.5)
			(thermal_bridge_width 0.5)
			(island_removal_mode 0)
		)
		(polygon
			(pts
				(xy 323.895974 -296.61231) (xy 323.895974 -226.66579) (xy 324.434454 -226.12731) (xy 324.434454 -223.33331)
				(xy 326.593454 -221.17431) (xy 395.859254 -221.17431) (xy 395.859254 -296.61231) (xy 383.270252 -296.61231)
				(xy 383.175002 -296.51706) (xy 379.16104 -296.51706) (xy 379.06579 -296.61231)
			)
		)
	)
	(zone
		(layer "B.Cu")
		(hatch none 0.5)
		(connect_pads
			(clearance 0)
		)
		(min_thickness 0.25)
		(keepout
			(tracks allowed)
			(vias allowed)
			(pads allowed)
			(copperpour allowed)
			(footprints allowed)
		)
		(placement
			(enabled no)
			(sheetname "")
		)
		(fill
			(thermal_gap 0.5)
			(thermal_bridge_width 0.5)
			(island_removal_mode 0)
		)
		(polygon
			(pts
				(xy 202.26782 -37.15512) (xy 202.26782 -34.62782) (xy 204.75956 -34.62782) (xy 204.75956 -37.15512)
			)
		)
	)
	(zone
		(layer "B.Cu")
		(hatch none 0.5)
		(connect_pads
			(clearance 0)
		)
		(min_thickness 0.25)
		(keepout
			(tracks not_allowed)
			(vias allowed)
			(pads allowed)
			(copperpour not_allowed)
			(footprints allowed)
		)
		(placement
			(enabled no)
			(sheetname "")
		)
		(fill
			(thermal_gap 0.5)
			(thermal_bridge_width 0.5)
			(island_removal_mode 0)
		)
		(polygon
			(pts
				(arc
					(start 58.906156 -385.31038)
					(mid 58.276236 -385.31038)
					(end 58.906156 -385.31038)
				)
			)
		)
	)
	(zone
		(layer "B.Cu")
		(hatch none 0.5)
		(connect_pads
			(clearance 0)
		)
		(min_thickness 0.25)
		(keepout
			(tracks allowed)
			(vias allowed)
			(pads allowed)
			(copperpour allowed)
			(footprints not_allowed)
		)
		(placement
			(enabled no)
			(sheetname "")
		)
		(fill
			(thermal_gap 0.5)
			(thermal_bridge_width 0.5)
			(island_removal_mode 0)
		)
		(polygon
			(pts
				(arc
					(start 215.674956 -360.764074)
					(mid 213.67496 -358.764078)
					(end 211.674964 -360.764074)
				)
				(arc
					(start 211.674964 -360.764074)
					(mid 213.67496 -362.76407)
					(end 215.674956 -360.764074)
				)
			)
		)
	)
	(zone
		(layer "B.Cu")
		(hatch none 0.5)
		(connect_pads
			(clearance 0)
		)
		(min_thickness 0.25)
		(keepout
			(tracks allowed)
			(vias allowed)
			(pads allowed)
			(copperpour allowed)
			(footprints allowed)
		)
		(placement
			(enabled no)
			(sheetname "")
		)
		(fill
			(thermal_gap 0.5)
			(thermal_bridge_width 0.5)
			(island_removal_mode 0)
		)
		(polygon
			(pts
				(xy 140.6652 -409.046426) (xy 140.6652 -408.04211) (xy 142.042134 -408.04211) (xy 142.042134 -409.046426)
			)
		)
	)
	(zone
		(layer "B.Cu")
		(hatch none 0.5)
		(connect_pads
			(clearance 0)
		)
		(min_thickness 0.25)
		(keepout
			(tracks allowed)
			(vias allowed)
			(pads allowed)
			(copperpour allowed)
			(footprints not_allowed)
		)
		(placement
			(enabled no)
			(sheetname "")
		)
		(fill
			(thermal_gap 0.5)
			(thermal_bridge_width 0.5)
			(island_removal_mode 0)
		)
		(polygon
			(pts
				(arc
					(start 310.399938 -160.50006)
					(mid 322.90004 -173.000162)
					(end 335.399888 -160.50006)
				)
				(arc
					(start 335.399888 -160.50006)
					(mid 322.90004 -148.000212)
					(end 310.399938 -160.50006)
				)
			)
		)
	)
	(zone
		(layer "B.Cu")
		(hatch none 0.5)
		(connect_pads
			(clearance 0)
		)
		(min_thickness 0.25)
		(keepout
			(tracks not_allowed)
			(vias allowed)
			(pads allowed)
			(copperpour not_allowed)
			(footprints allowed)
		)
		(placement
			(enabled no)
			(sheetname "")
		)
		(fill
			(thermal_gap 0.5)
			(thermal_bridge_width 0.5)
			(island_removal_mode 0)
		)
		(polygon
			(pts
				(arc
					(start 114.4397 -248.534428)
					(mid 113.80978 -248.534428)
					(end 114.4397 -248.534428)
				)
			)
		)
	)
	(zone
		(layer "B.Cu")
		(hatch none 0.5)
		(connect_pads
			(clearance 0)
		)
		(min_thickness 0.25)
		(keepout
			(tracks allowed)
			(vias allowed)
			(pads allowed)
			(copperpour allowed)
			(footprints allowed)
		)
		(placement
			(enabled no)
			(sheetname "")
		)
		(fill
			(thermal_gap 0.5)
			(thermal_bridge_width 0.5)
			(island_removal_mode 0)
		)
		(polygon
			(pts
				(xy 275.682456 -348.970092) (xy 275.682456 -351.129092) (xy 275.301456 -351.510092) (xy 272.507456 -351.510092)
				(xy 271.364456 -350.367092) (xy 271.364456 -347.446092) (xy 271.872456 -346.938092) (xy 273.650456 -346.938092)
			)
		)
	)
	(zone
		(layer "B.Cu")
		(hatch none 0.5)
		(connect_pads
			(clearance 0)
		)
		(min_thickness 0.25)
		(keepout
			(tracks not_allowed)
			(vias allowed)
			(pads allowed)
			(copperpour not_allowed)
			(footprints allowed)
		)
		(placement
			(enabled no)
			(sheetname "")
		)
		(fill
			(thermal_gap 0.5)
			(thermal_bridge_width 0.5)
			(island_removal_mode 0)
		)
		(polygon
			(pts
				(arc
					(start 432.340004 -399.029936)
					(mid 435.440074 -402.130006)
					(end 438.53989 -399.029936)
				)
				(arc
					(start 438.53989 -399.029936)
					(mid 435.440074 -395.93012)
					(end 432.340004 -399.029936)
				)
			)
		)
	)
	(zone
		(layer "B.Cu")
		(hatch none 0.5)
		(connect_pads
			(clearance 0)
		)
		(min_thickness 0.25)
		(keepout
			(tracks allowed)
			(vias allowed)
			(pads allowed)
			(copperpour allowed)
			(footprints not_allowed)
		)
		(placement
			(enabled no)
			(sheetname "")
		)
		(fill
			(thermal_gap 0.5)
			(thermal_bridge_width 0.5)
			(island_removal_mode 0)
		)
		(polygon
			(pts
				(arc
					(start 435.749954 -384.869944)
					(mid 433.500022 -382.620012)
					(end 431.25009 -384.869944)
				)
				(arc
					(start 431.25009 -384.869944)
					(mid 433.500022 -387.119876)
					(end 435.749954 -384.869944)
				)
			)
		)
	)
	(zone
		(layer "B.Cu")
		(hatch none 0.5)
		(connect_pads
			(clearance 0)
		)
		(min_thickness 0.25)
		(keepout
			(tracks allowed)
			(vias allowed)
			(pads allowed)
			(copperpour allowed)
			(footprints not_allowed)
		)
		(placement
			(enabled no)
			(sheetname "")
		)
		(fill
			(thermal_gap 0.5)
			(thermal_bridge_width 0.5)
			(island_removal_mode 0)
		)
		(polygon
			(pts
				(arc
					(start 5.340096 -160.50006)
					(mid 10.340086 -165.50005)
					(end 15.340076 -160.50006)
				)
				(arc
					(start 15.340076 -160.50006)
					(mid 10.340086 -155.50007)
					(end 5.340096 -160.50006)
				)
			)
		)
	)
	(zone
		(layer "B.Cu")
		(hatch none 0.5)
		(connect_pads
			(clearance 0)
		)
		(min_thickness 0.25)
		(keepout
			(tracks not_allowed)
			(vias allowed)
			(pads allowed)
			(copperpour not_allowed)
			(footprints allowed)
		)
		(placement
			(enabled no)
			(sheetname "")
		)
		(fill
			(thermal_gap 0.5)
			(thermal_bridge_width 0.5)
			(island_removal_mode 0)
		)
		(polygon
			(pts
				(arc
					(start 287.070038 -384.869944)
					(mid 291.07003 -388.869936)
					(end 295.070022 -384.869944)
				)
				(arc
					(start 295.070022 -384.869944)
					(mid 291.07003 -380.869952)
					(end 287.070038 -384.869944)
				)
			)
		)
	)
	(zone
		(layer "B.Cu")
		(hatch none 0.5)
		(connect_pads
			(clearance 0)
		)
		(min_thickness 0.25)
		(keepout
			(tracks not_allowed)
			(vias allowed)
			(pads allowed)
			(copperpour not_allowed)
			(footprints allowed)
		)
		(placement
			(enabled no)
			(sheetname "")
		)
		(fill
			(thermal_gap 0.5)
			(thermal_bridge_width 0.5)
			(island_removal_mode 0)
		)
		(polygon
			(pts
				(arc
					(start 412.178246 -400.811238)
					(mid 411.510226 -400.811238)
					(end 412.178246 -400.811238)
				)
			)
		)
	)
	(zone
		(layer "B.Cu")
		(hatch none 0.5)
		(connect_pads
			(clearance 0)
		)
		(min_thickness 0.25)
		(keepout
			(tracks allowed)
			(vias allowed)
			(pads allowed)
			(copperpour allowed)
			(footprints not_allowed)
		)
		(placement
			(enabled no)
			(sheetname "")
		)
		(fill
			(thermal_gap 0.5)
			(thermal_bridge_width 0.5)
			(island_removal_mode 0)
		)
		(polygon
			(pts
				(arc
					(start 464.25993 -347.700092)
					(mid 461.460088 -344.90025)
					(end 458.659992 -347.700092)
				)
				(arc
					(start 458.659992 -347.700092)
					(mid 461.460088 -350.500188)
					(end 464.25993 -347.700092)
				)
			)
		)
	)
	(zone
		(layer "B.Cu")
		(hatch none 0.5)
		(connect_pads
			(clearance 0)
		)
		(min_thickness 0.25)
		(keepout
			(tracks allowed)
			(vias allowed)
			(pads allowed)
			(copperpour allowed)
			(footprints not_allowed)
		)
		(placement
			(enabled no)
			(sheetname "")
		)
		(fill
			(thermal_gap 0.5)
			(thermal_bridge_width 0.5)
			(island_removal_mode 0)
		)
		(polygon
			(pts
				(arc
					(start 173.250098 -404.789894)
					(mid 171.000166 -402.539962)
					(end 168.74998 -404.789894)
				)
				(arc
					(start 168.74998 -404.789894)
					(mid 171.000166 -407.04008)
					(end 173.250098 -404.789894)
				)
			)
		)
	)
	(zone
		(layer "B.Cu")
		(hatch none 0.5)
		(connect_pads
			(clearance 0)
		)
		(min_thickness 0.25)
		(keepout
			(tracks allowed)
			(vias allowed)
			(pads allowed)
			(copperpour allowed)
			(footprints allowed)
		)
		(placement
			(enabled no)
			(sheetname "")
		)
		(fill
			(thermal_gap 0.5)
			(thermal_bridge_width 0.5)
			(island_removal_mode 0)
		)
		(polygon
			(pts
				(xy 91.944698 -409.046426) (xy 91.944698 -408.04211) (xy 93.321632 -408.04211) (xy 93.321632 -409.046426)
			)
		)
	)
	(zone
		(layer "B.Cu")
		(hatch none 0.5)
		(connect_pads
			(clearance 0)
		)
		(min_thickness 0.25)
		(keepout
			(tracks allowed)
			(vias allowed)
			(pads allowed)
			(copperpour allowed)
			(footprints allowed)
		)
		(placement
			(enabled no)
			(sheetname "")
		)
		(fill
			(thermal_gap 0.5)
			(thermal_bridge_width 0.5)
			(island_removal_mode 0)
		)
		(polygon
			(pts
				(xy 64.375538 -409.046426) (xy 64.375538 -408.04211) (xy 65.752472 -408.04211) (xy 65.752472 -409.046426)
			)
		)
	)
	(zone
		(layer "B.Cu")
		(hatch none 0.5)
		(connect_pads
			(clearance 0)
		)
		(min_thickness 0.25)
		(keepout
			(tracks allowed)
			(vias allowed)
			(pads allowed)
			(copperpour allowed)
			(footprints allowed)
		)
		(placement
			(enabled no)
			(sheetname "")
		)
		(fill
			(thermal_gap 0.5)
			(thermal_bridge_width 0.5)
			(island_removal_mode 0)
		)
		(polygon
			(pts
				(xy 447.60388 -194.4243) (xy 447.60388 -190.32982) (xy 450.17182 -190.32982) (xy 450.17182 -194.4243)
			)
		)
	)
	(zone
		(layer "B.Cu")
		(hatch none 0.5)
		(connect_pads
			(clearance 0)
		)
		(min_thickness 0.25)
		(keepout
			(tracks not_allowed)
			(vias allowed)
			(pads allowed)
			(copperpour not_allowed)
			(footprints allowed)
		)
		(placement
			(enabled no)
			(sheetname "")
		)
		(fill
			(thermal_gap 0.5)
			(thermal_bridge_width 0.5)
			(island_removal_mode 0)
		)
		(polygon
			(pts
				(arc
					(start 256.261108 -194.296284)
					(mid 255.593088 -194.296284)
					(end 256.261108 -194.296284)
				)
			)
		)
	)
	(zone
		(layer "B.Cu")
		(hatch none 0.5)
		(connect_pads
			(clearance 0)
		)
		(min_thickness 0.25)
		(keepout
			(tracks not_allowed)
			(vias allowed)
			(pads allowed)
			(copperpour not_allowed)
			(footprints allowed)
		)
		(placement
			(enabled no)
			(sheetname "")
		)
		(fill
			(thermal_gap 0.5)
			(thermal_bridge_width 0.5)
			(island_removal_mode 0)
		)
		(polygon
			(pts
				(arc
					(start 209.674968 -360.764074)
					(mid 213.67496 -364.764066)
					(end 217.674952 -360.764074)
				)
				(arc
					(start 217.674952 -360.764074)
					(mid 213.67496 -356.764082)
					(end 209.674968 -360.764074)
				)
			)
		)
	)
	(zone
		(layer "B.Cu")
		(hatch none 0.5)
		(connect_pads
			(clearance 0)
		)
		(min_thickness 0.25)
		(keepout
			(tracks allowed)
			(vias allowed)
			(pads allowed)
			(copperpour allowed)
			(footprints not_allowed)
		)
		(placement
			(enabled no)
			(sheetname "")
		)
		(fill
			(thermal_gap 0.5)
			(thermal_bridge_width 0.5)
			(island_removal_mode 0)
		)
		(polygon
			(pts
				(arc
					(start 288.550096 -435.600094)
					(mid 293.550086 -440.600084)
					(end 298.550076 -435.600094)
				)
				(arc
					(start 298.550076 -435.600094)
					(mid 293.550086 -430.600104)
					(end 288.550096 -435.600094)
				)
			)
		)
	)
	(zone
		(layer "B.Cu")
		(hatch none 0.5)
		(connect_pads
			(clearance 0)
		)
		(min_thickness 0.25)
		(keepout
			(tracks allowed)
			(vias allowed)
			(pads allowed)
			(copperpour allowed)
			(footprints allowed)
		)
		(placement
			(enabled no)
			(sheetname "")
		)
		(fill
			(thermal_gap 0.5)
			(thermal_bridge_width 0.5)
			(island_removal_mode 0)
		)
		(polygon
			(pts
				(xy 30.02534 -194.18046) (xy 30.02534 -193.16192) (xy 31.9405 -193.16192) (xy 31.9405 -194.18046)
			)
		)
	)
	(zone
		(layer "B.Cu")
		(hatch none 0.5)
		(connect_pads
			(clearance 0)
		)
		(min_thickness 0.25)
		(keepout
			(tracks allowed)
			(vias allowed)
			(pads allowed)
			(copperpour allowed)
			(footprints not_allowed)
		)
		(placement
			(enabled no)
			(sheetname "")
		)
		(fill
			(thermal_gap 0.5)
			(thermal_bridge_width 0.5)
			(island_removal_mode 0)
		)
		(polygon
			(pts
				(arc
					(start 462.637886 -172.944282)
					(mid 465.036131 -172.477497)
					(end 467.29777 -171.553124)
				)
				(arc
					(start 467.301072 -342.233504)
					(mid 465.178133 -340.616474)
					(end 462.641442 -339.787738)
				)
			)
		)
	)
	(zone
		(layer "B.Cu")
		(hatch none 0.5)
		(connect_pads
			(clearance 0)
		)
		(min_thickness 0.25)
		(keepout
			(tracks not_allowed)
			(vias allowed)
			(pads allowed)
			(copperpour not_allowed)
			(footprints allowed)
		)
		(placement
			(enabled no)
			(sheetname "")
		)
		(fill
			(thermal_gap 0.5)
			(thermal_bridge_width 0.5)
			(island_removal_mode 0)
		)
		(polygon
			(pts
				(arc
					(start 320.90614 -393.69238)
					(mid 320.27622 -393.69238)
					(end 320.90614 -393.69238)
				)
			)
		)
	)
	(zone
		(layer "B.Cu")
		(hatch none 0.5)
		(connect_pads
			(clearance 0)
		)
		(min_thickness 0.25)
		(keepout
			(tracks not_allowed)
			(vias allowed)
			(pads allowed)
			(copperpour not_allowed)
			(footprints allowed)
		)
		(placement
			(enabled no)
			(sheetname "")
		)
		(fill
			(thermal_gap 0.5)
			(thermal_bridge_width 0.5)
			(island_removal_mode 0)
		)
		(polygon
			(pts
				(arc
					(start 325.699882 -160.50006)
					(mid 322.90004 -157.700218)
					(end 320.099944 -160.50006)
				)
				(arc
					(start 320.099944 -160.50006)
					(mid 322.90004 -163.300156)
					(end 325.699882 -160.50006)
				)
			)
		)
	)
	(zone
		(layer "B.Cu")
		(hatch none 0.5)
		(connect_pads
			(clearance 0)
		)
		(min_thickness 0.25)
		(keepout
			(tracks not_allowed)
			(vias allowed)
			(pads allowed)
			(copperpour not_allowed)
			(footprints allowed)
		)
		(placement
			(enabled no)
			(sheetname "")
		)
		(fill
			(thermal_gap 0.5)
			(thermal_bridge_width 0.5)
			(island_removal_mode 0)
		)
		(polygon
			(pts
				(arc
					(start 157.3784 -393.292838)
					(mid 156.71038 -393.292838)
					(end 157.3784 -393.292838)
				)
			)
		)
	)
	(zone
		(layer "B.Cu")
		(hatch none 0.5)
		(connect_pads
			(clearance 0)
		)
		(min_thickness 0.25)
		(keepout
			(tracks not_allowed)
			(vias allowed)
			(pads allowed)
			(copperpour not_allowed)
			(footprints allowed)
		)
		(placement
			(enabled no)
			(sheetname "")
		)
		(fill
			(thermal_gap 0.5)
			(thermal_bridge_width 0.5)
			(island_removal_mode 0)
		)
		(polygon
			(pts
				(arc
					(start 65.036954 -437.889904)
					(mid 64.262762 -437.889904)
					(end 65.036954 -437.889904)
				)
			)
		)
	)
	(zone
		(layer "B.Cu")
		(hatch none 0.5)
		(connect_pads
			(clearance 0)
		)
		(min_thickness 0.25)
		(keepout
			(tracks not_allowed)
			(vias allowed)
			(pads allowed)
			(copperpour not_allowed)
			(footprints allowed)
		)
		(placement
			(enabled no)
			(sheetname "")
		)
		(fill
			(thermal_gap 0.5)
			(thermal_bridge_width 0.5)
			(island_removal_mode 0)
		)
		(polygon
			(pts
				(arc
					(start 198.399908 -22.29993)
					(mid 203.399898 -27.29992)
					(end 208.399888 -22.29993)
				)
				(arc
					(start 208.399888 -22.29993)
					(mid 203.399898 -17.29994)
					(end 198.399908 -22.29993)
				)
			)
		)
	)
	(zone
		(layer "B.Cu")
		(hatch none 0.5)
		(connect_pads
			(clearance 0)
		)
		(min_thickness 0.25)
		(keepout
			(tracks allowed)
			(vias allowed)
			(pads allowed)
			(copperpour allowed)
			(footprints allowed)
		)
		(placement
			(enabled no)
			(sheetname "")
		)
		(fill
			(thermal_gap 0.5)
			(thermal_bridge_width 0.5)
			(island_removal_mode 0)
		)
		(polygon
			(pts
				(xy 228.28504 -403.689566) (xy 228.28504 -402.68525) (xy 228.978206 -402.68525) (xy 228.978206 -403.689566)
			)
		)
	)
	(zone
		(layer "B.Cu")
		(hatch none 0.5)
		(connect_pads
			(clearance 0)
		)
		(min_thickness 0.25)
		(keepout
			(tracks not_allowed)
			(vias allowed)
			(pads allowed)
			(copperpour not_allowed)
			(footprints allowed)
		)
		(placement
			(enabled no)
			(sheetname "")
		)
		(fill
			(thermal_gap 0.5)
			(thermal_bridge_width 0.5)
			(island_removal_mode 0)
		)
		(polygon
			(pts
				(arc
					(start 182.550054 -435.600094)
					(mid 179.750212 -432.800252)
					(end 176.950116 -435.600094)
				)
				(arc
					(start 176.950116 -435.600094)
					(mid 179.750212 -438.40019)
					(end 182.550054 -435.600094)
				)
			)
		)
	)
	(zone
		(layer "B.Cu")
		(hatch none 0.5)
		(connect_pads
			(clearance 0)
		)
		(min_thickness 0.25)
		(keepout
			(tracks allowed)
			(vias allowed)
			(pads allowed)
			(copperpour allowed)
			(footprints allowed)
		)
		(placement
			(enabled no)
			(sheetname "")
		)
		(fill
			(thermal_gap 0.5)
			(thermal_bridge_width 0.5)
			(island_removal_mode 0)
		)
		(polygon
			(pts
				(xy 15.385034 -392.429746) (xy 16.752062 -392.429746) (xy 16.752062 -393.266676) (xy 15.385034 -393.266676)
			)
		)
	)
	(zone
		(layer "B.Cu")
		(hatch none 0.5)
		(connect_pads
			(clearance 0)
		)
		(min_thickness 0.25)
		(keepout
			(tracks not_allowed)
			(vias allowed)
			(pads allowed)
			(copperpour not_allowed)
			(footprints allowed)
		)
		(placement
			(enabled no)
			(sheetname "")
		)
		(fill
			(thermal_gap 0.5)
			(thermal_bridge_width 0.5)
			(island_removal_mode 0)
		)
		(polygon
			(pts
				(arc
					(start 401.13712 -437.889904)
					(mid 400.362928 -437.889904)
					(end 401.13712 -437.889904)
				)
			)
		)
	)
	(zone
		(layer "B.Cu")
		(hatch none 0.5)
		(connect_pads
			(clearance 0)
		)
		(min_thickness 0.25)
		(keepout
			(tracks allowed)
			(vias allowed)
			(pads allowed)
			(copperpour allowed)
			(footprints allowed)
		)
		(placement
			(enabled no)
			(sheetname "")
		)
		(fill
			(thermal_gap 0.5)
			(thermal_bridge_width 0.5)
			(island_removal_mode 0)
		)
		(polygon
			(pts
				(xy 399.493994 -143.23441) (xy 400.408394 -143.23441) (xy 400.408394 -144.74317) (xy 399.493994 -144.74317)
			)
		)
	)
	(zone
		(layer "B.Cu")
		(hatch none 0.5)
		(connect_pads
			(clearance 0)
		)
		(min_thickness 0.25)
		(keepout
			(tracks not_allowed)
			(vias allowed)
			(pads allowed)
			(copperpour not_allowed)
			(footprints allowed)
		)
		(placement
			(enabled no)
			(sheetname "")
		)
		(fill
			(thermal_gap 0.5)
			(thermal_bridge_width 0.5)
			(island_removal_mode 0)
		)
		(polygon
			(pts
				(arc
					(start 132.136896 -437.889904)
					(mid 131.362704 -437.889904)
					(end 132.136896 -437.889904)
				)
			)
		)
	)
	(zone
		(layer "B.Cu")
		(hatch none 0.5)
		(connect_pads
			(clearance 0)
		)
		(min_thickness 0.25)
		(keepout
			(tracks not_allowed)
			(vias allowed)
			(pads allowed)
			(copperpour not_allowed)
			(footprints allowed)
		)
		(placement
			(enabled no)
			(sheetname "")
		)
		(fill
			(thermal_gap 0.5)
			(thermal_bridge_width 0.5)
			(island_removal_mode 0)
		)
		(polygon
			(pts
				(arc
					(start 159.778446 -392.429238)
					(mid 159.110426 -392.429238)
					(end 159.778446 -392.429238)
				)
			)
		)
	)
	(zone
		(layer "B.Cu")
		(hatch none 0.5)
		(connect_pads
			(clearance 0)
		)
		(min_thickness 0.25)
		(keepout
			(tracks not_allowed)
			(vias allowed)
			(pads allowed)
			(copperpour not_allowed)
			(footprints allowed)
		)
		(placement
			(enabled no)
			(sheetname "")
		)
		(fill
			(thermal_gap 0.5)
			(thermal_bridge_width 0.5)
			(island_removal_mode 0)
		)
		(polygon
			(pts
				(arc
					(start 140.99413 -31.65856)
					(mid 140.32611 -31.65856)
					(end 140.99413 -31.65856)
				)
			)
		)
	)
	(zone
		(layer "B.Cu")
		(hatch none 0.5)
		(connect_pads
			(clearance 0)
		)
		(min_thickness 0.25)
		(keepout
			(tracks not_allowed)
			(vias allowed)
			(pads allowed)
			(copperpour not_allowed)
			(footprints allowed)
		)
		(placement
			(enabled no)
			(sheetname "")
		)
		(fill
			(thermal_gap 0.5)
			(thermal_bridge_width 0.5)
			(island_removal_mode 0)
		)
		(polygon
			(pts
				(arc
					(start 317.036704 -437.889904)
					(mid 316.262512 -437.889904)
					(end 317.036704 -437.889904)
				)
			)
		)
	)
	(zone
		(layer "B.Cu")
		(hatch none 0.5)
		(connect_pads
			(clearance 0)
		)
		(min_thickness 0.25)
		(keepout
			(tracks allowed)
			(vias allowed)
			(pads allowed)
			(copperpour allowed)
			(footprints not_allowed)
		)
		(placement
			(enabled no)
			(sheetname "")
		)
		(fill
			(thermal_gap 0.5)
			(thermal_bridge_width 0.5)
			(island_removal_mode 0)
		)
		(polygon
			(pts
				(arc
					(start 296.349928 -435.600094)
					(mid 293.550086 -432.800252)
					(end 290.74999 -435.600094)
				)
				(arc
					(start 290.74999 -435.600094)
					(mid 293.550086 -438.40019)
					(end 296.349928 -435.600094)
				)
			)
		)
	)
	(zone
		(layer "B.Cu")
		(hatch none 0.5)
		(connect_pads
			(clearance 0)
		)
		(min_thickness 0.25)
		(keepout
			(tracks allowed)
			(vias allowed)
			(pads allowed)
			(copperpour allowed)
			(footprints allowed)
		)
		(placement
			(enabled no)
			(sheetname "")
		)
		(fill
			(thermal_gap 0.5)
			(thermal_bridge_width 0.5)
			(island_removal_mode 0)
		)
		(polygon
			(pts
				(xy 344.8812 -417.428426) (xy 344.8812 -416.42411) (xy 346.258134 -416.42411) (xy 346.258134 -417.428426)
			)
		)
	)
	(zone
		(layer "B.Cu")
		(hatch none 0.5)
		(connect_pads
			(clearance 0)
		)
		(min_thickness 0.25)
		(keepout
			(tracks not_allowed)
			(vias allowed)
			(pads allowed)
			(copperpour not_allowed)
			(footprints allowed)
		)
		(placement
			(enabled no)
			(sheetname "")
		)
		(fill
			(thermal_gap 0.5)
			(thermal_bridge_width 0.5)
			(island_removal_mode 0)
		)
		(polygon
			(pts
				(arc
					(start 407.137108 -438.089802)
					(mid 406.362916 -438.089802)
					(end 407.137108 -438.089802)
				)
			)
		)
	)
	(zone
		(layer "B.Cu")
		(hatch none 0.5)
		(connect_pads
			(clearance 0)
		)
		(min_thickness 0.25)
		(keepout
			(tracks allowed)
			(vias allowed)
			(pads allowed)
			(copperpour allowed)
			(footprints allowed)
		)
		(placement
			(enabled no)
			(sheetname "")
		)
		(fill
			(thermal_gap 0.5)
			(thermal_bridge_width 0.5)
			(island_removal_mode 0)
		)
		(polygon
			(pts
				(xy 45.252894 -348.898972) (xy 45.252894 -351.057972) (xy 44.871894 -351.438972) (xy 42.077894 -351.438972)
				(xy 40.934894 -350.295972) (xy 40.934894 -347.374972) (xy 41.442894 -346.866972) (xy 43.220894 -346.866972)
			)
		)
	)
	(zone
		(layer "B.Cu")
		(hatch none 0.5)
		(connect_pads
			(clearance 0)
		)
		(min_thickness 0.25)
		(keepout
			(tracks not_allowed)
			(vias allowed)
			(pads allowed)
			(copperpour not_allowed)
			(footprints allowed)
		)
		(placement
			(enabled no)
			(sheetname "")
		)
		(fill
			(thermal_gap 0.5)
			(thermal_bridge_width 0.5)
			(island_removal_mode 0)
		)
		(polygon
			(pts
				(arc
					(start 407.137108 -436.889906)
					(mid 406.362916 -436.889906)
					(end 407.137108 -436.889906)
				)
			)
		)
	)
	(zone
		(layer "B.Cu")
		(hatch none 0.5)
		(connect_pads
			(clearance 0)
		)
		(min_thickness 0.25)
		(keepout
			(tracks not_allowed)
			(vias allowed)
			(pads allowed)
			(copperpour not_allowed)
			(footprints allowed)
		)
		(placement
			(enabled no)
			(sheetname "")
		)
		(fill
			(thermal_gap 0.5)
			(thermal_bridge_width 0.5)
			(island_removal_mode 0)
		)
		(polygon
			(pts
				(arc
					(start 311.350406 -400.811238)
					(mid 310.682386 -400.811238)
					(end 311.350406 -400.811238)
				)
			)
		)
	)
	(zone
		(layer "B.Cu")
		(hatch none 0.5)
		(connect_pads
			(clearance 0)
		)
		(min_thickness 0.25)
		(keepout
			(tracks allowed)
			(vias allowed)
			(pads allowed)
			(copperpour allowed)
			(footprints not_allowed)
		)
		(placement
			(enabled no)
			(sheetname "")
		)
		(fill
			(thermal_gap 0.5)
			(thermal_bridge_width 0.5)
			(island_removal_mode 0)
		)
		(polygon
			(pts
				(arc
					(start 424.310048 -401.670012)
					(mid 425.370706 -401.23062)
					(end 425.809918 -400.169888)
				)
				(arc
					(start 425.809918 -379.469904)
					(mid 425.370616 -378.409336)
					(end 424.310048 -377.970034)
				)
				(arc
					(start 305.01844 -377.970034)
					(mid 304.444518 -378.084288)
					(end 303.95799 -378.409454)
				)
				(arc
					(start 298.419266 -383.947924)
					(mid 298.094176 -384.434594)
					(end 297.9801 -385.008628)
				)
				(arc
					(start 297.9801 -400.169888)
					(mid 298.419297 -401.23071)
					(end 299.47997 -401.670012)
				)
				(arc
					(start 318.771778 -401.670012)
					(mid 319.805655 -401.790333)
					(end 320.78422 -402.144992)
				)
				(arc
					(start 321.517264 -402.511514)
					(mid 321.843446 -402.629801)
					(end 322.188078 -402.67001)
				)
				(arc
					(start 401.601686 -402.67001)
					(mid 401.946324 -402.629825)
					(end 402.2725 -402.511514)
				)
				(arc
					(start 403.005798 -402.144992)
					(mid 403.984368 -401.790353)
					(end 405.01824 -401.670012)
				)
			)
		)
	)
	(zone
		(layer "B.Cu")
		(hatch none 0.5)
		(connect_pads
			(clearance 0)
		)
		(min_thickness 0.25)
		(keepout
			(tracks not_allowed)
			(vias allowed)
			(pads allowed)
			(copperpour not_allowed)
			(footprints allowed)
		)
		(placement
			(enabled no)
			(sheetname "")
		)
		(fill
			(thermal_gap 0.5)
			(thermal_bridge_width 0.5)
			(island_removal_mode 0)
		)
		(polygon
			(pts
				(arc
					(start 414.578292 -400.811238)
					(mid 413.910272 -400.811238)
					(end 414.578292 -400.811238)
				)
			)
		)
	)
	(zone
		(layer "B.Cu")
		(hatch none 0.5)
		(connect_pads
			(clearance 0)
		)
		(min_thickness 0.25)
		(keepout
			(tracks allowed)
			(vias allowed)
			(pads allowed)
			(copperpour allowed)
			(footprints not_allowed)
		)
		(placement
			(enabled no)
			(sheetname "")
		)
		(fill
			(thermal_gap 0.5)
			(thermal_bridge_width 0.5)
			(island_removal_mode 0)
		)
		(polygon
			(pts
				(arc
					(start 204.020674 -352.824034)
					(mid 198.558263 -350.029864)
					(end 202.996546 -354.266246)
				)
				(arc
					(start 202.996546 -354.266246)
					(mid 210.300794 -372.800074)
					(end 226.175062 -360.764074)
				)
				(arc
					(start 226.175062 -360.764074)
					(mid 217.892293 -348.996889)
					(end 204.020674 -352.824034)
				)
			)
		)
	)
	(zone
		(layer "B.Cu")
		(hatch none 0.5)
		(connect_pads
			(clearance 0)
		)
		(min_thickness 0.25)
		(keepout
			(tracks allowed)
			(vias allowed)
			(pads allowed)
			(copperpour allowed)
			(footprints allowed)
		)
		(placement
			(enabled no)
			(sheetname "")
		)
		(fill
			(thermal_gap 0.5)
			(thermal_bridge_width 0.5)
			(island_removal_mode 0)
		)
		(polygon
			(pts
				(xy 123.832366 -162.837876) (xy 123.832366 -160.678876) (xy 124.213366 -160.297876) (xy 127.007366 -160.297876)
				(xy 128.150366 -161.440876) (xy 128.150366 -164.361876) (xy 127.642366 -164.869876) (xy 125.864366 -164.869876)
			)
		)
	)
	(zone
		(layer "B.Cu")
		(hatch none 0.5)
		(connect_pads
			(clearance 0)
		)
		(min_thickness 0.25)
		(keepout
			(tracks allowed)
			(vias allowed)
			(pads allowed)
			(copperpour allowed)
			(footprints allowed)
		)
		(placement
			(enabled no)
			(sheetname "")
		)
		(fill
			(thermal_gap 0.5)
			(thermal_bridge_width 0.5)
			(island_removal_mode 0)
		)
		(polygon
			(pts
				(xy 134.53872 -409.046426) (xy 134.53872 -408.04211) (xy 135.915654 -408.04211) (xy 135.915654 -409.046426)
			)
		)
	)
	(zone
		(layer "B.Cu")
		(hatch none 0.5)
		(connect_pads
			(clearance 0)
		)
		(min_thickness 0.25)
		(keepout
			(tracks allowed)
			(vias allowed)
			(pads allowed)
			(copperpour allowed)
			(footprints allowed)
		)
		(placement
			(enabled no)
			(sheetname "")
		)
		(fill
			(thermal_gap 0.5)
			(thermal_bridge_width 0.5)
			(island_removal_mode 0)
		)
		(polygon
			(pts
				(xy 328.3331 1.8034) (xy 328.3331 3.85064) (xy 330.64704 3.85064) (xy 330.64704 1.8034)
			)
		)
	)
	(zone
		(layer "B.Cu")
		(hatch none 0.5)
		(connect_pads
			(clearance 0)
		)
		(min_thickness 0.25)
		(keepout
			(tracks not_allowed)
			(vias allowed)
			(pads allowed)
			(copperpour not_allowed)
			(footprints allowed)
		)
		(placement
			(enabled no)
			(sheetname "")
		)
		(fill
			(thermal_gap 0.5)
			(thermal_bridge_width 0.5)
			(island_removal_mode 0)
		)
		(polygon
			(pts
				(arc
					(start 63.036958 -438.089802)
					(mid 62.262766 -438.089802)
					(end 63.036958 -438.089802)
				)
			)
		)
	)
	(zone
		(layer "B.Cu")
		(hatch none 0.5)
		(connect_pads
			(clearance 0)
		)
		(min_thickness 0.25)
		(keepout
			(tracks allowed)
			(vias allowed)
			(pads allowed)
			(copperpour allowed)
			(footprints not_allowed)
		)
		(placement
			(enabled no)
			(sheetname "")
		)
		(fill
			(thermal_gap 0.5)
			(thermal_bridge_width 0.5)
			(island_removal_mode 0)
		)
		(polygon
			(pts
				(arc
					(start 356.851966 -340.315042)
					(mid 359.952036 -343.415112)
					(end 363.052106 -340.315042)
				)
				(arc
					(start 363.052106 -340.315042)
					(mid 359.952036 -337.214972)
					(end 356.851966 -340.315042)
				)
			)
		)
	)
	(zone
		(layer "B.Cu")
		(hatch none 0.5)
		(connect_pads
			(clearance 0)
		)
		(min_thickness 0.25)
		(keepout
			(tracks not_allowed)
			(vias allowed)
			(pads allowed)
			(copperpour not_allowed)
			(footprints allowed)
		)
		(placement
			(enabled no)
			(sheetname "")
		)
		(fill
			(thermal_gap 0.5)
			(thermal_bridge_width 0.5)
			(island_removal_mode 0)
		)
		(polygon
			(pts
				(arc
					(start 145.33245 -30.81274)
					(mid 144.66443 -30.81274)
					(end 145.33245 -30.81274)
				)
			)
		)
	)
	(zone
		(layer "B.Cu")
		(hatch none 0.5)
		(connect_pads
			(clearance 0)
		)
		(min_thickness 0.25)
		(keepout
			(tracks allowed)
			(vias allowed)
			(pads allowed)
			(copperpour allowed)
			(footprints not_allowed)
		)
		(placement
			(enabled no)
			(sheetname "")
		)
		(fill
			(thermal_gap 0.5)
			(thermal_bridge_width 0.5)
			(island_removal_mode 0)
		)
		(polygon
			(pts
				(arc
					(start 439.302906 -74.767948)
					(mid 426.803058 -87.267796)
					(end 414.302956 -74.767948)
				)
				(arc
					(start 414.302956 -66.06794)
					(mid 426.803058 -53.567838)
					(end 439.302906 -66.06794)
				)
			)
		)
	)
	(zone
		(layer "B.Cu")
		(hatch none 0.5)
		(connect_pads
			(clearance 0)
		)
		(min_thickness 0.25)
		(keepout
			(tracks allowed)
			(vias allowed)
			(pads allowed)
			(copperpour allowed)
			(footprints not_allowed)
		)
		(placement
			(enabled no)
			(sheetname "")
		)
		(fill
			(thermal_gap 0.5)
			(thermal_bridge_width 0.5)
			(island_removal_mode 0)
		)
		(polygon
			(pts
				(arc
					(start 227.530406 -388.161784)
					(mid 225.430588 -386.061966)
					(end 223.330516 -388.161784)
				)
				(arc
					(start 223.330516 -388.161784)
					(mid 225.430588 -390.261856)
					(end 227.530406 -388.161784)
				)
			)
		)
	)
	(zone
		(layer "B.Cu")
		(hatch none 0.5)
		(connect_pads
			(clearance 0)
		)
		(min_thickness 0.25)
		(keepout
			(tracks not_allowed)
			(vias allowed)
			(pads allowed)
			(copperpour not_allowed)
			(footprints allowed)
		)
		(placement
			(enabled no)
			(sheetname "")
		)
		(fill
			(thermal_gap 0.5)
			(thermal_bridge_width 0.5)
			(island_removal_mode 0)
		)
		(polygon
			(pts
				(arc
					(start 123.72213 -36.053268)
					(mid 123.05411 -36.053268)
					(end 123.72213 -36.053268)
				)
			)
		)
	)
	(zone
		(layer "B.Cu")
		(hatch none 0.5)
		(connect_pads
			(clearance 0)
		)
		(min_thickness 0.25)
		(keepout
			(tracks allowed)
			(vias allowed)
			(pads allowed)
			(copperpour allowed)
			(footprints not_allowed)
		)
		(placement
			(enabled no)
			(sheetname "")
		)
		(fill
			(thermal_gap 0.5)
			(thermal_bridge_width 0.5)
			(island_removal_mode 0)
		)
		(polygon
			(pts
				(xy 159.740092 -310.522112) (xy 159.740092 -273.02206) (xy 214.739982 -273.02206) (xy 214.739982 -310.522112)
			)
		)
	)
	(zone
		(layer "B.Cu")
		(hatch none 0.5)
		(connect_pads
			(clearance 0)
		)
		(min_thickness 0.25)
		(keepout
			(tracks not_allowed)
			(vias allowed)
			(pads allowed)
			(copperpour not_allowed)
			(footprints allowed)
		)
		(placement
			(enabled no)
			(sheetname "")
		)
		(fill
			(thermal_gap 0.5)
			(thermal_bridge_width 0.5)
			(island_removal_mode 0)
		)
		(polygon
			(pts
				(arc
					(start 50.550572 -393.292838)
					(mid 49.882552 -393.292838)
					(end 50.550572 -393.292838)
				)
			)
		)
	)
	(zone
		(layer "B.Cu")
		(hatch none 0.5)
		(connect_pads
			(clearance 0)
		)
		(min_thickness 0.25)
		(keepout
			(tracks not_allowed)
			(vias allowed)
			(pads allowed)
			(copperpour not_allowed)
			(footprints allowed)
		)
		(placement
			(enabled no)
			(sheetname "")
		)
		(fill
			(thermal_gap 0.5)
			(thermal_bridge_width 0.5)
			(island_removal_mode 0)
		)
		(polygon
			(pts
				(arc
					(start 60.106306 -385.31038)
					(mid 59.476386 -385.31038)
					(end 60.106306 -385.31038)
				)
			)
		)
	)
	(zone
		(layer "B.Cu")
		(hatch none 0.5)
		(connect_pads
			(clearance 0)
		)
		(min_thickness 0.25)
		(keepout
			(tracks allowed)
			(vias allowed)
			(pads allowed)
			(copperpour allowed)
			(footprints not_allowed)
		)
		(placement
			(enabled no)
			(sheetname "")
		)
		(fill
			(thermal_gap 0.5)
			(thermal_bridge_width 0.5)
			(island_removal_mode 0)
		)
		(polygon
			(pts
				(arc
					(start 239.450118 -352.49993)
					(mid 236.650022 -349.699834)
					(end 233.849926 -352.49993)
				)
				(arc
					(start 233.849926 -352.49993)
					(mid 236.650022 -355.300026)
					(end 239.450118 -352.49993)
				)
			)
		)
	)
	(zone
		(layer "B.Cu")
		(hatch none 0.5)
		(connect_pads
			(clearance 0)
		)
		(min_thickness 0.25)
		(keepout
			(tracks not_allowed)
			(vias allowed)
			(pads allowed)
			(copperpour not_allowed)
			(footprints allowed)
		)
		(placement
			(enabled no)
			(sheetname "")
		)
		(fill
			(thermal_gap 0.5)
			(thermal_bridge_width 0.5)
			(island_removal_mode 0)
		)
		(polygon
			(pts
				(arc
					(start 145.33245 -31.67634)
					(mid 144.66443 -31.67634)
					(end 145.33245 -31.67634)
				)
			)
		)
	)
	(zone
		(layer "B.Cu")
		(hatch none 0.5)
		(connect_pads
			(clearance 0)
		)
		(min_thickness 0.25)
		(keepout
			(tracks not_allowed)
			(vias allowed)
			(pads allowed)
			(copperpour not_allowed)
			(footprints allowed)
		)
		(placement
			(enabled no)
			(sheetname "")
		)
		(fill
			(thermal_gap 0.5)
			(thermal_bridge_width 0.5)
			(island_removal_mode 0)
		)
		(polygon
			(pts
				(arc
					(start 318.90589 -394.385292)
					(mid 318.27597 -394.385292)
					(end 318.90589 -394.385292)
				)
			)
		)
	)
	(zone
		(layer "B.Cu")
		(hatch none 0.5)
		(connect_pads
			(clearance 0)
		)
		(min_thickness 0.25)
		(keepout
			(tracks allowed)
			(vias allowed)
			(pads allowed)
			(copperpour allowed)
			(footprints allowed)
		)
		(placement
			(enabled no)
			(sheetname "")
		)
		(fill
			(thermal_gap 0.5)
			(thermal_bridge_width 0.5)
			(island_removal_mode 0)
		)
		(polygon
			(pts
				(xy 155.9814 -409.046426) (xy 155.9814 -408.04211) (xy 157.358334 -408.04211) (xy 157.358334 -409.046426)
			)
		)
	)
	(zone
		(layer "B.Cu")
		(hatch none 0.5)
		(connect_pads
			(clearance 0)
		)
		(min_thickness 0.25)
		(keepout
			(tracks not_allowed)
			(vias allowed)
			(pads allowed)
			(copperpour not_allowed)
			(footprints allowed)
		)
		(placement
			(enabled no)
			(sheetname "")
		)
		(fill
			(thermal_gap 0.5)
			(thermal_bridge_width 0.5)
			(island_removal_mode 0)
		)
		(polygon
			(pts
				(arc
					(start 386.421884 -173.315122)
					(mid 389.521954 -176.415192)
					(end 392.622024 -173.315122)
				)
				(arc
					(start 392.622024 -173.315122)
					(mid 389.521954 -170.215052)
					(end 386.421884 -173.315122)
				)
			)
		)
	)
	(zone
		(layer "B.Cu")
		(hatch none 0.5)
		(connect_pads
			(clearance 0)
		)
		(min_thickness 0.25)
		(keepout
			(tracks allowed)
			(vias allowed)
			(pads allowed)
			(copperpour allowed)
			(footprints not_allowed)
		)
		(placement
			(enabled no)
			(sheetname "")
		)
		(fill
			(thermal_gap 0.5)
			(thermal_bridge_width 0.5)
			(island_removal_mode 0)
		)
		(polygon
			(pts
				(arc
					(start 182.550054 -435.600094)
					(mid 179.750212 -432.800252)
					(end 176.950116 -435.600094)
				)
				(arc
					(start 176.950116 -435.600094)
					(mid 179.750212 -438.40019)
					(end 182.550054 -435.600094)
				)
			)
		)
	)
	(zone
		(layer "B.Cu")
		(hatch none 0.5)
		(connect_pads
			(clearance 0)
		)
		(min_thickness 0.25)
		(keepout
			(tracks not_allowed)
			(vias allowed)
			(pads allowed)
			(copperpour not_allowed)
			(footprints allowed)
		)
		(placement
			(enabled no)
			(sheetname "")
		)
		(fill
			(thermal_gap 0.5)
			(thermal_bridge_width 0.5)
			(island_removal_mode 0)
		)
		(polygon
			(pts
				(arc
					(start 314.106052 -394.385292)
					(mid 313.476132 -394.385292)
					(end 314.106052 -394.385292)
				)
			)
		)
	)
	(zone
		(layer "B.Cu")
		(hatch none 0.5)
		(connect_pads
			(clearance 0)
		)
		(min_thickness 0.25)
		(keepout
			(tracks not_allowed)
			(vias allowed)
			(pads allowed)
			(copperpour not_allowed)
			(footprints allowed)
		)
		(placement
			(enabled no)
			(sheetname "")
		)
		(fill
			(thermal_gap 0.5)
			(thermal_bridge_width 0.5)
			(island_removal_mode 0)
		)
		(polygon
			(pts
				(arc
					(start 419.78199 -163.314888)
					(mid 422.88206 -166.414958)
					(end 425.981876 -163.314888)
				)
				(arc
					(start 425.981876 -163.314888)
					(mid 422.88206 -160.215072)
					(end 419.78199 -163.314888)
				)
			)
		)
	)
	(zone
		(layer "B.Cu")
		(hatch none 0.5)
		(connect_pads
			(clearance 0)
		)
		(min_thickness 0.25)
		(keepout
			(tracks not_allowed)
			(vias allowed)
			(pads allowed)
			(copperpour not_allowed)
			(footprints allowed)
		)
		(placement
			(enabled no)
			(sheetname "")
		)
		(fill
			(thermal_gap 0.5)
			(thermal_bridge_width 0.5)
			(island_removal_mode 0)
		)
		(polygon
			(pts
				(arc
					(start 49.350422 -392.429238)
					(mid 48.682402 -392.429238)
					(end 49.350422 -392.429238)
				)
			)
		)
	)
	(zone
		(layer "B.Cu")
		(hatch none 0.5)
		(connect_pads
			(clearance 0)
		)
		(min_thickness 0.25)
		(keepout
			(tracks allowed)
			(vias allowed)
			(pads allowed)
			(copperpour allowed)
			(footprints not_allowed)
		)
		(placement
			(enabled no)
			(sheetname "")
		)
		(fill
			(thermal_gap 0.5)
			(thermal_bridge_width 0.5)
			(island_removal_mode 0)
		)
		(polygon
			(pts
				(arc
					(start 77.829918 -304.790094)
					(mid 81.330038 -308.290214)
					(end 84.829904 -304.790094)
				)
				(arc
					(start 84.829904 -304.790094)
					(mid 81.330038 -301.290228)
					(end 77.829918 -304.790094)
				)
			)
		)
	)
	(zone
		(layer "B.Cu")
		(hatch none 0.5)
		(connect_pads
			(clearance 0)
		)
		(min_thickness 0.25)
		(keepout
			(tracks allowed)
			(vias allowed)
			(pads allowed)
			(copperpour allowed)
			(footprints allowed)
		)
		(placement
			(enabled no)
			(sheetname "")
		)
		(fill
			(thermal_gap 0.5)
			(thermal_bridge_width 0.5)
			(island_removal_mode 0)
		)
		(polygon
			(pts
				(xy 328.28738 -3.13944) (xy 328.28738 -1.31318) (xy 330.51496 -1.31318) (xy 330.51496 -3.13944)
			)
		)
	)
	(zone
		(layer "B.Cu")
		(hatch none 0.5)
		(connect_pads
			(clearance 0)
		)
		(min_thickness 0.25)
		(keepout
			(tracks allowed)
			(vias allowed)
			(pads allowed)
			(copperpour allowed)
			(footprints not_allowed)
		)
		(placement
			(enabled no)
			(sheetname "")
		)
		(fill
			(thermal_gap 0.5)
			(thermal_bridge_width 0.5)
			(island_removal_mode 0)
		)
		(polygon
			(pts
				(arc
					(start 1.999996 -22.29993)
					(mid 6.999986 -27.29992)
					(end 11.999976 -22.29993)
				)
				(arc
					(start 11.999976 -22.29993)
					(mid 6.999986 -17.29994)
					(end 1.999996 -22.29993)
				)
			)
		)
	)
	(zone
		(layer "B.Cu")
		(hatch none 0.5)
		(connect_pads
			(clearance 0)
		)
		(min_thickness 0.25)
		(keepout
			(tracks not_allowed)
			(vias allowed)
			(pads allowed)
			(copperpour not_allowed)
			(footprints allowed)
		)
		(placement
			(enabled no)
			(sheetname "")
		)
		(fill
			(thermal_gap 0.5)
			(thermal_bridge_width 0.5)
			(island_removal_mode 0)
		)
		(polygon
			(pts
				(arc
					(start 437.304942 -399.029936)
					(mid 435.440074 -397.165068)
					(end 433.574952 -399.029936)
				)
				(arc
					(start 433.574952 -399.029936)
					(mid 435.440074 -400.895058)
					(end 437.304942 -399.029936)
				)
			)
		)
	)
	(zone
		(layer "B.Cu")
		(hatch none 0.5)
		(connect_pads
			(clearance 0)
		)
		(min_thickness 0.25)
		(keepout
			(tracks allowed)
			(vias allowed)
			(pads allowed)
			(copperpour allowed)
			(footprints not_allowed)
		)
		(placement
			(enabled no)
			(sheetname "")
		)
		(fill
			(thermal_gap 0.5)
			(thermal_bridge_width 0.5)
			(island_removal_mode 0)
		)
		(polygon
			(pts
				(arc
					(start 239.450118 -272.50009)
					(mid 236.650022 -269.699994)
					(end 233.849926 -272.50009)
				)
				(arc
					(start 233.849926 -272.50009)
					(mid 236.650022 -275.300186)
					(end 239.450118 -272.50009)
				)
			)
		)
	)
	(zone
		(layer "B.Cu")
		(hatch none 0.5)
		(connect_pads
			(clearance 0)
		)
		(min_thickness 0.25)
		(keepout
			(tracks not_allowed)
			(vias allowed)
			(pads allowed)
			(copperpour not_allowed)
			(footprints allowed)
		)
		(placement
			(enabled no)
			(sheetname "")
		)
		(fill
			(thermal_gap 0.5)
			(thermal_bridge_width 0.5)
			(island_removal_mode 0)
		)
		(polygon
			(pts
				(arc
					(start 206.199994 -22.29993)
					(mid 203.400152 -19.500088)
					(end 200.600056 -22.29993)
				)
				(arc
					(start 200.600056 -22.29993)
					(mid 203.400152 -25.100026)
					(end 206.199994 -22.29993)
				)
			)
		)
	)
	(zone
		(layer "B.Cu")
		(hatch none 0.5)
		(connect_pads
			(clearance 0)
		)
		(min_thickness 0.25)
		(keepout
			(tracks not_allowed)
			(vias allowed)
			(pads allowed)
			(copperpour not_allowed)
			(footprints allowed)
		)
		(placement
			(enabled no)
			(sheetname "")
		)
		(fill
			(thermal_gap 0.5)
			(thermal_bridge_width 0.5)
			(island_removal_mode 0)
		)
		(polygon
			(pts
				(arc
					(start 109.105954 -274.08632)
					(mid 108.476034 -274.08632)
					(end 109.105954 -274.08632)
				)
			)
		)
	)
	(zone
		(layer "B.Cu")
		(hatch none 0.5)
		(connect_pads
			(clearance 0)
		)
		(min_thickness 0.25)
		(keepout
			(tracks not_allowed)
			(vias allowed)
			(pads allowed)
			(copperpour not_allowed)
			(footprints allowed)
		)
		(placement
			(enabled no)
			(sheetname "")
		)
		(fill
			(thermal_gap 0.5)
			(thermal_bridge_width 0.5)
			(island_removal_mode 0)
		)
		(polygon
			(pts
				(arc
					(start 25.592532 -421.266874)
					(mid 24.924512 -421.266874)
					(end 25.592532 -421.266874)
				)
			)
		)
	)
	(zone
		(layer "B.Cu")
		(hatch none 0.5)
		(connect_pads
			(clearance 0)
		)
		(min_thickness 0.25)
		(keepout
			(tracks not_allowed)
			(vias allowed)
			(pads allowed)
			(copperpour not_allowed)
			(footprints allowed)
		)
		(placement
			(enabled no)
			(sheetname "")
		)
		(fill
			(thermal_gap 0.5)
			(thermal_bridge_width 0.5)
			(island_removal_mode 0)
		)
		(polygon
			(pts
				(arc
					(start 344.036904 -436.889906)
					(mid 343.262712 -436.889906)
					(end 344.036904 -436.889906)
				)
			)
		)
	)
	(zone
		(layer "B.Cu")
		(hatch none 0.5)
		(connect_pads
			(clearance 0)
		)
		(min_thickness 0.25)
		(keepout
			(tracks allowed)
			(vias allowed)
			(pads allowed)
			(copperpour allowed)
			(footprints allowed)
		)
		(placement
			(enabled no)
			(sheetname "")
		)
		(fill
			(thermal_gap 0.5)
			(thermal_bridge_width 0.5)
			(island_removal_mode 0)
		)
		(polygon
			(pts
				(xy 416.70478 -194.29222) (xy 416.70478 -190.70574) (xy 419.5826 -190.70574) (xy 419.5826 -194.29222)
			)
		)
	)
	(zone
		(layer "B.Cu")
		(hatch none 0.5)
		(connect_pads
			(clearance 0)
		)
		(min_thickness 0.25)
		(keepout
			(tracks allowed)
			(vias allowed)
			(pads allowed)
			(copperpour allowed)
			(footprints allowed)
		)
		(placement
			(enabled no)
			(sheetname "")
		)
		(fill
			(thermal_gap 0.5)
			(thermal_bridge_width 0.5)
			(island_removal_mode 0)
		)
		(polygon
			(pts
				(xy 338.12734 4.34086) (xy 338.12734 6.3881) (xy 340.3981 6.3881) (xy 340.3981 4.34086)
			)
		)
	)
	(zone
		(layer "B.Cu")
		(hatch none 0.5)
		(connect_pads
			(clearance 0)
		)
		(min_thickness 0.25)
		(keepout
			(tracks allowed)
			(vias allowed)
			(pads allowed)
			(copperpour allowed)
			(footprints not_allowed)
		)
		(placement
			(enabled no)
			(sheetname "")
		)
		(fill
			(thermal_gap 0.5)
			(thermal_bridge_width 0.5)
			(island_removal_mode 0)
		)
		(polygon
			(pts
				(arc
					(start 191.363346 -74.767948)
					(mid 178.863498 -87.267796)
					(end 166.363396 -74.767948)
				)
				(arc
					(start 166.363396 -66.06794)
					(mid 178.863498 -53.567838)
					(end 191.363346 -66.06794)
				)
			)
		)
	)
	(zone
		(layer "B.Cu")
		(hatch none 0.5)
		(connect_pads
			(clearance 0)
		)
		(min_thickness 0.25)
		(keepout
			(tracks not_allowed)
			(vias allowed)
			(pads allowed)
			(copperpour not_allowed)
			(footprints allowed)
		)
		(placement
			(enabled no)
			(sheetname "")
		)
		(fill
			(thermal_gap 0.5)
			(thermal_bridge_width 0.5)
			(island_removal_mode 0)
		)
		(polygon
			(pts
				(arc
					(start 154.978354 -393.292838)
					(mid 154.310334 -393.292838)
					(end 154.978354 -393.292838)
				)
			)
		)
	)
	(zone
		(layer "B.Cu")
		(hatch none 0.5)
		(connect_pads
			(clearance 0)
		)
		(min_thickness 0.25)
		(keepout
			(tracks allowed)
			(vias allowed)
			(pads allowed)
			(copperpour allowed)
			(footprints not_allowed)
		)
		(placement
			(enabled no)
			(sheetname "")
		)
		(fill
			(thermal_gap 0.5)
			(thermal_bridge_width 0.5)
			(island_removal_mode 0)
		)
		(polygon
			(pts
				(xy 257.040126 -239.862106) (xy 257.040126 -202.362054) (xy 312.040016 -202.362054) (xy 312.040016 -239.862106)
			)
		)
	)
	(zone
		(layer "B.Cu")
		(hatch none 0.5)
		(connect_pads
			(clearance 0)
		)
		(min_thickness 0.25)
		(keepout
			(tracks not_allowed)
			(vias allowed)
			(pads allowed)
			(copperpour not_allowed)
			(footprints allowed)
		)
		(placement
			(enabled no)
			(sheetname "")
		)
		(fill
			(thermal_gap 0.5)
			(thermal_bridge_width 0.5)
			(island_removal_mode 0)
		)
		(polygon
			(pts
				(arc
					(start 56.55056 -392.429238)
					(mid 55.88254 -392.429238)
					(end 56.55056 -392.429238)
				)
			)
		)
	)
	(zone
		(layer "B.Cu")
		(hatch none 0.5)
		(connect_pads
			(clearance 0)
		)
		(min_thickness 0.25)
		(keepout
			(tracks not_allowed)
			(vias allowed)
			(pads allowed)
			(copperpour not_allowed)
			(footprints allowed)
		)
		(placement
			(enabled no)
			(sheetname "")
		)
		(fill
			(thermal_gap 0.5)
			(thermal_bridge_width 0.5)
			(island_removal_mode 0)
		)
		(polygon
			(pts
				(arc
					(start 355.636068 -273.27606)
					(mid 355.006148 -273.27606)
					(end 355.636068 -273.27606)
				)
			)
		)
	)
	(zone
		(layer "B.Cu")
		(hatch none 0.5)
		(connect_pads
			(clearance 0)
		)
		(min_thickness 0.25)
		(keepout
			(tracks not_allowed)
			(vias allowed)
			(pads allowed)
			(copperpour not_allowed)
			(footprints allowed)
		)
		(placement
			(enabled no)
			(sheetname "")
		)
		(fill
			(thermal_gap 0.5)
			(thermal_bridge_width 0.5)
			(island_removal_mode 0)
		)
		(polygon
			(pts
				(arc
					(start 384.1369 -439.0898)
					(mid 383.362708 -439.0898)
					(end 384.1369 -439.0898)
				)
			)
		)
	)
	(zone
		(layer "B.Cu")
		(hatch none 0.5)
		(connect_pads
			(clearance 0)
		)
		(min_thickness 0.25)
		(keepout
			(tracks not_allowed)
			(vias allowed)
			(pads allowed)
			(copperpour not_allowed)
			(footprints allowed)
		)
		(placement
			(enabled no)
			(sheetname "")
		)
		(fill
			(thermal_gap 0.5)
			(thermal_bridge_width 0.5)
			(island_removal_mode 0)
		)
		(polygon
			(pts
				(arc
					(start 43.82008 -404.789894)
					(mid 41.570148 -402.539962)
					(end 39.319962 -404.789894)
				)
				(arc
					(start 39.319962 -404.789894)
					(mid 41.570148 -407.04008)
					(end 43.82008 -404.789894)
				)
			)
		)
	)
	(zone
		(layer "B.Cu")
		(hatch none 0.5)
		(connect_pads
			(clearance 0)
		)
		(min_thickness 0.25)
		(keepout
			(tracks allowed)
			(vias allowed)
			(pads allowed)
			(copperpour allowed)
			(footprints not_allowed)
		)
		(placement
			(enabled no)
			(sheetname "")
		)
		(fill
			(thermal_gap 0.5)
			(thermal_bridge_width 0.5)
			(island_removal_mode 0)
		)
		(polygon
			(pts
				(arc
					(start 224.14992 -192.499996)
					(mid 236.650022 -205.000098)
					(end 249.150124 -192.499996)
				)
				(arc
					(start 249.150124 -192.499996)
					(mid 236.650022 -179.999894)
					(end 224.14992 -192.499996)
				)
			)
		)
	)
	(zone
		(layer "B.Cu")
		(hatch none 0.5)
		(connect_pads
			(clearance 0)
		)
		(min_thickness 0.25)
		(keepout
			(tracks not_allowed)
			(vias allowed)
			(pads allowed)
			(copperpour not_allowed)
			(footprints allowed)
		)
		(placement
			(enabled no)
			(sheetname "")
		)
		(fill
			(thermal_gap 0.5)
			(thermal_bridge_width 0.5)
			(island_removal_mode 0)
		)
		(polygon
			(pts
				(arc
					(start 315.036708 -436.889906)
					(mid 314.262516 -436.889906)
					(end 315.036708 -436.889906)
				)
			)
		)
	)
	(zone
		(layer "B.Cu")
		(hatch none 0.5)
		(connect_pads
			(clearance 0)
		)
		(min_thickness 0.25)
		(keepout
			(tracks not_allowed)
			(vias allowed)
			(pads allowed)
			(copperpour not_allowed)
			(footprints allowed)
		)
		(placement
			(enabled no)
			(sheetname "")
		)
		(fill
			(thermal_gap 0.5)
			(thermal_bridge_width 0.5)
			(island_removal_mode 0)
		)
		(polygon
			(pts
				(arc
					(start 25.846532 -427.752002)
					(mid 25.178512 -427.752002)
					(end 25.846532 -427.752002)
				)
			)
		)
	)
	(zone
		(layer "B.Cu")
		(hatch none 0.5)
		(connect_pads
			(clearance 0)
		)
		(min_thickness 0.25)
		(keepout
			(tracks allowed)
			(vias allowed)
			(pads allowed)
			(copperpour allowed)
			(footprints not_allowed)
		)
		(placement
			(enabled no)
			(sheetname "")
		)
		(fill
			(thermal_gap 0.5)
			(thermal_bridge_width 0.5)
			(island_removal_mode 0)
		)
		(polygon
			(pts
				(arc
					(start 9.800082 -22.29993)
					(mid 6.999986 -19.499834)
					(end 4.19989 -22.29993)
				)
				(arc
					(start 4.19989 -22.29993)
					(mid 6.999986 -25.100026)
					(end 9.800082 -22.29993)
				)
			)
		)
	)
	(zone
		(layer "B.Cu")
		(hatch none 0.5)
		(connect_pads
			(clearance 0)
		)
		(min_thickness 0.25)
		(keepout
			(tracks allowed)
			(vias allowed)
			(pads allowed)
			(copperpour allowed)
			(footprints allowed)
		)
		(placement
			(enabled no)
			(sheetname "")
		)
		(fill
			(thermal_gap 0.5)
			(thermal_bridge_width 0.5)
			(island_removal_mode 0)
		)
		(polygon
			(pts
				(xy 351.918524 -342.211152) (xy 351.918524 -344.370152) (xy 351.537524 -344.751152) (xy 348.743524 -344.751152)
				(xy 347.600524 -343.608152) (xy 347.600524 -340.687152) (xy 348.108524 -340.179152) (xy 349.886524 -340.179152)
			)
		)
	)
	(zone
		(layer "B.Cu")
		(hatch none 0.5)
		(connect_pads
			(clearance 0)
		)
		(min_thickness 0.25)
		(keepout
			(tracks allowed)
			(vias allowed)
			(pads allowed)
			(copperpour allowed)
			(footprints allowed)
		)
		(placement
			(enabled no)
			(sheetname "")
		)
		(fill
			(thermal_gap 0.5)
			(thermal_bridge_width 0.5)
			(island_removal_mode 0)
		)
		(polygon
			(pts
				(xy 372.159276 -417.428426) (xy 372.159276 -416.42411) (xy 373.53621 -416.42411) (xy 373.53621 -417.428426)
			)
		)
	)
	(zone
		(layer "B.Cu")
		(hatch none 0.5)
		(connect_pads
			(clearance 0)
		)
		(min_thickness 0.25)
		(keepout
			(tracks not_allowed)
			(vias allowed)
			(pads allowed)
			(copperpour not_allowed)
			(footprints allowed)
		)
		(placement
			(enabled no)
			(sheetname "")
		)
		(fill
			(thermal_gap 0.5)
			(thermal_bridge_width 0.5)
			(island_removal_mode 0)
		)
		(polygon
			(pts
				(arc
					(start 357.686102 -246.914162)
					(mid 357.056182 -246.914162)
					(end 357.686102 -246.914162)
				)
			)
		)
	)
	(zone
		(layer "B.Cu")
		(hatch none 0.5)
		(connect_pads
			(clearance 0)
		)
		(min_thickness 0.25)
		(keepout
			(tracks allowed)
			(vias allowed)
			(pads allowed)
			(copperpour allowed)
			(footprints not_allowed)
		)
		(placement
			(enabled no)
			(sheetname "")
		)
		(fill
			(thermal_gap 0.5)
			(thermal_bridge_width 0.5)
			(island_removal_mode 0)
		)
		(polygon
			(pts
				(arc
					(start 280.505662 -74.901806)
					(mid 293.0699 -87.259011)
					(end 305.50104 -74.767948)
				)
				(arc
					(start 305.493928 -66.538094)
					(mid 293.239615 -53.563259)
					(end 280.503122 -66.064892)
				)
			)
		)
	)
	(zone
		(layer "B.Cu")
		(hatch none 0.5)
		(connect_pads
			(clearance 0)
		)
		(min_thickness 0.25)
		(keepout
			(tracks not_allowed)
			(vias allowed)
			(pads allowed)
			(copperpour not_allowed)
			(footprints allowed)
		)
		(placement
			(enabled no)
			(sheetname "")
		)
		(fill
			(thermal_gap 0.5)
			(thermal_bridge_width 0.5)
			(island_removal_mode 0)
		)
		(polygon
			(pts
				(arc
					(start 356.746048 -248.534174)
					(mid 356.116128 -248.534174)
					(end 356.746048 -248.534174)
				)
			)
		)
	)
	(zone
		(layer "B.Cu")
		(hatch none 0.5)
		(connect_pads
			(clearance 0)
		)
		(min_thickness 0.25)
		(keepout
			(tracks not_allowed)
			(vias allowed)
			(pads allowed)
			(copperpour not_allowed)
			(footprints allowed)
		)
		(placement
			(enabled no)
			(sheetname "")
		)
		(fill
			(thermal_gap 0.5)
			(thermal_bridge_width 0.5)
			(island_removal_mode 0)
		)
		(polygon
			(pts
				(arc
					(start 113.612422 -431.360072)
					(mid 112.024922 -429.772572)
					(end 110.437422 -431.360072)
				)
				(arc
					(start 110.437422 -431.360072)
					(mid 112.024922 -432.947572)
					(end 113.612422 -431.360072)
				)
			)
		)
	)
	(zone
		(layer "B.Cu")
		(hatch none 0.5)
		(connect_pads
			(clearance 0)
		)
		(min_thickness 0.25)
		(keepout
			(tracks allowed)
			(vias allowed)
			(pads allowed)
			(copperpour allowed)
			(footprints not_allowed)
		)
		(placement
			(enabled no)
			(sheetname "")
		)
		(fill
			(thermal_gap 0.5)
			(thermal_bridge_width 0.5)
			(island_removal_mode 0)
		)
		(polygon
			(pts
				(arc
					(start 236.374432 -46.576488)
					(mid 245.040899 -45.591102)
					(end 247.655588 -37.269928)
				)
				(xy 232.244392 -37.269928)
				(arc
					(start 232.225596 -37.338508)
					(mid 221.352268 -47.772448)
					(end 236.374432 -46.576488)
				)
			)
		)
	)
	(zone
		(layer "B.Cu")
		(hatch none 0.5)
		(connect_pads
			(clearance 0)
		)
		(min_thickness 0.25)
		(keepout
			(tracks not_allowed)
			(vias allowed)
			(pads allowed)
			(copperpour not_allowed)
			(footprints allowed)
		)
		(placement
			(enabled no)
			(sheetname "")
		)
		(fill
			(thermal_gap 0.5)
			(thermal_bridge_width 0.5)
			(island_removal_mode 0)
		)
		(polygon
			(pts
				(arc
					(start 148.978112 -393.292838)
					(mid 148.310092 -393.292838)
					(end 148.978112 -393.292838)
				)
			)
		)
	)
	(zone
		(layer "B.Cu")
		(hatch none 0.5)
		(connect_pads
			(clearance 0)
		)
		(min_thickness 0.25)
		(keepout
			(tracks not_allowed)
			(vias allowed)
			(pads allowed)
			(copperpour not_allowed)
			(footprints allowed)
		)
		(placement
			(enabled no)
			(sheetname "")
		)
		(fill
			(thermal_gap 0.5)
			(thermal_bridge_width 0.5)
			(island_removal_mode 0)
		)
		(polygon
			(pts
				(arc
					(start 142.212314 -18.144744)
					(mid 141.544294 -18.144744)
					(end 142.212314 -18.144744)
				)
			)
		)
	)
	(zone
		(layer "B.Cu")
		(hatch none 0.5)
		(connect_pads
			(clearance 0)
		)
		(min_thickness 0.25)
		(keepout
			(tracks not_allowed)
			(vias allowed)
			(pads allowed)
			(copperpour not_allowed)
			(footprints allowed)
		)
		(placement
			(enabled no)
			(sheetname "")
		)
		(fill
			(thermal_gap 0.5)
			(thermal_bridge_width 0.5)
			(island_removal_mode 0)
		)
		(polygon
			(pts
				(arc
					(start 218.799918 -290.900104)
					(mid 221.899988 -294.000174)
					(end 225.000058 -290.900104)
				)
				(arc
					(start 225.000058 -290.900104)
					(mid 221.899988 -287.800034)
					(end 218.799918 -290.900104)
				)
			)
		)
	)
	(zone
		(layer "B.Cu")
		(hatch none 0.5)
		(connect_pads
			(clearance 0)
		)
		(min_thickness 0.25)
		(keepout
			(tracks not_allowed)
			(vias allowed)
			(pads allowed)
			(copperpour not_allowed)
			(footprints allowed)
		)
		(placement
			(enabled no)
			(sheetname "")
		)
		(fill
			(thermal_gap 0.5)
			(thermal_bridge_width 0.5)
			(island_removal_mode 0)
		)
		(polygon
			(pts
				(arc
					(start 336.03692 -436.889906)
					(mid 335.262728 -436.889906)
					(end 336.03692 -436.889906)
				)
			)
		)
	)
	(zone
		(layer "B.Cu")
		(hatch none 0.5)
		(connect_pads
			(clearance 0)
		)
		(min_thickness 0.25)
		(keepout
			(tracks allowed)
			(vias allowed)
			(pads allowed)
			(copperpour allowed)
			(footprints allowed)
		)
		(placement
			(enabled no)
			(sheetname "")
		)
		(fill
			(thermal_gap 0.5)
			(thermal_bridge_width 0.5)
			(island_removal_mode 0)
		)
		(polygon
			(pts
				(xy 115.577366 -169.441876) (xy 115.577366 -167.282876) (xy 115.958366 -166.901876) (xy 118.752366 -166.901876)
				(xy 119.895366 -168.044876) (xy 119.895366 -170.965876) (xy 119.387366 -171.473876) (xy 117.609366 -171.473876)
			)
		)
	)
	(zone
		(layer "B.Cu")
		(hatch none 0.5)
		(connect_pads
			(clearance 0)
		)
		(min_thickness 0.25)
		(keepout
			(tracks allowed)
			(vias allowed)
			(pads allowed)
			(copperpour allowed)
			(footprints not_allowed)
		)
		(placement
			(enabled no)
			(sheetname "")
		)
		(fill
			(thermal_gap 0.5)
			(thermal_bridge_width 0.5)
			(island_removal_mode 0)
		)
		(polygon
			(pts
				(arc
					(start 192.149984 -51.999896)
					(mid 204.650086 -64.499998)
					(end 217.149934 -51.999896)
				)
				(arc
					(start 217.149934 -51.999896)
					(mid 204.650086 -39.500048)
					(end 192.149984 -51.999896)
				)
			)
		)
	)
	(zone
		(layer "B.Cu")
		(hatch none 0.5)
		(connect_pads
			(clearance 0)
		)
		(min_thickness 0.25)
		(keepout
			(tracks not_allowed)
			(vias allowed)
			(pads allowed)
			(copperpour not_allowed)
			(footprints allowed)
		)
		(placement
			(enabled no)
			(sheetname "")
		)
		(fill
			(thermal_gap 0.5)
			(thermal_bridge_width 0.5)
			(island_removal_mode 0)
		)
		(polygon
			(pts
				(arc
					(start 386.136896 -436.889906)
					(mid 385.362704 -436.889906)
					(end 386.136896 -436.889906)
				)
			)
		)
	)
	(zone
		(layer "B.Cu")
		(hatch none 0.5)
		(connect_pads
			(clearance 0)
		)
		(min_thickness 0.25)
		(keepout
			(tracks not_allowed)
			(vias allowed)
			(pads allowed)
			(copperpour not_allowed)
			(footprints allowed)
		)
		(placement
			(enabled no)
			(sheetname "")
		)
		(fill
			(thermal_gap 0.5)
			(thermal_bridge_width 0.5)
			(island_removal_mode 0)
		)
		(polygon
			(pts
				(arc
					(start 170.699938 -160.50006)
					(mid 167.900096 -157.700218)
					(end 165.1 -160.50006)
				)
				(arc
					(start 165.1 -160.50006)
					(mid 167.900096 -163.300156)
					(end 170.699938 -160.50006)
				)
			)
		)
	)
	(zone
		(layer "B.Cu")
		(hatch none 0.5)
		(connect_pads
			(clearance 0)
		)
		(min_thickness 0.25)
		(keepout
			(tracks allowed)
			(vias allowed)
			(pads allowed)
			(copperpour allowed)
			(footprints not_allowed)
		)
		(placement
			(enabled no)
			(sheetname "")
		)
		(fill
			(thermal_gap 0.5)
			(thermal_bridge_width 0.5)
			(island_removal_mode 0)
		)
		(polygon
			(pts
				(arc
					(start 273.649948 -51.999896)
					(mid 268.649958 -46.999906)
					(end 263.649968 -51.999896)
				)
				(arc
					(start 263.649968 -51.999896)
					(mid 268.649958 -56.999886)
					(end 273.649948 -51.999896)
				)
			)
		)
	)
	(zone
		(layer "B.Cu")
		(hatch none 0.5)
		(connect_pads
			(clearance 0)
		)
		(min_thickness 0.25)
		(keepout
			(tracks not_allowed)
			(vias allowed)
			(pads allowed)
			(copperpour not_allowed)
			(footprints allowed)
		)
		(placement
			(enabled no)
			(sheetname "")
		)
		(fill
			(thermal_gap 0.5)
			(thermal_bridge_width 0.5)
			(island_removal_mode 0)
		)
		(polygon
			(pts
				(arc
					(start 16.288258 -104.6734)
					(mid 15.620238 -104.6734)
					(end 16.288258 -104.6734)
				)
			)
		)
	)
	(zone
		(layer "B.Cu")
		(hatch none 0.5)
		(connect_pads
			(clearance 0)
		)
		(min_thickness 0.25)
		(keepout
			(tracks not_allowed)
			(vias allowed)
			(pads allowed)
			(copperpour not_allowed)
			(footprints allowed)
		)
		(placement
			(enabled no)
			(sheetname "")
		)
		(fill
			(thermal_gap 0.5)
			(thermal_bridge_width 0.5)
			(island_removal_mode 0)
		)
		(polygon
			(pts
				(arc
					(start 394.13688 -436.889906)
					(mid 393.362688 -436.889906)
					(end 394.13688 -436.889906)
				)
			)
		)
	)
	(zone
		(layer "B.Cu")
		(hatch none 0.5)
		(connect_pads
			(clearance 0)
		)
		(min_thickness 0.25)
		(keepout
			(tracks allowed)
			(vias allowed)
			(pads allowed)
			(copperpour allowed)
			(footprints not_allowed)
		)
		(placement
			(enabled no)
			(sheetname "")
		)
		(fill
			(thermal_gap 0.5)
			(thermal_bridge_width 0.5)
			(island_removal_mode 0)
		)
		(polygon
			(pts
				(arc
					(start 92.782898 -45.449998)
					(mid 91.182952 -47.049944)
					(end 92.782898 -48.64989)
				)
				(arc
					(start 94.383098 -48.64989)
					(mid 95.983044 -47.049944)
					(end 94.383098 -45.449998)
				)
			)
		)
	)
	(zone
		(layer "B.Cu")
		(hatch none 0.5)
		(connect_pads
			(clearance 0)
		)
		(min_thickness 0.25)
		(keepout
			(tracks not_allowed)
			(vias allowed)
			(pads allowed)
			(copperpour not_allowed)
			(footprints allowed)
		)
		(placement
			(enabled no)
			(sheetname "")
		)
		(fill
			(thermal_gap 0.5)
			(thermal_bridge_width 0.5)
			(island_removal_mode 0)
		)
		(polygon
			(pts
				(arc
					(start 84.03717 -438.089802)
					(mid 83.262978 -438.089802)
					(end 84.03717 -438.089802)
				)
			)
		)
	)
	(zone
		(layer "B.Cu")
		(hatch none 0.5)
		(connect_pads
			(clearance 0)
		)
		(min_thickness 0.25)
		(keepout
			(tracks allowed)
			(vias allowed)
			(pads allowed)
			(copperpour allowed)
			(footprints not_allowed)
		)
		(placement
			(enabled no)
			(sheetname "")
		)
		(fill
			(thermal_gap 0.5)
			(thermal_bridge_width 0.5)
			(island_removal_mode 0)
		)
		(polygon
			(pts
				(arc
					(start 83.330034 -304.790094)
					(mid 81.330038 -302.790098)
					(end 79.330042 -304.790094)
				)
				(arc
					(start 79.330042 -304.790094)
					(mid 81.330038 -306.79009)
					(end 83.330034 -304.790094)
				)
			)
		)
	)
	(zone
		(layer "B.Cu")
		(hatch none 0.5)
		(connect_pads
			(clearance 0)
		)
		(min_thickness 0.25)
		(keepout
			(tracks not_allowed)
			(vias allowed)
			(pads allowed)
			(copperpour not_allowed)
			(footprints allowed)
		)
		(placement
			(enabled no)
			(sheetname "")
		)
		(fill
			(thermal_gap 0.5)
			(thermal_bridge_width 0.5)
			(island_removal_mode 0)
		)
		(polygon
			(pts
				(arc
					(start 56.58104 -167.135048)
					(mid 54.716172 -165.27018)
					(end 52.85105 -167.135048)
				)
				(arc
					(start 52.85105 -167.135048)
					(mid 54.716172 -169.00017)
					(end 56.58104 -167.135048)
				)
			)
		)
	)
	(zone
		(layer "B.Cu")
		(hatch none 0.5)
		(connect_pads
			(clearance 0)
		)
		(min_thickness 0.25)
		(keepout
			(tracks not_allowed)
			(vias allowed)
			(pads allowed)
			(copperpour not_allowed)
			(footprints allowed)
		)
		(placement
			(enabled no)
			(sheetname "")
		)
		(fill
			(thermal_gap 0.5)
			(thermal_bridge_width 0.5)
			(island_removal_mode 0)
		)
		(polygon
			(pts
				(arc
					(start 137.03935 -23.016972)
					(mid 136.37133 -23.016972)
					(end 137.03935 -23.016972)
				)
			)
		)
	)
	(zone
		(layer "B.Cu")
		(hatch none 0.5)
		(connect_pads
			(clearance 0)
		)
		(min_thickness 0.25)
		(keepout
			(tracks allowed)
			(vias allowed)
			(pads allowed)
			(copperpour allowed)
			(footprints not_allowed)
		)
		(placement
			(enabled no)
			(sheetname "")
		)
		(fill
			(thermal_gap 0.5)
			(thermal_bridge_width 0.5)
			(island_removal_mode 0)
		)
		(polygon
			(pts
				(arc
					(start 386.970016 -304.790094)
					(mid 390.470136 -308.290214)
					(end 393.970002 -304.790094)
				)
				(arc
					(start 393.970002 -304.790094)
					(mid 390.470136 -301.290228)
					(end 386.970016 -304.790094)
				)
			)
		)
	)
	(zone
		(layer "B.Cu")
		(hatch none 0.5)
		(connect_pads
			(clearance 0)
		)
		(min_thickness 0.25)
		(keepout
			(tracks allowed)
			(vias allowed)
			(pads allowed)
			(copperpour allowed)
			(footprints allowed)
		)
		(placement
			(enabled no)
			(sheetname "")
		)
		(fill
			(thermal_gap 0.5)
			(thermal_bridge_width 0.5)
			(island_removal_mode 0)
		)
		(polygon
			(pts
				(xy 183.192166 -353.572064) (xy 183.192166 -355.731064) (xy 182.811166 -356.112064) (xy 180.017166 -356.112064)
				(xy 178.874166 -354.969064) (xy 178.874166 -352.048064) (xy 179.382166 -351.540064) (xy 181.160166 -351.540064)
			)
		)
	)
	(zone
		(layer "B.Cu")
		(hatch none 0.5)
		(connect_pads
			(clearance 0)
		)
		(min_thickness 0.25)
		(keepout
			(tracks allowed)
			(vias allowed)
			(pads allowed)
			(copperpour allowed)
			(footprints allowed)
		)
		(placement
			(enabled no)
			(sheetname "")
		)
		(fill
			(thermal_gap 0.5)
			(thermal_bridge_width 0.5)
			(island_removal_mode 0)
		)
		(polygon
			(pts
				(xy 58.249058 -409.046426) (xy 58.249058 -408.04211) (xy 59.625992 -408.04211) (xy 59.625992 -409.046426)
			)
		)
	)
	(zone
		(layer "B.Cu")
		(hatch none 0.5)
		(connect_pads
			(clearance 0)
		)
		(min_thickness 0.25)
		(keepout
			(tracks not_allowed)
			(vias allowed)
			(pads allowed)
			(copperpour not_allowed)
			(footprints allowed)
		)
		(placement
			(enabled no)
			(sheetname "")
		)
		(fill
			(thermal_gap 0.5)
			(thermal_bridge_width 0.5)
			(island_removal_mode 0)
		)
		(polygon
			(pts
				(arc
					(start 443.816994 -351.415096)
					(mid 441.952126 -349.550228)
					(end 440.087004 -351.415096)
				)
				(arc
					(start 440.087004 -351.415096)
					(mid 441.952126 -353.280218)
					(end 443.816994 -351.415096)
				)
			)
		)
	)
	(zone
		(layer "B.Cu")
		(hatch none 0.5)
		(connect_pads
			(clearance 0)
		)
		(min_thickness 0.25)
		(keepout
			(tracks allowed)
			(vias allowed)
			(pads allowed)
			(copperpour allowed)
			(footprints not_allowed)
		)
		(placement
			(enabled no)
			(sheetname "")
		)
		(fill
			(thermal_gap 0.5)
			(thermal_bridge_width 0.5)
			(island_removal_mode 0)
		)
		(polygon
			(pts
				(arc
					(start 8.73506 -389.439912)
					(mid 6.870192 -387.575044)
					(end 5.00507 -389.439912)
				)
				(arc
					(start 5.00507 -389.439912)
					(mid 6.870192 -391.305034)
					(end 8.73506 -389.439912)
				)
			)
		)
	)
	(zone
		(layer "B.Cu")
		(hatch none 0.5)
		(connect_pads
			(clearance 0)
		)
		(min_thickness 0.25)
		(keepout
			(tracks not_allowed)
			(vias allowed)
			(pads allowed)
			(copperpour not_allowed)
			(footprints allowed)
		)
		(placement
			(enabled no)
			(sheetname "")
		)
		(fill
			(thermal_gap 0.5)
			(thermal_bridge_width 0.5)
			(island_removal_mode 0)
		)
		(polygon
			(pts
				(arc
					(start 61.350652 -392.429238)
					(mid 60.682632 -392.429238)
					(end 61.350652 -392.429238)
				)
			)
		)
	)
	(zone
		(layer "B.Cu")
		(hatch none 0.5)
		(connect_pads
			(clearance 0)
		)
		(min_thickness 0.25)
		(keepout
			(tracks not_allowed)
			(vias allowed)
			(pads allowed)
			(copperpour not_allowed)
			(footprints allowed)
		)
		(placement
			(enabled no)
			(sheetname "")
		)
		(fill
			(thermal_gap 0.5)
			(thermal_bridge_width 0.5)
			(island_removal_mode 0)
		)
		(polygon
			(pts
				(arc
					(start 130.1369 -438.089802)
					(mid 129.362708 -438.089802)
					(end 130.1369 -438.089802)
				)
			)
		)
	)
	(zone
		(layer "B.Cu")
		(hatch none 0.5)
		(connect_pads
			(clearance 0)
		)
		(min_thickness 0.25)
		(keepout
			(tracks not_allowed)
			(vias allowed)
			(pads allowed)
			(copperpour not_allowed)
			(footprints allowed)
		)
		(placement
			(enabled no)
			(sheetname "")
		)
		(fill
			(thermal_gap 0.5)
			(thermal_bridge_width 0.5)
			(island_removal_mode 0)
		)
		(polygon
			(pts
				(arc
					(start 120.54967 -246.10441)
					(mid 119.91975 -246.10441)
					(end 120.54967 -246.10441)
				)
			)
		)
	)
	(zone
		(layer "B.Cu")
		(hatch none 0.5)
		(connect_pads
			(clearance 0)
		)
		(min_thickness 0.25)
		(keepout
			(tracks allowed)
			(vias allowed)
			(pads allowed)
			(copperpour allowed)
			(footprints not_allowed)
		)
		(placement
			(enabled no)
			(sheetname "")
		)
		(fill
			(thermal_gap 0.5)
			(thermal_bridge_width 0.5)
			(island_removal_mode 0)
		)
		(polygon
			(pts
				(arc
					(start 464.25993 -160.50006)
					(mid 461.460088 -157.700218)
					(end 458.659992 -160.50006)
				)
				(arc
					(start 458.659992 -160.50006)
					(mid 461.460088 -163.300156)
					(end 464.25993 -160.50006)
				)
			)
		)
	)
	(zone
		(layer "B.Cu")
		(hatch none 0.5)
		(connect_pads
			(clearance 0)
		)
		(min_thickness 0.25)
		(keepout
			(tracks not_allowed)
			(vias allowed)
			(pads allowed)
			(copperpour not_allowed)
			(footprints allowed)
		)
		(placement
			(enabled no)
			(sheetname "")
		)
		(fill
			(thermal_gap 0.5)
			(thermal_bridge_width 0.5)
			(island_removal_mode 0)
		)
		(polygon
			(pts
				(arc
					(start 126.18974 -247.724422)
					(mid 125.55982 -247.724422)
					(end 126.18974 -247.724422)
				)
			)
		)
	)
	(zone
		(layer "B.Cu")
		(hatch none 0.5)
		(connect_pads
			(clearance 0)
		)
		(min_thickness 0.25)
		(keepout
			(tracks not_allowed)
			(vias allowed)
			(pads allowed)
			(copperpour not_allowed)
			(footprints allowed)
		)
		(placement
			(enabled no)
			(sheetname "")
		)
		(fill
			(thermal_gap 0.5)
			(thermal_bridge_width 0.5)
			(island_removal_mode 0)
		)
		(polygon
			(pts
				(arc
					(start 10.920476 -425.887642)
					(mid 10.252456 -425.887642)
					(end 10.920476 -425.887642)
				)
			)
		)
	)
	(zone
		(layer "B.Cu")
		(hatch none 0.5)
		(connect_pads
			(clearance 0)
		)
		(min_thickness 0.25)
		(keepout
			(tracks not_allowed)
			(vias allowed)
			(pads allowed)
			(copperpour not_allowed)
			(footprints allowed)
		)
		(placement
			(enabled no)
			(sheetname "")
		)
		(fill
			(thermal_gap 0.5)
			(thermal_bridge_width 0.5)
			(island_removal_mode 0)
		)
		(polygon
			(pts
				(arc
					(start 48.150526 -392.429238)
					(mid 47.482506 -392.429238)
					(end 48.150526 -392.429238)
				)
			)
		)
	)
	(zone
		(layer "B.Cu")
		(hatch none 0.5)
		(connect_pads
			(clearance 0)
		)
		(min_thickness 0.25)
		(keepout
			(tracks allowed)
			(vias allowed)
			(pads allowed)
			(copperpour allowed)
			(footprints not_allowed)
		)
		(placement
			(enabled no)
			(sheetname "")
		)
		(fill
			(thermal_gap 0.5)
			(thermal_bridge_width 0.5)
			(island_removal_mode 0)
		)
		(polygon
			(pts
				(arc
					(start 31.070042 -376.489976)
					(mid 35.070034 -380.489968)
					(end 39.070026 -376.489976)
				)
				(arc
					(start 39.070026 -376.489976)
					(mid 35.070034 -372.489984)
					(end 31.070042 -376.489976)
				)
			)
		)
	)
	(zone
		(layer "B.Cu")
		(hatch none 0.5)
		(connect_pads
			(clearance 0)
		)
		(min_thickness 0.25)
		(keepout
			(tracks not_allowed)
			(vias allowed)
			(pads allowed)
			(copperpour not_allowed)
			(footprints allowed)
		)
		(placement
			(enabled no)
			(sheetname "")
		)
		(fill
			(thermal_gap 0.5)
			(thermal_bridge_width 0.5)
			(island_removal_mode 0)
		)
		(polygon
			(pts
				(arc
					(start 319.317116 -344.814906)
					(mid 317.452248 -342.950038)
					(end 315.587126 -344.814906)
				)
				(arc
					(start 315.587126 -344.814906)
					(mid 317.452248 -346.680028)
					(end 319.317116 -344.814906)
				)
			)
		)
	)
	(zone
		(layer "B.Cu")
		(hatch none 0.5)
		(connect_pads
			(clearance 0)
		)
		(min_thickness 0.25)
		(keepout
			(tracks not_allowed)
			(vias allowed)
			(pads allowed)
			(copperpour not_allowed)
			(footprints allowed)
		)
		(placement
			(enabled no)
			(sheetname "")
		)
		(fill
			(thermal_gap 0.5)
			(thermal_bridge_width 0.5)
			(island_removal_mode 0)
		)
		(polygon
			(pts
				(arc
					(start 106.755946 -273.276314)
					(mid 106.126026 -273.276314)
					(end 106.755946 -273.276314)
				)
			)
		)
	)
	(zone
		(layer "B.Cu")
		(hatch none 0.5)
		(connect_pads
			(clearance 0)
		)
		(min_thickness 0.25)
		(keepout
			(tracks not_allowed)
			(vias allowed)
			(pads allowed)
			(copperpour not_allowed)
			(footprints allowed)
		)
		(placement
			(enabled no)
			(sheetname "")
		)
		(fill
			(thermal_gap 0.5)
			(thermal_bridge_width 0.5)
			(island_removal_mode 0)
		)
		(polygon
			(pts
				(arc
					(start 58.10631 -386.003292)
					(mid 57.47639 -386.003292)
					(end 58.10631 -386.003292)
				)
			)
		)
	)
	(zone
		(layer "B.Cu")
		(hatch none 0.5)
		(connect_pads
			(clearance 0)
		)
		(min_thickness 0.25)
		(keepout
			(tracks allowed)
			(vias allowed)
			(pads allowed)
			(copperpour allowed)
			(footprints allowed)
		)
		(placement
			(enabled no)
			(sheetname "")
		)
		(fill
			(thermal_gap 0.5)
			(thermal_bridge_width 0.5)
			(island_removal_mode 0)
		)
		(polygon
			(pts
				(xy 355.175566 -393.293854) (xy 355.175566 -391.776966) (xy 355.1682 -391.7696) (xy 355.1682 -391.258806)
				(xy 354.621846 -390.712452) (xy 353.341432 -390.712452) (xy 353.1235 -390.930384) (xy 337.123024 -390.930384)
				(xy 336.572606 -391.480802) (xy 336.572606 -393.293854)
			)
		)
	)
	(zone
		(layer "B.Cu")
		(hatch none 0.5)
		(connect_pads
			(clearance 0)
		)
		(min_thickness 0.25)
		(keepout
			(tracks not_allowed)
			(vias allowed)
			(pads allowed)
			(copperpour not_allowed)
			(footprints allowed)
		)
		(placement
			(enabled no)
			(sheetname "")
		)
		(fill
			(thermal_gap 0.5)
			(thermal_bridge_width 0.5)
			(island_removal_mode 0)
		)
		(polygon
			(pts
				(xy 378.423678 -139.867132) (xy 380.892304 -139.867132) (xy 380.892304 -144.855184) (xy 375.904252 -144.855184)
				(xy 375.904252 -139.867132) (xy 378.398278 -139.867132) (xy 378.398278 -140.100558) (xy 376.137678 -140.100558)
				(xy 376.137678 -144.621758) (xy 380.658878 -144.621758) (xy 380.658878 -140.100558) (xy 378.423678 -140.100558)
			)
		)
	)
	(zone
		(layer "B.Cu")
		(hatch none 0.5)
		(connect_pads
			(clearance 0)
		)
		(min_thickness 0.25)
		(keepout
			(tracks not_allowed)
			(vias allowed)
			(pads allowed)
			(copperpour not_allowed)
			(footprints allowed)
		)
		(placement
			(enabled no)
			(sheetname "")
		)
		(fill
			(thermal_gap 0.5)
			(thermal_bridge_width 0.5)
			(island_removal_mode 0)
		)
		(polygon
			(pts
				(arc
					(start 76.037186 -438.089802)
					(mid 75.262994 -438.089802)
					(end 76.037186 -438.089802)
				)
			)
		)
	)
	(zone
		(layer "B.Cu")
		(hatch none 0.5)
		(connect_pads
			(clearance 0)
		)
		(min_thickness 0.25)
		(keepout
			(tracks allowed)
			(vias allowed)
			(pads allowed)
			(copperpour allowed)
			(footprints not_allowed)
		)
		(placement
			(enabled no)
			(sheetname "")
		)
		(fill
			(thermal_gap 0.5)
			(thermal_bridge_width 0.5)
			(island_removal_mode 0)
		)
		(polygon
			(pts
				(arc
					(start 369.15471 -427.892718)
					(mid 378.112986 -431.40888)
					(end 377.21032 -440.989974)
				)
				(arc
					(start 357.080058 -440.989974)
					(mid 352.422785 -424.581969)
					(end 369.15471 -427.892718)
				)
			)
		)
	)
	(zone
		(layer "B.Cu")
		(hatch none 0.5)
		(connect_pads
			(clearance 0)
		)
		(min_thickness 0.25)
		(keepout
			(tracks allowed)
			(vias allowed)
			(pads allowed)
			(copperpour allowed)
			(footprints allowed)
		)
		(placement
			(enabled no)
			(sheetname "")
		)
		(fill
			(thermal_gap 0.5)
			(thermal_bridge_width 0.5)
			(island_removal_mode 0)
		)
		(polygon
			(pts
				(xy 234.00004 -402.689568) (xy 234.00004 -401.685252) (xy 234.693206 -401.685252) (xy 234.693206 -402.689568)
			)
		)
	)
	(zone
		(layer "B.Cu")
		(hatch none 0.5)
		(connect_pads
			(clearance 0)
		)
		(min_thickness 0.25)
		(keepout
			(tracks not_allowed)
			(vias allowed)
			(pads allowed)
			(copperpour not_allowed)
			(footprints allowed)
		)
		(placement
			(enabled no)
			(sheetname "")
		)
		(fill
			(thermal_gap 0.5)
			(thermal_bridge_width 0.5)
			(island_removal_mode 0)
		)
		(polygon
			(pts
				(arc
					(start 409.7782 -401.674838)
					(mid 409.11018 -401.674838)
					(end 409.7782 -401.674838)
				)
			)
		)
	)
	(zone
		(layer "B.Cu")
		(hatch none 0.5)
		(connect_pads
			(clearance 0)
		)
		(min_thickness 0.25)
		(keepout
			(tracks not_allowed)
			(vias allowed)
			(pads allowed)
			(copperpour not_allowed)
			(footprints allowed)
		)
		(placement
			(enabled no)
			(sheetname "")
		)
		(fill
			(thermal_gap 0.5)
			(thermal_bridge_width 0.5)
			(island_removal_mode 0)
		)
		(polygon
			(pts
				(arc
					(start 54.150514 -393.292838)
					(mid 53.482494 -393.292838)
					(end 54.150514 -393.292838)
				)
			)
		)
	)
	(zone
		(layer "B.Cu")
		(hatch none 0.5)
		(connect_pads
			(clearance 0)
		)
		(min_thickness 0.25)
		(keepout
			(tracks not_allowed)
			(vias allowed)
			(pads allowed)
			(copperpour not_allowed)
			(footprints allowed)
		)
		(placement
			(enabled no)
			(sheetname "")
		)
		(fill
			(thermal_gap 0.5)
			(thermal_bridge_width 0.5)
			(island_removal_mode 0)
		)
		(polygon
			(pts
				(arc
					(start 317.705994 -394.385292)
					(mid 317.076074 -394.385292)
					(end 317.705994 -394.385292)
				)
			)
		)
	)
	(zone
		(layer "B.Cu")
		(hatch none 0.5)
		(connect_pads
			(clearance 0)
		)
		(min_thickness 0.25)
		(keepout
			(tracks not_allowed)
			(vias allowed)
			(pads allowed)
			(copperpour not_allowed)
			(footprints allowed)
		)
		(placement
			(enabled no)
			(sheetname "")
		)
		(fill
			(thermal_gap 0.5)
			(thermal_bridge_width 0.5)
			(island_removal_mode 0)
		)
		(polygon
			(pts
				(arc
					(start 319.70599 -393.69238)
					(mid 319.07607 -393.69238)
					(end 319.70599 -393.69238)
				)
			)
		)
	)
	(zone
		(layer "B.Cu")
		(hatch none 0.5)
		(connect_pads
			(clearance 0)
		)
		(min_thickness 0.25)
		(keepout
			(tracks allowed)
			(vias allowed)
			(pads allowed)
			(copperpour allowed)
			(footprints not_allowed)
		)
		(placement
			(enabled no)
			(sheetname "")
		)
		(fill
			(thermal_gap 0.5)
			(thermal_bridge_width 0.5)
			(island_removal_mode 0)
		)
		(polygon
			(pts
				(arc
					(start 270.625062 -360.764074)
					(mid 258.125214 -348.264226)
					(end 245.625112 -360.764074)
				)
				(arc
					(start 245.625112 -360.764074)
					(mid 258.125214 -373.264176)
					(end 270.625062 -360.764074)
				)
			)
		)
	)
	(zone
		(layer "B.Cu")
		(hatch none 0.5)
		(connect_pads
			(clearance 0)
		)
		(min_thickness 0.25)
		(keepout
			(tracks not_allowed)
			(vias allowed)
			(pads allowed)
			(copperpour not_allowed)
			(footprints allowed)
		)
		(placement
			(enabled no)
			(sheetname "")
		)
		(fill
			(thermal_gap 0.5)
			(thermal_bridge_width 0.5)
			(island_removal_mode 0)
		)
		(polygon
			(pts
				(arc
					(start 197.985888 -351.825052)
					(mid 201.085958 -354.925122)
					(end 204.186028 -351.825052)
				)
				(arc
					(start 204.186028 -351.825052)
					(mid 201.085958 -348.724982)
					(end 197.985888 -351.825052)
				)
			)
		)
	)
	(zone
		(layer "B.Cu")
		(hatch none 0.5)
		(connect_pads
			(clearance 0)
		)
		(min_thickness 0.25)
		(keepout
			(tracks allowed)
			(vias allowed)
			(pads allowed)
			(copperpour allowed)
			(footprints allowed)
		)
		(placement
			(enabled no)
			(sheetname "")
		)
		(fill
			(thermal_gap 0.5)
			(thermal_bridge_width 0.5)
			(island_removal_mode 0)
		)
		(polygon
			(pts
				(xy 246.818404 -50.01514) (xy 246.818404 -53.758846) (xy 243.606574 -53.758846) (xy 243.606574 -50.01514)
			)
		)
	)
	(zone
		(layer "B.Cu")
		(hatch none 0.5)
		(connect_pads
			(clearance 0)
		)
		(min_thickness 0.25)
		(keepout
			(tracks not_allowed)
			(vias allowed)
			(pads allowed)
			(copperpour not_allowed)
			(footprints allowed)
		)
		(placement
			(enabled no)
			(sheetname "")
		)
		(fill
			(thermal_gap 0.5)
			(thermal_bridge_width 0.5)
			(island_removal_mode 0)
		)
		(polygon
			(pts
				(arc
					(start 318.506094 -393.69238)
					(mid 317.876174 -393.69238)
					(end 318.506094 -393.69238)
				)
			)
		)
	)
	(zone
		(layer "B.Cu")
		(hatch none 0.5)
		(connect_pads
			(clearance 0)
		)
		(min_thickness 0.25)
		(keepout
			(tracks allowed)
			(vias allowed)
			(pads allowed)
			(copperpour allowed)
			(footprints allowed)
		)
		(placement
			(enabled no)
			(sheetname "")
		)
		(fill
			(thermal_gap 0.5)
			(thermal_bridge_width 0.5)
			(island_removal_mode 0)
		)
		(polygon
			(pts
				(xy 22.53234 -194.20332) (xy 22.53234 -193.15176) (xy 24.6126 -193.15176) (xy 24.6126 -194.20332)
			)
		)
	)
	(zone
		(layer "B.Cu")
		(hatch none 0.5)
		(connect_pads
			(clearance 0)
		)
		(min_thickness 0.25)
		(keepout
			(tracks not_allowed)
			(vias allowed)
			(pads allowed)
			(copperpour not_allowed)
			(footprints allowed)
		)
		(placement
			(enabled no)
			(sheetname "")
		)
		(fill
			(thermal_gap 0.5)
			(thermal_bridge_width 0.5)
			(island_removal_mode 0)
		)
		(polygon
			(pts
				(arc
					(start 322.506086 -394.385292)
					(mid 321.876166 -394.385292)
					(end 322.506086 -394.385292)
				)
			)
		)
	)
	(zone
		(layer "B.Cu")
		(hatch none 0.5)
		(connect_pads
			(clearance 0)
		)
		(min_thickness 0.25)
		(keepout
			(tracks allowed)
			(vias allowed)
			(pads allowed)
			(copperpour allowed)
			(footprints not_allowed)
		)
		(placement
			(enabled no)
			(sheetname "")
		)
		(fill
			(thermal_gap 0.5)
			(thermal_bridge_width 0.5)
			(island_removal_mode 0)
		)
		(polygon
			(pts
				(arc
					(start 72.63003 -258.890008)
					(mid 69.830188 -256.090166)
					(end 67.030092 -258.890008)
				)
				(arc
					(start 67.030092 -258.890008)
					(mid 69.830188 -261.690104)
					(end 72.63003 -258.890008)
				)
			)
		)
	)
	(zone
		(layer "B.Cu")
		(hatch none 0.5)
		(connect_pads
			(clearance 0)
		)
		(min_thickness 0.25)
		(keepout
			(tracks not_allowed)
			(vias allowed)
			(pads allowed)
			(copperpour not_allowed)
			(footprints allowed)
		)
		(placement
			(enabled no)
			(sheetname "")
		)
		(fill
			(thermal_gap 0.5)
			(thermal_bridge_width 0.5)
			(island_removal_mode 0)
		)
		(polygon
			(pts
				(arc
					(start 59.036966 -438.089802)
					(mid 58.262774 -438.089802)
					(end 59.036966 -438.089802)
				)
			)
		)
	)
	(zone
		(layer "B.Cu")
		(hatch none 0.5)
		(connect_pads
			(clearance 0)
		)
		(min_thickness 0.25)
		(keepout
			(tracks allowed)
			(vias allowed)
			(pads allowed)
			(copperpour allowed)
			(footprints allowed)
		)
		(placement
			(enabled no)
			(sheetname "")
		)
		(fill
			(thermal_gap 0.5)
			(thermal_bridge_width 0.5)
			(island_removal_mode 0)
		)
		(polygon
			(pts
				(xy 223.33204 -402.689568) (xy 223.33204 -401.685252) (xy 224.025206 -401.685252) (xy 224.025206 -402.689568)
			)
		)
	)
	(zone
		(layer "B.Cu")
		(hatch none 0.5)
		(connect_pads
			(clearance 0)
		)
		(min_thickness 0.25)
		(keepout
			(tracks allowed)
			(vias allowed)
			(pads allowed)
			(copperpour allowed)
			(footprints allowed)
		)
		(placement
			(enabled no)
			(sheetname "")
		)
		(fill
			(thermal_gap 0.5)
			(thermal_bridge_width 0.5)
			(island_removal_mode 0)
		)
		(polygon
			(pts
				(xy 73.794366 -175.283876) (xy 73.794366 -173.124876) (xy 74.175366 -172.743876) (xy 76.969366 -172.743876)
				(xy 78.112366 -173.886876) (xy 78.112366 -176.807876) (xy 77.604366 -177.315876) (xy 75.826366 -177.315876)
			)
		)
	)
	(zone
		(layer "B.Cu")
		(hatch none 0.5)
		(connect_pads
			(clearance 0)
		)
		(min_thickness 0.25)
		(keepout
			(tracks not_allowed)
			(vias allowed)
			(pads allowed)
			(copperpour not_allowed)
			(footprints allowed)
		)
		(placement
			(enabled no)
			(sheetname "")
		)
		(fill
			(thermal_gap 0.5)
			(thermal_bridge_width 0.5)
			(island_removal_mode 0)
		)
		(polygon
			(pts
				(arc
					(start 7.999984 -435.600094)
					(mid 12.999974 -440.600084)
					(end 17.999964 -435.600094)
				)
				(arc
					(start 17.999964 -435.600094)
					(mid 12.999974 -430.600104)
					(end 7.999984 -435.600094)
				)
			)
		)
	)
	(zone
		(layer "B.Cu")
		(hatch none 0.5)
		(connect_pads
			(clearance 0)
		)
		(min_thickness 0.25)
		(keepout
			(tracks allowed)
			(vias allowed)
			(pads allowed)
			(copperpour allowed)
			(footprints not_allowed)
		)
		(placement
			(enabled no)
			(sheetname "")
		)
		(fill
			(thermal_gap 0.5)
			(thermal_bridge_width 0.5)
			(island_removal_mode 0)
		)
		(polygon
			(pts
				(arc
					(start 84.12988 -212.989922)
					(mid 81.330038 -210.19008)
					(end 78.529942 -212.989922)
				)
				(arc
					(start 78.529942 -212.989922)
					(mid 81.330038 -215.790018)
					(end 84.12988 -212.989922)
				)
			)
		)
	)
	(zone
		(layer "B.Cu")
		(hatch none 0.5)
		(connect_pads
			(clearance 0)
		)
		(min_thickness 0.25)
		(keepout
			(tracks not_allowed)
			(vias allowed)
			(pads allowed)
			(copperpour not_allowed)
			(footprints allowed)
		)
		(placement
			(enabled no)
			(sheetname "")
		)
		(fill
			(thermal_gap 0.5)
			(thermal_bridge_width 0.5)
			(island_removal_mode 0)
		)
		(polygon
			(pts
				(arc
					(start 166.99992 -404.789894)
					(mid 170.999912 -408.789886)
					(end 174.999904 -404.789894)
				)
				(arc
					(start 174.999904 -404.789894)
					(mid 170.999912 -400.789902)
					(end 166.99992 -404.789894)
				)
			)
		)
	)
	(zone
		(layer "B.Cu")
		(hatch none 0.5)
		(connect_pads
			(clearance 0)
		)
		(min_thickness 0.25)
		(keepout
			(tracks not_allowed)
			(vias allowed)
			(pads allowed)
			(copperpour not_allowed)
			(footprints allowed)
		)
		(placement
			(enabled no)
			(sheetname "")
		)
		(fill
			(thermal_gap 0.5)
			(thermal_bridge_width 0.5)
			(island_removal_mode 0)
		)
		(polygon
			(pts
				(arc
					(start 418.178234 -400.811238)
					(mid 417.510214 -400.811238)
					(end 418.178234 -400.811238)
				)
			)
		)
	)
	(zone
		(layer "B.Cu")
		(hatch none 0.5)
		(connect_pads
			(clearance 0)
		)
		(min_thickness 0.25)
		(keepout
			(tracks allowed)
			(vias allowed)
			(pads allowed)
			(copperpour allowed)
			(footprints not_allowed)
		)
		(placement
			(enabled no)
			(sheetname "")
		)
		(fill
			(thermal_gap 0.5)
			(thermal_bridge_width 0.5)
			(island_removal_mode 0)
		)
		(polygon
			(pts
				(arc
					(start 319.317116 -344.814906)
					(mid 317.452248 -342.950038)
					(end 315.587126 -344.814906)
				)
				(arc
					(start 315.587126 -344.814906)
					(mid 317.452248 -346.680028)
					(end 319.317116 -344.814906)
				)
			)
		)
	)
	(zone
		(layer "B.Cu")
		(hatch none 0.5)
		(connect_pads
			(clearance 0)
		)
		(min_thickness 0.25)
		(keepout
			(tracks not_allowed)
			(vias allowed)
			(pads allowed)
			(copperpour not_allowed)
			(footprints allowed)
		)
		(placement
			(enabled no)
			(sheetname "")
		)
		(fill
			(thermal_gap 0.5)
			(thermal_bridge_width 0.5)
			(island_removal_mode 0)
		)
		(polygon
			(pts
				(arc
					(start 62.550548 -393.292838)
					(mid 61.882528 -393.292838)
					(end 62.550548 -393.292838)
				)
			)
		)
	)
	(zone
		(layer "B.Cu")
		(hatch none 0.5)
		(connect_pads
			(clearance 0)
		)
		(min_thickness 0.25)
		(keepout
			(tracks allowed)
			(vias allowed)
			(pads allowed)
			(copperpour allowed)
			(footprints allowed)
		)
		(placement
			(enabled no)
			(sheetname "")
		)
		(fill
			(thermal_gap 0.5)
			(thermal_bridge_width 0.5)
			(island_removal_mode 0)
		)
		(polygon
			(pts
				(xy 52.122578 -409.046426) (xy 52.122578 -408.04211) (xy 53.499512 -408.04211) (xy 53.499512 -409.046426)
			)
		)
	)
	(zone
		(layer "B.Cu")
		(hatch none 0.5)
		(connect_pads
			(clearance 0)
		)
		(min_thickness 0.25)
		(keepout
			(tracks allowed)
			(vias allowed)
			(pads allowed)
			(copperpour allowed)
			(footprints allowed)
		)
		(placement
			(enabled no)
			(sheetname "")
		)
		(fill
			(thermal_gap 0.5)
			(thermal_bridge_width 0.5)
			(island_removal_mode 0)
		)
		(polygon
			(pts
				(xy 375.222516 -417.428426) (xy 375.222516 -416.42411) (xy 376.59945 -416.42411) (xy 376.59945 -417.428426)
			)
		)
	)
	(zone
		(layer "B.Cu")
		(hatch none 0.5)
		(connect_pads
			(clearance 0)
		)
		(min_thickness 0.25)
		(keepout
			(tracks not_allowed)
			(vias allowed)
			(pads allowed)
			(copperpour not_allowed)
			(footprints allowed)
		)
		(placement
			(enabled no)
			(sheetname "")
		)
		(fill
			(thermal_gap 0.5)
			(thermal_bridge_width 0.5)
			(island_removal_mode 0)
		)
		(polygon
			(pts
				(arc
					(start 90.037158 -437.889904)
					(mid 89.262966 -437.889904)
					(end 90.037158 -437.889904)
				)
			)
		)
	)
	(zone
		(layer "B.Cu")
		(hatch none 0.5)
		(connect_pads
			(clearance 0)
		)
		(min_thickness 0.25)
		(keepout
			(tracks allowed)
			(vias allowed)
			(pads allowed)
			(copperpour allowed)
			(footprints allowed)
		)
		(placement
			(enabled no)
			(sheetname "")
		)
		(fill
			(thermal_gap 0.5)
			(thermal_bridge_width 0.5)
			(island_removal_mode 0)
		)
		(polygon
			(pts
				(xy 146.79168 -409.046426) (xy 146.79168 -408.04211) (xy 148.168614 -408.04211) (xy 148.168614 -409.046426)
			)
		)
	)
	(zone
		(layer "B.Cu")
		(hatch none 0.5)
		(connect_pads
			(clearance 0)
		)
		(min_thickness 0.25)
		(keepout
			(tracks not_allowed)
			(vias allowed)
			(pads allowed)
			(copperpour not_allowed)
			(footprints allowed)
		)
		(placement
			(enabled no)
			(sheetname "")
		)
		(fill
			(thermal_gap 0.5)
			(thermal_bridge_width 0.5)
			(island_removal_mode 0)
		)
		(polygon
			(pts
				(arc
					(start 76.037186 -436.889906)
					(mid 75.262994 -436.889906)
					(end 76.037186 -436.889906)
				)
			)
		)
	)
	(zone
		(layer "B.Cu")
		(hatch none 0.5)
		(connect_pads
			(clearance 0)
		)
		(min_thickness 0.25)
		(keepout
			(tracks allowed)
			(vias allowed)
			(pads allowed)
			(copperpour allowed)
			(footprints allowed)
		)
		(placement
			(enabled no)
			(sheetname "")
		)
		(fill
			(thermal_gap 0.5)
			(thermal_bridge_width 0.5)
			(island_removal_mode 0)
		)
		(polygon
			(pts
				(xy 391.322814 -319.804796) (xy 391.322814 -318.451484) (xy 393.302236 -318.451484) (xy 393.302236 -319.804796)
			)
		)
	)
	(zone
		(layer "B.Cu")
		(hatch none 0.5)
		(connect_pads
			(clearance 0)
		)
		(min_thickness 0.25)
		(keepout
			(tracks allowed)
			(vias allowed)
			(pads allowed)
			(copperpour allowed)
			(footprints not_allowed)
		)
		(placement
			(enabled no)
			(sheetname "")
		)
		(fill
			(thermal_gap 0.5)
			(thermal_bridge_width 0.5)
			(island_removal_mode 0)
		)
		(polygon
			(pts
				(arc
					(start 385.602988 -12.78001)
					(mid 386.780177 -12.539398)
					(end 387.768592 -11.856212)
				)
				(arc
					(start 387.768592 -11.856212)
					(mid 381.669826 -34.776658)
					(end 372.799356 -12.78001)
				)
			)
		)
	)
	(zone
		(layer "B.Cu")
		(hatch none 0.5)
		(connect_pads
			(clearance 0)
		)
		(min_thickness 0.25)
		(keepout
			(tracks not_allowed)
			(vias allowed)
			(pads allowed)
			(copperpour not_allowed)
			(footprints allowed)
		)
		(placement
			(enabled no)
			(sheetname "")
		)
		(fill
			(thermal_gap 0.5)
			(thermal_bridge_width 0.5)
			(island_removal_mode 0)
		)
		(polygon
			(pts
				(arc
					(start 139.029948 -304.790094)
					(mid 142.530068 -308.290214)
					(end 146.029934 -304.790094)
				)
				(arc
					(start 146.029934 -304.790094)
					(mid 142.530068 -301.290228)
					(end 139.029948 -304.790094)
				)
			)
		)
	)
	(zone
		(layer "B.Cu")
		(hatch none 0.5)
		(connect_pads
			(clearance 0)
		)
		(min_thickness 0.25)
		(keepout
			(tracks allowed)
			(vias allowed)
			(pads allowed)
			(copperpour allowed)
			(footprints allowed)
		)
		(placement
			(enabled no)
			(sheetname "")
		)
		(fill
			(thermal_gap 0.5)
			(thermal_bridge_width 0.5)
			(island_removal_mode 0)
		)
		(polygon
			(pts
				(xy 405.87549 -166.317168) (xy 405.87549 -164.158168) (xy 406.25649 -163.777168) (xy 409.05049 -163.777168)
				(xy 410.19349 -164.920168) (xy 410.19349 -167.841168) (xy 409.68549 -168.349168) (xy 407.90749 -168.349168)
			)
		)
	)
	(zone
		(layer "B.Cu")
		(hatch none 0.5)
		(connect_pads
			(clearance 0)
		)
		(min_thickness 0.25)
		(keepout
			(tracks allowed)
			(vias allowed)
			(pads allowed)
			(copperpour allowed)
			(footprints not_allowed)
		)
		(placement
			(enabled no)
			(sheetname "")
		)
		(fill
			(thermal_gap 0.5)
			(thermal_bridge_width 0.5)
			(island_removal_mode 0)
		)
		(polygon
			(pts
				(xy 407.640028 -310.522112) (xy 407.640028 -273.02206) (xy 462.639918 -273.02206) (xy 462.639918 -310.522112)
			)
		)
	)
	(zone
		(layer "B.Cu")
		(hatch none 0.5)
		(connect_pads
			(clearance 0)
		)
		(min_thickness 0.25)
		(keepout
			(tracks not_allowed)
			(vias allowed)
			(pads allowed)
			(copperpour not_allowed)
			(footprints allowed)
		)
		(placement
			(enabled no)
			(sheetname "")
		)
		(fill
			(thermal_gap 0.5)
			(thermal_bridge_width 0.5)
			(island_removal_mode 0)
		)
		(polygon
			(pts
				(arc
					(start 348.75597 -247.724168)
					(mid 348.12605 -247.724168)
					(end 348.75597 -247.724168)
				)
			)
		)
	)
	(zone
		(layer "B.Cu")
		(hatch none 0.5)
		(connect_pads
			(clearance 0)
		)
		(min_thickness 0.25)
		(keepout
			(tracks not_allowed)
			(vias allowed)
			(pads allowed)
			(copperpour not_allowed)
			(footprints allowed)
		)
		(placement
			(enabled no)
			(sheetname "")
		)
		(fill
			(thermal_gap 0.5)
			(thermal_bridge_width 0.5)
			(island_removal_mode 0)
		)
		(polygon
			(pts
				(arc
					(start 122.85853 -36.053268)
					(mid 122.19051 -36.053268)
					(end 122.85853 -36.053268)
				)
			)
		)
	)
	(zone
		(layer "B.Cu")
		(hatch none 0.5)
		(connect_pads
			(clearance 0)
		)
		(min_thickness 0.25)
		(keepout
			(tracks allowed)
			(vias allowed)
			(pads allowed)
			(copperpour allowed)
			(footprints not_allowed)
		)
		(placement
			(enabled no)
			(sheetname "")
		)
		(fill
			(thermal_gap 0.5)
			(thermal_bridge_width 0.5)
			(island_removal_mode 0)
		)
		(polygon
			(pts
				(arc
					(start 314.351924 -344.814906)
					(mid 317.451994 -347.914976)
					(end 320.552064 -344.814906)
				)
				(arc
					(start 320.552064 -344.814906)
					(mid 317.451994 -341.714836)
					(end 314.351924 -344.814906)
				)
			)
		)
	)
	(zone
		(layer "B.Cu")
		(hatch none 0.5)
		(connect_pads
			(clearance 0)
		)
		(min_thickness 0.25)
		(keepout
			(tracks allowed)
			(vias allowed)
			(pads allowed)
			(copperpour allowed)
			(footprints not_allowed)
		)
		(placement
			(enabled no)
			(sheetname "")
		)
		(fill
			(thermal_gap 0.5)
			(thermal_bridge_width 0.5)
			(island_removal_mode 0)
		)
		(polygon
			(pts
				(arc
					(start 293.319962 -384.869944)
					(mid 291.07003 -382.620012)
					(end 288.820098 -384.869944)
				)
				(arc
					(start 288.820098 -384.869944)
					(mid 291.07003 -387.119876)
					(end 293.319962 -384.869944)
				)
			)
		)
	)
	(zone
		(layer "B.Cu")
		(hatch none 0.5)
		(connect_pads
			(clearance 0)
		)
		(min_thickness 0.25)
		(keepout
			(tracks allowed)
			(vias allowed)
			(pads allowed)
			(copperpour allowed)
			(footprints not_allowed)
		)
		(placement
			(enabled no)
			(sheetname "")
		)
		(fill
			(thermal_gap 0.5)
			(thermal_bridge_width 0.5)
			(island_removal_mode 0)
		)
		(polygon
			(pts
				(arc
					(start 223.76511 -290.900104)
					(mid 221.900242 -289.035236)
					(end 220.03512 -290.900104)
				)
				(arc
					(start 220.03512 -290.900104)
					(mid 221.900242 -292.765226)
					(end 223.76511 -290.900104)
				)
			)
		)
	)
	(zone
		(layer "B.Cu")
		(hatch none 0.5)
		(connect_pads
			(clearance 0)
		)
		(min_thickness 0.25)
		(keepout
			(tracks not_allowed)
			(vias allowed)
			(pads allowed)
			(copperpour not_allowed)
			(footprints allowed)
		)
		(placement
			(enabled no)
			(sheetname "")
		)
		(fill
			(thermal_gap 0.5)
			(thermal_bridge_width 0.5)
			(island_removal_mode 0)
		)
		(polygon
			(pts
				(arc
					(start 354.39604 -247.724168)
					(mid 353.76612 -247.724168)
					(end 354.39604 -247.724168)
				)
			)
		)
	)
	(zone
		(layer "B.Cu")
		(hatch none 0.5)
		(connect_pads
			(clearance 0)
		)
		(min_thickness 0.25)
		(keepout
			(tracks allowed)
			(vias allowed)
			(pads allowed)
			(copperpour allowed)
			(footprints allowed)
		)
		(placement
			(enabled no)
			(sheetname "")
		)
		(fill
			(thermal_gap 0.5)
			(thermal_bridge_width 0.5)
			(island_removal_mode 0)
		)
		(polygon
			(pts
				(xy 201.99604 -402.689568) (xy 201.99604 -401.685252) (xy 202.689206 -401.685252) (xy 202.689206 -402.689568)
			)
		)
	)
	(zone
		(layer "B.Cu")
		(hatch none 0.5)
		(connect_pads
			(clearance 0)
		)
		(min_thickness 0.25)
		(keepout
			(tracks not_allowed)
			(vias allowed)
			(pads allowed)
			(copperpour not_allowed)
			(footprints allowed)
		)
		(placement
			(enabled no)
			(sheetname "")
		)
		(fill
			(thermal_gap 0.5)
			(thermal_bridge_width 0.5)
			(island_removal_mode 0)
		)
		(polygon
			(pts
				(arc
					(start 59.036966 -436.889906)
					(mid 58.262774 -436.889906)
					(end 59.036966 -436.889906)
				)
			)
		)
	)
	(zone
		(layer "B.Cu")
		(hatch none 0.5)
		(connect_pads
			(clearance 0)
		)
		(min_thickness 0.25)
		(keepout
			(tracks not_allowed)
			(vias allowed)
			(pads allowed)
			(copperpour not_allowed)
			(footprints allowed)
		)
		(placement
			(enabled no)
			(sheetname "")
		)
		(fill
			(thermal_gap 0.5)
			(thermal_bridge_width 0.5)
			(island_removal_mode 0)
		)
		(polygon
			(pts
				(arc
					(start 403.778212 -401.674838)
					(mid 403.110192 -401.674838)
					(end 403.778212 -401.674838)
				)
			)
		)
	)
	(zone
		(layer "B.Cu")
		(hatch none 0.5)
		(connect_pads
			(clearance 0)
		)
		(min_thickness 0.25)
		(keepout
			(tracks not_allowed)
			(vias allowed)
			(pads allowed)
			(copperpour not_allowed)
			(footprints allowed)
		)
		(placement
			(enabled no)
			(sheetname "")
		)
		(fill
			(thermal_gap 0.5)
			(thermal_bridge_width 0.5)
			(island_removal_mode 0)
		)
		(polygon
			(pts
				(arc
					(start 386.970016 -304.790094)
					(mid 390.470136 -308.290214)
					(end 393.970002 -304.790094)
				)
				(arc
					(start 393.970002 -304.790094)
					(mid 390.470136 -301.290228)
					(end 386.970016 -304.790094)
				)
			)
		)
	)
	(zone
		(layer "B.Cu")
		(hatch none 0.5)
		(connect_pads
			(clearance 0)
		)
		(min_thickness 0.25)
		(keepout
			(tracks allowed)
			(vias allowed)
			(pads allowed)
			(copperpour allowed)
			(footprints allowed)
		)
		(placement
			(enabled no)
			(sheetname "")
		)
		(fill
			(thermal_gap 0.5)
			(thermal_bridge_width 0.5)
			(island_removal_mode 0)
		)
		(polygon
			(pts
				(xy 381.348996 -417.428426) (xy 381.348996 -416.42411) (xy 382.72593 -416.42411) (xy 382.72593 -417.428426)
			)
		)
	)
	(zone
		(layer "B.Cu")
		(hatch none 0.5)
		(connect_pads
			(clearance 0)
		)
		(min_thickness 0.25)
		(keepout
			(tracks not_allowed)
			(vias allowed)
			(pads allowed)
			(copperpour not_allowed)
			(footprints allowed)
		)
		(placement
			(enabled no)
			(sheetname "")
		)
		(fill
			(thermal_gap 0.5)
			(thermal_bridge_width 0.5)
			(island_removal_mode 0)
		)
		(polygon
			(pts
				(arc
					(start 357.986076 -270.846042)
					(mid 357.356156 -270.846042)
					(end 357.986076 -270.846042)
				)
			)
		)
	)
	(zone
		(layer "B.Cu")
		(hatch none 0.5)
		(connect_pads
			(clearance 0)
		)
		(min_thickness 0.25)
		(keepout
			(tracks not_allowed)
			(vias allowed)
			(pads allowed)
			(copperpour not_allowed)
			(footprints allowed)
		)
		(placement
			(enabled no)
			(sheetname "")
		)
		(fill
			(thermal_gap 0.5)
			(thermal_bridge_width 0.5)
			(island_removal_mode 0)
		)
		(polygon
			(pts
				(arc
					(start 319.0367 -438.089802)
					(mid 318.262508 -438.089802)
					(end 319.0367 -438.089802)
				)
			)
		)
	)
	(zone
		(layer "B.Cu")
		(hatch none 0.5)
		(connect_pads
			(clearance 0)
		)
		(min_thickness 0.25)
		(keepout
			(tracks allowed)
			(vias allowed)
			(pads allowed)
			(copperpour allowed)
			(footprints not_allowed)
		)
		(placement
			(enabled no)
			(sheetname "")
		)
		(fill
			(thermal_gap 0.5)
			(thermal_bridge_width 0.5)
			(island_removal_mode 0)
		)
		(polygon
			(pts
				(arc
					(start 443.816994 -351.415096)
					(mid 441.952126 -349.550228)
					(end 440.087004 -351.415096)
				)
				(arc
					(start 440.087004 -351.415096)
					(mid 441.952126 -353.280218)
					(end 443.816994 -351.415096)
				)
			)
		)
	)
	(zone
		(layer "B.Cu")
		(hatch none 0.5)
		(connect_pads
			(clearance 0)
		)
		(min_thickness 0.25)
		(keepout
			(tracks allowed)
			(vias allowed)
			(pads allowed)
			(copperpour allowed)
			(footprints not_allowed)
		)
		(placement
			(enabled no)
			(sheetname "")
		)
		(fill
			(thermal_gap 0.5)
			(thermal_bridge_width 0.5)
			(island_removal_mode 0)
		)
		(polygon
			(pts
				(xy 407.640028 -273.02206) (xy 406.567894 -273.02206) (xy 406.567894 -267.380974) (xy 409.667964 -264.38098)
				(xy 409.667964 -253.381002) (xy 406.567894 -250.381008) (xy 406.567894 -239.862106) (xy 407.640028 -239.862106)
				(xy 462.639918 -239.862106) (xy 462.639918 -273.02206)
			)
		)
	)
	(zone
		(layer "B.Cu")
		(hatch none 0.5)
		(connect_pads
			(clearance 0)
		)
		(min_thickness 0.25)
		(keepout
			(tracks not_allowed)
			(vias allowed)
			(pads allowed)
			(copperpour not_allowed)
			(footprints allowed)
		)
		(placement
			(enabled no)
			(sheetname "")
		)
		(fill
			(thermal_gap 0.5)
			(thermal_bridge_width 0.5)
			(island_removal_mode 0)
		)
		(polygon
			(pts
				(arc
					(start 140.99413 -30.79496)
					(mid 140.32611 -30.79496)
					(end 140.99413 -30.79496)
				)
			)
		)
	)
	(zone
		(layer "B.Cu")
		(hatch none 0.5)
		(connect_pads
			(clearance 0)
		)
		(min_thickness 0.25)
		(keepout
			(tracks not_allowed)
			(vias allowed)
			(pads allowed)
			(copperpour not_allowed)
			(footprints allowed)
		)
		(placement
			(enabled no)
			(sheetname "")
		)
		(fill
			(thermal_gap 0.5)
			(thermal_bridge_width 0.5)
			(island_removal_mode 0)
		)
		(polygon
			(pts
				(arc
					(start 52.950618 -392.429238)
					(mid 52.282598 -392.429238)
					(end 52.950618 -392.429238)
				)
			)
		)
	)
	(zone
		(layer "B.Cu")
		(hatch none 0.5)
		(connect_pads
			(clearance 0)
		)
		(min_thickness 0.25)
		(keepout
			(tracks allowed)
			(vias allowed)
			(pads allowed)
			(copperpour allowed)
			(footprints allowed)
		)
		(placement
			(enabled no)
			(sheetname "")
		)
		(fill
			(thermal_gap 0.5)
			(thermal_bridge_width 0.5)
			(island_removal_mode 0)
		)
		(polygon
			(pts
				(xy 285.37662 -194.10426) (xy 285.37662 -190.7159) (xy 287.96742 -190.7159) (xy 287.96742 -194.10426)
			)
		)
	)
	(zone
		(layer "B.Cu")
		(hatch none 0.5)
		(connect_pads
			(clearance 0)
		)
		(min_thickness 0.25)
		(keepout
			(tracks allowed)
			(vias allowed)
			(pads allowed)
			(copperpour allowed)
			(footprints allowed)
		)
		(placement
			(enabled no)
			(sheetname "")
		)
		(fill
			(thermal_gap 0.5)
			(thermal_bridge_width 0.5)
			(island_removal_mode 0)
		)
		(polygon
			(pts
				(xy 149.85492 -409.046426) (xy 149.85492 -408.04211) (xy 151.231854 -408.04211) (xy 151.231854 -409.046426)
			)
		)
	)
	(zone
		(layer "B.Cu")
		(hatch none 0.5)
		(connect_pads
			(clearance 0)
		)
		(min_thickness 0.25)
		(keepout
			(tracks allowed)
			(vias allowed)
			(pads allowed)
			(copperpour allowed)
			(footprints not_allowed)
		)
		(placement
			(enabled no)
			(sheetname "")
		)
		(fill
			(thermal_gap 0.5)
			(thermal_bridge_width 0.5)
			(island_removal_mode 0)
		)
		(polygon
			(pts
				(arc
					(start 166.99992 -404.789894)
					(mid 170.999912 -408.789886)
					(end 174.999904 -404.789894)
				)
				(arc
					(start 174.999904 -404.789894)
					(mid 170.999912 -400.789902)
					(end 166.99992 -404.789894)
				)
			)
		)
	)
	(zone
		(layer "B.Cu")
		(hatch none 0.5)
		(connect_pads
			(clearance 0)
		)
		(min_thickness 0.25)
		(keepout
			(tracks not_allowed)
			(vias allowed)
			(pads allowed)
			(copperpour not_allowed)
			(footprints allowed)
		)
		(placement
			(enabled no)
			(sheetname "")
		)
		(fill
			(thermal_gap 0.5)
			(thermal_bridge_width 0.5)
			(island_removal_mode 0)
		)
		(polygon
			(pts
				(arc
					(start 119.609616 -246.10441)
					(mid 118.979696 -246.10441)
					(end 119.609616 -246.10441)
				)
			)
		)
	)
	(zone
		(layer "B.Cu")
		(hatch none 0.5)
		(connect_pads
			(clearance 0)
		)
		(min_thickness 0.25)
		(keepout
			(tracks not_allowed)
			(vias allowed)
			(pads allowed)
			(copperpour not_allowed)
			(footprints allowed)
		)
		(placement
			(enabled no)
			(sheetname "")
		)
		(fill
			(thermal_gap 0.5)
			(thermal_bridge_width 0.5)
			(island_removal_mode 0)
		)
		(polygon
			(pts
				(arc
					(start 20.734782 -137.010902)
					(mid 20.066762 -137.010902)
					(end 20.734782 -137.010902)
				)
			)
		)
	)
	(zone
		(layer "B.Cu")
		(hatch none 0.5)
		(connect_pads
			(clearance 0)
		)
		(min_thickness 0.25)
		(keepout
			(tracks allowed)
			(vias allowed)
			(pads allowed)
			(copperpour allowed)
			(footprints not_allowed)
		)
		(placement
			(enabled no)
			(sheetname "")
		)
		(fill
			(thermal_gap 0.5)
			(thermal_bridge_width 0.5)
			(island_removal_mode 0)
		)
		(polygon
			(pts
				(arc
					(start 145.32991 -304.790094)
					(mid 142.530068 -301.990252)
					(end 139.729972 -304.790094)
				)
				(arc
					(start 139.729972 -304.790094)
					(mid 142.530068 -307.59019)
					(end 145.32991 -304.790094)
				)
			)
		)
	)
	(zone
		(layer "B.Cu")
		(hatch none 0.5)
		(connect_pads
			(clearance 0)
		)
		(min_thickness 0.25)
		(keepout
			(tracks not_allowed)
			(vias allowed)
			(pads allowed)
			(copperpour not_allowed)
			(footprints allowed)
		)
		(placement
			(enabled no)
			(sheetname "")
		)
		(fill
			(thermal_gap 0.5)
			(thermal_bridge_width 0.5)
			(island_removal_mode 0)
		)
		(polygon
			(pts
				(arc
					(start 315.036708 -438.089802)
					(mid 314.262516 -438.089802)
					(end 315.036708 -438.089802)
				)
			)
		)
	)
	(zone
		(layer "B.Cu")
		(hatch none 0.5)
		(connect_pads
			(clearance 0)
		)
		(min_thickness 0.25)
		(keepout
			(tracks allowed)
			(vias allowed)
			(pads allowed)
			(copperpour allowed)
			(footprints allowed)
		)
		(placement
			(enabled no)
			(sheetname "")
		)
		(fill
			(thermal_gap 0.5)
			(thermal_bridge_width 0.5)
			(island_removal_mode 0)
		)
		(polygon
			(pts
				(xy 308.12232 -417.428426) (xy 308.12232 -416.42411) (xy 309.499254 -416.42411) (xy 309.499254 -417.428426)
			)
		)
	)
	(zone
		(layer "B.Cu")
		(hatch none 0.5)
		(connect_pads
			(clearance 0)
		)
		(min_thickness 0.25)
		(keepout
			(tracks not_allowed)
			(vias allowed)
			(pads allowed)
			(copperpour not_allowed)
			(footprints allowed)
		)
		(placement
			(enabled no)
			(sheetname "")
		)
		(fill
			(thermal_gap 0.5)
			(thermal_bridge_width 0.5)
			(island_removal_mode 0)
		)
		(polygon
			(pts
				(arc
					(start 305.350164 -400.811238)
					(mid 304.682144 -400.811238)
					(end 305.350164 -400.811238)
				)
			)
		)
	)
	(zone
		(layer "B.Cu")
		(hatch none 0.5)
		(connect_pads
			(clearance 0)
		)
		(min_thickness 0.25)
		(keepout
			(tracks allowed)
			(vias allowed)
			(pads allowed)
			(copperpour allowed)
			(footprints allowed)
		)
		(placement
			(enabled no)
			(sheetname "")
		)
		(fill
			(thermal_gap 0.5)
			(thermal_bridge_width 0.5)
			(island_removal_mode 0)
		)
		(polygon
			(pts
				(xy 49.059338 -409.046426) (xy 49.059338 -408.04211) (xy 50.436272 -408.04211) (xy 50.436272 -409.046426)
			)
		)
	)
	(zone
		(layer "B.Cu")
		(hatch none 0.5)
		(connect_pads
			(clearance 0)
		)
		(min_thickness 0.25)
		(keepout
			(tracks allowed)
			(vias allowed)
			(pads allowed)
			(copperpour allowed)
			(footprints not_allowed)
		)
		(placement
			(enabled no)
			(sheetname "")
		)
		(fill
			(thermal_gap 0.5)
			(thermal_bridge_width 0.5)
			(island_removal_mode 0)
		)
		(polygon
			(pts
				(arc
					(start 391.387076 -173.315122)
					(mid 389.522208 -171.450254)
					(end 387.657086 -173.315122)
				)
				(arc
					(start 387.657086 -173.315122)
					(mid 389.522208 -175.180244)
					(end 391.387076 -173.315122)
				)
			)
		)
	)
	(zone
		(layer "B.Cu")
		(hatch none 0.5)
		(connect_pads
			(clearance 0)
		)
		(min_thickness 0.25)
		(keepout
			(tracks not_allowed)
			(vias allowed)
			(pads allowed)
			(copperpour not_allowed)
			(footprints allowed)
		)
		(placement
			(enabled no)
			(sheetname "")
		)
		(fill
			(thermal_gap 0.5)
			(thermal_bridge_width 0.5)
			(island_removal_mode 0)
		)
		(polygon
			(pts
				(arc
					(start 22.080982 -347.8149)
					(mid 20.216114 -345.950032)
					(end 18.350992 -347.8149)
				)
				(arc
					(start 18.350992 -347.8149)
					(mid 20.216114 -349.680022)
					(end 22.080982 -347.8149)
				)
			)
		)
	)
	(zone
		(layer "B.Cu")
		(hatch none 0.5)
		(connect_pads
			(clearance 0)
		)
		(min_thickness 0.25)
		(keepout
			(tracks allowed)
			(vias allowed)
			(pads allowed)
			(copperpour allowed)
			(footprints not_allowed)
		)
		(placement
			(enabled no)
			(sheetname "")
		)
		(fill
			(thermal_gap 0.5)
			(thermal_bridge_width 0.5)
			(island_removal_mode 0)
		)
		(polygon
			(pts
				(arc
					(start 422.999916 -413.170116)
					(mid 426.999908 -417.170108)
					(end 430.9999 -413.170116)
				)
				(arc
					(start 430.9999 -413.170116)
					(mid 426.999908 -409.170124)
					(end 422.999916 -413.170116)
				)
			)
		)
	)
	(zone
		(layers "B.Cu" "In2.Cu" "In4.Cu" "In6.Cu" "In8.Cu" "In9.Cu" "In11.Cu" "In13.Cu"
			"In15.Cu"
		)
		(hatch none 0.5)
		(connect_pads
			(clearance 0)
		)
		(min_thickness 0.25)
		(keepout
			(tracks not_allowed)
			(vias allowed)
			(pads allowed)
			(copperpour not_allowed)
			(footprints allowed)
		)
		(placement
			(enabled no)
			(sheetname "")
		)
		(fill yes
			(thermal_gap 0.5)
			(thermal_bridge_width 0.5)
			(island_removal_mode 0)
		)
		(polygon
			(pts
				(arc
					(start 258.12496 -365.031274)
					(mid 253.85776 -360.764074)
					(end 258.12496 -356.496874)
				)
				(arc
					(start 258.12496 -356.725474)
					(mid 254.08636 -360.764074)
					(end 258.12496 -364.802674)
				)
			)
		)
	)
	(zone
		(layers "B.Cu" "In2.Cu" "In4.Cu" "In6.Cu" "In8.Cu" "In9.Cu" "In11.Cu" "In13.Cu"
			"In15.Cu"
		)
		(hatch none 0.5)
		(connect_pads
			(clearance 0)
		)
		(min_thickness 0.25)
		(keepout
			(tracks not_allowed)
			(vias allowed)
			(pads allowed)
			(copperpour not_allowed)
			(footprints allowed)
		)
		(placement
			(enabled no)
			(sheetname "")
		)
		(fill yes
			(thermal_gap 0.5)
			(thermal_bridge_width 0.5)
			(island_removal_mode 0)
		)
		(polygon
			(pts
				(arc
					(start 258.12496 -365.031274)
					(mid 262.39216 -360.764074)
					(end 258.12496 -356.496874)
				)
				(arc
					(start 258.12496 -356.725474)
					(mid 262.16356 -360.764074)
					(end 258.12496 -364.802674)
				)
			)
		)
	)
	(zone
		(layers "B.Cu" "In2.Cu" "In4.Cu" "In6.Cu" "In11.Cu" "In13.Cu")
		(hatch none 0.5)
		(connect_pads
			(clearance 0)
		)
		(min_thickness 0.25)
		(keepout
			(tracks allowed)
			(vias allowed)
			(pads allowed)
			(copperpour allowed)
			(footprints allowed)
		)
		(placement
			(enabled no)
			(sheetname "")
		)
		(fill yes
			(thermal_gap 0.5)
			(thermal_bridge_width 0.5)
			(island_removal_mode 0)
		)
		(polygon
			(pts
				(xy 16.38173 -191.38519) (xy 16.38173 -319.66281) (xy 60.725812 -319.66281) (xy 60.725812 -191.38519)
			)
		)
	)
	(zone
		(layers "B.Cu" "In2.Cu" "In4.Cu" "In6.Cu" "In11.Cu" "In13.Cu" "In15.Cu")
		(hatch none 0.5)
		(connect_pads
			(clearance 0)
		)
		(min_thickness 0.25)
		(keepout
			(tracks not_allowed)
			(vias allowed)
			(pads allowed)
			(copperpour not_allowed)
			(footprints allowed)
		)
		(placement
			(enabled no)
			(sheetname "")
		)
		(fill yes
			(thermal_gap 0.5)
			(thermal_bridge_width 0.5)
			(island_removal_mode 0)
		)
		(polygon
			(pts
				(xy 365.311944 -422.743376) (xy 370.312188 -422.743376) (xy 370.312188 -421.18026) (xy 370.116354 -421.18026)
				(xy 370.116354 -420.7383) (xy 370.312188 -420.7383) (xy 370.312188 -415.847784) (xy 365.311944 -415.847784)
			)
		)
	)
	(zone
		(layers "B.Cu" "In2.Cu" "In4.Cu" "In6.Cu" "In11.Cu" "In13.Cu" "In15.Cu")
		(hatch none 0.5)
		(connect_pads
			(clearance 0)
		)
		(min_thickness 0.25)
		(keepout
			(tracks not_allowed)
			(vias allowed)
			(pads allowed)
			(copperpour not_allowed)
			(footprints allowed)
		)
		(placement
			(enabled no)
			(sheetname "")
		)
		(fill yes
			(thermal_gap 0.5)
			(thermal_bridge_width 0.5)
			(island_removal_mode 0)
		)
		(polygon
			(pts
				(xy 102.150418 -414.277302) (xy 102.150418 -421.172894) (xy 97.150174 -421.172894) (xy 97.150174 -414.277302)
			)
		)
	)
	(zone
		(layers "B.Cu" "In2.Cu" "In4.Cu" "In6.Cu" "In11.Cu" "In15.Cu")
		(hatch none 0.5)
		(connect_pads
			(clearance 0)
		)
		(min_thickness 0.25)
		(keepout
			(tracks not_allowed)
			(vias allowed)
			(pads allowed)
			(copperpour not_allowed)
			(footprints allowed)
		)
		(placement
			(enabled no)
			(sheetname "")
		)
		(fill yes
			(thermal_gap 0.5)
			(thermal_bridge_width 0.5)
			(island_removal_mode 0)
		)
		(polygon
			(pts
				(xy 109.758734 -13.378942) (xy 116.654326 -13.378942) (xy 116.654326 -18.379186) (xy 109.758734 -18.379186)
			)
		)
	)
	(zone
		(layers "B.Cu" "In2.Cu" "In4.Cu" "In11.Cu" "In13.Cu")
		(hatch none 0.5)
		(connect_pads
			(clearance 0)
		)
		(min_thickness 0.25)
		(keepout
			(tracks allowed)
			(vias allowed)
			(pads allowed)
			(copperpour allowed)
			(footprints allowed)
		)
		(placement
			(enabled no)
			(sheetname "")
		)
		(fill yes
			(thermal_gap 0.5)
			(thermal_bridge_width 0.5)
			(island_removal_mode 0)
		)
		(polygon
			(pts
				(xy 163.23564 -191.38519) (xy 163.23564 -319.66281) (xy 207.31099 -319.66281) (xy 207.31099 -191.38519)
			)
		)
	)
	(zone
		(layers "B.Cu" "In2.Cu" "In13.Cu" "In15.Cu")
		(hatch none 0.5)
		(connect_pads
			(clearance 0)
		)
		(min_thickness 0.25)
		(keepout
			(tracks not_allowed)
			(vias allowed)
			(pads allowed)
			(copperpour not_allowed)
			(footprints allowed)
		)
		(placement
			(enabled no)
			(sheetname "")
		)
		(fill yes
			(thermal_gap 0.5)
			(thermal_bridge_width 0.5)
			(island_removal_mode 0)
		)
		(polygon
			(pts
				(xy 290.91763 -12.914122) (xy 297.813222 -12.914122) (xy 297.813222 -17.914366)
				(arc
					(start 290.94303 -17.914366)
					(mid 290.925069 -17.906927)
					(end 290.91763 -17.888966)
				)
			)
		)
	)
	(zone
		(layers "B.Cu" "In4.Cu" "In6.Cu" "In11.Cu" "In13.Cu" "In15.Cu")
		(hatch none 0.5)
		(connect_pads
			(clearance 0)
		)
		(min_thickness 0.25)
		(keepout
			(tracks not_allowed)
			(vias allowed)
			(pads allowed)
			(copperpour not_allowed)
			(footprints allowed)
		)
		(placement
			(enabled no)
			(sheetname "")
		)
		(fill yes
			(thermal_gap 0.5)
			(thermal_bridge_width 0.5)
			(island_removal_mode 0)
		)
		(polygon
			(pts
				(arc
					(start 378.189744 -266.796012)
					(mid 377.559824 -266.796012)
					(end 378.189744 -266.796012)
				)
			)
		)
	)
	(zone
		(layers "B.Cu" "In4.Cu" "In6.Cu" "In11.Cu" "In13.Cu" "In15.Cu")
		(hatch none 0.5)
		(connect_pads
			(clearance 0)
		)
		(min_thickness 0.25)
		(keepout
			(tracks not_allowed)
			(vias allowed)
			(pads allowed)
			(copperpour not_allowed)
			(footprints allowed)
		)
		(placement
			(enabled no)
			(sheetname "")
		)
		(fill yes
			(thermal_gap 0.5)
			(thermal_bridge_width 0.5)
			(island_removal_mode 0)
		)
		(polygon
			(pts
				(arc
					(start 376.77979 -283.806138)
					(mid 376.14987 -283.806138)
					(end 376.77979 -283.806138)
				)
			)
		)
	)
	(zone
		(layers "B.Cu" "In4.Cu" "In6.Cu" "In11.Cu" "In13.Cu" "In15.Cu")
		(hatch none 0.5)
		(connect_pads
			(clearance 0)
		)
		(min_thickness 0.25)
		(keepout
			(tracks not_allowed)
			(vias allowed)
			(pads allowed)
			(copperpour not_allowed)
			(footprints allowed)
		)
		(placement
			(enabled no)
			(sheetname "")
		)
		(fill yes
			(thermal_gap 0.5)
			(thermal_bridge_width 0.5)
			(island_removal_mode 0)
		)
		(polygon
			(pts
				(arc
					(start 179.850034 -226.23526)
					(mid 179.182014 -226.23526)
					(end 179.850034 -226.23526)
				)
			)
		)
	)
	(zone
		(layers "B.Cu" "In4.Cu" "In6.Cu" "In11.Cu" "In13.Cu" "In15.Cu")
		(hatch none 0.5)
		(connect_pads
			(clearance 0)
		)
		(min_thickness 0.25)
		(keepout
			(tracks not_allowed)
			(vias allowed)
			(pads allowed)
			(copperpour not_allowed)
			(footprints allowed)
		)
		(placement
			(enabled no)
			(sheetname "")
		)
		(fill yes
			(thermal_gap 0.5)
			(thermal_bridge_width 0.5)
			(island_removal_mode 0)
		)
		(polygon
			(pts
				(arc
					(start 343.586054 -230.714296)
					(mid 342.956134 -230.714296)
					(end 343.586054 -230.714296)
				)
			)
		)
	)
	(zone
		(layers "B.Cu" "In4.Cu" "In6.Cu" "In11.Cu" "In13.Cu" "In15.Cu")
		(hatch none 0.5)
		(connect_pads
			(clearance 0)
		)
		(min_thickness 0.25)
		(keepout
			(tracks not_allowed)
			(vias allowed)
			(pads allowed)
			(copperpour not_allowed)
			(footprints allowed)
		)
		(placement
			(enabled no)
			(sheetname "")
		)
		(fill yes
			(thermal_gap 0.5)
			(thermal_bridge_width 0.5)
			(island_removal_mode 0)
		)
		(polygon
			(pts
				(arc
					(start 378.189744 -271.656048)
					(mid 377.559824 -271.656048)
					(end 378.189744 -271.656048)
				)
			)
		)
	)
	(zone
		(layers "B.Cu" "In4.Cu" "In6.Cu" "In11.Cu" "In13.Cu" "In15.Cu")
		(hatch none 0.5)
		(connect_pads
			(clearance 0)
		)
		(min_thickness 0.25)
		(keepout
			(tracks not_allowed)
			(vias allowed)
			(pads allowed)
			(copperpour not_allowed)
			(footprints allowed)
		)
		(placement
			(enabled no)
			(sheetname "")
		)
		(fill yes
			(thermal_gap 0.5)
			(thermal_bridge_width 0.5)
			(island_removal_mode 0)
		)
		(polygon
			(pts
				(arc
					(start 431.89017 -227.085144)
					(mid 431.22215 -227.085144)
					(end 431.89017 -227.085144)
				)
			)
		)
	)
	(zone
		(layers "B.Cu" "In4.Cu" "In6.Cu" "In11.Cu" "In13.Cu" "In15.Cu")
		(hatch none 0.5)
		(connect_pads
			(clearance 0)
		)
		(min_thickness 0.25)
		(keepout
			(tracks not_allowed)
			(vias allowed)
			(pads allowed)
			(copperpour not_allowed)
			(footprints allowed)
		)
		(placement
			(enabled no)
			(sheetname "")
		)
		(fill yes
			(thermal_gap 0.5)
			(thermal_bridge_width 0.5)
			(island_removal_mode 0)
		)
		(polygon
			(pts
				(arc
					(start 179.850034 -251.735336)
					(mid 179.182014 -251.735336)
					(end 179.850034 -251.735336)
				)
			)
		)
	)
	(zone
		(layers "B.Cu" "In4.Cu" "In6.Cu" "In11.Cu" "In13.Cu" "In15.Cu")
		(hatch none 0.5)
		(connect_pads
			(clearance 0)
		)
		(min_thickness 0.25)
		(keepout
			(tracks not_allowed)
			(vias allowed)
			(pads allowed)
			(copperpour not_allowed)
			(footprints allowed)
		)
		(placement
			(enabled no)
			(sheetname "")
		)
		(fill yes
			(thermal_gap 0.5)
			(thermal_bridge_width 0.5)
			(island_removal_mode 0)
		)
		(polygon
			(pts
				(arc
					(start 342.945974 -285.42615)
					(mid 342.316054 -285.42615)
					(end 342.945974 -285.42615)
				)
			)
		)
	)
	(zone
		(layers "B.Cu" "In4.Cu" "In6.Cu" "In11.Cu" "In13.Cu" "In15.Cu")
		(hatch none 0.5)
		(connect_pads
			(clearance 0)
		)
		(min_thickness 0.25)
		(keepout
			(tracks not_allowed)
			(vias allowed)
			(pads allowed)
			(copperpour not_allowed)
			(footprints allowed)
		)
		(placement
			(enabled no)
			(sheetname "")
		)
		(fill yes
			(thermal_gap 0.5)
			(thermal_bridge_width 0.5)
			(island_removal_mode 0)
		)
		(polygon
			(pts
				(arc
					(start 431.89017 -242.385088)
					(mid 431.22215 -242.385088)
					(end 431.89017 -242.385088)
				)
			)
		)
	)
	(zone
		(layers "B.Cu" "In4.Cu" "In6.Cu" "In11.Cu" "In13.Cu" "In15.Cu")
		(hatch none 0.5)
		(connect_pads
			(clearance 0)
		)
		(min_thickness 0.25)
		(keepout
			(tracks not_allowed)
			(vias allowed)
			(pads allowed)
			(copperpour not_allowed)
			(footprints allowed)
		)
		(placement
			(enabled no)
			(sheetname "")
		)
		(fill yes
			(thermal_gap 0.5)
			(thermal_bridge_width 0.5)
			(island_removal_mode 0)
		)
		(polygon
			(pts
				(arc
					(start 431.89017 -281.485086)
					(mid 431.22215 -281.485086)
					(end 431.89017 -281.485086)
				)
			)
		)
	)
	(zone
		(layers "B.Cu" "In4.Cu" "In6.Cu" "In11.Cu" "In13.Cu" "In15.Cu")
		(hatch none 0.5)
		(connect_pads
			(clearance 0)
		)
		(min_thickness 0.25)
		(keepout
			(tracks not_allowed)
			(vias allowed)
			(pads allowed)
			(copperpour not_allowed)
			(footprints allowed)
		)
		(placement
			(enabled no)
			(sheetname "")
		)
		(fill yes
			(thermal_gap 0.5)
			(thermal_bridge_width 0.5)
			(island_removal_mode 0)
		)
		(polygon
			(pts
				(arc
					(start 44.674028 -273.835368)
					(mid 44.006008 -273.835368)
					(end 44.674028 -273.835368)
				)
			)
		)
	)
	(zone
		(layers "B.Cu" "In4.Cu" "In6.Cu" "In11.Cu" "In13.Cu" "In15.Cu")
		(hatch none 0.5)
		(connect_pads
			(clearance 0)
		)
		(min_thickness 0.25)
		(keepout
			(tracks not_allowed)
			(vias allowed)
			(pads allowed)
			(copperpour not_allowed)
			(footprints allowed)
		)
		(placement
			(enabled no)
			(sheetname "")
		)
		(fill yes
			(thermal_gap 0.5)
			(thermal_bridge_width 0.5)
			(island_removal_mode 0)
		)
		(polygon
			(pts
				(arc
					(start 370.369846 -228.284278)
					(mid 369.739926 -228.284278)
					(end 370.369846 -228.284278)
				)
			)
		)
	)
	(zone
		(layers "B.Cu" "In4.Cu" "In6.Cu" "In11.Cu" "In13.Cu" "In15.Cu")
		(hatch none 0.5)
		(connect_pads
			(clearance 0)
		)
		(min_thickness 0.25)
		(keepout
			(tracks not_allowed)
			(vias allowed)
			(pads allowed)
			(copperpour not_allowed)
			(footprints allowed)
		)
		(placement
			(enabled no)
			(sheetname "")
		)
		(fill yes
			(thermal_gap 0.5)
			(thermal_bridge_width 0.5)
			(island_removal_mode 0)
		)
		(polygon
			(pts
				(arc
					(start 40.57396 -301.035212)
					(mid 39.90594 -301.035212)
					(end 40.57396 -301.035212)
				)
			)
		)
	)
	(zone
		(layers "B.Cu" "In4.Cu" "In6.Cu" "In11.Cu" "In13.Cu" "In15.Cu")
		(hatch none 0.5)
		(connect_pads
			(clearance 0)
		)
		(min_thickness 0.25)
		(keepout
			(tracks not_allowed)
			(vias allowed)
			(pads allowed)
			(copperpour not_allowed)
			(footprints allowed)
		)
		(placement
			(enabled no)
			(sheetname "")
		)
		(fill yes
			(thermal_gap 0.5)
			(thermal_bridge_width 0.5)
			(island_removal_mode 0)
		)
		(polygon
			(pts
				(arc
					(start 40.57396 -205.83525)
					(mid 39.90594 -205.83525)
					(end 40.57396 -205.83525)
				)
			)
		)
	)
	(zone
		(layers "B.Cu" "In4.Cu" "In6.Cu" "In11.Cu" "In13.Cu" "In15.Cu")
		(hatch none 0.5)
		(connect_pads
			(clearance 0)
		)
		(min_thickness 0.25)
		(keepout
			(tracks not_allowed)
			(vias allowed)
			(pads allowed)
			(copperpour not_allowed)
			(footprints allowed)
		)
		(placement
			(enabled no)
			(sheetname "")
		)
		(fill yes
			(thermal_gap 0.5)
			(thermal_bridge_width 0.5)
			(island_removal_mode 0)
		)
		(polygon
			(pts
				(arc
					(start 427.790102 -263.634982)
					(mid 427.122082 -263.634982)
					(end 427.790102 -263.634982)
				)
			)
		)
	)
	(zone
		(layers "B.Cu" "In4.Cu" "In6.Cu" "In11.Cu" "In13.Cu" "In15.Cu")
		(hatch none 0.5)
		(connect_pads
			(clearance 0)
		)
		(min_thickness 0.25)
		(keepout
			(tracks not_allowed)
			(vias allowed)
			(pads allowed)
			(copperpour not_allowed)
			(footprints allowed)
		)
		(placement
			(enabled no)
			(sheetname "")
		)
		(fill yes
			(thermal_gap 0.5)
			(thermal_bridge_width 0.5)
			(island_removal_mode 0)
		)
		(polygon
			(pts
				(arc
					(start 94.705932 -255.014476)
					(mid 94.076012 -255.014476)
					(end 94.705932 -255.014476)
				)
			)
		)
	)
	(zone
		(layers "B.Cu" "In4.Cu" "In6.Cu" "In11.Cu" "In13.Cu" "In15.Cu")
		(hatch none 0.5)
		(connect_pads
			(clearance 0)
		)
		(min_thickness 0.25)
		(keepout
			(tracks not_allowed)
			(vias allowed)
			(pads allowed)
			(copperpour not_allowed)
			(footprints allowed)
		)
		(placement
			(enabled no)
			(sheetname "")
		)
		(fill yes
			(thermal_gap 0.5)
			(thermal_bridge_width 0.5)
			(island_removal_mode 0)
		)
		(polygon
			(pts
				(arc
					(start 40.57396 -198.185278)
					(mid 39.90594 -198.185278)
					(end 40.57396 -198.185278)
				)
			)
		)
	)
	(zone
		(layers "B.Cu" "In4.Cu" "In6.Cu" "In11.Cu" "In13.Cu" "In15.Cu")
		(hatch none 0.5)
		(connect_pads
			(clearance 0)
		)
		(min_thickness 0.25)
		(keepout
			(tracks not_allowed)
			(vias allowed)
			(pads allowed)
			(copperpour not_allowed)
			(footprints allowed)
		)
		(placement
			(enabled no)
			(sheetname "")
		)
		(fill yes
			(thermal_gap 0.5)
			(thermal_bridge_width 0.5)
			(island_removal_mode 0)
		)
		(polygon
			(pts
				(arc
					(start 292.614096 -312.935112)
					(mid 291.946076 -312.935112)
					(end 292.614096 -312.935112)
				)
			)
		)
	)
	(zone
		(layers "B.Cu" "In4.Cu" "In6.Cu" "In11.Cu" "In13.Cu" "In15.Cu")
		(hatch none 0.5)
		(connect_pads
			(clearance 0)
		)
		(min_thickness 0.25)
		(keepout
			(tracks not_allowed)
			(vias allowed)
			(pads allowed)
			(copperpour not_allowed)
			(footprints allowed)
		)
		(placement
			(enabled no)
			(sheetname "")
		)
		(fill yes
			(thermal_gap 0.5)
			(thermal_bridge_width 0.5)
			(island_removal_mode 0)
		)
		(polygon
			(pts
				(arc
					(start 365.66983 -228.284278)
					(mid 365.03991 -228.284278)
					(end 365.66983 -228.284278)
				)
			)
		)
	)
	(zone
		(layers "B.Cu" "In4.Cu" "In6.Cu" "In11.Cu" "In13.Cu" "In15.Cu")
		(hatch none 0.5)
		(connect_pads
			(clearance 0)
		)
		(min_thickness 0.25)
		(keepout
			(tracks not_allowed)
			(vias allowed)
			(pads allowed)
			(copperpour not_allowed)
			(footprints allowed)
		)
		(placement
			(enabled no)
			(sheetname "")
		)
		(fill yes
			(thermal_gap 0.5)
			(thermal_bridge_width 0.5)
			(island_removal_mode 0)
		)
		(polygon
			(pts
				(arc
					(start 376.479816 -225.85426)
					(mid 375.849896 -225.85426)
					(end 376.479816 -225.85426)
				)
			)
		)
	)
	(zone
		(layers "B.Cu" "In4.Cu" "In6.Cu" "In11.Cu" "In13.Cu" "In15.Cu")
		(hatch none 0.5)
		(connect_pads
			(clearance 0)
		)
		(min_thickness 0.25)
		(keepout
			(tracks not_allowed)
			(vias allowed)
			(pads allowed)
			(copperpour not_allowed)
			(footprints allowed)
		)
		(placement
			(enabled no)
			(sheetname "")
		)
		(fill yes
			(thermal_gap 0.5)
			(thermal_bridge_width 0.5)
			(island_removal_mode 0)
		)
		(polygon
			(pts
				(arc
					(start 376.30989 -287.856168)
					(mid 375.67997 -287.856168)
					(end 376.30989 -287.856168)
				)
			)
		)
	)
	(zone
		(layers "B.Cu" "In4.Cu" "In6.Cu" "In11.Cu" "In13.Cu" "In15.Cu")
		(hatch none 0.5)
		(connect_pads
			(clearance 0)
		)
		(min_thickness 0.25)
		(keepout
			(tracks not_allowed)
			(vias allowed)
			(pads allowed)
			(copperpour not_allowed)
			(footprints allowed)
		)
		(placement
			(enabled no)
			(sheetname "")
		)
		(fill yes
			(thermal_gap 0.5)
			(thermal_bridge_width 0.5)
			(island_removal_mode 0)
		)
		(polygon
			(pts
				(arc
					(start 40.57396 -293.38524)
					(mid 39.90594 -293.38524)
					(end 40.57396 -293.38524)
				)
			)
		)
	)
	(zone
		(layers "B.Cu" "In4.Cu" "In6.Cu" "In11.Cu" "In13.Cu" "In15.Cu")
		(hatch none 0.5)
		(connect_pads
			(clearance 0)
		)
		(min_thickness 0.25)
		(keepout
			(tracks not_allowed)
			(vias allowed)
			(pads allowed)
			(copperpour not_allowed)
			(footprints allowed)
		)
		(placement
			(enabled no)
			(sheetname "")
		)
		(fill yes
			(thermal_gap 0.5)
			(thermal_bridge_width 0.5)
			(island_removal_mode 0)
		)
		(polygon
			(pts
				(arc
					(start 288.514028 -253.435104)
					(mid 287.846008 -253.435104)
					(end 288.514028 -253.435104)
				)
			)
		)
	)
	(zone
		(layers "B.Cu" "In4.Cu" "In6.Cu" "In11.Cu" "In13.Cu" "In15.Cu")
		(hatch none 0.5)
		(connect_pads
			(clearance 0)
		)
		(min_thickness 0.25)
		(keepout
			(tracks not_allowed)
			(vias allowed)
			(pads allowed)
			(copperpour not_allowed)
			(footprints allowed)
		)
		(placement
			(enabled no)
			(sheetname "")
		)
		(fill yes
			(thermal_gap 0.5)
			(thermal_bridge_width 0.5)
			(island_removal_mode 0)
		)
		(polygon
			(pts
				(arc
					(start 427.790102 -277.235158)
					(mid 427.122082 -277.235158)
					(end 427.790102 -277.235158)
				)
			)
		)
	)
	(zone
		(layers "B.Cu" "In4.Cu" "In6.Cu" "In11.Cu" "In13.Cu" "In15.Cu")
		(hatch none 0.5)
		(connect_pads
			(clearance 0)
		)
		(min_thickness 0.25)
		(keepout
			(tracks not_allowed)
			(vias allowed)
			(pads allowed)
			(copperpour not_allowed)
			(footprints allowed)
		)
		(placement
			(enabled no)
			(sheetname "")
		)
		(fill yes
			(thermal_gap 0.5)
			(thermal_bridge_width 0.5)
			(island_removal_mode 0)
		)
		(polygon
			(pts
				(arc
					(start 342.1761 -247.724168)
					(mid 341.54618 -247.724168)
					(end 342.1761 -247.724168)
				)
			)
		)
	)
	(zone
		(layers "B.Cu" "In4.Cu" "In6.Cu" "In11.Cu" "In13.Cu" "In15.Cu")
		(hatch none 0.5)
		(connect_pads
			(clearance 0)
		)
		(min_thickness 0.25)
		(keepout
			(tracks not_allowed)
			(vias allowed)
			(pads allowed)
			(copperpour not_allowed)
			(footprints allowed)
		)
		(placement
			(enabled no)
			(sheetname "")
		)
		(fill yes
			(thermal_gap 0.5)
			(thermal_bridge_width 0.5)
			(island_removal_mode 0)
		)
		(polygon
			(pts
				(arc
					(start 129.479802 -230.71455)
					(mid 128.849882 -230.71455)
					(end 129.479802 -230.71455)
				)
			)
		)
	)
	(zone
		(layers "B.Cu" "In4.Cu" "In6.Cu" "In11.Cu" "In13.Cu" "In15.Cu")
		(hatch none 0.5)
		(connect_pads
			(clearance 0)
		)
		(min_thickness 0.25)
		(keepout
			(tracks not_allowed)
			(vias allowed)
			(pads allowed)
			(copperpour not_allowed)
			(footprints allowed)
		)
		(placement
			(enabled no)
			(sheetname "")
		)
		(fill yes
			(thermal_gap 0.5)
			(thermal_bridge_width 0.5)
			(island_removal_mode 0)
		)
		(polygon
			(pts
				(arc
					(start 431.89017 -225.385122)
					(mid 431.22215 -225.385122)
					(end 431.89017 -225.385122)
				)
			)
		)
	)
	(zone
		(layers "B.Cu" "In4.Cu" "In6.Cu" "In11.Cu" "In13.Cu" "In15.Cu")
		(hatch none 0.5)
		(connect_pads
			(clearance 0)
		)
		(min_thickness 0.25)
		(keepout
			(tracks not_allowed)
			(vias allowed)
			(pads allowed)
			(copperpour not_allowed)
			(footprints allowed)
		)
		(placement
			(enabled no)
			(sheetname "")
		)
		(fill yes
			(thermal_gap 0.5)
			(thermal_bridge_width 0.5)
			(island_removal_mode 0)
		)
		(polygon
			(pts
				(arc
					(start 344.356182 -278.136096)
					(mid 343.726262 -278.136096)
					(end 344.356182 -278.136096)
				)
			)
		)
	)
	(zone
		(layers "B.Cu" "In4.Cu" "In6.Cu" "In11.Cu" "In13.Cu" "In15.Cu")
		(hatch none 0.5)
		(connect_pads
			(clearance 0)
		)
		(min_thickness 0.25)
		(keepout
			(tracks not_allowed)
			(vias allowed)
			(pads allowed)
			(copperpour not_allowed)
			(footprints allowed)
		)
		(placement
			(enabled no)
			(sheetname "")
		)
		(fill yes
			(thermal_gap 0.5)
			(thermal_bridge_width 0.5)
			(island_removal_mode 0)
		)
		(polygon
			(pts
				(arc
					(start 94.705932 -248.534428)
					(mid 94.076012 -248.534428)
					(end 94.705932 -248.534428)
				)
			)
		)
	)
	(zone
		(layers "B.Cu" "In4.Cu" "In6.Cu" "In11.Cu" "In13.Cu" "In15.Cu")
		(hatch none 0.5)
		(connect_pads
			(clearance 0)
		)
		(min_thickness 0.25)
		(keepout
			(tracks not_allowed)
			(vias allowed)
			(pads allowed)
			(copperpour not_allowed)
			(footprints allowed)
		)
		(placement
			(enabled no)
			(sheetname "")
		)
		(fill yes
			(thermal_gap 0.5)
			(thermal_bridge_width 0.5)
			(island_removal_mode 0)
		)
		(polygon
			(pts
				(arc
					(start 344.055954 -239.624108)
					(mid 343.426034 -239.624108)
					(end 344.055954 -239.624108)
				)
			)
		)
	)
	(zone
		(layers "B.Cu" "In4.Cu" "In6.Cu" "In11.Cu" "In13.Cu" "In15.Cu")
		(hatch none 0.5)
		(connect_pads
			(clearance 0)
		)
		(min_thickness 0.25)
		(keepout
			(tracks not_allowed)
			(vias allowed)
			(pads allowed)
			(copperpour not_allowed)
			(footprints allowed)
		)
		(placement
			(enabled no)
			(sheetname "")
		)
		(fill yes
			(thermal_gap 0.5)
			(thermal_bridge_width 0.5)
			(island_removal_mode 0)
		)
		(polygon
			(pts
				(arc
					(start 431.89017 -234.735116)
					(mid 431.22215 -234.735116)
					(end 431.89017 -234.735116)
				)
			)
		)
	)
	(zone
		(layers "B.Cu" "In4.Cu" "In6.Cu" "In11.Cu" "In13.Cu" "In15.Cu")
		(hatch none 0.5)
		(connect_pads
			(clearance 0)
		)
		(min_thickness 0.25)
		(keepout
			(tracks not_allowed)
			(vias allowed)
			(pads allowed)
			(copperpour not_allowed)
			(footprints allowed)
		)
		(placement
			(enabled no)
			(sheetname "")
		)
		(fill yes
			(thermal_gap 0.5)
			(thermal_bridge_width 0.5)
			(island_removal_mode 0)
		)
		(polygon
			(pts
				(arc
					(start 378.189744 -278.136096)
					(mid 377.559824 -278.136096)
					(end 378.189744 -278.136096)
				)
			)
		)
	)
	(zone
		(layers "B.Cu" "In4.Cu" "In6.Cu" "In11.Cu" "In13.Cu" "In15.Cu")
		(hatch none 0.5)
		(connect_pads
			(clearance 0)
		)
		(min_thickness 0.25)
		(keepout
			(tracks not_allowed)
			(vias allowed)
			(pads allowed)
			(copperpour not_allowed)
			(footprints allowed)
		)
		(placement
			(enabled no)
			(sheetname "")
		)
		(fill yes
			(thermal_gap 0.5)
			(thermal_bridge_width 0.5)
			(island_removal_mode 0)
		)
		(polygon
			(pts
				(arc
					(start 292.614096 -300.185074)
					(mid 291.946076 -300.185074)
					(end 292.614096 -300.185074)
				)
			)
		)
	)
	(zone
		(layers "B.Cu" "In4.Cu" "In6.Cu" "In11.Cu" "In13.Cu" "In15.Cu")
		(hatch none 0.5)
		(connect_pads
			(clearance 0)
		)
		(min_thickness 0.25)
		(keepout
			(tracks not_allowed)
			(vias allowed)
			(pads allowed)
			(copperpour not_allowed)
			(footprints allowed)
		)
		(placement
			(enabled no)
			(sheetname "")
		)
		(fill yes
			(thermal_gap 0.5)
			(thermal_bridge_width 0.5)
			(island_removal_mode 0)
		)
		(polygon
			(pts
				(arc
					(start 292.614096 -285.735014)
					(mid 291.946076 -285.735014)
					(end 292.614096 -285.735014)
				)
			)
		)
	)
	(zone
		(layers "B.Cu" "In4.Cu" "In6.Cu" "In11.Cu" "In13.Cu" "In15.Cu")
		(hatch none 0.5)
		(connect_pads
			(clearance 0)
		)
		(min_thickness 0.25)
		(keepout
			(tracks not_allowed)
			(vias allowed)
			(pads allowed)
			(copperpour not_allowed)
			(footprints allowed)
		)
		(placement
			(enabled no)
			(sheetname "")
		)
		(fill yes
			(thermal_gap 0.5)
			(thermal_bridge_width 0.5)
			(island_removal_mode 0)
		)
		(polygon
			(pts
				(arc
					(start 342.945974 -287.045908)
					(mid 342.316054 -287.045908)
					(end 342.945974 -287.045908)
				)
			)
		)
	)
	(zone
		(layers "B.Cu" "In4.Cu" "In6.Cu" "In11.Cu" "In13.Cu" "In15.Cu")
		(hatch none 0.5)
		(connect_pads
			(clearance 0)
		)
		(min_thickness 0.25)
		(keepout
			(tracks not_allowed)
			(vias allowed)
			(pads allowed)
			(copperpour not_allowed)
			(footprints allowed)
		)
		(placement
			(enabled no)
			(sheetname "")
		)
		(fill yes
			(thermal_gap 0.5)
			(thermal_bridge_width 0.5)
			(island_removal_mode 0)
		)
		(polygon
			(pts
				(arc
					(start 94.536006 -282.996386)
					(mid 93.906086 -282.996386)
					(end 94.536006 -282.996386)
				)
			)
		)
	)
	(zone
		(layers "B.Cu" "In4.Cu" "In6.Cu" "In11.Cu" "In13.Cu" "In15.Cu")
		(hatch none 0.5)
		(connect_pads
			(clearance 0)
		)
		(min_thickness 0.25)
		(keepout
			(tracks not_allowed)
			(vias allowed)
			(pads allowed)
			(copperpour not_allowed)
			(footprints allowed)
		)
		(placement
			(enabled no)
			(sheetname "")
		)
		(fill yes
			(thermal_gap 0.5)
			(thermal_bridge_width 0.5)
			(island_removal_mode 0)
		)
		(polygon
			(pts
				(arc
					(start 28.038552 -421.69969)
					(mid 27.370532 -421.69969)
					(end 28.038552 -421.69969)
				)
			)
		)
	)
	(zone
		(layers "B.Cu" "In4.Cu" "In6.Cu" "In11.Cu" "In13.Cu" "In15.Cu")
		(hatch none 0.5)
		(connect_pads
			(clearance 0)
		)
		(min_thickness 0.25)
		(keepout
			(tracks not_allowed)
			(vias allowed)
			(pads allowed)
			(copperpour not_allowed)
			(footprints allowed)
		)
		(placement
			(enabled no)
			(sheetname "")
		)
		(fill yes
			(thermal_gap 0.5)
			(thermal_bridge_width 0.5)
			(island_removal_mode 0)
		)
		(polygon
			(pts
				(arc
					(start 376.009662 -239.624108)
					(mid 375.379742 -239.624108)
					(end 376.009662 -239.624108)
				)
			)
		)
	)
	(zone
		(layers "B.Cu" "In4.Cu" "In6.Cu" "In11.Cu" "In13.Cu" "In15.Cu")
		(hatch none 0.5)
		(connect_pads
			(clearance 0)
		)
		(min_thickness 0.25)
		(keepout
			(tracks not_allowed)
			(vias allowed)
			(pads allowed)
			(copperpour not_allowed)
			(footprints allowed)
		)
		(placement
			(enabled no)
			(sheetname "")
		)
		(fill yes
			(thermal_gap 0.5)
			(thermal_bridge_width 0.5)
			(island_removal_mode 0)
		)
		(polygon
			(pts
				(arc
					(start 179.850034 -293.38524)
					(mid 179.182014 -293.38524)
					(end 179.850034 -293.38524)
				)
			)
		)
	)
	(zone
		(layers "B.Cu" "In4.Cu" "In6.Cu" "In11.Cu" "In13.Cu" "In15.Cu")
		(hatch none 0.5)
		(connect_pads
			(clearance 0)
		)
		(min_thickness 0.25)
		(keepout
			(tracks not_allowed)
			(vias allowed)
			(pads allowed)
			(copperpour not_allowed)
			(footprints allowed)
		)
		(placement
			(enabled no)
			(sheetname "")
		)
		(fill yes
			(thermal_gap 0.5)
			(thermal_bridge_width 0.5)
			(island_removal_mode 0)
		)
		(polygon
			(pts
				(arc
					(start 40.57396 -209.235294)
					(mid 39.90594 -209.235294)
					(end 40.57396 -209.235294)
				)
			)
		)
	)
	(zone
		(layers "B.Cu" "In4.Cu" "In6.Cu" "In11.Cu" "In13.Cu" "In15.Cu")
		(hatch none 0.5)
		(connect_pads
			(clearance 0)
		)
		(min_thickness 0.25)
		(keepout
			(tracks not_allowed)
			(vias allowed)
			(pads allowed)
			(copperpour not_allowed)
			(footprints allowed)
		)
		(placement
			(enabled no)
			(sheetname "")
		)
		(fill yes
			(thermal_gap 0.5)
			(thermal_bridge_width 0.5)
			(island_removal_mode 0)
		)
		(polygon
			(pts
				(arc
					(start 129.479802 -243.674392)
					(mid 128.849882 -243.674392)
					(end 129.479802 -243.674392)
				)
			)
		)
	)
	(zone
		(layers "B.Cu" "In4.Cu" "In6.Cu" "In11.Cu" "In13.Cu" "In15.Cu")
		(hatch none 0.5)
		(connect_pads
			(clearance 0)
		)
		(min_thickness 0.25)
		(keepout
			(tracks not_allowed)
			(vias allowed)
			(pads allowed)
			(copperpour not_allowed)
			(footprints allowed)
		)
		(placement
			(enabled no)
			(sheetname "")
		)
		(fill yes
			(thermal_gap 0.5)
			(thermal_bridge_width 0.5)
			(island_removal_mode 0)
		)
		(polygon
			(pts
				(arc
					(start 95.005906 -288.666174)
					(mid 94.375986 -288.666174)
					(end 95.005906 -288.666174)
				)
			)
		)
	)
	(zone
		(layers "B.Cu" "In4.Cu" "In6.Cu" "In11.Cu" "In13.Cu" "In15.Cu")
		(hatch none 0.5)
		(connect_pads
			(clearance 0)
		)
		(min_thickness 0.25)
		(keepout
			(tracks not_allowed)
			(vias allowed)
			(pads allowed)
			(copperpour not_allowed)
			(footprints allowed)
		)
		(placement
			(enabled no)
			(sheetname "")
		)
		(fill yes
			(thermal_gap 0.5)
			(thermal_bridge_width 0.5)
			(island_removal_mode 0)
		)
		(polygon
			(pts
				(arc
					(start 103.636064 -229.90429)
					(mid 103.006144 -229.90429)
					(end 103.636064 -229.90429)
				)
			)
		)
	)
	(zone
		(layers "B.Cu" "In4.Cu" "In6.Cu" "In11.Cu" "In13.Cu" "In15.Cu")
		(hatch none 0.5)
		(connect_pads
			(clearance 0)
		)
		(min_thickness 0.25)
		(keepout
			(tracks not_allowed)
			(vias allowed)
			(pads allowed)
			(copperpour not_allowed)
			(footprints allowed)
		)
		(placement
			(enabled no)
			(sheetname "")
		)
		(fill yes
			(thermal_gap 0.5)
			(thermal_bridge_width 0.5)
			(island_removal_mode 0)
		)
		(polygon
			(pts
				(arc
					(start 288.514028 -250.03506)
					(mid 287.846008 -250.03506)
					(end 288.514028 -250.03506)
				)
			)
		)
	)
	(zone
		(layers "B.Cu" "In4.Cu" "In6.Cu" "In11.Cu" "In13.Cu" "In15.Cu")
		(hatch none 0.5)
		(connect_pads
			(clearance 0)
		)
		(min_thickness 0.25)
		(keepout
			(tracks not_allowed)
			(vias allowed)
			(pads allowed)
			(copperpour not_allowed)
			(footprints allowed)
		)
		(placement
			(enabled no)
			(sheetname "")
		)
		(fill yes
			(thermal_gap 0.5)
			(thermal_bridge_width 0.5)
			(island_removal_mode 0)
		)
		(polygon
			(pts
				(arc
					(start 342.945974 -283.806138)
					(mid 342.316054 -283.806138)
					(end 342.945974 -283.806138)
				)
			)
		)
	)
	(zone
		(layers "B.Cu" "In4.Cu" "In6.Cu" "In11.Cu" "In13.Cu" "In15.Cu")
		(hatch none 0.5)
		(connect_pads
			(clearance 0)
		)
		(min_thickness 0.25)
		(keepout
			(tracks not_allowed)
			(vias allowed)
			(pads allowed)
			(copperpour not_allowed)
			(footprints allowed)
		)
		(placement
			(enabled no)
			(sheetname "")
		)
		(fill yes
			(thermal_gap 0.5)
			(thermal_bridge_width 0.5)
			(island_removal_mode 0)
		)
		(polygon
			(pts
				(arc
					(start 377.88977 -254.204216)
					(mid 377.25985 -254.204216)
					(end 377.88977 -254.204216)
				)
			)
		)
	)
	(zone
		(layers "B.Cu" "In4.Cu" "In6.Cu" "In11.Cu" "In13.Cu" "In15.Cu")
		(hatch none 0.5)
		(connect_pads
			(clearance 0)
		)
		(min_thickness 0.25)
		(keepout
			(tracks not_allowed)
			(vias allowed)
			(pads allowed)
			(copperpour not_allowed)
			(footprints allowed)
		)
		(placement
			(enabled no)
			(sheetname "")
		)
		(fill yes
			(thermal_gap 0.5)
			(thermal_bridge_width 0.5)
			(island_removal_mode 0)
		)
		(polygon
			(pts
				(arc
					(start 40.57396 -299.335444)
					(mid 39.90594 -299.335444)
					(end 40.57396 -299.335444)
				)
			)
		)
	)
	(zone
		(layers "B.Cu" "In4.Cu" "In6.Cu" "In11.Cu" "In13.Cu" "In15.Cu")
		(hatch none 0.5)
		(connect_pads
			(clearance 0)
		)
		(min_thickness 0.25)
		(keepout
			(tracks not_allowed)
			(vias allowed)
			(pads allowed)
			(copperpour not_allowed)
			(footprints allowed)
		)
		(placement
			(enabled no)
			(sheetname "")
		)
		(fill yes
			(thermal_gap 0.5)
			(thermal_bridge_width 0.5)
			(island_removal_mode 0)
		)
		(polygon
			(pts
				(arc
					(start 95.005906 -267.606272)
					(mid 94.375986 -267.606272)
					(end 95.005906 -267.606272)
				)
			)
		)
	)
	(zone
		(layers "B.Cu" "In4.Cu" "In6.Cu" "In11.Cu" "In13.Cu" "In15.Cu")
		(hatch none 0.5)
		(connect_pads
			(clearance 0)
		)
		(min_thickness 0.25)
		(keepout
			(tracks not_allowed)
			(vias allowed)
			(pads allowed)
			(copperpour not_allowed)
			(footprints allowed)
		)
		(placement
			(enabled no)
			(sheetname "")
		)
		(fill yes
			(thermal_gap 0.5)
			(thermal_bridge_width 0.5)
			(island_removal_mode 0)
		)
		(polygon
			(pts
				(arc
					(start 288.514028 -285.735014)
					(mid 287.846008 -285.735014)
					(end 288.514028 -285.735014)
				)
			)
		)
	)
	(zone
		(layers "B.Cu" "In4.Cu" "In6.Cu" "In11.Cu" "In13.Cu" "In15.Cu")
		(hatch none 0.5)
		(connect_pads
			(clearance 0)
		)
		(min_thickness 0.25)
		(keepout
			(tracks not_allowed)
			(vias allowed)
			(pads allowed)
			(copperpour not_allowed)
			(footprints allowed)
		)
		(placement
			(enabled no)
			(sheetname "")
		)
		(fill yes
			(thermal_gap 0.5)
			(thermal_bridge_width 0.5)
			(island_removal_mode 0)
		)
		(polygon
			(pts
				(arc
					(start 120.44934 -33.02508)
					(mid 119.78132 -33.02508)
					(end 120.44934 -33.02508)
				)
			)
		)
	)
	(zone
		(layers "B.Cu" "In4.Cu" "In6.Cu" "In11.Cu" "In13.Cu" "In15.Cu")
		(hatch none 0.5)
		(connect_pads
			(clearance 0)
		)
		(min_thickness 0.25)
		(keepout
			(tracks not_allowed)
			(vias allowed)
			(pads allowed)
			(copperpour not_allowed)
			(footprints allowed)
		)
		(placement
			(enabled no)
			(sheetname "")
		)
		(fill yes
			(thermal_gap 0.5)
			(thermal_bridge_width 0.5)
			(island_removal_mode 0)
		)
		(polygon
			(pts
				(arc
					(start 44.674028 -236.435392)
					(mid 44.006008 -236.435392)
					(end 44.674028 -236.435392)
				)
			)
		)
	)
	(zone
		(layers "B.Cu" "In4.Cu" "In6.Cu" "In11.Cu" "In13.Cu" "In15.Cu")
		(hatch none 0.5)
		(connect_pads
			(clearance 0)
		)
		(min_thickness 0.25)
		(keepout
			(tracks not_allowed)
			(vias allowed)
			(pads allowed)
			(copperpour not_allowed)
			(footprints allowed)
		)
		(placement
			(enabled no)
			(sheetname "")
		)
		(fill yes
			(thermal_gap 0.5)
			(thermal_bridge_width 0.5)
			(island_removal_mode 0)
		)
		(polygon
			(pts
				(arc
					(start 292.614096 -270.43507)
					(mid 291.946076 -270.43507)
					(end 292.614096 -270.43507)
				)
			)
		)
	)
	(zone
		(layers "B.Cu" "In4.Cu" "In6.Cu" "In11.Cu" "In13.Cu" "In15.Cu")
		(hatch none 0.5)
		(connect_pads
			(clearance 0)
		)
		(min_thickness 0.25)
		(keepout
			(tracks not_allowed)
			(vias allowed)
			(pads allowed)
			(copperpour not_allowed)
			(footprints allowed)
		)
		(placement
			(enabled no)
			(sheetname "")
		)
		(fill yes
			(thermal_gap 0.5)
			(thermal_bridge_width 0.5)
			(island_removal_mode 0)
		)
		(polygon
			(pts
				(arc
					(start 183.950102 -242.385342)
					(mid 183.282082 -242.385342)
					(end 183.950102 -242.385342)
				)
			)
		)
	)
	(zone
		(layers "B.Cu" "In4.Cu" "In6.Cu" "In11.Cu" "In13.Cu" "In15.Cu")
		(hatch none 0.5)
		(connect_pads
			(clearance 0)
		)
		(min_thickness 0.25)
		(keepout
			(tracks not_allowed)
			(vias allowed)
			(pads allowed)
			(copperpour not_allowed)
			(footprints allowed)
		)
		(placement
			(enabled no)
			(sheetname "")
		)
		(fill yes
			(thermal_gap 0.5)
			(thermal_bridge_width 0.5)
			(island_removal_mode 0)
		)
		(polygon
			(pts
				(arc
					(start 96.416114 -292.716204)
					(mid 95.786194 -292.716204)
					(end 96.416114 -292.716204)
				)
			)
		)
	)
	(zone
		(layers "B.Cu" "In4.Cu" "In6.Cu" "In11.Cu" "In13.Cu" "In15.Cu")
		(hatch none 0.5)
		(connect_pads
			(clearance 0)
		)
		(min_thickness 0.25)
		(keepout
			(tracks not_allowed)
			(vias allowed)
			(pads allowed)
			(copperpour not_allowed)
			(footprints allowed)
		)
		(placement
			(enabled no)
			(sheetname "")
		)
		(fill yes
			(thermal_gap 0.5)
			(thermal_bridge_width 0.5)
			(island_removal_mode 0)
		)
		(polygon
			(pts
				(arc
					(start 105.815892 -294.336216)
					(mid 105.185972 -294.336216)
					(end 105.815892 -294.336216)
				)
			)
		)
	)
	(zone
		(layers "B.Cu" "In4.Cu" "In6.Cu" "In11.Cu" "In13.Cu" "In15.Cu")
		(hatch none 0.5)
		(connect_pads
			(clearance 0)
		)
		(min_thickness 0.25)
		(keepout
			(tracks not_allowed)
			(vias allowed)
			(pads allowed)
			(copperpour not_allowed)
			(footprints allowed)
		)
		(placement
			(enabled no)
			(sheetname "")
		)
		(fill yes
			(thermal_gap 0.5)
			(thermal_bridge_width 0.5)
			(island_removal_mode 0)
		)
		(polygon
			(pts
				(arc
					(start 94.236032 -254.20447)
					(mid 93.606112 -254.20447)
					(end 94.236032 -254.20447)
				)
			)
		)
	)
	(zone
		(layers "B.Cu" "In4.Cu" "In6.Cu" "In11.Cu" "In13.Cu" "In15.Cu")
		(hatch none 0.5)
		(connect_pads
			(clearance 0)
		)
		(min_thickness 0.25)
		(keepout
			(tracks not_allowed)
			(vias allowed)
			(pads allowed)
			(copperpour not_allowed)
			(footprints allowed)
		)
		(placement
			(enabled no)
			(sheetname "")
		)
		(fill yes
			(thermal_gap 0.5)
			(thermal_bridge_width 0.5)
			(island_removal_mode 0)
		)
		(polygon
			(pts
				(arc
					(start 342.646 -255.014222)
					(mid 342.01608 -255.014222)
					(end 342.646 -255.014222)
				)
			)
		)
	)
	(zone
		(layers "B.Cu" "In4.Cu" "In6.Cu" "In11.Cu" "In13.Cu" "In15.Cu")
		(hatch none 0.5)
		(connect_pads
			(clearance 0)
		)
		(min_thickness 0.25)
		(keepout
			(tracks not_allowed)
			(vias allowed)
			(pads allowed)
			(copperpour not_allowed)
			(footprints allowed)
		)
		(placement
			(enabled no)
			(sheetname "")
		)
		(fill yes
			(thermal_gap 0.5)
			(thermal_bridge_width 0.5)
			(island_removal_mode 0)
		)
		(polygon
			(pts
				(arc
					(start 342.476074 -276.516084)
					(mid 341.846154 -276.516084)
					(end 342.476074 -276.516084)
				)
			)
		)
	)
	(zone
		(layers "B.Cu" "In4.Cu" "In6.Cu" "In11.Cu" "In13.Cu" "In15.Cu")
		(hatch none 0.5)
		(connect_pads
			(clearance 0)
		)
		(min_thickness 0.25)
		(keepout
			(tracks not_allowed)
			(vias allowed)
			(pads allowed)
			(copperpour not_allowed)
			(footprints allowed)
		)
		(placement
			(enabled no)
			(sheetname "")
		)
		(fill yes
			(thermal_gap 0.5)
			(thermal_bridge_width 0.5)
			(island_removal_mode 0)
		)
		(polygon
			(pts
				(arc
					(start 40.57396 -222.835216)
					(mid 39.90594 -222.835216)
					(end 40.57396 -222.835216)
				)
			)
		)
	)
	(zone
		(layers "B.Cu" "In4.Cu" "In6.Cu" "In11.Cu" "In13.Cu" "In15.Cu")
		(hatch none 0.5)
		(connect_pads
			(clearance 0)
		)
		(min_thickness 0.25)
		(keepout
			(tracks not_allowed)
			(vias allowed)
			(pads allowed)
			(copperpour not_allowed)
			(footprints allowed)
		)
		(placement
			(enabled no)
			(sheetname "")
		)
		(fill yes
			(thermal_gap 0.5)
			(thermal_bridge_width 0.5)
			(island_removal_mode 0)
		)
		(polygon
			(pts
				(arc
					(start 179.850034 -209.235294)
					(mid 179.182014 -209.235294)
					(end 179.850034 -209.235294)
				)
			)
		)
	)
	(zone
		(layers "B.Cu" "In4.Cu" "In6.Cu" "In11.Cu" "In13.Cu" "In15.Cu")
		(hatch none 0.5)
		(connect_pads
			(clearance 0)
		)
		(min_thickness 0.25)
		(keepout
			(tracks not_allowed)
			(vias allowed)
			(pads allowed)
			(copperpour not_allowed)
			(footprints allowed)
		)
		(placement
			(enabled no)
			(sheetname "")
		)
		(fill yes
			(thermal_gap 0.5)
			(thermal_bridge_width 0.5)
			(island_removal_mode 0)
		)
		(polygon
			(pts
				(arc
					(start 129.779776 -280.566368)
					(mid 129.149856 -280.566368)
					(end 129.779776 -280.566368)
				)
			)
		)
	)
	(zone
		(layers "B.Cu" "In4.Cu" "In6.Cu" "In11.Cu" "In13.Cu" "In15.Cu")
		(hatch none 0.5)
		(connect_pads
			(clearance 0)
		)
		(min_thickness 0.25)
		(keepout
			(tracks not_allowed)
			(vias allowed)
			(pads allowed)
			(copperpour not_allowed)
			(footprints allowed)
		)
		(placement
			(enabled no)
			(sheetname "")
		)
		(fill yes
			(thermal_gap 0.5)
			(thermal_bridge_width 0.5)
			(island_removal_mode 0)
		)
		(polygon
			(pts
				(arc
					(start 179.850034 -230.485442)
					(mid 179.182014 -230.485442)
					(end 179.850034 -230.485442)
				)
			)
		)
	)
	(zone
		(layers "B.Cu" "In4.Cu" "In6.Cu" "In11.Cu" "In13.Cu" "In15.Cu")
		(hatch none 0.5)
		(connect_pads
			(clearance 0)
		)
		(min_thickness 0.25)
		(keepout
			(tracks not_allowed)
			(vias allowed)
			(pads allowed)
			(copperpour not_allowed)
			(footprints allowed)
		)
		(placement
			(enabled no)
			(sheetname "")
		)
		(fill yes
			(thermal_gap 0.5)
			(thermal_bridge_width 0.5)
			(island_removal_mode 0)
		)
		(polygon
			(pts
				(arc
					(start 342.646 -229.094284)
					(mid 342.01608 -229.094284)
					(end 342.646 -229.094284)
				)
			)
		)
	)
	(zone
		(layers "B.Cu" "In4.Cu" "In6.Cu" "In11.Cu" "In13.Cu" "In15.Cu")
		(hatch none 0.5)
		(connect_pads
			(clearance 0)
		)
		(min_thickness 0.25)
		(keepout
			(tracks not_allowed)
			(vias allowed)
			(pads allowed)
			(copperpour not_allowed)
			(footprints allowed)
		)
		(placement
			(enabled no)
			(sheetname "")
		)
		(fill yes
			(thermal_gap 0.5)
			(thermal_bridge_width 0.5)
			(island_removal_mode 0)
		)
		(polygon
			(pts
				(arc
					(start 40.57396 -302.735234)
					(mid 39.90594 -302.735234)
					(end 40.57396 -302.735234)
				)
			)
		)
	)
	(zone
		(layers "B.Cu" "In4.Cu" "In6.Cu" "In11.Cu" "In13.Cu" "In15.Cu")
		(hatch none 0.5)
		(connect_pads
			(clearance 0)
		)
		(min_thickness 0.25)
		(keepout
			(tracks not_allowed)
			(vias allowed)
			(pads allowed)
			(copperpour not_allowed)
			(footprints allowed)
		)
		(placement
			(enabled no)
			(sheetname "")
		)
		(fill yes
			(thermal_gap 0.5)
			(thermal_bridge_width 0.5)
			(island_removal_mode 0)
		)
		(polygon
			(pts
				(arc
					(start 431.89017 -220.285056)
					(mid 431.22215 -220.285056)
					(end 431.89017 -220.285056)
				)
			)
		)
	)
	(zone
		(layers "B.Cu" "In4.Cu" "In6.Cu" "In11.Cu" "In13.Cu" "In15.Cu")
		(hatch none 0.5)
		(connect_pads
			(clearance 0)
		)
		(min_thickness 0.25)
		(keepout
			(tracks not_allowed)
			(vias allowed)
			(pads allowed)
			(copperpour not_allowed)
			(footprints allowed)
		)
		(placement
			(enabled no)
			(sheetname "")
		)
		(fill yes
			(thermal_gap 0.5)
			(thermal_bridge_width 0.5)
			(island_removal_mode 0)
		)
		(polygon
			(pts
				(arc
					(start 288.514028 -286.585152)
					(mid 287.846008 -286.585152)
					(end 288.514028 -286.585152)
				)
			)
		)
	)
	(zone
		(layers "B.Cu" "In4.Cu" "In6.Cu" "In11.Cu" "In13.Cu" "In15.Cu")
		(hatch none 0.5)
		(connect_pads
			(clearance 0)
		)
		(min_thickness 0.25)
		(keepout
			(tracks not_allowed)
			(vias allowed)
			(pads allowed)
			(copperpour not_allowed)
			(footprints allowed)
		)
		(placement
			(enabled no)
			(sheetname "")
		)
		(fill yes
			(thermal_gap 0.5)
			(thermal_bridge_width 0.5)
			(island_removal_mode 0)
		)
		(polygon
			(pts
				(arc
					(start 342.646 -230.714296)
					(mid 342.01608 -230.714296)
					(end 342.646 -230.714296)
				)
			)
		)
	)
	(zone
		(layers "B.Cu" "In4.Cu" "In6.Cu" "In11.Cu" "In13.Cu" "In15.Cu")
		(hatch none 0.5)
		(connect_pads
			(clearance 0)
		)
		(min_thickness 0.25)
		(keepout
			(tracks not_allowed)
			(vias allowed)
			(pads allowed)
			(copperpour not_allowed)
			(footprints allowed)
		)
		(placement
			(enabled no)
			(sheetname "")
		)
		(fill yes
			(thermal_gap 0.5)
			(thermal_bridge_width 0.5)
			(island_removal_mode 0)
		)
		(polygon
			(pts
				(arc
					(start 377.88977 -252.584204)
					(mid 377.25985 -252.584204)
					(end 377.88977 -252.584204)
				)
			)
		)
	)
	(zone
		(layers "B.Cu" "In4.Cu" "In6.Cu" "In11.Cu" "In13.Cu" "In15.Cu")
		(hatch none 0.5)
		(connect_pads
			(clearance 0)
		)
		(min_thickness 0.25)
		(keepout
			(tracks not_allowed)
			(vias allowed)
			(pads allowed)
			(copperpour not_allowed)
			(footprints allowed)
		)
		(placement
			(enabled no)
			(sheetname "")
		)
		(fill yes
			(thermal_gap 0.5)
			(thermal_bridge_width 0.5)
			(island_removal_mode 0)
		)
		(polygon
			(pts
				(arc
					(start 431.89017 -306.135024)
					(mid 431.22215 -306.135024)
					(end 431.89017 -306.135024)
				)
			)
		)
	)
	(zone
		(layers "B.Cu" "In4.Cu" "In6.Cu" "In11.Cu" "In13.Cu" "In15.Cu")
		(hatch none 0.5)
		(connect_pads
			(clearance 0)
		)
		(min_thickness 0.25)
		(keepout
			(tracks not_allowed)
			(vias allowed)
			(pads allowed)
			(copperpour not_allowed)
			(footprints allowed)
		)
		(placement
			(enabled no)
			(sheetname "")
		)
		(fill yes
			(thermal_gap 0.5)
			(thermal_bridge_width 0.5)
			(island_removal_mode 0)
		)
		(polygon
			(pts
				(arc
					(start 179.850034 -274.685252)
					(mid 179.182014 -274.685252)
					(end 179.850034 -274.685252)
				)
			)
		)
	)
	(zone
		(layers "B.Cu" "In4.Cu" "In6.Cu" "In11.Cu" "In13.Cu" "In15.Cu")
		(hatch none 0.5)
		(connect_pads
			(clearance 0)
		)
		(min_thickness 0.25)
		(keepout
			(tracks not_allowed)
			(vias allowed)
			(pads allowed)
			(copperpour not_allowed)
			(footprints allowed)
		)
		(placement
			(enabled no)
			(sheetname "")
		)
		(fill yes
			(thermal_gap 0.5)
			(thermal_bridge_width 0.5)
			(island_removal_mode 0)
		)
		(polygon
			(pts
				(arc
					(start 94.536006 -271.656302)
					(mid 93.906086 -271.656302)
					(end 94.536006 -271.656302)
				)
			)
		)
	)
	(zone
		(layers "B.Cu" "In4.Cu" "In6.Cu" "In11.Cu" "In13.Cu" "In15.Cu")
		(hatch none 0.5)
		(connect_pads
			(clearance 0)
		)
		(min_thickness 0.25)
		(keepout
			(tracks not_allowed)
			(vias allowed)
			(pads allowed)
			(copperpour not_allowed)
			(footprints allowed)
		)
		(placement
			(enabled no)
			(sheetname "")
		)
		(fill yes
			(thermal_gap 0.5)
			(thermal_bridge_width 0.5)
			(island_removal_mode 0)
		)
		(polygon
			(pts
				(arc
					(start 183.950102 -292.535356)
					(mid 183.282082 -292.535356)
					(end 183.950102 -292.535356)
				)
			)
		)
	)
	(zone
		(layers "B.Cu" "In4.Cu" "In6.Cu" "In11.Cu" "In13.Cu" "In15.Cu")
		(hatch none 0.5)
		(connect_pads
			(clearance 0)
		)
		(min_thickness 0.25)
		(keepout
			(tracks not_allowed)
			(vias allowed)
			(pads allowed)
			(copperpour not_allowed)
			(footprints allowed)
		)
		(placement
			(enabled no)
			(sheetname "")
		)
		(fill yes
			(thermal_gap 0.5)
			(thermal_bridge_width 0.5)
			(island_removal_mode 0)
		)
		(polygon
			(pts
				(arc
					(start 377.719844 -264.365994)
					(mid 377.089924 -264.365994)
					(end 377.719844 -264.365994)
				)
			)
		)
	)
	(zone
		(layers "B.Cu" "In4.Cu" "In6.Cu" "In11.Cu" "In13.Cu" "In15.Cu")
		(hatch none 0.5)
		(connect_pads
			(clearance 0)
		)
		(min_thickness 0.25)
		(keepout
			(tracks not_allowed)
			(vias allowed)
			(pads allowed)
			(copperpour not_allowed)
			(footprints allowed)
		)
		(placement
			(enabled no)
			(sheetname "")
		)
		(fill yes
			(thermal_gap 0.5)
			(thermal_bridge_width 0.5)
			(island_removal_mode 0)
		)
		(polygon
			(pts
				(arc
					(start 95.94596 -277.326344)
					(mid 95.31604 -277.326344)
					(end 95.94596 -277.326344)
				)
			)
		)
	)
	(zone
		(layers "B.Cu" "In4.Cu" "In6.Cu" "In11.Cu" "In13.Cu" "In15.Cu")
		(hatch none 0.5)
		(connect_pads
			(clearance 0)
		)
		(min_thickness 0.25)
		(keepout
			(tracks not_allowed)
			(vias allowed)
			(pads allowed)
			(copperpour not_allowed)
			(footprints allowed)
		)
		(placement
			(enabled no)
			(sheetname "")
		)
		(fill yes
			(thermal_gap 0.5)
			(thermal_bridge_width 0.5)
			(island_removal_mode 0)
		)
		(polygon
			(pts
				(arc
					(start 343.586054 -238.814102)
					(mid 342.956134 -238.814102)
					(end 343.586054 -238.814102)
				)
			)
		)
	)
	(zone
		(layers "B.Cu" "In4.Cu" "In6.Cu" "In11.Cu" "In13.Cu" "In15.Cu")
		(hatch none 0.5)
		(connect_pads
			(clearance 0)
		)
		(min_thickness 0.25)
		(keepout
			(tracks not_allowed)
			(vias allowed)
			(pads allowed)
			(copperpour not_allowed)
			(footprints allowed)
		)
		(placement
			(enabled no)
			(sheetname "")
		)
		(fill yes
			(thermal_gap 0.5)
			(thermal_bridge_width 0.5)
			(island_removal_mode 0)
		)
		(polygon
			(pts
				(arc
					(start 183.950102 -210.935316)
					(mid 183.282082 -210.935316)
					(end 183.950102 -210.935316)
				)
			)
		)
	)
	(zone
		(layers "B.Cu" "In4.Cu" "In6.Cu" "In11.Cu" "In13.Cu" "In15.Cu")
		(hatch none 0.5)
		(connect_pads
			(clearance 0)
		)
		(min_thickness 0.25)
		(keepout
			(tracks not_allowed)
			(vias allowed)
			(pads allowed)
			(copperpour not_allowed)
			(footprints allowed)
		)
		(placement
			(enabled no)
			(sheetname "")
		)
		(fill yes
			(thermal_gap 0.5)
			(thermal_bridge_width 0.5)
			(island_removal_mode 0)
		)
		(polygon
			(pts
				(arc
					(start 95.94596 -270.846296)
					(mid 95.31604 -270.846296)
					(end 95.94596 -270.846296)
				)
			)
		)
	)
	(zone
		(layers "B.Cu" "In4.Cu" "In6.Cu" "In11.Cu" "In13.Cu" "In15.Cu")
		(hatch none 0.5)
		(connect_pads
			(clearance 0)
		)
		(min_thickness 0.25)
		(keepout
			(tracks not_allowed)
			(vias allowed)
			(pads allowed)
			(copperpour not_allowed)
			(footprints allowed)
		)
		(placement
			(enabled no)
			(sheetname "")
		)
		(fill yes
			(thermal_gap 0.5)
			(thermal_bridge_width 0.5)
			(island_removal_mode 0)
		)
		(polygon
			(pts
				(arc
					(start 40.57396 -237.285276)
					(mid 39.90594 -237.285276)
					(end 40.57396 -237.285276)
				)
			)
		)
	)
	(zone
		(layers "B.Cu" "In4.Cu" "In6.Cu" "In11.Cu" "In13.Cu" "In15.Cu")
		(hatch none 0.5)
		(connect_pads
			(clearance 0)
		)
		(min_thickness 0.25)
		(keepout
			(tracks not_allowed)
			(vias allowed)
			(pads allowed)
			(copperpour not_allowed)
			(footprints allowed)
		)
		(placement
			(enabled no)
			(sheetname "")
		)
		(fill yes
			(thermal_gap 0.5)
			(thermal_bridge_width 0.5)
			(island_removal_mode 0)
		)
		(polygon
			(pts
				(arc
					(start 44.674028 -200.735438)
					(mid 44.006008 -200.735438)
					(end 44.674028 -200.735438)
				)
			)
		)
	)
	(zone
		(layers "B.Cu" "In4.Cu" "In6.Cu" "In11.Cu" "In13.Cu" "In15.Cu")
		(hatch none 0.5)
		(connect_pads
			(clearance 0)
		)
		(min_thickness 0.25)
		(keepout
			(tracks not_allowed)
			(vias allowed)
			(pads allowed)
			(copperpour not_allowed)
			(footprints allowed)
		)
		(placement
			(enabled no)
			(sheetname "")
		)
		(fill yes
			(thermal_gap 0.5)
			(thermal_bridge_width 0.5)
			(island_removal_mode 0)
		)
		(polygon
			(pts
				(arc
					(start 103.636064 -228.284532)
					(mid 103.006144 -228.284532)
					(end 103.636064 -228.284532)
				)
			)
		)
	)
	(zone
		(layers "B.Cu" "In4.Cu" "In6.Cu" "In11.Cu" "In13.Cu" "In15.Cu")
		(hatch none 0.5)
		(connect_pads
			(clearance 0)
		)
		(min_thickness 0.25)
		(keepout
			(tracks not_allowed)
			(vias allowed)
			(pads allowed)
			(copperpour not_allowed)
			(footprints allowed)
		)
		(placement
			(enabled no)
			(sheetname "")
		)
		(fill yes
			(thermal_gap 0.5)
			(thermal_bridge_width 0.5)
			(island_removal_mode 0)
		)
		(polygon
			(pts
				(arc
					(start 427.790102 -288.285174)
					(mid 427.122082 -288.285174)
					(end 427.790102 -288.285174)
				)
			)
		)
	)
	(zone
		(layers "B.Cu" "In4.Cu" "In6.Cu" "In11.Cu" "In13.Cu" "In15.Cu")
		(hatch none 0.5)
		(connect_pads
			(clearance 0)
		)
		(min_thickness 0.25)
		(keepout
			(tracks not_allowed)
			(vias allowed)
			(pads allowed)
			(copperpour not_allowed)
			(footprints allowed)
		)
		(placement
			(enabled no)
			(sheetname "")
		)
		(fill yes
			(thermal_gap 0.5)
			(thermal_bridge_width 0.5)
			(island_removal_mode 0)
		)
		(polygon
			(pts
				(arc
					(start 128.839722 -262.746236)
					(mid 128.209802 -262.746236)
					(end 128.839722 -262.746236)
				)
			)
		)
	)
	(zone
		(layers "B.Cu" "In4.Cu" "In6.Cu" "In11.Cu" "In13.Cu" "In15.Cu")
		(hatch none 0.5)
		(connect_pads
			(clearance 0)
		)
		(min_thickness 0.25)
		(keepout
			(tracks not_allowed)
			(vias allowed)
			(pads allowed)
			(copperpour not_allowed)
			(footprints allowed)
		)
		(placement
			(enabled no)
			(sheetname "")
		)
		(fill yes
			(thermal_gap 0.5)
			(thermal_bridge_width 0.5)
			(island_removal_mode 0)
		)
		(polygon
			(pts
				(arc
					(start 95.005906 -272.466308)
					(mid 94.375986 -272.466308)
					(end 95.005906 -272.466308)
				)
			)
		)
	)
	(zone
		(layers "B.Cu" "In4.Cu" "In6.Cu" "In11.Cu" "In13.Cu" "In15.Cu")
		(hatch none 0.5)
		(connect_pads
			(clearance 0)
		)
		(min_thickness 0.25)
		(keepout
			(tracks not_allowed)
			(vias allowed)
			(pads allowed)
			(copperpour not_allowed)
			(footprints allowed)
		)
		(placement
			(enabled no)
			(sheetname "")
		)
		(fill yes
			(thermal_gap 0.5)
			(thermal_bridge_width 0.5)
			(island_removal_mode 0)
		)
		(polygon
			(pts
				(arc
					(start 377.41987 -256.634234)
					(mid 376.78995 -256.634234)
					(end 377.41987 -256.634234)
				)
			)
		)
	)
	(zone
		(layers "B.Cu" "In4.Cu" "In6.Cu" "In11.Cu" "In13.Cu" "In15.Cu")
		(hatch none 0.5)
		(connect_pads
			(clearance 0)
		)
		(min_thickness 0.25)
		(keepout
			(tracks not_allowed)
			(vias allowed)
			(pads allowed)
			(copperpour not_allowed)
			(footprints allowed)
		)
		(placement
			(enabled no)
			(sheetname "")
		)
		(fill yes
			(thermal_gap 0.5)
			(thermal_bridge_width 0.5)
			(island_removal_mode 0)
		)
		(polygon
			(pts
				(arc
					(start 427.790102 -295.935146)
					(mid 427.122082 -295.935146)
					(end 427.790102 -295.935146)
				)
			)
		)
	)
	(zone
		(layers "B.Cu" "In4.Cu" "In6.Cu" "In11.Cu" "In13.Cu" "In15.Cu")
		(hatch none 0.5)
		(connect_pads
			(clearance 0)
		)
		(min_thickness 0.25)
		(keepout
			(tracks not_allowed)
			(vias allowed)
			(pads allowed)
			(copperpour not_allowed)
			(footprints allowed)
		)
		(placement
			(enabled no)
			(sheetname "")
		)
		(fill yes
			(thermal_gap 0.5)
			(thermal_bridge_width 0.5)
			(island_removal_mode 0)
		)
		(polygon
			(pts
				(arc
					(start 128.839722 -291.906198)
					(mid 128.209802 -291.906198)
					(end 128.839722 -291.906198)
				)
			)
		)
	)
	(zone
		(layers "B.Cu" "In4.Cu" "In6.Cu" "In11.Cu" "In13.Cu" "In15.Cu")
		(hatch none 0.5)
		(connect_pads
			(clearance 0)
		)
		(min_thickness 0.25)
		(keepout
			(tracks not_allowed)
			(vias allowed)
			(pads allowed)
			(copperpour not_allowed)
			(footprints allowed)
		)
		(placement
			(enabled no)
			(sheetname "")
		)
		(fill yes
			(thermal_gap 0.5)
			(thermal_bridge_width 0.5)
			(island_removal_mode 0)
		)
		(polygon
			(pts
				(arc
					(start 40.57396 -235.585254)
					(mid 39.90594 -235.585254)
					(end 40.57396 -235.585254)
				)
			)
		)
	)
	(zone
		(layers "B.Cu" "In4.Cu" "In6.Cu" "In11.Cu" "In13.Cu" "In15.Cu")
		(hatch none 0.5)
		(connect_pads
			(clearance 0)
		)
		(min_thickness 0.25)
		(keepout
			(tracks not_allowed)
			(vias allowed)
			(pads allowed)
			(copperpour not_allowed)
			(footprints allowed)
		)
		(placement
			(enabled no)
			(sheetname "")
		)
		(fill yes
			(thermal_gap 0.5)
			(thermal_bridge_width 0.5)
			(island_removal_mode 0)
		)
		(polygon
			(pts
				(arc
					(start 431.89017 -216.035128)
					(mid 431.22215 -216.035128)
					(end 431.89017 -216.035128)
				)
			)
		)
	)
	(zone
		(layers "B.Cu" "In4.Cu" "In6.Cu" "In11.Cu" "In13.Cu" "In15.Cu")
		(hatch none 0.5)
		(connect_pads
			(clearance 0)
		)
		(min_thickness 0.25)
		(keepout
			(tracks not_allowed)
			(vias allowed)
			(pads allowed)
			(copperpour not_allowed)
			(footprints allowed)
		)
		(placement
			(enabled no)
			(sheetname "")
		)
		(fill yes
			(thermal_gap 0.5)
			(thermal_bridge_width 0.5)
			(island_removal_mode 0)
		)
		(polygon
			(pts
				(arc
					(start 44.674028 -298.485306)
					(mid 44.006008 -298.485306)
					(end 44.674028 -298.485306)
				)
			)
		)
	)
	(zone
		(layers "B.Cu" "In4.Cu" "In6.Cu" "In11.Cu" "In13.Cu" "In15.Cu")
		(hatch none 0.5)
		(connect_pads
			(clearance 0)
		)
		(min_thickness 0.25)
		(keepout
			(tracks not_allowed)
			(vias allowed)
			(pads allowed)
			(copperpour not_allowed)
			(footprints allowed)
		)
		(placement
			(enabled no)
			(sheetname "")
		)
		(fill yes
			(thermal_gap 0.5)
			(thermal_bridge_width 0.5)
			(island_removal_mode 0)
		)
		(polygon
			(pts
				(arc
					(start 44.674028 -306.135278)
					(mid 44.006008 -306.135278)
					(end 44.674028 -306.135278)
				)
			)
		)
	)
	(zone
		(layers "B.Cu" "In4.Cu" "In6.Cu" "In11.Cu" "In13.Cu" "In15.Cu")
		(hatch none 0.5)
		(connect_pads
			(clearance 0)
		)
		(min_thickness 0.25)
		(keepout
			(tracks not_allowed)
			(vias allowed)
			(pads allowed)
			(copperpour not_allowed)
			(footprints allowed)
		)
		(placement
			(enabled no)
			(sheetname "")
		)
		(fill yes
			(thermal_gap 0.5)
			(thermal_bridge_width 0.5)
			(island_removal_mode 0)
		)
		(polygon
			(pts
				(arc
					(start 179.850034 -302.735234)
					(mid 179.182014 -302.735234)
					(end 179.850034 -302.735234)
				)
			)
		)
	)
	(zone
		(layers "B.Cu" "In4.Cu" "In6.Cu" "In11.Cu" "In13.Cu" "In15.Cu")
		(hatch none 0.5)
		(connect_pads
			(clearance 0)
		)
		(min_thickness 0.25)
		(keepout
			(tracks not_allowed)
			(vias allowed)
			(pads allowed)
			(copperpour not_allowed)
			(footprints allowed)
		)
		(placement
			(enabled no)
			(sheetname "")
		)
		(fill yes
			(thermal_gap 0.5)
			(thermal_bridge_width 0.5)
			(island_removal_mode 0)
		)
		(polygon
			(pts
				(arc
					(start 94.536006 -263.556242)
					(mid 93.906086 -263.556242)
					(end 94.536006 -263.556242)
				)
			)
		)
	)
	(zone
		(layers "B.Cu" "In4.Cu" "In6.Cu" "In11.Cu" "In13.Cu" "In15.Cu")
		(hatch none 0.5)
		(connect_pads
			(clearance 0)
		)
		(min_thickness 0.25)
		(keepout
			(tracks not_allowed)
			(vias allowed)
			(pads allowed)
			(copperpour not_allowed)
			(footprints allowed)
		)
		(placement
			(enabled no)
			(sheetname "")
		)
		(fill yes
			(thermal_gap 0.5)
			(thermal_bridge_width 0.5)
			(island_removal_mode 0)
		)
		(polygon
			(pts
				(arc
					(start 376.77979 -278.946102)
					(mid 376.14987 -278.946102)
					(end 376.77979 -278.946102)
				)
			)
		)
	)
	(zone
		(layers "B.Cu" "In4.Cu" "In6.Cu" "In11.Cu" "In13.Cu" "In15.Cu")
		(hatch none 0.5)
		(connect_pads
			(clearance 0)
		)
		(min_thickness 0.25)
		(keepout
			(tracks not_allowed)
			(vias allowed)
			(pads allowed)
			(copperpour not_allowed)
			(footprints allowed)
		)
		(placement
			(enabled no)
			(sheetname "")
		)
		(fill yes
			(thermal_gap 0.5)
			(thermal_bridge_width 0.5)
			(island_removal_mode 0)
		)
		(polygon
			(pts
				(arc
					(start 376.009662 -255.824228)
					(mid 375.379742 -255.824228)
					(end 376.009662 -255.824228)
				)
			)
		)
	)
	(zone
		(layers "B.Cu" "In4.Cu" "In6.Cu" "In11.Cu" "In13.Cu" "In15.Cu")
		(hatch none 0.5)
		(connect_pads
			(clearance 0)
		)
		(min_thickness 0.25)
		(keepout
			(tracks not_allowed)
			(vias allowed)
			(pads allowed)
			(copperpour not_allowed)
			(footprints allowed)
		)
		(placement
			(enabled no)
			(sheetname "")
		)
		(fill yes
			(thermal_gap 0.5)
			(thermal_bridge_width 0.5)
			(island_removal_mode 0)
		)
		(polygon
			(pts
				(arc
					(start 431.89017 -311.23509)
					(mid 431.22215 -311.23509)
					(end 431.89017 -311.23509)
				)
			)
		)
	)
	(zone
		(layers "B.Cu" "In4.Cu" "In6.Cu" "In11.Cu" "In13.Cu" "In15.Cu")
		(hatch none 0.5)
		(connect_pads
			(clearance 0)
		)
		(min_thickness 0.25)
		(keepout
			(tracks not_allowed)
			(vias allowed)
			(pads allowed)
			(copperpour not_allowed)
			(footprints allowed)
		)
		(placement
			(enabled no)
			(sheetname "")
		)
		(fill yes
			(thermal_gap 0.5)
			(thermal_bridge_width 0.5)
			(island_removal_mode 0)
		)
		(polygon
			(pts
				(arc
					(start 179.850034 -295.9354)
					(mid 179.182014 -295.9354)
					(end 179.850034 -295.9354)
				)
			)
		)
	)
	(zone
		(layers "B.Cu" "In4.Cu" "In6.Cu" "In11.Cu" "In13.Cu" "In15.Cu")
		(hatch none 0.5)
		(connect_pads
			(clearance 0)
		)
		(min_thickness 0.25)
		(keepout
			(tracks not_allowed)
			(vias allowed)
			(pads allowed)
			(copperpour not_allowed)
			(footprints allowed)
		)
		(placement
			(enabled no)
			(sheetname "")
		)
		(fill yes
			(thermal_gap 0.5)
			(thermal_bridge_width 0.5)
			(island_removal_mode 0)
		)
		(polygon
			(pts
				(arc
					(start 128.369822 -263.556242)
					(mid 127.739902 -263.556242)
					(end 128.369822 -263.556242)
				)
			)
		)
	)
	(zone
		(layers "B.Cu" "In4.Cu" "In6.Cu" "In11.Cu" "In13.Cu" "In15.Cu")
		(hatch none 0.5)
		(connect_pads
			(clearance 0)
		)
		(min_thickness 0.25)
		(keepout
			(tracks not_allowed)
			(vias allowed)
			(pads allowed)
			(copperpour not_allowed)
			(footprints allowed)
		)
		(placement
			(enabled no)
			(sheetname "")
		)
		(fill yes
			(thermal_gap 0.5)
			(thermal_bridge_width 0.5)
			(island_removal_mode 0)
		)
		(polygon
			(pts
				(arc
					(start 431.89017 -203.28509)
					(mid 431.22215 -203.28509)
					(end 431.89017 -203.28509)
				)
			)
		)
	)
	(zone
		(layers "B.Cu" "In4.Cu" "In6.Cu" "In11.Cu" "In13.Cu" "In15.Cu")
		(hatch none 0.5)
		(connect_pads
			(clearance 0)
		)
		(min_thickness 0.25)
		(keepout
			(tracks not_allowed)
			(vias allowed)
			(pads allowed)
			(copperpour not_allowed)
			(footprints allowed)
		)
		(placement
			(enabled no)
			(sheetname "")
		)
		(fill yes
			(thermal_gap 0.5)
			(thermal_bridge_width 0.5)
			(island_removal_mode 0)
		)
		(polygon
			(pts
				(arc
					(start 343.886028 -291.905944)
					(mid 343.256108 -291.905944)
					(end 343.886028 -291.905944)
				)
			)
		)
	)
	(zone
		(layers "B.Cu" "In4.Cu" "In6.Cu" "In11.Cu" "In13.Cu" "In15.Cu")
		(hatch none 0.5)
		(connect_pads
			(clearance 0)
		)
		(min_thickness 0.25)
		(keepout
			(tracks not_allowed)
			(vias allowed)
			(pads allowed)
			(copperpour not_allowed)
			(footprints allowed)
		)
		(placement
			(enabled no)
			(sheetname "")
		)
		(fill yes
			(thermal_gap 0.5)
			(thermal_bridge_width 0.5)
			(island_removal_mode 0)
		)
		(polygon
			(pts
				(arc
					(start 427.790102 -226.235006)
					(mid 427.122082 -226.235006)
					(end 427.790102 -226.235006)
				)
			)
		)
	)
	(zone
		(layers "B.Cu" "In4.Cu" "In6.Cu" "In11.Cu" "In13.Cu" "In15.Cu")
		(hatch none 0.5)
		(connect_pads
			(clearance 0)
		)
		(min_thickness 0.25)
		(keepout
			(tracks not_allowed)
			(vias allowed)
			(pads allowed)
			(copperpour not_allowed)
			(footprints allowed)
		)
		(placement
			(enabled no)
			(sheetname "")
		)
		(fill yes
			(thermal_gap 0.5)
			(thermal_bridge_width 0.5)
			(island_removal_mode 0)
		)
		(polygon
			(pts
				(arc
					(start 40.57396 -248.335292)
					(mid 39.90594 -248.335292)
					(end 40.57396 -248.335292)
				)
			)
		)
	)
	(zone
		(layers "B.Cu" "In4.Cu" "In6.Cu" "In11.Cu" "In13.Cu" "In15.Cu")
		(hatch none 0.5)
		(connect_pads
			(clearance 0)
		)
		(min_thickness 0.25)
		(keepout
			(tracks not_allowed)
			(vias allowed)
			(pads allowed)
			(copperpour not_allowed)
			(footprints allowed)
		)
		(placement
			(enabled no)
			(sheetname "")
		)
		(fill yes
			(thermal_gap 0.5)
			(thermal_bridge_width 0.5)
			(island_removal_mode 0)
		)
		(polygon
			(pts
				(arc
					(start 364.729776 -228.284278)
					(mid 364.099856 -228.284278)
					(end 364.729776 -228.284278)
				)
			)
		)
	)
	(zone
		(layers "B.Cu" "In4.Cu" "In6.Cu" "In11.Cu" "In13.Cu" "In15.Cu")
		(hatch none 0.5)
		(connect_pads
			(clearance 0)
		)
		(min_thickness 0.25)
		(keepout
			(tracks not_allowed)
			(vias allowed)
			(pads allowed)
			(copperpour not_allowed)
			(footprints allowed)
		)
		(placement
			(enabled no)
			(sheetname "")
		)
		(fill yes
			(thermal_gap 0.5)
			(thermal_bridge_width 0.5)
			(island_removal_mode 0)
		)
		(polygon
			(pts
				(arc
					(start 343.886028 -264.365994)
					(mid 343.256108 -264.365994)
					(end 343.886028 -264.365994)
				)
			)
		)
	)
	(zone
		(layers "B.Cu" "In4.Cu" "In6.Cu" "In11.Cu" "In13.Cu" "In15.Cu")
		(hatch none 0.5)
		(connect_pads
			(clearance 0)
		)
		(min_thickness 0.25)
		(keepout
			(tracks not_allowed)
			(vias allowed)
			(pads allowed)
			(copperpour not_allowed)
			(footprints allowed)
		)
		(placement
			(enabled no)
			(sheetname "")
		)
		(fill yes
			(thermal_gap 0.5)
			(thermal_bridge_width 0.5)
			(island_removal_mode 0)
		)
		(polygon
			(pts
				(arc
					(start 427.790102 -261.93496)
					(mid 427.122082 -261.93496)
					(end 427.790102 -261.93496)
				)
			)
		)
	)
	(zone
		(layers "B.Cu" "In4.Cu" "In6.Cu" "In11.Cu" "In13.Cu" "In15.Cu")
		(hatch none 0.5)
		(connect_pads
			(clearance 0)
		)
		(min_thickness 0.25)
		(keepout
			(tracks not_allowed)
			(vias allowed)
			(pads allowed)
			(copperpour not_allowed)
			(footprints allowed)
		)
		(placement
			(enabled no)
			(sheetname "")
		)
		(fill yes
			(thermal_gap 0.5)
			(thermal_bridge_width 0.5)
			(island_removal_mode 0)
		)
		(polygon
			(pts
				(arc
					(start 288.514028 -239.835182)
					(mid 287.846008 -239.835182)
					(end 288.514028 -239.835182)
				)
			)
		)
	)
	(zone
		(layers "B.Cu" "In4.Cu" "In6.Cu" "In11.Cu" "In13.Cu" "In15.Cu")
		(hatch none 0.5)
		(connect_pads
			(clearance 0)
		)
		(min_thickness 0.25)
		(keepout
			(tracks not_allowed)
			(vias allowed)
			(pads allowed)
			(copperpour not_allowed)
			(footprints allowed)
		)
		(placement
			(enabled no)
			(sheetname "")
		)
		(fill yes
			(thermal_gap 0.5)
			(thermal_bridge_width 0.5)
			(island_removal_mode 0)
		)
		(polygon
			(pts
				(arc
					(start 44.674028 -245.785386)
					(mid 44.006008 -245.785386)
					(end 44.674028 -245.785386)
				)
			)
		)
	)
	(zone
		(layers "B.Cu" "In4.Cu" "In6.Cu" "In11.Cu" "In13.Cu" "In15.Cu")
		(hatch none 0.5)
		(connect_pads
			(clearance 0)
		)
		(min_thickness 0.25)
		(keepout
			(tracks not_allowed)
			(vias allowed)
			(pads allowed)
			(copperpour not_allowed)
			(footprints allowed)
		)
		(placement
			(enabled no)
			(sheetname "")
		)
		(fill yes
			(thermal_gap 0.5)
			(thermal_bridge_width 0.5)
			(island_removal_mode 0)
		)
		(polygon
			(pts
				(arc
					(start 376.30989 -263.555988)
					(mid 375.67997 -263.555988)
					(end 376.30989 -263.555988)
				)
			)
		)
	)
	(zone
		(layers "B.Cu" "In4.Cu" "In6.Cu" "In11.Cu" "In13.Cu" "In15.Cu")
		(hatch none 0.5)
		(connect_pads
			(clearance 0)
		)
		(min_thickness 0.25)
		(keepout
			(tracks not_allowed)
			(vias allowed)
			(pads allowed)
			(copperpour not_allowed)
			(footprints allowed)
		)
		(placement
			(enabled no)
			(sheetname "")
		)
		(fill yes
			(thermal_gap 0.5)
			(thermal_bridge_width 0.5)
			(island_removal_mode 0)
		)
		(polygon
			(pts
				(arc
					(start 94.705932 -233.95432)
					(mid 94.076012 -233.95432)
					(end 94.705932 -233.95432)
				)
			)
		)
	)
	(zone
		(layers "B.Cu" "In4.Cu" "In6.Cu" "In11.Cu" "In13.Cu" "In15.Cu")
		(hatch none 0.5)
		(connect_pads
			(clearance 0)
		)
		(min_thickness 0.25)
		(keepout
			(tracks not_allowed)
			(vias allowed)
			(pads allowed)
			(copperpour not_allowed)
			(footprints allowed)
		)
		(placement
			(enabled no)
			(sheetname "")
		)
		(fill yes
			(thermal_gap 0.5)
			(thermal_bridge_width 0.5)
			(island_removal_mode 0)
		)
		(polygon
			(pts
				(arc
					(start 183.950102 -197.335394)
					(mid 183.282082 -197.335394)
					(end 183.950102 -197.335394)
				)
			)
		)
	)
	(zone
		(layers "B.Cu" "In4.Cu" "In6.Cu" "In11.Cu" "In13.Cu" "In15.Cu")
		(hatch none 0.5)
		(connect_pads
			(clearance 0)
		)
		(min_thickness 0.25)
		(keepout
			(tracks not_allowed)
			(vias allowed)
			(pads allowed)
			(copperpour not_allowed)
			(footprints allowed)
		)
		(placement
			(enabled no)
			(sheetname "")
		)
		(fill yes
			(thermal_gap 0.5)
			(thermal_bridge_width 0.5)
			(island_removal_mode 0)
		)
		(polygon
			(pts
				(arc
					(start 96.416114 -274.896326)
					(mid 95.786194 -274.896326)
					(end 96.416114 -274.896326)
				)
			)
		)
	)
	(zone
		(layers "B.Cu" "In4.Cu" "In6.Cu" "In11.Cu" "In13.Cu" "In15.Cu")
		(hatch none 0.5)
		(connect_pads
			(clearance 0)
		)
		(min_thickness 0.25)
		(keepout
			(tracks not_allowed)
			(vias allowed)
			(pads allowed)
			(copperpour not_allowed)
			(footprints allowed)
		)
		(placement
			(enabled no)
			(sheetname "")
		)
		(fill yes
			(thermal_gap 0.5)
			(thermal_bridge_width 0.5)
			(island_removal_mode 0)
		)
		(polygon
			(pts
				(arc
					(start 40.57396 -211.7852)
					(mid 39.90594 -211.7852)
					(end 40.57396 -211.7852)
				)
			)
		)
	)
	(zone
		(layers "B.Cu" "In4.Cu" "In6.Cu" "In11.Cu" "In13.Cu" "In15.Cu")
		(hatch none 0.5)
		(connect_pads
			(clearance 0)
		)
		(min_thickness 0.25)
		(keepout
			(tracks not_allowed)
			(vias allowed)
			(pads allowed)
			(copperpour not_allowed)
			(footprints allowed)
		)
		(placement
			(enabled no)
			(sheetname "")
		)
		(fill yes
			(thermal_gap 0.5)
			(thermal_bridge_width 0.5)
			(island_removal_mode 0)
		)
		(polygon
			(pts
				(arc
					(start 96.416114 -263.556242)
					(mid 95.786194 -263.556242)
					(end 96.416114 -263.556242)
				)
			)
		)
	)
	(zone
		(layers "B.Cu" "In4.Cu" "In6.Cu" "In11.Cu" "In13.Cu" "In15.Cu")
		(hatch none 0.5)
		(connect_pads
			(clearance 0)
		)
		(min_thickness 0.25)
		(keepout
			(tracks not_allowed)
			(vias allowed)
			(pads allowed)
			(copperpour not_allowed)
			(footprints allowed)
		)
		(placement
			(enabled no)
			(sheetname "")
		)
		(fill yes
			(thermal_gap 0.5)
			(thermal_bridge_width 0.5)
			(island_removal_mode 0)
		)
		(polygon
			(pts
				(arc
					(start 376.009662 -234.764072)
					(mid 375.379742 -234.764072)
					(end 376.009662 -234.764072)
				)
			)
		)
	)
	(zone
		(layers "B.Cu" "In4.Cu" "In6.Cu" "In11.Cu" "In13.Cu" "In15.Cu")
		(hatch none 0.5)
		(connect_pads
			(clearance 0)
		)
		(min_thickness 0.25)
		(keepout
			(tracks not_allowed)
			(vias allowed)
			(pads allowed)
			(copperpour not_allowed)
			(footprints allowed)
		)
		(placement
			(enabled no)
			(sheetname "")
		)
		(fill yes
			(thermal_gap 0.5)
			(thermal_bridge_width 0.5)
			(island_removal_mode 0)
		)
		(polygon
			(pts
				(arc
					(start 376.479816 -246.914162)
					(mid 375.849896 -246.914162)
					(end 376.479816 -246.914162)
				)
			)
		)
	)
	(zone
		(layers "B.Cu" "In4.Cu" "In6.Cu" "In11.Cu" "In13.Cu" "In15.Cu")
		(hatch none 0.5)
		(connect_pads
			(clearance 0)
		)
		(min_thickness 0.25)
		(keepout
			(tracks not_allowed)
			(vias allowed)
			(pads allowed)
			(copperpour not_allowed)
			(footprints allowed)
		)
		(placement
			(enabled no)
			(sheetname "")
		)
		(fill yes
			(thermal_gap 0.5)
			(thermal_bridge_width 0.5)
			(island_removal_mode 0)
		)
		(polygon
			(pts
				(arc
					(start 40.57396 -308.685438)
					(mid 39.90594 -308.685438)
					(end 40.57396 -308.685438)
				)
			)
		)
	)
	(zone
		(layers "B.Cu" "In4.Cu" "In6.Cu" "In11.Cu" "In13.Cu" "In15.Cu")
		(hatch none 0.5)
		(connect_pads
			(clearance 0)
		)
		(min_thickness 0.25)
		(keepout
			(tracks not_allowed)
			(vias allowed)
			(pads allowed)
			(copperpour not_allowed)
			(footprints allowed)
		)
		(placement
			(enabled no)
			(sheetname "")
		)
		(fill yes
			(thermal_gap 0.5)
			(thermal_bridge_width 0.5)
			(island_removal_mode 0)
		)
		(polygon
			(pts
				(arc
					(start 128.839722 -270.846296)
					(mid 128.209802 -270.846296)
					(end 128.839722 -270.846296)
				)
			)
		)
	)
	(zone
		(layers "B.Cu" "In4.Cu" "In6.Cu" "In11.Cu" "In13.Cu" "In15.Cu")
		(hatch none 0.5)
		(connect_pads
			(clearance 0)
		)
		(min_thickness 0.25)
		(keepout
			(tracks not_allowed)
			(vias allowed)
			(pads allowed)
			(copperpour not_allowed)
			(footprints allowed)
		)
		(placement
			(enabled no)
			(sheetname "")
		)
		(fill yes
			(thermal_gap 0.5)
			(thermal_bridge_width 0.5)
			(island_removal_mode 0)
		)
		(polygon
			(pts
				(arc
					(start 288.514028 -220.285056)
					(mid 287.846008 -220.285056)
					(end 288.514028 -220.285056)
				)
			)
		)
	)
	(zone
		(layers "B.Cu" "In4.Cu" "In6.Cu" "In11.Cu" "In13.Cu" "In15.Cu")
		(hatch none 0.5)
		(connect_pads
			(clearance 0)
		)
		(min_thickness 0.25)
		(keepout
			(tracks not_allowed)
			(vias allowed)
			(pads allowed)
			(copperpour not_allowed)
			(footprints allowed)
		)
		(placement
			(enabled no)
			(sheetname "")
		)
		(fill yes
			(thermal_gap 0.5)
			(thermal_bridge_width 0.5)
			(island_removal_mode 0)
		)
		(polygon
			(pts
				(arc
					(start 44.674028 -270.435324)
					(mid 44.006008 -270.435324)
					(end 44.674028 -270.435324)
				)
			)
		)
	)
	(zone
		(layers "B.Cu" "In4.Cu" "In6.Cu" "In11.Cu" "In13.Cu" "In15.Cu")
		(hatch none 0.5)
		(connect_pads
			(clearance 0)
		)
		(min_thickness 0.25)
		(keepout
			(tracks not_allowed)
			(vias allowed)
			(pads allowed)
			(copperpour not_allowed)
			(footprints allowed)
		)
		(placement
			(enabled no)
			(sheetname "")
		)
		(fill yes
			(thermal_gap 0.5)
			(thermal_bridge_width 0.5)
			(island_removal_mode 0)
		)
		(polygon
			(pts
				(arc
					(start 288.514028 -313.784996)
					(mid 287.846008 -313.784996)
					(end 288.514028 -313.784996)
				)
			)
		)
	)
	(zone
		(layers "B.Cu" "In4.Cu" "In6.Cu" "In11.Cu" "In13.Cu" "In15.Cu")
		(hatch none 0.5)
		(connect_pads
			(clearance 0)
		)
		(min_thickness 0.25)
		(keepout
			(tracks not_allowed)
			(vias allowed)
			(pads allowed)
			(copperpour not_allowed)
			(footprints allowed)
		)
		(placement
			(enabled no)
			(sheetname "")
		)
		(fill yes
			(thermal_gap 0.5)
			(thermal_bridge_width 0.5)
			(island_removal_mode 0)
		)
		(polygon
			(pts
				(arc
					(start 288.514028 -235.585)
					(mid 287.846008 -235.585)
					(end 288.514028 -235.585)
				)
			)
		)
	)
	(zone
		(layers "B.Cu" "In4.Cu" "In6.Cu" "In11.Cu" "In13.Cu" "In15.Cu")
		(hatch none 0.5)
		(connect_pads
			(clearance 0)
		)
		(min_thickness 0.25)
		(keepout
			(tracks not_allowed)
			(vias allowed)
			(pads allowed)
			(copperpour not_allowed)
			(footprints allowed)
		)
		(placement
			(enabled no)
			(sheetname "")
		)
		(fill yes
			(thermal_gap 0.5)
			(thermal_bridge_width 0.5)
			(island_removal_mode 0)
		)
		(polygon
			(pts
				(arc
					(start 377.41987 -253.39421)
					(mid 376.78995 -253.39421)
					(end 377.41987 -253.39421)
				)
			)
		)
	)
	(zone
		(layers "B.Cu" "In4.Cu" "In6.Cu" "In11.Cu" "In13.Cu" "In15.Cu")
		(hatch none 0.5)
		(connect_pads
			(clearance 0)
		)
		(min_thickness 0.25)
		(keepout
			(tracks not_allowed)
			(vias allowed)
			(pads allowed)
			(copperpour not_allowed)
			(footprints allowed)
		)
		(placement
			(enabled no)
			(sheetname "")
		)
		(fill yes
			(thermal_gap 0.5)
			(thermal_bridge_width 0.5)
			(island_removal_mode 0)
		)
		(polygon
			(pts
				(arc
					(start 292.614096 -197.33514)
					(mid 291.946076 -197.33514)
					(end 292.614096 -197.33514)
				)
			)
		)
	)
	(zone
		(layers "B.Cu" "In4.Cu" "In6.Cu" "In11.Cu" "In13.Cu" "In15.Cu")
		(hatch none 0.5)
		(connect_pads
			(clearance 0)
		)
		(min_thickness 0.25)
		(keepout
			(tracks not_allowed)
			(vias allowed)
			(pads allowed)
			(copperpour not_allowed)
			(footprints allowed)
		)
		(placement
			(enabled no)
			(sheetname "")
		)
		(fill yes
			(thermal_gap 0.5)
			(thermal_bridge_width 0.5)
			(island_removal_mode 0)
		)
		(polygon
			(pts
				(arc
					(start 179.850034 -288.285428)
					(mid 179.182014 -288.285428)
					(end 179.850034 -288.285428)
				)
			)
		)
	)
	(zone
		(layers "B.Cu" "In4.Cu" "In6.Cu" "In11.Cu" "In13.Cu" "In15.Cu")
		(hatch none 0.5)
		(connect_pads
			(clearance 0)
		)
		(min_thickness 0.25)
		(keepout
			(tracks not_allowed)
			(vias allowed)
			(pads allowed)
			(copperpour not_allowed)
			(footprints allowed)
		)
		(placement
			(enabled no)
			(sheetname "")
		)
		(fill yes
			(thermal_gap 0.5)
			(thermal_bridge_width 0.5)
			(island_removal_mode 0)
		)
		(polygon
			(pts
				(arc
					(start 129.479802 -229.094538)
					(mid 128.849882 -229.094538)
					(end 129.479802 -229.094538)
				)
			)
		)
	)
	(zone
		(layers "B.Cu" "In4.Cu" "In6.Cu" "In11.Cu" "In13.Cu" "In15.Cu")
		(hatch none 0.5)
		(connect_pads
			(clearance 0)
		)
		(min_thickness 0.25)
		(keepout
			(tracks not_allowed)
			(vias allowed)
			(pads allowed)
			(copperpour not_allowed)
			(footprints allowed)
		)
		(placement
			(enabled no)
			(sheetname "")
		)
		(fill yes
			(thermal_gap 0.5)
			(thermal_bridge_width 0.5)
			(island_removal_mode 0)
		)
		(polygon
			(pts
				(arc
					(start 44.674028 -290.835334)
					(mid 44.006008 -290.835334)
					(end 44.674028 -290.835334)
				)
			)
		)
	)
	(zone
		(layers "B.Cu" "In4.Cu" "In6.Cu" "In11.Cu" "In13.Cu" "In15.Cu")
		(hatch none 0.5)
		(connect_pads
			(clearance 0)
		)
		(min_thickness 0.25)
		(keepout
			(tracks not_allowed)
			(vias allowed)
			(pads allowed)
			(copperpour not_allowed)
			(footprints allowed)
		)
		(placement
			(enabled no)
			(sheetname "")
		)
		(fill yes
			(thermal_gap 0.5)
			(thermal_bridge_width 0.5)
			(island_removal_mode 0)
		)
		(polygon
			(pts
				(arc
					(start 427.790102 -280.634948)
					(mid 427.122082 -280.634948)
					(end 427.790102 -280.634948)
				)
			)
		)
	)
	(zone
		(layers "B.Cu" "In4.Cu" "In6.Cu" "In11.Cu" "In13.Cu" "In15.Cu")
		(hatch none 0.5)
		(connect_pads
			(clearance 0)
		)
		(min_thickness 0.25)
		(keepout
			(tracks not_allowed)
			(vias allowed)
			(pads allowed)
			(copperpour not_allowed)
			(footprints allowed)
		)
		(placement
			(enabled no)
			(sheetname "")
		)
		(fill yes
			(thermal_gap 0.5)
			(thermal_bridge_width 0.5)
			(island_removal_mode 0)
		)
		(polygon
			(pts
				(arc
					(start 96.115886 -239.624362)
					(mid 95.485966 -239.624362)
					(end 96.115886 -239.624362)
				)
			)
		)
	)
	(zone
		(layers "B.Cu" "In4.Cu" "In6.Cu" "In11.Cu" "In13.Cu" "In15.Cu")
		(hatch none 0.5)
		(connect_pads
			(clearance 0)
		)
		(min_thickness 0.25)
		(keepout
			(tracks not_allowed)
			(vias allowed)
			(pads allowed)
			(copperpour not_allowed)
			(footprints allowed)
		)
		(placement
			(enabled no)
			(sheetname "")
		)
		(fill yes
			(thermal_gap 0.5)
			(thermal_bridge_width 0.5)
			(island_removal_mode 0)
		)
		(polygon
			(pts
				(arc
					(start 183.950102 -270.435324)
					(mid 183.282082 -270.435324)
					(end 183.950102 -270.435324)
				)
			)
		)
	)
	(zone
		(layers "B.Cu" "In4.Cu" "In6.Cu" "In11.Cu" "In13.Cu" "In15.Cu")
		(hatch none 0.5)
		(connect_pads
			(clearance 0)
		)
		(min_thickness 0.25)
		(keepout
			(tracks not_allowed)
			(vias allowed)
			(pads allowed)
			(copperpour not_allowed)
			(footprints allowed)
		)
		(placement
			(enabled no)
			(sheetname "")
		)
		(fill yes
			(thermal_gap 0.5)
			(thermal_bridge_width 0.5)
			(island_removal_mode 0)
		)
		(polygon
			(pts
				(arc
					(start 431.89017 -238.13516)
					(mid 431.22215 -238.13516)
					(end 431.89017 -238.13516)
				)
			)
		)
	)
	(zone
		(layers "B.Cu" "In4.Cu" "In6.Cu" "In11.Cu" "In13.Cu" "In15.Cu")
		(hatch none 0.5)
		(connect_pads
			(clearance 0)
		)
		(min_thickness 0.25)
		(keepout
			(tracks not_allowed)
			(vias allowed)
			(pads allowed)
			(copperpour not_allowed)
			(footprints allowed)
		)
		(placement
			(enabled no)
			(sheetname "")
		)
		(fill yes
			(thermal_gap 0.5)
			(thermal_bridge_width 0.5)
			(island_removal_mode 0)
		)
		(polygon
			(pts
				(arc
					(start 179.850034 -297.635422)
					(mid 179.182014 -297.635422)
					(end 179.850034 -297.635422)
				)
			)
		)
	)
	(zone
		(layers "B.Cu" "In4.Cu" "In6.Cu" "In11.Cu" "In13.Cu" "In15.Cu")
		(hatch none 0.5)
		(connect_pads
			(clearance 0)
		)
		(min_thickness 0.25)
		(keepout
			(tracks not_allowed)
			(vias allowed)
			(pads allowed)
			(copperpour not_allowed)
			(footprints allowed)
		)
		(placement
			(enabled no)
			(sheetname "")
		)
		(fill yes
			(thermal_gap 0.5)
			(thermal_bridge_width 0.5)
			(island_removal_mode 0)
		)
		(polygon
			(pts
				(arc
					(start 44.674028 -304.435256)
					(mid 44.006008 -304.435256)
					(end 44.674028 -304.435256)
				)
			)
		)
	)
	(zone
		(layers "B.Cu" "In4.Cu" "In6.Cu" "In11.Cu" "In13.Cu" "In15.Cu")
		(hatch none 0.5)
		(connect_pads
			(clearance 0)
		)
		(min_thickness 0.25)
		(keepout
			(tracks not_allowed)
			(vias allowed)
			(pads allowed)
			(copperpour not_allowed)
			(footprints allowed)
		)
		(placement
			(enabled no)
			(sheetname "")
		)
		(fill yes
			(thermal_gap 0.5)
			(thermal_bridge_width 0.5)
			(island_removal_mode 0)
		)
		(polygon
			(pts
				(arc
					(start 129.779776 -272.466308)
					(mid 129.149856 -272.466308)
					(end 129.779776 -272.466308)
				)
			)
		)
	)
	(zone
		(layers "B.Cu" "In4.Cu" "In6.Cu" "In11.Cu" "In13.Cu" "In15.Cu")
		(hatch none 0.5)
		(connect_pads
			(clearance 0)
		)
		(min_thickness 0.25)
		(keepout
			(tracks not_allowed)
			(vias allowed)
			(pads allowed)
			(copperpour not_allowed)
			(footprints allowed)
		)
		(placement
			(enabled no)
			(sheetname "")
		)
		(fill yes
			(thermal_gap 0.5)
			(thermal_bridge_width 0.5)
			(island_removal_mode 0)
		)
		(polygon
			(pts
				(arc
					(start 342.945974 -264.365994)
					(mid 342.316054 -264.365994)
					(end 342.945974 -264.365994)
				)
			)
		)
	)
	(zone
		(layers "B.Cu" "In4.Cu" "In6.Cu" "In11.Cu" "In13.Cu" "In15.Cu")
		(hatch none 0.5)
		(connect_pads
			(clearance 0)
		)
		(min_thickness 0.25)
		(keepout
			(tracks not_allowed)
			(vias allowed)
			(pads allowed)
			(copperpour not_allowed)
			(footprints allowed)
		)
		(placement
			(enabled no)
			(sheetname "")
		)
		(fill yes
			(thermal_gap 0.5)
			(thermal_bridge_width 0.5)
			(island_removal_mode 0)
		)
		(polygon
			(pts
				(arc
					(start 431.89017 -276.38502)
					(mid 431.22215 -276.38502)
					(end 431.89017 -276.38502)
				)
			)
		)
	)
	(zone
		(layers "B.Cu" "In4.Cu" "In6.Cu" "In11.Cu" "In13.Cu" "In15.Cu")
		(hatch none 0.5)
		(connect_pads
			(clearance 0)
		)
		(min_thickness 0.25)
		(keepout
			(tracks not_allowed)
			(vias allowed)
			(pads allowed)
			(copperpour not_allowed)
			(footprints allowed)
		)
		(placement
			(enabled no)
			(sheetname "")
		)
		(fill yes
			(thermal_gap 0.5)
			(thermal_bridge_width 0.5)
			(island_removal_mode 0)
		)
		(polygon
			(pts
				(arc
					(start 292.614096 -201.585068)
					(mid 291.946076 -201.585068)
					(end 292.614096 -201.585068)
				)
			)
		)
	)
	(zone
		(layers "B.Cu" "In4.Cu" "In6.Cu" "In11.Cu" "In13.Cu" "In15.Cu")
		(hatch none 0.5)
		(connect_pads
			(clearance 0)
		)
		(min_thickness 0.25)
		(keepout
			(tracks not_allowed)
			(vias allowed)
			(pads allowed)
			(copperpour not_allowed)
			(footprints allowed)
		)
		(placement
			(enabled no)
			(sheetname "")
		)
		(fill yes
			(thermal_gap 0.5)
			(thermal_bridge_width 0.5)
			(island_removal_mode 0)
		)
		(polygon
			(pts
				(arc
					(start 183.950102 -298.485306)
					(mid 183.282082 -298.485306)
					(end 183.950102 -298.485306)
				)
			)
		)
	)
	(zone
		(layers "B.Cu" "In4.Cu" "In6.Cu" "In11.Cu" "In13.Cu" "In15.Cu")
		(hatch none 0.5)
		(connect_pads
			(clearance 0)
		)
		(min_thickness 0.25)
		(keepout
			(tracks not_allowed)
			(vias allowed)
			(pads allowed)
			(copperpour not_allowed)
			(footprints allowed)
		)
		(placement
			(enabled no)
			(sheetname "")
		)
		(fill yes
			(thermal_gap 0.5)
			(thermal_bridge_width 0.5)
			(island_removal_mode 0)
		)
		(polygon
			(pts
				(arc
					(start 376.479816 -250.154186)
					(mid 375.849896 -250.154186)
					(end 376.479816 -250.154186)
				)
			)
		)
	)
	(zone
		(layers "B.Cu" "In4.Cu" "In6.Cu" "In11.Cu" "In13.Cu" "In15.Cu")
		(hatch none 0.5)
		(connect_pads
			(clearance 0)
		)
		(min_thickness 0.25)
		(keepout
			(tracks not_allowed)
			(vias allowed)
			(pads allowed)
			(copperpour not_allowed)
			(footprints allowed)
		)
		(placement
			(enabled no)
			(sheetname "")
		)
		(fill yes
			(thermal_gap 0.5)
			(thermal_bridge_width 0.5)
			(island_removal_mode 0)
		)
		(polygon
			(pts
				(arc
					(start 179.345844 -49.48174)
					(mid 178.677824 -49.48174)
					(end 179.345844 -49.48174)
				)
			)
		)
	)
	(zone
		(layers "B.Cu" "In4.Cu" "In6.Cu" "In11.Cu" "In13.Cu" "In15.Cu")
		(hatch none 0.5)
		(connect_pads
			(clearance 0)
		)
		(min_thickness 0.25)
		(keepout
			(tracks not_allowed)
			(vias allowed)
			(pads allowed)
			(copperpour not_allowed)
			(footprints allowed)
		)
		(placement
			(enabled no)
			(sheetname "")
		)
		(fill yes
			(thermal_gap 0.5)
			(thermal_bridge_width 0.5)
			(island_removal_mode 0)
		)
		(polygon
			(pts
				(arc
					(start 344.055954 -233.14406)
					(mid 343.426034 -233.14406)
					(end 344.055954 -233.14406)
				)
			)
		)
	)
	(zone
		(layers "B.Cu" "In4.Cu" "In6.Cu" "In11.Cu" "In13.Cu" "In15.Cu")
		(hatch none 0.5)
		(connect_pads
			(clearance 0)
		)
		(min_thickness 0.25)
		(keepout
			(tracks not_allowed)
			(vias allowed)
			(pads allowed)
			(copperpour not_allowed)
			(footprints allowed)
		)
		(placement
			(enabled no)
			(sheetname "")
		)
		(fill yes
			(thermal_gap 0.5)
			(thermal_bridge_width 0.5)
			(island_removal_mode 0)
		)
		(polygon
			(pts
				(arc
					(start 179.850034 -221.135194)
					(mid 179.182014 -221.135194)
					(end 179.850034 -221.135194)
				)
			)
		)
	)
	(zone
		(layers "B.Cu" "In4.Cu" "In6.Cu" "In11.Cu" "In13.Cu" "In15.Cu")
		(hatch none 0.5)
		(connect_pads
			(clearance 0)
		)
		(min_thickness 0.25)
		(keepout
			(tracks not_allowed)
			(vias allowed)
			(pads allowed)
			(copperpour not_allowed)
			(footprints allowed)
		)
		(placement
			(enabled no)
			(sheetname "")
		)
		(fill yes
			(thermal_gap 0.5)
			(thermal_bridge_width 0.5)
			(island_removal_mode 0)
		)
		(polygon
			(pts
				(arc
					(start 96.115886 -255.824482)
					(mid 95.485966 -255.824482)
					(end 96.115886 -255.824482)
				)
			)
		)
	)
	(zone
		(layers "B.Cu" "In4.Cu" "In6.Cu" "In11.Cu" "In13.Cu" "In15.Cu")
		(hatch none 0.5)
		(connect_pads
			(clearance 0)
		)
		(min_thickness 0.25)
		(keepout
			(tracks not_allowed)
			(vias allowed)
			(pads allowed)
			(copperpour not_allowed)
			(footprints allowed)
		)
		(placement
			(enabled no)
			(sheetname "")
		)
		(fill yes
			(thermal_gap 0.5)
			(thermal_bridge_width 0.5)
			(island_removal_mode 0)
		)
		(polygon
			(pts
				(arc
					(start 427.790102 -314.635134)
					(mid 427.122082 -314.635134)
					(end 427.790102 -314.635134)
				)
			)
		)
	)
	(zone
		(layers "B.Cu" "In4.Cu" "In6.Cu" "In11.Cu" "In13.Cu" "In15.Cu")
		(hatch none 0.5)
		(connect_pads
			(clearance 0)
		)
		(min_thickness 0.25)
		(keepout
			(tracks not_allowed)
			(vias allowed)
			(pads allowed)
			(copperpour not_allowed)
			(footprints allowed)
		)
		(placement
			(enabled no)
			(sheetname "")
		)
		(fill yes
			(thermal_gap 0.5)
			(thermal_bridge_width 0.5)
			(island_removal_mode 0)
		)
		(polygon
			(pts
				(arc
					(start 376.479816 -235.574078)
					(mid 375.849896 -235.574078)
					(end 376.479816 -235.574078)
				)
			)
		)
	)
	(zone
		(layers "B.Cu" "In4.Cu" "In6.Cu" "In11.Cu" "In13.Cu" "In15.Cu")
		(hatch none 0.5)
		(connect_pads
			(clearance 0)
		)
		(min_thickness 0.25)
		(keepout
			(tracks not_allowed)
			(vias allowed)
			(pads allowed)
			(copperpour not_allowed)
			(footprints allowed)
		)
		(placement
			(enabled no)
			(sheetname "")
		)
		(fill yes
			(thermal_gap 0.5)
			(thermal_bridge_width 0.5)
			(island_removal_mode 0)
		)
		(polygon
			(pts
				(arc
					(start 129.949702 -228.284532)
					(mid 129.319782 -228.284532)
					(end 129.949702 -228.284532)
				)
			)
		)
	)
	(zone
		(layers "B.Cu" "In4.Cu" "In6.Cu" "In11.Cu" "In13.Cu" "In15.Cu")
		(hatch none 0.5)
		(connect_pads
			(clearance 0)
		)
		(min_thickness 0.25)
		(keepout
			(tracks not_allowed)
			(vias allowed)
			(pads allowed)
			(copperpour not_allowed)
			(footprints allowed)
		)
		(placement
			(enabled no)
			(sheetname "")
		)
		(fill yes
			(thermal_gap 0.5)
			(thermal_bridge_width 0.5)
			(island_removal_mode 0)
		)
		(polygon
			(pts
				(arc
					(start 288.514028 -216.885012)
					(mid 287.846008 -216.885012)
					(end 288.514028 -216.885012)
				)
			)
		)
	)
	(zone
		(layers "B.Cu" "In4.Cu" "In6.Cu" "In11.Cu" "In13.Cu" "In15.Cu")
		(hatch none 0.5)
		(connect_pads
			(clearance 0)
		)
		(min_thickness 0.25)
		(keepout
			(tracks not_allowed)
			(vias allowed)
			(pads allowed)
			(copperpour not_allowed)
			(footprints allowed)
		)
		(placement
			(enabled no)
			(sheetname "")
		)
		(fill yes
			(thermal_gap 0.5)
			(thermal_bridge_width 0.5)
			(island_removal_mode 0)
		)
		(polygon
			(pts
				(arc
					(start 288.514028 -213.484968)
					(mid 287.846008 -213.484968)
					(end 288.514028 -213.484968)
				)
			)
		)
	)
	(zone
		(layers "B.Cu" "In4.Cu" "In6.Cu" "In11.Cu" "In13.Cu" "In15.Cu")
		(hatch none 0.5)
		(connect_pads
			(clearance 0)
		)
		(min_thickness 0.25)
		(keepout
			(tracks not_allowed)
			(vias allowed)
			(pads allowed)
			(copperpour not_allowed)
			(footprints allowed)
		)
		(placement
			(enabled no)
			(sheetname "")
		)
		(fill yes
			(thermal_gap 0.5)
			(thermal_bridge_width 0.5)
			(island_removal_mode 0)
		)
		(polygon
			(pts
				(arc
					(start 179.850034 -314.635388)
					(mid 179.182014 -314.635388)
					(end 179.850034 -314.635388)
				)
			)
		)
	)
	(zone
		(layers "B.Cu" "In4.Cu" "In6.Cu" "In11.Cu" "In13.Cu" "In15.Cu")
		(hatch none 0.5)
		(connect_pads
			(clearance 0)
		)
		(min_thickness 0.25)
		(keepout
			(tracks not_allowed)
			(vias allowed)
			(pads allowed)
			(copperpour not_allowed)
			(footprints allowed)
		)
		(placement
			(enabled no)
			(sheetname "")
		)
		(fill yes
			(thermal_gap 0.5)
			(thermal_bridge_width 0.5)
			(island_removal_mode 0)
		)
		(polygon
			(pts
				(arc
					(start 431.89017 -313.784996)
					(mid 431.22215 -313.784996)
					(end 431.89017 -313.784996)
				)
			)
		)
	)
	(zone
		(layers "B.Cu" "In4.Cu" "In6.Cu" "In11.Cu" "In13.Cu" "In15.Cu")
		(hatch none 0.5)
		(connect_pads
			(clearance 0)
		)
		(min_thickness 0.25)
		(keepout
			(tracks not_allowed)
			(vias allowed)
			(pads allowed)
			(copperpour not_allowed)
			(footprints allowed)
		)
		(placement
			(enabled no)
			(sheetname "")
		)
		(fill yes
			(thermal_gap 0.5)
			(thermal_bridge_width 0.5)
			(island_removal_mode 0)
		)
		(polygon
			(pts
				(arc
					(start 288.514028 -295.935146)
					(mid 287.846008 -295.935146)
					(end 288.514028 -295.935146)
				)
			)
		)
	)
	(zone
		(layers "B.Cu" "In4.Cu" "In6.Cu" "In11.Cu" "In13.Cu" "In15.Cu")
		(hatch none 0.5)
		(connect_pads
			(clearance 0)
		)
		(min_thickness 0.25)
		(keepout
			(tracks not_allowed)
			(vias allowed)
			(pads allowed)
			(copperpour not_allowed)
			(footprints allowed)
		)
		(placement
			(enabled no)
			(sheetname "")
		)
		(fill yes
			(thermal_gap 0.5)
			(thermal_bridge_width 0.5)
			(island_removal_mode 0)
		)
		(polygon
			(pts
				(arc
					(start 94.236032 -225.044508)
					(mid 93.606112 -225.044508)
					(end 94.236032 -225.044508)
				)
			)
		)
	)
	(zone
		(layers "B.Cu" "In4.Cu" "In6.Cu" "In11.Cu" "In13.Cu" "In15.Cu")
		(hatch none 0.5)
		(connect_pads
			(clearance 0)
		)
		(min_thickness 0.25)
		(keepout
			(tracks not_allowed)
			(vias allowed)
			(pads allowed)
			(copperpour not_allowed)
			(footprints allowed)
		)
		(placement
			(enabled no)
			(sheetname "")
		)
		(fill yes
			(thermal_gap 0.5)
			(thermal_bridge_width 0.5)
			(island_removal_mode 0)
		)
		(polygon
			(pts
				(arc
					(start 130.249676 -284.616398)
					(mid 129.619756 -284.616398)
					(end 130.249676 -284.616398)
				)
			)
		)
	)
	(zone
		(layers "B.Cu" "In4.Cu" "In6.Cu" "In11.Cu" "In13.Cu" "In15.Cu")
		(hatch none 0.5)
		(connect_pads
			(clearance 0)
		)
		(min_thickness 0.25)
		(keepout
			(tracks not_allowed)
			(vias allowed)
			(pads allowed)
			(copperpour not_allowed)
			(footprints allowed)
		)
		(placement
			(enabled no)
			(sheetname "")
		)
		(fill yes
			(thermal_gap 0.5)
			(thermal_bridge_width 0.5)
			(island_removal_mode 0)
		)
		(polygon
			(pts
				(arc
					(start 128.839722 -264.366248)
					(mid 128.209802 -264.366248)
					(end 128.839722 -264.366248)
				)
			)
		)
	)
	(zone
		(layers "B.Cu" "In4.Cu" "In6.Cu" "In11.Cu" "In13.Cu" "In15.Cu")
		(hatch none 0.5)
		(connect_pads
			(clearance 0)
		)
		(min_thickness 0.25)
		(keepout
			(tracks not_allowed)
			(vias allowed)
			(pads allowed)
			(copperpour not_allowed)
			(footprints allowed)
		)
		(placement
			(enabled no)
			(sheetname "")
		)
		(fill yes
			(thermal_gap 0.5)
			(thermal_bridge_width 0.5)
			(island_removal_mode 0)
		)
		(polygon
			(pts
				(arc
					(start 101.11613 -292.716204)
					(mid 100.48621 -292.716204)
					(end 101.11613 -292.716204)
				)
			)
		)
	)
	(zone
		(layers "B.Cu" "In4.Cu" "In6.Cu" "In11.Cu" "In13.Cu" "In15.Cu")
		(hatch none 0.5)
		(connect_pads
			(clearance 0)
		)
		(min_thickness 0.25)
		(keepout
			(tracks not_allowed)
			(vias allowed)
			(pads allowed)
			(copperpour not_allowed)
			(footprints allowed)
		)
		(placement
			(enabled no)
			(sheetname "")
		)
		(fill yes
			(thermal_gap 0.5)
			(thermal_bridge_width 0.5)
			(island_removal_mode 0)
		)
		(polygon
			(pts
				(arc
					(start 183.950102 -231.335326)
					(mid 183.282082 -231.335326)
					(end 183.950102 -231.335326)
				)
			)
		)
	)
	(zone
		(layers "B.Cu" "In4.Cu" "In6.Cu" "In11.Cu" "In13.Cu" "In15.Cu")
		(hatch none 0.5)
		(connect_pads
			(clearance 0)
		)
		(min_thickness 0.25)
		(keepout
			(tracks not_allowed)
			(vias allowed)
			(pads allowed)
			(copperpour not_allowed)
			(footprints allowed)
		)
		(placement
			(enabled no)
			(sheetname "")
		)
		(fill yes
			(thermal_gap 0.5)
			(thermal_bridge_width 0.5)
			(island_removal_mode 0)
		)
		(polygon
			(pts
				(arc
					(start 183.950102 -312.935366)
					(mid 183.282082 -312.935366)
					(end 183.950102 -312.935366)
				)
			)
		)
	)
	(zone
		(layers "B.Cu" "In4.Cu" "In6.Cu" "In11.Cu" "In13.Cu" "In15.Cu")
		(hatch none 0.5)
		(connect_pads
			(clearance 0)
		)
		(min_thickness 0.25)
		(keepout
			(tracks not_allowed)
			(vias allowed)
			(pads allowed)
			(copperpour not_allowed)
			(footprints allowed)
		)
		(placement
			(enabled no)
			(sheetname "")
		)
		(fill yes
			(thermal_gap 0.5)
			(thermal_bridge_width 0.5)
			(island_removal_mode 0)
		)
		(polygon
			(pts
				(arc
					(start 342.476074 -274.896072)
					(mid 341.846154 -274.896072)
					(end 342.476074 -274.896072)
				)
			)
		)
	)
	(zone
		(layers "B.Cu" "In4.Cu" "In6.Cu" "In11.Cu" "In13.Cu" "In15.Cu")
		(hatch none 0.5)
		(connect_pads
			(clearance 0)
		)
		(min_thickness 0.25)
		(keepout
			(tracks not_allowed)
			(vias allowed)
			(pads allowed)
			(copperpour not_allowed)
			(footprints allowed)
		)
		(placement
			(enabled no)
			(sheetname "")
		)
		(fill yes
			(thermal_gap 0.5)
			(thermal_bridge_width 0.5)
			(island_removal_mode 0)
		)
		(polygon
			(pts
				(arc
					(start 343.586054 -235.574078)
					(mid 342.956134 -235.574078)
					(end 343.586054 -235.574078)
				)
			)
		)
	)
	(zone
		(layers "B.Cu" "In4.Cu" "In6.Cu" "In11.Cu" "In13.Cu" "In15.Cu")
		(hatch none 0.5)
		(connect_pads
			(clearance 0)
		)
		(min_thickness 0.25)
		(keepout
			(tracks not_allowed)
			(vias allowed)
			(pads allowed)
			(copperpour not_allowed)
			(footprints allowed)
		)
		(placement
			(enabled no)
			(sheetname "")
		)
		(fill yes
			(thermal_gap 0.5)
			(thermal_bridge_width 0.5)
			(island_removal_mode 0)
		)
		(polygon
			(pts
				(arc
					(start 292.614096 -221.985078)
					(mid 291.946076 -221.985078)
					(end 292.614096 -221.985078)
				)
			)
		)
	)
	(zone
		(layers "B.Cu" "In4.Cu" "In6.Cu" "In11.Cu" "In13.Cu" "In15.Cu")
		(hatch none 0.5)
		(connect_pads
			(clearance 0)
		)
		(min_thickness 0.25)
		(keepout
			(tracks not_allowed)
			(vias allowed)
			(pads allowed)
			(copperpour not_allowed)
			(footprints allowed)
		)
		(placement
			(enabled no)
			(sheetname "")
		)
		(fill yes
			(thermal_gap 0.5)
			(thermal_bridge_width 0.5)
			(island_removal_mode 0)
		)
		(polygon
			(pts
				(arc
					(start 344.055954 -226.664266)
					(mid 343.426034 -226.664266)
					(end 344.055954 -226.664266)
				)
			)
		)
	)
	(zone
		(layers "B.Cu" "In4.Cu" "In6.Cu" "In11.Cu" "In13.Cu" "In15.Cu")
		(hatch none 0.5)
		(connect_pads
			(clearance 0)
		)
		(min_thickness 0.25)
		(keepout
			(tracks not_allowed)
			(vias allowed)
			(pads allowed)
			(copperpour not_allowed)
			(footprints allowed)
		)
		(placement
			(enabled no)
			(sheetname "")
		)
		(fill yes
			(thermal_gap 0.5)
			(thermal_bridge_width 0.5)
			(island_removal_mode 0)
		)
		(polygon
			(pts
				(arc
					(start 44.674028 -283.185362)
					(mid 44.006008 -283.185362)
					(end 44.674028 -283.185362)
				)
			)
		)
	)
	(zone
		(layers "B.Cu" "In4.Cu" "In6.Cu" "In11.Cu" "In13.Cu" "In15.Cu")
		(hatch none 0.5)
		(connect_pads
			(clearance 0)
		)
		(min_thickness 0.25)
		(keepout
			(tracks not_allowed)
			(vias allowed)
			(pads allowed)
			(copperpour not_allowed)
			(footprints allowed)
		)
		(placement
			(enabled no)
			(sheetname "")
		)
		(fill yes
			(thermal_gap 0.5)
			(thermal_bridge_width 0.5)
			(island_removal_mode 0)
		)
		(polygon
			(pts
				(arc
					(start 179.850034 -310.385206)
					(mid 179.182014 -310.385206)
					(end 179.850034 -310.385206)
				)
			)
		)
	)
	(zone
		(layers "B.Cu" "In4.Cu" "In6.Cu" "In11.Cu" "In13.Cu" "In15.Cu")
		(hatch none 0.5)
		(connect_pads
			(clearance 0)
		)
		(min_thickness 0.25)
		(keepout
			(tracks not_allowed)
			(vias allowed)
			(pads allowed)
			(copperpour not_allowed)
			(footprints allowed)
		)
		(placement
			(enabled no)
			(sheetname "")
		)
		(fill yes
			(thermal_gap 0.5)
			(thermal_bridge_width 0.5)
			(island_removal_mode 0)
		)
		(polygon
			(pts
				(arc
					(start 183.950102 -283.185362)
					(mid 183.282082 -283.185362)
					(end 183.950102 -283.185362)
				)
			)
		)
	)
	(zone
		(layers "B.Cu" "In4.Cu" "In6.Cu" "In11.Cu" "In13.Cu" "In15.Cu")
		(hatch none 0.5)
		(connect_pads
			(clearance 0)
		)
		(min_thickness 0.25)
		(keepout
			(tracks not_allowed)
			(vias allowed)
			(pads allowed)
			(copperpour not_allowed)
			(footprints allowed)
		)
		(placement
			(enabled no)
			(sheetname "")
		)
		(fill yes
			(thermal_gap 0.5)
			(thermal_bridge_width 0.5)
			(island_removal_mode 0)
		)
		(polygon
			(pts
				(arc
					(start 376.77979 -290.285932)
					(mid 376.14987 -290.285932)
					(end 376.77979 -290.285932)
				)
			)
		)
	)
	(zone
		(layers "B.Cu" "In4.Cu" "In6.Cu" "In11.Cu" "In13.Cu" "In15.Cu")
		(hatch none 0.5)
		(connect_pads
			(clearance 0)
		)
		(min_thickness 0.25)
		(keepout
			(tracks not_allowed)
			(vias allowed)
			(pads allowed)
			(copperpour not_allowed)
			(footprints allowed)
		)
		(placement
			(enabled no)
			(sheetname "")
		)
		(fill yes
			(thermal_gap 0.5)
			(thermal_bridge_width 0.5)
			(island_removal_mode 0)
		)
		(polygon
			(pts
				(arc
					(start 292.614096 -269.585186)
					(mid 291.946076 -269.585186)
					(end 292.614096 -269.585186)
				)
			)
		)
	)
	(zone
		(layers "B.Cu" "In4.Cu" "In6.Cu" "In11.Cu" "In13.Cu" "In15.Cu")
		(hatch none 0.5)
		(connect_pads
			(clearance 0)
		)
		(min_thickness 0.25)
		(keepout
			(tracks not_allowed)
			(vias allowed)
			(pads allowed)
			(copperpour not_allowed)
			(footprints allowed)
		)
		(placement
			(enabled no)
			(sheetname "")
		)
		(fill yes
			(thermal_gap 0.5)
			(thermal_bridge_width 0.5)
			(island_removal_mode 0)
		)
		(polygon
			(pts
				(arc
					(start 94.705932 -235.574332)
					(mid 94.076012 -235.574332)
					(end 94.705932 -235.574332)
				)
			)
		)
	)
	(zone
		(layers "B.Cu" "In4.Cu" "In6.Cu" "In11.Cu" "In13.Cu" "In15.Cu")
		(hatch none 0.5)
		(connect_pads
			(clearance 0)
		)
		(min_thickness 0.25)
		(keepout
			(tracks not_allowed)
			(vias allowed)
			(pads allowed)
			(copperpour not_allowed)
			(footprints allowed)
		)
		(placement
			(enabled no)
			(sheetname "")
		)
		(fill yes
			(thermal_gap 0.5)
			(thermal_bridge_width 0.5)
			(island_removal_mode 0)
		)
		(polygon
			(pts
				(arc
					(start 99.607624 6.495034)
					(mid 98.939604 6.495034)
					(end 99.607624 6.495034)
				)
			)
		)
	)
	(zone
		(layers "B.Cu" "In4.Cu" "In6.Cu" "In11.Cu" "In13.Cu" "In15.Cu")
		(hatch none 0.5)
		(connect_pads
			(clearance 0)
		)
		(min_thickness 0.25)
		(keepout
			(tracks not_allowed)
			(vias allowed)
			(pads allowed)
			(copperpour not_allowed)
			(footprints allowed)
		)
		(placement
			(enabled no)
			(sheetname "")
		)
		(fill yes
			(thermal_gap 0.5)
			(thermal_bridge_width 0.5)
			(island_removal_mode 0)
		)
		(polygon
			(pts
				(arc
					(start 40.57396 -284.035246)
					(mid 39.90594 -284.035246)
					(end 40.57396 -284.035246)
				)
			)
		)
	)
	(zone
		(layers "B.Cu" "In4.Cu" "In6.Cu" "In11.Cu" "In13.Cu" "In15.Cu")
		(hatch none 0.5)
		(connect_pads
			(clearance 0)
		)
		(min_thickness 0.25)
		(keepout
			(tracks not_allowed)
			(vias allowed)
			(pads allowed)
			(copperpour not_allowed)
			(footprints allowed)
		)
		(placement
			(enabled no)
			(sheetname "")
		)
		(fill yes
			(thermal_gap 0.5)
			(thermal_bridge_width 0.5)
			(island_removal_mode 0)
		)
		(polygon
			(pts
				(arc
					(start 183.950102 -234.73537)
					(mid 183.282082 -234.73537)
					(end 183.950102 -234.73537)
				)
			)
		)
	)
	(zone
		(layers "B.Cu" "In4.Cu" "In6.Cu" "In11.Cu" "In13.Cu" "In15.Cu")
		(hatch none 0.5)
		(connect_pads
			(clearance 0)
		)
		(min_thickness 0.25)
		(keepout
			(tracks not_allowed)
			(vias allowed)
			(pads allowed)
			(copperpour not_allowed)
			(footprints allowed)
		)
		(placement
			(enabled no)
			(sheetname "")
		)
		(fill yes
			(thermal_gap 0.5)
			(thermal_bridge_width 0.5)
			(island_removal_mode 0)
		)
		(polygon
			(pts
				(arc
					(start 183.950102 -233.035348)
					(mid 183.282082 -233.035348)
					(end 183.950102 -233.035348)
				)
			)
		)
	)
	(zone
		(layers "B.Cu" "In4.Cu" "In6.Cu" "In11.Cu" "In13.Cu" "In15.Cu")
		(hatch none 0.5)
		(connect_pads
			(clearance 0)
		)
		(min_thickness 0.25)
		(keepout
			(tracks not_allowed)
			(vias allowed)
			(pads allowed)
			(copperpour not_allowed)
			(footprints allowed)
		)
		(placement
			(enabled no)
			(sheetname "")
		)
		(fill yes
			(thermal_gap 0.5)
			(thermal_bridge_width 0.5)
			(island_removal_mode 0)
		)
		(polygon
			(pts
				(arc
					(start 367.549684 -226.664266)
					(mid 366.919764 -226.664266)
					(end 367.549684 -226.664266)
				)
			)
		)
	)
	(zone
		(layers "B.Cu" "In4.Cu" "In6.Cu" "In11.Cu" "In13.Cu" "In15.Cu")
		(hatch none 0.5)
		(connect_pads
			(clearance 0)
		)
		(min_thickness 0.25)
		(keepout
			(tracks not_allowed)
			(vias allowed)
			(pads allowed)
			(copperpour not_allowed)
			(footprints allowed)
		)
		(placement
			(enabled no)
			(sheetname "")
		)
		(fill yes
			(thermal_gap 0.5)
			(thermal_bridge_width 0.5)
			(island_removal_mode 0)
		)
		(polygon
			(pts
				(arc
					(start 427.790102 -243.234972)
					(mid 427.122082 -243.234972)
					(end 427.790102 -243.234972)
				)
			)
		)
	)
	(zone
		(layers "B.Cu" "In4.Cu" "In6.Cu" "In11.Cu" "In13.Cu" "In15.Cu")
		(hatch none 0.5)
		(connect_pads
			(clearance 0)
		)
		(min_thickness 0.25)
		(keepout
			(tracks not_allowed)
			(vias allowed)
			(pads allowed)
			(copperpour not_allowed)
			(footprints allowed)
		)
		(placement
			(enabled no)
			(sheetname "")
		)
		(fill yes
			(thermal_gap 0.5)
			(thermal_bridge_width 0.5)
			(island_removal_mode 0)
		)
		(polygon
			(pts
				(arc
					(start 128.069594 -254.20447)
					(mid 127.439674 -254.20447)
					(end 128.069594 -254.20447)
				)
			)
		)
	)
	(zone
		(layers "B.Cu" "In4.Cu" "In6.Cu" "In11.Cu" "In13.Cu" "In15.Cu")
		(hatch none 0.5)
		(connect_pads
			(clearance 0)
		)
		(min_thickness 0.25)
		(keepout
			(tracks not_allowed)
			(vias allowed)
			(pads allowed)
			(copperpour not_allowed)
			(footprints allowed)
		)
		(placement
			(enabled no)
			(sheetname "")
		)
		(fill yes
			(thermal_gap 0.5)
			(thermal_bridge_width 0.5)
			(island_removal_mode 0)
		)
		(polygon
			(pts
				(arc
					(start 40.57396 -304.435256)
					(mid 39.90594 -304.435256)
					(end 40.57396 -304.435256)
				)
			)
		)
	)
	(zone
		(layers "B.Cu" "In4.Cu" "In6.Cu" "In11.Cu" "In13.Cu" "In15.Cu")
		(hatch none 0.5)
		(connect_pads
			(clearance 0)
		)
		(min_thickness 0.25)
		(keepout
			(tracks not_allowed)
			(vias allowed)
			(pads allowed)
			(copperpour not_allowed)
			(footprints allowed)
		)
		(placement
			(enabled no)
			(sheetname "")
		)
		(fill yes
			(thermal_gap 0.5)
			(thermal_bridge_width 0.5)
			(island_removal_mode 0)
		)
		(polygon
			(pts
				(arc
					(start 377.719844 -288.66592)
					(mid 377.089924 -288.66592)
					(end 377.719844 -288.66592)
				)
			)
		)
	)
	(zone
		(layers "B.Cu" "In4.Cu" "In6.Cu" "In11.Cu" "In13.Cu" "In15.Cu")
		(hatch none 0.5)
		(connect_pads
			(clearance 0)
		)
		(min_thickness 0.25)
		(keepout
			(tracks not_allowed)
			(vias allowed)
			(pads allowed)
			(copperpour not_allowed)
			(footprints allowed)
		)
		(placement
			(enabled no)
			(sheetname "")
		)
		(fill yes
			(thermal_gap 0.5)
			(thermal_bridge_width 0.5)
			(island_removal_mode 0)
		)
		(polygon
			(pts
				(arc
					(start 376.30989 -284.616144)
					(mid 375.67997 -284.616144)
					(end 376.30989 -284.616144)
				)
			)
		)
	)
	(zone
		(layers "B.Cu" "In4.Cu" "In6.Cu" "In11.Cu" "In13.Cu" "In15.Cu")
		(hatch none 0.5)
		(connect_pads
			(clearance 0)
		)
		(min_thickness 0.25)
		(keepout
			(tracks not_allowed)
			(vias allowed)
			(pads allowed)
			(copperpour not_allowed)
			(footprints allowed)
		)
		(placement
			(enabled no)
			(sheetname "")
		)
		(fill yes
			(thermal_gap 0.5)
			(thermal_bridge_width 0.5)
			(island_removal_mode 0)
		)
		(polygon
			(pts
				(arc
					(start 179.850034 -313.78525)
					(mid 179.182014 -313.78525)
					(end 179.850034 -313.78525)
				)
			)
		)
	)
	(zone
		(layers "B.Cu" "In4.Cu" "In6.Cu" "In11.Cu" "In13.Cu" "In15.Cu")
		(hatch none 0.5)
		(connect_pads
			(clearance 0)
		)
		(min_thickness 0.25)
		(keepout
			(tracks not_allowed)
			(vias allowed)
			(pads allowed)
			(copperpour not_allowed)
			(footprints allowed)
		)
		(placement
			(enabled no)
			(sheetname "")
		)
		(fill yes
			(thermal_gap 0.5)
			(thermal_bridge_width 0.5)
			(island_removal_mode 0)
		)
		(polygon
			(pts
				(arc
					(start 94.236032 -226.66452)
					(mid 93.606112 -226.66452)
					(end 94.236032 -226.66452)
				)
			)
		)
	)
	(zone
		(layers "B.Cu" "In4.Cu" "In6.Cu" "In11.Cu" "In13.Cu" "In15.Cu")
		(hatch none 0.5)
		(connect_pads
			(clearance 0)
		)
		(min_thickness 0.25)
		(keepout
			(tracks not_allowed)
			(vias allowed)
			(pads allowed)
			(copperpour not_allowed)
			(footprints allowed)
		)
		(placement
			(enabled no)
			(sheetname "")
		)
		(fill yes
			(thermal_gap 0.5)
			(thermal_bridge_width 0.5)
			(island_removal_mode 0)
		)
		(polygon
			(pts
				(arc
					(start 377.88977 -241.24412)
					(mid 377.25985 -241.24412)
					(end 377.88977 -241.24412)
				)
			)
		)
	)
	(zone
		(layers "B.Cu" "In4.Cu" "In6.Cu" "In11.Cu" "In13.Cu" "In15.Cu")
		(hatch none 0.5)
		(connect_pads
			(clearance 0)
		)
		(min_thickness 0.25)
		(keepout
			(tracks not_allowed)
			(vias allowed)
			(pads allowed)
			(copperpour not_allowed)
			(footprints allowed)
		)
		(placement
			(enabled no)
			(sheetname "")
		)
		(fill yes
			(thermal_gap 0.5)
			(thermal_bridge_width 0.5)
			(island_removal_mode 0)
		)
		(polygon
			(pts
				(arc
					(start 44.674028 -289.135312)
					(mid 44.006008 -289.135312)
					(end 44.674028 -289.135312)
				)
			)
		)
	)
	(zone
		(layers "B.Cu" "In4.Cu" "In6.Cu" "In11.Cu" "In13.Cu" "In15.Cu")
		(hatch none 0.5)
		(connect_pads
			(clearance 0)
		)
		(min_thickness 0.25)
		(keepout
			(tracks not_allowed)
			(vias allowed)
			(pads allowed)
			(copperpour not_allowed)
			(footprints allowed)
		)
		(placement
			(enabled no)
			(sheetname "")
		)
		(fill yes
			(thermal_gap 0.5)
			(thermal_bridge_width 0.5)
			(island_removal_mode 0)
		)
		(polygon
			(pts
				(arc
					(start 98.936048 -231.524302)
					(mid 98.306128 -231.524302)
					(end 98.936048 -231.524302)
				)
			)
		)
	)
	(zone
		(layers "B.Cu" "In4.Cu" "In6.Cu" "In11.Cu" "In13.Cu" "In15.Cu")
		(hatch none 0.5)
		(connect_pads
			(clearance 0)
		)
		(min_thickness 0.25)
		(keepout
			(tracks not_allowed)
			(vias allowed)
			(pads allowed)
			(copperpour not_allowed)
			(footprints allowed)
		)
		(placement
			(enabled no)
			(sheetname "")
		)
		(fill yes
			(thermal_gap 0.5)
			(thermal_bridge_width 0.5)
			(island_removal_mode 0)
		)
		(polygon
			(pts
				(arc
					(start 129.779776 -290.286186)
					(mid 129.149856 -290.286186)
					(end 129.779776 -290.286186)
				)
			)
		)
	)
	(zone
		(layers "B.Cu" "In4.Cu" "In6.Cu" "In11.Cu" "In13.Cu" "In15.Cu")
		(hatch none 0.5)
		(connect_pads
			(clearance 0)
		)
		(min_thickness 0.25)
		(keepout
			(tracks not_allowed)
			(vias allowed)
			(pads allowed)
			(copperpour not_allowed)
			(footprints allowed)
		)
		(placement
			(enabled no)
			(sheetname "")
		)
		(fill yes
			(thermal_gap 0.5)
			(thermal_bridge_width 0.5)
			(island_removal_mode 0)
		)
		(polygon
			(pts
				(arc
					(start 342.476074 -291.095938)
					(mid 341.846154 -291.095938)
					(end 342.476074 -291.095938)
				)
			)
		)
	)
	(zone
		(layers "B.Cu" "In4.Cu" "In6.Cu" "In11.Cu" "In13.Cu" "In15.Cu")
		(hatch none 0.5)
		(connect_pads
			(clearance 0)
		)
		(min_thickness 0.25)
		(keepout
			(tracks not_allowed)
			(vias allowed)
			(pads allowed)
			(copperpour not_allowed)
			(footprints allowed)
		)
		(placement
			(enabled no)
			(sheetname "")
		)
		(fill yes
			(thermal_gap 0.5)
			(thermal_bridge_width 0.5)
			(island_removal_mode 0)
		)
		(polygon
			(pts
				(arc
					(start 179.850034 -198.185278)
					(mid 179.182014 -198.185278)
					(end 179.850034 -198.185278)
				)
			)
		)
	)
	(zone
		(layers "B.Cu" "In4.Cu" "In6.Cu" "In11.Cu" "In13.Cu" "In15.Cu")
		(hatch none 0.5)
		(connect_pads
			(clearance 0)
		)
		(min_thickness 0.25)
		(keepout
			(tracks not_allowed)
			(vias allowed)
			(pads allowed)
			(copperpour not_allowed)
			(footprints allowed)
		)
		(placement
			(enabled no)
			(sheetname "")
		)
		(fill yes
			(thermal_gap 0.5)
			(thermal_bridge_width 0.5)
			(island_removal_mode 0)
		)
		(polygon
			(pts
				(arc
					(start 44.674028 -240.68532)
					(mid 44.006008 -240.68532)
					(end 44.674028 -240.68532)
				)
			)
		)
	)
	(zone
		(layers "B.Cu" "In4.Cu" "In6.Cu" "In11.Cu" "In13.Cu" "In15.Cu")
		(hatch none 0.5)
		(connect_pads
			(clearance 0)
		)
		(min_thickness 0.25)
		(keepout
			(tracks not_allowed)
			(vias allowed)
			(pads allowed)
			(copperpour not_allowed)
			(footprints allowed)
		)
		(placement
			(enabled no)
			(sheetname "")
		)
		(fill yes
			(thermal_gap 0.5)
			(thermal_bridge_width 0.5)
			(island_removal_mode 0)
		)
		(polygon
			(pts
				(arc
					(start 352.81616 -292.71595)
					(mid 352.18624 -292.71595)
					(end 352.81616 -292.71595)
				)
			)
		)
	)
	(zone
		(layers "B.Cu" "In4.Cu" "In6.Cu" "In11.Cu" "In13.Cu" "In15.Cu")
		(hatch none 0.5)
		(connect_pads
			(clearance 0)
		)
		(min_thickness 0.25)
		(keepout
			(tracks not_allowed)
			(vias allowed)
			(pads allowed)
			(copperpour not_allowed)
			(footprints allowed)
		)
		(placement
			(enabled no)
			(sheetname "")
		)
		(fill yes
			(thermal_gap 0.5)
			(thermal_bridge_width 0.5)
			(island_removal_mode 0)
		)
		(polygon
			(pts
				(arc
					(start 427.790102 -289.985196)
					(mid 427.122082 -289.985196)
					(end 427.790102 -289.985196)
				)
			)
		)
	)
	(zone
		(layers "B.Cu" "In4.Cu" "In6.Cu" "In11.Cu" "In13.Cu" "In15.Cu")
		(hatch none 0.5)
		(connect_pads
			(clearance 0)
		)
		(min_thickness 0.25)
		(keepout
			(tracks not_allowed)
			(vias allowed)
			(pads allowed)
			(copperpour not_allowed)
			(footprints allowed)
		)
		(placement
			(enabled no)
			(sheetname "")
		)
		(fill yes
			(thermal_gap 0.5)
			(thermal_bridge_width 0.5)
			(island_removal_mode 0)
		)
		(polygon
			(pts
				(arc
					(start 129.479802 -232.334308)
					(mid 128.849882 -232.334308)
					(end 129.479802 -232.334308)
				)
			)
		)
	)
	(zone
		(layers "B.Cu" "In4.Cu" "In6.Cu" "In11.Cu" "In13.Cu" "In15.Cu")
		(hatch none 0.5)
		(connect_pads
			(clearance 0)
		)
		(min_thickness 0.25)
		(keepout
			(tracks not_allowed)
			(vias allowed)
			(pads allowed)
			(copperpour not_allowed)
			(footprints allowed)
		)
		(placement
			(enabled no)
			(sheetname "")
		)
		(fill yes
			(thermal_gap 0.5)
			(thermal_bridge_width 0.5)
			(island_removal_mode 0)
		)
		(polygon
			(pts
				(arc
					(start 179.850034 -291.685218)
					(mid 179.182014 -291.685218)
					(end 179.850034 -291.685218)
				)
			)
		)
	)
	(zone
		(layers "B.Cu" "In4.Cu" "In6.Cu" "In11.Cu" "In13.Cu" "In15.Cu")
		(hatch none 0.5)
		(connect_pads
			(clearance 0)
		)
		(min_thickness 0.25)
		(keepout
			(tracks not_allowed)
			(vias allowed)
			(pads allowed)
			(copperpour not_allowed)
			(footprints allowed)
		)
		(placement
			(enabled no)
			(sheetname "")
		)
		(fill yes
			(thermal_gap 0.5)
			(thermal_bridge_width 0.5)
			(island_removal_mode 0)
		)
		(polygon
			(pts
				(arc
					(start 342.1761 -229.904036)
					(mid 341.54618 -229.904036)
					(end 342.1761 -229.904036)
				)
			)
		)
	)
	(zone
		(layers "B.Cu" "In4.Cu" "In6.Cu" "In11.Cu" "In13.Cu" "In15.Cu")
		(hatch none 0.5)
		(connect_pads
			(clearance 0)
		)
		(min_thickness 0.25)
		(keepout
			(tracks not_allowed)
			(vias allowed)
			(pads allowed)
			(copperpour not_allowed)
			(footprints allowed)
		)
		(placement
			(enabled no)
			(sheetname "")
		)
		(fill yes
			(thermal_gap 0.5)
			(thermal_bridge_width 0.5)
			(island_removal_mode 0)
		)
		(polygon
			(pts
				(arc
					(start 44.674028 -219.435426)
					(mid 44.006008 -219.435426)
					(end 44.674028 -219.435426)
				)
			)
		)
	)
	(zone
		(layers "B.Cu" "In4.Cu" "In6.Cu" "In11.Cu" "In13.Cu" "In15.Cu")
		(hatch none 0.5)
		(connect_pads
			(clearance 0)
		)
		(min_thickness 0.25)
		(keepout
			(tracks not_allowed)
			(vias allowed)
			(pads allowed)
			(copperpour not_allowed)
			(footprints allowed)
		)
		(placement
			(enabled no)
			(sheetname "")
		)
		(fill yes
			(thermal_gap 0.5)
			(thermal_bridge_width 0.5)
			(island_removal_mode 0)
		)
		(polygon
			(pts
				(arc
					(start 40.57396 -277.235412)
					(mid 39.90594 -277.235412)
					(end 40.57396 -277.235412)
				)
			)
		)
	)
	(zone
		(layers "B.Cu" "In4.Cu" "In6.Cu" "In11.Cu" "In13.Cu" "In15.Cu")
		(hatch none 0.5)
		(connect_pads
			(clearance 0)
		)
		(min_thickness 0.25)
		(keepout
			(tracks not_allowed)
			(vias allowed)
			(pads allowed)
			(copperpour not_allowed)
			(footprints allowed)
		)
		(placement
			(enabled no)
			(sheetname "")
		)
		(fill yes
			(thermal_gap 0.5)
			(thermal_bridge_width 0.5)
			(island_removal_mode 0)
		)
		(polygon
			(pts
				(arc
					(start 367.549684 -229.904036)
					(mid 366.919764 -229.904036)
					(end 367.549684 -229.904036)
				)
			)
		)
	)
	(zone
		(layers "B.Cu" "In4.Cu" "In6.Cu" "In11.Cu" "In13.Cu" "In15.Cu")
		(hatch none 0.5)
		(connect_pads
			(clearance 0)
		)
		(min_thickness 0.25)
		(keepout
			(tracks not_allowed)
			(vias allowed)
			(pads allowed)
			(copperpour not_allowed)
			(footprints allowed)
		)
		(placement
			(enabled no)
			(sheetname "")
		)
		(fill yes
			(thermal_gap 0.5)
			(thermal_bridge_width 0.5)
			(island_removal_mode 0)
		)
		(polygon
			(pts
				(arc
					(start 44.674028 -300.185328)
					(mid 44.006008 -300.185328)
					(end 44.674028 -300.185328)
				)
			)
		)
	)
	(zone
		(layers "B.Cu" "In4.Cu" "In6.Cu" "In11.Cu" "In13.Cu" "In15.Cu")
		(hatch none 0.5)
		(connect_pads
			(clearance 0)
		)
		(min_thickness 0.25)
		(keepout
			(tracks not_allowed)
			(vias allowed)
			(pads allowed)
			(copperpour not_allowed)
			(footprints allowed)
		)
		(placement
			(enabled no)
			(sheetname "")
		)
		(fill yes
			(thermal_gap 0.5)
			(thermal_bridge_width 0.5)
			(island_removal_mode 0)
		)
		(polygon
			(pts
				(arc
					(start 94.236032 -238.00435)
					(mid 93.606112 -238.00435)
					(end 94.236032 -238.00435)
				)
			)
		)
	)
	(zone
		(layers "B.Cu" "In4.Cu" "In6.Cu" "In11.Cu" "In13.Cu" "In15.Cu")
		(hatch none 0.5)
		(connect_pads
			(clearance 0)
		)
		(min_thickness 0.25)
		(keepout
			(tracks not_allowed)
			(vias allowed)
			(pads allowed)
			(copperpour not_allowed)
			(footprints allowed)
		)
		(placement
			(enabled no)
			(sheetname "")
		)
		(fill yes
			(thermal_gap 0.5)
			(thermal_bridge_width 0.5)
			(island_removal_mode 0)
		)
		(polygon
			(pts
				(arc
					(start 431.89017 -289.135058)
					(mid 431.22215 -289.135058)
					(end 431.89017 -289.135058)
				)
			)
		)
	)
	(zone
		(layers "B.Cu" "In4.Cu" "In6.Cu" "In11.Cu" "In13.Cu" "In15.Cu")
		(hatch none 0.5)
		(connect_pads
			(clearance 0)
		)
		(min_thickness 0.25)
		(keepout
			(tracks not_allowed)
			(vias allowed)
			(pads allowed)
			(copperpour not_allowed)
			(footprints allowed)
		)
		(placement
			(enabled no)
			(sheetname "")
		)
		(fill yes
			(thermal_gap 0.5)
			(thermal_bridge_width 0.5)
			(island_removal_mode 0)
		)
		(polygon
			(pts
				(arc
					(start 94.236032 -231.524302)
					(mid 93.606112 -231.524302)
					(end 94.236032 -231.524302)
				)
			)
		)
	)
	(zone
		(layers "B.Cu" "In4.Cu" "In6.Cu" "In11.Cu" "In13.Cu" "In15.Cu")
		(hatch none 0.5)
		(connect_pads
			(clearance 0)
		)
		(min_thickness 0.25)
		(keepout
			(tracks not_allowed)
			(vias allowed)
			(pads allowed)
			(copperpour not_allowed)
			(footprints allowed)
		)
		(placement
			(enabled no)
			(sheetname "")
		)
		(fill yes
			(thermal_gap 0.5)
			(thermal_bridge_width 0.5)
			(island_removal_mode 0)
		)
		(polygon
			(pts
				(arc
					(start 427.790102 -272.984976)
					(mid 427.122082 -272.984976)
					(end 427.790102 -272.984976)
				)
			)
		)
	)
	(zone
		(layers "B.Cu" "In4.Cu" "In6.Cu" "In11.Cu" "In13.Cu" "In15.Cu")
		(hatch none 0.5)
		(connect_pads
			(clearance 0)
		)
		(min_thickness 0.25)
		(keepout
			(tracks not_allowed)
			(vias allowed)
			(pads allowed)
			(copperpour not_allowed)
			(footprints allowed)
		)
		(placement
			(enabled no)
			(sheetname "")
		)
		(fill yes
			(thermal_gap 0.5)
			(thermal_bridge_width 0.5)
			(island_removal_mode 0)
		)
		(polygon
			(pts
				(arc
					(start 376.77979 -280.566114)
					(mid 376.14987 -280.566114)
					(end 376.77979 -280.566114)
				)
			)
		)
	)
	(zone
		(layers "B.Cu" "In4.Cu" "In6.Cu" "In11.Cu" "In13.Cu" "In15.Cu")
		(hatch none 0.5)
		(connect_pads
			(clearance 0)
		)
		(min_thickness 0.25)
		(keepout
			(tracks not_allowed)
			(vias allowed)
			(pads allowed)
			(copperpour not_allowed)
			(footprints allowed)
		)
		(placement
			(enabled no)
			(sheetname "")
		)
		(fill yes
			(thermal_gap 0.5)
			(thermal_bridge_width 0.5)
			(island_removal_mode 0)
		)
		(polygon
			(pts
				(arc
					(start 94.705932 -225.854514)
					(mid 94.076012 -225.854514)
					(end 94.705932 -225.854514)
				)
			)
		)
	)
	(zone
		(layers "B.Cu" "In4.Cu" "In6.Cu" "In11.Cu" "In13.Cu" "In15.Cu")
		(hatch none 0.5)
		(connect_pads
			(clearance 0)
		)
		(min_thickness 0.25)
		(keepout
			(tracks not_allowed)
			(vias allowed)
			(pads allowed)
			(copperpour not_allowed)
			(footprints allowed)
		)
		(placement
			(enabled no)
			(sheetname "")
		)
		(fill yes
			(thermal_gap 0.5)
			(thermal_bridge_width 0.5)
			(island_removal_mode 0)
		)
		(polygon
			(pts
				(arc
					(start 377.719844 -280.566114)
					(mid 377.089924 -280.566114)
					(end 377.719844 -280.566114)
				)
			)
		)
	)
	(zone
		(layers "B.Cu" "In4.Cu" "In6.Cu" "In11.Cu" "In13.Cu" "In15.Cu")
		(hatch none 0.5)
		(connect_pads
			(clearance 0)
		)
		(min_thickness 0.25)
		(keepout
			(tracks not_allowed)
			(vias allowed)
			(pads allowed)
			(copperpour not_allowed)
			(footprints allowed)
		)
		(placement
			(enabled no)
			(sheetname "")
		)
		(fill yes
			(thermal_gap 0.5)
			(thermal_bridge_width 0.5)
			(island_removal_mode 0)
		)
		(polygon
			(pts
				(arc
					(start 292.614096 -278.085042)
					(mid 291.946076 -278.085042)
					(end 292.614096 -278.085042)
				)
			)
		)
	)
	(zone
		(layers "B.Cu" "In4.Cu" "In6.Cu" "In11.Cu" "In13.Cu" "In15.Cu")
		(hatch none 0.5)
		(connect_pads
			(clearance 0)
		)
		(min_thickness 0.25)
		(keepout
			(tracks not_allowed)
			(vias allowed)
			(pads allowed)
			(copperpour not_allowed)
			(footprints allowed)
		)
		(placement
			(enabled no)
			(sheetname "")
		)
		(fill yes
			(thermal_gap 0.5)
			(thermal_bridge_width 0.5)
			(island_removal_mode 0)
		)
		(polygon
			(pts
				(arc
					(start 427.790102 -308.685184)
					(mid 427.122082 -308.685184)
					(end 427.790102 -308.685184)
				)
			)
		)
	)
	(zone
		(layers "B.Cu" "In4.Cu" "In6.Cu" "In11.Cu" "In13.Cu" "In15.Cu")
		(hatch none 0.5)
		(connect_pads
			(clearance 0)
		)
		(min_thickness 0.25)
		(keepout
			(tracks not_allowed)
			(vias allowed)
			(pads allowed)
			(copperpour not_allowed)
			(footprints allowed)
		)
		(placement
			(enabled no)
			(sheetname "")
		)
		(fill yes
			(thermal_gap 0.5)
			(thermal_bridge_width 0.5)
			(island_removal_mode 0)
		)
		(polygon
			(pts
				(arc
					(start 44.674028 -278.085296)
					(mid 44.006008 -278.085296)
					(end 44.674028 -278.085296)
				)
			)
		)
	)
	(zone
		(layers "B.Cu" "In4.Cu" "In6.Cu" "In11.Cu" "In13.Cu" "In15.Cu")
		(hatch none 0.5)
		(connect_pads
			(clearance 0)
		)
		(min_thickness 0.25)
		(keepout
			(tracks not_allowed)
			(vias allowed)
			(pads allowed)
			(copperpour not_allowed)
			(footprints allowed)
		)
		(placement
			(enabled no)
			(sheetname "")
		)
		(fill yes
			(thermal_gap 0.5)
			(thermal_bridge_width 0.5)
			(island_removal_mode 0)
		)
		(polygon
			(pts
				(arc
					(start 128.839722 -272.466308)
					(mid 128.209802 -272.466308)
					(end 128.839722 -272.466308)
				)
			)
		)
	)
	(zone
		(layers "B.Cu" "In4.Cu" "In6.Cu" "In11.Cu" "In13.Cu" "In15.Cu")
		(hatch none 0.5)
		(connect_pads
			(clearance 0)
		)
		(min_thickness 0.25)
		(keepout
			(tracks not_allowed)
			(vias allowed)
			(pads allowed)
			(copperpour not_allowed)
			(footprints allowed)
		)
		(placement
			(enabled no)
			(sheetname "")
		)
		(fill yes
			(thermal_gap 0.5)
			(thermal_bridge_width 0.5)
			(island_removal_mode 0)
		)
		(polygon
			(pts
				(arc
					(start 431.89017 -285.735014)
					(mid 431.22215 -285.735014)
					(end 431.89017 -285.735014)
				)
			)
		)
	)
	(zone
		(layers "B.Cu" "In4.Cu" "In6.Cu" "In11.Cu" "In13.Cu" "In15.Cu")
		(hatch none 0.5)
		(connect_pads
			(clearance 0)
		)
		(min_thickness 0.25)
		(keepout
			(tracks not_allowed)
			(vias allowed)
			(pads allowed)
			(copperpour not_allowed)
			(footprints allowed)
		)
		(placement
			(enabled no)
			(sheetname "")
		)
		(fill yes
			(thermal_gap 0.5)
			(thermal_bridge_width 0.5)
			(island_removal_mode 0)
		)
		(polygon
			(pts
				(arc
					(start 100.815902 -229.90429)
					(mid 100.185982 -229.90429)
					(end 100.815902 -229.90429)
				)
			)
		)
	)
	(zone
		(layers "B.Cu" "In4.Cu" "In6.Cu" "In11.Cu" "In13.Cu" "In15.Cu")
		(hatch none 0.5)
		(connect_pads
			(clearance 0)
		)
		(min_thickness 0.25)
		(keepout
			(tracks not_allowed)
			(vias allowed)
			(pads allowed)
			(copperpour not_allowed)
			(footprints allowed)
		)
		(placement
			(enabled no)
			(sheetname "")
		)
		(fill yes
			(thermal_gap 0.5)
			(thermal_bridge_width 0.5)
			(island_removal_mode 0)
		)
		(polygon
			(pts
				(arc
					(start 363.319822 -227.474272)
					(mid 362.689902 -227.474272)
					(end 363.319822 -227.474272)
				)
			)
		)
	)
	(zone
		(layers "B.Cu" "In4.Cu" "In6.Cu" "In11.Cu" "In13.Cu" "In15.Cu")
		(hatch none 0.5)
		(connect_pads
			(clearance 0)
		)
		(min_thickness 0.25)
		(keepout
			(tracks not_allowed)
			(vias allowed)
			(pads allowed)
			(copperpour not_allowed)
			(footprints allowed)
		)
		(placement
			(enabled no)
			(sheetname "")
		)
		(fill yes
			(thermal_gap 0.5)
			(thermal_bridge_width 0.5)
			(island_removal_mode 0)
		)
		(polygon
			(pts
				(arc
					(start 431.89017 -283.185108)
					(mid 431.22215 -283.185108)
					(end 431.89017 -283.185108)
				)
			)
		)
	)
	(zone
		(layers "B.Cu" "In4.Cu" "In6.Cu" "In11.Cu" "In13.Cu" "In15.Cu")
		(hatch none 0.5)
		(connect_pads
			(clearance 0)
		)
		(min_thickness 0.25)
		(keepout
			(tracks not_allowed)
			(vias allowed)
			(pads allowed)
			(copperpour not_allowed)
			(footprints allowed)
		)
		(placement
			(enabled no)
			(sheetname "")
		)
		(fill yes
			(thermal_gap 0.5)
			(thermal_bridge_width 0.5)
			(island_removal_mode 0)
		)
		(polygon
			(pts
				(arc
					(start 95.94596 -274.08632)
					(mid 95.31604 -274.08632)
					(end 95.94596 -274.08632)
				)
			)
		)
	)
	(zone
		(layers "B.Cu" "In4.Cu" "In6.Cu" "In11.Cu" "In13.Cu" "In15.Cu")
		(hatch none 0.5)
		(connect_pads
			(clearance 0)
		)
		(min_thickness 0.25)
		(keepout
			(tracks not_allowed)
			(vias allowed)
			(pads allowed)
			(copperpour not_allowed)
			(footprints allowed)
		)
		(placement
			(enabled no)
			(sheetname "")
		)
		(fill yes
			(thermal_gap 0.5)
			(thermal_bridge_width 0.5)
			(island_removal_mode 0)
		)
		(polygon
			(pts
				(arc
					(start 102.05593 -292.716204)
					(mid 101.42601 -292.716204)
					(end 102.05593 -292.716204)
				)
			)
		)
	)
	(zone
		(layers "B.Cu" "In4.Cu" "In6.Cu" "In11.Cu" "In13.Cu" "In15.Cu")
		(hatch none 0.5)
		(connect_pads
			(clearance 0)
		)
		(min_thickness 0.25)
		(keepout
			(tracks not_allowed)
			(vias allowed)
			(pads allowed)
			(copperpour not_allowed)
			(footprints allowed)
		)
		(placement
			(enabled no)
			(sheetname "")
		)
		(fill yes
			(thermal_gap 0.5)
			(thermal_bridge_width 0.5)
			(island_removal_mode 0)
		)
		(polygon
			(pts
				(arc
					(start 288.514028 -314.635134)
					(mid 287.846008 -314.635134)
					(end 288.514028 -314.635134)
				)
			)
		)
	)
	(zone
		(layers "B.Cu" "In4.Cu" "In6.Cu" "In11.Cu" "In13.Cu" "In15.Cu")
		(hatch none 0.5)
		(connect_pads
			(clearance 0)
		)
		(min_thickness 0.25)
		(keepout
			(tracks not_allowed)
			(vias allowed)
			(pads allowed)
			(copperpour not_allowed)
			(footprints allowed)
		)
		(placement
			(enabled no)
			(sheetname "")
		)
		(fill yes
			(thermal_gap 0.5)
			(thermal_bridge_width 0.5)
			(island_removal_mode 0)
		)
		(polygon
			(pts
				(arc
					(start 95.005906 -291.906198)
					(mid 94.375986 -291.906198)
					(end 95.005906 -291.906198)
				)
			)
		)
	)
	(zone
		(layers "B.Cu" "In4.Cu" "In6.Cu" "In11.Cu" "In13.Cu" "In15.Cu")
		(hatch none 0.5)
		(connect_pads
			(clearance 0)
		)
		(min_thickness 0.25)
		(keepout
			(tracks not_allowed)
			(vias allowed)
			(pads allowed)
			(copperpour not_allowed)
			(footprints allowed)
		)
		(placement
			(enabled no)
			(sheetname "")
		)
		(fill yes
			(thermal_gap 0.5)
			(thermal_bridge_width 0.5)
			(island_removal_mode 0)
		)
		(polygon
			(pts
				(arc
					(start 179.850034 -213.485222)
					(mid 179.182014 -213.485222)
					(end 179.850034 -213.485222)
				)
			)
		)
	)
	(zone
		(layers "B.Cu" "In4.Cu" "In6.Cu" "In11.Cu" "In13.Cu" "In15.Cu")
		(hatch none 0.5)
		(connect_pads
			(clearance 0)
		)
		(min_thickness 0.25)
		(keepout
			(tracks not_allowed)
			(vias allowed)
			(pads allowed)
			(copperpour not_allowed)
			(footprints allowed)
		)
		(placement
			(enabled no)
			(sheetname "")
		)
		(fill yes
			(thermal_gap 0.5)
			(thermal_bridge_width 0.5)
			(island_removal_mode 0)
		)
		(polygon
			(pts
				(arc
					(start 256.261108 -205.439772)
					(mid 255.593088 -205.439772)
					(end 256.261108 -205.439772)
				)
			)
		)
	)
	(zone
		(layers "B.Cu" "In4.Cu" "In6.Cu" "In11.Cu" "In13.Cu" "In15.Cu")
		(hatch none 0.5)
		(connect_pads
			(clearance 0)
		)
		(min_thickness 0.25)
		(keepout
			(tracks not_allowed)
			(vias allowed)
			(pads allowed)
			(copperpour not_allowed)
			(footprints allowed)
		)
		(placement
			(enabled no)
			(sheetname "")
		)
		(fill yes
			(thermal_gap 0.5)
			(thermal_bridge_width 0.5)
			(island_removal_mode 0)
		)
		(polygon
			(pts
				(arc
					(start 288.514028 -268.735048)
					(mid 287.846008 -268.735048)
					(end 288.514028 -268.735048)
				)
			)
		)
	)
	(zone
		(layers "B.Cu" "In4.Cu" "In6.Cu" "In11.Cu" "In13.Cu" "In15.Cu")
		(hatch none 0.5)
		(connect_pads
			(clearance 0)
		)
		(min_thickness 0.25)
		(keepout
			(tracks not_allowed)
			(vias allowed)
			(pads allowed)
			(copperpour not_allowed)
			(footprints allowed)
		)
		(placement
			(enabled no)
			(sheetname "")
		)
		(fill yes
			(thermal_gap 0.5)
			(thermal_bridge_width 0.5)
			(island_removal_mode 0)
		)
		(polygon
			(pts
				(arc
					(start 374.129808 -228.284278)
					(mid 373.499888 -228.284278)
					(end 374.129808 -228.284278)
				)
			)
		)
	)
	(zone
		(layers "B.Cu" "In4.Cu" "In6.Cu" "In11.Cu" "In13.Cu" "In15.Cu")
		(hatch none 0.5)
		(connect_pads
			(clearance 0)
		)
		(min_thickness 0.25)
		(keepout
			(tracks not_allowed)
			(vias allowed)
			(pads allowed)
			(copperpour not_allowed)
			(footprints allowed)
		)
		(placement
			(enabled no)
			(sheetname "")
		)
		(fill yes
			(thermal_gap 0.5)
			(thermal_bridge_width 0.5)
			(island_removal_mode 0)
		)
		(polygon
			(pts
				(arc
					(start 292.614096 -223.6851)
					(mid 291.946076 -223.6851)
					(end 292.614096 -223.6851)
				)
			)
		)
	)
	(zone
		(layers "B.Cu" "In4.Cu" "In6.Cu" "In11.Cu" "In13.Cu" "In15.Cu")
		(hatch none 0.5)
		(connect_pads
			(clearance 0)
		)
		(min_thickness 0.25)
		(keepout
			(tracks not_allowed)
			(vias allowed)
			(pads allowed)
			(copperpour not_allowed)
			(footprints allowed)
		)
		(placement
			(enabled no)
			(sheetname "")
		)
		(fill yes
			(thermal_gap 0.5)
			(thermal_bridge_width 0.5)
			(island_removal_mode 0)
		)
		(polygon
			(pts
				(arc
					(start 40.57396 -216.885266)
					(mid 39.90594 -216.885266)
					(end 40.57396 -216.885266)
				)
			)
		)
	)
	(zone
		(layers "B.Cu" "In4.Cu" "In6.Cu" "In11.Cu" "In13.Cu" "In15.Cu")
		(hatch none 0.5)
		(connect_pads
			(clearance 0)
		)
		(min_thickness 0.25)
		(keepout
			(tracks not_allowed)
			(vias allowed)
			(pads allowed)
			(copperpour not_allowed)
			(footprints allowed)
		)
		(placement
			(enabled no)
			(sheetname "")
		)
		(fill yes
			(thermal_gap 0.5)
			(thermal_bridge_width 0.5)
			(island_removal_mode 0)
		)
		(polygon
			(pts
				(arc
					(start 376.009662 -244.484144)
					(mid 375.379742 -244.484144)
					(end 376.009662 -244.484144)
				)
			)
		)
	)
	(zone
		(layers "B.Cu" "In4.Cu" "In6.Cu" "In11.Cu" "In13.Cu" "In15.Cu")
		(hatch none 0.5)
		(connect_pads
			(clearance 0)
		)
		(min_thickness 0.25)
		(keepout
			(tracks not_allowed)
			(vias allowed)
			(pads allowed)
			(copperpour not_allowed)
			(footprints allowed)
		)
		(placement
			(enabled no)
			(sheetname "")
		)
		(fill yes
			(thermal_gap 0.5)
			(thermal_bridge_width 0.5)
			(island_removal_mode 0)
		)
		(polygon
			(pts
				(arc
					(start 44.674028 -275.53539)
					(mid 44.006008 -275.53539)
					(end 44.674028 -275.53539)
				)
			)
		)
	)
	(zone
		(layers "B.Cu" "In4.Cu" "In6.Cu" "In11.Cu" "In13.Cu" "In15.Cu")
		(hatch none 0.5)
		(connect_pads
			(clearance 0)
		)
		(min_thickness 0.25)
		(keepout
			(tracks not_allowed)
			(vias allowed)
			(pads allowed)
			(copperpour not_allowed)
			(footprints allowed)
		)
		(placement
			(enabled no)
			(sheetname "")
		)
		(fill yes
			(thermal_gap 0.5)
			(thermal_bridge_width 0.5)
			(island_removal_mode 0)
		)
		(polygon
			(pts
				(arc
					(start 427.790102 -251.735082)
					(mid 427.122082 -251.735082)
					(end 427.790102 -251.735082)
				)
			)
		)
	)
	(zone
		(layers "B.Cu" "In4.Cu" "In6.Cu" "In11.Cu" "In13.Cu" "In15.Cu")
		(hatch none 0.5)
		(connect_pads
			(clearance 0)
		)
		(min_thickness 0.25)
		(keepout
			(tracks not_allowed)
			(vias allowed)
			(pads allowed)
			(copperpour not_allowed)
			(footprints allowed)
		)
		(placement
			(enabled no)
			(sheetname "")
		)
		(fill yes
			(thermal_gap 0.5)
			(thermal_bridge_width 0.5)
			(island_removal_mode 0)
		)
		(polygon
			(pts
				(arc
					(start 179.850034 -248.335292)
					(mid 179.182014 -248.335292)
					(end 179.850034 -248.335292)
				)
			)
		)
	)
	(zone
		(layers "B.Cu" "In4.Cu" "In6.Cu" "In11.Cu" "In13.Cu" "In15.Cu")
		(hatch none 0.5)
		(connect_pads
			(clearance 0)
		)
		(min_thickness 0.25)
		(keepout
			(tracks not_allowed)
			(vias allowed)
			(pads allowed)
			(copperpour not_allowed)
			(footprints allowed)
		)
		(placement
			(enabled no)
			(sheetname "")
		)
		(fill yes
			(thermal_gap 0.5)
			(thermal_bridge_width 0.5)
			(island_removal_mode 0)
		)
		(polygon
			(pts
				(arc
					(start 98.936048 -229.90429)
					(mid 98.306128 -229.90429)
					(end 98.936048 -229.90429)
				)
			)
		)
	)
	(zone
		(layers "B.Cu" "In4.Cu" "In6.Cu" "In11.Cu" "In13.Cu" "In15.Cu")
		(hatch none 0.5)
		(connect_pads
			(clearance 0)
		)
		(min_thickness 0.25)
		(keepout
			(tracks not_allowed)
			(vias allowed)
			(pads allowed)
			(copperpour not_allowed)
			(footprints allowed)
		)
		(placement
			(enabled no)
			(sheetname "")
		)
		(fill yes
			(thermal_gap 0.5)
			(thermal_bridge_width 0.5)
			(island_removal_mode 0)
		)
		(polygon
			(pts
				(arc
					(start 44.674028 -210.935316)
					(mid 44.006008 -210.935316)
					(end 44.674028 -210.935316)
				)
			)
		)
	)
	(zone
		(layers "B.Cu" "In4.Cu" "In6.Cu" "In11.Cu" "In13.Cu" "In15.Cu")
		(hatch none 0.5)
		(connect_pads
			(clearance 0)
		)
		(min_thickness 0.25)
		(keepout
			(tracks not_allowed)
			(vias allowed)
			(pads allowed)
			(copperpour not_allowed)
			(footprints allowed)
		)
		(placement
			(enabled no)
			(sheetname "")
		)
		(fill yes
			(thermal_gap 0.5)
			(thermal_bridge_width 0.5)
			(island_removal_mode 0)
		)
		(polygon
			(pts
				(arc
					(start 343.886028 -278.946102)
					(mid 343.256108 -278.946102)
					(end 343.886028 -278.946102)
				)
			)
		)
	)
	(zone
		(layers "B.Cu" "In4.Cu" "In6.Cu" "In11.Cu" "In13.Cu" "In15.Cu")
		(hatch none 0.5)
		(connect_pads
			(clearance 0)
		)
		(min_thickness 0.25)
		(keepout
			(tracks not_allowed)
			(vias allowed)
			(pads allowed)
			(copperpour not_allowed)
			(footprints allowed)
		)
		(placement
			(enabled no)
			(sheetname "")
		)
		(fill yes
			(thermal_gap 0.5)
			(thermal_bridge_width 0.5)
			(island_removal_mode 0)
		)
		(polygon
			(pts
				(arc
					(start 292.614096 -203.28509)
					(mid 291.946076 -203.28509)
					(end 292.614096 -203.28509)
				)
			)
		)
	)
	(zone
		(layers "B.Cu" "In4.Cu" "In6.Cu" "In11.Cu" "In13.Cu" "In15.Cu")
		(hatch none 0.5)
		(connect_pads
			(clearance 0)
		)
		(min_thickness 0.25)
		(keepout
			(tracks not_allowed)
			(vias allowed)
			(pads allowed)
			(copperpour not_allowed)
			(footprints allowed)
		)
		(placement
			(enabled no)
			(sheetname "")
		)
		(fill yes
			(thermal_gap 0.5)
			(thermal_bridge_width 0.5)
			(island_removal_mode 0)
		)
		(polygon
			(pts
				(arc
					(start 344.055954 -231.524048)
					(mid 343.426034 -231.524048)
					(end 344.055954 -231.524048)
				)
			)
		)
	)
	(zone
		(layers "B.Cu" "In4.Cu" "In6.Cu" "In11.Cu" "In13.Cu" "In15.Cu")
		(hatch none 0.5)
		(connect_pads
			(clearance 0)
		)
		(min_thickness 0.25)
		(keepout
			(tracks not_allowed)
			(vias allowed)
			(pads allowed)
			(copperpour not_allowed)
			(footprints allowed)
		)
		(placement
			(enabled no)
			(sheetname "")
		)
		(fill yes
			(thermal_gap 0.5)
			(thermal_bridge_width 0.5)
			(island_removal_mode 0)
		)
		(polygon
			(pts
				(arc
					(start 292.614096 -283.185108)
					(mid 291.946076 -283.185108)
					(end 292.614096 -283.185108)
				)
			)
		)
	)
	(zone
		(layers "B.Cu" "In4.Cu" "In6.Cu" "In11.Cu" "In13.Cu" "In15.Cu")
		(hatch none 0.5)
		(connect_pads
			(clearance 0)
		)
		(min_thickness 0.25)
		(keepout
			(tracks not_allowed)
			(vias allowed)
			(pads allowed)
			(copperpour not_allowed)
			(footprints allowed)
		)
		(placement
			(enabled no)
			(sheetname "")
		)
		(fill yes
			(thermal_gap 0.5)
			(thermal_bridge_width 0.5)
			(island_removal_mode 0)
		)
		(polygon
			(pts
				(arc
					(start 431.89017 -200.735184)
					(mid 431.22215 -200.735184)
					(end 431.89017 -200.735184)
				)
			)
		)
	)
	(zone
		(layers "B.Cu" "In4.Cu" "In6.Cu" "In11.Cu" "In13.Cu" "In15.Cu")
		(hatch none 0.5)
		(connect_pads
			(clearance 0)
		)
		(min_thickness 0.25)
		(keepout
			(tracks not_allowed)
			(vias allowed)
			(pads allowed)
			(copperpour not_allowed)
			(footprints allowed)
		)
		(placement
			(enabled no)
			(sheetname "")
		)
		(fill yes
			(thermal_gap 0.5)
			(thermal_bridge_width 0.5)
			(island_removal_mode 0)
		)
		(polygon
			(pts
				(arc
					(start 128.539748 -245.294404)
					(mid 127.909828 -245.294404)
					(end 128.539748 -245.294404)
				)
			)
		)
	)
	(zone
		(layers "B.Cu" "In4.Cu" "In6.Cu" "In11.Cu" "In13.Cu" "In15.Cu")
		(hatch none 0.5)
		(connect_pads
			(clearance 0)
		)
		(min_thickness 0.25)
		(keepout
			(tracks not_allowed)
			(vias allowed)
			(pads allowed)
			(copperpour not_allowed)
			(footprints allowed)
		)
		(placement
			(enabled no)
			(sheetname "")
		)
		(fill yes
			(thermal_gap 0.5)
			(thermal_bridge_width 0.5)
			(island_removal_mode 0)
		)
		(polygon
			(pts
				(arc
					(start 342.945974 -267.606018)
					(mid 342.316054 -267.606018)
					(end 342.945974 -267.606018)
				)
			)
		)
	)
	(zone
		(layers "B.Cu" "In4.Cu" "In6.Cu" "In11.Cu" "In13.Cu" "In15.Cu")
		(hatch none 0.5)
		(connect_pads
			(clearance 0)
		)
		(min_thickness 0.25)
		(keepout
			(tracks not_allowed)
			(vias allowed)
			(pads allowed)
			(copperpour not_allowed)
			(footprints allowed)
		)
		(placement
			(enabled no)
			(sheetname "")
		)
		(fill yes
			(thermal_gap 0.5)
			(thermal_bridge_width 0.5)
			(island_removal_mode 0)
		)
		(polygon
			(pts
				(arc
					(start 376.77979 -293.525956)
					(mid 376.14987 -293.525956)
					(end 376.77979 -293.525956)
				)
			)
		)
	)
	(zone
		(layers "B.Cu" "In4.Cu" "In6.Cu" "In11.Cu" "In13.Cu" "In15.Cu")
		(hatch none 0.5)
		(connect_pads
			(clearance 0)
		)
		(min_thickness 0.25)
		(keepout
			(tracks not_allowed)
			(vias allowed)
			(pads allowed)
			(copperpour not_allowed)
			(footprints allowed)
		)
		(placement
			(enabled no)
			(sheetname "")
		)
		(fill yes
			(thermal_gap 0.5)
			(thermal_bridge_width 0.5)
			(island_removal_mode 0)
		)
		(polygon
			(pts
				(arc
					(start 96.416114 -287.856422)
					(mid 95.786194 -287.856422)
					(end 96.416114 -287.856422)
				)
			)
		)
	)
	(zone
		(layers "B.Cu" "In4.Cu" "In6.Cu" "In11.Cu" "In13.Cu" "In15.Cu")
		(hatch none 0.5)
		(connect_pads
			(clearance 0)
		)
		(min_thickness 0.25)
		(keepout
			(tracks not_allowed)
			(vias allowed)
			(pads allowed)
			(copperpour not_allowed)
			(footprints allowed)
		)
		(placement
			(enabled no)
			(sheetname "")
		)
		(fill yes
			(thermal_gap 0.5)
			(thermal_bridge_width 0.5)
			(island_removal_mode 0)
		)
		(polygon
			(pts
				(arc
					(start 288.514028 -289.985196)
					(mid 287.846008 -289.985196)
					(end 288.514028 -289.985196)
				)
			)
		)
	)
	(zone
		(layers "B.Cu" "In4.Cu" "In6.Cu" "In11.Cu" "In13.Cu" "In15.Cu")
		(hatch none 0.5)
		(connect_pads
			(clearance 0)
		)
		(min_thickness 0.25)
		(keepout
			(tracks not_allowed)
			(vias allowed)
			(pads allowed)
			(copperpour not_allowed)
			(footprints allowed)
		)
		(placement
			(enabled no)
			(sheetname "")
		)
		(fill yes
			(thermal_gap 0.5)
			(thermal_bridge_width 0.5)
			(island_removal_mode 0)
		)
		(polygon
			(pts
				(arc
					(start 342.476074 -271.656048)
					(mid 341.846154 -271.656048)
					(end 342.476074 -271.656048)
				)
			)
		)
	)
	(zone
		(layers "B.Cu" "In4.Cu" "In6.Cu" "In11.Cu" "In13.Cu" "In15.Cu")
		(hatch none 0.5)
		(connect_pads
			(clearance 0)
		)
		(min_thickness 0.25)
		(keepout
			(tracks not_allowed)
			(vias allowed)
			(pads allowed)
			(copperpour not_allowed)
			(footprints allowed)
		)
		(placement
			(enabled no)
			(sheetname "")
		)
		(fill yes
			(thermal_gap 0.5)
			(thermal_bridge_width 0.5)
			(island_removal_mode 0)
		)
		(polygon
			(pts
				(arc
					(start 427.790102 -211.784946)
					(mid 427.122082 -211.784946)
					(end 427.790102 -211.784946)
				)
			)
		)
	)
	(zone
		(layers "B.Cu" "In4.Cu" "In6.Cu" "In11.Cu" "In13.Cu" "In15.Cu")
		(hatch none 0.5)
		(connect_pads
			(clearance 0)
		)
		(min_thickness 0.25)
		(keepout
			(tracks not_allowed)
			(vias allowed)
			(pads allowed)
			(copperpour not_allowed)
			(footprints allowed)
		)
		(placement
			(enabled no)
			(sheetname "")
		)
		(fill yes
			(thermal_gap 0.5)
			(thermal_bridge_width 0.5)
			(island_removal_mode 0)
		)
		(polygon
			(pts
				(arc
					(start 342.1761 -234.764072)
					(mid 341.54618 -234.764072)
					(end 342.1761 -234.764072)
				)
			)
		)
	)
	(zone
		(layers "B.Cu" "In4.Cu" "In6.Cu" "In11.Cu" "In13.Cu" "In15.Cu")
		(hatch none 0.5)
		(connect_pads
			(clearance 0)
		)
		(min_thickness 0.25)
		(keepout
			(tracks not_allowed)
			(vias allowed)
			(pads allowed)
			(copperpour not_allowed)
			(footprints allowed)
		)
		(placement
			(enabled no)
			(sheetname "")
		)
		(fill yes
			(thermal_gap 0.5)
			(thermal_bridge_width 0.5)
			(island_removal_mode 0)
		)
		(polygon
			(pts
				(arc
					(start 95.94596 -264.366248)
					(mid 95.31604 -264.366248)
					(end 95.94596 -264.366248)
				)
			)
		)
	)
	(zone
		(layers "B.Cu" "In4.Cu" "In6.Cu" "In11.Cu" "In13.Cu" "In15.Cu")
		(hatch none 0.5)
		(connect_pads
			(clearance 0)
		)
		(min_thickness 0.25)
		(keepout
			(tracks not_allowed)
			(vias allowed)
			(pads allowed)
			(copperpour not_allowed)
			(footprints allowed)
		)
		(placement
			(enabled no)
			(sheetname "")
		)
		(fill yes
			(thermal_gap 0.5)
			(thermal_bridge_width 0.5)
			(island_removal_mode 0)
		)
		(polygon
			(pts
				(arc
					(start 343.586054 -237.19409)
					(mid 342.956134 -237.19409)
					(end 343.586054 -237.19409)
				)
			)
		)
	)
	(zone
		(layers "B.Cu" "In4.Cu" "In6.Cu" "In11.Cu" "In13.Cu" "In15.Cu")
		(hatch none 0.5)
		(connect_pads
			(clearance 0)
		)
		(min_thickness 0.25)
		(keepout
			(tracks not_allowed)
			(vias allowed)
			(pads allowed)
			(copperpour not_allowed)
			(footprints allowed)
		)
		(placement
			(enabled no)
			(sheetname "")
		)
		(fill yes
			(thermal_gap 0.5)
			(thermal_bridge_width 0.5)
			(island_removal_mode 0)
		)
		(polygon
			(pts
				(arc
					(start 431.89017 -304.435002)
					(mid 431.22215 -304.435002)
					(end 431.89017 -304.435002)
				)
			)
		)
	)
	(zone
		(layers "B.Cu" "In4.Cu" "In6.Cu" "In11.Cu" "In13.Cu" "In15.Cu")
		(hatch none 0.5)
		(connect_pads
			(clearance 0)
		)
		(min_thickness 0.25)
		(keepout
			(tracks not_allowed)
			(vias allowed)
			(pads allowed)
			(copperpour not_allowed)
			(footprints allowed)
		)
		(placement
			(enabled no)
			(sheetname "")
		)
		(fill yes
			(thermal_gap 0.5)
			(thermal_bridge_width 0.5)
			(island_removal_mode 0)
		)
		(polygon
			(pts
				(arc
					(start 427.790102 -229.63505)
					(mid 427.122082 -229.63505)
					(end 427.790102 -229.63505)
				)
			)
		)
	)
	(zone
		(layers "B.Cu" "In4.Cu" "In6.Cu" "In11.Cu" "In13.Cu" "In15.Cu")
		(hatch none 0.5)
		(connect_pads
			(clearance 0)
		)
		(min_thickness 0.25)
		(keepout
			(tracks not_allowed)
			(vias allowed)
			(pads allowed)
			(copperpour not_allowed)
			(footprints allowed)
		)
		(placement
			(enabled no)
			(sheetname "")
		)
		(fill yes
			(thermal_gap 0.5)
			(thermal_bridge_width 0.5)
			(island_removal_mode 0)
		)
		(polygon
			(pts
				(arc
					(start 128.369822 -287.856422)
					(mid 127.739902 -287.856422)
					(end 128.369822 -287.856422)
				)
			)
		)
	)
	(zone
		(layers "B.Cu" "In4.Cu" "In6.Cu" "In11.Cu" "In13.Cu" "In15.Cu")
		(hatch none 0.5)
		(connect_pads
			(clearance 0)
		)
		(min_thickness 0.25)
		(keepout
			(tracks not_allowed)
			(vias allowed)
			(pads allowed)
			(copperpour not_allowed)
			(footprints allowed)
		)
		(placement
			(enabled no)
			(sheetname "")
		)
		(fill yes
			(thermal_gap 0.5)
			(thermal_bridge_width 0.5)
			(island_removal_mode 0)
		)
		(polygon
			(pts
				(arc
					(start 365.144812 5.514594)
					(mid 364.476792 5.514594)
					(end 365.144812 5.514594)
				)
			)
		)
	)
	(zone
		(layers "B.Cu" "In4.Cu" "In6.Cu" "In11.Cu" "In13.Cu" "In15.Cu")
		(hatch none 0.5)
		(connect_pads
			(clearance 0)
		)
		(min_thickness 0.25)
		(keepout
			(tracks not_allowed)
			(vias allowed)
			(pads allowed)
			(copperpour not_allowed)
			(footprints allowed)
		)
		(placement
			(enabled no)
			(sheetname "")
		)
		(fill yes
			(thermal_gap 0.5)
			(thermal_bridge_width 0.5)
			(island_removal_mode 0)
		)
		(polygon
			(pts
				(arc
					(start 97.995994 -228.284532)
					(mid 97.366074 -228.284532)
					(end 97.995994 -228.284532)
				)
			)
		)
	)
	(zone
		(layers "B.Cu" "In4.Cu" "In6.Cu" "In11.Cu" "In13.Cu" "In15.Cu")
		(hatch none 0.5)
		(connect_pads
			(clearance 0)
		)
		(min_thickness 0.25)
		(keepout
			(tracks not_allowed)
			(vias allowed)
			(pads allowed)
			(copperpour not_allowed)
			(footprints allowed)
		)
		(placement
			(enabled no)
			(sheetname "")
		)
		(fill yes
			(thermal_gap 0.5)
			(thermal_bridge_width 0.5)
			(island_removal_mode 0)
		)
		(polygon
			(pts
				(arc
					(start 98.936048 -226.66452)
					(mid 98.306128 -226.66452)
					(end 98.936048 -226.66452)
				)
			)
		)
	)
	(zone
		(layers "B.Cu" "In4.Cu" "In6.Cu" "In11.Cu" "In13.Cu" "In15.Cu")
		(hatch none 0.5)
		(connect_pads
			(clearance 0)
		)
		(min_thickness 0.25)
		(keepout
			(tracks not_allowed)
			(vias allowed)
			(pads allowed)
			(copperpour not_allowed)
			(footprints allowed)
		)
		(placement
			(enabled no)
			(sheetname "")
		)
		(fill yes
			(thermal_gap 0.5)
			(thermal_bridge_width 0.5)
			(island_removal_mode 0)
		)
		(polygon
			(pts
				(arc
					(start 183.950102 -229.635304)
					(mid 183.282082 -229.635304)
					(end 183.950102 -229.635304)
				)
			)
		)
	)
	(zone
		(layers "B.Cu" "In4.Cu" "In6.Cu" "In11.Cu" "In13.Cu" "In15.Cu")
		(hatch none 0.5)
		(connect_pads
			(clearance 0)
		)
		(min_thickness 0.25)
		(keepout
			(tracks not_allowed)
			(vias allowed)
			(pads allowed)
			(copperpour not_allowed)
			(footprints allowed)
		)
		(placement
			(enabled no)
			(sheetname "")
		)
		(fill yes
			(thermal_gap 0.5)
			(thermal_bridge_width 0.5)
			(island_removal_mode 0)
		)
		(polygon
			(pts
				(arc
					(start 292.614096 -276.38502)
					(mid 291.946076 -276.38502)
					(end 292.614096 -276.38502)
				)
			)
		)
	)
	(zone
		(layers "B.Cu" "In4.Cu" "In6.Cu" "In11.Cu" "In13.Cu" "In15.Cu")
		(hatch none 0.5)
		(connect_pads
			(clearance 0)
		)
		(min_thickness 0.25)
		(keepout
			(tracks not_allowed)
			(vias allowed)
			(pads allowed)
			(copperpour not_allowed)
			(footprints allowed)
		)
		(placement
			(enabled no)
			(sheetname "")
		)
		(fill yes
			(thermal_gap 0.5)
			(thermal_bridge_width 0.5)
			(island_removal_mode 0)
		)
		(polygon
			(pts
				(arc
					(start 129.479802 -248.534428)
					(mid 128.849882 -248.534428)
					(end 129.479802 -248.534428)
				)
			)
		)
	)
	(zone
		(layers "B.Cu" "In4.Cu" "In6.Cu" "In11.Cu" "In13.Cu" "In15.Cu")
		(hatch none 0.5)
		(connect_pads
			(clearance 0)
		)
		(min_thickness 0.25)
		(keepout
			(tracks not_allowed)
			(vias allowed)
			(pads allowed)
			(copperpour not_allowed)
			(footprints allowed)
		)
		(placement
			(enabled no)
			(sheetname "")
		)
		(fill yes
			(thermal_gap 0.5)
			(thermal_bridge_width 0.5)
			(island_removal_mode 0)
		)
		(polygon
			(pts
				(arc
					(start 256.261108 -204.576172)
					(mid 255.593088 -204.576172)
					(end 256.261108 -204.576172)
				)
			)
		)
	)
	(zone
		(layers "B.Cu" "In4.Cu" "In6.Cu" "In11.Cu" "In13.Cu" "In15.Cu")
		(hatch none 0.5)
		(connect_pads
			(clearance 0)
		)
		(min_thickness 0.25)
		(keepout
			(tracks not_allowed)
			(vias allowed)
			(pads allowed)
			(copperpour not_allowed)
			(footprints allowed)
		)
		(placement
			(enabled no)
			(sheetname "")
		)
		(fill yes
			(thermal_gap 0.5)
			(thermal_bridge_width 0.5)
			(island_removal_mode 0)
		)
		(polygon
			(pts
				(arc
					(start 98.295968 -292.716204)
					(mid 97.666048 -292.716204)
					(end 98.295968 -292.716204)
				)
			)
		)
	)
	(zone
		(layers "B.Cu" "In4.Cu" "In6.Cu" "In11.Cu" "In13.Cu" "In15.Cu")
		(hatch none 0.5)
		(connect_pads
			(clearance 0)
		)
		(min_thickness 0.25)
		(keepout
			(tracks not_allowed)
			(vias allowed)
			(pads allowed)
			(copperpour not_allowed)
			(footprints allowed)
		)
		(placement
			(enabled no)
			(sheetname "")
		)
		(fill yes
			(thermal_gap 0.5)
			(thermal_bridge_width 0.5)
			(island_removal_mode 0)
		)
		(polygon
			(pts
				(arc
					(start 129.779776 -270.846296)
					(mid 129.149856 -270.846296)
					(end 129.779776 -270.846296)
				)
			)
		)
	)
	(zone
		(layers "B.Cu" "In4.Cu" "In6.Cu" "In11.Cu" "In13.Cu" "In15.Cu")
		(hatch none 0.5)
		(connect_pads
			(clearance 0)
		)
		(min_thickness 0.25)
		(keepout
			(tracks not_allowed)
			(vias allowed)
			(pads allowed)
			(copperpour not_allowed)
			(footprints allowed)
		)
		(placement
			(enabled no)
			(sheetname "")
		)
		(fill yes
			(thermal_gap 0.5)
			(thermal_bridge_width 0.5)
			(island_removal_mode 0)
		)
		(polygon
			(pts
				(arc
					(start 95.94596 -290.286186)
					(mid 95.31604 -290.286186)
					(end 95.94596 -290.286186)
				)
			)
		)
	)
	(zone
		(layers "B.Cu" "In4.Cu" "In6.Cu" "In11.Cu" "In13.Cu" "In15.Cu")
		(hatch none 0.5)
		(connect_pads
			(clearance 0)
		)
		(min_thickness 0.25)
		(keepout
			(tracks not_allowed)
			(vias allowed)
			(pads allowed)
			(copperpour not_allowed)
			(footprints allowed)
		)
		(placement
			(enabled no)
			(sheetname "")
		)
		(fill yes
			(thermal_gap 0.5)
			(thermal_bridge_width 0.5)
			(island_removal_mode 0)
		)
		(polygon
			(pts
				(arc
					(start 292.614096 -273.835114)
					(mid 291.946076 -273.835114)
					(end 292.614096 -273.835114)
				)
			)
		)
	)
	(zone
		(layers "B.Cu" "In4.Cu" "In6.Cu" "In11.Cu" "In13.Cu" "In15.Cu")
		(hatch none 0.5)
		(connect_pads
			(clearance 0)
		)
		(min_thickness 0.25)
		(keepout
			(tracks not_allowed)
			(vias allowed)
			(pads allowed)
			(copperpour not_allowed)
			(footprints allowed)
		)
		(placement
			(enabled no)
			(sheetname "")
		)
		(fill yes
			(thermal_gap 0.5)
			(thermal_bridge_width 0.5)
			(island_removal_mode 0)
		)
		(polygon
			(pts
				(arc
					(start 179.850034 -316.33541)
					(mid 179.182014 -316.33541)
					(end 179.850034 -316.33541)
				)
			)
		)
	)
	(zone
		(layers "B.Cu" "In4.Cu" "In6.Cu" "In11.Cu" "In13.Cu" "In15.Cu")
		(hatch none 0.5)
		(connect_pads
			(clearance 0)
		)
		(min_thickness 0.25)
		(keepout
			(tracks not_allowed)
			(vias allowed)
			(pads allowed)
			(copperpour not_allowed)
			(footprints allowed)
		)
		(placement
			(enabled no)
			(sheetname "")
		)
		(fill yes
			(thermal_gap 0.5)
			(thermal_bridge_width 0.5)
			(island_removal_mode 0)
		)
		(polygon
			(pts
				(arc
					(start 95.005906 -262.746236)
					(mid 94.375986 -262.746236)
					(end 95.005906 -262.746236)
				)
			)
		)
	)
	(zone
		(layers "B.Cu" "In4.Cu" "In6.Cu" "In11.Cu" "In13.Cu" "In15.Cu")
		(hatch none 0.5)
		(connect_pads
			(clearance 0)
		)
		(min_thickness 0.25)
		(keepout
			(tracks not_allowed)
			(vias allowed)
			(pads allowed)
			(copperpour not_allowed)
			(footprints allowed)
		)
		(placement
			(enabled no)
			(sheetname "")
		)
		(fill yes
			(thermal_gap 0.5)
			(thermal_bridge_width 0.5)
			(island_removal_mode 0)
		)
		(polygon
			(pts
				(arc
					(start 292.614096 -250.884944)
					(mid 291.946076 -250.884944)
					(end 292.614096 -250.884944)
				)
			)
		)
	)
	(zone
		(layers "B.Cu" "In4.Cu" "In6.Cu" "In11.Cu" "In13.Cu" "In15.Cu")
		(hatch none 0.5)
		(connect_pads
			(clearance 0)
		)
		(min_thickness 0.25)
		(keepout
			(tracks not_allowed)
			(vias allowed)
			(pads allowed)
			(copperpour not_allowed)
			(footprints allowed)
		)
		(placement
			(enabled no)
			(sheetname "")
		)
		(fill yes
			(thermal_gap 0.5)
			(thermal_bridge_width 0.5)
			(island_removal_mode 0)
		)
		(polygon
			(pts
				(arc
					(start 343.586054 -242.054126)
					(mid 342.956134 -242.054126)
					(end 343.586054 -242.054126)
				)
			)
		)
	)
	(zone
		(layers "B.Cu" "In4.Cu" "In6.Cu" "In11.Cu" "In13.Cu" "In15.Cu")
		(hatch none 0.5)
		(connect_pads
			(clearance 0)
		)
		(min_thickness 0.25)
		(keepout
			(tracks not_allowed)
			(vias allowed)
			(pads allowed)
			(copperpour not_allowed)
			(footprints allowed)
		)
		(placement
			(enabled no)
			(sheetname "")
		)
		(fill yes
			(thermal_gap 0.5)
			(thermal_bridge_width 0.5)
			(island_removal_mode 0)
		)
		(polygon
			(pts
				(arc
					(start 44.674028 -272.135346)
					(mid 44.006008 -272.135346)
					(end 44.674028 -272.135346)
				)
			)
		)
	)
	(zone
		(layers "B.Cu" "In4.Cu" "In6.Cu" "In11.Cu" "In13.Cu" "In15.Cu")
		(hatch none 0.5)
		(connect_pads
			(clearance 0)
		)
		(min_thickness 0.25)
		(keepout
			(tracks not_allowed)
			(vias allowed)
			(pads allowed)
			(copperpour not_allowed)
			(footprints allowed)
		)
		(placement
			(enabled no)
			(sheetname "")
		)
		(fill yes
			(thermal_gap 0.5)
			(thermal_bridge_width 0.5)
			(island_removal_mode 0)
		)
		(polygon
			(pts
				(arc
					(start 44.674028 -249.18543)
					(mid 44.006008 -249.18543)
					(end 44.674028 -249.18543)
				)
			)
		)
	)
	(zone
		(layers "B.Cu" "In4.Cu" "In6.Cu" "In11.Cu" "In13.Cu" "In15.Cu")
		(hatch none 0.5)
		(connect_pads
			(clearance 0)
		)
		(min_thickness 0.25)
		(keepout
			(tracks not_allowed)
			(vias allowed)
			(pads allowed)
			(copperpour not_allowed)
			(footprints allowed)
		)
		(placement
			(enabled no)
			(sheetname "")
		)
		(fill yes
			(thermal_gap 0.5)
			(thermal_bridge_width 0.5)
			(island_removal_mode 0)
		)
		(polygon
			(pts
				(arc
					(start 431.89017 -267.885164)
					(mid 431.22215 -267.885164)
					(end 431.89017 -267.885164)
				)
			)
		)
	)
	(zone
		(layers "B.Cu" "In4.Cu" "In6.Cu" "In11.Cu" "In13.Cu" "In15.Cu")
		(hatch none 0.5)
		(connect_pads
			(clearance 0)
		)
		(min_thickness 0.25)
		(keepout
			(tracks not_allowed)
			(vias allowed)
			(pads allowed)
			(copperpour not_allowed)
			(footprints allowed)
		)
		(placement
			(enabled no)
			(sheetname "")
		)
		(fill yes
			(thermal_gap 0.5)
			(thermal_bridge_width 0.5)
			(island_removal_mode 0)
		)
		(polygon
			(pts
				(arc
					(start 292.614096 -279.785064)
					(mid 291.946076 -279.785064)
					(end 292.614096 -279.785064)
				)
			)
		)
	)
	(zone
		(layers "B.Cu" "In4.Cu" "In6.Cu" "In11.Cu" "In13.Cu" "In15.Cu")
		(hatch none 0.5)
		(connect_pads
			(clearance 0)
		)
		(min_thickness 0.25)
		(keepout
			(tracks not_allowed)
			(vias allowed)
			(pads allowed)
			(copperpour not_allowed)
			(footprints allowed)
		)
		(placement
			(enabled no)
			(sheetname "")
		)
		(fill yes
			(thermal_gap 0.5)
			(thermal_bridge_width 0.5)
			(island_removal_mode 0)
		)
		(polygon
			(pts
				(arc
					(start 376.479816 -233.954066)
					(mid 375.849896 -233.954066)
					(end 376.479816 -233.954066)
				)
			)
		)
	)
	(zone
		(layers "B.Cu" "In4.Cu" "In6.Cu" "In11.Cu" "In13.Cu" "In15.Cu")
		(hatch none 0.5)
		(connect_pads
			(clearance 0)
		)
		(min_thickness 0.25)
		(keepout
			(tracks not_allowed)
			(vias allowed)
			(pads allowed)
			(copperpour not_allowed)
			(footprints allowed)
		)
		(placement
			(enabled no)
			(sheetname "")
		)
		(fill yes
			(thermal_gap 0.5)
			(thermal_bridge_width 0.5)
			(island_removal_mode 0)
		)
		(polygon
			(pts
				(arc
					(start 183.950102 -225.385376)
					(mid 183.282082 -225.385376)
					(end 183.950102 -225.385376)
				)
			)
		)
	)
	(zone
		(layers "B.Cu" "In4.Cu" "In6.Cu" "In11.Cu" "In13.Cu" "In15.Cu")
		(hatch none 0.5)
		(connect_pads
			(clearance 0)
		)
		(min_thickness 0.25)
		(keepout
			(tracks not_allowed)
			(vias allowed)
			(pads allowed)
			(copperpour not_allowed)
			(footprints allowed)
		)
		(placement
			(enabled no)
			(sheetname "")
		)
		(fill yes
			(thermal_gap 0.5)
			(thermal_bridge_width 0.5)
			(island_removal_mode 0)
		)
		(polygon
			(pts
				(arc
					(start 431.89017 -284.88513)
					(mid 431.22215 -284.88513)
					(end 431.89017 -284.88513)
				)
			)
		)
	)
	(zone
		(layers "B.Cu" "In4.Cu" "In6.Cu" "In11.Cu" "In13.Cu" "In15.Cu")
		(hatch none 0.5)
		(connect_pads
			(clearance 0)
		)
		(min_thickness 0.25)
		(keepout
			(tracks not_allowed)
			(vias allowed)
			(pads allowed)
			(copperpour not_allowed)
			(footprints allowed)
		)
		(placement
			(enabled no)
			(sheetname "")
		)
		(fill yes
			(thermal_gap 0.5)
			(thermal_bridge_width 0.5)
			(island_removal_mode 0)
		)
		(polygon
			(pts
				(arc
					(start 292.614096 -220.285056)
					(mid 291.946076 -220.285056)
					(end 292.614096 -220.285056)
				)
			)
		)
	)
	(zone
		(layers "B.Cu" "In4.Cu" "In6.Cu" "In11.Cu" "In13.Cu" "In15.Cu")
		(hatch none 0.5)
		(connect_pads
			(clearance 0)
		)
		(min_thickness 0.25)
		(keepout
			(tracks not_allowed)
			(vias allowed)
			(pads allowed)
			(copperpour not_allowed)
			(footprints allowed)
		)
		(placement
			(enabled no)
			(sheetname "")
		)
		(fill yes
			(thermal_gap 0.5)
			(thermal_bridge_width 0.5)
			(island_removal_mode 0)
		)
		(polygon
			(pts
				(arc
					(start 288.514028 -229.63505)
					(mid 287.846008 -229.63505)
					(end 288.514028 -229.63505)
				)
			)
		)
	)
	(zone
		(layers "B.Cu" "In4.Cu" "In6.Cu" "In11.Cu" "In13.Cu" "In15.Cu")
		(hatch none 0.5)
		(connect_pads
			(clearance 0)
		)
		(min_thickness 0.25)
		(keepout
			(tracks not_allowed)
			(vias allowed)
			(pads allowed)
			(copperpour not_allowed)
			(footprints allowed)
		)
		(placement
			(enabled no)
			(sheetname "")
		)
		(fill yes
			(thermal_gap 0.5)
			(thermal_bridge_width 0.5)
			(island_removal_mode 0)
		)
		(polygon
			(pts
				(arc
					(start 128.369822 -273.276314)
					(mid 127.739902 -273.276314)
					(end 128.369822 -273.276314)
				)
			)
		)
	)
	(zone
		(layers "B.Cu" "In4.Cu" "In6.Cu" "In11.Cu" "In13.Cu" "In15.Cu")
		(hatch none 0.5)
		(connect_pads
			(clearance 0)
		)
		(min_thickness 0.25)
		(keepout
			(tracks not_allowed)
			(vias allowed)
			(pads allowed)
			(copperpour not_allowed)
			(footprints allowed)
		)
		(placement
			(enabled no)
			(sheetname "")
		)
		(fill yes
			(thermal_gap 0.5)
			(thermal_bridge_width 0.5)
			(island_removal_mode 0)
		)
		(polygon
			(pts
				(arc
					(start 94.705932 -256.634488)
					(mid 94.076012 -256.634488)
					(end 94.705932 -256.634488)
				)
			)
		)
	)
	(zone
		(layers "B.Cu" "In4.Cu" "In6.Cu" "In11.Cu" "In13.Cu" "In15.Cu")
		(hatch none 0.5)
		(connect_pads
			(clearance 0)
		)
		(min_thickness 0.25)
		(keepout
			(tracks not_allowed)
			(vias allowed)
			(pads allowed)
			(copperpour not_allowed)
			(footprints allowed)
		)
		(placement
			(enabled no)
			(sheetname "")
		)
		(fill yes
			(thermal_gap 0.5)
			(thermal_bridge_width 0.5)
			(island_removal_mode 0)
		)
		(polygon
			(pts
				(arc
					(start 256.261108 -211.011516)
					(mid 255.593088 -211.011516)
					(end 256.261108 -211.011516)
				)
			)
		)
	)
	(zone
		(layers "B.Cu" "In4.Cu" "In6.Cu" "In11.Cu" "In13.Cu" "In15.Cu")
		(hatch none 0.5)
		(connect_pads
			(clearance 0)
		)
		(min_thickness 0.25)
		(keepout
			(tracks not_allowed)
			(vias allowed)
			(pads allowed)
			(copperpour not_allowed)
			(footprints allowed)
		)
		(placement
			(enabled no)
			(sheetname "")
		)
		(fill yes
			(thermal_gap 0.5)
			(thermal_bridge_width 0.5)
			(island_removal_mode 0)
		)
		(polygon
			(pts
				(arc
					(start 376.77979 -265.986006)
					(mid 376.14987 -265.986006)
					(end 376.77979 -265.986006)
				)
			)
		)
	)
	(zone
		(layers "B.Cu" "In4.Cu" "In6.Cu" "In11.Cu" "In13.Cu" "In15.Cu")
		(hatch none 0.5)
		(connect_pads
			(clearance 0)
		)
		(min_thickness 0.25)
		(keepout
			(tracks not_allowed)
			(vias allowed)
			(pads allowed)
			(copperpour not_allowed)
			(footprints allowed)
		)
		(placement
			(enabled no)
			(sheetname "")
		)
		(fill yes
			(thermal_gap 0.5)
			(thermal_bridge_width 0.5)
			(island_removal_mode 0)
		)
		(polygon
			(pts
				(arc
					(start 128.369822 -284.616398)
					(mid 127.739902 -284.616398)
					(end 128.369822 -284.616398)
				)
			)
		)
	)
	(zone
		(layers "B.Cu" "In4.Cu" "In6.Cu" "In11.Cu" "In13.Cu" "In15.Cu")
		(hatch none 0.5)
		(connect_pads
			(clearance 0)
		)
		(min_thickness 0.25)
		(keepout
			(tracks not_allowed)
			(vias allowed)
			(pads allowed)
			(copperpour not_allowed)
			(footprints allowed)
		)
		(placement
			(enabled no)
			(sheetname "")
		)
		(fill yes
			(thermal_gap 0.5)
			(thermal_bridge_width 0.5)
			(island_removal_mode 0)
		)
		(polygon
			(pts
				(arc
					(start 183.950102 -208.38541)
					(mid 183.282082 -208.38541)
					(end 183.950102 -208.38541)
				)
			)
		)
	)
	(zone
		(layers "B.Cu" "In4.Cu" "In6.Cu" "In11.Cu" "In13.Cu" "In15.Cu")
		(hatch none 0.5)
		(connect_pads
			(clearance 0)
		)
		(min_thickness 0.25)
		(keepout
			(tracks not_allowed)
			(vias allowed)
			(pads allowed)
			(copperpour not_allowed)
			(footprints allowed)
		)
		(placement
			(enabled no)
			(sheetname "")
		)
		(fill yes
			(thermal_gap 0.5)
			(thermal_bridge_width 0.5)
			(island_removal_mode 0)
		)
		(polygon
			(pts
				(arc
					(start 183.950102 -216.035382)
					(mid 183.282082 -216.035382)
					(end 183.950102 -216.035382)
				)
			)
		)
	)
	(zone
		(layers "B.Cu" "In4.Cu" "In6.Cu" "In11.Cu" "In13.Cu" "In15.Cu")
		(hatch none 0.5)
		(connect_pads
			(clearance 0)
		)
		(min_thickness 0.25)
		(keepout
			(tracks not_allowed)
			(vias allowed)
			(pads allowed)
			(copperpour not_allowed)
			(footprints allowed)
		)
		(placement
			(enabled no)
			(sheetname "")
		)
		(fill yes
			(thermal_gap 0.5)
			(thermal_bridge_width 0.5)
			(island_removal_mode 0)
		)
		(polygon
			(pts
				(arc
					(start 95.645986 -227.474526)
					(mid 95.016066 -227.474526)
					(end 95.645986 -227.474526)
				)
			)
		)
	)
	(zone
		(layers "B.Cu" "In4.Cu" "In6.Cu" "In11.Cu" "In13.Cu" "In15.Cu")
		(hatch none 0.5)
		(connect_pads
			(clearance 0)
		)
		(min_thickness 0.25)
		(keepout
			(tracks not_allowed)
			(vias allowed)
			(pads allowed)
			(copperpour not_allowed)
			(footprints allowed)
		)
		(placement
			(enabled no)
			(sheetname "")
		)
		(fill yes
			(thermal_gap 0.5)
			(thermal_bridge_width 0.5)
			(island_removal_mode 0)
		)
		(polygon
			(pts
				(arc
					(start 129.949702 -241.244374)
					(mid 129.319782 -241.244374)
					(end 129.949702 -241.244374)
				)
			)
		)
	)
	(zone
		(layers "B.Cu" "In4.Cu" "In6.Cu" "In11.Cu" "In13.Cu" "In15.Cu")
		(hatch none 0.5)
		(connect_pads
			(clearance 0)
		)
		(min_thickness 0.25)
		(keepout
			(tracks not_allowed)
			(vias allowed)
			(pads allowed)
			(copperpour not_allowed)
			(footprints allowed)
		)
		(placement
			(enabled no)
			(sheetname "")
		)
		(fill yes
			(thermal_gap 0.5)
			(thermal_bridge_width 0.5)
			(island_removal_mode 0)
		)
		(polygon
			(pts
				(arc
					(start 376.009662 -250.964192)
					(mid 375.379742 -250.964192)
					(end 376.009662 -250.964192)
				)
			)
		)
	)
	(zone
		(layers "B.Cu" "In4.Cu" "In6.Cu" "In11.Cu" "In13.Cu" "In15.Cu")
		(hatch none 0.5)
		(connect_pads
			(clearance 0)
		)
		(min_thickness 0.25)
		(keepout
			(tracks not_allowed)
			(vias allowed)
			(pads allowed)
			(copperpour not_allowed)
			(footprints allowed)
		)
		(placement
			(enabled no)
			(sheetname "")
		)
		(fill yes
			(thermal_gap 0.5)
			(thermal_bridge_width 0.5)
			(island_removal_mode 0)
		)
		(polygon
			(pts
				(arc
					(start 288.514028 -211.784946)
					(mid 287.846008 -211.784946)
					(end 288.514028 -211.784946)
				)
			)
		)
	)
	(zone
		(layers "B.Cu" "In4.Cu" "In6.Cu" "In11.Cu" "In13.Cu" "In15.Cu")
		(hatch none 0.5)
		(connect_pads
			(clearance 0)
		)
		(min_thickness 0.25)
		(keepout
			(tracks not_allowed)
			(vias allowed)
			(pads allowed)
			(copperpour not_allowed)
			(footprints allowed)
		)
		(placement
			(enabled no)
			(sheetname "")
		)
		(fill yes
			(thermal_gap 0.5)
			(thermal_bridge_width 0.5)
			(island_removal_mode 0)
		)
		(polygon
			(pts
				(arc
					(start 427.790102 -313.784996)
					(mid 427.122082 -313.784996)
					(end 427.790102 -313.784996)
				)
			)
		)
	)
	(zone
		(layers "B.Cu" "In4.Cu" "In6.Cu" "In11.Cu" "In13.Cu" "In15.Cu")
		(hatch none 0.5)
		(connect_pads
			(clearance 0)
		)
		(min_thickness 0.25)
		(keepout
			(tracks not_allowed)
			(vias allowed)
			(pads allowed)
			(copperpour not_allowed)
			(footprints allowed)
		)
		(placement
			(enabled no)
			(sheetname "")
		)
		(fill yes
			(thermal_gap 0.5)
			(thermal_bridge_width 0.5)
			(island_removal_mode 0)
		)
		(polygon
			(pts
				(arc
					(start 128.839722 -283.806392)
					(mid 128.209802 -283.806392)
					(end 128.839722 -283.806392)
				)
			)
		)
	)
	(zone
		(layers "B.Cu" "In4.Cu" "In6.Cu" "In11.Cu" "In13.Cu" "In15.Cu")
		(hatch none 0.5)
		(connect_pads
			(clearance 0)
		)
		(min_thickness 0.25)
		(keepout
			(tracks not_allowed)
			(vias allowed)
			(pads allowed)
			(copperpour not_allowed)
			(footprints allowed)
		)
		(placement
			(enabled no)
			(sheetname "")
		)
		(fill yes
			(thermal_gap 0.5)
			(thermal_bridge_width 0.5)
			(island_removal_mode 0)
		)
		(polygon
			(pts
				(arc
					(start 40.57396 -280.635202)
					(mid 39.90594 -280.635202)
					(end 40.57396 -280.635202)
				)
			)
		)
	)
	(zone
		(layers "B.Cu" "In4.Cu" "In6.Cu" "In11.Cu" "In13.Cu" "In15.Cu")
		(hatch none 0.5)
		(connect_pads
			(clearance 0)
		)
		(min_thickness 0.25)
		(keepout
			(tracks not_allowed)
			(vias allowed)
			(pads allowed)
			(copperpour not_allowed)
			(footprints allowed)
		)
		(placement
			(enabled no)
			(sheetname "")
		)
		(fill yes
			(thermal_gap 0.5)
			(thermal_bridge_width 0.5)
			(island_removal_mode 0)
		)
		(polygon
			(pts
				(arc
					(start 342.945974 -272.466054)
					(mid 342.316054 -272.466054)
					(end 342.945974 -272.466054)
				)
			)
		)
	)
	(zone
		(layers "B.Cu" "In4.Cu" "In6.Cu" "In11.Cu" "In13.Cu" "In15.Cu")
		(hatch none 0.5)
		(connect_pads
			(clearance 0)
		)
		(min_thickness 0.25)
		(keepout
			(tracks not_allowed)
			(vias allowed)
			(pads allowed)
			(copperpour not_allowed)
			(footprints allowed)
		)
		(placement
			(enabled no)
			(sheetname "")
		)
		(fill yes
			(thermal_gap 0.5)
			(thermal_bridge_width 0.5)
			(island_removal_mode 0)
		)
		(polygon
			(pts
				(arc
					(start 183.950102 -206.685388)
					(mid 183.282082 -206.685388)
					(end 183.950102 -206.685388)
				)
			)
		)
	)
	(zone
		(layers "B.Cu" "In4.Cu" "In6.Cu" "In11.Cu" "In13.Cu" "In15.Cu")
		(hatch none 0.5)
		(connect_pads
			(clearance 0)
		)
		(min_thickness 0.25)
		(keepout
			(tracks not_allowed)
			(vias allowed)
			(pads allowed)
			(copperpour not_allowed)
			(footprints allowed)
		)
		(placement
			(enabled no)
			(sheetname "")
		)
		(fill yes
			(thermal_gap 0.5)
			(thermal_bridge_width 0.5)
			(island_removal_mode 0)
		)
		(polygon
			(pts
				(arc
					(start 344.356182 -284.616144)
					(mid 343.726262 -284.616144)
					(end 344.356182 -284.616144)
				)
			)
		)
	)
	(zone
		(layers "B.Cu" "In4.Cu" "In6.Cu" "In11.Cu" "In13.Cu" "In15.Cu")
		(hatch none 0.5)
		(connect_pads
			(clearance 0)
		)
		(min_thickness 0.25)
		(keepout
			(tracks not_allowed)
			(vias allowed)
			(pads allowed)
			(copperpour not_allowed)
			(footprints allowed)
		)
		(placement
			(enabled no)
			(sheetname "")
		)
		(fill yes
			(thermal_gap 0.5)
			(thermal_bridge_width 0.5)
			(island_removal_mode 0)
		)
		(polygon
			(pts
				(arc
					(start 342.1761 -238.004096)
					(mid 341.54618 -238.004096)
					(end 342.1761 -238.004096)
				)
			)
		)
	)
	(zone
		(layers "B.Cu" "In4.Cu" "In6.Cu" "In11.Cu" "In13.Cu" "In15.Cu")
		(hatch none 0.5)
		(connect_pads
			(clearance 0)
		)
		(min_thickness 0.25)
		(keepout
			(tracks not_allowed)
			(vias allowed)
			(pads allowed)
			(copperpour not_allowed)
			(footprints allowed)
		)
		(placement
			(enabled no)
			(sheetname "")
		)
		(fill yes
			(thermal_gap 0.5)
			(thermal_bridge_width 0.5)
			(island_removal_mode 0)
		)
		(polygon
			(pts
				(arc
					(start 427.790102 -224.534984)
					(mid 427.122082 -224.534984)
					(end 427.790102 -224.534984)
				)
			)
		)
	)
	(zone
		(layers "B.Cu" "In4.Cu" "In6.Cu" "In11.Cu" "In13.Cu" "In15.Cu")
		(hatch none 0.5)
		(connect_pads
			(clearance 0)
		)
		(min_thickness 0.25)
		(keepout
			(tracks not_allowed)
			(vias allowed)
			(pads allowed)
			(copperpour not_allowed)
			(footprints allowed)
		)
		(placement
			(enabled no)
			(sheetname "")
		)
		(fill yes
			(thermal_gap 0.5)
			(thermal_bridge_width 0.5)
			(island_removal_mode 0)
		)
		(polygon
			(pts
				(arc
					(start 95.645986 -233.95432)
					(mid 95.016066 -233.95432)
					(end 95.645986 -233.95432)
				)
			)
		)
	)
	(zone
		(layers "B.Cu" "In4.Cu" "In6.Cu" "In11.Cu" "In13.Cu" "In15.Cu")
		(hatch none 0.5)
		(connect_pads
			(clearance 0)
		)
		(min_thickness 0.25)
		(keepout
			(tracks not_allowed)
			(vias allowed)
			(pads allowed)
			(copperpour not_allowed)
			(footprints allowed)
		)
		(placement
			(enabled no)
			(sheetname "")
		)
		(fill yes
			(thermal_gap 0.5)
			(thermal_bridge_width 0.5)
			(island_removal_mode 0)
		)
		(polygon
			(pts
				(arc
					(start 179.850034 -304.435256)
					(mid 179.182014 -304.435256)
					(end 179.850034 -304.435256)
				)
			)
		)
	)
	(zone
		(layers "B.Cu" "In4.Cu" "In6.Cu" "In11.Cu" "In13.Cu" "In15.Cu")
		(hatch none 0.5)
		(connect_pads
			(clearance 0)
		)
		(min_thickness 0.25)
		(keepout
			(tracks not_allowed)
			(vias allowed)
			(pads allowed)
			(copperpour not_allowed)
			(footprints allowed)
		)
		(placement
			(enabled no)
			(sheetname "")
		)
		(fill yes
			(thermal_gap 0.5)
			(thermal_bridge_width 0.5)
			(island_removal_mode 0)
		)
		(polygon
			(pts
				(arc
					(start 40.57396 -243.235226)
					(mid 39.90594 -243.235226)
					(end 40.57396 -243.235226)
				)
			)
		)
	)
	(zone
		(layers "B.Cu" "In4.Cu" "In6.Cu" "In11.Cu" "In13.Cu" "In15.Cu")
		(hatch none 0.5)
		(connect_pads
			(clearance 0)
		)
		(min_thickness 0.25)
		(keepout
			(tracks not_allowed)
			(vias allowed)
			(pads allowed)
			(copperpour not_allowed)
			(footprints allowed)
		)
		(placement
			(enabled no)
			(sheetname "")
		)
		(fill yes
			(thermal_gap 0.5)
			(thermal_bridge_width 0.5)
			(island_removal_mode 0)
		)
		(polygon
			(pts
				(arc
					(start 362.379768 -230.714296)
					(mid 361.749848 -230.714296)
					(end 362.379768 -230.714296)
				)
			)
		)
	)
	(zone
		(layers "B.Cu" "In4.Cu" "In6.Cu" "In11.Cu" "In13.Cu" "In15.Cu")
		(hatch none 0.5)
		(connect_pads
			(clearance 0)
		)
		(min_thickness 0.25)
		(keepout
			(tracks not_allowed)
			(vias allowed)
			(pads allowed)
			(copperpour not_allowed)
			(footprints allowed)
		)
		(placement
			(enabled no)
			(sheetname "")
		)
		(fill yes
			(thermal_gap 0.5)
			(thermal_bridge_width 0.5)
			(island_removal_mode 0)
		)
		(polygon
			(pts
				(arc
					(start 44.674028 -231.335326)
					(mid 44.006008 -231.335326)
					(end 44.674028 -231.335326)
				)
			)
		)
	)
	(zone
		(layers "B.Cu" "In4.Cu" "In6.Cu" "In11.Cu" "In13.Cu" "In15.Cu")
		(hatch none 0.5)
		(connect_pads
			(clearance 0)
		)
		(min_thickness 0.25)
		(keepout
			(tracks not_allowed)
			(vias allowed)
			(pads allowed)
			(copperpour not_allowed)
			(footprints allowed)
		)
		(placement
			(enabled no)
			(sheetname "")
		)
		(fill yes
			(thermal_gap 0.5)
			(thermal_bridge_width 0.5)
			(island_removal_mode 0)
		)
		(polygon
			(pts
				(arc
					(start 128.539748 -225.854514)
					(mid 127.909828 -225.854514)
					(end 128.539748 -225.854514)
				)
			)
		)
	)
	(zone
		(layers "B.Cu" "In4.Cu" "In6.Cu" "In11.Cu" "In13.Cu" "In15.Cu")
		(hatch none 0.5)
		(connect_pads
			(clearance 0)
		)
		(min_thickness 0.25)
		(keepout
			(tracks not_allowed)
			(vias allowed)
			(pads allowed)
			(copperpour not_allowed)
			(footprints allowed)
		)
		(placement
			(enabled no)
			(sheetname "")
		)
		(fill yes
			(thermal_gap 0.5)
			(thermal_bridge_width 0.5)
			(island_removal_mode 0)
		)
		(polygon
			(pts
				(arc
					(start 342.476074 -278.136096)
					(mid 341.846154 -278.136096)
					(end 342.476074 -278.136096)
				)
			)
		)
	)
	(zone
		(layers "B.Cu" "In4.Cu" "In6.Cu" "In11.Cu" "In13.Cu" "In15.Cu")
		(hatch none 0.5)
		(connect_pads
			(clearance 0)
		)
		(min_thickness 0.25)
		(keepout
			(tracks not_allowed)
			(vias allowed)
			(pads allowed)
			(copperpour not_allowed)
			(footprints allowed)
		)
		(placement
			(enabled no)
			(sheetname "")
		)
		(fill yes
			(thermal_gap 0.5)
			(thermal_bridge_width 0.5)
			(island_removal_mode 0)
		)
		(polygon
			(pts
				(arc
					(start 377.41987 -245.29415)
					(mid 376.78995 -245.29415)
					(end 377.41987 -245.29415)
				)
			)
		)
	)
	(zone
		(layers "B.Cu" "In4.Cu" "In6.Cu" "In11.Cu" "In13.Cu" "In15.Cu")
		(hatch none 0.5)
		(connect_pads
			(clearance 0)
		)
		(min_thickness 0.25)
		(keepout
			(tracks not_allowed)
			(vias allowed)
			(pads allowed)
			(copperpour not_allowed)
			(footprints allowed)
		)
		(placement
			(enabled no)
			(sheetname "")
		)
		(fill yes
			(thermal_gap 0.5)
			(thermal_bridge_width 0.5)
			(island_removal_mode 0)
		)
		(polygon
			(pts
				(arc
					(start 130.249676 -281.376374)
					(mid 129.619756 -281.376374)
					(end 130.249676 -281.376374)
				)
			)
		)
	)
	(zone
		(layers "B.Cu" "In4.Cu" "In6.Cu" "In11.Cu" "In13.Cu" "In15.Cu")
		(hatch none 0.5)
		(connect_pads
			(clearance 0)
		)
		(min_thickness 0.25)
		(keepout
			(tracks not_allowed)
			(vias allowed)
			(pads allowed)
			(copperpour not_allowed)
			(footprints allowed)
		)
		(placement
			(enabled no)
			(sheetname "")
		)
		(fill yes
			(thermal_gap 0.5)
			(thermal_bridge_width 0.5)
			(island_removal_mode 0)
		)
		(polygon
			(pts
				(arc
					(start 292.614096 -272.135092)
					(mid 291.946076 -272.135092)
					(end 292.614096 -272.135092)
				)
			)
		)
	)
	(zone
		(layers "B.Cu" "In4.Cu" "In6.Cu" "In11.Cu" "In13.Cu" "In15.Cu")
		(hatch none 0.5)
		(connect_pads
			(clearance 0)
		)
		(min_thickness 0.25)
		(keepout
			(tracks not_allowed)
			(vias allowed)
			(pads allowed)
			(copperpour not_allowed)
			(footprints allowed)
		)
		(placement
			(enabled no)
			(sheetname "")
		)
		(fill yes
			(thermal_gap 0.5)
			(thermal_bridge_width 0.5)
			(island_removal_mode 0)
		)
		(polygon
			(pts
				(arc
					(start 292.614096 -199.035162)
					(mid 291.946076 -199.035162)
					(end 292.614096 -199.035162)
				)
			)
		)
	)
	(zone
		(layers "B.Cu" "In4.Cu" "In6.Cu" "In11.Cu" "In13.Cu" "In15.Cu")
		(hatch none 0.5)
		(connect_pads
			(clearance 0)
		)
		(min_thickness 0.25)
		(keepout
			(tracks not_allowed)
			(vias allowed)
			(pads allowed)
			(copperpour not_allowed)
			(footprints allowed)
		)
		(placement
			(enabled no)
			(sheetname "")
		)
		(fill yes
			(thermal_gap 0.5)
			(thermal_bridge_width 0.5)
			(island_removal_mode 0)
		)
		(polygon
			(pts
				(arc
					(start 377.719844 -270.846042)
					(mid 377.089924 -270.846042)
					(end 377.719844 -270.846042)
				)
			)
		)
	)
	(zone
		(layers "B.Cu" "In4.Cu" "In6.Cu" "In11.Cu" "In13.Cu" "In15.Cu")
		(hatch none 0.5)
		(connect_pads
			(clearance 0)
		)
		(min_thickness 0.25)
		(keepout
			(tracks not_allowed)
			(vias allowed)
			(pads allowed)
			(copperpour not_allowed)
			(footprints allowed)
		)
		(placement
			(enabled no)
			(sheetname "")
		)
		(fill yes
			(thermal_gap 0.5)
			(thermal_bridge_width 0.5)
			(island_removal_mode 0)
		)
		(polygon
			(pts
				(arc
					(start 431.89017 -262.785098)
					(mid 431.22215 -262.785098)
					(end 431.89017 -262.785098)
				)
			)
		)
	)
	(zone
		(layers "B.Cu" "In4.Cu" "In6.Cu" "In11.Cu" "In13.Cu" "In15.Cu")
		(hatch none 0.5)
		(connect_pads
			(clearance 0)
		)
		(min_thickness 0.25)
		(keepout
			(tracks not_allowed)
			(vias allowed)
			(pads allowed)
			(copperpour not_allowed)
			(footprints allowed)
		)
		(placement
			(enabled no)
			(sheetname "")
		)
		(fill yes
			(thermal_gap 0.5)
			(thermal_bridge_width 0.5)
			(island_removal_mode 0)
		)
		(polygon
			(pts
				(arc
					(start 96.416114 -273.276314)
					(mid 95.786194 -273.276314)
					(end 96.416114 -273.276314)
				)
			)
		)
	)
	(zone
		(layers "B.Cu" "In4.Cu" "In6.Cu" "In11.Cu" "In13.Cu" "In15.Cu")
		(hatch none 0.5)
		(connect_pads
			(clearance 0)
		)
		(min_thickness 0.25)
		(keepout
			(tracks not_allowed)
			(vias allowed)
			(pads allowed)
			(copperpour not_allowed)
			(footprints allowed)
		)
		(placement
			(enabled no)
			(sheetname "")
		)
		(fill yes
			(thermal_gap 0.5)
			(thermal_bridge_width 0.5)
			(island_removal_mode 0)
		)
		(polygon
			(pts
				(arc
					(start 377.88977 -236.384084)
					(mid 377.25985 -236.384084)
					(end 377.88977 -236.384084)
				)
			)
		)
	)
	(zone
		(layers "B.Cu" "In4.Cu" "In6.Cu" "In11.Cu" "In13.Cu" "In15.Cu")
		(hatch none 0.5)
		(connect_pads
			(clearance 0)
		)
		(min_thickness 0.25)
		(keepout
			(tracks not_allowed)
			(vias allowed)
			(pads allowed)
			(copperpour not_allowed)
			(footprints allowed)
		)
		(placement
			(enabled no)
			(sheetname "")
		)
		(fill yes
			(thermal_gap 0.5)
			(thermal_bridge_width 0.5)
			(island_removal_mode 0)
		)
		(polygon
			(pts
				(arc
					(start 44.674028 -252.58522)
					(mid 44.006008 -252.58522)
					(end 44.674028 -252.58522)
				)
			)
		)
	)
	(zone
		(layers "B.Cu" "In4.Cu" "In6.Cu" "In11.Cu" "In13.Cu" "In15.Cu")
		(hatch none 0.5)
		(connect_pads
			(clearance 0)
		)
		(min_thickness 0.25)
		(keepout
			(tracks not_allowed)
			(vias allowed)
			(pads allowed)
			(copperpour not_allowed)
			(footprints allowed)
		)
		(placement
			(enabled no)
			(sheetname "")
		)
		(fill yes
			(thermal_gap 0.5)
			(thermal_bridge_width 0.5)
			(island_removal_mode 0)
		)
		(polygon
			(pts
				(arc
					(start 292.614096 -307.835046)
					(mid 291.946076 -307.835046)
					(end 292.614096 -307.835046)
				)
			)
		)
	)
	(zone
		(layers "B.Cu" "In4.Cu" "In6.Cu" "In11.Cu" "In13.Cu" "In15.Cu")
		(hatch none 0.5)
		(connect_pads
			(clearance 0)
		)
		(min_thickness 0.25)
		(keepout
			(tracks not_allowed)
			(vias allowed)
			(pads allowed)
			(copperpour not_allowed)
			(footprints allowed)
		)
		(placement
			(enabled no)
			(sheetname "")
		)
		(fill yes
			(thermal_gap 0.5)
			(thermal_bridge_width 0.5)
			(island_removal_mode 0)
		)
		(polygon
			(pts
				(arc
					(start 128.839722 -278.946356)
					(mid 128.209802 -278.946356)
					(end 128.839722 -278.946356)
				)
			)
		)
	)
	(zone
		(layers "B.Cu" "In4.Cu" "In6.Cu" "In11.Cu" "In13.Cu" "In15.Cu")
		(hatch none 0.5)
		(connect_pads
			(clearance 0)
		)
		(min_thickness 0.25)
		(keepout
			(tracks not_allowed)
			(vias allowed)
			(pads allowed)
			(copperpour not_allowed)
			(footprints allowed)
		)
		(placement
			(enabled no)
			(sheetname "")
		)
		(fill yes
			(thermal_gap 0.5)
			(thermal_bridge_width 0.5)
			(island_removal_mode 0)
		)
		(polygon
			(pts
				(arc
					(start 179.850034 -265.335258)
					(mid 179.182014 -265.335258)
					(end 179.850034 -265.335258)
				)
			)
		)
	)
	(zone
		(layers "B.Cu" "In4.Cu" "In6.Cu" "In11.Cu" "In13.Cu" "In15.Cu")
		(hatch none 0.5)
		(connect_pads
			(clearance 0)
		)
		(min_thickness 0.25)
		(keepout
			(tracks not_allowed)
			(vias allowed)
			(pads allowed)
			(copperpour not_allowed)
			(footprints allowed)
		)
		(placement
			(enabled no)
			(sheetname "")
		)
		(fill yes
			(thermal_gap 0.5)
			(thermal_bridge_width 0.5)
			(island_removal_mode 0)
		)
		(polygon
			(pts
				(arc
					(start 179.345844 -54.618128)
					(mid 178.677824 -54.618128)
					(end 179.345844 -54.618128)
				)
			)
		)
	)
	(zone
		(layers "B.Cu" "In4.Cu" "In6.Cu" "In11.Cu" "In13.Cu" "In15.Cu")
		(hatch none 0.5)
		(connect_pads
			(clearance 0)
		)
		(min_thickness 0.25)
		(keepout
			(tracks not_allowed)
			(vias allowed)
			(pads allowed)
			(copperpour not_allowed)
			(footprints allowed)
		)
		(placement
			(enabled no)
			(sheetname "")
		)
		(fill yes
			(thermal_gap 0.5)
			(thermal_bridge_width 0.5)
			(island_removal_mode 0)
		)
		(polygon
			(pts
				(arc
					(start 343.886028 -262.745982)
					(mid 343.256108 -262.745982)
					(end 343.886028 -262.745982)
				)
			)
		)
	)
	(zone
		(layers "B.Cu" "In4.Cu" "In6.Cu" "In11.Cu" "In13.Cu" "In15.Cu")
		(hatch none 0.5)
		(connect_pads
			(clearance 0)
		)
		(min_thickness 0.25)
		(keepout
			(tracks not_allowed)
			(vias allowed)
			(pads allowed)
			(copperpour not_allowed)
			(footprints allowed)
		)
		(placement
			(enabled no)
			(sheetname "")
		)
		(fill yes
			(thermal_gap 0.5)
			(thermal_bridge_width 0.5)
			(island_removal_mode 0)
		)
		(polygon
			(pts
				(arc
					(start 292.614096 -304.435002)
					(mid 291.946076 -304.435002)
					(end 292.614096 -304.435002)
				)
			)
		)
	)
	(zone
		(layers "B.Cu" "In4.Cu" "In6.Cu" "In11.Cu" "In13.Cu" "In15.Cu")
		(hatch none 0.5)
		(connect_pads
			(clearance 0)
		)
		(min_thickness 0.25)
		(keepout
			(tracks not_allowed)
			(vias allowed)
			(pads allowed)
			(copperpour not_allowed)
			(footprints allowed)
		)
		(placement
			(enabled no)
			(sheetname "")
		)
		(fill yes
			(thermal_gap 0.5)
			(thermal_bridge_width 0.5)
			(island_removal_mode 0)
		)
		(polygon
			(pts
				(arc
					(start 44.674028 -303.585372)
					(mid 44.006008 -303.585372)
					(end 44.674028 -303.585372)
				)
			)
		)
	)
	(zone
		(layers "B.Cu" "In4.Cu" "In6.Cu" "In11.Cu" "In13.Cu" "In15.Cu")
		(hatch none 0.5)
		(connect_pads
			(clearance 0)
		)
		(min_thickness 0.25)
		(keepout
			(tracks not_allowed)
			(vias allowed)
			(pads allowed)
			(copperpour not_allowed)
			(footprints allowed)
		)
		(placement
			(enabled no)
			(sheetname "")
		)
		(fill yes
			(thermal_gap 0.5)
			(thermal_bridge_width 0.5)
			(island_removal_mode 0)
		)
		(polygon
			(pts
				(arc
					(start 292.614096 -236.435138)
					(mid 291.946076 -236.435138)
					(end 292.614096 -236.435138)
				)
			)
		)
	)
	(zone
		(layers "B.Cu" "In4.Cu" "In6.Cu" "In11.Cu" "In13.Cu" "In15.Cu")
		(hatch none 0.5)
		(connect_pads
			(clearance 0)
		)
		(min_thickness 0.25)
		(keepout
			(tracks not_allowed)
			(vias allowed)
			(pads allowed)
			(copperpour not_allowed)
			(footprints allowed)
		)
		(placement
			(enabled no)
			(sheetname "")
		)
		(fill yes
			(thermal_gap 0.5)
			(thermal_bridge_width 0.5)
			(island_removal_mode 0)
		)
		(polygon
			(pts
				(arc
					(start 362.379768 -227.474272)
					(mid 361.749848 -227.474272)
					(end 362.379768 -227.474272)
				)
			)
		)
	)
	(zone
		(layers "B.Cu" "In4.Cu" "In6.Cu" "In11.Cu" "In13.Cu" "In15.Cu")
		(hatch none 0.5)
		(connect_pads
			(clearance 0)
		)
		(min_thickness 0.25)
		(keepout
			(tracks not_allowed)
			(vias allowed)
			(pads allowed)
			(copperpour not_allowed)
			(footprints allowed)
		)
		(placement
			(enabled no)
			(sheetname "")
		)
		(fill yes
			(thermal_gap 0.5)
			(thermal_bridge_width 0.5)
			(island_removal_mode 0)
		)
		(polygon
			(pts
				(arc
					(start 377.88977 -238.004096)
					(mid 377.25985 -238.004096)
					(end 377.88977 -238.004096)
				)
			)
		)
	)
	(zone
		(layers "B.Cu" "In4.Cu" "In6.Cu" "In11.Cu" "In13.Cu" "In15.Cu")
		(hatch none 0.5)
		(connect_pads
			(clearance 0)
		)
		(min_thickness 0.25)
		(keepout
			(tracks not_allowed)
			(vias allowed)
			(pads allowed)
			(copperpour not_allowed)
			(footprints allowed)
		)
		(placement
			(enabled no)
			(sheetname "")
		)
		(fill yes
			(thermal_gap 0.5)
			(thermal_bridge_width 0.5)
			(island_removal_mode 0)
		)
		(polygon
			(pts
				(arc
					(start 179.850034 -204.135228)
					(mid 179.182014 -204.135228)
					(end 179.850034 -204.135228)
				)
			)
		)
	)
	(zone
		(layers "B.Cu" "In4.Cu" "In6.Cu" "In11.Cu" "In13.Cu" "In15.Cu")
		(hatch none 0.5)
		(connect_pads
			(clearance 0)
		)
		(min_thickness 0.25)
		(keepout
			(tracks not_allowed)
			(vias allowed)
			(pads allowed)
			(copperpour not_allowed)
			(footprints allowed)
		)
		(placement
			(enabled no)
			(sheetname "")
		)
		(fill yes
			(thermal_gap 0.5)
			(thermal_bridge_width 0.5)
			(island_removal_mode 0)
		)
		(polygon
			(pts
				(arc
					(start 343.886028 -283.806138)
					(mid 343.256108 -283.806138)
					(end 343.886028 -283.806138)
				)
			)
		)
	)
	(zone
		(layers "B.Cu" "In4.Cu" "In6.Cu" "In11.Cu" "In13.Cu" "In15.Cu")
		(hatch none 0.5)
		(connect_pads
			(clearance 0)
		)
		(min_thickness 0.25)
		(keepout
			(tracks not_allowed)
			(vias allowed)
			(pads allowed)
			(copperpour not_allowed)
			(footprints allowed)
		)
		(placement
			(enabled no)
			(sheetname "")
		)
		(fill yes
			(thermal_gap 0.5)
			(thermal_bridge_width 0.5)
			(island_removal_mode 0)
		)
		(polygon
			(pts
				(arc
					(start 431.89017 -300.185074)
					(mid 431.22215 -300.185074)
					(end 431.89017 -300.185074)
				)
			)
		)
	)
	(zone
		(layers "B.Cu" "In4.Cu" "In6.Cu" "In11.Cu" "In13.Cu" "In15.Cu")
		(hatch none 0.5)
		(connect_pads
			(clearance 0)
		)
		(min_thickness 0.25)
		(keepout
			(tracks not_allowed)
			(vias allowed)
			(pads allowed)
			(copperpour not_allowed)
			(footprints allowed)
		)
		(placement
			(enabled no)
			(sheetname "")
		)
		(fill yes
			(thermal_gap 0.5)
			(thermal_bridge_width 0.5)
			(island_removal_mode 0)
		)
		(polygon
			(pts
				(arc
					(start 288.514028 -202.434952)
					(mid 287.846008 -202.434952)
					(end 288.514028 -202.434952)
				)
			)
		)
	)
	(zone
		(layers "B.Cu" "In4.Cu" "In6.Cu" "In11.Cu" "In13.Cu" "In15.Cu")
		(hatch none 0.5)
		(connect_pads
			(clearance 0)
		)
		(min_thickness 0.25)
		(keepout
			(tracks not_allowed)
			(vias allowed)
			(pads allowed)
			(copperpour not_allowed)
			(footprints allowed)
		)
		(placement
			(enabled no)
			(sheetname "")
		)
		(fill yes
			(thermal_gap 0.5)
			(thermal_bridge_width 0.5)
			(island_removal_mode 0)
		)
		(polygon
			(pts
				(arc
					(start 343.886028 -280.566114)
					(mid 343.256108 -280.566114)
					(end 343.886028 -280.566114)
				)
			)
		)
	)
	(zone
		(layers "B.Cu" "In4.Cu" "In6.Cu" "In11.Cu" "In13.Cu" "In15.Cu")
		(hatch none 0.5)
		(connect_pads
			(clearance 0)
		)
		(min_thickness 0.25)
		(keepout
			(tracks not_allowed)
			(vias allowed)
			(pads allowed)
			(copperpour not_allowed)
			(footprints allowed)
		)
		(placement
			(enabled no)
			(sheetname "")
		)
		(fill yes
			(thermal_gap 0.5)
			(thermal_bridge_width 0.5)
			(island_removal_mode 0)
		)
		(polygon
			(pts
				(arc
					(start 343.886028 -274.086066)
					(mid 343.256108 -274.086066)
					(end 343.886028 -274.086066)
				)
			)
		)
	)
	(zone
		(layers "B.Cu" "In4.Cu" "In6.Cu" "In11.Cu" "In13.Cu" "In15.Cu")
		(hatch none 0.5)
		(connect_pads
			(clearance 0)
		)
		(min_thickness 0.25)
		(keepout
			(tracks not_allowed)
			(vias allowed)
			(pads allowed)
			(copperpour not_allowed)
			(footprints allowed)
		)
		(placement
			(enabled no)
			(sheetname "")
		)
		(fill yes
			(thermal_gap 0.5)
			(thermal_bridge_width 0.5)
			(island_removal_mode 0)
		)
		(polygon
			(pts
				(arc
					(start 44.674028 -296.785284)
					(mid 44.006008 -296.785284)
					(end 44.674028 -296.785284)
				)
			)
		)
	)
	(zone
		(layers "B.Cu" "In4.Cu" "In6.Cu" "In11.Cu" "In13.Cu" "In15.Cu")
		(hatch none 0.5)
		(connect_pads
			(clearance 0)
		)
		(min_thickness 0.25)
		(keepout
			(tracks not_allowed)
			(vias allowed)
			(pads allowed)
			(copperpour not_allowed)
			(footprints allowed)
		)
		(placement
			(enabled no)
			(sheetname "")
		)
		(fill yes
			(thermal_gap 0.5)
			(thermal_bridge_width 0.5)
			(island_removal_mode 0)
		)
		(polygon
			(pts
				(arc
					(start 128.069594 -228.284532)
					(mid 127.439674 -228.284532)
					(end 128.069594 -228.284532)
				)
			)
		)
	)
	(zone
		(layers "B.Cu" "In4.Cu" "In6.Cu" "In11.Cu" "In13.Cu" "In15.Cu")
		(hatch none 0.5)
		(connect_pads
			(clearance 0)
		)
		(min_thickness 0.25)
		(keepout
			(tracks not_allowed)
			(vias allowed)
			(pads allowed)
			(copperpour not_allowed)
			(footprints allowed)
		)
		(placement
			(enabled no)
			(sheetname "")
		)
		(fill yes
			(thermal_gap 0.5)
			(thermal_bridge_width 0.5)
			(island_removal_mode 0)
		)
		(polygon
			(pts
				(arc
					(start 179.850034 -210.935316)
					(mid 179.182014 -210.935316)
					(end 179.850034 -210.935316)
				)
			)
		)
	)
	(zone
		(layers "B.Cu" "In4.Cu" "In6.Cu" "In11.Cu" "In13.Cu" "In15.Cu")
		(hatch none 0.5)
		(connect_pads
			(clearance 0)
		)
		(min_thickness 0.25)
		(keepout
			(tracks not_allowed)
			(vias allowed)
			(pads allowed)
			(copperpour not_allowed)
			(footprints allowed)
		)
		(placement
			(enabled no)
			(sheetname "")
		)
		(fill yes
			(thermal_gap 0.5)
			(thermal_bridge_width 0.5)
			(island_removal_mode 0)
		)
		(polygon
			(pts
				(arc
					(start 292.614096 -267.885164)
					(mid 291.946076 -267.885164)
					(end 292.614096 -267.885164)
				)
			)
		)
	)
	(zone
		(layers "B.Cu" "In4.Cu" "In6.Cu" "In11.Cu" "In13.Cu" "In15.Cu")
		(hatch none 0.5)
		(connect_pads
			(clearance 0)
		)
		(min_thickness 0.25)
		(keepout
			(tracks not_allowed)
			(vias allowed)
			(pads allowed)
			(copperpour not_allowed)
			(footprints allowed)
		)
		(placement
			(enabled no)
			(sheetname "")
		)
		(fill yes
			(thermal_gap 0.5)
			(thermal_bridge_width 0.5)
			(island_removal_mode 0)
		)
		(polygon
			(pts
				(arc
					(start 288.514028 -288.285174)
					(mid 287.846008 -288.285174)
					(end 288.514028 -288.285174)
				)
			)
		)
	)
	(zone
		(layers "B.Cu" "In4.Cu" "In6.Cu" "In11.Cu" "In13.Cu" "In15.Cu")
		(hatch none 0.5)
		(connect_pads
			(clearance 0)
		)
		(min_thickness 0.25)
		(keepout
			(tracks not_allowed)
			(vias allowed)
			(pads allowed)
			(copperpour not_allowed)
			(footprints allowed)
		)
		(placement
			(enabled no)
			(sheetname "")
		)
		(fill yes
			(thermal_gap 0.5)
			(thermal_bridge_width 0.5)
			(island_removal_mode 0)
		)
		(polygon
			(pts
				(arc
					(start 427.790102 -291.684964)
					(mid 427.122082 -291.684964)
					(end 427.790102 -291.684964)
				)
			)
		)
	)
	(zone
		(layers "B.Cu" "In4.Cu" "In6.Cu" "In11.Cu" "In13.Cu" "In15.Cu")
		(hatch none 0.5)
		(connect_pads
			(clearance 0)
		)
		(min_thickness 0.25)
		(keepout
			(tracks not_allowed)
			(vias allowed)
			(pads allowed)
			(copperpour not_allowed)
			(footprints allowed)
		)
		(placement
			(enabled no)
			(sheetname "")
		)
		(fill yes
			(thermal_gap 0.5)
			(thermal_bridge_width 0.5)
			(island_removal_mode 0)
		)
		(polygon
			(pts
				(arc
					(start 179.850034 -239.835436)
					(mid 179.182014 -239.835436)
					(end 179.850034 -239.835436)
				)
			)
		)
	)
	(zone
		(layers "B.Cu" "In4.Cu" "In6.Cu" "In11.Cu" "In13.Cu" "In15.Cu")
		(hatch none 0.5)
		(connect_pads
			(clearance 0)
		)
		(min_thickness 0.25)
		(keepout
			(tracks not_allowed)
			(vias allowed)
			(pads allowed)
			(copperpour not_allowed)
			(footprints allowed)
		)
		(placement
			(enabled no)
			(sheetname "")
		)
		(fill yes
			(thermal_gap 0.5)
			(thermal_bridge_width 0.5)
			(island_removal_mode 0)
		)
		(polygon
			(pts
				(arc
					(start 95.005906 -264.366248)
					(mid 94.375986 -264.366248)
					(end 95.005906 -264.366248)
				)
			)
		)
	)
	(zone
		(layers "B.Cu" "In4.Cu" "In6.Cu" "In11.Cu" "In13.Cu" "In15.Cu")
		(hatch none 0.5)
		(connect_pads
			(clearance 0)
		)
		(min_thickness 0.25)
		(keepout
			(tracks not_allowed)
			(vias allowed)
			(pads allowed)
			(copperpour not_allowed)
			(footprints allowed)
		)
		(placement
			(enabled no)
			(sheetname "")
		)
		(fill yes
			(thermal_gap 0.5)
			(thermal_bridge_width 0.5)
			(island_removal_mode 0)
		)
		(polygon
			(pts
				(arc
					(start 103.936038 -292.716204)
					(mid 103.306118 -292.716204)
					(end 103.936038 -292.716204)
				)
			)
		)
	)
	(zone
		(layers "B.Cu" "In4.Cu" "In6.Cu" "In11.Cu" "In13.Cu" "In15.Cu")
		(hatch none 0.5)
		(connect_pads
			(clearance 0)
		)
		(min_thickness 0.25)
		(keepout
			(tracks not_allowed)
			(vias allowed)
			(pads allowed)
			(copperpour not_allowed)
			(footprints allowed)
		)
		(placement
			(enabled no)
			(sheetname "")
		)
		(fill yes
			(thermal_gap 0.5)
			(thermal_bridge_width 0.5)
			(island_removal_mode 0)
		)
		(polygon
			(pts
				(arc
					(start 128.539748 -240.434368)
					(mid 127.909828 -240.434368)
					(end 128.539748 -240.434368)
				)
			)
		)
	)
	(zone
		(layers "B.Cu" "In4.Cu" "In6.Cu" "In11.Cu" "In13.Cu" "In15.Cu")
		(hatch none 0.5)
		(connect_pads
			(clearance 0)
		)
		(min_thickness 0.25)
		(keepout
			(tracks not_allowed)
			(vias allowed)
			(pads allowed)
			(copperpour not_allowed)
			(footprints allowed)
		)
		(placement
			(enabled no)
			(sheetname "")
		)
		(fill yes
			(thermal_gap 0.5)
			(thermal_bridge_width 0.5)
			(island_removal_mode 0)
		)
		(polygon
			(pts
				(arc
					(start 373.189754 -229.904036)
					(mid 372.559834 -229.904036)
					(end 373.189754 -229.904036)
				)
			)
		)
	)
	(zone
		(layers "B.Cu" "In4.Cu" "In6.Cu" "In11.Cu" "In13.Cu" "In15.Cu")
		(hatch none 0.5)
		(connect_pads
			(clearance 0)
		)
		(min_thickness 0.25)
		(keepout
			(tracks not_allowed)
			(vias allowed)
			(pads allowed)
			(copperpour not_allowed)
			(footprints allowed)
		)
		(placement
			(enabled no)
			(sheetname "")
		)
		(fill yes
			(thermal_gap 0.5)
			(thermal_bridge_width 0.5)
			(island_removal_mode 0)
		)
		(polygon
			(pts
				(arc
					(start 377.719844 -278.946102)
					(mid 377.089924 -278.946102)
					(end 377.719844 -278.946102)
				)
			)
		)
	)
	(zone
		(layers "B.Cu" "In4.Cu" "In6.Cu" "In11.Cu" "In13.Cu" "In15.Cu")
		(hatch none 0.5)
		(connect_pads
			(clearance 0)
		)
		(min_thickness 0.25)
		(keepout
			(tracks not_allowed)
			(vias allowed)
			(pads allowed)
			(copperpour not_allowed)
			(footprints allowed)
		)
		(placement
			(enabled no)
			(sheetname "")
		)
		(fill yes
			(thermal_gap 0.5)
			(thermal_bridge_width 0.5)
			(island_removal_mode 0)
		)
		(polygon
			(pts
				(arc
					(start 288.514028 -297.635168)
					(mid 287.846008 -297.635168)
					(end 288.514028 -297.635168)
				)
			)
		)
	)
	(zone
		(layers "B.Cu" "In4.Cu" "In6.Cu" "In11.Cu" "In13.Cu" "In15.Cu")
		(hatch none 0.5)
		(connect_pads
			(clearance 0)
		)
		(min_thickness 0.25)
		(keepout
			(tracks not_allowed)
			(vias allowed)
			(pads allowed)
			(copperpour not_allowed)
			(footprints allowed)
		)
		(placement
			(enabled no)
			(sheetname "")
		)
		(fill yes
			(thermal_gap 0.5)
			(thermal_bridge_width 0.5)
			(island_removal_mode 0)
		)
		(polygon
			(pts
				(arc
					(start 183.950102 -266.185396)
					(mid 183.282082 -266.185396)
					(end 183.950102 -266.185396)
				)
			)
		)
	)
	(zone
		(layers "B.Cu" "In4.Cu" "In6.Cu" "In11.Cu" "In13.Cu" "In15.Cu")
		(hatch none 0.5)
		(connect_pads
			(clearance 0)
		)
		(min_thickness 0.25)
		(keepout
			(tracks not_allowed)
			(vias allowed)
			(pads allowed)
			(copperpour not_allowed)
			(footprints allowed)
		)
		(placement
			(enabled no)
			(sheetname "")
		)
		(fill yes
			(thermal_gap 0.5)
			(thermal_bridge_width 0.5)
			(island_removal_mode 0)
		)
		(polygon
			(pts
				(arc
					(start 344.356182 -286.236156)
					(mid 343.726262 -286.236156)
					(end 344.356182 -286.236156)
				)
			)
		)
	)
	(zone
		(layers "B.Cu" "In4.Cu" "In6.Cu" "In11.Cu" "In13.Cu" "In15.Cu")
		(hatch none 0.5)
		(connect_pads
			(clearance 0)
		)
		(min_thickness 0.25)
		(keepout
			(tracks not_allowed)
			(vias allowed)
			(pads allowed)
			(copperpour not_allowed)
			(footprints allowed)
		)
		(placement
			(enabled no)
			(sheetname "")
		)
		(fill yes
			(thermal_gap 0.5)
			(thermal_bridge_width 0.5)
			(island_removal_mode 0)
		)
		(polygon
			(pts
				(arc
					(start 292.614096 -214.335106)
					(mid 291.946076 -214.335106)
					(end 292.614096 -214.335106)
				)
			)
		)
	)
	(zone
		(layers "B.Cu" "In4.Cu" "In6.Cu" "In11.Cu" "In13.Cu" "In15.Cu")
		(hatch none 0.5)
		(connect_pads
			(clearance 0)
		)
		(min_thickness 0.25)
		(keepout
			(tracks not_allowed)
			(vias allowed)
			(pads allowed)
			(copperpour not_allowed)
			(footprints allowed)
		)
		(placement
			(enabled no)
			(sheetname "")
		)
		(fill yes
			(thermal_gap 0.5)
			(thermal_bridge_width 0.5)
			(island_removal_mode 0)
		)
		(polygon
			(pts
				(arc
					(start 376.30989 -279.756108)
					(mid 375.67997 -279.756108)
					(end 376.30989 -279.756108)
				)
			)
		)
	)
	(zone
		(layers "B.Cu" "In4.Cu" "In6.Cu" "In11.Cu" "In13.Cu" "In15.Cu")
		(hatch none 0.5)
		(connect_pads
			(clearance 0)
		)
		(min_thickness 0.25)
		(keepout
			(tracks not_allowed)
			(vias allowed)
			(pads allowed)
			(copperpour not_allowed)
			(footprints allowed)
		)
		(placement
			(enabled no)
			(sheetname "")
		)
		(fill yes
			(thermal_gap 0.5)
			(thermal_bridge_width 0.5)
			(island_removal_mode 0)
		)
		(polygon
			(pts
				(arc
					(start 431.89017 -210.085178)
					(mid 431.22215 -210.085178)
					(end 431.89017 -210.085178)
				)
			)
		)
	)
	(zone
		(layers "B.Cu" "In4.Cu" "In6.Cu" "In11.Cu" "In13.Cu" "In15.Cu")
		(hatch none 0.5)
		(connect_pads
			(clearance 0)
		)
		(min_thickness 0.25)
		(keepout
			(tracks not_allowed)
			(vias allowed)
			(pads allowed)
			(copperpour not_allowed)
			(footprints allowed)
		)
		(placement
			(enabled no)
			(sheetname "")
		)
		(fill yes
			(thermal_gap 0.5)
			(thermal_bridge_width 0.5)
			(island_removal_mode 0)
		)
		(polygon
			(pts
				(arc
					(start 129.949702 -233.144314)
					(mid 129.319782 -233.144314)
					(end 129.949702 -233.144314)
				)
			)
		)
	)
	(zone
		(layers "B.Cu" "In4.Cu" "In6.Cu" "In11.Cu" "In13.Cu" "In15.Cu")
		(hatch none 0.5)
		(connect_pads
			(clearance 0)
		)
		(min_thickness 0.25)
		(keepout
			(tracks not_allowed)
			(vias allowed)
			(pads allowed)
			(copperpour not_allowed)
			(footprints allowed)
		)
		(placement
			(enabled no)
			(sheetname "")
		)
		(fill yes
			(thermal_gap 0.5)
			(thermal_bridge_width 0.5)
			(island_removal_mode 0)
		)
		(polygon
			(pts
				(arc
					(start 94.705932 -238.814356)
					(mid 94.076012 -238.814356)
					(end 94.705932 -238.814356)
				)
			)
		)
	)
	(zone
		(layers "B.Cu" "In4.Cu" "In6.Cu" "In11.Cu" "In13.Cu" "In15.Cu")
		(hatch none 0.5)
		(connect_pads
			(clearance 0)
		)
		(min_thickness 0.25)
		(keepout
			(tracks not_allowed)
			(vias allowed)
			(pads allowed)
			(copperpour not_allowed)
			(footprints allowed)
		)
		(placement
			(enabled no)
			(sheetname "")
		)
		(fill yes
			(thermal_gap 0.5)
			(thermal_bridge_width 0.5)
			(island_removal_mode 0)
		)
		(polygon
			(pts
				(arc
					(start 44.674028 -287.43529)
					(mid 44.006008 -287.43529)
					(end 44.674028 -287.43529)
				)
			)
		)
	)
	(zone
		(layers "B.Cu" "In4.Cu" "In6.Cu" "In11.Cu" "In13.Cu" "In15.Cu")
		(hatch none 0.5)
		(connect_pads
			(clearance 0)
		)
		(min_thickness 0.25)
		(keepout
			(tracks not_allowed)
			(vias allowed)
			(pads allowed)
			(copperpour not_allowed)
			(footprints allowed)
		)
		(placement
			(enabled no)
			(sheetname "")
		)
		(fill yes
			(thermal_gap 0.5)
			(thermal_bridge_width 0.5)
			(island_removal_mode 0)
		)
		(polygon
			(pts
				(arc
					(start 377.41987 -248.534174)
					(mid 376.78995 -248.534174)
					(end 377.41987 -248.534174)
				)
			)
		)
	)
	(zone
		(layers "B.Cu" "In4.Cu" "In6.Cu" "In11.Cu" "In13.Cu" "In15.Cu")
		(hatch none 0.5)
		(connect_pads
			(clearance 0)
		)
		(min_thickness 0.25)
		(keepout
			(tracks not_allowed)
			(vias allowed)
			(pads allowed)
			(copperpour not_allowed)
			(footprints allowed)
		)
		(placement
			(enabled no)
			(sheetname "")
		)
		(fill yes
			(thermal_gap 0.5)
			(thermal_bridge_width 0.5)
			(island_removal_mode 0)
		)
		(polygon
			(pts
				(arc
					(start 94.236032 -247.724422)
					(mid 93.606112 -247.724422)
					(end 94.236032 -247.724422)
				)
			)
		)
	)
	(zone
		(layers "B.Cu" "In4.Cu" "In6.Cu" "In11.Cu" "In13.Cu" "In15.Cu")
		(hatch none 0.5)
		(connect_pads
			(clearance 0)
		)
		(min_thickness 0.25)
		(keepout
			(tracks not_allowed)
			(vias allowed)
			(pads allowed)
			(copperpour not_allowed)
			(footprints allowed)
		)
		(placement
			(enabled no)
			(sheetname "")
		)
		(fill yes
			(thermal_gap 0.5)
			(thermal_bridge_width 0.5)
			(island_removal_mode 0)
		)
		(polygon
			(pts
				(arc
					(start 95.94596 -287.046162)
					(mid 95.31604 -287.046162)
					(end 95.94596 -287.046162)
				)
			)
		)
	)
	(zone
		(layers "B.Cu" "In4.Cu" "In6.Cu" "In11.Cu" "In13.Cu" "In15.Cu")
		(hatch none 0.5)
		(connect_pads
			(clearance 0)
		)
		(min_thickness 0.25)
		(keepout
			(tracks not_allowed)
			(vias allowed)
			(pads allowed)
			(copperpour not_allowed)
			(footprints allowed)
		)
		(placement
			(enabled no)
			(sheetname "")
		)
		(fill yes
			(thermal_gap 0.5)
			(thermal_bridge_width 0.5)
			(island_removal_mode 0)
		)
		(polygon
			(pts
				(arc
					(start 40.57396 -215.185244)
					(mid 39.90594 -215.185244)
					(end 40.57396 -215.185244)
				)
			)
		)
	)
	(zone
		(layers "B.Cu" "In4.Cu" "In6.Cu" "In11.Cu" "In13.Cu" "In15.Cu")
		(hatch none 0.5)
		(connect_pads
			(clearance 0)
		)
		(min_thickness 0.25)
		(keepout
			(tracks not_allowed)
			(vias allowed)
			(pads allowed)
			(copperpour not_allowed)
			(footprints allowed)
		)
		(placement
			(enabled no)
			(sheetname "")
		)
		(fill yes
			(thermal_gap 0.5)
			(thermal_bridge_width 0.5)
			(island_removal_mode 0)
		)
		(polygon
			(pts
				(arc
					(start 344.356182 -271.656048)
					(mid 343.726262 -271.656048)
					(end 344.356182 -271.656048)
				)
			)
		)
	)
	(zone
		(layers "B.Cu" "In4.Cu" "In6.Cu" "In11.Cu" "In13.Cu" "In15.Cu")
		(hatch none 0.5)
		(connect_pads
			(clearance 0)
		)
		(min_thickness 0.25)
		(keepout
			(tracks not_allowed)
			(vias allowed)
			(pads allowed)
			(copperpour not_allowed)
			(footprints allowed)
		)
		(placement
			(enabled no)
			(sheetname "")
		)
		(fill yes
			(thermal_gap 0.5)
			(thermal_bridge_width 0.5)
			(island_removal_mode 0)
		)
		(polygon
			(pts
				(arc
					(start 183.950102 -212.635338)
					(mid 183.282082 -212.635338)
					(end 183.950102 -212.635338)
				)
			)
		)
	)
	(zone
		(layers "B.Cu" "In4.Cu" "In6.Cu" "In11.Cu" "In13.Cu" "In15.Cu")
		(hatch none 0.5)
		(connect_pads
			(clearance 0)
		)
		(min_thickness 0.25)
		(keepout
			(tracks not_allowed)
			(vias allowed)
			(pads allowed)
			(copperpour not_allowed)
			(footprints allowed)
		)
		(placement
			(enabled no)
			(sheetname "")
		)
		(fill yes
			(thermal_gap 0.5)
			(thermal_bridge_width 0.5)
			(island_removal_mode 0)
		)
		(polygon
			(pts
				(arc
					(start 40.57396 -227.935282)
					(mid 39.90594 -227.935282)
					(end 40.57396 -227.935282)
				)
			)
		)
	)
	(zone
		(layers "B.Cu" "In4.Cu" "In6.Cu" "In11.Cu" "In13.Cu" "In15.Cu")
		(hatch none 0.5)
		(connect_pads
			(clearance 0)
		)
		(min_thickness 0.25)
		(keepout
			(tracks not_allowed)
			(vias allowed)
			(pads allowed)
			(copperpour not_allowed)
			(footprints allowed)
		)
		(placement
			(enabled no)
			(sheetname "")
		)
		(fill yes
			(thermal_gap 0.5)
			(thermal_bridge_width 0.5)
			(island_removal_mode 0)
		)
		(polygon
			(pts
				(arc
					(start 44.674028 -313.78525)
					(mid 44.006008 -313.78525)
					(end 44.674028 -313.78525)
				)
			)
		)
	)
	(zone
		(layers "B.Cu" "In4.Cu" "In6.Cu" "In11.Cu" "In13.Cu" "In15.Cu")
		(hatch none 0.5)
		(connect_pads
			(clearance 0)
		)
		(min_thickness 0.25)
		(keepout
			(tracks not_allowed)
			(vias allowed)
			(pads allowed)
			(copperpour not_allowed)
			(footprints allowed)
		)
		(placement
			(enabled no)
			(sheetname "")
		)
		(fill yes
			(thermal_gap 0.5)
			(thermal_bridge_width 0.5)
			(island_removal_mode 0)
		)
		(polygon
			(pts
				(arc
					(start 344.356182 -279.756108)
					(mid 343.726262 -279.756108)
					(end 344.356182 -279.756108)
				)
			)
		)
	)
	(zone
		(layers "B.Cu" "In4.Cu" "In6.Cu" "In11.Cu" "In13.Cu" "In15.Cu")
		(hatch none 0.5)
		(connect_pads
			(clearance 0)
		)
		(min_thickness 0.25)
		(keepout
			(tracks not_allowed)
			(vias allowed)
			(pads allowed)
			(copperpour not_allowed)
			(footprints allowed)
		)
		(placement
			(enabled no)
			(sheetname "")
		)
		(fill yes
			(thermal_gap 0.5)
			(thermal_bridge_width 0.5)
			(island_removal_mode 0)
		)
		(polygon
			(pts
				(arc
					(start 288.514028 -265.335004)
					(mid 287.846008 -265.335004)
					(end 288.514028 -265.335004)
				)
			)
		)
	)
	(zone
		(layers "B.Cu" "In4.Cu" "In6.Cu" "In11.Cu" "In13.Cu" "In15.Cu")
		(hatch none 0.5)
		(connect_pads
			(clearance 0)
		)
		(min_thickness 0.25)
		(keepout
			(tracks not_allowed)
			(vias allowed)
			(pads allowed)
			(copperpour not_allowed)
			(footprints allowed)
		)
		(placement
			(enabled no)
			(sheetname "")
		)
		(fill yes
			(thermal_gap 0.5)
			(thermal_bridge_width 0.5)
			(island_removal_mode 0)
		)
		(polygon
			(pts
				(arc
					(start 94.536006 -273.276314)
					(mid 93.906086 -273.276314)
					(end 94.536006 -273.276314)
				)
			)
		)
	)
	(zone
		(layers "B.Cu" "In4.Cu" "In6.Cu" "In11.Cu" "In13.Cu" "In15.Cu")
		(hatch none 0.5)
		(connect_pads
			(clearance 0)
		)
		(min_thickness 0.25)
		(keepout
			(tracks not_allowed)
			(vias allowed)
			(pads allowed)
			(copperpour not_allowed)
			(footprints allowed)
		)
		(placement
			(enabled no)
			(sheetname "")
		)
		(fill yes
			(thermal_gap 0.5)
			(thermal_bridge_width 0.5)
			(island_removal_mode 0)
		)
		(polygon
			(pts
				(arc
					(start 256.261108 -207.353408)
					(mid 255.593088 -207.353408)
					(end 256.261108 -207.353408)
				)
			)
		)
	)
	(zone
		(layers "B.Cu" "In4.Cu" "In6.Cu" "In11.Cu" "In13.Cu" "In15.Cu")
		(hatch none 0.5)
		(connect_pads
			(clearance 0)
		)
		(min_thickness 0.25)
		(keepout
			(tracks not_allowed)
			(vias allowed)
			(pads allowed)
			(copperpour not_allowed)
			(footprints allowed)
		)
		(placement
			(enabled no)
			(sheetname "")
		)
		(fill yes
			(thermal_gap 0.5)
			(thermal_bridge_width 0.5)
			(island_removal_mode 0)
		)
		(polygon
			(pts
				(arc
					(start 292.614096 -252.584966)
					(mid 291.946076 -252.584966)
					(end 292.614096 -252.584966)
				)
			)
		)
	)
	(zone
		(layers "B.Cu" "In4.Cu" "In6.Cu" "In11.Cu" "In13.Cu" "In15.Cu")
		(hatch none 0.5)
		(connect_pads
			(clearance 0)
		)
		(min_thickness 0.25)
		(keepout
			(tracks not_allowed)
			(vias allowed)
			(pads allowed)
			(copperpour not_allowed)
			(footprints allowed)
		)
		(placement
			(enabled no)
			(sheetname "")
		)
		(fill yes
			(thermal_gap 0.5)
			(thermal_bridge_width 0.5)
			(island_removal_mode 0)
		)
		(polygon
			(pts
				(arc
					(start 288.514028 -207.535018)
					(mid 287.846008 -207.535018)
					(end 288.514028 -207.535018)
				)
			)
		)
	)
	(zone
		(layers "B.Cu" "In4.Cu" "In6.Cu" "In11.Cu" "In13.Cu" "In15.Cu")
		(hatch none 0.5)
		(connect_pads
			(clearance 0)
		)
		(min_thickness 0.25)
		(keepout
			(tracks not_allowed)
			(vias allowed)
			(pads allowed)
			(copperpour not_allowed)
			(footprints allowed)
		)
		(placement
			(enabled no)
			(sheetname "")
		)
		(fill yes
			(thermal_gap 0.5)
			(thermal_bridge_width 0.5)
			(island_removal_mode 0)
		)
		(polygon
			(pts
				(arc
					(start 40.57396 -289.98545)
					(mid 39.90594 -289.98545)
					(end 40.57396 -289.98545)
				)
			)
		)
	)
	(zone
		(layers "B.Cu" "In4.Cu" "In6.Cu" "In11.Cu" "In13.Cu" "In15.Cu")
		(hatch none 0.5)
		(connect_pads
			(clearance 0)
		)
		(min_thickness 0.25)
		(keepout
			(tracks not_allowed)
			(vias allowed)
			(pads allowed)
			(copperpour not_allowed)
			(footprints allowed)
		)
		(placement
			(enabled no)
			(sheetname "")
		)
		(fill yes
			(thermal_gap 0.5)
			(thermal_bridge_width 0.5)
			(island_removal_mode 0)
		)
		(polygon
			(pts
				(arc
					(start 288.514028 -227.935028)
					(mid 287.846008 -227.935028)
					(end 288.514028 -227.935028)
				)
			)
		)
	)
	(zone
		(layers "B.Cu" "In4.Cu" "In6.Cu" "In11.Cu" "In13.Cu" "In15.Cu")
		(hatch none 0.5)
		(connect_pads
			(clearance 0)
		)
		(min_thickness 0.25)
		(keepout
			(tracks not_allowed)
			(vias allowed)
			(pads allowed)
			(copperpour not_allowed)
			(footprints allowed)
		)
		(placement
			(enabled no)
			(sheetname "")
		)
		(fill yes
			(thermal_gap 0.5)
			(thermal_bridge_width 0.5)
			(island_removal_mode 0)
		)
		(polygon
			(pts
				(arc
					(start 431.89017 -250.884944)
					(mid 431.22215 -250.884944)
					(end 431.89017 -250.884944)
				)
			)
		)
	)
	(zone
		(layers "B.Cu" "In4.Cu" "In6.Cu" "In11.Cu" "In13.Cu" "In15.Cu")
		(hatch none 0.5)
		(connect_pads
			(clearance 0)
		)
		(min_thickness 0.25)
		(keepout
			(tracks not_allowed)
			(vias allowed)
			(pads allowed)
			(copperpour not_allowed)
			(footprints allowed)
		)
		(placement
			(enabled no)
			(sheetname "")
		)
		(fill yes
			(thermal_gap 0.5)
			(thermal_bridge_width 0.5)
			(island_removal_mode 0)
		)
		(polygon
			(pts
				(arc
					(start 346.236036 -294.335962)
					(mid 345.606116 -294.335962)
					(end 346.236036 -294.335962)
				)
			)
		)
	)
	(zone
		(layers "B.Cu" "In4.Cu" "In6.Cu" "In11.Cu" "In13.Cu" "In15.Cu")
		(hatch none 0.5)
		(connect_pads
			(clearance 0)
		)
		(min_thickness 0.25)
		(keepout
			(tracks not_allowed)
			(vias allowed)
			(pads allowed)
			(copperpour not_allowed)
			(footprints allowed)
		)
		(placement
			(enabled no)
			(sheetname "")
		)
		(fill yes
			(thermal_gap 0.5)
			(thermal_bridge_width 0.5)
			(island_removal_mode 0)
		)
		(polygon
			(pts
				(arc
					(start 288.514028 -254.284988)
					(mid 287.846008 -254.284988)
					(end 288.514028 -254.284988)
				)
			)
		)
	)
	(zone
		(layers "B.Cu" "In4.Cu" "In6.Cu" "In11.Cu" "In13.Cu" "In15.Cu")
		(hatch none 0.5)
		(connect_pads
			(clearance 0)
		)
		(min_thickness 0.25)
		(keepout
			(tracks not_allowed)
			(vias allowed)
			(pads allowed)
			(copperpour not_allowed)
			(footprints allowed)
		)
		(placement
			(enabled no)
			(sheetname "")
		)
		(fill yes
			(thermal_gap 0.5)
			(thermal_bridge_width 0.5)
			(island_removal_mode 0)
		)
		(polygon
			(pts
				(arc
					(start 129.479802 -253.394464)
					(mid 128.849882 -253.394464)
					(end 129.479802 -253.394464)
				)
			)
		)
	)
	(zone
		(layers "B.Cu" "In4.Cu" "In6.Cu" "In11.Cu" "In13.Cu" "In15.Cu")
		(hatch none 0.5)
		(connect_pads
			(clearance 0)
		)
		(min_thickness 0.25)
		(keepout
			(tracks not_allowed)
			(vias allowed)
			(pads allowed)
			(copperpour not_allowed)
			(footprints allowed)
		)
		(placement
			(enabled no)
			(sheetname "")
		)
		(fill yes
			(thermal_gap 0.5)
			(thermal_bridge_width 0.5)
			(island_removal_mode 0)
		)
		(polygon
			(pts
				(arc
					(start 129.949702 -225.044508)
					(mid 129.319782 -225.044508)
					(end 129.949702 -225.044508)
				)
			)
		)
	)
	(zone
		(layers "B.Cu" "In4.Cu" "In6.Cu" "In11.Cu" "In13.Cu" "In15.Cu")
		(hatch none 0.5)
		(connect_pads
			(clearance 0)
		)
		(min_thickness 0.25)
		(keepout
			(tracks not_allowed)
			(vias allowed)
			(pads allowed)
			(copperpour not_allowed)
			(footprints allowed)
		)
		(placement
			(enabled no)
			(sheetname "")
		)
		(fill yes
			(thermal_gap 0.5)
			(thermal_bridge_width 0.5)
			(island_removal_mode 0)
		)
		(polygon
			(pts
				(arc
					(start 94.705932 -230.71455)
					(mid 94.076012 -230.71455)
					(end 94.705932 -230.71455)
				)
			)
		)
	)
	(zone
		(layers "B.Cu" "In4.Cu" "In6.Cu" "In11.Cu" "In13.Cu" "In15.Cu")
		(hatch none 0.5)
		(connect_pads
			(clearance 0)
		)
		(min_thickness 0.25)
		(keepout
			(tracks not_allowed)
			(vias allowed)
			(pads allowed)
			(copperpour not_allowed)
			(footprints allowed)
		)
		(placement
			(enabled no)
			(sheetname "")
		)
		(fill yes
			(thermal_gap 0.5)
			(thermal_bridge_width 0.5)
			(island_removal_mode 0)
		)
		(polygon
			(pts
				(arc
					(start 128.839722 -287.046162)
					(mid 128.209802 -287.046162)
					(end 128.839722 -287.046162)
				)
			)
		)
	)
	(zone
		(layers "B.Cu" "In4.Cu" "In6.Cu" "In11.Cu" "In13.Cu" "In15.Cu")
		(hatch none 0.5)
		(connect_pads
			(clearance 0)
		)
		(min_thickness 0.25)
		(keepout
			(tracks not_allowed)
			(vias allowed)
			(pads allowed)
			(copperpour not_allowed)
			(footprints allowed)
		)
		(placement
			(enabled no)
			(sheetname "")
		)
		(fill yes
			(thermal_gap 0.5)
			(thermal_bridge_width 0.5)
			(island_removal_mode 0)
		)
		(polygon
			(pts
				(arc
					(start 427.790102 -305.28514)
					(mid 427.122082 -305.28514)
					(end 427.790102 -305.28514)
				)
			)
		)
	)
	(zone
		(layers "B.Cu" "In4.Cu" "In6.Cu" "In11.Cu" "In13.Cu" "In15.Cu")
		(hatch none 0.5)
		(connect_pads
			(clearance 0)
		)
		(min_thickness 0.25)
		(keepout
			(tracks not_allowed)
			(vias allowed)
			(pads allowed)
			(copperpour not_allowed)
			(footprints allowed)
		)
		(placement
			(enabled no)
			(sheetname "")
		)
		(fill yes
			(thermal_gap 0.5)
			(thermal_bridge_width 0.5)
			(island_removal_mode 0)
		)
		(polygon
			(pts
				(arc
					(start 427.790102 -285.735014)
					(mid 427.122082 -285.735014)
					(end 427.790102 -285.735014)
				)
			)
		)
	)
	(zone
		(layers "B.Cu" "In4.Cu" "In6.Cu" "In11.Cu" "In13.Cu" "In15.Cu")
		(hatch none 0.5)
		(connect_pads
			(clearance 0)
		)
		(min_thickness 0.25)
		(keepout
			(tracks not_allowed)
			(vias allowed)
			(pads allowed)
			(copperpour not_allowed)
			(footprints allowed)
		)
		(placement
			(enabled no)
			(sheetname "")
		)
		(fill yes
			(thermal_gap 0.5)
			(thermal_bridge_width 0.5)
			(island_removal_mode 0)
		)
		(polygon
			(pts
				(arc
					(start 129.949702 -255.824482)
					(mid 129.319782 -255.824482)
					(end 129.949702 -255.824482)
				)
			)
		)
	)
	(zone
		(layers "B.Cu" "In4.Cu" "In6.Cu" "In11.Cu" "In13.Cu" "In15.Cu")
		(hatch none 0.5)
		(connect_pads
			(clearance 0)
		)
		(min_thickness 0.25)
		(keepout
			(tracks not_allowed)
			(vias allowed)
			(pads allowed)
			(copperpour not_allowed)
			(footprints allowed)
		)
		(placement
			(enabled no)
			(sheetname "")
		)
		(fill yes
			(thermal_gap 0.5)
			(thermal_bridge_width 0.5)
			(island_removal_mode 0)
		)
		(polygon
			(pts
				(arc
					(start 128.839722 -285.426404)
					(mid 128.209802 -285.426404)
					(end 128.839722 -285.426404)
				)
			)
		)
	)
	(zone
		(layers "B.Cu" "In4.Cu" "In6.Cu" "In11.Cu" "In13.Cu" "In15.Cu")
		(hatch none 0.5)
		(connect_pads
			(clearance 0)
		)
		(min_thickness 0.25)
		(keepout
			(tracks not_allowed)
			(vias allowed)
			(pads allowed)
			(copperpour not_allowed)
			(footprints allowed)
		)
		(placement
			(enabled no)
			(sheetname "")
		)
		(fill yes
			(thermal_gap 0.5)
			(thermal_bridge_width 0.5)
			(island_removal_mode 0)
		)
		(polygon
			(pts
				(arc
					(start 183.950102 -220.28531)
					(mid 183.282082 -220.28531)
					(end 183.950102 -220.28531)
				)
			)
		)
	)
	(zone
		(layers "B.Cu" "In4.Cu" "In6.Cu" "In11.Cu" "In13.Cu" "In15.Cu")
		(hatch none 0.5)
		(connect_pads
			(clearance 0)
		)
		(min_thickness 0.25)
		(keepout
			(tracks not_allowed)
			(vias allowed)
			(pads allowed)
			(copperpour not_allowed)
			(footprints allowed)
		)
		(placement
			(enabled no)
			(sheetname "")
		)
		(fill yes
			(thermal_gap 0.5)
			(thermal_bridge_width 0.5)
			(island_removal_mode 0)
		)
		(polygon
			(pts
				(arc
					(start 431.89017 -249.185176)
					(mid 431.22215 -249.185176)
					(end 431.89017 -249.185176)
				)
			)
		)
	)
	(zone
		(layers "B.Cu" "In4.Cu" "In6.Cu" "In11.Cu" "In13.Cu" "In15.Cu")
		(hatch none 0.5)
		(connect_pads
			(clearance 0)
		)
		(min_thickness 0.25)
		(keepout
			(tracks not_allowed)
			(vias allowed)
			(pads allowed)
			(copperpour not_allowed)
			(footprints allowed)
		)
		(placement
			(enabled no)
			(sheetname "")
		)
		(fill yes
			(thermal_gap 0.5)
			(thermal_bridge_width 0.5)
			(island_removal_mode 0)
		)
		(polygon
			(pts
				(arc
					(start 364.729776 -226.664266)
					(mid 364.099856 -226.664266)
					(end 364.729776 -226.664266)
				)
			)
		)
	)
	(zone
		(layers "B.Cu" "In4.Cu" "In6.Cu" "In11.Cu" "In13.Cu" "In15.Cu")
		(hatch none 0.5)
		(connect_pads
			(clearance 0)
		)
		(min_thickness 0.25)
		(keepout
			(tracks not_allowed)
			(vias allowed)
			(pads allowed)
			(copperpour not_allowed)
			(footprints allowed)
		)
		(placement
			(enabled no)
			(sheetname "")
		)
		(fill yes
			(thermal_gap 0.5)
			(thermal_bridge_width 0.5)
			(island_removal_mode 0)
		)
		(polygon
			(pts
				(arc
					(start 95.645986 -225.854514)
					(mid 95.016066 -225.854514)
					(end 95.645986 -225.854514)
				)
			)
		)
	)
	(zone
		(layers "B.Cu" "In4.Cu" "In6.Cu" "In11.Cu" "In13.Cu" "In15.Cu")
		(hatch none 0.5)
		(connect_pads
			(clearance 0)
		)
		(min_thickness 0.25)
		(keepout
			(tracks not_allowed)
			(vias allowed)
			(pads allowed)
			(copperpour not_allowed)
			(footprints allowed)
		)
		(placement
			(enabled no)
			(sheetname "")
		)
		(fill yes
			(thermal_gap 0.5)
			(thermal_bridge_width 0.5)
			(island_removal_mode 0)
		)
		(polygon
			(pts
				(arc
					(start 128.369822 -291.096192)
					(mid 127.739902 -291.096192)
					(end 128.369822 -291.096192)
				)
			)
		)
	)
	(zone
		(layers "B.Cu" "In4.Cu" "In6.Cu" "In11.Cu" "In13.Cu" "In15.Cu")
		(hatch none 0.5)
		(connect_pads
			(clearance 0)
		)
		(min_thickness 0.25)
		(keepout
			(tracks not_allowed)
			(vias allowed)
			(pads allowed)
			(copperpour not_allowed)
			(footprints allowed)
		)
		(placement
			(enabled no)
			(sheetname "")
		)
		(fill yes
			(thermal_gap 0.5)
			(thermal_bridge_width 0.5)
			(island_removal_mode 0)
		)
		(polygon
			(pts
				(arc
					(start 377.41987 -230.714296)
					(mid 376.78995 -230.714296)
					(end 377.41987 -230.714296)
				)
			)
		)
	)
	(zone
		(layers "B.Cu" "In4.Cu" "In6.Cu" "In11.Cu" "In13.Cu" "In15.Cu")
		(hatch none 0.5)
		(connect_pads
			(clearance 0)
		)
		(min_thickness 0.25)
		(keepout
			(tracks not_allowed)
			(vias allowed)
			(pads allowed)
			(copperpour not_allowed)
			(footprints allowed)
		)
		(placement
			(enabled no)
			(sheetname "")
		)
		(fill yes
			(thermal_gap 0.5)
			(thermal_bridge_width 0.5)
			(island_removal_mode 0)
		)
		(polygon
			(pts
				(arc
					(start 94.236032 -228.284532)
					(mid 93.606112 -228.284532)
					(end 94.236032 -228.284532)
				)
			)
		)
	)
	(zone
		(layers "B.Cu" "In4.Cu" "In6.Cu" "In11.Cu" "In13.Cu" "In15.Cu")
		(hatch none 0.5)
		(connect_pads
			(clearance 0)
		)
		(min_thickness 0.25)
		(keepout
			(tracks not_allowed)
			(vias allowed)
			(pads allowed)
			(copperpour not_allowed)
			(footprints allowed)
		)
		(placement
			(enabled no)
			(sheetname "")
		)
		(fill yes
			(thermal_gap 0.5)
			(thermal_bridge_width 0.5)
			(island_removal_mode 0)
		)
		(polygon
			(pts
				(arc
					(start 129.949702 -236.384338)
					(mid 129.319782 -236.384338)
					(end 129.949702 -236.384338)
				)
			)
		)
	)
	(zone
		(layers "B.Cu" "In4.Cu" "In6.Cu" "In11.Cu" "In13.Cu" "In15.Cu")
		(hatch none 0.5)
		(connect_pads
			(clearance 0)
		)
		(min_thickness 0.25)
		(keepout
			(tracks not_allowed)
			(vias allowed)
			(pads allowed)
			(copperpour not_allowed)
			(footprints allowed)
		)
		(placement
			(enabled no)
			(sheetname "")
		)
		(fill yes
			(thermal_gap 0.5)
			(thermal_bridge_width 0.5)
			(island_removal_mode 0)
		)
		(polygon
			(pts
				(arc
					(start 355.636068 -292.71595)
					(mid 355.006148 -292.71595)
					(end 355.636068 -292.71595)
				)
			)
		)
	)
	(zone
		(layers "B.Cu" "In4.Cu" "In6.Cu" "In11.Cu" "In13.Cu" "In15.Cu")
		(hatch none 0.5)
		(connect_pads
			(clearance 0)
		)
		(min_thickness 0.25)
		(keepout
			(tracks not_allowed)
			(vias allowed)
			(pads allowed)
			(copperpour not_allowed)
			(footprints allowed)
		)
		(placement
			(enabled no)
			(sheetname "")
		)
		(fill yes
			(thermal_gap 0.5)
			(thermal_bridge_width 0.5)
			(island_removal_mode 0)
		)
		(polygon
			(pts
				(arc
					(start 292.614096 -249.185176)
					(mid 291.946076 -249.185176)
					(end 292.614096 -249.185176)
				)
			)
		)
	)
	(zone
		(layers "B.Cu" "In4.Cu" "In6.Cu" "In11.Cu" "In13.Cu" "In15.Cu")
		(hatch none 0.5)
		(connect_pads
			(clearance 0)
		)
		(min_thickness 0.25)
		(keepout
			(tracks not_allowed)
			(vias allowed)
			(pads allowed)
			(copperpour not_allowed)
			(footprints allowed)
		)
		(placement
			(enabled no)
			(sheetname "")
		)
		(fill yes
			(thermal_gap 0.5)
			(thermal_bridge_width 0.5)
			(island_removal_mode 0)
		)
		(polygon
			(pts
				(arc
					(start 44.674028 -295.085262)
					(mid 44.006008 -295.085262)
					(end 44.674028 -295.085262)
				)
			)
		)
	)
	(zone
		(layers "B.Cu" "In4.Cu" "In6.Cu" "In11.Cu" "In13.Cu" "In15.Cu")
		(hatch none 0.5)
		(connect_pads
			(clearance 0)
		)
		(min_thickness 0.25)
		(keepout
			(tracks not_allowed)
			(vias allowed)
			(pads allowed)
			(copperpour not_allowed)
			(footprints allowed)
		)
		(placement
			(enabled no)
			(sheetname "")
		)
		(fill yes
			(thermal_gap 0.5)
			(thermal_bridge_width 0.5)
			(island_removal_mode 0)
		)
		(polygon
			(pts
				(arc
					(start 44.674028 -204.985366)
					(mid 44.006008 -204.985366)
					(end 44.674028 -204.985366)
				)
			)
		)
	)
	(zone
		(layers "B.Cu" "In4.Cu" "In6.Cu" "In11.Cu" "In13.Cu" "In15.Cu")
		(hatch none 0.5)
		(connect_pads
			(clearance 0)
		)
		(min_thickness 0.25)
		(keepout
			(tracks not_allowed)
			(vias allowed)
			(pads allowed)
			(copperpour not_allowed)
			(footprints allowed)
		)
		(placement
			(enabled no)
			(sheetname "")
		)
		(fill yes
			(thermal_gap 0.5)
			(thermal_bridge_width 0.5)
			(island_removal_mode 0)
		)
		(polygon
			(pts
				(arc
					(start 183.950102 -295.085262)
					(mid 183.282082 -295.085262)
					(end 183.950102 -295.085262)
				)
			)
		)
	)
	(zone
		(layers "B.Cu" "In4.Cu" "In6.Cu" "In11.Cu" "In13.Cu" "In15.Cu")
		(hatch none 0.5)
		(connect_pads
			(clearance 0)
		)
		(min_thickness 0.25)
		(keepout
			(tracks not_allowed)
			(vias allowed)
			(pads allowed)
			(copperpour not_allowed)
			(footprints allowed)
		)
		(placement
			(enabled no)
			(sheetname "")
		)
		(fill yes
			(thermal_gap 0.5)
			(thermal_bridge_width 0.5)
			(island_removal_mode 0)
		)
		(polygon
			(pts
				(arc
					(start 427.790102 -254.284988)
					(mid 427.122082 -254.284988)
					(end 427.790102 -254.284988)
				)
			)
		)
	)
	(zone
		(layers "B.Cu" "In4.Cu" "In6.Cu" "In11.Cu" "In13.Cu" "In15.Cu")
		(hatch none 0.5)
		(connect_pads
			(clearance 0)
		)
		(min_thickness 0.25)
		(keepout
			(tracks not_allowed)
			(vias allowed)
			(pads allowed)
			(copperpour not_allowed)
			(footprints allowed)
		)
		(placement
			(enabled no)
			(sheetname "")
		)
		(fill yes
			(thermal_gap 0.5)
			(thermal_bridge_width 0.5)
			(island_removal_mode 0)
		)
		(polygon
			(pts
				(arc
					(start 40.57396 -314.635388)
					(mid 39.90594 -314.635388)
					(end 40.57396 -314.635388)
				)
			)
		)
	)
	(zone
		(layers "B.Cu" "In4.Cu" "In6.Cu" "In11.Cu" "In13.Cu" "In15.Cu")
		(hatch none 0.5)
		(connect_pads
			(clearance 0)
		)
		(min_thickness 0.25)
		(keepout
			(tracks not_allowed)
			(vias allowed)
			(pads allowed)
			(copperpour not_allowed)
			(footprints allowed)
		)
		(placement
			(enabled no)
			(sheetname "")
		)
		(fill yes
			(thermal_gap 0.5)
			(thermal_bridge_width 0.5)
			(island_removal_mode 0)
		)
		(polygon
			(pts
				(arc
					(start 183.950102 -227.085398)
					(mid 183.282082 -227.085398)
					(end 183.950102 -227.085398)
				)
			)
		)
	)
	(zone
		(layers "B.Cu" "In4.Cu" "In6.Cu" "In11.Cu" "In13.Cu" "In15.Cu")
		(hatch none 0.5)
		(connect_pads
			(clearance 0)
		)
		(min_thickness 0.25)
		(keepout
			(tracks not_allowed)
			(vias allowed)
			(pads allowed)
			(copperpour not_allowed)
			(footprints allowed)
		)
		(placement
			(enabled no)
			(sheetname "")
		)
		(fill yes
			(thermal_gap 0.5)
			(thermal_bridge_width 0.5)
			(island_removal_mode 0)
		)
		(polygon
			(pts
				(arc
					(start 373.189754 -226.664266)
					(mid 372.559834 -226.664266)
					(end 373.189754 -226.664266)
				)
			)
		)
	)
	(zone
		(layers "B.Cu" "In4.Cu" "In6.Cu" "In11.Cu" "In13.Cu" "In15.Cu")
		(hatch none 0.5)
		(connect_pads
			(clearance 0)
		)
		(min_thickness 0.25)
		(keepout
			(tracks not_allowed)
			(vias allowed)
			(pads allowed)
			(copperpour not_allowed)
			(footprints allowed)
		)
		(placement
			(enabled no)
			(sheetname "")
		)
		(fill yes
			(thermal_gap 0.5)
			(thermal_bridge_width 0.5)
			(island_removal_mode 0)
		)
		(polygon
			(pts
				(arc
					(start 40.57396 -268.735302)
					(mid 39.90594 -268.735302)
					(end 40.57396 -268.735302)
				)
			)
		)
	)
	(zone
		(layers "B.Cu" "In4.Cu" "In6.Cu" "In11.Cu" "In13.Cu" "In15.Cu")
		(hatch none 0.5)
		(connect_pads
			(clearance 0)
		)
		(min_thickness 0.25)
		(keepout
			(tracks not_allowed)
			(vias allowed)
			(pads allowed)
			(copperpour not_allowed)
			(footprints allowed)
		)
		(placement
			(enabled no)
			(sheetname "")
		)
		(fill yes
			(thermal_gap 0.5)
			(thermal_bridge_width 0.5)
			(island_removal_mode 0)
		)
		(polygon
			(pts
				(arc
					(start 288.514028 -318.035178)
					(mid 287.846008 -318.035178)
					(end 288.514028 -318.035178)
				)
			)
		)
	)
	(zone
		(layers "B.Cu" "In4.Cu" "In6.Cu" "In11.Cu" "In13.Cu" "In15.Cu")
		(hatch none 0.5)
		(connect_pads
			(clearance 0)
		)
		(min_thickness 0.25)
		(keepout
			(tracks not_allowed)
			(vias allowed)
			(pads allowed)
			(copperpour not_allowed)
			(footprints allowed)
		)
		(placement
			(enabled no)
			(sheetname "")
		)
		(fill yes
			(thermal_gap 0.5)
			(thermal_bridge_width 0.5)
			(island_removal_mode 0)
		)
		(polygon
			(pts
				(arc
					(start 374.129808 -231.524048)
					(mid 373.499888 -231.524048)
					(end 374.129808 -231.524048)
				)
			)
		)
	)
	(zone
		(layers "B.Cu" "In4.Cu" "In6.Cu" "In11.Cu" "In13.Cu" "In15.Cu")
		(hatch none 0.5)
		(connect_pads
			(clearance 0)
		)
		(min_thickness 0.25)
		(keepout
			(tracks not_allowed)
			(vias allowed)
			(pads allowed)
			(copperpour not_allowed)
			(footprints allowed)
		)
		(placement
			(enabled no)
			(sheetname "")
		)
		(fill yes
			(thermal_gap 0.5)
			(thermal_bridge_width 0.5)
			(island_removal_mode 0)
		)
		(polygon
			(pts
				(arc
					(start 96.416114 -279.756362)
					(mid 95.786194 -279.756362)
					(end 96.416114 -279.756362)
				)
			)
		)
	)
	(zone
		(layers "B.Cu" "In4.Cu" "In6.Cu" "In11.Cu" "In13.Cu" "In15.Cu")
		(hatch none 0.5)
		(connect_pads
			(clearance 0)
		)
		(min_thickness 0.25)
		(keepout
			(tracks not_allowed)
			(vias allowed)
			(pads allowed)
			(copperpour not_allowed)
			(footprints allowed)
		)
		(placement
			(enabled no)
			(sheetname "")
		)
		(fill yes
			(thermal_gap 0.5)
			(thermal_bridge_width 0.5)
			(island_removal_mode 0)
		)
		(polygon
			(pts
				(arc
					(start 344.055954 -255.824228)
					(mid 343.426034 -255.824228)
					(end 344.055954 -255.824228)
				)
			)
		)
	)
	(zone
		(layers "B.Cu" "In4.Cu" "In6.Cu" "In11.Cu" "In13.Cu" "In15.Cu")
		(hatch none 0.5)
		(connect_pads
			(clearance 0)
		)
		(min_thickness 0.25)
		(keepout
			(tracks not_allowed)
			(vias allowed)
			(pads allowed)
			(copperpour not_allowed)
			(footprints allowed)
		)
		(placement
			(enabled no)
			(sheetname "")
		)
		(fill yes
			(thermal_gap 0.5)
			(thermal_bridge_width 0.5)
			(island_removal_mode 0)
		)
		(polygon
			(pts
				(arc
					(start 183.950102 -267.885418)
					(mid 183.282082 -267.885418)
					(end 183.950102 -267.885418)
				)
			)
		)
	)
	(zone
		(layers "B.Cu" "In4.Cu" "In6.Cu" "In11.Cu" "In13.Cu" "In15.Cu")
		(hatch none 0.5)
		(connect_pads
			(clearance 0)
		)
		(min_thickness 0.25)
		(keepout
			(tracks not_allowed)
			(vias allowed)
			(pads allowed)
			(copperpour not_allowed)
			(footprints allowed)
		)
		(placement
			(enabled no)
			(sheetname "")
		)
		(fill yes
			(thermal_gap 0.5)
			(thermal_bridge_width 0.5)
			(island_removal_mode 0)
		)
		(polygon
			(pts
				(arc
					(start 94.536006 -266.796266)
					(mid 93.906086 -266.796266)
					(end 94.536006 -266.796266)
				)
			)
		)
	)
	(zone
		(layers "B.Cu" "In4.Cu" "In6.Cu" "In11.Cu" "In13.Cu" "In15.Cu")
		(hatch none 0.5)
		(connect_pads
			(clearance 0)
		)
		(min_thickness 0.25)
		(keepout
			(tracks not_allowed)
			(vias allowed)
			(pads allowed)
			(copperpour not_allowed)
			(footprints allowed)
		)
		(placement
			(enabled no)
			(sheetname "")
		)
		(fill yes
			(thermal_gap 0.5)
			(thermal_bridge_width 0.5)
			(island_removal_mode 0)
		)
		(polygon
			(pts
				(arc
					(start 288.514028 -218.585034)
					(mid 287.846008 -218.585034)
					(end 288.514028 -218.585034)
				)
			)
		)
	)
	(zone
		(layers "B.Cu" "In4.Cu" "In6.Cu" "In11.Cu" "In13.Cu" "In15.Cu")
		(hatch none 0.5)
		(connect_pads
			(clearance 0)
		)
		(min_thickness 0.25)
		(keepout
			(tracks not_allowed)
			(vias allowed)
			(pads allowed)
			(copperpour not_allowed)
			(footprints allowed)
		)
		(placement
			(enabled no)
			(sheetname "")
		)
		(fill yes
			(thermal_gap 0.5)
			(thermal_bridge_width 0.5)
			(island_removal_mode 0)
		)
		(polygon
			(pts
				(arc
					(start 342.945974 -291.905944)
					(mid 342.316054 -291.905944)
					(end 342.945974 -291.905944)
				)
			)
		)
	)
	(zone
		(layers "B.Cu" "In4.Cu" "In6.Cu" "In11.Cu" "In13.Cu" "In15.Cu")
		(hatch none 0.5)
		(connect_pads
			(clearance 0)
		)
		(min_thickness 0.25)
		(keepout
			(tracks not_allowed)
			(vias allowed)
			(pads allowed)
			(copperpour not_allowed)
			(footprints allowed)
		)
		(placement
			(enabled no)
			(sheetname "")
		)
		(fill yes
			(thermal_gap 0.5)
			(thermal_bridge_width 0.5)
			(island_removal_mode 0)
		)
		(polygon
			(pts
				(arc
					(start 288.514028 -312.084974)
					(mid 287.846008 -312.084974)
					(end 288.514028 -312.084974)
				)
			)
		)
	)
	(zone
		(layers "B.Cu" "In4.Cu" "In6.Cu" "In11.Cu" "In13.Cu" "In15.Cu")
		(hatch none 0.5)
		(connect_pads
			(clearance 0)
		)
		(min_thickness 0.25)
		(keepout
			(tracks not_allowed)
			(vias allowed)
			(pads allowed)
			(copperpour not_allowed)
			(footprints allowed)
		)
		(placement
			(enabled no)
			(sheetname "")
		)
		(fill yes
			(thermal_gap 0.5)
			(thermal_bridge_width 0.5)
			(island_removal_mode 0)
		)
		(polygon
			(pts
				(arc
					(start 431.89017 -270.43507)
					(mid 431.22215 -270.43507)
					(end 431.89017 -270.43507)
				)
			)
		)
	)
	(zone
		(layers "B.Cu" "In4.Cu" "In6.Cu" "In11.Cu" "In13.Cu" "In15.Cu")
		(hatch none 0.5)
		(connect_pads
			(clearance 0)
		)
		(min_thickness 0.25)
		(keepout
			(tracks not_allowed)
			(vias allowed)
			(pads allowed)
			(copperpour not_allowed)
			(footprints allowed)
		)
		(placement
			(enabled no)
			(sheetname "")
		)
		(fill yes
			(thermal_gap 0.5)
			(thermal_bridge_width 0.5)
			(island_removal_mode 0)
		)
		(polygon
			(pts
				(arc
					(start 129.779776 -285.426404)
					(mid 129.149856 -285.426404)
					(end 129.779776 -285.426404)
				)
			)
		)
	)
	(zone
		(layers "B.Cu" "In4.Cu" "In6.Cu" "In11.Cu" "In13.Cu" "In15.Cu")
		(hatch none 0.5)
		(connect_pads
			(clearance 0)
		)
		(min_thickness 0.25)
		(keepout
			(tracks not_allowed)
			(vias allowed)
			(pads allowed)
			(copperpour not_allowed)
			(footprints allowed)
		)
		(placement
			(enabled no)
			(sheetname "")
		)
		(fill yes
			(thermal_gap 0.5)
			(thermal_bridge_width 0.5)
			(island_removal_mode 0)
		)
		(polygon
			(pts
				(arc
					(start 100.815902 -228.284532)
					(mid 100.185982 -228.284532)
					(end 100.815902 -228.284532)
				)
			)
		)
	)
	(zone
		(layers "B.Cu" "In4.Cu" "In6.Cu" "In11.Cu" "In13.Cu" "In15.Cu")
		(hatch none 0.5)
		(connect_pads
			(clearance 0)
		)
		(min_thickness 0.25)
		(keepout
			(tracks not_allowed)
			(vias allowed)
			(pads allowed)
			(copperpour not_allowed)
			(footprints allowed)
		)
		(placement
			(enabled no)
			(sheetname "")
		)
		(fill yes
			(thermal_gap 0.5)
			(thermal_bridge_width 0.5)
			(island_removal_mode 0)
		)
		(polygon
			(pts
				(arc
					(start 344.055954 -254.204216)
					(mid 343.426034 -254.204216)
					(end 344.055954 -254.204216)
				)
			)
		)
	)
	(zone
		(layers "B.Cu" "In4.Cu" "In6.Cu" "In11.Cu" "In13.Cu" "In15.Cu")
		(hatch none 0.5)
		(connect_pads
			(clearance 0)
		)
		(min_thickness 0.25)
		(keepout
			(tracks not_allowed)
			(vias allowed)
			(pads allowed)
			(copperpour not_allowed)
			(footprints allowed)
		)
		(placement
			(enabled no)
			(sheetname "")
		)
		(fill yes
			(thermal_gap 0.5)
			(thermal_bridge_width 0.5)
			(island_removal_mode 0)
		)
		(polygon
			(pts
				(arc
					(start 344.356182 -274.896072)
					(mid 343.726262 -274.896072)
					(end 344.356182 -274.896072)
				)
			)
		)
	)
	(zone
		(layers "B.Cu" "In4.Cu" "In6.Cu" "In11.Cu" "In13.Cu" "In15.Cu")
		(hatch none 0.5)
		(connect_pads
			(clearance 0)
		)
		(min_thickness 0.25)
		(keepout
			(tracks not_allowed)
			(vias allowed)
			(pads allowed)
			(copperpour not_allowed)
			(footprints allowed)
		)
		(placement
			(enabled no)
			(sheetname "")
		)
		(fill yes
			(thermal_gap 0.5)
			(thermal_bridge_width 0.5)
			(island_removal_mode 0)
		)
		(polygon
			(pts
				(arc
					(start 343.886028 -282.186126)
					(mid 343.256108 -282.186126)
					(end 343.886028 -282.186126)
				)
			)
		)
	)
	(zone
		(layers "B.Cu" "In4.Cu" "In6.Cu" "In11.Cu" "In13.Cu" "In15.Cu")
		(hatch none 0.5)
		(connect_pads
			(clearance 0)
		)
		(min_thickness 0.25)
		(keepout
			(tracks not_allowed)
			(vias allowed)
			(pads allowed)
			(copperpour not_allowed)
			(footprints allowed)
		)
		(placement
			(enabled no)
			(sheetname "")
		)
		(fill yes
			(thermal_gap 0.5)
			(thermal_bridge_width 0.5)
			(island_removal_mode 0)
		)
		(polygon
			(pts
				(arc
					(start 292.614096 -311.23509)
					(mid 291.946076 -311.23509)
					(end 292.614096 -311.23509)
				)
			)
		)
	)
	(zone
		(layers "B.Cu" "In4.Cu" "In6.Cu" "In11.Cu" "In13.Cu" "In15.Cu")
		(hatch none 0.5)
		(connect_pads
			(clearance 0)
		)
		(min_thickness 0.25)
		(keepout
			(tracks not_allowed)
			(vias allowed)
			(pads allowed)
			(copperpour not_allowed)
			(footprints allowed)
		)
		(placement
			(enabled no)
			(sheetname "")
		)
		(fill yes
			(thermal_gap 0.5)
			(thermal_bridge_width 0.5)
			(island_removal_mode 0)
		)
		(polygon
			(pts
				(arc
					(start 376.30989 -278.136096)
					(mid 375.67997 -278.136096)
					(end 376.30989 -278.136096)
				)
			)
		)
	)
	(zone
		(layers "B.Cu" "In4.Cu" "In6.Cu" "In11.Cu" "In13.Cu" "In15.Cu")
		(hatch none 0.5)
		(connect_pads
			(clearance 0)
		)
		(min_thickness 0.25)
		(keepout
			(tracks not_allowed)
			(vias allowed)
			(pads allowed)
			(copperpour not_allowed)
			(footprints allowed)
		)
		(placement
			(enabled no)
			(sheetname "")
		)
		(fill yes
			(thermal_gap 0.5)
			(thermal_bridge_width 0.5)
			(island_removal_mode 0)
		)
		(polygon
			(pts
				(arc
					(start 342.1761 -242.864132)
					(mid 341.54618 -242.864132)
					(end 342.1761 -242.864132)
				)
			)
		)
	)
	(zone
		(layers "B.Cu" "In4.Cu" "In6.Cu" "In11.Cu" "In13.Cu" "In15.Cu")
		(hatch none 0.5)
		(connect_pads
			(clearance 0)
		)
		(min_thickness 0.25)
		(keepout
			(tracks not_allowed)
			(vias allowed)
			(pads allowed)
			(copperpour not_allowed)
			(footprints allowed)
		)
		(placement
			(enabled no)
			(sheetname "")
		)
		(fill yes
			(thermal_gap 0.5)
			(thermal_bridge_width 0.5)
			(island_removal_mode 0)
		)
		(polygon
			(pts
				(arc
					(start 44.674028 -266.185396)
					(mid 44.006008 -266.185396)
					(end 44.674028 -266.185396)
				)
			)
		)
	)
	(zone
		(layers "B.Cu" "In4.Cu" "In6.Cu" "In11.Cu" "In13.Cu" "In15.Cu")
		(hatch none 0.5)
		(connect_pads
			(clearance 0)
		)
		(min_thickness 0.25)
		(keepout
			(tracks not_allowed)
			(vias allowed)
			(pads allowed)
			(copperpour not_allowed)
			(footprints allowed)
		)
		(placement
			(enabled no)
			(sheetname "")
		)
		(fill yes
			(thermal_gap 0.5)
			(thermal_bridge_width 0.5)
			(island_removal_mode 0)
		)
		(polygon
			(pts
				(arc
					(start 344.055954 -238.004096)
					(mid 343.426034 -238.004096)
					(end 344.055954 -238.004096)
				)
			)
		)
	)
	(zone
		(layers "B.Cu" "In4.Cu" "In6.Cu" "In11.Cu" "In13.Cu" "In15.Cu")
		(hatch none 0.5)
		(connect_pads
			(clearance 0)
		)
		(min_thickness 0.25)
		(keepout
			(tracks not_allowed)
			(vias allowed)
			(pads allowed)
			(copperpour not_allowed)
			(footprints allowed)
		)
		(placement
			(enabled no)
			(sheetname "")
		)
		(fill yes
			(thermal_gap 0.5)
			(thermal_bridge_width 0.5)
			(island_removal_mode 0)
		)
		(polygon
			(pts
				(arc
					(start 292.614096 -281.485086)
					(mid 291.946076 -281.485086)
					(end 292.614096 -281.485086)
				)
			)
		)
	)
	(zone
		(layers "B.Cu" "In4.Cu" "In6.Cu" "In11.Cu" "In13.Cu" "In15.Cu")
		(hatch none 0.5)
		(connect_pads
			(clearance 0)
		)
		(min_thickness 0.25)
		(keepout
			(tracks not_allowed)
			(vias allowed)
			(pads allowed)
			(copperpour not_allowed)
			(footprints allowed)
		)
		(placement
			(enabled no)
			(sheetname "")
		)
		(fill yes
			(thermal_gap 0.5)
			(thermal_bridge_width 0.5)
			(island_removal_mode 0)
		)
		(polygon
			(pts
				(arc
					(start 44.674028 -307.8353)
					(mid 44.006008 -307.8353)
					(end 44.674028 -307.8353)
				)
			)
		)
	)
	(zone
		(layers "B.Cu" "In4.Cu" "In6.Cu" "In11.Cu" "In13.Cu" "In15.Cu")
		(hatch none 0.5)
		(connect_pads
			(clearance 0)
		)
		(min_thickness 0.25)
		(keepout
			(tracks not_allowed)
			(vias allowed)
			(pads allowed)
			(copperpour not_allowed)
			(footprints allowed)
		)
		(placement
			(enabled no)
			(sheetname "")
		)
		(fill yes
			(thermal_gap 0.5)
			(thermal_bridge_width 0.5)
			(island_removal_mode 0)
		)
		(polygon
			(pts
				(arc
					(start 44.674028 -216.035382)
					(mid 44.006008 -216.035382)
					(end 44.674028 -216.035382)
				)
			)
		)
	)
	(zone
		(layers "B.Cu" "In4.Cu" "In6.Cu" "In11.Cu" "In13.Cu" "In15.Cu")
		(hatch none 0.5)
		(connect_pads
			(clearance 0)
		)
		(min_thickness 0.25)
		(keepout
			(tracks not_allowed)
			(vias allowed)
			(pads allowed)
			(copperpour not_allowed)
			(footprints allowed)
		)
		(placement
			(enabled no)
			(sheetname "")
		)
		(fill yes
			(thermal_gap 0.5)
			(thermal_bridge_width 0.5)
			(island_removal_mode 0)
		)
		(polygon
			(pts
				(arc
					(start 344.356182 -291.095938)
					(mid 343.726262 -291.095938)
					(end 344.356182 -291.095938)
				)
			)
		)
	)
	(zone
		(layers "B.Cu" "In4.Cu" "In6.Cu" "In11.Cu" "In13.Cu" "In15.Cu")
		(hatch none 0.5)
		(connect_pads
			(clearance 0)
		)
		(min_thickness 0.25)
		(keepout
			(tracks not_allowed)
			(vias allowed)
			(pads allowed)
			(copperpour not_allowed)
			(footprints allowed)
		)
		(placement
			(enabled no)
			(sheetname "")
		)
		(fill yes
			(thermal_gap 0.5)
			(thermal_bridge_width 0.5)
			(island_removal_mode 0)
		)
		(polygon
			(pts
				(arc
					(start 128.539748 -235.574332)
					(mid 127.909828 -235.574332)
					(end 128.539748 -235.574332)
				)
			)
		)
	)
	(zone
		(layers "B.Cu" "In4.Cu" "In6.Cu" "In11.Cu" "In13.Cu" "In15.Cu")
		(hatch none 0.5)
		(connect_pads
			(clearance 0)
		)
		(min_thickness 0.25)
		(keepout
			(tracks not_allowed)
			(vias allowed)
			(pads allowed)
			(copperpour not_allowed)
			(footprints allowed)
		)
		(placement
			(enabled no)
			(sheetname "")
		)
		(fill yes
			(thermal_gap 0.5)
			(thermal_bridge_width 0.5)
			(island_removal_mode 0)
		)
		(polygon
			(pts
				(arc
					(start 427.790102 -232.184956)
					(mid 427.122082 -232.184956)
					(end 427.790102 -232.184956)
				)
			)
		)
	)
	(zone
		(layers "B.Cu" "In4.Cu" "In6.Cu" "In11.Cu" "In13.Cu" "In15.Cu")
		(hatch none 0.5)
		(connect_pads
			(clearance 0)
		)
		(min_thickness 0.25)
		(keepout
			(tracks not_allowed)
			(vias allowed)
			(pads allowed)
			(copperpour not_allowed)
			(footprints allowed)
		)
		(placement
			(enabled no)
			(sheetname "")
		)
		(fill yes
			(thermal_gap 0.5)
			(thermal_bridge_width 0.5)
			(island_removal_mode 0)
		)
		(polygon
			(pts
				(arc
					(start 376.77979 -282.186126)
					(mid 376.14987 -282.186126)
					(end 376.77979 -282.186126)
				)
			)
		)
	)
	(zone
		(layers "B.Cu" "In4.Cu" "In6.Cu" "In11.Cu" "In13.Cu" "In15.Cu")
		(hatch none 0.5)
		(connect_pads
			(clearance 0)
		)
		(min_thickness 0.25)
		(keepout
			(tracks not_allowed)
			(vias allowed)
			(pads allowed)
			(copperpour not_allowed)
			(footprints allowed)
		)
		(placement
			(enabled no)
			(sheetname "")
		)
		(fill yes
			(thermal_gap 0.5)
			(thermal_bridge_width 0.5)
			(island_removal_mode 0)
		)
		(polygon
			(pts
				(arc
					(start 292.614096 -298.485052)
					(mid 291.946076 -298.485052)
					(end 292.614096 -298.485052)
				)
			)
		)
	)
	(zone
		(layers "B.Cu" "In4.Cu" "In6.Cu" "In11.Cu" "In13.Cu" "In15.Cu")
		(hatch none 0.5)
		(connect_pads
			(clearance 0)
		)
		(min_thickness 0.25)
		(keepout
			(tracks not_allowed)
			(vias allowed)
			(pads allowed)
			(copperpour not_allowed)
			(footprints allowed)
		)
		(placement
			(enabled no)
			(sheetname "")
		)
		(fill yes
			(thermal_gap 0.5)
			(thermal_bridge_width 0.5)
			(island_removal_mode 0)
		)
		(polygon
			(pts
				(arc
					(start 40.57396 -285.735268)
					(mid 39.90594 -285.735268)
					(end 40.57396 -285.735268)
				)
			)
		)
	)
	(zone
		(layers "B.Cu" "In4.Cu" "In6.Cu" "In11.Cu" "In13.Cu" "In15.Cu")
		(hatch none 0.5)
		(connect_pads
			(clearance 0)
		)
		(min_thickness 0.25)
		(keepout
			(tracks not_allowed)
			(vias allowed)
			(pads allowed)
			(copperpour not_allowed)
			(footprints allowed)
		)
		(placement
			(enabled no)
			(sheetname "")
		)
		(fill yes
			(thermal_gap 0.5)
			(thermal_bridge_width 0.5)
			(island_removal_mode 0)
		)
		(polygon
			(pts
				(arc
					(start 377.88977 -250.964192)
					(mid 377.25985 -250.964192)
					(end 377.88977 -250.964192)
				)
			)
		)
	)
	(zone
		(layers "B.Cu" "In4.Cu" "In6.Cu" "In11.Cu" "In13.Cu" "In15.Cu")
		(hatch none 0.5)
		(connect_pads
			(clearance 0)
		)
		(min_thickness 0.25)
		(keepout
			(tracks not_allowed)
			(vias allowed)
			(pads allowed)
			(copperpour not_allowed)
			(footprints allowed)
		)
		(placement
			(enabled no)
			(sheetname "")
		)
		(fill yes
			(thermal_gap 0.5)
			(thermal_bridge_width 0.5)
			(island_removal_mode 0)
		)
		(polygon
			(pts
				(arc
					(start 427.790102 -268.735048)
					(mid 427.122082 -268.735048)
					(end 427.790102 -268.735048)
				)
			)
		)
	)
	(zone
		(layers "B.Cu" "In4.Cu" "In6.Cu" "In11.Cu" "In13.Cu" "In15.Cu")
		(hatch none 0.5)
		(connect_pads
			(clearance 0)
		)
		(min_thickness 0.25)
		(keepout
			(tracks not_allowed)
			(vias allowed)
			(pads allowed)
			(copperpour not_allowed)
			(footprints allowed)
		)
		(placement
			(enabled no)
			(sheetname "")
		)
		(fill yes
			(thermal_gap 0.5)
			(thermal_bridge_width 0.5)
			(island_removal_mode 0)
		)
		(polygon
			(pts
				(arc
					(start 371.309646 -226.664266)
					(mid 370.679726 -226.664266)
					(end 371.309646 -226.664266)
				)
			)
		)
	)
	(zone
		(layers "B.Cu" "In4.Cu" "In6.Cu" "In11.Cu" "In13.Cu" "In15.Cu")
		(hatch none 0.5)
		(connect_pads
			(clearance 0)
		)
		(min_thickness 0.25)
		(keepout
			(tracks not_allowed)
			(vias allowed)
			(pads allowed)
			(copperpour not_allowed)
			(footprints allowed)
		)
		(placement
			(enabled no)
			(sheetname "")
		)
		(fill yes
			(thermal_gap 0.5)
			(thermal_bridge_width 0.5)
			(island_removal_mode 0)
		)
		(polygon
			(pts
				(arc
					(start 344.055954 -242.864132)
					(mid 343.426034 -242.864132)
					(end 344.055954 -242.864132)
				)
			)
		)
	)
	(zone
		(layers "B.Cu" "In4.Cu" "In6.Cu" "In11.Cu" "In13.Cu" "In15.Cu")
		(hatch none 0.5)
		(connect_pads
			(clearance 0)
		)
		(min_thickness 0.25)
		(keepout
			(tracks not_allowed)
			(vias allowed)
			(pads allowed)
			(copperpour not_allowed)
			(footprints allowed)
		)
		(placement
			(enabled no)
			(sheetname "")
		)
		(fill yes
			(thermal_gap 0.5)
			(thermal_bridge_width 0.5)
			(island_removal_mode 0)
		)
		(polygon
			(pts
				(arc
					(start 44.674028 -309.535322)
					(mid 44.006008 -309.535322)
					(end 44.674028 -309.535322)
				)
			)
		)
	)
	(zone
		(layers "B.Cu" "In4.Cu" "In6.Cu" "In11.Cu" "In13.Cu" "In15.Cu")
		(hatch none 0.5)
		(connect_pads
			(clearance 0)
		)
		(min_thickness 0.25)
		(keepout
			(tracks not_allowed)
			(vias allowed)
			(pads allowed)
			(copperpour not_allowed)
			(footprints allowed)
		)
		(placement
			(enabled no)
			(sheetname "")
		)
		(fill yes
			(thermal_gap 0.5)
			(thermal_bridge_width 0.5)
			(island_removal_mode 0)
		)
		(polygon
			(pts
				(arc
					(start 109.746034 -227.474526)
					(mid 109.116114 -227.474526)
					(end 109.746034 -227.474526)
				)
			)
		)
	)
	(zone
		(layers "B.Cu" "In4.Cu" "In6.Cu" "In11.Cu" "In13.Cu" "In15.Cu")
		(hatch none 0.5)
		(connect_pads
			(clearance 0)
		)
		(min_thickness 0.25)
		(keepout
			(tracks not_allowed)
			(vias allowed)
			(pads allowed)
			(copperpour not_allowed)
			(footprints allowed)
		)
		(placement
			(enabled no)
			(sheetname "")
		)
		(fill yes
			(thermal_gap 0.5)
			(thermal_bridge_width 0.5)
			(island_removal_mode 0)
		)
		(polygon
			(pts
				(arc
					(start 431.89017 -303.585118)
					(mid 431.22215 -303.585118)
					(end 431.89017 -303.585118)
				)
			)
		)
	)
	(zone
		(layers "B.Cu" "In4.Cu" "In6.Cu" "In11.Cu" "In13.Cu" "In15.Cu")
		(hatch none 0.5)
		(connect_pads
			(clearance 0)
		)
		(min_thickness 0.25)
		(keepout
			(tracks not_allowed)
			(vias allowed)
			(pads allowed)
			(copperpour not_allowed)
			(footprints allowed)
		)
		(placement
			(enabled no)
			(sheetname "")
		)
		(fill yes
			(thermal_gap 0.5)
			(thermal_bridge_width 0.5)
			(island_removal_mode 0)
		)
		(polygon
			(pts
				(arc
					(start 342.476074 -286.236156)
					(mid 341.846154 -286.236156)
					(end 342.476074 -286.236156)
				)
			)
		)
	)
	(zone
		(layers "B.Cu" "In4.Cu" "In6.Cu" "In11.Cu" "In13.Cu" "In15.Cu")
		(hatch none 0.5)
		(connect_pads
			(clearance 0)
		)
		(min_thickness 0.25)
		(keepout
			(tracks not_allowed)
			(vias allowed)
			(pads allowed)
			(copperpour not_allowed)
			(footprints allowed)
		)
		(placement
			(enabled no)
			(sheetname "")
		)
		(fill yes
			(thermal_gap 0.5)
			(thermal_bridge_width 0.5)
			(island_removal_mode 0)
		)
		(polygon
			(pts
				(arc
					(start 184.71896 5.631434)
					(mid 184.05094 5.631434)
					(end 184.71896 5.631434)
				)
			)
		)
	)
	(zone
		(layers "B.Cu" "In4.Cu" "In6.Cu" "In11.Cu" "In13.Cu" "In15.Cu")
		(hatch none 0.5)
		(connect_pads
			(clearance 0)
		)
		(min_thickness 0.25)
		(keepout
			(tracks not_allowed)
			(vias allowed)
			(pads allowed)
			(copperpour not_allowed)
			(footprints allowed)
		)
		(placement
			(enabled no)
			(sheetname "")
		)
		(fill yes
			(thermal_gap 0.5)
			(thermal_bridge_width 0.5)
			(island_removal_mode 0)
		)
		(polygon
			(pts
				(arc
					(start 343.586054 -232.334054)
					(mid 342.956134 -232.334054)
					(end 343.586054 -232.334054)
				)
			)
		)
	)
	(zone
		(layers "B.Cu" "In4.Cu" "In6.Cu" "In11.Cu" "In13.Cu" "In15.Cu")
		(hatch none 0.5)
		(connect_pads
			(clearance 0)
		)
		(min_thickness 0.25)
		(keepout
			(tracks not_allowed)
			(vias allowed)
			(pads allowed)
			(copperpour not_allowed)
			(footprints allowed)
		)
		(placement
			(enabled no)
			(sheetname "")
		)
		(fill yes
			(thermal_gap 0.5)
			(thermal_bridge_width 0.5)
			(island_removal_mode 0)
		)
		(polygon
			(pts
				(arc
					(start 427.790102 -278.93518)
					(mid 427.122082 -278.93518)
					(end 427.790102 -278.93518)
				)
			)
		)
	)
	(zone
		(layers "B.Cu" "In4.Cu" "In6.Cu" "In11.Cu" "In13.Cu" "In15.Cu")
		(hatch none 0.5)
		(connect_pads
			(clearance 0)
		)
		(min_thickness 0.25)
		(keepout
			(tracks not_allowed)
			(vias allowed)
			(pads allowed)
			(copperpour not_allowed)
			(footprints allowed)
		)
		(placement
			(enabled no)
			(sheetname "")
		)
		(fill yes
			(thermal_gap 0.5)
			(thermal_bridge_width 0.5)
			(island_removal_mode 0)
		)
		(polygon
			(pts
				(arc
					(start 288.514028 -282.33497)
					(mid 287.846008 -282.33497)
					(end 288.514028 -282.33497)
				)
			)
		)
	)
	(zone
		(layers "B.Cu" "In4.Cu" "In6.Cu" "In11.Cu" "In13.Cu" "In15.Cu")
		(hatch none 0.5)
		(connect_pads
			(clearance 0)
		)
		(min_thickness 0.25)
		(keepout
			(tracks not_allowed)
			(vias allowed)
			(pads allowed)
			(copperpour not_allowed)
			(footprints allowed)
		)
		(placement
			(enabled no)
			(sheetname "")
		)
		(fill yes
			(thermal_gap 0.5)
			(thermal_bridge_width 0.5)
			(island_removal_mode 0)
		)
		(polygon
			(pts
				(arc
					(start 344.356182 -273.27606)
					(mid 343.726262 -273.27606)
					(end 344.356182 -273.27606)
				)
			)
		)
	)
	(zone
		(layers "B.Cu" "In4.Cu" "In6.Cu" "In11.Cu" "In13.Cu" "In15.Cu")
		(hatch none 0.5)
		(connect_pads
			(clearance 0)
		)
		(min_thickness 0.25)
		(keepout
			(tracks not_allowed)
			(vias allowed)
			(pads allowed)
			(copperpour not_allowed)
			(footprints allowed)
		)
		(placement
			(enabled no)
			(sheetname "")
		)
		(fill yes
			(thermal_gap 0.5)
			(thermal_bridge_width 0.5)
			(island_removal_mode 0)
		)
		(polygon
			(pts
				(arc
					(start 94.236032 -233.144314)
					(mid 93.606112 -233.144314)
					(end 94.236032 -233.144314)
				)
			)
		)
	)
	(zone
		(layers "B.Cu" "In4.Cu" "In6.Cu" "In11.Cu" "In13.Cu" "In15.Cu")
		(hatch none 0.5)
		(connect_pads
			(clearance 0)
		)
		(min_thickness 0.25)
		(keepout
			(tracks not_allowed)
			(vias allowed)
			(pads allowed)
			(copperpour not_allowed)
			(footprints allowed)
		)
		(placement
			(enabled no)
			(sheetname "")
		)
		(fill yes
			(thermal_gap 0.5)
			(thermal_bridge_width 0.5)
			(island_removal_mode 0)
		)
		(polygon
			(pts
				(arc
					(start 179.850034 -284.035246)
					(mid 179.182014 -284.035246)
					(end 179.850034 -284.035246)
				)
			)
		)
	)
	(zone
		(layers "B.Cu" "In4.Cu" "In6.Cu" "In11.Cu" "In13.Cu" "In15.Cu")
		(hatch none 0.5)
		(connect_pads
			(clearance 0)
		)
		(min_thickness 0.25)
		(keepout
			(tracks not_allowed)
			(vias allowed)
			(pads allowed)
			(copperpour not_allowed)
			(footprints allowed)
		)
		(placement
			(enabled no)
			(sheetname "")
		)
		(fill yes
			(thermal_gap 0.5)
			(thermal_bridge_width 0.5)
			(island_removal_mode 0)
		)
		(polygon
			(pts
				(arc
					(start 376.77979 -264.365994)
					(mid 376.14987 -264.365994)
					(end 376.77979 -264.365994)
				)
			)
		)
	)
	(zone
		(layers "B.Cu" "In4.Cu" "In6.Cu" "In11.Cu" "In13.Cu" "In15.Cu")
		(hatch none 0.5)
		(connect_pads
			(clearance 0)
		)
		(min_thickness 0.25)
		(keepout
			(tracks not_allowed)
			(vias allowed)
			(pads allowed)
			(copperpour not_allowed)
			(footprints allowed)
		)
		(placement
			(enabled no)
			(sheetname "")
		)
		(fill yes
			(thermal_gap 0.5)
			(thermal_bridge_width 0.5)
			(island_removal_mode 0)
		)
		(polygon
			(pts
				(arc
					(start 28.520136 -428.183802)
					(mid 27.852116 -428.183802)
					(end 28.520136 -428.183802)
				)
			)
		)
	)
	(zone
		(layers "B.Cu" "In4.Cu" "In6.Cu" "In11.Cu" "In13.Cu" "In15.Cu")
		(hatch none 0.5)
		(connect_pads
			(clearance 0)
		)
		(min_thickness 0.25)
		(keepout
			(tracks not_allowed)
			(vias allowed)
			(pads allowed)
			(copperpour not_allowed)
			(footprints allowed)
		)
		(placement
			(enabled no)
			(sheetname "")
		)
		(fill yes
			(thermal_gap 0.5)
			(thermal_bridge_width 0.5)
			(island_removal_mode 0)
		)
		(polygon
			(pts
				(arc
					(start 342.476074 -270.036036)
					(mid 341.846154 -270.036036)
					(end 342.476074 -270.036036)
				)
			)
		)
	)
	(zone
		(layers "B.Cu" "In4.Cu" "In6.Cu" "In11.Cu" "In13.Cu" "In15.Cu")
		(hatch none 0.5)
		(connect_pads
			(clearance 0)
		)
		(min_thickness 0.25)
		(keepout
			(tracks not_allowed)
			(vias allowed)
			(pads allowed)
			(copperpour not_allowed)
			(footprints allowed)
		)
		(placement
			(enabled no)
			(sheetname "")
		)
		(fill yes
			(thermal_gap 0.5)
			(thermal_bridge_width 0.5)
			(island_removal_mode 0)
		)
		(polygon
			(pts
				(arc
					(start 40.57396 -261.935214)
					(mid 39.90594 -261.935214)
					(end 40.57396 -261.935214)
				)
			)
		)
	)
	(zone
		(layers "B.Cu" "In4.Cu" "In6.Cu" "In11.Cu" "In13.Cu" "In15.Cu")
		(hatch none 0.5)
		(connect_pads
			(clearance 0)
		)
		(min_thickness 0.25)
		(keepout
			(tracks not_allowed)
			(vias allowed)
			(pads allowed)
			(copperpour not_allowed)
			(footprints allowed)
		)
		(placement
			(enabled no)
			(sheetname "")
		)
		(fill yes
			(thermal_gap 0.5)
			(thermal_bridge_width 0.5)
			(island_removal_mode 0)
		)
		(polygon
			(pts
				(arc
					(start 40.57396 -202.435206)
					(mid 39.90594 -202.435206)
					(end 40.57396 -202.435206)
				)
			)
		)
	)
	(zone
		(layers "B.Cu" "In4.Cu" "In6.Cu" "In11.Cu" "In13.Cu" "In15.Cu")
		(hatch none 0.5)
		(connect_pads
			(clearance 0)
		)
		(min_thickness 0.25)
		(keepout
			(tracks not_allowed)
			(vias allowed)
			(pads allowed)
			(copperpour not_allowed)
			(footprints allowed)
		)
		(placement
			(enabled no)
			(sheetname "")
		)
		(fill yes
			(thermal_gap 0.5)
			(thermal_bridge_width 0.5)
			(island_removal_mode 0)
		)
		(polygon
			(pts
				(arc
					(start 343.586054 -233.954066)
					(mid 342.956134 -233.954066)
					(end 343.586054 -233.954066)
				)
			)
		)
	)
	(zone
		(layers "B.Cu" "In4.Cu" "In6.Cu" "In11.Cu" "In13.Cu" "In15.Cu")
		(hatch none 0.5)
		(connect_pads
			(clearance 0)
		)
		(min_thickness 0.25)
		(keepout
			(tracks not_allowed)
			(vias allowed)
			(pads allowed)
			(copperpour not_allowed)
			(footprints allowed)
		)
		(placement
			(enabled no)
			(sheetname "")
		)
		(fill yes
			(thermal_gap 0.5)
			(thermal_bridge_width 0.5)
			(island_removal_mode 0)
		)
		(polygon
			(pts
				(arc
					(start 344.356182 -281.37612)
					(mid 343.726262 -281.37612)
					(end 344.356182 -281.37612)
				)
			)
		)
	)
	(zone
		(layers "B.Cu" "In4.Cu" "In6.Cu" "In11.Cu" "In13.Cu" "In15.Cu")
		(hatch none 0.5)
		(connect_pads
			(clearance 0)
		)
		(min_thickness 0.25)
		(keepout
			(tracks not_allowed)
			(vias allowed)
			(pads allowed)
			(copperpour not_allowed)
			(footprints allowed)
		)
		(placement
			(enabled no)
			(sheetname "")
		)
		(fill yes
			(thermal_gap 0.5)
			(thermal_bridge_width 0.5)
			(island_removal_mode 0)
		)
		(polygon
			(pts
				(arc
					(start 40.57396 -251.735336)
					(mid 39.90594 -251.735336)
					(end 40.57396 -251.735336)
				)
			)
		)
	)
	(zone
		(layers "B.Cu" "In4.Cu" "In6.Cu" "In11.Cu" "In13.Cu" "In15.Cu")
		(hatch none 0.5)
		(connect_pads
			(clearance 0)
		)
		(min_thickness 0.25)
		(keepout
			(tracks not_allowed)
			(vias allowed)
			(pads allowed)
			(copperpour not_allowed)
			(footprints allowed)
		)
		(placement
			(enabled no)
			(sheetname "")
		)
		(fill yes
			(thermal_gap 0.5)
			(thermal_bridge_width 0.5)
			(island_removal_mode 0)
		)
		(polygon
			(pts
				(arc
					(start 94.236032 -242.864386)
					(mid 93.606112 -242.864386)
					(end 94.236032 -242.864386)
				)
			)
		)
	)
	(zone
		(layers "B.Cu" "In4.Cu" "In6.Cu" "In11.Cu" "In13.Cu" "In15.Cu")
		(hatch none 0.5)
		(connect_pads
			(clearance 0)
		)
		(min_thickness 0.25)
		(keepout
			(tracks not_allowed)
			(vias allowed)
			(pads allowed)
			(copperpour not_allowed)
			(footprints allowed)
		)
		(placement
			(enabled no)
			(sheetname "")
		)
		(fill yes
			(thermal_gap 0.5)
			(thermal_bridge_width 0.5)
			(island_removal_mode 0)
		)
		(polygon
			(pts
				(arc
					(start 40.57396 -316.33541)
					(mid 39.90594 -316.33541)
					(end 40.57396 -316.33541)
				)
			)
		)
	)
	(zone
		(layers "B.Cu" "In4.Cu" "In6.Cu" "In11.Cu" "In13.Cu" "In15.Cu")
		(hatch none 0.5)
		(connect_pads
			(clearance 0)
		)
		(min_thickness 0.25)
		(keepout
			(tracks not_allowed)
			(vias allowed)
			(pads allowed)
			(copperpour not_allowed)
			(footprints allowed)
		)
		(placement
			(enabled no)
			(sheetname "")
		)
		(fill yes
			(thermal_gap 0.5)
			(thermal_bridge_width 0.5)
			(island_removal_mode 0)
		)
		(polygon
			(pts
				(arc
					(start 44.674028 -203.285344)
					(mid 44.006008 -203.285344)
					(end 44.674028 -203.285344)
				)
			)
		)
	)
	(zone
		(layers "B.Cu" "In4.Cu" "In6.Cu" "In11.Cu" "In13.Cu" "In15.Cu")
		(hatch none 0.5)
		(connect_pads
			(clearance 0)
		)
		(min_thickness 0.25)
		(keepout
			(tracks not_allowed)
			(vias allowed)
			(pads allowed)
			(copperpour not_allowed)
			(footprints allowed)
		)
		(placement
			(enabled no)
			(sheetname "")
		)
		(fill yes
			(thermal_gap 0.5)
			(thermal_bridge_width 0.5)
			(island_removal_mode 0)
		)
		(polygon
			(pts
				(arc
					(start 179.850034 -233.885232)
					(mid 179.182014 -233.885232)
					(end 179.850034 -233.885232)
				)
			)
		)
	)
	(zone
		(layers "B.Cu" "In4.Cu" "In6.Cu" "In11.Cu" "In13.Cu" "In15.Cu")
		(hatch none 0.5)
		(connect_pads
			(clearance 0)
		)
		(min_thickness 0.25)
		(keepout
			(tracks not_allowed)
			(vias allowed)
			(pads allowed)
			(copperpour not_allowed)
			(footprints allowed)
		)
		(placement
			(enabled no)
			(sheetname "")
		)
		(fill yes
			(thermal_gap 0.5)
			(thermal_bridge_width 0.5)
			(island_removal_mode 0)
		)
		(polygon
			(pts
				(arc
					(start 44.674028 -247.485408)
					(mid 44.006008 -247.485408)
					(end 44.674028 -247.485408)
				)
			)
		)
	)
	(zone
		(layers "B.Cu" "In4.Cu" "In6.Cu" "In11.Cu" "In13.Cu" "In15.Cu")
		(hatch none 0.5)
		(connect_pads
			(clearance 0)
		)
		(min_thickness 0.25)
		(keepout
			(tracks not_allowed)
			(vias allowed)
			(pads allowed)
			(copperpour not_allowed)
			(footprints allowed)
		)
		(placement
			(enabled no)
			(sheetname "")
		)
		(fill yes
			(thermal_gap 0.5)
			(thermal_bridge_width 0.5)
			(island_removal_mode 0)
		)
		(polygon
			(pts
				(arc
					(start 179.850034 -199.8853)
					(mid 179.182014 -199.8853)
					(end 179.850034 -199.8853)
				)
			)
		)
	)
	(zone
		(layers "B.Cu" "In4.Cu" "In6.Cu" "In11.Cu" "In13.Cu" "In15.Cu")
		(hatch none 0.5)
		(connect_pads
			(clearance 0)
		)
		(min_thickness 0.25)
		(keepout
			(tracks not_allowed)
			(vias allowed)
			(pads allowed)
			(copperpour not_allowed)
			(footprints allowed)
		)
		(placement
			(enabled no)
			(sheetname "")
		)
		(fill yes
			(thermal_gap 0.5)
			(thermal_bridge_width 0.5)
			(island_removal_mode 0)
		)
		(polygon
			(pts
				(arc
					(start 44.674028 -312.935366)
					(mid 44.006008 -312.935366)
					(end 44.674028 -312.935366)
				)
			)
		)
	)
	(zone
		(layers "B.Cu" "In4.Cu" "In6.Cu" "In11.Cu" "In13.Cu" "In15.Cu")
		(hatch none 0.5)
		(connect_pads
			(clearance 0)
		)
		(min_thickness 0.25)
		(keepout
			(tracks not_allowed)
			(vias allowed)
			(pads allowed)
			(copperpour not_allowed)
			(footprints allowed)
		)
		(placement
			(enabled no)
			(sheetname "")
		)
		(fill yes
			(thermal_gap 0.5)
			(thermal_bridge_width 0.5)
			(island_removal_mode 0)
		)
		(polygon
			(pts
				(arc
					(start 316.77737 5.514594)
					(mid 316.10935 5.514594)
					(end 316.77737 5.514594)
				)
			)
		)
	)
	(zone
		(layers "B.Cu" "In4.Cu" "In6.Cu" "In11.Cu" "In13.Cu" "In15.Cu")
		(hatch none 0.5)
		(connect_pads
			(clearance 0)
		)
		(min_thickness 0.25)
		(keepout
			(tracks not_allowed)
			(vias allowed)
			(pads allowed)
			(copperpour not_allowed)
			(footprints allowed)
		)
		(placement
			(enabled no)
			(sheetname "")
		)
		(fill yes
			(thermal_gap 0.5)
			(thermal_bridge_width 0.5)
			(island_removal_mode 0)
		)
		(polygon
			(pts
				(arc
					(start 129.479802 -240.434368)
					(mid 128.849882 -240.434368)
					(end 129.479802 -240.434368)
				)
			)
		)
	)
	(zone
		(layers "B.Cu" "In4.Cu" "In6.Cu" "In11.Cu" "In13.Cu" "In15.Cu")
		(hatch none 0.5)
		(connect_pads
			(clearance 0)
		)
		(min_thickness 0.25)
		(keepout
			(tracks not_allowed)
			(vias allowed)
			(pads allowed)
			(copperpour not_allowed)
			(footprints allowed)
		)
		(placement
			(enabled no)
			(sheetname "")
		)
		(fill yes
			(thermal_gap 0.5)
			(thermal_bridge_width 0.5)
			(island_removal_mode 0)
		)
		(polygon
			(pts
				(arc
					(start 40.57396 -263.635236)
					(mid 39.90594 -263.635236)
					(end 40.57396 -263.635236)
				)
			)
		)
	)
	(zone
		(layers "B.Cu" "In4.Cu" "In6.Cu" "In11.Cu" "In13.Cu" "In15.Cu")
		(hatch none 0.5)
		(connect_pads
			(clearance 0)
		)
		(min_thickness 0.25)
		(keepout
			(tracks not_allowed)
			(vias allowed)
			(pads allowed)
			(copperpour not_allowed)
			(footprints allowed)
		)
		(placement
			(enabled no)
			(sheetname "")
		)
		(fill yes
			(thermal_gap 0.5)
			(thermal_bridge_width 0.5)
			(island_removal_mode 0)
		)
		(polygon
			(pts
				(arc
					(start 96.115886 -242.864386)
					(mid 95.485966 -242.864386)
					(end 96.115886 -242.864386)
				)
			)
		)
	)
	(zone
		(layers "B.Cu" "In4.Cu" "In6.Cu" "In11.Cu" "In13.Cu" "In15.Cu")
		(hatch none 0.5)
		(connect_pads
			(clearance 0)
		)
		(min_thickness 0.25)
		(keepout
			(tracks not_allowed)
			(vias allowed)
			(pads allowed)
			(copperpour not_allowed)
			(footprints allowed)
		)
		(placement
			(enabled no)
			(sheetname "")
		)
		(fill yes
			(thermal_gap 0.5)
			(thermal_bridge_width 0.5)
			(island_removal_mode 0)
		)
		(polygon
			(pts
				(arc
					(start 292.614096 -227.085144)
					(mid 291.946076 -227.085144)
					(end 292.614096 -227.085144)
				)
			)
		)
	)
	(zone
		(layers "B.Cu" "In4.Cu" "In6.Cu" "In11.Cu" "In13.Cu" "In15.Cu")
		(hatch none 0.5)
		(connect_pads
			(clearance 0)
		)
		(min_thickness 0.25)
		(keepout
			(tracks not_allowed)
			(vias allowed)
			(pads allowed)
			(copperpour not_allowed)
			(footprints allowed)
		)
		(placement
			(enabled no)
			(sheetname "")
		)
		(fill yes
			(thermal_gap 0.5)
			(thermal_bridge_width 0.5)
			(island_removal_mode 0)
		)
		(polygon
			(pts
				(arc
					(start 292.614096 -217.73515)
					(mid 291.946076 -217.73515)
					(end 292.614096 -217.73515)
				)
			)
		)
	)
	(zone
		(layers "B.Cu" "In4.Cu" "In6.Cu" "In11.Cu" "In13.Cu" "In15.Cu")
		(hatch none 0.5)
		(connect_pads
			(clearance 0)
		)
		(min_thickness 0.25)
		(keepout
			(tracks not_allowed)
			(vias allowed)
			(pads allowed)
			(copperpour not_allowed)
			(footprints allowed)
		)
		(placement
			(enabled no)
			(sheetname "")
		)
		(fill yes
			(thermal_gap 0.5)
			(thermal_bridge_width 0.5)
			(island_removal_mode 0)
		)
		(polygon
			(pts
				(arc
					(start 44.674028 -233.035348)
					(mid 44.006008 -233.035348)
					(end 44.674028 -233.035348)
				)
			)
		)
	)
	(zone
		(layers "B.Cu" "In4.Cu" "In6.Cu" "In11.Cu" "In13.Cu" "In15.Cu")
		(hatch none 0.5)
		(connect_pads
			(clearance 0)
		)
		(min_thickness 0.25)
		(keepout
			(tracks not_allowed)
			(vias allowed)
			(pads allowed)
			(copperpour not_allowed)
			(footprints allowed)
		)
		(placement
			(enabled no)
			(sheetname "")
		)
		(fill yes
			(thermal_gap 0.5)
			(thermal_bridge_width 0.5)
			(island_removal_mode 0)
		)
		(polygon
			(pts
				(arc
					(start 179.850034 -282.335224)
					(mid 179.182014 -282.335224)
					(end 179.850034 -282.335224)
				)
			)
		)
	)
	(zone
		(layers "B.Cu" "In4.Cu" "In6.Cu" "In11.Cu" "In13.Cu" "In15.Cu")
		(hatch none 0.5)
		(connect_pads
			(clearance 0)
		)
		(min_thickness 0.25)
		(keepout
			(tracks not_allowed)
			(vias allowed)
			(pads allowed)
			(copperpour not_allowed)
			(footprints allowed)
		)
		(placement
			(enabled no)
			(sheetname "")
		)
		(fill yes
			(thermal_gap 0.5)
			(thermal_bridge_width 0.5)
			(island_removal_mode 0)
		)
		(polygon
			(pts
				(arc
					(start 288.514028 -295.085008)
					(mid 287.846008 -295.085008)
					(end 288.514028 -295.085008)
				)
			)
		)
	)
	(zone
		(layers "B.Cu" "In4.Cu" "In6.Cu" "In11.Cu" "In13.Cu" "In15.Cu")
		(hatch none 0.5)
		(connect_pads
			(clearance 0)
		)
		(min_thickness 0.25)
		(keepout
			(tracks not_allowed)
			(vias allowed)
			(pads allowed)
			(copperpour not_allowed)
			(footprints allowed)
		)
		(placement
			(enabled no)
			(sheetname "")
		)
		(fill yes
			(thermal_gap 0.5)
			(thermal_bridge_width 0.5)
			(island_removal_mode 0)
		)
		(polygon
			(pts
				(arc
					(start 431.89017 -266.185142)
					(mid 431.22215 -266.185142)
					(end 431.89017 -266.185142)
				)
			)
		)
	)
	(zone
		(layers "B.Cu" "In4.Cu" "In6.Cu" "In11.Cu" "In13.Cu" "In15.Cu")
		(hatch none 0.5)
		(connect_pads
			(clearance 0)
		)
		(min_thickness 0.25)
		(keepout
			(tracks not_allowed)
			(vias allowed)
			(pads allowed)
			(copperpour not_allowed)
			(footprints allowed)
		)
		(placement
			(enabled no)
			(sheetname "")
		)
		(fill yes
			(thermal_gap 0.5)
			(thermal_bridge_width 0.5)
			(island_removal_mode 0)
		)
		(polygon
			(pts
				(arc
					(start 376.479816 -237.19409)
					(mid 375.849896 -237.19409)
					(end 376.479816 -237.19409)
				)
			)
		)
	)
	(zone
		(layers "B.Cu" "In4.Cu" "In6.Cu" "In11.Cu" "In13.Cu" "In15.Cu")
		(hatch none 0.5)
		(connect_pads
			(clearance 0)
		)
		(min_thickness 0.25)
		(keepout
			(tracks not_allowed)
			(vias allowed)
			(pads allowed)
			(copperpour not_allowed)
			(footprints allowed)
		)
		(placement
			(enabled no)
			(sheetname "")
		)
		(fill yes
			(thermal_gap 0.5)
			(thermal_bridge_width 0.5)
			(island_removal_mode 0)
		)
		(polygon
			(pts
				(arc
					(start 292.614096 -275.535136)
					(mid 291.946076 -275.535136)
					(end 292.614096 -275.535136)
				)
			)
		)
	)
	(zone
		(layers "B.Cu" "In4.Cu" "In6.Cu" "In11.Cu" "In13.Cu" "In15.Cu")
		(hatch none 0.5)
		(connect_pads
			(clearance 0)
		)
		(min_thickness 0.25)
		(keepout
			(tracks not_allowed)
			(vias allowed)
			(pads allowed)
			(copperpour not_allowed)
			(footprints allowed)
		)
		(placement
			(enabled no)
			(sheetname "")
		)
		(fill yes
			(thermal_gap 0.5)
			(thermal_bridge_width 0.5)
			(island_removal_mode 0)
		)
		(polygon
			(pts
				(arc
					(start 183.950102 -278.085296)
					(mid 183.282082 -278.085296)
					(end 183.950102 -278.085296)
				)
			)
		)
	)
	(zone
		(layers "B.Cu" "In4.Cu" "In6.Cu" "In11.Cu" "In13.Cu" "In15.Cu")
		(hatch none 0.5)
		(connect_pads
			(clearance 0)
		)
		(min_thickness 0.25)
		(keepout
			(tracks not_allowed)
			(vias allowed)
			(pads allowed)
			(copperpour not_allowed)
			(footprints allowed)
		)
		(placement
			(enabled no)
			(sheetname "")
		)
		(fill yes
			(thermal_gap 0.5)
			(thermal_bridge_width 0.5)
			(island_removal_mode 0)
		)
		(polygon
			(pts
				(arc
					(start 94.536006 -289.47618)
					(mid 93.906086 -289.47618)
					(end 94.536006 -289.47618)
				)
			)
		)
	)
	(zone
		(layers "B.Cu" "In4.Cu" "In6.Cu" "In11.Cu" "In13.Cu" "In15.Cu")
		(hatch none 0.5)
		(connect_pads
			(clearance 0)
		)
		(min_thickness 0.25)
		(keepout
			(tracks not_allowed)
			(vias allowed)
			(pads allowed)
			(copperpour not_allowed)
			(footprints allowed)
		)
		(placement
			(enabled no)
			(sheetname "")
		)
		(fill yes
			(thermal_gap 0.5)
			(thermal_bridge_width 0.5)
			(island_removal_mode 0)
		)
		(polygon
			(pts
				(arc
					(start 344.055954 -246.104156)
					(mid 343.426034 -246.104156)
					(end 344.055954 -246.104156)
				)
			)
		)
	)
	(zone
		(layers "B.Cu" "In4.Cu" "In6.Cu" "In11.Cu" "In13.Cu" "In15.Cu")
		(hatch none 0.5)
		(connect_pads
			(clearance 0)
		)
		(min_thickness 0.25)
		(keepout
			(tracks not_allowed)
			(vias allowed)
			(pads allowed)
			(copperpour not_allowed)
			(footprints allowed)
		)
		(placement
			(enabled no)
			(sheetname "")
		)
		(fill yes
			(thermal_gap 0.5)
			(thermal_bridge_width 0.5)
			(island_removal_mode 0)
		)
		(polygon
			(pts
				(arc
					(start 99.236022 -292.716204)
					(mid 98.606102 -292.716204)
					(end 99.236022 -292.716204)
				)
			)
		)
	)
	(zone
		(layers "B.Cu" "In4.Cu" "In6.Cu" "In11.Cu" "In13.Cu" "In15.Cu")
		(hatch none 0.5)
		(connect_pads
			(clearance 0)
		)
		(min_thickness 0.25)
		(keepout
			(tracks not_allowed)
			(vias allowed)
			(pads allowed)
			(copperpour not_allowed)
			(footprints allowed)
		)
		(placement
			(enabled no)
			(sheetname "")
		)
		(fill yes
			(thermal_gap 0.5)
			(thermal_bridge_width 0.5)
			(island_removal_mode 0)
		)
		(polygon
			(pts
				(arc
					(start 96.115886 -252.584458)
					(mid 95.485966 -252.584458)
					(end 96.115886 -252.584458)
				)
			)
		)
	)
	(zone
		(layers "B.Cu" "In4.Cu" "In6.Cu" "In11.Cu" "In13.Cu" "In15.Cu")
		(hatch none 0.5)
		(connect_pads
			(clearance 0)
		)
		(min_thickness 0.25)
		(keepout
			(tracks not_allowed)
			(vias allowed)
			(pads allowed)
			(copperpour not_allowed)
			(footprints allowed)
		)
		(placement
			(enabled no)
			(sheetname "")
		)
		(fill yes
			(thermal_gap 0.5)
			(thermal_bridge_width 0.5)
			(island_removal_mode 0)
		)
		(polygon
			(pts
				(arc
					(start 343.886028 -275.706078)
					(mid 343.256108 -275.706078)
					(end 343.886028 -275.706078)
				)
			)
		)
	)
	(zone
		(layers "B.Cu" "In4.Cu" "In6.Cu" "In11.Cu" "In13.Cu" "In15.Cu")
		(hatch none 0.5)
		(connect_pads
			(clearance 0)
		)
		(min_thickness 0.25)
		(keepout
			(tracks not_allowed)
			(vias allowed)
			(pads allowed)
			(copperpour not_allowed)
			(footprints allowed)
		)
		(placement
			(enabled no)
			(sheetname "")
		)
		(fill yes
			(thermal_gap 0.5)
			(thermal_bridge_width 0.5)
			(island_removal_mode 0)
		)
		(polygon
			(pts
				(arc
					(start 431.89017 -228.785166)
					(mid 431.22215 -228.785166)
					(end 431.89017 -228.785166)
				)
			)
		)
	)
	(zone
		(layers "B.Cu" "In4.Cu" "In6.Cu" "In11.Cu" "In13.Cu" "In15.Cu")
		(hatch none 0.5)
		(connect_pads
			(clearance 0)
		)
		(min_thickness 0.25)
		(keepout
			(tracks not_allowed)
			(vias allowed)
			(pads allowed)
			(copperpour not_allowed)
			(footprints allowed)
		)
		(placement
			(enabled no)
			(sheetname "")
		)
		(fill yes
			(thermal_gap 0.5)
			(thermal_bridge_width 0.5)
			(island_removal_mode 0)
		)
		(polygon
			(pts
				(arc
					(start 94.536006 -265.176254)
					(mid 93.906086 -265.176254)
					(end 94.536006 -265.176254)
				)
			)
		)
	)
	(zone
		(layers "B.Cu" "In4.Cu" "In6.Cu" "In11.Cu" "In13.Cu" "In15.Cu")
		(hatch none 0.5)
		(connect_pads
			(clearance 0)
		)
		(min_thickness 0.25)
		(keepout
			(tracks not_allowed)
			(vias allowed)
			(pads allowed)
			(copperpour not_allowed)
			(footprints allowed)
		)
		(placement
			(enabled no)
			(sheetname "")
		)
		(fill yes
			(thermal_gap 0.5)
			(thermal_bridge_width 0.5)
			(island_removal_mode 0)
		)
		(polygon
			(pts
				(arc
					(start 427.790102 -250.03506)
					(mid 427.122082 -250.03506)
					(end 427.790102 -250.03506)
				)
			)
		)
	)
	(zone
		(layers "B.Cu" "In4.Cu" "In6.Cu" "In11.Cu" "In13.Cu" "In15.Cu")
		(hatch none 0.5)
		(connect_pads
			(clearance 0)
		)
		(min_thickness 0.25)
		(keepout
			(tracks not_allowed)
			(vias allowed)
			(pads allowed)
			(copperpour not_allowed)
			(footprints allowed)
		)
		(placement
			(enabled no)
			(sheetname "")
		)
		(fill yes
			(thermal_gap 0.5)
			(thermal_bridge_width 0.5)
			(island_removal_mode 0)
		)
		(polygon
			(pts
				(arc
					(start 183.950102 -285.735268)
					(mid 183.282082 -285.735268)
					(end 183.950102 -285.735268)
				)
			)
		)
	)
	(zone
		(layers "B.Cu" "In4.Cu" "In6.Cu" "In11.Cu" "In13.Cu" "In15.Cu")
		(hatch none 0.5)
		(connect_pads
			(clearance 0)
		)
		(min_thickness 0.25)
		(keepout
			(tracks not_allowed)
			(vias allowed)
			(pads allowed)
			(copperpour not_allowed)
			(footprints allowed)
		)
		(placement
			(enabled no)
			(sheetname "")
		)
		(fill yes
			(thermal_gap 0.5)
			(thermal_bridge_width 0.5)
			(island_removal_mode 0)
		)
		(polygon
			(pts
				(arc
					(start 95.645986 -250.15444)
					(mid 95.016066 -250.15444)
					(end 95.645986 -250.15444)
				)
			)
		)
	)
	(zone
		(layers "B.Cu" "In4.Cu" "In6.Cu" "In11.Cu" "In13.Cu" "In15.Cu")
		(hatch none 0.5)
		(connect_pads
			(clearance 0)
		)
		(min_thickness 0.25)
		(keepout
			(tracks not_allowed)
			(vias allowed)
			(pads allowed)
			(copperpour not_allowed)
			(footprints allowed)
		)
		(placement
			(enabled no)
			(sheetname "")
		)
		(fill yes
			(thermal_gap 0.5)
			(thermal_bridge_width 0.5)
			(island_removal_mode 0)
		)
		(polygon
			(pts
				(arc
					(start 179.850034 -301.035212)
					(mid 179.182014 -301.035212)
					(end 179.850034 -301.035212)
				)
			)
		)
	)
	(zone
		(layers "B.Cu" "In4.Cu" "In6.Cu" "In11.Cu" "In13.Cu" "In15.Cu")
		(hatch none 0.5)
		(connect_pads
			(clearance 0)
		)
		(min_thickness 0.25)
		(keepout
			(tracks not_allowed)
			(vias allowed)
			(pads allowed)
			(copperpour not_allowed)
			(footprints allowed)
		)
		(placement
			(enabled no)
			(sheetname "")
		)
		(fill yes
			(thermal_gap 0.5)
			(thermal_bridge_width 0.5)
			(island_removal_mode 0)
		)
		(polygon
			(pts
				(arc
					(start 179.850034 -238.985298)
					(mid 179.182014 -238.985298)
					(end 179.850034 -238.985298)
				)
			)
		)
	)
	(zone
		(layers "B.Cu" "In4.Cu" "In6.Cu" "In11.Cu" "In13.Cu" "In15.Cu")
		(hatch none 0.5)
		(connect_pads
			(clearance 0)
		)
		(min_thickness 0.25)
		(keepout
			(tracks not_allowed)
			(vias allowed)
			(pads allowed)
			(copperpour not_allowed)
			(footprints allowed)
		)
		(placement
			(enabled no)
			(sheetname "")
		)
		(fill yes
			(thermal_gap 0.5)
			(thermal_bridge_width 0.5)
			(island_removal_mode 0)
		)
		(polygon
			(pts
				(arc
					(start 129.479802 -225.854514)
					(mid 128.849882 -225.854514)
					(end 129.479802 -225.854514)
				)
			)
		)
	)
	(zone
		(layers "B.Cu" "In4.Cu" "In6.Cu" "In11.Cu" "In13.Cu" "In15.Cu")
		(hatch none 0.5)
		(connect_pads
			(clearance 0)
		)
		(min_thickness 0.25)
		(keepout
			(tracks not_allowed)
			(vias allowed)
			(pads allowed)
			(copperpour not_allowed)
			(footprints allowed)
		)
		(placement
			(enabled no)
			(sheetname "")
		)
		(fill yes
			(thermal_gap 0.5)
			(thermal_bridge_width 0.5)
			(island_removal_mode 0)
		)
		(polygon
			(pts
				(arc
					(start 364.729776 -229.904036)
					(mid 364.099856 -229.904036)
					(end 364.729776 -229.904036)
				)
			)
		)
	)
	(zone
		(layers "B.Cu" "In4.Cu" "In6.Cu" "In11.Cu" "In13.Cu" "In15.Cu")
		(hatch none 0.5)
		(connect_pads
			(clearance 0)
		)
		(min_thickness 0.25)
		(keepout
			(tracks not_allowed)
			(vias allowed)
			(pads allowed)
			(copperpour not_allowed)
			(footprints allowed)
		)
		(placement
			(enabled no)
			(sheetname "")
		)
		(fill yes
			(thermal_gap 0.5)
			(thermal_bridge_width 0.5)
			(island_removal_mode 0)
		)
		(polygon
			(pts
				(arc
					(start 292.614096 -315.485018)
					(mid 291.946076 -315.485018)
					(end 292.614096 -315.485018)
				)
			)
		)
	)
	(zone
		(layers "B.Cu" "In4.Cu" "In6.Cu" "In11.Cu" "In13.Cu" "In15.Cu")
		(hatch none 0.5)
		(connect_pads
			(clearance 0)
		)
		(min_thickness 0.25)
		(keepout
			(tracks not_allowed)
			(vias allowed)
			(pads allowed)
			(copperpour not_allowed)
			(footprints allowed)
		)
		(placement
			(enabled no)
			(sheetname "")
		)
		(fill yes
			(thermal_gap 0.5)
			(thermal_bridge_width 0.5)
			(island_removal_mode 0)
		)
		(polygon
			(pts
				(arc
					(start 95.645986 -238.814356)
					(mid 95.016066 -238.814356)
					(end 95.645986 -238.814356)
				)
			)
		)
	)
	(zone
		(layers "B.Cu" "In4.Cu" "In6.Cu" "In11.Cu" "In13.Cu" "In15.Cu")
		(hatch none 0.5)
		(connect_pads
			(clearance 0)
		)
		(min_thickness 0.25)
		(keepout
			(tracks not_allowed)
			(vias allowed)
			(pads allowed)
			(copperpour not_allowed)
			(footprints allowed)
		)
		(placement
			(enabled no)
			(sheetname "")
		)
		(fill yes
			(thermal_gap 0.5)
			(thermal_bridge_width 0.5)
			(island_removal_mode 0)
		)
		(polygon
			(pts
				(arc
					(start 342.646 -243.674138)
					(mid 342.01608 -243.674138)
					(end 342.646 -243.674138)
				)
			)
		)
	)
	(zone
		(layers "B.Cu" "In4.Cu" "In6.Cu" "In11.Cu" "In13.Cu" "In15.Cu")
		(hatch none 0.5)
		(connect_pads
			(clearance 0)
		)
		(min_thickness 0.25)
		(keepout
			(tracks not_allowed)
			(vias allowed)
			(pads allowed)
			(copperpour not_allowed)
			(footprints allowed)
		)
		(placement
			(enabled no)
			(sheetname "")
		)
		(fill yes
			(thermal_gap 0.5)
			(thermal_bridge_width 0.5)
			(island_removal_mode 0)
		)
		(polygon
			(pts
				(arc
					(start 377.88977 -247.724168)
					(mid 377.25985 -247.724168)
					(end 377.88977 -247.724168)
				)
			)
		)
	)
	(zone
		(layers "B.Cu" "In4.Cu" "In6.Cu" "In11.Cu" "In13.Cu" "In15.Cu")
		(hatch none 0.5)
		(connect_pads
			(clearance 0)
		)
		(min_thickness 0.25)
		(keepout
			(tracks not_allowed)
			(vias allowed)
			(pads allowed)
			(copperpour not_allowed)
			(footprints allowed)
		)
		(placement
			(enabled no)
			(sheetname "")
		)
		(fill yes
			(thermal_gap 0.5)
			(thermal_bridge_width 0.5)
			(island_removal_mode 0)
		)
		(polygon
			(pts
				(arc
					(start 128.839722 -274.08632)
					(mid 128.209802 -274.08632)
					(end 128.839722 -274.08632)
				)
			)
		)
	)
	(zone
		(layers "B.Cu" "In4.Cu" "In6.Cu" "In11.Cu" "In13.Cu" "In15.Cu")
		(hatch none 0.5)
		(connect_pads
			(clearance 0)
		)
		(min_thickness 0.25)
		(keepout
			(tracks not_allowed)
			(vias allowed)
			(pads allowed)
			(copperpour not_allowed)
			(footprints allowed)
		)
		(placement
			(enabled no)
			(sheetname "")
		)
		(fill yes
			(thermal_gap 0.5)
			(thermal_bridge_width 0.5)
			(island_removal_mode 0)
		)
		(polygon
			(pts
				(arc
					(start 96.416114 -291.096192)
					(mid 95.786194 -291.096192)
					(end 96.416114 -291.096192)
				)
			)
		)
	)
	(zone
		(layers "B.Cu" "In4.Cu" "In6.Cu" "In11.Cu" "In13.Cu" "In15.Cu")
		(hatch none 0.5)
		(connect_pads
			(clearance 0)
		)
		(min_thickness 0.25)
		(keepout
			(tracks not_allowed)
			(vias allowed)
			(pads allowed)
			(copperpour not_allowed)
			(footprints allowed)
		)
		(placement
			(enabled no)
			(sheetname "")
		)
		(fill yes
			(thermal_gap 0.5)
			(thermal_bridge_width 0.5)
			(island_removal_mode 0)
		)
		(polygon
			(pts
				(arc
					(start 179.850034 -305.285394)
					(mid 179.182014 -305.285394)
					(end 179.850034 -305.285394)
				)
			)
		)
	)
	(zone
		(layers "B.Cu" "In4.Cu" "In6.Cu" "In11.Cu" "In13.Cu" "In15.Cu")
		(hatch none 0.5)
		(connect_pads
			(clearance 0)
		)
		(min_thickness 0.25)
		(keepout
			(tracks not_allowed)
			(vias allowed)
			(pads allowed)
			(copperpour not_allowed)
			(footprints allowed)
		)
		(placement
			(enabled no)
			(sheetname "")
		)
		(fill yes
			(thermal_gap 0.5)
			(thermal_bridge_width 0.5)
			(island_removal_mode 0)
		)
		(polygon
			(pts
				(arc
					(start 179.850034 -224.535238)
					(mid 179.182014 -224.535238)
					(end 179.850034 -224.535238)
				)
			)
		)
	)
	(zone
		(layers "B.Cu" "In4.Cu" "In6.Cu" "In11.Cu" "In13.Cu" "In15.Cu")
		(hatch none 0.5)
		(connect_pads
			(clearance 0)
		)
		(min_thickness 0.25)
		(keepout
			(tracks not_allowed)
			(vias allowed)
			(pads allowed)
			(copperpour not_allowed)
			(footprints allowed)
		)
		(placement
			(enabled no)
			(sheetname "")
		)
		(fill yes
			(thermal_gap 0.5)
			(thermal_bridge_width 0.5)
			(island_removal_mode 0)
		)
		(polygon
			(pts
				(arc
					(start 40.57396 -239.835436)
					(mid 39.90594 -239.835436)
					(end 40.57396 -239.835436)
				)
			)
		)
	)
	(zone
		(layers "B.Cu" "In4.Cu" "In6.Cu" "In11.Cu" "In13.Cu" "In15.Cu")
		(hatch none 0.5)
		(connect_pads
			(clearance 0)
		)
		(min_thickness 0.25)
		(keepout
			(tracks not_allowed)
			(vias allowed)
			(pads allowed)
			(copperpour not_allowed)
			(footprints allowed)
		)
		(placement
			(enabled no)
			(sheetname "")
		)
		(fill yes
			(thermal_gap 0.5)
			(thermal_bridge_width 0.5)
			(island_removal_mode 0)
		)
		(polygon
			(pts
				(arc
					(start 128.069594 -247.724422)
					(mid 127.439674 -247.724422)
					(end 128.069594 -247.724422)
				)
			)
		)
	)
	(zone
		(layers "B.Cu" "In4.Cu" "In6.Cu" "In11.Cu" "In13.Cu" "In15.Cu")
		(hatch none 0.5)
		(connect_pads
			(clearance 0)
		)
		(min_thickness 0.25)
		(keepout
			(tracks not_allowed)
			(vias allowed)
			(pads allowed)
			(copperpour not_allowed)
			(footprints allowed)
		)
		(placement
			(enabled no)
			(sheetname "")
		)
		(fill yes
			(thermal_gap 0.5)
			(thermal_bridge_width 0.5)
			(island_removal_mode 0)
		)
		(polygon
			(pts
				(arc
					(start 344.356182 -266.796012)
					(mid 343.726262 -266.796012)
					(end 344.356182 -266.796012)
				)
			)
		)
	)
	(zone
		(layers "B.Cu" "In4.Cu" "In6.Cu" "In11.Cu" "In13.Cu" "In15.Cu")
		(hatch none 0.5)
		(connect_pads
			(clearance 0)
		)
		(min_thickness 0.25)
		(keepout
			(tracks not_allowed)
			(vias allowed)
			(pads allowed)
			(copperpour not_allowed)
			(footprints allowed)
		)
		(placement
			(enabled no)
			(sheetname "")
		)
		(fill yes
			(thermal_gap 0.5)
			(thermal_bridge_width 0.5)
			(island_removal_mode 0)
		)
		(polygon
			(pts
				(arc
					(start 183.950102 -262.785352)
					(mid 183.282082 -262.785352)
					(end 183.950102 -262.785352)
				)
			)
		)
	)
	(zone
		(layers "B.Cu" "In4.Cu" "In6.Cu" "In11.Cu" "In13.Cu" "In15.Cu")
		(hatch none 0.5)
		(connect_pads
			(clearance 0)
		)
		(min_thickness 0.25)
		(keepout
			(tracks not_allowed)
			(vias allowed)
			(pads allowed)
			(copperpour not_allowed)
			(footprints allowed)
		)
		(placement
			(enabled no)
			(sheetname "")
		)
		(fill yes
			(thermal_gap 0.5)
			(thermal_bridge_width 0.5)
			(island_removal_mode 0)
		)
		(polygon
			(pts
				(arc
					(start 106.455972 -226.66452)
					(mid 105.826052 -226.66452)
					(end 106.455972 -226.66452)
				)
			)
		)
	)
	(zone
		(layers "B.Cu" "In4.Cu" "In6.Cu" "In11.Cu" "In13.Cu" "In15.Cu")
		(hatch none 0.5)
		(connect_pads
			(clearance 0)
		)
		(min_thickness 0.25)
		(keepout
			(tracks not_allowed)
			(vias allowed)
			(pads allowed)
			(copperpour not_allowed)
			(footprints allowed)
		)
		(placement
			(enabled no)
			(sheetname "")
		)
		(fill yes
			(thermal_gap 0.5)
			(thermal_bridge_width 0.5)
			(island_removal_mode 0)
		)
		(polygon
			(pts
				(arc
					(start 377.719844 -291.905944)
					(mid 377.089924 -291.905944)
					(end 377.719844 -291.905944)
				)
			)
		)
	)
	(zone
		(layers "B.Cu" "In4.Cu" "In6.Cu" "In11.Cu" "In13.Cu" "In15.Cu")
		(hatch none 0.5)
		(connect_pads
			(clearance 0)
		)
		(min_thickness 0.25)
		(keepout
			(tracks not_allowed)
			(vias allowed)
			(pads allowed)
			(copperpour not_allowed)
			(footprints allowed)
		)
		(placement
			(enabled no)
			(sheetname "")
		)
		(fill yes
			(thermal_gap 0.5)
			(thermal_bridge_width 0.5)
			(island_removal_mode 0)
		)
		(polygon
			(pts
				(arc
					(start 427.790102 -276.38502)
					(mid 427.122082 -276.38502)
					(end 427.790102 -276.38502)
				)
			)
		)
	)
	(zone
		(layers "B.Cu" "In4.Cu" "In6.Cu" "In11.Cu" "In13.Cu" "In15.Cu")
		(hatch none 0.5)
		(connect_pads
			(clearance 0)
		)
		(min_thickness 0.25)
		(keepout
			(tracks not_allowed)
			(vias allowed)
			(pads allowed)
			(copperpour not_allowed)
			(footprints allowed)
		)
		(placement
			(enabled no)
			(sheetname "")
		)
		(fill yes
			(thermal_gap 0.5)
			(thermal_bridge_width 0.5)
			(island_removal_mode 0)
		)
		(polygon
			(pts
				(arc
					(start 288.514028 -233.884978)
					(mid 287.846008 -233.884978)
					(end 288.514028 -233.884978)
				)
			)
		)
	)
	(zone
		(layers "B.Cu" "In4.Cu" "In6.Cu" "In11.Cu" "In13.Cu" "In15.Cu")
		(hatch none 0.5)
		(connect_pads
			(clearance 0)
		)
		(min_thickness 0.25)
		(keepout
			(tracks not_allowed)
			(vias allowed)
			(pads allowed)
			(copperpour not_allowed)
			(footprints allowed)
		)
		(placement
			(enabled no)
			(sheetname "")
		)
		(fill yes
			(thermal_gap 0.5)
			(thermal_bridge_width 0.5)
			(island_removal_mode 0)
		)
		(polygon
			(pts
				(arc
					(start 292.614096 -261.085076)
					(mid 291.946076 -261.085076)
					(end 292.614096 -261.085076)
				)
			)
		)
	)
	(zone
		(layers "B.Cu" "In4.Cu" "In6.Cu" "In11.Cu" "In13.Cu" "In15.Cu")
		(hatch none 0.5)
		(connect_pads
			(clearance 0)
		)
		(min_thickness 0.25)
		(keepout
			(tracks not_allowed)
			(vias allowed)
			(pads allowed)
			(copperpour not_allowed)
			(footprints allowed)
		)
		(placement
			(enabled no)
			(sheetname "")
		)
		(fill yes
			(thermal_gap 0.5)
			(thermal_bridge_width 0.5)
			(island_removal_mode 0)
		)
		(polygon
			(pts
				(arc
					(start 101.755956 -228.284532)
					(mid 101.126036 -228.284532)
					(end 101.755956 -228.284532)
				)
			)
		)
	)
	(zone
		(layers "B.Cu" "In4.Cu" "In6.Cu" "In11.Cu" "In13.Cu" "In15.Cu")
		(hatch none 0.5)
		(connect_pads
			(clearance 0)
		)
		(min_thickness 0.25)
		(keepout
			(tracks not_allowed)
			(vias allowed)
			(pads allowed)
			(copperpour not_allowed)
			(footprints allowed)
		)
		(placement
			(enabled no)
			(sheetname "")
		)
		(fill yes
			(thermal_gap 0.5)
			(thermal_bridge_width 0.5)
			(island_removal_mode 0)
		)
		(polygon
			(pts
				(arc
					(start 367.549684 -228.284278)
					(mid 366.919764 -228.284278)
					(end 367.549684 -228.284278)
				)
			)
		)
	)
	(zone
		(layers "B.Cu" "In4.Cu" "In6.Cu" "In11.Cu" "In13.Cu" "In15.Cu")
		(hatch none 0.5)
		(connect_pads
			(clearance 0)
		)
		(min_thickness 0.25)
		(keepout
			(tracks not_allowed)
			(vias allowed)
			(pads allowed)
			(copperpour not_allowed)
			(footprints allowed)
		)
		(placement
			(enabled no)
			(sheetname "")
		)
		(fill yes
			(thermal_gap 0.5)
			(thermal_bridge_width 0.5)
			(island_removal_mode 0)
		)
		(polygon
			(pts
				(arc
					(start 288.514028 -243.234972)
					(mid 287.846008 -243.234972)
					(end 288.514028 -243.234972)
				)
			)
		)
	)
	(zone
		(layers "B.Cu" "In4.Cu" "In6.Cu" "In11.Cu" "In13.Cu" "In15.Cu")
		(hatch none 0.5)
		(connect_pads
			(clearance 0)
		)
		(min_thickness 0.25)
		(keepout
			(tracks not_allowed)
			(vias allowed)
			(pads allowed)
			(copperpour not_allowed)
			(footprints allowed)
		)
		(placement
			(enabled no)
			(sheetname "")
		)
		(fill yes
			(thermal_gap 0.5)
			(thermal_bridge_width 0.5)
			(island_removal_mode 0)
		)
		(polygon
			(pts
				(arc
					(start 377.719844 -262.745982)
					(mid 377.089924 -262.745982)
					(end 377.719844 -262.745982)
				)
			)
		)
	)
	(zone
		(layers "B.Cu" "In4.Cu" "In6.Cu" "In11.Cu" "In13.Cu" "In15.Cu")
		(hatch none 0.5)
		(connect_pads
			(clearance 0)
		)
		(min_thickness 0.25)
		(keepout
			(tracks not_allowed)
			(vias allowed)
			(pads allowed)
			(copperpour not_allowed)
			(footprints allowed)
		)
		(placement
			(enabled no)
			(sheetname "")
		)
		(fill yes
			(thermal_gap 0.5)
			(thermal_bridge_width 0.5)
			(island_removal_mode 0)
		)
		(polygon
			(pts
				(arc
					(start 129.949702 -242.864386)
					(mid 129.319782 -242.864386)
					(end 129.949702 -242.864386)
				)
			)
		)
	)
	(zone
		(layers "B.Cu" "In4.Cu" "In6.Cu" "In11.Cu" "In13.Cu" "In15.Cu")
		(hatch none 0.5)
		(connect_pads
			(clearance 0)
		)
		(min_thickness 0.25)
		(keepout
			(tracks not_allowed)
			(vias allowed)
			(pads allowed)
			(copperpour not_allowed)
			(footprints allowed)
		)
		(placement
			(enabled no)
			(sheetname "")
		)
		(fill yes
			(thermal_gap 0.5)
			(thermal_bridge_width 0.5)
			(island_removal_mode 0)
		)
		(polygon
			(pts
				(arc
					(start 179.345844 -48.61814)
					(mid 178.677824 -48.61814)
					(end 179.345844 -48.61814)
				)
			)
		)
	)
	(zone
		(layers "B.Cu" "In4.Cu" "In6.Cu" "In11.Cu" "In13.Cu" "In15.Cu")
		(hatch none 0.5)
		(connect_pads
			(clearance 0)
		)
		(min_thickness 0.25)
		(keepout
			(tracks not_allowed)
			(vias allowed)
			(pads allowed)
			(copperpour not_allowed)
			(footprints allowed)
		)
		(placement
			(enabled no)
			(sheetname "")
		)
		(fill yes
			(thermal_gap 0.5)
			(thermal_bridge_width 0.5)
			(island_removal_mode 0)
		)
		(polygon
			(pts
				(arc
					(start 95.005906 -278.946356)
					(mid 94.375986 -278.946356)
					(end 95.005906 -278.946356)
				)
			)
		)
	)
	(zone
		(layers "B.Cu" "In4.Cu" "In6.Cu" "In11.Cu" "In13.Cu" "In15.Cu")
		(hatch none 0.5)
		(connect_pads
			(clearance 0)
		)
		(min_thickness 0.25)
		(keepout
			(tracks not_allowed)
			(vias allowed)
			(pads allowed)
			(copperpour not_allowed)
			(footprints allowed)
		)
		(placement
			(enabled no)
			(sheetname "")
		)
		(fill yes
			(thermal_gap 0.5)
			(thermal_bridge_width 0.5)
			(island_removal_mode 0)
		)
		(polygon
			(pts
				(arc
					(start 288.514028 -272.984976)
					(mid 287.846008 -272.984976)
					(end 288.514028 -272.984976)
				)
			)
		)
	)
	(zone
		(layers "B.Cu" "In4.Cu" "In6.Cu" "In11.Cu" "In13.Cu" "In15.Cu")
		(hatch none 0.5)
		(connect_pads
			(clearance 0)
		)
		(min_thickness 0.25)
		(keepout
			(tracks not_allowed)
			(vias allowed)
			(pads allowed)
			(copperpour not_allowed)
			(footprints allowed)
		)
		(placement
			(enabled no)
			(sheetname "")
		)
		(fill yes
			(thermal_gap 0.5)
			(thermal_bridge_width 0.5)
			(island_removal_mode 0)
		)
		(polygon
			(pts
				(arc
					(start 370.369846 -229.904036)
					(mid 369.739926 -229.904036)
					(end 370.369846 -229.904036)
				)
			)
		)
	)
	(zone
		(layers "B.Cu" "In4.Cu" "In6.Cu" "In11.Cu" "In13.Cu" "In15.Cu")
		(hatch none 0.5)
		(connect_pads
			(clearance 0)
		)
		(min_thickness 0.25)
		(keepout
			(tracks not_allowed)
			(vias allowed)
			(pads allowed)
			(copperpour not_allowed)
			(footprints allowed)
		)
		(placement
			(enabled no)
			(sheetname "")
		)
		(fill yes
			(thermal_gap 0.5)
			(thermal_bridge_width 0.5)
			(island_removal_mode 0)
		)
		(polygon
			(pts
				(arc
					(start 377.719844 -285.42615)
					(mid 377.089924 -285.42615)
					(end 377.719844 -285.42615)
				)
			)
		)
	)
	(zone
		(layers "B.Cu" "In4.Cu" "In6.Cu" "In11.Cu" "In13.Cu" "In15.Cu")
		(hatch none 0.5)
		(connect_pads
			(clearance 0)
		)
		(min_thickness 0.25)
		(keepout
			(tracks not_allowed)
			(vias allowed)
			(pads allowed)
			(copperpour not_allowed)
			(footprints allowed)
		)
		(placement
			(enabled no)
			(sheetname "")
		)
		(fill yes
			(thermal_gap 0.5)
			(thermal_bridge_width 0.5)
			(island_removal_mode 0)
		)
		(polygon
			(pts
				(arc
					(start 342.646 -256.634234)
					(mid 342.01608 -256.634234)
					(end 342.646 -256.634234)
				)
			)
		)
	)
	(zone
		(layers "B.Cu" "In4.Cu" "In6.Cu" "In11.Cu" "In13.Cu" "In15.Cu")
		(hatch none 0.5)
		(connect_pads
			(clearance 0)
		)
		(min_thickness 0.25)
		(keepout
			(tracks not_allowed)
			(vias allowed)
			(pads allowed)
			(copperpour not_allowed)
			(footprints allowed)
		)
		(placement
			(enabled no)
			(sheetname "")
		)
		(fill yes
			(thermal_gap 0.5)
			(thermal_bridge_width 0.5)
			(island_removal_mode 0)
		)
		(polygon
			(pts
				(arc
					(start 94.536006 -270.03629)
					(mid 93.906086 -270.03629)
					(end 94.536006 -270.03629)
				)
			)
		)
	)
	(zone
		(layers "B.Cu" "In4.Cu" "In6.Cu" "In11.Cu" "In13.Cu" "In15.Cu")
		(hatch none 0.5)
		(connect_pads
			(clearance 0)
		)
		(min_thickness 0.25)
		(keepout
			(tracks not_allowed)
			(vias allowed)
			(pads allowed)
			(copperpour not_allowed)
			(footprints allowed)
		)
		(placement
			(enabled no)
			(sheetname "")
		)
		(fill yes
			(thermal_gap 0.5)
			(thermal_bridge_width 0.5)
			(island_removal_mode 0)
		)
		(polygon
			(pts
				(arc
					(start 292.614096 -216.035128)
					(mid 291.946076 -216.035128)
					(end 292.614096 -216.035128)
				)
			)
		)
	)
	(zone
		(layers "B.Cu" "In4.Cu" "In6.Cu" "In11.Cu" "In13.Cu" "In15.Cu")
		(hatch none 0.5)
		(connect_pads
			(clearance 0)
		)
		(min_thickness 0.25)
		(keepout
			(tracks not_allowed)
			(vias allowed)
			(pads allowed)
			(copperpour not_allowed)
			(footprints allowed)
		)
		(placement
			(enabled no)
			(sheetname "")
		)
		(fill yes
			(thermal_gap 0.5)
			(thermal_bridge_width 0.5)
			(island_removal_mode 0)
		)
		(polygon
			(pts
				(arc
					(start 40.57396 -229.635304)
					(mid 39.90594 -229.635304)
					(end 40.57396 -229.635304)
				)
			)
		)
	)
	(zone
		(layers "B.Cu" "In4.Cu" "In6.Cu" "In11.Cu" "In13.Cu" "In15.Cu")
		(hatch none 0.5)
		(connect_pads
			(clearance 0)
		)
		(min_thickness 0.25)
		(keepout
			(tracks not_allowed)
			(vias allowed)
			(pads allowed)
			(copperpour not_allowed)
			(footprints allowed)
		)
		(placement
			(enabled no)
			(sheetname "")
		)
		(fill yes
			(thermal_gap 0.5)
			(thermal_bridge_width 0.5)
			(island_removal_mode 0)
		)
		(polygon
			(pts
				(arc
					(start 427.790102 -299.33519)
					(mid 427.122082 -299.33519)
					(end 427.790102 -299.33519)
				)
			)
		)
	)
	(zone
		(layers "B.Cu" "In4.Cu" "In6.Cu" "In11.Cu" "In13.Cu" "In15.Cu")
		(hatch none 0.5)
		(connect_pads
			(clearance 0)
		)
		(min_thickness 0.25)
		(keepout
			(tracks not_allowed)
			(vias allowed)
			(pads allowed)
			(copperpour not_allowed)
			(footprints allowed)
		)
		(placement
			(enabled no)
			(sheetname "")
		)
		(fill yes
			(thermal_gap 0.5)
			(thermal_bridge_width 0.5)
			(island_removal_mode 0)
		)
		(polygon
			(pts
				(arc
					(start 95.645986 -255.014476)
					(mid 95.016066 -255.014476)
					(end 95.645986 -255.014476)
				)
			)
		)
	)
	(zone
		(layers "B.Cu" "In4.Cu" "In6.Cu" "In11.Cu" "In13.Cu" "In15.Cu")
		(hatch none 0.5)
		(connect_pads
			(clearance 0)
		)
		(min_thickness 0.25)
		(keepout
			(tracks not_allowed)
			(vias allowed)
			(pads allowed)
			(copperpour not_allowed)
			(footprints allowed)
		)
		(placement
			(enabled no)
			(sheetname "")
		)
		(fill yes
			(thermal_gap 0.5)
			(thermal_bridge_width 0.5)
			(island_removal_mode 0)
		)
		(polygon
			(pts
				(arc
					(start 288.514028 -210.935062)
					(mid 287.846008 -210.935062)
					(end 288.514028 -210.935062)
				)
			)
		)
	)
	(zone
		(layers "B.Cu" "In4.Cu" "In6.Cu" "In11.Cu" "In13.Cu" "In15.Cu")
		(hatch none 0.5)
		(connect_pads
			(clearance 0)
		)
		(min_thickness 0.25)
		(keepout
			(tracks not_allowed)
			(vias allowed)
			(pads allowed)
			(copperpour not_allowed)
			(footprints allowed)
		)
		(placement
			(enabled no)
			(sheetname "")
		)
		(fill yes
			(thermal_gap 0.5)
			(thermal_bridge_width 0.5)
			(island_removal_mode 0)
		)
		(polygon
			(pts
				(arc
					(start 292.614096 -238.985044)
					(mid 291.946076 -238.985044)
					(end 292.614096 -238.985044)
				)
			)
		)
	)
	(zone
		(layers "B.Cu" "In4.Cu" "In6.Cu" "In11.Cu" "In13.Cu" "In15.Cu")
		(hatch none 0.5)
		(connect_pads
			(clearance 0)
		)
		(min_thickness 0.25)
		(keepout
			(tracks not_allowed)
			(vias allowed)
			(pads allowed)
			(copperpour not_allowed)
			(footprints allowed)
		)
		(placement
			(enabled no)
			(sheetname "")
		)
		(fill yes
			(thermal_gap 0.5)
			(thermal_bridge_width 0.5)
			(island_removal_mode 0)
		)
		(polygon
			(pts
				(arc
					(start 95.94596 -285.426404)
					(mid 95.31604 -285.426404)
					(end 95.94596 -285.426404)
				)
			)
		)
	)
	(zone
		(layers "B.Cu" "In4.Cu" "In6.Cu" "In11.Cu" "In13.Cu" "In15.Cu")
		(hatch none 0.5)
		(connect_pads
			(clearance 0)
		)
		(min_thickness 0.25)
		(keepout
			(tracks not_allowed)
			(vias allowed)
			(pads allowed)
			(copperpour not_allowed)
			(footprints allowed)
		)
		(placement
			(enabled no)
			(sheetname "")
		)
		(fill yes
			(thermal_gap 0.5)
			(thermal_bridge_width 0.5)
			(island_removal_mode 0)
		)
		(polygon
			(pts
				(arc
					(start 94.236032 -229.90429)
					(mid 93.606112 -229.90429)
					(end 94.236032 -229.90429)
				)
			)
		)
	)
	(zone
		(layers "B.Cu" "In4.Cu" "In6.Cu" "In11.Cu" "In13.Cu" "In15.Cu")
		(hatch none 0.5)
		(connect_pads
			(clearance 0)
		)
		(min_thickness 0.25)
		(keepout
			(tracks not_allowed)
			(vias allowed)
			(pads allowed)
			(copperpour not_allowed)
			(footprints allowed)
		)
		(placement
			(enabled no)
			(sheetname "")
		)
		(fill yes
			(thermal_gap 0.5)
			(thermal_bridge_width 0.5)
			(island_removal_mode 0)
		)
		(polygon
			(pts
				(arc
					(start 128.369822 -289.47618)
					(mid 127.739902 -289.47618)
					(end 128.369822 -289.47618)
				)
			)
		)
	)
	(zone
		(layers "B.Cu" "In4.Cu" "In6.Cu" "In11.Cu" "In13.Cu" "In15.Cu")
		(hatch none 0.5)
		(connect_pads
			(clearance 0)
		)
		(min_thickness 0.25)
		(keepout
			(tracks not_allowed)
			(vias allowed)
			(pads allowed)
			(copperpour not_allowed)
			(footprints allowed)
		)
		(placement
			(enabled no)
			(sheetname "")
		)
		(fill yes
			(thermal_gap 0.5)
			(thermal_bridge_width 0.5)
			(island_removal_mode 0)
		)
		(polygon
			(pts
				(arc
					(start 40.57396 -220.28531)
					(mid 39.90594 -220.28531)
					(end 40.57396 -220.28531)
				)
			)
		)
	)
	(zone
		(layers "B.Cu" "In4.Cu" "In6.Cu" "In11.Cu" "In13.Cu" "In15.Cu")
		(hatch none 0.5)
		(connect_pads
			(clearance 0)
		)
		(min_thickness 0.25)
		(keepout
			(tracks not_allowed)
			(vias allowed)
			(pads allowed)
			(copperpour not_allowed)
			(footprints allowed)
		)
		(placement
			(enabled no)
			(sheetname "")
		)
		(fill yes
			(thermal_gap 0.5)
			(thermal_bridge_width 0.5)
			(island_removal_mode 0)
		)
		(polygon
			(pts
				(arc
					(start 292.614096 -210.085178)
					(mid 291.946076 -210.085178)
					(end 292.614096 -210.085178)
				)
			)
		)
	)
	(zone
		(layers "B.Cu" "In4.Cu" "In6.Cu" "In11.Cu" "In13.Cu" "In15.Cu")
		(hatch none 0.5)
		(connect_pads
			(clearance 0)
		)
		(min_thickness 0.25)
		(keepout
			(tracks not_allowed)
			(vias allowed)
			(pads allowed)
			(copperpour not_allowed)
			(footprints allowed)
		)
		(placement
			(enabled no)
			(sheetname "")
		)
		(fill yes
			(thermal_gap 0.5)
			(thermal_bridge_width 0.5)
			(island_removal_mode 0)
		)
		(polygon
			(pts
				(arc
					(start 376.30989 -265.176)
					(mid 375.67997 -265.176)
					(end 376.30989 -265.176)
				)
			)
		)
	)
	(zone
		(layers "B.Cu" "In4.Cu" "In6.Cu" "In11.Cu" "In13.Cu" "In15.Cu")
		(hatch none 0.5)
		(connect_pads
			(clearance 0)
		)
		(min_thickness 0.25)
		(keepout
			(tracks not_allowed)
			(vias allowed)
			(pads allowed)
			(copperpour not_allowed)
			(footprints allowed)
		)
		(placement
			(enabled no)
			(sheetname "")
		)
		(fill yes
			(thermal_gap 0.5)
			(thermal_bridge_width 0.5)
			(island_removal_mode 0)
		)
		(polygon
			(pts
				(arc
					(start 179.345844 -51.618134)
					(mid 178.677824 -51.618134)
					(end 179.345844 -51.618134)
				)
			)
		)
	)
	(zone
		(layers "B.Cu" "In4.Cu" "In6.Cu" "In11.Cu" "In13.Cu" "In15.Cu")
		(hatch none 0.5)
		(connect_pads
			(clearance 0)
		)
		(min_thickness 0.25)
		(keepout
			(tracks not_allowed)
			(vias allowed)
			(pads allowed)
			(copperpour not_allowed)
			(footprints allowed)
		)
		(placement
			(enabled no)
			(sheetname "")
		)
		(fill yes
			(thermal_gap 0.5)
			(thermal_bridge_width 0.5)
			(island_removal_mode 0)
		)
		(polygon
			(pts
				(arc
					(start 94.536006 -274.896326)
					(mid 93.906086 -274.896326)
					(end 94.536006 -274.896326)
				)
			)
		)
	)
	(zone
		(layers "B.Cu" "In4.Cu" "In6.Cu" "In11.Cu" "In13.Cu" "In15.Cu")
		(hatch none 0.5)
		(connect_pads
			(clearance 0)
		)
		(min_thickness 0.25)
		(keepout
			(tracks not_allowed)
			(vias allowed)
			(pads allowed)
			(copperpour not_allowed)
			(footprints allowed)
		)
		(placement
			(enabled no)
			(sheetname "")
		)
		(fill yes
			(thermal_gap 0.5)
			(thermal_bridge_width 0.5)
			(island_removal_mode 0)
		)
		(polygon
			(pts
				(arc
					(start 376.479816 -227.474272)
					(mid 375.849896 -227.474272)
					(end 376.479816 -227.474272)
				)
			)
		)
	)
	(zone
		(layers "B.Cu" "In4.Cu" "In6.Cu" "In11.Cu" "In13.Cu" "In15.Cu")
		(hatch none 0.5)
		(connect_pads
			(clearance 0)
		)
		(min_thickness 0.25)
		(keepout
			(tracks not_allowed)
			(vias allowed)
			(pads allowed)
			(copperpour not_allowed)
			(footprints allowed)
		)
		(placement
			(enabled no)
			(sheetname "")
		)
		(fill yes
			(thermal_gap 0.5)
			(thermal_bridge_width 0.5)
			(island_removal_mode 0)
		)
		(polygon
			(pts
				(arc
					(start 292.614096 -313.784996)
					(mid 291.946076 -313.784996)
					(end 292.614096 -313.784996)
				)
			)
		)
	)
	(zone
		(layers "B.Cu" "In4.Cu" "In6.Cu" "In11.Cu" "In13.Cu" "In15.Cu")
		(hatch none 0.5)
		(connect_pads
			(clearance 0)
		)
		(min_thickness 0.25)
		(keepout
			(tracks not_allowed)
			(vias allowed)
			(pads allowed)
			(copperpour not_allowed)
			(footprints allowed)
		)
		(placement
			(enabled no)
			(sheetname "")
		)
		(fill yes
			(thermal_gap 0.5)
			(thermal_bridge_width 0.5)
			(island_removal_mode 0)
		)
		(polygon
			(pts
				(arc
					(start 128.539748 -243.674392)
					(mid 127.909828 -243.674392)
					(end 128.539748 -243.674392)
				)
			)
		)
	)
	(zone
		(layers "B.Cu" "In4.Cu" "In6.Cu" "In11.Cu" "In13.Cu" "In15.Cu")
		(hatch none 0.5)
		(connect_pads
			(clearance 0)
		)
		(min_thickness 0.25)
		(keepout
			(tracks not_allowed)
			(vias allowed)
			(pads allowed)
			(copperpour not_allowed)
			(footprints allowed)
		)
		(placement
			(enabled no)
			(sheetname "")
		)
		(fill yes
			(thermal_gap 0.5)
			(thermal_bridge_width 0.5)
			(island_removal_mode 0)
		)
		(polygon
			(pts
				(arc
					(start 427.790102 -230.485188)
					(mid 427.122082 -230.485188)
					(end 427.790102 -230.485188)
				)
			)
		)
	)
	(zone
		(layers "B.Cu" "In4.Cu" "In6.Cu" "In11.Cu" "In13.Cu" "In15.Cu")
		(hatch none 0.5)
		(connect_pads
			(clearance 0)
		)
		(min_thickness 0.25)
		(keepout
			(tracks not_allowed)
			(vias allowed)
			(pads allowed)
			(copperpour not_allowed)
			(footprints allowed)
		)
		(placement
			(enabled no)
			(sheetname "")
		)
		(fill yes
			(thermal_gap 0.5)
			(thermal_bridge_width 0.5)
			(island_removal_mode 0)
		)
		(polygon
			(pts
				(arc
					(start 377.41987 -240.434114)
					(mid 376.78995 -240.434114)
					(end 377.41987 -240.434114)
				)
			)
		)
	)
	(zone
		(layers "B.Cu" "In4.Cu" "In6.Cu" "In11.Cu" "In13.Cu" "In15.Cu")
		(hatch none 0.5)
		(connect_pads
			(clearance 0)
		)
		(min_thickness 0.25)
		(keepout
			(tracks not_allowed)
			(vias allowed)
			(pads allowed)
			(copperpour not_allowed)
			(footprints allowed)
		)
		(placement
			(enabled no)
			(sheetname "")
		)
		(fill yes
			(thermal_gap 0.5)
			(thermal_bridge_width 0.5)
			(island_removal_mode 0)
		)
		(polygon
			(pts
				(arc
					(start 128.369822 -276.516338)
					(mid 127.739902 -276.516338)
					(end 128.369822 -276.516338)
				)
			)
		)
	)
	(zone
		(layers "B.Cu" "In4.Cu" "In6.Cu" "In11.Cu" "In13.Cu" "In15.Cu")
		(hatch none 0.5)
		(connect_pads
			(clearance 0)
		)
		(min_thickness 0.25)
		(keepout
			(tracks not_allowed)
			(vias allowed)
			(pads allowed)
			(copperpour not_allowed)
			(footprints allowed)
		)
		(placement
			(enabled no)
			(sheetname "")
		)
		(fill yes
			(thermal_gap 0.5)
			(thermal_bridge_width 0.5)
			(island_removal_mode 0)
		)
		(polygon
			(pts
				(arc
					(start 128.539748 -255.014476)
					(mid 127.909828 -255.014476)
					(end 128.539748 -255.014476)
				)
			)
		)
	)
	(zone
		(layers "B.Cu" "In4.Cu" "In6.Cu" "In11.Cu" "In13.Cu" "In15.Cu")
		(hatch none 0.5)
		(connect_pads
			(clearance 0)
		)
		(min_thickness 0.25)
		(keepout
			(tracks not_allowed)
			(vias allowed)
			(pads allowed)
			(copperpour not_allowed)
			(footprints allowed)
		)
		(placement
			(enabled no)
			(sheetname "")
		)
		(fill yes
			(thermal_gap 0.5)
			(thermal_bridge_width 0.5)
			(island_removal_mode 0)
		)
		(polygon
			(pts
				(arc
					(start 95.645986 -230.71455)
					(mid 95.016066 -230.71455)
					(end 95.645986 -230.71455)
				)
			)
		)
	)
	(zone
		(layers "B.Cu" "In4.Cu" "In6.Cu" "In11.Cu" "In13.Cu" "In15.Cu")
		(hatch none 0.5)
		(connect_pads
			(clearance 0)
		)
		(min_thickness 0.25)
		(keepout
			(tracks not_allowed)
			(vias allowed)
			(pads allowed)
			(copperpour not_allowed)
			(footprints allowed)
		)
		(placement
			(enabled no)
			(sheetname "")
		)
		(fill yes
			(thermal_gap 0.5)
			(thermal_bridge_width 0.5)
			(island_removal_mode 0)
		)
		(polygon
			(pts
				(arc
					(start 95.645986 -248.534428)
					(mid 95.016066 -248.534428)
					(end 95.645986 -248.534428)
				)
			)
		)
	)
	(zone
		(layers "B.Cu" "In4.Cu" "In6.Cu" "In11.Cu" "In13.Cu" "In15.Cu")
		(hatch none 0.5)
		(connect_pads
			(clearance 0)
		)
		(min_thickness 0.25)
		(keepout
			(tracks not_allowed)
			(vias allowed)
			(pads allowed)
			(copperpour not_allowed)
			(footprints allowed)
		)
		(placement
			(enabled no)
			(sheetname "")
		)
		(fill yes
			(thermal_gap 0.5)
			(thermal_bridge_width 0.5)
			(island_removal_mode 0)
		)
		(polygon
			(pts
				(arc
					(start 44.674028 -229.635304)
					(mid 44.006008 -229.635304)
					(end 44.674028 -229.635304)
				)
			)
		)
	)
	(zone
		(layers "B.Cu" "In4.Cu" "In6.Cu" "In11.Cu" "In13.Cu" "In15.Cu")
		(hatch none 0.5)
		(connect_pads
			(clearance 0)
		)
		(min_thickness 0.25)
		(keepout
			(tracks not_allowed)
			(vias allowed)
			(pads allowed)
			(copperpour not_allowed)
			(footprints allowed)
		)
		(placement
			(enabled no)
			(sheetname "")
		)
		(fill yes
			(thermal_gap 0.5)
			(thermal_bridge_width 0.5)
			(island_removal_mode 0)
		)
		(polygon
			(pts
				(arc
					(start 370.369846 -226.664266)
					(mid 369.739926 -226.664266)
					(end 370.369846 -226.664266)
				)
			)
		)
	)
	(zone
		(layers "B.Cu" "In4.Cu" "In6.Cu" "In11.Cu" "In13.Cu" "In15.Cu")
		(hatch none 0.5)
		(connect_pads
			(clearance 0)
		)
		(min_thickness 0.25)
		(keepout
			(tracks not_allowed)
			(vias allowed)
			(pads allowed)
			(copperpour not_allowed)
			(footprints allowed)
		)
		(placement
			(enabled no)
			(sheetname "")
		)
		(fill yes
			(thermal_gap 0.5)
			(thermal_bridge_width 0.5)
			(island_removal_mode 0)
		)
		(polygon
			(pts
				(arc
					(start 95.005906 -277.326344)
					(mid 94.375986 -277.326344)
					(end 95.005906 -277.326344)
				)
			)
		)
	)
	(zone
		(layers "B.Cu" "In4.Cu" "In6.Cu" "In11.Cu" "In13.Cu" "In15.Cu")
		(hatch none 0.5)
		(connect_pads
			(clearance 0)
		)
		(min_thickness 0.25)
		(keepout
			(tracks not_allowed)
			(vias allowed)
			(pads allowed)
			(copperpour not_allowed)
			(footprints allowed)
		)
		(placement
			(enabled no)
			(sheetname "")
		)
		(fill yes
			(thermal_gap 0.5)
			(thermal_bridge_width 0.5)
			(island_removal_mode 0)
		)
		(polygon
			(pts
				(arc
					(start 44.674028 -221.985332)
					(mid 44.006008 -221.985332)
					(end 44.674028 -221.985332)
				)
			)
		)
	)
	(zone
		(layers "B.Cu" "In4.Cu" "In6.Cu" "In11.Cu" "In13.Cu" "In15.Cu")
		(hatch none 0.5)
		(connect_pads
			(clearance 0)
		)
		(min_thickness 0.25)
		(keepout
			(tracks not_allowed)
			(vias allowed)
			(pads allowed)
			(copperpour not_allowed)
			(footprints allowed)
		)
		(placement
			(enabled no)
			(sheetname "")
		)
		(fill yes
			(thermal_gap 0.5)
			(thermal_bridge_width 0.5)
			(island_removal_mode 0)
		)
		(polygon
			(pts
				(arc
					(start 292.614096 -242.385088)
					(mid 291.946076 -242.385088)
					(end 292.614096 -242.385088)
				)
			)
		)
	)
	(zone
		(layers "B.Cu" "In4.Cu" "In6.Cu" "In11.Cu" "In13.Cu" "In15.Cu")
		(hatch none 0.5)
		(connect_pads
			(clearance 0)
		)
		(min_thickness 0.25)
		(keepout
			(tracks not_allowed)
			(vias allowed)
			(pads allowed)
			(copperpour not_allowed)
			(footprints allowed)
		)
		(placement
			(enabled no)
			(sheetname "")
		)
		(fill yes
			(thermal_gap 0.5)
			(thermal_bridge_width 0.5)
			(island_removal_mode 0)
		)
		(polygon
			(pts
				(arc
					(start 431.89017 -295.085008)
					(mid 431.22215 -295.085008)
					(end 431.89017 -295.085008)
				)
			)
		)
	)
	(zone
		(layers "B.Cu" "In4.Cu" "In6.Cu" "In11.Cu" "In13.Cu" "In15.Cu")
		(hatch none 0.5)
		(connect_pads
			(clearance 0)
		)
		(min_thickness 0.25)
		(keepout
			(tracks not_allowed)
			(vias allowed)
			(pads allowed)
			(copperpour not_allowed)
			(footprints allowed)
		)
		(placement
			(enabled no)
			(sheetname "")
		)
		(fill yes
			(thermal_gap 0.5)
			(thermal_bridge_width 0.5)
			(island_removal_mode 0)
		)
		(polygon
			(pts
				(arc
					(start 44.674028 -220.28531)
					(mid 44.006008 -220.28531)
					(end 44.674028 -220.28531)
				)
			)
		)
	)
	(zone
		(layers "B.Cu" "In4.Cu" "In6.Cu" "In11.Cu" "In13.Cu" "In15.Cu")
		(hatch none 0.5)
		(connect_pads
			(clearance 0)
		)
		(min_thickness 0.25)
		(keepout
			(tracks not_allowed)
			(vias allowed)
			(pads allowed)
			(copperpour not_allowed)
			(footprints allowed)
		)
		(placement
			(enabled no)
			(sheetname "")
		)
		(fill yes
			(thermal_gap 0.5)
			(thermal_bridge_width 0.5)
			(island_removal_mode 0)
		)
		(polygon
			(pts
				(arc
					(start 106.755946 -292.716204)
					(mid 106.126026 -292.716204)
					(end 106.755946 -292.716204)
				)
			)
		)
	)
	(zone
		(layers "B.Cu" "In4.Cu" "In6.Cu" "In11.Cu" "In13.Cu" "In15.Cu")
		(hatch none 0.5)
		(connect_pads
			(clearance 0)
		)
		(min_thickness 0.25)
		(keepout
			(tracks not_allowed)
			(vias allowed)
			(pads allowed)
			(copperpour not_allowed)
			(footprints allowed)
		)
		(placement
			(enabled no)
			(sheetname "")
		)
		(fill yes
			(thermal_gap 0.5)
			(thermal_bridge_width 0.5)
			(island_removal_mode 0)
		)
		(polygon
			(pts
				(arc
					(start 129.779776 -278.946356)
					(mid 129.149856 -278.946356)
					(end 129.779776 -278.946356)
				)
			)
		)
	)
	(zone
		(layers "B.Cu" "In4.Cu" "In6.Cu" "In11.Cu" "In13.Cu" "In15.Cu")
		(hatch none 0.5)
		(connect_pads
			(clearance 0)
		)
		(min_thickness 0.25)
		(keepout
			(tracks not_allowed)
			(vias allowed)
			(pads allowed)
			(copperpour not_allowed)
			(footprints allowed)
		)
		(placement
			(enabled no)
			(sheetname "")
		)
		(fill yes
			(thermal_gap 0.5)
			(thermal_bridge_width 0.5)
			(island_removal_mode 0)
		)
		(polygon
			(pts
				(arc
					(start 288.514028 -246.635016)
					(mid 287.846008 -246.635016)
					(end 288.514028 -246.635016)
				)
			)
		)
	)
	(zone
		(layers "B.Cu" "In4.Cu" "In6.Cu" "In11.Cu" "In13.Cu" "In15.Cu")
		(hatch none 0.5)
		(connect_pads
			(clearance 0)
		)
		(min_thickness 0.25)
		(keepout
			(tracks not_allowed)
			(vias allowed)
			(pads allowed)
			(copperpour not_allowed)
			(footprints allowed)
		)
		(placement
			(enabled no)
			(sheetname "")
		)
		(fill yes
			(thermal_gap 0.5)
			(thermal_bridge_width 0.5)
			(island_removal_mode 0)
		)
		(polygon
			(pts
				(arc
					(start 27.656536 -428.183802)
					(mid 26.988516 -428.183802)
					(end 27.656536 -428.183802)
				)
			)
		)
	)
	(zone
		(layers "B.Cu" "In4.Cu" "In6.Cu" "In11.Cu" "In13.Cu" "In15.Cu")
		(hatch none 0.5)
		(connect_pads
			(clearance 0)
		)
		(min_thickness 0.25)
		(keepout
			(tracks not_allowed)
			(vias allowed)
			(pads allowed)
			(copperpour not_allowed)
			(footprints allowed)
		)
		(placement
			(enabled no)
			(sheetname "")
		)
		(fill yes
			(thermal_gap 0.5)
			(thermal_bridge_width 0.5)
			(island_removal_mode 0)
		)
		(polygon
			(pts
				(arc
					(start 377.88977 -239.624108)
					(mid 377.25985 -239.624108)
					(end 377.88977 -239.624108)
				)
			)
		)
	)
	(zone
		(layers "B.Cu" "In4.Cu" "In6.Cu" "In11.Cu" "In13.Cu" "In15.Cu")
		(hatch none 0.5)
		(connect_pads
			(clearance 0)
		)
		(min_thickness 0.25)
		(keepout
			(tracks not_allowed)
			(vias allowed)
			(pads allowed)
			(copperpour not_allowed)
			(footprints allowed)
		)
		(placement
			(enabled no)
			(sheetname "")
		)
		(fill yes
			(thermal_gap 0.5)
			(thermal_bridge_width 0.5)
			(island_removal_mode 0)
		)
		(polygon
			(pts
				(arc
					(start 40.57396 -274.685252)
					(mid 39.90594 -274.685252)
					(end 40.57396 -274.685252)
				)
			)
		)
	)
	(zone
		(layers "B.Cu" "In4.Cu" "In6.Cu" "In11.Cu" "In13.Cu" "In15.Cu")
		(hatch none 0.5)
		(connect_pads
			(clearance 0)
		)
		(min_thickness 0.25)
		(keepout
			(tracks not_allowed)
			(vias allowed)
			(pads allowed)
			(copperpour not_allowed)
			(footprints allowed)
		)
		(placement
			(enabled no)
			(sheetname "")
		)
		(fill yes
			(thermal_gap 0.5)
			(thermal_bridge_width 0.5)
			(island_removal_mode 0)
		)
		(polygon
			(pts
				(arc
					(start 342.945974 -280.566114)
					(mid 342.316054 -280.566114)
					(end 342.945974 -280.566114)
				)
			)
		)
	)
	(zone
		(layers "B.Cu" "In4.Cu" "In6.Cu" "In11.Cu" "In13.Cu" "In15.Cu")
		(hatch none 0.5)
		(connect_pads
			(clearance 0)
		)
		(min_thickness 0.25)
		(keepout
			(tracks not_allowed)
			(vias allowed)
			(pads allowed)
			(copperpour not_allowed)
			(footprints allowed)
		)
		(placement
			(enabled no)
			(sheetname "")
		)
		(fill yes
			(thermal_gap 0.5)
			(thermal_bridge_width 0.5)
			(island_removal_mode 0)
		)
		(polygon
			(pts
				(arc
					(start 183.950102 -250.885198)
					(mid 183.282082 -250.885198)
					(end 183.950102 -250.885198)
				)
			)
		)
	)
	(zone
		(layers "B.Cu" "In4.Cu" "In6.Cu" "In11.Cu" "In13.Cu" "In15.Cu")
		(hatch none 0.5)
		(connect_pads
			(clearance 0)
		)
		(min_thickness 0.25)
		(keepout
			(tracks not_allowed)
			(vias allowed)
			(pads allowed)
			(copperpour not_allowed)
			(footprints allowed)
		)
		(placement
			(enabled no)
			(sheetname "")
		)
		(fill yes
			(thermal_gap 0.5)
			(thermal_bridge_width 0.5)
			(island_removal_mode 0)
		)
		(polygon
			(pts
				(arc
					(start 377.88977 -246.104156)
					(mid 377.25985 -246.104156)
					(end 377.88977 -246.104156)
				)
			)
		)
	)
	(zone
		(layers "B.Cu" "In4.Cu" "In6.Cu" "In11.Cu" "In13.Cu" "In15.Cu")
		(hatch none 0.5)
		(connect_pads
			(clearance 0)
		)
		(min_thickness 0.25)
		(keepout
			(tracks not_allowed)
			(vias allowed)
			(pads allowed)
			(copperpour not_allowed)
			(footprints allowed)
		)
		(placement
			(enabled no)
			(sheetname "")
		)
		(fill yes
			(thermal_gap 0.5)
			(thermal_bridge_width 0.5)
			(island_removal_mode 0)
		)
		(polygon
			(pts
				(arc
					(start 427.790102 -235.585)
					(mid 427.122082 -235.585)
					(end 427.790102 -235.585)
				)
			)
		)
	)
	(zone
		(layers "B.Cu" "In4.Cu" "In6.Cu" "In11.Cu" "In13.Cu" "In15.Cu")
		(hatch none 0.5)
		(connect_pads
			(clearance 0)
		)
		(min_thickness 0.25)
		(keepout
			(tracks not_allowed)
			(vias allowed)
			(pads allowed)
			(copperpour not_allowed)
			(footprints allowed)
		)
		(placement
			(enabled no)
			(sheetname "")
		)
		(fill yes
			(thermal_gap 0.5)
			(thermal_bridge_width 0.5)
			(island_removal_mode 0)
		)
		(polygon
			(pts
				(arc
					(start 342.646 -225.85426)
					(mid 342.01608 -225.85426)
					(end 342.646 -225.85426)
				)
			)
		)
	)
	(zone
		(layers "B.Cu" "In4.Cu" "In6.Cu" "In11.Cu" "In13.Cu" "In15.Cu")
		(hatch none 0.5)
		(connect_pads
			(clearance 0)
		)
		(min_thickness 0.25)
		(keepout
			(tracks not_allowed)
			(vias allowed)
			(pads allowed)
			(copperpour not_allowed)
			(footprints allowed)
		)
		(placement
			(enabled no)
			(sheetname "")
		)
		(fill yes
			(thermal_gap 0.5)
			(thermal_bridge_width 0.5)
			(island_removal_mode 0)
		)
		(polygon
			(pts
				(arc
					(start 427.790102 -274.684998)
					(mid 427.122082 -274.684998)
					(end 427.790102 -274.684998)
				)
			)
		)
	)
	(zone
		(layers "B.Cu" "In4.Cu" "In6.Cu" "In11.Cu" "In13.Cu" "In15.Cu")
		(hatch none 0.5)
		(connect_pads
			(clearance 0)
		)
		(min_thickness 0.25)
		(keepout
			(tracks not_allowed)
			(vias allowed)
			(pads allowed)
			(copperpour not_allowed)
			(footprints allowed)
		)
		(placement
			(enabled no)
			(sheetname "")
		)
		(fill yes
			(thermal_gap 0.5)
			(thermal_bridge_width 0.5)
			(island_removal_mode 0)
		)
		(polygon
			(pts
				(arc
					(start 104.576118 -229.90429)
					(mid 103.946198 -229.90429)
					(end 104.576118 -229.90429)
				)
			)
		)
	)
	(zone
		(layers "B.Cu" "In4.Cu" "In6.Cu" "In11.Cu" "In13.Cu" "In15.Cu")
		(hatch none 0.5)
		(connect_pads
			(clearance 0)
		)
		(min_thickness 0.25)
		(keepout
			(tracks not_allowed)
			(vias allowed)
			(pads allowed)
			(copperpour not_allowed)
			(footprints allowed)
		)
		(placement
			(enabled no)
			(sheetname "")
		)
		(fill yes
			(thermal_gap 0.5)
			(thermal_bridge_width 0.5)
			(island_removal_mode 0)
		)
		(polygon
			(pts
				(arc
					(start 44.674028 -284.885384)
					(mid 44.006008 -284.885384)
					(end 44.674028 -284.885384)
				)
			)
		)
	)
	(zone
		(layers "B.Cu" "In4.Cu" "In6.Cu" "In11.Cu" "In13.Cu" "In15.Cu")
		(hatch none 0.5)
		(connect_pads
			(clearance 0)
		)
		(min_thickness 0.25)
		(keepout
			(tracks not_allowed)
			(vias allowed)
			(pads allowed)
			(copperpour not_allowed)
			(footprints allowed)
		)
		(placement
			(enabled no)
			(sheetname "")
		)
		(fill yes
			(thermal_gap 0.5)
			(thermal_bridge_width 0.5)
			(island_removal_mode 0)
		)
		(polygon
			(pts
				(arc
					(start 342.945974 -275.706078)
					(mid 342.316054 -275.706078)
					(end 342.945974 -275.706078)
				)
			)
		)
	)
	(zone
		(layers "B.Cu" "In4.Cu" "In6.Cu" "In11.Cu" "In13.Cu" "In15.Cu")
		(hatch none 0.5)
		(connect_pads
			(clearance 0)
		)
		(min_thickness 0.25)
		(keepout
			(tracks not_allowed)
			(vias allowed)
			(pads allowed)
			(copperpour not_allowed)
			(footprints allowed)
		)
		(placement
			(enabled no)
			(sheetname "")
		)
		(fill yes
			(thermal_gap 0.5)
			(thermal_bridge_width 0.5)
			(island_removal_mode 0)
		)
		(polygon
			(pts
				(arc
					(start 316.77737 4.650994)
					(mid 316.10935 4.650994)
					(end 316.77737 4.650994)
				)
			)
		)
	)
	(zone
		(layers "B.Cu" "In4.Cu" "In6.Cu" "In11.Cu" "In13.Cu" "In15.Cu")
		(hatch none 0.5)
		(connect_pads
			(clearance 0)
		)
		(min_thickness 0.25)
		(keepout
			(tracks not_allowed)
			(vias allowed)
			(pads allowed)
			(copperpour not_allowed)
			(footprints allowed)
		)
		(placement
			(enabled no)
			(sheetname "")
		)
		(fill yes
			(thermal_gap 0.5)
			(thermal_bridge_width 0.5)
			(island_removal_mode 0)
		)
		(polygon
			(pts
				(arc
					(start 376.009662 -231.524048)
					(mid 375.379742 -231.524048)
					(end 376.009662 -231.524048)
				)
			)
		)
	)
	(zone
		(layers "B.Cu" "In4.Cu" "In6.Cu" "In11.Cu" "In13.Cu" "In15.Cu")
		(hatch none 0.5)
		(connect_pads
			(clearance 0)
		)
		(min_thickness 0.25)
		(keepout
			(tracks not_allowed)
			(vias allowed)
			(pads allowed)
			(copperpour not_allowed)
			(footprints allowed)
		)
		(placement
			(enabled no)
			(sheetname "")
		)
		(fill yes
			(thermal_gap 0.5)
			(thermal_bridge_width 0.5)
			(island_removal_mode 0)
		)
		(polygon
			(pts
				(arc
					(start 94.705932 -237.194344)
					(mid 94.076012 -237.194344)
					(end 94.705932 -237.194344)
				)
			)
		)
	)
	(zone
		(layers "B.Cu" "In4.Cu" "In6.Cu" "In11.Cu" "In13.Cu" "In15.Cu")
		(hatch none 0.5)
		(connect_pads
			(clearance 0)
		)
		(min_thickness 0.25)
		(keepout
			(tracks not_allowed)
			(vias allowed)
			(pads allowed)
			(copperpour not_allowed)
			(footprints allowed)
		)
		(placement
			(enabled no)
			(sheetname "")
		)
		(fill yes
			(thermal_gap 0.5)
			(thermal_bridge_width 0.5)
			(island_removal_mode 0)
		)
		(polygon
			(pts
				(arc
					(start 342.945974 -270.846042)
					(mid 342.316054 -270.846042)
					(end 342.945974 -270.846042)
				)
			)
		)
	)
	(zone
		(layers "B.Cu" "In4.Cu" "In6.Cu" "In11.Cu" "In13.Cu" "In15.Cu")
		(hatch none 0.5)
		(connect_pads
			(clearance 0)
		)
		(min_thickness 0.25)
		(keepout
			(tracks not_allowed)
			(vias allowed)
			(pads allowed)
			(copperpour not_allowed)
			(footprints allowed)
		)
		(placement
			(enabled no)
			(sheetname "")
		)
		(fill yes
			(thermal_gap 0.5)
			(thermal_bridge_width 0.5)
			(island_removal_mode 0)
		)
		(polygon
			(pts
				(arc
					(start 342.646 -245.29415)
					(mid 342.01608 -245.29415)
					(end 342.646 -245.29415)
				)
			)
		)
	)
	(zone
		(layers "B.Cu" "In4.Cu" "In6.Cu" "In11.Cu" "In13.Cu" "In15.Cu")
		(hatch none 0.5)
		(connect_pads
			(clearance 0)
		)
		(min_thickness 0.25)
		(keepout
			(tracks not_allowed)
			(vias allowed)
			(pads allowed)
			(copperpour not_allowed)
			(footprints allowed)
		)
		(placement
			(enabled no)
			(sheetname "")
		)
		(fill yes
			(thermal_gap 0.5)
			(thermal_bridge_width 0.5)
			(island_removal_mode 0)
		)
		(polygon
			(pts
				(arc
					(start 128.369822 -261.93623)
					(mid 127.739902 -261.93623)
					(end 128.369822 -261.93623)
				)
			)
		)
	)
	(zone
		(layers "B.Cu" "In4.Cu" "In6.Cu" "In11.Cu" "In13.Cu" "In15.Cu")
		(hatch none 0.5)
		(connect_pads
			(clearance 0)
		)
		(min_thickness 0.25)
		(keepout
			(tracks not_allowed)
			(vias allowed)
			(pads allowed)
			(copperpour not_allowed)
			(footprints allowed)
		)
		(placement
			(enabled no)
			(sheetname "")
		)
		(fill yes
			(thermal_gap 0.5)
			(thermal_bridge_width 0.5)
			(island_removal_mode 0)
		)
		(polygon
			(pts
				(arc
					(start 94.236032 -244.484398)
					(mid 93.606112 -244.484398)
					(end 94.236032 -244.484398)
				)
			)
		)
	)
	(zone
		(layers "B.Cu" "In4.Cu" "In6.Cu" "In11.Cu" "In13.Cu" "In15.Cu")
		(hatch none 0.5)
		(connect_pads
			(clearance 0)
		)
		(min_thickness 0.25)
		(keepout
			(tracks not_allowed)
			(vias allowed)
			(pads allowed)
			(copperpour not_allowed)
			(footprints allowed)
		)
		(placement
			(enabled no)
			(sheetname "")
		)
		(fill yes
			(thermal_gap 0.5)
			(thermal_bridge_width 0.5)
			(island_removal_mode 0)
		)
		(polygon
			(pts
				(arc
					(start 128.069594 -246.10441)
					(mid 127.439674 -246.10441)
					(end 128.069594 -246.10441)
				)
			)
		)
	)
	(zone
		(layers "B.Cu" "In4.Cu" "In6.Cu" "In11.Cu" "In13.Cu" "In15.Cu")
		(hatch none 0.5)
		(connect_pads
			(clearance 0)
		)
		(min_thickness 0.25)
		(keepout
			(tracks not_allowed)
			(vias allowed)
			(pads allowed)
			(copperpour not_allowed)
			(footprints allowed)
		)
		(placement
			(enabled no)
			(sheetname "")
		)
		(fill yes
			(thermal_gap 0.5)
			(thermal_bridge_width 0.5)
			(island_removal_mode 0)
		)
		(polygon
			(pts
				(arc
					(start 256.261108 -213.806024)
					(mid 255.593088 -213.806024)
					(end 256.261108 -213.806024)
				)
			)
		)
	)
	(zone
		(layers "B.Cu" "In4.Cu" "In6.Cu" "In11.Cu" "In13.Cu" "In15.Cu")
		(hatch none 0.5)
		(connect_pads
			(clearance 0)
		)
		(min_thickness 0.25)
		(keepout
			(tracks not_allowed)
			(vias allowed)
			(pads allowed)
			(copperpour not_allowed)
			(footprints allowed)
		)
		(placement
			(enabled no)
			(sheetname "")
		)
		(fill yes
			(thermal_gap 0.5)
			(thermal_bridge_width 0.5)
			(island_removal_mode 0)
		)
		(polygon
			(pts
				(arc
					(start 183.950102 -272.135346)
					(mid 183.282082 -272.135346)
					(end 183.950102 -272.135346)
				)
			)
		)
	)
	(zone
		(layers "B.Cu" "In4.Cu" "In6.Cu" "In11.Cu" "In13.Cu" "In15.Cu")
		(hatch none 0.5)
		(connect_pads
			(clearance 0)
		)
		(min_thickness 0.25)
		(keepout
			(tracks not_allowed)
			(vias allowed)
			(pads allowed)
			(copperpour not_allowed)
			(footprints allowed)
		)
		(placement
			(enabled no)
			(sheetname "")
		)
		(fill yes
			(thermal_gap 0.5)
			(thermal_bridge_width 0.5)
			(island_removal_mode 0)
		)
		(polygon
			(pts
				(arc
					(start 128.539748 -253.394464)
					(mid 127.909828 -253.394464)
					(end 128.539748 -253.394464)
				)
			)
		)
	)
	(zone
		(layers "B.Cu" "In4.Cu" "In6.Cu" "In11.Cu" "In13.Cu" "In15.Cu")
		(hatch none 0.5)
		(connect_pads
			(clearance 0)
		)
		(min_thickness 0.25)
		(keepout
			(tracks not_allowed)
			(vias allowed)
			(pads allowed)
			(copperpour not_allowed)
			(footprints allowed)
		)
		(placement
			(enabled no)
			(sheetname "")
		)
		(fill yes
			(thermal_gap 0.5)
			(thermal_bridge_width 0.5)
			(island_removal_mode 0)
		)
		(polygon
			(pts
				(arc
					(start 427.790102 -216.885012)
					(mid 427.122082 -216.885012)
					(end 427.790102 -216.885012)
				)
			)
		)
	)
	(zone
		(layers "B.Cu" "In4.Cu" "In6.Cu" "In11.Cu" "In13.Cu" "In15.Cu")
		(hatch none 0.5)
		(connect_pads
			(clearance 0)
		)
		(min_thickness 0.25)
		(keepout
			(tracks not_allowed)
			(vias allowed)
			(pads allowed)
			(copperpour not_allowed)
			(footprints allowed)
		)
		(placement
			(enabled no)
			(sheetname "")
		)
		(fill yes
			(thermal_gap 0.5)
			(thermal_bridge_width 0.5)
			(island_removal_mode 0)
		)
		(polygon
			(pts
				(arc
					(start 288.514028 -304.435002)
					(mid 287.846008 -304.435002)
					(end 288.514028 -304.435002)
				)
			)
		)
	)
	(zone
		(layers "B.Cu" "In4.Cu" "In6.Cu" "In11.Cu" "In13.Cu" "In15.Cu")
		(hatch none 0.5)
		(connect_pads
			(clearance 0)
		)
		(min_thickness 0.25)
		(keepout
			(tracks not_allowed)
			(vias allowed)
			(pads allowed)
			(copperpour not_allowed)
			(footprints allowed)
		)
		(placement
			(enabled no)
			(sheetname "")
		)
		(fill yes
			(thermal_gap 0.5)
			(thermal_bridge_width 0.5)
			(island_removal_mode 0)
		)
		(polygon
			(pts
				(arc
					(start 96.115886 -246.10441)
					(mid 95.485966 -246.10441)
					(end 96.115886 -246.10441)
				)
			)
		)
	)
	(zone
		(layers "B.Cu" "In4.Cu" "In6.Cu" "In11.Cu" "In13.Cu" "In15.Cu")
		(hatch none 0.5)
		(connect_pads
			(clearance 0)
		)
		(min_thickness 0.25)
		(keepout
			(tracks not_allowed)
			(vias allowed)
			(pads allowed)
			(copperpour not_allowed)
			(footprints allowed)
		)
		(placement
			(enabled no)
			(sheetname "")
		)
		(fill yes
			(thermal_gap 0.5)
			(thermal_bridge_width 0.5)
			(island_removal_mode 0)
		)
		(polygon
			(pts
				(arc
					(start 288.514028 -261.93496)
					(mid 287.846008 -261.93496)
					(end 288.514028 -261.93496)
				)
			)
		)
	)
	(zone
		(layers "B.Cu" "In4.Cu" "In6.Cu" "In11.Cu" "In13.Cu" "In15.Cu")
		(hatch none 0.5)
		(connect_pads
			(clearance 0)
		)
		(min_thickness 0.25)
		(keepout
			(tracks not_allowed)
			(vias allowed)
			(pads allowed)
			(copperpour not_allowed)
			(footprints allowed)
		)
		(placement
			(enabled no)
			(sheetname "")
		)
		(fill yes
			(thermal_gap 0.5)
			(thermal_bridge_width 0.5)
			(island_removal_mode 0)
		)
		(polygon
			(pts
				(arc
					(start 183.950102 -219.435426)
					(mid 183.282082 -219.435426)
					(end 183.950102 -219.435426)
				)
			)
		)
	)
	(zone
		(layers "B.Cu" "In4.Cu" "In6.Cu" "In11.Cu" "In13.Cu" "In15.Cu")
		(hatch none 0.5)
		(connect_pads
			(clearance 0)
		)
		(min_thickness 0.25)
		(keepout
			(tracks not_allowed)
			(vias allowed)
			(pads allowed)
			(copperpour not_allowed)
			(footprints allowed)
		)
		(placement
			(enabled no)
			(sheetname "")
		)
		(fill yes
			(thermal_gap 0.5)
			(thermal_bridge_width 0.5)
			(island_removal_mode 0)
		)
		(polygon
			(pts
				(arc
					(start 40.57396 -221.135194)
					(mid 39.90594 -221.135194)
					(end 40.57396 -221.135194)
				)
			)
		)
	)
	(zone
		(layers "B.Cu" "In4.Cu" "In6.Cu" "In11.Cu" "In13.Cu" "In15.Cu")
		(hatch none 0.5)
		(connect_pads
			(clearance 0)
		)
		(min_thickness 0.25)
		(keepout
			(tracks not_allowed)
			(vias allowed)
			(pads allowed)
			(copperpour not_allowed)
			(footprints allowed)
		)
		(placement
			(enabled no)
			(sheetname "")
		)
		(fill yes
			(thermal_gap 0.5)
			(thermal_bridge_width 0.5)
			(island_removal_mode 0)
		)
		(polygon
			(pts
				(arc
					(start 128.069594 -226.66452)
					(mid 127.439674 -226.66452)
					(end 128.069594 -226.66452)
				)
			)
		)
	)
	(zone
		(layers "B.Cu" "In4.Cu" "In6.Cu" "In11.Cu" "In13.Cu" "In15.Cu")
		(hatch none 0.5)
		(connect_pads
			(clearance 0)
		)
		(min_thickness 0.25)
		(keepout
			(tracks not_allowed)
			(vias allowed)
			(pads allowed)
			(copperpour not_allowed)
			(footprints allowed)
		)
		(placement
			(enabled no)
			(sheetname "")
		)
		(fill yes
			(thermal_gap 0.5)
			(thermal_bridge_width 0.5)
			(island_removal_mode 0)
		)
		(polygon
			(pts
				(arc
					(start 40.57396 -241.535204)
					(mid 39.90594 -241.535204)
					(end 40.57396 -241.535204)
				)
			)
		)
	)
	(zone
		(layers "B.Cu" "In4.Cu" "In6.Cu" "In11.Cu" "In13.Cu" "In15.Cu")
		(hatch none 0.5)
		(connect_pads
			(clearance 0)
		)
		(min_thickness 0.25)
		(keepout
			(tracks not_allowed)
			(vias allowed)
			(pads allowed)
			(copperpour not_allowed)
			(footprints allowed)
		)
		(placement
			(enabled no)
			(sheetname "")
		)
		(fill yes
			(thermal_gap 0.5)
			(thermal_bridge_width 0.5)
			(island_removal_mode 0)
		)
		(polygon
			(pts
				(arc
					(start 40.57396 -233.885232)
					(mid 39.90594 -233.885232)
					(end 40.57396 -233.885232)
				)
			)
		)
	)
	(zone
		(layers "B.Cu" "In4.Cu" "In6.Cu" "In11.Cu" "In13.Cu" "In15.Cu")
		(hatch none 0.5)
		(connect_pads
			(clearance 0)
		)
		(min_thickness 0.25)
		(keepout
			(tracks not_allowed)
			(vias allowed)
			(pads allowed)
			(copperpour not_allowed)
			(footprints allowed)
		)
		(placement
			(enabled no)
			(sheetname "")
		)
		(fill yes
			(thermal_gap 0.5)
			(thermal_bridge_width 0.5)
			(island_removal_mode 0)
		)
		(polygon
			(pts
				(arc
					(start 95.005906 -290.286186)
					(mid 94.375986 -290.286186)
					(end 95.005906 -290.286186)
				)
			)
		)
	)
	(zone
		(layers "B.Cu" "In4.Cu" "In6.Cu" "In11.Cu" "In13.Cu" "In15.Cu")
		(hatch none 0.5)
		(connect_pads
			(clearance 0)
		)
		(min_thickness 0.25)
		(keepout
			(tracks not_allowed)
			(vias allowed)
			(pads allowed)
			(copperpour not_allowed)
			(footprints allowed)
		)
		(placement
			(enabled no)
			(sheetname "")
		)
		(fill yes
			(thermal_gap 0.5)
			(thermal_bridge_width 0.5)
			(island_removal_mode 0)
		)
		(polygon
			(pts
				(arc
					(start 40.57396 -232.18521)
					(mid 39.90594 -232.18521)
					(end 40.57396 -232.18521)
				)
			)
		)
	)
	(zone
		(layers "B.Cu" "In4.Cu" "In6.Cu" "In11.Cu" "In13.Cu" "In15.Cu")
		(hatch none 0.5)
		(connect_pads
			(clearance 0)
		)
		(min_thickness 0.25)
		(keepout
			(tracks not_allowed)
			(vias allowed)
			(pads allowed)
			(copperpour not_allowed)
			(footprints allowed)
		)
		(placement
			(enabled no)
			(sheetname "")
		)
		(fill yes
			(thermal_gap 0.5)
			(thermal_bridge_width 0.5)
			(island_removal_mode 0)
		)
		(polygon
			(pts
				(arc
					(start 129.949702 -238.00435)
					(mid 129.319782 -238.00435)
					(end 129.949702 -238.00435)
				)
			)
		)
	)
	(zone
		(layers "B.Cu" "In4.Cu" "In6.Cu" "In11.Cu" "In13.Cu" "In15.Cu")
		(hatch none 0.5)
		(connect_pads
			(clearance 0)
		)
		(min_thickness 0.25)
		(keepout
			(tracks not_allowed)
			(vias allowed)
			(pads allowed)
			(copperpour not_allowed)
			(footprints allowed)
		)
		(placement
			(enabled no)
			(sheetname "")
		)
		(fill yes
			(thermal_gap 0.5)
			(thermal_bridge_width 0.5)
			(island_removal_mode 0)
		)
		(polygon
			(pts
				(arc
					(start 288.514028 -238.985044)
					(mid 287.846008 -238.985044)
					(end 288.514028 -238.985044)
				)
			)
		)
	)
	(zone
		(layers "B.Cu" "In4.Cu" "In6.Cu" "In11.Cu" "In13.Cu" "In15.Cu")
		(hatch none 0.5)
		(connect_pads
			(clearance 0)
		)
		(min_thickness 0.25)
		(keepout
			(tracks not_allowed)
			(vias allowed)
			(pads allowed)
			(copperpour not_allowed)
			(footprints allowed)
		)
		(placement
			(enabled no)
			(sheetname "")
		)
		(fill yes
			(thermal_gap 0.5)
			(thermal_bridge_width 0.5)
			(island_removal_mode 0)
		)
		(polygon
			(pts
				(arc
					(start 288.514028 -310.384952)
					(mid 287.846008 -310.384952)
					(end 288.514028 -310.384952)
				)
			)
		)
	)
	(zone
		(layers "B.Cu" "In4.Cu" "In6.Cu" "In11.Cu" "In13.Cu" "In15.Cu")
		(hatch none 0.5)
		(connect_pads
			(clearance 0)
		)
		(min_thickness 0.25)
		(keepout
			(tracks not_allowed)
			(vias allowed)
			(pads allowed)
			(copperpour not_allowed)
			(footprints allowed)
		)
		(placement
			(enabled no)
			(sheetname "")
		)
		(fill yes
			(thermal_gap 0.5)
			(thermal_bridge_width 0.5)
			(island_removal_mode 0)
		)
		(polygon
			(pts
				(arc
					(start 183.950102 -273.835368)
					(mid 183.282082 -273.835368)
					(end 183.950102 -273.835368)
				)
			)
		)
	)
	(zone
		(layers "B.Cu" "In4.Cu" "In6.Cu" "In11.Cu" "In13.Cu" "In15.Cu")
		(hatch none 0.5)
		(connect_pads
			(clearance 0)
		)
		(min_thickness 0.25)
		(keepout
			(tracks not_allowed)
			(vias allowed)
			(pads allowed)
			(copperpour not_allowed)
			(footprints allowed)
		)
		(placement
			(enabled no)
			(sheetname "")
		)
		(fill yes
			(thermal_gap 0.5)
			(thermal_bridge_width 0.5)
			(island_removal_mode 0)
		)
		(polygon
			(pts
				(arc
					(start 343.586054 -229.094284)
					(mid 342.956134 -229.094284)
					(end 343.586054 -229.094284)
				)
			)
		)
	)
	(zone
		(layers "B.Cu" "In4.Cu" "In6.Cu" "In11.Cu" "In13.Cu" "In15.Cu")
		(hatch none 0.5)
		(connect_pads
			(clearance 0)
		)
		(min_thickness 0.25)
		(keepout
			(tracks not_allowed)
			(vias allowed)
			(pads allowed)
			(copperpour not_allowed)
			(footprints allowed)
		)
		(placement
			(enabled no)
			(sheetname "")
		)
		(fill yes
			(thermal_gap 0.5)
			(thermal_bridge_width 0.5)
			(island_removal_mode 0)
		)
		(polygon
			(pts
				(arc
					(start 377.719844 -277.32609)
					(mid 377.089924 -277.32609)
					(end 377.719844 -277.32609)
				)
			)
		)
	)
	(zone
		(layers "B.Cu" "In4.Cu" "In6.Cu" "In11.Cu" "In13.Cu" "In15.Cu")
		(hatch none 0.5)
		(connect_pads
			(clearance 0)
		)
		(min_thickness 0.25)
		(keepout
			(tracks not_allowed)
			(vias allowed)
			(pads allowed)
			(copperpour not_allowed)
			(footprints allowed)
		)
		(placement
			(enabled no)
			(sheetname "")
		)
		(fill yes
			(thermal_gap 0.5)
			(thermal_bridge_width 0.5)
			(island_removal_mode 0)
		)
		(polygon
			(pts
				(arc
					(start 129.779776 -262.746236)
					(mid 129.149856 -262.746236)
					(end 129.779776 -262.746236)
				)
			)
		)
	)
	(zone
		(layers "B.Cu" "In4.Cu" "In6.Cu" "In11.Cu" "In13.Cu" "In15.Cu")
		(hatch none 0.5)
		(connect_pads
			(clearance 0)
		)
		(min_thickness 0.25)
		(keepout
			(tracks not_allowed)
			(vias allowed)
			(pads allowed)
			(copperpour not_allowed)
			(footprints allowed)
		)
		(placement
			(enabled no)
			(sheetname "")
		)
		(fill yes
			(thermal_gap 0.5)
			(thermal_bridge_width 0.5)
			(island_removal_mode 0)
		)
		(polygon
			(pts
				(arc
					(start 292.614096 -204.985112)
					(mid 291.946076 -204.985112)
					(end 292.614096 -204.985112)
				)
			)
		)
	)
	(zone
		(layers "B.Cu" "In4.Cu" "In6.Cu" "In11.Cu" "In13.Cu" "In15.Cu")
		(hatch none 0.5)
		(connect_pads
			(clearance 0)
		)
		(min_thickness 0.25)
		(keepout
			(tracks not_allowed)
			(vias allowed)
			(pads allowed)
			(copperpour not_allowed)
			(footprints allowed)
		)
		(placement
			(enabled no)
			(sheetname "")
		)
		(fill yes
			(thermal_gap 0.5)
			(thermal_bridge_width 0.5)
			(island_removal_mode 0)
		)
		(polygon
			(pts
				(arc
					(start 376.77979 -287.045908)
					(mid 376.14987 -287.045908)
					(end 376.77979 -287.045908)
				)
			)
		)
	)
	(zone
		(layers "B.Cu" "In4.Cu" "In6.Cu" "In11.Cu" "In13.Cu" "In15.Cu")
		(hatch none 0.5)
		(connect_pads
			(clearance 0)
		)
		(min_thickness 0.25)
		(keepout
			(tracks not_allowed)
			(vias allowed)
			(pads allowed)
			(copperpour not_allowed)
			(footprints allowed)
		)
		(placement
			(enabled no)
			(sheetname "")
		)
		(fill yes
			(thermal_gap 0.5)
			(thermal_bridge_width 0.5)
			(island_removal_mode 0)
		)
		(polygon
			(pts
				(arc
					(start 288.514028 -306.985162)
					(mid 287.846008 -306.985162)
					(end 288.514028 -306.985162)
				)
			)
		)
	)
	(zone
		(layers "B.Cu" "In4.Cu" "In6.Cu" "In11.Cu" "In13.Cu" "In15.Cu")
		(hatch none 0.5)
		(connect_pads
			(clearance 0)
		)
		(min_thickness 0.25)
		(keepout
			(tracks not_allowed)
			(vias allowed)
			(pads allowed)
			(copperpour not_allowed)
			(footprints allowed)
		)
		(placement
			(enabled no)
			(sheetname "")
		)
		(fill yes
			(thermal_gap 0.5)
			(thermal_bridge_width 0.5)
			(island_removal_mode 0)
		)
		(polygon
			(pts
				(arc
					(start 44.674028 -279.785318)
					(mid 44.006008 -279.785318)
					(end 44.674028 -279.785318)
				)
			)
		)
	)
	(zone
		(layers "B.Cu" "In4.Cu" "In6.Cu" "In11.Cu" "In13.Cu" "In15.Cu")
		(hatch none 0.5)
		(connect_pads
			(clearance 0)
		)
		(min_thickness 0.25)
		(keepout
			(tracks not_allowed)
			(vias allowed)
			(pads allowed)
			(copperpour not_allowed)
			(footprints allowed)
		)
		(placement
			(enabled no)
			(sheetname "")
		)
		(fill yes
			(thermal_gap 0.5)
			(thermal_bridge_width 0.5)
			(island_removal_mode 0)
		)
		(polygon
			(pts
				(arc
					(start 128.839722 -277.326344)
					(mid 128.209802 -277.326344)
					(end 128.839722 -277.326344)
				)
			)
		)
	)
	(zone
		(layers "B.Cu" "In4.Cu" "In6.Cu" "In11.Cu" "In13.Cu" "In15.Cu")
		(hatch none 0.5)
		(connect_pads
			(clearance 0)
		)
		(min_thickness 0.25)
		(keepout
			(tracks not_allowed)
			(vias allowed)
			(pads allowed)
			(copperpour not_allowed)
			(footprints allowed)
		)
		(placement
			(enabled no)
			(sheetname "")
		)
		(fill yes
			(thermal_gap 0.5)
			(thermal_bridge_width 0.5)
			(island_removal_mode 0)
		)
		(polygon
			(pts
				(arc
					(start 377.88977 -242.864132)
					(mid 377.25985 -242.864132)
					(end 377.88977 -242.864132)
				)
			)
		)
	)
	(zone
		(layers "B.Cu" "In4.Cu" "In6.Cu" "In11.Cu" "In13.Cu" "In15.Cu")
		(hatch none 0.5)
		(connect_pads
			(clearance 0)
		)
		(min_thickness 0.25)
		(keepout
			(tracks not_allowed)
			(vias allowed)
			(pads allowed)
			(copperpour not_allowed)
			(footprints allowed)
		)
		(placement
			(enabled no)
			(sheetname "")
		)
		(fill yes
			(thermal_gap 0.5)
			(thermal_bridge_width 0.5)
			(island_removal_mode 0)
		)
		(polygon
			(pts
				(arc
					(start 106.455972 -228.284532)
					(mid 105.826052 -228.284532)
					(end 106.455972 -228.284532)
				)
			)
		)
	)
	(zone
		(layers "B.Cu" "In4.Cu" "In6.Cu" "In11.Cu" "In13.Cu" "In15.Cu")
		(hatch none 0.5)
		(connect_pads
			(clearance 0)
		)
		(min_thickness 0.25)
		(keepout
			(tracks not_allowed)
			(vias allowed)
			(pads allowed)
			(copperpour not_allowed)
			(footprints allowed)
		)
		(placement
			(enabled no)
			(sheetname "")
		)
		(fill yes
			(thermal_gap 0.5)
			(thermal_bridge_width 0.5)
			(island_removal_mode 0)
		)
		(polygon
			(pts
				(arc
					(start 129.949702 -244.484398)
					(mid 129.319782 -244.484398)
					(end 129.949702 -244.484398)
				)
			)
		)
	)
	(zone
		(layers "B.Cu" "In4.Cu" "In6.Cu" "In11.Cu" "In13.Cu" "In15.Cu")
		(hatch none 0.5)
		(connect_pads
			(clearance 0)
		)
		(min_thickness 0.25)
		(keepout
			(tracks not_allowed)
			(vias allowed)
			(pads allowed)
			(copperpour not_allowed)
			(footprints allowed)
		)
		(placement
			(enabled no)
			(sheetname "")
		)
		(fill yes
			(thermal_gap 0.5)
			(thermal_bridge_width 0.5)
			(island_removal_mode 0)
		)
		(polygon
			(pts
				(arc
					(start 431.89017 -208.385156)
					(mid 431.22215 -208.385156)
					(end 431.89017 -208.385156)
				)
			)
		)
	)
	(zone
		(layers "B.Cu" "In4.Cu" "In6.Cu" "In11.Cu" "In13.Cu" "In15.Cu")
		(hatch none 0.5)
		(connect_pads
			(clearance 0)
		)
		(min_thickness 0.25)
		(keepout
			(tracks not_allowed)
			(vias allowed)
			(pads allowed)
			(copperpour not_allowed)
			(footprints allowed)
		)
		(placement
			(enabled no)
			(sheetname "")
		)
		(fill yes
			(thermal_gap 0.5)
			(thermal_bridge_width 0.5)
			(island_removal_mode 0)
		)
		(polygon
			(pts
				(arc
					(start 427.790102 -318.035178)
					(mid 427.122082 -318.035178)
					(end 427.790102 -318.035178)
				)
			)
		)
	)
	(zone
		(layers "B.Cu" "In4.Cu" "In6.Cu" "In11.Cu" "In13.Cu" "In15.Cu")
		(hatch none 0.5)
		(connect_pads
			(clearance 0)
		)
		(min_thickness 0.25)
		(keepout
			(tracks not_allowed)
			(vias allowed)
			(pads allowed)
			(copperpour not_allowed)
			(footprints allowed)
		)
		(placement
			(enabled no)
			(sheetname "")
		)
		(fill yes
			(thermal_gap 0.5)
			(thermal_bridge_width 0.5)
			(island_removal_mode 0)
		)
		(polygon
			(pts
				(arc
					(start 342.1761 -239.624108)
					(mid 341.54618 -239.624108)
					(end 342.1761 -239.624108)
				)
			)
		)
	)
	(zone
		(layers "B.Cu" "In4.Cu" "In6.Cu" "In11.Cu" "In13.Cu" "In15.Cu")
		(hatch none 0.5)
		(connect_pads
			(clearance 0)
		)
		(min_thickness 0.25)
		(keepout
			(tracks not_allowed)
			(vias allowed)
			(pads allowed)
			(copperpour not_allowed)
			(footprints allowed)
		)
		(placement
			(enabled no)
			(sheetname "")
		)
		(fill yes
			(thermal_gap 0.5)
			(thermal_bridge_width 0.5)
			(island_removal_mode 0)
		)
		(polygon
			(pts
				(arc
					(start 376.009662 -247.724168)
					(mid 375.379742 -247.724168)
					(end 376.009662 -247.724168)
				)
			)
		)
	)
	(zone
		(layers "B.Cu" "In4.Cu" "In6.Cu" "In11.Cu" "In13.Cu" "In15.Cu")
		(hatch none 0.5)
		(connect_pads
			(clearance 0)
		)
		(min_thickness 0.25)
		(keepout
			(tracks not_allowed)
			(vias allowed)
			(pads allowed)
			(copperpour not_allowed)
			(footprints allowed)
		)
		(placement
			(enabled no)
			(sheetname "")
		)
		(fill yes
			(thermal_gap 0.5)
			(thermal_bridge_width 0.5)
			(island_removal_mode 0)
		)
		(polygon
			(pts
				(arc
					(start 44.674028 -225.385376)
					(mid 44.006008 -225.385376)
					(end 44.674028 -225.385376)
				)
			)
		)
	)
	(zone
		(layers "B.Cu" "In4.Cu" "In6.Cu" "In11.Cu" "In13.Cu" "In15.Cu")
		(hatch none 0.5)
		(connect_pads
			(clearance 0)
		)
		(min_thickness 0.25)
		(keepout
			(tracks not_allowed)
			(vias allowed)
			(pads allowed)
			(copperpour not_allowed)
			(footprints allowed)
		)
		(placement
			(enabled no)
			(sheetname "")
		)
		(fill yes
			(thermal_gap 0.5)
			(thermal_bridge_width 0.5)
			(island_removal_mode 0)
		)
		(polygon
			(pts
				(arc
					(start 288.514028 -276.38502)
					(mid 287.846008 -276.38502)
					(end 288.514028 -276.38502)
				)
			)
		)
	)
	(zone
		(layers "B.Cu" "In4.Cu" "In6.Cu" "In11.Cu" "In13.Cu" "In15.Cu")
		(hatch none 0.5)
		(connect_pads
			(clearance 0)
		)
		(min_thickness 0.25)
		(keepout
			(tracks not_allowed)
			(vias allowed)
			(pads allowed)
			(copperpour not_allowed)
			(footprints allowed)
		)
		(placement
			(enabled no)
			(sheetname "")
		)
		(fill yes
			(thermal_gap 0.5)
			(thermal_bridge_width 0.5)
			(island_removal_mode 0)
		)
		(polygon
			(pts
				(arc
					(start 40.57396 -313.78525)
					(mid 39.90594 -313.78525)
					(end 40.57396 -313.78525)
				)
			)
		)
	)
	(zone
		(layers "B.Cu" "In4.Cu" "In6.Cu" "In11.Cu" "In13.Cu" "In15.Cu")
		(hatch none 0.5)
		(connect_pads
			(clearance 0)
		)
		(min_thickness 0.25)
		(keepout
			(tracks not_allowed)
			(vias allowed)
			(pads allowed)
			(copperpour not_allowed)
			(footprints allowed)
		)
		(placement
			(enabled no)
			(sheetname "")
		)
		(fill yes
			(thermal_gap 0.5)
			(thermal_bridge_width 0.5)
			(island_removal_mode 0)
		)
		(polygon
			(pts
				(arc
					(start 378.189744 -292.71595)
					(mid 377.559824 -292.71595)
					(end 378.189744 -292.71595)
				)
			)
		)
	)
	(zone
		(layers "B.Cu" "In4.Cu" "In6.Cu" "In11.Cu" "In13.Cu" "In15.Cu")
		(hatch none 0.5)
		(connect_pads
			(clearance 0)
		)
		(min_thickness 0.25)
		(keepout
			(tracks not_allowed)
			(vias allowed)
			(pads allowed)
			(copperpour not_allowed)
			(footprints allowed)
		)
		(placement
			(enabled no)
			(sheetname "")
		)
		(fill yes
			(thermal_gap 0.5)
			(thermal_bridge_width 0.5)
			(island_removal_mode 0)
		)
		(polygon
			(pts
				(arc
					(start 40.57396 -305.285394)
					(mid 39.90594 -305.285394)
					(end 40.57396 -305.285394)
				)
			)
		)
	)
	(zone
		(layers "B.Cu" "In4.Cu" "In6.Cu" "In11.Cu" "In13.Cu" "In15.Cu")
		(hatch none 0.5)
		(connect_pads
			(clearance 0)
		)
		(min_thickness 0.25)
		(keepout
			(tracks not_allowed)
			(vias allowed)
			(pads allowed)
			(copperpour not_allowed)
			(footprints allowed)
		)
		(placement
			(enabled no)
			(sheetname "")
		)
		(fill yes
			(thermal_gap 0.5)
			(thermal_bridge_width 0.5)
			(island_removal_mode 0)
		)
		(polygon
			(pts
				(arc
					(start 376.009662 -233.14406)
					(mid 375.379742 -233.14406)
					(end 376.009662 -233.14406)
				)
			)
		)
	)
	(zone
		(layers "B.Cu" "In4.Cu" "In6.Cu" "In11.Cu" "In13.Cu" "In15.Cu")
		(hatch none 0.5)
		(connect_pads
			(clearance 0)
		)
		(min_thickness 0.25)
		(keepout
			(tracks not_allowed)
			(vias allowed)
			(pads allowed)
			(copperpour not_allowed)
			(footprints allowed)
		)
		(placement
			(enabled no)
			(sheetname "")
		)
		(fill yes
			(thermal_gap 0.5)
			(thermal_bridge_width 0.5)
			(island_removal_mode 0)
		)
		(polygon
			(pts
				(arc
					(start 95.645986 -232.334308)
					(mid 95.016066 -232.334308)
					(end 95.645986 -232.334308)
				)
			)
		)
	)
	(zone
		(layers "B.Cu" "In4.Cu" "In6.Cu" "In11.Cu" "In13.Cu" "In15.Cu")
		(hatch none 0.5)
		(connect_pads
			(clearance 0)
		)
		(min_thickness 0.25)
		(keepout
			(tracks not_allowed)
			(vias allowed)
			(pads allowed)
			(copperpour not_allowed)
			(footprints allowed)
		)
		(placement
			(enabled no)
			(sheetname "")
		)
		(fill yes
			(thermal_gap 0.5)
			(thermal_bridge_width 0.5)
			(island_removal_mode 0)
		)
		(polygon
			(pts
				(arc
					(start 427.790102 -244.934994)
					(mid 427.122082 -244.934994)
					(end 427.790102 -244.934994)
				)
			)
		)
	)
	(zone
		(layers "B.Cu" "In4.Cu" "In6.Cu" "In11.Cu" "In13.Cu" "In15.Cu")
		(hatch none 0.5)
		(connect_pads
			(clearance 0)
		)
		(min_thickness 0.25)
		(keepout
			(tracks not_allowed)
			(vias allowed)
			(pads allowed)
			(copperpour not_allowed)
			(footprints allowed)
		)
		(placement
			(enabled no)
			(sheetname "")
		)
		(fill yes
			(thermal_gap 0.5)
			(thermal_bridge_width 0.5)
			(island_removal_mode 0)
		)
		(polygon
			(pts
				(arc
					(start 40.57396 -230.485442)
					(mid 39.90594 -230.485442)
					(end 40.57396 -230.485442)
				)
			)
		)
	)
	(zone
		(layers "B.Cu" "In4.Cu" "In6.Cu" "In11.Cu" "In13.Cu" "In15.Cu")
		(hatch none 0.5)
		(connect_pads
			(clearance 0)
		)
		(min_thickness 0.25)
		(keepout
			(tracks not_allowed)
			(vias allowed)
			(pads allowed)
			(copperpour not_allowed)
			(footprints allowed)
		)
		(placement
			(enabled no)
			(sheetname "")
		)
		(fill yes
			(thermal_gap 0.5)
			(thermal_bridge_width 0.5)
			(island_removal_mode 0)
		)
		(polygon
			(pts
				(arc
					(start 183.950102 -311.235344)
					(mid 183.282082 -311.235344)
					(end 183.950102 -311.235344)
				)
			)
		)
	)
	(zone
		(layers "B.Cu" "In4.Cu" "In6.Cu" "In11.Cu" "In13.Cu" "In15.Cu")
		(hatch none 0.5)
		(connect_pads
			(clearance 0)
		)
		(min_thickness 0.25)
		(keepout
			(tracks not_allowed)
			(vias allowed)
			(pads allowed)
			(copperpour not_allowed)
			(footprints allowed)
		)
		(placement
			(enabled no)
			(sheetname "")
		)
		(fill yes
			(thermal_gap 0.5)
			(thermal_bridge_width 0.5)
			(island_removal_mode 0)
		)
		(polygon
			(pts
				(arc
					(start 94.236032 -241.244374)
					(mid 93.606112 -241.244374)
					(end 94.236032 -241.244374)
				)
			)
		)
	)
	(zone
		(layers "B.Cu" "In4.Cu" "In6.Cu" "In11.Cu" "In13.Cu" "In15.Cu")
		(hatch none 0.5)
		(connect_pads
			(clearance 0)
		)
		(min_thickness 0.25)
		(keepout
			(tracks not_allowed)
			(vias allowed)
			(pads allowed)
			(copperpour not_allowed)
			(footprints allowed)
		)
		(placement
			(enabled no)
			(sheetname "")
		)
		(fill yes
			(thermal_gap 0.5)
			(thermal_bridge_width 0.5)
			(island_removal_mode 0)
		)
		(polygon
			(pts
				(arc
					(start 95.645986 -243.674392)
					(mid 95.016066 -243.674392)
					(end 95.645986 -243.674392)
				)
			)
		)
	)
	(zone
		(layers "B.Cu" "In4.Cu" "In6.Cu" "In11.Cu" "In13.Cu" "In15.Cu")
		(hatch none 0.5)
		(connect_pads
			(clearance 0)
		)
		(min_thickness 0.25)
		(keepout
			(tracks not_allowed)
			(vias allowed)
			(pads allowed)
			(copperpour not_allowed)
			(footprints allowed)
		)
		(placement
			(enabled no)
			(sheetname "")
		)
		(fill yes
			(thermal_gap 0.5)
			(thermal_bridge_width 0.5)
			(island_removal_mode 0)
		)
		(polygon
			(pts
				(arc
					(start 431.89017 -236.435138)
					(mid 431.22215 -236.435138)
					(end 431.89017 -236.435138)
				)
			)
		)
	)
	(zone
		(layers "B.Cu" "In4.Cu" "In6.Cu" "In11.Cu" "In13.Cu" "In15.Cu")
		(hatch none 0.5)
		(connect_pads
			(clearance 0)
		)
		(min_thickness 0.25)
		(keepout
			(tracks not_allowed)
			(vias allowed)
			(pads allowed)
			(copperpour not_allowed)
			(footprints allowed)
		)
		(placement
			(enabled no)
			(sheetname "")
		)
		(fill yes
			(thermal_gap 0.5)
			(thermal_bridge_width 0.5)
			(island_removal_mode 0)
		)
		(polygon
			(pts
				(arc
					(start 179.850034 -289.98545)
					(mid 179.182014 -289.98545)
					(end 179.850034 -289.98545)
				)
			)
		)
	)
	(zone
		(layers "B.Cu" "In4.Cu" "In6.Cu" "In11.Cu" "In13.Cu" "In15.Cu")
		(hatch none 0.5)
		(connect_pads
			(clearance 0)
		)
		(min_thickness 0.25)
		(keepout
			(tracks not_allowed)
			(vias allowed)
			(pads allowed)
			(copperpour not_allowed)
			(footprints allowed)
		)
		(placement
			(enabled no)
			(sheetname "")
		)
		(fill yes
			(thermal_gap 0.5)
			(thermal_bridge_width 0.5)
			(island_removal_mode 0)
		)
		(polygon
			(pts
				(arc
					(start 101.11613 -294.336216)
					(mid 100.48621 -294.336216)
					(end 101.11613 -294.336216)
				)
			)
		)
	)
	(zone
		(layers "B.Cu" "In4.Cu" "In6.Cu" "In11.Cu" "In13.Cu" "In15.Cu")
		(hatch none 0.5)
		(connect_pads
			(clearance 0)
		)
		(min_thickness 0.25)
		(keepout
			(tracks not_allowed)
			(vias allowed)
			(pads allowed)
			(copperpour not_allowed)
			(footprints allowed)
		)
		(placement
			(enabled no)
			(sheetname "")
		)
		(fill yes
			(thermal_gap 0.5)
			(thermal_bridge_width 0.5)
			(island_removal_mode 0)
		)
		(polygon
			(pts
				(arc
					(start 95.005906 -275.706332)
					(mid 94.375986 -275.706332)
					(end 95.005906 -275.706332)
				)
			)
		)
	)
	(zone
		(layers "B.Cu" "In4.Cu" "In6.Cu" "In11.Cu" "In13.Cu" "In15.Cu")
		(hatch none 0.5)
		(connect_pads
			(clearance 0)
		)
		(min_thickness 0.25)
		(keepout
			(tracks not_allowed)
			(vias allowed)
			(pads allowed)
			(copperpour not_allowed)
			(footprints allowed)
		)
		(placement
			(enabled no)
			(sheetname "")
		)
		(fill yes
			(thermal_gap 0.5)
			(thermal_bridge_width 0.5)
			(island_removal_mode 0)
		)
		(polygon
			(pts
				(arc
					(start 179.850034 -267.03528)
					(mid 179.182014 -267.03528)
					(end 179.850034 -267.03528)
				)
			)
		)
	)
	(zone
		(layers "B.Cu" "In4.Cu" "In6.Cu" "In11.Cu" "In13.Cu" "In15.Cu")
		(hatch none 0.5)
		(connect_pads
			(clearance 0)
		)
		(min_thickness 0.25)
		(keepout
			(tracks not_allowed)
			(vias allowed)
			(pads allowed)
			(copperpour not_allowed)
			(footprints allowed)
		)
		(placement
			(enabled no)
			(sheetname "")
		)
		(fill yes
			(thermal_gap 0.5)
			(thermal_bridge_width 0.5)
			(island_removal_mode 0)
		)
		(polygon
			(pts
				(arc
					(start 44.674028 -212.635338)
					(mid 44.006008 -212.635338)
					(end 44.674028 -212.635338)
				)
			)
		)
	)
	(zone
		(layers "B.Cu" "In4.Cu" "In6.Cu" "In11.Cu" "In13.Cu" "In15.Cu")
		(hatch none 0.5)
		(connect_pads
			(clearance 0)
		)
		(min_thickness 0.25)
		(keepout
			(tracks not_allowed)
			(vias allowed)
			(pads allowed)
			(copperpour not_allowed)
			(footprints allowed)
		)
		(placement
			(enabled no)
			(sheetname "")
		)
		(fill yes
			(thermal_gap 0.5)
			(thermal_bridge_width 0.5)
			(island_removal_mode 0)
		)
		(polygon
			(pts
				(arc
					(start 377.88977 -231.524048)
					(mid 377.25985 -231.524048)
					(end 377.88977 -231.524048)
				)
			)
		)
	)
	(zone
		(layers "B.Cu" "In4.Cu" "In6.Cu" "In11.Cu" "In13.Cu" "In15.Cu")
		(hatch none 0.5)
		(connect_pads
			(clearance 0)
		)
		(min_thickness 0.25)
		(keepout
			(tracks not_allowed)
			(vias allowed)
			(pads allowed)
			(copperpour not_allowed)
			(footprints allowed)
		)
		(placement
			(enabled no)
			(sheetname "")
		)
		(fill yes
			(thermal_gap 0.5)
			(thermal_bridge_width 0.5)
			(island_removal_mode 0)
		)
		(polygon
			(pts
				(arc
					(start 108.80598 -227.474526)
					(mid 108.17606 -227.474526)
					(end 108.80598 -227.474526)
				)
			)
		)
	)
	(zone
		(layers "B.Cu" "In4.Cu" "In6.Cu" "In11.Cu" "In13.Cu" "In15.Cu")
		(hatch none 0.5)
		(connect_pads
			(clearance 0)
		)
		(min_thickness 0.25)
		(keepout
			(tracks not_allowed)
			(vias allowed)
			(pads allowed)
			(copperpour not_allowed)
			(footprints allowed)
		)
		(placement
			(enabled no)
			(sheetname "")
		)
		(fill yes
			(thermal_gap 0.5)
			(thermal_bridge_width 0.5)
			(island_removal_mode 0)
		)
		(polygon
			(pts
				(arc
					(start 40.57396 -210.935316)
					(mid 39.90594 -210.935316)
					(end 40.57396 -210.935316)
				)
			)
		)
	)
	(zone
		(layers "B.Cu" "In4.Cu" "In6.Cu" "In11.Cu" "In13.Cu" "In15.Cu")
		(hatch none 0.5)
		(connect_pads
			(clearance 0)
		)
		(min_thickness 0.25)
		(keepout
			(tracks not_allowed)
			(vias allowed)
			(pads allowed)
			(copperpour not_allowed)
			(footprints allowed)
		)
		(placement
			(enabled no)
			(sheetname "")
		)
		(fill yes
			(thermal_gap 0.5)
			(thermal_bridge_width 0.5)
			(island_removal_mode 0)
		)
		(polygon
			(pts
				(arc
					(start 94.705932 -240.434368)
					(mid 94.076012 -240.434368)
					(end 94.705932 -240.434368)
				)
			)
		)
	)
	(zone
		(layers "B.Cu" "In4.Cu" "In6.Cu" "In11.Cu" "In13.Cu" "In15.Cu")
		(hatch none 0.5)
		(connect_pads
			(clearance 0)
		)
		(min_thickness 0.25)
		(keepout
			(tracks not_allowed)
			(vias allowed)
			(pads allowed)
			(copperpour not_allowed)
			(footprints allowed)
		)
		(placement
			(enabled no)
			(sheetname "")
		)
		(fill yes
			(thermal_gap 0.5)
			(thermal_bridge_width 0.5)
			(island_removal_mode 0)
		)
		(polygon
			(pts
				(arc
					(start 344.356182 -289.475926)
					(mid 343.726262 -289.475926)
					(end 344.356182 -289.475926)
				)
			)
		)
	)
	(zone
		(layers "B.Cu" "In4.Cu" "In6.Cu" "In11.Cu" "In13.Cu" "In15.Cu")
		(hatch none 0.5)
		(connect_pads
			(clearance 0)
		)
		(min_thickness 0.25)
		(keepout
			(tracks not_allowed)
			(vias allowed)
			(pads allowed)
			(copperpour not_allowed)
			(footprints allowed)
		)
		(placement
			(enabled no)
			(sheetname "")
		)
		(fill yes
			(thermal_gap 0.5)
			(thermal_bridge_width 0.5)
			(island_removal_mode 0)
		)
		(polygon
			(pts
				(arc
					(start 95.005906 -283.806392)
					(mid 94.375986 -283.806392)
					(end 95.005906 -283.806392)
				)
			)
		)
	)
	(zone
		(layers "B.Cu" "In4.Cu" "In6.Cu" "In11.Cu" "In13.Cu" "In15.Cu")
		(hatch none 0.5)
		(connect_pads
			(clearance 0)
		)
		(min_thickness 0.25)
		(keepout
			(tracks not_allowed)
			(vias allowed)
			(pads allowed)
			(copperpour not_allowed)
			(footprints allowed)
		)
		(placement
			(enabled no)
			(sheetname "")
		)
		(fill yes
			(thermal_gap 0.5)
			(thermal_bridge_width 0.5)
			(island_removal_mode 0)
		)
		(polygon
			(pts
				(arc
					(start 427.790102 -316.335156)
					(mid 427.122082 -316.335156)
					(end 427.790102 -316.335156)
				)
			)
		)
	)
	(zone
		(layers "B.Cu" "In4.Cu" "In6.Cu" "In11.Cu" "In13.Cu" "In15.Cu")
		(hatch none 0.5)
		(connect_pads
			(clearance 0)
		)
		(min_thickness 0.25)
		(keepout
			(tracks not_allowed)
			(vias allowed)
			(pads allowed)
			(copperpour not_allowed)
			(footprints allowed)
		)
		(placement
			(enabled no)
			(sheetname "")
		)
		(fill yes
			(thermal_gap 0.5)
			(thermal_bridge_width 0.5)
			(island_removal_mode 0)
		)
		(polygon
			(pts
				(arc
					(start 95.94596 -293.52621)
					(mid 95.31604 -293.52621)
					(end 95.94596 -293.52621)
				)
			)
		)
	)
	(zone
		(layers "B.Cu" "In4.Cu" "In6.Cu" "In11.Cu" "In13.Cu" "In15.Cu")
		(hatch none 0.5)
		(connect_pads
			(clearance 0)
		)
		(min_thickness 0.25)
		(keepout
			(tracks not_allowed)
			(vias allowed)
			(pads allowed)
			(copperpour not_allowed)
			(footprints allowed)
		)
		(placement
			(enabled no)
			(sheetname "")
		)
		(fill yes
			(thermal_gap 0.5)
			(thermal_bridge_width 0.5)
			(island_removal_mode 0)
		)
		(polygon
			(pts
				(arc
					(start 427.790102 -306.985162)
					(mid 427.122082 -306.985162)
					(end 427.790102 -306.985162)
				)
			)
		)
	)
	(zone
		(layers "B.Cu" "In4.Cu" "In6.Cu" "In11.Cu" "In13.Cu" "In15.Cu")
		(hatch none 0.5)
		(connect_pads
			(clearance 0)
		)
		(min_thickness 0.25)
		(keepout
			(tracks not_allowed)
			(vias allowed)
			(pads allowed)
			(copperpour not_allowed)
			(footprints allowed)
		)
		(placement
			(enabled no)
			(sheetname "")
		)
		(fill yes
			(thermal_gap 0.5)
			(thermal_bridge_width 0.5)
			(island_removal_mode 0)
		)
		(polygon
			(pts
				(arc
					(start 183.950102 -304.435256)
					(mid 183.282082 -304.435256)
					(end 183.950102 -304.435256)
				)
			)
		)
	)
	(zone
		(layers "B.Cu" "In4.Cu" "In6.Cu" "In11.Cu" "In13.Cu" "In15.Cu")
		(hatch none 0.5)
		(connect_pads
			(clearance 0)
		)
		(min_thickness 0.25)
		(keepout
			(tracks not_allowed)
			(vias allowed)
			(pads allowed)
			(copperpour not_allowed)
			(footprints allowed)
		)
		(placement
			(enabled no)
			(sheetname "")
		)
		(fill yes
			(thermal_gap 0.5)
			(thermal_bridge_width 0.5)
			(island_removal_mode 0)
		)
		(polygon
			(pts
				(arc
					(start 183.950102 -245.785386)
					(mid 183.282082 -245.785386)
					(end 183.950102 -245.785386)
				)
			)
		)
	)
	(zone
		(layers "B.Cu" "In4.Cu" "In6.Cu" "In11.Cu" "In13.Cu" "In15.Cu")
		(hatch none 0.5)
		(connect_pads
			(clearance 0)
		)
		(min_thickness 0.25)
		(keepout
			(tracks not_allowed)
			(vias allowed)
			(pads allowed)
			(copperpour not_allowed)
			(footprints allowed)
		)
		(placement
			(enabled no)
			(sheetname "")
		)
		(fill yes
			(thermal_gap 0.5)
			(thermal_bridge_width 0.5)
			(island_removal_mode 0)
		)
		(polygon
			(pts
				(arc
					(start 342.945974 -278.946102)
					(mid 342.316054 -278.946102)
					(end 342.945974 -278.946102)
				)
			)
		)
	)
	(zone
		(layers "B.Cu" "In4.Cu" "In6.Cu" "In11.Cu" "In13.Cu" "In15.Cu")
		(hatch none 0.5)
		(connect_pads
			(clearance 0)
		)
		(min_thickness 0.25)
		(keepout
			(tracks not_allowed)
			(vias allowed)
			(pads allowed)
			(copperpour not_allowed)
			(footprints allowed)
		)
		(placement
			(enabled no)
			(sheetname "")
		)
		(fill yes
			(thermal_gap 0.5)
			(thermal_bridge_width 0.5)
			(island_removal_mode 0)
		)
		(polygon
			(pts
				(arc
					(start 376.77979 -262.745982)
					(mid 376.14987 -262.745982)
					(end 376.77979 -262.745982)
				)
			)
		)
	)
	(zone
		(layers "B.Cu" "In4.Cu" "In6.Cu" "In11.Cu" "In13.Cu" "In15.Cu")
		(hatch none 0.5)
		(connect_pads
			(clearance 0)
		)
		(min_thickness 0.25)
		(keepout
			(tracks not_allowed)
			(vias allowed)
			(pads allowed)
			(copperpour not_allowed)
			(footprints allowed)
		)
		(placement
			(enabled no)
			(sheetname "")
		)
		(fill yes
			(thermal_gap 0.5)
			(thermal_bridge_width 0.5)
			(island_removal_mode 0)
		)
		(polygon
			(pts
				(arc
					(start 128.839722 -282.18638)
					(mid 128.209802 -282.18638)
					(end 128.839722 -282.18638)
				)
			)
		)
	)
	(zone
		(layers "B.Cu" "In4.Cu" "In6.Cu" "In11.Cu" "In13.Cu" "In15.Cu")
		(hatch none 0.5)
		(connect_pads
			(clearance 0)
		)
		(min_thickness 0.25)
		(keepout
			(tracks not_allowed)
			(vias allowed)
			(pads allowed)
			(copperpour not_allowed)
			(footprints allowed)
		)
		(placement
			(enabled no)
			(sheetname "")
		)
		(fill yes
			(thermal_gap 0.5)
			(thermal_bridge_width 0.5)
			(island_removal_mode 0)
		)
		(polygon
			(pts
				(arc
					(start 377.88977 -234.764072)
					(mid 377.25985 -234.764072)
					(end 377.88977 -234.764072)
				)
			)
		)
	)
	(zone
		(layers "B.Cu" "In4.Cu" "In6.Cu" "In11.Cu" "In13.Cu" "In15.Cu")
		(hatch none 0.5)
		(connect_pads
			(clearance 0)
		)
		(min_thickness 0.25)
		(keepout
			(tracks not_allowed)
			(vias allowed)
			(pads allowed)
			(copperpour not_allowed)
			(footprints allowed)
		)
		(placement
			(enabled no)
			(sheetname "")
		)
		(fill yes
			(thermal_gap 0.5)
			(thermal_bridge_width 0.5)
			(island_removal_mode 0)
		)
		(polygon
			(pts
				(arc
					(start 179.850034 -306.985416)
					(mid 179.182014 -306.985416)
					(end 179.850034 -306.985416)
				)
			)
		)
	)
	(zone
		(layers "B.Cu" "In4.Cu" "In6.Cu" "In11.Cu" "In13.Cu" "In15.Cu")
		(hatch none 0.5)
		(connect_pads
			(clearance 0)
		)
		(min_thickness 0.25)
		(keepout
			(tracks not_allowed)
			(vias allowed)
			(pads allowed)
			(copperpour not_allowed)
			(footprints allowed)
		)
		(placement
			(enabled no)
			(sheetname "")
		)
		(fill yes
			(thermal_gap 0.5)
			(thermal_bridge_width 0.5)
			(island_removal_mode 0)
		)
		(polygon
			(pts
				(arc
					(start 376.009662 -238.004096)
					(mid 375.379742 -238.004096)
					(end 376.009662 -238.004096)
				)
			)
		)
	)
	(zone
		(layers "B.Cu" "In4.Cu" "In6.Cu" "In11.Cu" "In13.Cu" "In15.Cu")
		(hatch none 0.5)
		(connect_pads
			(clearance 0)
		)
		(min_thickness 0.25)
		(keepout
			(tracks not_allowed)
			(vias allowed)
			(pads allowed)
			(copperpour not_allowed)
			(footprints allowed)
		)
		(placement
			(enabled no)
			(sheetname "")
		)
		(fill yes
			(thermal_gap 0.5)
			(thermal_bridge_width 0.5)
			(island_removal_mode 0)
		)
		(polygon
			(pts
				(arc
					(start 44.674028 -276.385274)
					(mid 44.006008 -276.385274)
					(end 44.674028 -276.385274)
				)
			)
		)
	)
	(zone
		(layers "B.Cu" "In4.Cu" "In6.Cu" "In11.Cu" "In13.Cu" "In15.Cu")
		(hatch none 0.5)
		(connect_pads
			(clearance 0)
		)
		(min_thickness 0.25)
		(keepout
			(tracks not_allowed)
			(vias allowed)
			(pads allowed)
			(copperpour not_allowed)
			(footprints allowed)
		)
		(placement
			(enabled no)
			(sheetname "")
		)
		(fill yes
			(thermal_gap 0.5)
			(thermal_bridge_width 0.5)
			(island_removal_mode 0)
		)
		(polygon
			(pts
				(arc
					(start 377.88977 -228.284278)
					(mid 377.25985 -228.284278)
					(end 377.88977 -228.284278)
				)
			)
		)
	)
	(zone
		(layers "B.Cu" "In4.Cu" "In6.Cu" "In11.Cu" "In13.Cu" "In15.Cu")
		(hatch none 0.5)
		(connect_pads
			(clearance 0)
		)
		(min_thickness 0.25)
		(keepout
			(tracks not_allowed)
			(vias allowed)
			(pads allowed)
			(copperpour not_allowed)
			(footprints allowed)
		)
		(placement
			(enabled no)
			(sheetname "")
		)
		(fill yes
			(thermal_gap 0.5)
			(thermal_bridge_width 0.5)
			(island_removal_mode 0)
		)
		(polygon
			(pts
				(arc
					(start 373.189754 -228.284278)
					(mid 372.559834 -228.284278)
					(end 373.189754 -228.284278)
				)
			)
		)
	)
	(zone
		(layers "B.Cu" "In4.Cu" "In6.Cu" "In11.Cu" "In13.Cu" "In15.Cu")
		(hatch none 0.5)
		(connect_pads
			(clearance 0)
		)
		(min_thickness 0.25)
		(keepout
			(tracks not_allowed)
			(vias allowed)
			(pads allowed)
			(copperpour not_allowed)
			(footprints allowed)
		)
		(placement
			(enabled no)
			(sheetname "")
		)
		(fill yes
			(thermal_gap 0.5)
			(thermal_bridge_width 0.5)
			(island_removal_mode 0)
		)
		(polygon
			(pts
				(arc
					(start 350.936052 -294.335962)
					(mid 350.306132 -294.335962)
					(end 350.936052 -294.335962)
				)
			)
		)
	)
	(zone
		(layers "B.Cu" "In4.Cu" "In6.Cu" "In11.Cu" "In13.Cu" "In15.Cu")
		(hatch none 0.5)
		(connect_pads
			(clearance 0)
		)
		(min_thickness 0.25)
		(keepout
			(tracks not_allowed)
			(vias allowed)
			(pads allowed)
			(copperpour not_allowed)
			(footprints allowed)
		)
		(placement
			(enabled no)
			(sheetname "")
		)
		(fill yes
			(thermal_gap 0.5)
			(thermal_bridge_width 0.5)
			(island_removal_mode 0)
		)
		(polygon
			(pts
				(arc
					(start 183.950102 -315.485272)
					(mid 183.282082 -315.485272)
					(end 183.950102 -315.485272)
				)
			)
		)
	)
	(zone
		(layers "B.Cu" "In4.Cu" "In6.Cu" "In11.Cu" "In13.Cu" "In15.Cu")
		(hatch none 0.5)
		(connect_pads
			(clearance 0)
		)
		(min_thickness 0.25)
		(keepout
			(tracks not_allowed)
			(vias allowed)
			(pads allowed)
			(copperpour not_allowed)
			(footprints allowed)
		)
		(placement
			(enabled no)
			(sheetname "")
		)
		(fill yes
			(thermal_gap 0.5)
			(thermal_bridge_width 0.5)
			(island_removal_mode 0)
		)
		(polygon
			(pts
				(arc
					(start 342.945974 -269.22603)
					(mid 342.316054 -269.22603)
					(end 342.945974 -269.22603)
				)
			)
		)
	)
	(zone
		(layers "B.Cu" "In4.Cu" "In6.Cu" "In11.Cu" "In13.Cu" "In15.Cu")
		(hatch none 0.5)
		(connect_pads
			(clearance 0)
		)
		(min_thickness 0.25)
		(keepout
			(tracks not_allowed)
			(vias allowed)
			(pads allowed)
			(copperpour not_allowed)
			(footprints allowed)
		)
		(placement
			(enabled no)
			(sheetname "")
		)
		(fill yes
			(thermal_gap 0.5)
			(thermal_bridge_width 0.5)
			(island_removal_mode 0)
		)
		(polygon
			(pts
				(arc
					(start 342.476074 -281.37612)
					(mid 341.846154 -281.37612)
					(end 342.476074 -281.37612)
				)
			)
		)
	)
	(zone
		(layers "B.Cu" "In4.Cu" "In6.Cu" "In11.Cu" "In13.Cu" "In15.Cu")
		(hatch none 0.5)
		(connect_pads
			(clearance 0)
		)
		(min_thickness 0.25)
		(keepout
			(tracks not_allowed)
			(vias allowed)
			(pads allowed)
			(copperpour not_allowed)
			(footprints allowed)
		)
		(placement
			(enabled no)
			(sheetname "")
		)
		(fill yes
			(thermal_gap 0.5)
			(thermal_bridge_width 0.5)
			(island_removal_mode 0)
		)
		(polygon
			(pts
				(arc
					(start 344.356182 -261.935976)
					(mid 343.726262 -261.935976)
					(end 344.356182 -261.935976)
				)
			)
		)
	)
	(zone
		(layers "B.Cu" "In4.Cu" "In6.Cu" "In11.Cu" "In13.Cu" "In15.Cu")
		(hatch none 0.5)
		(connect_pads
			(clearance 0)
		)
		(min_thickness 0.25)
		(keepout
			(tracks not_allowed)
			(vias allowed)
			(pads allowed)
			(copperpour not_allowed)
			(footprints allowed)
		)
		(placement
			(enabled no)
			(sheetname "")
		)
		(fill yes
			(thermal_gap 0.5)
			(thermal_bridge_width 0.5)
			(island_removal_mode 0)
		)
		(polygon
			(pts
				(arc
					(start 107.396026 -226.66452)
					(mid 106.766106 -226.66452)
					(end 107.396026 -226.66452)
				)
			)
		)
	)
	(zone
		(layers "B.Cu" "In4.Cu" "In6.Cu" "In11.Cu" "In13.Cu" "In15.Cu")
		(hatch none 0.5)
		(connect_pads
			(clearance 0)
		)
		(min_thickness 0.25)
		(keepout
			(tracks not_allowed)
			(vias allowed)
			(pads allowed)
			(copperpour not_allowed)
			(footprints allowed)
		)
		(placement
			(enabled no)
			(sheetname "")
		)
		(fill yes
			(thermal_gap 0.5)
			(thermal_bridge_width 0.5)
			(island_removal_mode 0)
		)
		(polygon
			(pts
				(arc
					(start 431.89017 -317.18504)
					(mid 431.22215 -317.18504)
					(end 431.89017 -317.18504)
				)
			)
		)
	)
	(zone
		(layers "B.Cu" "In4.Cu" "In6.Cu" "In11.Cu" "In13.Cu" "In15.Cu")
		(hatch none 0.5)
		(connect_pads
			(clearance 0)
		)
		(min_thickness 0.25)
		(keepout
			(tracks not_allowed)
			(vias allowed)
			(pads allowed)
			(copperpour not_allowed)
			(footprints allowed)
		)
		(placement
			(enabled no)
			(sheetname "")
		)
		(fill yes
			(thermal_gap 0.5)
			(thermal_bridge_width 0.5)
			(island_removal_mode 0)
		)
		(polygon
			(pts
				(arc
					(start 342.476074 -284.616144)
					(mid 341.846154 -284.616144)
					(end 342.476074 -284.616144)
				)
			)
		)
	)
	(zone
		(layers "B.Cu" "In4.Cu" "In6.Cu" "In11.Cu" "In13.Cu" "In15.Cu")
		(hatch none 0.5)
		(connect_pads
			(clearance 0)
		)
		(min_thickness 0.25)
		(keepout
			(tracks not_allowed)
			(vias allowed)
			(pads allowed)
			(copperpour not_allowed)
			(footprints allowed)
		)
		(placement
			(enabled no)
			(sheetname "")
		)
		(fill yes
			(thermal_gap 0.5)
			(thermal_bridge_width 0.5)
			(island_removal_mode 0)
		)
		(polygon
			(pts
				(arc
					(start 288.514028 -263.634982)
					(mid 287.846008 -263.634982)
					(end 288.514028 -263.634982)
				)
			)
		)
	)
	(zone
		(layers "B.Cu" "In4.Cu" "In6.Cu" "In11.Cu" "In13.Cu" "In15.Cu")
		(hatch none 0.5)
		(connect_pads
			(clearance 0)
		)
		(min_thickness 0.25)
		(keepout
			(tracks not_allowed)
			(vias allowed)
			(pads allowed)
			(copperpour not_allowed)
			(footprints allowed)
		)
		(placement
			(enabled no)
			(sheetname "")
		)
		(fill yes
			(thermal_gap 0.5)
			(thermal_bridge_width 0.5)
			(island_removal_mode 0)
		)
		(polygon
			(pts
				(arc
					(start 40.57396 -286.585406)
					(mid 39.90594 -286.585406)
					(end 40.57396 -286.585406)
				)
			)
		)
	)
	(zone
		(layers "B.Cu" "In4.Cu" "In6.Cu" "In11.Cu" "In13.Cu" "In15.Cu")
		(hatch none 0.5)
		(connect_pads
			(clearance 0)
		)
		(min_thickness 0.25)
		(keepout
			(tracks not_allowed)
			(vias allowed)
			(pads allowed)
			(copperpour not_allowed)
			(footprints allowed)
		)
		(placement
			(enabled no)
			(sheetname "")
		)
		(fill yes
			(thermal_gap 0.5)
			(thermal_bridge_width 0.5)
			(island_removal_mode 0)
		)
		(polygon
			(pts
				(arc
					(start 183.950102 -247.485408)
					(mid 183.282082 -247.485408)
					(end 183.950102 -247.485408)
				)
			)
		)
	)
	(zone
		(layers "B.Cu" "In4.Cu" "In6.Cu" "In11.Cu" "In13.Cu" "In15.Cu")
		(hatch none 0.5)
		(connect_pads
			(clearance 0)
		)
		(min_thickness 0.25)
		(keepout
			(tracks not_allowed)
			(vias allowed)
			(pads allowed)
			(copperpour not_allowed)
			(footprints allowed)
		)
		(placement
			(enabled no)
			(sheetname "")
		)
		(fill yes
			(thermal_gap 0.5)
			(thermal_bridge_width 0.5)
			(island_removal_mode 0)
		)
		(polygon
			(pts
				(arc
					(start 343.586054 -227.474272)
					(mid 342.956134 -227.474272)
					(end 343.586054 -227.474272)
				)
			)
		)
	)
	(zone
		(layers "B.Cu" "In4.Cu" "In6.Cu" "In11.Cu" "In13.Cu" "In15.Cu")
		(hatch none 0.5)
		(connect_pads
			(clearance 0)
		)
		(min_thickness 0.25)
		(keepout
			(tracks not_allowed)
			(vias allowed)
			(pads allowed)
			(copperpour not_allowed)
			(footprints allowed)
		)
		(placement
			(enabled no)
			(sheetname "")
		)
		(fill yes
			(thermal_gap 0.5)
			(thermal_bridge_width 0.5)
			(island_removal_mode 0)
		)
		(polygon
			(pts
				(arc
					(start 128.539748 -229.094538)
					(mid 127.909828 -229.094538)
					(end 128.539748 -229.094538)
				)
			)
		)
	)
	(zone
		(layers "B.Cu" "In4.Cu" "In6.Cu" "In11.Cu" "In13.Cu" "In15.Cu")
		(hatch none 0.5)
		(connect_pads
			(clearance 0)
		)
		(min_thickness 0.25)
		(keepout
			(tracks not_allowed)
			(vias allowed)
			(pads allowed)
			(copperpour not_allowed)
			(footprints allowed)
		)
		(placement
			(enabled no)
			(sheetname "")
		)
		(fill yes
			(thermal_gap 0.5)
			(thermal_bridge_width 0.5)
			(island_removal_mode 0)
		)
		(polygon
			(pts
				(arc
					(start 376.009662 -228.284278)
					(mid 375.379742 -228.284278)
					(end 376.009662 -228.284278)
				)
			)
		)
	)
	(zone
		(layers "B.Cu" "In4.Cu" "In6.Cu" "In11.Cu" "In13.Cu" "In15.Cu")
		(hatch none 0.5)
		(connect_pads
			(clearance 0)
		)
		(min_thickness 0.25)
		(keepout
			(tracks not_allowed)
			(vias allowed)
			(pads allowed)
			(copperpour not_allowed)
			(footprints allowed)
		)
		(placement
			(enabled no)
			(sheetname "")
		)
		(fill yes
			(thermal_gap 0.5)
			(thermal_bridge_width 0.5)
			(island_removal_mode 0)
		)
		(polygon
			(pts
				(arc
					(start 94.536006 -281.376374)
					(mid 93.906086 -281.376374)
					(end 94.536006 -281.376374)
				)
			)
		)
	)
	(zone
		(layers "B.Cu" "In4.Cu" "In6.Cu" "In11.Cu" "In13.Cu" "In15.Cu")
		(hatch none 0.5)
		(connect_pads
			(clearance 0)
		)
		(min_thickness 0.25)
		(keepout
			(tracks not_allowed)
			(vias allowed)
			(pads allowed)
			(copperpour not_allowed)
			(footprints allowed)
		)
		(placement
			(enabled no)
			(sheetname "")
		)
		(fill yes
			(thermal_gap 0.5)
			(thermal_bridge_width 0.5)
			(island_removal_mode 0)
		)
		(polygon
			(pts
				(arc
					(start 376.479816 -238.814102)
					(mid 375.849896 -238.814102)
					(end 376.479816 -238.814102)
				)
			)
		)
	)
	(zone
		(layers "B.Cu" "In4.Cu" "In6.Cu" "In11.Cu" "In13.Cu" "In15.Cu")
		(hatch none 0.5)
		(connect_pads
			(clearance 0)
		)
		(min_thickness 0.25)
		(keepout
			(tracks not_allowed)
			(vias allowed)
			(pads allowed)
			(copperpour not_allowed)
			(footprints allowed)
		)
		(placement
			(enabled no)
			(sheetname "")
		)
		(fill yes
			(thermal_gap 0.5)
			(thermal_bridge_width 0.5)
			(island_removal_mode 0)
		)
		(polygon
			(pts
				(arc
					(start 342.476074 -265.176)
					(mid 341.846154 -265.176)
					(end 342.476074 -265.176)
				)
			)
		)
	)
	(zone
		(layers "B.Cu" "In4.Cu" "In6.Cu" "In11.Cu" "In13.Cu" "In15.Cu")
		(hatch none 0.5)
		(connect_pads
			(clearance 0)
		)
		(min_thickness 0.25)
		(keepout
			(tracks not_allowed)
			(vias allowed)
			(pads allowed)
			(copperpour not_allowed)
			(footprints allowed)
		)
		(placement
			(enabled no)
			(sheetname "")
		)
		(fill yes
			(thermal_gap 0.5)
			(thermal_bridge_width 0.5)
			(island_removal_mode 0)
		)
		(polygon
			(pts
				(arc
					(start 292.614096 -240.685066)
					(mid 291.946076 -240.685066)
					(end 292.614096 -240.685066)
				)
			)
		)
	)
	(zone
		(layers "B.Cu" "In4.Cu" "In6.Cu" "In11.Cu" "In13.Cu" "In15.Cu")
		(hatch none 0.5)
		(connect_pads
			(clearance 0)
		)
		(min_thickness 0.25)
		(keepout
			(tracks not_allowed)
			(vias allowed)
			(pads allowed)
			(copperpour not_allowed)
			(footprints allowed)
		)
		(placement
			(enabled no)
			(sheetname "")
		)
		(fill yes
			(thermal_gap 0.5)
			(thermal_bridge_width 0.5)
			(island_removal_mode 0)
		)
		(polygon
			(pts
				(arc
					(start 128.539748 -232.334308)
					(mid 127.909828 -232.334308)
					(end 128.539748 -232.334308)
				)
			)
		)
	)
	(zone
		(layers "B.Cu" "In4.Cu" "In6.Cu" "In11.Cu" "In13.Cu" "In15.Cu")
		(hatch none 0.5)
		(connect_pads
			(clearance 0)
		)
		(min_thickness 0.25)
		(keepout
			(tracks not_allowed)
			(vias allowed)
			(pads allowed)
			(copperpour not_allowed)
			(footprints allowed)
		)
		(placement
			(enabled no)
			(sheetname "")
		)
		(fill yes
			(thermal_gap 0.5)
			(thermal_bridge_width 0.5)
			(island_removal_mode 0)
		)
		(polygon
			(pts
				(arc
					(start 376.30989 -261.935976)
					(mid 375.67997 -261.935976)
					(end 376.30989 -261.935976)
				)
			)
		)
	)
	(zone
		(layers "B.Cu" "In4.Cu" "In6.Cu" "In11.Cu" "In13.Cu" "In15.Cu")
		(hatch none 0.5)
		(connect_pads
			(clearance 0)
		)
		(min_thickness 0.25)
		(keepout
			(tracks not_allowed)
			(vias allowed)
			(pads allowed)
			(copperpour not_allowed)
			(footprints allowed)
		)
		(placement
			(enabled no)
			(sheetname "")
		)
		(fill yes
			(thermal_gap 0.5)
			(thermal_bridge_width 0.5)
			(island_removal_mode 0)
		)
		(polygon
			(pts
				(arc
					(start 427.790102 -238.985044)
					(mid 427.122082 -238.985044)
					(end 427.790102 -238.985044)
				)
			)
		)
	)
	(zone
		(layers "B.Cu" "In4.Cu" "In6.Cu" "In11.Cu" "In13.Cu" "In15.Cu")
		(hatch none 0.5)
		(connect_pads
			(clearance 0)
		)
		(min_thickness 0.25)
		(keepout
			(tracks not_allowed)
			(vias allowed)
			(pads allowed)
			(copperpour not_allowed)
			(footprints allowed)
		)
		(placement
			(enabled no)
			(sheetname "")
		)
		(fill yes
			(thermal_gap 0.5)
			(thermal_bridge_width 0.5)
			(island_removal_mode 0)
		)
		(polygon
			(pts
				(arc
					(start 44.674028 -210.085432)
					(mid 44.006008 -210.085432)
					(end 44.674028 -210.085432)
				)
			)
		)
	)
	(zone
		(layers "B.Cu" "In4.Cu" "In6.Cu" "In11.Cu" "In13.Cu" "In15.Cu")
		(hatch none 0.5)
		(connect_pads
			(clearance 0)
		)
		(min_thickness 0.25)
		(keepout
			(tracks not_allowed)
			(vias allowed)
			(pads allowed)
			(copperpour not_allowed)
			(footprints allowed)
		)
		(placement
			(enabled no)
			(sheetname "")
		)
		(fill yes
			(thermal_gap 0.5)
			(thermal_bridge_width 0.5)
			(island_removal_mode 0)
		)
		(polygon
			(pts
				(arc
					(start 342.646 -246.914162)
					(mid 342.01608 -246.914162)
					(end 342.646 -246.914162)
				)
			)
		)
	)
	(zone
		(layers "B.Cu" "In4.Cu" "In6.Cu" "In11.Cu" "In13.Cu" "In15.Cu")
		(hatch none 0.5)
		(connect_pads
			(clearance 0)
		)
		(min_thickness 0.25)
		(keepout
			(tracks not_allowed)
			(vias allowed)
			(pads allowed)
			(copperpour not_allowed)
			(footprints allowed)
		)
		(placement
			(enabled no)
			(sheetname "")
		)
		(fill yes
			(thermal_gap 0.5)
			(thermal_bridge_width 0.5)
			(island_removal_mode 0)
		)
		(polygon
			(pts
				(arc
					(start 376.009662 -246.104156)
					(mid 375.379742 -246.104156)
					(end 376.009662 -246.104156)
				)
			)
		)
	)
	(zone
		(layers "B.Cu" "In4.Cu" "In6.Cu" "In11.Cu" "In13.Cu" "In15.Cu")
		(hatch none 0.5)
		(connect_pads
			(clearance 0)
		)
		(min_thickness 0.25)
		(keepout
			(tracks not_allowed)
			(vias allowed)
			(pads allowed)
			(copperpour not_allowed)
			(footprints allowed)
		)
		(placement
			(enabled no)
			(sheetname "")
		)
		(fill yes
			(thermal_gap 0.5)
			(thermal_bridge_width 0.5)
			(island_removal_mode 0)
		)
		(polygon
			(pts
				(arc
					(start 129.479802 -227.474526)
					(mid 128.849882 -227.474526)
					(end 129.479802 -227.474526)
				)
			)
		)
	)
	(zone
		(layers "B.Cu" "In4.Cu" "In6.Cu" "In11.Cu" "In13.Cu" "In15.Cu")
		(hatch none 0.5)
		(connect_pads
			(clearance 0)
		)
		(min_thickness 0.25)
		(keepout
			(tracks not_allowed)
			(vias allowed)
			(pads allowed)
			(copperpour not_allowed)
			(footprints allowed)
		)
		(placement
			(enabled no)
			(sheetname "")
		)
		(fill yes
			(thermal_gap 0.5)
			(thermal_bridge_width 0.5)
			(island_removal_mode 0)
		)
		(polygon
			(pts
				(arc
					(start 427.790102 -201.585068)
					(mid 427.122082 -201.585068)
					(end 427.790102 -201.585068)
				)
			)
		)
	)
	(zone
		(layers "B.Cu" "In4.Cu" "In6.Cu" "In11.Cu" "In13.Cu" "In15.Cu")
		(hatch none 0.5)
		(connect_pads
			(clearance 0)
		)
		(min_thickness 0.25)
		(keepout
			(tracks not_allowed)
			(vias allowed)
			(pads allowed)
			(copperpour not_allowed)
			(footprints allowed)
		)
		(placement
			(enabled no)
			(sheetname "")
		)
		(fill yes
			(thermal_gap 0.5)
			(thermal_bridge_width 0.5)
			(island_removal_mode 0)
		)
		(polygon
			(pts
				(arc
					(start 288.514028 -244.934994)
					(mid 287.846008 -244.934994)
					(end 288.514028 -244.934994)
				)
			)
		)
	)
	(zone
		(layers "B.Cu" "In4.Cu" "In6.Cu" "In11.Cu" "In13.Cu" "In15.Cu")
		(hatch none 0.5)
		(connect_pads
			(clearance 0)
		)
		(min_thickness 0.25)
		(keepout
			(tracks not_allowed)
			(vias allowed)
			(pads allowed)
			(copperpour not_allowed)
			(footprints allowed)
		)
		(placement
			(enabled no)
			(sheetname "")
		)
		(fill yes
			(thermal_gap 0.5)
			(thermal_bridge_width 0.5)
			(island_removal_mode 0)
		)
		(polygon
			(pts
				(arc
					(start 292.614096 -206.685134)
					(mid 291.946076 -206.685134)
					(end 292.614096 -206.685134)
				)
			)
		)
	)
	(zone
		(layers "B.Cu" "In4.Cu" "In6.Cu" "In11.Cu" "In13.Cu" "In15.Cu")
		(hatch none 0.5)
		(connect_pads
			(clearance 0)
		)
		(min_thickness 0.25)
		(keepout
			(tracks not_allowed)
			(vias allowed)
			(pads allowed)
			(copperpour not_allowed)
			(footprints allowed)
		)
		(placement
			(enabled no)
			(sheetname "")
		)
		(fill yes
			(thermal_gap 0.5)
			(thermal_bridge_width 0.5)
			(island_removal_mode 0)
		)
		(polygon
			(pts
				(arc
					(start 130.249676 -279.756362)
					(mid 129.619756 -279.756362)
					(end 130.249676 -279.756362)
				)
			)
		)
	)
	(zone
		(layers "B.Cu" "In4.Cu" "In6.Cu" "In11.Cu" "In13.Cu" "In15.Cu")
		(hatch none 0.5)
		(connect_pads
			(clearance 0)
		)
		(min_thickness 0.25)
		(keepout
			(tracks not_allowed)
			(vias allowed)
			(pads allowed)
			(copperpour not_allowed)
			(footprints allowed)
		)
		(placement
			(enabled no)
			(sheetname "")
		)
		(fill yes
			(thermal_gap 0.5)
			(thermal_bridge_width 0.5)
			(island_removal_mode 0)
		)
		(polygon
			(pts
				(arc
					(start 128.069594 -242.864386)
					(mid 127.439674 -242.864386)
					(end 128.069594 -242.864386)
				)
			)
		)
	)
	(zone
		(layers "B.Cu" "In4.Cu" "In6.Cu" "In11.Cu" "In13.Cu" "In15.Cu")
		(hatch none 0.5)
		(connect_pads
			(clearance 0)
		)
		(min_thickness 0.25)
		(keepout
			(tracks not_allowed)
			(vias allowed)
			(pads allowed)
			(copperpour not_allowed)
			(footprints allowed)
		)
		(placement
			(enabled no)
			(sheetname "")
		)
		(fill yes
			(thermal_gap 0.5)
			(thermal_bridge_width 0.5)
			(island_removal_mode 0)
		)
		(polygon
			(pts
				(arc
					(start 179.850034 -280.635202)
					(mid 179.182014 -280.635202)
					(end 179.850034 -280.635202)
				)
			)
		)
	)
	(zone
		(layers "B.Cu" "In4.Cu" "In6.Cu" "In11.Cu" "In13.Cu" "In15.Cu")
		(hatch none 0.5)
		(connect_pads
			(clearance 0)
		)
		(min_thickness 0.25)
		(keepout
			(tracks not_allowed)
			(vias allowed)
			(pads allowed)
			(copperpour not_allowed)
			(footprints allowed)
		)
		(placement
			(enabled no)
			(sheetname "")
		)
		(fill yes
			(thermal_gap 0.5)
			(thermal_bridge_width 0.5)
			(island_removal_mode 0)
		)
		(polygon
			(pts
				(arc
					(start 377.88977 -255.824228)
					(mid 377.25985 -255.824228)
					(end 377.88977 -255.824228)
				)
			)
		)
	)
	(zone
		(layers "B.Cu" "In4.Cu" "In6.Cu" "In11.Cu" "In13.Cu" "In15.Cu")
		(hatch none 0.5)
		(connect_pads
			(clearance 0)
		)
		(min_thickness 0.25)
		(keepout
			(tracks not_allowed)
			(vias allowed)
			(pads allowed)
			(copperpour not_allowed)
			(footprints allowed)
		)
		(placement
			(enabled no)
			(sheetname "")
		)
		(fill yes
			(thermal_gap 0.5)
			(thermal_bridge_width 0.5)
			(island_removal_mode 0)
		)
		(polygon
			(pts
				(arc
					(start 115.167918 -22.532594)
					(mid 114.499898 -22.532594)
					(end 115.167918 -22.532594)
				)
			)
		)
	)
	(zone
		(layers "B.Cu" "In4.Cu" "In6.Cu" "In11.Cu" "In13.Cu" "In15.Cu")
		(hatch none 0.5)
		(connect_pads
			(clearance 0)
		)
		(min_thickness 0.25)
		(keepout
			(tracks not_allowed)
			(vias allowed)
			(pads allowed)
			(copperpour not_allowed)
			(footprints allowed)
		)
		(placement
			(enabled no)
			(sheetname "")
		)
		(fill yes
			(thermal_gap 0.5)
			(thermal_bridge_width 0.5)
			(island_removal_mode 0)
		)
		(polygon
			(pts
				(arc
					(start 40.57396 -312.085228)
					(mid 39.90594 -312.085228)
					(end 40.57396 -312.085228)
				)
			)
		)
	)
	(zone
		(layers "B.Cu" "In4.Cu" "In6.Cu" "In11.Cu" "In13.Cu" "In15.Cu")
		(hatch none 0.5)
		(connect_pads
			(clearance 0)
		)
		(min_thickness 0.25)
		(keepout
			(tracks not_allowed)
			(vias allowed)
			(pads allowed)
			(copperpour not_allowed)
			(footprints allowed)
		)
		(placement
			(enabled no)
			(sheetname "")
		)
		(fill yes
			(thermal_gap 0.5)
			(thermal_bridge_width 0.5)
			(island_removal_mode 0)
		)
		(polygon
			(pts
				(arc
					(start 104.576118 -226.66452)
					(mid 103.946198 -226.66452)
					(end 104.576118 -226.66452)
				)
			)
		)
	)
	(zone
		(layers "B.Cu" "In4.Cu" "In6.Cu" "In11.Cu" "In13.Cu" "In15.Cu")
		(hatch none 0.5)
		(connect_pads
			(clearance 0)
		)
		(min_thickness 0.25)
		(keepout
			(tracks not_allowed)
			(vias allowed)
			(pads allowed)
			(copperpour not_allowed)
			(footprints allowed)
		)
		(placement
			(enabled no)
			(sheetname "")
		)
		(fill yes
			(thermal_gap 0.5)
			(thermal_bridge_width 0.5)
			(island_removal_mode 0)
		)
		(polygon
			(pts
				(arc
					(start 376.30989 -274.896072)
					(mid 375.67997 -274.896072)
					(end 376.30989 -274.896072)
				)
			)
		)
	)
	(zone
		(layers "B.Cu" "In4.Cu" "In6.Cu" "In11.Cu" "In13.Cu" "In15.Cu")
		(hatch none 0.5)
		(connect_pads
			(clearance 0)
		)
		(min_thickness 0.25)
		(keepout
			(tracks not_allowed)
			(vias allowed)
			(pads allowed)
			(copperpour not_allowed)
			(footprints allowed)
		)
		(placement
			(enabled no)
			(sheetname "")
		)
		(fill yes
			(thermal_gap 0.5)
			(thermal_bridge_width 0.5)
			(island_removal_mode 0)
		)
		(polygon
			(pts
				(arc
					(start 376.30989 -271.656048)
					(mid 375.67997 -271.656048)
					(end 376.30989 -271.656048)
				)
			)
		)
	)
	(zone
		(layers "B.Cu" "In4.Cu" "In6.Cu" "In11.Cu" "In13.Cu" "In15.Cu")
		(hatch none 0.5)
		(connect_pads
			(clearance 0)
		)
		(min_thickness 0.25)
		(keepout
			(tracks not_allowed)
			(vias allowed)
			(pads allowed)
			(copperpour not_allowed)
			(footprints allowed)
		)
		(placement
			(enabled no)
			(sheetname "")
		)
		(fill yes
			(thermal_gap 0.5)
			(thermal_bridge_width 0.5)
			(island_removal_mode 0)
		)
		(polygon
			(pts
				(arc
					(start 288.514028 -201.585068)
					(mid 287.846008 -201.585068)
					(end 288.514028 -201.585068)
				)
			)
		)
	)
	(zone
		(layers "B.Cu" "In4.Cu" "In6.Cu" "In11.Cu" "In13.Cu" "In15.Cu")
		(hatch none 0.5)
		(connect_pads
			(clearance 0)
		)
		(min_thickness 0.25)
		(keepout
			(tracks not_allowed)
			(vias allowed)
			(pads allowed)
			(copperpour not_allowed)
			(footprints allowed)
		)
		(placement
			(enabled no)
			(sheetname "")
		)
		(fill yes
			(thermal_gap 0.5)
			(thermal_bridge_width 0.5)
			(island_removal_mode 0)
		)
		(polygon
			(pts
				(arc
					(start 427.790102 -207.535018)
					(mid 427.122082 -207.535018)
					(end 427.790102 -207.535018)
				)
			)
		)
	)
	(zone
		(layers "B.Cu" "In4.Cu" "In6.Cu" "In11.Cu" "In13.Cu" "In15.Cu")
		(hatch none 0.5)
		(connect_pads
			(clearance 0)
		)
		(min_thickness 0.25)
		(keepout
			(tracks not_allowed)
			(vias allowed)
			(pads allowed)
			(copperpour not_allowed)
			(footprints allowed)
		)
		(placement
			(enabled no)
			(sheetname "")
		)
		(fill yes
			(thermal_gap 0.5)
			(thermal_bridge_width 0.5)
			(island_removal_mode 0)
		)
		(polygon
			(pts
				(arc
					(start 183.950102 -281.48534)
					(mid 183.282082 -281.48534)
					(end 183.950102 -281.48534)
				)
			)
		)
	)
	(zone
		(layers "B.Cu" "In4.Cu" "In6.Cu" "In11.Cu" "In13.Cu" "In15.Cu")
		(hatch none 0.5)
		(connect_pads
			(clearance 0)
		)
		(min_thickness 0.25)
		(keepout
			(tracks not_allowed)
			(vias allowed)
			(pads allowed)
			(copperpour not_allowed)
			(footprints allowed)
		)
		(placement
			(enabled no)
			(sheetname "")
		)
		(fill yes
			(thermal_gap 0.5)
			(thermal_bridge_width 0.5)
			(island_removal_mode 0)
		)
		(polygon
			(pts
				(arc
					(start 431.89017 -254.284988)
					(mid 431.22215 -254.284988)
					(end 431.89017 -254.284988)
				)
			)
		)
	)
	(zone
		(layers "B.Cu" "In4.Cu" "In6.Cu" "In11.Cu" "In13.Cu" "In15.Cu")
		(hatch none 0.5)
		(connect_pads
			(clearance 0)
		)
		(min_thickness 0.25)
		(keepout
			(tracks not_allowed)
			(vias allowed)
			(pads allowed)
			(copperpour not_allowed)
			(footprints allowed)
		)
		(placement
			(enabled no)
			(sheetname "")
		)
		(fill yes
			(thermal_gap 0.5)
			(thermal_bridge_width 0.5)
			(island_removal_mode 0)
		)
		(polygon
			(pts
				(arc
					(start 94.236032 -252.584458)
					(mid 93.606112 -252.584458)
					(end 94.236032 -252.584458)
				)
			)
		)
	)
	(zone
		(layers "B.Cu" "In4.Cu" "In6.Cu" "In11.Cu" "In13.Cu" "In15.Cu")
		(hatch none 0.5)
		(connect_pads
			(clearance 0)
		)
		(min_thickness 0.25)
		(keepout
			(tracks not_allowed)
			(vias allowed)
			(pads allowed)
			(copperpour not_allowed)
			(footprints allowed)
		)
		(placement
			(enabled no)
			(sheetname "")
		)
		(fill yes
			(thermal_gap 0.5)
			(thermal_bridge_width 0.5)
			(island_removal_mode 0)
		)
		(polygon
			(pts
				(arc
					(start 342.646 -233.954066)
					(mid 342.01608 -233.954066)
					(end 342.646 -233.954066)
				)
			)
		)
	)
	(zone
		(layers "B.Cu" "In4.Cu" "In6.Cu" "In11.Cu" "In13.Cu" "In15.Cu")
		(hatch none 0.5)
		(connect_pads
			(clearance 0)
		)
		(min_thickness 0.25)
		(keepout
			(tracks not_allowed)
			(vias allowed)
			(pads allowed)
			(copperpour not_allowed)
			(footprints allowed)
		)
		(placement
			(enabled no)
			(sheetname "")
		)
		(fill yes
			(thermal_gap 0.5)
			(thermal_bridge_width 0.5)
			(island_removal_mode 0)
		)
		(polygon
			(pts
				(arc
					(start 129.779776 -269.226284)
					(mid 129.149856 -269.226284)
					(end 129.779776 -269.226284)
				)
			)
		)
	)
	(zone
		(layers "B.Cu" "In4.Cu" "In6.Cu" "In11.Cu" "In13.Cu" "In15.Cu")
		(hatch none 0.5)
		(connect_pads
			(clearance 0)
		)
		(min_thickness 0.25)
		(keepout
			(tracks not_allowed)
			(vias allowed)
			(pads allowed)
			(copperpour not_allowed)
			(footprints allowed)
		)
		(placement
			(enabled no)
			(sheetname "")
		)
		(fill yes
			(thermal_gap 0.5)
			(thermal_bridge_width 0.5)
			(island_removal_mode 0)
		)
		(polygon
			(pts
				(arc
					(start 256.261108 -210.147916)
					(mid 255.593088 -210.147916)
					(end 256.261108 -210.147916)
				)
			)
		)
	)
	(zone
		(layers "B.Cu" "In4.Cu" "In6.Cu" "In11.Cu" "In13.Cu" "In15.Cu")
		(hatch none 0.5)
		(connect_pads
			(clearance 0)
		)
		(min_thickness 0.25)
		(keepout
			(tracks not_allowed)
			(vias allowed)
			(pads allowed)
			(copperpour not_allowed)
			(footprints allowed)
		)
		(placement
			(enabled no)
			(sheetname "")
		)
		(fill yes
			(thermal_gap 0.5)
			(thermal_bridge_width 0.5)
			(island_removal_mode 0)
		)
		(polygon
			(pts
				(arc
					(start 96.416114 -284.616398)
					(mid 95.786194 -284.616398)
					(end 96.416114 -284.616398)
				)
			)
		)
	)
	(zone
		(layers "B.Cu" "In4.Cu" "In6.Cu" "In11.Cu" "In13.Cu" "In15.Cu")
		(hatch none 0.5)
		(connect_pads
			(clearance 0)
		)
		(min_thickness 0.25)
		(keepout
			(tracks not_allowed)
			(vias allowed)
			(pads allowed)
			(copperpour not_allowed)
			(footprints allowed)
		)
		(placement
			(enabled no)
			(sheetname "")
		)
		(fill yes
			(thermal_gap 0.5)
			(thermal_bridge_width 0.5)
			(island_removal_mode 0)
		)
		(polygon
			(pts
				(arc
					(start 183.950102 -309.535322)
					(mid 183.282082 -309.535322)
					(end 183.950102 -309.535322)
				)
			)
		)
	)
	(zone
		(layers "B.Cu" "In4.Cu" "In6.Cu" "In11.Cu" "In13.Cu" "In15.Cu")
		(hatch none 0.5)
		(connect_pads
			(clearance 0)
		)
		(min_thickness 0.25)
		(keepout
			(tracks not_allowed)
			(vias allowed)
			(pads allowed)
			(copperpour not_allowed)
			(footprints allowed)
		)
		(placement
			(enabled no)
			(sheetname "")
		)
		(fill yes
			(thermal_gap 0.5)
			(thermal_bridge_width 0.5)
			(island_removal_mode 0)
		)
		(polygon
			(pts
				(arc
					(start 94.536006 -284.616398)
					(mid 93.906086 -284.616398)
					(end 94.536006 -284.616398)
				)
			)
		)
	)
	(zone
		(layers "B.Cu" "In4.Cu" "In6.Cu" "In11.Cu" "In13.Cu" "In15.Cu")
		(hatch none 0.5)
		(connect_pads
			(clearance 0)
		)
		(min_thickness 0.25)
		(keepout
			(tracks not_allowed)
			(vias allowed)
			(pads allowed)
			(copperpour not_allowed)
			(footprints allowed)
		)
		(placement
			(enabled no)
			(sheetname "")
		)
		(fill yes
			(thermal_gap 0.5)
			(thermal_bridge_width 0.5)
			(island_removal_mode 0)
		)
		(polygon
			(pts
				(arc
					(start 40.57396 -250.035314)
					(mid 39.90594 -250.035314)
					(end 40.57396 -250.035314)
				)
			)
		)
	)
	(zone
		(layers "B.Cu" "In4.Cu" "In6.Cu" "In11.Cu" "In13.Cu" "In15.Cu")
		(hatch none 0.5)
		(connect_pads
			(clearance 0)
		)
		(min_thickness 0.25)
		(keepout
			(tracks not_allowed)
			(vias allowed)
			(pads allowed)
			(copperpour not_allowed)
			(footprints allowed)
		)
		(placement
			(enabled no)
			(sheetname "")
		)
		(fill yes
			(thermal_gap 0.5)
			(thermal_bridge_width 0.5)
			(island_removal_mode 0)
		)
		(polygon
			(pts
				(arc
					(start 128.069594 -255.824482)
					(mid 127.439674 -255.824482)
					(end 128.069594 -255.824482)
				)
			)
		)
	)
	(zone
		(layers "B.Cu" "In4.Cu" "In6.Cu" "In11.Cu" "In13.Cu" "In15.Cu")
		(hatch none 0.5)
		(connect_pads
			(clearance 0)
		)
		(min_thickness 0.25)
		(keepout
			(tracks not_allowed)
			(vias allowed)
			(pads allowed)
			(copperpour not_allowed)
			(footprints allowed)
		)
		(placement
			(enabled no)
			(sheetname "")
		)
		(fill yes
			(thermal_gap 0.5)
			(thermal_bridge_width 0.5)
			(island_removal_mode 0)
		)
		(polygon
			(pts
				(arc
					(start 44.674028 -201.585322)
					(mid 44.006008 -201.585322)
					(end 44.674028 -201.585322)
				)
			)
		)
	)
	(zone
		(layers "B.Cu" "In4.Cu" "In6.Cu" "In11.Cu" "In13.Cu" "In15.Cu")
		(hatch none 0.5)
		(connect_pads
			(clearance 0)
		)
		(min_thickness 0.25)
		(keepout
			(tracks not_allowed)
			(vias allowed)
			(pads allowed)
			(copperpour not_allowed)
			(footprints allowed)
		)
		(placement
			(enabled no)
			(sheetname "")
		)
		(fill yes
			(thermal_gap 0.5)
			(thermal_bridge_width 0.5)
			(island_removal_mode 0)
		)
		(polygon
			(pts
				(arc
					(start 427.790102 -209.23504)
					(mid 427.122082 -209.23504)
					(end 427.790102 -209.23504)
				)
			)
		)
	)
	(zone
		(layers "B.Cu" "In4.Cu" "In6.Cu" "In11.Cu" "In13.Cu" "In15.Cu")
		(hatch none 0.5)
		(connect_pads
			(clearance 0)
		)
		(min_thickness 0.25)
		(keepout
			(tracks not_allowed)
			(vias allowed)
			(pads allowed)
			(copperpour not_allowed)
			(footprints allowed)
		)
		(placement
			(enabled no)
			(sheetname "")
		)
		(fill yes
			(thermal_gap 0.5)
			(thermal_bridge_width 0.5)
			(island_removal_mode 0)
		)
		(polygon
			(pts
				(arc
					(start 40.57396 -288.285428)
					(mid 39.90594 -288.285428)
					(end 40.57396 -288.285428)
				)
			)
		)
	)
	(zone
		(layers "B.Cu" "In4.Cu" "In6.Cu" "In11.Cu" "In13.Cu" "In15.Cu")
		(hatch none 0.5)
		(connect_pads
			(clearance 0)
		)
		(min_thickness 0.25)
		(keepout
			(tracks not_allowed)
			(vias allowed)
			(pads allowed)
			(copperpour not_allowed)
			(footprints allowed)
		)
		(placement
			(enabled no)
			(sheetname "")
		)
		(fill yes
			(thermal_gap 0.5)
			(thermal_bridge_width 0.5)
			(island_removal_mode 0)
		)
		(polygon
			(pts
				(arc
					(start 129.479802 -242.05438)
					(mid 128.849882 -242.05438)
					(end 129.479802 -242.05438)
				)
			)
		)
	)
	(zone
		(layers "B.Cu" "In4.Cu" "In6.Cu" "In11.Cu" "In13.Cu" "In15.Cu")
		(hatch none 0.5)
		(connect_pads
			(clearance 0)
		)
		(min_thickness 0.25)
		(keepout
			(tracks not_allowed)
			(vias allowed)
			(pads allowed)
			(copperpour not_allowed)
			(footprints allowed)
		)
		(placement
			(enabled no)
			(sheetname "")
		)
		(fill yes
			(thermal_gap 0.5)
			(thermal_bridge_width 0.5)
			(island_removal_mode 0)
		)
		(polygon
			(pts
				(arc
					(start 107.696 -292.716204)
					(mid 107.06608 -292.716204)
					(end 107.696 -292.716204)
				)
			)
		)
	)
	(zone
		(layers "B.Cu" "In4.Cu" "In6.Cu" "In11.Cu" "In13.Cu" "In15.Cu")
		(hatch none 0.5)
		(connect_pads
			(clearance 0)
		)
		(min_thickness 0.25)
		(keepout
			(tracks not_allowed)
			(vias allowed)
			(pads allowed)
			(copperpour not_allowed)
			(footprints allowed)
		)
		(placement
			(enabled no)
			(sheetname "")
		)
		(fill yes
			(thermal_gap 0.5)
			(thermal_bridge_width 0.5)
			(island_removal_mode 0)
		)
		(polygon
			(pts
				(arc
					(start 96.416114 -276.516338)
					(mid 95.786194 -276.516338)
					(end 96.416114 -276.516338)
				)
			)
		)
	)
	(zone
		(layers "B.Cu" "In4.Cu" "In6.Cu" "In11.Cu" "In13.Cu" "In15.Cu")
		(hatch none 0.5)
		(connect_pads
			(clearance 0)
		)
		(min_thickness 0.25)
		(keepout
			(tracks not_allowed)
			(vias allowed)
			(pads allowed)
			(copperpour not_allowed)
			(footprints allowed)
		)
		(placement
			(enabled no)
			(sheetname "")
		)
		(fill yes
			(thermal_gap 0.5)
			(thermal_bridge_width 0.5)
			(island_removal_mode 0)
		)
		(polygon
			(pts
				(arc
					(start 183.950102 -287.43529)
					(mid 183.282082 -287.43529)
					(end 183.950102 -287.43529)
				)
			)
		)
	)
	(zone
		(layers "B.Cu" "In4.Cu" "In6.Cu" "In11.Cu" "In13.Cu" "In15.Cu")
		(hatch none 0.5)
		(connect_pads
			(clearance 0)
		)
		(min_thickness 0.25)
		(keepout
			(tracks not_allowed)
			(vias allowed)
			(pads allowed)
			(copperpour not_allowed)
			(footprints allowed)
		)
		(placement
			(enabled no)
			(sheetname "")
		)
		(fill yes
			(thermal_gap 0.5)
			(thermal_bridge_width 0.5)
			(island_removal_mode 0)
		)
		(polygon
			(pts
				(arc
					(start 377.88977 -226.664266)
					(mid 377.25985 -226.664266)
					(end 377.88977 -226.664266)
				)
			)
		)
	)
	(zone
		(layers "B.Cu" "In4.Cu" "In6.Cu" "In11.Cu" "In13.Cu" "In15.Cu")
		(hatch none 0.5)
		(connect_pads
			(clearance 0)
		)
		(min_thickness 0.25)
		(keepout
			(tracks not_allowed)
			(vias allowed)
			(pads allowed)
			(copperpour not_allowed)
			(footprints allowed)
		)
		(placement
			(enabled no)
			(sheetname "")
		)
		(fill yes
			(thermal_gap 0.5)
			(thermal_bridge_width 0.5)
			(island_removal_mode 0)
		)
		(polygon
			(pts
				(arc
					(start 292.614096 -306.135024)
					(mid 291.946076 -306.135024)
					(end 292.614096 -306.135024)
				)
			)
		)
	)
	(zone
		(layers "B.Cu" "In4.Cu" "In6.Cu" "In11.Cu" "In13.Cu" "In15.Cu")
		(hatch none 0.5)
		(connect_pads
			(clearance 0)
		)
		(min_thickness 0.25)
		(keepout
			(tracks not_allowed)
			(vias allowed)
			(pads allowed)
			(copperpour not_allowed)
			(footprints allowed)
		)
		(placement
			(enabled no)
			(sheetname "")
		)
		(fill yes
			(thermal_gap 0.5)
			(thermal_bridge_width 0.5)
			(island_removal_mode 0)
		)
		(polygon
			(pts
				(arc
					(start 40.57396 -272.98523)
					(mid 39.90594 -272.98523)
					(end 40.57396 -272.98523)
				)
			)
		)
	)
	(zone
		(layers "B.Cu" "In4.Cu" "In6.Cu" "In11.Cu" "In13.Cu" "In15.Cu")
		(hatch none 0.5)
		(connect_pads
			(clearance 0)
		)
		(min_thickness 0.25)
		(keepout
			(tracks not_allowed)
			(vias allowed)
			(pads allowed)
			(copperpour not_allowed)
			(footprints allowed)
		)
		(placement
			(enabled no)
			(sheetname "")
		)
		(fill yes
			(thermal_gap 0.5)
			(thermal_bridge_width 0.5)
			(island_removal_mode 0)
		)
		(polygon
			(pts
				(arc
					(start 106.755946 -294.336216)
					(mid 106.126026 -294.336216)
					(end 106.755946 -294.336216)
				)
			)
		)
	)
	(zone
		(layers "B.Cu" "In4.Cu" "In6.Cu" "In11.Cu" "In13.Cu" "In15.Cu")
		(hatch none 0.5)
		(connect_pads
			(clearance 0)
		)
		(min_thickness 0.25)
		(keepout
			(tracks not_allowed)
			(vias allowed)
			(pads allowed)
			(copperpour not_allowed)
			(footprints allowed)
		)
		(placement
			(enabled no)
			(sheetname "")
		)
		(fill yes
			(thermal_gap 0.5)
			(thermal_bridge_width 0.5)
			(island_removal_mode 0)
		)
		(polygon
			(pts
				(arc
					(start 368.489738 -226.664266)
					(mid 367.859818 -226.664266)
					(end 368.489738 -226.664266)
				)
			)
		)
	)
	(zone
		(layers "B.Cu" "In4.Cu" "In6.Cu" "In11.Cu" "In13.Cu" "In15.Cu")
		(hatch none 0.5)
		(connect_pads
			(clearance 0)
		)
		(min_thickness 0.25)
		(keepout
			(tracks not_allowed)
			(vias allowed)
			(pads allowed)
			(copperpour not_allowed)
			(footprints allowed)
		)
		(placement
			(enabled no)
			(sheetname "")
		)
		(fill yes
			(thermal_gap 0.5)
			(thermal_bridge_width 0.5)
			(island_removal_mode 0)
		)
		(polygon
			(pts
				(arc
					(start 342.1761 -225.044254)
					(mid 341.54618 -225.044254)
					(end 342.1761 -225.044254)
				)
			)
		)
	)
	(zone
		(layers "B.Cu" "In4.Cu" "In6.Cu" "In11.Cu" "In13.Cu" "In15.Cu")
		(hatch none 0.5)
		(connect_pads
			(clearance 0)
		)
		(min_thickness 0.25)
		(keepout
			(tracks not_allowed)
			(vias allowed)
			(pads allowed)
			(copperpour not_allowed)
			(footprints allowed)
		)
		(placement
			(enabled no)
			(sheetname "")
		)
		(fill yes
			(thermal_gap 0.5)
			(thermal_bridge_width 0.5)
			(island_removal_mode 0)
		)
		(polygon
			(pts
				(arc
					(start 376.479816 -230.714296)
					(mid 375.849896 -230.714296)
					(end 376.479816 -230.714296)
				)
			)
		)
	)
	(zone
		(layers "B.Cu" "In4.Cu" "In6.Cu" "In11.Cu" "In13.Cu" "In15.Cu")
		(hatch none 0.5)
		(connect_pads
			(clearance 0)
		)
		(min_thickness 0.25)
		(keepout
			(tracks not_allowed)
			(vias allowed)
			(pads allowed)
			(copperpour not_allowed)
			(footprints allowed)
		)
		(placement
			(enabled no)
			(sheetname "")
		)
		(fill yes
			(thermal_gap 0.5)
			(thermal_bridge_width 0.5)
			(island_removal_mode 0)
		)
		(polygon
			(pts
				(arc
					(start 96.416114 -289.47618)
					(mid 95.786194 -289.47618)
					(end 96.416114 -289.47618)
				)
			)
		)
	)
	(zone
		(layers "B.Cu" "In4.Cu" "In6.Cu" "In11.Cu" "In13.Cu" "In15.Cu")
		(hatch none 0.5)
		(connect_pads
			(clearance 0)
		)
		(min_thickness 0.25)
		(keepout
			(tracks not_allowed)
			(vias allowed)
			(pads allowed)
			(copperpour not_allowed)
			(footprints allowed)
		)
		(placement
			(enabled no)
			(sheetname "")
		)
		(fill yes
			(thermal_gap 0.5)
			(thermal_bridge_width 0.5)
			(island_removal_mode 0)
		)
		(polygon
			(pts
				(arc
					(start 104.576118 -228.284532)
					(mid 103.946198 -228.284532)
					(end 104.576118 -228.284532)
				)
			)
		)
	)
	(zone
		(layers "B.Cu" "In4.Cu" "In6.Cu" "In11.Cu" "In13.Cu" "In15.Cu")
		(hatch none 0.5)
		(connect_pads
			(clearance 0)
		)
		(min_thickness 0.25)
		(keepout
			(tracks not_allowed)
			(vias allowed)
			(pads allowed)
			(copperpour not_allowed)
			(footprints allowed)
		)
		(placement
			(enabled no)
			(sheetname "")
		)
		(fill yes
			(thermal_gap 0.5)
			(thermal_bridge_width 0.5)
			(island_removal_mode 0)
		)
		(polygon
			(pts
				(arc
					(start 377.719844 -283.806138)
					(mid 377.089924 -283.806138)
					(end 377.719844 -283.806138)
				)
			)
		)
	)
	(zone
		(layers "B.Cu" "In4.Cu" "In6.Cu" "In11.Cu" "In13.Cu" "In15.Cu")
		(hatch none 0.5)
		(connect_pads
			(clearance 0)
		)
		(min_thickness 0.25)
		(keepout
			(tracks not_allowed)
			(vias allowed)
			(pads allowed)
			(copperpour not_allowed)
			(footprints allowed)
		)
		(placement
			(enabled no)
			(sheetname "")
		)
		(fill yes
			(thermal_gap 0.5)
			(thermal_bridge_width 0.5)
			(island_removal_mode 0)
		)
		(polygon
			(pts
				(arc
					(start 431.89017 -269.585186)
					(mid 431.22215 -269.585186)
					(end 431.89017 -269.585186)
				)
			)
		)
	)
	(zone
		(layers "B.Cu" "In4.Cu" "In6.Cu" "In11.Cu" "In13.Cu" "In15.Cu")
		(hatch none 0.5)
		(connect_pads
			(clearance 0)
		)
		(min_thickness 0.25)
		(keepout
			(tracks not_allowed)
			(vias allowed)
			(pads allowed)
			(copperpour not_allowed)
			(footprints allowed)
		)
		(placement
			(enabled no)
			(sheetname "")
		)
		(fill yes
			(thermal_gap 0.5)
			(thermal_bridge_width 0.5)
			(island_removal_mode 0)
		)
		(polygon
			(pts
				(arc
					(start 95.005906 -282.18638)
					(mid 94.375986 -282.18638)
					(end 95.005906 -282.18638)
				)
			)
		)
	)
	(zone
		(layers "B.Cu" "In4.Cu" "In6.Cu" "In11.Cu" "In13.Cu" "In15.Cu")
		(hatch none 0.5)
		(connect_pads
			(clearance 0)
		)
		(min_thickness 0.25)
		(keepout
			(tracks not_allowed)
			(vias allowed)
			(pads allowed)
			(copperpour not_allowed)
			(footprints allowed)
		)
		(placement
			(enabled no)
			(sheetname "")
		)
		(fill yes
			(thermal_gap 0.5)
			(thermal_bridge_width 0.5)
			(island_removal_mode 0)
		)
		(polygon
			(pts
				(arc
					(start 377.719844 -274.086066)
					(mid 377.089924 -274.086066)
					(end 377.719844 -274.086066)
				)
			)
		)
	)
	(zone
		(layers "B.Cu" "In4.Cu" "In6.Cu" "In11.Cu" "In13.Cu" "In15.Cu")
		(hatch none 0.5)
		(connect_pads
			(clearance 0)
		)
		(min_thickness 0.25)
		(keepout
			(tracks not_allowed)
			(vias allowed)
			(pads allowed)
			(copperpour not_allowed)
			(footprints allowed)
		)
		(placement
			(enabled no)
			(sheetname "")
		)
		(fill yes
			(thermal_gap 0.5)
			(thermal_bridge_width 0.5)
			(island_removal_mode 0)
		)
		(polygon
			(pts
				(arc
					(start 431.89017 -221.985078)
					(mid 431.22215 -221.985078)
					(end 431.89017 -221.985078)
				)
			)
		)
	)
	(zone
		(layers "B.Cu" "In4.Cu" "In6.Cu" "In11.Cu" "In13.Cu" "In15.Cu")
		(hatch none 0.5)
		(connect_pads
			(clearance 0)
		)
		(min_thickness 0.25)
		(keepout
			(tracks not_allowed)
			(vias allowed)
			(pads allowed)
			(copperpour not_allowed)
			(footprints allowed)
		)
		(placement
			(enabled no)
			(sheetname "")
		)
		(fill yes
			(thermal_gap 0.5)
			(thermal_bridge_width 0.5)
			(island_removal_mode 0)
		)
		(polygon
			(pts
				(arc
					(start 44.674028 -317.185294)
					(mid 44.006008 -317.185294)
					(end 44.674028 -317.185294)
				)
			)
		)
	)
	(zone
		(layers "B.Cu" "In4.Cu" "In6.Cu" "In11.Cu" "In13.Cu" "In15.Cu")
		(hatch none 0.5)
		(connect_pads
			(clearance 0)
		)
		(min_thickness 0.25)
		(keepout
			(tracks not_allowed)
			(vias allowed)
			(pads allowed)
			(copperpour not_allowed)
			(footprints allowed)
		)
		(placement
			(enabled no)
			(sheetname "")
		)
		(fill yes
			(thermal_gap 0.5)
			(thermal_bridge_width 0.5)
			(island_removal_mode 0)
		)
		(polygon
			(pts
				(arc
					(start 40.57396 -199.8853)
					(mid 39.90594 -199.8853)
					(end 40.57396 -199.8853)
				)
			)
		)
	)
	(zone
		(layers "B.Cu" "In4.Cu" "In6.Cu" "In11.Cu" "In13.Cu" "In15.Cu")
		(hatch none 0.5)
		(connect_pads
			(clearance 0)
		)
		(min_thickness 0.25)
		(keepout
			(tracks not_allowed)
			(vias allowed)
			(pads allowed)
			(copperpour not_allowed)
			(footprints allowed)
		)
		(placement
			(enabled no)
			(sheetname "")
		)
		(fill yes
			(thermal_gap 0.5)
			(thermal_bridge_width 0.5)
			(island_removal_mode 0)
		)
		(polygon
			(pts
				(arc
					(start 40.57396 -291.685218)
					(mid 39.90594 -291.685218)
					(end 40.57396 -291.685218)
				)
			)
		)
	)
	(zone
		(layers "B.Cu" "In4.Cu" "In6.Cu" "In11.Cu" "In13.Cu" "In15.Cu")
		(hatch none 0.5)
		(connect_pads
			(clearance 0)
		)
		(min_thickness 0.25)
		(keepout
			(tracks not_allowed)
			(vias allowed)
			(pads allowed)
			(copperpour not_allowed)
			(footprints allowed)
		)
		(placement
			(enabled no)
			(sheetname "")
		)
		(fill yes
			(thermal_gap 0.5)
			(thermal_bridge_width 0.5)
			(island_removal_mode 0)
		)
		(polygon
			(pts
				(arc
					(start 365.66983 -226.664266)
					(mid 365.03991 -226.664266)
					(end 365.66983 -226.664266)
				)
			)
		)
	)
	(zone
		(layers "B.Cu" "In4.Cu" "In6.Cu" "In11.Cu" "In13.Cu" "In15.Cu")
		(hatch none 0.5)
		(connect_pads
			(clearance 0)
		)
		(min_thickness 0.25)
		(keepout
			(tracks not_allowed)
			(vias allowed)
			(pads allowed)
			(copperpour not_allowed)
			(footprints allowed)
		)
		(placement
			(enabled no)
			(sheetname "")
		)
		(fill yes
			(thermal_gap 0.5)
			(thermal_bridge_width 0.5)
			(island_removal_mode 0)
		)
		(polygon
			(pts
				(arc
					(start 40.57396 -310.385206)
					(mid 39.90594 -310.385206)
					(end 40.57396 -310.385206)
				)
			)
		)
	)
	(zone
		(layers "B.Cu" "In4.Cu" "In6.Cu" "In11.Cu" "In13.Cu" "In15.Cu")
		(hatch none 0.5)
		(connect_pads
			(clearance 0)
		)
		(min_thickness 0.25)
		(keepout
			(tracks not_allowed)
			(vias allowed)
			(pads allowed)
			(copperpour not_allowed)
			(footprints allowed)
		)
		(placement
			(enabled no)
			(sheetname "")
		)
		(fill yes
			(thermal_gap 0.5)
			(thermal_bridge_width 0.5)
			(island_removal_mode 0)
		)
		(polygon
			(pts
				(arc
					(start 183.950102 -240.68532)
					(mid 183.282082 -240.68532)
					(end 183.950102 -240.68532)
				)
			)
		)
	)
	(zone
		(layers "B.Cu" "In4.Cu" "In6.Cu" "In11.Cu" "In13.Cu" "In15.Cu")
		(hatch none 0.5)
		(connect_pads
			(clearance 0)
		)
		(min_thickness 0.25)
		(keepout
			(tracks not_allowed)
			(vias allowed)
			(pads allowed)
			(copperpour not_allowed)
			(footprints allowed)
		)
		(placement
			(enabled no)
			(sheetname "")
		)
		(fill yes
			(thermal_gap 0.5)
			(thermal_bridge_width 0.5)
			(island_removal_mode 0)
		)
		(polygon
			(pts
				(arc
					(start 179.850034 -250.035314)
					(mid 179.182014 -250.035314)
					(end 179.850034 -250.035314)
				)
			)
		)
	)
	(zone
		(layers "B.Cu" "In4.Cu" "In6.Cu" "In11.Cu" "In13.Cu" "In15.Cu")
		(hatch none 0.5)
		(connect_pads
			(clearance 0)
		)
		(min_thickness 0.25)
		(keepout
			(tracks not_allowed)
			(vias allowed)
			(pads allowed)
			(copperpour not_allowed)
			(footprints allowed)
		)
		(placement
			(enabled no)
			(sheetname "")
		)
		(fill yes
			(thermal_gap 0.5)
			(thermal_bridge_width 0.5)
			(island_removal_mode 0)
		)
		(polygon
			(pts
				(arc
					(start 343.586054 -225.85426)
					(mid 342.956134 -225.85426)
					(end 343.586054 -225.85426)
				)
			)
		)
	)
	(zone
		(layers "B.Cu" "In4.Cu" "In6.Cu" "In11.Cu" "In13.Cu" "In15.Cu")
		(hatch none 0.5)
		(connect_pads
			(clearance 0)
		)
		(min_thickness 0.25)
		(keepout
			(tracks not_allowed)
			(vias allowed)
			(pads allowed)
			(copperpour not_allowed)
			(footprints allowed)
		)
		(placement
			(enabled no)
			(sheetname "")
		)
		(fill yes
			(thermal_gap 0.5)
			(thermal_bridge_width 0.5)
			(island_removal_mode 0)
		)
		(polygon
			(pts
				(arc
					(start 96.115886 -236.384338)
					(mid 95.485966 -236.384338)
					(end 96.115886 -236.384338)
				)
			)
		)
	)
	(zone
		(layers "B.Cu" "In4.Cu" "In6.Cu" "In11.Cu" "In13.Cu" "In15.Cu")
		(hatch none 0.5)
		(connect_pads
			(clearance 0)
		)
		(min_thickness 0.25)
		(keepout
			(tracks not_allowed)
			(vias allowed)
			(pads allowed)
			(copperpour not_allowed)
			(footprints allowed)
		)
		(placement
			(enabled no)
			(sheetname "")
		)
		(fill yes
			(thermal_gap 0.5)
			(thermal_bridge_width 0.5)
			(island_removal_mode 0)
		)
		(polygon
			(pts
				(arc
					(start 129.779776 -287.046162)
					(mid 129.149856 -287.046162)
					(end 129.779776 -287.046162)
				)
			)
		)
	)
	(zone
		(layers "B.Cu" "In4.Cu" "In6.Cu" "In11.Cu" "In13.Cu" "In15.Cu")
		(hatch none 0.5)
		(connect_pads
			(clearance 0)
		)
		(min_thickness 0.25)
		(keepout
			(tracks not_allowed)
			(vias allowed)
			(pads allowed)
			(copperpour not_allowed)
			(footprints allowed)
		)
		(placement
			(enabled no)
			(sheetname "")
		)
		(fill yes
			(thermal_gap 0.5)
			(thermal_bridge_width 0.5)
			(island_removal_mode 0)
		)
		(polygon
			(pts
				(arc
					(start 94.536006 -276.516338)
					(mid 93.906086 -276.516338)
					(end 94.536006 -276.516338)
				)
			)
		)
	)
	(zone
		(layers "B.Cu" "In4.Cu" "In6.Cu" "In11.Cu" "In13.Cu" "In15.Cu")
		(hatch none 0.5)
		(connect_pads
			(clearance 0)
		)
		(min_thickness 0.25)
		(keepout
			(tracks not_allowed)
			(vias allowed)
			(pads allowed)
			(copperpour not_allowed)
			(footprints allowed)
		)
		(placement
			(enabled no)
			(sheetname "")
		)
		(fill yes
			(thermal_gap 0.5)
			(thermal_bridge_width 0.5)
			(island_removal_mode 0)
		)
		(polygon
			(pts
				(arc
					(start 96.416114 -266.796266)
					(mid 95.786194 -266.796266)
					(end 96.416114 -266.796266)
				)
			)
		)
	)
	(zone
		(layers "B.Cu" "In4.Cu" "In6.Cu" "In11.Cu" "In13.Cu" "In15.Cu")
		(hatch none 0.5)
		(connect_pads
			(clearance 0)
		)
		(min_thickness 0.25)
		(keepout
			(tracks not_allowed)
			(vias allowed)
			(pads allowed)
			(copperpour not_allowed)
			(footprints allowed)
		)
		(placement
			(enabled no)
			(sheetname "")
		)
		(fill yes
			(thermal_gap 0.5)
			(thermal_bridge_width 0.5)
			(island_removal_mode 0)
		)
		(polygon
			(pts
				(arc
					(start 342.646 -235.574078)
					(mid 342.01608 -235.574078)
					(end 342.646 -235.574078)
				)
			)
		)
	)
	(zone
		(layers "B.Cu" "In4.Cu" "In6.Cu" "In11.Cu" "In13.Cu" "In15.Cu")
		(hatch none 0.5)
		(connect_pads
			(clearance 0)
		)
		(min_thickness 0.25)
		(keepout
			(tracks not_allowed)
			(vias allowed)
			(pads allowed)
			(copperpour not_allowed)
			(footprints allowed)
		)
		(placement
			(enabled no)
			(sheetname "")
		)
		(fill yes
			(thermal_gap 0.5)
			(thermal_bridge_width 0.5)
			(island_removal_mode 0)
		)
		(polygon
			(pts
				(arc
					(start 128.839722 -293.52621)
					(mid 128.209802 -293.52621)
					(end 128.839722 -293.52621)
				)
			)
		)
	)
	(zone
		(layers "B.Cu" "In4.Cu" "In6.Cu" "In11.Cu" "In13.Cu" "In15.Cu")
		(hatch none 0.5)
		(connect_pads
			(clearance 0)
		)
		(min_thickness 0.25)
		(keepout
			(tracks not_allowed)
			(vias allowed)
			(pads allowed)
			(copperpour not_allowed)
			(footprints allowed)
		)
		(placement
			(enabled no)
			(sheetname "")
		)
		(fill yes
			(thermal_gap 0.5)
			(thermal_bridge_width 0.5)
			(island_removal_mode 0)
		)
		(polygon
			(pts
				(arc
					(start 292.614096 -233.035094)
					(mid 291.946076 -233.035094)
					(end 292.614096 -233.035094)
				)
			)
		)
	)
	(zone
		(layers "B.Cu" "In4.Cu" "In6.Cu" "In11.Cu" "In13.Cu" "In15.Cu")
		(hatch none 0.5)
		(connect_pads
			(clearance 0)
		)
		(min_thickness 0.25)
		(keepout
			(tracks not_allowed)
			(vias allowed)
			(pads allowed)
			(copperpour not_allowed)
			(footprints allowed)
		)
		(placement
			(enabled no)
			(sheetname "")
		)
		(fill yes
			(thermal_gap 0.5)
			(thermal_bridge_width 0.5)
			(island_removal_mode 0)
		)
		(polygon
			(pts
				(arc
					(start 342.646 -240.434114)
					(mid 342.01608 -240.434114)
					(end 342.646 -240.434114)
				)
			)
		)
	)
	(zone
		(layers "B.Cu" "In4.Cu" "In6.Cu" "In11.Cu" "In13.Cu" "In15.Cu")
		(hatch none 0.5)
		(connect_pads
			(clearance 0)
		)
		(min_thickness 0.25)
		(keepout
			(tracks not_allowed)
			(vias allowed)
			(pads allowed)
			(copperpour not_allowed)
			(footprints allowed)
		)
		(placement
			(enabled no)
			(sheetname "")
		)
		(fill yes
			(thermal_gap 0.5)
			(thermal_bridge_width 0.5)
			(island_removal_mode 0)
		)
		(polygon
			(pts
				(arc
					(start 427.790102 -302.73498)
					(mid 427.122082 -302.73498)
					(end 427.790102 -302.73498)
				)
			)
		)
	)
	(zone
		(layers "B.Cu" "In4.Cu" "In6.Cu" "In11.Cu" "In13.Cu" "In15.Cu")
		(hatch none 0.5)
		(connect_pads
			(clearance 0)
		)
		(min_thickness 0.25)
		(keepout
			(tracks not_allowed)
			(vias allowed)
			(pads allowed)
			(copperpour not_allowed)
			(footprints allowed)
		)
		(placement
			(enabled no)
			(sheetname "")
		)
		(fill yes
			(thermal_gap 0.5)
			(thermal_bridge_width 0.5)
			(island_removal_mode 0)
		)
		(polygon
			(pts
				(arc
					(start 44.674028 -238.135414)
					(mid 44.006008 -238.135414)
					(end 44.674028 -238.135414)
				)
			)
		)
	)
	(zone
		(layers "B.Cu" "In4.Cu" "In6.Cu" "In11.Cu" "In13.Cu" "In15.Cu")
		(hatch none 0.5)
		(connect_pads
			(clearance 0)
		)
		(min_thickness 0.25)
		(keepout
			(tracks not_allowed)
			(vias allowed)
			(pads allowed)
			(copperpour not_allowed)
			(footprints allowed)
		)
		(placement
			(enabled no)
			(sheetname "")
		)
		(fill yes
			(thermal_gap 0.5)
			(thermal_bridge_width 0.5)
			(island_removal_mode 0)
		)
		(polygon
			(pts
				(arc
					(start 343.886028 -285.42615)
					(mid 343.256108 -285.42615)
					(end 343.886028 -285.42615)
				)
			)
		)
	)
	(zone
		(layers "B.Cu" "In4.Cu" "In6.Cu" "In11.Cu" "In13.Cu" "In15.Cu")
		(hatch none 0.5)
		(connect_pads
			(clearance 0)
		)
		(min_thickness 0.25)
		(keepout
			(tracks not_allowed)
			(vias allowed)
			(pads allowed)
			(copperpour not_allowed)
			(footprints allowed)
		)
		(placement
			(enabled no)
			(sheetname "")
		)
		(fill yes
			(thermal_gap 0.5)
			(thermal_bridge_width 0.5)
			(island_removal_mode 0)
		)
		(polygon
			(pts
				(arc
					(start 342.945974 -282.186126)
					(mid 342.316054 -282.186126)
					(end 342.945974 -282.186126)
				)
			)
		)
	)
	(zone
		(layers "B.Cu" "In4.Cu" "In6.Cu" "In11.Cu" "In13.Cu" "In15.Cu")
		(hatch none 0.5)
		(connect_pads
			(clearance 0)
		)
		(min_thickness 0.25)
		(keepout
			(tracks not_allowed)
			(vias allowed)
			(pads allowed)
			(copperpour not_allowed)
			(footprints allowed)
		)
		(placement
			(enabled no)
			(sheetname "")
		)
		(fill yes
			(thermal_gap 0.5)
			(thermal_bridge_width 0.5)
			(island_removal_mode 0)
		)
		(polygon
			(pts
				(arc
					(start 129.779776 -264.366248)
					(mid 129.149856 -264.366248)
					(end 129.779776 -264.366248)
				)
			)
		)
	)
	(zone
		(layers "B.Cu" "In4.Cu" "In6.Cu" "In11.Cu" "In13.Cu" "In15.Cu")
		(hatch none 0.5)
		(connect_pads
			(clearance 0)
		)
		(min_thickness 0.25)
		(keepout
			(tracks not_allowed)
			(vias allowed)
			(pads allowed)
			(copperpour not_allowed)
			(footprints allowed)
		)
		(placement
			(enabled no)
			(sheetname "")
		)
		(fill yes
			(thermal_gap 0.5)
			(thermal_bridge_width 0.5)
			(island_removal_mode 0)
		)
		(polygon
			(pts
				(arc
					(start 95.94596 -272.466308)
					(mid 95.31604 -272.466308)
					(end 95.94596 -272.466308)
				)
			)
		)
	)
	(zone
		(layers "B.Cu" "In4.Cu" "In6.Cu" "In11.Cu" "In13.Cu" "In15.Cu")
		(hatch none 0.5)
		(connect_pads
			(clearance 0)
		)
		(min_thickness 0.25)
		(keepout
			(tracks not_allowed)
			(vias allowed)
			(pads allowed)
			(copperpour not_allowed)
			(footprints allowed)
		)
		(placement
			(enabled no)
			(sheetname "")
		)
		(fill yes
			(thermal_gap 0.5)
			(thermal_bridge_width 0.5)
			(island_removal_mode 0)
		)
		(polygon
			(pts
				(arc
					(start 288.514028 -278.93518)
					(mid 287.846008 -278.93518)
					(end 288.514028 -278.93518)
				)
			)
		)
	)
	(zone
		(layers "B.Cu" "In4.Cu" "In6.Cu" "In11.Cu" "In13.Cu" "In15.Cu")
		(hatch none 0.5)
		(connect_pads
			(clearance 0)
		)
		(min_thickness 0.25)
		(keepout
			(tracks not_allowed)
			(vias allowed)
			(pads allowed)
			(copperpour not_allowed)
			(footprints allowed)
		)
		(placement
			(enabled no)
			(sheetname "")
		)
		(fill yes
			(thermal_gap 0.5)
			(thermal_bridge_width 0.5)
			(island_removal_mode 0)
		)
		(polygon
			(pts
				(arc
					(start 377.41987 -227.474272)
					(mid 376.78995 -227.474272)
					(end 377.41987 -227.474272)
				)
			)
		)
	)
	(zone
		(layers "B.Cu" "In4.Cu" "In6.Cu" "In11.Cu" "In13.Cu" "In15.Cu")
		(hatch none 0.5)
		(connect_pads
			(clearance 0)
		)
		(min_thickness 0.25)
		(keepout
			(tracks not_allowed)
			(vias allowed)
			(pads allowed)
			(copperpour not_allowed)
			(footprints allowed)
		)
		(placement
			(enabled no)
			(sheetname "")
		)
		(fill yes
			(thermal_gap 0.5)
			(thermal_bridge_width 0.5)
			(island_removal_mode 0)
		)
		(polygon
			(pts
				(arc
					(start 376.30989 -273.27606)
					(mid 375.67997 -273.27606)
					(end 376.30989 -273.27606)
				)
			)
		)
	)
	(zone
		(layers "B.Cu" "In4.Cu" "In6.Cu" "In11.Cu" "In13.Cu" "In15.Cu")
		(hatch none 0.5)
		(connect_pads
			(clearance 0)
		)
		(min_thickness 0.25)
		(keepout
			(tracks not_allowed)
			(vias allowed)
			(pads allowed)
			(copperpour not_allowed)
			(footprints allowed)
		)
		(placement
			(enabled no)
			(sheetname "")
		)
		(fill yes
			(thermal_gap 0.5)
			(thermal_bridge_width 0.5)
			(island_removal_mode 0)
		)
		(polygon
			(pts
				(arc
					(start 44.674028 -250.885198)
					(mid 44.006008 -250.885198)
					(end 44.674028 -250.885198)
				)
			)
		)
	)
	(zone
		(layers "B.Cu" "In4.Cu" "In6.Cu" "In11.Cu" "In13.Cu" "In15.Cu")
		(hatch none 0.5)
		(connect_pads
			(clearance 0)
		)
		(min_thickness 0.25)
		(keepout
			(tracks not_allowed)
			(vias allowed)
			(pads allowed)
			(copperpour not_allowed)
			(footprints allowed)
		)
		(placement
			(enabled no)
			(sheetname "")
		)
		(fill yes
			(thermal_gap 0.5)
			(thermal_bridge_width 0.5)
			(island_removal_mode 0)
		)
		(polygon
			(pts
				(arc
					(start 183.950102 -284.885384)
					(mid 183.282082 -284.885384)
					(end 183.950102 -284.885384)
				)
			)
		)
	)
	(zone
		(layers "B.Cu" "In4.Cu" "In6.Cu" "In11.Cu" "In13.Cu" "In15.Cu")
		(hatch none 0.5)
		(connect_pads
			(clearance 0)
		)
		(min_thickness 0.25)
		(keepout
			(tracks not_allowed)
			(vias allowed)
			(pads allowed)
			(copperpour not_allowed)
			(footprints allowed)
		)
		(placement
			(enabled no)
			(sheetname "")
		)
		(fill yes
			(thermal_gap 0.5)
			(thermal_bridge_width 0.5)
			(island_removal_mode 0)
		)
		(polygon
			(pts
				(arc
					(start 129.779776 -277.326344)
					(mid 129.149856 -277.326344)
					(end 129.779776 -277.326344)
				)
			)
		)
	)
	(zone
		(layers "B.Cu" "In4.Cu" "In6.Cu" "In11.Cu" "In13.Cu" "In15.Cu")
		(hatch none 0.5)
		(connect_pads
			(clearance 0)
		)
		(min_thickness 0.25)
		(keepout
			(tracks not_allowed)
			(vias allowed)
			(pads allowed)
			(copperpour not_allowed)
			(footprints allowed)
		)
		(placement
			(enabled no)
			(sheetname "")
		)
		(fill yes
			(thermal_gap 0.5)
			(thermal_bridge_width 0.5)
			(island_removal_mode 0)
		)
		(polygon
			(pts
				(arc
					(start 44.674028 -227.085398)
					(mid 44.006008 -227.085398)
					(end 44.674028 -227.085398)
				)
			)
		)
	)
	(zone
		(layers "B.Cu" "In4.Cu" "In6.Cu" "In11.Cu" "In13.Cu" "In15.Cu")
		(hatch none 0.5)
		(connect_pads
			(clearance 0)
		)
		(min_thickness 0.25)
		(keepout
			(tracks not_allowed)
			(vias allowed)
			(pads allowed)
			(copperpour not_allowed)
			(footprints allowed)
		)
		(placement
			(enabled no)
			(sheetname "")
		)
		(fill yes
			(thermal_gap 0.5)
			(thermal_bridge_width 0.5)
			(island_removal_mode 0)
		)
		(polygon
			(pts
				(arc
					(start 344.055954 -228.284278)
					(mid 343.426034 -228.284278)
					(end 344.055954 -228.284278)
				)
			)
		)
	)
	(zone
		(layers "B.Cu" "In4.Cu" "In6.Cu" "In11.Cu" "In13.Cu" "In15.Cu")
		(hatch none 0.5)
		(connect_pads
			(clearance 0)
		)
		(min_thickness 0.25)
		(keepout
			(tracks not_allowed)
			(vias allowed)
			(pads allowed)
			(copperpour not_allowed)
			(footprints allowed)
		)
		(placement
			(enabled no)
			(sheetname "")
		)
		(fill yes
			(thermal_gap 0.5)
			(thermal_bridge_width 0.5)
			(island_removal_mode 0)
		)
		(polygon
			(pts
				(arc
					(start 179.850034 -254.285242)
					(mid 179.182014 -254.285242)
					(end 179.850034 -254.285242)
				)
			)
		)
	)
	(zone
		(layers "B.Cu" "In4.Cu" "In6.Cu" "In11.Cu" "In13.Cu" "In15.Cu")
		(hatch none 0.5)
		(connect_pads
			(clearance 0)
		)
		(min_thickness 0.25)
		(keepout
			(tracks not_allowed)
			(vias allowed)
			(pads allowed)
			(copperpour not_allowed)
			(footprints allowed)
		)
		(placement
			(enabled no)
			(sheetname "")
		)
		(fill yes
			(thermal_gap 0.5)
			(thermal_bridge_width 0.5)
			(island_removal_mode 0)
		)
		(polygon
			(pts
				(arc
					(start 377.719844 -269.22603)
					(mid 377.089924 -269.22603)
					(end 377.719844 -269.22603)
				)
			)
		)
	)
	(zone
		(layers "B.Cu" "In4.Cu" "In6.Cu" "In11.Cu" "In13.Cu" "In15.Cu")
		(hatch none 0.5)
		(connect_pads
			(clearance 0)
		)
		(min_thickness 0.25)
		(keepout
			(tracks not_allowed)
			(vias allowed)
			(pads allowed)
			(copperpour not_allowed)
			(footprints allowed)
		)
		(placement
			(enabled no)
			(sheetname "")
		)
		(fill yes
			(thermal_gap 0.5)
			(thermal_bridge_width 0.5)
			(island_removal_mode 0)
		)
		(polygon
			(pts
				(arc
					(start 431.89017 -252.584966)
					(mid 431.22215 -252.584966)
					(end 431.89017 -252.584966)
				)
			)
		)
	)
	(zone
		(layers "B.Cu" "In4.Cu" "In6.Cu" "In11.Cu" "In13.Cu" "In15.Cu")
		(hatch none 0.5)
		(connect_pads
			(clearance 0)
		)
		(min_thickness 0.25)
		(keepout
			(tracks not_allowed)
			(vias allowed)
			(pads allowed)
			(copperpour not_allowed)
			(footprints allowed)
		)
		(placement
			(enabled no)
			(sheetname "")
		)
		(fill yes
			(thermal_gap 0.5)
			(thermal_bridge_width 0.5)
			(island_removal_mode 0)
		)
		(polygon
			(pts
				(arc
					(start 128.069594 -244.484398)
					(mid 127.439674 -244.484398)
					(end 128.069594 -244.484398)
				)
			)
		)
	)
	(zone
		(layers "B.Cu" "In4.Cu" "In6.Cu" "In11.Cu" "In13.Cu" "In15.Cu")
		(hatch none 0.5)
		(connect_pads
			(clearance 0)
		)
		(min_thickness 0.25)
		(keepout
			(tracks not_allowed)
			(vias allowed)
			(pads allowed)
			(copperpour not_allowed)
			(footprints allowed)
		)
		(placement
			(enabled no)
			(sheetname "")
		)
		(fill yes
			(thermal_gap 0.5)
			(thermal_bridge_width 0.5)
			(island_removal_mode 0)
		)
		(polygon
			(pts
				(arc
					(start 128.069594 -250.964446)
					(mid 127.439674 -250.964446)
					(end 128.069594 -250.964446)
				)
			)
		)
	)
	(zone
		(layers "B.Cu" "In4.Cu" "In6.Cu" "In11.Cu" "In13.Cu" "In15.Cu")
		(hatch none 0.5)
		(connect_pads
			(clearance 0)
		)
		(min_thickness 0.25)
		(keepout
			(tracks not_allowed)
			(vias allowed)
			(pads allowed)
			(copperpour not_allowed)
			(footprints allowed)
		)
		(placement
			(enabled no)
			(sheetname "")
		)
		(fill yes
			(thermal_gap 0.5)
			(thermal_bridge_width 0.5)
			(island_removal_mode 0)
		)
		(polygon
			(pts
				(arc
					(start 44.674028 -228.78542)
					(mid 44.006008 -228.78542)
					(end 44.674028 -228.78542)
				)
			)
		)
	)
	(zone
		(layers "B.Cu" "In4.Cu" "In6.Cu" "In11.Cu" "In13.Cu" "In15.Cu")
		(hatch none 0.5)
		(connect_pads
			(clearance 0)
		)
		(min_thickness 0.25)
		(keepout
			(tracks not_allowed)
			(vias allowed)
			(pads allowed)
			(copperpour not_allowed)
			(footprints allowed)
		)
		(placement
			(enabled no)
			(sheetname "")
		)
		(fill yes
			(thermal_gap 0.5)
			(thermal_bridge_width 0.5)
			(island_removal_mode 0)
		)
		(polygon
			(pts
				(arc
					(start 427.790102 -199.885046)
					(mid 427.122082 -199.885046)
					(end 427.790102 -199.885046)
				)
			)
		)
	)
	(zone
		(layers "B.Cu" "In4.Cu" "In6.Cu" "In11.Cu" "In13.Cu" "In15.Cu")
		(hatch none 0.5)
		(connect_pads
			(clearance 0)
		)
		(min_thickness 0.25)
		(keepout
			(tracks not_allowed)
			(vias allowed)
			(pads allowed)
			(copperpour not_allowed)
			(footprints allowed)
		)
		(placement
			(enabled no)
			(sheetname "")
		)
		(fill yes
			(thermal_gap 0.5)
			(thermal_bridge_width 0.5)
			(island_removal_mode 0)
		)
		(polygon
			(pts
				(arc
					(start 431.89017 -197.33514)
					(mid 431.22215 -197.33514)
					(end 431.89017 -197.33514)
				)
			)
		)
	)
	(zone
		(layers "B.Cu" "In4.Cu" "In6.Cu" "In11.Cu" "In13.Cu" "In15.Cu")
		(hatch none 0.5)
		(connect_pads
			(clearance 0)
		)
		(min_thickness 0.25)
		(keepout
			(tracks not_allowed)
			(vias allowed)
			(pads allowed)
			(copperpour not_allowed)
			(footprints allowed)
		)
		(placement
			(enabled no)
			(sheetname "")
		)
		(fill yes
			(thermal_gap 0.5)
			(thermal_bridge_width 0.5)
			(island_removal_mode 0)
		)
		(polygon
			(pts
				(arc
					(start 377.41987 -225.85426)
					(mid 376.78995 -225.85426)
					(end 377.41987 -225.85426)
				)
			)
		)
	)
	(zone
		(layers "B.Cu" "In4.Cu" "In6.Cu" "In11.Cu" "In13.Cu" "In15.Cu")
		(hatch none 0.5)
		(connect_pads
			(clearance 0)
		)
		(min_thickness 0.25)
		(keepout
			(tracks not_allowed)
			(vias allowed)
			(pads allowed)
			(copperpour not_allowed)
			(footprints allowed)
		)
		(placement
			(enabled no)
			(sheetname "")
		)
		(fill yes
			(thermal_gap 0.5)
			(thermal_bridge_width 0.5)
			(island_removal_mode 0)
		)
		(polygon
			(pts
				(arc
					(start 342.1761 -236.384084)
					(mid 341.54618 -236.384084)
					(end 342.1761 -236.384084)
				)
			)
		)
	)
	(zone
		(layers "B.Cu" "In4.Cu" "In6.Cu" "In11.Cu" "In13.Cu" "In15.Cu")
		(hatch none 0.5)
		(connect_pads
			(clearance 0)
		)
		(min_thickness 0.25)
		(keepout
			(tracks not_allowed)
			(vias allowed)
			(pads allowed)
			(copperpour not_allowed)
			(footprints allowed)
		)
		(placement
			(enabled no)
			(sheetname "")
		)
		(fill yes
			(thermal_gap 0.5)
			(thermal_bridge_width 0.5)
			(island_removal_mode 0)
		)
		(polygon
			(pts
				(arc
					(start 378.189744 -286.236156)
					(mid 377.559824 -286.236156)
					(end 378.189744 -286.236156)
				)
			)
		)
	)
	(zone
		(layers "B.Cu" "In4.Cu" "In6.Cu" "In11.Cu" "In13.Cu" "In15.Cu")
		(hatch none 0.5)
		(connect_pads
			(clearance 0)
		)
		(min_thickness 0.25)
		(keepout
			(tracks not_allowed)
			(vias allowed)
			(pads allowed)
			(copperpour not_allowed)
			(footprints allowed)
		)
		(placement
			(enabled no)
			(sheetname "")
		)
		(fill yes
			(thermal_gap 0.5)
			(thermal_bridge_width 0.5)
			(island_removal_mode 0)
		)
		(polygon
			(pts
				(arc
					(start 94.536006 -291.096192)
					(mid 93.906086 -291.096192)
					(end 94.536006 -291.096192)
				)
			)
		)
	)
	(zone
		(layers "B.Cu" "In4.Cu" "In6.Cu" "In11.Cu" "In13.Cu" "In15.Cu")
		(hatch none 0.5)
		(connect_pads
			(clearance 0)
		)
		(min_thickness 0.25)
		(keepout
			(tracks not_allowed)
			(vias allowed)
			(pads allowed)
			(copperpour not_allowed)
			(footprints allowed)
		)
		(placement
			(enabled no)
			(sheetname "")
		)
		(fill yes
			(thermal_gap 0.5)
			(thermal_bridge_width 0.5)
			(island_removal_mode 0)
		)
		(polygon
			(pts
				(arc
					(start 431.89017 -307.835046)
					(mid 431.22215 -307.835046)
					(end 431.89017 -307.835046)
				)
			)
		)
	)
	(zone
		(layers "B.Cu" "In4.Cu" "In6.Cu" "In11.Cu" "In13.Cu" "In15.Cu")
		(hatch none 0.5)
		(connect_pads
			(clearance 0)
		)
		(min_thickness 0.25)
		(keepout
			(tracks not_allowed)
			(vias allowed)
			(pads allowed)
			(copperpour not_allowed)
			(footprints allowed)
		)
		(placement
			(enabled no)
			(sheetname "")
		)
		(fill yes
			(thermal_gap 0.5)
			(thermal_bridge_width 0.5)
			(island_removal_mode 0)
		)
		(polygon
			(pts
				(arc
					(start 353.75596 -294.335962)
					(mid 353.12604 -294.335962)
					(end 353.75596 -294.335962)
				)
			)
		)
	)
	(zone
		(layers "B.Cu" "In4.Cu" "In6.Cu" "In11.Cu" "In13.Cu" "In15.Cu")
		(hatch none 0.5)
		(connect_pads
			(clearance 0)
		)
		(min_thickness 0.25)
		(keepout
			(tracks not_allowed)
			(vias allowed)
			(pads allowed)
			(copperpour not_allowed)
			(footprints allowed)
		)
		(placement
			(enabled no)
			(sheetname "")
		)
		(fill yes
			(thermal_gap 0.5)
			(thermal_bridge_width 0.5)
			(island_removal_mode 0)
		)
		(polygon
			(pts
				(arc
					(start 94.705932 -242.05438)
					(mid 94.076012 -242.05438)
					(end 94.705932 -242.05438)
				)
			)
		)
	)
	(zone
		(layers "B.Cu" "In4.Cu" "In6.Cu" "In11.Cu" "In13.Cu" "In15.Cu")
		(hatch none 0.5)
		(connect_pads
			(clearance 0)
		)
		(min_thickness 0.25)
		(keepout
			(tracks not_allowed)
			(vias allowed)
			(pads allowed)
			(copperpour not_allowed)
			(footprints allowed)
		)
		(placement
			(enabled no)
			(sheetname "")
		)
		(fill yes
			(thermal_gap 0.5)
			(thermal_bridge_width 0.5)
			(island_removal_mode 0)
		)
		(polygon
			(pts
				(arc
					(start 344.356182 -276.516084)
					(mid 343.726262 -276.516084)
					(end 344.356182 -276.516084)
				)
			)
		)
	)
	(zone
		(layers "B.Cu" "In4.Cu" "In6.Cu" "In11.Cu" "In13.Cu" "In15.Cu")
		(hatch none 0.5)
		(connect_pads
			(clearance 0)
		)
		(min_thickness 0.25)
		(keepout
			(tracks not_allowed)
			(vias allowed)
			(pads allowed)
			(copperpour not_allowed)
			(footprints allowed)
		)
		(placement
			(enabled no)
			(sheetname "")
		)
		(fill yes
			(thermal_gap 0.5)
			(thermal_bridge_width 0.5)
			(island_removal_mode 0)
		)
		(polygon
			(pts
				(arc
					(start 378.189744 -274.896072)
					(mid 377.559824 -274.896072)
					(end 378.189744 -274.896072)
				)
			)
		)
	)
	(zone
		(layers "B.Cu" "In4.Cu" "In6.Cu" "In11.Cu" "In13.Cu" "In15.Cu")
		(hatch none 0.5)
		(connect_pads
			(clearance 0)
		)
		(min_thickness 0.25)
		(keepout
			(tracks not_allowed)
			(vias allowed)
			(pads allowed)
			(copperpour not_allowed)
			(footprints allowed)
		)
		(placement
			(enabled no)
			(sheetname "")
		)
		(fill yes
			(thermal_gap 0.5)
			(thermal_bridge_width 0.5)
			(island_removal_mode 0)
		)
		(polygon
			(pts
				(arc
					(start 342.476074 -279.756108)
					(mid 341.846154 -279.756108)
					(end 342.476074 -279.756108)
				)
			)
		)
	)
	(zone
		(layers "B.Cu" "In4.Cu" "In6.Cu" "In11.Cu" "In13.Cu" "In15.Cu")
		(hatch none 0.5)
		(connect_pads
			(clearance 0)
		)
		(min_thickness 0.25)
		(keepout
			(tracks not_allowed)
			(vias allowed)
			(pads allowed)
			(copperpour not_allowed)
			(footprints allowed)
		)
		(placement
			(enabled no)
			(sheetname "")
		)
		(fill yes
			(thermal_gap 0.5)
			(thermal_bridge_width 0.5)
			(island_removal_mode 0)
		)
		(polygon
			(pts
				(arc
					(start 431.89017 -290.83508)
					(mid 431.22215 -290.83508)
					(end 431.89017 -290.83508)
				)
			)
		)
	)
	(zone
		(layers "B.Cu" "In4.Cu" "In6.Cu" "In11.Cu" "In13.Cu" "In15.Cu")
		(hatch none 0.5)
		(connect_pads
			(clearance 0)
		)
		(min_thickness 0.25)
		(keepout
			(tracks not_allowed)
			(vias allowed)
			(pads allowed)
			(copperpour not_allowed)
			(footprints allowed)
		)
		(placement
			(enabled no)
			(sheetname "")
		)
		(fill yes
			(thermal_gap 0.5)
			(thermal_bridge_width 0.5)
			(island_removal_mode 0)
		)
		(polygon
			(pts
				(arc
					(start 376.479816 -245.29415)
					(mid 375.849896 -245.29415)
					(end 376.479816 -245.29415)
				)
			)
		)
	)
	(zone
		(layers "B.Cu" "In4.Cu" "In6.Cu" "In11.Cu" "In13.Cu" "In15.Cu")
		(hatch none 0.5)
		(connect_pads
			(clearance 0)
		)
		(min_thickness 0.25)
		(keepout
			(tracks not_allowed)
			(vias allowed)
			(pads allowed)
			(copperpour not_allowed)
			(footprints allowed)
		)
		(placement
			(enabled no)
			(sheetname "")
		)
		(fill yes
			(thermal_gap 0.5)
			(thermal_bridge_width 0.5)
			(island_removal_mode 0)
		)
		(polygon
			(pts
				(arc
					(start 128.539748 -238.814356)
					(mid 127.909828 -238.814356)
					(end 128.539748 -238.814356)
				)
			)
		)
	)
	(zone
		(layers "B.Cu" "In4.Cu" "In6.Cu" "In11.Cu" "In13.Cu" "In15.Cu")
		(hatch none 0.5)
		(connect_pads
			(clearance 0)
		)
		(min_thickness 0.25)
		(keepout
			(tracks not_allowed)
			(vias allowed)
			(pads allowed)
			(copperpour not_allowed)
			(footprints allowed)
		)
		(placement
			(enabled no)
			(sheetname "")
		)
		(fill yes
			(thermal_gap 0.5)
			(thermal_bridge_width 0.5)
			(island_removal_mode 0)
		)
		(polygon
			(pts
				(arc
					(start 288.514028 -221.13494)
					(mid 287.846008 -221.13494)
					(end 288.514028 -221.13494)
				)
			)
		)
	)
	(zone
		(layers "B.Cu" "In4.Cu" "In6.Cu" "In11.Cu" "In13.Cu" "In15.Cu")
		(hatch none 0.5)
		(connect_pads
			(clearance 0)
		)
		(min_thickness 0.25)
		(keepout
			(tracks not_allowed)
			(vias allowed)
			(pads allowed)
			(copperpour not_allowed)
			(footprints allowed)
		)
		(placement
			(enabled no)
			(sheetname "")
		)
		(fill yes
			(thermal_gap 0.5)
			(thermal_bridge_width 0.5)
			(island_removal_mode 0)
		)
		(polygon
			(pts
				(arc
					(start 128.069594 -231.524302)
					(mid 127.439674 -231.524302)
					(end 128.069594 -231.524302)
				)
			)
		)
	)
	(zone
		(layers "B.Cu" "In4.Cu" "In6.Cu" "In11.Cu" "In13.Cu" "In15.Cu")
		(hatch none 0.5)
		(connect_pads
			(clearance 0)
		)
		(min_thickness 0.25)
		(keepout
			(tracks not_allowed)
			(vias allowed)
			(pads allowed)
			(copperpour not_allowed)
			(footprints allowed)
		)
		(placement
			(enabled no)
			(sheetname "")
		)
		(fill yes
			(thermal_gap 0.5)
			(thermal_bridge_width 0.5)
			(island_removal_mode 0)
		)
		(polygon
			(pts
				(arc
					(start 94.705932 -251.774452)
					(mid 94.076012 -251.774452)
					(end 94.705932 -251.774452)
				)
			)
		)
	)
	(zone
		(layers "B.Cu" "In4.Cu" "In6.Cu" "In11.Cu" "In13.Cu" "In15.Cu")
		(hatch none 0.5)
		(connect_pads
			(clearance 0)
		)
		(min_thickness 0.25)
		(keepout
			(tracks not_allowed)
			(vias allowed)
			(pads allowed)
			(copperpour not_allowed)
			(footprints allowed)
		)
		(placement
			(enabled no)
			(sheetname "")
		)
		(fill yes
			(thermal_gap 0.5)
			(thermal_bridge_width 0.5)
			(island_removal_mode 0)
		)
		(polygon
			(pts
				(arc
					(start 344.055954 -250.964192)
					(mid 343.426034 -250.964192)
					(end 344.055954 -250.964192)
				)
			)
		)
	)
	(zone
		(layers "B.Cu" "In4.Cu" "In6.Cu" "In11.Cu" "In13.Cu" "In15.Cu")
		(hatch none 0.5)
		(connect_pads
			(clearance 0)
		)
		(min_thickness 0.25)
		(keepout
			(tracks not_allowed)
			(vias allowed)
			(pads allowed)
			(copperpour not_allowed)
			(footprints allowed)
		)
		(placement
			(enabled no)
			(sheetname "")
		)
		(fill yes
			(thermal_gap 0.5)
			(thermal_bridge_width 0.5)
			(island_removal_mode 0)
		)
		(polygon
			(pts
				(arc
					(start 179.345844 -55.481728)
					(mid 178.677824 -55.481728)
					(end 179.345844 -55.481728)
				)
			)
		)
	)
	(zone
		(layers "B.Cu" "In4.Cu" "In6.Cu" "In11.Cu" "In13.Cu" "In15.Cu")
		(hatch none 0.5)
		(connect_pads
			(clearance 0)
		)
		(min_thickness 0.25)
		(keepout
			(tracks not_allowed)
			(vias allowed)
			(pads allowed)
			(copperpour not_allowed)
			(footprints allowed)
		)
		(placement
			(enabled no)
			(sheetname "")
		)
		(fill yes
			(thermal_gap 0.5)
			(thermal_bridge_width 0.5)
			(island_removal_mode 0)
		)
		(polygon
			(pts
				(arc
					(start 44.674028 -292.535356)
					(mid 44.006008 -292.535356)
					(end 44.674028 -292.535356)
				)
			)
		)
	)
	(zone
		(layers "B.Cu" "In4.Cu" "In6.Cu" "In11.Cu" "In13.Cu" "In15.Cu")
		(hatch none 0.5)
		(connect_pads
			(clearance 0)
		)
		(min_thickness 0.25)
		(keepout
			(tracks not_allowed)
			(vias allowed)
			(pads allowed)
			(copperpour not_allowed)
			(footprints allowed)
		)
		(placement
			(enabled no)
			(sheetname "")
		)
		(fill yes
			(thermal_gap 0.5)
			(thermal_bridge_width 0.5)
			(island_removal_mode 0)
		)
		(polygon
			(pts
				(arc
					(start 292.614096 -309.535068)
					(mid 291.946076 -309.535068)
					(end 292.614096 -309.535068)
				)
			)
		)
	)
	(zone
		(layers "B.Cu" "In4.Cu" "In6.Cu" "In11.Cu" "In13.Cu" "In15.Cu")
		(hatch none 0.5)
		(connect_pads
			(clearance 0)
		)
		(min_thickness 0.25)
		(keepout
			(tracks not_allowed)
			(vias allowed)
			(pads allowed)
			(copperpour not_allowed)
			(footprints allowed)
		)
		(placement
			(enabled no)
			(sheetname "")
		)
		(fill yes
			(thermal_gap 0.5)
			(thermal_bridge_width 0.5)
			(island_removal_mode 0)
		)
		(polygon
			(pts
				(arc
					(start 183.950102 -317.185294)
					(mid 183.282082 -317.185294)
					(end 183.950102 -317.185294)
				)
			)
		)
	)
	(zone
		(layers "B.Cu" "In4.Cu" "In6.Cu" "In11.Cu" "In13.Cu" "In15.Cu")
		(hatch none 0.5)
		(connect_pads
			(clearance 0)
		)
		(min_thickness 0.25)
		(keepout
			(tracks not_allowed)
			(vias allowed)
			(pads allowed)
			(copperpour not_allowed)
			(footprints allowed)
		)
		(placement
			(enabled no)
			(sheetname "")
		)
		(fill yes
			(thermal_gap 0.5)
			(thermal_bridge_width 0.5)
			(island_removal_mode 0)
		)
		(polygon
			(pts
				(arc
					(start 292.614096 -219.435172)
					(mid 291.946076 -219.435172)
					(end 292.614096 -219.435172)
				)
			)
		)
	)
	(zone
		(layers "B.Cu" "In4.Cu" "In6.Cu" "In11.Cu" "In13.Cu" "In15.Cu")
		(hatch none 0.5)
		(connect_pads
			(clearance 0)
		)
		(min_thickness 0.25)
		(keepout
			(tracks not_allowed)
			(vias allowed)
			(pads allowed)
			(copperpour not_allowed)
			(footprints allowed)
		)
		(placement
			(enabled no)
			(sheetname "")
		)
		(fill yes
			(thermal_gap 0.5)
			(thermal_bridge_width 0.5)
			(island_removal_mode 0)
		)
		(polygon
			(pts
				(arc
					(start 431.89017 -217.73515)
					(mid 431.22215 -217.73515)
					(end 431.89017 -217.73515)
				)
			)
		)
	)
	(zone
		(layers "B.Cu" "In4.Cu" "In6.Cu" "In11.Cu" "In13.Cu" "In15.Cu")
		(hatch none 0.5)
		(connect_pads
			(clearance 0)
		)
		(min_thickness 0.25)
		(keepout
			(tracks not_allowed)
			(vias allowed)
			(pads allowed)
			(copperpour not_allowed)
			(footprints allowed)
		)
		(placement
			(enabled no)
			(sheetname "")
		)
		(fill yes
			(thermal_gap 0.5)
			(thermal_bridge_width 0.5)
			(island_removal_mode 0)
		)
		(polygon
			(pts
				(arc
					(start 40.57396 -318.035432)
					(mid 39.90594 -318.035432)
					(end 40.57396 -318.035432)
				)
			)
		)
	)
	(zone
		(layers "B.Cu" "In4.Cu" "In6.Cu" "In11.Cu" "In13.Cu" "In15.Cu")
		(hatch none 0.5)
		(connect_pads
			(clearance 0)
		)
		(min_thickness 0.25)
		(keepout
			(tracks not_allowed)
			(vias allowed)
			(pads allowed)
			(copperpour not_allowed)
			(footprints allowed)
		)
		(placement
			(enabled no)
			(sheetname "")
		)
		(fill yes
			(thermal_gap 0.5)
			(thermal_bridge_width 0.5)
			(island_removal_mode 0)
		)
		(polygon
			(pts
				(arc
					(start 343.886028 -293.525956)
					(mid 343.256108 -293.525956)
					(end 343.886028 -293.525956)
				)
			)
		)
	)
	(zone
		(layers "B.Cu" "In4.Cu" "In6.Cu" "In11.Cu" "In13.Cu" "In15.Cu")
		(hatch none 0.5)
		(connect_pads
			(clearance 0)
		)
		(min_thickness 0.25)
		(keepout
			(tracks not_allowed)
			(vias allowed)
			(pads allowed)
			(copperpour not_allowed)
			(footprints allowed)
		)
		(placement
			(enabled no)
			(sheetname "")
		)
		(fill yes
			(thermal_gap 0.5)
			(thermal_bridge_width 0.5)
			(island_removal_mode 0)
		)
		(polygon
			(pts
				(arc
					(start 431.89017 -287.435036)
					(mid 431.22215 -287.435036)
					(end 431.89017 -287.435036)
				)
			)
		)
	)
	(zone
		(layers "B.Cu" "In4.Cu" "In6.Cu" "In11.Cu" "In13.Cu" "In15.Cu")
		(hatch none 0.5)
		(connect_pads
			(clearance 0)
		)
		(min_thickness 0.25)
		(keepout
			(tracks not_allowed)
			(vias allowed)
			(pads allowed)
			(copperpour not_allowed)
			(footprints allowed)
		)
		(placement
			(enabled no)
			(sheetname "")
		)
		(fill yes
			(thermal_gap 0.5)
			(thermal_bridge_width 0.5)
			(island_removal_mode 0)
		)
		(polygon
			(pts
				(arc
					(start 183.950102 -200.735438)
					(mid 183.282082 -200.735438)
					(end 183.950102 -200.735438)
				)
			)
		)
	)
	(zone
		(layers "B.Cu" "In4.Cu" "In6.Cu" "In11.Cu" "In13.Cu" "In15.Cu")
		(hatch none 0.5)
		(connect_pads
			(clearance 0)
		)
		(min_thickness 0.25)
		(keepout
			(tracks not_allowed)
			(vias allowed)
			(pads allowed)
			(copperpour not_allowed)
			(footprints allowed)
		)
		(placement
			(enabled no)
			(sheetname "")
		)
		(fill yes
			(thermal_gap 0.5)
			(thermal_bridge_width 0.5)
			(island_removal_mode 0)
		)
		(polygon
			(pts
				(arc
					(start 128.369822 -270.03629)
					(mid 127.739902 -270.03629)
					(end 128.369822 -270.03629)
				)
			)
		)
	)
	(zone
		(layers "B.Cu" "In4.Cu" "In6.Cu" "In11.Cu" "In13.Cu" "In15.Cu")
		(hatch none 0.5)
		(connect_pads
			(clearance 0)
		)
		(min_thickness 0.25)
		(keepout
			(tracks not_allowed)
			(vias allowed)
			(pads allowed)
			(copperpour not_allowed)
			(footprints allowed)
		)
		(placement
			(enabled no)
			(sheetname "")
		)
		(fill yes
			(thermal_gap 0.5)
			(thermal_bridge_width 0.5)
			(island_removal_mode 0)
		)
		(polygon
			(pts
				(arc
					(start 179.850034 -216.885266)
					(mid 179.182014 -216.885266)
					(end 179.850034 -216.885266)
				)
			)
		)
	)
	(zone
		(layers "B.Cu" "In4.Cu" "In6.Cu" "In11.Cu" "In13.Cu" "In15.Cu")
		(hatch none 0.5)
		(connect_pads
			(clearance 0)
		)
		(min_thickness 0.25)
		(keepout
			(tracks not_allowed)
			(vias allowed)
			(pads allowed)
			(copperpour not_allowed)
			(footprints allowed)
		)
		(placement
			(enabled no)
			(sheetname "")
		)
		(fill yes
			(thermal_gap 0.5)
			(thermal_bridge_width 0.5)
			(island_removal_mode 0)
		)
		(polygon
			(pts
				(arc
					(start 342.1761 -246.104156)
					(mid 341.54618 -246.104156)
					(end 342.1761 -246.104156)
				)
			)
		)
	)
	(zone
		(layers "B.Cu" "In4.Cu" "In6.Cu" "In11.Cu" "In13.Cu" "In15.Cu")
		(hatch none 0.5)
		(connect_pads
			(clearance 0)
		)
		(min_thickness 0.25)
		(keepout
			(tracks not_allowed)
			(vias allowed)
			(pads allowed)
			(copperpour not_allowed)
			(footprints allowed)
		)
		(placement
			(enabled no)
			(sheetname "")
		)
		(fill yes
			(thermal_gap 0.5)
			(thermal_bridge_width 0.5)
			(island_removal_mode 0)
		)
		(polygon
			(pts
				(arc
					(start 342.1761 -231.524048)
					(mid 341.54618 -231.524048)
					(end 342.1761 -231.524048)
				)
			)
		)
	)
	(zone
		(layers "B.Cu" "In4.Cu" "In6.Cu" "In11.Cu" "In13.Cu" "In15.Cu")
		(hatch none 0.5)
		(connect_pads
			(clearance 0)
		)
		(min_thickness 0.25)
		(keepout
			(tracks not_allowed)
			(vias allowed)
			(pads allowed)
			(copperpour not_allowed)
			(footprints allowed)
		)
		(placement
			(enabled no)
			(sheetname "")
		)
		(fill yes
			(thermal_gap 0.5)
			(thermal_bridge_width 0.5)
			(island_removal_mode 0)
		)
		(polygon
			(pts
				(arc
					(start 288.514028 -230.485188)
					(mid 287.846008 -230.485188)
					(end 288.514028 -230.485188)
				)
			)
		)
	)
	(zone
		(layers "B.Cu" "In4.Cu" "In6.Cu" "In11.Cu" "In13.Cu" "In15.Cu")
		(hatch none 0.5)
		(connect_pads
			(clearance 0)
		)
		(min_thickness 0.25)
		(keepout
			(tracks not_allowed)
			(vias allowed)
			(pads allowed)
			(copperpour not_allowed)
			(footprints allowed)
		)
		(placement
			(enabled no)
			(sheetname "")
		)
		(fill yes
			(thermal_gap 0.5)
			(thermal_bridge_width 0.5)
			(island_removal_mode 0)
		)
		(polygon
			(pts
				(arc
					(start 94.236032 -239.624362)
					(mid 93.606112 -239.624362)
					(end 94.236032 -239.624362)
				)
			)
		)
	)
	(zone
		(layers "B.Cu" "In4.Cu" "In6.Cu" "In11.Cu" "In13.Cu" "In15.Cu")
		(hatch none 0.5)
		(connect_pads
			(clearance 0)
		)
		(min_thickness 0.25)
		(keepout
			(tracks not_allowed)
			(vias allowed)
			(pads allowed)
			(copperpour not_allowed)
			(footprints allowed)
		)
		(placement
			(enabled no)
			(sheetname "")
		)
		(fill yes
			(thermal_gap 0.5)
			(thermal_bridge_width 0.5)
			(island_removal_mode 0)
		)
		(polygon
			(pts
				(arc
					(start 351.876106 -294.335962)
					(mid 351.246186 -294.335962)
					(end 351.876106 -294.335962)
				)
			)
		)
	)
	(zone
		(layers "B.Cu" "In4.Cu" "In6.Cu" "In11.Cu" "In13.Cu" "In15.Cu")
		(hatch none 0.5)
		(connect_pads
			(clearance 0)
		)
		(min_thickness 0.25)
		(keepout
			(tracks not_allowed)
			(vias allowed)
			(pads allowed)
			(copperpour not_allowed)
			(footprints allowed)
		)
		(placement
			(enabled no)
			(sheetname "")
		)
		(fill yes
			(thermal_gap 0.5)
			(thermal_bridge_width 0.5)
			(island_removal_mode 0)
		)
		(polygon
			(pts
				(arc
					(start 183.950102 -249.18543)
					(mid 183.282082 -249.18543)
					(end 183.950102 -249.18543)
				)
			)
		)
	)
	(zone
		(layers "B.Cu" "In4.Cu" "In6.Cu" "In11.Cu" "In13.Cu" "In15.Cu")
		(hatch none 0.5)
		(connect_pads
			(clearance 0)
		)
		(min_thickness 0.25)
		(keepout
			(tracks not_allowed)
			(vias allowed)
			(pads allowed)
			(copperpour not_allowed)
			(footprints allowed)
		)
		(placement
			(enabled no)
			(sheetname "")
		)
		(fill yes
			(thermal_gap 0.5)
			(thermal_bridge_width 0.5)
			(island_removal_mode 0)
		)
		(polygon
			(pts
				(arc
					(start 342.945974 -288.66592)
					(mid 342.316054 -288.66592)
					(end 342.945974 -288.66592)
				)
			)
		)
	)
	(zone
		(layers "B.Cu" "In4.Cu" "In6.Cu" "In11.Cu" "In13.Cu" "In15.Cu")
		(hatch none 0.5)
		(connect_pads
			(clearance 0)
		)
		(min_thickness 0.25)
		(keepout
			(tracks not_allowed)
			(vias allowed)
			(pads allowed)
			(copperpour not_allowed)
			(footprints allowed)
		)
		(placement
			(enabled no)
			(sheetname "")
		)
		(fill yes
			(thermal_gap 0.5)
			(thermal_bridge_width 0.5)
			(island_removal_mode 0)
		)
		(polygon
			(pts
				(arc
					(start 183.950102 -252.58522)
					(mid 183.282082 -252.58522)
					(end 183.950102 -252.58522)
				)
			)
		)
	)
	(zone
		(layers "B.Cu" "In4.Cu" "In6.Cu" "In11.Cu" "In13.Cu" "In15.Cu")
		(hatch none 0.5)
		(connect_pads
			(clearance 0)
		)
		(min_thickness 0.25)
		(keepout
			(tracks not_allowed)
			(vias allowed)
			(pads allowed)
			(copperpour not_allowed)
			(footprints allowed)
		)
		(placement
			(enabled no)
			(sheetname "")
		)
		(fill yes
			(thermal_gap 0.5)
			(thermal_bridge_width 0.5)
			(island_removal_mode 0)
		)
		(polygon
			(pts
				(arc
					(start 427.790102 -239.835182)
					(mid 427.122082 -239.835182)
					(end 427.790102 -239.835182)
				)
			)
		)
	)
	(zone
		(layers "B.Cu" "In4.Cu" "In6.Cu" "In11.Cu" "In13.Cu" "In15.Cu")
		(hatch none 0.5)
		(connect_pads
			(clearance 0)
		)
		(min_thickness 0.25)
		(keepout
			(tracks not_allowed)
			(vias allowed)
			(pads allowed)
			(copperpour not_allowed)
			(footprints allowed)
		)
		(placement
			(enabled no)
			(sheetname "")
		)
		(fill yes
			(thermal_gap 0.5)
			(thermal_bridge_width 0.5)
			(island_removal_mode 0)
		)
		(polygon
			(pts
				(arc
					(start 128.369822 -282.996386)
					(mid 127.739902 -282.996386)
					(end 128.369822 -282.996386)
				)
			)
		)
	)
	(zone
		(layers "B.Cu" "In4.Cu" "In6.Cu" "In11.Cu" "In13.Cu" "In15.Cu")
		(hatch none 0.5)
		(connect_pads
			(clearance 0)
		)
		(min_thickness 0.25)
		(keepout
			(tracks not_allowed)
			(vias allowed)
			(pads allowed)
			(copperpour not_allowed)
			(footprints allowed)
		)
		(placement
			(enabled no)
			(sheetname "")
		)
		(fill yes
			(thermal_gap 0.5)
			(thermal_bridge_width 0.5)
			(island_removal_mode 0)
		)
		(polygon
			(pts
				(arc
					(start 343.586054 -250.154186)
					(mid 342.956134 -250.154186)
					(end 343.586054 -250.154186)
				)
			)
		)
	)
	(zone
		(layers "B.Cu" "In4.Cu" "In6.Cu" "In11.Cu" "In13.Cu" "In15.Cu")
		(hatch none 0.5)
		(connect_pads
			(clearance 0)
		)
		(min_thickness 0.25)
		(keepout
			(tracks not_allowed)
			(vias allowed)
			(pads allowed)
			(copperpour not_allowed)
			(footprints allowed)
		)
		(placement
			(enabled no)
			(sheetname "")
		)
		(fill yes
			(thermal_gap 0.5)
			(thermal_bridge_width 0.5)
			(island_removal_mode 0)
		)
		(polygon
			(pts
				(arc
					(start 377.719844 -287.045908)
					(mid 377.089924 -287.045908)
					(end 377.719844 -287.045908)
				)
			)
		)
	)
	(zone
		(layers "B.Cu" "In4.Cu" "In6.Cu" "In11.Cu" "In13.Cu" "In15.Cu")
		(hatch none 0.5)
		(connect_pads
			(clearance 0)
		)
		(min_thickness 0.25)
		(keepout
			(tracks not_allowed)
			(vias allowed)
			(pads allowed)
			(copperpour not_allowed)
			(footprints allowed)
		)
		(placement
			(enabled no)
			(sheetname "")
		)
		(fill yes
			(thermal_gap 0.5)
			(thermal_bridge_width 0.5)
			(island_removal_mode 0)
		)
		(polygon
			(pts
				(arc
					(start 44.674028 -206.685388)
					(mid 44.006008 -206.685388)
					(end 44.674028 -206.685388)
				)
			)
		)
	)
	(zone
		(layers "B.Cu" "In4.Cu" "In6.Cu" "In11.Cu" "In13.Cu" "In15.Cu")
		(hatch none 0.5)
		(connect_pads
			(clearance 0)
		)
		(min_thickness 0.25)
		(keepout
			(tracks not_allowed)
			(vias allowed)
			(pads allowed)
			(copperpour not_allowed)
			(footprints allowed)
		)
		(placement
			(enabled no)
			(sheetname "")
		)
		(fill yes
			(thermal_gap 0.5)
			(thermal_bridge_width 0.5)
			(island_removal_mode 0)
		)
		(polygon
			(pts
				(arc
					(start 96.115886 -234.764326)
					(mid 95.485966 -234.764326)
					(end 96.115886 -234.764326)
				)
			)
		)
	)
	(zone
		(layers "B.Cu" "In4.Cu" "In6.Cu" "In11.Cu" "In13.Cu" "In15.Cu")
		(hatch none 0.5)
		(connect_pads
			(clearance 0)
		)
		(min_thickness 0.25)
		(keepout
			(tracks not_allowed)
			(vias allowed)
			(pads allowed)
			(copperpour not_allowed)
			(footprints allowed)
		)
		(placement
			(enabled no)
			(sheetname "")
		)
		(fill yes
			(thermal_gap 0.5)
			(thermal_bridge_width 0.5)
			(island_removal_mode 0)
		)
		(polygon
			(pts
				(arc
					(start 378.189744 -281.37612)
					(mid 377.559824 -281.37612)
					(end 378.189744 -281.37612)
				)
			)
		)
	)
	(zone
		(layers "B.Cu" "In4.Cu" "In6.Cu" "In11.Cu" "In13.Cu" "In15.Cu")
		(hatch none 0.5)
		(connect_pads
			(clearance 0)
		)
		(min_thickness 0.25)
		(keepout
			(tracks not_allowed)
			(vias allowed)
			(pads allowed)
			(copperpour not_allowed)
			(footprints allowed)
		)
		(placement
			(enabled no)
			(sheetname "")
		)
		(fill yes
			(thermal_gap 0.5)
			(thermal_bridge_width 0.5)
			(island_removal_mode 0)
		)
		(polygon
			(pts
				(arc
					(start 179.850034 -318.035432)
					(mid 179.182014 -318.035432)
					(end 179.850034 -318.035432)
				)
			)
		)
	)
	(zone
		(layers "B.Cu" "In4.Cu" "In6.Cu" "In11.Cu" "In13.Cu" "In15.Cu")
		(hatch none 0.5)
		(connect_pads
			(clearance 0)
		)
		(min_thickness 0.25)
		(keepout
			(tracks not_allowed)
			(vias allowed)
			(pads allowed)
			(copperpour not_allowed)
			(footprints allowed)
		)
		(placement
			(enabled no)
			(sheetname "")
		)
		(fill yes
			(thermal_gap 0.5)
			(thermal_bridge_width 0.5)
			(island_removal_mode 0)
		)
		(polygon
			(pts
				(arc
					(start 349.995998 -292.71595)
					(mid 349.366078 -292.71595)
					(end 349.995998 -292.71595)
				)
			)
		)
	)
	(zone
		(layers "B.Cu" "In4.Cu" "In6.Cu" "In11.Cu" "In13.Cu" "In15.Cu")
		(hatch none 0.5)
		(connect_pads
			(clearance 0)
		)
		(min_thickness 0.25)
		(keepout
			(tracks not_allowed)
			(vias allowed)
			(pads allowed)
			(copperpour not_allowed)
			(footprints allowed)
		)
		(placement
			(enabled no)
			(sheetname "")
		)
		(fill yes
			(thermal_gap 0.5)
			(thermal_bridge_width 0.5)
			(island_removal_mode 0)
		)
		(polygon
			(pts
				(arc
					(start 376.30989 -291.095938)
					(mid 375.67997 -291.095938)
					(end 376.30989 -291.095938)
				)
			)
		)
	)
	(zone
		(layers "B.Cu" "In4.Cu" "In6.Cu" "In11.Cu" "In13.Cu" "In15.Cu")
		(hatch none 0.5)
		(connect_pads
			(clearance 0)
		)
		(min_thickness 0.25)
		(keepout
			(tracks not_allowed)
			(vias allowed)
			(pads allowed)
			(copperpour not_allowed)
			(footprints allowed)
		)
		(placement
			(enabled no)
			(sheetname "")
		)
		(fill yes
			(thermal_gap 0.5)
			(thermal_bridge_width 0.5)
			(island_removal_mode 0)
		)
		(polygon
			(pts
				(arc
					(start 288.514028 -305.28514)
					(mid 287.846008 -305.28514)
					(end 288.514028 -305.28514)
				)
			)
		)
	)
	(zone
		(layers "B.Cu" "In4.Cu" "In6.Cu" "In11.Cu" "In13.Cu" "In15.Cu")
		(hatch none 0.5)
		(connect_pads
			(clearance 0)
		)
		(min_thickness 0.25)
		(keepout
			(tracks not_allowed)
			(vias allowed)
			(pads allowed)
			(copperpour not_allowed)
			(footprints allowed)
		)
		(placement
			(enabled no)
			(sheetname "")
		)
		(fill yes
			(thermal_gap 0.5)
			(thermal_bridge_width 0.5)
			(island_removal_mode 0)
		)
		(polygon
			(pts
				(arc
					(start 101.755956 -229.90429)
					(mid 101.126036 -229.90429)
					(end 101.755956 -229.90429)
				)
			)
		)
	)
	(zone
		(layers "B.Cu" "In4.Cu" "In6.Cu" "In11.Cu" "In13.Cu" "In15.Cu")
		(hatch none 0.5)
		(connect_pads
			(clearance 0)
		)
		(min_thickness 0.25)
		(keepout
			(tracks not_allowed)
			(vias allowed)
			(pads allowed)
			(copperpour not_allowed)
			(footprints allowed)
		)
		(placement
			(enabled no)
			(sheetname "")
		)
		(fill yes
			(thermal_gap 0.5)
			(thermal_bridge_width 0.5)
			(island_removal_mode 0)
		)
		(polygon
			(pts
				(arc
					(start 292.614096 -284.88513)
					(mid 291.946076 -284.88513)
					(end 292.614096 -284.88513)
				)
			)
		)
	)
	(zone
		(layers "B.Cu" "In4.Cu" "In6.Cu" "In11.Cu" "In13.Cu" "In15.Cu")
		(hatch none 0.5)
		(connect_pads
			(clearance 0)
		)
		(min_thickness 0.25)
		(keepout
			(tracks not_allowed)
			(vias allowed)
			(pads allowed)
			(copperpour not_allowed)
			(footprints allowed)
		)
		(placement
			(enabled no)
			(sheetname "")
		)
		(fill yes
			(thermal_gap 0.5)
			(thermal_bridge_width 0.5)
			(island_removal_mode 0)
		)
		(polygon
			(pts
				(arc
					(start 292.614096 -254.284988)
					(mid 291.946076 -254.284988)
					(end 292.614096 -254.284988)
				)
			)
		)
	)
	(zone
		(layers "B.Cu" "In4.Cu" "In6.Cu" "In11.Cu" "In13.Cu" "In15.Cu")
		(hatch none 0.5)
		(connect_pads
			(clearance 0)
		)
		(min_thickness 0.25)
		(keepout
			(tracks not_allowed)
			(vias allowed)
			(pads allowed)
			(copperpour not_allowed)
			(footprints allowed)
		)
		(placement
			(enabled no)
			(sheetname "")
		)
		(fill yes
			(thermal_gap 0.5)
			(thermal_bridge_width 0.5)
			(island_removal_mode 0)
		)
		(polygon
			(pts
				(arc
					(start 376.30989 -292.71595)
					(mid 375.67997 -292.71595)
					(end 376.30989 -292.71595)
				)
			)
		)
	)
	(zone
		(layers "B.Cu" "In4.Cu" "In6.Cu" "In11.Cu" "In13.Cu" "In15.Cu")
		(hatch none 0.5)
		(connect_pads
			(clearance 0)
		)
		(min_thickness 0.25)
		(keepout
			(tracks not_allowed)
			(vias allowed)
			(pads allowed)
			(copperpour not_allowed)
			(footprints allowed)
		)
		(placement
			(enabled no)
			(sheetname "")
		)
		(fill yes
			(thermal_gap 0.5)
			(thermal_bridge_width 0.5)
			(island_removal_mode 0)
		)
		(polygon
			(pts
				(arc
					(start 97.995994 -229.90429)
					(mid 97.366074 -229.90429)
					(end 97.995994 -229.90429)
				)
			)
		)
	)
	(zone
		(layers "B.Cu" "In4.Cu" "In6.Cu" "In11.Cu" "In13.Cu" "In15.Cu")
		(hatch none 0.5)
		(connect_pads
			(clearance 0)
		)
		(min_thickness 0.25)
		(keepout
			(tracks not_allowed)
			(vias allowed)
			(pads allowed)
			(copperpour not_allowed)
			(footprints allowed)
		)
		(placement
			(enabled no)
			(sheetname "")
		)
		(fill yes
			(thermal_gap 0.5)
			(thermal_bridge_width 0.5)
			(island_removal_mode 0)
		)
		(polygon
			(pts
				(arc
					(start 374.129808 -226.664266)
					(mid 373.499888 -226.664266)
					(end 374.129808 -226.664266)
				)
			)
		)
	)
	(zone
		(layers "B.Cu" "In4.Cu" "In6.Cu" "In11.Cu" "In13.Cu" "In15.Cu")
		(hatch none 0.5)
		(connect_pads
			(clearance 0)
		)
		(min_thickness 0.25)
		(keepout
			(tracks not_allowed)
			(vias allowed)
			(pads allowed)
			(copperpour not_allowed)
			(footprints allowed)
		)
		(placement
			(enabled no)
			(sheetname "")
		)
		(fill yes
			(thermal_gap 0.5)
			(thermal_bridge_width 0.5)
			(island_removal_mode 0)
		)
		(polygon
			(pts
				(arc
					(start 342.1761 -254.204216)
					(mid 341.54618 -254.204216)
					(end 342.1761 -254.204216)
				)
			)
		)
	)
	(zone
		(layers "B.Cu" "In4.Cu" "In6.Cu" "In11.Cu" "In13.Cu" "In15.Cu")
		(hatch none 0.5)
		(connect_pads
			(clearance 0)
		)
		(min_thickness 0.25)
		(keepout
			(tracks not_allowed)
			(vias allowed)
			(pads allowed)
			(copperpour not_allowed)
			(footprints allowed)
		)
		(placement
			(enabled no)
			(sheetname "")
		)
		(fill yes
			(thermal_gap 0.5)
			(thermal_bridge_width 0.5)
			(island_removal_mode 0)
		)
		(polygon
			(pts
				(arc
					(start 179.850034 -235.585254)
					(mid 179.182014 -235.585254)
					(end 179.850034 -235.585254)
				)
			)
		)
	)
	(zone
		(layers "B.Cu" "In4.Cu" "In6.Cu" "In11.Cu" "In13.Cu" "In15.Cu")
		(hatch none 0.5)
		(connect_pads
			(clearance 0)
		)
		(min_thickness 0.25)
		(keepout
			(tracks not_allowed)
			(vias allowed)
			(pads allowed)
			(copperpour not_allowed)
			(footprints allowed)
		)
		(placement
			(enabled no)
			(sheetname "")
		)
		(fill yes
			(thermal_gap 0.5)
			(thermal_bridge_width 0.5)
			(island_removal_mode 0)
		)
		(polygon
			(pts
				(arc
					(start 183.950102 -228.78542)
					(mid 183.282082 -228.78542)
					(end 183.950102 -228.78542)
				)
			)
		)
	)
	(zone
		(layers "B.Cu" "In4.Cu" "In6.Cu" "In11.Cu" "In13.Cu" "In15.Cu")
		(hatch none 0.5)
		(connect_pads
			(clearance 0)
		)
		(min_thickness 0.25)
		(keepout
			(tracks not_allowed)
			(vias allowed)
			(pads allowed)
			(copperpour not_allowed)
			(footprints allowed)
		)
		(placement
			(enabled no)
			(sheetname "")
		)
		(fill yes
			(thermal_gap 0.5)
			(thermal_bridge_width 0.5)
			(island_removal_mode 0)
		)
		(polygon
			(pts
				(arc
					(start 95.645986 -237.194344)
					(mid 95.016066 -237.194344)
					(end 95.645986 -237.194344)
				)
			)
		)
	)
	(zone
		(layers "B.Cu" "In4.Cu" "In6.Cu" "In11.Cu" "In13.Cu" "In15.Cu")
		(hatch none 0.5)
		(connect_pads
			(clearance 0)
		)
		(min_thickness 0.25)
		(keepout
			(tracks not_allowed)
			(vias allowed)
			(pads allowed)
			(copperpour not_allowed)
			(footprints allowed)
		)
		(placement
			(enabled no)
			(sheetname "")
		)
		(fill yes
			(thermal_gap 0.5)
			(thermal_bridge_width 0.5)
			(island_removal_mode 0)
		)
		(polygon
			(pts
				(arc
					(start 363.319822 -230.714296)
					(mid 362.689902 -230.714296)
					(end 363.319822 -230.714296)
				)
			)
		)
	)
	(zone
		(layers "B.Cu" "In4.Cu" "In6.Cu" "In11.Cu" "In13.Cu" "In15.Cu")
		(hatch none 0.5)
		(connect_pads
			(clearance 0)
		)
		(min_thickness 0.25)
		(keepout
			(tracks not_allowed)
			(vias allowed)
			(pads allowed)
			(copperpour not_allowed)
			(footprints allowed)
		)
		(placement
			(enabled no)
			(sheetname "")
		)
		(fill yes
			(thermal_gap 0.5)
			(thermal_bridge_width 0.5)
			(island_removal_mode 0)
		)
		(polygon
			(pts
				(arc
					(start 107.396026 -228.284532)
					(mid 106.766106 -228.284532)
					(end 107.396026 -228.284532)
				)
			)
		)
	)
	(zone
		(layers "B.Cu" "In4.Cu" "In6.Cu" "In11.Cu" "In13.Cu" "In15.Cu")
		(hatch none 0.5)
		(connect_pads
			(clearance 0)
		)
		(min_thickness 0.25)
		(keepout
			(tracks not_allowed)
			(vias allowed)
			(pads allowed)
			(copperpour not_allowed)
			(footprints allowed)
		)
		(placement
			(enabled no)
			(sheetname "")
		)
		(fill yes
			(thermal_gap 0.5)
			(thermal_bridge_width 0.5)
			(island_removal_mode 0)
		)
		(polygon
			(pts
				(arc
					(start 103.636064 -226.66452)
					(mid 103.006144 -226.66452)
					(end 103.636064 -226.66452)
				)
			)
		)
	)
	(zone
		(layers "B.Cu" "In4.Cu" "In6.Cu" "In11.Cu" "In13.Cu" "In15.Cu")
		(hatch none 0.5)
		(connect_pads
			(clearance 0)
		)
		(min_thickness 0.25)
		(keepout
			(tracks not_allowed)
			(vias allowed)
			(pads allowed)
			(copperpour not_allowed)
			(footprints allowed)
		)
		(placement
			(enabled no)
			(sheetname "")
		)
		(fill yes
			(thermal_gap 0.5)
			(thermal_bridge_width 0.5)
			(island_removal_mode 0)
		)
		(polygon
			(pts
				(arc
					(start 40.57396 -295.9354)
					(mid 39.90594 -295.9354)
					(end 40.57396 -295.9354)
				)
			)
		)
	)
	(zone
		(layers "B.Cu" "In4.Cu" "In6.Cu" "In11.Cu" "In13.Cu" "In15.Cu")
		(hatch none 0.5)
		(connect_pads
			(clearance 0)
		)
		(min_thickness 0.25)
		(keepout
			(tracks not_allowed)
			(vias allowed)
			(pads allowed)
			(copperpour not_allowed)
			(footprints allowed)
		)
		(placement
			(enabled no)
			(sheetname "")
		)
		(fill yes
			(thermal_gap 0.5)
			(thermal_bridge_width 0.5)
			(island_removal_mode 0)
		)
		(polygon
			(pts
				(arc
					(start 98.936048 -228.284532)
					(mid 98.306128 -228.284532)
					(end 98.936048 -228.284532)
				)
			)
		)
	)
	(zone
		(layers "B.Cu" "In4.Cu" "In6.Cu" "In11.Cu" "In13.Cu" "In15.Cu")
		(hatch none 0.5)
		(connect_pads
			(clearance 0)
		)
		(min_thickness 0.25)
		(keepout
			(tracks not_allowed)
			(vias allowed)
			(pads allowed)
			(copperpour not_allowed)
			(footprints allowed)
		)
		(placement
			(enabled no)
			(sheetname "")
		)
		(fill yes
			(thermal_gap 0.5)
			(thermal_bridge_width 0.5)
			(island_removal_mode 0)
		)
		(polygon
			(pts
				(arc
					(start 377.719844 -275.706078)
					(mid 377.089924 -275.706078)
					(end 377.719844 -275.706078)
				)
			)
		)
	)
	(zone
		(layers "B.Cu" "In4.Cu" "In6.Cu" "In11.Cu" "In13.Cu" "In15.Cu")
		(hatch none 0.5)
		(connect_pads
			(clearance 0)
		)
		(min_thickness 0.25)
		(keepout
			(tracks not_allowed)
			(vias allowed)
			(pads allowed)
			(copperpour not_allowed)
			(footprints allowed)
		)
		(placement
			(enabled no)
			(sheetname "")
		)
		(fill yes
			(thermal_gap 0.5)
			(thermal_bridge_width 0.5)
			(island_removal_mode 0)
		)
		(polygon
			(pts
				(arc
					(start 427.790102 -222.834962)
					(mid 427.122082 -222.834962)
					(end 427.790102 -222.834962)
				)
			)
		)
	)
	(zone
		(layers "B.Cu" "In4.Cu" "In6.Cu" "In11.Cu" "In13.Cu" "In15.Cu")
		(hatch none 0.5)
		(connect_pads
			(clearance 0)
		)
		(min_thickness 0.25)
		(keepout
			(tracks not_allowed)
			(vias allowed)
			(pads allowed)
			(copperpour not_allowed)
			(footprints allowed)
		)
		(placement
			(enabled no)
			(sheetname "")
		)
		(fill yes
			(thermal_gap 0.5)
			(thermal_bridge_width 0.5)
			(island_removal_mode 0)
		)
		(polygon
			(pts
				(arc
					(start 40.57396 -218.585288)
					(mid 39.90594 -218.585288)
					(end 40.57396 -218.585288)
				)
			)
		)
	)
	(zone
		(layers "B.Cu" "In4.Cu" "In6.Cu" "In11.Cu" "In13.Cu" "In15.Cu")
		(hatch none 0.5)
		(connect_pads
			(clearance 0)
		)
		(min_thickness 0.25)
		(keepout
			(tracks not_allowed)
			(vias allowed)
			(pads allowed)
			(copperpour not_allowed)
			(footprints allowed)
		)
		(placement
			(enabled no)
			(sheetname "")
		)
		(fill yes
			(thermal_gap 0.5)
			(thermal_bridge_width 0.5)
			(island_removal_mode 0)
		)
		(polygon
			(pts
				(arc
					(start 183.950102 -214.33536)
					(mid 183.282082 -214.33536)
					(end 183.950102 -214.33536)
				)
			)
		)
	)
	(zone
		(layers "B.Cu" "In4.Cu" "In6.Cu" "In11.Cu" "In13.Cu" "In15.Cu")
		(hatch none 0.5)
		(connect_pads
			(clearance 0)
		)
		(min_thickness 0.25)
		(keepout
			(tracks not_allowed)
			(vias allowed)
			(pads allowed)
			(copperpour not_allowed)
			(footprints allowed)
		)
		(placement
			(enabled no)
			(sheetname "")
		)
		(fill yes
			(thermal_gap 0.5)
			(thermal_bridge_width 0.5)
			(island_removal_mode 0)
		)
		(polygon
			(pts
				(arc
					(start 40.57396 -295.085262)
					(mid 39.90594 -295.085262)
					(end 40.57396 -295.085262)
				)
			)
		)
	)
	(zone
		(layers "B.Cu" "In4.Cu" "In6.Cu" "In11.Cu" "In13.Cu" "In15.Cu")
		(hatch none 0.5)
		(connect_pads
			(clearance 0)
		)
		(min_thickness 0.25)
		(keepout
			(tracks not_allowed)
			(vias allowed)
			(pads allowed)
			(copperpour not_allowed)
			(footprints allowed)
		)
		(placement
			(enabled no)
			(sheetname "")
		)
		(fill yes
			(thermal_gap 0.5)
			(thermal_bridge_width 0.5)
			(island_removal_mode 0)
		)
		(polygon
			(pts
				(arc
					(start 128.539748 -227.474526)
					(mid 127.909828 -227.474526)
					(end 128.539748 -227.474526)
				)
			)
		)
	)
	(zone
		(layers "B.Cu" "In4.Cu" "In6.Cu" "In11.Cu" "In13.Cu" "In15.Cu")
		(hatch none 0.5)
		(connect_pads
			(clearance 0)
		)
		(min_thickness 0.25)
		(keepout
			(tracks not_allowed)
			(vias allowed)
			(pads allowed)
			(copperpour not_allowed)
			(footprints allowed)
		)
		(placement
			(enabled no)
			(sheetname "")
		)
		(fill yes
			(thermal_gap 0.5)
			(thermal_bridge_width 0.5)
			(island_removal_mode 0)
		)
		(polygon
			(pts
				(arc
					(start 179.850034 -241.535204)
					(mid 179.182014 -241.535204)
					(end 179.850034 -241.535204)
				)
			)
		)
	)
	(zone
		(layers "B.Cu" "In4.Cu" "In6.Cu" "In11.Cu" "In13.Cu" "In15.Cu")
		(hatch none 0.5)
		(connect_pads
			(clearance 0)
		)
		(min_thickness 0.25)
		(keepout
			(tracks not_allowed)
			(vias allowed)
			(pads allowed)
			(copperpour not_allowed)
			(footprints allowed)
		)
		(placement
			(enabled no)
			(sheetname "")
		)
		(fill yes
			(thermal_gap 0.5)
			(thermal_bridge_width 0.5)
			(island_removal_mode 0)
		)
		(polygon
			(pts
				(arc
					(start 288.514028 -293.384986)
					(mid 287.846008 -293.384986)
					(end 288.514028 -293.384986)
				)
			)
		)
	)
	(zone
		(layers "B.Cu" "In4.Cu" "In6.Cu" "In11.Cu" "In13.Cu" "In15.Cu")
		(hatch none 0.5)
		(connect_pads
			(clearance 0)
		)
		(min_thickness 0.25)
		(keepout
			(tracks not_allowed)
			(vias allowed)
			(pads allowed)
			(copperpour not_allowed)
			(footprints allowed)
		)
		(placement
			(enabled no)
			(sheetname "")
		)
		(fill yes
			(thermal_gap 0.5)
			(thermal_bridge_width 0.5)
			(island_removal_mode 0)
		)
		(polygon
			(pts
				(arc
					(start 130.249676 -286.23641)
					(mid 129.619756 -286.23641)
					(end 130.249676 -286.23641)
				)
			)
		)
	)
	(zone
		(layers "B.Cu" "In4.Cu" "In6.Cu" "In11.Cu" "In13.Cu" "In15.Cu")
		(hatch none 0.5)
		(connect_pads
			(clearance 0)
		)
		(min_thickness 0.25)
		(keepout
			(tracks not_allowed)
			(vias allowed)
			(pads allowed)
			(copperpour not_allowed)
			(footprints allowed)
		)
		(placement
			(enabled no)
			(sheetname "")
		)
		(fill yes
			(thermal_gap 0.5)
			(thermal_bridge_width 0.5)
			(island_removal_mode 0)
		)
		(polygon
			(pts
				(arc
					(start 128.539748 -246.914416)
					(mid 127.909828 -246.914416)
					(end 128.539748 -246.914416)
				)
			)
		)
	)
	(zone
		(layers "B.Cu" "In4.Cu" "In6.Cu" "In11.Cu" "In13.Cu" "In15.Cu")
		(hatch none 0.5)
		(connect_pads
			(clearance 0)
		)
		(min_thickness 0.25)
		(keepout
			(tracks not_allowed)
			(vias allowed)
			(pads allowed)
			(copperpour not_allowed)
			(footprints allowed)
		)
		(placement
			(enabled no)
			(sheetname "")
		)
		(fill yes
			(thermal_gap 0.5)
			(thermal_bridge_width 0.5)
			(island_removal_mode 0)
		)
		(polygon
			(pts
				(arc
					(start 288.514028 -224.534984)
					(mid 287.846008 -224.534984)
					(end 288.514028 -224.534984)
				)
			)
		)
	)
	(zone
		(layers "B.Cu" "In4.Cu" "In6.Cu" "In11.Cu" "In13.Cu" "In15.Cu")
		(hatch none 0.5)
		(connect_pads
			(clearance 0)
		)
		(min_thickness 0.25)
		(keepout
			(tracks not_allowed)
			(vias allowed)
			(pads allowed)
			(copperpour not_allowed)
			(footprints allowed)
		)
		(placement
			(enabled no)
			(sheetname "")
		)
		(fill yes
			(thermal_gap 0.5)
			(thermal_bridge_width 0.5)
			(island_removal_mode 0)
		)
		(polygon
			(pts
				(arc
					(start 427.790102 -265.335004)
					(mid 427.122082 -265.335004)
					(end 427.790102 -265.335004)
				)
			)
		)
	)
	(zone
		(layers "B.Cu" "In4.Cu" "In6.Cu" "In11.Cu" "In13.Cu" "In15.Cu")
		(hatch none 0.5)
		(connect_pads
			(clearance 0)
		)
		(min_thickness 0.25)
		(keepout
			(tracks not_allowed)
			(vias allowed)
			(pads allowed)
			(copperpour not_allowed)
			(footprints allowed)
		)
		(placement
			(enabled no)
			(sheetname "")
		)
		(fill yes
			(thermal_gap 0.5)
			(thermal_bridge_width 0.5)
			(island_removal_mode 0)
		)
		(polygon
			(pts
				(arc
					(start 96.115886 -254.20447)
					(mid 95.485966 -254.20447)
					(end 96.115886 -254.20447)
				)
			)
		)
	)
	(zone
		(layers "B.Cu" "In4.Cu" "In6.Cu" "In11.Cu" "In13.Cu" "In15.Cu")
		(hatch none 0.5)
		(connect_pads
			(clearance 0)
		)
		(min_thickness 0.25)
		(keepout
			(tracks not_allowed)
			(vias allowed)
			(pads allowed)
			(copperpour not_allowed)
			(footprints allowed)
		)
		(placement
			(enabled no)
			(sheetname "")
		)
		(fill yes
			(thermal_gap 0.5)
			(thermal_bridge_width 0.5)
			(island_removal_mode 0)
		)
		(polygon
			(pts
				(arc
					(start 378.189744 -270.036036)
					(mid 377.559824 -270.036036)
					(end 378.189744 -270.036036)
				)
			)
		)
	)
	(zone
		(layers "B.Cu" "In4.Cu" "In6.Cu" "In11.Cu" "In13.Cu" "In15.Cu")
		(hatch none 0.5)
		(connect_pads
			(clearance 0)
		)
		(min_thickness 0.25)
		(keepout
			(tracks not_allowed)
			(vias allowed)
			(pads allowed)
			(copperpour not_allowed)
			(footprints allowed)
		)
		(placement
			(enabled no)
			(sheetname "")
		)
		(fill yes
			(thermal_gap 0.5)
			(thermal_bridge_width 0.5)
			(island_removal_mode 0)
		)
		(polygon
			(pts
				(arc
					(start 292.614096 -231.335072)
					(mid 291.946076 -231.335072)
					(end 292.614096 -231.335072)
				)
			)
		)
	)
	(zone
		(layers "B.Cu" "In4.Cu" "In6.Cu" "In11.Cu" "In13.Cu" "In15.Cu")
		(hatch none 0.5)
		(connect_pads
			(clearance 0)
		)
		(min_thickness 0.25)
		(keepout
			(tracks not_allowed)
			(vias allowed)
			(pads allowed)
			(copperpour not_allowed)
			(footprints allowed)
		)
		(placement
			(enabled no)
			(sheetname "")
		)
		(fill yes
			(thermal_gap 0.5)
			(thermal_bridge_width 0.5)
			(island_removal_mode 0)
		)
		(polygon
			(pts
				(arc
					(start 128.539748 -248.534428)
					(mid 127.909828 -248.534428)
					(end 128.539748 -248.534428)
				)
			)
		)
	)
	(zone
		(layers "B.Cu" "In4.Cu" "In6.Cu" "In11.Cu" "In13.Cu" "In15.Cu")
		(hatch none 0.5)
		(connect_pads
			(clearance 0)
		)
		(min_thickness 0.25)
		(keepout
			(tracks not_allowed)
			(vias allowed)
			(pads allowed)
			(copperpour not_allowed)
			(footprints allowed)
		)
		(placement
			(enabled no)
			(sheetname "")
		)
		(fill yes
			(thermal_gap 0.5)
			(thermal_bridge_width 0.5)
			(island_removal_mode 0)
		)
		(polygon
			(pts
				(arc
					(start 130.249676 -287.856422)
					(mid 129.619756 -287.856422)
					(end 130.249676 -287.856422)
				)
			)
		)
	)
	(zone
		(layers "B.Cu" "In4.Cu" "In6.Cu" "In11.Cu" "In13.Cu" "In15.Cu")
		(hatch none 0.5)
		(connect_pads
			(clearance 0)
		)
		(min_thickness 0.25)
		(keepout
			(tracks not_allowed)
			(vias allowed)
			(pads allowed)
			(copperpour not_allowed)
			(footprints allowed)
		)
		(placement
			(enabled no)
			(sheetname "")
		)
		(fill yes
			(thermal_gap 0.5)
			(thermal_bridge_width 0.5)
			(island_removal_mode 0)
		)
		(polygon
			(pts
				(arc
					(start 342.476074 -282.996132)
					(mid 341.846154 -282.996132)
					(end 342.476074 -282.996132)
				)
			)
		)
	)
	(zone
		(layers "B.Cu" "In4.Cu" "In6.Cu" "In11.Cu" "In13.Cu" "In15.Cu")
		(hatch none 0.5)
		(connect_pads
			(clearance 0)
		)
		(min_thickness 0.25)
		(keepout
			(tracks not_allowed)
			(vias allowed)
			(pads allowed)
			(copperpour not_allowed)
			(footprints allowed)
		)
		(placement
			(enabled no)
			(sheetname "")
		)
		(fill yes
			(thermal_gap 0.5)
			(thermal_bridge_width 0.5)
			(island_removal_mode 0)
		)
		(polygon
			(pts
				(arc
					(start 129.779776 -274.08632)
					(mid 129.149856 -274.08632)
					(end 129.779776 -274.08632)
				)
			)
		)
	)
	(zone
		(layers "B.Cu" "In4.Cu" "In6.Cu" "In11.Cu" "In13.Cu" "In15.Cu")
		(hatch none 0.5)
		(connect_pads
			(clearance 0)
		)
		(min_thickness 0.25)
		(keepout
			(tracks not_allowed)
			(vias allowed)
			(pads allowed)
			(copperpour not_allowed)
			(footprints allowed)
		)
		(placement
			(enabled no)
			(sheetname "")
		)
		(fill yes
			(thermal_gap 0.5)
			(thermal_bridge_width 0.5)
			(island_removal_mode 0)
		)
		(polygon
			(pts
				(arc
					(start 344.055954 -252.584204)
					(mid 343.426034 -252.584204)
					(end 344.055954 -252.584204)
				)
			)
		)
	)
	(zone
		(layers "B.Cu" "In4.Cu" "In6.Cu" "In11.Cu" "In13.Cu" "In15.Cu")
		(hatch none 0.5)
		(connect_pads
			(clearance 0)
		)
		(min_thickness 0.25)
		(keepout
			(tracks not_allowed)
			(vias allowed)
			(pads allowed)
			(copperpour not_allowed)
			(footprints allowed)
		)
		(placement
			(enabled no)
			(sheetname "")
		)
		(fill yes
			(thermal_gap 0.5)
			(thermal_bridge_width 0.5)
			(island_removal_mode 0)
		)
		(polygon
			(pts
				(arc
					(start 427.790102 -293.384986)
					(mid 427.122082 -293.384986)
					(end 427.790102 -293.384986)
				)
			)
		)
	)
	(zone
		(layers "B.Cu" "In4.Cu" "In6.Cu" "In11.Cu" "In13.Cu" "In15.Cu")
		(hatch none 0.5)
		(connect_pads
			(clearance 0)
		)
		(min_thickness 0.25)
		(keepout
			(tracks not_allowed)
			(vias allowed)
			(pads allowed)
			(copperpour not_allowed)
			(footprints allowed)
		)
		(placement
			(enabled no)
			(sheetname "")
		)
		(fill yes
			(thermal_gap 0.5)
			(thermal_bridge_width 0.5)
			(island_removal_mode 0)
		)
		(polygon
			(pts
				(arc
					(start 342.1761 -241.24412)
					(mid 341.54618 -241.24412)
					(end 342.1761 -241.24412)
				)
			)
		)
	)
	(zone
		(layers "B.Cu" "In4.Cu" "In6.Cu" "In11.Cu" "In13.Cu" "In15.Cu")
		(hatch none 0.5)
		(connect_pads
			(clearance 0)
		)
		(min_thickness 0.25)
		(keepout
			(tracks not_allowed)
			(vias allowed)
			(pads allowed)
			(copperpour not_allowed)
			(footprints allowed)
		)
		(placement
			(enabled no)
			(sheetname "")
		)
		(fill yes
			(thermal_gap 0.5)
			(thermal_bridge_width 0.5)
			(island_removal_mode 0)
		)
		(polygon
			(pts
				(arc
					(start 342.1761 -226.664266)
					(mid 341.54618 -226.664266)
					(end 342.1761 -226.664266)
				)
			)
		)
	)
	(zone
		(layers "B.Cu" "In4.Cu" "In6.Cu" "In11.Cu" "In13.Cu" "In15.Cu")
		(hatch none 0.5)
		(connect_pads
			(clearance 0)
		)
		(min_thickness 0.25)
		(keepout
			(tracks not_allowed)
			(vias allowed)
			(pads allowed)
			(copperpour not_allowed)
			(footprints allowed)
		)
		(placement
			(enabled no)
			(sheetname "")
		)
		(fill yes
			(thermal_gap 0.5)
			(thermal_bridge_width 0.5)
			(island_removal_mode 0)
		)
		(polygon
			(pts
				(arc
					(start 95.005906 -285.426404)
					(mid 94.375986 -285.426404)
					(end 95.005906 -285.426404)
				)
			)
		)
	)
	(zone
		(layers "B.Cu" "In4.Cu" "In6.Cu" "In11.Cu" "In13.Cu" "In15.Cu")
		(hatch none 0.5)
		(connect_pads
			(clearance 0)
		)
		(min_thickness 0.25)
		(keepout
			(tracks not_allowed)
			(vias allowed)
			(pads allowed)
			(copperpour not_allowed)
			(footprints allowed)
		)
		(placement
			(enabled no)
			(sheetname "")
		)
		(fill yes
			(thermal_gap 0.5)
			(thermal_bridge_width 0.5)
			(island_removal_mode 0)
		)
		(polygon
			(pts
				(arc
					(start 431.89017 -273.835114)
					(mid 431.22215 -273.835114)
					(end 431.89017 -273.835114)
				)
			)
		)
	)
	(zone
		(layers "B.Cu" "In4.Cu" "In6.Cu" "In11.Cu" "In13.Cu" "In15.Cu")
		(hatch none 0.5)
		(connect_pads
			(clearance 0)
		)
		(min_thickness 0.25)
		(keepout
			(tracks not_allowed)
			(vias allowed)
			(pads allowed)
			(copperpour not_allowed)
			(footprints allowed)
		)
		(placement
			(enabled no)
			(sheetname "")
		)
		(fill yes
			(thermal_gap 0.5)
			(thermal_bridge_width 0.5)
			(island_removal_mode 0)
		)
		(polygon
			(pts
				(arc
					(start 376.30989 -282.996132)
					(mid 375.67997 -282.996132)
					(end 376.30989 -282.996132)
				)
			)
		)
	)
	(zone
		(layers "B.Cu" "In4.Cu" "In6.Cu" "In11.Cu" "In13.Cu" "In15.Cu")
		(hatch none 0.5)
		(connect_pads
			(clearance 0)
		)
		(min_thickness 0.25)
		(keepout
			(tracks not_allowed)
			(vias allowed)
			(pads allowed)
			(copperpour not_allowed)
			(footprints allowed)
		)
		(placement
			(enabled no)
			(sheetname "")
		)
		(fill yes
			(thermal_gap 0.5)
			(thermal_bridge_width 0.5)
			(island_removal_mode 0)
		)
		(polygon
			(pts
				(arc
					(start 377.719844 -282.186126)
					(mid 377.089924 -282.186126)
					(end 377.719844 -282.186126)
				)
			)
		)
	)
	(zone
		(layers "B.Cu" "In4.Cu" "In6.Cu" "In11.Cu" "In13.Cu" "In15.Cu")
		(hatch none 0.5)
		(connect_pads
			(clearance 0)
		)
		(min_thickness 0.25)
		(keepout
			(tracks not_allowed)
			(vias allowed)
			(pads allowed)
			(copperpour not_allowed)
			(footprints allowed)
		)
		(placement
			(enabled no)
			(sheetname "")
		)
		(fill yes
			(thermal_gap 0.5)
			(thermal_bridge_width 0.5)
			(island_removal_mode 0)
		)
		(polygon
			(pts
				(arc
					(start 376.77979 -285.42615)
					(mid 376.14987 -285.42615)
					(end 376.77979 -285.42615)
				)
			)
		)
	)
	(zone
		(layers "B.Cu" "In4.Cu" "In6.Cu" "In11.Cu" "In13.Cu" "In15.Cu")
		(hatch none 0.5)
		(connect_pads
			(clearance 0)
		)
		(min_thickness 0.25)
		(keepout
			(tracks not_allowed)
			(vias allowed)
			(pads allowed)
			(copperpour not_allowed)
			(footprints allowed)
		)
		(placement
			(enabled no)
			(sheetname "")
		)
		(fill yes
			(thermal_gap 0.5)
			(thermal_bridge_width 0.5)
			(island_removal_mode 0)
		)
		(polygon
			(pts
				(arc
					(start 431.89017 -204.985112)
					(mid 431.22215 -204.985112)
					(end 431.89017 -204.985112)
				)
			)
		)
	)
	(zone
		(layers "B.Cu" "In4.Cu" "In6.Cu" "In11.Cu" "In13.Cu" "In15.Cu")
		(hatch none 0.5)
		(connect_pads
			(clearance 0)
		)
		(min_thickness 0.25)
		(keepout
			(tracks not_allowed)
			(vias allowed)
			(pads allowed)
			(copperpour not_allowed)
			(footprints allowed)
		)
		(placement
			(enabled no)
			(sheetname "")
		)
		(fill yes
			(thermal_gap 0.5)
			(thermal_bridge_width 0.5)
			(island_removal_mode 0)
		)
		(polygon
			(pts
				(arc
					(start 44.674028 -254.285242)
					(mid 44.006008 -254.285242)
					(end 44.674028 -254.285242)
				)
			)
		)
	)
	(zone
		(layers "B.Cu" "In4.Cu" "In6.Cu" "In11.Cu" "In13.Cu" "In15.Cu")
		(hatch none 0.5)
		(connect_pads
			(clearance 0)
		)
		(min_thickness 0.25)
		(keepout
			(tracks not_allowed)
			(vias allowed)
			(pads allowed)
			(copperpour not_allowed)
			(footprints allowed)
		)
		(placement
			(enabled no)
			(sheetname "")
		)
		(fill yes
			(thermal_gap 0.5)
			(thermal_bridge_width 0.5)
			(island_removal_mode 0)
		)
		(polygon
			(pts
				(arc
					(start 427.790102 -202.434952)
					(mid 427.122082 -202.434952)
					(end 427.790102 -202.434952)
				)
			)
		)
	)
	(zone
		(layers "B.Cu" "In4.Cu" "In6.Cu" "In11.Cu" "In13.Cu" "In15.Cu")
		(hatch none 0.5)
		(connect_pads
			(clearance 0)
		)
		(min_thickness 0.25)
		(keepout
			(tracks not_allowed)
			(vias allowed)
			(pads allowed)
			(copperpour not_allowed)
			(footprints allowed)
		)
		(placement
			(enabled no)
			(sheetname "")
		)
		(fill yes
			(thermal_gap 0.5)
			(thermal_bridge_width 0.5)
			(island_removal_mode 0)
		)
		(polygon
			(pts
				(arc
					(start 377.41987 -243.674138)
					(mid 376.78995 -243.674138)
					(end 377.41987 -243.674138)
				)
			)
		)
	)
	(zone
		(layers "B.Cu" "In4.Cu" "In6.Cu" "In11.Cu" "In13.Cu" "In15.Cu")
		(hatch none 0.5)
		(connect_pads
			(clearance 0)
		)
		(min_thickness 0.25)
		(keepout
			(tracks not_allowed)
			(vias allowed)
			(pads allowed)
			(copperpour not_allowed)
			(footprints allowed)
		)
		(placement
			(enabled no)
			(sheetname "")
		)
		(fill yes
			(thermal_gap 0.5)
			(thermal_bridge_width 0.5)
			(island_removal_mode 0)
		)
		(polygon
			(pts
				(arc
					(start 95.645986 -235.574332)
					(mid 95.016066 -235.574332)
					(end 95.645986 -235.574332)
				)
			)
		)
	)
	(zone
		(layers "B.Cu" "In4.Cu" "In6.Cu" "In11.Cu" "In13.Cu" "In15.Cu")
		(hatch none 0.5)
		(connect_pads
			(clearance 0)
		)
		(min_thickness 0.25)
		(keepout
			(tracks not_allowed)
			(vias allowed)
			(pads allowed)
			(copperpour not_allowed)
			(footprints allowed)
		)
		(placement
			(enabled no)
			(sheetname "")
		)
		(fill yes
			(thermal_gap 0.5)
			(thermal_bridge_width 0.5)
			(island_removal_mode 0)
		)
		(polygon
			(pts
				(arc
					(start 130.249676 -289.47618)
					(mid 129.619756 -289.47618)
					(end 130.249676 -289.47618)
				)
			)
		)
	)
	(zone
		(layers "B.Cu" "In4.Cu" "In6.Cu" "In11.Cu" "In13.Cu" "In15.Cu")
		(hatch none 0.5)
		(connect_pads
			(clearance 0)
		)
		(min_thickness 0.25)
		(keepout
			(tracks not_allowed)
			(vias allowed)
			(pads allowed)
			(copperpour not_allowed)
			(footprints allowed)
		)
		(placement
			(enabled no)
			(sheetname "")
		)
		(fill yes
			(thermal_gap 0.5)
			(thermal_bridge_width 0.5)
			(island_removal_mode 0)
		)
		(polygon
			(pts
				(arc
					(start 128.369822 -286.23641)
					(mid 127.739902 -286.23641)
					(end 128.369822 -286.23641)
				)
			)
		)
	)
	(zone
		(layers "B.Cu" "In4.Cu" "In6.Cu" "In11.Cu" "In13.Cu" "In15.Cu")
		(hatch none 0.5)
		(connect_pads
			(clearance 0)
		)
		(min_thickness 0.25)
		(keepout
			(tracks not_allowed)
			(vias allowed)
			(pads allowed)
			(copperpour not_allowed)
			(footprints allowed)
		)
		(placement
			(enabled no)
			(sheetname "")
		)
		(fill yes
			(thermal_gap 0.5)
			(thermal_bridge_width 0.5)
			(island_removal_mode 0)
		)
		(polygon
			(pts
				(arc
					(start 128.839722 -275.706332)
					(mid 128.209802 -275.706332)
					(end 128.839722 -275.706332)
				)
			)
		)
	)
	(zone
		(layers "B.Cu" "In4.Cu" "In6.Cu" "In11.Cu" "In13.Cu" "In15.Cu")
		(hatch none 0.5)
		(connect_pads
			(clearance 0)
		)
		(min_thickness 0.25)
		(keepout
			(tracks not_allowed)
			(vias allowed)
			(pads allowed)
			(copperpour not_allowed)
			(footprints allowed)
		)
		(placement
			(enabled no)
			(sheetname "")
		)
		(fill yes
			(thermal_gap 0.5)
			(thermal_bridge_width 0.5)
			(island_removal_mode 0)
		)
		(polygon
			(pts
				(arc
					(start 292.614096 -212.635084)
					(mid 291.946076 -212.635084)
					(end 292.614096 -212.635084)
				)
			)
		)
	)
	(zone
		(layers "B.Cu" "In4.Cu" "In6.Cu" "In11.Cu" "In13.Cu" "In15.Cu")
		(hatch none 0.5)
		(connect_pads
			(clearance 0)
		)
		(min_thickness 0.25)
		(keepout
			(tracks not_allowed)
			(vias allowed)
			(pads allowed)
			(copperpour not_allowed)
			(footprints allowed)
		)
		(placement
			(enabled no)
			(sheetname "")
		)
		(fill yes
			(thermal_gap 0.5)
			(thermal_bridge_width 0.5)
			(island_removal_mode 0)
		)
		(polygon
			(pts
				(arc
					(start 100.815902 -226.66452)
					(mid 100.185982 -226.66452)
					(end 100.815902 -226.66452)
				)
			)
		)
	)
	(zone
		(layers "B.Cu" "In4.Cu" "In6.Cu" "In11.Cu" "In13.Cu" "In15.Cu")
		(hatch none 0.5)
		(connect_pads
			(clearance 0)
		)
		(min_thickness 0.25)
		(keepout
			(tracks not_allowed)
			(vias allowed)
			(pads allowed)
			(copperpour not_allowed)
			(footprints allowed)
		)
		(placement
			(enabled no)
			(sheetname "")
		)
		(fill yes
			(thermal_gap 0.5)
			(thermal_bridge_width 0.5)
			(island_removal_mode 0)
		)
		(polygon
			(pts
				(arc
					(start 342.476074 -273.27606)
					(mid 341.846154 -273.27606)
					(end 342.476074 -273.27606)
				)
			)
		)
	)
	(zone
		(layers "B.Cu" "In4.Cu" "In6.Cu" "In11.Cu" "In13.Cu" "In15.Cu")
		(hatch none 0.5)
		(connect_pads
			(clearance 0)
		)
		(min_thickness 0.25)
		(keepout
			(tracks not_allowed)
			(vias allowed)
			(pads allowed)
			(copperpour not_allowed)
			(footprints allowed)
		)
		(placement
			(enabled no)
			(sheetname "")
		)
		(fill yes
			(thermal_gap 0.5)
			(thermal_bridge_width 0.5)
			(island_removal_mode 0)
		)
		(polygon
			(pts
				(arc
					(start 377.719844 -290.285932)
					(mid 377.089924 -290.285932)
					(end 377.719844 -290.285932)
				)
			)
		)
	)
	(zone
		(layers "B.Cu" "In4.Cu" "In6.Cu" "In11.Cu" "In13.Cu" "In15.Cu")
		(hatch none 0.5)
		(connect_pads
			(clearance 0)
		)
		(min_thickness 0.25)
		(keepout
			(tracks not_allowed)
			(vias allowed)
			(pads allowed)
			(copperpour not_allowed)
			(footprints allowed)
		)
		(placement
			(enabled no)
			(sheetname "")
		)
		(fill yes
			(thermal_gap 0.5)
			(thermal_bridge_width 0.5)
			(island_removal_mode 0)
		)
		(polygon
			(pts
				(arc
					(start 343.586054 -240.434114)
					(mid 342.956134 -240.434114)
					(end 343.586054 -240.434114)
				)
			)
		)
	)
	(zone
		(layers "B.Cu" "In4.Cu" "In6.Cu" "In11.Cu" "In13.Cu" "In15.Cu")
		(hatch none 0.5)
		(connect_pads
			(clearance 0)
		)
		(min_thickness 0.25)
		(keepout
			(tracks not_allowed)
			(vias allowed)
			(pads allowed)
			(copperpour not_allowed)
			(footprints allowed)
		)
		(placement
			(enabled no)
			(sheetname "")
		)
		(fill yes
			(thermal_gap 0.5)
			(thermal_bridge_width 0.5)
			(island_removal_mode 0)
		)
		(polygon
			(pts
				(arc
					(start 183.950102 -294.235378)
					(mid 183.282082 -294.235378)
					(end 183.950102 -294.235378)
				)
			)
		)
	)
	(zone
		(layers "B.Cu" "In4.Cu" "In6.Cu" "In11.Cu" "In13.Cu" "In15.Cu")
		(hatch none 0.5)
		(connect_pads
			(clearance 0)
		)
		(min_thickness 0.25)
		(keepout
			(tracks not_allowed)
			(vias allowed)
			(pads allowed)
			(copperpour not_allowed)
			(footprints allowed)
		)
		(placement
			(enabled no)
			(sheetname "")
		)
		(fill yes
			(thermal_gap 0.5)
			(thermal_bridge_width 0.5)
			(island_removal_mode 0)
		)
		(polygon
			(pts
				(arc
					(start 376.77979 -274.086066)
					(mid 376.14987 -274.086066)
					(end 376.77979 -274.086066)
				)
			)
		)
	)
	(zone
		(layers "B.Cu" "In4.Cu" "In6.Cu" "In11.Cu" "In13.Cu" "In15.Cu")
		(hatch none 0.5)
		(connect_pads
			(clearance 0)
		)
		(min_thickness 0.25)
		(keepout
			(tracks not_allowed)
			(vias allowed)
			(pads allowed)
			(copperpour not_allowed)
			(footprints allowed)
		)
		(placement
			(enabled no)
			(sheetname "")
		)
		(fill yes
			(thermal_gap 0.5)
			(thermal_bridge_width 0.5)
			(island_removal_mode 0)
		)
		(polygon
			(pts
				(arc
					(start 427.790102 -241.53495)
					(mid 427.122082 -241.53495)
					(end 427.790102 -241.53495)
				)
			)
		)
	)
	(zone
		(layers "B.Cu" "In4.Cu" "In6.Cu" "In11.Cu" "In13.Cu" "In15.Cu")
		(hatch none 0.5)
		(connect_pads
			(clearance 0)
		)
		(min_thickness 0.25)
		(keepout
			(tracks not_allowed)
			(vias allowed)
			(pads allowed)
			(copperpour not_allowed)
			(footprints allowed)
		)
		(placement
			(enabled no)
			(sheetname "")
		)
		(fill yes
			(thermal_gap 0.5)
			(thermal_bridge_width 0.5)
			(island_removal_mode 0)
		)
		(polygon
			(pts
				(arc
					(start 128.369822 -292.716204)
					(mid 127.739902 -292.716204)
					(end 128.369822 -292.716204)
				)
			)
		)
	)
	(zone
		(layers "B.Cu" "In4.Cu" "In6.Cu" "In11.Cu" "In13.Cu" "In15.Cu")
		(hatch none 0.5)
		(connect_pads
			(clearance 0)
		)
		(min_thickness 0.25)
		(keepout
			(tracks not_allowed)
			(vias allowed)
			(pads allowed)
			(copperpour not_allowed)
			(footprints allowed)
		)
		(placement
			(enabled no)
			(sheetname "")
		)
		(fill yes
			(thermal_gap 0.5)
			(thermal_bridge_width 0.5)
			(island_removal_mode 0)
		)
		(polygon
			(pts
				(arc
					(start 183.950102 -313.78525)
					(mid 183.282082 -313.78525)
					(end 183.950102 -313.78525)
				)
			)
		)
	)
	(zone
		(layers "B.Cu" "In4.Cu" "In6.Cu" "In11.Cu" "In13.Cu" "In15.Cu")
		(hatch none 0.5)
		(connect_pads
			(clearance 0)
		)
		(min_thickness 0.25)
		(keepout
			(tracks not_allowed)
			(vias allowed)
			(pads allowed)
			(copperpour not_allowed)
			(footprints allowed)
		)
		(placement
			(enabled no)
			(sheetname "")
		)
		(fill yes
			(thermal_gap 0.5)
			(thermal_bridge_width 0.5)
			(island_removal_mode 0)
		)
		(polygon
			(pts
				(arc
					(start 130.249676 -276.516338)
					(mid 129.619756 -276.516338)
					(end 130.249676 -276.516338)
				)
			)
		)
	)
	(zone
		(layers "B.Cu" "In4.Cu" "In6.Cu" "In11.Cu" "In13.Cu" "In15.Cu")
		(hatch none 0.5)
		(connect_pads
			(clearance 0)
		)
		(min_thickness 0.25)
		(keepout
			(tracks not_allowed)
			(vias allowed)
			(pads allowed)
			(copperpour not_allowed)
			(footprints allowed)
		)
		(placement
			(enabled no)
			(sheetname "")
		)
		(fill yes
			(thermal_gap 0.5)
			(thermal_bridge_width 0.5)
			(island_removal_mode 0)
		)
		(polygon
			(pts
				(arc
					(start 179.850034 -285.735268)
					(mid 179.182014 -285.735268)
					(end 179.850034 -285.735268)
				)
			)
		)
	)
	(zone
		(layers "B.Cu" "In4.Cu" "In6.Cu" "In11.Cu" "In13.Cu" "In15.Cu")
		(hatch none 0.5)
		(connect_pads
			(clearance 0)
		)
		(min_thickness 0.25)
		(keepout
			(tracks not_allowed)
			(vias allowed)
			(pads allowed)
			(copperpour not_allowed)
			(footprints allowed)
		)
		(placement
			(enabled no)
			(sheetname "")
		)
		(fill yes
			(thermal_gap 0.5)
			(thermal_bridge_width 0.5)
			(island_removal_mode 0)
		)
		(polygon
			(pts
				(arc
					(start 292.614096 -292.535102)
					(mid 291.946076 -292.535102)
					(end 292.614096 -292.535102)
				)
			)
		)
	)
	(zone
		(layers "B.Cu" "In4.Cu" "In6.Cu" "In11.Cu" "In13.Cu" "In15.Cu")
		(hatch none 0.5)
		(connect_pads
			(clearance 0)
		)
		(min_thickness 0.25)
		(keepout
			(tracks not_allowed)
			(vias allowed)
			(pads allowed)
			(copperpour not_allowed)
			(footprints allowed)
		)
		(placement
			(enabled no)
			(sheetname "")
		)
		(fill yes
			(thermal_gap 0.5)
			(thermal_bridge_width 0.5)
			(island_removal_mode 0)
		)
		(polygon
			(pts
				(arc
					(start 288.514028 -222.834962)
					(mid 287.846008 -222.834962)
					(end 288.514028 -222.834962)
				)
			)
		)
	)
	(zone
		(layers "B.Cu" "In4.Cu" "In6.Cu" "In11.Cu" "In13.Cu" "In15.Cu")
		(hatch none 0.5)
		(connect_pads
			(clearance 0)
		)
		(min_thickness 0.25)
		(keepout
			(tracks not_allowed)
			(vias allowed)
			(pads allowed)
			(copperpour not_allowed)
			(footprints allowed)
		)
		(placement
			(enabled no)
			(sheetname "")
		)
		(fill yes
			(thermal_gap 0.5)
			(thermal_bridge_width 0.5)
			(island_removal_mode 0)
		)
		(polygon
			(pts
				(arc
					(start 342.945974 -277.32609)
					(mid 342.316054 -277.32609)
					(end 342.945974 -277.32609)
				)
			)
		)
	)
	(zone
		(layers "B.Cu" "In4.Cu" "In6.Cu" "In11.Cu" "In13.Cu" "In15.Cu")
		(hatch none 0.5)
		(connect_pads
			(clearance 0)
		)
		(min_thickness 0.25)
		(keepout
			(tracks not_allowed)
			(vias allowed)
			(pads allowed)
			(copperpour not_allowed)
			(footprints allowed)
		)
		(placement
			(enabled no)
			(sheetname "")
		)
		(fill yes
			(thermal_gap 0.5)
			(thermal_bridge_width 0.5)
			(island_removal_mode 0)
		)
		(polygon
			(pts
				(arc
					(start 431.89017 -275.535136)
					(mid 431.22215 -275.535136)
					(end 431.89017 -275.535136)
				)
			)
		)
	)
	(zone
		(layers "B.Cu" "In4.Cu" "In6.Cu" "In11.Cu" "In13.Cu" "In15.Cu")
		(hatch none 0.5)
		(connect_pads
			(clearance 0)
		)
		(min_thickness 0.25)
		(keepout
			(tracks not_allowed)
			(vias allowed)
			(pads allowed)
			(copperpour not_allowed)
			(footprints allowed)
		)
		(placement
			(enabled no)
			(sheetname "")
		)
		(fill yes
			(thermal_gap 0.5)
			(thermal_bridge_width 0.5)
			(island_removal_mode 0)
		)
		(polygon
			(pts
				(arc
					(start 342.476074 -289.475926)
					(mid 341.846154 -289.475926)
					(end 342.476074 -289.475926)
				)
			)
		)
	)
	(zone
		(layers "B.Cu" "In4.Cu" "In6.Cu" "In11.Cu" "In13.Cu" "In15.Cu")
		(hatch none 0.5)
		(connect_pads
			(clearance 0)
		)
		(min_thickness 0.25)
		(keepout
			(tracks not_allowed)
			(vias allowed)
			(pads allowed)
			(copperpour not_allowed)
			(footprints allowed)
		)
		(placement
			(enabled no)
			(sheetname "")
		)
		(fill yes
			(thermal_gap 0.5)
			(thermal_bridge_width 0.5)
			(island_removal_mode 0)
		)
		(polygon
			(pts
				(arc
					(start 129.779776 -288.666174)
					(mid 129.149856 -288.666174)
					(end 129.779776 -288.666174)
				)
			)
		)
	)
	(zone
		(layers "B.Cu" "In4.Cu" "In6.Cu" "In11.Cu" "In13.Cu" "In15.Cu")
		(hatch none 0.5)
		(connect_pads
			(clearance 0)
		)
		(min_thickness 0.25)
		(keepout
			(tracks not_allowed)
			(vias allowed)
			(pads allowed)
			(copperpour not_allowed)
			(footprints allowed)
		)
		(placement
			(enabled no)
			(sheetname "")
		)
		(fill yes
			(thermal_gap 0.5)
			(thermal_bridge_width 0.5)
			(island_removal_mode 0)
		)
		(polygon
			(pts
				(arc
					(start 44.674028 -234.73537)
					(mid 44.006008 -234.73537)
					(end 44.674028 -234.73537)
				)
			)
		)
	)
	(zone
		(layers "B.Cu" "In4.Cu" "In6.Cu" "In11.Cu" "In13.Cu" "In15.Cu")
		(hatch none 0.5)
		(connect_pads
			(clearance 0)
		)
		(min_thickness 0.25)
		(keepout
			(tracks not_allowed)
			(vias allowed)
			(pads allowed)
			(copperpour not_allowed)
			(footprints allowed)
		)
		(placement
			(enabled no)
			(sheetname "")
		)
		(fill yes
			(thermal_gap 0.5)
			(thermal_bridge_width 0.5)
			(island_removal_mode 0)
		)
		(polygon
			(pts
				(arc
					(start 94.705932 -227.474526)
					(mid 94.076012 -227.474526)
					(end 94.705932 -227.474526)
				)
			)
		)
	)
	(zone
		(layers "B.Cu" "In4.Cu" "In6.Cu" "In11.Cu" "In13.Cu" "In15.Cu")
		(hatch none 0.5)
		(connect_pads
			(clearance 0)
		)
		(min_thickness 0.25)
		(keepout
			(tracks not_allowed)
			(vias allowed)
			(pads allowed)
			(copperpour not_allowed)
			(footprints allowed)
		)
		(placement
			(enabled no)
			(sheetname "")
		)
		(fill yes
			(thermal_gap 0.5)
			(thermal_bridge_width 0.5)
			(island_removal_mode 0)
		)
		(polygon
			(pts
				(arc
					(start 129.779776 -282.18638)
					(mid 129.149856 -282.18638)
					(end 129.779776 -282.18638)
				)
			)
		)
	)
	(zone
		(layers "B.Cu" "In4.Cu" "In6.Cu" "In11.Cu" "In13.Cu" "In15.Cu")
		(hatch none 0.5)
		(connect_pads
			(clearance 0)
		)
		(min_thickness 0.25)
		(keepout
			(tracks not_allowed)
			(vias allowed)
			(pads allowed)
			(copperpour not_allowed)
			(footprints allowed)
		)
		(placement
			(enabled no)
			(sheetname "")
		)
		(fill yes
			(thermal_gap 0.5)
			(thermal_bridge_width 0.5)
			(island_removal_mode 0)
		)
		(polygon
			(pts
				(arc
					(start 129.479802 -256.634488)
					(mid 128.849882 -256.634488)
					(end 129.479802 -256.634488)
				)
			)
		)
	)
	(zone
		(layers "B.Cu" "In4.Cu" "In6.Cu" "In11.Cu" "In13.Cu" "In15.Cu")
		(hatch none 0.5)
		(connect_pads
			(clearance 0)
		)
		(min_thickness 0.25)
		(keepout
			(tracks not_allowed)
			(vias allowed)
			(pads allowed)
			(copperpour not_allowed)
			(footprints allowed)
		)
		(placement
			(enabled no)
			(sheetname "")
		)
		(fill yes
			(thermal_gap 0.5)
			(thermal_bridge_width 0.5)
			(island_removal_mode 0)
		)
		(polygon
			(pts
				(arc
					(start 292.614096 -301.885096)
					(mid 291.946076 -301.885096)
					(end 292.614096 -301.885096)
				)
			)
		)
	)
	(zone
		(layers "B.Cu" "In4.Cu" "In6.Cu" "In11.Cu" "In13.Cu" "In15.Cu")
		(hatch none 0.5)
		(connect_pads
			(clearance 0)
		)
		(min_thickness 0.25)
		(keepout
			(tracks not_allowed)
			(vias allowed)
			(pads allowed)
			(copperpour not_allowed)
			(footprints allowed)
		)
		(placement
			(enabled no)
			(sheetname "")
		)
		(fill yes
			(thermal_gap 0.5)
			(thermal_bridge_width 0.5)
			(island_removal_mode 0)
		)
		(polygon
			(pts
				(arc
					(start 179.850034 -261.935214)
					(mid 179.182014 -261.935214)
					(end 179.850034 -261.935214)
				)
			)
		)
	)
	(zone
		(layers "B.Cu" "In4.Cu" "In6.Cu" "In11.Cu" "In13.Cu" "In15.Cu")
		(hatch none 0.5)
		(connect_pads
			(clearance 0)
		)
		(min_thickness 0.25)
		(keepout
			(tracks not_allowed)
			(vias allowed)
			(pads allowed)
			(copperpour not_allowed)
			(footprints allowed)
		)
		(placement
			(enabled no)
			(sheetname "")
		)
		(fill yes
			(thermal_gap 0.5)
			(thermal_bridge_width 0.5)
			(island_removal_mode 0)
		)
		(polygon
			(pts
				(arc
					(start 292.614096 -262.785098)
					(mid 291.946076 -262.785098)
					(end 292.614096 -262.785098)
				)
			)
		)
	)
	(zone
		(layers "B.Cu" "In4.Cu" "In6.Cu" "In11.Cu" "In13.Cu" "In15.Cu")
		(hatch none 0.5)
		(connect_pads
			(clearance 0)
		)
		(min_thickness 0.25)
		(keepout
			(tracks not_allowed)
			(vias allowed)
			(pads allowed)
			(copperpour not_allowed)
			(footprints allowed)
		)
		(placement
			(enabled no)
			(sheetname "")
		)
		(fill yes
			(thermal_gap 0.5)
			(thermal_bridge_width 0.5)
			(island_removal_mode 0)
		)
		(polygon
			(pts
				(arc
					(start 95.94596 -265.98626)
					(mid 95.31604 -265.98626)
					(end 95.94596 -265.98626)
				)
			)
		)
	)
	(zone
		(layers "B.Cu" "In4.Cu" "In6.Cu" "In11.Cu" "In13.Cu" "In15.Cu")
		(hatch none 0.5)
		(connect_pads
			(clearance 0)
		)
		(min_thickness 0.25)
		(keepout
			(tracks not_allowed)
			(vias allowed)
			(pads allowed)
			(copperpour not_allowed)
			(footprints allowed)
		)
		(placement
			(enabled no)
			(sheetname "")
		)
		(fill yes
			(thermal_gap 0.5)
			(thermal_bridge_width 0.5)
			(island_removal_mode 0)
		)
		(polygon
			(pts
				(arc
					(start 378.189744 -273.27606)
					(mid 377.559824 -273.27606)
					(end 378.189744 -273.27606)
				)
			)
		)
	)
	(zone
		(layers "B.Cu" "In4.Cu" "In6.Cu" "In11.Cu" "In13.Cu" "In15.Cu")
		(hatch none 0.5)
		(connect_pads
			(clearance 0)
		)
		(min_thickness 0.25)
		(keepout
			(tracks not_allowed)
			(vias allowed)
			(pads allowed)
			(copperpour not_allowed)
			(footprints allowed)
		)
		(placement
			(enabled no)
			(sheetname "")
		)
		(fill yes
			(thermal_gap 0.5)
			(thermal_bridge_width 0.5)
			(island_removal_mode 0)
		)
		(polygon
			(pts
				(arc
					(start 377.41987 -242.054126)
					(mid 376.78995 -242.054126)
					(end 377.41987 -242.054126)
				)
			)
		)
	)
	(zone
		(layers "B.Cu" "In4.Cu" "In6.Cu" "In11.Cu" "In13.Cu" "In15.Cu")
		(hatch none 0.5)
		(connect_pads
			(clearance 0)
		)
		(min_thickness 0.25)
		(keepout
			(tracks not_allowed)
			(vias allowed)
			(pads allowed)
			(copperpour not_allowed)
			(footprints allowed)
		)
		(placement
			(enabled no)
			(sheetname "")
		)
		(fill yes
			(thermal_gap 0.5)
			(thermal_bridge_width 0.5)
			(island_removal_mode 0)
		)
		(polygon
			(pts
				(arc
					(start 129.479802 -255.014476)
					(mid 128.849882 -255.014476)
					(end 129.479802 -255.014476)
				)
			)
		)
	)
	(zone
		(layers "B.Cu" "In4.Cu" "In6.Cu" "In11.Cu" "In13.Cu" "In15.Cu")
		(hatch none 0.5)
		(connect_pads
			(clearance 0)
		)
		(min_thickness 0.25)
		(keepout
			(tracks not_allowed)
			(vias allowed)
			(pads allowed)
			(copperpour not_allowed)
			(footprints allowed)
		)
		(placement
			(enabled no)
			(sheetname "")
		)
		(fill yes
			(thermal_gap 0.5)
			(thermal_bridge_width 0.5)
			(island_removal_mode 0)
		)
		(polygon
			(pts
				(arc
					(start 130.249676 -271.656302)
					(mid 129.619756 -271.656302)
					(end 130.249676 -271.656302)
				)
			)
		)
	)
	(zone
		(layers "B.Cu" "In4.Cu" "In6.Cu" "In11.Cu" "In13.Cu" "In15.Cu")
		(hatch none 0.5)
		(connect_pads
			(clearance 0)
		)
		(min_thickness 0.25)
		(keepout
			(tracks not_allowed)
			(vias allowed)
			(pads allowed)
			(copperpour not_allowed)
			(footprints allowed)
		)
		(placement
			(enabled no)
			(sheetname "")
		)
		(fill yes
			(thermal_gap 0.5)
			(thermal_bridge_width 0.5)
			(island_removal_mode 0)
		)
		(polygon
			(pts
				(arc
					(start 345.295982 -294.335962)
					(mid 344.666062 -294.335962)
					(end 345.295982 -294.335962)
				)
			)
		)
	)
	(zone
		(layers "B.Cu" "In4.Cu" "In6.Cu" "In11.Cu" "In13.Cu" "In15.Cu")
		(hatch none 0.5)
		(connect_pads
			(clearance 0)
		)
		(min_thickness 0.25)
		(keepout
			(tracks not_allowed)
			(vias allowed)
			(pads allowed)
			(copperpour not_allowed)
			(footprints allowed)
		)
		(placement
			(enabled no)
			(sheetname "")
		)
		(fill yes
			(thermal_gap 0.5)
			(thermal_bridge_width 0.5)
			(island_removal_mode 0)
		)
		(polygon
			(pts
				(arc
					(start 40.57396 -204.135228)
					(mid 39.90594 -204.135228)
					(end 40.57396 -204.135228)
				)
			)
		)
	)
	(zone
		(layers "B.Cu" "In4.Cu" "In6.Cu" "In11.Cu" "In13.Cu" "In15.Cu")
		(hatch none 0.5)
		(connect_pads
			(clearance 0)
		)
		(min_thickness 0.25)
		(keepout
			(tracks not_allowed)
			(vias allowed)
			(pads allowed)
			(copperpour not_allowed)
			(footprints allowed)
		)
		(placement
			(enabled no)
			(sheetname "")
		)
		(fill yes
			(thermal_gap 0.5)
			(thermal_bridge_width 0.5)
			(island_removal_mode 0)
		)
		(polygon
			(pts
				(arc
					(start 183.950102 -279.785318)
					(mid 183.282082 -279.785318)
					(end 183.950102 -279.785318)
				)
			)
		)
	)
	(zone
		(layers "B.Cu" "In4.Cu" "In6.Cu" "In11.Cu" "In13.Cu" "In15.Cu")
		(hatch none 0.5)
		(connect_pads
			(clearance 0)
		)
		(min_thickness 0.25)
		(keepout
			(tracks not_allowed)
			(vias allowed)
			(pads allowed)
			(copperpour not_allowed)
			(footprints allowed)
		)
		(placement
			(enabled no)
			(sheetname "")
		)
		(fill yes
			(thermal_gap 0.5)
			(thermal_bridge_width 0.5)
			(island_removal_mode 0)
		)
		(polygon
			(pts
				(arc
					(start 343.886028 -290.285932)
					(mid 343.256108 -290.285932)
					(end 343.886028 -290.285932)
				)
			)
		)
	)
	(zone
		(layers "B.Cu" "In4.Cu" "In6.Cu" "In11.Cu" "In13.Cu" "In15.Cu")
		(hatch none 0.5)
		(connect_pads
			(clearance 0)
		)
		(min_thickness 0.25)
		(keepout
			(tracks not_allowed)
			(vias allowed)
			(pads allowed)
			(copperpour not_allowed)
			(footprints allowed)
		)
		(placement
			(enabled no)
			(sheetname "")
		)
		(fill yes
			(thermal_gap 0.5)
			(thermal_bridge_width 0.5)
			(island_removal_mode 0)
		)
		(polygon
			(pts
				(arc
					(start 378.189744 -276.516084)
					(mid 377.559824 -276.516084)
					(end 378.189744 -276.516084)
				)
			)
		)
	)
	(zone
		(layers "B.Cu" "In4.Cu" "In6.Cu" "In11.Cu" "In13.Cu" "In15.Cu")
		(hatch none 0.5)
		(connect_pads
			(clearance 0)
		)
		(min_thickness 0.25)
		(keepout
			(tracks not_allowed)
			(vias allowed)
			(pads allowed)
			(copperpour not_allowed)
			(footprints allowed)
		)
		(placement
			(enabled no)
			(sheetname "")
		)
		(fill yes
			(thermal_gap 0.5)
			(thermal_bridge_width 0.5)
			(island_removal_mode 0)
		)
		(polygon
			(pts
				(arc
					(start 427.790102 -237.285022)
					(mid 427.122082 -237.285022)
					(end 427.790102 -237.285022)
				)
			)
		)
	)
	(zone
		(layers "B.Cu" "In4.Cu" "In6.Cu" "In11.Cu" "In13.Cu" "In15.Cu")
		(hatch none 0.5)
		(connect_pads
			(clearance 0)
		)
		(min_thickness 0.25)
		(keepout
			(tracks not_allowed)
			(vias allowed)
			(pads allowed)
			(copperpour not_allowed)
			(footprints allowed)
		)
		(placement
			(enabled no)
			(sheetname "")
		)
		(fill yes
			(thermal_gap 0.5)
			(thermal_bridge_width 0.5)
			(island_removal_mode 0)
		)
		(polygon
			(pts
				(arc
					(start 101.755956 -226.66452)
					(mid 101.126036 -226.66452)
					(end 101.755956 -226.66452)
				)
			)
		)
	)
	(zone
		(layers "B.Cu" "In4.Cu" "In6.Cu" "In11.Cu" "In13.Cu" "In15.Cu")
		(hatch none 0.5)
		(connect_pads
			(clearance 0)
		)
		(min_thickness 0.25)
		(keepout
			(tracks not_allowed)
			(vias allowed)
			(pads allowed)
			(copperpour not_allowed)
			(footprints allowed)
		)
		(placement
			(enabled no)
			(sheetname "")
		)
		(fill yes
			(thermal_gap 0.5)
			(thermal_bridge_width 0.5)
			(island_removal_mode 0)
		)
		(polygon
			(pts
				(arc
					(start 96.115886 -244.484398)
					(mid 95.485966 -244.484398)
					(end 96.115886 -244.484398)
				)
			)
		)
	)
	(zone
		(layers "B.Cu" "In4.Cu" "In6.Cu" "In11.Cu" "In13.Cu" "In15.Cu")
		(hatch none 0.5)
		(connect_pads
			(clearance 0)
		)
		(min_thickness 0.25)
		(keepout
			(tracks not_allowed)
			(vias allowed)
			(pads allowed)
			(copperpour not_allowed)
			(footprints allowed)
		)
		(placement
			(enabled no)
			(sheetname "")
		)
		(fill yes
			(thermal_gap 0.5)
			(thermal_bridge_width 0.5)
			(island_removal_mode 0)
		)
		(polygon
			(pts
				(arc
					(start 349.056198 -294.335962)
					(mid 348.426278 -294.335962)
					(end 349.056198 -294.335962)
				)
			)
		)
	)
	(zone
		(layers "B.Cu" "In4.Cu" "In6.Cu" "In11.Cu" "In13.Cu" "In15.Cu")
		(hatch none 0.5)
		(connect_pads
			(clearance 0)
		)
		(min_thickness 0.25)
		(keepout
			(tracks not_allowed)
			(vias allowed)
			(pads allowed)
			(copperpour not_allowed)
			(footprints allowed)
		)
		(placement
			(enabled no)
			(sheetname "")
		)
		(fill yes
			(thermal_gap 0.5)
			(thermal_bridge_width 0.5)
			(island_removal_mode 0)
		)
		(polygon
			(pts
				(arc
					(start 95.94596 -278.946356)
					(mid 95.31604 -278.946356)
					(end 95.94596 -278.946356)
				)
			)
		)
	)
	(zone
		(layers "B.Cu" "In4.Cu" "In6.Cu" "In11.Cu" "In13.Cu" "In15.Cu")
		(hatch none 0.5)
		(connect_pads
			(clearance 0)
		)
		(min_thickness 0.25)
		(keepout
			(tracks not_allowed)
			(vias allowed)
			(pads allowed)
			(copperpour not_allowed)
			(footprints allowed)
		)
		(placement
			(enabled no)
			(sheetname "")
		)
		(fill yes
			(thermal_gap 0.5)
			(thermal_bridge_width 0.5)
			(island_removal_mode 0)
		)
		(polygon
			(pts
				(arc
					(start 351.876106 -292.71595)
					(mid 351.246186 -292.71595)
					(end 351.876106 -292.71595)
				)
			)
		)
	)
	(zone
		(layers "B.Cu" "In4.Cu" "In6.Cu" "In11.Cu" "In13.Cu" "In15.Cu")
		(hatch none 0.5)
		(connect_pads
			(clearance 0)
		)
		(min_thickness 0.25)
		(keepout
			(tracks not_allowed)
			(vias allowed)
			(pads allowed)
			(copperpour not_allowed)
			(footprints allowed)
		)
		(placement
			(enabled no)
			(sheetname "")
		)
		(fill yes
			(thermal_gap 0.5)
			(thermal_bridge_width 0.5)
			(island_removal_mode 0)
		)
		(polygon
			(pts
				(arc
					(start 292.614096 -295.085008)
					(mid 291.946076 -295.085008)
					(end 292.614096 -295.085008)
				)
			)
		)
	)
	(zone
		(layers "B.Cu" "In4.Cu" "In6.Cu" "In11.Cu" "In13.Cu" "In15.Cu")
		(hatch none 0.5)
		(connect_pads
			(clearance 0)
		)
		(min_thickness 0.25)
		(keepout
			(tracks not_allowed)
			(vias allowed)
			(pads allowed)
			(copperpour not_allowed)
			(footprints allowed)
		)
		(placement
			(enabled no)
			(sheetname "")
		)
		(fill yes
			(thermal_gap 0.5)
			(thermal_bridge_width 0.5)
			(island_removal_mode 0)
		)
		(polygon
			(pts
				(arc
					(start 377.88977 -233.14406)
					(mid 377.25985 -233.14406)
					(end 377.88977 -233.14406)
				)
			)
		)
	)
	(zone
		(layers "B.Cu" "In4.Cu" "In6.Cu" "In11.Cu" "In13.Cu" "In15.Cu")
		(hatch none 0.5)
		(connect_pads
			(clearance 0)
		)
		(min_thickness 0.25)
		(keepout
			(tracks not_allowed)
			(vias allowed)
			(pads allowed)
			(copperpour not_allowed)
			(footprints allowed)
		)
		(placement
			(enabled no)
			(sheetname "")
		)
		(fill yes
			(thermal_gap 0.5)
			(thermal_bridge_width 0.5)
			(island_removal_mode 0)
		)
		(polygon
			(pts
				(arc
					(start 96.416114 -286.23641)
					(mid 95.786194 -286.23641)
					(end 96.416114 -286.23641)
				)
			)
		)
	)
	(zone
		(layers "B.Cu" "In4.Cu" "In6.Cu" "In11.Cu" "In13.Cu" "In15.Cu")
		(hatch none 0.5)
		(connect_pads
			(clearance 0)
		)
		(min_thickness 0.25)
		(keepout
			(tracks not_allowed)
			(vias allowed)
			(pads allowed)
			(copperpour not_allowed)
			(footprints allowed)
		)
		(placement
			(enabled no)
			(sheetname "")
		)
		(fill yes
			(thermal_gap 0.5)
			(thermal_bridge_width 0.5)
			(island_removal_mode 0)
		)
		(polygon
			(pts
				(arc
					(start 129.949702 -247.724422)
					(mid 129.319782 -247.724422)
					(end 129.949702 -247.724422)
				)
			)
		)
	)
	(zone
		(layers "B.Cu" "In4.Cu" "In6.Cu" "In11.Cu" "In13.Cu" "In15.Cu")
		(hatch none 0.5)
		(connect_pads
			(clearance 0)
		)
		(min_thickness 0.25)
		(keepout
			(tracks not_allowed)
			(vias allowed)
			(pads allowed)
			(copperpour not_allowed)
			(footprints allowed)
		)
		(placement
			(enabled no)
			(sheetname "")
		)
		(fill yes
			(thermal_gap 0.5)
			(thermal_bridge_width 0.5)
			(island_removal_mode 0)
		)
		(polygon
			(pts
				(arc
					(start 183.950102 -203.285344)
					(mid 183.282082 -203.285344)
					(end 183.950102 -203.285344)
				)
			)
		)
	)
	(zone
		(layers "B.Cu" "In4.Cu" "In6.Cu" "In11.Cu" "In13.Cu" "In15.Cu")
		(hatch none 0.5)
		(connect_pads
			(clearance 0)
		)
		(min_thickness 0.25)
		(keepout
			(tracks not_allowed)
			(vias allowed)
			(pads allowed)
			(copperpour not_allowed)
			(footprints allowed)
		)
		(placement
			(enabled no)
			(sheetname "")
		)
		(fill yes
			(thermal_gap 0.5)
			(thermal_bridge_width 0.5)
			(island_removal_mode 0)
		)
		(polygon
			(pts
				(arc
					(start 431.89017 -223.6851)
					(mid 431.22215 -223.6851)
					(end 431.89017 -223.6851)
				)
			)
		)
	)
	(zone
		(layers "B.Cu" "In4.Cu" "In6.Cu" "In11.Cu" "In13.Cu" "In15.Cu")
		(hatch none 0.5)
		(connect_pads
			(clearance 0)
		)
		(min_thickness 0.25)
		(keepout
			(tracks not_allowed)
			(vias allowed)
			(pads allowed)
			(copperpour not_allowed)
			(footprints allowed)
		)
		(placement
			(enabled no)
			(sheetname "")
		)
		(fill yes
			(thermal_gap 0.5)
			(thermal_bridge_width 0.5)
			(island_removal_mode 0)
		)
		(polygon
			(pts
				(arc
					(start 292.614096 -208.385156)
					(mid 291.946076 -208.385156)
					(end 292.614096 -208.385156)
				)
			)
		)
	)
	(zone
		(layers "B.Cu" "In4.Cu" "In6.Cu" "In11.Cu" "In13.Cu" "In15.Cu")
		(hatch none 0.5)
		(connect_pads
			(clearance 0)
		)
		(min_thickness 0.25)
		(keepout
			(tracks not_allowed)
			(vias allowed)
			(pads allowed)
			(copperpour not_allowed)
			(footprints allowed)
		)
		(placement
			(enabled no)
			(sheetname "")
		)
		(fill yes
			(thermal_gap 0.5)
			(thermal_bridge_width 0.5)
			(island_removal_mode 0)
		)
		(polygon
			(pts
				(arc
					(start 183.950102 -236.435392)
					(mid 183.282082 -236.435392)
					(end 183.950102 -236.435392)
				)
			)
		)
	)
	(zone
		(layers "B.Cu" "In4.Cu" "In6.Cu" "In11.Cu" "In13.Cu" "In15.Cu")
		(hatch none 0.5)
		(connect_pads
			(clearance 0)
		)
		(min_thickness 0.25)
		(keepout
			(tracks not_allowed)
			(vias allowed)
			(pads allowed)
			(copperpour not_allowed)
			(footprints allowed)
		)
		(placement
			(enabled no)
			(sheetname "")
		)
		(fill yes
			(thermal_gap 0.5)
			(thermal_bridge_width 0.5)
			(island_removal_mode 0)
		)
		(polygon
			(pts
				(arc
					(start 179.850034 -312.085228)
					(mid 179.182014 -312.085228)
					(end 179.850034 -312.085228)
				)
			)
		)
	)
	(zone
		(layers "B.Cu" "In4.Cu" "In6.Cu" "In11.Cu" "In13.Cu" "In15.Cu")
		(hatch none 0.5)
		(connect_pads
			(clearance 0)
		)
		(min_thickness 0.25)
		(keepout
			(tracks not_allowed)
			(vias allowed)
			(pads allowed)
			(copperpour not_allowed)
			(footprints allowed)
		)
		(placement
			(enabled no)
			(sheetname "")
		)
		(fill yes
			(thermal_gap 0.5)
			(thermal_bridge_width 0.5)
			(island_removal_mode 0)
		)
		(polygon
			(pts
				(arc
					(start 431.89017 -240.685066)
					(mid 431.22215 -240.685066)
					(end 431.89017 -240.685066)
				)
			)
		)
	)
	(zone
		(layers "B.Cu" "In4.Cu" "In6.Cu" "In11.Cu" "In13.Cu" "In15.Cu")
		(hatch none 0.5)
		(connect_pads
			(clearance 0)
		)
		(min_thickness 0.25)
		(keepout
			(tracks not_allowed)
			(vias allowed)
			(pads allowed)
			(copperpour not_allowed)
			(footprints allowed)
		)
		(placement
			(enabled no)
			(sheetname "")
		)
		(fill yes
			(thermal_gap 0.5)
			(thermal_bridge_width 0.5)
			(island_removal_mode 0)
		)
		(polygon
			(pts
				(arc
					(start 376.30989 -286.236156)
					(mid 375.67997 -286.236156)
					(end 376.30989 -286.236156)
				)
			)
		)
	)
	(zone
		(layers "B.Cu" "In4.Cu" "In6.Cu" "In11.Cu" "In13.Cu" "In15.Cu")
		(hatch none 0.5)
		(connect_pads
			(clearance 0)
		)
		(min_thickness 0.25)
		(keepout
			(tracks not_allowed)
			(vias allowed)
			(pads allowed)
			(copperpour not_allowed)
			(footprints allowed)
		)
		(placement
			(enabled no)
			(sheetname "")
		)
		(fill yes
			(thermal_gap 0.5)
			(thermal_bridge_width 0.5)
			(island_removal_mode 0)
		)
		(polygon
			(pts
				(arc
					(start 40.57396 -244.935248)
					(mid 39.90594 -244.935248)
					(end 40.57396 -244.935248)
				)
			)
		)
	)
	(zone
		(layers "B.Cu" "In4.Cu" "In6.Cu" "In11.Cu" "In13.Cu" "In15.Cu")
		(hatch none 0.5)
		(connect_pads
			(clearance 0)
		)
		(min_thickness 0.25)
		(keepout
			(tracks not_allowed)
			(vias allowed)
			(pads allowed)
			(copperpour not_allowed)
			(footprints allowed)
		)
		(placement
			(enabled no)
			(sheetname "")
		)
		(fill yes
			(thermal_gap 0.5)
			(thermal_bridge_width 0.5)
			(island_removal_mode 0)
		)
		(polygon
			(pts
				(arc
					(start 376.479816 -251.774198)
					(mid 375.849896 -251.774198)
					(end 376.479816 -251.774198)
				)
			)
		)
	)
	(zone
		(layers "B.Cu" "In4.Cu" "In6.Cu" "In11.Cu" "In13.Cu" "In15.Cu")
		(hatch none 0.5)
		(connect_pads
			(clearance 0)
		)
		(min_thickness 0.25)
		(keepout
			(tracks not_allowed)
			(vias allowed)
			(pads allowed)
			(copperpour not_allowed)
			(footprints allowed)
		)
		(placement
			(enabled no)
			(sheetname "")
		)
		(fill yes
			(thermal_gap 0.5)
			(thermal_bridge_width 0.5)
			(island_removal_mode 0)
		)
		(polygon
			(pts
				(arc
					(start 183.950102 -307.8353)
					(mid 183.282082 -307.8353)
					(end 183.950102 -307.8353)
				)
			)
		)
	)
	(zone
		(layers "B.Cu" "In4.Cu" "In6.Cu" "In11.Cu" "In13.Cu" "In15.Cu")
		(hatch none 0.5)
		(connect_pads
			(clearance 0)
		)
		(min_thickness 0.25)
		(keepout
			(tracks not_allowed)
			(vias allowed)
			(pads allowed)
			(copperpour not_allowed)
			(footprints allowed)
		)
		(placement
			(enabled no)
			(sheetname "")
		)
		(fill yes
			(thermal_gap 0.5)
			(thermal_bridge_width 0.5)
			(island_removal_mode 0)
		)
		(polygon
			(pts
				(arc
					(start 95.005906 -270.846296)
					(mid 94.375986 -270.846296)
					(end 95.005906 -270.846296)
				)
			)
		)
	)
	(zone
		(layers "B.Cu" "In4.Cu" "In6.Cu" "In11.Cu" "In13.Cu" "In15.Cu")
		(hatch none 0.5)
		(connect_pads
			(clearance 0)
		)
		(min_thickness 0.25)
		(keepout
			(tracks not_allowed)
			(vias allowed)
			(pads allowed)
			(copperpour not_allowed)
			(footprints allowed)
		)
		(placement
			(enabled no)
			(sheetname "")
		)
		(fill yes
			(thermal_gap 0.5)
			(thermal_bridge_width 0.5)
			(island_removal_mode 0)
		)
		(polygon
			(pts
				(arc
					(start 292.614096 -225.385122)
					(mid 291.946076 -225.385122)
					(end 292.614096 -225.385122)
				)
			)
		)
	)
	(zone
		(layers "B.Cu" "In4.Cu" "In6.Cu" "In11.Cu" "In13.Cu" "In15.Cu")
		(hatch none 0.5)
		(connect_pads
			(clearance 0)
		)
		(min_thickness 0.25)
		(keepout
			(tracks not_allowed)
			(vias allowed)
			(pads allowed)
			(copperpour not_allowed)
			(footprints allowed)
		)
		(placement
			(enabled no)
			(sheetname "")
		)
		(fill yes
			(thermal_gap 0.5)
			(thermal_bridge_width 0.5)
			(island_removal_mode 0)
		)
		(polygon
			(pts
				(arc
					(start 130.249676 -273.276314)
					(mid 129.619756 -273.276314)
					(end 130.249676 -273.276314)
				)
			)
		)
	)
	(zone
		(layers "B.Cu" "In4.Cu" "In6.Cu" "In11.Cu" "In13.Cu" "In15.Cu")
		(hatch none 0.5)
		(connect_pads
			(clearance 0)
		)
		(min_thickness 0.25)
		(keepout
			(tracks not_allowed)
			(vias allowed)
			(pads allowed)
			(copperpour not_allowed)
			(footprints allowed)
		)
		(placement
			(enabled no)
			(sheetname "")
		)
		(fill yes
			(thermal_gap 0.5)
			(thermal_bridge_width 0.5)
			(island_removal_mode 0)
		)
		(polygon
			(pts
				(arc
					(start 376.77979 -275.706078)
					(mid 376.14987 -275.706078)
					(end 376.77979 -275.706078)
				)
			)
		)
	)
	(zone
		(layers "B.Cu" "In4.Cu" "In6.Cu" "In11.Cu" "In13.Cu" "In15.Cu")
		(hatch none 0.5)
		(connect_pads
			(clearance 0)
		)
		(min_thickness 0.25)
		(keepout
			(tracks not_allowed)
			(vias allowed)
			(pads allowed)
			(copperpour not_allowed)
			(footprints allowed)
		)
		(placement
			(enabled no)
			(sheetname "")
		)
		(fill yes
			(thermal_gap 0.5)
			(thermal_bridge_width 0.5)
			(island_removal_mode 0)
		)
		(polygon
			(pts
				(arc
					(start 116.031518 -22.532594)
					(mid 115.363498 -22.532594)
					(end 116.031518 -22.532594)
				)
			)
		)
	)
	(zone
		(layers "B.Cu" "In4.Cu" "In6.Cu" "In11.Cu" "In13.Cu" "In15.Cu")
		(hatch none 0.5)
		(connect_pads
			(clearance 0)
		)
		(min_thickness 0.25)
		(keepout
			(tracks not_allowed)
			(vias allowed)
			(pads allowed)
			(copperpour not_allowed)
			(footprints allowed)
		)
		(placement
			(enabled no)
			(sheetname "")
		)
		(fill yes
			(thermal_gap 0.5)
			(thermal_bridge_width 0.5)
			(island_removal_mode 0)
		)
		(polygon
			(pts
				(arc
					(start 128.069594 -229.90429)
					(mid 127.439674 -229.90429)
					(end 128.069594 -229.90429)
				)
			)
		)
	)
	(zone
		(layers "B.Cu" "In4.Cu" "In6.Cu" "In11.Cu" "In13.Cu" "In15.Cu")
		(hatch none 0.5)
		(connect_pads
			(clearance 0)
		)
		(min_thickness 0.25)
		(keepout
			(tracks not_allowed)
			(vias allowed)
			(pads allowed)
			(copperpour not_allowed)
			(footprints allowed)
		)
		(placement
			(enabled no)
			(sheetname "")
		)
		(fill yes
			(thermal_gap 0.5)
			(thermal_bridge_width 0.5)
			(island_removal_mode 0)
		)
		(polygon
			(pts
				(arc
					(start 102.995984 -294.336216)
					(mid 102.366064 -294.336216)
					(end 102.995984 -294.336216)
				)
			)
		)
	)
	(zone
		(layers "B.Cu" "In4.Cu" "In6.Cu" "In11.Cu" "In13.Cu" "In15.Cu")
		(hatch none 0.5)
		(connect_pads
			(clearance 0)
		)
		(min_thickness 0.25)
		(keepout
			(tracks not_allowed)
			(vias allowed)
			(pads allowed)
			(copperpour not_allowed)
			(footprints allowed)
		)
		(placement
			(enabled no)
			(sheetname "")
		)
		(fill yes
			(thermal_gap 0.5)
			(thermal_bridge_width 0.5)
			(island_removal_mode 0)
		)
		(polygon
			(pts
				(arc
					(start 343.586054 -255.014222)
					(mid 342.956134 -255.014222)
					(end 343.586054 -255.014222)
				)
			)
		)
	)
	(zone
		(layers "B.Cu" "In4.Cu" "In6.Cu" "In11.Cu" "In13.Cu" "In15.Cu")
		(hatch none 0.5)
		(connect_pads
			(clearance 0)
		)
		(min_thickness 0.25)
		(keepout
			(tracks not_allowed)
			(vias allowed)
			(pads allowed)
			(copperpour not_allowed)
			(footprints allowed)
		)
		(placement
			(enabled no)
			(sheetname "")
		)
		(fill yes
			(thermal_gap 0.5)
			(thermal_bridge_width 0.5)
			(island_removal_mode 0)
		)
		(polygon
			(pts
				(arc
					(start 179.850034 -278.935434)
					(mid 179.182014 -278.935434)
					(end 179.850034 -278.935434)
				)
			)
		)
	)
	(zone
		(layers "B.Cu" "In4.Cu" "In6.Cu" "In11.Cu" "In13.Cu" "In15.Cu")
		(hatch none 0.5)
		(connect_pads
			(clearance 0)
		)
		(min_thickness 0.25)
		(keepout
			(tracks not_allowed)
			(vias allowed)
			(pads allowed)
			(copperpour not_allowed)
			(footprints allowed)
		)
		(placement
			(enabled no)
			(sheetname "")
		)
		(fill yes
			(thermal_gap 0.5)
			(thermal_bridge_width 0.5)
			(island_removal_mode 0)
		)
		(polygon
			(pts
				(arc
					(start 179.850034 -222.835216)
					(mid 179.182014 -222.835216)
					(end 179.850034 -222.835216)
				)
			)
		)
	)
	(zone
		(layers "B.Cu" "In4.Cu" "In6.Cu" "In11.Cu" "In13.Cu" "In15.Cu")
		(hatch none 0.5)
		(connect_pads
			(clearance 0)
		)
		(min_thickness 0.25)
		(keepout
			(tracks not_allowed)
			(vias allowed)
			(pads allowed)
			(copperpour not_allowed)
			(footprints allowed)
		)
		(placement
			(enabled no)
			(sheetname "")
		)
		(fill yes
			(thermal_gap 0.5)
			(thermal_bridge_width 0.5)
			(island_removal_mode 0)
		)
		(polygon
			(pts
				(arc
					(start 342.646 -232.334054)
					(mid 342.01608 -232.334054)
					(end 342.646 -232.334054)
				)
			)
		)
	)
	(zone
		(layers "B.Cu" "In4.Cu" "In6.Cu" "In11.Cu" "In13.Cu" "In15.Cu")
		(hatch none 0.5)
		(connect_pads
			(clearance 0)
		)
		(min_thickness 0.25)
		(keepout
			(tracks not_allowed)
			(vias allowed)
			(pads allowed)
			(copperpour not_allowed)
			(footprints allowed)
		)
		(placement
			(enabled no)
			(sheetname "")
		)
		(fill yes
			(thermal_gap 0.5)
			(thermal_bridge_width 0.5)
			(island_removal_mode 0)
		)
		(polygon
			(pts
				(arc
					(start 342.1761 -244.484144)
					(mid 341.54618 -244.484144)
					(end 342.1761 -244.484144)
				)
			)
		)
	)
	(zone
		(layers "B.Cu" "In4.Cu" "In6.Cu" "In11.Cu" "In13.Cu" "In15.Cu")
		(hatch none 0.5)
		(connect_pads
			(clearance 0)
		)
		(min_thickness 0.25)
		(keepout
			(tracks not_allowed)
			(vias allowed)
			(pads allowed)
			(copperpour not_allowed)
			(footprints allowed)
		)
		(placement
			(enabled no)
			(sheetname "")
		)
		(fill yes
			(thermal_gap 0.5)
			(thermal_bridge_width 0.5)
			(island_removal_mode 0)
		)
		(polygon
			(pts
				(arc
					(start 342.476074 -292.71595)
					(mid 341.846154 -292.71595)
					(end 342.476074 -292.71595)
				)
			)
		)
	)
	(zone
		(layers "B.Cu" "In4.Cu" "In6.Cu" "In11.Cu" "In13.Cu" "In15.Cu")
		(hatch none 0.5)
		(connect_pads
			(clearance 0)
		)
		(min_thickness 0.25)
		(keepout
			(tracks not_allowed)
			(vias allowed)
			(pads allowed)
			(copperpour not_allowed)
			(footprints allowed)
		)
		(placement
			(enabled no)
			(sheetname "")
		)
		(fill yes
			(thermal_gap 0.5)
			(thermal_bridge_width 0.5)
			(island_removal_mode 0)
		)
		(polygon
			(pts
				(arc
					(start 179.850034 -253.435358)
					(mid 179.182014 -253.435358)
					(end 179.850034 -253.435358)
				)
			)
		)
	)
	(zone
		(layers "B.Cu" "In4.Cu" "In6.Cu" "In11.Cu" "In13.Cu" "In15.Cu")
		(hatch none 0.5)
		(connect_pads
			(clearance 0)
		)
		(min_thickness 0.25)
		(keepout
			(tracks not_allowed)
			(vias allowed)
			(pads allowed)
			(copperpour not_allowed)
			(footprints allowed)
		)
		(placement
			(enabled no)
			(sheetname "")
		)
		(fill yes
			(thermal_gap 0.5)
			(thermal_bridge_width 0.5)
			(island_removal_mode 0)
		)
		(polygon
			(pts
				(arc
					(start 344.356182 -270.036036)
					(mid 343.726262 -270.036036)
					(end 344.356182 -270.036036)
				)
			)
		)
	)
	(zone
		(layers "B.Cu" "In4.Cu" "In6.Cu" "In11.Cu" "In13.Cu" "In15.Cu")
		(hatch none 0.5)
		(connect_pads
			(clearance 0)
		)
		(min_thickness 0.25)
		(keepout
			(tracks not_allowed)
			(vias allowed)
			(pads allowed)
			(copperpour not_allowed)
			(footprints allowed)
		)
		(placement
			(enabled no)
			(sheetname "")
		)
		(fill yes
			(thermal_gap 0.5)
			(thermal_bridge_width 0.5)
			(island_removal_mode 0)
		)
		(polygon
			(pts
				(arc
					(start 376.30989 -289.475926)
					(mid 375.67997 -289.475926)
					(end 376.30989 -289.475926)
				)
			)
		)
	)
	(zone
		(layers "B.Cu" "In4.Cu" "In6.Cu" "In11.Cu" "In13.Cu" "In15.Cu")
		(hatch none 0.5)
		(connect_pads
			(clearance 0)
		)
		(min_thickness 0.25)
		(keepout
			(tracks not_allowed)
			(vias allowed)
			(pads allowed)
			(copperpour not_allowed)
			(footprints allowed)
		)
		(placement
			(enabled no)
			(sheetname "")
		)
		(fill yes
			(thermal_gap 0.5)
			(thermal_bridge_width 0.5)
			(island_removal_mode 0)
		)
		(polygon
			(pts
				(arc
					(start 40.57396 -278.935434)
					(mid 39.90594 -278.935434)
					(end 40.57396 -278.935434)
				)
			)
		)
	)
	(zone
		(layers "B.Cu" "In4.Cu" "In6.Cu" "In11.Cu" "In13.Cu" "In15.Cu")
		(hatch none 0.5)
		(connect_pads
			(clearance 0)
		)
		(min_thickness 0.25)
		(keepout
			(tracks not_allowed)
			(vias allowed)
			(pads allowed)
			(copperpour not_allowed)
			(footprints allowed)
		)
		(placement
			(enabled no)
			(sheetname "")
		)
		(fill yes
			(thermal_gap 0.5)
			(thermal_bridge_width 0.5)
			(island_removal_mode 0)
		)
		(polygon
			(pts
				(arc
					(start 292.614096 -264.48512)
					(mid 291.946076 -264.48512)
					(end 292.614096 -264.48512)
				)
			)
		)
	)
	(zone
		(layers "B.Cu" "In4.Cu" "In6.Cu" "In11.Cu" "In13.Cu" "In15.Cu")
		(hatch none 0.5)
		(connect_pads
			(clearance 0)
		)
		(min_thickness 0.25)
		(keepout
			(tracks not_allowed)
			(vias allowed)
			(pads allowed)
			(copperpour not_allowed)
			(footprints allowed)
		)
		(placement
			(enabled no)
			(sheetname "")
		)
		(fill yes
			(thermal_gap 0.5)
			(thermal_bridge_width 0.5)
			(island_removal_mode 0)
		)
		(polygon
			(pts
				(arc
					(start 44.674028 -301.88535)
					(mid 44.006008 -301.88535)
					(end 44.674028 -301.88535)
				)
			)
		)
	)
	(zone
		(layers "B.Cu" "In4.Cu" "In6.Cu" "In11.Cu" "In13.Cu" "In15.Cu")
		(hatch none 0.5)
		(connect_pads
			(clearance 0)
		)
		(min_thickness 0.25)
		(keepout
			(tracks not_allowed)
			(vias allowed)
			(pads allowed)
			(copperpour not_allowed)
			(footprints allowed)
		)
		(placement
			(enabled no)
			(sheetname "")
		)
		(fill yes
			(thermal_gap 0.5)
			(thermal_bridge_width 0.5)
			(island_removal_mode 0)
		)
		(polygon
			(pts
				(arc
					(start 292.614096 -247.485154)
					(mid 291.946076 -247.485154)
					(end 292.614096 -247.485154)
				)
			)
		)
	)
	(zone
		(layers "B.Cu" "In4.Cu" "In6.Cu" "In11.Cu" "In13.Cu" "In15.Cu")
		(hatch none 0.5)
		(connect_pads
			(clearance 0)
		)
		(min_thickness 0.25)
		(keepout
			(tracks not_allowed)
			(vias allowed)
			(pads allowed)
			(copperpour not_allowed)
			(footprints allowed)
		)
		(placement
			(enabled no)
			(sheetname "")
		)
		(fill yes
			(thermal_gap 0.5)
			(thermal_bridge_width 0.5)
			(island_removal_mode 0)
		)
		(polygon
			(pts
				(arc
					(start 427.790102 -248.335038)
					(mid 427.122082 -248.335038)
					(end 427.790102 -248.335038)
				)
			)
		)
	)
	(zone
		(layers "B.Cu" "In4.Cu" "In6.Cu" "In11.Cu" "In13.Cu" "In15.Cu")
		(hatch none 0.5)
		(connect_pads
			(clearance 0)
		)
		(min_thickness 0.25)
		(keepout
			(tracks not_allowed)
			(vias allowed)
			(pads allowed)
			(copperpour not_allowed)
			(footprints allowed)
		)
		(placement
			(enabled no)
			(sheetname "")
		)
		(fill yes
			(thermal_gap 0.5)
			(thermal_bridge_width 0.5)
			(island_removal_mode 0)
		)
		(polygon
			(pts
				(arc
					(start 431.89017 -219.435172)
					(mid 431.22215 -219.435172)
					(end 431.89017 -219.435172)
				)
			)
		)
	)
	(zone
		(layers "B.Cu" "In4.Cu" "In6.Cu" "In11.Cu" "In13.Cu" "In15.Cu")
		(hatch none 0.5)
		(connect_pads
			(clearance 0)
		)
		(min_thickness 0.25)
		(keepout
			(tracks not_allowed)
			(vias allowed)
			(pads allowed)
			(copperpour not_allowed)
			(footprints allowed)
		)
		(placement
			(enabled no)
			(sheetname "")
		)
		(fill yes
			(thermal_gap 0.5)
			(thermal_bridge_width 0.5)
			(island_removal_mode 0)
		)
		(polygon
			(pts
				(arc
					(start 96.416114 -261.93623)
					(mid 95.786194 -261.93623)
					(end 96.416114 -261.93623)
				)
			)
		)
	)
	(zone
		(layers "B.Cu" "In4.Cu" "In6.Cu" "In11.Cu" "In13.Cu" "In15.Cu")
		(hatch none 0.5)
		(connect_pads
			(clearance 0)
		)
		(min_thickness 0.25)
		(keepout
			(tracks not_allowed)
			(vias allowed)
			(pads allowed)
			(copperpour not_allowed)
			(footprints allowed)
		)
		(placement
			(enabled no)
			(sheetname "")
		)
		(fill yes
			(thermal_gap 0.5)
			(thermal_bridge_width 0.5)
			(island_removal_mode 0)
		)
		(polygon
			(pts
				(arc
					(start 179.850034 -202.435206)
					(mid 179.182014 -202.435206)
					(end 179.850034 -202.435206)
				)
			)
		)
	)
	(zone
		(layers "B.Cu" "In4.Cu" "In6.Cu" "In11.Cu" "In13.Cu" "In15.Cu")
		(hatch none 0.5)
		(connect_pads
			(clearance 0)
		)
		(min_thickness 0.25)
		(keepout
			(tracks not_allowed)
			(vias allowed)
			(pads allowed)
			(copperpour not_allowed)
			(footprints allowed)
		)
		(placement
			(enabled no)
			(sheetname "")
		)
		(fill yes
			(thermal_gap 0.5)
			(thermal_bridge_width 0.5)
			(island_removal_mode 0)
		)
		(polygon
			(pts
				(arc
					(start 108.80598 -229.094538)
					(mid 108.17606 -229.094538)
					(end 108.80598 -229.094538)
				)
			)
		)
	)
	(zone
		(layers "B.Cu" "In4.Cu" "In6.Cu" "In11.Cu" "In13.Cu" "In15.Cu")
		(hatch none 0.5)
		(connect_pads
			(clearance 0)
		)
		(min_thickness 0.25)
		(keepout
			(tracks not_allowed)
			(vias allowed)
			(pads allowed)
			(copperpour not_allowed)
			(footprints allowed)
		)
		(placement
			(enabled no)
			(sheetname "")
		)
		(fill yes
			(thermal_gap 0.5)
			(thermal_bridge_width 0.5)
			(island_removal_mode 0)
		)
		(polygon
			(pts
				(arc
					(start 371.309646 -228.284278)
					(mid 370.679726 -228.284278)
					(end 371.309646 -228.284278)
				)
			)
		)
	)
	(zone
		(layers "B.Cu" "In4.Cu" "In6.Cu" "In11.Cu" "In13.Cu" "In15.Cu")
		(hatch none 0.5)
		(connect_pads
			(clearance 0)
		)
		(min_thickness 0.25)
		(keepout
			(tracks not_allowed)
			(vias allowed)
			(pads allowed)
			(copperpour not_allowed)
			(footprints allowed)
		)
		(placement
			(enabled no)
			(sheetname "")
		)
		(fill yes
			(thermal_gap 0.5)
			(thermal_bridge_width 0.5)
			(island_removal_mode 0)
		)
		(polygon
			(pts
				(arc
					(start 427.790102 -295.085008)
					(mid 427.122082 -295.085008)
					(end 427.790102 -295.085008)
				)
			)
		)
	)
	(zone
		(layers "B.Cu" "In4.Cu" "In6.Cu" "In11.Cu" "In13.Cu" "In15.Cu")
		(hatch none 0.5)
		(connect_pads
			(clearance 0)
		)
		(min_thickness 0.25)
		(keepout
			(tracks not_allowed)
			(vias allowed)
			(pads allowed)
			(copperpour not_allowed)
			(footprints allowed)
		)
		(placement
			(enabled no)
			(sheetname "")
		)
		(fill yes
			(thermal_gap 0.5)
			(thermal_bridge_width 0.5)
			(island_removal_mode 0)
		)
		(polygon
			(pts
				(arc
					(start 354.696014 -292.71595)
					(mid 354.066094 -292.71595)
					(end 354.696014 -292.71595)
				)
			)
		)
	)
	(zone
		(layers "B.Cu" "In4.Cu" "In6.Cu" "In11.Cu" "In13.Cu" "In15.Cu")
		(hatch none 0.5)
		(connect_pads
			(clearance 0)
		)
		(min_thickness 0.25)
		(keepout
			(tracks not_allowed)
			(vias allowed)
			(pads allowed)
			(copperpour not_allowed)
			(footprints allowed)
		)
		(placement
			(enabled no)
			(sheetname "")
		)
		(fill yes
			(thermal_gap 0.5)
			(thermal_bridge_width 0.5)
			(island_removal_mode 0)
		)
		(polygon
			(pts
				(arc
					(start 129.479802 -238.814356)
					(mid 128.849882 -238.814356)
					(end 129.479802 -238.814356)
				)
			)
		)
	)
	(zone
		(layers "B.Cu" "In4.Cu" "In6.Cu" "In11.Cu" "In13.Cu" "In15.Cu")
		(hatch none 0.5)
		(connect_pads
			(clearance 0)
		)
		(min_thickness 0.25)
		(keepout
			(tracks not_allowed)
			(vias allowed)
			(pads allowed)
			(copperpour not_allowed)
			(footprints allowed)
		)
		(placement
			(enabled no)
			(sheetname "")
		)
		(fill yes
			(thermal_gap 0.5)
			(thermal_bridge_width 0.5)
			(island_removal_mode 0)
		)
		(polygon
			(pts
				(arc
					(start 44.674028 -315.485272)
					(mid 44.006008 -315.485272)
					(end 44.674028 -315.485272)
				)
			)
		)
	)
	(zone
		(layers "B.Cu" "In4.Cu" "In6.Cu" "In11.Cu" "In13.Cu" "In15.Cu")
		(hatch none 0.5)
		(connect_pads
			(clearance 0)
		)
		(min_thickness 0.25)
		(keepout
			(tracks not_allowed)
			(vias allowed)
			(pads allowed)
			(copperpour not_allowed)
			(footprints allowed)
		)
		(placement
			(enabled no)
			(sheetname "")
		)
		(fill yes
			(thermal_gap 0.5)
			(thermal_bridge_width 0.5)
			(island_removal_mode 0)
		)
		(polygon
			(pts
				(arc
					(start 427.790102 -286.585152)
					(mid 427.122082 -286.585152)
					(end 427.790102 -286.585152)
				)
			)
		)
	)
	(zone
		(layers "B.Cu" "In4.Cu" "In6.Cu" "In11.Cu" "In13.Cu" "In15.Cu")
		(hatch none 0.5)
		(connect_pads
			(clearance 0)
		)
		(min_thickness 0.25)
		(keepout
			(tracks not_allowed)
			(vias allowed)
			(pads allowed)
			(copperpour not_allowed)
			(footprints allowed)
		)
		(placement
			(enabled no)
			(sheetname "")
		)
		(fill yes
			(thermal_gap 0.5)
			(thermal_bridge_width 0.5)
			(island_removal_mode 0)
		)
		(polygon
			(pts
				(arc
					(start 342.646 -227.474272)
					(mid 342.01608 -227.474272)
					(end 342.646 -227.474272)
				)
			)
		)
	)
	(zone
		(layers "B.Cu" "In4.Cu" "In6.Cu" "In11.Cu" "In13.Cu" "In15.Cu")
		(hatch none 0.5)
		(connect_pads
			(clearance 0)
		)
		(min_thickness 0.25)
		(keepout
			(tracks not_allowed)
			(vias allowed)
			(pads allowed)
			(copperpour not_allowed)
			(footprints allowed)
		)
		(placement
			(enabled no)
			(sheetname "")
		)
		(fill yes
			(thermal_gap 0.5)
			(thermal_bridge_width 0.5)
			(island_removal_mode 0)
		)
		(polygon
			(pts
				(arc
					(start 377.41987 -233.954066)
					(mid 376.78995 -233.954066)
					(end 377.41987 -233.954066)
				)
			)
		)
	)
	(zone
		(layers "B.Cu" "In4.Cu" "In6.Cu" "In11.Cu" "In13.Cu" "In15.Cu")
		(hatch none 0.5)
		(connect_pads
			(clearance 0)
		)
		(min_thickness 0.25)
		(keepout
			(tracks not_allowed)
			(vias allowed)
			(pads allowed)
			(copperpour not_allowed)
			(footprints allowed)
		)
		(placement
			(enabled no)
			(sheetname "")
		)
		(fill yes
			(thermal_gap 0.5)
			(thermal_bridge_width 0.5)
			(island_removal_mode 0)
		)
		(polygon
			(pts
				(arc
					(start 431.89017 -214.335106)
					(mid 431.22215 -214.335106)
					(end 431.89017 -214.335106)
				)
			)
		)
	)
	(zone
		(layers "B.Cu" "In4.Cu" "In6.Cu" "In11.Cu" "In13.Cu" "In15.Cu")
		(hatch none 0.5)
		(connect_pads
			(clearance 0)
		)
		(min_thickness 0.25)
		(keepout
			(tracks not_allowed)
			(vias allowed)
			(pads allowed)
			(copperpour not_allowed)
			(footprints allowed)
		)
		(placement
			(enabled no)
			(sheetname "")
		)
		(fill yes
			(thermal_gap 0.5)
			(thermal_bridge_width 0.5)
			(island_removal_mode 0)
		)
		(polygon
			(pts
				(arc
					(start 344.356182 -282.996132)
					(mid 343.726262 -282.996132)
					(end 344.356182 -282.996132)
				)
			)
		)
	)
	(zone
		(layers "B.Cu" "In4.Cu" "In6.Cu" "In11.Cu" "In13.Cu" "In15.Cu")
		(hatch none 0.5)
		(connect_pads
			(clearance 0)
		)
		(min_thickness 0.25)
		(keepout
			(tracks not_allowed)
			(vias allowed)
			(pads allowed)
			(copperpour not_allowed)
			(footprints allowed)
		)
		(placement
			(enabled no)
			(sheetname "")
		)
		(fill yes
			(thermal_gap 0.5)
			(thermal_bridge_width 0.5)
			(island_removal_mode 0)
		)
		(polygon
			(pts
				(arc
					(start 129.479802 -233.95432)
					(mid 128.849882 -233.95432)
					(end 129.479802 -233.95432)
				)
			)
		)
	)
	(zone
		(layers "B.Cu" "In4.Cu" "In6.Cu" "In11.Cu" "In13.Cu" "In15.Cu")
		(hatch none 0.5)
		(connect_pads
			(clearance 0)
		)
		(min_thickness 0.25)
		(keepout
			(tracks not_allowed)
			(vias allowed)
			(pads allowed)
			(copperpour not_allowed)
			(footprints allowed)
		)
		(placement
			(enabled no)
			(sheetname "")
		)
		(fill yes
			(thermal_gap 0.5)
			(thermal_bridge_width 0.5)
			(island_removal_mode 0)
		)
		(polygon
			(pts
				(arc
					(start 427.790102 -297.635168)
					(mid 427.122082 -297.635168)
					(end 427.790102 -297.635168)
				)
			)
		)
	)
	(zone
		(layers "B.Cu" "In4.Cu" "In6.Cu" "In11.Cu" "In13.Cu" "In15.Cu")
		(hatch none 0.5)
		(connect_pads
			(clearance 0)
		)
		(min_thickness 0.25)
		(keepout
			(tracks not_allowed)
			(vias allowed)
			(pads allowed)
			(copperpour not_allowed)
			(footprints allowed)
		)
		(placement
			(enabled no)
			(sheetname "")
		)
		(fill yes
			(thermal_gap 0.5)
			(thermal_bridge_width 0.5)
			(island_removal_mode 0)
		)
		(polygon
			(pts
				(arc
					(start 128.369822 -281.376374)
					(mid 127.739902 -281.376374)
					(end 128.369822 -281.376374)
				)
			)
		)
	)
	(zone
		(layers "B.Cu" "In4.Cu" "In6.Cu" "In11.Cu" "In13.Cu" "In15.Cu")
		(hatch none 0.5)
		(connect_pads
			(clearance 0)
		)
		(min_thickness 0.25)
		(keepout
			(tracks not_allowed)
			(vias allowed)
			(pads allowed)
			(copperpour not_allowed)
			(footprints allowed)
		)
		(placement
			(enabled no)
			(sheetname "")
		)
		(fill yes
			(thermal_gap 0.5)
			(thermal_bridge_width 0.5)
			(island_removal_mode 0)
		)
		(polygon
			(pts
				(arc
					(start 183.950102 -264.485374)
					(mid 183.282082 -264.485374)
					(end 183.950102 -264.485374)
				)
			)
		)
	)
	(zone
		(layers "B.Cu" "In4.Cu" "In6.Cu" "In11.Cu" "In13.Cu" "In15.Cu")
		(hatch none 0.5)
		(connect_pads
			(clearance 0)
		)
		(min_thickness 0.25)
		(keepout
			(tracks not_allowed)
			(vias allowed)
			(pads allowed)
			(copperpour not_allowed)
			(footprints allowed)
		)
		(placement
			(enabled no)
			(sheetname "")
		)
		(fill yes
			(thermal_gap 0.5)
			(thermal_bridge_width 0.5)
			(island_removal_mode 0)
		)
		(polygon
			(pts
				(arc
					(start 130.249676 -291.096192)
					(mid 129.619756 -291.096192)
					(end 130.249676 -291.096192)
				)
			)
		)
	)
	(zone
		(layers "B.Cu" "In4.Cu" "In6.Cu" "In11.Cu" "In13.Cu" "In15.Cu")
		(hatch none 0.5)
		(connect_pads
			(clearance 0)
		)
		(min_thickness 0.25)
		(keepout
			(tracks not_allowed)
			(vias allowed)
			(pads allowed)
			(copperpour not_allowed)
			(footprints allowed)
		)
		(placement
			(enabled no)
			(sheetname "")
		)
		(fill yes
			(thermal_gap 0.5)
			(thermal_bridge_width 0.5)
			(island_removal_mode 0)
		)
		(polygon
			(pts
				(arc
					(start 179.850034 -237.285276)
					(mid 179.182014 -237.285276)
					(end 179.850034 -237.285276)
				)
			)
		)
	)
	(zone
		(layers "B.Cu" "In4.Cu" "In6.Cu" "In11.Cu" "In13.Cu" "In15.Cu")
		(hatch none 0.5)
		(connect_pads
			(clearance 0)
		)
		(min_thickness 0.25)
		(keepout
			(tracks not_allowed)
			(vias allowed)
			(pads allowed)
			(copperpour not_allowed)
			(footprints allowed)
		)
		(placement
			(enabled no)
			(sheetname "")
		)
		(fill yes
			(thermal_gap 0.5)
			(thermal_bridge_width 0.5)
			(island_removal_mode 0)
		)
		(polygon
			(pts
				(arc
					(start 288.514028 -251.735082)
					(mid 287.846008 -251.735082)
					(end 288.514028 -251.735082)
				)
			)
		)
	)
	(zone
		(layers "B.Cu" "In4.Cu" "In6.Cu" "In11.Cu" "In13.Cu" "In15.Cu")
		(hatch none 0.5)
		(connect_pads
			(clearance 0)
		)
		(min_thickness 0.25)
		(keepout
			(tracks not_allowed)
			(vias allowed)
			(pads allowed)
			(copperpour not_allowed)
			(footprints allowed)
		)
		(placement
			(enabled no)
			(sheetname "")
		)
		(fill yes
			(thermal_gap 0.5)
			(thermal_bridge_width 0.5)
			(island_removal_mode 0)
		)
		(polygon
			(pts
				(arc
					(start 96.416114 -270.03629)
					(mid 95.786194 -270.03629)
					(end 96.416114 -270.03629)
				)
			)
		)
	)
	(zone
		(layers "B.Cu" "In4.Cu" "In6.Cu" "In11.Cu" "In13.Cu" "In15.Cu")
		(hatch none 0.5)
		(connect_pads
			(clearance 0)
		)
		(min_thickness 0.25)
		(keepout
			(tracks not_allowed)
			(vias allowed)
			(pads allowed)
			(copperpour not_allowed)
			(footprints allowed)
		)
		(placement
			(enabled no)
			(sheetname "")
		)
		(fill yes
			(thermal_gap 0.5)
			(thermal_bridge_width 0.5)
			(island_removal_mode 0)
		)
		(polygon
			(pts
				(arc
					(start 129.779776 -283.806392)
					(mid 129.149856 -283.806392)
					(end 129.779776 -283.806392)
				)
			)
		)
	)
	(zone
		(layers "B.Cu" "In4.Cu" "In6.Cu" "In11.Cu" "In13.Cu" "In15.Cu")
		(hatch none 0.5)
		(connect_pads
			(clearance 0)
		)
		(min_thickness 0.25)
		(keepout
			(tracks not_allowed)
			(vias allowed)
			(pads allowed)
			(copperpour not_allowed)
			(footprints allowed)
		)
		(placement
			(enabled no)
			(sheetname "")
		)
		(fill yes
			(thermal_gap 0.5)
			(thermal_bridge_width 0.5)
			(island_removal_mode 0)
		)
		(polygon
			(pts
				(arc
					(start 377.88977 -225.044254)
					(mid 377.25985 -225.044254)
					(end 377.88977 -225.044254)
				)
			)
		)
	)
	(zone
		(layers "B.Cu" "In4.Cu" "In6.Cu" "In11.Cu" "In13.Cu" "In15.Cu")
		(hatch none 0.5)
		(connect_pads
			(clearance 0)
		)
		(min_thickness 0.25)
		(keepout
			(tracks not_allowed)
			(vias allowed)
			(pads allowed)
			(copperpour not_allowed)
			(footprints allowed)
		)
		(placement
			(enabled no)
			(sheetname "")
		)
		(fill yes
			(thermal_gap 0.5)
			(thermal_bridge_width 0.5)
			(island_removal_mode 0)
		)
		(polygon
			(pts
				(arc
					(start 288.514028 -299.33519)
					(mid 287.846008 -299.33519)
					(end 288.514028 -299.33519)
				)
			)
		)
	)
	(zone
		(layers "B.Cu" "In4.Cu" "In6.Cu" "In11.Cu" "In13.Cu" "In15.Cu")
		(hatch none 0.5)
		(connect_pads
			(clearance 0)
		)
		(min_thickness 0.25)
		(keepout
			(tracks not_allowed)
			(vias allowed)
			(pads allowed)
			(copperpour not_allowed)
			(footprints allowed)
		)
		(placement
			(enabled no)
			(sheetname "")
		)
		(fill yes
			(thermal_gap 0.5)
			(thermal_bridge_width 0.5)
			(island_removal_mode 0)
		)
		(polygon
			(pts
				(arc
					(start 292.614096 -238.13516)
					(mid 291.946076 -238.13516)
					(end 292.614096 -238.13516)
				)
			)
		)
	)
	(zone
		(layers "B.Cu" "In4.Cu" "In6.Cu" "In11.Cu" "In13.Cu" "In15.Cu")
		(hatch none 0.5)
		(connect_pads
			(clearance 0)
		)
		(min_thickness 0.25)
		(keepout
			(tracks not_allowed)
			(vias allowed)
			(pads allowed)
			(copperpour not_allowed)
			(footprints allowed)
		)
		(placement
			(enabled no)
			(sheetname "")
		)
		(fill yes
			(thermal_gap 0.5)
			(thermal_bridge_width 0.5)
			(island_removal_mode 0)
		)
		(polygon
			(pts
				(arc
					(start 179.850034 -263.635236)
					(mid 179.182014 -263.635236)
					(end 179.850034 -263.635236)
				)
			)
		)
	)
	(zone
		(layers "B.Cu" "In4.Cu" "In6.Cu" "In11.Cu" "In13.Cu" "In15.Cu")
		(hatch none 0.5)
		(connect_pads
			(clearance 0)
		)
		(min_thickness 0.25)
		(keepout
			(tracks not_allowed)
			(vias allowed)
			(pads allowed)
			(copperpour not_allowed)
			(footprints allowed)
		)
		(placement
			(enabled no)
			(sheetname "")
		)
		(fill yes
			(thermal_gap 0.5)
			(thermal_bridge_width 0.5)
			(island_removal_mode 0)
		)
		(polygon
			(pts
				(arc
					(start 342.1761 -255.824228)
					(mid 341.54618 -255.824228)
					(end 342.1761 -255.824228)
				)
			)
		)
	)
	(zone
		(layers "B.Cu" "In4.Cu" "In6.Cu" "In11.Cu" "In13.Cu" "In15.Cu")
		(hatch none 0.5)
		(connect_pads
			(clearance 0)
		)
		(min_thickness 0.25)
		(keepout
			(tracks not_allowed)
			(vias allowed)
			(pads allowed)
			(copperpour not_allowed)
			(footprints allowed)
		)
		(placement
			(enabled no)
			(sheetname "")
		)
		(fill yes
			(thermal_gap 0.5)
			(thermal_bridge_width 0.5)
			(island_removal_mode 0)
		)
		(polygon
			(pts
				(arc
					(start 376.479816 -240.434114)
					(mid 375.849896 -240.434114)
					(end 376.479816 -240.434114)
				)
			)
		)
	)
	(zone
		(layers "B.Cu" "In4.Cu" "In6.Cu" "In11.Cu" "In13.Cu" "In15.Cu")
		(hatch none 0.5)
		(connect_pads
			(clearance 0)
		)
		(min_thickness 0.25)
		(keepout
			(tracks not_allowed)
			(vias allowed)
			(pads allowed)
			(copperpour not_allowed)
			(footprints allowed)
		)
		(placement
			(enabled no)
			(sheetname "")
		)
		(fill yes
			(thermal_gap 0.5)
			(thermal_bridge_width 0.5)
			(island_removal_mode 0)
		)
		(polygon
			(pts
				(arc
					(start 183.950102 -301.88535)
					(mid 183.282082 -301.88535)
					(end 183.950102 -301.88535)
				)
			)
		)
	)
	(zone
		(layers "B.Cu" "In4.Cu" "In6.Cu" "In11.Cu" "In13.Cu" "In15.Cu")
		(hatch none 0.5)
		(connect_pads
			(clearance 0)
		)
		(min_thickness 0.25)
		(keepout
			(tracks not_allowed)
			(vias allowed)
			(pads allowed)
			(copperpour not_allowed)
			(footprints allowed)
		)
		(placement
			(enabled no)
			(sheetname "")
		)
		(fill yes
			(thermal_gap 0.5)
			(thermal_bridge_width 0.5)
			(island_removal_mode 0)
		)
		(polygon
			(pts
				(arc
					(start 183.950102 -306.135278)
					(mid 183.282082 -306.135278)
					(end 183.950102 -306.135278)
				)
			)
		)
	)
	(zone
		(layers "B.Cu" "In4.Cu" "In6.Cu" "In11.Cu" "In13.Cu" "In15.Cu")
		(hatch none 0.5)
		(connect_pads
			(clearance 0)
		)
		(min_thickness 0.25)
		(keepout
			(tracks not_allowed)
			(vias allowed)
			(pads allowed)
			(copperpour not_allowed)
			(footprints allowed)
		)
		(placement
			(enabled no)
			(sheetname "")
		)
		(fill yes
			(thermal_gap 0.5)
			(thermal_bridge_width 0.5)
			(island_removal_mode 0)
		)
		(polygon
			(pts
				(arc
					(start 344.055954 -236.384084)
					(mid 343.426034 -236.384084)
					(end 344.055954 -236.384084)
				)
			)
		)
	)
	(zone
		(layers "B.Cu" "In4.Cu" "In6.Cu" "In11.Cu" "In13.Cu" "In15.Cu")
		(hatch none 0.5)
		(connect_pads
			(clearance 0)
		)
		(min_thickness 0.25)
		(keepout
			(tracks not_allowed)
			(vias allowed)
			(pads allowed)
			(copperpour not_allowed)
			(footprints allowed)
		)
		(placement
			(enabled no)
			(sheetname "")
		)
		(fill yes
			(thermal_gap 0.5)
			(thermal_bridge_width 0.5)
			(island_removal_mode 0)
		)
		(polygon
			(pts
				(arc
					(start 179.850034 -243.235226)
					(mid 179.182014 -243.235226)
					(end 179.850034 -243.235226)
				)
			)
		)
	)
	(zone
		(layers "B.Cu" "In4.Cu" "In6.Cu" "In11.Cu" "In13.Cu" "In15.Cu")
		(hatch none 0.5)
		(connect_pads
			(clearance 0)
		)
		(min_thickness 0.25)
		(keepout
			(tracks not_allowed)
			(vias allowed)
			(pads allowed)
			(copperpour not_allowed)
			(footprints allowed)
		)
		(placement
			(enabled no)
			(sheetname "")
		)
		(fill yes
			(thermal_gap 0.5)
			(thermal_bridge_width 0.5)
			(island_removal_mode 0)
		)
		(polygon
			(pts
				(arc
					(start 288.514028 -205.834996)
					(mid 287.846008 -205.834996)
					(end 288.514028 -205.834996)
				)
			)
		)
	)
	(zone
		(layers "B.Cu" "In4.Cu" "In6.Cu" "In11.Cu" "In13.Cu" "In15.Cu")
		(hatch none 0.5)
		(connect_pads
			(clearance 0)
		)
		(min_thickness 0.25)
		(keepout
			(tracks not_allowed)
			(vias allowed)
			(pads allowed)
			(copperpour not_allowed)
			(footprints allowed)
		)
		(placement
			(enabled no)
			(sheetname "")
		)
		(fill yes
			(thermal_gap 0.5)
			(thermal_bridge_width 0.5)
			(island_removal_mode 0)
		)
		(polygon
			(pts
				(arc
					(start 371.309646 -229.904036)
					(mid 370.679726 -229.904036)
					(end 371.309646 -229.904036)
				)
			)
		)
	)
	(zone
		(layers "B.Cu" "In4.Cu" "In6.Cu" "In11.Cu" "In13.Cu" "In15.Cu")
		(hatch none 0.5)
		(connect_pads
			(clearance 0)
		)
		(min_thickness 0.25)
		(keepout
			(tracks not_allowed)
			(vias allowed)
			(pads allowed)
			(copperpour not_allowed)
			(footprints allowed)
		)
		(placement
			(enabled no)
			(sheetname "")
		)
		(fill yes
			(thermal_gap 0.5)
			(thermal_bridge_width 0.5)
			(island_removal_mode 0)
		)
		(polygon
			(pts
				(arc
					(start 288.514028 -302.73498)
					(mid 287.846008 -302.73498)
					(end 288.514028 -302.73498)
				)
			)
		)
	)
	(zone
		(layers "B.Cu" "In4.Cu" "In6.Cu" "In11.Cu" "In13.Cu" "In15.Cu")
		(hatch none 0.5)
		(connect_pads
			(clearance 0)
		)
		(min_thickness 0.25)
		(keepout
			(tracks not_allowed)
			(vias allowed)
			(pads allowed)
			(copperpour not_allowed)
			(footprints allowed)
		)
		(placement
			(enabled no)
			(sheetname "")
		)
		(fill yes
			(thermal_gap 0.5)
			(thermal_bridge_width 0.5)
			(island_removal_mode 0)
		)
		(polygon
			(pts
				(arc
					(start 44.674028 -199.035416)
					(mid 44.006008 -199.035416)
					(end 44.674028 -199.035416)
				)
			)
		)
	)
	(zone
		(layers "B.Cu" "In4.Cu" "In6.Cu" "In11.Cu" "In13.Cu" "In15.Cu")
		(hatch none 0.5)
		(connect_pads
			(clearance 0)
		)
		(min_thickness 0.25)
		(keepout
			(tracks not_allowed)
			(vias allowed)
			(pads allowed)
			(copperpour not_allowed)
			(footprints allowed)
		)
		(placement
			(enabled no)
			(sheetname "")
		)
		(fill yes
			(thermal_gap 0.5)
			(thermal_bridge_width 0.5)
			(island_removal_mode 0)
		)
		(polygon
			(pts
				(arc
					(start 376.479816 -242.054126)
					(mid 375.849896 -242.054126)
					(end 376.479816 -242.054126)
				)
			)
		)
	)
	(zone
		(layers "B.Cu" "In4.Cu" "In6.Cu" "In11.Cu" "In13.Cu" "In15.Cu")
		(hatch none 0.5)
		(connect_pads
			(clearance 0)
		)
		(min_thickness 0.25)
		(keepout
			(tracks not_allowed)
			(vias allowed)
			(pads allowed)
			(copperpour not_allowed)
			(footprints allowed)
		)
		(placement
			(enabled no)
			(sheetname "")
		)
		(fill yes
			(thermal_gap 0.5)
			(thermal_bridge_width 0.5)
			(island_removal_mode 0)
		)
		(polygon
			(pts
				(arc
					(start 431.89017 -206.685134)
					(mid 431.22215 -206.685134)
					(end 431.89017 -206.685134)
				)
			)
		)
	)
	(zone
		(layers "B.Cu" "In4.Cu" "In6.Cu" "In11.Cu" "In13.Cu" "In15.Cu")
		(hatch none 0.5)
		(connect_pads
			(clearance 0)
		)
		(min_thickness 0.25)
		(keepout
			(tracks not_allowed)
			(vias allowed)
			(pads allowed)
			(copperpour not_allowed)
			(footprints allowed)
		)
		(placement
			(enabled no)
			(sheetname "")
		)
		(fill yes
			(thermal_gap 0.5)
			(thermal_bridge_width 0.5)
			(island_removal_mode 0)
		)
		(polygon
			(pts
				(arc
					(start 376.009662 -226.664266)
					(mid 375.379742 -226.664266)
					(end 376.009662 -226.664266)
				)
			)
		)
	)
	(zone
		(layers "B.Cu" "In4.Cu" "In6.Cu" "In11.Cu" "In13.Cu" "In15.Cu")
		(hatch none 0.5)
		(connect_pads
			(clearance 0)
		)
		(min_thickness 0.25)
		(keepout
			(tracks not_allowed)
			(vias allowed)
			(pads allowed)
			(copperpour not_allowed)
			(footprints allowed)
		)
		(placement
			(enabled no)
			(sheetname "")
		)
		(fill yes
			(thermal_gap 0.5)
			(thermal_bridge_width 0.5)
			(island_removal_mode 0)
		)
		(polygon
			(pts
				(arc
					(start 44.674028 -208.38541)
					(mid 44.006008 -208.38541)
					(end 44.674028 -208.38541)
				)
			)
		)
	)
	(zone
		(layers "B.Cu" "In4.Cu" "In6.Cu" "In11.Cu" "In13.Cu" "In15.Cu")
		(hatch none 0.5)
		(connect_pads
			(clearance 0)
		)
		(min_thickness 0.25)
		(keepout
			(tracks not_allowed)
			(vias allowed)
			(pads allowed)
			(copperpour not_allowed)
			(footprints allowed)
		)
		(placement
			(enabled no)
			(sheetname "")
		)
		(fill yes
			(thermal_gap 0.5)
			(thermal_bridge_width 0.5)
			(island_removal_mode 0)
		)
		(polygon
			(pts
				(arc
					(start 129.949702 -229.90429)
					(mid 129.319782 -229.90429)
					(end 129.949702 -229.90429)
				)
			)
		)
	)
	(zone
		(layers "B.Cu" "In4.Cu" "In6.Cu" "In11.Cu" "In13.Cu" "In15.Cu")
		(hatch none 0.5)
		(connect_pads
			(clearance 0)
		)
		(min_thickness 0.25)
		(keepout
			(tracks not_allowed)
			(vias allowed)
			(pads allowed)
			(copperpour not_allowed)
			(footprints allowed)
		)
		(placement
			(enabled no)
			(sheetname "")
		)
		(fill yes
			(thermal_gap 0.5)
			(thermal_bridge_width 0.5)
			(island_removal_mode 0)
		)
		(polygon
			(pts
				(arc
					(start 44.674028 -285.735268)
					(mid 44.006008 -285.735268)
					(end 44.674028 -285.735268)
				)
			)
		)
	)
	(zone
		(layers "B.Cu" "In4.Cu" "In6.Cu" "In11.Cu" "In13.Cu" "In15.Cu")
		(hatch none 0.5)
		(connect_pads
			(clearance 0)
		)
		(min_thickness 0.25)
		(keepout
			(tracks not_allowed)
			(vias allowed)
			(pads allowed)
			(copperpour not_allowed)
			(footprints allowed)
		)
		(placement
			(enabled no)
			(sheetname "")
		)
		(fill yes
			(thermal_gap 0.5)
			(thermal_bridge_width 0.5)
			(island_removal_mode 0)
		)
		(polygon
			(pts
				(arc
					(start 342.646 -242.054126)
					(mid 342.01608 -242.054126)
					(end 342.646 -242.054126)
				)
			)
		)
	)
	(zone
		(layers "B.Cu" "In4.Cu" "In6.Cu" "In11.Cu" "In13.Cu" "In15.Cu")
		(hatch none 0.5)
		(connect_pads
			(clearance 0)
		)
		(min_thickness 0.25)
		(keepout
			(tracks not_allowed)
			(vias allowed)
			(pads allowed)
			(copperpour not_allowed)
			(footprints allowed)
		)
		(placement
			(enabled no)
			(sheetname "")
		)
		(fill yes
			(thermal_gap 0.5)
			(thermal_bridge_width 0.5)
			(island_removal_mode 0)
		)
		(polygon
			(pts
				(arc
					(start 95.94596 -280.566368)
					(mid 95.31604 -280.566368)
					(end 95.94596 -280.566368)
				)
			)
		)
	)
	(zone
		(layers "B.Cu" "In4.Cu" "In6.Cu" "In11.Cu" "In13.Cu" "In15.Cu")
		(hatch none 0.5)
		(connect_pads
			(clearance 0)
		)
		(min_thickness 0.25)
		(keepout
			(tracks not_allowed)
			(vias allowed)
			(pads allowed)
			(copperpour not_allowed)
			(footprints allowed)
		)
		(placement
			(enabled no)
			(sheetname "")
		)
		(fill yes
			(thermal_gap 0.5)
			(thermal_bridge_width 0.5)
			(island_removal_mode 0)
		)
		(polygon
			(pts
				(arc
					(start 378.189744 -263.555988)
					(mid 377.559824 -263.555988)
					(end 378.189744 -263.555988)
				)
			)
		)
	)
	(zone
		(layers "B.Cu" "In4.Cu" "In6.Cu" "In11.Cu" "In13.Cu" "In15.Cu")
		(hatch none 0.5)
		(connect_pads
			(clearance 0)
		)
		(min_thickness 0.25)
		(keepout
			(tracks not_allowed)
			(vias allowed)
			(pads allowed)
			(copperpour not_allowed)
			(footprints allowed)
		)
		(placement
			(enabled no)
			(sheetname "")
		)
		(fill yes
			(thermal_gap 0.5)
			(thermal_bridge_width 0.5)
			(island_removal_mode 0)
		)
		(polygon
			(pts
				(arc
					(start 431.89017 -294.235124)
					(mid 431.22215 -294.235124)
					(end 431.89017 -294.235124)
				)
			)
		)
	)
	(zone
		(layers "B.Cu" "In4.Cu" "In6.Cu" "In11.Cu" "In13.Cu" "In15.Cu")
		(hatch none 0.5)
		(connect_pads
			(clearance 0)
		)
		(min_thickness 0.25)
		(keepout
			(tracks not_allowed)
			(vias allowed)
			(pads allowed)
			(copperpour not_allowed)
			(footprints allowed)
		)
		(placement
			(enabled no)
			(sheetname "")
		)
		(fill yes
			(thermal_gap 0.5)
			(thermal_bridge_width 0.5)
			(island_removal_mode 0)
		)
		(polygon
			(pts
				(arc
					(start 129.949702 -231.524302)
					(mid 129.319782 -231.524302)
					(end 129.949702 -231.524302)
				)
			)
		)
	)
	(zone
		(layers "B.Cu" "In4.Cu" "In6.Cu" "In11.Cu" "In13.Cu" "In15.Cu")
		(hatch none 0.5)
		(connect_pads
			(clearance 0)
		)
		(min_thickness 0.25)
		(keepout
			(tracks not_allowed)
			(vias allowed)
			(pads allowed)
			(copperpour not_allowed)
			(footprints allowed)
		)
		(placement
			(enabled no)
			(sheetname "")
		)
		(fill yes
			(thermal_gap 0.5)
			(thermal_bridge_width 0.5)
			(island_removal_mode 0)
		)
		(polygon
			(pts
				(arc
					(start 288.514028 -248.335038)
					(mid 287.846008 -248.335038)
					(end 288.514028 -248.335038)
				)
			)
		)
	)
	(zone
		(layers "B.Cu" "In4.Cu" "In6.Cu" "In11.Cu" "In13.Cu" "In15.Cu")
		(hatch none 0.5)
		(connect_pads
			(clearance 0)
		)
		(min_thickness 0.25)
		(keepout
			(tracks not_allowed)
			(vias allowed)
			(pads allowed)
			(copperpour not_allowed)
			(footprints allowed)
		)
		(placement
			(enabled no)
			(sheetname "")
		)
		(fill yes
			(thermal_gap 0.5)
			(thermal_bridge_width 0.5)
			(island_removal_mode 0)
		)
		(polygon
			(pts
				(arc
					(start 373.189754 -231.524048)
					(mid 372.559834 -231.524048)
					(end 373.189754 -231.524048)
				)
			)
		)
	)
	(zone
		(layers "B.Cu" "In4.Cu" "In6.Cu" "In11.Cu" "In13.Cu" "In15.Cu")
		(hatch none 0.5)
		(connect_pads
			(clearance 0)
		)
		(min_thickness 0.25)
		(keepout
			(tracks not_allowed)
			(vias allowed)
			(pads allowed)
			(copperpour not_allowed)
			(footprints allowed)
		)
		(placement
			(enabled no)
			(sheetname "")
		)
		(fill yes
			(thermal_gap 0.5)
			(thermal_bridge_width 0.5)
			(island_removal_mode 0)
		)
		(polygon
			(pts
				(arc
					(start 129.949702 -226.66452)
					(mid 129.319782 -226.66452)
					(end 129.949702 -226.66452)
				)
			)
		)
	)
	(zone
		(layers "B.Cu" "In4.Cu" "In6.Cu" "In11.Cu" "In13.Cu" "In15.Cu")
		(hatch none 0.5)
		(connect_pads
			(clearance 0)
		)
		(min_thickness 0.25)
		(keepout
			(tracks not_allowed)
			(vias allowed)
			(pads allowed)
			(copperpour not_allowed)
			(footprints allowed)
		)
		(placement
			(enabled no)
			(sheetname "")
		)
		(fill yes
			(thermal_gap 0.5)
			(thermal_bridge_width 0.5)
			(island_removal_mode 0)
		)
		(polygon
			(pts
				(arc
					(start 179.850034 -286.585406)
					(mid 179.182014 -286.585406)
					(end 179.850034 -286.585406)
				)
			)
		)
	)
	(zone
		(layers "B.Cu" "In4.Cu" "In6.Cu" "In11.Cu" "In13.Cu" "In15.Cu")
		(hatch none 0.5)
		(connect_pads
			(clearance 0)
		)
		(min_thickness 0.25)
		(keepout
			(tracks not_allowed)
			(vias allowed)
			(pads allowed)
			(copperpour not_allowed)
			(footprints allowed)
		)
		(placement
			(enabled no)
			(sheetname "")
		)
		(fill yes
			(thermal_gap 0.5)
			(thermal_bridge_width 0.5)
			(island_removal_mode 0)
		)
		(polygon
			(pts
				(arc
					(start 343.586054 -245.29415)
					(mid 342.956134 -245.29415)
					(end 343.586054 -245.29415)
				)
			)
		)
	)
	(zone
		(layers "B.Cu" "In4.Cu" "In6.Cu" "In11.Cu" "In13.Cu" "In15.Cu")
		(hatch none 0.5)
		(connect_pads
			(clearance 0)
		)
		(min_thickness 0.25)
		(keepout
			(tracks not_allowed)
			(vias allowed)
			(pads allowed)
			(copperpour not_allowed)
			(footprints allowed)
		)
		(placement
			(enabled no)
			(sheetname "")
		)
		(fill yes
			(thermal_gap 0.5)
			(thermal_bridge_width 0.5)
			(island_removal_mode 0)
		)
		(polygon
			(pts
				(arc
					(start 183.950102 -276.385274)
					(mid 183.282082 -276.385274)
					(end 183.950102 -276.385274)
				)
			)
		)
	)
	(zone
		(layers "B.Cu" "In4.Cu" "In6.Cu" "In11.Cu" "In13.Cu" "In15.Cu")
		(hatch none 0.5)
		(connect_pads
			(clearance 0)
		)
		(min_thickness 0.25)
		(keepout
			(tracks not_allowed)
			(vias allowed)
			(pads allowed)
			(copperpour not_allowed)
			(footprints allowed)
		)
		(placement
			(enabled no)
			(sheetname "")
		)
		(fill yes
			(thermal_gap 0.5)
			(thermal_bridge_width 0.5)
			(island_removal_mode 0)
		)
		(polygon
			(pts
				(arc
					(start 376.479816 -255.014222)
					(mid 375.849896 -255.014222)
					(end 376.479816 -255.014222)
				)
			)
		)
	)
	(zone
		(layers "B.Cu" "In4.Cu" "In6.Cu" "In11.Cu" "In13.Cu" "In15.Cu")
		(hatch none 0.5)
		(connect_pads
			(clearance 0)
		)
		(min_thickness 0.25)
		(keepout
			(tracks not_allowed)
			(vias allowed)
			(pads allowed)
			(copperpour not_allowed)
			(footprints allowed)
		)
		(placement
			(enabled no)
			(sheetname "")
		)
		(fill yes
			(thermal_gap 0.5)
			(thermal_bridge_width 0.5)
			(island_removal_mode 0)
		)
		(polygon
			(pts
				(arc
					(start 431.89017 -312.935112)
					(mid 431.22215 -312.935112)
					(end 431.89017 -312.935112)
				)
			)
		)
	)
	(zone
		(layers "B.Cu" "In4.Cu" "In6.Cu" "In11.Cu" "In13.Cu" "In15.Cu")
		(hatch none 0.5)
		(connect_pads
			(clearance 0)
		)
		(min_thickness 0.25)
		(keepout
			(tracks not_allowed)
			(vias allowed)
			(pads allowed)
			(copperpour not_allowed)
			(footprints allowed)
		)
		(placement
			(enabled no)
			(sheetname "")
		)
		(fill yes
			(thermal_gap 0.5)
			(thermal_bridge_width 0.5)
			(island_removal_mode 0)
		)
		(polygon
			(pts
				(arc
					(start 292.614096 -229.63505)
					(mid 291.946076 -229.63505)
					(end 292.614096 -229.63505)
				)
			)
		)
	)
	(zone
		(layers "B.Cu" "In4.Cu" "In6.Cu" "In11.Cu" "In13.Cu" "In15.Cu")
		(hatch none 0.5)
		(connect_pads
			(clearance 0)
		)
		(min_thickness 0.25)
		(keepout
			(tracks not_allowed)
			(vias allowed)
			(pads allowed)
			(copperpour not_allowed)
			(footprints allowed)
		)
		(placement
			(enabled no)
			(sheetname "")
		)
		(fill yes
			(thermal_gap 0.5)
			(thermal_bridge_width 0.5)
			(island_removal_mode 0)
		)
		(polygon
			(pts
				(arc
					(start 44.674028 -269.58544)
					(mid 44.006008 -269.58544)
					(end 44.674028 -269.58544)
				)
			)
		)
	)
	(zone
		(layers "B.Cu" "In4.Cu" "In6.Cu" "In11.Cu" "In13.Cu" "In15.Cu")
		(hatch none 0.5)
		(connect_pads
			(clearance 0)
		)
		(min_thickness 0.25)
		(keepout
			(tracks not_allowed)
			(vias allowed)
			(pads allowed)
			(copperpour not_allowed)
			(footprints allowed)
		)
		(placement
			(enabled no)
			(sheetname "")
		)
		(fill yes
			(thermal_gap 0.5)
			(thermal_bridge_width 0.5)
			(island_removal_mode 0)
		)
		(polygon
			(pts
				(arc
					(start 179.850034 -227.935282)
					(mid 179.182014 -227.935282)
					(end 179.850034 -227.935282)
				)
			)
		)
	)
	(zone
		(layers "B.Cu" "In4.Cu" "In6.Cu" "In11.Cu" "In13.Cu" "In15.Cu")
		(hatch none 0.5)
		(connect_pads
			(clearance 0)
		)
		(min_thickness 0.25)
		(keepout
			(tracks not_allowed)
			(vias allowed)
			(pads allowed)
			(copperpour not_allowed)
			(footprints allowed)
		)
		(placement
			(enabled no)
			(sheetname "")
		)
		(fill yes
			(thermal_gap 0.5)
			(thermal_bridge_width 0.5)
			(island_removal_mode 0)
		)
		(polygon
			(pts
				(arc
					(start 376.30989 -270.036036)
					(mid 375.67997 -270.036036)
					(end 376.30989 -270.036036)
				)
			)
		)
	)
	(zone
		(layers "B.Cu" "In4.Cu" "In6.Cu" "In11.Cu" "In13.Cu" "In15.Cu")
		(hatch none 0.5)
		(connect_pads
			(clearance 0)
		)
		(min_thickness 0.25)
		(keepout
			(tracks not_allowed)
			(vias allowed)
			(pads allowed)
			(copperpour not_allowed)
			(footprints allowed)
		)
		(placement
			(enabled no)
			(sheetname "")
		)
		(fill yes
			(thermal_gap 0.5)
			(thermal_bridge_width 0.5)
			(island_removal_mode 0)
		)
		(polygon
			(pts
				(arc
					(start 377.88977 -244.484144)
					(mid 377.25985 -244.484144)
					(end 377.88977 -244.484144)
				)
			)
		)
	)
	(zone
		(layers "B.Cu" "In4.Cu" "In6.Cu" "In11.Cu" "In13.Cu" "In15.Cu")
		(hatch none 0.5)
		(connect_pads
			(clearance 0)
		)
		(min_thickness 0.25)
		(keepout
			(tracks not_allowed)
			(vias allowed)
			(pads allowed)
			(copperpour not_allowed)
			(footprints allowed)
		)
		(placement
			(enabled no)
			(sheetname "")
		)
		(fill yes
			(thermal_gap 0.5)
			(thermal_bridge_width 0.5)
			(island_removal_mode 0)
		)
		(polygon
			(pts
				(arc
					(start 376.009662 -236.384084)
					(mid 375.379742 -236.384084)
					(end 376.009662 -236.384084)
				)
			)
		)
	)
	(zone
		(layers "B.Cu" "In4.Cu" "In6.Cu" "In11.Cu" "In13.Cu" "In15.Cu")
		(hatch none 0.5)
		(connect_pads
			(clearance 0)
		)
		(min_thickness 0.25)
		(keepout
			(tracks not_allowed)
			(vias allowed)
			(pads allowed)
			(copperpour not_allowed)
			(footprints allowed)
		)
		(placement
			(enabled no)
			(sheetname "")
		)
		(fill yes
			(thermal_gap 0.5)
			(thermal_bridge_width 0.5)
			(island_removal_mode 0)
		)
		(polygon
			(pts
				(arc
					(start 94.536006 -286.23641)
					(mid 93.906086 -286.23641)
					(end 94.536006 -286.23641)
				)
			)
		)
	)
	(zone
		(layers "B.Cu" "In4.Cu" "In6.Cu" "In11.Cu" "In13.Cu" "In15.Cu")
		(hatch none 0.5)
		(connect_pads
			(clearance 0)
		)
		(min_thickness 0.25)
		(keepout
			(tracks not_allowed)
			(vias allowed)
			(pads allowed)
			(copperpour not_allowed)
			(footprints allowed)
		)
		(placement
			(enabled no)
			(sheetname "")
		)
		(fill yes
			(thermal_gap 0.5)
			(thermal_bridge_width 0.5)
			(island_removal_mode 0)
		)
		(polygon
			(pts
				(arc
					(start 343.586054 -246.914162)
					(mid 342.956134 -246.914162)
					(end 343.586054 -246.914162)
				)
			)
		)
	)
	(zone
		(layers "B.Cu" "In4.Cu" "In6.Cu" "In11.Cu" "In13.Cu" "In15.Cu")
		(hatch none 0.5)
		(connect_pads
			(clearance 0)
		)
		(min_thickness 0.25)
		(keepout
			(tracks not_allowed)
			(vias allowed)
			(pads allowed)
			(copperpour not_allowed)
			(footprints allowed)
		)
		(placement
			(enabled no)
			(sheetname "")
		)
		(fill yes
			(thermal_gap 0.5)
			(thermal_bridge_width 0.5)
			(island_removal_mode 0)
		)
		(polygon
			(pts
				(arc
					(start 94.236032 -255.824482)
					(mid 93.606112 -255.824482)
					(end 94.236032 -255.824482)
				)
			)
		)
	)
	(zone
		(layers "B.Cu" "In4.Cu" "In6.Cu" "In11.Cu" "In13.Cu" "In15.Cu")
		(hatch none 0.5)
		(connect_pads
			(clearance 0)
		)
		(min_thickness 0.25)
		(keepout
			(tracks not_allowed)
			(vias allowed)
			(pads allowed)
			(copperpour not_allowed)
			(footprints allowed)
		)
		(placement
			(enabled no)
			(sheetname "")
		)
		(fill yes
			(thermal_gap 0.5)
			(thermal_bridge_width 0.5)
			(island_removal_mode 0)
		)
		(polygon
			(pts
				(arc
					(start 342.476074 -287.856168)
					(mid 341.846154 -287.856168)
					(end 342.476074 -287.856168)
				)
			)
		)
	)
	(zone
		(layers "B.Cu" "In4.Cu" "In6.Cu" "In11.Cu" "In13.Cu" "In15.Cu")
		(hatch none 0.5)
		(connect_pads
			(clearance 0)
		)
		(min_thickness 0.25)
		(keepout
			(tracks not_allowed)
			(vias allowed)
			(pads allowed)
			(copperpour not_allowed)
			(footprints allowed)
		)
		(placement
			(enabled no)
			(sheetname "")
		)
		(fill yes
			(thermal_gap 0.5)
			(thermal_bridge_width 0.5)
			(island_removal_mode 0)
		)
		(polygon
			(pts
				(arc
					(start 427.790102 -198.185024)
					(mid 427.122082 -198.185024)
					(end 427.790102 -198.185024)
				)
			)
		)
	)
	(zone
		(layers "B.Cu" "In4.Cu" "In6.Cu" "In11.Cu" "In13.Cu" "In15.Cu")
		(hatch none 0.5)
		(connect_pads
			(clearance 0)
		)
		(min_thickness 0.25)
		(keepout
			(tracks not_allowed)
			(vias allowed)
			(pads allowed)
			(copperpour not_allowed)
			(footprints allowed)
		)
		(placement
			(enabled no)
			(sheetname "")
		)
		(fill yes
			(thermal_gap 0.5)
			(thermal_bridge_width 0.5)
			(island_removal_mode 0)
		)
		(polygon
			(pts
				(arc
					(start 427.790102 -246.635016)
					(mid 427.122082 -246.635016)
					(end 427.790102 -246.635016)
				)
			)
		)
	)
	(zone
		(layers "B.Cu" "In4.Cu" "In6.Cu" "In11.Cu" "In13.Cu" "In15.Cu")
		(hatch none 0.5)
		(connect_pads
			(clearance 0)
		)
		(min_thickness 0.25)
		(keepout
			(tracks not_allowed)
			(vias allowed)
			(pads allowed)
			(copperpour not_allowed)
			(footprints allowed)
		)
		(placement
			(enabled no)
			(sheetname "")
		)
		(fill yes
			(thermal_gap 0.5)
			(thermal_bridge_width 0.5)
			(island_removal_mode 0)
		)
		(polygon
			(pts
				(arc
					(start 256.261108 -208.217008)
					(mid 255.593088 -208.217008)
					(end 256.261108 -208.217008)
				)
			)
		)
	)
	(zone
		(layers "B.Cu" "In4.Cu" "In6.Cu" "In11.Cu" "In13.Cu" "In15.Cu")
		(hatch none 0.5)
		(connect_pads
			(clearance 0)
		)
		(min_thickness 0.25)
		(keepout
			(tracks not_allowed)
			(vias allowed)
			(pads allowed)
			(copperpour not_allowed)
			(footprints allowed)
		)
		(placement
			(enabled no)
			(sheetname "")
		)
		(fill yes
			(thermal_gap 0.5)
			(thermal_bridge_width 0.5)
			(island_removal_mode 0)
		)
		(polygon
			(pts
				(arc
					(start 179.850034 -211.7852)
					(mid 179.182014 -211.7852)
					(end 179.850034 -211.7852)
				)
			)
		)
	)
	(zone
		(layers "B.Cu" "In4.Cu" "In6.Cu" "In11.Cu" "In13.Cu" "In15.Cu")
		(hatch none 0.5)
		(connect_pads
			(clearance 0)
		)
		(min_thickness 0.25)
		(keepout
			(tracks not_allowed)
			(vias allowed)
			(pads allowed)
			(copperpour not_allowed)
			(footprints allowed)
		)
		(placement
			(enabled no)
			(sheetname "")
		)
		(fill yes
			(thermal_gap 0.5)
			(thermal_bridge_width 0.5)
			(island_removal_mode 0)
		)
		(polygon
			(pts
				(arc
					(start 128.539748 -250.15444)
					(mid 127.909828 -250.15444)
					(end 128.539748 -250.15444)
				)
			)
		)
	)
	(zone
		(layers "B.Cu" "In4.Cu" "In6.Cu" "In11.Cu" "In13.Cu" "In15.Cu")
		(hatch none 0.5)
		(connect_pads
			(clearance 0)
		)
		(min_thickness 0.25)
		(keepout
			(tracks not_allowed)
			(vias allowed)
			(pads allowed)
			(copperpour not_allowed)
			(footprints allowed)
		)
		(placement
			(enabled no)
			(sheetname "")
		)
		(fill yes
			(thermal_gap 0.5)
			(thermal_bridge_width 0.5)
			(island_removal_mode 0)
		)
		(polygon
			(pts
				(arc
					(start 44.674028 -223.685354)
					(mid 44.006008 -223.685354)
					(end 44.674028 -223.685354)
				)
			)
		)
	)
	(zone
		(layers "B.Cu" "In4.Cu" "In6.Cu" "In11.Cu" "In13.Cu" "In15.Cu")
		(hatch none 0.5)
		(connect_pads
			(clearance 0)
		)
		(min_thickness 0.25)
		(keepout
			(tracks not_allowed)
			(vias allowed)
			(pads allowed)
			(copperpour not_allowed)
			(footprints allowed)
		)
		(placement
			(enabled no)
			(sheetname "")
		)
		(fill yes
			(thermal_gap 0.5)
			(thermal_bridge_width 0.5)
			(island_removal_mode 0)
		)
		(polygon
			(pts
				(arc
					(start 354.696014 -294.335962)
					(mid 354.066094 -294.335962)
					(end 354.696014 -294.335962)
				)
			)
		)
	)
	(zone
		(layers "B.Cu" "In4.Cu" "In6.Cu" "In11.Cu" "In13.Cu" "In15.Cu")
		(hatch none 0.5)
		(connect_pads
			(clearance 0)
		)
		(min_thickness 0.25)
		(keepout
			(tracks not_allowed)
			(vias allowed)
			(pads allowed)
			(copperpour not_allowed)
			(footprints allowed)
		)
		(placement
			(enabled no)
			(sheetname "")
		)
		(fill yes
			(thermal_gap 0.5)
			(thermal_bridge_width 0.5)
			(island_removal_mode 0)
		)
		(polygon
			(pts
				(arc
					(start 179.850034 -232.18521)
					(mid 179.182014 -232.18521)
					(end 179.850034 -232.18521)
				)
			)
		)
	)
	(zone
		(layers "B.Cu" "In4.Cu" "In6.Cu" "In11.Cu" "In13.Cu" "In15.Cu")
		(hatch none 0.5)
		(connect_pads
			(clearance 0)
		)
		(min_thickness 0.25)
		(keepout
			(tracks not_allowed)
			(vias allowed)
			(pads allowed)
			(copperpour not_allowed)
			(footprints allowed)
		)
		(placement
			(enabled no)
			(sheetname "")
		)
		(fill yes
			(thermal_gap 0.5)
			(thermal_bridge_width 0.5)
			(island_removal_mode 0)
		)
		(polygon
			(pts
				(arc
					(start 95.645986 -242.05438)
					(mid 95.016066 -242.05438)
					(end 95.645986 -242.05438)
				)
			)
		)
	)
	(zone
		(layers "B.Cu" "In4.Cu" "In6.Cu" "In11.Cu" "In13.Cu" "In15.Cu")
		(hatch none 0.5)
		(connect_pads
			(clearance 0)
		)
		(min_thickness 0.25)
		(keepout
			(tracks not_allowed)
			(vias allowed)
			(pads allowed)
			(copperpour not_allowed)
			(footprints allowed)
		)
		(placement
			(enabled no)
			(sheetname "")
		)
		(fill yes
			(thermal_gap 0.5)
			(thermal_bridge_width 0.5)
			(island_removal_mode 0)
		)
		(polygon
			(pts
				(arc
					(start 128.369822 -265.176254)
					(mid 127.739902 -265.176254)
					(end 128.369822 -265.176254)
				)
			)
		)
	)
	(zone
		(layers "B.Cu" "In4.Cu" "In6.Cu" "In11.Cu" "In13.Cu" "In15.Cu")
		(hatch none 0.5)
		(connect_pads
			(clearance 0)
		)
		(min_thickness 0.25)
		(keepout
			(tracks not_allowed)
			(vias allowed)
			(pads allowed)
			(copperpour not_allowed)
			(footprints allowed)
		)
		(placement
			(enabled no)
			(sheetname "")
		)
		(fill yes
			(thermal_gap 0.5)
			(thermal_bridge_width 0.5)
			(island_removal_mode 0)
		)
		(polygon
			(pts
				(arc
					(start 343.886028 -270.846042)
					(mid 343.256108 -270.846042)
					(end 343.886028 -270.846042)
				)
			)
		)
	)
	(zone
		(layers "B.Cu" "In4.Cu" "In6.Cu" "In11.Cu" "In13.Cu" "In15.Cu")
		(hatch none 0.5)
		(connect_pads
			(clearance 0)
		)
		(min_thickness 0.25)
		(keepout
			(tracks not_allowed)
			(vias allowed)
			(pads allowed)
			(copperpour not_allowed)
			(footprints allowed)
		)
		(placement
			(enabled no)
			(sheetname "")
		)
		(fill yes
			(thermal_gap 0.5)
			(thermal_bridge_width 0.5)
			(island_removal_mode 0)
		)
		(polygon
			(pts
				(arc
					(start 376.30989 -276.516084)
					(mid 375.67997 -276.516084)
					(end 376.30989 -276.516084)
				)
			)
		)
	)
	(zone
		(layers "B.Cu" "In4.Cu" "In6.Cu" "In11.Cu" "In13.Cu" "In15.Cu")
		(hatch none 0.5)
		(connect_pads
			(clearance 0)
		)
		(min_thickness 0.25)
		(keepout
			(tracks not_allowed)
			(vias allowed)
			(pads allowed)
			(copperpour not_allowed)
			(footprints allowed)
		)
		(placement
			(enabled no)
			(sheetname "")
		)
		(fill yes
			(thermal_gap 0.5)
			(thermal_bridge_width 0.5)
			(island_removal_mode 0)
		)
		(polygon
			(pts
				(arc
					(start 121.31294 -33.02508)
					(mid 120.64492 -33.02508)
					(end 121.31294 -33.02508)
				)
			)
		)
	)
	(zone
		(layers "B.Cu" "In4.Cu" "In6.Cu" "In11.Cu" "In13.Cu" "In15.Cu")
		(hatch none 0.5)
		(connect_pads
			(clearance 0)
		)
		(min_thickness 0.25)
		(keepout
			(tracks not_allowed)
			(vias allowed)
			(pads allowed)
			(copperpour not_allowed)
			(footprints allowed)
		)
		(placement
			(enabled no)
			(sheetname "")
		)
		(fill yes
			(thermal_gap 0.5)
			(thermal_bridge_width 0.5)
			(island_removal_mode 0)
		)
		(polygon
			(pts
				(arc
					(start 431.89017 -279.785064)
					(mid 431.22215 -279.785064)
					(end 431.89017 -279.785064)
				)
			)
		)
	)
	(zone
		(layers "B.Cu" "In4.Cu" "In6.Cu" "In11.Cu" "In13.Cu" "In15.Cu")
		(hatch none 0.5)
		(connect_pads
			(clearance 0)
		)
		(min_thickness 0.25)
		(keepout
			(tracks not_allowed)
			(vias allowed)
			(pads allowed)
			(copperpour not_allowed)
			(footprints allowed)
		)
		(placement
			(enabled no)
			(sheetname "")
		)
		(fill yes
			(thermal_gap 0.5)
			(thermal_bridge_width 0.5)
			(island_removal_mode 0)
		)
		(polygon
			(pts
				(arc
					(start 44.674028 -261.08533)
					(mid 44.006008 -261.08533)
					(end 44.674028 -261.08533)
				)
			)
		)
	)
	(zone
		(layers "B.Cu" "In4.Cu" "In6.Cu" "In11.Cu" "In13.Cu" "In15.Cu")
		(hatch none 0.5)
		(connect_pads
			(clearance 0)
		)
		(min_thickness 0.25)
		(keepout
			(tracks not_allowed)
			(vias allowed)
			(pads allowed)
			(copperpour not_allowed)
			(footprints allowed)
		)
		(placement
			(enabled no)
			(sheetname "")
		)
		(fill yes
			(thermal_gap 0.5)
			(thermal_bridge_width 0.5)
			(island_removal_mode 0)
		)
		(polygon
			(pts
				(arc
					(start 344.055954 -241.24412)
					(mid 343.426034 -241.24412)
					(end 344.055954 -241.24412)
				)
			)
		)
	)
	(zone
		(layers "B.Cu" "In4.Cu" "In6.Cu" "In11.Cu" "In13.Cu" "In15.Cu")
		(hatch none 0.5)
		(connect_pads
			(clearance 0)
		)
		(min_thickness 0.25)
		(keepout
			(tracks not_allowed)
			(vias allowed)
			(pads allowed)
			(copperpour not_allowed)
			(footprints allowed)
		)
		(placement
			(enabled no)
			(sheetname "")
		)
		(fill yes
			(thermal_gap 0.5)
			(thermal_bridge_width 0.5)
			(island_removal_mode 0)
		)
		(polygon
			(pts
				(arc
					(start 344.055954 -244.484144)
					(mid 343.426034 -244.484144)
					(end 344.055954 -244.484144)
				)
			)
		)
	)
	(zone
		(layers "B.Cu" "In4.Cu" "In6.Cu" "In11.Cu" "In13.Cu" "In15.Cu")
		(hatch none 0.5)
		(connect_pads
			(clearance 0)
		)
		(min_thickness 0.25)
		(keepout
			(tracks not_allowed)
			(vias allowed)
			(pads allowed)
			(copperpour not_allowed)
			(footprints allowed)
		)
		(placement
			(enabled no)
			(sheetname "")
		)
		(fill yes
			(thermal_gap 0.5)
			(thermal_bridge_width 0.5)
			(island_removal_mode 0)
		)
		(polygon
			(pts
				(arc
					(start 179.850034 -308.685438)
					(mid 179.182014 -308.685438)
					(end 179.850034 -308.685438)
				)
			)
		)
	)
	(zone
		(layers "B.Cu" "In4.Cu" "In6.Cu" "In11.Cu" "In13.Cu" "In15.Cu")
		(hatch none 0.5)
		(connect_pads
			(clearance 0)
		)
		(min_thickness 0.25)
		(keepout
			(tracks not_allowed)
			(vias allowed)
			(pads allowed)
			(copperpour not_allowed)
			(footprints allowed)
		)
		(placement
			(enabled no)
			(sheetname "")
		)
		(fill yes
			(thermal_gap 0.5)
			(thermal_bridge_width 0.5)
			(island_removal_mode 0)
		)
		(polygon
			(pts
				(arc
					(start 342.646 -237.19409)
					(mid 342.01608 -237.19409)
					(end 342.646 -237.19409)
				)
			)
		)
	)
	(zone
		(layers "B.Cu" "In4.Cu" "In6.Cu" "In11.Cu" "In13.Cu" "In15.Cu")
		(hatch none 0.5)
		(connect_pads
			(clearance 0)
		)
		(min_thickness 0.25)
		(keepout
			(tracks not_allowed)
			(vias allowed)
			(pads allowed)
			(copperpour not_allowed)
			(footprints allowed)
		)
		(placement
			(enabled no)
			(sheetname "")
		)
		(fill yes
			(thermal_gap 0.5)
			(thermal_bridge_width 0.5)
			(island_removal_mode 0)
		)
		(polygon
			(pts
				(arc
					(start 431.89017 -199.035162)
					(mid 431.22215 -199.035162)
					(end 431.89017 -199.035162)
				)
			)
		)
	)
	(zone
		(layers "B.Cu" "In4.Cu" "In6.Cu" "In11.Cu" "In13.Cu" "In15.Cu")
		(hatch none 0.5)
		(connect_pads
			(clearance 0)
		)
		(min_thickness 0.25)
		(keepout
			(tracks not_allowed)
			(vias allowed)
			(pads allowed)
			(copperpour not_allowed)
			(footprints allowed)
		)
		(placement
			(enabled no)
			(sheetname "")
		)
		(fill yes
			(thermal_gap 0.5)
			(thermal_bridge_width 0.5)
			(island_removal_mode 0)
		)
		(polygon
			(pts
				(arc
					(start 342.945974 -290.285932)
					(mid 342.316054 -290.285932)
					(end 342.945974 -290.285932)
				)
			)
		)
	)
	(zone
		(layers "B.Cu" "In4.Cu" "In6.Cu" "In11.Cu" "In13.Cu" "In15.Cu")
		(hatch none 0.5)
		(connect_pads
			(clearance 0)
		)
		(min_thickness 0.25)
		(keepout
			(tracks not_allowed)
			(vias allowed)
			(pads allowed)
			(copperpour not_allowed)
			(footprints allowed)
		)
		(placement
			(enabled no)
			(sheetname "")
		)
		(fill yes
			(thermal_gap 0.5)
			(thermal_bridge_width 0.5)
			(island_removal_mode 0)
		)
		(polygon
			(pts
				(arc
					(start 96.416114 -271.656302)
					(mid 95.786194 -271.656302)
					(end 96.416114 -271.656302)
				)
			)
		)
	)
	(zone
		(layers "B.Cu" "In4.Cu" "In6.Cu" "In11.Cu" "In13.Cu" "In15.Cu")
		(hatch none 0.5)
		(connect_pads
			(clearance 0)
		)
		(min_thickness 0.25)
		(keepout
			(tracks not_allowed)
			(vias allowed)
			(pads allowed)
			(copperpour not_allowed)
			(footprints allowed)
		)
		(placement
			(enabled no)
			(sheetname "")
		)
		(fill yes
			(thermal_gap 0.5)
			(thermal_bridge_width 0.5)
			(island_removal_mode 0)
		)
		(polygon
			(pts
				(arc
					(start 95.645986 -229.094538)
					(mid 95.016066 -229.094538)
					(end 95.645986 -229.094538)
				)
			)
		)
	)
	(zone
		(layers "B.Cu" "In4.Cu" "In6.Cu" "In11.Cu" "In13.Cu" "In15.Cu")
		(hatch none 0.5)
		(connect_pads
			(clearance 0)
		)
		(min_thickness 0.25)
		(keepout
			(tracks not_allowed)
			(vias allowed)
			(pads allowed)
			(copperpour not_allowed)
			(footprints allowed)
		)
		(placement
			(enabled no)
			(sheetname "")
		)
		(fill yes
			(thermal_gap 0.5)
			(thermal_bridge_width 0.5)
			(island_removal_mode 0)
		)
		(polygon
			(pts
				(arc
					(start 378.189744 -282.996132)
					(mid 377.559824 -282.996132)
					(end 378.189744 -282.996132)
				)
			)
		)
	)
	(zone
		(layers "B.Cu" "In4.Cu" "In6.Cu" "In11.Cu" "In13.Cu" "In15.Cu")
		(hatch none 0.5)
		(connect_pads
			(clearance 0)
		)
		(min_thickness 0.25)
		(keepout
			(tracks not_allowed)
			(vias allowed)
			(pads allowed)
			(copperpour not_allowed)
			(footprints allowed)
		)
		(placement
			(enabled no)
			(sheetname "")
		)
		(fill yes
			(thermal_gap 0.5)
			(thermal_bridge_width 0.5)
			(island_removal_mode 0)
		)
		(polygon
			(pts
				(arc
					(start 292.614096 -303.585118)
					(mid 291.946076 -303.585118)
					(end 292.614096 -303.585118)
				)
			)
		)
	)
	(zone
		(layers "B.Cu" "In4.Cu" "In6.Cu" "In11.Cu" "In13.Cu" "In15.Cu")
		(hatch none 0.5)
		(connect_pads
			(clearance 0)
		)
		(min_thickness 0.25)
		(keepout
			(tracks not_allowed)
			(vias allowed)
			(pads allowed)
			(copperpour not_allowed)
			(footprints allowed)
		)
		(placement
			(enabled no)
			(sheetname "")
		)
		(fill yes
			(thermal_gap 0.5)
			(thermal_bridge_width 0.5)
			(island_removal_mode 0)
		)
		(polygon
			(pts
				(arc
					(start 378.189744 -287.856168)
					(mid 377.559824 -287.856168)
					(end 378.189744 -287.856168)
				)
			)
		)
	)
	(zone
		(layers "B.Cu" "In4.Cu" "In6.Cu" "In11.Cu" "In13.Cu" "In15.Cu")
		(hatch none 0.5)
		(connect_pads
			(clearance 0)
		)
		(min_thickness 0.25)
		(keepout
			(tracks not_allowed)
			(vias allowed)
			(pads allowed)
			(copperpour not_allowed)
			(footprints allowed)
		)
		(placement
			(enabled no)
			(sheetname "")
		)
		(fill yes
			(thermal_gap 0.5)
			(thermal_bridge_width 0.5)
			(island_removal_mode 0)
		)
		(polygon
			(pts
				(arc
					(start 95.645986 -253.394464)
					(mid 95.016066 -253.394464)
					(end 95.645986 -253.394464)
				)
			)
		)
	)
	(zone
		(layers "B.Cu" "In4.Cu" "In6.Cu" "In11.Cu" "In13.Cu" "In15.Cu")
		(hatch none 0.5)
		(connect_pads
			(clearance 0)
		)
		(min_thickness 0.25)
		(keepout
			(tracks not_allowed)
			(vias allowed)
			(pads allowed)
			(copperpour not_allowed)
			(footprints allowed)
		)
		(placement
			(enabled no)
			(sheetname "")
		)
		(fill yes
			(thermal_gap 0.5)
			(thermal_bridge_width 0.5)
			(island_removal_mode 0)
		)
		(polygon
			(pts
				(arc
					(start 378.189744 -291.095938)
					(mid 377.559824 -291.095938)
					(end 378.189744 -291.095938)
				)
			)
		)
	)
	(zone
		(layers "B.Cu" "In4.Cu" "In6.Cu" "In11.Cu" "In13.Cu" "In15.Cu")
		(hatch none 0.5)
		(connect_pads
			(clearance 0)
		)
		(min_thickness 0.25)
		(keepout
			(tracks not_allowed)
			(vias allowed)
			(pads allowed)
			(copperpour not_allowed)
			(footprints allowed)
		)
		(placement
			(enabled no)
			(sheetname "")
		)
		(fill yes
			(thermal_gap 0.5)
			(thermal_bridge_width 0.5)
			(island_removal_mode 0)
		)
		(polygon
			(pts
				(arc
					(start 128.539748 -251.774452)
					(mid 127.909828 -251.774452)
					(end 128.539748 -251.774452)
				)
			)
		)
	)
	(zone
		(layers "B.Cu" "In4.Cu" "In6.Cu" "In11.Cu" "In13.Cu" "In15.Cu")
		(hatch none 0.5)
		(connect_pads
			(clearance 0)
		)
		(min_thickness 0.25)
		(keepout
			(tracks not_allowed)
			(vias allowed)
			(pads allowed)
			(copperpour not_allowed)
			(footprints allowed)
		)
		(placement
			(enabled no)
			(sheetname "")
		)
		(fill yes
			(thermal_gap 0.5)
			(thermal_bridge_width 0.5)
			(island_removal_mode 0)
		)
		(polygon
			(pts
				(arc
					(start 94.236032 -246.10441)
					(mid 93.606112 -246.10441)
					(end 94.236032 -246.10441)
				)
			)
		)
	)
	(zone
		(layers "B.Cu" "In4.Cu" "In6.Cu" "In11.Cu" "In13.Cu" "In15.Cu")
		(hatch none 0.5)
		(connect_pads
			(clearance 0)
		)
		(min_thickness 0.25)
		(keepout
			(tracks not_allowed)
			(vias allowed)
			(pads allowed)
			(copperpour not_allowed)
			(footprints allowed)
		)
		(placement
			(enabled no)
			(sheetname "")
		)
		(fill yes
			(thermal_gap 0.5)
			(thermal_bridge_width 0.5)
			(island_removal_mode 0)
		)
		(polygon
			(pts
				(arc
					(start 129.949702 -246.10441)
					(mid 129.319782 -246.10441)
					(end 129.949702 -246.10441)
				)
			)
		)
	)
	(zone
		(layers "B.Cu" "In4.Cu" "In6.Cu" "In11.Cu" "In13.Cu" "In15.Cu")
		(hatch none 0.5)
		(connect_pads
			(clearance 0)
		)
		(min_thickness 0.25)
		(keepout
			(tracks not_allowed)
			(vias allowed)
			(pads allowed)
			(copperpour not_allowed)
			(footprints allowed)
		)
		(placement
			(enabled no)
			(sheetname "")
		)
		(fill yes
			(thermal_gap 0.5)
			(thermal_bridge_width 0.5)
			(island_removal_mode 0)
		)
		(polygon
			(pts
				(arc
					(start 362.379768 -229.094284)
					(mid 361.749848 -229.094284)
					(end 362.379768 -229.094284)
				)
			)
		)
	)
	(zone
		(layers "B.Cu" "In4.Cu" "In6.Cu" "In11.Cu" "In13.Cu" "In15.Cu")
		(hatch none 0.5)
		(connect_pads
			(clearance 0)
		)
		(min_thickness 0.25)
		(keepout
			(tracks not_allowed)
			(vias allowed)
			(pads allowed)
			(copperpour not_allowed)
			(footprints allowed)
		)
		(placement
			(enabled no)
			(sheetname "")
		)
		(fill yes
			(thermal_gap 0.5)
			(thermal_bridge_width 0.5)
			(island_removal_mode 0)
		)
		(polygon
			(pts
				(arc
					(start 378.189744 -289.475926)
					(mid 377.559824 -289.475926)
					(end 378.189744 -289.475926)
				)
			)
		)
	)
	(zone
		(layers "B.Cu" "In4.Cu" "In6.Cu" "In11.Cu" "In13.Cu" "In15.Cu")
		(hatch none 0.5)
		(connect_pads
			(clearance 0)
		)
		(min_thickness 0.25)
		(keepout
			(tracks not_allowed)
			(vias allowed)
			(pads allowed)
			(copperpour not_allowed)
			(footprints allowed)
		)
		(placement
			(enabled no)
			(sheetname "")
		)
		(fill yes
			(thermal_gap 0.5)
			(thermal_bridge_width 0.5)
			(island_removal_mode 0)
		)
		(polygon
			(pts
				(arc
					(start 128.069594 -234.764326)
					(mid 127.439674 -234.764326)
					(end 128.069594 -234.764326)
				)
			)
		)
	)
	(zone
		(layers "B.Cu" "In4.Cu" "In6.Cu" "In11.Cu" "In13.Cu" "In15.Cu")
		(hatch none 0.5)
		(connect_pads
			(clearance 0)
		)
		(min_thickness 0.25)
		(keepout
			(tracks not_allowed)
			(vias allowed)
			(pads allowed)
			(copperpour not_allowed)
			(footprints allowed)
		)
		(placement
			(enabled no)
			(sheetname "")
		)
		(fill yes
			(thermal_gap 0.5)
			(thermal_bridge_width 0.5)
			(island_removal_mode 0)
		)
		(polygon
			(pts
				(arc
					(start 342.646 -251.774198)
					(mid 342.01608 -251.774198)
					(end 342.646 -251.774198)
				)
			)
		)
	)
	(zone
		(layers "B.Cu" "In4.Cu" "In6.Cu" "In11.Cu" "In13.Cu" "In15.Cu")
		(hatch none 0.5)
		(connect_pads
			(clearance 0)
		)
		(min_thickness 0.25)
		(keepout
			(tracks not_allowed)
			(vias allowed)
			(pads allowed)
			(copperpour not_allowed)
			(footprints allowed)
		)
		(placement
			(enabled no)
			(sheetname "")
		)
		(fill yes
			(thermal_gap 0.5)
			(thermal_bridge_width 0.5)
			(island_removal_mode 0)
		)
		(polygon
			(pts
				(arc
					(start 343.886028 -272.466054)
					(mid 343.256108 -272.466054)
					(end 343.886028 -272.466054)
				)
			)
		)
	)
	(zone
		(layers "B.Cu" "In4.Cu" "In6.Cu" "In11.Cu" "In13.Cu" "In15.Cu")
		(hatch none 0.5)
		(connect_pads
			(clearance 0)
		)
		(min_thickness 0.25)
		(keepout
			(tracks not_allowed)
			(vias allowed)
			(pads allowed)
			(copperpour not_allowed)
			(footprints allowed)
		)
		(placement
			(enabled no)
			(sheetname "")
		)
		(fill yes
			(thermal_gap 0.5)
			(thermal_bridge_width 0.5)
			(island_removal_mode 0)
		)
		(polygon
			(pts
				(arc
					(start 343.586054 -243.674138)
					(mid 342.956134 -243.674138)
					(end 343.586054 -243.674138)
				)
			)
		)
	)
	(zone
		(layers "B.Cu" "In4.Cu" "In6.Cu" "In11.Cu" "In13.Cu" "In15.Cu")
		(hatch none 0.5)
		(connect_pads
			(clearance 0)
		)
		(min_thickness 0.25)
		(keepout
			(tracks not_allowed)
			(vias allowed)
			(pads allowed)
			(copperpour not_allowed)
			(footprints allowed)
		)
		(placement
			(enabled no)
			(sheetname "")
		)
		(fill yes
			(thermal_gap 0.5)
			(thermal_bridge_width 0.5)
			(island_removal_mode 0)
		)
		(polygon
			(pts
				(arc
					(start 179.345844 -45.618146)
					(mid 178.677824 -45.618146)
					(end 179.345844 -45.618146)
				)
			)
		)
	)
	(zone
		(layers "B.Cu" "In4.Cu" "In6.Cu" "In11.Cu" "In13.Cu" "In15.Cu")
		(hatch none 0.5)
		(connect_pads
			(clearance 0)
		)
		(min_thickness 0.25)
		(keepout
			(tracks not_allowed)
			(vias allowed)
			(pads allowed)
			(copperpour not_allowed)
			(footprints allowed)
		)
		(placement
			(enabled no)
			(sheetname "")
		)
		(fill yes
			(thermal_gap 0.5)
			(thermal_bridge_width 0.5)
			(island_removal_mode 0)
		)
		(polygon
			(pts
				(arc
					(start 427.790102 -284.034992)
					(mid 427.122082 -284.034992)
					(end 427.790102 -284.034992)
				)
			)
		)
	)
	(zone
		(layers "B.Cu" "In4.Cu" "In6.Cu" "In11.Cu" "In13.Cu" "In15.Cu")
		(hatch none 0.5)
		(connect_pads
			(clearance 0)
		)
		(min_thickness 0.25)
		(keepout
			(tracks not_allowed)
			(vias allowed)
			(pads allowed)
			(copperpour not_allowed)
			(footprints allowed)
		)
		(placement
			(enabled no)
			(sheetname "")
		)
		(fill yes
			(thermal_gap 0.5)
			(thermal_bridge_width 0.5)
			(island_removal_mode 0)
		)
		(polygon
			(pts
				(arc
					(start 40.57396 -276.385274)
					(mid 39.90594 -276.385274)
					(end 40.57396 -276.385274)
				)
			)
		)
	)
	(zone
		(layers "B.Cu" "In4.Cu" "In6.Cu" "In11.Cu" "In13.Cu" "In15.Cu")
		(hatch none 0.5)
		(connect_pads
			(clearance 0)
		)
		(min_thickness 0.25)
		(keepout
			(tracks not_allowed)
			(vias allowed)
			(pads allowed)
			(copperpour not_allowed)
			(footprints allowed)
		)
		(placement
			(enabled no)
			(sheetname "")
		)
		(fill yes
			(thermal_gap 0.5)
			(thermal_bridge_width 0.5)
			(island_removal_mode 0)
		)
		(polygon
			(pts
				(arc
					(start 40.57396 -246.63527)
					(mid 39.90594 -246.63527)
					(end 40.57396 -246.63527)
				)
			)
		)
	)
	(zone
		(layers "B.Cu" "In4.Cu" "In6.Cu" "In11.Cu" "In13.Cu" "In15.Cu")
		(hatch none 0.5)
		(connect_pads
			(clearance 0)
		)
		(min_thickness 0.25)
		(keepout
			(tracks not_allowed)
			(vias allowed)
			(pads allowed)
			(copperpour not_allowed)
			(footprints allowed)
		)
		(placement
			(enabled no)
			(sheetname "")
		)
		(fill yes
			(thermal_gap 0.5)
			(thermal_bridge_width 0.5)
			(island_removal_mode 0)
		)
		(polygon
			(pts
				(arc
					(start 431.89017 -298.485052)
					(mid 431.22215 -298.485052)
					(end 431.89017 -298.485052)
				)
			)
		)
	)
	(zone
		(layers "B.Cu" "In4.Cu" "In6.Cu" "In11.Cu" "In13.Cu" "In15.Cu")
		(hatch none 0.5)
		(connect_pads
			(clearance 0)
		)
		(min_thickness 0.25)
		(keepout
			(tracks not_allowed)
			(vias allowed)
			(pads allowed)
			(copperpour not_allowed)
			(footprints allowed)
		)
		(placement
			(enabled no)
			(sheetname "")
		)
		(fill yes
			(thermal_gap 0.5)
			(thermal_bridge_width 0.5)
			(island_removal_mode 0)
		)
		(polygon
			(pts
				(arc
					(start 128.369822 -266.796266)
					(mid 127.739902 -266.796266)
					(end 128.369822 -266.796266)
				)
			)
		)
	)
	(zone
		(layers "B.Cu" "In4.Cu" "In6.Cu" "In11.Cu" "In13.Cu" "In15.Cu")
		(hatch none 0.5)
		(connect_pads
			(clearance 0)
		)
		(min_thickness 0.25)
		(keepout
			(tracks not_allowed)
			(vias allowed)
			(pads allowed)
			(copperpour not_allowed)
			(footprints allowed)
		)
		(placement
			(enabled no)
			(sheetname "")
		)
		(fill yes
			(thermal_gap 0.5)
			(thermal_bridge_width 0.5)
			(island_removal_mode 0)
		)
		(polygon
			(pts
				(arc
					(start 183.950102 -199.035416)
					(mid 183.282082 -199.035416)
					(end 183.950102 -199.035416)
				)
			)
		)
	)
	(zone
		(layers "B.Cu" "In4.Cu" "In6.Cu" "In11.Cu" "In13.Cu" "In15.Cu")
		(hatch none 0.5)
		(connect_pads
			(clearance 0)
		)
		(min_thickness 0.25)
		(keepout
			(tracks not_allowed)
			(vias allowed)
			(pads allowed)
			(copperpour not_allowed)
			(footprints allowed)
		)
		(placement
			(enabled no)
			(sheetname "")
		)
		(fill yes
			(thermal_gap 0.5)
			(thermal_bridge_width 0.5)
			(island_removal_mode 0)
		)
		(polygon
			(pts
				(arc
					(start 377.719844 -267.606018)
					(mid 377.089924 -267.606018)
					(end 377.719844 -267.606018)
				)
			)
		)
	)
	(zone
		(layers "B.Cu" "In4.Cu" "In6.Cu" "In11.Cu" "In13.Cu" "In15.Cu")
		(hatch none 0.5)
		(connect_pads
			(clearance 0)
		)
		(min_thickness 0.25)
		(keepout
			(tracks not_allowed)
			(vias allowed)
			(pads allowed)
			(copperpour not_allowed)
			(footprints allowed)
		)
		(placement
			(enabled no)
			(sheetname "")
		)
		(fill yes
			(thermal_gap 0.5)
			(thermal_bridge_width 0.5)
			(island_removal_mode 0)
		)
		(polygon
			(pts
				(arc
					(start 100.176076 -294.336216)
					(mid 99.546156 -294.336216)
					(end 100.176076 -294.336216)
				)
			)
		)
	)
	(zone
		(layers "B.Cu" "In4.Cu" "In6.Cu" "In11.Cu" "In13.Cu" "In15.Cu")
		(hatch none 0.5)
		(connect_pads
			(clearance 0)
		)
		(min_thickness 0.25)
		(keepout
			(tracks not_allowed)
			(vias allowed)
			(pads allowed)
			(copperpour not_allowed)
			(footprints allowed)
		)
		(placement
			(enabled no)
			(sheetname "")
		)
		(fill yes
			(thermal_gap 0.5)
			(thermal_bridge_width 0.5)
			(island_removal_mode 0)
		)
		(polygon
			(pts
				(arc
					(start 44.674028 -294.235378)
					(mid 44.006008 -294.235378)
					(end 44.674028 -294.235378)
				)
			)
		)
	)
	(zone
		(layers "B.Cu" "In4.Cu" "In6.Cu" "In11.Cu" "In13.Cu" "In15.Cu")
		(hatch none 0.5)
		(connect_pads
			(clearance 0)
		)
		(min_thickness 0.25)
		(keepout
			(tracks not_allowed)
			(vias allowed)
			(pads allowed)
			(copperpour not_allowed)
			(footprints allowed)
		)
		(placement
			(enabled no)
			(sheetname "")
		)
		(fill yes
			(thermal_gap 0.5)
			(thermal_bridge_width 0.5)
			(island_removal_mode 0)
		)
		(polygon
			(pts
				(arc
					(start 342.476074 -266.796012)
					(mid 341.846154 -266.796012)
					(end 342.476074 -266.796012)
				)
			)
		)
	)
	(zone
		(layers "B.Cu" "In4.Cu" "In6.Cu" "In11.Cu" "In13.Cu" "In15.Cu")
		(hatch none 0.5)
		(connect_pads
			(clearance 0)
		)
		(min_thickness 0.25)
		(keepout
			(tracks not_allowed)
			(vias allowed)
			(pads allowed)
			(copperpour not_allowed)
			(footprints allowed)
		)
		(placement
			(enabled no)
			(sheetname "")
		)
		(fill yes
			(thermal_gap 0.5)
			(thermal_bridge_width 0.5)
			(island_removal_mode 0)
		)
		(polygon
			(pts
				(arc
					(start 363.319822 -229.094284)
					(mid 362.689902 -229.094284)
					(end 363.319822 -229.094284)
				)
			)
		)
	)
	(zone
		(layers "B.Cu" "In4.Cu" "In6.Cu" "In11.Cu" "In13.Cu" "In15.Cu")
		(hatch none 0.5)
		(connect_pads
			(clearance 0)
		)
		(min_thickness 0.25)
		(keepout
			(tracks not_allowed)
			(vias allowed)
			(pads allowed)
			(copperpour not_allowed)
			(footprints allowed)
		)
		(placement
			(enabled no)
			(sheetname "")
		)
		(fill yes
			(thermal_gap 0.5)
			(thermal_bridge_width 0.5)
			(island_removal_mode 0)
		)
		(polygon
			(pts
				(arc
					(start 292.614096 -289.135058)
					(mid 291.946076 -289.135058)
					(end 292.614096 -289.135058)
				)
			)
		)
	)
	(zone
		(layers "B.Cu" "In4.Cu" "In6.Cu" "In11.Cu" "In13.Cu" "In15.Cu")
		(hatch none 0.5)
		(connect_pads
			(clearance 0)
		)
		(min_thickness 0.25)
		(keepout
			(tracks not_allowed)
			(vias allowed)
			(pads allowed)
			(copperpour not_allowed)
			(footprints allowed)
		)
		(placement
			(enabled no)
			(sheetname "")
		)
		(fill yes
			(thermal_gap 0.5)
			(thermal_bridge_width 0.5)
			(island_removal_mode 0)
		)
		(polygon
			(pts
				(arc
					(start 427.790102 -253.435104)
					(mid 427.122082 -253.435104)
					(end 427.790102 -253.435104)
				)
			)
		)
	)
	(zone
		(layers "B.Cu" "In4.Cu" "In6.Cu" "In11.Cu" "In13.Cu" "In15.Cu")
		(hatch none 0.5)
		(connect_pads
			(clearance 0)
		)
		(min_thickness 0.25)
		(keepout
			(tracks not_allowed)
			(vias allowed)
			(pads allowed)
			(copperpour not_allowed)
			(footprints allowed)
		)
		(placement
			(enabled no)
			(sheetname "")
		)
		(fill yes
			(thermal_gap 0.5)
			(thermal_bridge_width 0.5)
			(island_removal_mode 0)
		)
		(polygon
			(pts
				(arc
					(start 94.705932 -253.394464)
					(mid 94.076012 -253.394464)
					(end 94.705932 -253.394464)
				)
			)
		)
	)
	(zone
		(layers "B.Cu" "In4.Cu" "In6.Cu" "In11.Cu" "In13.Cu" "In15.Cu")
		(hatch none 0.5)
		(connect_pads
			(clearance 0)
		)
		(min_thickness 0.25)
		(keepout
			(tracks not_allowed)
			(vias allowed)
			(pads allowed)
			(copperpour not_allowed)
			(footprints allowed)
		)
		(placement
			(enabled no)
			(sheetname "")
		)
		(fill yes
			(thermal_gap 0.5)
			(thermal_bridge_width 0.5)
			(island_removal_mode 0)
		)
		(polygon
			(pts
				(arc
					(start 95.005906 -274.08632)
					(mid 94.375986 -274.08632)
					(end 95.005906 -274.08632)
				)
			)
		)
	)
	(zone
		(layers "B.Cu" "In4.Cu" "In6.Cu" "In11.Cu" "In13.Cu" "In15.Cu")
		(hatch none 0.5)
		(connect_pads
			(clearance 0)
		)
		(min_thickness 0.25)
		(keepout
			(tracks not_allowed)
			(vias allowed)
			(pads allowed)
			(copperpour not_allowed)
			(footprints allowed)
		)
		(placement
			(enabled no)
			(sheetname "")
		)
		(fill yes
			(thermal_gap 0.5)
			(thermal_bridge_width 0.5)
			(island_removal_mode 0)
		)
		(polygon
			(pts
				(arc
					(start 431.89017 -315.485018)
					(mid 431.22215 -315.485018)
					(end 431.89017 -315.485018)
				)
			)
		)
	)
	(zone
		(layers "B.Cu" "In4.Cu" "In6.Cu" "In11.Cu" "In13.Cu" "In15.Cu")
		(hatch none 0.5)
		(connect_pads
			(clearance 0)
		)
		(min_thickness 0.25)
		(keepout
			(tracks not_allowed)
			(vias allowed)
			(pads allowed)
			(copperpour not_allowed)
			(footprints allowed)
		)
		(placement
			(enabled no)
			(sheetname "")
		)
		(fill yes
			(thermal_gap 0.5)
			(thermal_bridge_width 0.5)
			(island_removal_mode 0)
		)
		(polygon
			(pts
				(arc
					(start 179.345844 -46.481746)
					(mid 178.677824 -46.481746)
					(end 179.345844 -46.481746)
				)
			)
		)
	)
	(zone
		(layers "B.Cu" "In4.Cu" "In6.Cu" "In11.Cu" "In13.Cu" "In15.Cu")
		(hatch none 0.5)
		(connect_pads
			(clearance 0)
		)
		(min_thickness 0.25)
		(keepout
			(tracks not_allowed)
			(vias allowed)
			(pads allowed)
			(copperpour not_allowed)
			(footprints allowed)
		)
		(placement
			(enabled no)
			(sheetname "")
		)
		(fill yes
			(thermal_gap 0.5)
			(thermal_bridge_width 0.5)
			(island_removal_mode 0)
		)
		(polygon
			(pts
				(arc
					(start 40.57396 -213.485222)
					(mid 39.90594 -213.485222)
					(end 40.57396 -213.485222)
				)
			)
		)
	)
	(zone
		(layers "B.Cu" "In4.Cu" "In6.Cu" "In11.Cu" "In13.Cu" "In15.Cu")
		(hatch none 0.5)
		(connect_pads
			(clearance 0)
		)
		(min_thickness 0.25)
		(keepout
			(tracks not_allowed)
			(vias allowed)
			(pads allowed)
			(copperpour not_allowed)
			(footprints allowed)
		)
		(placement
			(enabled no)
			(sheetname "")
		)
		(fill yes
			(thermal_gap 0.5)
			(thermal_bridge_width 0.5)
			(island_removal_mode 0)
		)
		(polygon
			(pts
				(arc
					(start 431.89017 -210.935062)
					(mid 431.22215 -210.935062)
					(end 431.89017 -210.935062)
				)
			)
		)
	)
	(zone
		(layers "B.Cu" "In4.Cu" "In6.Cu" "In11.Cu" "In13.Cu" "In15.Cu")
		(hatch none 0.5)
		(connect_pads
			(clearance 0)
		)
		(min_thickness 0.25)
		(keepout
			(tracks not_allowed)
			(vias allowed)
			(pads allowed)
			(copperpour not_allowed)
			(footprints allowed)
		)
		(placement
			(enabled no)
			(sheetname "")
		)
		(fill yes
			(thermal_gap 0.5)
			(thermal_bridge_width 0.5)
			(island_removal_mode 0)
		)
		(polygon
			(pts
				(arc
					(start 431.89017 -296.78503)
					(mid 431.22215 -296.78503)
					(end 431.89017 -296.78503)
				)
			)
		)
	)
	(zone
		(layers "B.Cu" "In4.Cu" "In6.Cu" "In11.Cu" "In13.Cu" "In15.Cu")
		(hatch none 0.5)
		(connect_pads
			(clearance 0)
		)
		(min_thickness 0.25)
		(keepout
			(tracks not_allowed)
			(vias allowed)
			(pads allowed)
			(copperpour not_allowed)
			(footprints allowed)
		)
		(placement
			(enabled no)
			(sheetname "")
		)
		(fill yes
			(thermal_gap 0.5)
			(thermal_bridge_width 0.5)
			(island_removal_mode 0)
		)
		(polygon
			(pts
				(arc
					(start 376.009662 -254.204216)
					(mid 375.379742 -254.204216)
					(end 376.009662 -254.204216)
				)
			)
		)
	)
	(zone
		(layers "B.Cu" "In4.Cu" "In6.Cu" "In11.Cu" "In13.Cu" "In15.Cu")
		(hatch none 0.5)
		(connect_pads
			(clearance 0)
		)
		(min_thickness 0.25)
		(keepout
			(tracks not_allowed)
			(vias allowed)
			(pads allowed)
			(copperpour not_allowed)
			(footprints allowed)
		)
		(placement
			(enabled no)
			(sheetname "")
		)
		(fill yes
			(thermal_gap 0.5)
			(thermal_bridge_width 0.5)
			(island_removal_mode 0)
		)
		(polygon
			(pts
				(arc
					(start 288.514028 -284.034992)
					(mid 287.846008 -284.034992)
					(end 288.514028 -284.034992)
				)
			)
		)
	)
	(zone
		(layers "B.Cu" "In4.Cu" "In6.Cu" "In11.Cu" "In13.Cu" "In15.Cu")
		(hatch none 0.5)
		(connect_pads
			(clearance 0)
		)
		(min_thickness 0.25)
		(keepout
			(tracks not_allowed)
			(vias allowed)
			(pads allowed)
			(copperpour not_allowed)
			(footprints allowed)
		)
		(placement
			(enabled no)
			(sheetname "")
		)
		(fill yes
			(thermal_gap 0.5)
			(thermal_bridge_width 0.5)
			(island_removal_mode 0)
		)
		(polygon
			(pts
				(arc
					(start 104.876092 -292.716204)
					(mid 104.246172 -292.716204)
					(end 104.876092 -292.716204)
				)
			)
		)
	)
	(zone
		(layers "B.Cu" "In4.Cu" "In6.Cu" "In11.Cu" "In13.Cu" "In15.Cu")
		(hatch none 0.5)
		(connect_pads
			(clearance 0)
		)
		(min_thickness 0.25)
		(keepout
			(tracks not_allowed)
			(vias allowed)
			(pads allowed)
			(copperpour not_allowed)
			(footprints allowed)
		)
		(placement
			(enabled no)
			(sheetname "")
		)
		(fill yes
			(thermal_gap 0.5)
			(thermal_bridge_width 0.5)
			(island_removal_mode 0)
		)
		(polygon
			(pts
				(arc
					(start 179.850034 -272.98523)
					(mid 179.182014 -272.98523)
					(end 179.850034 -272.98523)
				)
			)
		)
	)
	(zone
		(layers "B.Cu" "In4.Cu" "In6.Cu" "In11.Cu" "In13.Cu" "In15.Cu")
		(hatch none 0.5)
		(connect_pads
			(clearance 0)
		)
		(min_thickness 0.25)
		(keepout
			(tracks not_allowed)
			(vias allowed)
			(pads allowed)
			(copperpour not_allowed)
			(footprints allowed)
		)
		(placement
			(enabled no)
			(sheetname "")
		)
		(fill yes
			(thermal_gap 0.5)
			(thermal_bridge_width 0.5)
			(island_removal_mode 0)
		)
		(polygon
			(pts
				(arc
					(start 183.950102 -204.985366)
					(mid 183.282082 -204.985366)
					(end 183.950102 -204.985366)
				)
			)
		)
	)
	(zone
		(layers "B.Cu" "In4.Cu" "In6.Cu" "In11.Cu" "In13.Cu" "In15.Cu")
		(hatch none 0.5)
		(connect_pads
			(clearance 0)
		)
		(min_thickness 0.25)
		(keepout
			(tracks not_allowed)
			(vias allowed)
			(pads allowed)
			(copperpour not_allowed)
			(footprints allowed)
		)
		(placement
			(enabled no)
			(sheetname "")
		)
		(fill yes
			(thermal_gap 0.5)
			(thermal_bridge_width 0.5)
			(island_removal_mode 0)
		)
		(polygon
			(pts
				(arc
					(start 128.369822 -278.13635)
					(mid 127.739902 -278.13635)
					(end 128.369822 -278.13635)
				)
			)
		)
	)
	(zone
		(layers "B.Cu" "In4.Cu" "In6.Cu" "In11.Cu" "In13.Cu" "In15.Cu")
		(hatch none 0.5)
		(connect_pads
			(clearance 0)
		)
		(min_thickness 0.25)
		(keepout
			(tracks not_allowed)
			(vias allowed)
			(pads allowed)
			(copperpour not_allowed)
			(footprints allowed)
		)
		(placement
			(enabled no)
			(sheetname "")
		)
		(fill yes
			(thermal_gap 0.5)
			(thermal_bridge_width 0.5)
			(island_removal_mode 0)
		)
		(polygon
			(pts
				(arc
					(start 40.57396 -253.435358)
					(mid 39.90594 -253.435358)
					(end 40.57396 -253.435358)
				)
			)
		)
	)
	(zone
		(layers "B.Cu" "In4.Cu" "In6.Cu" "In11.Cu" "In13.Cu" "In15.Cu")
		(hatch none 0.5)
		(connect_pads
			(clearance 0)
		)
		(min_thickness 0.25)
		(keepout
			(tracks not_allowed)
			(vias allowed)
			(pads allowed)
			(copperpour not_allowed)
			(footprints allowed)
		)
		(placement
			(enabled no)
			(sheetname "")
		)
		(fill yes
			(thermal_gap 0.5)
			(thermal_bridge_width 0.5)
			(island_removal_mode 0)
		)
		(polygon
			(pts
				(arc
					(start 179.850034 -215.185244)
					(mid 179.182014 -215.185244)
					(end 179.850034 -215.185244)
				)
			)
		)
	)
	(zone
		(layers "B.Cu" "In4.Cu" "In6.Cu" "In11.Cu" "In13.Cu" "In15.Cu")
		(hatch none 0.5)
		(connect_pads
			(clearance 0)
		)
		(min_thickness 0.25)
		(keepout
			(tracks not_allowed)
			(vias allowed)
			(pads allowed)
			(copperpour not_allowed)
			(footprints allowed)
		)
		(placement
			(enabled no)
			(sheetname "")
		)
		(fill yes
			(thermal_gap 0.5)
			(thermal_bridge_width 0.5)
			(island_removal_mode 0)
		)
		(polygon
			(pts
				(arc
					(start 129.479802 -246.914416)
					(mid 128.849882 -246.914416)
					(end 129.479802 -246.914416)
				)
			)
		)
	)
	(zone
		(layers "B.Cu" "In4.Cu" "In6.Cu" "In11.Cu" "In13.Cu" "In15.Cu")
		(hatch none 0.5)
		(connect_pads
			(clearance 0)
		)
		(min_thickness 0.25)
		(keepout
			(tracks not_allowed)
			(vias allowed)
			(pads allowed)
			(copperpour not_allowed)
			(footprints allowed)
		)
		(placement
			(enabled no)
			(sheetname "")
		)
		(fill yes
			(thermal_gap 0.5)
			(thermal_bridge_width 0.5)
			(island_removal_mode 0)
		)
		(polygon
			(pts
				(arc
					(start 342.1761 -233.14406)
					(mid 341.54618 -233.14406)
					(end 342.1761 -233.14406)
				)
			)
		)
	)
	(zone
		(layers "B.Cu" "In4.Cu" "In6.Cu" "In11.Cu" "In13.Cu" "In15.Cu")
		(hatch none 0.5)
		(connect_pads
			(clearance 0)
		)
		(min_thickness 0.25)
		(keepout
			(tracks not_allowed)
			(vias allowed)
			(pads allowed)
			(copperpour not_allowed)
			(footprints allowed)
		)
		(placement
			(enabled no)
			(sheetname "")
		)
		(fill yes
			(thermal_gap 0.5)
			(thermal_bridge_width 0.5)
			(island_removal_mode 0)
		)
		(polygon
			(pts
				(arc
					(start 97.995994 -226.66452)
					(mid 97.366074 -226.66452)
					(end 97.995994 -226.66452)
				)
			)
		)
	)
	(zone
		(layers "B.Cu" "In4.Cu" "In6.Cu" "In11.Cu" "In13.Cu" "In15.Cu")
		(hatch none 0.5)
		(connect_pads
			(clearance 0)
		)
		(min_thickness 0.25)
		(keepout
			(tracks not_allowed)
			(vias allowed)
			(pads allowed)
			(copperpour not_allowed)
			(footprints allowed)
		)
		(placement
			(enabled no)
			(sheetname "")
		)
		(fill yes
			(thermal_gap 0.5)
			(thermal_bridge_width 0.5)
			(island_removal_mode 0)
		)
		(polygon
			(pts
				(arc
					(start 128.369822 -279.756362)
					(mid 127.739902 -279.756362)
					(end 128.369822 -279.756362)
				)
			)
		)
	)
	(zone
		(layers "B.Cu" "In4.Cu" "In6.Cu" "In11.Cu" "In13.Cu" "In15.Cu")
		(hatch none 0.5)
		(connect_pads
			(clearance 0)
		)
		(min_thickness 0.25)
		(keepout
			(tracks not_allowed)
			(vias allowed)
			(pads allowed)
			(copperpour not_allowed)
			(footprints allowed)
		)
		(placement
			(enabled no)
			(sheetname "")
		)
		(fill yes
			(thermal_gap 0.5)
			(thermal_bridge_width 0.5)
			(island_removal_mode 0)
		)
		(polygon
			(pts
				(arc
					(start 342.646 -253.39421)
					(mid 342.01608 -253.39421)
					(end 342.646 -253.39421)
				)
			)
		)
	)
	(zone
		(layers "B.Cu" "In4.Cu" "In6.Cu" "In11.Cu" "In13.Cu" "In15.Cu")
		(hatch none 0.5)
		(connect_pads
			(clearance 0)
		)
		(min_thickness 0.25)
		(keepout
			(tracks not_allowed)
			(vias allowed)
			(pads allowed)
			(copperpour not_allowed)
			(footprints allowed)
		)
		(placement
			(enabled no)
			(sheetname "")
		)
		(fill yes
			(thermal_gap 0.5)
			(thermal_bridge_width 0.5)
			(island_removal_mode 0)
		)
		(polygon
			(pts
				(arc
					(start 183.950102 -238.135414)
					(mid 183.282082 -238.135414)
					(end 183.950102 -238.135414)
				)
			)
		)
	)
	(zone
		(layers "B.Cu" "In4.Cu" "In6.Cu" "In11.Cu" "In13.Cu" "In15.Cu")
		(hatch none 0.5)
		(connect_pads
			(clearance 0)
		)
		(min_thickness 0.25)
		(keepout
			(tracks not_allowed)
			(vias allowed)
			(pads allowed)
			(copperpour not_allowed)
			(footprints allowed)
		)
		(placement
			(enabled no)
			(sheetname "")
		)
		(fill yes
			(thermal_gap 0.5)
			(thermal_bridge_width 0.5)
			(island_removal_mode 0)
		)
		(polygon
			(pts
				(arc
					(start 129.779776 -275.706332)
					(mid 129.149856 -275.706332)
					(end 129.779776 -275.706332)
				)
			)
		)
	)
	(zone
		(layers "B.Cu" "In4.Cu" "In6.Cu" "In11.Cu" "In13.Cu" "In15.Cu")
		(hatch none 0.5)
		(connect_pads
			(clearance 0)
		)
		(min_thickness 0.25)
		(keepout
			(tracks not_allowed)
			(vias allowed)
			(pads allowed)
			(copperpour not_allowed)
			(footprints allowed)
		)
		(placement
			(enabled no)
			(sheetname "")
		)
		(fill yes
			(thermal_gap 0.5)
			(thermal_bridge_width 0.5)
			(island_removal_mode 0)
		)
		(polygon
			(pts
				(arc
					(start 179.850034 -277.235412)
					(mid 179.182014 -277.235412)
					(end 179.850034 -277.235412)
				)
			)
		)
	)
	(zone
		(layers "B.Cu" "In4.Cu" "In6.Cu" "In11.Cu" "In13.Cu" "In15.Cu")
		(hatch none 0.5)
		(connect_pads
			(clearance 0)
		)
		(min_thickness 0.25)
		(keepout
			(tracks not_allowed)
			(vias allowed)
			(pads allowed)
			(copperpour not_allowed)
			(footprints allowed)
		)
		(placement
			(enabled no)
			(sheetname "")
		)
		(fill yes
			(thermal_gap 0.5)
			(thermal_bridge_width 0.5)
			(island_removal_mode 0)
		)
		(polygon
			(pts
				(arc
					(start 376.77979 -288.66592)
					(mid 376.14987 -288.66592)
					(end 376.77979 -288.66592)
				)
			)
		)
	)
	(zone
		(layers "B.Cu" "In4.Cu" "In6.Cu" "In11.Cu" "In13.Cu" "In15.Cu")
		(hatch none 0.5)
		(connect_pads
			(clearance 0)
		)
		(min_thickness 0.25)
		(keepout
			(tracks not_allowed)
			(vias allowed)
			(pads allowed)
			(copperpour not_allowed)
			(footprints allowed)
		)
		(placement
			(enabled no)
			(sheetname "")
		)
		(fill yes
			(thermal_gap 0.5)
			(thermal_bridge_width 0.5)
			(island_removal_mode 0)
		)
		(polygon
			(pts
				(arc
					(start 376.30989 -281.37612)
					(mid 375.67997 -281.37612)
					(end 376.30989 -281.37612)
				)
			)
		)
	)
	(zone
		(layers "B.Cu" "In4.Cu" "In6.Cu" "In11.Cu" "In13.Cu" "In15.Cu")
		(hatch none 0.5)
		(connect_pads
			(clearance 0)
		)
		(min_thickness 0.25)
		(keepout
			(tracks not_allowed)
			(vias allowed)
			(pads allowed)
			(copperpour not_allowed)
			(footprints allowed)
		)
		(placement
			(enabled no)
			(sheetname "")
		)
		(fill yes
			(thermal_gap 0.5)
			(thermal_bridge_width 0.5)
			(island_removal_mode 0)
		)
		(polygon
			(pts
				(arc
					(start 292.614096 -317.18504)
					(mid 291.946076 -317.18504)
					(end 292.614096 -317.18504)
				)
			)
		)
	)
	(zone
		(layers "B.Cu" "In4.Cu" "In6.Cu" "In11.Cu" "In13.Cu" "In15.Cu")
		(hatch none 0.5)
		(connect_pads
			(clearance 0)
		)
		(min_thickness 0.25)
		(keepout
			(tracks not_allowed)
			(vias allowed)
			(pads allowed)
			(copperpour not_allowed)
			(footprints allowed)
		)
		(placement
			(enabled no)
			(sheetname "")
		)
		(fill yes
			(thermal_gap 0.5)
			(thermal_bridge_width 0.5)
			(island_removal_mode 0)
		)
		(polygon
			(pts
				(arc
					(start 427.790102 -304.435002)
					(mid 427.122082 -304.435002)
					(end 427.790102 -304.435002)
				)
			)
		)
	)
	(zone
		(layers "B.Cu" "In4.Cu" "In6.Cu" "In11.Cu" "In13.Cu" "In15.Cu")
		(hatch none 0.5)
		(connect_pads
			(clearance 0)
		)
		(min_thickness 0.25)
		(keepout
			(tracks not_allowed)
			(vias allowed)
			(pads allowed)
			(copperpour not_allowed)
			(footprints allowed)
		)
		(placement
			(enabled no)
			(sheetname "")
		)
		(fill yes
			(thermal_gap 0.5)
			(thermal_bridge_width 0.5)
			(island_removal_mode 0)
		)
		(polygon
			(pts
				(arc
					(start 40.57396 -306.985416)
					(mid 39.90594 -306.985416)
					(end 40.57396 -306.985416)
				)
			)
		)
	)
	(zone
		(layers "B.Cu" "In4.Cu" "In6.Cu" "In11.Cu" "In13.Cu" "In15.Cu")
		(hatch none 0.5)
		(connect_pads
			(clearance 0)
		)
		(min_thickness 0.25)
		(keepout
			(tracks not_allowed)
			(vias allowed)
			(pads allowed)
			(copperpour not_allowed)
			(footprints allowed)
		)
		(placement
			(enabled no)
			(sheetname "")
		)
		(fill yes
			(thermal_gap 0.5)
			(thermal_bridge_width 0.5)
			(island_removal_mode 0)
		)
		(polygon
			(pts
				(arc
					(start 292.614096 -294.235124)
					(mid 291.946076 -294.235124)
					(end 292.614096 -294.235124)
				)
			)
		)
	)
	(zone
		(layers "B.Cu" "In4.Cu" "In6.Cu" "In11.Cu" "In13.Cu" "In15.Cu")
		(hatch none 0.5)
		(connect_pads
			(clearance 0)
		)
		(min_thickness 0.25)
		(keepout
			(tracks not_allowed)
			(vias allowed)
			(pads allowed)
			(copperpour not_allowed)
			(footprints allowed)
		)
		(placement
			(enabled no)
			(sheetname "")
		)
		(fill yes
			(thermal_gap 0.5)
			(thermal_bridge_width 0.5)
			(island_removal_mode 0)
		)
		(polygon
			(pts
				(arc
					(start 183.950102 -303.585372)
					(mid 183.282082 -303.585372)
					(end 183.950102 -303.585372)
				)
			)
		)
	)
	(zone
		(layers "B.Cu" "In4.Cu" "In6.Cu" "In11.Cu" "In13.Cu" "In15.Cu")
		(hatch none 0.5)
		(connect_pads
			(clearance 0)
		)
		(min_thickness 0.25)
		(keepout
			(tracks not_allowed)
			(vias allowed)
			(pads allowed)
			(copperpour not_allowed)
			(footprints allowed)
		)
		(placement
			(enabled no)
			(sheetname "")
		)
		(fill yes
			(thermal_gap 0.5)
			(thermal_bridge_width 0.5)
			(island_removal_mode 0)
		)
		(polygon
			(pts
				(arc
					(start 427.790102 -233.884978)
					(mid 427.122082 -233.884978)
					(end 427.790102 -233.884978)
				)
			)
		)
	)
	(zone
		(layers "B.Cu" "In4.Cu" "In6.Cu" "In11.Cu" "In13.Cu" "In15.Cu")
		(hatch none 0.5)
		(connect_pads
			(clearance 0)
		)
		(min_thickness 0.25)
		(keepout
			(tracks not_allowed)
			(vias allowed)
			(pads allowed)
			(copperpour not_allowed)
			(footprints allowed)
		)
		(placement
			(enabled no)
			(sheetname "")
		)
		(fill yes
			(thermal_gap 0.5)
			(thermal_bridge_width 0.5)
			(island_removal_mode 0)
		)
		(polygon
			(pts
				(arc
					(start 130.249676 -266.796266)
					(mid 129.619756 -266.796266)
					(end 130.249676 -266.796266)
				)
			)
		)
	)
	(zone
		(layers "B.Cu" "In4.Cu" "In6.Cu" "In11.Cu" "In13.Cu" "In15.Cu")
		(hatch none 0.5)
		(connect_pads
			(clearance 0)
		)
		(min_thickness 0.25)
		(keepout
			(tracks not_allowed)
			(vias allowed)
			(pads allowed)
			(copperpour not_allowed)
			(footprints allowed)
		)
		(placement
			(enabled no)
			(sheetname "")
		)
		(fill yes
			(thermal_gap 0.5)
			(thermal_bridge_width 0.5)
			(island_removal_mode 0)
		)
		(polygon
			(pts
				(arc
					(start 427.790102 -282.33497)
					(mid 427.122082 -282.33497)
					(end 427.790102 -282.33497)
				)
			)
		)
	)
	(zone
		(layers "B.Cu" "In4.Cu" "In6.Cu" "In11.Cu" "In13.Cu" "In15.Cu")
		(hatch none 0.5)
		(connect_pads
			(clearance 0)
		)
		(min_thickness 0.25)
		(keepout
			(tracks not_allowed)
			(vias allowed)
			(pads allowed)
			(copperpour not_allowed)
			(footprints allowed)
		)
		(placement
			(enabled no)
			(sheetname "")
		)
		(fill yes
			(thermal_gap 0.5)
			(thermal_bridge_width 0.5)
			(island_removal_mode 0)
		)
		(polygon
			(pts
				(arc
					(start 342.646 -248.534174)
					(mid 342.01608 -248.534174)
					(end 342.646 -248.534174)
				)
			)
		)
	)
	(zone
		(layers "B.Cu" "In4.Cu" "In6.Cu" "In11.Cu" "In13.Cu" "In15.Cu")
		(hatch none 0.5)
		(connect_pads
			(clearance 0)
		)
		(min_thickness 0.25)
		(keepout
			(tracks not_allowed)
			(vias allowed)
			(pads allowed)
			(copperpour not_allowed)
			(footprints allowed)
		)
		(placement
			(enabled no)
			(sheetname "")
		)
		(fill yes
			(thermal_gap 0.5)
			(thermal_bridge_width 0.5)
			(island_removal_mode 0)
		)
		(polygon
			(pts
				(arc
					(start 347.17609 -292.71595)
					(mid 346.54617 -292.71595)
					(end 347.17609 -292.71595)
				)
			)
		)
	)
	(zone
		(layers "B.Cu" "In4.Cu" "In6.Cu" "In11.Cu" "In13.Cu" "In15.Cu")
		(hatch none 0.5)
		(connect_pads
			(clearance 0)
		)
		(min_thickness 0.25)
		(keepout
			(tracks not_allowed)
			(vias allowed)
			(pads allowed)
			(copperpour not_allowed)
			(footprints allowed)
		)
		(placement
			(enabled no)
			(sheetname "")
		)
		(fill yes
			(thermal_gap 0.5)
			(thermal_bridge_width 0.5)
			(island_removal_mode 0)
		)
		(polygon
			(pts
				(arc
					(start 288.514028 -277.235158)
					(mid 287.846008 -277.235158)
					(end 288.514028 -277.235158)
				)
			)
		)
	)
	(zone
		(layers "B.Cu" "In4.Cu" "In6.Cu" "In11.Cu" "In13.Cu" "In15.Cu")
		(hatch none 0.5)
		(connect_pads
			(clearance 0)
		)
		(min_thickness 0.25)
		(keepout
			(tracks not_allowed)
			(vias allowed)
			(pads allowed)
			(copperpour not_allowed)
			(footprints allowed)
		)
		(placement
			(enabled no)
			(sheetname "")
		)
		(fill yes
			(thermal_gap 0.5)
			(thermal_bridge_width 0.5)
			(island_removal_mode 0)
		)
		(polygon
			(pts
				(arc
					(start 342.945974 -262.745982)
					(mid 342.316054 -262.745982)
					(end 342.945974 -262.745982)
				)
			)
		)
	)
	(zone
		(layers "B.Cu" "In4.Cu" "In6.Cu" "In11.Cu" "In13.Cu" "In15.Cu")
		(hatch none 0.5)
		(connect_pads
			(clearance 0)
		)
		(min_thickness 0.25)
		(keepout
			(tracks not_allowed)
			(vias allowed)
			(pads allowed)
			(copperpour not_allowed)
			(footprints allowed)
		)
		(placement
			(enabled no)
			(sheetname "")
		)
		(fill yes
			(thermal_gap 0.5)
			(thermal_bridge_width 0.5)
			(island_removal_mode 0)
		)
		(polygon
			(pts
				(arc
					(start 97.995994 -231.524302)
					(mid 97.366074 -231.524302)
					(end 97.995994 -231.524302)
				)
			)
		)
	)
	(zone
		(layers "B.Cu" "In4.Cu" "In6.Cu" "In11.Cu" "In13.Cu" "In15.Cu")
		(hatch none 0.5)
		(connect_pads
			(clearance 0)
		)
		(min_thickness 0.25)
		(keepout
			(tracks not_allowed)
			(vias allowed)
			(pads allowed)
			(copperpour not_allowed)
			(footprints allowed)
		)
		(placement
			(enabled no)
			(sheetname "")
		)
		(fill yes
			(thermal_gap 0.5)
			(thermal_bridge_width 0.5)
			(island_removal_mode 0)
		)
		(polygon
			(pts
				(arc
					(start 288.514028 -291.684964)
					(mid 287.846008 -291.684964)
					(end 288.514028 -291.684964)
				)
			)
		)
	)
	(zone
		(layers "B.Cu" "In4.Cu" "In6.Cu" "In11.Cu" "In13.Cu" "In15.Cu")
		(hatch none 0.5)
		(connect_pads
			(clearance 0)
		)
		(min_thickness 0.25)
		(keepout
			(tracks not_allowed)
			(vias allowed)
			(pads allowed)
			(copperpour not_allowed)
			(footprints allowed)
		)
		(placement
			(enabled no)
			(sheetname "")
		)
		(fill yes
			(thermal_gap 0.5)
			(thermal_bridge_width 0.5)
			(island_removal_mode 0)
		)
		(polygon
			(pts
				(arc
					(start 179.850034 -268.735302)
					(mid 179.182014 -268.735302)
					(end 179.850034 -268.735302)
				)
			)
		)
	)
	(zone
		(layers "B.Cu" "In4.Cu" "In6.Cu" "In11.Cu" "In13.Cu" "In15.Cu")
		(hatch none 0.5)
		(connect_pads
			(clearance 0)
		)
		(min_thickness 0.25)
		(keepout
			(tracks not_allowed)
			(vias allowed)
			(pads allowed)
			(copperpour not_allowed)
			(footprints allowed)
		)
		(placement
			(enabled no)
			(sheetname "")
		)
		(fill yes
			(thermal_gap 0.5)
			(thermal_bridge_width 0.5)
			(island_removal_mode 0)
		)
		(polygon
			(pts
				(arc
					(start 179.850034 -295.085262)
					(mid 179.182014 -295.085262)
					(end 179.850034 -295.085262)
				)
			)
		)
	)
	(zone
		(layers "B.Cu" "In4.Cu" "In6.Cu" "In11.Cu" "In13.Cu" "In15.Cu")
		(hatch none 0.5)
		(connect_pads
			(clearance 0)
		)
		(min_thickness 0.25)
		(keepout
			(tracks not_allowed)
			(vias allowed)
			(pads allowed)
			(copperpour not_allowed)
			(footprints allowed)
		)
		(placement
			(enabled no)
			(sheetname "")
		)
		(fill yes
			(thermal_gap 0.5)
			(thermal_bridge_width 0.5)
			(island_removal_mode 0)
		)
		(polygon
			(pts
				(arc
					(start 431.89017 -301.885096)
					(mid 431.22215 -301.885096)
					(end 431.89017 -301.885096)
				)
			)
		)
	)
	(zone
		(layers "B.Cu" "In4.Cu" "In6.Cu" "In11.Cu" "In13.Cu" "In15.Cu")
		(hatch none 0.5)
		(connect_pads
			(clearance 0)
		)
		(min_thickness 0.25)
		(keepout
			(tracks not_allowed)
			(vias allowed)
			(pads allowed)
			(copperpour not_allowed)
			(footprints allowed)
		)
		(placement
			(enabled no)
			(sheetname "")
		)
		(fill yes
			(thermal_gap 0.5)
			(thermal_bridge_width 0.5)
			(island_removal_mode 0)
		)
		(polygon
			(pts
				(arc
					(start 40.57396 -265.335258)
					(mid 39.90594 -265.335258)
					(end 40.57396 -265.335258)
				)
			)
		)
	)
	(zone
		(layers "B.Cu" "In4.Cu" "In6.Cu" "In11.Cu" "In13.Cu" "In15.Cu")
		(hatch none 0.5)
		(connect_pads
			(clearance 0)
		)
		(min_thickness 0.25)
		(keepout
			(tracks not_allowed)
			(vias allowed)
			(pads allowed)
			(copperpour not_allowed)
			(footprints allowed)
		)
		(placement
			(enabled no)
			(sheetname "")
		)
		(fill yes
			(thermal_gap 0.5)
			(thermal_bridge_width 0.5)
			(island_removal_mode 0)
		)
		(polygon
			(pts
				(arc
					(start 129.949702 -254.20447)
					(mid 129.319782 -254.20447)
					(end 129.949702 -254.20447)
				)
			)
		)
	)
	(zone
		(layers "B.Cu" "In4.Cu" "In6.Cu" "In11.Cu" "In13.Cu" "In15.Cu")
		(hatch none 0.5)
		(connect_pads
			(clearance 0)
		)
		(min_thickness 0.25)
		(keepout
			(tracks not_allowed)
			(vias allowed)
			(pads allowed)
			(copperpour not_allowed)
			(footprints allowed)
		)
		(placement
			(enabled no)
			(sheetname "")
		)
		(fill yes
			(thermal_gap 0.5)
			(thermal_bridge_width 0.5)
			(island_removal_mode 0)
		)
		(polygon
			(pts
				(arc
					(start 431.89017 -264.48512)
					(mid 431.22215 -264.48512)
					(end 431.89017 -264.48512)
				)
			)
		)
	)
	(zone
		(layers "B.Cu" "In4.Cu" "In6.Cu" "In11.Cu" "In13.Cu" "In15.Cu")
		(hatch none 0.5)
		(connect_pads
			(clearance 0)
		)
		(min_thickness 0.25)
		(keepout
			(tracks not_allowed)
			(vias allowed)
			(pads allowed)
			(copperpour not_allowed)
			(footprints allowed)
		)
		(placement
			(enabled no)
			(sheetname "")
		)
		(fill yes
			(thermal_gap 0.5)
			(thermal_bridge_width 0.5)
			(island_removal_mode 0)
		)
		(polygon
			(pts
				(arc
					(start 349.056198 -292.71595)
					(mid 348.426278 -292.71595)
					(end 349.056198 -292.71595)
				)
			)
		)
	)
	(zone
		(layers "B.Cu" "In4.Cu" "In6.Cu" "In11.Cu" "In13.Cu" "In15.Cu")
		(hatch none 0.5)
		(connect_pads
			(clearance 0)
		)
		(min_thickness 0.25)
		(keepout
			(tracks not_allowed)
			(vias allowed)
			(pads allowed)
			(copperpour not_allowed)
			(footprints allowed)
		)
		(placement
			(enabled no)
			(sheetname "")
		)
		(fill yes
			(thermal_gap 0.5)
			(thermal_bridge_width 0.5)
			(island_removal_mode 0)
		)
		(polygon
			(pts
				(arc
					(start 179.850034 -246.63527)
					(mid 179.182014 -246.63527)
					(end 179.850034 -246.63527)
				)
			)
		)
	)
	(zone
		(layers "B.Cu" "In4.Cu" "In6.Cu" "In11.Cu" "In13.Cu" "In15.Cu")
		(hatch none 0.5)
		(connect_pads
			(clearance 0)
		)
		(min_thickness 0.25)
		(keepout
			(tracks not_allowed)
			(vias allowed)
			(pads allowed)
			(copperpour not_allowed)
			(footprints allowed)
		)
		(placement
			(enabled no)
			(sheetname "")
		)
		(fill yes
			(thermal_gap 0.5)
			(thermal_bridge_width 0.5)
			(island_removal_mode 0)
		)
		(polygon
			(pts
				(arc
					(start 343.886028 -277.32609)
					(mid 343.256108 -277.32609)
					(end 343.886028 -277.32609)
				)
			)
		)
	)
	(zone
		(layers "B.Cu" "In4.Cu" "In6.Cu" "In11.Cu" "In13.Cu" "In15.Cu")
		(hatch none 0.5)
		(connect_pads
			(clearance 0)
		)
		(min_thickness 0.25)
		(keepout
			(tracks not_allowed)
			(vias allowed)
			(pads allowed)
			(copperpour not_allowed)
			(footprints allowed)
		)
		(placement
			(enabled no)
			(sheetname "")
		)
		(fill yes
			(thermal_gap 0.5)
			(thermal_bridge_width 0.5)
			(island_removal_mode 0)
		)
		(polygon
			(pts
				(arc
					(start 431.89017 -229.63505)
					(mid 431.22215 -229.63505)
					(end 431.89017 -229.63505)
				)
			)
		)
	)
	(zone
		(layers "B.Cu" "In4.Cu" "In6.Cu" "In11.Cu" "In13.Cu" "In15.Cu")
		(hatch none 0.5)
		(connect_pads
			(clearance 0)
		)
		(min_thickness 0.25)
		(keepout
			(tracks not_allowed)
			(vias allowed)
			(pads allowed)
			(copperpour not_allowed)
			(footprints allowed)
		)
		(placement
			(enabled no)
			(sheetname "")
		)
		(fill yes
			(thermal_gap 0.5)
			(thermal_bridge_width 0.5)
			(island_removal_mode 0)
		)
		(polygon
			(pts
				(arc
					(start 96.115886 -241.244374)
					(mid 95.485966 -241.244374)
					(end 96.115886 -241.244374)
				)
			)
		)
	)
	(zone
		(layers "B.Cu" "In4.Cu" "In6.Cu" "In11.Cu" "In13.Cu" "In15.Cu")
		(hatch none 0.5)
		(connect_pads
			(clearance 0)
		)
		(min_thickness 0.25)
		(keepout
			(tracks not_allowed)
			(vias allowed)
			(pads allowed)
			(copperpour not_allowed)
			(footprints allowed)
		)
		(placement
			(enabled no)
			(sheetname "")
		)
		(fill yes
			(thermal_gap 0.5)
			(thermal_bridge_width 0.5)
			(island_removal_mode 0)
		)
		(polygon
			(pts
				(arc
					(start 44.674028 -238.985298)
					(mid 44.006008 -238.985298)
					(end 44.674028 -238.985298)
				)
			)
		)
	)
	(zone
		(layers "B.Cu" "In4.Cu" "In6.Cu" "In11.Cu" "In13.Cu" "In15.Cu")
		(hatch none 0.5)
		(connect_pads
			(clearance 0)
		)
		(min_thickness 0.25)
		(keepout
			(tracks not_allowed)
			(vias allowed)
			(pads allowed)
			(copperpour not_allowed)
			(footprints allowed)
		)
		(placement
			(enabled no)
			(sheetname "")
		)
		(fill yes
			(thermal_gap 0.5)
			(thermal_bridge_width 0.5)
			(island_removal_mode 0)
		)
		(polygon
			(pts
				(arc
					(start 129.479802 -237.194344)
					(mid 128.849882 -237.194344)
					(end 129.479802 -237.194344)
				)
			)
		)
	)
	(zone
		(layers "B.Cu" "In4.Cu" "In6.Cu" "In11.Cu" "In13.Cu" "In15.Cu")
		(hatch none 0.5)
		(connect_pads
			(clearance 0)
		)
		(min_thickness 0.25)
		(keepout
			(tracks not_allowed)
			(vias allowed)
			(pads allowed)
			(copperpour not_allowed)
			(footprints allowed)
		)
		(placement
			(enabled no)
			(sheetname "")
		)
		(fill yes
			(thermal_gap 0.5)
			(thermal_bridge_width 0.5)
			(island_removal_mode 0)
		)
		(polygon
			(pts
				(arc
					(start 129.949702 -252.584458)
					(mid 129.319782 -252.584458)
					(end 129.949702 -252.584458)
				)
			)
		)
	)
	(zone
		(layers "B.Cu" "In4.Cu" "In6.Cu" "In11.Cu" "In13.Cu" "In15.Cu")
		(hatch none 0.5)
		(connect_pads
			(clearance 0)
		)
		(min_thickness 0.25)
		(keepout
			(tracks not_allowed)
			(vias allowed)
			(pads allowed)
			(copperpour not_allowed)
			(footprints allowed)
		)
		(placement
			(enabled no)
			(sheetname "")
		)
		(fill yes
			(thermal_gap 0.5)
			(thermal_bridge_width 0.5)
			(island_removal_mode 0)
		)
		(polygon
			(pts
				(arc
					(start 183.950102 -290.835334)
					(mid 183.282082 -290.835334)
					(end 183.950102 -290.835334)
				)
			)
		)
	)
	(zone
		(layers "B.Cu" "In4.Cu" "In6.Cu" "In11.Cu" "In13.Cu" "In15.Cu")
		(hatch none 0.5)
		(connect_pads
			(clearance 0)
		)
		(min_thickness 0.25)
		(keepout
			(tracks not_allowed)
			(vias allowed)
			(pads allowed)
			(copperpour not_allowed)
			(footprints allowed)
		)
		(placement
			(enabled no)
			(sheetname "")
		)
		(fill yes
			(thermal_gap 0.5)
			(thermal_bridge_width 0.5)
			(island_removal_mode 0)
		)
		(polygon
			(pts
				(arc
					(start 431.89017 -201.585068)
					(mid 431.22215 -201.585068)
					(end 431.89017 -201.585068)
				)
			)
		)
	)
	(zone
		(layers "B.Cu" "In4.Cu" "In6.Cu" "In11.Cu" "In13.Cu" "In15.Cu")
		(hatch none 0.5)
		(connect_pads
			(clearance 0)
		)
		(min_thickness 0.25)
		(keepout
			(tracks not_allowed)
			(vias allowed)
			(pads allowed)
			(copperpour not_allowed)
			(footprints allowed)
		)
		(placement
			(enabled no)
			(sheetname "")
		)
		(fill yes
			(thermal_gap 0.5)
			(thermal_bridge_width 0.5)
			(island_removal_mode 0)
		)
		(polygon
			(pts
				(arc
					(start 128.539748 -237.194344)
					(mid 127.909828 -237.194344)
					(end 128.539748 -237.194344)
				)
			)
		)
	)
	(zone
		(layers "B.Cu" "In4.Cu" "In6.Cu" "In11.Cu" "In13.Cu" "In15.Cu")
		(hatch none 0.5)
		(connect_pads
			(clearance 0)
		)
		(min_thickness 0.25)
		(keepout
			(tracks not_allowed)
			(vias allowed)
			(pads allowed)
			(copperpour not_allowed)
			(footprints allowed)
		)
		(placement
			(enabled no)
			(sheetname "")
		)
		(fill yes
			(thermal_gap 0.5)
			(thermal_bridge_width 0.5)
			(island_removal_mode 0)
		)
		(polygon
			(pts
				(arc
					(start 128.069594 -249.344434)
					(mid 127.439674 -249.344434)
					(end 128.069594 -249.344434)
				)
			)
		)
	)
	(zone
		(layers "B.Cu" "In4.Cu" "In6.Cu" "In11.Cu" "In13.Cu" "In15.Cu")
		(hatch none 0.5)
		(connect_pads
			(clearance 0)
		)
		(min_thickness 0.25)
		(keepout
			(tracks not_allowed)
			(vias allowed)
			(pads allowed)
			(copperpour not_allowed)
			(footprints allowed)
		)
		(placement
			(enabled no)
			(sheetname "")
		)
		(fill yes
			(thermal_gap 0.5)
			(thermal_bridge_width 0.5)
			(island_removal_mode 0)
		)
		(polygon
			(pts
				(arc
					(start 128.539748 -230.71455)
					(mid 127.909828 -230.71455)
					(end 128.539748 -230.71455)
				)
			)
		)
	)
	(zone
		(layers "B.Cu" "In4.Cu" "In6.Cu" "In11.Cu" "In13.Cu" "In15.Cu")
		(hatch none 0.5)
		(connect_pads
			(clearance 0)
		)
		(min_thickness 0.25)
		(keepout
			(tracks not_allowed)
			(vias allowed)
			(pads allowed)
			(copperpour not_allowed)
			(footprints allowed)
		)
		(placement
			(enabled no)
			(sheetname "")
		)
		(fill yes
			(thermal_gap 0.5)
			(thermal_bridge_width 0.5)
			(island_removal_mode 0)
		)
		(polygon
			(pts
				(arc
					(start 183.950102 -221.985332)
					(mid 183.282082 -221.985332)
					(end 183.950102 -221.985332)
				)
			)
		)
	)
	(zone
		(layers "B.Cu" "In4.Cu" "In6.Cu" "In11.Cu" "In13.Cu" "In15.Cu")
		(hatch none 0.5)
		(connect_pads
			(clearance 0)
		)
		(min_thickness 0.25)
		(keepout
			(tracks not_allowed)
			(vias allowed)
			(pads allowed)
			(copperpour not_allowed)
			(footprints allowed)
		)
		(placement
			(enabled no)
			(sheetname "")
		)
		(fill yes
			(thermal_gap 0.5)
			(thermal_bridge_width 0.5)
			(island_removal_mode 0)
		)
		(polygon
			(pts
				(arc
					(start 94.236032 -234.764326)
					(mid 93.606112 -234.764326)
					(end 94.236032 -234.764326)
				)
			)
		)
	)
	(zone
		(layers "B.Cu" "In4.Cu" "In6.Cu" "In11.Cu" "In13.Cu" "In15.Cu")
		(hatch none 0.5)
		(connect_pads
			(clearance 0)
		)
		(min_thickness 0.25)
		(keepout
			(tracks not_allowed)
			(vias allowed)
			(pads allowed)
			(copperpour not_allowed)
			(footprints allowed)
		)
		(placement
			(enabled no)
			(sheetname "")
		)
		(fill yes
			(thermal_gap 0.5)
			(thermal_bridge_width 0.5)
			(island_removal_mode 0)
		)
		(polygon
			(pts
				(arc
					(start 288.514028 -301.034958)
					(mid 287.846008 -301.034958)
					(end 288.514028 -301.034958)
				)
			)
		)
	)
	(zone
		(layers "B.Cu" "In4.Cu" "In6.Cu" "In11.Cu" "In13.Cu" "In15.Cu")
		(hatch none 0.5)
		(connect_pads
			(clearance 0)
		)
		(min_thickness 0.25)
		(keepout
			(tracks not_allowed)
			(vias allowed)
			(pads allowed)
			(copperpour not_allowed)
			(footprints allowed)
		)
		(placement
			(enabled no)
			(sheetname "")
		)
		(fill yes
			(thermal_gap 0.5)
			(thermal_bridge_width 0.5)
			(island_removal_mode 0)
		)
		(polygon
			(pts
				(arc
					(start 95.94596 -291.906198)
					(mid 95.31604 -291.906198)
					(end 95.94596 -291.906198)
				)
			)
		)
	)
	(zone
		(layers "B.Cu" "In4.Cu" "In6.Cu" "In11.Cu" "In13.Cu" "In15.Cu")
		(hatch none 0.5)
		(connect_pads
			(clearance 0)
		)
		(min_thickness 0.25)
		(keepout
			(tracks not_allowed)
			(vias allowed)
			(pads allowed)
			(copperpour not_allowed)
			(footprints allowed)
		)
		(placement
			(enabled no)
			(sheetname "")
		)
		(fill yes
			(thermal_gap 0.5)
			(thermal_bridge_width 0.5)
			(island_removal_mode 0)
		)
		(polygon
			(pts
				(arc
					(start 378.189744 -284.616144)
					(mid 377.559824 -284.616144)
					(end 378.189744 -284.616144)
				)
			)
		)
	)
	(zone
		(layers "B.Cu" "In4.Cu" "In6.Cu" "In11.Cu" "In13.Cu" "In15.Cu")
		(hatch none 0.5)
		(connect_pads
			(clearance 0)
		)
		(min_thickness 0.25)
		(keepout
			(tracks not_allowed)
			(vias allowed)
			(pads allowed)
			(copperpour not_allowed)
			(footprints allowed)
		)
		(placement
			(enabled no)
			(sheetname "")
		)
		(fill yes
			(thermal_gap 0.5)
			(thermal_bridge_width 0.5)
			(island_removal_mode 0)
		)
		(polygon
			(pts
				(arc
					(start 376.009662 -249.34418)
					(mid 375.379742 -249.34418)
					(end 376.009662 -249.34418)
				)
			)
		)
	)
	(zone
		(layers "B.Cu" "In4.Cu" "In6.Cu" "In11.Cu" "In13.Cu" "In15.Cu")
		(hatch none 0.5)
		(connect_pads
			(clearance 0)
		)
		(min_thickness 0.25)
		(keepout
			(tracks not_allowed)
			(vias allowed)
			(pads allowed)
			(copperpour not_allowed)
			(footprints allowed)
		)
		(placement
			(enabled no)
			(sheetname "")
		)
		(fill yes
			(thermal_gap 0.5)
			(thermal_bridge_width 0.5)
			(island_removal_mode 0)
		)
		(polygon
			(pts
				(arc
					(start 95.645986 -245.294404)
					(mid 95.016066 -245.294404)
					(end 95.645986 -245.294404)
				)
			)
		)
	)
	(zone
		(layers "B.Cu" "In4.Cu" "In6.Cu" "In11.Cu" "In13.Cu" "In15.Cu")
		(hatch none 0.5)
		(connect_pads
			(clearance 0)
		)
		(min_thickness 0.25)
		(keepout
			(tracks not_allowed)
			(vias allowed)
			(pads allowed)
			(copperpour not_allowed)
			(footprints allowed)
		)
		(placement
			(enabled no)
			(sheetname "")
		)
		(fill yes
			(thermal_gap 0.5)
			(thermal_bridge_width 0.5)
			(island_removal_mode 0)
		)
		(polygon
			(pts
				(arc
					(start 183.950102 -201.585322)
					(mid 183.282082 -201.585322)
					(end 183.950102 -201.585322)
				)
			)
		)
	)
	(zone
		(layers "B.Cu" "In4.Cu" "In6.Cu" "In11.Cu" "In13.Cu" "In15.Cu")
		(hatch none 0.5)
		(connect_pads
			(clearance 0)
		)
		(min_thickness 0.25)
		(keepout
			(tracks not_allowed)
			(vias allowed)
			(pads allowed)
			(copperpour not_allowed)
			(footprints allowed)
		)
		(placement
			(enabled no)
			(sheetname "")
		)
		(fill yes
			(thermal_gap 0.5)
			(thermal_bridge_width 0.5)
			(island_removal_mode 0)
		)
		(polygon
			(pts
				(arc
					(start 431.89017 -272.135092)
					(mid 431.22215 -272.135092)
					(end 431.89017 -272.135092)
				)
			)
		)
	)
	(zone
		(layers "B.Cu" "In4.Cu" "In6.Cu" "In11.Cu" "In13.Cu" "In15.Cu")
		(hatch none 0.5)
		(connect_pads
			(clearance 0)
		)
		(min_thickness 0.25)
		(keepout
			(tracks not_allowed)
			(vias allowed)
			(pads allowed)
			(copperpour not_allowed)
			(footprints allowed)
		)
		(placement
			(enabled no)
			(sheetname "")
		)
		(fill yes
			(thermal_gap 0.5)
			(thermal_bridge_width 0.5)
			(island_removal_mode 0)
		)
		(polygon
			(pts
				(arc
					(start 344.055954 -229.904036)
					(mid 343.426034 -229.904036)
					(end 344.055954 -229.904036)
				)
			)
		)
	)
	(zone
		(layers "B.Cu" "In4.Cu" "In6.Cu" "In11.Cu" "In13.Cu" "In15.Cu")
		(hatch none 0.5)
		(connect_pads
			(clearance 0)
		)
		(min_thickness 0.25)
		(keepout
			(tracks not_allowed)
			(vias allowed)
			(pads allowed)
			(copperpour not_allowed)
			(footprints allowed)
		)
		(placement
			(enabled no)
			(sheetname "")
		)
		(fill yes
			(thermal_gap 0.5)
			(thermal_bridge_width 0.5)
			(island_removal_mode 0)
		)
		(polygon
			(pts
				(arc
					(start 108.80598 -230.71455)
					(mid 108.17606 -230.71455)
					(end 108.80598 -230.71455)
				)
			)
		)
	)
	(zone
		(layers "B.Cu" "In4.Cu" "In6.Cu" "In11.Cu" "In13.Cu" "In15.Cu")
		(hatch none 0.5)
		(connect_pads
			(clearance 0)
		)
		(min_thickness 0.25)
		(keepout
			(tracks not_allowed)
			(vias allowed)
			(pads allowed)
			(copperpour not_allowed)
			(footprints allowed)
		)
		(placement
			(enabled no)
			(sheetname "")
		)
		(fill yes
			(thermal_gap 0.5)
			(thermal_bridge_width 0.5)
			(island_removal_mode 0)
		)
		(polygon
			(pts
				(arc
					(start 427.790102 -210.935062)
					(mid 427.122082 -210.935062)
					(end 427.790102 -210.935062)
				)
			)
		)
	)
	(zone
		(layers "B.Cu" "In4.Cu" "In6.Cu" "In11.Cu" "In13.Cu" "In15.Cu")
		(hatch none 0.5)
		(connect_pads
			(clearance 0)
		)
		(min_thickness 0.25)
		(keepout
			(tracks not_allowed)
			(vias allowed)
			(pads allowed)
			(copperpour not_allowed)
			(footprints allowed)
		)
		(placement
			(enabled no)
			(sheetname "")
		)
		(fill yes
			(thermal_gap 0.5)
			(thermal_bridge_width 0.5)
			(island_removal_mode 0)
		)
		(polygon
			(pts
				(arc
					(start 40.57396 -254.285242)
					(mid 39.90594 -254.285242)
					(end 40.57396 -254.285242)
				)
			)
		)
	)
	(zone
		(layers "B.Cu" "In4.Cu" "In6.Cu" "In11.Cu" "In13.Cu" "In15.Cu")
		(hatch none 0.5)
		(connect_pads
			(clearance 0)
		)
		(min_thickness 0.25)
		(keepout
			(tracks not_allowed)
			(vias allowed)
			(pads allowed)
			(copperpour not_allowed)
			(footprints allowed)
		)
		(placement
			(enabled no)
			(sheetname "")
		)
		(fill yes
			(thermal_gap 0.5)
			(thermal_bridge_width 0.5)
			(island_removal_mode 0)
		)
		(polygon
			(pts
				(arc
					(start 96.115886 -238.00435)
					(mid 95.485966 -238.00435)
					(end 96.115886 -238.00435)
				)
			)
		)
	)
	(zone
		(layers "B.Cu" "In4.Cu" "In6.Cu" "In11.Cu" "In13.Cu" "In15.Cu")
		(hatch none 0.5)
		(connect_pads
			(clearance 0)
		)
		(min_thickness 0.25)
		(keepout
			(tracks not_allowed)
			(vias allowed)
			(pads allowed)
			(copperpour not_allowed)
			(footprints allowed)
		)
		(placement
			(enabled no)
			(sheetname "")
		)
		(fill yes
			(thermal_gap 0.5)
			(thermal_bridge_width 0.5)
			(island_removal_mode 0)
		)
		(polygon
			(pts
				(arc
					(start 97.355914 -294.336216)
					(mid 96.725994 -294.336216)
					(end 97.355914 -294.336216)
				)
			)
		)
	)
	(zone
		(layers "B.Cu" "In4.Cu" "In6.Cu" "In11.Cu" "In13.Cu" "In15.Cu")
		(hatch none 0.5)
		(connect_pads
			(clearance 0)
		)
		(min_thickness 0.25)
		(keepout
			(tracks not_allowed)
			(vias allowed)
			(pads allowed)
			(copperpour not_allowed)
			(footprints allowed)
		)
		(placement
			(enabled no)
			(sheetname "")
		)
		(fill yes
			(thermal_gap 0.5)
			(thermal_bridge_width 0.5)
			(island_removal_mode 0)
		)
		(polygon
			(pts
				(arc
					(start 40.57396 -224.535238)
					(mid 39.90594 -224.535238)
					(end 40.57396 -224.535238)
				)
			)
		)
	)
	(zone
		(layers "B.Cu" "In4.Cu" "In6.Cu" "In11.Cu" "In13.Cu" "In15.Cu")
		(hatch none 0.5)
		(connect_pads
			(clearance 0)
		)
		(min_thickness 0.25)
		(keepout
			(tracks not_allowed)
			(vias allowed)
			(pads allowed)
			(copperpour not_allowed)
			(footprints allowed)
		)
		(placement
			(enabled no)
			(sheetname "")
		)
		(fill yes
			(thermal_gap 0.5)
			(thermal_bridge_width 0.5)
			(island_removal_mode 0)
		)
		(polygon
			(pts
				(arc
					(start 376.77979 -277.32609)
					(mid 376.14987 -277.32609)
					(end 376.77979 -277.32609)
				)
			)
		)
	)
	(zone
		(layers "B.Cu" "In4.Cu" "In6.Cu" "In11.Cu" "In13.Cu" "In15.Cu")
		(hatch none 0.5)
		(connect_pads
			(clearance 0)
		)
		(min_thickness 0.25)
		(keepout
			(tracks not_allowed)
			(vias allowed)
			(pads allowed)
			(copperpour not_allowed)
			(footprints allowed)
		)
		(placement
			(enabled no)
			(sheetname "")
		)
		(fill yes
			(thermal_gap 0.5)
			(thermal_bridge_width 0.5)
			(island_removal_mode 0)
		)
		(polygon
			(pts
				(arc
					(start 95.94596 -282.18638)
					(mid 95.31604 -282.18638)
					(end 95.94596 -282.18638)
				)
			)
		)
	)
	(zone
		(layers "B.Cu" "In4.Cu" "In6.Cu" "In11.Cu" "In13.Cu" "In15.Cu")
		(hatch none 0.5)
		(connect_pads
			(clearance 0)
		)
		(min_thickness 0.25)
		(keepout
			(tracks not_allowed)
			(vias allowed)
			(pads allowed)
			(copperpour not_allowed)
			(footprints allowed)
		)
		(placement
			(enabled no)
			(sheetname "")
		)
		(fill yes
			(thermal_gap 0.5)
			(thermal_bridge_width 0.5)
			(island_removal_mode 0)
		)
		(polygon
			(pts
				(arc
					(start 368.489738 -229.904036)
					(mid 367.859818 -229.904036)
					(end 368.489738 -229.904036)
				)
			)
		)
	)
	(zone
		(layers "B.Cu" "In4.Cu" "In6.Cu" "In11.Cu" "In13.Cu" "In15.Cu")
		(hatch none 0.5)
		(connect_pads
			(clearance 0)
		)
		(min_thickness 0.25)
		(keepout
			(tracks not_allowed)
			(vias allowed)
			(pads allowed)
			(copperpour not_allowed)
			(footprints allowed)
		)
		(placement
			(enabled no)
			(sheetname "")
		)
		(fill yes
			(thermal_gap 0.5)
			(thermal_bridge_width 0.5)
			(island_removal_mode 0)
		)
		(polygon
			(pts
				(arc
					(start 288.514028 -226.235006)
					(mid 287.846008 -226.235006)
					(end 288.514028 -226.235006)
				)
			)
		)
	)
	(zone
		(layers "B.Cu" "In4.Cu" "In6.Cu" "In11.Cu" "In13.Cu" "In15.Cu")
		(hatch none 0.5)
		(connect_pads
			(clearance 0)
		)
		(min_thickness 0.25)
		(keepout
			(tracks not_allowed)
			(vias allowed)
			(pads allowed)
			(copperpour not_allowed)
			(footprints allowed)
		)
		(placement
			(enabled no)
			(sheetname "")
		)
		(fill yes
			(thermal_gap 0.5)
			(thermal_bridge_width 0.5)
			(island_removal_mode 0)
		)
		(polygon
			(pts
				(arc
					(start 130.249676 -263.556242)
					(mid 129.619756 -263.556242)
					(end 130.249676 -263.556242)
				)
			)
		)
	)
	(zone
		(layers "B.Cu" "In4.Cu" "In6.Cu" "In11.Cu" "In13.Cu" "In15.Cu")
		(hatch none 0.5)
		(connect_pads
			(clearance 0)
		)
		(min_thickness 0.25)
		(keepout
			(tracks not_allowed)
			(vias allowed)
			(pads allowed)
			(copperpour not_allowed)
			(footprints allowed)
		)
		(placement
			(enabled no)
			(sheetname "")
		)
		(fill yes
			(thermal_gap 0.5)
			(thermal_bridge_width 0.5)
			(island_removal_mode 0)
		)
		(polygon
			(pts
				(arc
					(start 40.57396 -282.335224)
					(mid 39.90594 -282.335224)
					(end 40.57396 -282.335224)
				)
			)
		)
	)
	(zone
		(layers "B.Cu" "In4.Cu" "In6.Cu" "In11.Cu" "In13.Cu" "In15.Cu")
		(hatch none 0.5)
		(connect_pads
			(clearance 0)
		)
		(min_thickness 0.25)
		(keepout
			(tracks not_allowed)
			(vias allowed)
			(pads allowed)
			(copperpour not_allowed)
			(footprints allowed)
		)
		(placement
			(enabled no)
			(sheetname "")
		)
		(fill yes
			(thermal_gap 0.5)
			(thermal_bridge_width 0.5)
			(island_removal_mode 0)
		)
		(polygon
			(pts
				(arc
					(start 183.950102 -296.785284)
					(mid 183.282082 -296.785284)
					(end 183.950102 -296.785284)
				)
			)
		)
	)
	(zone
		(layers "B.Cu" "In4.Cu" "In6.Cu" "In11.Cu" "In13.Cu" "In15.Cu")
		(hatch none 0.5)
		(connect_pads
			(clearance 0)
		)
		(min_thickness 0.25)
		(keepout
			(tracks not_allowed)
			(vias allowed)
			(pads allowed)
			(copperpour not_allowed)
			(footprints allowed)
		)
		(placement
			(enabled no)
			(sheetname "")
		)
		(fill yes
			(thermal_gap 0.5)
			(thermal_bridge_width 0.5)
			(island_removal_mode 0)
		)
		(polygon
			(pts
				(arc
					(start 40.57396 -201.585322)
					(mid 39.90594 -201.585322)
					(end 40.57396 -201.585322)
				)
			)
		)
	)
	(zone
		(layers "B.Cu" "In4.Cu" "In6.Cu" "In11.Cu" "In13.Cu" "In15.Cu")
		(hatch none 0.5)
		(connect_pads
			(clearance 0)
		)
		(min_thickness 0.25)
		(keepout
			(tracks not_allowed)
			(vias allowed)
			(pads allowed)
			(copperpour not_allowed)
			(footprints allowed)
		)
		(placement
			(enabled no)
			(sheetname "")
		)
		(fill yes
			(thermal_gap 0.5)
			(thermal_bridge_width 0.5)
			(island_removal_mode 0)
		)
		(polygon
			(pts
				(arc
					(start 374.129808 -229.904036)
					(mid 373.499888 -229.904036)
					(end 374.129808 -229.904036)
				)
			)
		)
	)
	(zone
		(layers "B.Cu" "In4.Cu" "In6.Cu" "In11.Cu" "In13.Cu" "In15.Cu")
		(hatch none 0.5)
		(connect_pads
			(clearance 0)
		)
		(min_thickness 0.25)
		(keepout
			(tracks not_allowed)
			(vias allowed)
			(pads allowed)
			(copperpour not_allowed)
			(footprints allowed)
		)
		(placement
			(enabled no)
			(sheetname "")
		)
		(fill yes
			(thermal_gap 0.5)
			(thermal_bridge_width 0.5)
			(island_removal_mode 0)
		)
		(polygon
			(pts
				(arc
					(start 292.614096 -245.785132)
					(mid 291.946076 -245.785132)
					(end 292.614096 -245.785132)
				)
			)
		)
	)
	(zone
		(layers "B.Cu" "In4.Cu" "In6.Cu" "In11.Cu" "In13.Cu" "In15.Cu")
		(hatch none 0.5)
		(connect_pads
			(clearance 0)
		)
		(min_thickness 0.25)
		(keepout
			(tracks not_allowed)
			(vias allowed)
			(pads allowed)
			(copperpour not_allowed)
			(footprints allowed)
		)
		(placement
			(enabled no)
			(sheetname "")
		)
		(fill yes
			(thermal_gap 0.5)
			(thermal_bridge_width 0.5)
			(island_removal_mode 0)
		)
		(polygon
			(pts
				(arc
					(start 95.94596 -275.706332)
					(mid 95.31604 -275.706332)
					(end 95.94596 -275.706332)
				)
			)
		)
	)
	(zone
		(layers "B.Cu" "In4.Cu" "In6.Cu" "In11.Cu" "In13.Cu" "In15.Cu")
		(hatch none 0.5)
		(connect_pads
			(clearance 0)
		)
		(min_thickness 0.25)
		(keepout
			(tracks not_allowed)
			(vias allowed)
			(pads allowed)
			(copperpour not_allowed)
			(footprints allowed)
		)
		(placement
			(enabled no)
			(sheetname "")
		)
		(fill yes
			(thermal_gap 0.5)
			(thermal_bridge_width 0.5)
			(island_removal_mode 0)
		)
		(polygon
			(pts
				(arc
					(start 130.249676 -274.896326)
					(mid 129.619756 -274.896326)
					(end 130.249676 -274.896326)
				)
			)
		)
	)
	(zone
		(layers "B.Cu" "In4.Cu" "In6.Cu" "In11.Cu" "In13.Cu" "In15.Cu")
		(hatch none 0.5)
		(connect_pads
			(clearance 0)
		)
		(min_thickness 0.25)
		(keepout
			(tracks not_allowed)
			(vias allowed)
			(pads allowed)
			(copperpour not_allowed)
			(footprints allowed)
		)
		(placement
			(enabled no)
			(sheetname "")
		)
		(fill yes
			(thermal_gap 0.5)
			(thermal_bridge_width 0.5)
			(island_removal_mode 0)
		)
		(polygon
			(pts
				(arc
					(start 40.57396 -238.985298)
					(mid 39.90594 -238.985298)
					(end 40.57396 -238.985298)
				)
			)
		)
	)
	(zone
		(layers "B.Cu" "In4.Cu" "In6.Cu" "In11.Cu" "In13.Cu" "In15.Cu")
		(hatch none 0.5)
		(connect_pads
			(clearance 0)
		)
		(min_thickness 0.25)
		(keepout
			(tracks not_allowed)
			(vias allowed)
			(pads allowed)
			(copperpour not_allowed)
			(footprints allowed)
		)
		(placement
			(enabled no)
			(sheetname "")
		)
		(fill yes
			(thermal_gap 0.5)
			(thermal_bridge_width 0.5)
			(island_removal_mode 0)
		)
		(polygon
			(pts
				(arc
					(start 292.614096 -287.435036)
					(mid 291.946076 -287.435036)
					(end 292.614096 -287.435036)
				)
			)
		)
	)
	(zone
		(layers "B.Cu" "In4.Cu" "In6.Cu" "In11.Cu" "In13.Cu" "In15.Cu")
		(hatch none 0.5)
		(connect_pads
			(clearance 0)
		)
		(min_thickness 0.25)
		(keepout
			(tracks not_allowed)
			(vias allowed)
			(pads allowed)
			(copperpour not_allowed)
			(footprints allowed)
		)
		(placement
			(enabled no)
			(sheetname "")
		)
		(fill yes
			(thermal_gap 0.5)
			(thermal_bridge_width 0.5)
			(island_removal_mode 0)
		)
		(polygon
			(pts
				(arc
					(start 95.94596 -262.746236)
					(mid 95.31604 -262.746236)
					(end 95.94596 -262.746236)
				)
			)
		)
	)
	(zone
		(layers "B.Cu" "In4.Cu" "In6.Cu" "In11.Cu" "In13.Cu" "In15.Cu")
		(hatch none 0.5)
		(connect_pads
			(clearance 0)
		)
		(min_thickness 0.25)
		(keepout
			(tracks not_allowed)
			(vias allowed)
			(pads allowed)
			(copperpour not_allowed)
			(footprints allowed)
		)
		(placement
			(enabled no)
			(sheetname "")
		)
		(fill yes
			(thermal_gap 0.5)
			(thermal_bridge_width 0.5)
			(island_removal_mode 0)
		)
		(polygon
			(pts
				(arc
					(start 377.41987 -246.914162)
					(mid 376.78995 -246.914162)
					(end 377.41987 -246.914162)
				)
			)
		)
	)
	(zone
		(layers "B.Cu" "In4.Cu" "In6.Cu" "In11.Cu" "In13.Cu" "In15.Cu")
		(hatch none 0.5)
		(connect_pads
			(clearance 0)
		)
		(min_thickness 0.25)
		(keepout
			(tracks not_allowed)
			(vias allowed)
			(pads allowed)
			(copperpour not_allowed)
			(footprints allowed)
		)
		(placement
			(enabled no)
			(sheetname "")
		)
		(fill yes
			(thermal_gap 0.5)
			(thermal_bridge_width 0.5)
			(island_removal_mode 0)
		)
		(polygon
			(pts
				(arc
					(start 342.646 -238.814102)
					(mid 342.01608 -238.814102)
					(end 342.646 -238.814102)
				)
			)
		)
	)
	(zone
		(layers "B.Cu" "In4.Cu" "In6.Cu" "In11.Cu" "In13.Cu" "In15.Cu")
		(hatch none 0.5)
		(connect_pads
			(clearance 0)
		)
		(min_thickness 0.25)
		(keepout
			(tracks not_allowed)
			(vias allowed)
			(pads allowed)
			(copperpour not_allowed)
			(footprints allowed)
		)
		(placement
			(enabled no)
			(sheetname "")
		)
		(fill yes
			(thermal_gap 0.5)
			(thermal_bridge_width 0.5)
			(island_removal_mode 0)
		)
		(polygon
			(pts
				(arc
					(start 348.116144 -294.335962)
					(mid 347.486224 -294.335962)
					(end 348.116144 -294.335962)
				)
			)
		)
	)
	(zone
		(layers "B.Cu" "In4.Cu" "In6.Cu" "In11.Cu" "In13.Cu" "In15.Cu")
		(hatch none 0.5)
		(connect_pads
			(clearance 0)
		)
		(min_thickness 0.25)
		(keepout
			(tracks not_allowed)
			(vias allowed)
			(pads allowed)
			(copperpour not_allowed)
			(footprints allowed)
		)
		(placement
			(enabled no)
			(sheetname "")
		)
		(fill yes
			(thermal_gap 0.5)
			(thermal_bridge_width 0.5)
			(island_removal_mode 0)
		)
		(polygon
			(pts
				(arc
					(start 344.055954 -234.764072)
					(mid 343.426034 -234.764072)
					(end 344.055954 -234.764072)
				)
			)
		)
	)
	(zone
		(layers "B.Cu" "In4.Cu" "In6.Cu" "In11.Cu" "In13.Cu" "In15.Cu")
		(hatch none 0.5)
		(connect_pads
			(clearance 0)
		)
		(min_thickness 0.25)
		(keepout
			(tracks not_allowed)
			(vias allowed)
			(pads allowed)
			(copperpour not_allowed)
			(footprints allowed)
		)
		(placement
			(enabled no)
			(sheetname "")
		)
		(fill yes
			(thermal_gap 0.5)
			(thermal_bridge_width 0.5)
			(island_removal_mode 0)
		)
		(polygon
			(pts
				(arc
					(start 344.356182 -263.555988)
					(mid 343.726262 -263.555988)
					(end 344.356182 -263.555988)
				)
			)
		)
	)
	(zone
		(layers "B.Cu" "In4.Cu" "In6.Cu" "In11.Cu" "In13.Cu" "In15.Cu")
		(hatch none 0.5)
		(connect_pads
			(clearance 0)
		)
		(min_thickness 0.25)
		(keepout
			(tracks not_allowed)
			(vias allowed)
			(pads allowed)
			(copperpour not_allowed)
			(footprints allowed)
		)
		(placement
			(enabled no)
			(sheetname "")
		)
		(fill yes
			(thermal_gap 0.5)
			(thermal_bridge_width 0.5)
			(island_removal_mode 0)
		)
		(polygon
			(pts
				(arc
					(start 292.614096 -210.935062)
					(mid 291.946076 -210.935062)
					(end 292.614096 -210.935062)
				)
			)
		)
	)
	(zone
		(layers "B.Cu" "In4.Cu" "In6.Cu" "In11.Cu" "In13.Cu" "In15.Cu")
		(hatch none 0.5)
		(connect_pads
			(clearance 0)
		)
		(min_thickness 0.25)
		(keepout
			(tracks not_allowed)
			(vias allowed)
			(pads allowed)
			(copperpour not_allowed)
			(footprints allowed)
		)
		(placement
			(enabled no)
			(sheetname "")
		)
		(fill yes
			(thermal_gap 0.5)
			(thermal_bridge_width 0.5)
			(island_removal_mode 0)
		)
		(polygon
			(pts
				(arc
					(start 129.779776 -291.906198)
					(mid 129.149856 -291.906198)
					(end 129.779776 -291.906198)
				)
			)
		)
	)
	(zone
		(layers "B.Cu" "In4.Cu" "In6.Cu" "In11.Cu" "In13.Cu" "In15.Cu")
		(hatch none 0.5)
		(connect_pads
			(clearance 0)
		)
		(min_thickness 0.25)
		(keepout
			(tracks not_allowed)
			(vias allowed)
			(pads allowed)
			(copperpour not_allowed)
			(footprints allowed)
		)
		(placement
			(enabled no)
			(sheetname "")
		)
		(fill yes
			(thermal_gap 0.5)
			(thermal_bridge_width 0.5)
			(island_removal_mode 0)
		)
		(polygon
			(pts
				(arc
					(start 95.005906 -287.046162)
					(mid 94.375986 -287.046162)
					(end 95.005906 -287.046162)
				)
			)
		)
	)
	(zone
		(layers "B.Cu" "In4.Cu" "In6.Cu" "In11.Cu" "In13.Cu" "In15.Cu")
		(hatch none 0.5)
		(connect_pads
			(clearance 0)
		)
		(min_thickness 0.25)
		(keepout
			(tracks not_allowed)
			(vias allowed)
			(pads allowed)
			(copperpour not_allowed)
			(footprints allowed)
		)
		(placement
			(enabled no)
			(sheetname "")
		)
		(fill yes
			(thermal_gap 0.5)
			(thermal_bridge_width 0.5)
			(island_removal_mode 0)
		)
		(polygon
			(pts
				(arc
					(start 292.614096 -290.83508)
					(mid 291.946076 -290.83508)
					(end 292.614096 -290.83508)
				)
			)
		)
	)
	(zone
		(layers "B.Cu" "In4.Cu" "In6.Cu" "In11.Cu" "In13.Cu" "In15.Cu")
		(hatch none 0.5)
		(connect_pads
			(clearance 0)
		)
		(min_thickness 0.25)
		(keepout
			(tracks not_allowed)
			(vias allowed)
			(pads allowed)
			(copperpour not_allowed)
			(footprints allowed)
		)
		(placement
			(enabled no)
			(sheetname "")
		)
		(fill yes
			(thermal_gap 0.5)
			(thermal_bridge_width 0.5)
			(island_removal_mode 0)
		)
		(polygon
			(pts
				(arc
					(start 378.189744 -279.756108)
					(mid 377.559824 -279.756108)
					(end 378.189744 -279.756108)
				)
			)
		)
	)
	(zone
		(layers "B.Cu" "In4.Cu" "In6.Cu" "In11.Cu" "In13.Cu" "In15.Cu")
		(hatch none 0.5)
		(connect_pads
			(clearance 0)
		)
		(min_thickness 0.25)
		(keepout
			(tracks not_allowed)
			(vias allowed)
			(pads allowed)
			(copperpour not_allowed)
			(footprints allowed)
		)
		(placement
			(enabled no)
			(sheetname "")
		)
		(fill yes
			(thermal_gap 0.5)
			(thermal_bridge_width 0.5)
			(island_removal_mode 0)
		)
		(polygon
			(pts
				(arc
					(start 179.850034 -244.935248)
					(mid 179.182014 -244.935248)
					(end 179.850034 -244.935248)
				)
			)
		)
	)
	(zone
		(layers "B.Cu" "In4.Cu" "In6.Cu" "In11.Cu" "In13.Cu" "In15.Cu")
		(hatch none 0.5)
		(connect_pads
			(clearance 0)
		)
		(min_thickness 0.25)
		(keepout
			(tracks not_allowed)
			(vias allowed)
			(pads allowed)
			(copperpour not_allowed)
			(footprints allowed)
		)
		(placement
			(enabled no)
			(sheetname "")
		)
		(fill yes
			(thermal_gap 0.5)
			(thermal_bridge_width 0.5)
			(island_removal_mode 0)
		)
		(polygon
			(pts
				(arc
					(start 96.115886 -250.964446)
					(mid 95.485966 -250.964446)
					(end 96.115886 -250.964446)
				)
			)
		)
	)
	(zone
		(layers "B.Cu" "In4.Cu" "In6.Cu" "In11.Cu" "In13.Cu" "In15.Cu")
		(hatch none 0.5)
		(connect_pads
			(clearance 0)
		)
		(min_thickness 0.25)
		(keepout
			(tracks not_allowed)
			(vias allowed)
			(pads allowed)
			(copperpour not_allowed)
			(footprints allowed)
		)
		(placement
			(enabled no)
			(sheetname "")
		)
		(fill yes
			(thermal_gap 0.5)
			(thermal_bridge_width 0.5)
			(island_removal_mode 0)
		)
		(polygon
			(pts
				(arc
					(start 96.115886 -231.524302)
					(mid 95.485966 -231.524302)
					(end 96.115886 -231.524302)
				)
			)
		)
	)
	(zone
		(layers "B.Cu" "In4.Cu" "In6.Cu" "In11.Cu" "In13.Cu" "In15.Cu")
		(hatch none 0.5)
		(connect_pads
			(clearance 0)
		)
		(min_thickness 0.25)
		(keepout
			(tracks not_allowed)
			(vias allowed)
			(pads allowed)
			(copperpour not_allowed)
			(footprints allowed)
		)
		(placement
			(enabled no)
			(sheetname "")
		)
		(fill yes
			(thermal_gap 0.5)
			(thermal_bridge_width 0.5)
			(island_removal_mode 0)
		)
		(polygon
			(pts
				(arc
					(start 377.719844 -272.466054)
					(mid 377.089924 -272.466054)
					(end 377.719844 -272.466054)
				)
			)
		)
	)
	(zone
		(layers "B.Cu" "In4.Cu" "In6.Cu" "In11.Cu" "In13.Cu" "In15.Cu")
		(hatch none 0.5)
		(connect_pads
			(clearance 0)
		)
		(min_thickness 0.25)
		(keepout
			(tracks not_allowed)
			(vias allowed)
			(pads allowed)
			(copperpour not_allowed)
			(footprints allowed)
		)
		(placement
			(enabled no)
			(sheetname "")
		)
		(fill yes
			(thermal_gap 0.5)
			(thermal_bridge_width 0.5)
			(island_removal_mode 0)
		)
		(polygon
			(pts
				(arc
					(start 128.069594 -239.624362)
					(mid 127.439674 -239.624362)
					(end 128.069594 -239.624362)
				)
			)
		)
	)
	(zone
		(layers "B.Cu" "In4.Cu" "In6.Cu" "In11.Cu" "In13.Cu" "In15.Cu")
		(hatch none 0.5)
		(connect_pads
			(clearance 0)
		)
		(min_thickness 0.25)
		(keepout
			(tracks not_allowed)
			(vias allowed)
			(pads allowed)
			(copperpour not_allowed)
			(footprints allowed)
		)
		(placement
			(enabled no)
			(sheetname "")
		)
		(fill yes
			(thermal_gap 0.5)
			(thermal_bridge_width 0.5)
			(island_removal_mode 0)
		)
		(polygon
			(pts
				(arc
					(start 288.514028 -316.335156)
					(mid 287.846008 -316.335156)
					(end 288.514028 -316.335156)
				)
			)
		)
	)
	(zone
		(layers "B.Cu" "In4.Cu" "In6.Cu" "In11.Cu" "In13.Cu" "In15.Cu")
		(hatch none 0.5)
		(connect_pads
			(clearance 0)
		)
		(min_thickness 0.25)
		(keepout
			(tracks not_allowed)
			(vias allowed)
			(pads allowed)
			(copperpour not_allowed)
			(footprints allowed)
		)
		(placement
			(enabled no)
			(sheetname "")
		)
		(fill yes
			(thermal_gap 0.5)
			(thermal_bridge_width 0.5)
			(island_removal_mode 0)
		)
		(polygon
			(pts
				(arc
					(start 431.89017 -245.785132)
					(mid 431.22215 -245.785132)
					(end 431.89017 -245.785132)
				)
			)
		)
	)
	(zone
		(layers "B.Cu" "In4.Cu" "In6.Cu" "In11.Cu" "In13.Cu" "In15.Cu")
		(hatch none 0.5)
		(connect_pads
			(clearance 0)
		)
		(min_thickness 0.25)
		(keepout
			(tracks not_allowed)
			(vias allowed)
			(pads allowed)
			(copperpour not_allowed)
			(footprints allowed)
		)
		(placement
			(enabled no)
			(sheetname "")
		)
		(fill yes
			(thermal_gap 0.5)
			(thermal_bridge_width 0.5)
			(island_removal_mode 0)
		)
		(polygon
			(pts
				(arc
					(start 344.356182 -287.856168)
					(mid 343.726262 -287.856168)
					(end 344.356182 -287.856168)
				)
			)
		)
	)
	(zone
		(layers "B.Cu" "In4.Cu" "In6.Cu" "In11.Cu" "In13.Cu" "In15.Cu")
		(hatch none 0.5)
		(connect_pads
			(clearance 0)
		)
		(min_thickness 0.25)
		(keepout
			(tracks not_allowed)
			(vias allowed)
			(pads allowed)
			(copperpour not_allowed)
			(footprints allowed)
		)
		(placement
			(enabled no)
			(sheetname "")
		)
		(fill yes
			(thermal_gap 0.5)
			(thermal_bridge_width 0.5)
			(island_removal_mode 0)
		)
		(polygon
			(pts
				(arc
					(start 288.514028 -237.285022)
					(mid 287.846008 -237.285022)
					(end 288.514028 -237.285022)
				)
			)
		)
	)
	(zone
		(layers "B.Cu" "In4.Cu" "In6.Cu" "In11.Cu" "In13.Cu" "In15.Cu")
		(hatch none 0.5)
		(connect_pads
			(clearance 0)
		)
		(min_thickness 0.25)
		(keepout
			(tracks not_allowed)
			(vias allowed)
			(pads allowed)
			(copperpour not_allowed)
			(footprints allowed)
		)
		(placement
			(enabled no)
			(sheetname "")
		)
		(fill yes
			(thermal_gap 0.5)
			(thermal_bridge_width 0.5)
			(island_removal_mode 0)
		)
		(polygon
			(pts
				(arc
					(start 183.950102 -275.53539)
					(mid 183.282082 -275.53539)
					(end 183.950102 -275.53539)
				)
			)
		)
	)
	(zone
		(layers "B.Cu" "In4.Cu" "In6.Cu" "In11.Cu" "In13.Cu" "In15.Cu")
		(hatch none 0.5)
		(connect_pads
			(clearance 0)
		)
		(min_thickness 0.25)
		(keepout
			(tracks not_allowed)
			(vias allowed)
			(pads allowed)
			(copperpour not_allowed)
			(footprints allowed)
		)
		(placement
			(enabled no)
			(sheetname "")
		)
		(fill yes
			(thermal_gap 0.5)
			(thermal_bridge_width 0.5)
			(island_removal_mode 0)
		)
		(polygon
			(pts
				(arc
					(start 179.850034 -220.28531)
					(mid 179.182014 -220.28531)
					(end 179.850034 -220.28531)
				)
			)
		)
	)
	(zone
		(layers "B.Cu" "In4.Cu" "In6.Cu" "In11.Cu" "In13.Cu" "In15.Cu")
		(hatch none 0.5)
		(connect_pads
			(clearance 0)
		)
		(min_thickness 0.25)
		(keepout
			(tracks not_allowed)
			(vias allowed)
			(pads allowed)
			(copperpour not_allowed)
			(footprints allowed)
		)
		(placement
			(enabled no)
			(sheetname "")
		)
		(fill yes
			(thermal_gap 0.5)
			(thermal_bridge_width 0.5)
			(island_removal_mode 0)
		)
		(polygon
			(pts
				(arc
					(start 377.88977 -229.904036)
					(mid 377.25985 -229.904036)
					(end 377.88977 -229.904036)
				)
			)
		)
	)
	(zone
		(layers "B.Cu" "In4.Cu" "In6.Cu" "In11.Cu" "In13.Cu" "In15.Cu")
		(hatch none 0.5)
		(connect_pads
			(clearance 0)
		)
		(min_thickness 0.25)
		(keepout
			(tracks not_allowed)
			(vias allowed)
			(pads allowed)
			(copperpour not_allowed)
			(footprints allowed)
		)
		(placement
			(enabled no)
			(sheetname "")
		)
		(fill yes
			(thermal_gap 0.5)
			(thermal_bridge_width 0.5)
			(island_removal_mode 0)
		)
		(polygon
			(pts
				(arc
					(start 377.41987 -232.334054)
					(mid 376.78995 -232.334054)
					(end 377.41987 -232.334054)
				)
			)
		)
	)
	(zone
		(layers "B.Cu" "In4.Cu" "In6.Cu" "In11.Cu" "In13.Cu" "In15.Cu")
		(hatch none 0.5)
		(connect_pads
			(clearance 0)
		)
		(min_thickness 0.25)
		(keepout
			(tracks not_allowed)
			(vias allowed)
			(pads allowed)
			(copperpour not_allowed)
			(footprints allowed)
		)
		(placement
			(enabled no)
			(sheetname "")
		)
		(fill yes
			(thermal_gap 0.5)
			(thermal_bridge_width 0.5)
			(island_removal_mode 0)
		)
		(polygon
			(pts
				(arc
					(start 95.005906 -280.566368)
					(mid 94.375986 -280.566368)
					(end 95.005906 -280.566368)
				)
			)
		)
	)
	(zone
		(layers "B.Cu" "In4.Cu" "In6.Cu" "In11.Cu" "In13.Cu" "In15.Cu")
		(hatch none 0.5)
		(connect_pads
			(clearance 0)
		)
		(min_thickness 0.25)
		(keepout
			(tracks not_allowed)
			(vias allowed)
			(pads allowed)
			(copperpour not_allowed)
			(footprints allowed)
		)
		(placement
			(enabled no)
			(sheetname "")
		)
		(fill yes
			(thermal_gap 0.5)
			(thermal_bridge_width 0.5)
			(island_removal_mode 0)
		)
		(polygon
			(pts
				(arc
					(start 95.645986 -246.914416)
					(mid 95.016066 -246.914416)
					(end 95.645986 -246.914416)
				)
			)
		)
	)
	(zone
		(layers "B.Cu" "In4.Cu" "In6.Cu" "In11.Cu" "In13.Cu" "In15.Cu")
		(hatch none 0.5)
		(connect_pads
			(clearance 0)
		)
		(min_thickness 0.25)
		(keepout
			(tracks not_allowed)
			(vias allowed)
			(pads allowed)
			(copperpour not_allowed)
			(footprints allowed)
		)
		(placement
			(enabled no)
			(sheetname "")
		)
		(fill yes
			(thermal_gap 0.5)
			(thermal_bridge_width 0.5)
			(island_removal_mode 0)
		)
		(polygon
			(pts
				(arc
					(start 431.89017 -309.535068)
					(mid 431.22215 -309.535068)
					(end 431.89017 -309.535068)
				)
			)
		)
	)
	(zone
		(layers "B.Cu" "In4.Cu" "In6.Cu" "In11.Cu" "In13.Cu" "In15.Cu")
		(hatch none 0.5)
		(connect_pads
			(clearance 0)
		)
		(min_thickness 0.25)
		(keepout
			(tracks not_allowed)
			(vias allowed)
			(pads allowed)
			(copperpour not_allowed)
			(footprints allowed)
		)
		(placement
			(enabled no)
			(sheetname "")
		)
		(fill yes
			(thermal_gap 0.5)
			(thermal_bridge_width 0.5)
			(island_removal_mode 0)
		)
		(polygon
			(pts
				(arc
					(start 183.950102 -300.185328)
					(mid 183.282082 -300.185328)
					(end 183.950102 -300.185328)
				)
			)
		)
	)
	(zone
		(layers "B.Cu" "In4.Cu" "In6.Cu" "In11.Cu" "In13.Cu" "In15.Cu")
		(hatch none 0.5)
		(connect_pads
			(clearance 0)
		)
		(min_thickness 0.25)
		(keepout
			(tracks not_allowed)
			(vias allowed)
			(pads allowed)
			(copperpour not_allowed)
			(footprints allowed)
		)
		(placement
			(enabled no)
			(sheetname "")
		)
		(fill yes
			(thermal_gap 0.5)
			(thermal_bridge_width 0.5)
			(island_removal_mode 0)
		)
		(polygon
			(pts
				(arc
					(start 44.674028 -197.335394)
					(mid 44.006008 -197.335394)
					(end 44.674028 -197.335394)
				)
			)
		)
	)
	(zone
		(layers "B.Cu" "In4.Cu" "In6.Cu" "In11.Cu" "In13.Cu" "In15.Cu")
		(hatch none 0.5)
		(connect_pads
			(clearance 0)
		)
		(min_thickness 0.25)
		(keepout
			(tracks not_allowed)
			(vias allowed)
			(pads allowed)
			(copperpour not_allowed)
			(footprints allowed)
		)
		(placement
			(enabled no)
			(sheetname "")
		)
		(fill yes
			(thermal_gap 0.5)
			(thermal_bridge_width 0.5)
			(island_removal_mode 0)
		)
		(polygon
			(pts
				(arc
					(start 128.839722 -265.98626)
					(mid 128.209802 -265.98626)
					(end 128.839722 -265.98626)
				)
			)
		)
	)
	(zone
		(layers "B.Cu" "In4.Cu" "In6.Cu" "In11.Cu" "In13.Cu" "In15.Cu")
		(hatch none 0.5)
		(connect_pads
			(clearance 0)
		)
		(min_thickness 0.25)
		(keepout
			(tracks not_allowed)
			(vias allowed)
			(pads allowed)
			(copperpour not_allowed)
			(footprints allowed)
		)
		(placement
			(enabled no)
			(sheetname "")
		)
		(fill yes
			(thermal_gap 0.5)
			(thermal_bridge_width 0.5)
			(island_removal_mode 0)
		)
		(polygon
			(pts
				(arc
					(start 179.850034 -218.585288)
					(mid 179.182014 -218.585288)
					(end 179.850034 -218.585288)
				)
			)
		)
	)
	(zone
		(layers "B.Cu" "In4.Cu" "In6.Cu" "In11.Cu" "In13.Cu" "In15.Cu")
		(hatch none 0.5)
		(connect_pads
			(clearance 0)
		)
		(min_thickness 0.25)
		(keepout
			(tracks not_allowed)
			(vias allowed)
			(pads allowed)
			(copperpour not_allowed)
			(footprints allowed)
		)
		(placement
			(enabled no)
			(sheetname "")
		)
		(fill yes
			(thermal_gap 0.5)
			(thermal_bridge_width 0.5)
			(island_removal_mode 0)
		)
		(polygon
			(pts
				(arc
					(start 343.586054 -253.39421)
					(mid 342.956134 -253.39421)
					(end 343.586054 -253.39421)
				)
			)
		)
	)
	(zone
		(layers "B.Cu" "In4.Cu" "In6.Cu" "In11.Cu" "In13.Cu" "In15.Cu")
		(hatch none 0.5)
		(connect_pads
			(clearance 0)
		)
		(min_thickness 0.25)
		(keepout
			(tracks not_allowed)
			(vias allowed)
			(pads allowed)
			(copperpour not_allowed)
			(footprints allowed)
		)
		(placement
			(enabled no)
			(sheetname "")
		)
		(fill yes
			(thermal_gap 0.5)
			(thermal_bridge_width 0.5)
			(island_removal_mode 0)
		)
		(polygon
			(pts
				(arc
					(start 128.369822 -271.656302)
					(mid 127.739902 -271.656302)
					(end 128.369822 -271.656302)
				)
			)
		)
	)
	(zone
		(layers "B.Cu" "In4.Cu" "In6.Cu" "In11.Cu" "In13.Cu" "In15.Cu")
		(hatch none 0.5)
		(connect_pads
			(clearance 0)
		)
		(min_thickness 0.25)
		(keepout
			(tracks not_allowed)
			(vias allowed)
			(pads allowed)
			(copperpour not_allowed)
			(footprints allowed)
		)
		(placement
			(enabled no)
			(sheetname "")
		)
		(fill yes
			(thermal_gap 0.5)
			(thermal_bridge_width 0.5)
			(island_removal_mode 0)
		)
		(polygon
			(pts
				(arc
					(start 344.356182 -292.71595)
					(mid 343.726262 -292.71595)
					(end 344.356182 -292.71595)
				)
			)
		)
	)
	(zone
		(layers "B.Cu" "In4.Cu" "In6.Cu" "In11.Cu" "In13.Cu" "In15.Cu")
		(hatch none 0.5)
		(connect_pads
			(clearance 0)
		)
		(min_thickness 0.25)
		(keepout
			(tracks not_allowed)
			(vias allowed)
			(pads allowed)
			(copperpour not_allowed)
			(footprints allowed)
		)
		(placement
			(enabled no)
			(sheetname "")
		)
		(fill yes
			(thermal_gap 0.5)
			(thermal_bridge_width 0.5)
			(island_removal_mode 0)
		)
		(polygon
			(pts
				(arc
					(start 128.069594 -236.384338)
					(mid 127.439674 -236.384338)
					(end 128.069594 -236.384338)
				)
			)
		)
	)
	(zone
		(layers "B.Cu" "In4.Cu" "In6.Cu" "In11.Cu" "In13.Cu" "In15.Cu")
		(hatch none 0.5)
		(connect_pads
			(clearance 0)
		)
		(min_thickness 0.25)
		(keepout
			(tracks not_allowed)
			(vias allowed)
			(pads allowed)
			(copperpour not_allowed)
			(footprints allowed)
		)
		(placement
			(enabled no)
			(sheetname "")
		)
		(fill yes
			(thermal_gap 0.5)
			(thermal_bridge_width 0.5)
			(island_removal_mode 0)
		)
		(polygon
			(pts
				(arc
					(start 256.261108 -212.942424)
					(mid 255.593088 -212.942424)
					(end 256.261108 -212.942424)
				)
			)
		)
	)
	(zone
		(layers "B.Cu" "In4.Cu" "In6.Cu" "In11.Cu" "In13.Cu" "In15.Cu")
		(hatch none 0.5)
		(connect_pads
			(clearance 0)
		)
		(min_thickness 0.25)
		(keepout
			(tracks not_allowed)
			(vias allowed)
			(pads allowed)
			(copperpour not_allowed)
			(footprints allowed)
		)
		(placement
			(enabled no)
			(sheetname "")
		)
		(fill yes
			(thermal_gap 0.5)
			(thermal_bridge_width 0.5)
			(island_removal_mode 0)
		)
		(polygon
			(pts
				(arc
					(start 431.89017 -261.085076)
					(mid 431.22215 -261.085076)
					(end 431.89017 -261.085076)
				)
			)
		)
	)
	(zone
		(layers "B.Cu" "In4.Cu" "In6.Cu" "In11.Cu" "In13.Cu" "In15.Cu")
		(hatch none 0.5)
		(connect_pads
			(clearance 0)
		)
		(min_thickness 0.25)
		(keepout
			(tracks not_allowed)
			(vias allowed)
			(pads allowed)
			(copperpour not_allowed)
			(footprints allowed)
		)
		(placement
			(enabled no)
			(sheetname "")
		)
		(fill yes
			(thermal_gap 0.5)
			(thermal_bridge_width 0.5)
			(island_removal_mode 0)
		)
		(polygon
			(pts
				(arc
					(start 376.77979 -291.905944)
					(mid 376.14987 -291.905944)
					(end 376.77979 -291.905944)
				)
			)
		)
	)
	(zone
		(layers "B.Cu" "In4.Cu" "In6.Cu" "In11.Cu" "In13.Cu" "In15.Cu")
		(hatch none 0.5)
		(connect_pads
			(clearance 0)
		)
		(min_thickness 0.25)
		(keepout
			(tracks not_allowed)
			(vias allowed)
			(pads allowed)
			(copperpour not_allowed)
			(footprints allowed)
		)
		(placement
			(enabled no)
			(sheetname "")
		)
		(fill yes
			(thermal_gap 0.5)
			(thermal_bridge_width 0.5)
			(island_removal_mode 0)
		)
		(polygon
			(pts
				(arc
					(start 128.069594 -233.144314)
					(mid 127.439674 -233.144314)
					(end 128.069594 -233.144314)
				)
			)
		)
	)
	(zone
		(layers "B.Cu" "In4.Cu" "In6.Cu" "In11.Cu" "In13.Cu" "In15.Cu")
		(hatch none 0.5)
		(connect_pads
			(clearance 0)
		)
		(min_thickness 0.25)
		(keepout
			(tracks not_allowed)
			(vias allowed)
			(pads allowed)
			(copperpour not_allowed)
			(footprints allowed)
		)
		(placement
			(enabled no)
			(sheetname "")
		)
		(fill yes
			(thermal_gap 0.5)
			(thermal_bridge_width 0.5)
			(island_removal_mode 0)
		)
		(polygon
			(pts
				(arc
					(start 292.614096 -234.735116)
					(mid 291.946076 -234.735116)
					(end 292.614096 -234.735116)
				)
			)
		)
	)
	(zone
		(layers "B.Cu" "In4.Cu" "In6.Cu" "In11.Cu" "In13.Cu" "In15.Cu")
		(hatch none 0.5)
		(connect_pads
			(clearance 0)
		)
		(min_thickness 0.25)
		(keepout
			(tracks not_allowed)
			(vias allowed)
			(pads allowed)
			(copperpour not_allowed)
			(footprints allowed)
		)
		(placement
			(enabled no)
			(sheetname "")
		)
		(fill yes
			(thermal_gap 0.5)
			(thermal_bridge_width 0.5)
			(island_removal_mode 0)
		)
		(polygon
			(pts
				(arc
					(start 96.416114 -281.376374)
					(mid 95.786194 -281.376374)
					(end 96.416114 -281.376374)
				)
			)
		)
	)
	(zone
		(layers "B.Cu" "In4.Cu" "In6.Cu" "In11.Cu" "In13.Cu" "In15.Cu")
		(hatch none 0.5)
		(connect_pads
			(clearance 0)
		)
		(min_thickness 0.25)
		(keepout
			(tracks not_allowed)
			(vias allowed)
			(pads allowed)
			(copperpour not_allowed)
			(footprints allowed)
		)
		(placement
			(enabled no)
			(sheetname "")
		)
		(fill yes
			(thermal_gap 0.5)
			(thermal_bridge_width 0.5)
			(island_removal_mode 0)
		)
		(polygon
			(pts
				(arc
					(start 288.514028 -199.885046)
					(mid 287.846008 -199.885046)
					(end 288.514028 -199.885046)
				)
			)
		)
	)
	(zone
		(layers "B.Cu" "In4.Cu" "In6.Cu" "In11.Cu" "In13.Cu" "In15.Cu")
		(hatch none 0.5)
		(connect_pads
			(clearance 0)
		)
		(min_thickness 0.25)
		(keepout
			(tracks not_allowed)
			(vias allowed)
			(pads allowed)
			(copperpour not_allowed)
			(footprints allowed)
		)
		(placement
			(enabled no)
			(sheetname "")
		)
		(fill yes
			(thermal_gap 0.5)
			(thermal_bridge_width 0.5)
			(island_removal_mode 0)
		)
		(polygon
			(pts
				(arc
					(start 292.614096 -296.78503)
					(mid 291.946076 -296.78503)
					(end 292.614096 -296.78503)
				)
			)
		)
	)
	(zone
		(layers "B.Cu" "In4.Cu" "In6.Cu" "In11.Cu" "In13.Cu" "In15.Cu")
		(hatch none 0.5)
		(connect_pads
			(clearance 0)
		)
		(min_thickness 0.25)
		(keepout
			(tracks not_allowed)
			(vias allowed)
			(pads allowed)
			(copperpour not_allowed)
			(footprints allowed)
		)
		(placement
			(enabled no)
			(sheetname "")
		)
		(fill yes
			(thermal_gap 0.5)
			(thermal_bridge_width 0.5)
			(island_removal_mode 0)
		)
		(polygon
			(pts
				(arc
					(start 346.236036 -292.71595)
					(mid 345.606116 -292.71595)
					(end 346.236036 -292.71595)
				)
			)
		)
	)
	(zone
		(layers "B.Cu" "In4.Cu" "In6.Cu" "In11.Cu" "In13.Cu" "In15.Cu")
		(hatch none 0.5)
		(connect_pads
			(clearance 0)
		)
		(min_thickness 0.25)
		(keepout
			(tracks not_allowed)
			(vias allowed)
			(pads allowed)
			(copperpour not_allowed)
			(footprints allowed)
		)
		(placement
			(enabled no)
			(sheetname "")
		)
		(fill yes
			(thermal_gap 0.5)
			(thermal_bridge_width 0.5)
			(island_removal_mode 0)
		)
		(polygon
			(pts
				(arc
					(start 40.57396 -226.23526)
					(mid 39.90594 -226.23526)
					(end 40.57396 -226.23526)
				)
			)
		)
	)
	(zone
		(layers "B.Cu" "In4.Cu" "In6.Cu" "In11.Cu" "In13.Cu" "In15.Cu")
		(hatch none 0.5)
		(connect_pads
			(clearance 0)
		)
		(min_thickness 0.25)
		(keepout
			(tracks not_allowed)
			(vias allowed)
			(pads allowed)
			(copperpour not_allowed)
			(footprints allowed)
		)
		(placement
			(enabled no)
			(sheetname "")
		)
		(fill yes
			(thermal_gap 0.5)
			(thermal_bridge_width 0.5)
			(island_removal_mode 0)
		)
		(polygon
			(pts
				(arc
					(start 94.705932 -246.914416)
					(mid 94.076012 -246.914416)
					(end 94.705932 -246.914416)
				)
			)
		)
	)
	(zone
		(layers "B.Cu" "In4.Cu" "In6.Cu" "In11.Cu" "In13.Cu" "In15.Cu")
		(hatch none 0.5)
		(connect_pads
			(clearance 0)
		)
		(min_thickness 0.25)
		(keepout
			(tracks not_allowed)
			(vias allowed)
			(pads allowed)
			(copperpour not_allowed)
			(footprints allowed)
		)
		(placement
			(enabled no)
			(sheetname "")
		)
		(fill yes
			(thermal_gap 0.5)
			(thermal_bridge_width 0.5)
			(island_removal_mode 0)
		)
		(polygon
			(pts
				(arc
					(start 128.069594 -238.00435)
					(mid 127.439674 -238.00435)
					(end 128.069594 -238.00435)
				)
			)
		)
	)
	(zone
		(layers "B.Cu" "In4.Cu" "In6.Cu" "In11.Cu" "In13.Cu" "In15.Cu")
		(hatch none 0.5)
		(connect_pads
			(clearance 0)
		)
		(min_thickness 0.25)
		(keepout
			(tracks not_allowed)
			(vias allowed)
			(pads allowed)
			(copperpour not_allowed)
			(footprints allowed)
		)
		(placement
			(enabled no)
			(sheetname "")
		)
		(fill yes
			(thermal_gap 0.5)
			(thermal_bridge_width 0.5)
			(island_removal_mode 0)
		)
		(polygon
			(pts
				(arc
					(start 376.479816 -232.334054)
					(mid 375.849896 -232.334054)
					(end 376.479816 -232.334054)
				)
			)
		)
	)
	(zone
		(layers "B.Cu" "In4.Cu" "In6.Cu" "In11.Cu" "In13.Cu" "In15.Cu")
		(hatch none 0.5)
		(connect_pads
			(clearance 0)
		)
		(min_thickness 0.25)
		(keepout
			(tracks not_allowed)
			(vias allowed)
			(pads allowed)
			(copperpour not_allowed)
			(footprints allowed)
		)
		(placement
			(enabled no)
			(sheetname "")
		)
		(fill yes
			(thermal_gap 0.5)
			(thermal_bridge_width 0.5)
			(island_removal_mode 0)
		)
		(polygon
			(pts
				(arc
					(start 95.94596 -283.806392)
					(mid 95.31604 -283.806392)
					(end 95.94596 -283.806392)
				)
			)
		)
	)
	(zone
		(layers "B.Cu" "In4.Cu" "In6.Cu" "In11.Cu" "In13.Cu" "In15.Cu")
		(hatch none 0.5)
		(connect_pads
			(clearance 0)
		)
		(min_thickness 0.25)
		(keepout
			(tracks not_allowed)
			(vias allowed)
			(pads allowed)
			(copperpour not_allowed)
			(footprints allowed)
		)
		(placement
			(enabled no)
			(sheetname "")
		)
		(fill yes
			(thermal_gap 0.5)
			(thermal_bridge_width 0.5)
			(island_removal_mode 0)
		)
		(polygon
			(pts
				(arc
					(start 103.936038 -294.336216)
					(mid 103.306118 -294.336216)
					(end 103.936038 -294.336216)
				)
			)
		)
	)
	(zone
		(layers "B.Cu" "In4.Cu" "In6.Cu" "In11.Cu" "In13.Cu" "In15.Cu")
		(hatch none 0.5)
		(connect_pads
			(clearance 0)
		)
		(min_thickness 0.25)
		(keepout
			(tracks not_allowed)
			(vias allowed)
			(pads allowed)
			(copperpour not_allowed)
			(footprints allowed)
		)
		(placement
			(enabled no)
			(sheetname "")
		)
		(fill yes
			(thermal_gap 0.5)
			(thermal_bridge_width 0.5)
			(island_removal_mode 0)
		)
		(polygon
			(pts
				(arc
					(start 179.345844 -52.481734)
					(mid 178.677824 -52.481734)
					(end 179.345844 -52.481734)
				)
			)
		)
	)
	(zone
		(layers "B.Cu" "In4.Cu" "In6.Cu" "In11.Cu" "In13.Cu" "In15.Cu")
		(hatch none 0.5)
		(connect_pads
			(clearance 0)
		)
		(min_thickness 0.25)
		(keepout
			(tracks not_allowed)
			(vias allowed)
			(pads allowed)
			(copperpour not_allowed)
			(footprints allowed)
		)
		(placement
			(enabled no)
			(sheetname "")
		)
		(fill yes
			(thermal_gap 0.5)
			(thermal_bridge_width 0.5)
			(island_removal_mode 0)
		)
		(polygon
			(pts
				(arc
					(start 288.514028 -241.53495)
					(mid 287.846008 -241.53495)
					(end 288.514028 -241.53495)
				)
			)
		)
	)
	(zone
		(layers "B.Cu" "In4.Cu" "In6.Cu" "In11.Cu" "In13.Cu" "In15.Cu")
		(hatch none 0.5)
		(connect_pads
			(clearance 0)
		)
		(min_thickness 0.25)
		(keepout
			(tracks not_allowed)
			(vias allowed)
			(pads allowed)
			(copperpour not_allowed)
			(footprints allowed)
		)
		(placement
			(enabled no)
			(sheetname "")
		)
		(fill yes
			(thermal_gap 0.5)
			(thermal_bridge_width 0.5)
			(island_removal_mode 0)
		)
		(polygon
			(pts
				(arc
					(start 183.950102 -261.08533)
					(mid 183.282082 -261.08533)
					(end 183.950102 -261.08533)
				)
			)
		)
	)
	(zone
		(layers "B.Cu" "In4.Cu" "In6.Cu" "In11.Cu" "In13.Cu" "In15.Cu")
		(hatch none 0.5)
		(connect_pads
			(clearance 0)
		)
		(min_thickness 0.25)
		(keepout
			(tracks not_allowed)
			(vias allowed)
			(pads allowed)
			(copperpour not_allowed)
			(footprints allowed)
		)
		(placement
			(enabled no)
			(sheetname "")
		)
		(fill yes
			(thermal_gap 0.5)
			(thermal_bridge_width 0.5)
			(island_removal_mode 0)
		)
		(polygon
			(pts
				(arc
					(start 183.950102 -238.985298)
					(mid 183.282082 -238.985298)
					(end 183.950102 -238.985298)
				)
			)
		)
	)
	(zone
		(layers "B.Cu" "In4.Cu" "In6.Cu" "In11.Cu" "In13.Cu" "In15.Cu")
		(hatch none 0.5)
		(connect_pads
			(clearance 0)
		)
		(min_thickness 0.25)
		(keepout
			(tracks not_allowed)
			(vias allowed)
			(pads allowed)
			(copperpour not_allowed)
			(footprints allowed)
		)
		(placement
			(enabled no)
			(sheetname "")
		)
		(fill yes
			(thermal_gap 0.5)
			(thermal_bridge_width 0.5)
			(island_removal_mode 0)
		)
		(polygon
			(pts
				(arc
					(start 427.790102 -218.585034)
					(mid 427.122082 -218.585034)
					(end 427.790102 -218.585034)
				)
			)
		)
	)
	(zone
		(layers "B.Cu" "In4.Cu" "In6.Cu" "In11.Cu" "In13.Cu" "In15.Cu")
		(hatch none 0.5)
		(connect_pads
			(clearance 0)
		)
		(min_thickness 0.25)
		(keepout
			(tracks not_allowed)
			(vias allowed)
			(pads allowed)
			(copperpour not_allowed)
			(footprints allowed)
		)
		(placement
			(enabled no)
			(sheetname "")
		)
		(fill yes
			(thermal_gap 0.5)
			(thermal_bridge_width 0.5)
			(island_removal_mode 0)
		)
		(polygon
			(pts
				(arc
					(start 288.514028 -204.134974)
					(mid 287.846008 -204.134974)
					(end 288.514028 -204.134974)
				)
			)
		)
	)
	(zone
		(layers "B.Cu" "In4.Cu" "In6.Cu" "In11.Cu" "In13.Cu" "In15.Cu")
		(hatch none 0.5)
		(connect_pads
			(clearance 0)
		)
		(min_thickness 0.25)
		(keepout
			(tracks not_allowed)
			(vias allowed)
			(pads allowed)
			(copperpour not_allowed)
			(footprints allowed)
		)
		(placement
			(enabled no)
			(sheetname "")
		)
		(fill yes
			(thermal_gap 0.5)
			(thermal_bridge_width 0.5)
			(island_removal_mode 0)
		)
		(polygon
			(pts
				(arc
					(start 183.950102 -269.58544)
					(mid 183.282082 -269.58544)
					(end 183.950102 -269.58544)
				)
			)
		)
	)
	(zone
		(layers "B.Cu" "In4.Cu" "In6.Cu" "In11.Cu" "In13.Cu" "In15.Cu")
		(hatch none 0.5)
		(connect_pads
			(clearance 0)
		)
		(min_thickness 0.25)
		(keepout
			(tracks not_allowed)
			(vias allowed)
			(pads allowed)
			(copperpour not_allowed)
			(footprints allowed)
		)
		(placement
			(enabled no)
			(sheetname "")
		)
		(fill yes
			(thermal_gap 0.5)
			(thermal_bridge_width 0.5)
			(island_removal_mode 0)
		)
		(polygon
			(pts
				(arc
					(start 40.57396 -267.03528)
					(mid 39.90594 -267.03528)
					(end 40.57396 -267.03528)
				)
			)
		)
	)
	(zone
		(layers "B.Cu" "In4.Cu" "In6.Cu" "In11.Cu" "In13.Cu" "In15.Cu")
		(hatch none 0.5)
		(connect_pads
			(clearance 0)
		)
		(min_thickness 0.25)
		(keepout
			(tracks not_allowed)
			(vias allowed)
			(pads allowed)
			(copperpour not_allowed)
			(footprints allowed)
		)
		(placement
			(enabled no)
			(sheetname "")
		)
		(fill yes
			(thermal_gap 0.5)
			(thermal_bridge_width 0.5)
			(island_removal_mode 0)
		)
		(polygon
			(pts
				(arc
					(start 184.71896 6.495034)
					(mid 184.05094 6.495034)
					(end 184.71896 6.495034)
				)
			)
		)
	)
	(zone
		(layers "B.Cu" "In4.Cu" "In6.Cu" "In11.Cu" "In13.Cu" "In15.Cu")
		(hatch none 0.5)
		(connect_pads
			(clearance 0)
		)
		(min_thickness 0.25)
		(keepout
			(tracks not_allowed)
			(vias allowed)
			(pads allowed)
			(copperpour not_allowed)
			(footprints allowed)
		)
		(placement
			(enabled no)
			(sheetname "")
		)
		(fill yes
			(thermal_gap 0.5)
			(thermal_bridge_width 0.5)
			(island_removal_mode 0)
		)
		(polygon
			(pts
				(arc
					(start 183.950102 -289.135312)
					(mid 183.282082 -289.135312)
					(end 183.950102 -289.135312)
				)
			)
		)
	)
	(zone
		(layers "B.Cu" "In4.Cu" "In6.Cu" "In11.Cu" "In13.Cu" "In15.Cu")
		(hatch none 0.5)
		(connect_pads
			(clearance 0)
		)
		(min_thickness 0.25)
		(keepout
			(tracks not_allowed)
			(vias allowed)
			(pads allowed)
			(copperpour not_allowed)
			(footprints allowed)
		)
		(placement
			(enabled no)
			(sheetname "")
		)
		(fill yes
			(thermal_gap 0.5)
			(thermal_bridge_width 0.5)
			(island_removal_mode 0)
		)
		(polygon
			(pts
				(arc
					(start 179.850034 -207.535272)
					(mid 179.182014 -207.535272)
					(end 179.850034 -207.535272)
				)
			)
		)
	)
	(zone
		(layers "B.Cu" "In4.Cu" "In6.Cu" "In11.Cu" "In13.Cu" "In15.Cu")
		(hatch none 0.5)
		(connect_pads
			(clearance 0)
		)
		(min_thickness 0.25)
		(keepout
			(tracks not_allowed)
			(vias allowed)
			(pads allowed)
			(copperpour not_allowed)
			(footprints allowed)
		)
		(placement
			(enabled no)
			(sheetname "")
		)
		(fill yes
			(thermal_gap 0.5)
			(thermal_bridge_width 0.5)
			(island_removal_mode 0)
		)
		(polygon
			(pts
				(arc
					(start 343.586054 -248.534174)
					(mid 342.956134 -248.534174)
					(end 343.586054 -248.534174)
				)
			)
		)
	)
	(zone
		(layers "B.Cu" "In4.Cu" "In6.Cu" "In11.Cu" "In13.Cu" "In15.Cu")
		(hatch none 0.5)
		(connect_pads
			(clearance 0)
		)
		(min_thickness 0.25)
		(keepout
			(tracks not_allowed)
			(vias allowed)
			(pads allowed)
			(copperpour not_allowed)
			(footprints allowed)
		)
		(placement
			(enabled no)
			(sheetname "")
		)
		(fill yes
			(thermal_gap 0.5)
			(thermal_bridge_width 0.5)
			(island_removal_mode 0)
		)
		(polygon
			(pts
				(arc
					(start 342.945974 -274.086066)
					(mid 342.316054 -274.086066)
					(end 342.945974 -274.086066)
				)
			)
		)
	)
	(zone
		(layers "B.Cu" "In4.Cu" "In6.Cu" "In11.Cu" "In13.Cu" "In15.Cu")
		(hatch none 0.5)
		(connect_pads
			(clearance 0)
		)
		(min_thickness 0.25)
		(keepout
			(tracks not_allowed)
			(vias allowed)
			(pads allowed)
			(copperpour not_allowed)
			(footprints allowed)
		)
		(placement
			(enabled no)
			(sheetname "")
		)
		(fill yes
			(thermal_gap 0.5)
			(thermal_bridge_width 0.5)
			(island_removal_mode 0)
		)
		(polygon
			(pts
				(arc
					(start 128.539748 -242.05438)
					(mid 127.909828 -242.05438)
					(end 128.539748 -242.05438)
				)
			)
		)
	)
	(zone
		(layers "B.Cu" "In4.Cu" "In6.Cu" "In11.Cu" "In13.Cu" "In15.Cu")
		(hatch none 0.5)
		(connect_pads
			(clearance 0)
		)
		(min_thickness 0.25)
		(keepout
			(tracks not_allowed)
			(vias allowed)
			(pads allowed)
			(copperpour not_allowed)
			(footprints allowed)
		)
		(placement
			(enabled no)
			(sheetname "")
		)
		(fill yes
			(thermal_gap 0.5)
			(thermal_bridge_width 0.5)
			(island_removal_mode 0)
		)
		(polygon
			(pts
				(arc
					(start 94.236032 -236.384338)
					(mid 93.606112 -236.384338)
					(end 94.236032 -236.384338)
				)
			)
		)
	)
	(zone
		(layers "B.Cu" "In4.Cu" "In6.Cu" "In11.Cu" "In13.Cu" "In15.Cu")
		(hatch none 0.5)
		(connect_pads
			(clearance 0)
		)
		(min_thickness 0.25)
		(keepout
			(tracks not_allowed)
			(vias allowed)
			(pads allowed)
			(copperpour not_allowed)
			(footprints allowed)
		)
		(placement
			(enabled no)
			(sheetname "")
		)
		(fill yes
			(thermal_gap 0.5)
			(thermal_bridge_width 0.5)
			(island_removal_mode 0)
		)
		(polygon
			(pts
				(arc
					(start 288.514028 -267.035026)
					(mid 287.846008 -267.035026)
					(end 288.514028 -267.035026)
				)
			)
		)
	)
	(zone
		(layers "B.Cu" "In4.Cu" "In6.Cu" "In11.Cu" "In13.Cu" "In15.Cu")
		(hatch none 0.5)
		(connect_pads
			(clearance 0)
		)
		(min_thickness 0.25)
		(keepout
			(tracks not_allowed)
			(vias allowed)
			(pads allowed)
			(copperpour not_allowed)
			(footprints allowed)
		)
		(placement
			(enabled no)
			(sheetname "")
		)
		(fill yes
			(thermal_gap 0.5)
			(thermal_bridge_width 0.5)
			(island_removal_mode 0)
		)
		(polygon
			(pts
				(arc
					(start 109.746034 -229.094538)
					(mid 109.116114 -229.094538)
					(end 109.746034 -229.094538)
				)
			)
		)
	)
	(zone
		(layers "B.Cu" "In4.Cu" "In6.Cu" "In11.Cu" "In13.Cu" "In15.Cu")
		(hatch none 0.5)
		(connect_pads
			(clearance 0)
		)
		(min_thickness 0.25)
		(keepout
			(tracks not_allowed)
			(vias allowed)
			(pads allowed)
			(copperpour not_allowed)
			(footprints allowed)
		)
		(placement
			(enabled no)
			(sheetname "")
		)
		(fill yes
			(thermal_gap 0.5)
			(thermal_bridge_width 0.5)
			(island_removal_mode 0)
		)
		(polygon
			(pts
				(arc
					(start 107.396026 -229.90429)
					(mid 106.766106 -229.90429)
					(end 107.396026 -229.90429)
				)
			)
		)
	)
	(zone
		(layers "B.Cu" "In4.Cu" "In6.Cu" "In11.Cu" "In13.Cu" "In15.Cu")
		(hatch none 0.5)
		(connect_pads
			(clearance 0)
		)
		(min_thickness 0.25)
		(keepout
			(tracks not_allowed)
			(vias allowed)
			(pads allowed)
			(copperpour not_allowed)
			(footprints allowed)
		)
		(placement
			(enabled no)
			(sheetname "")
		)
		(fill yes
			(thermal_gap 0.5)
			(thermal_bridge_width 0.5)
			(island_removal_mode 0)
		)
		(polygon
			(pts
				(arc
					(start 431.89017 -247.485154)
					(mid 431.22215 -247.485154)
					(end 431.89017 -247.485154)
				)
			)
		)
	)
	(zone
		(layers "B.Cu" "In4.Cu" "In6.Cu" "In11.Cu" "In13.Cu" "In15.Cu")
		(hatch none 0.5)
		(connect_pads
			(clearance 0)
		)
		(min_thickness 0.25)
		(keepout
			(tracks not_allowed)
			(vias allowed)
			(pads allowed)
			(copperpour not_allowed)
			(footprints allowed)
		)
		(placement
			(enabled no)
			(sheetname "")
		)
		(fill yes
			(thermal_gap 0.5)
			(thermal_bridge_width 0.5)
			(island_removal_mode 0)
		)
		(polygon
			(pts
				(arc
					(start 376.009662 -229.904036)
					(mid 375.379742 -229.904036)
					(end 376.009662 -229.904036)
				)
			)
		)
	)
	(zone
		(layers "B.Cu" "In4.Cu" "In6.Cu" "In11.Cu" "In13.Cu" "In15.Cu")
		(hatch none 0.5)
		(connect_pads
			(clearance 0)
		)
		(min_thickness 0.25)
		(keepout
			(tracks not_allowed)
			(vias allowed)
			(pads allowed)
			(copperpour not_allowed)
			(footprints allowed)
		)
		(placement
			(enabled no)
			(sheetname "")
		)
		(fill yes
			(thermal_gap 0.5)
			(thermal_bridge_width 0.5)
			(island_removal_mode 0)
		)
		(polygon
			(pts
				(arc
					(start 96.115886 -247.724422)
					(mid 95.485966 -247.724422)
					(end 96.115886 -247.724422)
				)
			)
		)
	)
	(zone
		(layers "B.Cu" "In4.Cu" "In6.Cu" "In11.Cu" "In13.Cu" "In15.Cu")
		(hatch none 0.5)
		(connect_pads
			(clearance 0)
		)
		(min_thickness 0.25)
		(keepout
			(tracks not_allowed)
			(vias allowed)
			(pads allowed)
			(copperpour not_allowed)
			(footprints allowed)
		)
		(placement
			(enabled no)
			(sheetname "")
		)
		(fill yes
			(thermal_gap 0.5)
			(thermal_bridge_width 0.5)
			(island_removal_mode 0)
		)
		(polygon
			(pts
				(arc
					(start 427.790102 -312.084974)
					(mid 427.122082 -312.084974)
					(end 427.790102 -312.084974)
				)
			)
		)
	)
	(zone
		(layers "B.Cu" "In4.Cu" "In6.Cu" "In11.Cu" "In13.Cu" "In15.Cu")
		(hatch none 0.5)
		(connect_pads
			(clearance 0)
		)
		(min_thickness 0.25)
		(keepout
			(tracks not_allowed)
			(vias allowed)
			(pads allowed)
			(copperpour not_allowed)
			(footprints allowed)
		)
		(placement
			(enabled no)
			(sheetname "")
		)
		(fill yes
			(thermal_gap 0.5)
			(thermal_bridge_width 0.5)
			(island_removal_mode 0)
		)
		(polygon
			(pts
				(arc
					(start 377.41987 -235.574078)
					(mid 376.78995 -235.574078)
					(end 377.41987 -235.574078)
				)
			)
		)
	)
	(zone
		(layers "B.Cu" "In4.Cu" "In6.Cu" "In11.Cu" "In13.Cu" "In15.Cu")
		(hatch none 0.5)
		(connect_pads
			(clearance 0)
		)
		(min_thickness 0.25)
		(keepout
			(tracks not_allowed)
			(vias allowed)
			(pads allowed)
			(copperpour not_allowed)
			(footprints allowed)
		)
		(placement
			(enabled no)
			(sheetname "")
		)
		(fill yes
			(thermal_gap 0.5)
			(thermal_bridge_width 0.5)
			(island_removal_mode 0)
		)
		(polygon
			(pts
				(arc
					(start 342.1761 -252.584204)
					(mid 341.54618 -252.584204)
					(end 342.1761 -252.584204)
				)
			)
		)
	)
	(zone
		(layers "B.Cu" "In4.Cu" "In6.Cu" "In11.Cu" "In13.Cu" "In15.Cu")
		(hatch none 0.5)
		(connect_pads
			(clearance 0)
		)
		(min_thickness 0.25)
		(keepout
			(tracks not_allowed)
			(vias allowed)
			(pads allowed)
			(copperpour not_allowed)
			(footprints allowed)
		)
		(placement
			(enabled no)
			(sheetname "")
		)
		(fill yes
			(thermal_gap 0.5)
			(thermal_bridge_width 0.5)
			(island_removal_mode 0)
		)
		(polygon
			(pts
				(arc
					(start 40.57396 -207.535272)
					(mid 39.90594 -207.535272)
					(end 40.57396 -207.535272)
				)
			)
		)
	)
	(zone
		(layers "B.Cu" "In4.Cu" "In6.Cu" "In11.Cu" "In13.Cu" "In15.Cu")
		(hatch none 0.5)
		(connect_pads
			(clearance 0)
		)
		(min_thickness 0.25)
		(keepout
			(tracks not_allowed)
			(vias allowed)
			(pads allowed)
			(copperpour not_allowed)
			(footprints allowed)
		)
		(placement
			(enabled no)
			(sheetname "")
		)
		(fill yes
			(thermal_gap 0.5)
			(thermal_bridge_width 0.5)
			(island_removal_mode 0)
		)
		(polygon
			(pts
				(arc
					(start 288.514028 -209.23504)
					(mid 287.846008 -209.23504)
					(end 288.514028 -209.23504)
				)
			)
		)
	)
	(zone
		(layers "B.Cu" "In4.Cu" "In6.Cu" "In11.Cu" "In13.Cu" "In15.Cu")
		(hatch none 0.5)
		(connect_pads
			(clearance 0)
		)
		(min_thickness 0.25)
		(keepout
			(tracks not_allowed)
			(vias allowed)
			(pads allowed)
			(copperpour not_allowed)
			(footprints allowed)
		)
		(placement
			(enabled no)
			(sheetname "")
		)
		(fill yes
			(thermal_gap 0.5)
			(thermal_bridge_width 0.5)
			(island_removal_mode 0)
		)
		(polygon
			(pts
				(arc
					(start 96.115886 -228.284532)
					(mid 95.485966 -228.284532)
					(end 96.115886 -228.284532)
				)
			)
		)
	)
	(zone
		(layers "B.Cu" "In4.Cu" "In6.Cu" "In11.Cu" "In13.Cu" "In15.Cu")
		(hatch none 0.5)
		(connect_pads
			(clearance 0)
		)
		(min_thickness 0.25)
		(keepout
			(tracks not_allowed)
			(vias allowed)
			(pads allowed)
			(copperpour not_allowed)
			(footprints allowed)
		)
		(placement
			(enabled no)
			(sheetname "")
		)
		(fill yes
			(thermal_gap 0.5)
			(thermal_bridge_width 0.5)
			(island_removal_mode 0)
		)
		(polygon
			(pts
				(arc
					(start 376.30989 -266.796012)
					(mid 375.67997 -266.796012)
					(end 376.30989 -266.796012)
				)
			)
		)
	)
	(zone
		(layers "B.Cu" "In4.Cu" "In6.Cu" "In11.Cu" "In13.Cu" "In15.Cu")
		(hatch none 0.5)
		(connect_pads
			(clearance 0)
		)
		(min_thickness 0.25)
		(keepout
			(tracks not_allowed)
			(vias allowed)
			(pads allowed)
			(copperpour not_allowed)
			(footprints allowed)
		)
		(placement
			(enabled no)
			(sheetname "")
		)
		(fill yes
			(thermal_gap 0.5)
			(thermal_bridge_width 0.5)
			(island_removal_mode 0)
		)
		(polygon
			(pts
				(arc
					(start 376.479816 -253.39421)
					(mid 375.849896 -253.39421)
					(end 376.479816 -253.39421)
				)
			)
		)
	)
	(zone
		(layers "B.Cu" "In4.Cu" "In6.Cu" "In11.Cu" "In13.Cu" "In15.Cu")
		(hatch none 0.5)
		(connect_pads
			(clearance 0)
		)
		(min_thickness 0.25)
		(keepout
			(tracks not_allowed)
			(vias allowed)
			(pads allowed)
			(copperpour not_allowed)
			(footprints allowed)
		)
		(placement
			(enabled no)
			(sheetname "")
		)
		(fill yes
			(thermal_gap 0.5)
			(thermal_bridge_width 0.5)
			(island_removal_mode 0)
		)
		(polygon
			(pts
				(arc
					(start 183.950102 -210.085432)
					(mid 183.282082 -210.085432)
					(end 183.950102 -210.085432)
				)
			)
		)
	)
	(zone
		(layers "B.Cu" "In4.Cu" "In6.Cu" "In11.Cu" "In13.Cu" "In15.Cu")
		(hatch none 0.5)
		(connect_pads
			(clearance 0)
		)
		(min_thickness 0.25)
		(keepout
			(tracks not_allowed)
			(vias allowed)
			(pads allowed)
			(copperpour not_allowed)
			(footprints allowed)
		)
		(placement
			(enabled no)
			(sheetname "")
		)
		(fill yes
			(thermal_gap 0.5)
			(thermal_bridge_width 0.5)
			(island_removal_mode 0)
		)
		(polygon
			(pts
				(arc
					(start 368.489738 -228.284278)
					(mid 367.859818 -228.284278)
					(end 368.489738 -228.284278)
				)
			)
		)
	)
	(zone
		(layers "B.Cu" "In4.Cu" "In6.Cu" "In11.Cu" "In13.Cu" "In15.Cu")
		(hatch none 0.5)
		(connect_pads
			(clearance 0)
		)
		(min_thickness 0.25)
		(keepout
			(tracks not_allowed)
			(vias allowed)
			(pads allowed)
			(copperpour not_allowed)
			(footprints allowed)
		)
		(placement
			(enabled no)
			(sheetname "")
		)
		(fill yes
			(thermal_gap 0.5)
			(thermal_bridge_width 0.5)
			(island_removal_mode 0)
		)
		(polygon
			(pts
				(arc
					(start 292.614096 -228.785166)
					(mid 291.946076 -228.785166)
					(end 292.614096 -228.785166)
				)
			)
		)
	)
	(zone
		(layers "B.Cu" "In4.Cu" "In6.Cu" "In11.Cu" "In13.Cu" "In15.Cu")
		(hatch none 0.5)
		(connect_pads
			(clearance 0)
		)
		(min_thickness 0.25)
		(keepout
			(tracks not_allowed)
			(vias allowed)
			(pads allowed)
			(copperpour not_allowed)
			(footprints allowed)
		)
		(placement
			(enabled no)
			(sheetname "")
		)
		(fill yes
			(thermal_gap 0.5)
			(thermal_bridge_width 0.5)
			(island_removal_mode 0)
		)
		(polygon
			(pts
				(arc
					(start 94.705932 -245.294404)
					(mid 94.076012 -245.294404)
					(end 94.705932 -245.294404)
				)
			)
		)
	)
	(zone
		(layers "B.Cu" "In4.Cu" "In6.Cu" "In11.Cu" "In13.Cu" "In15.Cu")
		(hatch none 0.5)
		(connect_pads
			(clearance 0)
		)
		(min_thickness 0.25)
		(keepout
			(tracks not_allowed)
			(vias allowed)
			(pads allowed)
			(copperpour not_allowed)
			(footprints allowed)
		)
		(placement
			(enabled no)
			(sheetname "")
		)
		(fill yes
			(thermal_gap 0.5)
			(thermal_bridge_width 0.5)
			(island_removal_mode 0)
		)
		(polygon
			(pts
				(arc
					(start 376.77979 -270.846042)
					(mid 376.14987 -270.846042)
					(end 376.77979 -270.846042)
				)
			)
		)
	)
	(zone
		(layers "B.Cu" "In4.Cu" "In6.Cu" "In11.Cu" "In13.Cu" "In15.Cu")
		(hatch none 0.5)
		(connect_pads
			(clearance 0)
		)
		(min_thickness 0.25)
		(keepout
			(tracks not_allowed)
			(vias allowed)
			(pads allowed)
			(copperpour not_allowed)
			(footprints allowed)
		)
		(placement
			(enabled no)
			(sheetname "")
		)
		(fill yes
			(thermal_gap 0.5)
			(thermal_bridge_width 0.5)
			(island_removal_mode 0)
		)
		(polygon
			(pts
				(arc
					(start 96.115886 -226.66452)
					(mid 95.485966 -226.66452)
					(end 96.115886 -226.66452)
				)
			)
		)
	)
	(zone
		(layers "B.Cu" "In4.Cu" "In6.Cu" "In11.Cu" "In13.Cu" "In15.Cu")
		(hatch none 0.5)
		(connect_pads
			(clearance 0)
		)
		(min_thickness 0.25)
		(keepout
			(tracks not_allowed)
			(vias allowed)
			(pads allowed)
			(copperpour not_allowed)
			(footprints allowed)
		)
		(placement
			(enabled no)
			(sheetname "")
		)
		(fill yes
			(thermal_gap 0.5)
			(thermal_bridge_width 0.5)
			(island_removal_mode 0)
		)
		(polygon
			(pts
				(arc
					(start 94.536006 -279.756362)
					(mid 93.906086 -279.756362)
					(end 94.536006 -279.756362)
				)
			)
		)
	)
	(zone
		(layers "B.Cu" "In4.Cu" "In6.Cu" "In11.Cu" "In13.Cu" "In15.Cu")
		(hatch none 0.5)
		(connect_pads
			(clearance 0)
		)
		(min_thickness 0.25)
		(keepout
			(tracks not_allowed)
			(vias allowed)
			(pads allowed)
			(copperpour not_allowed)
			(footprints allowed)
		)
		(placement
			(enabled no)
			(sheetname "")
		)
		(fill yes
			(thermal_gap 0.5)
			(thermal_bridge_width 0.5)
			(island_removal_mode 0)
		)
		(polygon
			(pts
				(arc
					(start 427.790102 -221.13494)
					(mid 427.122082 -221.13494)
					(end 427.790102 -221.13494)
				)
			)
		)
	)
	(zone
		(layers "B.Cu" "In4.Cu" "In6.Cu" "In11.Cu" "In13.Cu" "In15.Cu")
		(hatch none 0.5)
		(connect_pads
			(clearance 0)
		)
		(min_thickness 0.25)
		(keepout
			(tracks not_allowed)
			(vias allowed)
			(pads allowed)
			(copperpour not_allowed)
			(footprints allowed)
		)
		(placement
			(enabled no)
			(sheetname "")
		)
		(fill yes
			(thermal_gap 0.5)
			(thermal_bridge_width 0.5)
			(island_removal_mode 0)
		)
		(polygon
			(pts
				(arc
					(start 292.614096 -266.185142)
					(mid 291.946076 -266.185142)
					(end 292.614096 -266.185142)
				)
			)
		)
	)
	(zone
		(layers "B.Cu" "In4.Cu" "In6.Cu" "In11.Cu" "In13.Cu" "In15.Cu")
		(hatch none 0.5)
		(connect_pads
			(clearance 0)
		)
		(min_thickness 0.25)
		(keepout
			(tracks not_allowed)
			(vias allowed)
			(pads allowed)
			(copperpour not_allowed)
			(footprints allowed)
		)
		(placement
			(enabled no)
			(sheetname "")
		)
		(fill yes
			(thermal_gap 0.5)
			(thermal_bridge_width 0.5)
			(island_removal_mode 0)
		)
		(polygon
			(pts
				(arc
					(start 183.950102 -217.735404)
					(mid 183.282082 -217.735404)
					(end 183.950102 -217.735404)
				)
			)
		)
	)
	(zone
		(layers "B.Cu" "In4.Cu" "In6.Cu" "In11.Cu" "In13.Cu" "In15.Cu")
		(hatch none 0.5)
		(connect_pads
			(clearance 0)
		)
		(min_thickness 0.25)
		(keepout
			(tracks not_allowed)
			(vias allowed)
			(pads allowed)
			(copperpour not_allowed)
			(footprints allowed)
		)
		(placement
			(enabled no)
			(sheetname "")
		)
		(fill yes
			(thermal_gap 0.5)
			(thermal_bridge_width 0.5)
			(island_removal_mode 0)
		)
		(polygon
			(pts
				(arc
					(start 40.57396 -297.635422)
					(mid 39.90594 -297.635422)
					(end 40.57396 -297.635422)
				)
			)
		)
	)
	(zone
		(layers "B.Cu" "In4.Cu" "In6.Cu" "In11.Cu" "In13.Cu" "In15.Cu")
		(hatch none 0.5)
		(connect_pads
			(clearance 0)
		)
		(min_thickness 0.25)
		(keepout
			(tracks not_allowed)
			(vias allowed)
			(pads allowed)
			(copperpour not_allowed)
			(footprints allowed)
		)
		(placement
			(enabled no)
			(sheetname "")
		)
		(fill yes
			(thermal_gap 0.5)
			(thermal_bridge_width 0.5)
			(island_removal_mode 0)
		)
		(polygon
			(pts
				(arc
					(start 128.069594 -241.244374)
					(mid 127.439674 -241.244374)
					(end 128.069594 -241.244374)
				)
			)
		)
	)
	(zone
		(layers "B.Cu" "In4.Cu" "In6.Cu" "In11.Cu" "In13.Cu" "In15.Cu")
		(hatch none 0.5)
		(connect_pads
			(clearance 0)
		)
		(min_thickness 0.25)
		(keepout
			(tracks not_allowed)
			(vias allowed)
			(pads allowed)
			(copperpour not_allowed)
			(footprints allowed)
		)
		(placement
			(enabled no)
			(sheetname "")
		)
		(fill yes
			(thermal_gap 0.5)
			(thermal_bridge_width 0.5)
			(island_removal_mode 0)
		)
		(polygon
			(pts
				(arc
					(start 94.705932 -232.334308)
					(mid 94.076012 -232.334308)
					(end 94.705932 -232.334308)
				)
			)
		)
	)
	(zone
		(layers "B.Cu" "In4.Cu" "In6.Cu" "In11.Cu" "In13.Cu" "In15.Cu")
		(hatch none 0.5)
		(connect_pads
			(clearance 0)
		)
		(min_thickness 0.25)
		(keepout
			(tracks not_allowed)
			(vias allowed)
			(pads allowed)
			(copperpour not_allowed)
			(footprints allowed)
		)
		(placement
			(enabled no)
			(sheetname "")
		)
		(fill yes
			(thermal_gap 0.5)
			(thermal_bridge_width 0.5)
			(island_removal_mode 0)
		)
		(polygon
			(pts
				(arc
					(start 431.89017 -233.035094)
					(mid 431.22215 -233.035094)
					(end 431.89017 -233.035094)
				)
			)
		)
	)
	(zone
		(layers "B.Cu" "In4.Cu" "In6.Cu" "In11.Cu" "In13.Cu" "In15.Cu")
		(hatch none 0.5)
		(connect_pads
			(clearance 0)
		)
		(min_thickness 0.25)
		(keepout
			(tracks not_allowed)
			(vias allowed)
			(pads allowed)
			(copperpour not_allowed)
			(footprints allowed)
		)
		(placement
			(enabled no)
			(sheetname "")
		)
		(fill yes
			(thermal_gap 0.5)
			(thermal_bridge_width 0.5)
			(island_removal_mode 0)
		)
		(polygon
			(pts
				(arc
					(start 95.94596 -288.666174)
					(mid 95.31604 -288.666174)
					(end 95.94596 -288.666174)
				)
			)
		)
	)
	(zone
		(layers "B.Cu" "In4.Cu" "In6.Cu" "In11.Cu" "In13.Cu" "In15.Cu")
		(hatch none 0.5)
		(connect_pads
			(clearance 0)
		)
		(min_thickness 0.25)
		(keepout
			(tracks not_allowed)
			(vias allowed)
			(pads allowed)
			(copperpour not_allowed)
			(footprints allowed)
		)
		(placement
			(enabled no)
			(sheetname "")
		)
		(fill yes
			(thermal_gap 0.5)
			(thermal_bridge_width 0.5)
			(island_removal_mode 0)
		)
		(polygon
			(pts
				(arc
					(start 44.674028 -267.885418)
					(mid 44.006008 -267.885418)
					(end 44.674028 -267.885418)
				)
			)
		)
	)
	(zone
		(layers "B.Cu" "In4.Cu" "In6.Cu" "In11.Cu" "In13.Cu" "In15.Cu")
		(hatch none 0.5)
		(connect_pads
			(clearance 0)
		)
		(min_thickness 0.25)
		(keepout
			(tracks not_allowed)
			(vias allowed)
			(pads allowed)
			(copperpour not_allowed)
			(footprints allowed)
		)
		(placement
			(enabled no)
			(sheetname "")
		)
		(fill yes
			(thermal_gap 0.5)
			(thermal_bridge_width 0.5)
			(island_removal_mode 0)
		)
		(polygon
			(pts
				(arc
					(start 365.66983 -229.904036)
					(mid 365.03991 -229.904036)
					(end 365.66983 -229.904036)
				)
			)
		)
	)
	(zone
		(layers "B.Cu" "In4.Cu" "In6.Cu" "In11.Cu" "In13.Cu" "In15.Cu")
		(hatch none 0.5)
		(connect_pads
			(clearance 0)
		)
		(min_thickness 0.25)
		(keepout
			(tracks not_allowed)
			(vias allowed)
			(pads allowed)
			(copperpour not_allowed)
			(footprints allowed)
		)
		(placement
			(enabled no)
			(sheetname "")
		)
		(fill yes
			(thermal_gap 0.5)
			(thermal_bridge_width 0.5)
			(island_removal_mode 0)
		)
		(polygon
			(pts
				(arc
					(start 427.790102 -205.834996)
					(mid 427.122082 -205.834996)
					(end 427.790102 -205.834996)
				)
			)
		)
	)
	(zone
		(layers "B.Cu" "In4.Cu" "In6.Cu" "In11.Cu" "In13.Cu" "In15.Cu")
		(hatch none 0.5)
		(connect_pads
			(clearance 0)
		)
		(min_thickness 0.25)
		(keepout
			(tracks not_allowed)
			(vias allowed)
			(pads allowed)
			(copperpour not_allowed)
			(footprints allowed)
		)
		(placement
			(enabled no)
			(sheetname "")
		)
		(fill yes
			(thermal_gap 0.5)
			(thermal_bridge_width 0.5)
			(island_removal_mode 0)
		)
		(polygon
			(pts
				(arc
					(start 288.514028 -232.184956)
					(mid 287.846008 -232.184956)
					(end 288.514028 -232.184956)
				)
			)
		)
	)
	(zone
		(layers "B.Cu" "In4.Cu" "In6.Cu" "In11.Cu" "In13.Cu" "In15.Cu")
		(hatch none 0.5)
		(connect_pads
			(clearance 0)
		)
		(min_thickness 0.25)
		(keepout
			(tracks not_allowed)
			(vias allowed)
			(pads allowed)
			(copperpour not_allowed)
			(footprints allowed)
		)
		(placement
			(enabled no)
			(sheetname "")
		)
		(fill yes
			(thermal_gap 0.5)
			(thermal_bridge_width 0.5)
			(island_removal_mode 0)
		)
		(polygon
			(pts
				(arc
					(start 128.839722 -288.666174)
					(mid 128.209802 -288.666174)
					(end 128.839722 -288.666174)
				)
			)
		)
	)
	(zone
		(layers "B.Cu" "In4.Cu" "In6.Cu" "In11.Cu" "In13.Cu" "In15.Cu")
		(hatch none 0.5)
		(connect_pads
			(clearance 0)
		)
		(min_thickness 0.25)
		(keepout
			(tracks not_allowed)
			(vias allowed)
			(pads allowed)
			(copperpour not_allowed)
			(footprints allowed)
		)
		(placement
			(enabled no)
			(sheetname "")
		)
		(fill yes
			(thermal_gap 0.5)
			(thermal_bridge_width 0.5)
			(island_removal_mode 0)
		)
		(polygon
			(pts
				(arc
					(start 183.950102 -223.685354)
					(mid 183.282082 -223.685354)
					(end 183.950102 -223.685354)
				)
			)
		)
	)
	(zone
		(layers "B.Cu" "In4.Cu" "In6.Cu" "In11.Cu" "In13.Cu" "In15.Cu")
		(hatch none 0.5)
		(connect_pads
			(clearance 0)
		)
		(min_thickness 0.25)
		(keepout
			(tracks not_allowed)
			(vias allowed)
			(pads allowed)
			(copperpour not_allowed)
			(footprints allowed)
		)
		(placement
			(enabled no)
			(sheetname "")
		)
		(fill yes
			(thermal_gap 0.5)
			(thermal_bridge_width 0.5)
			(island_removal_mode 0)
		)
		(polygon
			(pts
				(arc
					(start 376.009662 -242.864132)
					(mid 375.379742 -242.864132)
					(end 376.009662 -242.864132)
				)
			)
		)
	)
	(zone
		(layers "B.Cu" "In4.Cu" "In6.Cu" "In11.Cu" "In13.Cu" "In15.Cu")
		(hatch none 0.5)
		(connect_pads
			(clearance 0)
		)
		(min_thickness 0.25)
		(keepout
			(tracks not_allowed)
			(vias allowed)
			(pads allowed)
			(copperpour not_allowed)
			(footprints allowed)
		)
		(placement
			(enabled no)
			(sheetname "")
		)
		(fill yes
			(thermal_gap 0.5)
			(thermal_bridge_width 0.5)
			(island_removal_mode 0)
		)
		(polygon
			(pts
				(arc
					(start 376.77979 -272.466054)
					(mid 376.14987 -272.466054)
					(end 376.77979 -272.466054)
				)
			)
		)
	)
	(zone
		(layers "B.Cu" "In4.Cu" "In6.Cu" "In11.Cu" "In13.Cu" "In15.Cu")
		(hatch none 0.5)
		(connect_pads
			(clearance 0)
		)
		(min_thickness 0.25)
		(keepout
			(tracks not_allowed)
			(vias allowed)
			(pads allowed)
			(copperpour not_allowed)
			(footprints allowed)
		)
		(placement
			(enabled no)
			(sheetname "")
		)
		(fill yes
			(thermal_gap 0.5)
			(thermal_bridge_width 0.5)
			(island_removal_mode 0)
		)
		(polygon
			(pts
				(arc
					(start 376.009662 -241.24412)
					(mid 375.379742 -241.24412)
					(end 376.009662 -241.24412)
				)
			)
		)
	)
	(zone
		(layers "B.Cu" "In4.Cu" "In6.Cu" "In11.Cu" "In13.Cu" "In15.Cu")
		(hatch none 0.5)
		(connect_pads
			(clearance 0)
		)
		(min_thickness 0.25)
		(keepout
			(tracks not_allowed)
			(vias allowed)
			(pads allowed)
			(copperpour not_allowed)
			(footprints allowed)
		)
		(placement
			(enabled no)
			(sheetname "")
		)
		(fill yes
			(thermal_gap 0.5)
			(thermal_bridge_width 0.5)
			(island_removal_mode 0)
		)
		(polygon
			(pts
				(arc
					(start 288.514028 -274.684998)
					(mid 287.846008 -274.684998)
					(end 288.514028 -274.684998)
				)
			)
		)
	)
	(zone
		(layers "B.Cu" "In4.Cu" "In6.Cu" "In11.Cu" "In13.Cu" "In15.Cu")
		(hatch none 0.5)
		(connect_pads
			(clearance 0)
		)
		(min_thickness 0.25)
		(keepout
			(tracks not_allowed)
			(vias allowed)
			(pads allowed)
			(copperpour not_allowed)
			(footprints allowed)
		)
		(placement
			(enabled no)
			(sheetname "")
		)
		(fill yes
			(thermal_gap 0.5)
			(thermal_bridge_width 0.5)
			(island_removal_mode 0)
		)
		(polygon
			(pts
				(arc
					(start 129.949702 -239.624362)
					(mid 129.319782 -239.624362)
					(end 129.949702 -239.624362)
				)
			)
		)
	)
	(zone
		(layers "B.Cu" "In4.Cu" "In6.Cu" "In11.Cu" "In13.Cu" "In15.Cu")
		(hatch none 0.5)
		(connect_pads
			(clearance 0)
		)
		(min_thickness 0.25)
		(keepout
			(tracks not_allowed)
			(vias allowed)
			(pads allowed)
			(copperpour not_allowed)
			(footprints allowed)
		)
		(placement
			(enabled no)
			(sheetname "")
		)
		(fill yes
			(thermal_gap 0.5)
			(thermal_bridge_width 0.5)
			(island_removal_mode 0)
		)
		(polygon
			(pts
				(arc
					(start 427.790102 -215.18499)
					(mid 427.122082 -215.18499)
					(end 427.790102 -215.18499)
				)
			)
		)
	)
	(zone
		(layers "B.Cu" "In4.Cu" "In6.Cu" "In11.Cu" "In13.Cu" "In15.Cu")
		(hatch none 0.5)
		(connect_pads
			(clearance 0)
		)
		(min_thickness 0.25)
		(keepout
			(tracks not_allowed)
			(vias allowed)
			(pads allowed)
			(copperpour not_allowed)
			(footprints allowed)
		)
		(placement
			(enabled no)
			(sheetname "")
		)
		(fill yes
			(thermal_gap 0.5)
			(thermal_bridge_width 0.5)
			(island_removal_mode 0)
		)
		(polygon
			(pts
				(arc
					(start 96.115886 -229.90429)
					(mid 95.485966 -229.90429)
					(end 96.115886 -229.90429)
				)
			)
		)
	)
	(zone
		(layers "B.Cu" "In4.Cu" "In6.Cu" "In11.Cu" "In13.Cu" "In15.Cu")
		(hatch none 0.5)
		(connect_pads
			(clearance 0)
		)
		(min_thickness 0.25)
		(keepout
			(tracks not_allowed)
			(vias allowed)
			(pads allowed)
			(copperpour not_allowed)
			(footprints allowed)
		)
		(placement
			(enabled no)
			(sheetname "")
		)
		(fill yes
			(thermal_gap 0.5)
			(thermal_bridge_width 0.5)
			(island_removal_mode 0)
		)
		(polygon
			(pts
				(arc
					(start 130.249676 -292.716204)
					(mid 129.619756 -292.716204)
					(end 130.249676 -292.716204)
				)
			)
		)
	)
	(zone
		(layers "B.Cu" "In4.Cu" "In6.Cu" "In11.Cu" "In13.Cu" "In15.Cu")
		(hatch none 0.5)
		(connect_pads
			(clearance 0)
		)
		(min_thickness 0.25)
		(keepout
			(tracks not_allowed)
			(vias allowed)
			(pads allowed)
			(copperpour not_allowed)
			(footprints allowed)
		)
		(placement
			(enabled no)
			(sheetname "")
		)
		(fill yes
			(thermal_gap 0.5)
			(thermal_bridge_width 0.5)
			(island_removal_mode 0)
		)
		(polygon
			(pts
				(arc
					(start 130.249676 -282.996386)
					(mid 129.619756 -282.996386)
					(end 130.249676 -282.996386)
				)
			)
		)
	)
	(zone
		(layers "B.Cu" "In4.Cu" "In6.Cu" "In11.Cu" "In13.Cu" "In15.Cu")
		(hatch none 0.5)
		(connect_pads
			(clearance 0)
		)
		(min_thickness 0.25)
		(keepout
			(tracks not_allowed)
			(vias allowed)
			(pads allowed)
			(copperpour not_allowed)
			(footprints allowed)
		)
		(placement
			(enabled no)
			(sheetname "")
		)
		(fill yes
			(thermal_gap 0.5)
			(thermal_bridge_width 0.5)
			(island_removal_mode 0)
		)
		(polygon
			(pts
				(arc
					(start 94.536006 -278.13635)
					(mid 93.906086 -278.13635)
					(end 94.536006 -278.13635)
				)
			)
		)
	)
	(zone
		(layers "B.Cu" "In4.Cu" "In6.Cu" "In11.Cu" "In13.Cu" "In15.Cu")
		(hatch none 0.5)
		(connect_pads
			(clearance 0)
		)
		(min_thickness 0.25)
		(keepout
			(tracks not_allowed)
			(vias allowed)
			(pads allowed)
			(copperpour not_allowed)
			(footprints allowed)
		)
		(placement
			(enabled no)
			(sheetname "")
		)
		(fill yes
			(thermal_gap 0.5)
			(thermal_bridge_width 0.5)
			(island_removal_mode 0)
		)
		(polygon
			(pts
				(arc
					(start 128.539748 -233.95432)
					(mid 127.909828 -233.95432)
					(end 128.539748 -233.95432)
				)
			)
		)
	)
	(zone
		(layers "B.Cu" "In4.Cu" "In6.Cu" "In11.Cu" "In13.Cu" "In15.Cu")
		(hatch none 0.5)
		(connect_pads
			(clearance 0)
		)
		(min_thickness 0.25)
		(keepout
			(tracks not_allowed)
			(vias allowed)
			(pads allowed)
			(copperpour not_allowed)
			(footprints allowed)
		)
		(placement
			(enabled no)
			(sheetname "")
		)
		(fill yes
			(thermal_gap 0.5)
			(thermal_bridge_width 0.5)
			(island_removal_mode 0)
		)
		(polygon
			(pts
				(arc
					(start 129.479802 -235.574332)
					(mid 128.849882 -235.574332)
					(end 129.479802 -235.574332)
				)
			)
		)
	)
	(zone
		(layers "B.Cu" "In4.Cu" "In6.Cu" "In11.Cu" "In13.Cu" "In15.Cu")
		(hatch none 0.5)
		(connect_pads
			(clearance 0)
		)
		(min_thickness 0.25)
		(keepout
			(tracks not_allowed)
			(vias allowed)
			(pads allowed)
			(copperpour not_allowed)
			(footprints allowed)
		)
		(placement
			(enabled no)
			(sheetname "")
		)
		(fill yes
			(thermal_gap 0.5)
			(thermal_bridge_width 0.5)
			(island_removal_mode 0)
		)
		(polygon
			(pts
				(arc
					(start 179.850034 -205.83525)
					(mid 179.182014 -205.83525)
					(end 179.850034 -205.83525)
				)
			)
		)
	)
	(zone
		(layers "B.Cu" "In4.Cu" "In6.Cu" "In11.Cu" "In13.Cu" "In15.Cu")
		(hatch none 0.5)
		(connect_pads
			(clearance 0)
		)
		(min_thickness 0.25)
		(keepout
			(tracks not_allowed)
			(vias allowed)
			(pads allowed)
			(copperpour not_allowed)
			(footprints allowed)
		)
		(placement
			(enabled no)
			(sheetname "")
		)
		(fill yes
			(thermal_gap 0.5)
			(thermal_bridge_width 0.5)
			(island_removal_mode 0)
		)
		(polygon
			(pts
				(arc
					(start 94.536006 -292.716204)
					(mid 93.906086 -292.716204)
					(end 94.536006 -292.716204)
				)
			)
		)
	)
	(zone
		(layers "B.Cu" "In4.Cu" "In6.Cu" "In11.Cu" "In13.Cu" "In15.Cu")
		(hatch none 0.5)
		(connect_pads
			(clearance 0)
		)
		(min_thickness 0.25)
		(keepout
			(tracks not_allowed)
			(vias allowed)
			(pads allowed)
			(copperpour not_allowed)
			(footprints allowed)
		)
		(placement
			(enabled no)
			(sheetname "")
		)
		(fill yes
			(thermal_gap 0.5)
			(thermal_bridge_width 0.5)
			(island_removal_mode 0)
		)
		(polygon
			(pts
				(arc
					(start 431.89017 -278.085042)
					(mid 431.22215 -278.085042)
					(end 431.89017 -278.085042)
				)
			)
		)
	)
	(zone
		(layers "B.Cu" "In4.Cu" "In6.Cu" "In11.Cu" "In13.Cu" "In15.Cu")
		(hatch none 0.5)
		(connect_pads
			(clearance 0)
		)
		(min_thickness 0.25)
		(keepout
			(tracks not_allowed)
			(vias allowed)
			(pads allowed)
			(copperpour not_allowed)
			(footprints allowed)
		)
		(placement
			(enabled no)
			(sheetname "")
		)
		(fill yes
			(thermal_gap 0.5)
			(thermal_bridge_width 0.5)
			(island_removal_mode 0)
		)
		(polygon
			(pts
				(arc
					(start 129.779776 -267.606272)
					(mid 129.149856 -267.606272)
					(end 129.779776 -267.606272)
				)
			)
		)
	)
	(zone
		(layers "B.Cu" "In4.Cu" "In6.Cu" "In11.Cu" "In13.Cu" "In15.Cu")
		(hatch none 0.5)
		(connect_pads
			(clearance 0)
		)
		(min_thickness 0.25)
		(keepout
			(tracks not_allowed)
			(vias allowed)
			(pads allowed)
			(copperpour not_allowed)
			(footprints allowed)
		)
		(placement
			(enabled no)
			(sheetname "")
		)
		(fill yes
			(thermal_gap 0.5)
			(thermal_bridge_width 0.5)
			(island_removal_mode 0)
		)
		(polygon
			(pts
				(arc
					(start 44.674028 -311.235344)
					(mid 44.006008 -311.235344)
					(end 44.674028 -311.235344)
				)
			)
		)
	)
	(zone
		(layers "B.Cu" "In4.Cu" "In6.Cu" "In11.Cu" "In13.Cu" "In15.Cu")
		(hatch none 0.5)
		(connect_pads
			(clearance 0)
		)
		(min_thickness 0.25)
		(keepout
			(tracks not_allowed)
			(vias allowed)
			(pads allowed)
			(copperpour not_allowed)
			(footprints allowed)
		)
		(placement
			(enabled no)
			(sheetname "")
		)
		(fill yes
			(thermal_gap 0.5)
			(thermal_bridge_width 0.5)
			(island_removal_mode 0)
		)
		(polygon
			(pts
				(arc
					(start 427.790102 -213.484968)
					(mid 427.122082 -213.484968)
					(end 427.790102 -213.484968)
				)
			)
		)
	)
	(zone
		(layers "B.Cu" "In4.Cu" "In6.Cu" "In11.Cu" "In13.Cu" "In15.Cu")
		(hatch none 0.5)
		(connect_pads
			(clearance 0)
		)
		(min_thickness 0.25)
		(keepout
			(tracks not_allowed)
			(vias allowed)
			(pads allowed)
			(copperpour not_allowed)
			(footprints allowed)
		)
		(placement
			(enabled no)
			(sheetname "")
		)
		(fill yes
			(thermal_gap 0.5)
			(thermal_bridge_width 0.5)
			(island_removal_mode 0)
		)
		(polygon
			(pts
				(arc
					(start 98.295968 -294.336216)
					(mid 97.666048 -294.336216)
					(end 98.295968 -294.336216)
				)
			)
		)
	)
	(zone
		(layers "B.Cu" "In4.Cu" "In6.Cu" "In11.Cu" "In13.Cu" "In15.Cu")
		(hatch none 0.5)
		(connect_pads
			(clearance 0)
		)
		(min_thickness 0.25)
		(keepout
			(tracks not_allowed)
			(vias allowed)
			(pads allowed)
			(copperpour not_allowed)
			(footprints allowed)
		)
		(placement
			(enabled no)
			(sheetname "")
		)
		(fill yes
			(thermal_gap 0.5)
			(thermal_bridge_width 0.5)
			(island_removal_mode 0)
		)
		(polygon
			(pts
				(arc
					(start 94.536006 -287.856422)
					(mid 93.906086 -287.856422)
					(end 94.536006 -287.856422)
				)
			)
		)
	)
	(zone
		(layers "B.Cu" "In4.Cu" "In6.Cu" "In11.Cu" "In13.Cu" "In15.Cu")
		(hatch none 0.5)
		(connect_pads
			(clearance 0)
		)
		(min_thickness 0.25)
		(keepout
			(tracks not_allowed)
			(vias allowed)
			(pads allowed)
			(copperpour not_allowed)
			(footprints allowed)
		)
		(placement
			(enabled no)
			(sheetname "")
		)
		(fill yes
			(thermal_gap 0.5)
			(thermal_bridge_width 0.5)
			(island_removal_mode 0)
		)
		(polygon
			(pts
				(arc
					(start 376.479816 -248.534174)
					(mid 375.849896 -248.534174)
					(end 376.479816 -248.534174)
				)
			)
		)
	)
	(zone
		(layers "B.Cu" "In4.Cu" "In6.Cu" "In11.Cu" "In13.Cu" "In15.Cu")
		(hatch none 0.5)
		(connect_pads
			(clearance 0)
		)
		(min_thickness 0.25)
		(keepout
			(tracks not_allowed)
			(vias allowed)
			(pads allowed)
			(copperpour not_allowed)
			(footprints allowed)
		)
		(placement
			(enabled no)
			(sheetname "")
		)
		(fill yes
			(thermal_gap 0.5)
			(thermal_bridge_width 0.5)
			(island_removal_mode 0)
		)
		(polygon
			(pts
				(arc
					(start 130.249676 -278.13635)
					(mid 129.619756 -278.13635)
					(end 130.249676 -278.13635)
				)
			)
		)
	)
	(zone
		(layers "B.Cu" "In4.Cu" "In6.Cu" "In11.Cu" "In13.Cu" "In15.Cu")
		(hatch none 0.5)
		(connect_pads
			(clearance 0)
		)
		(min_thickness 0.25)
		(keepout
			(tracks not_allowed)
			(vias allowed)
			(pads allowed)
			(copperpour not_allowed)
			(footprints allowed)
		)
		(placement
			(enabled no)
			(sheetname "")
		)
		(fill yes
			(thermal_gap 0.5)
			(thermal_bridge_width 0.5)
			(island_removal_mode 0)
		)
		(polygon
			(pts
				(arc
					(start 44.674028 -281.48534)
					(mid 44.006008 -281.48534)
					(end 44.674028 -281.48534)
				)
			)
		)
	)
	(zone
		(layers "B.Cu" "In4.Cu" "In6.Cu" "In11.Cu" "In13.Cu" "In15.Cu")
		(hatch none 0.5)
		(connect_pads
			(clearance 0)
		)
		(min_thickness 0.25)
		(keepout
			(tracks not_allowed)
			(vias allowed)
			(pads allowed)
			(copperpour not_allowed)
			(footprints allowed)
		)
		(placement
			(enabled no)
			(sheetname "")
		)
		(fill yes
			(thermal_gap 0.5)
			(thermal_bridge_width 0.5)
			(island_removal_mode 0)
		)
		(polygon
			(pts
				(arc
					(start 95.645986 -240.434368)
					(mid 95.016066 -240.434368)
					(end 95.645986 -240.434368)
				)
			)
		)
	)
	(zone
		(layers "B.Cu" "In4.Cu" "In6.Cu" "In11.Cu" "In13.Cu" "In15.Cu")
		(hatch none 0.5)
		(connect_pads
			(clearance 0)
		)
		(min_thickness 0.25)
		(keepout
			(tracks not_allowed)
			(vias allowed)
			(pads allowed)
			(copperpour not_allowed)
			(footprints allowed)
		)
		(placement
			(enabled no)
			(sheetname "")
		)
		(fill yes
			(thermal_gap 0.5)
			(thermal_bridge_width 0.5)
			(island_removal_mode 0)
		)
		(polygon
			(pts
				(arc
					(start 377.41987 -237.19409)
					(mid 376.78995 -237.19409)
					(end 377.41987 -237.19409)
				)
			)
		)
	)
	(zone
		(layers "B.Cu" "In4.Cu" "In6.Cu" "In11.Cu" "In13.Cu" "In15.Cu")
		(hatch none 0.5)
		(connect_pads
			(clearance 0)
		)
		(min_thickness 0.25)
		(keepout
			(tracks not_allowed)
			(vias allowed)
			(pads allowed)
			(copperpour not_allowed)
			(footprints allowed)
		)
		(placement
			(enabled no)
			(sheetname "")
		)
		(fill yes
			(thermal_gap 0.5)
			(thermal_bridge_width 0.5)
			(island_removal_mode 0)
		)
		(polygon
			(pts
				(arc
					(start 96.115886 -233.144314)
					(mid 95.485966 -233.144314)
					(end 96.115886 -233.144314)
				)
			)
		)
	)
	(zone
		(layers "B.Cu" "In4.Cu" "In6.Cu" "In11.Cu" "In13.Cu" "In15.Cu")
		(hatch none 0.5)
		(connect_pads
			(clearance 0)
		)
		(min_thickness 0.25)
		(keepout
			(tracks not_allowed)
			(vias allowed)
			(pads allowed)
			(copperpour not_allowed)
			(footprints allowed)
		)
		(placement
			(enabled no)
			(sheetname "")
		)
		(fill yes
			(thermal_gap 0.5)
			(thermal_bridge_width 0.5)
			(island_removal_mode 0)
		)
		(polygon
			(pts
				(arc
					(start 44.674028 -264.485374)
					(mid 44.006008 -264.485374)
					(end 44.674028 -264.485374)
				)
			)
		)
	)
	(zone
		(layers "B.Cu" "In4.Cu" "In6.Cu" "In11.Cu" "In13.Cu" "In15.Cu")
		(hatch none 0.5)
		(connect_pads
			(clearance 0)
		)
		(min_thickness 0.25)
		(keepout
			(tracks not_allowed)
			(vias allowed)
			(pads allowed)
			(copperpour not_allowed)
			(footprints allowed)
		)
		(placement
			(enabled no)
			(sheetname "")
		)
		(fill yes
			(thermal_gap 0.5)
			(thermal_bridge_width 0.5)
			(island_removal_mode 0)
		)
		(polygon
			(pts
				(arc
					(start 179.850034 -276.385274)
					(mid 179.182014 -276.385274)
					(end 179.850034 -276.385274)
				)
			)
		)
	)
	(zone
		(layers "B.Cu" "In4.Cu" "In6.Cu" "In11.Cu" "In13.Cu" "In15.Cu")
		(hatch none 0.5)
		(connect_pads
			(clearance 0)
		)
		(min_thickness 0.25)
		(keepout
			(tracks not_allowed)
			(vias allowed)
			(pads allowed)
			(copperpour not_allowed)
			(footprints allowed)
		)
		(placement
			(enabled no)
			(sheetname "")
		)
		(fill yes
			(thermal_gap 0.5)
			(thermal_bridge_width 0.5)
			(island_removal_mode 0)
		)
		(polygon
			(pts
				(arc
					(start 44.674028 -214.33536)
					(mid 44.006008 -214.33536)
					(end 44.674028 -214.33536)
				)
			)
		)
	)
	(zone
		(layers "B.Cu" "In4.Cu" "In6.Cu" "In11.Cu" "In13.Cu" "In15.Cu")
		(hatch none 0.5)
		(connect_pads
			(clearance 0)
		)
		(min_thickness 0.25)
		(keepout
			(tracks not_allowed)
			(vias allowed)
			(pads allowed)
			(copperpour not_allowed)
			(footprints allowed)
		)
		(placement
			(enabled no)
			(sheetname "")
		)
		(fill yes
			(thermal_gap 0.5)
			(thermal_bridge_width 0.5)
			(island_removal_mode 0)
		)
		(polygon
			(pts
				(arc
					(start 106.455972 -229.90429)
					(mid 105.826052 -229.90429)
					(end 106.455972 -229.90429)
				)
			)
		)
	)
	(zone
		(layers "B.Cu" "In4.Cu" "In6.Cu" "In11.Cu" "In13.Cu" "In15.Cu")
		(hatch none 0.5)
		(connect_pads
			(clearance 0)
		)
		(min_thickness 0.25)
		(keepout
			(tracks not_allowed)
			(vias allowed)
			(pads allowed)
			(copperpour not_allowed)
			(footprints allowed)
		)
		(placement
			(enabled no)
			(sheetname "")
		)
		(fill yes
			(thermal_gap 0.5)
			(thermal_bridge_width 0.5)
			(island_removal_mode 0)
		)
		(polygon
			(pts
				(arc
					(start 343.886028 -287.045908)
					(mid 343.256108 -287.045908)
					(end 343.886028 -287.045908)
				)
			)
		)
	)
	(zone
		(layers "B.Cu" "In4.Cu" "In6.Cu" "In11.Cu" "In13.Cu" "In15.Cu")
		(hatch none 0.5)
		(connect_pads
			(clearance 0)
		)
		(min_thickness 0.25)
		(keepout
			(tracks not_allowed)
			(vias allowed)
			(pads allowed)
			(copperpour not_allowed)
			(footprints allowed)
		)
		(placement
			(enabled no)
			(sheetname "")
		)
		(fill yes
			(thermal_gap 0.5)
			(thermal_bridge_width 0.5)
			(island_removal_mode 0)
		)
		(polygon
			(pts
				(arc
					(start 109.746034 -230.71455)
					(mid 109.116114 -230.71455)
					(end 109.746034 -230.71455)
				)
			)
		)
	)
	(zone
		(layers "B.Cu" "In4.Cu" "In6.Cu" "In11.Cu" "In13.Cu" "In15.Cu")
		(hatch none 0.5)
		(connect_pads
			(clearance 0)
		)
		(min_thickness 0.25)
		(keepout
			(tracks not_allowed)
			(vias allowed)
			(pads allowed)
			(copperpour not_allowed)
			(footprints allowed)
		)
		(placement
			(enabled no)
			(sheetname "")
		)
		(fill yes
			(thermal_gap 0.5)
			(thermal_bridge_width 0.5)
			(island_removal_mode 0)
		)
		(polygon
			(pts
				(arc
					(start 431.89017 -238.985044)
					(mid 431.22215 -238.985044)
					(end 431.89017 -238.985044)
				)
			)
		)
	)
	(zone
		(layers "B.Cu" "In4.Cu" "In6.Cu" "In11.Cu" "In13.Cu" "In15.Cu")
		(hatch none 0.5)
		(connect_pads
			(clearance 0)
		)
		(min_thickness 0.25)
		(keepout
			(tracks not_allowed)
			(vias allowed)
			(pads allowed)
			(copperpour not_allowed)
			(footprints allowed)
		)
		(placement
			(enabled no)
			(sheetname "")
		)
		(fill yes
			(thermal_gap 0.5)
			(thermal_bridge_width 0.5)
			(island_removal_mode 0)
		)
		(polygon
			(pts
				(arc
					(start 129.949702 -234.764326)
					(mid 129.319782 -234.764326)
					(end 129.949702 -234.764326)
				)
			)
		)
	)
	(zone
		(layers "B.Cu" "In4.Cu" "In6.Cu" "In11.Cu" "In13.Cu" "In15.Cu")
		(hatch none 0.5)
		(connect_pads
			(clearance 0)
		)
		(min_thickness 0.25)
		(keepout
			(tracks not_allowed)
			(vias allowed)
			(pads allowed)
			(copperpour not_allowed)
			(footprints allowed)
		)
		(placement
			(enabled no)
			(sheetname "")
		)
		(fill yes
			(thermal_gap 0.5)
			(thermal_bridge_width 0.5)
			(island_removal_mode 0)
		)
		(polygon
			(pts
				(arc
					(start 99.607624 5.631434)
					(mid 98.939604 5.631434)
					(end 99.607624 5.631434)
				)
			)
		)
	)
	(zone
		(layers "B.Cu" "In4.Cu" "In6.Cu" "In11.Cu" "In13.Cu" "In15.Cu")
		(hatch none 0.5)
		(connect_pads
			(clearance 0)
		)
		(min_thickness 0.25)
		(keepout
			(tracks not_allowed)
			(vias allowed)
			(pads allowed)
			(copperpour not_allowed)
			(footprints allowed)
		)
		(placement
			(enabled no)
			(sheetname "")
		)
		(fill yes
			(thermal_gap 0.5)
			(thermal_bridge_width 0.5)
			(island_removal_mode 0)
		)
		(polygon
			(pts
				(arc
					(start 431.89017 -231.335072)
					(mid 431.22215 -231.335072)
					(end 431.89017 -231.335072)
				)
			)
		)
	)
	(zone
		(layers "B.Cu" "In4.Cu" "In6.Cu" "In11.Cu" "In13.Cu" "In15.Cu")
		(hatch none 0.5)
		(connect_pads
			(clearance 0)
		)
		(min_thickness 0.25)
		(keepout
			(tracks not_allowed)
			(vias allowed)
			(pads allowed)
			(copperpour not_allowed)
			(footprints allowed)
		)
		(placement
			(enabled no)
			(sheetname "")
		)
		(fill yes
			(thermal_gap 0.5)
			(thermal_bridge_width 0.5)
			(island_removal_mode 0)
		)
		(polygon
			(pts
				(arc
					(start 130.249676 -270.03629)
					(mid 129.619756 -270.03629)
					(end 130.249676 -270.03629)
				)
			)
		)
	)
	(zone
		(layers "B.Cu" "In4.Cu" "In6.Cu" "In11.Cu" "In13.Cu" "In15.Cu")
		(hatch none 0.5)
		(connect_pads
			(clearance 0)
		)
		(min_thickness 0.25)
		(keepout
			(tracks not_allowed)
			(vias allowed)
			(pads allowed)
			(copperpour not_allowed)
			(footprints allowed)
		)
		(placement
			(enabled no)
			(sheetname "")
		)
		(fill yes
			(thermal_gap 0.5)
			(thermal_bridge_width 0.5)
			(island_removal_mode 0)
		)
		(polygon
			(pts
				(arc
					(start 96.115886 -249.344434)
					(mid 95.485966 -249.344434)
					(end 96.115886 -249.344434)
				)
			)
		)
	)
	(zone
		(layers "B.Cu" "In4.Cu" "In6.Cu" "In11.Cu" "In13.Cu" "In15.Cu")
		(hatch none 0.5)
		(connect_pads
			(clearance 0)
		)
		(min_thickness 0.25)
		(keepout
			(tracks not_allowed)
			(vias allowed)
			(pads allowed)
			(copperpour not_allowed)
			(footprints allowed)
		)
		(placement
			(enabled no)
			(sheetname "")
		)
		(fill yes
			(thermal_gap 0.5)
			(thermal_bridge_width 0.5)
			(island_removal_mode 0)
		)
		(polygon
			(pts
				(arc
					(start 44.674028 -262.785352)
					(mid 44.006008 -262.785352)
					(end 44.674028 -262.785352)
				)
			)
		)
	)
	(zone
		(layers "B.Cu" "In4.Cu" "In6.Cu" "In11.Cu" "In13.Cu" "In15.Cu")
		(hatch none 0.5)
		(connect_pads
			(clearance 0)
		)
		(min_thickness 0.25)
		(keepout
			(tracks not_allowed)
			(vias allowed)
			(pads allowed)
			(copperpour not_allowed)
			(footprints allowed)
		)
		(placement
			(enabled no)
			(sheetname "")
		)
		(fill yes
			(thermal_gap 0.5)
			(thermal_bridge_width 0.5)
			(island_removal_mode 0)
		)
		(polygon
			(pts
				(arc
					(start 44.674028 -242.385342)
					(mid 44.006008 -242.385342)
					(end 44.674028 -242.385342)
				)
			)
		)
	)
	(zone
		(layers "B.Cu" "In4.Cu" "In6.Cu" "In11.Cu" "In13.Cu" "In15.Cu")
		(hatch none 0.5)
		(connect_pads
			(clearance 0)
		)
		(min_thickness 0.25)
		(keepout
			(tracks not_allowed)
			(vias allowed)
			(pads allowed)
			(copperpour not_allowed)
			(footprints allowed)
		)
		(placement
			(enabled no)
			(sheetname "")
		)
		(fill yes
			(thermal_gap 0.5)
			(thermal_bridge_width 0.5)
			(island_removal_mode 0)
		)
		(polygon
			(pts
				(arc
					(start 344.055954 -247.724168)
					(mid 343.426034 -247.724168)
					(end 344.055954 -247.724168)
				)
			)
		)
	)
	(zone
		(layers "B.Cu" "In4.Cu" "In6.Cu" "In11.Cu" "In13.Cu" "In15.Cu")
		(hatch none 0.5)
		(connect_pads
			(clearance 0)
		)
		(min_thickness 0.25)
		(keepout
			(tracks not_allowed)
			(vias allowed)
			(pads allowed)
			(copperpour not_allowed)
			(footprints allowed)
		)
		(placement
			(enabled no)
			(sheetname "")
		)
		(fill yes
			(thermal_gap 0.5)
			(thermal_bridge_width 0.5)
			(island_removal_mode 0)
		)
		(polygon
			(pts
				(arc
					(start 431.89017 -292.535102)
					(mid 431.22215 -292.535102)
					(end 431.89017 -292.535102)
				)
			)
		)
	)
	(zone
		(layers "B.Cu" "In4.Cu" "In6.Cu" "In11.Cu" "In13.Cu" "In15.Cu")
		(hatch none 0.5)
		(connect_pads
			(clearance 0)
		)
		(min_thickness 0.25)
		(keepout
			(tracks not_allowed)
			(vias allowed)
			(pads allowed)
			(copperpour not_allowed)
			(footprints allowed)
		)
		(placement
			(enabled no)
			(sheetname "")
		)
		(fill yes
			(thermal_gap 0.5)
			(thermal_bridge_width 0.5)
			(island_removal_mode 0)
		)
		(polygon
			(pts
				(arc
					(start 427.790102 -227.935028)
					(mid 427.122082 -227.935028)
					(end 427.790102 -227.935028)
				)
			)
		)
	)
	(zone
		(layers "B.Cu" "In4.Cu" "In6.Cu" "In11.Cu" "In13.Cu" "In15.Cu")
		(hatch none 0.5)
		(connect_pads
			(clearance 0)
		)
		(min_thickness 0.25)
		(keepout
			(tracks not_allowed)
			(vias allowed)
			(pads allowed)
			(copperpour not_allowed)
			(footprints allowed)
		)
		(placement
			(enabled no)
			(sheetname "")
		)
		(fill yes
			(thermal_gap 0.5)
			(thermal_bridge_width 0.5)
			(island_removal_mode 0)
		)
		(polygon
			(pts
				(arc
					(start 342.476074 -263.555988)
					(mid 341.846154 -263.555988)
					(end 342.476074 -263.555988)
				)
			)
		)
	)
	(zone
		(layers "B.Cu" "In4.Cu" "In6.Cu" "In11.Cu" "In13.Cu" "In15.Cu")
		(hatch none 0.5)
		(connect_pads
			(clearance 0)
		)
		(min_thickness 0.25)
		(keepout
			(tracks not_allowed)
			(vias allowed)
			(pads allowed)
			(copperpour not_allowed)
			(footprints allowed)
		)
		(placement
			(enabled no)
			(sheetname "")
		)
		(fill yes
			(thermal_gap 0.5)
			(thermal_bridge_width 0.5)
			(island_removal_mode 0)
		)
		(polygon
			(pts
				(arc
					(start 44.674028 -217.735404)
					(mid 44.006008 -217.735404)
					(end 44.674028 -217.735404)
				)
			)
		)
	)
	(zone
		(layers "B.Cu" "In4.Cu" "In6.Cu" "In11.Cu" "In13.Cu" "In15.Cu")
		(hatch none 0.5)
		(connect_pads
			(clearance 0)
		)
		(min_thickness 0.25)
		(keepout
			(tracks not_allowed)
			(vias allowed)
			(pads allowed)
			(copperpour not_allowed)
			(footprints allowed)
		)
		(placement
			(enabled no)
			(sheetname "")
		)
		(fill yes
			(thermal_gap 0.5)
			(thermal_bridge_width 0.5)
			(island_removal_mode 0)
		)
		(polygon
			(pts
				(arc
					(start 342.1761 -228.284278)
					(mid 341.54618 -228.284278)
					(end 342.1761 -228.284278)
				)
			)
		)
	)
	(zone
		(layers "B.Cu" "In4.Cu" "In6.Cu" "In11.Cu" "In13.Cu" "In15.Cu")
		(hatch none 0.5)
		(connect_pads
			(clearance 0)
		)
		(min_thickness 0.25)
		(keepout
			(tracks not_allowed)
			(vias allowed)
			(pads allowed)
			(copperpour not_allowed)
			(footprints allowed)
		)
		(placement
			(enabled no)
			(sheetname "")
		)
		(fill yes
			(thermal_gap 0.5)
			(thermal_bridge_width 0.5)
			(island_removal_mode 0)
		)
		(polygon
			(pts
				(arc
					(start 288.514028 -308.685184)
					(mid 287.846008 -308.685184)
					(end 288.514028 -308.685184)
				)
			)
		)
	)
	(zone
		(layers "B.Cu" "In4.Cu" "In6.Cu" "In11.Cu" "In13.Cu" "In15.Cu")
		(hatch none 0.5)
		(connect_pads
			(clearance 0)
		)
		(min_thickness 0.25)
		(keepout
			(tracks not_allowed)
			(vias allowed)
			(pads allowed)
			(copperpour not_allowed)
			(footprints allowed)
		)
		(placement
			(enabled no)
			(sheetname "")
		)
		(fill yes
			(thermal_gap 0.5)
			(thermal_bridge_width 0.5)
			(island_removal_mode 0)
		)
		(polygon
			(pts
				(arc
					(start 376.479816 -229.094284)
					(mid 375.849896 -229.094284)
					(end 376.479816 -229.094284)
				)
			)
		)
	)
	(zone
		(layers "B.Cu" "In4.Cu" "In6.Cu" "In11.Cu" "In13.Cu" "In15.Cu")
		(hatch none 0.5)
		(connect_pads
			(clearance 0)
		)
		(min_thickness 0.25)
		(keepout
			(tracks not_allowed)
			(vias allowed)
			(pads allowed)
			(copperpour not_allowed)
			(footprints allowed)
		)
		(placement
			(enabled no)
			(sheetname "")
		)
		(fill yes
			(thermal_gap 0.5)
			(thermal_bridge_width 0.5)
			(island_removal_mode 0)
		)
		(polygon
			(pts
				(arc
					(start 427.790102 -310.384952)
					(mid 427.122082 -310.384952)
					(end 427.790102 -310.384952)
				)
			)
		)
	)
	(zone
		(layers "B.Cu" "In4.Cu" "In6.Cu" "In11.Cu" "In13.Cu" "In15.Cu")
		(hatch none 0.5)
		(connect_pads
			(clearance 0)
		)
		(min_thickness 0.25)
		(keepout
			(tracks not_allowed)
			(vias allowed)
			(pads allowed)
			(copperpour not_allowed)
			(footprints allowed)
		)
		(placement
			(enabled no)
			(sheetname "")
		)
		(fill yes
			(thermal_gap 0.5)
			(thermal_bridge_width 0.5)
			(island_removal_mode 0)
		)
		(polygon
			(pts
				(arc
					(start 95.005906 -269.226284)
					(mid 94.375986 -269.226284)
					(end 95.005906 -269.226284)
				)
			)
		)
	)
	(zone
		(layers "B.Cu" "In4.Cu" "In6.Cu" "In11.Cu" "In13.Cu" "In15.Cu")
		(hatch none 0.5)
		(connect_pads
			(clearance 0)
		)
		(min_thickness 0.25)
		(keepout
			(tracks not_allowed)
			(vias allowed)
			(pads allowed)
			(copperpour not_allowed)
			(footprints allowed)
		)
		(placement
			(enabled no)
			(sheetname "")
		)
		(fill yes
			(thermal_gap 0.5)
			(thermal_bridge_width 0.5)
			(island_removal_mode 0)
		)
		(polygon
			(pts
				(arc
					(start 427.790102 -204.134974)
					(mid 427.122082 -204.134974)
					(end 427.790102 -204.134974)
				)
			)
		)
	)
	(zone
		(layers "B.Cu" "In4.Cu" "In6.Cu" "In11.Cu" "In13.Cu" "In15.Cu")
		(hatch none 0.5)
		(connect_pads
			(clearance 0)
		)
		(min_thickness 0.25)
		(keepout
			(tracks not_allowed)
			(vias allowed)
			(pads allowed)
			(copperpour not_allowed)
			(footprints allowed)
		)
		(placement
			(enabled no)
			(sheetname "")
		)
		(fill yes
			(thermal_gap 0.5)
			(thermal_bridge_width 0.5)
			(island_removal_mode 0)
		)
		(polygon
			(pts
				(arc
					(start 344.055954 -249.34418)
					(mid 343.426034 -249.34418)
					(end 344.055954 -249.34418)
				)
			)
		)
	)
	(zone
		(layers "B.Cu" "In4.Cu" "In6.Cu" "In11.Cu" "In13.Cu" "In15.Cu")
		(hatch none 0.5)
		(connect_pads
			(clearance 0)
		)
		(min_thickness 0.25)
		(keepout
			(tracks not_allowed)
			(vias allowed)
			(pads allowed)
			(copperpour not_allowed)
			(footprints allowed)
		)
		(placement
			(enabled no)
			(sheetname "")
		)
		(fill yes
			(thermal_gap 0.5)
			(thermal_bridge_width 0.5)
			(island_removal_mode 0)
		)
		(polygon
			(pts
				(arc
					(start 179.850034 -201.585322)
					(mid 179.182014 -201.585322)
					(end 179.850034 -201.585322)
				)
			)
		)
	)
	(zone
		(layers "B.Cu" "In4.Cu" "In6.Cu" "In11.Cu" "In13.Cu" "In15.Cu")
		(hatch none 0.5)
		(connect_pads
			(clearance 0)
		)
		(min_thickness 0.25)
		(keepout
			(tracks not_allowed)
			(vias allowed)
			(pads allowed)
			(copperpour not_allowed)
			(footprints allowed)
		)
		(placement
			(enabled no)
			(sheetname "")
		)
		(fill yes
			(thermal_gap 0.5)
			(thermal_bridge_width 0.5)
			(island_removal_mode 0)
		)
		(polygon
			(pts
				(arc
					(start 365.144812 4.650994)
					(mid 364.476792 4.650994)
					(end 365.144812 4.650994)
				)
			)
		)
	)
	(zone
		(layers "B.Cu" "In4.Cu" "In6.Cu" "In11.Cu" "In13.Cu" "In15.Cu")
		(hatch none 0.5)
		(connect_pads
			(clearance 0)
		)
		(min_thickness 0.25)
		(keepout
			(tracks not_allowed)
			(vias allowed)
			(pads allowed)
			(copperpour not_allowed)
			(footprints allowed)
		)
		(placement
			(enabled no)
			(sheetname "")
		)
		(fill yes
			(thermal_gap 0.5)
			(thermal_bridge_width 0.5)
			(island_removal_mode 0)
		)
		(polygon
			(pts
				(arc
					(start 292.614096 -200.735184)
					(mid 291.946076 -200.735184)
					(end 292.614096 -200.735184)
				)
			)
		)
	)
	(zone
		(layers "B.Cu" "In4.Cu" "In6.Cu" "In11.Cu" "In13.Cu" "In15.Cu")
		(hatch none 0.5)
		(connect_pads
			(clearance 0)
		)
		(min_thickness 0.25)
		(keepout
			(tracks not_allowed)
			(vias allowed)
			(pads allowed)
			(copperpour not_allowed)
			(footprints allowed)
		)
		(placement
			(enabled no)
			(sheetname "")
		)
		(fill yes
			(thermal_gap 0.5)
			(thermal_bridge_width 0.5)
			(island_removal_mode 0)
		)
		(polygon
			(pts
				(arc
					(start 179.850034 -299.335444)
					(mid 179.182014 -299.335444)
					(end 179.850034 -299.335444)
				)
			)
		)
	)
	(zone
		(layers "B.Cu" "In4.Cu" "In6.Cu" "In11.Cu" "In13.Cu" "In15.Cu")
		(hatch none 0.5)
		(connect_pads
			(clearance 0)
		)
		(min_thickness 0.25)
		(keepout
			(tracks not_allowed)
			(vias allowed)
			(pads allowed)
			(copperpour not_allowed)
			(footprints allowed)
		)
		(placement
			(enabled no)
			(sheetname "")
		)
		(fill yes
			(thermal_gap 0.5)
			(thermal_bridge_width 0.5)
			(island_removal_mode 0)
		)
		(polygon
			(pts
				(arc
					(start 128.839722 -280.566368)
					(mid 128.209802 -280.566368)
					(end 128.839722 -280.566368)
				)
			)
		)
	)
	(zone
		(layers "B.Cu" "In4.Cu" "In6.Cu" "In11.Cu" "In13.Cu" "In15.Cu")
		(hatch none 0.5)
		(connect_pads
			(clearance 0)
		)
		(min_thickness 0.25)
		(keepout
			(tracks not_allowed)
			(vias allowed)
			(pads allowed)
			(copperpour not_allowed)
			(footprints allowed)
		)
		(placement
			(enabled no)
			(sheetname "")
		)
		(fill yes
			(thermal_gap 0.5)
			(thermal_bridge_width 0.5)
			(island_removal_mode 0)
		)
		(polygon
			(pts
				(arc
					(start 128.839722 -290.286186)
					(mid 128.209802 -290.286186)
					(end 128.839722 -290.286186)
				)
			)
		)
	)
	(zone
		(layers "B.Cu" "In4.Cu" "In6.Cu" "In11.Cu" "In13.Cu" "In15.Cu")
		(hatch none 0.5)
		(connect_pads
			(clearance 0)
		)
		(min_thickness 0.25)
		(keepout
			(tracks not_allowed)
			(vias allowed)
			(pads allowed)
			(copperpour not_allowed)
			(footprints allowed)
		)
		(placement
			(enabled no)
			(sheetname "")
		)
		(fill yes
			(thermal_gap 0.5)
			(thermal_bridge_width 0.5)
			(island_removal_mode 0)
		)
		(polygon
			(pts
				(arc
					(start 128.369822 -274.896326)
					(mid 127.739902 -274.896326)
					(end 128.369822 -274.896326)
				)
			)
		)
	)
	(zone
		(layers "B.Cu" "In4.Cu" "In6.Cu" "In11.Cu" "In13.Cu" "In15.Cu")
		(hatch none 0.5)
		(connect_pads
			(clearance 0)
		)
		(min_thickness 0.25)
		(keepout
			(tracks not_allowed)
			(vias allowed)
			(pads allowed)
			(copperpour not_allowed)
			(footprints allowed)
		)
		(placement
			(enabled no)
			(sheetname "")
		)
		(fill yes
			(thermal_gap 0.5)
			(thermal_bridge_width 0.5)
			(island_removal_mode 0)
		)
		(polygon
			(pts
				(arc
					(start 129.949702 -250.964446)
					(mid 129.319782 -250.964446)
					(end 129.949702 -250.964446)
				)
			)
		)
	)
	(zone
		(layers "B.Cu" "In4.Cu" "In6.Cu" "In11.Cu" "In13.Cu" "In15.Cu")
		(hatch none 0.5)
		(connect_pads
			(clearance 0)
		)
		(min_thickness 0.25)
		(keepout
			(tracks not_allowed)
			(vias allowed)
			(pads allowed)
			(copperpour not_allowed)
			(footprints allowed)
		)
		(placement
			(enabled no)
			(sheetname "")
		)
		(fill yes
			(thermal_gap 0.5)
			(thermal_bridge_width 0.5)
			(island_removal_mode 0)
		)
		(polygon
			(pts
				(arc
					(start 427.790102 -267.035026)
					(mid 427.122082 -267.035026)
					(end 427.790102 -267.035026)
				)
			)
		)
	)
	(zone
		(layers "B.Cu" "In4.Cu" "In6.Cu" "In11.Cu" "In13.Cu" "In15.Cu")
		(hatch none 0.5)
		(connect_pads
			(clearance 0)
		)
		(min_thickness 0.25)
		(keepout
			(tracks not_allowed)
			(vias allowed)
			(pads allowed)
			(copperpour not_allowed)
			(footprints allowed)
		)
		(placement
			(enabled no)
			(sheetname "")
		)
		(fill yes
			(thermal_gap 0.5)
			(thermal_bridge_width 0.5)
			(island_removal_mode 0)
		)
		(polygon
			(pts
				(arc
					(start 427.790102 -301.034958)
					(mid 427.122082 -301.034958)
					(end 427.790102 -301.034958)
				)
			)
		)
	)
	(zone
		(layers "B.Cu" "In4.Cu" "In6.Cu" "In11.Cu" "In13.Cu" "In15.Cu")
		(hatch none 0.5)
		(connect_pads
			(clearance 0)
		)
		(min_thickness 0.25)
		(keepout
			(tracks not_allowed)
			(vias allowed)
			(pads allowed)
			(copperpour not_allowed)
			(footprints allowed)
		)
		(placement
			(enabled no)
			(sheetname "")
		)
		(fill yes
			(thermal_gap 0.5)
			(thermal_bridge_width 0.5)
			(island_removal_mode 0)
		)
		(polygon
			(pts
				(arc
					(start 288.514028 -215.18499)
					(mid 287.846008 -215.18499)
					(end 288.514028 -215.18499)
				)
			)
		)
	)
	(zone
		(layers "B.Cu" "In4.Cu" "In6.Cu" "In11.Cu" "In13.Cu" "In15.Cu")
		(hatch none 0.5)
		(connect_pads
			(clearance 0)
		)
		(min_thickness 0.25)
		(keepout
			(tracks not_allowed)
			(vias allowed)
			(pads allowed)
			(copperpour not_allowed)
			(footprints allowed)
		)
		(placement
			(enabled no)
			(sheetname "")
		)
		(fill yes
			(thermal_gap 0.5)
			(thermal_bridge_width 0.5)
			(island_removal_mode 0)
		)
		(polygon
			(pts
				(arc
					(start 431.89017 -212.635084)
					(mid 431.22215 -212.635084)
					(end 431.89017 -212.635084)
				)
			)
		)
	)
	(zone
		(layers "B.Cu" "In4.Cu" "In6.Cu" "In11.Cu" "In13.Cu" "In15.Cu")
		(hatch none 0.5)
		(connect_pads
			(clearance 0)
		)
		(min_thickness 0.25)
		(keepout
			(tracks not_allowed)
			(vias allowed)
			(pads allowed)
			(copperpour not_allowed)
			(footprints allowed)
		)
		(placement
			(enabled no)
			(sheetname "")
		)
		(fill yes
			(thermal_gap 0.5)
			(thermal_bridge_width 0.5)
			(island_removal_mode 0)
		)
		(polygon
			(pts
				(arc
					(start 343.886028 -265.986006)
					(mid 343.256108 -265.986006)
					(end 343.886028 -265.986006)
				)
			)
		)
	)
	(zone
		(layers "B.Cu" "In4.Cu" "In6.Cu" "In11.Cu" "In13.Cu" "In15.Cu")
		(hatch none 0.5)
		(connect_pads
			(clearance 0)
		)
		(min_thickness 0.25)
		(keepout
			(tracks not_allowed)
			(vias allowed)
			(pads allowed)
			(copperpour not_allowed)
			(footprints allowed)
		)
		(placement
			(enabled no)
			(sheetname "")
		)
		(fill yes
			(thermal_gap 0.5)
			(thermal_bridge_width 0.5)
			(island_removal_mode 0)
		)
		(polygon
			(pts
				(arc
					(start 376.479816 -243.674138)
					(mid 375.849896 -243.674138)
					(end 376.479816 -243.674138)
				)
			)
		)
	)
	(zone
		(layers "B.Cu" "In4.Cu" "In6.Cu" "In11.Cu" "In13.Cu" "In15.Cu")
		(hatch none 0.5)
		(connect_pads
			(clearance 0)
		)
		(min_thickness 0.25)
		(keepout
			(tracks not_allowed)
			(vias allowed)
			(pads allowed)
			(copperpour not_allowed)
			(footprints allowed)
		)
		(placement
			(enabled no)
			(sheetname "")
		)
		(fill yes
			(thermal_gap 0.5)
			(thermal_bridge_width 0.5)
			(island_removal_mode 0)
		)
		(polygon
			(pts
				(arc
					(start 96.416114 -278.13635)
					(mid 95.786194 -278.13635)
					(end 96.416114 -278.13635)
				)
			)
		)
	)
	(zone
		(layers "B.Cu" "In4.Cu" "In6.Cu" "In11.Cu" "In13.Cu" "In15.Cu")
		(hatch none 0.5)
		(connect_pads
			(clearance 0)
		)
		(min_thickness 0.25)
		(keepout
			(tracks not_allowed)
			(vias allowed)
			(pads allowed)
			(copperpour not_allowed)
			(footprints allowed)
		)
		(placement
			(enabled no)
			(sheetname "")
		)
		(fill yes
			(thermal_gap 0.5)
			(thermal_bridge_width 0.5)
			(island_removal_mode 0)
		)
		(polygon
			(pts
				(arc
					(start 94.705932 -243.674392)
					(mid 94.076012 -243.674392)
					(end 94.705932 -243.674392)
				)
			)
		)
	)
	(zone
		(layers "B.Cu" "In4.Cu" "In6.Cu" "In11.Cu" "In13.Cu" "In15.Cu")
		(hatch none 0.5)
		(connect_pads
			(clearance 0)
		)
		(min_thickness 0.25)
		(keepout
			(tracks not_allowed)
			(vias allowed)
			(pads allowed)
			(copperpour not_allowed)
			(footprints allowed)
		)
		(placement
			(enabled no)
			(sheetname "")
		)
		(fill yes
			(thermal_gap 0.5)
			(thermal_bridge_width 0.5)
			(island_removal_mode 0)
		)
		(polygon
			(pts
				(arc
					(start 377.41987 -255.014222)
					(mid 376.78995 -255.014222)
					(end 377.41987 -255.014222)
				)
			)
		)
	)
	(zone
		(layers "B.Cu" "In4.Cu" "In6.Cu" "In11.Cu" "In13.Cu" "In15.Cu")
		(hatch none 0.5)
		(connect_pads
			(clearance 0)
		)
		(min_thickness 0.25)
		(keepout
			(tracks not_allowed)
			(vias allowed)
			(pads allowed)
			(copperpour not_allowed)
			(footprints allowed)
		)
		(placement
			(enabled no)
			(sheetname "")
		)
		(fill yes
			(thermal_gap 0.5)
			(thermal_bridge_width 0.5)
			(island_removal_mode 0)
		)
		(polygon
			(pts
				(arc
					(start 179.850034 -229.635304)
					(mid 179.182014 -229.635304)
					(end 179.850034 -229.635304)
				)
			)
		)
	)
	(zone
		(layers "B.Cu" "In4.Cu" "In6.Cu" "In11.Cu" "In13.Cu" "In15.Cu")
		(hatch none 0.5)
		(connect_pads
			(clearance 0)
		)
		(min_thickness 0.25)
		(keepout
			(tracks not_allowed)
			(vias allowed)
			(pads allowed)
			(copperpour not_allowed)
			(footprints allowed)
		)
		(placement
			(enabled no)
			(sheetname "")
		)
		(fill yes
			(thermal_gap 0.5)
			(thermal_bridge_width 0.5)
			(island_removal_mode 0)
		)
		(polygon
			(pts
				(arc
					(start 96.416114 -282.996386)
					(mid 95.786194 -282.996386)
					(end 96.416114 -282.996386)
				)
			)
		)
	)
	(zone
		(layers "B.Cu" "In4.Cu" "In6.Cu" "In11.Cu" "In13.Cu" "In15.Cu")
		(hatch none 0.5)
		(connect_pads
			(clearance 0)
		)
		(min_thickness 0.25)
		(keepout
			(tracks not_allowed)
			(vias allowed)
			(pads allowed)
			(copperpour not_allowed)
			(footprints allowed)
		)
		(placement
			(enabled no)
			(sheetname "")
		)
		(fill yes
			(thermal_gap 0.5)
			(thermal_bridge_width 0.5)
			(island_removal_mode 0)
		)
		(polygon
			(pts
				(arc
					(start 94.705932 -229.094538)
					(mid 94.076012 -229.094538)
					(end 94.705932 -229.094538)
				)
			)
		)
	)
	(zone
		(layers "B.Cu" "In4.Cu" "In6.Cu" "In11.Cu" "In13.Cu" "In15.Cu")
		(hatch none 0.5)
		(connect_pads
			(clearance 0)
		)
		(min_thickness 0.25)
		(keepout
			(tracks not_allowed)
			(vias allowed)
			(pads allowed)
			(copperpour not_allowed)
			(footprints allowed)
		)
		(placement
			(enabled no)
			(sheetname "")
		)
		(fill yes
			(thermal_gap 0.5)
			(thermal_bridge_width 0.5)
			(island_removal_mode 0)
		)
		(polygon
			(pts
				(arc
					(start 129.479802 -245.294404)
					(mid 128.849882 -245.294404)
					(end 129.479802 -245.294404)
				)
			)
		)
	)
	(zone
		(layers "B.Cu" "In4.Cu" "In6.Cu" "In11.Cu" "In13.Cu" "In15.Cu")
		(hatch none 0.5)
		(connect_pads
			(clearance 0)
		)
		(min_thickness 0.25)
		(keepout
			(tracks not_allowed)
			(vias allowed)
			(pads allowed)
			(copperpour not_allowed)
			(footprints allowed)
		)
		(placement
			(enabled no)
			(sheetname "")
		)
		(fill yes
			(thermal_gap 0.5)
			(thermal_bridge_width 0.5)
			(island_removal_mode 0)
		)
		(polygon
			(pts
				(arc
					(start 427.790102 -220.285056)
					(mid 427.122082 -220.285056)
					(end 427.790102 -220.285056)
				)
			)
		)
	)
	(zone
		(layers "B.Cu" "In4.Cu" "In6.Cu" "In11.Cu" "In13.Cu" "In15.Cu")
		(hatch none 0.5)
		(connect_pads
			(clearance 0)
		)
		(min_thickness 0.25)
		(keepout
			(tracks not_allowed)
			(vias allowed)
			(pads allowed)
			(copperpour not_allowed)
			(footprints allowed)
		)
		(placement
			(enabled no)
			(sheetname "")
		)
		(fill yes
			(thermal_gap 0.5)
			(thermal_bridge_width 0.5)
			(island_removal_mode 0)
		)
		(polygon
			(pts
				(arc
					(start 343.886028 -288.66592)
					(mid 343.256108 -288.66592)
					(end 343.886028 -288.66592)
				)
			)
		)
	)
	(zone
		(layers "B.Cu" "In4.Cu" "In6.Cu" "In11.Cu" "In13.Cu" "In15.Cu")
		(hatch none 0.5)
		(connect_pads
			(clearance 0)
		)
		(min_thickness 0.25)
		(keepout
			(tracks not_allowed)
			(vias allowed)
			(pads allowed)
			(copperpour not_allowed)
			(footprints allowed)
		)
		(placement
			(enabled no)
			(sheetname "")
		)
		(fill yes
			(thermal_gap 0.5)
			(thermal_bridge_width 0.5)
			(island_removal_mode 0)
		)
		(polygon
			(pts
				(arc
					(start 288.514028 -280.634948)
					(mid 287.846008 -280.634948)
					(end 288.514028 -280.634948)
				)
			)
		)
	)
	(zone
		(layers "B.Cu" "In4.Cu" "In6.Cu" "In11.Cu" "In13.Cu" "In15.Cu")
		(hatch none 0.5)
		(connect_pads
			(clearance 0)
		)
		(min_thickness 0.25)
		(keepout
			(tracks not_allowed)
			(vias allowed)
			(pads allowed)
			(copperpour not_allowed)
			(footprints allowed)
		)
		(placement
			(enabled no)
			(sheetname "")
		)
		(fill yes
			(thermal_gap 0.5)
			(thermal_bridge_width 0.5)
			(island_removal_mode 0)
		)
		(polygon
			(pts
				(arc
					(start 377.41987 -229.094284)
					(mid 376.78995 -229.094284)
					(end 377.41987 -229.094284)
				)
			)
		)
	)
	(zone
		(layers "B.Cu" "In4.Cu" "In6.Cu" "In11.Cu" "In13.Cu" "In15.Cu")
		(hatch none 0.5)
		(connect_pads
			(clearance 0)
		)
		(min_thickness 0.25)
		(keepout
			(tracks not_allowed)
			(vias allowed)
			(pads allowed)
			(copperpour not_allowed)
			(footprints allowed)
		)
		(placement
			(enabled no)
			(sheetname "")
		)
		(fill yes
			(thermal_gap 0.5)
			(thermal_bridge_width 0.5)
			(island_removal_mode 0)
		)
		(polygon
			(pts
				(arc
					(start 28.902152 -421.69969)
					(mid 28.234132 -421.69969)
					(end 28.902152 -421.69969)
				)
			)
		)
	)
	(zone
		(layers "B.Cu" "In4.Cu" "In6.Cu" "In11.Cu" "In13.Cu" "In15.Cu")
		(hatch none 0.5)
		(connect_pads
			(clearance 0)
		)
		(min_thickness 0.25)
		(keepout
			(tracks not_allowed)
			(vias allowed)
			(pads allowed)
			(copperpour not_allowed)
			(footprints allowed)
		)
		(placement
			(enabled no)
			(sheetname "")
		)
		(fill yes
			(thermal_gap 0.5)
			(thermal_bridge_width 0.5)
			(island_removal_mode 0)
		)
		(polygon
			(pts
				(arc
					(start 377.41987 -238.814102)
					(mid 376.78995 -238.814102)
					(end 377.41987 -238.814102)
				)
			)
		)
	)
	(zone
		(layers "B.Cu" "In4.Cu" "In6.Cu" "In11.Cu" "In13.Cu" "In15.Cu")
		(hatch none 0.5)
		(connect_pads
			(clearance 0)
		)
		(min_thickness 0.25)
		(keepout
			(tracks not_allowed)
			(vias allowed)
			(pads allowed)
			(copperpour not_allowed)
			(footprints allowed)
		)
		(placement
			(enabled no)
			(sheetname "")
		)
		(fill yes
			(thermal_gap 0.5)
			(thermal_bridge_width 0.5)
			(island_removal_mode 0)
		)
		(polygon
			(pts
				(arc
					(start 288.514028 -198.185024)
					(mid 287.846008 -198.185024)
					(end 288.514028 -198.185024)
				)
			)
		)
	)
	(zone
		(layers "B.Cu" "In4.Cu" "In6.Cu" "In11.Cu" "In13.Cu" "In15.Cu")
		(hatch none 0.5)
		(connect_pads
			(clearance 0)
		)
		(min_thickness 0.25)
		(keepout
			(tracks not_allowed)
			(vias allowed)
			(pads allowed)
			(copperpour not_allowed)
			(footprints allowed)
		)
		(placement
			(enabled no)
			(sheetname "")
		)
		(fill yes
			(thermal_gap 0.5)
			(thermal_bridge_width 0.5)
			(island_removal_mode 0)
		)
		(polygon
			(pts
				(arc
					(start 183.950102 -254.285242)
					(mid 183.282082 -254.285242)
					(end 183.950102 -254.285242)
				)
			)
		)
	)
	(zone
		(layers "B.Cu" "In6.Cu" "In11.Cu" "In13.Cu" "In15.Cu")
		(hatch none 0.5)
		(connect_pads
			(clearance 0)
		)
		(min_thickness 0.25)
		(keepout
			(tracks not_allowed)
			(vias allowed)
			(pads allowed)
			(copperpour not_allowed)
			(footprints allowed)
		)
		(placement
			(enabled no)
			(sheetname "")
		)
		(fill yes
			(thermal_gap 0.5)
			(thermal_bridge_width 0.5)
			(island_removal_mode 0)
		)
		(polygon
			(pts
				(arc
					(start 401.860512 -412.84652)
					(mid 401.192492 -412.84652)
					(end 401.860512 -412.84652)
				)
			)
		)
	)
	(zone
		(layers "B.Cu" "In6.Cu" "In11.Cu" "In13.Cu" "In15.Cu")
		(hatch none 0.5)
		(connect_pads
			(clearance 0)
		)
		(min_thickness 0.25)
		(keepout
			(tracks not_allowed)
			(vias allowed)
			(pads allowed)
			(copperpour not_allowed)
			(footprints allowed)
		)
		(placement
			(enabled no)
			(sheetname "")
		)
		(fill yes
			(thermal_gap 0.5)
			(thermal_bridge_width 0.5)
			(island_removal_mode 0)
		)
		(polygon
			(pts
				(arc
					(start 90.94597 -225.854514)
					(mid 90.31605 -225.854514)
					(end 90.94597 -225.854514)
				)
			)
		)
	)
	(zone
		(layers "B.Cu" "In6.Cu" "In11.Cu" "In13.Cu" "In15.Cu")
		(hatch none 0.5)
		(connect_pads
			(clearance 0)
		)
		(min_thickness 0.25)
		(keepout
			(tracks not_allowed)
			(vias allowed)
			(pads allowed)
			(copperpour not_allowed)
			(footprints allowed)
		)
		(placement
			(enabled no)
			(sheetname "")
		)
		(fill yes
			(thermal_gap 0.5)
			(thermal_bridge_width 0.5)
			(island_removal_mode 0)
		)
		(polygon
			(pts
				(arc
					(start 126.18974 -226.66452)
					(mid 125.55982 -226.66452)
					(end 126.18974 -226.66452)
				)
			)
		)
	)
	(zone
		(layers "B.Cu" "In6.Cu" "In11.Cu" "In13.Cu" "In15.Cu")
		(hatch none 0.5)
		(connect_pads
			(clearance 0)
		)
		(min_thickness 0.25)
		(keepout
			(tracks not_allowed)
			(vias allowed)
			(pads allowed)
			(copperpour not_allowed)
			(footprints allowed)
		)
		(placement
			(enabled no)
			(sheetname "")
		)
		(fill yes
			(thermal_gap 0.5)
			(thermal_bridge_width 0.5)
			(island_removal_mode 0)
		)
		(polygon
			(pts
				(arc
					(start 37.129974 -313.78525)
					(mid 36.461954 -313.78525)
					(end 37.129974 -313.78525)
				)
			)
		)
	)
	(zone
		(layers "B.Cu" "In6.Cu" "In11.Cu" "In13.Cu" "In15.Cu")
		(hatch none 0.5)
		(connect_pads
			(clearance 0)
		)
		(min_thickness 0.25)
		(keepout
			(tracks not_allowed)
			(vias allowed)
			(pads allowed)
			(copperpour not_allowed)
			(footprints allowed)
		)
		(placement
			(enabled no)
			(sheetname "")
		)
		(fill yes
			(thermal_gap 0.5)
			(thermal_bridge_width 0.5)
			(island_removal_mode 0)
		)
		(polygon
			(pts
				(arc
					(start 191.494156 -228.78542)
					(mid 190.826136 -228.78542)
					(end 191.494156 -228.78542)
				)
			)
		)
	)
	(zone
		(layers "B.Cu" "In6.Cu" "In11.Cu" "In13.Cu" "In15.Cu")
		(hatch none 0.5)
		(connect_pads
			(clearance 0)
		)
		(min_thickness 0.25)
		(keepout
			(tracks not_allowed)
			(vias allowed)
			(pads allowed)
			(copperpour not_allowed)
			(footprints allowed)
		)
		(placement
			(enabled no)
			(sheetname "")
		)
		(fill yes
			(thermal_gap 0.5)
			(thermal_bridge_width 0.5)
			(island_removal_mode 0)
		)
		(polygon
			(pts
				(arc
					(start 55.874412 -4.963414)
					(mid 55.206392 -4.963414)
					(end 55.874412 -4.963414)
				)
			)
		)
	)
	(zone
		(layers "B.Cu" "In6.Cu" "In11.Cu" "In13.Cu" "In15.Cu")
		(hatch none 0.5)
		(connect_pads
			(clearance 0)
		)
		(min_thickness 0.25)
		(keepout
			(tracks not_allowed)
			(vias allowed)
			(pads allowed)
			(copperpour not_allowed)
			(footprints allowed)
		)
		(placement
			(enabled no)
			(sheetname "")
		)
		(fill yes
			(thermal_gap 0.5)
			(thermal_bridge_width 0.5)
			(island_removal_mode 0)
		)
		(polygon
			(pts
				(arc
					(start 425.06519 -17.61236)
					(mid 424.39717 -17.61236)
					(end 425.06519 -17.61236)
				)
			)
		)
	)
	(zone
		(layers "B.Cu" "In6.Cu" "In11.Cu" "In13.Cu" "In15.Cu")
		(hatch none 0.5)
		(connect_pads
			(clearance 0)
		)
		(min_thickness 0.25)
		(keepout
			(tracks not_allowed)
			(vias allowed)
			(pads allowed)
			(copperpour not_allowed)
			(footprints allowed)
		)
		(placement
			(enabled no)
			(sheetname "")
		)
		(fill yes
			(thermal_gap 0.5)
			(thermal_bridge_width 0.5)
			(island_removal_mode 0)
		)
		(polygon
			(pts
				(arc
					(start 132.76961 -228.284532)
					(mid 132.13969 -228.284532)
					(end 132.76961 -228.284532)
				)
			)
		)
	)
	(zone
		(layers "B.Cu" "In6.Cu" "In11.Cu" "In13.Cu" "In15.Cu")
		(hatch none 0.5)
		(connect_pads
			(clearance 0)
		)
		(min_thickness 0.25)
		(keepout
			(tracks not_allowed)
			(vias allowed)
			(pads allowed)
			(copperpour not_allowed)
			(footprints allowed)
		)
		(placement
			(enabled no)
			(sheetname "")
		)
		(fill yes
			(thermal_gap 0.5)
			(thermal_bridge_width 0.5)
			(island_removal_mode 0)
		)
		(polygon
			(pts
				(arc
					(start 381.179832 -233.954066)
					(mid 380.549912 -233.954066)
					(end 381.179832 -233.954066)
				)
			)
		)
	)
	(zone
		(layers "B.Cu" "In6.Cu" "In11.Cu" "In13.Cu" "In15.Cu")
		(hatch none 0.5)
		(connect_pads
			(clearance 0)
		)
		(min_thickness 0.25)
		(keepout
			(tracks not_allowed)
			(vias allowed)
			(pads allowed)
			(copperpour not_allowed)
			(footprints allowed)
		)
		(placement
			(enabled no)
			(sheetname "")
		)
		(fill yes
			(thermal_gap 0.5)
			(thermal_bridge_width 0.5)
			(island_removal_mode 0)
		)
		(polygon
			(pts
				(arc
					(start 92.655898 -281.376374)
					(mid 92.025978 -281.376374)
					(end 92.655898 -281.376374)
				)
			)
		)
	)
	(zone
		(layers "B.Cu" "In6.Cu" "In11.Cu" "In13.Cu" "In15.Cu")
		(hatch none 0.5)
		(connect_pads
			(clearance 0)
		)
		(min_thickness 0.25)
		(keepout
			(tracks not_allowed)
			(vias allowed)
			(pads allowed)
			(copperpour not_allowed)
			(footprints allowed)
		)
		(placement
			(enabled no)
			(sheetname "")
		)
		(fill yes
			(thermal_gap 0.5)
			(thermal_bridge_width 0.5)
			(island_removal_mode 0)
		)
		(polygon
			(pts
				(arc
					(start 285.070042 -287.435036)
					(mid 284.402022 -287.435036)
					(end 285.070042 -287.435036)
				)
			)
		)
	)
	(zone
		(layers "B.Cu" "In6.Cu" "In11.Cu" "In13.Cu" "In15.Cu")
		(hatch none 0.5)
		(connect_pads
			(clearance 0)
		)
		(min_thickness 0.25)
		(keepout
			(tracks not_allowed)
			(vias allowed)
			(pads allowed)
			(copperpour not_allowed)
			(footprints allowed)
		)
		(placement
			(enabled no)
			(sheetname "")
		)
		(fill yes
			(thermal_gap 0.5)
			(thermal_bridge_width 0.5)
			(island_removal_mode 0)
		)
		(polygon
			(pts
				(arc
					(start 37.129974 -296.785284)
					(mid 36.461954 -296.785284)
					(end 37.129974 -296.785284)
				)
			)
		)
	)
	(zone
		(layers "B.Cu" "In6.Cu" "In11.Cu" "In13.Cu" "In15.Cu")
		(hatch none 0.5)
		(connect_pads
			(clearance 0)
		)
		(min_thickness 0.25)
		(keepout
			(tracks not_allowed)
			(vias allowed)
			(pads allowed)
			(copperpour not_allowed)
			(footprints allowed)
		)
		(placement
			(enabled no)
			(sheetname "")
		)
		(fill yes
			(thermal_gap 0.5)
			(thermal_bridge_width 0.5)
			(island_removal_mode 0)
		)
		(polygon
			(pts
				(arc
					(start 191.494156 -287.43529)
					(mid 190.826136 -287.43529)
					(end 191.494156 -287.43529)
				)
			)
		)
	)
	(zone
		(layers "B.Cu" "In6.Cu" "In11.Cu" "In13.Cu" "In15.Cu")
		(hatch none 0.5)
		(connect_pads
			(clearance 0)
		)
		(min_thickness 0.25)
		(keepout
			(tracks not_allowed)
			(vias allowed)
			(pads allowed)
			(copperpour not_allowed)
			(footprints allowed)
		)
		(placement
			(enabled no)
			(sheetname "")
		)
		(fill yes
			(thermal_gap 0.5)
			(thermal_bridge_width 0.5)
			(island_removal_mode 0)
		)
		(polygon
			(pts
				(arc
					(start 435.334156 -251.735082)
					(mid 434.666136 -251.735082)
					(end 435.334156 -251.735082)
				)
			)
		)
	)
	(zone
		(layers "B.Cu" "In6.Cu" "In11.Cu" "In13.Cu" "In15.Cu")
		(hatch none 0.5)
		(connect_pads
			(clearance 0)
		)
		(min_thickness 0.25)
		(keepout
			(tracks not_allowed)
			(vias allowed)
			(pads allowed)
			(copperpour not_allowed)
			(footprints allowed)
		)
		(placement
			(enabled no)
			(sheetname "")
		)
		(fill yes
			(thermal_gap 0.5)
			(thermal_bridge_width 0.5)
			(island_removal_mode 0)
		)
		(polygon
			(pts
				(arc
					(start 439.434224 -254.284988)
					(mid 438.766204 -254.284988)
					(end 439.434224 -254.284988)
				)
			)
		)
	)
	(zone
		(layers "B.Cu" "In6.Cu" "In11.Cu" "In13.Cu" "In15.Cu")
		(hatch none 0.5)
		(connect_pads
			(clearance 0)
		)
		(min_thickness 0.25)
		(keepout
			(tracks not_allowed)
			(vias allowed)
			(pads allowed)
			(copperpour not_allowed)
			(footprints allowed)
		)
		(placement
			(enabled no)
			(sheetname "")
		)
		(fill yes
			(thermal_gap 0.5)
			(thermal_bridge_width 0.5)
			(island_removal_mode 0)
		)
		(polygon
			(pts
				(arc
					(start 187.394088 -295.085262)
					(mid 186.726068 -295.085262)
					(end 187.394088 -295.085262)
				)
			)
		)
	)
	(zone
		(layers "B.Cu" "In6.Cu" "In11.Cu" "In13.Cu" "In15.Cu")
		(hatch none 0.5)
		(connect_pads
			(clearance 0)
		)
		(min_thickness 0.25)
		(keepout
			(tracks not_allowed)
			(vias allowed)
			(pads allowed)
			(copperpour not_allowed)
			(footprints allowed)
		)
		(placement
			(enabled no)
			(sheetname "")
		)
		(fill yes
			(thermal_gap 0.5)
			(thermal_bridge_width 0.5)
			(island_removal_mode 0)
		)
		(polygon
			(pts
				(arc
					(start 132.00634 -385.31038)
					(mid 131.37642 -385.31038)
					(end 132.00634 -385.31038)
				)
			)
		)
	)
	(zone
		(layers "B.Cu" "In6.Cu" "In11.Cu" "In13.Cu" "In15.Cu")
		(hatch none 0.5)
		(connect_pads
			(clearance 0)
		)
		(min_thickness 0.25)
		(keepout
			(tracks not_allowed)
			(vias allowed)
			(pads allowed)
			(copperpour not_allowed)
			(footprints allowed)
		)
		(placement
			(enabled no)
			(sheetname "")
		)
		(fill yes
			(thermal_gap 0.5)
			(thermal_bridge_width 0.5)
			(island_removal_mode 0)
		)
		(polygon
			(pts
				(arc
					(start 114.4397 -227.474526)
					(mid 113.80978 -227.474526)
					(end 114.4397 -227.474526)
				)
			)
		)
	)
	(zone
		(layers "B.Cu" "In6.Cu" "In11.Cu" "In13.Cu" "In15.Cu")
		(hatch none 0.5)
		(connect_pads
			(clearance 0)
		)
		(min_thickness 0.25)
		(keepout
			(tracks not_allowed)
			(vias allowed)
			(pads allowed)
			(copperpour not_allowed)
			(footprints allowed)
		)
		(placement
			(enabled no)
			(sheetname "")
		)
		(fill yes
			(thermal_gap 0.5)
			(thermal_bridge_width 0.5)
			(island_removal_mode 0)
		)
		(polygon
			(pts
				(arc
					(start 187.394088 -299.335444)
					(mid 186.726068 -299.335444)
					(end 187.394088 -299.335444)
				)
			)
		)
	)
	(zone
		(layers "B.Cu" "In6.Cu" "In11.Cu" "In13.Cu" "In15.Cu")
		(hatch none 0.5)
		(connect_pads
			(clearance 0)
		)
		(min_thickness 0.25)
		(keepout
			(tracks not_allowed)
			(vias allowed)
			(pads allowed)
			(copperpour not_allowed)
			(footprints allowed)
		)
		(placement
			(enabled no)
			(sheetname "")
		)
		(fill yes
			(thermal_gap 0.5)
			(thermal_bridge_width 0.5)
			(island_removal_mode 0)
		)
		(polygon
			(pts
				(arc
					(start 132.129784 -273.276314)
					(mid 131.499864 -273.276314)
					(end 132.129784 -273.276314)
				)
			)
		)
	)
	(zone
		(layers "B.Cu" "In6.Cu" "In11.Cu" "In13.Cu" "In15.Cu")
		(hatch none 0.5)
		(connect_pads
			(clearance 0)
		)
		(min_thickness 0.25)
		(keepout
			(tracks not_allowed)
			(vias allowed)
			(pads allowed)
			(copperpour not_allowed)
			(footprints allowed)
		)
		(placement
			(enabled no)
			(sheetname "")
		)
		(fill yes
			(thermal_gap 0.5)
			(thermal_bridge_width 0.5)
			(island_removal_mode 0)
		)
		(polygon
			(pts
				(arc
					(start 439.434224 -250.884944)
					(mid 438.766204 -250.884944)
					(end 439.434224 -250.884944)
				)
			)
		)
	)
	(zone
		(layers "B.Cu" "In6.Cu" "In11.Cu" "In13.Cu" "In15.Cu")
		(hatch none 0.5)
		(connect_pads
			(clearance 0)
		)
		(min_thickness 0.25)
		(keepout
			(tracks not_allowed)
			(vias allowed)
			(pads allowed)
			(copperpour not_allowed)
			(footprints allowed)
		)
		(placement
			(enabled no)
			(sheetname "")
		)
		(fill yes
			(thermal_gap 0.5)
			(thermal_bridge_width 0.5)
			(island_removal_mode 0)
		)
		(polygon
			(pts
				(arc
					(start 133.539738 -290.286186)
					(mid 132.909818 -290.286186)
					(end 133.539738 -290.286186)
				)
			)
		)
	)
	(zone
		(layers "B.Cu" "In6.Cu" "In11.Cu" "In13.Cu" "In15.Cu")
		(hatch none 0.5)
		(connect_pads
			(clearance 0)
		)
		(min_thickness 0.25)
		(keepout
			(tracks not_allowed)
			(vias allowed)
			(pads allowed)
			(copperpour not_allowed)
			(footprints allowed)
		)
		(placement
			(enabled no)
			(sheetname "")
		)
		(fill yes
			(thermal_gap 0.5)
			(thermal_bridge_width 0.5)
			(island_removal_mode 0)
		)
		(polygon
			(pts
				(arc
					(start 381.009906 -282.996132)
					(mid 380.379986 -282.996132)
					(end 381.009906 -282.996132)
				)
			)
		)
	)
	(zone
		(layers "B.Cu" "In6.Cu" "In11.Cu" "In13.Cu" "In15.Cu")
		(hatch none 0.5)
		(connect_pads
			(clearance 0)
		)
		(min_thickness 0.25)
		(keepout
			(tracks not_allowed)
			(vias allowed)
			(pads allowed)
			(copperpour not_allowed)
			(footprints allowed)
		)
		(placement
			(enabled no)
			(sheetname "")
		)
		(fill yes
			(thermal_gap 0.5)
			(thermal_bridge_width 0.5)
			(island_removal_mode 0)
		)
		(polygon
			(pts
				(arc
					(start 97.995994 -236.384338)
					(mid 97.366074 -236.384338)
					(end 97.995994 -236.384338)
				)
			)
		)
	)
	(zone
		(layers "B.Cu" "In6.Cu" "In11.Cu" "In13.Cu" "In15.Cu")
		(hatch none 0.5)
		(connect_pads
			(clearance 0)
		)
		(min_thickness 0.25)
		(keepout
			(tracks not_allowed)
			(vias allowed)
			(pads allowed)
			(copperpour not_allowed)
			(footprints allowed)
		)
		(placement
			(enabled no)
			(sheetname "")
		)
		(fill yes
			(thermal_gap 0.5)
			(thermal_bridge_width 0.5)
			(island_removal_mode 0)
		)
		(polygon
			(pts
				(arc
					(start 91.245944 -282.18638)
					(mid 90.616024 -282.18638)
					(end 91.245944 -282.18638)
				)
			)
		)
	)
	(zone
		(layers "B.Cu" "In6.Cu" "In11.Cu" "In13.Cu" "In15.Cu")
		(hatch none 0.5)
		(connect_pads
			(clearance 0)
		)
		(min_thickness 0.25)
		(keepout
			(tracks not_allowed)
			(vias allowed)
			(pads allowed)
			(copperpour not_allowed)
			(footprints allowed)
		)
		(placement
			(enabled no)
			(sheetname "")
		)
		(fill yes
			(thermal_gap 0.5)
			(thermal_bridge_width 0.5)
			(island_removal_mode 0)
		)
		(polygon
			(pts
				(arc
					(start 132.76961 -242.864386)
					(mid 132.13969 -242.864386)
					(end 132.76961 -242.864386)
				)
			)
		)
	)
	(zone
		(layers "B.Cu" "In6.Cu" "In11.Cu" "In13.Cu" "In15.Cu")
		(hatch none 0.5)
		(connect_pads
			(clearance 0)
		)
		(min_thickness 0.25)
		(keepout
			(tracks not_allowed)
			(vias allowed)
			(pads allowed)
			(copperpour not_allowed)
			(footprints allowed)
		)
		(placement
			(enabled no)
			(sheetname "")
		)
		(fill yes
			(thermal_gap 0.5)
			(thermal_bridge_width 0.5)
			(island_removal_mode 0)
		)
		(polygon
			(pts
				(arc
					(start 162.533838 -389.467344)
					(mid 161.903918 -389.467344)
					(end 162.533838 -389.467344)
				)
			)
		)
	)
	(zone
		(layers "B.Cu" "In6.Cu" "In11.Cu" "In13.Cu" "In15.Cu")
		(hatch none 0.5)
		(connect_pads
			(clearance 0)
		)
		(min_thickness 0.25)
		(keepout
			(tracks not_allowed)
			(vias allowed)
			(pads allowed)
			(copperpour not_allowed)
			(footprints allowed)
		)
		(placement
			(enabled no)
			(sheetname "")
		)
		(fill yes
			(thermal_gap 0.5)
			(thermal_bridge_width 0.5)
			(island_removal_mode 0)
		)
		(polygon
			(pts
				(arc
					(start 133.539738 -275.706332)
					(mid 132.909818 -275.706332)
					(end 133.539738 -275.706332)
				)
			)
		)
	)
	(zone
		(layers "B.Cu" "In6.Cu" "In11.Cu" "In13.Cu" "In15.Cu")
		(hatch none 0.5)
		(connect_pads
			(clearance 0)
		)
		(min_thickness 0.25)
		(keepout
			(tracks not_allowed)
			(vias allowed)
			(pads allowed)
			(copperpour not_allowed)
			(footprints allowed)
		)
		(placement
			(enabled no)
			(sheetname "")
		)
		(fill yes
			(thermal_gap 0.5)
			(thermal_bridge_width 0.5)
			(island_removal_mode 0)
		)
		(polygon
			(pts
				(arc
					(start 346.876116 -229.904036)
					(mid 346.246196 -229.904036)
					(end 346.876116 -229.904036)
				)
			)
		)
	)
	(zone
		(layers "B.Cu" "In6.Cu" "In11.Cu" "In13.Cu" "In15.Cu")
		(hatch none 0.5)
		(connect_pads
			(clearance 0)
		)
		(min_thickness 0.25)
		(keepout
			(tracks not_allowed)
			(vias allowed)
			(pads allowed)
			(copperpour not_allowed)
			(footprints allowed)
		)
		(placement
			(enabled no)
			(sheetname "")
		)
		(fill yes
			(thermal_gap 0.5)
			(thermal_bridge_width 0.5)
			(island_removal_mode 0)
		)
		(polygon
			(pts
				(arc
					(start 132.76961 -236.384338)
					(mid 132.13969 -236.384338)
					(end 132.76961 -236.384338)
				)
			)
		)
	)
	(zone
		(layers "B.Cu" "In6.Cu" "In11.Cu" "In13.Cu" "In15.Cu")
		(hatch none 0.5)
		(connect_pads
			(clearance 0)
		)
		(min_thickness 0.25)
		(keepout
			(tracks not_allowed)
			(vias allowed)
			(pads allowed)
			(copperpour not_allowed)
			(footprints allowed)
		)
		(placement
			(enabled no)
			(sheetname "")
		)
		(fill yes
			(thermal_gap 0.5)
			(thermal_bridge_width 0.5)
			(island_removal_mode 0)
		)
		(polygon
			(pts
				(arc
					(start 156.53385 -389.467344)
					(mid 155.90393 -389.467344)
					(end 156.53385 -389.467344)
				)
			)
		)
	)
	(zone
		(layers "B.Cu" "In6.Cu" "In11.Cu" "In13.Cu" "In15.Cu")
		(hatch none 0.5)
		(connect_pads
			(clearance 0)
		)
		(min_thickness 0.25)
		(keepout
			(tracks not_allowed)
			(vias allowed)
			(pads allowed)
			(copperpour not_allowed)
			(footprints allowed)
		)
		(placement
			(enabled no)
			(sheetname "")
		)
		(fill yes
			(thermal_gap 0.5)
			(thermal_bridge_width 0.5)
			(island_removal_mode 0)
		)
		(polygon
			(pts
				(arc
					(start 133.539738 -262.746236)
					(mid 132.909818 -262.746236)
					(end 133.539738 -262.746236)
				)
			)
		)
	)
	(zone
		(layers "B.Cu" "In6.Cu" "In11.Cu" "In13.Cu" "In15.Cu")
		(hatch none 0.5)
		(connect_pads
			(clearance 0)
		)
		(min_thickness 0.25)
		(keepout
			(tracks not_allowed)
			(vias allowed)
			(pads allowed)
			(copperpour not_allowed)
			(footprints allowed)
		)
		(placement
			(enabled no)
			(sheetname "")
		)
		(fill yes
			(thermal_gap 0.5)
			(thermal_bridge_width 0.5)
			(island_removal_mode 0)
		)
		(polygon
			(pts
				(arc
					(start 132.76961 -234.764326)
					(mid 132.13969 -234.764326)
					(end 132.76961 -234.764326)
				)
			)
		)
	)
	(zone
		(layers "B.Cu" "In6.Cu" "In11.Cu" "In13.Cu" "In15.Cu")
		(hatch none 0.5)
		(connect_pads
			(clearance 0)
		)
		(min_thickness 0.25)
		(keepout
			(tracks not_allowed)
			(vias allowed)
			(pads allowed)
			(copperpour not_allowed)
			(footprints allowed)
		)
		(placement
			(enabled no)
			(sheetname "")
		)
		(fill yes
			(thermal_gap 0.5)
			(thermal_bridge_width 0.5)
			(island_removal_mode 0)
		)
		(polygon
			(pts
				(arc
					(start 91.716098 -292.716204)
					(mid 91.086178 -292.716204)
					(end 91.716098 -292.716204)
				)
			)
		)
	)
	(zone
		(layers "B.Cu" "In6.Cu" "In11.Cu" "In13.Cu" "In15.Cu")
		(hatch none 0.5)
		(connect_pads
			(clearance 0)
		)
		(min_thickness 0.25)
		(keepout
			(tracks not_allowed)
			(vias allowed)
			(pads allowed)
			(copperpour not_allowed)
			(footprints allowed)
		)
		(placement
			(enabled no)
			(sheetname "")
		)
		(fill yes
			(thermal_gap 0.5)
			(thermal_bridge_width 0.5)
			(island_removal_mode 0)
		)
		(polygon
			(pts
				(arc
					(start 357.686102 -227.474272)
					(mid 357.056182 -227.474272)
					(end 357.686102 -227.474272)
				)
			)
		)
	)
	(zone
		(layers "B.Cu" "In6.Cu" "In11.Cu" "In13.Cu" "In15.Cu")
		(hatch none 0.5)
		(connect_pads
			(clearance 0)
		)
		(min_thickness 0.25)
		(keepout
			(tracks not_allowed)
			(vias allowed)
			(pads allowed)
			(copperpour not_allowed)
			(footprints allowed)
		)
		(placement
			(enabled no)
			(sheetname "")
		)
		(fill yes
			(thermal_gap 0.5)
			(thermal_bridge_width 0.5)
			(island_removal_mode 0)
		)
		(polygon
			(pts
				(arc
					(start 379.769878 -231.524048)
					(mid 379.139958 -231.524048)
					(end 379.769878 -231.524048)
				)
			)
		)
	)
	(zone
		(layers "B.Cu" "In6.Cu" "In11.Cu" "In13.Cu" "In15.Cu")
		(hatch none 0.5)
		(connect_pads
			(clearance 0)
		)
		(min_thickness 0.25)
		(keepout
			(tracks not_allowed)
			(vias allowed)
			(pads allowed)
			(copperpour not_allowed)
			(footprints allowed)
		)
		(placement
			(enabled no)
			(sheetname "")
		)
		(fill yes
			(thermal_gap 0.5)
			(thermal_bridge_width 0.5)
			(island_removal_mode 0)
		)
		(polygon
			(pts
				(arc
					(start 280.969974 -295.935146)
					(mid 280.301954 -295.935146)
					(end 280.969974 -295.935146)
				)
			)
		)
	)
	(zone
		(layers "B.Cu" "In6.Cu" "In11.Cu" "In13.Cu" "In15.Cu")
		(hatch none 0.5)
		(connect_pads
			(clearance 0)
		)
		(min_thickness 0.25)
		(keepout
			(tracks not_allowed)
			(vias allowed)
			(pads allowed)
			(copperpour not_allowed)
			(footprints allowed)
		)
		(placement
			(enabled no)
			(sheetname "")
		)
		(fill yes
			(thermal_gap 0.5)
			(thermal_bridge_width 0.5)
			(island_removal_mode 0)
		)
		(polygon
			(pts
				(arc
					(start 33.029906 -213.485222)
					(mid 32.361886 -213.485222)
					(end 33.029906 -213.485222)
				)
			)
		)
	)
	(zone
		(layers "B.Cu" "In6.Cu" "In11.Cu" "In13.Cu" "In15.Cu")
		(hatch none 0.5)
		(connect_pads
			(clearance 0)
		)
		(min_thickness 0.25)
		(keepout
			(tracks not_allowed)
			(vias allowed)
			(pads allowed)
			(copperpour not_allowed)
			(footprints allowed)
		)
		(placement
			(enabled no)
			(sheetname "")
		)
		(fill yes
			(thermal_gap 0.5)
			(thermal_bridge_width 0.5)
			(island_removal_mode 0)
		)
		(polygon
			(pts
				(arc
					(start 354.39604 -226.664266)
					(mid 353.76612 -226.664266)
					(end 354.39604 -226.664266)
				)
			)
		)
	)
	(zone
		(layers "B.Cu" "In6.Cu" "In11.Cu" "In13.Cu" "In15.Cu")
		(hatch none 0.5)
		(connect_pads
			(clearance 0)
		)
		(min_thickness 0.25)
		(keepout
			(tracks not_allowed)
			(vias allowed)
			(pads allowed)
			(copperpour not_allowed)
			(footprints allowed)
		)
		(placement
			(enabled no)
			(sheetname "")
		)
		(fill yes
			(thermal_gap 0.5)
			(thermal_bridge_width 0.5)
			(island_removal_mode 0)
		)
		(polygon
			(pts
				(arc
					(start 357.403654 -377.41733)
					(mid 356.735634 -377.41733)
					(end 357.403654 -377.41733)
				)
			)
		)
	)
	(zone
		(layers "B.Cu" "In6.Cu" "In11.Cu" "In13.Cu" "In15.Cu")
		(hatch none 0.5)
		(connect_pads
			(clearance 0)
		)
		(min_thickness 0.25)
		(keepout
			(tracks not_allowed)
			(vias allowed)
			(pads allowed)
			(copperpour not_allowed)
			(footprints allowed)
		)
		(placement
			(enabled no)
			(sheetname "")
		)
		(fill yes
			(thermal_gap 0.5)
			(thermal_bridge_width 0.5)
			(island_removal_mode 0)
		)
		(polygon
			(pts
				(arc
					(start 191.494156 -269.58544)
					(mid 190.826136 -269.58544)
					(end 191.494156 -269.58544)
				)
			)
		)
	)
	(zone
		(layers "B.Cu" "In6.Cu" "In11.Cu" "In13.Cu" "In15.Cu")
		(hatch none 0.5)
		(connect_pads
			(clearance 0)
		)
		(min_thickness 0.25)
		(keepout
			(tracks not_allowed)
			(vias allowed)
			(pads allowed)
			(copperpour not_allowed)
			(footprints allowed)
		)
		(placement
			(enabled no)
			(sheetname "")
		)
		(fill yes
			(thermal_gap 0.5)
			(thermal_bridge_width 0.5)
			(island_removal_mode 0)
		)
		(polygon
			(pts
				(arc
					(start 104.876092 -291.096192)
					(mid 104.246172 -291.096192)
					(end 104.876092 -291.096192)
				)
			)
		)
	)
	(zone
		(layers "B.Cu" "In6.Cu" "In11.Cu" "In13.Cu" "In15.Cu")
		(hatch none 0.5)
		(connect_pads
			(clearance 0)
		)
		(min_thickness 0.25)
		(keepout
			(tracks not_allowed)
			(vias allowed)
			(pads allowed)
			(copperpour not_allowed)
			(footprints allowed)
		)
		(placement
			(enabled no)
			(sheetname "")
		)
		(fill yes
			(thermal_gap 0.5)
			(thermal_bridge_width 0.5)
			(island_removal_mode 0)
		)
		(polygon
			(pts
				(arc
					(start 340.295992 -255.824228)
					(mid 339.666072 -255.824228)
					(end 340.295992 -255.824228)
				)
			)
		)
	)
	(zone
		(layers "B.Cu" "In6.Cu" "In11.Cu" "In13.Cu" "In15.Cu")
		(hatch none 0.5)
		(connect_pads
			(clearance 0)
		)
		(min_thickness 0.25)
		(keepout
			(tracks not_allowed)
			(vias allowed)
			(pads allowed)
			(copperpour not_allowed)
			(footprints allowed)
		)
		(placement
			(enabled no)
			(sheetname "")
		)
		(fill yes
			(thermal_gap 0.5)
			(thermal_bridge_width 0.5)
			(island_removal_mode 0)
		)
		(polygon
			(pts
				(arc
					(start 363.619796 -290.285932)
					(mid 362.989876 -290.285932)
					(end 363.619796 -290.285932)
				)
			)
		)
	)
	(zone
		(layers "B.Cu" "In6.Cu" "In11.Cu" "In13.Cu" "In15.Cu")
		(hatch none 0.5)
		(connect_pads
			(clearance 0)
		)
		(min_thickness 0.25)
		(keepout
			(tracks not_allowed)
			(vias allowed)
			(pads allowed)
			(copperpour not_allowed)
			(footprints allowed)
		)
		(placement
			(enabled no)
			(sheetname "")
		)
		(fill yes
			(thermal_gap 0.5)
			(thermal_bridge_width 0.5)
			(island_removal_mode 0)
		)
		(polygon
			(pts
				(arc
					(start 122.806206 -386.003292)
					(mid 122.176286 -386.003292)
					(end 122.806206 -386.003292)
				)
			)
		)
	)
	(zone
		(layers "B.Cu" "In6.Cu" "In11.Cu" "In13.Cu" "In15.Cu")
		(hatch none 0.5)
		(connect_pads
			(clearance 0)
		)
		(min_thickness 0.25)
		(keepout
			(tracks not_allowed)
			(vias allowed)
			(pads allowed)
			(copperpour not_allowed)
			(footprints allowed)
		)
		(placement
			(enabled no)
			(sheetname "")
		)
		(fill yes
			(thermal_gap 0.5)
			(thermal_bridge_width 0.5)
			(island_removal_mode 0)
		)
		(polygon
			(pts
				(arc
					(start 280.969974 -204.134974)
					(mid 280.301954 -204.134974)
					(end 280.969974 -204.134974)
				)
			)
		)
	)
	(zone
		(layers "B.Cu" "In6.Cu" "In11.Cu" "In13.Cu" "In15.Cu")
		(hatch none 0.5)
		(connect_pads
			(clearance 0)
		)
		(min_thickness 0.25)
		(keepout
			(tracks not_allowed)
			(vias allowed)
			(pads allowed)
			(copperpour not_allowed)
			(footprints allowed)
		)
		(placement
			(enabled no)
			(sheetname "")
		)
		(fill yes
			(thermal_gap 0.5)
			(thermal_bridge_width 0.5)
			(island_removal_mode 0)
		)
		(polygon
			(pts
				(arc
					(start 44.664376 -4.963414)
					(mid 43.996356 -4.963414)
					(end 44.664376 -4.963414)
				)
			)
		)
	)
	(zone
		(layers "B.Cu" "In6.Cu" "In11.Cu" "In13.Cu" "In15.Cu")
		(hatch none 0.5)
		(connect_pads
			(clearance 0)
		)
		(min_thickness 0.25)
		(keepout
			(tracks not_allowed)
			(vias allowed)
			(pads allowed)
			(copperpour not_allowed)
			(footprints allowed)
		)
		(placement
			(enabled no)
			(sheetname "")
		)
		(fill yes
			(thermal_gap 0.5)
			(thermal_bridge_width 0.5)
			(island_removal_mode 0)
		)
		(polygon
			(pts
				(arc
					(start 33.029906 -198.185278)
					(mid 32.361886 -198.185278)
					(end 33.029906 -198.185278)
				)
			)
		)
	)
	(zone
		(layers "B.Cu" "In6.Cu" "In11.Cu" "In13.Cu" "In15.Cu")
		(hatch none 0.5)
		(connect_pads
			(clearance 0)
		)
		(min_thickness 0.25)
		(keepout
			(tracks not_allowed)
			(vias allowed)
			(pads allowed)
			(copperpour not_allowed)
			(footprints allowed)
		)
		(placement
			(enabled no)
			(sheetname "")
		)
		(fill yes
			(thermal_gap 0.5)
			(thermal_bridge_width 0.5)
			(island_removal_mode 0)
		)
		(polygon
			(pts
				(arc
					(start 285.070042 -262.785098)
					(mid 284.402022 -262.785098)
					(end 285.070042 -262.785098)
				)
			)
		)
	)
	(zone
		(layers "B.Cu" "In6.Cu" "In11.Cu" "In13.Cu" "In15.Cu")
		(hatch none 0.5)
		(connect_pads
			(clearance 0)
		)
		(min_thickness 0.25)
		(keepout
			(tracks not_allowed)
			(vias allowed)
			(pads allowed)
			(copperpour not_allowed)
			(footprints allowed)
		)
		(placement
			(enabled no)
			(sheetname "")
		)
		(fill yes
			(thermal_gap 0.5)
			(thermal_bridge_width 0.5)
			(island_removal_mode 0)
		)
		(polygon
			(pts
				(arc
					(start 383.206244 -393.69238)
					(mid 382.576324 -393.69238)
					(end 383.206244 -393.69238)
				)
			)
		)
	)
	(zone
		(layers "B.Cu" "In6.Cu" "In11.Cu" "In13.Cu" "In15.Cu")
		(hatch none 0.5)
		(connect_pads
			(clearance 0)
		)
		(min_thickness 0.25)
		(keepout
			(tracks not_allowed)
			(vias allowed)
			(pads allowed)
			(copperpour not_allowed)
			(footprints allowed)
		)
		(placement
			(enabled no)
			(sheetname "")
		)
		(fill yes
			(thermal_gap 0.5)
			(thermal_bridge_width 0.5)
			(island_removal_mode 0)
		)
		(polygon
			(pts
				(arc
					(start 74.29246 -376.83186)
					(mid 73.62444 -376.83186)
					(end 74.29246 -376.83186)
				)
			)
		)
	)
	(zone
		(layers "B.Cu" "In6.Cu" "In11.Cu" "In13.Cu" "In15.Cu")
		(hatch none 0.5)
		(connect_pads
			(clearance 0)
		)
		(min_thickness 0.25)
		(keepout
			(tracks not_allowed)
			(vias allowed)
			(pads allowed)
			(copperpour not_allowed)
			(footprints allowed)
		)
		(placement
			(enabled no)
			(sheetname "")
		)
		(fill yes
			(thermal_gap 0.5)
			(thermal_bridge_width 0.5)
			(island_removal_mode 0)
		)
		(polygon
			(pts
				(arc
					(start 133.539738 -282.18638)
					(mid 132.909818 -282.18638)
					(end 133.539738 -282.18638)
				)
			)
		)
	)
	(zone
		(layers "B.Cu" "In6.Cu" "In11.Cu" "In13.Cu" "In15.Cu")
		(hatch none 0.5)
		(connect_pads
			(clearance 0)
		)
		(min_thickness 0.25)
		(keepout
			(tracks not_allowed)
			(vias allowed)
			(pads allowed)
			(copperpour not_allowed)
			(footprints allowed)
		)
		(placement
			(enabled no)
			(sheetname "")
		)
		(fill yes
			(thermal_gap 0.5)
			(thermal_bridge_width 0.5)
			(island_removal_mode 0)
		)
		(polygon
			(pts
				(arc
					(start 357.986076 -287.045908)
					(mid 357.356156 -287.045908)
					(end 357.986076 -287.045908)
				)
			)
		)
	)
	(zone
		(layers "B.Cu" "In6.Cu" "In11.Cu" "In13.Cu" "In15.Cu")
		(hatch none 0.5)
		(connect_pads
			(clearance 0)
		)
		(min_thickness 0.25)
		(keepout
			(tracks not_allowed)
			(vias allowed)
			(pads allowed)
			(copperpour not_allowed)
			(footprints allowed)
		)
		(placement
			(enabled no)
			(sheetname "")
		)
		(fill yes
			(thermal_gap 0.5)
			(thermal_bridge_width 0.5)
			(island_removal_mode 0)
		)
		(polygon
			(pts
				(arc
					(start 92.655898 -279.756362)
					(mid 92.025978 -279.756362)
					(end 92.655898 -279.756362)
				)
			)
		)
	)
	(zone
		(layers "B.Cu" "In6.Cu" "In11.Cu" "In13.Cu" "In15.Cu")
		(hatch none 0.5)
		(connect_pads
			(clearance 0)
		)
		(min_thickness 0.25)
		(keepout
			(tracks not_allowed)
			(vias allowed)
			(pads allowed)
			(copperpour not_allowed)
			(footprints allowed)
		)
		(placement
			(enabled no)
			(sheetname "")
		)
		(fill yes
			(thermal_gap 0.5)
			(thermal_bridge_width 0.5)
			(island_removal_mode 0)
		)
		(polygon
			(pts
				(arc
					(start 187.394088 -265.335258)
					(mid 186.726068 -265.335258)
					(end 187.394088 -265.335258)
				)
			)
		)
	)
	(zone
		(layers "B.Cu" "In6.Cu" "In11.Cu" "In13.Cu" "In15.Cu")
		(hatch none 0.5)
		(connect_pads
			(clearance 0)
		)
		(min_thickness 0.25)
		(keepout
			(tracks not_allowed)
			(vias allowed)
			(pads allowed)
			(copperpour not_allowed)
			(footprints allowed)
		)
		(placement
			(enabled no)
			(sheetname "")
		)
		(fill yes
			(thermal_gap 0.5)
			(thermal_bridge_width 0.5)
			(island_removal_mode 0)
		)
		(polygon
			(pts
				(arc
					(start 341.06612 -274.086066)
					(mid 340.4362 -274.086066)
					(end 341.06612 -274.086066)
				)
			)
		)
	)
	(zone
		(layers "B.Cu" "In6.Cu" "In11.Cu" "In13.Cu" "In15.Cu")
		(hatch none 0.5)
		(connect_pads
			(clearance 0)
		)
		(min_thickness 0.25)
		(keepout
			(tracks not_allowed)
			(vias allowed)
			(pads allowed)
			(copperpour not_allowed)
			(footprints allowed)
		)
		(placement
			(enabled no)
			(sheetname "")
		)
		(fill yes
			(thermal_gap 0.5)
			(thermal_bridge_width 0.5)
			(island_removal_mode 0)
		)
		(polygon
			(pts
				(arc
					(start 92.826078 -243.674392)
					(mid 92.196158 -243.674392)
					(end 92.826078 -243.674392)
				)
			)
		)
	)
	(zone
		(layers "B.Cu" "In6.Cu" "In11.Cu" "In13.Cu" "In15.Cu")
		(hatch none 0.5)
		(connect_pads
			(clearance 0)
		)
		(min_thickness 0.25)
		(keepout
			(tracks not_allowed)
			(vias allowed)
			(pads allowed)
			(copperpour not_allowed)
			(footprints allowed)
		)
		(placement
			(enabled no)
			(sheetname "")
		)
		(fill yes
			(thermal_gap 0.5)
			(thermal_bridge_width 0.5)
			(island_removal_mode 0)
		)
		(polygon
			(pts
				(arc
					(start 128.344676 -404.46452)
					(mid 127.676656 -404.46452)
					(end 128.344676 -404.46452)
				)
			)
		)
	)
	(zone
		(layers "B.Cu" "In6.Cu" "In11.Cu" "In13.Cu" "In15.Cu")
		(hatch none 0.5)
		(connect_pads
			(clearance 0)
		)
		(min_thickness 0.25)
		(keepout
			(tracks not_allowed)
			(vias allowed)
			(pads allowed)
			(copperpour not_allowed)
			(footprints allowed)
		)
		(placement
			(enabled no)
			(sheetname "")
		)
		(fill yes
			(thermal_gap 0.5)
			(thermal_bridge_width 0.5)
			(island_removal_mode 0)
		)
		(polygon
			(pts
				(arc
					(start 133.239764 -246.914416)
					(mid 132.609844 -246.914416)
					(end 133.239764 -246.914416)
				)
			)
		)
	)
	(zone
		(layers "B.Cu" "In6.Cu" "In11.Cu" "In13.Cu" "In15.Cu")
		(hatch none 0.5)
		(connect_pads
			(clearance 0)
		)
		(min_thickness 0.25)
		(keepout
			(tracks not_allowed)
			(vias allowed)
			(pads allowed)
			(copperpour not_allowed)
			(footprints allowed)
		)
		(placement
			(enabled no)
			(sheetname "")
		)
		(fill yes
			(thermal_gap 0.5)
			(thermal_bridge_width 0.5)
			(island_removal_mode 0)
		)
		(polygon
			(pts
				(arc
					(start 280.969974 -227.935028)
					(mid 280.301954 -227.935028)
					(end 280.969974 -227.935028)
				)
			)
		)
	)
	(zone
		(layers "B.Cu" "In6.Cu" "In11.Cu" "In13.Cu" "In15.Cu")
		(hatch none 0.5)
		(connect_pads
			(clearance 0)
		)
		(min_thickness 0.25)
		(keepout
			(tracks not_allowed)
			(vias allowed)
			(pads allowed)
			(copperpour not_allowed)
			(footprints allowed)
		)
		(placement
			(enabled no)
			(sheetname "")
		)
		(fill yes
			(thermal_gap 0.5)
			(thermal_bridge_width 0.5)
			(island_removal_mode 0)
		)
		(polygon
			(pts
				(arc
					(start 379.599698 -285.42615)
					(mid 378.969778 -285.42615)
					(end 379.599698 -285.42615)
				)
			)
		)
	)
	(zone
		(layers "B.Cu" "In6.Cu" "In11.Cu" "In13.Cu" "In15.Cu")
		(hatch none 0.5)
		(connect_pads
			(clearance 0)
		)
		(min_thickness 0.25)
		(keepout
			(tracks not_allowed)
			(vias allowed)
			(pads allowed)
			(copperpour not_allowed)
			(footprints allowed)
		)
		(placement
			(enabled no)
			(sheetname "")
		)
		(fill yes
			(thermal_gap 0.5)
			(thermal_bridge_width 0.5)
			(island_removal_mode 0)
		)
		(polygon
			(pts
				(arc
					(start 435.334156 -306.985162)
					(mid 434.666136 -306.985162)
					(end 435.334156 -306.985162)
				)
			)
		)
	)
	(zone
		(layers "B.Cu" "In6.Cu" "In11.Cu" "In13.Cu" "In15.Cu")
		(hatch none 0.5)
		(connect_pads
			(clearance 0)
		)
		(min_thickness 0.25)
		(keepout
			(tracks not_allowed)
			(vias allowed)
			(pads allowed)
			(copperpour not_allowed)
			(footprints allowed)
		)
		(placement
			(enabled no)
			(sheetname "")
		)
		(fill yes
			(thermal_gap 0.5)
			(thermal_bridge_width 0.5)
			(island_removal_mode 0)
		)
		(polygon
			(pts
				(arc
					(start 345.936062 -226.664266)
					(mid 345.306142 -226.664266)
					(end 345.936062 -226.664266)
				)
			)
		)
	)
	(zone
		(layers "B.Cu" "In6.Cu" "In11.Cu" "In13.Cu" "In15.Cu")
		(hatch none 0.5)
		(connect_pads
			(clearance 0)
		)
		(min_thickness 0.25)
		(keepout
			(tracks not_allowed)
			(vias allowed)
			(pads allowed)
			(copperpour not_allowed)
			(footprints allowed)
		)
		(placement
			(enabled no)
			(sheetname "")
		)
		(fill yes
			(thermal_gap 0.5)
			(thermal_bridge_width 0.5)
			(island_removal_mode 0)
		)
		(polygon
			(pts
				(arc
					(start 108.80598 -235.574332)
					(mid 108.17606 -235.574332)
					(end 108.80598 -235.574332)
				)
			)
		)
	)
	(zone
		(layers "B.Cu" "In6.Cu" "In11.Cu" "In13.Cu" "In15.Cu")
		(hatch none 0.5)
		(connect_pads
			(clearance 0)
		)
		(min_thickness 0.25)
		(keepout
			(tracks not_allowed)
			(vias allowed)
			(pads allowed)
			(copperpour not_allowed)
			(footprints allowed)
		)
		(placement
			(enabled no)
			(sheetname "")
		)
		(fill yes
			(thermal_gap 0.5)
			(thermal_bridge_width 0.5)
			(island_removal_mode 0)
		)
		(polygon
			(pts
				(arc
					(start 91.245944 -278.946356)
					(mid 90.616024 -278.946356)
					(end 91.245944 -278.946356)
				)
			)
		)
	)
	(zone
		(layers "B.Cu" "In6.Cu" "In11.Cu" "In13.Cu" "In15.Cu")
		(hatch none 0.5)
		(connect_pads
			(clearance 0)
		)
		(min_thickness 0.25)
		(keepout
			(tracks not_allowed)
			(vias allowed)
			(pads allowed)
			(copperpour not_allowed)
			(footprints allowed)
		)
		(placement
			(enabled no)
			(sheetname "")
		)
		(fill yes
			(thermal_gap 0.5)
			(thermal_bridge_width 0.5)
			(island_removal_mode 0)
		)
		(polygon
			(pts
				(arc
					(start 435.334156 -213.484968)
					(mid 434.666136 -213.484968)
					(end 435.334156 -213.484968)
				)
			)
		)
	)
	(zone
		(layers "B.Cu" "In6.Cu" "In11.Cu" "In13.Cu" "In15.Cu")
		(hatch none 0.5)
		(connect_pads
			(clearance 0)
		)
		(min_thickness 0.25)
		(keepout
			(tracks not_allowed)
			(vias allowed)
			(pads allowed)
			(copperpour not_allowed)
			(footprints allowed)
		)
		(placement
			(enabled no)
			(sheetname "")
		)
		(fill yes
			(thermal_gap 0.5)
			(thermal_bridge_width 0.5)
			(island_removal_mode 0)
		)
		(polygon
			(pts
				(arc
					(start 37.129974 -247.485408)
					(mid 36.461954 -247.485408)
					(end 37.129974 -247.485408)
				)
			)
		)
	)
	(zone
		(layers "B.Cu" "In6.Cu" "In11.Cu" "In13.Cu" "In15.Cu")
		(hatch none 0.5)
		(connect_pads
			(clearance 0)
		)
		(min_thickness 0.25)
		(keepout
			(tracks not_allowed)
			(vias allowed)
			(pads allowed)
			(copperpour not_allowed)
			(footprints allowed)
		)
		(placement
			(enabled no)
			(sheetname "")
		)
		(fill yes
			(thermal_gap 0.5)
			(thermal_bridge_width 0.5)
			(island_removal_mode 0)
		)
		(polygon
			(pts
				(arc
					(start 304.106072 -397.156432)
					(mid 303.476152 -397.156432)
					(end 304.106072 -397.156432)
				)
			)
		)
	)
	(zone
		(layers "B.Cu" "In6.Cu" "In11.Cu" "In13.Cu" "In15.Cu")
		(hatch none 0.5)
		(connect_pads
			(clearance 0)
		)
		(min_thickness 0.25)
		(keepout
			(tracks not_allowed)
			(vias allowed)
			(pads allowed)
			(copperpour not_allowed)
			(footprints allowed)
		)
		(placement
			(enabled no)
			(sheetname "")
		)
		(fill yes
			(thermal_gap 0.5)
			(thermal_bridge_width 0.5)
			(island_removal_mode 0)
		)
		(polygon
			(pts
				(arc
					(start 133.539738 -278.946356)
					(mid 132.909818 -278.946356)
					(end 133.539738 -278.946356)
				)
			)
		)
	)
	(zone
		(layers "B.Cu" "In6.Cu" "In11.Cu" "In13.Cu" "In15.Cu")
		(hatch none 0.5)
		(connect_pads
			(clearance 0)
		)
		(min_thickness 0.25)
		(keepout
			(tracks not_allowed)
			(vias allowed)
			(pads allowed)
			(copperpour not_allowed)
			(footprints allowed)
		)
		(placement
			(enabled no)
			(sheetname "")
		)
		(fill yes
			(thermal_gap 0.5)
			(thermal_bridge_width 0.5)
			(island_removal_mode 0)
		)
		(polygon
			(pts
				(arc
					(start 103.636064 -231.524302)
					(mid 103.006144 -231.524302)
					(end 103.636064 -231.524302)
				)
			)
		)
	)
	(zone
		(layers "B.Cu" "In6.Cu" "In11.Cu" "In13.Cu" "In15.Cu")
		(hatch none 0.5)
		(connect_pads
			(clearance 0)
		)
		(min_thickness 0.25)
		(keepout
			(tracks not_allowed)
			(vias allowed)
			(pads allowed)
			(copperpour not_allowed)
			(footprints allowed)
		)
		(placement
			(enabled no)
			(sheetname "")
		)
		(fill yes
			(thermal_gap 0.5)
			(thermal_bridge_width 0.5)
			(island_removal_mode 0)
		)
		(polygon
			(pts
				(arc
					(start 117.729762 -228.284532)
					(mid 117.099842 -228.284532)
					(end 117.729762 -228.284532)
				)
			)
		)
	)
	(zone
		(layers "B.Cu" "In6.Cu" "In11.Cu" "In13.Cu" "In15.Cu")
		(hatch none 0.5)
		(connect_pads
			(clearance 0)
		)
		(min_thickness 0.25)
		(keepout
			(tracks not_allowed)
			(vias allowed)
			(pads allowed)
			(copperpour not_allowed)
			(footprints allowed)
		)
		(placement
			(enabled no)
			(sheetname "")
		)
		(fill yes
			(thermal_gap 0.5)
			(thermal_bridge_width 0.5)
			(island_removal_mode 0)
		)
		(polygon
			(pts
				(arc
					(start 379.769878 -255.824228)
					(mid 379.139958 -255.824228)
					(end 379.769878 -255.824228)
				)
			)
		)
	)
	(zone
		(layers "B.Cu" "In6.Cu" "In11.Cu" "In13.Cu" "In15.Cu")
		(hatch none 0.5)
		(connect_pads
			(clearance 0)
		)
		(min_thickness 0.25)
		(keepout
			(tracks not_allowed)
			(vias allowed)
			(pads allowed)
			(copperpour not_allowed)
			(footprints allowed)
		)
		(placement
			(enabled no)
			(sheetname "")
		)
		(fill yes
			(thermal_gap 0.5)
			(thermal_bridge_width 0.5)
			(island_removal_mode 0)
		)
		(polygon
			(pts
				(arc
					(start 285.070042 -203.28509)
					(mid 284.402022 -203.28509)
					(end 285.070042 -203.28509)
				)
			)
		)
	)
	(zone
		(layers "B.Cu" "In6.Cu" "In11.Cu" "In13.Cu" "In15.Cu")
		(hatch none 0.5)
		(connect_pads
			(clearance 0)
		)
		(min_thickness 0.25)
		(keepout
			(tracks not_allowed)
			(vias allowed)
			(pads allowed)
			(copperpour not_allowed)
			(footprints allowed)
		)
		(placement
			(enabled no)
			(sheetname "")
		)
		(fill yes
			(thermal_gap 0.5)
			(thermal_bridge_width 0.5)
			(island_removal_mode 0)
		)
		(polygon
			(pts
				(arc
					(start 414.977072 -412.84652)
					(mid 414.309052 -412.84652)
					(end 414.977072 -412.84652)
				)
			)
		)
	)
	(zone
		(layers "B.Cu" "In6.Cu" "In11.Cu" "In13.Cu" "In15.Cu")
		(hatch none 0.5)
		(connect_pads
			(clearance 0)
		)
		(min_thickness 0.25)
		(keepout
			(tracks not_allowed)
			(vias allowed)
			(pads allowed)
			(copperpour not_allowed)
			(footprints allowed)
		)
		(placement
			(enabled no)
			(sheetname "")
		)
		(fill yes
			(thermal_gap 0.5)
			(thermal_bridge_width 0.5)
			(island_removal_mode 0)
		)
		(polygon
			(pts
				(arc
					(start 347.192854 -377.41733)
					(mid 346.524834 -377.41733)
					(end 347.192854 -377.41733)
				)
			)
		)
	)
	(zone
		(layers "B.Cu" "In6.Cu" "In11.Cu" "In13.Cu" "In15.Cu")
		(hatch none 0.5)
		(connect_pads
			(clearance 0)
		)
		(min_thickness 0.25)
		(keepout
			(tracks not_allowed)
			(vias allowed)
			(pads allowed)
			(copperpour not_allowed)
			(footprints allowed)
		)
		(placement
			(enabled no)
			(sheetname "")
		)
		(fill yes
			(thermal_gap 0.5)
			(thermal_bridge_width 0.5)
			(island_removal_mode 0)
		)
		(polygon
			(pts
				(arc
					(start 381.479806 -267.606018)
					(mid 380.849886 -267.606018)
					(end 381.479806 -267.606018)
				)
			)
		)
	)
	(zone
		(layers "B.Cu" "In6.Cu" "In11.Cu" "In13.Cu" "In15.Cu")
		(hatch none 0.5)
		(connect_pads
			(clearance 0)
		)
		(min_thickness 0.25)
		(keepout
			(tracks not_allowed)
			(vias allowed)
			(pads allowed)
			(copperpour not_allowed)
			(footprints allowed)
		)
		(placement
			(enabled no)
			(sheetname "")
		)
		(fill yes
			(thermal_gap 0.5)
			(thermal_bridge_width 0.5)
			(island_removal_mode 0)
		)
		(polygon
			(pts
				(arc
					(start 362.679742 -288.66592)
					(mid 362.049822 -288.66592)
					(end 362.679742 -288.66592)
				)
			)
		)
	)
	(zone
		(layers "B.Cu" "In6.Cu" "In11.Cu" "In13.Cu" "In15.Cu")
		(hatch none 0.5)
		(connect_pads
			(clearance 0)
		)
		(min_thickness 0.25)
		(keepout
			(tracks not_allowed)
			(vias allowed)
			(pads allowed)
			(copperpour not_allowed)
			(footprints allowed)
		)
		(placement
			(enabled no)
			(sheetname "")
		)
		(fill yes
			(thermal_gap 0.5)
			(thermal_bridge_width 0.5)
			(island_removal_mode 0)
		)
		(polygon
			(pts
				(arc
					(start 393.534392 -412.84652)
					(mid 392.866372 -412.84652)
					(end 393.534392 -412.84652)
				)
			)
		)
	)
	(zone
		(layers "B.Cu" "In6.Cu" "In11.Cu" "In13.Cu" "In15.Cu")
		(hatch none 0.5)
		(connect_pads
			(clearance 0)
		)
		(min_thickness 0.25)
		(keepout
			(tracks not_allowed)
			(vias allowed)
			(pads allowed)
			(copperpour not_allowed)
			(footprints allowed)
		)
		(placement
			(enabled no)
			(sheetname "")
		)
		(fill yes
			(thermal_gap 0.5)
			(thermal_bridge_width 0.5)
			(island_removal_mode 0)
		)
		(polygon
			(pts
				(arc
					(start 380.069852 -291.095938)
					(mid 379.439932 -291.095938)
					(end 380.069852 -291.095938)
				)
			)
		)
	)
	(zone
		(layers "B.Cu" "In6.Cu" "In11.Cu" "In13.Cu" "In15.Cu")
		(hatch none 0.5)
		(connect_pads
			(clearance 0)
		)
		(min_thickness 0.25)
		(keepout
			(tracks not_allowed)
			(vias allowed)
			(pads allowed)
			(copperpour not_allowed)
			(footprints allowed)
		)
		(placement
			(enabled no)
			(sheetname "")
		)
		(fill yes
			(thermal_gap 0.5)
			(thermal_bridge_width 0.5)
			(island_removal_mode 0)
		)
		(polygon
			(pts
				(arc
					(start 367.549684 -231.524048)
					(mid 366.919764 -231.524048)
					(end 367.549684 -231.524048)
				)
			)
		)
	)
	(zone
		(layers "B.Cu" "In6.Cu" "In11.Cu" "In13.Cu" "In15.Cu")
		(hatch none 0.5)
		(connect_pads
			(clearance 0)
		)
		(min_thickness 0.25)
		(keepout
			(tracks not_allowed)
			(vias allowed)
			(pads allowed)
			(copperpour not_allowed)
			(footprints allowed)
		)
		(placement
			(enabled no)
			(sheetname "")
		)
		(fill yes
			(thermal_gap 0.5)
			(thermal_bridge_width 0.5)
			(island_removal_mode 0)
		)
		(polygon
			(pts
				(arc
					(start 285.070042 -223.6851)
					(mid 284.402022 -223.6851)
					(end 285.070042 -223.6851)
				)
			)
		)
	)
	(zone
		(layers "B.Cu" "In6.Cu" "In11.Cu" "In13.Cu" "In15.Cu")
		(hatch none 0.5)
		(connect_pads
			(clearance 0)
		)
		(min_thickness 0.25)
		(keepout
			(tracks not_allowed)
			(vias allowed)
			(pads allowed)
			(copperpour not_allowed)
			(footprints allowed)
		)
		(placement
			(enabled no)
			(sheetname "")
		)
		(fill yes
			(thermal_gap 0.5)
			(thermal_bridge_width 0.5)
			(island_removal_mode 0)
		)
		(polygon
			(pts
				(arc
					(start 92.826078 -232.334308)
					(mid 92.196158 -232.334308)
					(end 92.826078 -232.334308)
				)
			)
		)
	)
	(zone
		(layers "B.Cu" "In6.Cu" "In11.Cu" "In13.Cu" "In15.Cu")
		(hatch none 0.5)
		(connect_pads
			(clearance 0)
		)
		(min_thickness 0.25)
		(keepout
			(tracks not_allowed)
			(vias allowed)
			(pads allowed)
			(copperpour not_allowed)
			(footprints allowed)
		)
		(placement
			(enabled no)
			(sheetname "")
		)
		(fill yes
			(thermal_gap 0.5)
			(thermal_bridge_width 0.5)
			(island_removal_mode 0)
		)
		(polygon
			(pts
				(arc
					(start 340.766146 -246.914162)
					(mid 340.136226 -246.914162)
					(end 340.766146 -246.914162)
				)
			)
		)
	)
	(zone
		(layers "B.Cu" "In6.Cu" "In11.Cu" "In13.Cu" "In15.Cu")
		(hatch none 0.5)
		(connect_pads
			(clearance 0)
		)
		(min_thickness 0.25)
		(keepout
			(tracks not_allowed)
			(vias allowed)
			(pads allowed)
			(copperpour not_allowed)
			(footprints allowed)
		)
		(placement
			(enabled no)
			(sheetname "")
		)
		(fill yes
			(thermal_gap 0.5)
			(thermal_bridge_width 0.5)
			(island_removal_mode 0)
		)
		(polygon
			(pts
				(arc
					(start 133.239764 -227.474526)
					(mid 132.609844 -227.474526)
					(end 133.239764 -227.474526)
				)
			)
		)
	)
	(zone
		(layers "B.Cu" "In6.Cu" "In11.Cu" "In13.Cu" "In15.Cu")
		(hatch none 0.5)
		(connect_pads
			(clearance 0)
		)
		(min_thickness 0.25)
		(keepout
			(tracks not_allowed)
			(vias allowed)
			(pads allowed)
			(copperpour not_allowed)
			(footprints allowed)
		)
		(placement
			(enabled no)
			(sheetname "")
		)
		(fill yes
			(thermal_gap 0.5)
			(thermal_bridge_width 0.5)
			(island_removal_mode 0)
		)
		(polygon
			(pts
				(arc
					(start 37.129974 -300.185328)
					(mid 36.461954 -300.185328)
					(end 37.129974 -300.185328)
				)
			)
		)
	)
	(zone
		(layers "B.Cu" "In6.Cu" "In11.Cu" "In13.Cu" "In15.Cu")
		(hatch none 0.5)
		(connect_pads
			(clearance 0)
		)
		(min_thickness 0.25)
		(keepout
			(tracks not_allowed)
			(vias allowed)
			(pads allowed)
			(copperpour not_allowed)
			(footprints allowed)
		)
		(placement
			(enabled no)
			(sheetname "")
		)
		(fill yes
			(thermal_gap 0.5)
			(thermal_bridge_width 0.5)
			(island_removal_mode 0)
		)
		(polygon
			(pts
				(arc
					(start 187.394088 -313.78525)
					(mid 186.726068 -313.78525)
					(end 187.394088 -313.78525)
				)
			)
		)
	)
	(zone
		(layers "B.Cu" "In6.Cu" "In11.Cu" "In13.Cu" "In15.Cu")
		(hatch none 0.5)
		(connect_pads
			(clearance 0)
		)
		(min_thickness 0.25)
		(keepout
			(tracks not_allowed)
			(vias allowed)
			(pads allowed)
			(copperpour not_allowed)
			(footprints allowed)
		)
		(placement
			(enabled no)
			(sheetname "")
		)
		(fill yes
			(thermal_gap 0.5)
			(thermal_bridge_width 0.5)
			(island_removal_mode 0)
		)
		(polygon
			(pts
				(arc
					(start 187.394088 -280.635202)
					(mid 186.726068 -280.635202)
					(end 187.394088 -280.635202)
				)
			)
		)
	)
	(zone
		(layers "B.Cu" "In6.Cu" "In11.Cu" "In13.Cu" "In15.Cu")
		(hatch none 0.5)
		(connect_pads
			(clearance 0)
		)
		(min_thickness 0.25)
		(keepout
			(tracks not_allowed)
			(vias allowed)
			(pads allowed)
			(copperpour not_allowed)
			(footprints allowed)
		)
		(placement
			(enabled no)
			(sheetname "")
		)
		(fill yes
			(thermal_gap 0.5)
			(thermal_bridge_width 0.5)
			(island_removal_mode 0)
		)
		(polygon
			(pts
				(arc
					(start 150.134066 -388.774432)
					(mid 149.504146 -388.774432)
					(end 150.134066 -388.774432)
				)
			)
		)
	)
	(zone
		(layers "B.Cu" "In6.Cu" "In11.Cu" "In13.Cu" "In15.Cu")
		(hatch none 0.5)
		(connect_pads
			(clearance 0)
		)
		(min_thickness 0.25)
		(keepout
			(tracks not_allowed)
			(vias allowed)
			(pads allowed)
			(copperpour not_allowed)
			(footprints allowed)
		)
		(placement
			(enabled no)
			(sheetname "")
		)
		(fill yes
			(thermal_gap 0.5)
			(thermal_bridge_width 0.5)
			(island_removal_mode 0)
		)
		(polygon
			(pts
				(arc
					(start 90.94597 -238.814356)
					(mid 90.31605 -238.814356)
					(end 90.94597 -238.814356)
				)
			)
		)
	)
	(zone
		(layers "B.Cu" "In6.Cu" "In11.Cu" "In13.Cu" "In15.Cu")
		(hatch none 0.5)
		(connect_pads
			(clearance 0)
		)
		(min_thickness 0.25)
		(keepout
			(tracks not_allowed)
			(vias allowed)
			(pads allowed)
			(copperpour not_allowed)
			(footprints allowed)
		)
		(placement
			(enabled no)
			(sheetname "")
		)
		(fill yes
			(thermal_gap 0.5)
			(thermal_bridge_width 0.5)
			(island_removal_mode 0)
		)
		(polygon
			(pts
				(arc
					(start 106.755946 -287.856422)
					(mid 106.126026 -287.856422)
					(end 106.755946 -287.856422)
				)
			)
		)
	)
	(zone
		(layers "B.Cu" "In6.Cu" "In11.Cu" "In13.Cu" "In15.Cu")
		(hatch none 0.5)
		(connect_pads
			(clearance 0)
		)
		(min_thickness 0.25)
		(keepout
			(tracks not_allowed)
			(vias allowed)
			(pads allowed)
			(copperpour not_allowed)
			(footprints allowed)
		)
		(placement
			(enabled no)
			(sheetname "")
		)
		(fill yes
			(thermal_gap 0.5)
			(thermal_bridge_width 0.5)
			(island_removal_mode 0)
		)
		(polygon
			(pts
				(arc
					(start 417.333938 -397.849344)
					(mid 416.704018 -397.849344)
					(end 417.333938 -397.849344)
				)
			)
		)
	)
	(zone
		(layers "B.Cu" "In6.Cu" "In11.Cu" "In13.Cu" "In15.Cu")
		(hatch none 0.5)
		(connect_pads
			(clearance 0)
		)
		(min_thickness 0.25)
		(keepout
			(tracks not_allowed)
			(vias allowed)
			(pads allowed)
			(copperpour not_allowed)
			(footprints allowed)
		)
		(placement
			(enabled no)
			(sheetname "")
		)
		(fill yes
			(thermal_gap 0.5)
			(thermal_bridge_width 0.5)
			(island_removal_mode 0)
		)
		(polygon
			(pts
				(arc
					(start 380.006098 -394.385292)
					(mid 379.376178 -394.385292)
					(end 380.006098 -394.385292)
				)
			)
		)
	)
	(zone
		(layers "B.Cu" "In6.Cu" "In11.Cu" "In13.Cu" "In15.Cu")
		(hatch none 0.5)
		(connect_pads
			(clearance 0)
		)
		(min_thickness 0.25)
		(keepout
			(tracks not_allowed)
			(vias allowed)
			(pads allowed)
			(copperpour not_allowed)
			(footprints allowed)
		)
		(placement
			(enabled no)
			(sheetname "")
		)
		(fill yes
			(thermal_gap 0.5)
			(thermal_bridge_width 0.5)
			(island_removal_mode 0)
		)
		(polygon
			(pts
				(arc
					(start 92.655898 -276.516338)
					(mid 92.025978 -276.516338)
					(end 92.655898 -276.516338)
				)
			)
		)
	)
	(zone
		(layers "B.Cu" "In6.Cu" "In11.Cu" "In13.Cu" "In15.Cu")
		(hatch none 0.5)
		(connect_pads
			(clearance 0)
		)
		(min_thickness 0.25)
		(keepout
			(tracks not_allowed)
			(vias allowed)
			(pads allowed)
			(copperpour not_allowed)
			(footprints allowed)
		)
		(placement
			(enabled no)
			(sheetname "")
		)
		(fill yes
			(thermal_gap 0.5)
			(thermal_bridge_width 0.5)
			(island_removal_mode 0)
		)
		(polygon
			(pts
				(arc
					(start 305.706018 -397.849344)
					(mid 305.076098 -397.849344)
					(end 305.706018 -397.849344)
				)
			)
		)
	)
	(zone
		(layers "B.Cu" "In6.Cu" "In11.Cu" "In13.Cu" "In15.Cu")
		(hatch none 0.5)
		(connect_pads
			(clearance 0)
		)
		(min_thickness 0.25)
		(keepout
			(tracks not_allowed)
			(vias allowed)
			(pads allowed)
			(copperpour not_allowed)
			(footprints allowed)
		)
		(placement
			(enabled no)
			(sheetname "")
		)
		(fill yes
			(thermal_gap 0.5)
			(thermal_bridge_width 0.5)
			(island_removal_mode 0)
		)
		(polygon
			(pts
				(arc
					(start 280.969974 -297.635168)
					(mid 280.301954 -297.635168)
					(end 280.969974 -297.635168)
				)
			)
		)
	)
	(zone
		(layers "B.Cu" "In6.Cu" "In11.Cu" "In13.Cu" "In15.Cu")
		(hatch none 0.5)
		(connect_pads
			(clearance 0)
		)
		(min_thickness 0.25)
		(keepout
			(tracks not_allowed)
			(vias allowed)
			(pads allowed)
			(copperpour not_allowed)
			(footprints allowed)
		)
		(placement
			(enabled no)
			(sheetname "")
		)
		(fill yes
			(thermal_gap 0.5)
			(thermal_bridge_width 0.5)
			(island_removal_mode 0)
		)
		(polygon
			(pts
				(arc
					(start 280.969974 -207.535018)
					(mid 280.301954 -207.535018)
					(end 280.969974 -207.535018)
				)
			)
		)
	)
	(zone
		(layers "B.Cu" "In6.Cu" "In11.Cu" "In13.Cu" "In15.Cu")
		(hatch none 0.5)
		(connect_pads
			(clearance 0)
		)
		(min_thickness 0.25)
		(keepout
			(tracks not_allowed)
			(vias allowed)
			(pads allowed)
			(copperpour not_allowed)
			(footprints allowed)
		)
		(placement
			(enabled no)
			(sheetname "")
		)
		(fill yes
			(thermal_gap 0.5)
			(thermal_bridge_width 0.5)
			(island_removal_mode 0)
		)
		(polygon
			(pts
				(arc
					(start 92.826078 -250.15444)
					(mid 92.196158 -250.15444)
					(end 92.826078 -250.15444)
				)
			)
		)
	)
	(zone
		(layers "B.Cu" "In6.Cu" "In11.Cu" "In13.Cu" "In15.Cu")
		(hatch none 0.5)
		(connect_pads
			(clearance 0)
		)
		(min_thickness 0.25)
		(keepout
			(tracks not_allowed)
			(vias allowed)
			(pads allowed)
			(copperpour not_allowed)
			(footprints allowed)
		)
		(placement
			(enabled no)
			(sheetname "")
		)
		(fill yes
			(thermal_gap 0.5)
			(thermal_bridge_width 0.5)
			(island_removal_mode 0)
		)
		(polygon
			(pts
				(arc
					(start 187.394088 -268.735302)
					(mid 186.726068 -268.735302)
					(end 187.394088 -268.735302)
				)
			)
		)
	)
	(zone
		(layers "B.Cu" "In6.Cu" "In11.Cu" "In13.Cu" "In15.Cu")
		(hatch none 0.5)
		(connect_pads
			(clearance 0)
		)
		(min_thickness 0.25)
		(keepout
			(tracks not_allowed)
			(vias allowed)
			(pads allowed)
			(copperpour not_allowed)
			(footprints allowed)
		)
		(placement
			(enabled no)
			(sheetname "")
		)
		(fill yes
			(thermal_gap 0.5)
			(thermal_bridge_width 0.5)
			(island_removal_mode 0)
		)
		(polygon
			(pts
				(arc
					(start 285.070042 -250.884944)
					(mid 284.402022 -250.884944)
					(end 285.070042 -250.884944)
				)
			)
		)
	)
	(zone
		(layers "B.Cu" "In6.Cu" "In11.Cu" "In13.Cu" "In15.Cu")
		(hatch none 0.5)
		(connect_pads
			(clearance 0)
		)
		(min_thickness 0.25)
		(keepout
			(tracks not_allowed)
			(vias allowed)
			(pads allowed)
			(copperpour not_allowed)
			(footprints allowed)
		)
		(placement
			(enabled no)
			(sheetname "")
		)
		(fill yes
			(thermal_gap 0.5)
			(thermal_bridge_width 0.5)
			(island_removal_mode 0)
		)
		(polygon
			(pts
				(arc
					(start 439.434224 -289.135058)
					(mid 438.766204 -289.135058)
					(end 439.434224 -289.135058)
				)
			)
		)
	)
	(zone
		(layers "B.Cu" "In6.Cu" "In11.Cu" "In13.Cu" "In15.Cu")
		(hatch none 0.5)
		(connect_pads
			(clearance 0)
		)
		(min_thickness 0.25)
		(keepout
			(tracks not_allowed)
			(vias allowed)
			(pads allowed)
			(copperpour not_allowed)
			(footprints allowed)
		)
		(placement
			(enabled no)
			(sheetname "")
		)
		(fill yes
			(thermal_gap 0.5)
			(thermal_bridge_width 0.5)
			(island_removal_mode 0)
		)
		(polygon
			(pts
				(arc
					(start 99.236022 -289.47618)
					(mid 98.606102 -289.47618)
					(end 99.236022 -289.47618)
				)
			)
		)
	)
	(zone
		(layers "B.Cu" "In6.Cu" "In11.Cu" "In13.Cu" "In15.Cu")
		(hatch none 0.5)
		(connect_pads
			(clearance 0)
		)
		(min_thickness 0.25)
		(keepout
			(tracks not_allowed)
			(vias allowed)
			(pads allowed)
			(copperpour not_allowed)
			(footprints allowed)
		)
		(placement
			(enabled no)
			(sheetname "")
		)
		(fill yes
			(thermal_gap 0.5)
			(thermal_bridge_width 0.5)
			(island_removal_mode 0)
		)
		(polygon
			(pts
				(arc
					(start 101.755956 -234.764326)
					(mid 101.126036 -234.764326)
					(end 101.755956 -234.764326)
				)
			)
		)
	)
	(zone
		(layers "B.Cu" "In6.Cu" "In11.Cu" "In13.Cu" "In15.Cu")
		(hatch none 0.5)
		(connect_pads
			(clearance 0)
		)
		(min_thickness 0.25)
		(keepout
			(tracks not_allowed)
			(vias allowed)
			(pads allowed)
			(copperpour not_allowed)
			(footprints allowed)
		)
		(placement
			(enabled no)
			(sheetname "")
		)
		(fill yes
			(thermal_gap 0.5)
			(thermal_bridge_width 0.5)
			(island_removal_mode 0)
		)
		(polygon
			(pts
				(arc
					(start 74.29246 -382.36906)
					(mid 73.62444 -382.36906)
					(end 74.29246 -382.36906)
				)
			)
		)
	)
	(zone
		(layers "B.Cu" "In6.Cu" "In11.Cu" "In13.Cu" "In15.Cu")
		(hatch none 0.5)
		(connect_pads
			(clearance 0)
		)
		(min_thickness 0.25)
		(keepout
			(tracks not_allowed)
			(vias allowed)
			(pads allowed)
			(copperpour not_allowed)
			(footprints allowed)
		)
		(placement
			(enabled no)
			(sheetname "")
		)
		(fill yes
			(thermal_gap 0.5)
			(thermal_bridge_width 0.5)
			(island_removal_mode 0)
		)
		(polygon
			(pts
				(arc
					(start 407.734008 -397.849344)
					(mid 407.104088 -397.849344)
					(end 407.734008 -397.849344)
				)
			)
		)
	)
	(zone
		(layers "B.Cu" "In6.Cu" "In11.Cu" "In13.Cu" "In15.Cu")
		(hatch none 0.5)
		(connect_pads
			(clearance 0)
		)
		(min_thickness 0.25)
		(keepout
			(tracks not_allowed)
			(vias allowed)
			(pads allowed)
			(copperpour not_allowed)
			(footprints allowed)
		)
		(placement
			(enabled no)
			(sheetname "")
		)
		(fill yes
			(thermal_gap 0.5)
			(thermal_bridge_width 0.5)
			(island_removal_mode 0)
		)
		(polygon
			(pts
				(arc
					(start 439.434224 -267.885164)
					(mid 438.766204 -267.885164)
					(end 439.434224 -267.885164)
				)
			)
		)
	)
	(zone
		(layers "B.Cu" "In6.Cu" "In11.Cu" "In13.Cu" "In15.Cu")
		(hatch none 0.5)
		(connect_pads
			(clearance 0)
		)
		(min_thickness 0.25)
		(keepout
			(tracks not_allowed)
			(vias allowed)
			(pads allowed)
			(copperpour not_allowed)
			(footprints allowed)
		)
		(placement
			(enabled no)
			(sheetname "")
		)
		(fill yes
			(thermal_gap 0.5)
			(thermal_bridge_width 0.5)
			(island_removal_mode 0)
		)
		(polygon
			(pts
				(arc
					(start 109.105954 -290.286186)
					(mid 108.476034 -290.286186)
					(end 109.105954 -290.286186)
				)
			)
		)
	)
	(zone
		(layers "B.Cu" "In6.Cu" "In11.Cu" "In13.Cu" "In15.Cu")
		(hatch none 0.5)
		(connect_pads
			(clearance 0)
		)
		(min_thickness 0.25)
		(keepout
			(tracks not_allowed)
			(vias allowed)
			(pads allowed)
			(copperpour not_allowed)
			(footprints allowed)
		)
		(placement
			(enabled no)
			(sheetname "")
		)
		(fill yes
			(thermal_gap 0.5)
			(thermal_bridge_width 0.5)
			(island_removal_mode 0)
		)
		(polygon
			(pts
				(arc
					(start 435.334156 -218.585034)
					(mid 434.666136 -218.585034)
					(end 435.334156 -218.585034)
				)
			)
		)
	)
	(zone
		(layers "B.Cu" "In6.Cu" "In11.Cu" "In13.Cu" "In15.Cu")
		(hatch none 0.5)
		(connect_pads
			(clearance 0)
		)
		(min_thickness 0.25)
		(keepout
			(tracks not_allowed)
			(vias allowed)
			(pads allowed)
			(copperpour not_allowed)
			(footprints allowed)
		)
		(placement
			(enabled no)
			(sheetname "")
		)
		(fill yes
			(thermal_gap 0.5)
			(thermal_bridge_width 0.5)
			(island_removal_mode 0)
		)
		(polygon
			(pts
				(arc
					(start 347.17609 -286.236156)
					(mid 346.54617 -286.236156)
					(end 347.17609 -286.236156)
				)
			)
		)
	)
	(zone
		(layers "B.Cu" "In6.Cu" "In11.Cu" "In13.Cu" "In15.Cu")
		(hatch none 0.5)
		(connect_pads
			(clearance 0)
		)
		(min_thickness 0.25)
		(keepout
			(tracks not_allowed)
			(vias allowed)
			(pads allowed)
			(copperpour not_allowed)
			(footprints allowed)
		)
		(placement
			(enabled no)
			(sheetname "")
		)
		(fill yes
			(thermal_gap 0.5)
			(thermal_bridge_width 0.5)
			(island_removal_mode 0)
		)
		(polygon
			(pts
				(arc
					(start 280.969974 -314.635134)
					(mid 280.301954 -314.635134)
					(end 280.969974 -314.635134)
				)
			)
		)
	)
	(zone
		(layers "B.Cu" "In6.Cu" "In11.Cu" "In13.Cu" "In15.Cu")
		(hatch none 0.5)
		(connect_pads
			(clearance 0)
		)
		(min_thickness 0.25)
		(keepout
			(tracks not_allowed)
			(vias allowed)
			(pads allowed)
			(copperpour not_allowed)
			(footprints allowed)
		)
		(placement
			(enabled no)
			(sheetname "")
		)
		(fill yes
			(thermal_gap 0.5)
			(thermal_bridge_width 0.5)
			(island_removal_mode 0)
		)
		(polygon
			(pts
				(arc
					(start 20.21332 -6.725158)
					(mid 19.5453 -6.725158)
					(end 20.21332 -6.725158)
				)
			)
		)
	)
	(zone
		(layers "B.Cu" "In6.Cu" "In11.Cu" "In13.Cu" "In15.Cu")
		(hatch none 0.5)
		(connect_pads
			(clearance 0)
		)
		(min_thickness 0.25)
		(keepout
			(tracks not_allowed)
			(vias allowed)
			(pads allowed)
			(copperpour not_allowed)
			(footprints allowed)
		)
		(placement
			(enabled no)
			(sheetname "")
		)
		(fill yes
			(thermal_gap 0.5)
			(thermal_bridge_width 0.5)
			(island_removal_mode 0)
		)
		(polygon
			(pts
				(arc
					(start 388.006336 -393.69238)
					(mid 387.376416 -393.69238)
					(end 388.006336 -393.69238)
				)
			)
		)
	)
	(zone
		(layers "B.Cu" "In6.Cu" "In11.Cu" "In13.Cu" "In15.Cu")
		(hatch none 0.5)
		(connect_pads
			(clearance 0)
		)
		(min_thickness 0.25)
		(keepout
			(tracks not_allowed)
			(vias allowed)
			(pads allowed)
			(copperpour not_allowed)
			(footprints allowed)
		)
		(placement
			(enabled no)
			(sheetname "")
		)
		(fill yes
			(thermal_gap 0.5)
			(thermal_bridge_width 0.5)
			(island_removal_mode 0)
		)
		(polygon
			(pts
				(arc
					(start 338.886038 -246.914162)
					(mid 338.256118 -246.914162)
					(end 338.886038 -246.914162)
				)
			)
		)
	)
	(zone
		(layers "B.Cu" "In6.Cu" "In11.Cu" "In13.Cu" "In15.Cu")
		(hatch none 0.5)
		(connect_pads
			(clearance 0)
		)
		(min_thickness 0.25)
		(keepout
			(tracks not_allowed)
			(vias allowed)
			(pads allowed)
			(copperpour not_allowed)
			(footprints allowed)
		)
		(placement
			(enabled no)
			(sheetname "")
		)
		(fill yes
			(thermal_gap 0.5)
			(thermal_bridge_width 0.5)
			(island_removal_mode 0)
		)
		(polygon
			(pts
				(arc
					(start 33.029906 -286.585406)
					(mid 32.361886 -286.585406)
					(end 33.029906 -286.585406)
				)
			)
		)
	)
	(zone
		(layers "B.Cu" "In6.Cu" "In11.Cu" "In13.Cu" "In15.Cu")
		(hatch none 0.5)
		(connect_pads
			(clearance 0)
		)
		(min_thickness 0.25)
		(keepout
			(tracks not_allowed)
			(vias allowed)
			(pads allowed)
			(copperpour not_allowed)
			(footprints allowed)
		)
		(placement
			(enabled no)
			(sheetname "")
		)
		(fill yes
			(thermal_gap 0.5)
			(thermal_bridge_width 0.5)
			(island_removal_mode 0)
		)
		(polygon
			(pts
				(arc
					(start 191.494156 -223.685354)
					(mid 190.826136 -223.685354)
					(end 191.494156 -223.685354)
				)
			)
		)
	)
	(zone
		(layers "B.Cu" "In6.Cu" "In11.Cu" "In13.Cu" "In15.Cu")
		(hatch none 0.5)
		(connect_pads
			(clearance 0)
		)
		(min_thickness 0.25)
		(keepout
			(tracks not_allowed)
			(vias allowed)
			(pads allowed)
			(copperpour not_allowed)
			(footprints allowed)
		)
		(placement
			(enabled no)
			(sheetname "")
		)
		(fill yes
			(thermal_gap 0.5)
			(thermal_bridge_width 0.5)
			(island_removal_mode 0)
		)
		(polygon
			(pts
				(arc
					(start 131.65963 -274.08632)
					(mid 131.02971 -274.08632)
					(end 131.65963 -274.08632)
				)
			)
		)
	)
	(zone
		(layers "B.Cu" "In6.Cu" "In11.Cu" "In13.Cu" "In15.Cu")
		(hatch none 0.5)
		(connect_pads
			(clearance 0)
		)
		(min_thickness 0.25)
		(keepout
			(tracks not_allowed)
			(vias allowed)
			(pads allowed)
			(copperpour not_allowed)
			(footprints allowed)
		)
		(placement
			(enabled no)
			(sheetname "")
		)
		(fill yes
			(thermal_gap 0.5)
			(thermal_bridge_width 0.5)
			(island_removal_mode 0)
		)
		(polygon
			(pts
				(arc
					(start 78.442312 -369.03533)
					(mid 77.774292 -369.03533)
					(end 78.442312 -369.03533)
				)
			)
		)
	)
	(zone
		(layers "B.Cu" "In6.Cu" "In11.Cu" "In13.Cu" "In15.Cu")
		(hatch none 0.5)
		(connect_pads
			(clearance 0)
		)
		(min_thickness 0.25)
		(keepout
			(tracks not_allowed)
			(vias allowed)
			(pads allowed)
			(copperpour not_allowed)
			(footprints allowed)
		)
		(placement
			(enabled no)
			(sheetname "")
		)
		(fill yes
			(thermal_gap 0.5)
			(thermal_bridge_width 0.5)
			(island_removal_mode 0)
		)
		(polygon
			(pts
				(arc
					(start 415.733992 -397.156432)
					(mid 415.104072 -397.156432)
					(end 415.733992 -397.156432)
				)
			)
		)
	)
	(zone
		(layers "B.Cu" "In6.Cu" "In11.Cu" "In13.Cu" "In15.Cu")
		(hatch none 0.5)
		(connect_pads
			(clearance 0)
		)
		(min_thickness 0.25)
		(keepout
			(tracks not_allowed)
			(vias allowed)
			(pads allowed)
			(copperpour not_allowed)
			(footprints allowed)
		)
		(placement
			(enabled no)
			(sheetname "")
		)
		(fill yes
			(thermal_gap 0.5)
			(thermal_bridge_width 0.5)
			(island_removal_mode 0)
		)
		(polygon
			(pts
				(arc
					(start 119.609616 -228.284532)
					(mid 118.979696 -228.284532)
					(end 119.609616 -228.284532)
				)
			)
		)
	)
	(zone
		(layers "B.Cu" "In6.Cu" "In11.Cu" "In13.Cu" "In15.Cu")
		(hatch none 0.5)
		(connect_pads
			(clearance 0)
		)
		(min_thickness 0.25)
		(keepout
			(tracks not_allowed)
			(vias allowed)
			(pads allowed)
			(copperpour not_allowed)
			(footprints allowed)
		)
		(placement
			(enabled no)
			(sheetname "")
		)
		(fill yes
			(thermal_gap 0.5)
			(thermal_bridge_width 0.5)
			(island_removal_mode 0)
		)
		(polygon
			(pts
				(arc
					(start 305.305968 -397.156432)
					(mid 304.676048 -397.156432)
					(end 305.305968 -397.156432)
				)
			)
		)
	)
	(zone
		(layers "B.Cu" "In6.Cu" "In11.Cu" "In13.Cu" "In15.Cu")
		(hatch none 0.5)
		(connect_pads
			(clearance 0)
		)
		(min_thickness 0.25)
		(keepout
			(tracks not_allowed)
			(vias allowed)
			(pads allowed)
			(copperpour not_allowed)
			(footprints allowed)
		)
		(placement
			(enabled no)
			(sheetname "")
		)
		(fill yes
			(thermal_gap 0.5)
			(thermal_bridge_width 0.5)
			(island_removal_mode 0)
		)
		(polygon
			(pts
				(arc
					(start 334.760316 -412.84652)
					(mid 334.092296 -412.84652)
					(end 334.760316 -412.84652)
				)
			)
		)
	)
	(zone
		(layers "B.Cu" "In6.Cu" "In11.Cu" "In13.Cu" "In15.Cu")
		(hatch none 0.5)
		(connect_pads
			(clearance 0)
		)
		(min_thickness 0.25)
		(keepout
			(tracks not_allowed)
			(vias allowed)
			(pads allowed)
			(copperpour not_allowed)
			(footprints allowed)
		)
		(placement
			(enabled no)
			(sheetname "")
		)
		(fill yes
			(thermal_gap 0.5)
			(thermal_bridge_width 0.5)
			(island_removal_mode 0)
		)
		(polygon
			(pts
				(arc
					(start 90.94597 -242.05438)
					(mid 90.31605 -242.05438)
					(end 90.94597 -242.05438)
				)
			)
		)
	)
	(zone
		(layers "B.Cu" "In6.Cu" "In11.Cu" "In13.Cu" "In15.Cu")
		(hatch none 0.5)
		(connect_pads
			(clearance 0)
		)
		(min_thickness 0.25)
		(keepout
			(tracks not_allowed)
			(vias allowed)
			(pads allowed)
			(copperpour not_allowed)
			(footprints allowed)
		)
		(placement
			(enabled no)
			(sheetname "")
		)
		(fill yes
			(thermal_gap 0.5)
			(thermal_bridge_width 0.5)
			(island_removal_mode 0)
		)
		(polygon
			(pts
				(arc
					(start 379.599698 -265.986006)
					(mid 378.969778 -265.986006)
					(end 379.599698 -265.986006)
				)
			)
		)
	)
	(zone
		(layers "B.Cu" "In6.Cu" "In11.Cu" "In13.Cu" "In15.Cu")
		(hatch none 0.5)
		(connect_pads
			(clearance 0)
		)
		(min_thickness 0.25)
		(keepout
			(tracks not_allowed)
			(vias allowed)
			(pads allowed)
			(copperpour not_allowed)
			(footprints allowed)
		)
		(placement
			(enabled no)
			(sheetname "")
		)
		(fill yes
			(thermal_gap 0.5)
			(thermal_bridge_width 0.5)
			(island_removal_mode 0)
		)
		(polygon
			(pts
				(arc
					(start 379.599698 -262.745982)
					(mid 378.969778 -262.745982)
					(end 379.599698 -262.745982)
				)
			)
		)
	)
	(zone
		(layers "B.Cu" "In6.Cu" "In11.Cu" "In13.Cu" "In15.Cu")
		(hatch none 0.5)
		(connect_pads
			(clearance 0)
		)
		(min_thickness 0.25)
		(keepout
			(tracks not_allowed)
			(vias allowed)
			(pads allowed)
			(copperpour not_allowed)
			(footprints allowed)
		)
		(placement
			(enabled no)
			(sheetname "")
		)
		(fill yes
			(thermal_gap 0.5)
			(thermal_bridge_width 0.5)
			(island_removal_mode 0)
		)
		(polygon
			(pts
				(arc
					(start 191.494156 -250.885198)
					(mid 190.826136 -250.885198)
					(end 191.494156 -250.885198)
				)
			)
		)
	)
	(zone
		(layers "B.Cu" "In6.Cu" "In11.Cu" "In13.Cu" "In15.Cu")
		(hatch none 0.5)
		(connect_pads
			(clearance 0)
		)
		(min_thickness 0.25)
		(keepout
			(tracks not_allowed)
			(vias allowed)
			(pads allowed)
			(copperpour not_allowed)
			(footprints allowed)
		)
		(placement
			(enabled no)
			(sheetname "")
		)
		(fill yes
			(thermal_gap 0.5)
			(thermal_bridge_width 0.5)
			(island_removal_mode 0)
		)
		(polygon
			(pts
				(arc
					(start 338.886038 -240.434114)
					(mid 338.256118 -240.434114)
					(end 338.886038 -240.434114)
				)
			)
		)
	)
	(zone
		(layers "B.Cu" "In6.Cu" "In11.Cu" "In13.Cu" "In15.Cu")
		(hatch none 0.5)
		(connect_pads
			(clearance 0)
		)
		(min_thickness 0.25)
		(keepout
			(tracks not_allowed)
			(vias allowed)
			(pads allowed)
			(copperpour not_allowed)
			(footprints allowed)
		)
		(placement
			(enabled no)
			(sheetname "")
		)
		(fill yes
			(thermal_gap 0.5)
			(thermal_bridge_width 0.5)
			(island_removal_mode 0)
		)
		(polygon
			(pts
				(arc
					(start 90.94597 -237.194344)
					(mid 90.31605 -237.194344)
					(end 90.94597 -237.194344)
				)
			)
		)
	)
	(zone
		(layers "B.Cu" "In6.Cu" "In11.Cu" "In13.Cu" "In15.Cu")
		(hatch none 0.5)
		(connect_pads
			(clearance 0)
		)
		(min_thickness 0.25)
		(keepout
			(tracks not_allowed)
			(vias allowed)
			(pads allowed)
			(copperpour not_allowed)
			(footprints allowed)
		)
		(placement
			(enabled no)
			(sheetname "")
		)
		(fill yes
			(thermal_gap 0.5)
			(thermal_bridge_width 0.5)
			(island_removal_mode 0)
		)
		(polygon
			(pts
				(arc
					(start 339.186012 -282.186126)
					(mid 338.556092 -282.186126)
					(end 339.186012 -282.186126)
				)
			)
		)
	)
	(zone
		(layers "B.Cu" "In6.Cu" "In11.Cu" "In13.Cu" "In15.Cu")
		(hatch none 0.5)
		(connect_pads
			(clearance 0)
		)
		(min_thickness 0.25)
		(keepout
			(tracks not_allowed)
			(vias allowed)
			(pads allowed)
			(copperpour not_allowed)
			(footprints allowed)
		)
		(placement
			(enabled no)
			(sheetname "")
		)
		(fill yes
			(thermal_gap 0.5)
			(thermal_bridge_width 0.5)
			(island_removal_mode 0)
		)
		(polygon
			(pts
				(arc
					(start 331.697076 -412.84652)
					(mid 331.029056 -412.84652)
					(end 331.697076 -412.84652)
				)
			)
		)
	)
	(zone
		(layers "B.Cu" "In6.Cu" "In11.Cu" "In13.Cu" "In15.Cu")
		(hatch none 0.5)
		(connect_pads
			(clearance 0)
		)
		(min_thickness 0.25)
		(keepout
			(tracks not_allowed)
			(vias allowed)
			(pads allowed)
			(copperpour not_allowed)
			(footprints allowed)
		)
		(placement
			(enabled no)
			(sheetname "")
		)
		(fill yes
			(thermal_gap 0.5)
			(thermal_bridge_width 0.5)
			(island_removal_mode 0)
		)
		(polygon
			(pts
				(arc
					(start 33.029906 -251.735336)
					(mid 32.361886 -251.735336)
					(end 33.029906 -251.735336)
				)
			)
		)
	)
	(zone
		(layers "B.Cu" "In6.Cu" "In11.Cu" "In13.Cu" "In15.Cu")
		(hatch none 0.5)
		(connect_pads
			(clearance 0)
		)
		(min_thickness 0.25)
		(keepout
			(tracks not_allowed)
			(vias allowed)
			(pads allowed)
			(copperpour not_allowed)
			(footprints allowed)
		)
		(placement
			(enabled no)
			(sheetname "")
		)
		(fill yes
			(thermal_gap 0.5)
			(thermal_bridge_width 0.5)
			(island_removal_mode 0)
		)
		(polygon
			(pts
				(arc
					(start 304.506122 -397.849344)
					(mid 303.876202 -397.849344)
					(end 304.506122 -397.849344)
				)
			)
		)
	)
	(zone
		(layers "B.Cu" "In6.Cu" "In11.Cu" "In13.Cu" "In15.Cu")
		(hatch none 0.5)
		(connect_pads
			(clearance 0)
		)
		(min_thickness 0.25)
		(keepout
			(tracks not_allowed)
			(vias allowed)
			(pads allowed)
			(copperpour not_allowed)
			(footprints allowed)
		)
		(placement
			(enabled no)
			(sheetname "")
		)
		(fill yes
			(thermal_gap 0.5)
			(thermal_bridge_width 0.5)
			(island_removal_mode 0)
		)
		(polygon
			(pts
				(arc
					(start 125.54966 -289.47618)
					(mid 124.91974 -289.47618)
					(end 125.54966 -289.47618)
				)
			)
		)
	)
	(zone
		(layers "B.Cu" "In6.Cu" "In11.Cu" "In13.Cu" "In15.Cu")
		(hatch none 0.5)
		(connect_pads
			(clearance 0)
		)
		(min_thickness 0.25)
		(keepout
			(tracks not_allowed)
			(vias allowed)
			(pads allowed)
			(copperpour not_allowed)
			(footprints allowed)
		)
		(placement
			(enabled no)
			(sheetname "")
		)
		(fill yes
			(thermal_gap 0.5)
			(thermal_bridge_width 0.5)
			(island_removal_mode 0)
		)
		(polygon
			(pts
				(arc
					(start 285.070042 -210.085178)
					(mid 284.402022 -210.085178)
					(end 285.070042 -210.085178)
				)
			)
		)
	)
	(zone
		(layers "B.Cu" "In6.Cu" "In11.Cu" "In13.Cu" "In15.Cu")
		(hatch none 0.5)
		(connect_pads
			(clearance 0)
		)
		(min_thickness 0.25)
		(keepout
			(tracks not_allowed)
			(vias allowed)
			(pads allowed)
			(copperpour not_allowed)
			(footprints allowed)
		)
		(placement
			(enabled no)
			(sheetname "")
		)
		(fill yes
			(thermal_gap 0.5)
			(thermal_bridge_width 0.5)
			(island_removal_mode 0)
		)
		(polygon
			(pts
				(arc
					(start 405.787352 -412.84652)
					(mid 405.119332 -412.84652)
					(end 405.787352 -412.84652)
				)
			)
		)
	)
	(zone
		(layers "B.Cu" "In6.Cu" "In11.Cu" "In13.Cu" "In15.Cu")
		(hatch none 0.5)
		(connect_pads
			(clearance 0)
		)
		(min_thickness 0.25)
		(keepout
			(tracks not_allowed)
			(vias allowed)
			(pads allowed)
			(copperpour not_allowed)
			(footprints allowed)
		)
		(placement
			(enabled no)
			(sheetname "")
		)
		(fill yes
			(thermal_gap 0.5)
			(thermal_bridge_width 0.5)
			(island_removal_mode 0)
		)
		(polygon
			(pts
				(arc
					(start 156.134054 -388.774432)
					(mid 155.504134 -388.774432)
					(end 156.134054 -388.774432)
				)
			)
		)
	)
	(zone
		(layers "B.Cu" "In6.Cu" "In11.Cu" "In13.Cu" "In15.Cu")
		(hatch none 0.5)
		(connect_pads
			(clearance 0)
		)
		(min_thickness 0.25)
		(keepout
			(tracks not_allowed)
			(vias allowed)
			(pads allowed)
			(copperpour not_allowed)
			(footprints allowed)
		)
		(placement
			(enabled no)
			(sheetname "")
		)
		(fill yes
			(thermal_gap 0.5)
			(thermal_bridge_width 0.5)
			(island_removal_mode 0)
		)
		(polygon
			(pts
				(arc
					(start 37.129974 -317.185294)
					(mid 36.461954 -317.185294)
					(end 37.129974 -317.185294)
				)
			)
		)
	)
	(zone
		(layers "B.Cu" "In6.Cu" "In11.Cu" "In13.Cu" "In15.Cu")
		(hatch none 0.5)
		(connect_pads
			(clearance 0)
		)
		(min_thickness 0.25)
		(keepout
			(tracks not_allowed)
			(vias allowed)
			(pads allowed)
			(copperpour not_allowed)
			(footprints allowed)
		)
		(placement
			(enabled no)
			(sheetname "")
		)
		(fill yes
			(thermal_gap 0.5)
			(thermal_bridge_width 0.5)
			(island_removal_mode 0)
		)
		(polygon
			(pts
				(arc
					(start 311.305956 -397.156432)
					(mid 310.676036 -397.156432)
					(end 311.305956 -397.156432)
				)
			)
		)
	)
	(zone
		(layers "B.Cu" "In6.Cu" "In11.Cu" "In13.Cu" "In15.Cu")
		(hatch none 0.5)
		(connect_pads
			(clearance 0)
		)
		(min_thickness 0.25)
		(keepout
			(tracks not_allowed)
			(vias allowed)
			(pads allowed)
			(copperpour not_allowed)
			(footprints allowed)
		)
		(placement
			(enabled no)
			(sheetname "")
		)
		(fill yes
			(thermal_gap 0.5)
			(thermal_bridge_width 0.5)
			(island_removal_mode 0)
		)
		(polygon
			(pts
				(arc
					(start 92.655898 -263.556242)
					(mid 92.025978 -263.556242)
					(end 92.655898 -263.556242)
				)
			)
		)
	)
	(zone
		(layers "B.Cu" "In6.Cu" "In11.Cu" "In13.Cu" "In15.Cu")
		(hatch none 0.5)
		(connect_pads
			(clearance 0)
		)
		(min_thickness 0.25)
		(keepout
			(tracks not_allowed)
			(vias allowed)
			(pads allowed)
			(copperpour not_allowed)
			(footprints allowed)
		)
		(placement
			(enabled no)
			(sheetname "")
		)
		(fill yes
			(thermal_gap 0.5)
			(thermal_bridge_width 0.5)
			(island_removal_mode 0)
		)
		(polygon
			(pts
				(arc
					(start 37.129974 -212.635338)
					(mid 36.461954 -212.635338)
					(end 37.129974 -212.635338)
				)
			)
		)
	)
	(zone
		(layers "B.Cu" "In6.Cu" "In11.Cu" "In13.Cu" "In15.Cu")
		(hatch none 0.5)
		(connect_pads
			(clearance 0)
		)
		(min_thickness 0.25)
		(keepout
			(tracks not_allowed)
			(vias allowed)
			(pads allowed)
			(copperpour not_allowed)
			(footprints allowed)
		)
		(placement
			(enabled no)
			(sheetname "")
		)
		(fill yes
			(thermal_gap 0.5)
			(thermal_bridge_width 0.5)
			(island_removal_mode 0)
		)
		(polygon
			(pts
				(arc
					(start 285.070042 -236.435138)
					(mid 284.402022 -236.435138)
					(end 285.070042 -236.435138)
				)
			)
		)
	)
	(zone
		(layers "B.Cu" "In6.Cu" "In11.Cu" "In13.Cu" "In15.Cu")
		(hatch none 0.5)
		(connect_pads
			(clearance 0)
		)
		(min_thickness 0.25)
		(keepout
			(tracks not_allowed)
			(vias allowed)
			(pads allowed)
			(copperpour not_allowed)
			(footprints allowed)
		)
		(placement
			(enabled no)
			(sheetname "")
		)
		(fill yes
			(thermal_gap 0.5)
			(thermal_bridge_width 0.5)
			(island_removal_mode 0)
		)
		(polygon
			(pts
				(arc
					(start 285.070042 -292.535102)
					(mid 284.402022 -292.535102)
					(end 285.070042 -292.535102)
				)
			)
		)
	)
	(zone
		(layers "B.Cu" "In6.Cu" "In11.Cu" "In13.Cu" "In15.Cu")
		(hatch none 0.5)
		(connect_pads
			(clearance 0)
		)
		(min_thickness 0.25)
		(keepout
			(tracks not_allowed)
			(vias allowed)
			(pads allowed)
			(copperpour not_allowed)
			(footprints allowed)
		)
		(placement
			(enabled no)
			(sheetname "")
		)
		(fill yes
			(thermal_gap 0.5)
			(thermal_bridge_width 0.5)
			(island_removal_mode 0)
		)
		(polygon
			(pts
				(arc
					(start 339.656166 -266.796012)
					(mid 339.026246 -266.796012)
					(end 339.656166 -266.796012)
				)
			)
		)
	)
	(zone
		(layers "B.Cu" "In6.Cu" "In11.Cu" "In13.Cu" "In15.Cu")
		(hatch none 0.5)
		(connect_pads
			(clearance 0)
		)
		(min_thickness 0.25)
		(keepout
			(tracks not_allowed)
			(vias allowed)
			(pads allowed)
			(copperpour not_allowed)
			(footprints allowed)
		)
		(placement
			(enabled no)
			(sheetname "")
		)
		(fill yes
			(thermal_gap 0.5)
			(thermal_bridge_width 0.5)
			(island_removal_mode 0)
		)
		(polygon
			(pts
				(arc
					(start 133.239764 -248.534428)
					(mid 132.609844 -248.534428)
					(end 133.239764 -248.534428)
				)
			)
		)
	)
	(zone
		(layers "B.Cu" "In6.Cu" "In11.Cu" "In13.Cu" "In15.Cu")
		(hatch none 0.5)
		(connect_pads
			(clearance 0)
		)
		(min_thickness 0.25)
		(keepout
			(tracks not_allowed)
			(vias allowed)
			(pads allowed)
			(copperpour not_allowed)
			(footprints allowed)
		)
		(placement
			(enabled no)
			(sheetname "")
		)
		(fill yes
			(thermal_gap 0.5)
			(thermal_bridge_width 0.5)
			(island_removal_mode 0)
		)
		(polygon
			(pts
				(arc
					(start 37.129974 -289.135312)
					(mid 36.461954 -289.135312)
					(end 37.129974 -289.135312)
				)
			)
		)
	)
	(zone
		(layers "B.Cu" "In6.Cu" "In11.Cu" "In13.Cu" "In15.Cu")
		(hatch none 0.5)
		(connect_pads
			(clearance 0)
		)
		(min_thickness 0.25)
		(keepout
			(tracks not_allowed)
			(vias allowed)
			(pads allowed)
			(copperpour not_allowed)
			(footprints allowed)
		)
		(placement
			(enabled no)
			(sheetname "")
		)
		(fill yes
			(thermal_gap 0.5)
			(thermal_bridge_width 0.5)
			(island_removal_mode 0)
		)
		(polygon
			(pts
				(arc
					(start 381.009906 -266.796012)
					(mid 380.379986 -266.796012)
					(end 381.009906 -266.796012)
				)
			)
		)
	)
	(zone
		(layers "B.Cu" "In6.Cu" "In11.Cu" "In13.Cu" "In15.Cu")
		(hatch none 0.5)
		(connect_pads
			(clearance 0)
		)
		(min_thickness 0.25)
		(keepout
			(tracks not_allowed)
			(vias allowed)
			(pads allowed)
			(copperpour not_allowed)
			(footprints allowed)
		)
		(placement
			(enabled no)
			(sheetname "")
		)
		(fill yes
			(thermal_gap 0.5)
			(thermal_bridge_width 0.5)
			(island_removal_mode 0)
		)
		(polygon
			(pts
				(arc
					(start 280.969974 -306.985162)
					(mid 280.301954 -306.985162)
					(end 280.969974 -306.985162)
				)
			)
		)
	)
	(zone
		(layers "B.Cu" "In6.Cu" "In11.Cu" "In13.Cu" "In15.Cu")
		(hatch none 0.5)
		(connect_pads
			(clearance 0)
		)
		(min_thickness 0.25)
		(keepout
			(tracks not_allowed)
			(vias allowed)
			(pads allowed)
			(copperpour not_allowed)
			(footprints allowed)
		)
		(placement
			(enabled no)
			(sheetname "")
		)
		(fill yes
			(thermal_gap 0.5)
			(thermal_bridge_width 0.5)
			(island_removal_mode 0)
		)
		(polygon
			(pts
				(arc
					(start 187.394088 -244.935248)
					(mid 186.726068 -244.935248)
					(end 187.394088 -244.935248)
				)
			)
		)
	)
	(zone
		(layers "B.Cu" "In6.Cu" "In11.Cu" "In13.Cu" "In15.Cu")
		(hatch none 0.5)
		(connect_pads
			(clearance 0)
		)
		(min_thickness 0.25)
		(keepout
			(tracks not_allowed)
			(vias allowed)
			(pads allowed)
			(copperpour not_allowed)
			(footprints allowed)
		)
		(placement
			(enabled no)
			(sheetname "")
		)
		(fill yes
			(thermal_gap 0.5)
			(thermal_bridge_width 0.5)
			(island_removal_mode 0)
		)
		(polygon
			(pts
				(arc
					(start 383.481072 -412.84652)
					(mid 382.813052 -412.84652)
					(end 383.481072 -412.84652)
				)
			)
		)
	)
	(zone
		(layers "B.Cu" "In6.Cu" "In11.Cu" "In13.Cu" "In15.Cu")
		(hatch none 0.5)
		(connect_pads
			(clearance 0)
		)
		(min_thickness 0.25)
		(keepout
			(tracks not_allowed)
			(vias allowed)
			(pads allowed)
			(copperpour not_allowed)
			(footprints allowed)
		)
		(placement
			(enabled no)
			(sheetname "")
		)
		(fill yes
			(thermal_gap 0.5)
			(thermal_bridge_width 0.5)
			(island_removal_mode 0)
		)
		(polygon
			(pts
				(arc
					(start 367.549684 -234.764072)
					(mid 366.919764 -234.764072)
					(end 367.549684 -234.764072)
				)
			)
		)
	)
	(zone
		(layers "B.Cu" "In6.Cu" "In11.Cu" "In13.Cu" "In15.Cu")
		(hatch none 0.5)
		(connect_pads
			(clearance 0)
		)
		(min_thickness 0.25)
		(keepout
			(tracks not_allowed)
			(vias allowed)
			(pads allowed)
			(copperpour not_allowed)
			(footprints allowed)
		)
		(placement
			(enabled no)
			(sheetname "")
		)
		(fill yes
			(thermal_gap 0.5)
			(thermal_bridge_width 0.5)
			(island_removal_mode 0)
		)
		(polygon
			(pts
				(arc
					(start 96.298512 -371.49913)
					(mid 95.630492 -371.49913)
					(end 96.298512 -371.49913)
				)
			)
		)
	)
	(zone
		(layers "B.Cu" "In6.Cu" "In11.Cu" "In13.Cu" "In15.Cu")
		(hatch none 0.5)
		(connect_pads
			(clearance 0)
		)
		(min_thickness 0.25)
		(keepout
			(tracks not_allowed)
			(vias allowed)
			(pads allowed)
			(copperpour not_allowed)
			(footprints allowed)
		)
		(placement
			(enabled no)
			(sheetname "")
		)
		(fill yes
			(thermal_gap 0.5)
			(thermal_bridge_width 0.5)
			(island_removal_mode 0)
		)
		(polygon
			(pts
				(arc
					(start 435.334156 -288.285174)
					(mid 434.666136 -288.285174)
					(end 435.334156 -288.285174)
				)
			)
		)
	)
	(zone
		(layers "B.Cu" "In6.Cu" "In11.Cu" "In13.Cu" "In15.Cu")
		(hatch none 0.5)
		(connect_pads
			(clearance 0)
		)
		(min_thickness 0.25)
		(keepout
			(tracks not_allowed)
			(vias allowed)
			(pads allowed)
			(copperpour not_allowed)
			(footprints allowed)
		)
		(placement
			(enabled no)
			(sheetname "")
		)
		(fill yes
			(thermal_gap 0.5)
			(thermal_bridge_width 0.5)
			(island_removal_mode 0)
		)
		(polygon
			(pts
				(arc
					(start 33.029906 -250.035314)
					(mid 32.361886 -250.035314)
					(end 33.029906 -250.035314)
				)
			)
		)
	)
	(zone
		(layers "B.Cu" "In6.Cu" "In11.Cu" "In13.Cu" "In15.Cu")
		(hatch none 0.5)
		(connect_pads
			(clearance 0)
		)
		(min_thickness 0.25)
		(keepout
			(tracks not_allowed)
			(vias allowed)
			(pads allowed)
			(copperpour not_allowed)
			(footprints allowed)
		)
		(placement
			(enabled no)
			(sheetname "")
		)
		(fill yes
			(thermal_gap 0.5)
			(thermal_bridge_width 0.5)
			(island_removal_mode 0)
		)
		(polygon
			(pts
				(arc
					(start 379.299724 -251.774198)
					(mid 378.669804 -251.774198)
					(end 379.299724 -251.774198)
				)
			)
		)
	)
	(zone
		(layers "B.Cu" "In6.Cu" "In11.Cu" "In13.Cu" "In15.Cu")
		(hatch none 0.5)
		(connect_pads
			(clearance 0)
		)
		(min_thickness 0.25)
		(keepout
			(tracks not_allowed)
			(vias allowed)
			(pads allowed)
			(copperpour not_allowed)
			(footprints allowed)
		)
		(placement
			(enabled no)
			(sheetname "")
		)
		(fill yes
			(thermal_gap 0.5)
			(thermal_bridge_width 0.5)
			(island_removal_mode 0)
		)
		(polygon
			(pts
				(arc
					(start 119.154956 -404.46452)
					(mid 118.486936 -404.46452)
					(end 119.154956 -404.46452)
				)
			)
		)
	)
	(zone
		(layers "B.Cu" "In6.Cu" "In11.Cu" "In13.Cu" "In15.Cu")
		(hatch none 0.5)
		(connect_pads
			(clearance 0)
		)
		(min_thickness 0.25)
		(keepout
			(tracks not_allowed)
			(vias allowed)
			(pads allowed)
			(copperpour not_allowed)
			(footprints allowed)
		)
		(placement
			(enabled no)
			(sheetname "")
		)
		(fill yes
			(thermal_gap 0.5)
			(thermal_bridge_width 0.5)
			(island_removal_mode 0)
		)
		(polygon
			(pts
				(arc
					(start 339.355938 -228.284278)
					(mid 338.726018 -228.284278)
					(end 339.355938 -228.284278)
				)
			)
		)
	)
	(zone
		(layers "B.Cu" "In6.Cu" "In11.Cu" "In13.Cu" "In15.Cu")
		(hatch none 0.5)
		(connect_pads
			(clearance 0)
		)
		(min_thickness 0.25)
		(keepout
			(tracks not_allowed)
			(vias allowed)
			(pads allowed)
			(copperpour not_allowed)
			(footprints allowed)
		)
		(placement
			(enabled no)
			(sheetname "")
		)
		(fill yes
			(thermal_gap 0.5)
			(thermal_bridge_width 0.5)
			(island_removal_mode 0)
		)
		(polygon
			(pts
				(arc
					(start 346.876116 -228.284278)
					(mid 346.246196 -228.284278)
					(end 346.876116 -228.284278)
				)
			)
		)
	)
	(zone
		(layers "B.Cu" "In6.Cu" "In11.Cu" "In13.Cu" "In15.Cu")
		(hatch none 0.5)
		(connect_pads
			(clearance 0)
		)
		(min_thickness 0.25)
		(keepout
			(tracks not_allowed)
			(vias allowed)
			(pads allowed)
			(copperpour not_allowed)
			(footprints allowed)
		)
		(placement
			(enabled no)
			(sheetname "")
		)
		(fill yes
			(thermal_gap 0.5)
			(thermal_bridge_width 0.5)
			(island_removal_mode 0)
		)
		(polygon
			(pts
				(arc
					(start 90.94597 -233.95432)
					(mid 90.31605 -233.95432)
					(end 90.94597 -233.95432)
				)
			)
		)
	)
	(zone
		(layers "B.Cu" "In6.Cu" "In11.Cu" "In13.Cu" "In15.Cu")
		(hatch none 0.5)
		(connect_pads
			(clearance 0)
		)
		(min_thickness 0.25)
		(keepout
			(tracks not_allowed)
			(vias allowed)
			(pads allowed)
			(copperpour not_allowed)
			(footprints allowed)
		)
		(placement
			(enabled no)
			(sheetname "")
		)
		(fill yes
			(thermal_gap 0.5)
			(thermal_bridge_width 0.5)
			(island_removal_mode 0)
		)
		(polygon
			(pts
				(arc
					(start 39.259764 -6.725158)
					(mid 38.591744 -6.725158)
					(end 39.259764 -6.725158)
				)
			)
		)
	)
	(zone
		(layers "B.Cu" "In6.Cu" "In11.Cu" "In13.Cu" "In15.Cu")
		(hatch none 0.5)
		(connect_pads
			(clearance 0)
		)
		(min_thickness 0.25)
		(keepout
			(tracks not_allowed)
			(vias allowed)
			(pads allowed)
			(copperpour not_allowed)
			(footprints allowed)
		)
		(placement
			(enabled no)
			(sheetname "")
		)
		(fill yes
			(thermal_gap 0.5)
			(thermal_bridge_width 0.5)
			(island_removal_mode 0)
		)
		(polygon
			(pts
				(arc
					(start 191.494156 -285.735268)
					(mid 190.826136 -285.735268)
					(end 191.494156 -285.735268)
				)
			)
		)
	)
	(zone
		(layers "B.Cu" "In6.Cu" "In11.Cu" "In13.Cu" "In15.Cu")
		(hatch none 0.5)
		(connect_pads
			(clearance 0)
		)
		(min_thickness 0.25)
		(keepout
			(tracks not_allowed)
			(vias allowed)
			(pads allowed)
			(copperpour not_allowed)
			(footprints allowed)
		)
		(placement
			(enabled no)
			(sheetname "")
		)
		(fill yes
			(thermal_gap 0.5)
			(thermal_bridge_width 0.5)
			(island_removal_mode 0)
		)
		(polygon
			(pts
				(arc
					(start 115.379754 -230.71455)
					(mid 114.749834 -230.71455)
					(end 115.379754 -230.71455)
				)
			)
		)
	)
	(zone
		(layers "B.Cu" "In6.Cu" "In11.Cu" "In13.Cu" "In15.Cu")
		(hatch none 0.5)
		(connect_pads
			(clearance 0)
		)
		(min_thickness 0.25)
		(keepout
			(tracks not_allowed)
			(vias allowed)
			(pads allowed)
			(copperpour not_allowed)
			(footprints allowed)
		)
		(placement
			(enabled no)
			(sheetname "")
		)
		(fill yes
			(thermal_gap 0.5)
			(thermal_bridge_width 0.5)
			(island_removal_mode 0)
		)
		(polygon
			(pts
				(arc
					(start 340.595966 -266.796012)
					(mid 339.966046 -266.796012)
					(end 340.595966 -266.796012)
				)
			)
		)
	)
	(zone
		(layers "B.Cu" "In6.Cu" "In11.Cu" "In13.Cu" "In15.Cu")
		(hatch none 0.5)
		(connect_pads
			(clearance 0)
		)
		(min_thickness 0.25)
		(keepout
			(tracks not_allowed)
			(vias allowed)
			(pads allowed)
			(copperpour not_allowed)
			(footprints allowed)
		)
		(placement
			(enabled no)
			(sheetname "")
		)
		(fill yes
			(thermal_gap 0.5)
			(thermal_bridge_width 0.5)
			(island_removal_mode 0)
		)
		(polygon
			(pts
				(arc
					(start 155.050236 -404.46452)
					(mid 154.382216 -404.46452)
					(end 155.050236 -404.46452)
				)
			)
		)
	)
	(zone
		(layers "B.Cu" "In6.Cu" "In11.Cu" "In13.Cu" "In15.Cu")
		(hatch none 0.5)
		(connect_pads
			(clearance 0)
		)
		(min_thickness 0.25)
		(keepout
			(tracks not_allowed)
			(vias allowed)
			(pads allowed)
			(copperpour not_allowed)
			(footprints allowed)
		)
		(placement
			(enabled no)
			(sheetname "")
		)
		(fill yes
			(thermal_gap 0.5)
			(thermal_bridge_width 0.5)
			(island_removal_mode 0)
		)
		(polygon
			(pts
				(arc
					(start 439.434224 -199.035162)
					(mid 438.766204 -199.035162)
					(end 439.434224 -199.035162)
				)
			)
		)
	)
	(zone
		(layers "B.Cu" "In6.Cu" "In11.Cu" "In13.Cu" "In15.Cu")
		(hatch none 0.5)
		(connect_pads
			(clearance 0)
		)
		(min_thickness 0.25)
		(keepout
			(tracks not_allowed)
			(vias allowed)
			(pads allowed)
			(copperpour not_allowed)
			(footprints allowed)
		)
		(placement
			(enabled no)
			(sheetname "")
		)
		(fill yes
			(thermal_gap 0.5)
			(thermal_bridge_width 0.5)
			(island_removal_mode 0)
		)
		(polygon
			(pts
				(arc
					(start 74.29246 -375.96826)
					(mid 73.62444 -375.96826)
					(end 74.29246 -375.96826)
				)
			)
		)
	)
	(zone
		(layers "B.Cu" "In6.Cu" "In11.Cu" "In13.Cu" "In15.Cu")
		(hatch none 0.5)
		(connect_pads
			(clearance 0)
		)
		(min_thickness 0.25)
		(keepout
			(tracks not_allowed)
			(vias allowed)
			(pads allowed)
			(copperpour not_allowed)
			(footprints allowed)
		)
		(placement
			(enabled no)
			(sheetname "")
		)
		(fill yes
			(thermal_gap 0.5)
			(thermal_bridge_width 0.5)
			(island_removal_mode 0)
		)
		(polygon
			(pts
				(arc
					(start 131.82981 -229.90429)
					(mid 131.19989 -229.90429)
					(end 131.82981 -229.90429)
				)
			)
		)
	)
	(zone
		(layers "B.Cu" "In6.Cu" "In11.Cu" "In13.Cu" "In15.Cu")
		(hatch none 0.5)
		(connect_pads
			(clearance 0)
		)
		(min_thickness 0.25)
		(keepout
			(tracks not_allowed)
			(vias allowed)
			(pads allowed)
			(copperpour not_allowed)
			(footprints allowed)
		)
		(placement
			(enabled no)
			(sheetname "")
		)
		(fill yes
			(thermal_gap 0.5)
			(thermal_bridge_width 0.5)
			(island_removal_mode 0)
		)
		(polygon
			(pts
				(arc
					(start 439.434224 -292.535102)
					(mid 438.766204 -292.535102)
					(end 439.434224 -292.535102)
				)
			)
		)
	)
	(zone
		(layers "B.Cu" "In6.Cu" "In11.Cu" "In13.Cu" "In15.Cu")
		(hatch none 0.5)
		(connect_pads
			(clearance 0)
		)
		(min_thickness 0.25)
		(keepout
			(tracks not_allowed)
			(vias allowed)
			(pads allowed)
			(copperpour not_allowed)
			(footprints allowed)
		)
		(placement
			(enabled no)
			(sheetname "")
		)
		(fill yes
			(thermal_gap 0.5)
			(thermal_bridge_width 0.5)
			(island_removal_mode 0)
		)
		(polygon
			(pts
				(arc
					(start 285.070042 -221.985078)
					(mid 284.402022 -221.985078)
					(end 285.070042 -221.985078)
				)
			)
		)
	)
	(zone
		(layers "B.Cu" "In6.Cu" "In11.Cu" "In13.Cu" "In15.Cu")
		(hatch none 0.5)
		(connect_pads
			(clearance 0)
		)
		(min_thickness 0.25)
		(keepout
			(tracks not_allowed)
			(vias allowed)
			(pads allowed)
			(copperpour not_allowed)
			(footprints allowed)
		)
		(placement
			(enabled no)
			(sheetname "")
		)
		(fill yes
			(thermal_gap 0.5)
			(thermal_bridge_width 0.5)
			(island_removal_mode 0)
		)
		(polygon
			(pts
				(arc
					(start 280.969974 -272.984976)
					(mid 280.301954 -272.984976)
					(end 280.969974 -272.984976)
				)
			)
		)
	)
	(zone
		(layers "B.Cu" "In6.Cu" "In11.Cu" "In13.Cu" "In15.Cu")
		(hatch none 0.5)
		(connect_pads
			(clearance 0)
		)
		(min_thickness 0.25)
		(keepout
			(tracks not_allowed)
			(vias allowed)
			(pads allowed)
			(copperpour not_allowed)
			(footprints allowed)
		)
		(placement
			(enabled no)
			(sheetname "")
		)
		(fill yes
			(thermal_gap 0.5)
			(thermal_bridge_width 0.5)
			(island_removal_mode 0)
		)
		(polygon
			(pts
				(arc
					(start 109.746034 -232.334308)
					(mid 109.116114 -232.334308)
					(end 109.746034 -232.334308)
				)
			)
		)
	)
	(zone
		(layers "B.Cu" "In6.Cu" "In11.Cu" "In13.Cu" "In15.Cu")
		(hatch none 0.5)
		(connect_pads
			(clearance 0)
		)
		(min_thickness 0.25)
		(keepout
			(tracks not_allowed)
			(vias allowed)
			(pads allowed)
			(copperpour not_allowed)
			(footprints allowed)
		)
		(placement
			(enabled no)
			(sheetname "")
		)
		(fill yes
			(thermal_gap 0.5)
			(thermal_bridge_width 0.5)
			(island_removal_mode 0)
		)
		(polygon
			(pts
				(arc
					(start 91.245944 -291.906198)
					(mid 90.616024 -291.906198)
					(end 91.245944 -291.906198)
				)
			)
		)
	)
	(zone
		(layers "B.Cu" "In6.Cu" "In11.Cu" "In13.Cu" "In15.Cu")
		(hatch none 0.5)
		(connect_pads
			(clearance 0)
		)
		(min_thickness 0.25)
		(keepout
			(tracks not_allowed)
			(vias allowed)
			(pads allowed)
			(copperpour not_allowed)
			(footprints allowed)
		)
		(placement
			(enabled no)
			(sheetname "")
		)
		(fill yes
			(thermal_gap 0.5)
			(thermal_bridge_width 0.5)
			(island_removal_mode 0)
		)
		(polygon
			(pts
				(arc
					(start 381.009906 -279.756108)
					(mid 380.379986 -279.756108)
					(end 381.009906 -279.756108)
				)
			)
		)
	)
	(zone
		(layers "B.Cu" "In6.Cu" "In11.Cu" "In13.Cu" "In15.Cu")
		(hatch none 0.5)
		(connect_pads
			(clearance 0)
		)
		(min_thickness 0.25)
		(keepout
			(tracks not_allowed)
			(vias allowed)
			(pads allowed)
			(copperpour not_allowed)
			(footprints allowed)
		)
		(placement
			(enabled no)
			(sheetname "")
		)
		(fill yes
			(thermal_gap 0.5)
			(thermal_bridge_width 0.5)
			(island_removal_mode 0)
		)
		(polygon
			(pts
				(arc
					(start 381.179832 -225.85426)
					(mid 380.549912 -225.85426)
					(end 381.179832 -225.85426)
				)
			)
		)
	)
	(zone
		(layers "B.Cu" "In6.Cu" "In11.Cu" "In13.Cu" "In15.Cu")
		(hatch none 0.5)
		(connect_pads
			(clearance 0)
		)
		(min_thickness 0.25)
		(keepout
			(tracks not_allowed)
			(vias allowed)
			(pads allowed)
			(copperpour not_allowed)
			(footprints allowed)
		)
		(placement
			(enabled no)
			(sheetname "")
		)
		(fill yes
			(thermal_gap 0.5)
			(thermal_bridge_width 0.5)
			(island_removal_mode 0)
		)
		(polygon
			(pts
				(arc
					(start 439.434224 -295.085008)
					(mid 438.766204 -295.085008)
					(end 439.434224 -295.085008)
				)
			)
		)
	)
	(zone
		(layers "B.Cu" "In6.Cu" "In11.Cu" "In13.Cu" "In15.Cu")
		(hatch none 0.5)
		(connect_pads
			(clearance 0)
		)
		(min_thickness 0.25)
		(keepout
			(tracks not_allowed)
			(vias allowed)
			(pads allowed)
			(copperpour not_allowed)
			(footprints allowed)
		)
		(placement
			(enabled no)
			(sheetname "")
		)
		(fill yes
			(thermal_gap 0.5)
			(thermal_bridge_width 0.5)
			(island_removal_mode 0)
		)
		(polygon
			(pts
				(arc
					(start 379.769878 -228.284278)
					(mid 379.139958 -228.284278)
					(end 379.769878 -228.284278)
				)
			)
		)
	)
	(zone
		(layers "B.Cu" "In6.Cu" "In11.Cu" "In13.Cu" "In15.Cu")
		(hatch none 0.5)
		(connect_pads
			(clearance 0)
		)
		(min_thickness 0.25)
		(keepout
			(tracks not_allowed)
			(vias allowed)
			(pads allowed)
			(copperpour not_allowed)
			(footprints allowed)
		)
		(placement
			(enabled no)
			(sheetname "")
		)
		(fill yes
			(thermal_gap 0.5)
			(thermal_bridge_width 0.5)
			(island_removal_mode 0)
		)
		(polygon
			(pts
				(arc
					(start 120.54967 -226.66452)
					(mid 119.91975 -226.66452)
					(end 120.54967 -226.66452)
				)
			)
		)
	)
	(zone
		(layers "B.Cu" "In6.Cu" "In11.Cu" "In13.Cu" "In15.Cu")
		(hatch none 0.5)
		(connect_pads
			(clearance 0)
		)
		(min_thickness 0.25)
		(keepout
			(tracks not_allowed)
			(vias allowed)
			(pads allowed)
			(copperpour not_allowed)
			(footprints allowed)
		)
		(placement
			(enabled no)
			(sheetname "")
		)
		(fill yes
			(thermal_gap 0.5)
			(thermal_bridge_width 0.5)
			(island_removal_mode 0)
		)
		(polygon
			(pts
				(arc
					(start 133.239764 -238.814356)
					(mid 132.609844 -238.814356)
					(end 133.239764 -238.814356)
				)
			)
		)
	)
	(zone
		(layers "B.Cu" "In6.Cu" "In11.Cu" "In13.Cu" "In15.Cu")
		(hatch none 0.5)
		(connect_pads
			(clearance 0)
		)
		(min_thickness 0.25)
		(keepout
			(tracks not_allowed)
			(vias allowed)
			(pads allowed)
			(copperpour not_allowed)
			(footprints allowed)
		)
		(placement
			(enabled no)
			(sheetname "")
		)
		(fill yes
			(thermal_gap 0.5)
			(thermal_bridge_width 0.5)
			(island_removal_mode 0)
		)
		(polygon
			(pts
				(arc
					(start 90.354912 -371.49913)
					(mid 89.686892 -371.49913)
					(end 90.354912 -371.49913)
				)
			)
		)
	)
	(zone
		(layers "B.Cu" "In6.Cu" "In11.Cu" "In13.Cu" "In15.Cu")
		(hatch none 0.5)
		(connect_pads
			(clearance 0)
		)
		(min_thickness 0.25)
		(keepout
			(tracks not_allowed)
			(vias allowed)
			(pads allowed)
			(copperpour not_allowed)
			(footprints allowed)
		)
		(placement
			(enabled no)
			(sheetname "")
		)
		(fill yes
			(thermal_gap 0.5)
			(thermal_bridge_width 0.5)
			(island_removal_mode 0)
		)
		(polygon
			(pts
				(arc
					(start 145.860516 -404.46452)
					(mid 145.192496 -404.46452)
					(end 145.860516 -404.46452)
				)
			)
		)
	)
	(zone
		(layers "B.Cu" "In6.Cu" "In11.Cu" "In13.Cu" "In15.Cu")
		(hatch none 0.5)
		(connect_pads
			(clearance 0)
		)
		(min_thickness 0.25)
		(keepout
			(tracks not_allowed)
			(vias allowed)
			(pads allowed)
			(copperpour not_allowed)
			(footprints allowed)
		)
		(placement
			(enabled no)
			(sheetname "")
		)
		(fill yes
			(thermal_gap 0.5)
			(thermal_bridge_width 0.5)
			(island_removal_mode 0)
		)
		(polygon
			(pts
				(arc
					(start 351.876106 -287.856168)
					(mid 351.246186 -287.856168)
					(end 351.876106 -287.856168)
				)
			)
		)
	)
	(zone
		(layers "B.Cu" "In6.Cu" "In11.Cu" "In13.Cu" "In15.Cu")
		(hatch none 0.5)
		(connect_pads
			(clearance 0)
		)
		(min_thickness 0.25)
		(keepout
			(tracks not_allowed)
			(vias allowed)
			(pads allowed)
			(copperpour not_allowed)
			(footprints allowed)
		)
		(placement
			(enabled no)
			(sheetname "")
		)
		(fill yes
			(thermal_gap 0.5)
			(thermal_bridge_width 0.5)
			(island_removal_mode 0)
		)
		(polygon
			(pts
				(arc
					(start 33.029906 -306.985416)
					(mid 32.361886 -306.985416)
					(end 33.029906 -306.985416)
				)
			)
		)
	)
	(zone
		(layers "B.Cu" "In6.Cu" "In11.Cu" "In13.Cu" "In15.Cu")
		(hatch none 0.5)
		(connect_pads
			(clearance 0)
		)
		(min_thickness 0.25)
		(keepout
			(tracks not_allowed)
			(vias allowed)
			(pads allowed)
			(copperpour not_allowed)
			(footprints allowed)
		)
		(placement
			(enabled no)
			(sheetname "")
		)
		(fill yes
			(thermal_gap 0.5)
			(thermal_bridge_width 0.5)
			(island_removal_mode 0)
		)
		(polygon
			(pts
				(arc
					(start 377.206256 -393.69238)
					(mid 376.576336 -393.69238)
					(end 377.206256 -393.69238)
				)
			)
		)
	)
	(zone
		(layers "B.Cu" "In6.Cu" "In11.Cu" "In13.Cu" "In15.Cu")
		(hatch none 0.5)
		(connect_pads
			(clearance 0)
		)
		(min_thickness 0.25)
		(keepout
			(tracks not_allowed)
			(vias allowed)
			(pads allowed)
			(copperpour not_allowed)
			(footprints allowed)
		)
		(placement
			(enabled no)
			(sheetname "")
		)
		(fill yes
			(thermal_gap 0.5)
			(thermal_bridge_width 0.5)
			(island_removal_mode 0)
		)
		(polygon
			(pts
				(arc
					(start 412.718758 -17.613122)
					(mid 412.050738 -17.613122)
					(end 412.718758 -17.613122)
				)
			)
		)
	)
	(zone
		(layers "B.Cu" "In6.Cu" "In11.Cu" "In13.Cu" "In15.Cu")
		(hatch none 0.5)
		(connect_pads
			(clearance 0)
		)
		(min_thickness 0.25)
		(keepout
			(tracks not_allowed)
			(vias allowed)
			(pads allowed)
			(copperpour not_allowed)
			(footprints allowed)
		)
		(placement
			(enabled no)
			(sheetname "")
		)
		(fill yes
			(thermal_gap 0.5)
			(thermal_bridge_width 0.5)
			(island_removal_mode 0)
		)
		(polygon
			(pts
				(arc
					(start 370.66982 -287.856168)
					(mid 370.0399 -287.856168)
					(end 370.66982 -287.856168)
				)
			)
		)
	)
	(zone
		(layers "B.Cu" "In6.Cu" "In11.Cu" "In13.Cu" "In15.Cu")
		(hatch none 0.5)
		(connect_pads
			(clearance 0)
		)
		(min_thickness 0.25)
		(keepout
			(tracks not_allowed)
			(vias allowed)
			(pads allowed)
			(copperpour not_allowed)
			(footprints allowed)
		)
		(placement
			(enabled no)
			(sheetname "")
		)
		(fill yes
			(thermal_gap 0.5)
			(thermal_bridge_width 0.5)
			(island_removal_mode 0)
		)
		(polygon
			(pts
				(arc
					(start 191.494156 -311.235344)
					(mid 190.826136 -311.235344)
					(end 191.494156 -311.235344)
				)
			)
		)
	)
	(zone
		(layers "B.Cu" "In6.Cu" "In11.Cu" "In13.Cu" "In15.Cu")
		(hatch none 0.5)
		(connect_pads
			(clearance 0)
		)
		(min_thickness 0.25)
		(keepout
			(tracks not_allowed)
			(vias allowed)
			(pads allowed)
			(copperpour not_allowed)
			(footprints allowed)
		)
		(placement
			(enabled no)
			(sheetname "")
		)
		(fill yes
			(thermal_gap 0.5)
			(thermal_bridge_width 0.5)
			(island_removal_mode 0)
		)
		(polygon
			(pts
				(arc
					(start 370.66982 -289.475926)
					(mid 370.0399 -289.475926)
					(end 370.66982 -289.475926)
				)
			)
		)
	)
	(zone
		(layers "B.Cu" "In6.Cu" "In11.Cu" "In13.Cu" "In15.Cu")
		(hatch none 0.5)
		(connect_pads
			(clearance 0)
		)
		(min_thickness 0.25)
		(keepout
			(tracks not_allowed)
			(vias allowed)
			(pads allowed)
			(copperpour not_allowed)
			(footprints allowed)
		)
		(placement
			(enabled no)
			(sheetname "")
		)
		(fill yes
			(thermal_gap 0.5)
			(thermal_bridge_width 0.5)
			(island_removal_mode 0)
		)
		(polygon
			(pts
				(arc
					(start 381.179832 -227.474272)
					(mid 380.549912 -227.474272)
					(end 381.179832 -227.474272)
				)
			)
		)
	)
	(zone
		(layers "B.Cu" "In6.Cu" "In11.Cu" "In13.Cu" "In15.Cu")
		(hatch none 0.5)
		(connect_pads
			(clearance 0)
		)
		(min_thickness 0.25)
		(keepout
			(tracks not_allowed)
			(vias allowed)
			(pads allowed)
			(copperpour not_allowed)
			(footprints allowed)
		)
		(placement
			(enabled no)
			(sheetname "")
		)
		(fill yes
			(thermal_gap 0.5)
			(thermal_bridge_width 0.5)
			(island_removal_mode 0)
		)
		(polygon
			(pts
				(arc
					(start 92.655898 -291.096192)
					(mid 92.025978 -291.096192)
					(end 92.655898 -291.096192)
				)
			)
		)
	)
	(zone
		(layers "B.Cu" "In6.Cu" "In11.Cu" "In13.Cu" "In15.Cu")
		(hatch none 0.5)
		(connect_pads
			(clearance 0)
		)
		(min_thickness 0.25)
		(keepout
			(tracks not_allowed)
			(vias allowed)
			(pads allowed)
			(copperpour not_allowed)
			(footprints allowed)
		)
		(placement
			(enabled no)
			(sheetname "")
		)
		(fill yes
			(thermal_gap 0.5)
			(thermal_bridge_width 0.5)
			(island_removal_mode 0)
		)
		(polygon
			(pts
				(arc
					(start 93.126052 -277.326344)
					(mid 92.496132 -277.326344)
					(end 93.126052 -277.326344)
				)
			)
		)
	)
	(zone
		(layers "B.Cu" "In6.Cu" "In11.Cu" "In13.Cu" "In15.Cu")
		(hatch none 0.5)
		(connect_pads
			(clearance 0)
		)
		(min_thickness 0.25)
		(keepout
			(tracks not_allowed)
			(vias allowed)
			(pads allowed)
			(copperpour not_allowed)
			(footprints allowed)
		)
		(placement
			(enabled no)
			(sheetname "")
		)
		(fill yes
			(thermal_gap 0.5)
			(thermal_bridge_width 0.5)
			(island_removal_mode 0)
		)
		(polygon
			(pts
				(arc
					(start 340.595966 -274.896072)
					(mid 339.966046 -274.896072)
					(end 340.595966 -274.896072)
				)
			)
		)
	)
	(zone
		(layers "B.Cu" "In6.Cu" "In11.Cu" "In13.Cu" "In15.Cu")
		(hatch none 0.5)
		(connect_pads
			(clearance 0)
		)
		(min_thickness 0.25)
		(keepout
			(tracks not_allowed)
			(vias allowed)
			(pads allowed)
			(copperpour not_allowed)
			(footprints allowed)
		)
		(placement
			(enabled no)
			(sheetname "")
		)
		(fill yes
			(thermal_gap 0.5)
			(thermal_bridge_width 0.5)
			(island_removal_mode 0)
		)
		(polygon
			(pts
				(arc
					(start 92.826078 -245.294404)
					(mid 92.196158 -245.294404)
					(end 92.826078 -245.294404)
				)
			)
		)
	)
	(zone
		(layers "B.Cu" "In6.Cu" "In11.Cu" "In13.Cu" "In15.Cu")
		(hatch none 0.5)
		(connect_pads
			(clearance 0)
		)
		(min_thickness 0.25)
		(keepout
			(tracks not_allowed)
			(vias allowed)
			(pads allowed)
			(copperpour not_allowed)
			(footprints allowed)
		)
		(placement
			(enabled no)
			(sheetname "")
		)
		(fill yes
			(thermal_gap 0.5)
			(thermal_bridge_width 0.5)
			(island_removal_mode 0)
		)
		(polygon
			(pts
				(arc
					(start 285.070042 -212.635084)
					(mid 284.402022 -212.635084)
					(end 285.070042 -212.635084)
				)
			)
		)
	)
	(zone
		(layers "B.Cu" "In6.Cu" "In11.Cu" "In13.Cu" "In15.Cu")
		(hatch none 0.5)
		(connect_pads
			(clearance 0)
		)
		(min_thickness 0.25)
		(keepout
			(tracks not_allowed)
			(vias allowed)
			(pads allowed)
			(copperpour not_allowed)
			(footprints allowed)
		)
		(placement
			(enabled no)
			(sheetname "")
		)
		(fill yes
			(thermal_gap 0.5)
			(thermal_bridge_width 0.5)
			(island_removal_mode 0)
		)
		(polygon
			(pts
				(arc
					(start 419.333934 -397.156432)
					(mid 418.704014 -397.156432)
					(end 419.333934 -397.156432)
				)
			)
		)
	)
	(zone
		(layers "B.Cu" "In6.Cu" "In11.Cu" "In13.Cu" "In15.Cu")
		(hatch none 0.5)
		(connect_pads
			(clearance 0)
		)
		(min_thickness 0.25)
		(keepout
			(tracks not_allowed)
			(vias allowed)
			(pads allowed)
			(copperpour not_allowed)
			(footprints allowed)
		)
		(placement
			(enabled no)
			(sheetname "")
		)
		(fill yes
			(thermal_gap 0.5)
			(thermal_bridge_width 0.5)
			(island_removal_mode 0)
		)
		(polygon
			(pts
				(arc
					(start 338.886038 -238.814102)
					(mid 338.256118 -238.814102)
					(end 338.886038 -238.814102)
				)
			)
		)
	)
	(zone
		(layers "B.Cu" "In6.Cu" "In11.Cu" "In13.Cu" "In15.Cu")
		(hatch none 0.5)
		(connect_pads
			(clearance 0)
		)
		(min_thickness 0.25)
		(keepout
			(tracks not_allowed)
			(vias allowed)
			(pads allowed)
			(copperpour not_allowed)
			(footprints allowed)
		)
		(placement
			(enabled no)
			(sheetname "")
		)
		(fill yes
			(thermal_gap 0.5)
			(thermal_bridge_width 0.5)
			(island_removal_mode 0)
		)
		(polygon
			(pts
				(arc
					(start 374.129808 -233.14406)
					(mid 373.499888 -233.14406)
					(end 374.129808 -233.14406)
				)
			)
		)
	)
	(zone
		(layers "B.Cu" "In6.Cu" "In11.Cu" "In13.Cu" "In15.Cu")
		(hatch none 0.5)
		(connect_pads
			(clearance 0)
		)
		(min_thickness 0.25)
		(keepout
			(tracks not_allowed)
			(vias allowed)
			(pads allowed)
			(copperpour not_allowed)
			(footprints allowed)
		)
		(placement
			(enabled no)
			(sheetname "")
		)
		(fill yes
			(thermal_gap 0.5)
			(thermal_bridge_width 0.5)
			(island_removal_mode 0)
		)
		(polygon
			(pts
				(arc
					(start 162.134042 -388.774432)
					(mid 161.504122 -388.774432)
					(end 162.134042 -388.774432)
				)
			)
		)
	)
	(zone
		(layers "B.Cu" "In6.Cu" "In11.Cu" "In13.Cu" "In15.Cu")
		(hatch none 0.5)
		(connect_pads
			(clearance 0)
		)
		(min_thickness 0.25)
		(keepout
			(tracks not_allowed)
			(vias allowed)
			(pads allowed)
			(copperpour not_allowed)
			(footprints allowed)
		)
		(placement
			(enabled no)
			(sheetname "")
		)
		(fill yes
			(thermal_gap 0.5)
			(thermal_bridge_width 0.5)
			(island_removal_mode 0)
		)
		(polygon
			(pts
				(arc
					(start 339.656166 -279.756108)
					(mid 339.026246 -279.756108)
					(end 339.656166 -279.756108)
				)
			)
		)
	)
	(zone
		(layers "B.Cu" "In6.Cu" "In11.Cu" "In13.Cu" "In15.Cu")
		(hatch none 0.5)
		(connect_pads
			(clearance 0)
		)
		(min_thickness 0.25)
		(keepout
			(tracks not_allowed)
			(vias allowed)
			(pads allowed)
			(copperpour not_allowed)
			(footprints allowed)
		)
		(placement
			(enabled no)
			(sheetname "")
		)
		(fill yes
			(thermal_gap 0.5)
			(thermal_bridge_width 0.5)
			(island_removal_mode 0)
		)
		(polygon
			(pts
				(arc
					(start 187.394088 -248.335292)
					(mid 186.726068 -248.335292)
					(end 187.394088 -248.335292)
				)
			)
		)
	)
	(zone
		(layers "B.Cu" "In6.Cu" "In11.Cu" "In13.Cu" "In15.Cu")
		(hatch none 0.5)
		(connect_pads
			(clearance 0)
		)
		(min_thickness 0.25)
		(keepout
			(tracks not_allowed)
			(vias allowed)
			(pads allowed)
			(copperpour not_allowed)
			(footprints allowed)
		)
		(placement
			(enabled no)
			(sheetname "")
		)
		(fill yes
			(thermal_gap 0.5)
			(thermal_bridge_width 0.5)
			(island_removal_mode 0)
		)
		(polygon
			(pts
				(arc
					(start 91.41587 -244.484398)
					(mid 90.78595 -244.484398)
					(end 91.41587 -244.484398)
				)
			)
		)
	)
	(zone
		(layers "B.Cu" "In6.Cu" "In11.Cu" "In13.Cu" "In15.Cu")
		(hatch none 0.5)
		(connect_pads
			(clearance 0)
		)
		(min_thickness 0.25)
		(keepout
			(tracks not_allowed)
			(vias allowed)
			(pads allowed)
			(copperpour not_allowed)
			(footprints allowed)
		)
		(placement
			(enabled no)
			(sheetname "")
		)
		(fill yes
			(thermal_gap 0.5)
			(thermal_bridge_width 0.5)
			(island_removal_mode 0)
		)
		(polygon
			(pts
				(arc
					(start 91.245944 -264.366248)
					(mid 90.616024 -264.366248)
					(end 91.245944 -264.366248)
				)
			)
		)
	)
	(zone
		(layers "B.Cu" "In6.Cu" "In11.Cu" "In13.Cu" "In15.Cu")
		(hatch none 0.5)
		(connect_pads
			(clearance 0)
		)
		(min_thickness 0.25)
		(keepout
			(tracks not_allowed)
			(vias allowed)
			(pads allowed)
			(copperpour not_allowed)
			(footprints allowed)
		)
		(placement
			(enabled no)
			(sheetname "")
		)
		(fill yes
			(thermal_gap 0.5)
			(thermal_bridge_width 0.5)
			(island_removal_mode 0)
		)
		(polygon
			(pts
				(arc
					(start 126.18974 -228.284532)
					(mid 125.55982 -228.284532)
					(end 126.18974 -228.284532)
				)
			)
		)
	)
	(zone
		(layers "B.Cu" "In6.Cu" "In11.Cu" "In13.Cu" "In15.Cu")
		(hatch none 0.5)
		(connect_pads
			(clearance 0)
		)
		(min_thickness 0.25)
		(keepout
			(tracks not_allowed)
			(vias allowed)
			(pads allowed)
			(copperpour not_allowed)
			(footprints allowed)
		)
		(placement
			(enabled no)
			(sheetname "")
		)
		(fill yes
			(thermal_gap 0.5)
			(thermal_bridge_width 0.5)
			(island_removal_mode 0)
		)
		(polygon
			(pts
				(arc
					(start 410.789374 -19.13636)
					(mid 410.121354 -19.13636)
					(end 410.789374 -19.13636)
				)
			)
		)
	)
	(zone
		(layers "B.Cu" "In6.Cu" "In11.Cu" "In13.Cu" "In15.Cu")
		(hatch none 0.5)
		(connect_pads
			(clearance 0)
		)
		(min_thickness 0.25)
		(keepout
			(tracks not_allowed)
			(vias allowed)
			(pads allowed)
			(copperpour not_allowed)
			(footprints allowed)
		)
		(placement
			(enabled no)
			(sheetname "")
		)
		(fill yes
			(thermal_gap 0.5)
			(thermal_bridge_width 0.5)
			(island_removal_mode 0)
		)
		(polygon
			(pts
				(arc
					(start 187.394088 -216.885266)
					(mid 186.726068 -216.885266)
					(end 187.394088 -216.885266)
				)
			)
		)
	)
	(zone
		(layers "B.Cu" "In6.Cu" "In11.Cu" "In13.Cu" "In15.Cu")
		(hatch none 0.5)
		(connect_pads
			(clearance 0)
		)
		(min_thickness 0.25)
		(keepout
			(tracks not_allowed)
			(vias allowed)
			(pads allowed)
			(copperpour not_allowed)
			(footprints allowed)
		)
		(placement
			(enabled no)
			(sheetname "")
		)
		(fill yes
			(thermal_gap 0.5)
			(thermal_bridge_width 0.5)
			(island_removal_mode 0)
		)
		(polygon
			(pts
				(arc
					(start 380.709678 -234.764072)
					(mid 380.079758 -234.764072)
					(end 380.709678 -234.764072)
				)
			)
		)
	)
	(zone
		(layers "B.Cu" "In6.Cu" "In11.Cu" "In13.Cu" "In15.Cu")
		(hatch none 0.5)
		(connect_pads
			(clearance 0)
		)
		(min_thickness 0.25)
		(keepout
			(tracks not_allowed)
			(vias allowed)
			(pads allowed)
			(copperpour not_allowed)
			(footprints allowed)
		)
		(placement
			(enabled no)
			(sheetname "")
		)
		(fill yes
			(thermal_gap 0.5)
			(thermal_bridge_width 0.5)
			(island_removal_mode 0)
		)
		(polygon
			(pts
				(arc
					(start 380.709678 -252.584204)
					(mid 380.079758 -252.584204)
					(end 380.709678 -252.584204)
				)
			)
		)
	)
	(zone
		(layers "B.Cu" "In6.Cu" "In11.Cu" "In13.Cu" "In15.Cu")
		(hatch none 0.5)
		(connect_pads
			(clearance 0)
		)
		(min_thickness 0.25)
		(keepout
			(tracks not_allowed)
			(vias allowed)
			(pads allowed)
			(copperpour not_allowed)
			(footprints allowed)
		)
		(placement
			(enabled no)
			(sheetname "")
		)
		(fill yes
			(thermal_gap 0.5)
			(thermal_bridge_width 0.5)
			(island_removal_mode 0)
		)
		(polygon
			(pts
				(arc
					(start 435.334156 -224.534984)
					(mid 434.666136 -224.534984)
					(end 435.334156 -224.534984)
				)
			)
		)
	)
	(zone
		(layers "B.Cu" "In6.Cu" "In11.Cu" "In13.Cu" "In15.Cu")
		(hatch none 0.5)
		(connect_pads
			(clearance 0)
		)
		(min_thickness 0.25)
		(keepout
			(tracks not_allowed)
			(vias allowed)
			(pads allowed)
			(copperpour not_allowed)
			(footprints allowed)
		)
		(placement
			(enabled no)
			(sheetname "")
		)
		(fill yes
			(thermal_gap 0.5)
			(thermal_bridge_width 0.5)
			(island_removal_mode 0)
		)
		(polygon
			(pts
				(arc
					(start 414.113472 -412.84652)
					(mid 413.445452 -412.84652)
					(end 414.113472 -412.84652)
				)
			)
		)
	)
	(zone
		(layers "B.Cu" "In6.Cu" "In11.Cu" "In13.Cu" "In15.Cu")
		(hatch none 0.5)
		(connect_pads
			(clearance 0)
		)
		(min_thickness 0.25)
		(keepout
			(tracks not_allowed)
			(vias allowed)
			(pads allowed)
			(copperpour not_allowed)
			(footprints allowed)
		)
		(placement
			(enabled no)
			(sheetname "")
		)
		(fill yes
			(thermal_gap 0.5)
			(thermal_bridge_width 0.5)
			(island_removal_mode 0)
		)
		(polygon
			(pts
				(arc
					(start 33.029906 -241.535204)
					(mid 32.361886 -241.535204)
					(end 33.029906 -241.535204)
				)
			)
		)
	)
	(zone
		(layers "B.Cu" "In6.Cu" "In11.Cu" "In13.Cu" "In15.Cu")
		(hatch none 0.5)
		(connect_pads
			(clearance 0)
		)
		(min_thickness 0.25)
		(keepout
			(tracks not_allowed)
			(vias allowed)
			(pads allowed)
			(copperpour not_allowed)
			(footprints allowed)
		)
		(placement
			(enabled no)
			(sheetname "")
		)
		(fill yes
			(thermal_gap 0.5)
			(thermal_bridge_width 0.5)
			(island_removal_mode 0)
		)
		(polygon
			(pts
				(arc
					(start 280.969974 -301.034958)
					(mid 280.301954 -301.034958)
					(end 280.969974 -301.034958)
				)
			)
		)
	)
	(zone
		(layers "B.Cu" "In6.Cu" "In11.Cu" "In13.Cu" "In15.Cu")
		(hatch none 0.5)
		(connect_pads
			(clearance 0)
		)
		(min_thickness 0.25)
		(keepout
			(tracks not_allowed)
			(vias allowed)
			(pads allowed)
			(copperpour not_allowed)
			(footprints allowed)
		)
		(placement
			(enabled no)
			(sheetname "")
		)
		(fill yes
			(thermal_gap 0.5)
			(thermal_bridge_width 0.5)
			(island_removal_mode 0)
		)
		(polygon
			(pts
				(arc
					(start 374.429782 -289.475926)
					(mid 373.799862 -289.475926)
					(end 374.429782 -289.475926)
				)
			)
		)
	)
	(zone
		(layers "B.Cu" "In6.Cu" "In11.Cu" "In13.Cu" "In15.Cu")
		(hatch none 0.5)
		(connect_pads
			(clearance 0)
		)
		(min_thickness 0.25)
		(keepout
			(tracks not_allowed)
			(vias allowed)
			(pads allowed)
			(copperpour not_allowed)
			(footprints allowed)
		)
		(placement
			(enabled no)
			(sheetname "")
		)
		(fill yes
			(thermal_gap 0.5)
			(thermal_bridge_width 0.5)
			(island_removal_mode 0)
		)
		(polygon
			(pts
				(arc
					(start 285.070042 -272.135092)
					(mid 284.402022 -272.135092)
					(end 285.070042 -272.135092)
				)
			)
		)
	)
	(zone
		(layers "B.Cu" "In6.Cu" "In11.Cu" "In13.Cu" "In15.Cu")
		(hatch none 0.5)
		(connect_pads
			(clearance 0)
		)
		(min_thickness 0.25)
		(keepout
			(tracks not_allowed)
			(vias allowed)
			(pads allowed)
			(copperpour not_allowed)
			(footprints allowed)
		)
		(placement
			(enabled no)
			(sheetname "")
		)
		(fill yes
			(thermal_gap 0.5)
			(thermal_bridge_width 0.5)
			(island_removal_mode 0)
		)
		(polygon
			(pts
				(arc
					(start 347.876876 -412.84652)
					(mid 347.208856 -412.84652)
					(end 347.876876 -412.84652)
				)
			)
		)
	)
	(zone
		(layers "B.Cu" "In6.Cu" "In11.Cu" "In13.Cu" "In15.Cu")
		(hatch none 0.5)
		(connect_pads
			(clearance 0)
		)
		(min_thickness 0.25)
		(keepout
			(tracks not_allowed)
			(vias allowed)
			(pads allowed)
			(copperpour not_allowed)
			(footprints allowed)
		)
		(placement
			(enabled no)
			(sheetname "")
		)
		(fill yes
			(thermal_gap 0.5)
			(thermal_bridge_width 0.5)
			(island_removal_mode 0)
		)
		(polygon
			(pts
				(arc
					(start 435.334156 -237.285022)
					(mid 434.666136 -237.285022)
					(end 435.334156 -237.285022)
				)
			)
		)
	)
	(zone
		(layers "B.Cu" "In6.Cu" "In11.Cu" "In13.Cu" "In15.Cu")
		(hatch none 0.5)
		(connect_pads
			(clearance 0)
		)
		(min_thickness 0.25)
		(keepout
			(tracks not_allowed)
			(vias allowed)
			(pads allowed)
			(copperpour not_allowed)
			(footprints allowed)
		)
		(placement
			(enabled no)
			(sheetname "")
		)
		(fill yes
			(thermal_gap 0.5)
			(thermal_bridge_width 0.5)
			(island_removal_mode 0)
		)
		(polygon
			(pts
				(arc
					(start 318.90589 -397.849344)
					(mid 318.27597 -397.849344)
					(end 318.90589 -397.849344)
				)
			)
		)
	)
	(zone
		(layers "B.Cu" "In6.Cu" "In11.Cu" "In13.Cu" "In15.Cu")
		(hatch none 0.5)
		(connect_pads
			(clearance 0)
		)
		(min_thickness 0.25)
		(keepout
			(tracks not_allowed)
			(vias allowed)
			(pads allowed)
			(copperpour not_allowed)
			(footprints allowed)
		)
		(placement
			(enabled no)
			(sheetname "")
		)
		(fill yes
			(thermal_gap 0.5)
			(thermal_bridge_width 0.5)
			(island_removal_mode 0)
		)
		(polygon
			(pts
				(arc
					(start 341.06612 -285.42615)
					(mid 340.4362 -285.42615)
					(end 341.06612 -285.42615)
				)
			)
		)
	)
	(zone
		(layers "B.Cu" "In6.Cu" "In11.Cu" "In13.Cu" "In15.Cu")
		(hatch none 0.5)
		(connect_pads
			(clearance 0)
		)
		(min_thickness 0.25)
		(keepout
			(tracks not_allowed)
			(vias allowed)
			(pads allowed)
			(copperpour not_allowed)
			(footprints allowed)
		)
		(placement
			(enabled no)
			(sheetname "")
		)
		(fill yes
			(thermal_gap 0.5)
			(thermal_bridge_width 0.5)
			(island_removal_mode 0)
		)
		(polygon
			(pts
				(arc
					(start 93.126052 -270.846296)
					(mid 92.496132 -270.846296)
					(end 93.126052 -270.846296)
				)
			)
		)
	)
	(zone
		(layers "B.Cu" "In6.Cu" "In11.Cu" "In13.Cu" "In15.Cu")
		(hatch none 0.5)
		(connect_pads
			(clearance 0)
		)
		(min_thickness 0.25)
		(keepout
			(tracks not_allowed)
			(vias allowed)
			(pads allowed)
			(copperpour not_allowed)
			(footprints allowed)
		)
		(placement
			(enabled no)
			(sheetname "")
		)
		(fill yes
			(thermal_gap 0.5)
			(thermal_bridge_width 0.5)
			(island_removal_mode 0)
		)
		(polygon
			(pts
				(arc
					(start 363.319822 -233.954066)
					(mid 362.689902 -233.954066)
					(end 363.319822 -233.954066)
				)
			)
		)
	)
	(zone
		(layers "B.Cu" "In6.Cu" "In11.Cu" "In13.Cu" "In15.Cu")
		(hatch none 0.5)
		(connect_pads
			(clearance 0)
		)
		(min_thickness 0.25)
		(keepout
			(tracks not_allowed)
			(vias allowed)
			(pads allowed)
			(copperpour not_allowed)
			(footprints allowed)
		)
		(placement
			(enabled no)
			(sheetname "")
		)
		(fill yes
			(thermal_gap 0.5)
			(thermal_bridge_width 0.5)
			(island_removal_mode 0)
		)
		(polygon
			(pts
				(arc
					(start 133.239764 -253.394464)
					(mid 132.609844 -253.394464)
					(end 133.239764 -253.394464)
				)
			)
		)
	)
	(zone
		(layers "B.Cu" "In6.Cu" "In11.Cu" "In13.Cu" "In15.Cu")
		(hatch none 0.5)
		(connect_pads
			(clearance 0)
		)
		(min_thickness 0.25)
		(keepout
			(tracks not_allowed)
			(vias allowed)
			(pads allowed)
			(copperpour not_allowed)
			(footprints allowed)
		)
		(placement
			(enabled no)
			(sheetname "")
		)
		(fill yes
			(thermal_gap 0.5)
			(thermal_bridge_width 0.5)
			(island_removal_mode 0)
		)
		(polygon
			(pts
				(arc
					(start 280.969974 -289.985196)
					(mid 280.301954 -289.985196)
					(end 280.969974 -289.985196)
				)
			)
		)
	)
	(zone
		(layers "B.Cu" "In6.Cu" "In11.Cu" "In13.Cu" "In15.Cu")
		(hatch none 0.5)
		(connect_pads
			(clearance 0)
		)
		(min_thickness 0.25)
		(keepout
			(tracks not_allowed)
			(vias allowed)
			(pads allowed)
			(copperpour not_allowed)
			(footprints allowed)
		)
		(placement
			(enabled no)
			(sheetname "")
		)
		(fill yes
			(thermal_gap 0.5)
			(thermal_bridge_width 0.5)
			(island_removal_mode 0)
		)
		(polygon
			(pts
				(arc
					(start 354.000054 -377.41733)
					(mid 353.332034 -377.41733)
					(end 354.000054 -377.41733)
				)
			)
		)
	)
	(zone
		(layers "B.Cu" "In6.Cu" "In11.Cu" "In13.Cu" "In15.Cu")
		(hatch none 0.5)
		(connect_pads
			(clearance 0)
		)
		(min_thickness 0.25)
		(keepout
			(tracks not_allowed)
			(vias allowed)
			(pads allowed)
			(copperpour not_allowed)
			(footprints allowed)
		)
		(placement
			(enabled no)
			(sheetname "")
		)
		(fill yes
			(thermal_gap 0.5)
			(thermal_bridge_width 0.5)
			(island_removal_mode 0)
		)
		(polygon
			(pts
				(arc
					(start 379.769878 -249.34418)
					(mid 379.139958 -249.34418)
					(end 379.769878 -249.34418)
				)
			)
		)
	)
	(zone
		(layers "B.Cu" "In6.Cu" "In11.Cu" "In13.Cu" "In15.Cu")
		(hatch none 0.5)
		(connect_pads
			(clearance 0)
		)
		(min_thickness 0.25)
		(keepout
			(tracks not_allowed)
			(vias allowed)
			(pads allowed)
			(copperpour not_allowed)
			(footprints allowed)
		)
		(placement
			(enabled no)
			(sheetname "")
		)
		(fill yes
			(thermal_gap 0.5)
			(thermal_bridge_width 0.5)
			(island_removal_mode 0)
		)
		(polygon
			(pts
				(arc
					(start 91.41587 -231.524302)
					(mid 90.78595 -231.524302)
					(end 91.41587 -231.524302)
				)
			)
		)
	)
	(zone
		(layers "B.Cu" "In6.Cu" "In11.Cu" "In13.Cu" "In15.Cu")
		(hatch none 0.5)
		(connect_pads
			(clearance 0)
		)
		(min_thickness 0.25)
		(keepout
			(tracks not_allowed)
			(vias allowed)
			(pads allowed)
			(copperpour not_allowed)
			(footprints allowed)
		)
		(placement
			(enabled no)
			(sheetname "")
		)
		(fill yes
			(thermal_gap 0.5)
			(thermal_bridge_width 0.5)
			(island_removal_mode 0)
		)
		(polygon
			(pts
				(arc
					(start 187.394088 -235.585254)
					(mid 186.726068 -235.585254)
					(end 187.394088 -235.585254)
				)
			)
		)
	)
	(zone
		(layers "B.Cu" "In6.Cu" "In11.Cu" "In13.Cu" "In15.Cu")
		(hatch none 0.5)
		(connect_pads
			(clearance 0)
		)
		(min_thickness 0.25)
		(keepout
			(tracks not_allowed)
			(vias allowed)
			(pads allowed)
			(copperpour not_allowed)
			(footprints allowed)
		)
		(placement
			(enabled no)
			(sheetname "")
		)
		(fill yes
			(thermal_gap 0.5)
			(thermal_bridge_width 0.5)
			(island_removal_mode 0)
		)
		(polygon
			(pts
				(arc
					(start 104.876092 -287.856422)
					(mid 104.246172 -287.856422)
					(end 104.876092 -287.856422)
				)
			)
		)
	)
	(zone
		(layers "B.Cu" "In6.Cu" "In11.Cu" "In13.Cu" "In15.Cu")
		(hatch none 0.5)
		(connect_pads
			(clearance 0)
		)
		(min_thickness 0.25)
		(keepout
			(tracks not_allowed)
			(vias allowed)
			(pads allowed)
			(copperpour not_allowed)
			(footprints allowed)
		)
		(placement
			(enabled no)
			(sheetname "")
		)
		(fill yes
			(thermal_gap 0.5)
			(thermal_bridge_width 0.5)
			(island_removal_mode 0)
		)
		(polygon
			(pts
				(arc
					(start 439.434224 -307.835046)
					(mid 438.766204 -307.835046)
					(end 439.434224 -307.835046)
				)
			)
		)
	)
	(zone
		(layers "B.Cu" "In6.Cu" "In11.Cu" "In13.Cu" "In15.Cu")
		(hatch none 0.5)
		(connect_pads
			(clearance 0)
		)
		(min_thickness 0.25)
		(keepout
			(tracks not_allowed)
			(vias allowed)
			(pads allowed)
			(copperpour not_allowed)
			(footprints allowed)
		)
		(placement
			(enabled no)
			(sheetname "")
		)
		(fill yes
			(thermal_gap 0.5)
			(thermal_bridge_width 0.5)
			(island_removal_mode 0)
		)
		(polygon
			(pts
				(arc
					(start 92.355924 -250.964446)
					(mid 91.726004 -250.964446)
					(end 92.355924 -250.964446)
				)
			)
		)
	)
	(zone
		(layers "B.Cu" "In6.Cu" "In11.Cu" "In13.Cu" "In15.Cu")
		(hatch none 0.5)
		(connect_pads
			(clearance 0)
		)
		(min_thickness 0.25)
		(keepout
			(tracks not_allowed)
			(vias allowed)
			(pads allowed)
			(copperpour not_allowed)
			(footprints allowed)
		)
		(placement
			(enabled no)
			(sheetname "")
		)
		(fill yes
			(thermal_gap 0.5)
			(thermal_bridge_width 0.5)
			(island_removal_mode 0)
		)
		(polygon
			(pts
				(arc
					(start 384.344672 -412.84652)
					(mid 383.676652 -412.84652)
					(end 384.344672 -412.84652)
				)
			)
		)
	)
	(zone
		(layers "B.Cu" "In6.Cu" "In11.Cu" "In13.Cu" "In15.Cu")
		(hatch none 0.5)
		(connect_pads
			(clearance 0)
		)
		(min_thickness 0.25)
		(keepout
			(tracks not_allowed)
			(vias allowed)
			(pads allowed)
			(copperpour not_allowed)
			(footprints allowed)
		)
		(placement
			(enabled no)
			(sheetname "")
		)
		(fill yes
			(thermal_gap 0.5)
			(thermal_bridge_width 0.5)
			(island_removal_mode 0)
		)
		(polygon
			(pts
				(arc
					(start 380.709678 -225.044254)
					(mid 380.079758 -225.044254)
					(end 380.709678 -225.044254)
				)
			)
		)
	)
	(zone
		(layers "B.Cu" "In6.Cu" "In11.Cu" "In13.Cu" "In15.Cu")
		(hatch none 0.5)
		(connect_pads
			(clearance 0)
		)
		(min_thickness 0.25)
		(keepout
			(tracks not_allowed)
			(vias allowed)
			(pads allowed)
			(copperpour not_allowed)
			(footprints allowed)
		)
		(placement
			(enabled no)
			(sheetname "")
		)
		(fill yes
			(thermal_gap 0.5)
			(thermal_bridge_width 0.5)
			(island_removal_mode 0)
		)
		(polygon
			(pts
				(arc
					(start 93.126052 -264.366248)
					(mid 92.496132 -264.366248)
					(end 93.126052 -264.366248)
				)
			)
		)
	)
	(zone
		(layers "B.Cu" "In6.Cu" "In11.Cu" "In13.Cu" "In15.Cu")
		(hatch none 0.5)
		(connect_pads
			(clearance 0)
		)
		(min_thickness 0.25)
		(keepout
			(tracks not_allowed)
			(vias allowed)
			(pads allowed)
			(copperpour not_allowed)
			(footprints allowed)
		)
		(placement
			(enabled no)
			(sheetname "")
		)
		(fill yes
			(thermal_gap 0.5)
			(thermal_bridge_width 0.5)
			(island_removal_mode 0)
		)
		(polygon
			(pts
				(arc
					(start 131.359656 -242.05438)
					(mid 130.729736 -242.05438)
					(end 131.359656 -242.05438)
				)
			)
		)
	)
	(zone
		(layers "B.Cu" "In6.Cu" "In11.Cu" "In13.Cu" "In15.Cu")
		(hatch none 0.5)
		(connect_pads
			(clearance 0)
		)
		(min_thickness 0.25)
		(keepout
			(tracks not_allowed)
			(vias allowed)
			(pads allowed)
			(copperpour not_allowed)
			(footprints allowed)
		)
		(placement
			(enabled no)
			(sheetname "")
		)
		(fill yes
			(thermal_gap 0.5)
			(thermal_bridge_width 0.5)
			(island_removal_mode 0)
		)
		(polygon
			(pts
				(arc
					(start 33.029906 -237.285276)
					(mid 32.361886 -237.285276)
					(end 33.029906 -237.285276)
				)
			)
		)
	)
	(zone
		(layers "B.Cu" "In6.Cu" "In11.Cu" "In13.Cu" "In15.Cu")
		(hatch none 0.5)
		(connect_pads
			(clearance 0)
		)
		(min_thickness 0.25)
		(keepout
			(tracks not_allowed)
			(vias allowed)
			(pads allowed)
			(copperpour not_allowed)
			(footprints allowed)
		)
		(placement
			(enabled no)
			(sheetname "")
		)
		(fill yes
			(thermal_gap 0.5)
			(thermal_bridge_width 0.5)
			(island_removal_mode 0)
		)
		(polygon
			(pts
				(arc
					(start 439.434224 -312.935112)
					(mid 438.766204 -312.935112)
					(end 439.434224 -312.935112)
				)
			)
		)
	)
	(zone
		(layers "B.Cu" "In6.Cu" "In11.Cu" "In13.Cu" "In15.Cu")
		(hatch none 0.5)
		(connect_pads
			(clearance 0)
		)
		(min_thickness 0.25)
		(keepout
			(tracks not_allowed)
			(vias allowed)
			(pads allowed)
			(copperpour not_allowed)
			(footprints allowed)
		)
		(placement
			(enabled no)
			(sheetname "")
		)
		(fill yes
			(thermal_gap 0.5)
			(thermal_bridge_width 0.5)
			(island_removal_mode 0)
		)
		(polygon
			(pts
				(arc
					(start 341.06612 -262.745982)
					(mid 340.4362 -262.745982)
					(end 341.06612 -262.745982)
				)
			)
		)
	)
	(zone
		(layers "B.Cu" "In6.Cu" "In11.Cu" "In13.Cu" "In15.Cu")
		(hatch none 0.5)
		(connect_pads
			(clearance 0)
		)
		(min_thickness 0.25)
		(keepout
			(tracks not_allowed)
			(vias allowed)
			(pads allowed)
			(copperpour not_allowed)
			(footprints allowed)
		)
		(placement
			(enabled no)
			(sheetname "")
		)
		(fill yes
			(thermal_gap 0.5)
			(thermal_bridge_width 0.5)
			(island_removal_mode 0)
		)
		(polygon
			(pts
				(arc
					(start 285.070042 -210.935062)
					(mid 284.402022 -210.935062)
					(end 285.070042 -210.935062)
				)
			)
		)
	)
	(zone
		(layers "B.Cu" "In6.Cu" "In11.Cu" "In13.Cu" "In15.Cu")
		(hatch none 0.5)
		(connect_pads
			(clearance 0)
		)
		(min_thickness 0.25)
		(keepout
			(tracks not_allowed)
			(vias allowed)
			(pads allowed)
			(copperpour not_allowed)
			(footprints allowed)
		)
		(placement
			(enabled no)
			(sheetname "")
		)
		(fill yes
			(thermal_gap 0.5)
			(thermal_bridge_width 0.5)
			(island_removal_mode 0)
		)
		(polygon
			(pts
				(arc
					(start 91.41587 -234.764326)
					(mid 90.78595 -234.764326)
					(end 91.41587 -234.764326)
				)
			)
		)
	)
	(zone
		(layers "B.Cu" "In6.Cu" "In11.Cu" "In13.Cu" "In15.Cu")
		(hatch none 0.5)
		(connect_pads
			(clearance 0)
		)
		(min_thickness 0.25)
		(keepout
			(tracks not_allowed)
			(vias allowed)
			(pads allowed)
			(copperpour not_allowed)
			(footprints allowed)
		)
		(placement
			(enabled no)
			(sheetname "")
		)
		(fill yes
			(thermal_gap 0.5)
			(thermal_bridge_width 0.5)
			(island_removal_mode 0)
		)
		(polygon
			(pts
				(arc
					(start 116.091716 -404.46452)
					(mid 115.423696 -404.46452)
					(end 116.091716 -404.46452)
				)
			)
		)
	)
	(zone
		(layers "B.Cu" "In6.Cu" "In11.Cu" "In13.Cu" "In15.Cu")
		(hatch none 0.5)
		(connect_pads
			(clearance 0)
		)
		(min_thickness 0.25)
		(keepout
			(tracks not_allowed)
			(vias allowed)
			(pads allowed)
			(copperpour not_allowed)
			(footprints allowed)
		)
		(placement
			(enabled no)
			(sheetname "")
		)
		(fill yes
			(thermal_gap 0.5)
			(thermal_bridge_width 0.5)
			(island_removal_mode 0)
		)
		(polygon
			(pts
				(arc
					(start 341.06612 -277.32609)
					(mid 340.4362 -277.32609)
					(end 341.06612 -277.32609)
				)
			)
		)
	)
	(zone
		(layers "B.Cu" "In6.Cu" "In11.Cu" "In13.Cu" "In15.Cu")
		(hatch none 0.5)
		(connect_pads
			(clearance 0)
		)
		(min_thickness 0.25)
		(keepout
			(tracks not_allowed)
			(vias allowed)
			(pads allowed)
			(copperpour not_allowed)
			(footprints allowed)
		)
		(placement
			(enabled no)
			(sheetname "")
		)
		(fill yes
			(thermal_gap 0.5)
			(thermal_bridge_width 0.5)
			(island_removal_mode 0)
		)
		(polygon
			(pts
				(arc
					(start 345.936062 -228.284278)
					(mid 345.306142 -228.284278)
					(end 345.936062 -228.284278)
				)
			)
		)
	)
	(zone
		(layers "B.Cu" "In6.Cu" "In11.Cu" "In13.Cu" "In15.Cu")
		(hatch none 0.5)
		(connect_pads
			(clearance 0)
		)
		(min_thickness 0.25)
		(keepout
			(tracks not_allowed)
			(vias allowed)
			(pads allowed)
			(copperpour not_allowed)
			(footprints allowed)
		)
		(placement
			(enabled no)
			(sheetname "")
		)
		(fill yes
			(thermal_gap 0.5)
			(thermal_bridge_width 0.5)
			(island_removal_mode 0)
		)
		(polygon
			(pts
				(arc
					(start 391.231374 -17.61236)
					(mid 390.563354 -17.61236)
					(end 391.231374 -17.61236)
				)
			)
		)
	)
	(zone
		(layers "B.Cu" "In6.Cu" "In11.Cu" "In13.Cu" "In15.Cu")
		(hatch none 0.5)
		(connect_pads
			(clearance 0)
		)
		(min_thickness 0.25)
		(keepout
			(tracks not_allowed)
			(vias allowed)
			(pads allowed)
			(copperpour not_allowed)
			(footprints allowed)
		)
		(placement
			(enabled no)
			(sheetname "")
		)
		(fill yes
			(thermal_gap 0.5)
			(thermal_bridge_width 0.5)
			(island_removal_mode 0)
		)
		(polygon
			(pts
				(arc
					(start 91.41587 -233.144314)
					(mid 90.78595 -233.144314)
					(end 91.41587 -233.144314)
				)
			)
		)
	)
	(zone
		(layers "B.Cu" "In6.Cu" "In11.Cu" "In13.Cu" "In15.Cu")
		(hatch none 0.5)
		(connect_pads
			(clearance 0)
		)
		(min_thickness 0.25)
		(keepout
			(tracks not_allowed)
			(vias allowed)
			(pads allowed)
			(copperpour not_allowed)
			(footprints allowed)
		)
		(placement
			(enabled no)
			(sheetname "")
		)
		(fill yes
			(thermal_gap 0.5)
			(thermal_bridge_width 0.5)
			(island_removal_mode 0)
		)
		(polygon
			(pts
				(arc
					(start 37.129974 -201.585322)
					(mid 36.461954 -201.585322)
					(end 37.129974 -201.585322)
				)
			)
		)
	)
	(zone
		(layers "B.Cu" "In6.Cu" "In11.Cu" "In13.Cu" "In15.Cu")
		(hatch none 0.5)
		(connect_pads
			(clearance 0)
		)
		(min_thickness 0.25)
		(keepout
			(tracks not_allowed)
			(vias allowed)
			(pads allowed)
			(copperpour not_allowed)
			(footprints allowed)
		)
		(placement
			(enabled no)
			(sheetname "")
		)
		(fill yes
			(thermal_gap 0.5)
			(thermal_bridge_width 0.5)
			(island_removal_mode 0)
		)
		(polygon
			(pts
				(arc
					(start 91.245944 -262.746236)
					(mid 90.616024 -262.746236)
					(end 91.245944 -262.746236)
				)
			)
		)
	)
	(zone
		(layers "B.Cu" "In6.Cu" "In11.Cu" "In13.Cu" "In15.Cu")
		(hatch none 0.5)
		(connect_pads
			(clearance 0)
		)
		(min_thickness 0.25)
		(keepout
			(tracks not_allowed)
			(vias allowed)
			(pads allowed)
			(copperpour not_allowed)
			(footprints allowed)
		)
		(placement
			(enabled no)
			(sheetname "")
		)
		(fill yes
			(thermal_gap 0.5)
			(thermal_bridge_width 0.5)
			(island_removal_mode 0)
		)
		(polygon
			(pts
				(arc
					(start 91.245944 -275.706332)
					(mid 90.616024 -275.706332)
					(end 91.245944 -275.706332)
				)
			)
		)
	)
	(zone
		(layers "B.Cu" "In6.Cu" "In11.Cu" "In13.Cu" "In15.Cu")
		(hatch none 0.5)
		(connect_pads
			(clearance 0)
		)
		(min_thickness 0.25)
		(keepout
			(tracks not_allowed)
			(vias allowed)
			(pads allowed)
			(copperpour not_allowed)
			(footprints allowed)
		)
		(placement
			(enabled no)
			(sheetname "")
		)
		(fill yes
			(thermal_gap 0.5)
			(thermal_bridge_width 0.5)
			(island_removal_mode 0)
		)
		(polygon
			(pts
				(arc
					(start 33.029906 -239.835436)
					(mid 32.361886 -239.835436)
					(end 33.029906 -239.835436)
				)
			)
		)
	)
	(zone
		(layers "B.Cu" "In6.Cu" "In11.Cu" "In13.Cu" "In15.Cu")
		(hatch none 0.5)
		(connect_pads
			(clearance 0)
		)
		(min_thickness 0.25)
		(keepout
			(tracks not_allowed)
			(vias allowed)
			(pads allowed)
			(copperpour not_allowed)
			(footprints allowed)
		)
		(placement
			(enabled no)
			(sheetname "")
		)
		(fill yes
			(thermal_gap 0.5)
			(thermal_bridge_width 0.5)
			(island_removal_mode 0)
		)
		(polygon
			(pts
				(arc
					(start 108.80598 -233.95432)
					(mid 108.17606 -233.95432)
					(end 108.80598 -233.95432)
				)
			)
		)
	)
	(zone
		(layers "B.Cu" "In6.Cu" "In11.Cu" "In13.Cu" "In15.Cu")
		(hatch none 0.5)
		(connect_pads
			(clearance 0)
		)
		(min_thickness 0.25)
		(keepout
			(tracks not_allowed)
			(vias allowed)
			(pads allowed)
			(copperpour not_allowed)
			(footprints allowed)
		)
		(placement
			(enabled no)
			(sheetname "")
		)
		(fill yes
			(thermal_gap 0.5)
			(thermal_bridge_width 0.5)
			(island_removal_mode 0)
		)
		(polygon
			(pts
				(arc
					(start 90.94597 -246.914416)
					(mid 90.31605 -246.914416)
					(end 90.94597 -246.914416)
				)
			)
		)
	)
	(zone
		(layers "B.Cu" "In6.Cu" "In11.Cu" "In13.Cu" "In15.Cu")
		(hatch none 0.5)
		(connect_pads
			(clearance 0)
		)
		(min_thickness 0.25)
		(keepout
			(tracks not_allowed)
			(vias allowed)
			(pads allowed)
			(copperpour not_allowed)
			(footprints allowed)
		)
		(placement
			(enabled no)
			(sheetname "")
		)
		(fill yes
			(thermal_gap 0.5)
			(thermal_bridge_width 0.5)
			(island_removal_mode 0)
		)
		(polygon
			(pts
				(arc
					(start 191.494156 -234.73537)
					(mid 190.826136 -234.73537)
					(end 191.494156 -234.73537)
				)
			)
		)
	)
	(zone
		(layers "B.Cu" "In6.Cu" "In11.Cu" "In13.Cu" "In15.Cu")
		(hatch none 0.5)
		(connect_pads
			(clearance 0)
		)
		(min_thickness 0.25)
		(keepout
			(tracks not_allowed)
			(vias allowed)
			(pads allowed)
			(copperpour not_allowed)
			(footprints allowed)
		)
		(placement
			(enabled no)
			(sheetname "")
		)
		(fill yes
			(thermal_gap 0.5)
			(thermal_bridge_width 0.5)
			(island_removal_mode 0)
		)
		(polygon
			(pts
				(arc
					(start 115.679728 -290.286186)
					(mid 115.049808 -290.286186)
					(end 115.679728 -290.286186)
				)
			)
		)
	)
	(zone
		(layers "B.Cu" "In6.Cu" "In11.Cu" "In13.Cu" "In15.Cu")
		(hatch none 0.5)
		(connect_pads
			(clearance 0)
		)
		(min_thickness 0.25)
		(keepout
			(tracks not_allowed)
			(vias allowed)
			(pads allowed)
			(copperpour not_allowed)
			(footprints allowed)
		)
		(placement
			(enabled no)
			(sheetname "")
		)
		(fill yes
			(thermal_gap 0.5)
			(thermal_bridge_width 0.5)
			(island_removal_mode 0)
		)
		(polygon
			(pts
				(arc
					(start 312.905902 -397.849344)
					(mid 312.275982 -397.849344)
					(end 312.905902 -397.849344)
				)
			)
		)
	)
	(zone
		(layers "B.Cu" "In6.Cu" "In11.Cu" "In13.Cu" "In15.Cu")
		(hatch none 0.5)
		(connect_pads
			(clearance 0)
		)
		(min_thickness 0.25)
		(keepout
			(tracks not_allowed)
			(vias allowed)
			(pads allowed)
			(copperpour not_allowed)
			(footprints allowed)
		)
		(placement
			(enabled no)
			(sheetname "")
		)
		(fill yes
			(thermal_gap 0.5)
			(thermal_bridge_width 0.5)
			(island_removal_mode 0)
		)
		(polygon
			(pts
				(arc
					(start 439.434224 -233.035094)
					(mid 438.766204 -233.035094)
					(end 439.434224 -233.035094)
				)
			)
		)
	)
	(zone
		(layers "B.Cu" "In6.Cu" "In11.Cu" "In13.Cu" "In15.Cu")
		(hatch none 0.5)
		(connect_pads
			(clearance 0)
		)
		(min_thickness 0.25)
		(keepout
			(tracks not_allowed)
			(vias allowed)
			(pads allowed)
			(copperpour not_allowed)
			(footprints allowed)
		)
		(placement
			(enabled no)
			(sheetname "")
		)
		(fill yes
			(thermal_gap 0.5)
			(thermal_bridge_width 0.5)
			(island_removal_mode 0)
		)
		(polygon
			(pts
				(arc
					(start 54.933342 -6.725158)
					(mid 54.265322 -6.725158)
					(end 54.933342 -6.725158)
				)
			)
		)
	)
	(zone
		(layers "B.Cu" "In6.Cu" "In11.Cu" "In13.Cu" "In15.Cu")
		(hatch none 0.5)
		(connect_pads
			(clearance 0)
		)
		(min_thickness 0.25)
		(keepout
			(tracks not_allowed)
			(vias allowed)
			(pads allowed)
			(copperpour not_allowed)
			(footprints allowed)
		)
		(placement
			(enabled no)
			(sheetname "")
		)
		(fill yes
			(thermal_gap 0.5)
			(thermal_bridge_width 0.5)
			(island_removal_mode 0)
		)
		(polygon
			(pts
				(arc
					(start 386.544312 -412.84652)
					(mid 385.876292 -412.84652)
					(end 386.544312 -412.84652)
				)
			)
		)
	)
	(zone
		(layers "B.Cu" "In6.Cu" "In11.Cu" "In13.Cu" "In15.Cu")
		(hatch none 0.5)
		(connect_pads
			(clearance 0)
		)
		(min_thickness 0.25)
		(keepout
			(tracks not_allowed)
			(vias allowed)
			(pads allowed)
			(copperpour not_allowed)
			(footprints allowed)
		)
		(placement
			(enabled no)
			(sheetname "")
		)
		(fill yes
			(thermal_gap 0.5)
			(thermal_bridge_width 0.5)
			(island_removal_mode 0)
		)
		(polygon
			(pts
				(arc
					(start 280.969974 -308.685184)
					(mid 280.301954 -308.685184)
					(end 280.969974 -308.685184)
				)
			)
		)
	)
	(zone
		(layers "B.Cu" "In6.Cu" "In11.Cu" "In13.Cu" "In15.Cu")
		(hatch none 0.5)
		(connect_pads
			(clearance 0)
		)
		(min_thickness 0.25)
		(keepout
			(tracks not_allowed)
			(vias allowed)
			(pads allowed)
			(copperpour not_allowed)
			(footprints allowed)
		)
		(placement
			(enabled no)
			(sheetname "")
		)
		(fill yes
			(thermal_gap 0.5)
			(thermal_bridge_width 0.5)
			(island_removal_mode 0)
		)
		(polygon
			(pts
				(arc
					(start 37.129974 -203.285344)
					(mid 36.461954 -203.285344)
					(end 37.129974 -203.285344)
				)
			)
		)
	)
	(zone
		(layers "B.Cu" "In6.Cu" "In11.Cu" "In13.Cu" "In15.Cu")
		(hatch none 0.5)
		(connect_pads
			(clearance 0)
		)
		(min_thickness 0.25)
		(keepout
			(tracks not_allowed)
			(vias allowed)
			(pads allowed)
			(copperpour not_allowed)
			(footprints allowed)
		)
		(placement
			(enabled no)
			(sheetname "")
		)
		(fill yes
			(thermal_gap 0.5)
			(thermal_bridge_width 0.5)
			(island_removal_mode 0)
		)
		(polygon
			(pts
				(arc
					(start 132.129784 -291.096192)
					(mid 131.499864 -291.096192)
					(end 132.129784 -291.096192)
				)
			)
		)
	)
	(zone
		(layers "B.Cu" "In6.Cu" "In11.Cu" "In13.Cu" "In15.Cu")
		(hatch none 0.5)
		(connect_pads
			(clearance 0)
		)
		(min_thickness 0.25)
		(keepout
			(tracks not_allowed)
			(vias allowed)
			(pads allowed)
			(copperpour not_allowed)
			(footprints allowed)
		)
		(placement
			(enabled no)
			(sheetname "")
		)
		(fill yes
			(thermal_gap 0.5)
			(thermal_bridge_width 0.5)
			(island_removal_mode 0)
		)
		(polygon
			(pts
				(arc
					(start 166.449756 -362.396278)
					(mid 165.781736 -362.396278)
					(end 166.449756 -362.396278)
				)
			)
		)
	)
	(zone
		(layers "B.Cu" "In6.Cu" "In11.Cu" "In13.Cu" "In15.Cu")
		(hatch none 0.5)
		(connect_pads
			(clearance 0)
		)
		(min_thickness 0.25)
		(keepout
			(tracks not_allowed)
			(vias allowed)
			(pads allowed)
			(copperpour not_allowed)
			(footprints allowed)
		)
		(placement
			(enabled no)
			(sheetname "")
		)
		(fill yes
			(thermal_gap 0.5)
			(thermal_bridge_width 0.5)
			(island_removal_mode 0)
		)
		(polygon
			(pts
				(arc
					(start 280.969974 -310.384952)
					(mid 280.301954 -310.384952)
					(end 280.969974 -310.384952)
				)
			)
		)
	)
	(zone
		(layers "B.Cu" "In6.Cu" "In11.Cu" "In13.Cu" "In15.Cu")
		(hatch none 0.5)
		(connect_pads
			(clearance 0)
		)
		(min_thickness 0.25)
		(keepout
			(tracks not_allowed)
			(vias allowed)
			(pads allowed)
			(copperpour not_allowed)
			(footprints allowed)
		)
		(placement
			(enabled no)
			(sheetname "")
		)
		(fill yes
			(thermal_gap 0.5)
			(thermal_bridge_width 0.5)
			(island_removal_mode 0)
		)
		(polygon
			(pts
				(arc
					(start 191.494156 -301.88535)
					(mid 190.826136 -301.88535)
					(end 191.494156 -301.88535)
				)
			)
		)
	)
	(zone
		(layers "B.Cu" "In6.Cu" "In11.Cu" "In13.Cu" "In15.Cu")
		(hatch none 0.5)
		(connect_pads
			(clearance 0)
		)
		(min_thickness 0.25)
		(keepout
			(tracks not_allowed)
			(vias allowed)
			(pads allowed)
			(copperpour not_allowed)
			(footprints allowed)
		)
		(placement
			(enabled no)
			(sheetname "")
		)
		(fill yes
			(thermal_gap 0.5)
			(thermal_bridge_width 0.5)
			(island_removal_mode 0)
		)
		(polygon
			(pts
				(arc
					(start 191.494156 -217.735404)
					(mid 190.826136 -217.735404)
					(end 191.494156 -217.735404)
				)
			)
		)
	)
	(zone
		(layers "B.Cu" "In6.Cu" "In11.Cu" "In13.Cu" "In15.Cu")
		(hatch none 0.5)
		(connect_pads
			(clearance 0)
		)
		(min_thickness 0.25)
		(keepout
			(tracks not_allowed)
			(vias allowed)
			(pads allowed)
			(copperpour not_allowed)
			(footprints allowed)
		)
		(placement
			(enabled no)
			(sheetname "")
		)
		(fill yes
			(thermal_gap 0.5)
			(thermal_bridge_width 0.5)
			(island_removal_mode 0)
		)
		(polygon
			(pts
				(arc
					(start 132.76961 -231.524302)
					(mid 132.13969 -231.524302)
					(end 132.76961 -231.524302)
				)
			)
		)
	)
	(zone
		(layers "B.Cu" "In6.Cu" "In11.Cu" "In13.Cu" "In15.Cu")
		(hatch none 0.5)
		(connect_pads
			(clearance 0)
		)
		(min_thickness 0.25)
		(keepout
			(tracks not_allowed)
			(vias allowed)
			(pads allowed)
			(copperpour not_allowed)
			(footprints allowed)
		)
		(placement
			(enabled no)
			(sheetname "")
		)
		(fill yes
			(thermal_gap 0.5)
			(thermal_bridge_width 0.5)
			(island_removal_mode 0)
		)
		(polygon
			(pts
				(arc
					(start 33.029906 -289.98545)
					(mid 32.361886 -289.98545)
					(end 33.029906 -289.98545)
				)
			)
		)
	)
	(zone
		(layers "B.Cu" "In6.Cu" "In11.Cu" "In13.Cu" "In15.Cu")
		(hatch none 0.5)
		(connect_pads
			(clearance 0)
		)
		(min_thickness 0.25)
		(keepout
			(tracks not_allowed)
			(vias allowed)
			(pads allowed)
			(copperpour not_allowed)
			(footprints allowed)
		)
		(placement
			(enabled no)
			(sheetname "")
		)
		(fill yes
			(thermal_gap 0.5)
			(thermal_bridge_width 0.5)
			(island_removal_mode 0)
		)
		(polygon
			(pts
				(arc
					(start 439.434224 -221.985078)
					(mid 438.766204 -221.985078)
					(end 439.434224 -221.985078)
				)
			)
		)
	)
	(zone
		(layers "B.Cu" "In6.Cu" "In11.Cu" "In13.Cu" "In15.Cu")
		(hatch none 0.5)
		(connect_pads
			(clearance 0)
		)
		(min_thickness 0.25)
		(keepout
			(tracks not_allowed)
			(vias allowed)
			(pads allowed)
			(copperpour not_allowed)
			(footprints allowed)
		)
		(placement
			(enabled no)
			(sheetname "")
		)
		(fill yes
			(thermal_gap 0.5)
			(thermal_bridge_width 0.5)
			(island_removal_mode 0)
		)
		(polygon
			(pts
				(arc
					(start 435.334156 -314.635134)
					(mid 434.666136 -314.635134)
					(end 435.334156 -314.635134)
				)
			)
		)
	)
	(zone
		(layers "B.Cu" "In6.Cu" "In11.Cu" "In13.Cu" "In15.Cu")
		(hatch none 0.5)
		(connect_pads
			(clearance 0)
		)
		(min_thickness 0.25)
		(keepout
			(tracks not_allowed)
			(vias allowed)
			(pads allowed)
			(copperpour not_allowed)
			(footprints allowed)
		)
		(placement
			(enabled no)
			(sheetname "")
		)
		(fill yes
			(thermal_gap 0.5)
			(thermal_bridge_width 0.5)
			(island_removal_mode 0)
		)
		(polygon
			(pts
				(arc
					(start 92.826078 -225.854514)
					(mid 92.196158 -225.854514)
					(end 92.826078 -225.854514)
				)
			)
		)
	)
	(zone
		(layers "B.Cu" "In6.Cu" "In11.Cu" "In13.Cu" "In15.Cu")
		(hatch none 0.5)
		(connect_pads
			(clearance 0)
		)
		(min_thickness 0.25)
		(keepout
			(tracks not_allowed)
			(vias allowed)
			(pads allowed)
			(copperpour not_allowed)
			(footprints allowed)
		)
		(placement
			(enabled no)
			(sheetname "")
		)
		(fill yes
			(thermal_gap 0.5)
			(thermal_bridge_width 0.5)
			(island_removal_mode 0)
		)
		(polygon
			(pts
				(arc
					(start 91.245944 -293.52621)
					(mid 90.616024 -293.52621)
					(end 91.245944 -293.52621)
				)
			)
		)
	)
	(zone
		(layers "B.Cu" "In6.Cu" "In11.Cu" "In13.Cu" "In15.Cu")
		(hatch none 0.5)
		(connect_pads
			(clearance 0)
		)
		(min_thickness 0.25)
		(keepout
			(tracks not_allowed)
			(vias allowed)
			(pads allowed)
			(copperpour not_allowed)
			(footprints allowed)
		)
		(placement
			(enabled no)
			(sheetname "")
		)
		(fill yes
			(thermal_gap 0.5)
			(thermal_bridge_width 0.5)
			(island_removal_mode 0)
		)
		(polygon
			(pts
				(arc
					(start 187.394088 -276.385274)
					(mid 186.726068 -276.385274)
					(end 187.394088 -276.385274)
				)
			)
		)
	)
	(zone
		(layers "B.Cu" "In6.Cu" "In11.Cu" "In13.Cu" "In15.Cu")
		(hatch none 0.5)
		(connect_pads
			(clearance 0)
		)
		(min_thickness 0.25)
		(keepout
			(tracks not_allowed)
			(vias allowed)
			(pads allowed)
			(copperpour not_allowed)
			(footprints allowed)
		)
		(placement
			(enabled no)
			(sheetname "")
		)
		(fill yes
			(thermal_gap 0.5)
			(thermal_bridge_width 0.5)
			(island_removal_mode 0)
		)
		(polygon
			(pts
				(arc
					(start 379.299724 -255.014222)
					(mid 378.669804 -255.014222)
					(end 379.299724 -255.014222)
				)
			)
		)
	)
	(zone
		(layers "B.Cu" "In6.Cu" "In11.Cu" "In13.Cu" "In15.Cu")
		(hatch none 0.5)
		(connect_pads
			(clearance 0)
		)
		(min_thickness 0.25)
		(keepout
			(tracks not_allowed)
			(vias allowed)
			(pads allowed)
			(copperpour not_allowed)
			(footprints allowed)
		)
		(placement
			(enabled no)
			(sheetname "")
		)
		(fill yes
			(thermal_gap 0.5)
			(thermal_bridge_width 0.5)
			(island_removal_mode 0)
		)
		(polygon
			(pts
				(arc
					(start 115.679728 -287.046162)
					(mid 115.049808 -287.046162)
					(end 115.679728 -287.046162)
				)
			)
		)
	)
	(zone
		(layers "B.Cu" "In6.Cu" "In11.Cu" "In13.Cu" "In15.Cu")
		(hatch none 0.5)
		(connect_pads
			(clearance 0)
		)
		(min_thickness 0.25)
		(keepout
			(tracks not_allowed)
			(vias allowed)
			(pads allowed)
			(copperpour not_allowed)
			(footprints allowed)
		)
		(placement
			(enabled no)
			(sheetname "")
		)
		(fill yes
			(thermal_gap 0.5)
			(thermal_bridge_width 0.5)
			(island_removal_mode 0)
		)
		(polygon
			(pts
				(arc
					(start 380.069852 -265.176)
					(mid 379.439932 -265.176)
					(end 380.069852 -265.176)
				)
			)
		)
	)
	(zone
		(layers "B.Cu" "In6.Cu" "In11.Cu" "In13.Cu" "In15.Cu")
		(hatch none 0.5)
		(connect_pads
			(clearance 0)
		)
		(min_thickness 0.25)
		(keepout
			(tracks not_allowed)
			(vias allowed)
			(pads allowed)
			(copperpour not_allowed)
			(footprints allowed)
		)
		(placement
			(enabled no)
			(sheetname "")
		)
		(fill yes
			(thermal_gap 0.5)
			(thermal_bridge_width 0.5)
			(island_removal_mode 0)
		)
		(polygon
			(pts
				(arc
					(start 340.766146 -237.19409)
					(mid 340.136226 -237.19409)
					(end 340.766146 -237.19409)
				)
			)
		)
	)
	(zone
		(layers "B.Cu" "In6.Cu" "In11.Cu" "In13.Cu" "In15.Cu")
		(hatch none 0.5)
		(connect_pads
			(clearance 0)
		)
		(min_thickness 0.25)
		(keepout
			(tracks not_allowed)
			(vias allowed)
			(pads allowed)
			(copperpour not_allowed)
			(footprints allowed)
		)
		(placement
			(enabled no)
			(sheetname "")
		)
		(fill yes
			(thermal_gap 0.5)
			(thermal_bridge_width 0.5)
			(island_removal_mode 0)
		)
		(polygon
			(pts
				(arc
					(start 97.995994 -234.764326)
					(mid 97.366074 -234.764326)
					(end 97.995994 -234.764326)
				)
			)
		)
	)
	(zone
		(layers "B.Cu" "In6.Cu" "In11.Cu" "In13.Cu" "In15.Cu")
		(hatch none 0.5)
		(connect_pads
			(clearance 0)
		)
		(min_thickness 0.25)
		(keepout
			(tracks not_allowed)
			(vias allowed)
			(pads allowed)
			(copperpour not_allowed)
			(footprints allowed)
		)
		(placement
			(enabled no)
			(sheetname "")
		)
		(fill yes
			(thermal_gap 0.5)
			(thermal_bridge_width 0.5)
			(island_removal_mode 0)
		)
		(polygon
			(pts
				(arc
					(start 93.126052 -278.946356)
					(mid 92.496132 -278.946356)
					(end 93.126052 -278.946356)
				)
			)
		)
	)
	(zone
		(layers "B.Cu" "In6.Cu" "In11.Cu" "In13.Cu" "In15.Cu")
		(hatch none 0.5)
		(connect_pads
			(clearance 0)
		)
		(min_thickness 0.25)
		(keepout
			(tracks not_allowed)
			(vias allowed)
			(pads allowed)
			(copperpour not_allowed)
			(footprints allowed)
		)
		(placement
			(enabled no)
			(sheetname "")
		)
		(fill yes
			(thermal_gap 0.5)
			(thermal_bridge_width 0.5)
			(island_removal_mode 0)
		)
		(polygon
			(pts
				(arc
					(start 439.434224 -261.085076)
					(mid 438.766204 -261.085076)
					(end 439.434224 -261.085076)
				)
			)
		)
	)
	(zone
		(layers "B.Cu" "In6.Cu" "In11.Cu" "In13.Cu" "In15.Cu")
		(hatch none 0.5)
		(connect_pads
			(clearance 0)
		)
		(min_thickness 0.25)
		(keepout
			(tracks not_allowed)
			(vias allowed)
			(pads allowed)
			(copperpour not_allowed)
			(footprints allowed)
		)
		(placement
			(enabled no)
			(sheetname "")
		)
		(fill yes
			(thermal_gap 0.5)
			(thermal_bridge_width 0.5)
			(island_removal_mode 0)
		)
		(polygon
			(pts
				(arc
					(start 357.986076 -290.285932)
					(mid 357.356156 -290.285932)
					(end 357.986076 -290.285932)
				)
			)
		)
	)
	(zone
		(layers "B.Cu" "In6.Cu" "In11.Cu" "In13.Cu" "In15.Cu")
		(hatch none 0.5)
		(connect_pads
			(clearance 0)
		)
		(min_thickness 0.25)
		(keepout
			(tracks not_allowed)
			(vias allowed)
			(pads allowed)
			(copperpour not_allowed)
			(footprints allowed)
		)
		(placement
			(enabled no)
			(sheetname "")
		)
		(fill yes
			(thermal_gap 0.5)
			(thermal_bridge_width 0.5)
			(island_removal_mode 0)
		)
		(polygon
			(pts
				(arc
					(start 91.41587 -229.90429)
					(mid 90.78595 -229.90429)
					(end 91.41587 -229.90429)
				)
			)
		)
	)
	(zone
		(layers "B.Cu" "In6.Cu" "In11.Cu" "In13.Cu" "In15.Cu")
		(hatch none 0.5)
		(connect_pads
			(clearance 0)
		)
		(min_thickness 0.25)
		(keepout
			(tracks not_allowed)
			(vias allowed)
			(pads allowed)
			(copperpour not_allowed)
			(footprints allowed)
		)
		(placement
			(enabled no)
			(sheetname "")
		)
		(fill yes
			(thermal_gap 0.5)
			(thermal_bridge_width 0.5)
			(island_removal_mode 0)
		)
		(polygon
			(pts
				(arc
					(start 116.789708 -229.90429)
					(mid 116.159788 -229.90429)
					(end 116.789708 -229.90429)
				)
			)
		)
	)
	(zone
		(layers "B.Cu" "In6.Cu" "In11.Cu" "In13.Cu" "In15.Cu")
		(hatch none 0.5)
		(connect_pads
			(clearance 0)
		)
		(min_thickness 0.25)
		(keepout
			(tracks not_allowed)
			(vias allowed)
			(pads allowed)
			(copperpour not_allowed)
			(footprints allowed)
		)
		(placement
			(enabled no)
			(sheetname "")
		)
		(fill yes
			(thermal_gap 0.5)
			(thermal_bridge_width 0.5)
			(island_removal_mode 0)
		)
		(polygon
			(pts
				(arc
					(start 340.295992 -247.724168)
					(mid 339.666072 -247.724168)
					(end 340.295992 -247.724168)
				)
			)
		)
	)
	(zone
		(layers "B.Cu" "In6.Cu" "In11.Cu" "In13.Cu" "In15.Cu")
		(hatch none 0.5)
		(connect_pads
			(clearance 0)
		)
		(min_thickness 0.25)
		(keepout
			(tracks not_allowed)
			(vias allowed)
			(pads allowed)
			(copperpour not_allowed)
			(footprints allowed)
		)
		(placement
			(enabled no)
			(sheetname "")
		)
		(fill yes
			(thermal_gap 0.5)
			(thermal_bridge_width 0.5)
			(island_removal_mode 0)
		)
		(polygon
			(pts
				(arc
					(start 91.716098 -263.556242)
					(mid 91.086178 -263.556242)
					(end 91.716098 -263.556242)
				)
			)
		)
	)
	(zone
		(layers "B.Cu" "In6.Cu" "In11.Cu" "In13.Cu" "In15.Cu")
		(hatch none 0.5)
		(connect_pads
			(clearance 0)
		)
		(min_thickness 0.25)
		(keepout
			(tracks not_allowed)
			(vias allowed)
			(pads allowed)
			(copperpour not_allowed)
			(footprints allowed)
		)
		(placement
			(enabled no)
			(sheetname "")
		)
		(fill yes
			(thermal_gap 0.5)
			(thermal_bridge_width 0.5)
			(island_removal_mode 0)
		)
		(polygon
			(pts
				(arc
					(start 349.995998 -291.095938)
					(mid 349.366078 -291.095938)
					(end 349.995998 -291.095938)
				)
			)
		)
	)
	(zone
		(layers "B.Cu" "In6.Cu" "In11.Cu" "In13.Cu" "In15.Cu")
		(hatch none 0.5)
		(connect_pads
			(clearance 0)
		)
		(min_thickness 0.25)
		(keepout
			(tracks not_allowed)
			(vias allowed)
			(pads allowed)
			(copperpour not_allowed)
			(footprints allowed)
		)
		(placement
			(enabled no)
			(sheetname "")
		)
		(fill yes
			(thermal_gap 0.5)
			(thermal_bridge_width 0.5)
			(island_removal_mode 0)
		)
		(polygon
			(pts
				(arc
					(start 381.179832 -242.054126)
					(mid 380.549912 -242.054126)
					(end 381.179832 -242.054126)
				)
			)
		)
	)
	(zone
		(layers "B.Cu" "In6.Cu" "In11.Cu" "In13.Cu" "In15.Cu")
		(hatch none 0.5)
		(connect_pads
			(clearance 0)
		)
		(min_thickness 0.25)
		(keepout
			(tracks not_allowed)
			(vias allowed)
			(pads allowed)
			(copperpour not_allowed)
			(footprints allowed)
		)
		(placement
			(enabled no)
			(sheetname "")
		)
		(fill yes
			(thermal_gap 0.5)
			(thermal_bridge_width 0.5)
			(island_removal_mode 0)
		)
		(polygon
			(pts
				(arc
					(start 381.479806 -283.806138)
					(mid 380.849886 -283.806138)
					(end 381.479806 -283.806138)
				)
			)
		)
	)
	(zone
		(layers "B.Cu" "In6.Cu" "In11.Cu" "In13.Cu" "In15.Cu")
		(hatch none 0.5)
		(connect_pads
			(clearance 0)
		)
		(min_thickness 0.25)
		(keepout
			(tracks not_allowed)
			(vias allowed)
			(pads allowed)
			(copperpour not_allowed)
			(footprints allowed)
		)
		(placement
			(enabled no)
			(sheetname "")
		)
		(fill yes
			(thermal_gap 0.5)
			(thermal_bridge_width 0.5)
			(island_removal_mode 0)
		)
		(polygon
			(pts
				(arc
					(start 191.494156 -216.035382)
					(mid 190.826136 -216.035382)
					(end 191.494156 -216.035382)
				)
			)
		)
	)
	(zone
		(layers "B.Cu" "In6.Cu" "In11.Cu" "In13.Cu" "In15.Cu")
		(hatch none 0.5)
		(connect_pads
			(clearance 0)
		)
		(min_thickness 0.25)
		(keepout
			(tracks not_allowed)
			(vias allowed)
			(pads allowed)
			(copperpour not_allowed)
			(footprints allowed)
		)
		(placement
			(enabled no)
			(sheetname "")
		)
		(fill yes
			(thermal_gap 0.5)
			(thermal_bridge_width 0.5)
			(island_removal_mode 0)
		)
		(polygon
			(pts
				(arc
					(start 381.179832 -245.29415)
					(mid 380.549912 -245.29415)
					(end 381.179832 -245.29415)
				)
			)
		)
	)
	(zone
		(layers "B.Cu" "In6.Cu" "In11.Cu" "In13.Cu" "In15.Cu")
		(hatch none 0.5)
		(connect_pads
			(clearance 0)
		)
		(min_thickness 0.25)
		(keepout
			(tracks not_allowed)
			(vias allowed)
			(pads allowed)
			(copperpour not_allowed)
			(footprints allowed)
		)
		(placement
			(enabled no)
			(sheetname "")
		)
		(fill yes
			(thermal_gap 0.5)
			(thermal_bridge_width 0.5)
			(island_removal_mode 0)
		)
		(polygon
			(pts
				(arc
					(start 280.969974 -267.035026)
					(mid 280.301954 -267.035026)
					(end 280.969974 -267.035026)
				)
			)
		)
	)
	(zone
		(layers "B.Cu" "In6.Cu" "In11.Cu" "In13.Cu" "In15.Cu")
		(hatch none 0.5)
		(connect_pads
			(clearance 0)
		)
		(min_thickness 0.25)
		(keepout
			(tracks not_allowed)
			(vias allowed)
			(pads allowed)
			(copperpour not_allowed)
			(footprints allowed)
		)
		(placement
			(enabled no)
			(sheetname "")
		)
		(fill yes
			(thermal_gap 0.5)
			(thermal_bridge_width 0.5)
			(island_removal_mode 0)
		)
		(polygon
			(pts
				(arc
					(start 348.75597 -228.284278)
					(mid 348.12605 -228.284278)
					(end 348.75597 -228.284278)
				)
			)
		)
	)
	(zone
		(layers "B.Cu" "In6.Cu" "In11.Cu" "In13.Cu" "In15.Cu")
		(hatch none 0.5)
		(connect_pads
			(clearance 0)
		)
		(min_thickness 0.25)
		(keepout
			(tracks not_allowed)
			(vias allowed)
			(pads allowed)
			(copperpour not_allowed)
			(footprints allowed)
		)
		(placement
			(enabled no)
			(sheetname "")
		)
		(fill yes
			(thermal_gap 0.5)
			(thermal_bridge_width 0.5)
			(island_removal_mode 0)
		)
		(polygon
			(pts
				(arc
					(start 379.599698 -288.66592)
					(mid 378.969778 -288.66592)
					(end 379.599698 -288.66592)
				)
			)
		)
	)
	(zone
		(layers "B.Cu" "In6.Cu" "In11.Cu" "In13.Cu" "In15.Cu")
		(hatch none 0.5)
		(connect_pads
			(clearance 0)
		)
		(min_thickness 0.25)
		(keepout
			(tracks not_allowed)
			(vias allowed)
			(pads allowed)
			(copperpour not_allowed)
			(footprints allowed)
		)
		(placement
			(enabled no)
			(sheetname "")
		)
		(fill yes
			(thermal_gap 0.5)
			(thermal_bridge_width 0.5)
			(island_removal_mode 0)
		)
		(polygon
			(pts
				(arc
					(start 33.029906 -199.8853)
					(mid 32.361886 -199.8853)
					(end 33.029906 -199.8853)
				)
			)
		)
	)
	(zone
		(layers "B.Cu" "In6.Cu" "In11.Cu" "In13.Cu" "In15.Cu")
		(hatch none 0.5)
		(connect_pads
			(clearance 0)
		)
		(min_thickness 0.25)
		(keepout
			(tracks not_allowed)
			(vias allowed)
			(pads allowed)
			(copperpour not_allowed)
			(footprints allowed)
		)
		(placement
			(enabled no)
			(sheetname "")
		)
		(fill yes
			(thermal_gap 0.5)
			(thermal_bridge_width 0.5)
			(island_removal_mode 0)
		)
		(polygon
			(pts
				(arc
					(start 91.245944 -290.286186)
					(mid 90.616024 -290.286186)
					(end 91.245944 -290.286186)
				)
			)
		)
	)
	(zone
		(layers "B.Cu" "In6.Cu" "In11.Cu" "In13.Cu" "In15.Cu")
		(hatch none 0.5)
		(connect_pads
			(clearance 0)
		)
		(min_thickness 0.25)
		(keepout
			(tracks not_allowed)
			(vias allowed)
			(pads allowed)
			(copperpour not_allowed)
			(footprints allowed)
		)
		(placement
			(enabled no)
			(sheetname "")
		)
		(fill yes
			(thermal_gap 0.5)
			(thermal_bridge_width 0.5)
			(island_removal_mode 0)
		)
		(polygon
			(pts
				(arc
					(start 33.029906 -248.335292)
					(mid 32.361886 -248.335292)
					(end 33.029906 -248.335292)
				)
			)
		)
	)
	(zone
		(layers "B.Cu" "In6.Cu" "In11.Cu" "In13.Cu" "In15.Cu")
		(hatch none 0.5)
		(connect_pads
			(clearance 0)
		)
		(min_thickness 0.25)
		(keepout
			(tracks not_allowed)
			(vias allowed)
			(pads allowed)
			(copperpour not_allowed)
			(footprints allowed)
		)
		(placement
			(enabled no)
			(sheetname "")
		)
		(fill yes
			(thermal_gap 0.5)
			(thermal_bridge_width 0.5)
			(island_removal_mode 0)
		)
		(polygon
			(pts
				(arc
					(start 435.334156 -254.284988)
					(mid 434.666136 -254.284988)
					(end 435.334156 -254.284988)
				)
			)
		)
	)
	(zone
		(layers "B.Cu" "In6.Cu" "In11.Cu" "In13.Cu" "In15.Cu")
		(hatch none 0.5)
		(connect_pads
			(clearance 0)
		)
		(min_thickness 0.25)
		(keepout
			(tracks not_allowed)
			(vias allowed)
			(pads allowed)
			(copperpour not_allowed)
			(footprints allowed)
		)
		(placement
			(enabled no)
			(sheetname "")
		)
		(fill yes
			(thermal_gap 0.5)
			(thermal_bridge_width 0.5)
			(island_removal_mode 0)
		)
		(polygon
			(pts
				(arc
					(start 37.129974 -309.535322)
					(mid 36.461954 -309.535322)
					(end 37.129974 -309.535322)
				)
			)
		)
	)
	(zone
		(layers "B.Cu" "In6.Cu" "In11.Cu" "In13.Cu" "In15.Cu")
		(hatch none 0.5)
		(connect_pads
			(clearance 0)
		)
		(min_thickness 0.25)
		(keepout
			(tracks not_allowed)
			(vias allowed)
			(pads allowed)
			(copperpour not_allowed)
			(footprints allowed)
		)
		(placement
			(enabled no)
			(sheetname "")
		)
		(fill yes
			(thermal_gap 0.5)
			(thermal_bridge_width 0.5)
			(island_removal_mode 0)
		)
		(polygon
			(pts
				(arc
					(start 334.442054 -377.41733)
					(mid 333.774034 -377.41733)
					(end 334.442054 -377.41733)
				)
			)
		)
	)
	(zone
		(layers "B.Cu" "In6.Cu" "In11.Cu" "In13.Cu" "In15.Cu")
		(hatch none 0.5)
		(connect_pads
			(clearance 0)
		)
		(min_thickness 0.25)
		(keepout
			(tracks not_allowed)
			(vias allowed)
			(pads allowed)
			(copperpour not_allowed)
			(footprints allowed)
		)
		(placement
			(enabled no)
			(sheetname "")
		)
		(fill yes
			(thermal_gap 0.5)
			(thermal_bridge_width 0.5)
			(island_removal_mode 0)
		)
		(polygon
			(pts
				(arc
					(start 187.394088 -233.885232)
					(mid 186.726068 -233.885232)
					(end 187.394088 -233.885232)
				)
			)
		)
	)
	(zone
		(layers "B.Cu" "In6.Cu" "In11.Cu" "In13.Cu" "In15.Cu")
		(hatch none 0.5)
		(connect_pads
			(clearance 0)
		)
		(min_thickness 0.25)
		(keepout
			(tracks not_allowed)
			(vias allowed)
			(pads allowed)
			(copperpour not_allowed)
			(footprints allowed)
		)
		(placement
			(enabled no)
			(sheetname "")
		)
		(fill yes
			(thermal_gap 0.5)
			(thermal_bridge_width 0.5)
			(island_removal_mode 0)
		)
		(polygon
			(pts
				(arc
					(start 310.50611 -397.849344)
					(mid 309.87619 -397.849344)
					(end 310.50611 -397.849344)
				)
			)
		)
	)
	(zone
		(layers "B.Cu" "In6.Cu" "In11.Cu" "In13.Cu" "In15.Cu")
		(hatch none 0.5)
		(connect_pads
			(clearance 0)
		)
		(min_thickness 0.25)
		(keepout
			(tracks not_allowed)
			(vias allowed)
			(pads allowed)
			(copperpour not_allowed)
			(footprints allowed)
		)
		(placement
			(enabled no)
			(sheetname "")
		)
		(fill yes
			(thermal_gap 0.5)
			(thermal_bridge_width 0.5)
			(island_removal_mode 0)
		)
		(polygon
			(pts
				(arc
					(start 422.270174 -19.137122)
					(mid 421.602154 -19.137122)
					(end 422.270174 -19.137122)
				)
			)
		)
	)
	(zone
		(layers "B.Cu" "In6.Cu" "In11.Cu" "In13.Cu" "In15.Cu")
		(hatch none 0.5)
		(connect_pads
			(clearance 0)
		)
		(min_thickness 0.25)
		(keepout
			(tracks not_allowed)
			(vias allowed)
			(pads allowed)
			(copperpour not_allowed)
			(footprints allowed)
		)
		(placement
			(enabled no)
			(sheetname "")
		)
		(fill yes
			(thermal_gap 0.5)
			(thermal_bridge_width 0.5)
			(island_removal_mode 0)
		)
		(polygon
			(pts
				(arc
					(start 187.394088 -241.535204)
					(mid 186.726068 -241.535204)
					(end 187.394088 -241.535204)
				)
			)
		)
	)
	(zone
		(layers "B.Cu" "In6.Cu" "In11.Cu" "In13.Cu" "In15.Cu")
		(hatch none 0.5)
		(connect_pads
			(clearance 0)
		)
		(min_thickness 0.25)
		(keepout
			(tracks not_allowed)
			(vias allowed)
			(pads allowed)
			(copperpour not_allowed)
			(footprints allowed)
		)
		(placement
			(enabled no)
			(sheetname "")
		)
		(fill yes
			(thermal_gap 0.5)
			(thermal_bridge_width 0.5)
			(island_removal_mode 0)
		)
		(polygon
			(pts
				(arc
					(start 104.139492 -380.360428)
					(mid 103.471472 -380.360428)
					(end 104.139492 -380.360428)
				)
			)
		)
	)
	(zone
		(layers "B.Cu" "In6.Cu" "In11.Cu" "In13.Cu" "In15.Cu")
		(hatch none 0.5)
		(connect_pads
			(clearance 0)
		)
		(min_thickness 0.25)
		(keepout
			(tracks not_allowed)
			(vias allowed)
			(pads allowed)
			(copperpour not_allowed)
			(footprints allowed)
		)
		(placement
			(enabled no)
			(sheetname "")
		)
		(fill yes
			(thermal_gap 0.5)
			(thermal_bridge_width 0.5)
			(island_removal_mode 0)
		)
		(polygon
			(pts
				(arc
					(start 164.534088 -388.774432)
					(mid 163.904168 -388.774432)
					(end 164.534088 -388.774432)
				)
			)
		)
	)
	(zone
		(layers "B.Cu" "In6.Cu" "In11.Cu" "In13.Cu" "In15.Cu")
		(hatch none 0.5)
		(connect_pads
			(clearance 0)
		)
		(min_thickness 0.25)
		(keepout
			(tracks not_allowed)
			(vias allowed)
			(pads allowed)
			(copperpour not_allowed)
			(footprints allowed)
		)
		(placement
			(enabled no)
			(sheetname "")
		)
		(fill yes
			(thermal_gap 0.5)
			(thermal_bridge_width 0.5)
			(island_removal_mode 0)
		)
		(polygon
			(pts
				(arc
					(start 37.129974 -245.785386)
					(mid 36.461954 -245.785386)
					(end 37.129974 -245.785386)
				)
			)
		)
	)
	(zone
		(layers "B.Cu" "In6.Cu" "In11.Cu" "In13.Cu" "In15.Cu")
		(hatch none 0.5)
		(connect_pads
			(clearance 0)
		)
		(min_thickness 0.25)
		(keepout
			(tracks not_allowed)
			(vias allowed)
			(pads allowed)
			(copperpour not_allowed)
			(footprints allowed)
		)
		(placement
			(enabled no)
			(sheetname "")
		)
		(fill yes
			(thermal_gap 0.5)
			(thermal_bridge_width 0.5)
			(island_removal_mode 0)
		)
		(polygon
			(pts
				(arc
					(start 343.789254 -382.34493)
					(mid 343.121234 -382.34493)
					(end 343.789254 -382.34493)
				)
			)
		)
	)
	(zone
		(layers "B.Cu" "In6.Cu" "In11.Cu" "In13.Cu" "In15.Cu")
		(hatch none 0.5)
		(connect_pads
			(clearance 0)
		)
		(min_thickness 0.25)
		(keepout
			(tracks not_allowed)
			(vias allowed)
			(pads allowed)
			(copperpour not_allowed)
			(footprints allowed)
		)
		(placement
			(enabled no)
			(sheetname "")
		)
		(fill yes
			(thermal_gap 0.5)
			(thermal_bridge_width 0.5)
			(island_removal_mode 0)
		)
		(polygon
			(pts
				(arc
					(start 29.217874 -4.963414)
					(mid 28.549854 -4.963414)
					(end 29.217874 -4.963414)
				)
			)
		)
	)
	(zone
		(layers "B.Cu" "In6.Cu" "In11.Cu" "In13.Cu" "In15.Cu")
		(hatch none 0.5)
		(connect_pads
			(clearance 0)
		)
		(min_thickness 0.25)
		(keepout
			(tracks not_allowed)
			(vias allowed)
			(pads allowed)
			(copperpour not_allowed)
			(footprints allowed)
		)
		(placement
			(enabled no)
			(sheetname "")
		)
		(fill yes
			(thermal_gap 0.5)
			(thermal_bridge_width 0.5)
			(island_removal_mode 0)
		)
		(polygon
			(pts
				(arc
					(start 120.40616 -386.003292)
					(mid 119.77624 -386.003292)
					(end 120.40616 -386.003292)
				)
			)
		)
	)
	(zone
		(layers "B.Cu" "In6.Cu" "In11.Cu" "In13.Cu" "In15.Cu")
		(hatch none 0.5)
		(connect_pads
			(clearance 0)
		)
		(min_thickness 0.25)
		(keepout
			(tracks not_allowed)
			(vias allowed)
			(pads allowed)
			(copperpour not_allowed)
			(footprints allowed)
		)
		(placement
			(enabled no)
			(sheetname "")
		)
		(fill yes
			(thermal_gap 0.5)
			(thermal_bridge_width 0.5)
			(island_removal_mode 0)
		)
		(polygon
			(pts
				(arc
					(start 106.455972 -233.144314)
					(mid 105.826052 -233.144314)
					(end 106.455972 -233.144314)
				)
			)
		)
	)
	(zone
		(layers "B.Cu" "In6.Cu" "In11.Cu" "In13.Cu" "In15.Cu")
		(hatch none 0.5)
		(connect_pads
			(clearance 0)
		)
		(min_thickness 0.25)
		(keepout
			(tracks not_allowed)
			(vias allowed)
			(pads allowed)
			(copperpour not_allowed)
			(footprints allowed)
		)
		(placement
			(enabled no)
			(sheetname "")
		)
		(fill yes
			(thermal_gap 0.5)
			(thermal_bridge_width 0.5)
			(island_removal_mode 0)
		)
		(polygon
			(pts
				(arc
					(start 376.406156 -394.385292)
					(mid 375.776236 -394.385292)
					(end 376.406156 -394.385292)
				)
			)
		)
	)
	(zone
		(layers "B.Cu" "In6.Cu" "In11.Cu" "In13.Cu" "In15.Cu")
		(hatch none 0.5)
		(connect_pads
			(clearance 0)
		)
		(min_thickness 0.25)
		(keepout
			(tracks not_allowed)
			(vias allowed)
			(pads allowed)
			(copperpour not_allowed)
			(footprints allowed)
		)
		(placement
			(enabled no)
			(sheetname "")
		)
		(fill yes
			(thermal_gap 0.5)
			(thermal_bridge_width 0.5)
			(island_removal_mode 0)
		)
		(polygon
			(pts
				(arc
					(start 339.355938 -226.664266)
					(mid 338.726018 -226.664266)
					(end 339.355938 -226.664266)
				)
			)
		)
	)
	(zone
		(layers "B.Cu" "In6.Cu" "In11.Cu" "In13.Cu" "In15.Cu")
		(hatch none 0.5)
		(connect_pads
			(clearance 0)
		)
		(min_thickness 0.25)
		(keepout
			(tracks not_allowed)
			(vias allowed)
			(pads allowed)
			(copperpour not_allowed)
			(footprints allowed)
		)
		(placement
			(enabled no)
			(sheetname "")
		)
		(fill yes
			(thermal_gap 0.5)
			(thermal_bridge_width 0.5)
			(island_removal_mode 0)
		)
		(polygon
			(pts
				(arc
					(start 322.506086 -397.849344)
					(mid 321.876166 -397.849344)
					(end 322.506086 -397.849344)
				)
			)
		)
	)
	(zone
		(layers "B.Cu" "In6.Cu" "In11.Cu" "In13.Cu" "In15.Cu")
		(hatch none 0.5)
		(connect_pads
			(clearance 0)
		)
		(min_thickness 0.25)
		(keepout
			(tracks not_allowed)
			(vias allowed)
			(pads allowed)
			(copperpour not_allowed)
			(footprints allowed)
		)
		(placement
			(enabled no)
			(sheetname "")
		)
		(fill yes
			(thermal_gap 0.5)
			(thermal_bridge_width 0.5)
			(island_removal_mode 0)
		)
		(polygon
			(pts
				(arc
					(start 133.239764 -235.574332)
					(mid 132.609844 -235.574332)
					(end 133.239764 -235.574332)
				)
			)
		)
	)
	(zone
		(layers "B.Cu" "In6.Cu" "In11.Cu" "In13.Cu" "In15.Cu")
		(hatch none 0.5)
		(connect_pads
			(clearance 0)
		)
		(min_thickness 0.25)
		(keepout
			(tracks not_allowed)
			(vias allowed)
			(pads allowed)
			(copperpour not_allowed)
			(footprints allowed)
		)
		(placement
			(enabled no)
			(sheetname "")
		)
		(fill yes
			(thermal_gap 0.5)
			(thermal_bridge_width 0.5)
			(island_removal_mode 0)
		)
		(polygon
			(pts
				(arc
					(start 380.069852 -273.27606)
					(mid 379.439932 -273.27606)
					(end 380.069852 -273.27606)
				)
			)
		)
	)
	(zone
		(layers "B.Cu" "In6.Cu" "In11.Cu" "In13.Cu" "In15.Cu")
		(hatch none 0.5)
		(connect_pads
			(clearance 0)
		)
		(min_thickness 0.25)
		(keepout
			(tracks not_allowed)
			(vias allowed)
			(pads allowed)
			(copperpour not_allowed)
			(footprints allowed)
		)
		(placement
			(enabled no)
			(sheetname "")
		)
		(fill yes
			(thermal_gap 0.5)
			(thermal_bridge_width 0.5)
			(island_removal_mode 0)
		)
		(polygon
			(pts
				(arc
					(start 132.76961 -238.00435)
					(mid 132.13969 -238.00435)
					(end 132.76961 -238.00435)
				)
			)
		)
	)
	(zone
		(layers "B.Cu" "In6.Cu" "In11.Cu" "In13.Cu" "In15.Cu")
		(hatch none 0.5)
		(connect_pads
			(clearance 0)
		)
		(min_thickness 0.25)
		(keepout
			(tracks not_allowed)
			(vias allowed)
			(pads allowed)
			(copperpour not_allowed)
			(footprints allowed)
		)
		(placement
			(enabled no)
			(sheetname "")
		)
		(fill yes
			(thermal_gap 0.5)
			(thermal_bridge_width 0.5)
			(island_removal_mode 0)
		)
		(polygon
			(pts
				(arc
					(start 37.129974 -210.085432)
					(mid 36.461954 -210.085432)
					(end 37.129974 -210.085432)
				)
			)
		)
	)
	(zone
		(layers "B.Cu" "In6.Cu" "In11.Cu" "In13.Cu" "In15.Cu")
		(hatch none 0.5)
		(connect_pads
			(clearance 0)
		)
		(min_thickness 0.25)
		(keepout
			(tracks not_allowed)
			(vias allowed)
			(pads allowed)
			(copperpour not_allowed)
			(footprints allowed)
		)
		(placement
			(enabled no)
			(sheetname "")
		)
		(fill yes
			(thermal_gap 0.5)
			(thermal_bridge_width 0.5)
			(island_removal_mode 0)
		)
		(polygon
			(pts
				(arc
					(start 280.969974 -241.53495)
					(mid 280.301954 -241.53495)
					(end 280.969974 -241.53495)
				)
			)
		)
	)
	(zone
		(layers "B.Cu" "In6.Cu" "In11.Cu" "In13.Cu" "In15.Cu")
		(hatch none 0.5)
		(connect_pads
			(clearance 0)
		)
		(min_thickness 0.25)
		(keepout
			(tracks not_allowed)
			(vias allowed)
			(pads allowed)
			(copperpour not_allowed)
			(footprints allowed)
		)
		(placement
			(enabled no)
			(sheetname "")
		)
		(fill yes
			(thermal_gap 0.5)
			(thermal_bridge_width 0.5)
			(island_removal_mode 0)
		)
		(polygon
			(pts
				(arc
					(start 33.029906 -224.535238)
					(mid 32.361886 -224.535238)
					(end 33.029906 -224.535238)
				)
			)
		)
	)
	(zone
		(layers "B.Cu" "In6.Cu" "In11.Cu" "In13.Cu" "In15.Cu")
		(hatch none 0.5)
		(connect_pads
			(clearance 0)
		)
		(min_thickness 0.25)
		(keepout
			(tracks not_allowed)
			(vias allowed)
			(pads allowed)
			(copperpour not_allowed)
			(footprints allowed)
		)
		(placement
			(enabled no)
			(sheetname "")
		)
		(fill yes
			(thermal_gap 0.5)
			(thermal_bridge_width 0.5)
			(island_removal_mode 0)
		)
		(polygon
			(pts
				(arc
					(start 106.755946 -289.47618)
					(mid 106.126026 -289.47618)
					(end 106.755946 -289.47618)
				)
			)
		)
	)
	(zone
		(layers "B.Cu" "In6.Cu" "In11.Cu" "In13.Cu" "In15.Cu")
		(hatch none 0.5)
		(connect_pads
			(clearance 0)
		)
		(min_thickness 0.25)
		(keepout
			(tracks not_allowed)
			(vias allowed)
			(pads allowed)
			(copperpour not_allowed)
			(footprints allowed)
		)
		(placement
			(enabled no)
			(sheetname "")
		)
		(fill yes
			(thermal_gap 0.5)
			(thermal_bridge_width 0.5)
			(island_removal_mode 0)
		)
		(polygon
			(pts
				(arc
					(start 379.299724 -243.674138)
					(mid 378.669804 -243.674138)
					(end 379.299724 -243.674138)
				)
			)
		)
	)
	(zone
		(layers "B.Cu" "In6.Cu" "In11.Cu" "In13.Cu" "In15.Cu")
		(hatch none 0.5)
		(connect_pads
			(clearance 0)
		)
		(min_thickness 0.25)
		(keepout
			(tracks not_allowed)
			(vias allowed)
			(pads allowed)
			(copperpour not_allowed)
			(footprints allowed)
		)
		(placement
			(enabled no)
			(sheetname "")
		)
		(fill yes
			(thermal_gap 0.5)
			(thermal_bridge_width 0.5)
			(island_removal_mode 0)
		)
		(polygon
			(pts
				(arc
					(start 115.228116 -404.46452)
					(mid 114.560096 -404.46452)
					(end 115.228116 -404.46452)
				)
			)
		)
	)
	(zone
		(layers "B.Cu" "In6.Cu" "In11.Cu" "In13.Cu" "In15.Cu")
		(hatch none 0.5)
		(connect_pads
			(clearance 0)
		)
		(min_thickness 0.25)
		(keepout
			(tracks not_allowed)
			(vias allowed)
			(pads allowed)
			(copperpour not_allowed)
			(footprints allowed)
		)
		(placement
			(enabled no)
			(sheetname "")
		)
		(fill yes
			(thermal_gap 0.5)
			(thermal_bridge_width 0.5)
			(island_removal_mode 0)
		)
		(polygon
			(pts
				(arc
					(start 435.334156 -278.93518)
					(mid 434.666136 -278.93518)
					(end 435.334156 -278.93518)
				)
			)
		)
	)
	(zone
		(layers "B.Cu" "In6.Cu" "In11.Cu" "In13.Cu" "In15.Cu")
		(hatch none 0.5)
		(connect_pads
			(clearance 0)
		)
		(min_thickness 0.25)
		(keepout
			(tracks not_allowed)
			(vias allowed)
			(pads allowed)
			(copperpour not_allowed)
			(footprints allowed)
		)
		(placement
			(enabled no)
			(sheetname "")
		)
		(fill yes
			(thermal_gap 0.5)
			(thermal_bridge_width 0.5)
			(island_removal_mode 0)
		)
		(polygon
			(pts
				(arc
					(start 435.334156 -233.884978)
					(mid 434.666136 -233.884978)
					(end 435.334156 -233.884978)
				)
			)
		)
	)
	(zone
		(layers "B.Cu" "In6.Cu" "In11.Cu" "In13.Cu" "In15.Cu")
		(hatch none 0.5)
		(connect_pads
			(clearance 0)
		)
		(min_thickness 0.25)
		(keepout
			(tracks not_allowed)
			(vias allowed)
			(pads allowed)
			(copperpour not_allowed)
			(footprints allowed)
		)
		(placement
			(enabled no)
			(sheetname "")
		)
		(fill yes
			(thermal_gap 0.5)
			(thermal_bridge_width 0.5)
			(island_removal_mode 0)
		)
		(polygon
			(pts
				(arc
					(start 371.309646 -236.384084)
					(mid 370.679726 -236.384084)
					(end 371.309646 -236.384084)
				)
			)
		)
	)
	(zone
		(layers "B.Cu" "In6.Cu" "In11.Cu" "In13.Cu" "In15.Cu")
		(hatch none 0.5)
		(connect_pads
			(clearance 0)
		)
		(min_thickness 0.25)
		(keepout
			(tracks not_allowed)
			(vias allowed)
			(pads allowed)
			(copperpour not_allowed)
			(footprints allowed)
		)
		(placement
			(enabled no)
			(sheetname "")
		)
		(fill yes
			(thermal_gap 0.5)
			(thermal_bridge_width 0.5)
			(island_removal_mode 0)
		)
		(polygon
			(pts
				(arc
					(start 439.434224 -234.735116)
					(mid 438.766204 -234.735116)
					(end 439.434224 -234.735116)
				)
			)
		)
	)
	(zone
		(layers "B.Cu" "In6.Cu" "In11.Cu" "In13.Cu" "In15.Cu")
		(hatch none 0.5)
		(connect_pads
			(clearance 0)
		)
		(min_thickness 0.25)
		(keepout
			(tracks not_allowed)
			(vias allowed)
			(pads allowed)
			(copperpour not_allowed)
			(footprints allowed)
		)
		(placement
			(enabled no)
			(sheetname "")
		)
		(fill yes
			(thermal_gap 0.5)
			(thermal_bridge_width 0.5)
			(island_removal_mode 0)
		)
		(polygon
			(pts
				(arc
					(start 338.886038 -245.29415)
					(mid 338.256118 -245.29415)
					(end 338.886038 -245.29415)
				)
			)
		)
	)
	(zone
		(layers "B.Cu" "In6.Cu" "In11.Cu" "In13.Cu" "In15.Cu")
		(hatch none 0.5)
		(connect_pads
			(clearance 0)
		)
		(min_thickness 0.25)
		(keepout
			(tracks not_allowed)
			(vias allowed)
			(pads allowed)
			(copperpour not_allowed)
			(footprints allowed)
		)
		(placement
			(enabled no)
			(sheetname "")
		)
		(fill yes
			(thermal_gap 0.5)
			(thermal_bridge_width 0.5)
			(island_removal_mode 0)
		)
		(polygon
			(pts
				(arc
					(start 191.494156 -290.835334)
					(mid 190.826136 -290.835334)
					(end 191.494156 -290.835334)
				)
			)
		)
	)
	(zone
		(layers "B.Cu" "In6.Cu" "In11.Cu" "In13.Cu" "In15.Cu")
		(hatch none 0.5)
		(connect_pads
			(clearance 0)
		)
		(min_thickness 0.25)
		(keepout
			(tracks not_allowed)
			(vias allowed)
			(pads allowed)
			(copperpour not_allowed)
			(footprints allowed)
		)
		(placement
			(enabled no)
			(sheetname "")
		)
		(fill yes
			(thermal_gap 0.5)
			(thermal_bridge_width 0.5)
			(island_removal_mode 0)
		)
		(polygon
			(pts
				(arc
					(start 439.434224 -285.735014)
					(mid 438.766204 -285.735014)
					(end 439.434224 -285.735014)
				)
			)
		)
	)
	(zone
		(layers "B.Cu" "In6.Cu" "In11.Cu" "In13.Cu" "In15.Cu")
		(hatch none 0.5)
		(connect_pads
			(clearance 0)
		)
		(min_thickness 0.25)
		(keepout
			(tracks not_allowed)
			(vias allowed)
			(pads allowed)
			(copperpour not_allowed)
			(footprints allowed)
		)
		(placement
			(enabled no)
			(sheetname "")
		)
		(fill yes
			(thermal_gap 0.5)
			(thermal_bridge_width 0.5)
			(island_removal_mode 0)
		)
		(polygon
			(pts
				(arc
					(start 99.236022 -291.096192)
					(mid 98.606102 -291.096192)
					(end 99.236022 -291.096192)
				)
			)
		)
	)
	(zone
		(layers "B.Cu" "In6.Cu" "In11.Cu" "In13.Cu" "In15.Cu")
		(hatch none 0.5)
		(connect_pads
			(clearance 0)
		)
		(min_thickness 0.25)
		(keepout
			(tracks not_allowed)
			(vias allowed)
			(pads allowed)
			(copperpour not_allowed)
			(footprints allowed)
		)
		(placement
			(enabled no)
			(sheetname "")
		)
		(fill yes
			(thermal_gap 0.5)
			(thermal_bridge_width 0.5)
			(island_removal_mode 0)
		)
		(polygon
			(pts
				(arc
					(start 365.969804 -287.856168)
					(mid 365.339884 -287.856168)
					(end 365.969804 -287.856168)
				)
			)
		)
	)
	(zone
		(layers "B.Cu" "In6.Cu" "In11.Cu" "In13.Cu" "In15.Cu")
		(hatch none 0.5)
		(connect_pads
			(clearance 0)
		)
		(min_thickness 0.25)
		(keepout
			(tracks not_allowed)
			(vias allowed)
			(pads allowed)
			(copperpour not_allowed)
			(footprints allowed)
		)
		(placement
			(enabled no)
			(sheetname "")
		)
		(fill yes
			(thermal_gap 0.5)
			(thermal_bridge_width 0.5)
			(island_removal_mode 0)
		)
		(polygon
			(pts
				(arc
					(start 88.653112 -373.96293)
					(mid 87.985092 -373.96293)
					(end 88.653112 -373.96293)
				)
			)
		)
	)
	(zone
		(layers "B.Cu" "In6.Cu" "In11.Cu" "In13.Cu" "In15.Cu")
		(hatch none 0.5)
		(connect_pads
			(clearance 0)
		)
		(min_thickness 0.25)
		(keepout
			(tracks not_allowed)
			(vias allowed)
			(pads allowed)
			(copperpour not_allowed)
			(footprints allowed)
		)
		(placement
			(enabled no)
			(sheetname "")
		)
		(fill yes
			(thermal_gap 0.5)
			(thermal_bridge_width 0.5)
			(island_removal_mode 0)
		)
		(polygon
			(pts
				(arc
					(start 33.029906 -313.78525)
					(mid 32.361886 -313.78525)
					(end 33.029906 -313.78525)
				)
			)
		)
	)
	(zone
		(layers "B.Cu" "In6.Cu" "In11.Cu" "In13.Cu" "In15.Cu")
		(hatch none 0.5)
		(connect_pads
			(clearance 0)
		)
		(min_thickness 0.25)
		(keepout
			(tracks not_allowed)
			(vias allowed)
			(pads allowed)
			(copperpour not_allowed)
			(footprints allowed)
		)
		(placement
			(enabled no)
			(sheetname "")
		)
		(fill yes
			(thermal_gap 0.5)
			(thermal_bridge_width 0.5)
			(island_removal_mode 0)
		)
		(polygon
			(pts
				(arc
					(start 131.359656 -238.814356)
					(mid 130.729736 -238.814356)
					(end 131.359656 -238.814356)
				)
			)
		)
	)
	(zone
		(layers "B.Cu" "In6.Cu" "In11.Cu" "In13.Cu" "In15.Cu")
		(hatch none 0.5)
		(connect_pads
			(clearance 0)
		)
		(min_thickness 0.25)
		(keepout
			(tracks not_allowed)
			(vias allowed)
			(pads allowed)
			(copperpour not_allowed)
			(footprints allowed)
		)
		(placement
			(enabled no)
			(sheetname "")
		)
		(fill yes
			(thermal_gap 0.5)
			(thermal_bridge_width 0.5)
			(island_removal_mode 0)
		)
		(polygon
			(pts
				(arc
					(start 313.317636 -412.84652)
					(mid 312.649616 -412.84652)
					(end 313.317636 -412.84652)
				)
			)
		)
	)
	(zone
		(layers "B.Cu" "In6.Cu" "In11.Cu" "In13.Cu" "In15.Cu")
		(hatch none 0.5)
		(connect_pads
			(clearance 0)
		)
		(min_thickness 0.25)
		(keepout
			(tracks not_allowed)
			(vias allowed)
			(pads allowed)
			(copperpour not_allowed)
			(footprints allowed)
		)
		(placement
			(enabled no)
			(sheetname "")
		)
		(fill yes
			(thermal_gap 0.5)
			(thermal_bridge_width 0.5)
			(island_removal_mode 0)
		)
		(polygon
			(pts
				(arc
					(start 439.641488 5.718048)
					(mid 438.973468 5.718048)
					(end 439.641488 5.718048)
				)
			)
		)
	)
	(zone
		(layers "B.Cu" "In6.Cu" "In11.Cu" "In13.Cu" "In15.Cu")
		(hatch none 0.5)
		(connect_pads
			(clearance 0)
		)
		(min_thickness 0.25)
		(keepout
			(tracks not_allowed)
			(vias allowed)
			(pads allowed)
			(copperpour not_allowed)
			(footprints allowed)
		)
		(placement
			(enabled no)
			(sheetname "")
		)
		(fill yes
			(thermal_gap 0.5)
			(thermal_bridge_width 0.5)
			(island_removal_mode 0)
		)
		(polygon
			(pts
				(arc
					(start 439.434224 -300.185074)
					(mid 438.766204 -300.185074)
					(end 439.434224 -300.185074)
				)
			)
		)
	)
	(zone
		(layers "B.Cu" "In6.Cu" "In11.Cu" "In13.Cu" "In15.Cu")
		(hatch none 0.5)
		(connect_pads
			(clearance 0)
		)
		(min_thickness 0.25)
		(keepout
			(tracks not_allowed)
			(vias allowed)
			(pads allowed)
			(copperpour not_allowed)
			(footprints allowed)
		)
		(placement
			(enabled no)
			(sheetname "")
		)
		(fill yes
			(thermal_gap 0.5)
			(thermal_bridge_width 0.5)
			(island_removal_mode 0)
		)
		(polygon
			(pts
				(arc
					(start 439.434224 -315.485018)
					(mid 438.766204 -315.485018)
					(end 439.434224 -315.485018)
				)
			)
		)
	)
	(zone
		(layers "B.Cu" "In6.Cu" "In11.Cu" "In13.Cu" "In15.Cu")
		(hatch none 0.5)
		(connect_pads
			(clearance 0)
		)
		(min_thickness 0.25)
		(keepout
			(tracks not_allowed)
			(vias allowed)
			(pads allowed)
			(copperpour not_allowed)
			(footprints allowed)
		)
		(placement
			(enabled no)
			(sheetname "")
		)
		(fill yes
			(thermal_gap 0.5)
			(thermal_bridge_width 0.5)
			(island_removal_mode 0)
		)
		(polygon
			(pts
				(arc
					(start 339.656166 -274.896072)
					(mid 339.026246 -274.896072)
					(end 339.656166 -274.896072)
				)
			)
		)
	)
	(zone
		(layers "B.Cu" "In6.Cu" "In11.Cu" "In13.Cu" "In15.Cu")
		(hatch none 0.5)
		(connect_pads
			(clearance 0)
		)
		(min_thickness 0.25)
		(keepout
			(tracks not_allowed)
			(vias allowed)
			(pads allowed)
			(copperpour not_allowed)
			(footprints allowed)
		)
		(placement
			(enabled no)
			(sheetname "")
		)
		(fill yes
			(thermal_gap 0.5)
			(thermal_bridge_width 0.5)
			(island_removal_mode 0)
		)
		(polygon
			(pts
				(arc
					(start 37.129974 -295.085262)
					(mid 36.461954 -295.085262)
					(end 37.129974 -295.085262)
				)
			)
		)
	)
	(zone
		(layers "B.Cu" "In6.Cu" "In11.Cu" "In13.Cu" "In15.Cu")
		(hatch none 0.5)
		(connect_pads
			(clearance 0)
		)
		(min_thickness 0.25)
		(keepout
			(tracks not_allowed)
			(vias allowed)
			(pads allowed)
			(copperpour not_allowed)
			(footprints allowed)
		)
		(placement
			(enabled no)
			(sheetname "")
		)
		(fill yes
			(thermal_gap 0.5)
			(thermal_bridge_width 0.5)
			(island_removal_mode 0)
		)
		(polygon
			(pts
				(arc
					(start 435.334156 -268.735048)
					(mid 434.666136 -268.735048)
					(end 435.334156 -268.735048)
				)
			)
		)
	)
	(zone
		(layers "B.Cu" "In6.Cu" "In11.Cu" "In13.Cu" "In15.Cu")
		(hatch none 0.5)
		(connect_pads
			(clearance 0)
		)
		(min_thickness 0.25)
		(keepout
			(tracks not_allowed)
			(vias allowed)
			(pads allowed)
			(copperpour not_allowed)
			(footprints allowed)
		)
		(placement
			(enabled no)
			(sheetname "")
		)
		(fill yes
			(thermal_gap 0.5)
			(thermal_bridge_width 0.5)
			(island_removal_mode 0)
		)
		(polygon
			(pts
				(arc
					(start 207.165194 -351.54743)
					(mid 206.497174 -351.54743)
					(end 207.165194 -351.54743)
				)
			)
		)
	)
	(zone
		(layers "B.Cu" "In6.Cu" "In11.Cu" "In13.Cu" "In15.Cu")
		(hatch none 0.5)
		(connect_pads
			(clearance 0)
		)
		(min_thickness 0.25)
		(keepout
			(tracks not_allowed)
			(vias allowed)
			(pads allowed)
			(copperpour not_allowed)
			(footprints allowed)
		)
		(placement
			(enabled no)
			(sheetname "")
		)
		(fill yes
			(thermal_gap 0.5)
			(thermal_bridge_width 0.5)
			(island_removal_mode 0)
		)
		(polygon
			(pts
				(arc
					(start 379.769878 -254.204216)
					(mid 379.139958 -254.204216)
					(end 379.769878 -254.204216)
				)
			)
		)
	)
	(zone
		(layers "B.Cu" "In6.Cu" "In11.Cu" "In13.Cu" "In15.Cu")
		(hatch none 0.5)
		(connect_pads
			(clearance 0)
		)
		(min_thickness 0.25)
		(keepout
			(tracks not_allowed)
			(vias allowed)
			(pads allowed)
			(copperpour not_allowed)
			(footprints allowed)
		)
		(placement
			(enabled no)
			(sheetname "")
		)
		(fill yes
			(thermal_gap 0.5)
			(thermal_bridge_width 0.5)
			(island_removal_mode 0)
		)
		(polygon
			(pts
				(arc
					(start 26.549604 -6.725158)
					(mid 25.881584 -6.725158)
					(end 26.549604 -6.725158)
				)
			)
		)
	)
	(zone
		(layers "B.Cu" "In6.Cu" "In11.Cu" "In13.Cu" "In15.Cu")
		(hatch none 0.5)
		(connect_pads
			(clearance 0)
		)
		(min_thickness 0.25)
		(keepout
			(tracks not_allowed)
			(vias allowed)
			(pads allowed)
			(copperpour not_allowed)
			(footprints allowed)
		)
		(placement
			(enabled no)
			(sheetname "")
		)
		(fill yes
			(thermal_gap 0.5)
			(thermal_bridge_width 0.5)
			(island_removal_mode 0)
		)
		(polygon
			(pts
				(arc
					(start 339.355938 -234.764072)
					(mid 338.726018 -234.764072)
					(end 339.355938 -234.764072)
				)
			)
		)
	)
	(zone
		(layers "B.Cu" "In6.Cu" "In11.Cu" "In13.Cu" "In15.Cu")
		(hatch none 0.5)
		(connect_pads
			(clearance 0)
		)
		(min_thickness 0.25)
		(keepout
			(tracks not_allowed)
			(vias allowed)
			(pads allowed)
			(copperpour not_allowed)
			(footprints allowed)
		)
		(placement
			(enabled no)
			(sheetname "")
		)
		(fill yes
			(thermal_gap 0.5)
			(thermal_bridge_width 0.5)
			(island_removal_mode 0)
		)
		(polygon
			(pts
				(arc
					(start 97.162112 -371.49913)
					(mid 96.494092 -371.49913)
					(end 97.162112 -371.49913)
				)
			)
		)
	)
	(zone
		(layers "B.Cu" "In6.Cu" "In11.Cu" "In13.Cu" "In15.Cu")
		(hatch none 0.5)
		(connect_pads
			(clearance 0)
		)
		(min_thickness 0.25)
		(keepout
			(tracks not_allowed)
			(vias allowed)
			(pads allowed)
			(copperpour not_allowed)
			(footprints allowed)
		)
		(placement
			(enabled no)
			(sheetname "")
		)
		(fill yes
			(thermal_gap 0.5)
			(thermal_bridge_width 0.5)
			(island_removal_mode 0)
		)
		(polygon
			(pts
				(arc
					(start 407.986992 -412.84652)
					(mid 407.318972 -412.84652)
					(end 407.986992 -412.84652)
				)
			)
		)
	)
	(zone
		(layers "B.Cu" "In6.Cu" "In11.Cu" "In13.Cu" "In15.Cu")
		(hatch none 0.5)
		(connect_pads
			(clearance 0)
		)
		(min_thickness 0.25)
		(keepout
			(tracks not_allowed)
			(vias allowed)
			(pads allowed)
			(copperpour not_allowed)
			(footprints allowed)
		)
		(placement
			(enabled no)
			(sheetname "")
		)
		(fill yes
			(thermal_gap 0.5)
			(thermal_bridge_width 0.5)
			(island_removal_mode 0)
		)
		(polygon
			(pts
				(arc
					(start 131.359656 -245.294404)
					(mid 130.729736 -245.294404)
					(end 131.359656 -245.294404)
				)
			)
		)
	)
	(zone
		(layers "B.Cu" "In6.Cu" "In11.Cu" "In13.Cu" "In15.Cu")
		(hatch none 0.5)
		(connect_pads
			(clearance 0)
		)
		(min_thickness 0.25)
		(keepout
			(tracks not_allowed)
			(vias allowed)
			(pads allowed)
			(copperpour not_allowed)
			(footprints allowed)
		)
		(placement
			(enabled no)
			(sheetname "")
		)
		(fill yes
			(thermal_gap 0.5)
			(thermal_bridge_width 0.5)
			(island_removal_mode 0)
		)
		(polygon
			(pts
				(arc
					(start 357.046022 -287.045908)
					(mid 356.416102 -287.045908)
					(end 357.046022 -287.045908)
				)
			)
		)
	)
	(zone
		(layers "B.Cu" "In6.Cu" "In11.Cu" "In13.Cu" "In15.Cu")
		(hatch none 0.5)
		(connect_pads
			(clearance 0)
		)
		(min_thickness 0.25)
		(keepout
			(tracks not_allowed)
			(vias allowed)
			(pads allowed)
			(copperpour not_allowed)
			(footprints allowed)
		)
		(placement
			(enabled no)
			(sheetname "")
		)
		(fill yes
			(thermal_gap 0.5)
			(thermal_bridge_width 0.5)
			(island_removal_mode 0)
		)
		(polygon
			(pts
				(arc
					(start 33.029906 -267.03528)
					(mid 32.361886 -267.03528)
					(end 33.029906 -267.03528)
				)
			)
		)
	)
	(zone
		(layers "B.Cu" "In6.Cu" "In11.Cu" "In13.Cu" "In15.Cu")
		(hatch none 0.5)
		(connect_pads
			(clearance 0)
		)
		(min_thickness 0.25)
		(keepout
			(tracks not_allowed)
			(vias allowed)
			(pads allowed)
			(copperpour not_allowed)
			(footprints allowed)
		)
		(placement
			(enabled no)
			(sheetname "")
		)
		(fill yes
			(thermal_gap 0.5)
			(thermal_bridge_width 0.5)
			(island_removal_mode 0)
		)
		(polygon
			(pts
				(arc
					(start 374.80621 -393.69238)
					(mid 374.17629 -393.69238)
					(end 374.80621 -393.69238)
				)
			)
		)
	)
	(zone
		(layers "B.Cu" "In6.Cu" "In11.Cu" "In13.Cu" "In15.Cu")
		(hatch none 0.5)
		(connect_pads
			(clearance 0)
		)
		(min_thickness 0.25)
		(keepout
			(tracks not_allowed)
			(vias allowed)
			(pads allowed)
			(copperpour not_allowed)
			(footprints allowed)
		)
		(placement
			(enabled no)
			(sheetname "")
		)
		(fill yes
			(thermal_gap 0.5)
			(thermal_bridge_width 0.5)
			(island_removal_mode 0)
		)
		(polygon
			(pts
				(arc
					(start 379.299724 -253.39421)
					(mid 378.669804 -253.39421)
					(end 379.299724 -253.39421)
				)
			)
		)
	)
	(zone
		(layers "B.Cu" "In6.Cu" "In11.Cu" "In13.Cu" "In15.Cu")
		(hatch none 0.5)
		(connect_pads
			(clearance 0)
		)
		(min_thickness 0.25)
		(keepout
			(tracks not_allowed)
			(vias allowed)
			(pads allowed)
			(copperpour not_allowed)
			(footprints allowed)
		)
		(placement
			(enabled no)
			(sheetname "")
		)
		(fill yes
			(thermal_gap 0.5)
			(thermal_bridge_width 0.5)
			(island_removal_mode 0)
		)
		(polygon
			(pts
				(arc
					(start 132.76961 -254.20447)
					(mid 132.13969 -254.20447)
					(end 132.76961 -254.20447)
				)
			)
		)
	)
	(zone
		(layers "B.Cu" "In6.Cu" "In11.Cu" "In13.Cu" "In15.Cu")
		(hatch none 0.5)
		(connect_pads
			(clearance 0)
		)
		(min_thickness 0.25)
		(keepout
			(tracks not_allowed)
			(vias allowed)
			(pads allowed)
			(copperpour not_allowed)
			(footprints allowed)
		)
		(placement
			(enabled no)
			(sheetname "")
		)
		(fill yes
			(thermal_gap 0.5)
			(thermal_bridge_width 0.5)
			(island_removal_mode 0)
		)
		(polygon
			(pts
				(arc
					(start 341.06612 -278.946102)
					(mid 340.4362 -278.946102)
					(end 341.06612 -278.946102)
				)
			)
		)
	)
	(zone
		(layers "B.Cu" "In6.Cu" "In11.Cu" "In13.Cu" "In15.Cu")
		(hatch none 0.5)
		(connect_pads
			(clearance 0)
		)
		(min_thickness 0.25)
		(keepout
			(tracks not_allowed)
			(vias allowed)
			(pads allowed)
			(copperpour not_allowed)
			(footprints allowed)
		)
		(placement
			(enabled no)
			(sheetname "")
		)
		(fill yes
			(thermal_gap 0.5)
			(thermal_bridge_width 0.5)
			(island_removal_mode 0)
		)
		(polygon
			(pts
				(arc
					(start 102.05593 -289.47618)
					(mid 101.42601 -289.47618)
					(end 102.05593 -289.47618)
				)
			)
		)
	)
	(zone
		(layers "B.Cu" "In6.Cu" "In11.Cu" "In13.Cu" "In15.Cu")
		(hatch none 0.5)
		(connect_pads
			(clearance 0)
		)
		(min_thickness 0.25)
		(keepout
			(tracks not_allowed)
			(vias allowed)
			(pads allowed)
			(copperpour not_allowed)
			(footprints allowed)
		)
		(placement
			(enabled no)
			(sheetname "")
		)
		(fill yes
			(thermal_gap 0.5)
			(thermal_bridge_width 0.5)
			(island_removal_mode 0)
		)
		(polygon
			(pts
				(arc
					(start 280.969974 -295.085008)
					(mid 280.301954 -295.085008)
					(end 280.969974 -295.085008)
				)
			)
		)
	)
	(zone
		(layers "B.Cu" "In6.Cu" "In11.Cu" "In13.Cu" "In15.Cu")
		(hatch none 0.5)
		(connect_pads
			(clearance 0)
		)
		(min_thickness 0.25)
		(keepout
			(tracks not_allowed)
			(vias allowed)
			(pads allowed)
			(copperpour not_allowed)
			(footprints allowed)
		)
		(placement
			(enabled no)
			(sheetname "")
		)
		(fill yes
			(thermal_gap 0.5)
			(thermal_bridge_width 0.5)
			(island_removal_mode 0)
		)
		(polygon
			(pts
				(arc
					(start 37.129974 -214.33536)
					(mid 36.461954 -214.33536)
					(end 37.129974 -214.33536)
				)
			)
		)
	)
	(zone
		(layers "B.Cu" "In6.Cu" "In11.Cu" "In13.Cu" "In15.Cu")
		(hatch none 0.5)
		(connect_pads
			(clearance 0)
		)
		(min_thickness 0.25)
		(keepout
			(tracks not_allowed)
			(vias allowed)
			(pads allowed)
			(copperpour not_allowed)
			(footprints allowed)
		)
		(placement
			(enabled no)
			(sheetname "")
		)
		(fill yes
			(thermal_gap 0.5)
			(thermal_bridge_width 0.5)
			(island_removal_mode 0)
		)
		(polygon
			(pts
				(arc
					(start 439.434224 -303.585118)
					(mid 438.766204 -303.585118)
					(end 439.434224 -303.585118)
				)
			)
		)
	)
	(zone
		(layers "B.Cu" "In6.Cu" "In11.Cu" "In13.Cu" "In15.Cu")
		(hatch none 0.5)
		(connect_pads
			(clearance 0)
		)
		(min_thickness 0.25)
		(keepout
			(tracks not_allowed)
			(vias allowed)
			(pads allowed)
			(copperpour not_allowed)
			(footprints allowed)
		)
		(placement
			(enabled no)
			(sheetname "")
		)
		(fill yes
			(thermal_gap 0.5)
			(thermal_bridge_width 0.5)
			(island_removal_mode 0)
		)
		(polygon
			(pts
				(arc
					(start 439.434224 -301.885096)
					(mid 438.766204 -301.885096)
					(end 439.434224 -301.885096)
				)
			)
		)
	)
	(zone
		(layers "B.Cu" "In6.Cu" "In11.Cu" "In13.Cu" "In15.Cu")
		(hatch none 0.5)
		(connect_pads
			(clearance 0)
		)
		(min_thickness 0.25)
		(keepout
			(tracks not_allowed)
			(vias allowed)
			(pads allowed)
			(copperpour not_allowed)
			(footprints allowed)
		)
		(placement
			(enabled no)
			(sheetname "")
		)
		(fill yes
			(thermal_gap 0.5)
			(thermal_bridge_width 0.5)
			(island_removal_mode 0)
		)
		(polygon
			(pts
				(arc
					(start 91.41587 -236.384338)
					(mid 90.78595 -236.384338)
					(end 91.41587 -236.384338)
				)
			)
		)
	)
	(zone
		(layers "B.Cu" "In6.Cu" "In11.Cu" "In13.Cu" "In15.Cu")
		(hatch none 0.5)
		(connect_pads
			(clearance 0)
		)
		(min_thickness 0.25)
		(keepout
			(tracks not_allowed)
			(vias allowed)
			(pads allowed)
			(copperpour not_allowed)
			(footprints allowed)
		)
		(placement
			(enabled no)
			(sheetname "")
		)
		(fill yes
			(thermal_gap 0.5)
			(thermal_bridge_width 0.5)
			(island_removal_mode 0)
		)
		(polygon
			(pts
				(arc
					(start 148.933916 -388.774432)
					(mid 148.303996 -388.774432)
					(end 148.933916 -388.774432)
				)
			)
		)
	)
	(zone
		(layers "B.Cu" "In6.Cu" "In11.Cu" "In13.Cu" "In15.Cu")
		(hatch none 0.5)
		(connect_pads
			(clearance 0)
		)
		(min_thickness 0.25)
		(keepout
			(tracks not_allowed)
			(vias allowed)
			(pads allowed)
			(copperpour not_allowed)
			(footprints allowed)
		)
		(placement
			(enabled no)
			(sheetname "")
		)
		(fill yes
			(thermal_gap 0.5)
			(thermal_bridge_width 0.5)
			(island_removal_mode 0)
		)
		(polygon
			(pts
				(arc
					(start 285.070042 -315.485018)
					(mid 284.402022 -315.485018)
					(end 285.070042 -315.485018)
				)
			)
		)
	)
	(zone
		(layers "B.Cu" "In6.Cu" "In11.Cu" "In13.Cu" "In15.Cu")
		(hatch none 0.5)
		(connect_pads
			(clearance 0)
		)
		(min_thickness 0.25)
		(keepout
			(tracks not_allowed)
			(vias allowed)
			(pads allowed)
			(copperpour not_allowed)
			(footprints allowed)
		)
		(placement
			(enabled no)
			(sheetname "")
		)
		(fill yes
			(thermal_gap 0.5)
			(thermal_bridge_width 0.5)
			(island_removal_mode 0)
		)
		(polygon
			(pts
				(arc
					(start 37.129974 -231.335326)
					(mid 36.461954 -231.335326)
					(end 37.129974 -231.335326)
				)
			)
		)
	)
	(zone
		(layers "B.Cu" "In6.Cu" "In11.Cu" "In13.Cu" "In15.Cu")
		(hatch none 0.5)
		(connect_pads
			(clearance 0)
		)
		(min_thickness 0.25)
		(keepout
			(tracks not_allowed)
			(vias allowed)
			(pads allowed)
			(copperpour not_allowed)
			(footprints allowed)
		)
		(placement
			(enabled no)
			(sheetname "")
		)
		(fill yes
			(thermal_gap 0.5)
			(thermal_bridge_width 0.5)
			(island_removal_mode 0)
		)
		(polygon
			(pts
				(arc
					(start 338.886038 -227.474272)
					(mid 338.256118 -227.474272)
					(end 338.886038 -227.474272)
				)
			)
		)
	)
	(zone
		(layers "B.Cu" "In6.Cu" "In11.Cu" "In13.Cu" "In15.Cu")
		(hatch none 0.5)
		(connect_pads
			(clearance 0)
		)
		(min_thickness 0.25)
		(keepout
			(tracks not_allowed)
			(vias allowed)
			(pads allowed)
			(copperpour not_allowed)
			(footprints allowed)
		)
		(placement
			(enabled no)
			(sheetname "")
		)
		(fill yes
			(thermal_gap 0.5)
			(thermal_bridge_width 0.5)
			(island_removal_mode 0)
		)
		(polygon
			(pts
				(arc
					(start 322.507356 -412.84652)
					(mid 321.839336 -412.84652)
					(end 322.507356 -412.84652)
				)
			)
		)
	)
	(zone
		(layers "B.Cu" "In6.Cu" "In11.Cu" "In13.Cu" "In15.Cu")
		(hatch none 0.5)
		(connect_pads
			(clearance 0)
		)
		(min_thickness 0.25)
		(keepout
			(tracks not_allowed)
			(vias allowed)
			(pads allowed)
			(copperpour not_allowed)
			(footprints allowed)
		)
		(placement
			(enabled no)
			(sheetname "")
		)
		(fill yes
			(thermal_gap 0.5)
			(thermal_bridge_width 0.5)
			(island_removal_mode 0)
		)
		(polygon
			(pts
				(arc
					(start 435.334156 -238.985044)
					(mid 434.666136 -238.985044)
					(end 435.334156 -238.985044)
				)
			)
		)
	)
	(zone
		(layers "B.Cu" "In6.Cu" "In11.Cu" "In13.Cu" "In15.Cu")
		(hatch none 0.5)
		(connect_pads
			(clearance 0)
		)
		(min_thickness 0.25)
		(keepout
			(tracks not_allowed)
			(vias allowed)
			(pads allowed)
			(copperpour not_allowed)
			(footprints allowed)
		)
		(placement
			(enabled no)
			(sheetname "")
		)
		(fill yes
			(thermal_gap 0.5)
			(thermal_bridge_width 0.5)
			(island_removal_mode 0)
		)
		(polygon
			(pts
				(arc
					(start 389.607552 -412.84652)
					(mid 388.939532 -412.84652)
					(end 389.607552 -412.84652)
				)
			)
		)
	)
	(zone
		(layers "B.Cu" "In6.Cu" "In11.Cu" "In13.Cu" "In15.Cu")
		(hatch none 0.5)
		(connect_pads
			(clearance 0)
		)
		(min_thickness 0.25)
		(keepout
			(tracks not_allowed)
			(vias allowed)
			(pads allowed)
			(copperpour not_allowed)
			(footprints allowed)
		)
		(placement
			(enabled no)
			(sheetname "")
		)
		(fill yes
			(thermal_gap 0.5)
			(thermal_bridge_width 0.5)
			(island_removal_mode 0)
		)
		(polygon
			(pts
				(arc
					(start 42.859706 -6.725158)
					(mid 42.191686 -6.725158)
					(end 42.859706 -6.725158)
				)
			)
		)
	)
	(zone
		(layers "B.Cu" "In6.Cu" "In11.Cu" "In13.Cu" "In15.Cu")
		(hatch none 0.5)
		(connect_pads
			(clearance 0)
		)
		(min_thickness 0.25)
		(keepout
			(tracks not_allowed)
			(vias allowed)
			(pads allowed)
			(copperpour not_allowed)
			(footprints allowed)
		)
		(placement
			(enabled no)
			(sheetname "")
		)
		(fill yes
			(thermal_gap 0.5)
			(thermal_bridge_width 0.5)
			(island_removal_mode 0)
		)
		(polygon
			(pts
				(arc
					(start 191.494156 -309.535322)
					(mid 190.826136 -309.535322)
					(end 191.494156 -309.535322)
				)
			)
		)
	)
	(zone
		(layers "B.Cu" "In6.Cu" "In11.Cu" "In13.Cu" "In15.Cu")
		(hatch none 0.5)
		(connect_pads
			(clearance 0)
		)
		(min_thickness 0.25)
		(keepout
			(tracks not_allowed)
			(vias allowed)
			(pads allowed)
			(copperpour not_allowed)
			(footprints allowed)
		)
		(placement
			(enabled no)
			(sheetname "")
		)
		(fill yes
			(thermal_gap 0.5)
			(thermal_bridge_width 0.5)
			(island_removal_mode 0)
		)
		(polygon
			(pts
				(arc
					(start 381.009906 -284.616144)
					(mid 380.379986 -284.616144)
					(end 381.009906 -284.616144)
				)
			)
		)
	)
	(zone
		(layers "B.Cu" "In6.Cu" "In11.Cu" "In13.Cu" "In15.Cu")
		(hatch none 0.5)
		(connect_pads
			(clearance 0)
		)
		(min_thickness 0.25)
		(keepout
			(tracks not_allowed)
			(vias allowed)
			(pads allowed)
			(copperpour not_allowed)
			(footprints allowed)
		)
		(placement
			(enabled no)
			(sheetname "")
		)
		(fill yes
			(thermal_gap 0.5)
			(thermal_bridge_width 0.5)
			(island_removal_mode 0)
		)
		(polygon
			(pts
				(arc
					(start 398.749774 -19.13636)
					(mid 398.081754 -19.13636)
					(end 398.749774 -19.13636)
				)
			)
		)
	)
	(zone
		(layers "B.Cu" "In6.Cu" "In11.Cu" "In13.Cu" "In15.Cu")
		(hatch none 0.5)
		(connect_pads
			(clearance 0)
		)
		(min_thickness 0.25)
		(keepout
			(tracks not_allowed)
			(vias allowed)
			(pads allowed)
			(copperpour not_allowed)
			(footprints allowed)
		)
		(placement
			(enabled no)
			(sheetname "")
		)
		(fill yes
			(thermal_gap 0.5)
			(thermal_bridge_width 0.5)
			(island_removal_mode 0)
		)
		(polygon
			(pts
				(arc
					(start 439.434224 -317.18504)
					(mid 438.766204 -317.18504)
					(end 439.434224 -317.18504)
				)
			)
		)
	)
	(zone
		(layers "B.Cu" "In6.Cu" "In11.Cu" "In13.Cu" "In15.Cu")
		(hatch none 0.5)
		(connect_pads
			(clearance 0)
		)
		(min_thickness 0.25)
		(keepout
			(tracks not_allowed)
			(vias allowed)
			(pads allowed)
			(copperpour not_allowed)
			(footprints allowed)
		)
		(placement
			(enabled no)
			(sheetname "")
		)
		(fill yes
			(thermal_gap 0.5)
			(thermal_bridge_width 0.5)
			(island_removal_mode 0)
		)
		(polygon
			(pts
				(arc
					(start 439.434224 -269.585186)
					(mid 438.766204 -269.585186)
					(end 439.434224 -269.585186)
				)
			)
		)
	)
	(zone
		(layers "B.Cu" "In6.Cu" "In11.Cu" "In13.Cu" "In15.Cu")
		(hatch none 0.5)
		(connect_pads
			(clearance 0)
		)
		(min_thickness 0.25)
		(keepout
			(tracks not_allowed)
			(vias allowed)
			(pads allowed)
			(copperpour not_allowed)
			(footprints allowed)
		)
		(placement
			(enabled no)
			(sheetname "")
		)
		(fill yes
			(thermal_gap 0.5)
			(thermal_bridge_width 0.5)
			(island_removal_mode 0)
		)
		(polygon
			(pts
				(arc
					(start 187.394088 -210.935316)
					(mid 186.726068 -210.935316)
					(end 187.394088 -210.935316)
				)
			)
		)
	)
	(zone
		(layers "B.Cu" "In6.Cu" "In11.Cu" "In13.Cu" "In15.Cu")
		(hatch none 0.5)
		(connect_pads
			(clearance 0)
		)
		(min_thickness 0.25)
		(keepout
			(tracks not_allowed)
			(vias allowed)
			(pads allowed)
			(copperpour not_allowed)
			(footprints allowed)
		)
		(placement
			(enabled no)
			(sheetname "")
		)
		(fill yes
			(thermal_gap 0.5)
			(thermal_bridge_width 0.5)
			(island_removal_mode 0)
		)
		(polygon
			(pts
				(arc
					(start 439.434224 -252.584966)
					(mid 438.766204 -252.584966)
					(end 439.434224 -252.584966)
				)
			)
		)
	)
	(zone
		(layers "B.Cu" "In6.Cu" "In11.Cu" "In13.Cu" "In15.Cu")
		(hatch none 0.5)
		(connect_pads
			(clearance 0)
		)
		(min_thickness 0.25)
		(keepout
			(tracks not_allowed)
			(vias allowed)
			(pads allowed)
			(copperpour not_allowed)
			(footprints allowed)
		)
		(placement
			(enabled no)
			(sheetname "")
		)
		(fill yes
			(thermal_gap 0.5)
			(thermal_bridge_width 0.5)
			(island_removal_mode 0)
		)
		(polygon
			(pts
				(arc
					(start 37.129974 -199.035416)
					(mid 36.461954 -199.035416)
					(end 37.129974 -199.035416)
				)
			)
		)
	)
	(zone
		(layers "B.Cu" "In6.Cu" "In11.Cu" "In13.Cu" "In15.Cu")
		(hatch none 0.5)
		(connect_pads
			(clearance 0)
		)
		(min_thickness 0.25)
		(keepout
			(tracks not_allowed)
			(vias allowed)
			(pads allowed)
			(copperpour not_allowed)
			(footprints allowed)
		)
		(placement
			(enabled no)
			(sheetname "")
		)
		(fill yes
			(thermal_gap 0.5)
			(thermal_bridge_width 0.5)
			(island_removal_mode 0)
		)
		(polygon
			(pts
				(arc
					(start 126.406148 -386.003292)
					(mid 125.776228 -386.003292)
					(end 126.406148 -386.003292)
				)
			)
		)
	)
	(zone
		(layers "B.Cu" "In6.Cu" "In11.Cu" "In13.Cu" "In15.Cu")
		(hatch none 0.5)
		(connect_pads
			(clearance 0)
		)
		(min_thickness 0.25)
		(keepout
			(tracks not_allowed)
			(vias allowed)
			(pads allowed)
			(copperpour not_allowed)
			(footprints allowed)
		)
		(placement
			(enabled no)
			(sheetname "")
		)
		(fill yes
			(thermal_gap 0.5)
			(thermal_bridge_width 0.5)
			(island_removal_mode 0)
		)
		(polygon
			(pts
				(arc
					(start 91.245944 -277.326344)
					(mid 90.616024 -277.326344)
					(end 91.245944 -277.326344)
				)
			)
		)
	)
	(zone
		(layers "B.Cu" "In6.Cu" "In11.Cu" "In13.Cu" "In15.Cu")
		(hatch none 0.5)
		(connect_pads
			(clearance 0)
		)
		(min_thickness 0.25)
		(keepout
			(tracks not_allowed)
			(vias allowed)
			(pads allowed)
			(copperpour not_allowed)
			(footprints allowed)
		)
		(placement
			(enabled no)
			(sheetname "")
		)
		(fill yes
			(thermal_gap 0.5)
			(thermal_bridge_width 0.5)
			(island_removal_mode 0)
		)
		(polygon
			(pts
				(arc
					(start 37.129974 -254.285242)
					(mid 36.461954 -254.285242)
					(end 37.129974 -254.285242)
				)
			)
		)
	)
	(zone
		(layers "B.Cu" "In6.Cu" "In11.Cu" "In13.Cu" "In15.Cu")
		(hatch none 0.5)
		(connect_pads
			(clearance 0)
		)
		(min_thickness 0.25)
		(keepout
			(tracks not_allowed)
			(vias allowed)
			(pads allowed)
			(copperpour not_allowed)
			(footprints allowed)
		)
		(placement
			(enabled no)
			(sheetname "")
		)
		(fill yes
			(thermal_gap 0.5)
			(thermal_bridge_width 0.5)
			(island_removal_mode 0)
		)
		(polygon
			(pts
				(arc
					(start 131.65963 -264.366248)
					(mid 131.02971 -264.366248)
					(end 131.65963 -264.366248)
				)
			)
		)
	)
	(zone
		(layers "B.Cu" "In6.Cu" "In11.Cu" "In13.Cu" "In15.Cu")
		(hatch none 0.5)
		(connect_pads
			(clearance 0)
		)
		(min_thickness 0.25)
		(keepout
			(tracks not_allowed)
			(vias allowed)
			(pads allowed)
			(copperpour not_allowed)
			(footprints allowed)
		)
		(placement
			(enabled no)
			(sheetname "")
		)
		(fill yes
			(thermal_gap 0.5)
			(thermal_bridge_width 0.5)
			(island_removal_mode 0)
		)
		(polygon
			(pts
				(arc
					(start 102.267512 -369.03533)
					(mid 101.599492 -369.03533)
					(end 102.267512 -369.03533)
				)
			)
		)
	)
	(zone
		(layers "B.Cu" "In6.Cu" "In11.Cu" "In13.Cu" "In15.Cu")
		(hatch none 0.5)
		(connect_pads
			(clearance 0)
		)
		(min_thickness 0.25)
		(keepout
			(tracks not_allowed)
			(vias allowed)
			(pads allowed)
			(copperpour not_allowed)
			(footprints allowed)
		)
		(placement
			(enabled no)
			(sheetname "")
		)
		(fill yes
			(thermal_gap 0.5)
			(thermal_bridge_width 0.5)
			(island_removal_mode 0)
		)
		(polygon
			(pts
				(arc
					(start 439.434224 -294.235124)
					(mid 438.766204 -294.235124)
					(end 439.434224 -294.235124)
				)
			)
		)
	)
	(zone
		(layers "B.Cu" "In6.Cu" "In11.Cu" "In13.Cu" "In15.Cu")
		(hatch none 0.5)
		(connect_pads
			(clearance 0)
		)
		(min_thickness 0.25)
		(keepout
			(tracks not_allowed)
			(vias allowed)
			(pads allowed)
			(copperpour not_allowed)
			(footprints allowed)
		)
		(placement
			(enabled no)
			(sheetname "")
		)
		(fill yes
			(thermal_gap 0.5)
			(thermal_bridge_width 0.5)
			(island_removal_mode 0)
		)
		(polygon
			(pts
				(arc
					(start 360.139234 -385.338828)
					(mid 359.471214 -385.338828)
					(end 360.139234 -385.338828)
				)
			)
		)
	)
	(zone
		(layers "B.Cu" "In6.Cu" "In11.Cu" "In13.Cu" "In15.Cu")
		(hatch none 0.5)
		(connect_pads
			(clearance 0)
		)
		(min_thickness 0.25)
		(keepout
			(tracks not_allowed)
			(vias allowed)
			(pads allowed)
			(copperpour not_allowed)
			(footprints allowed)
		)
		(placement
			(enabled no)
			(sheetname "")
		)
		(fill yes
			(thermal_gap 0.5)
			(thermal_bridge_width 0.5)
			(island_removal_mode 0)
		)
		(polygon
			(pts
				(arc
					(start 90.94597 -227.474526)
					(mid 90.31605 -227.474526)
					(end 90.94597 -227.474526)
				)
			)
		)
	)
	(zone
		(layers "B.Cu" "In6.Cu" "In11.Cu" "In13.Cu" "In15.Cu")
		(hatch none 0.5)
		(connect_pads
			(clearance 0)
		)
		(min_thickness 0.25)
		(keepout
			(tracks not_allowed)
			(vias allowed)
			(pads allowed)
			(copperpour not_allowed)
			(footprints allowed)
		)
		(placement
			(enabled no)
			(sheetname "")
		)
		(fill yes
			(thermal_gap 0.5)
			(thermal_bridge_width 0.5)
			(island_removal_mode 0)
		)
		(polygon
			(pts
				(arc
					(start 418.040312 -412.84652)
					(mid 417.372292 -412.84652)
					(end 418.040312 -412.84652)
				)
			)
		)
	)
	(zone
		(layers "B.Cu" "In6.Cu" "In11.Cu" "In13.Cu" "In15.Cu")
		(hatch none 0.5)
		(connect_pads
			(clearance 0)
		)
		(min_thickness 0.25)
		(keepout
			(tracks not_allowed)
			(vias allowed)
			(pads allowed)
			(copperpour not_allowed)
			(footprints allowed)
		)
		(placement
			(enabled no)
			(sheetname "")
		)
		(fill yes
			(thermal_gap 0.5)
			(thermal_bridge_width 0.5)
			(island_removal_mode 0)
		)
		(polygon
			(pts
				(arc
					(start 374.291352 -412.84652)
					(mid 373.623332 -412.84652)
					(end 374.291352 -412.84652)
				)
			)
		)
	)
	(zone
		(layers "B.Cu" "In6.Cu" "In11.Cu" "In13.Cu" "In15.Cu")
		(hatch none 0.5)
		(connect_pads
			(clearance 0)
		)
		(min_thickness 0.25)
		(keepout
			(tracks not_allowed)
			(vias allowed)
			(pads allowed)
			(copperpour not_allowed)
			(footprints allowed)
		)
		(placement
			(enabled no)
			(sheetname "")
		)
		(fill yes
			(thermal_gap 0.5)
			(thermal_bridge_width 0.5)
			(island_removal_mode 0)
		)
		(polygon
			(pts
				(arc
					(start 280.969974 -216.885012)
					(mid 280.301954 -216.885012)
					(end 280.969974 -216.885012)
				)
			)
		)
	)
	(zone
		(layers "B.Cu" "In6.Cu" "In11.Cu" "In13.Cu" "In15.Cu")
		(hatch none 0.5)
		(connect_pads
			(clearance 0)
		)
		(min_thickness 0.25)
		(keepout
			(tracks not_allowed)
			(vias allowed)
			(pads allowed)
			(copperpour not_allowed)
			(footprints allowed)
		)
		(placement
			(enabled no)
			(sheetname "")
		)
		(fill yes
			(thermal_gap 0.5)
			(thermal_bridge_width 0.5)
			(island_removal_mode 0)
		)
		(polygon
			(pts
				(arc
					(start 123.369578 -226.66452)
					(mid 122.739658 -226.66452)
					(end 123.369578 -226.66452)
				)
			)
		)
	)
	(zone
		(layers "B.Cu" "In6.Cu" "In11.Cu" "In13.Cu" "In15.Cu")
		(hatch none 0.5)
		(connect_pads
			(clearance 0)
		)
		(min_thickness 0.25)
		(keepout
			(tracks not_allowed)
			(vias allowed)
			(pads allowed)
			(copperpour not_allowed)
			(footprints allowed)
		)
		(placement
			(enabled no)
			(sheetname "")
		)
		(fill yes
			(thermal_gap 0.5)
			(thermal_bridge_width 0.5)
			(island_removal_mode 0)
		)
		(polygon
			(pts
				(arc
					(start 353.161854 -379.88113)
					(mid 352.493834 -379.88113)
					(end 353.161854 -379.88113)
				)
			)
		)
	)
	(zone
		(layers "B.Cu" "In6.Cu" "In11.Cu" "In13.Cu" "In15.Cu")
		(hatch none 0.5)
		(connect_pads
			(clearance 0)
		)
		(min_thickness 0.25)
		(keepout
			(tracks not_allowed)
			(vias allowed)
			(pads allowed)
			(copperpour not_allowed)
			(footprints allowed)
		)
		(placement
			(enabled no)
			(sheetname "")
		)
		(fill yes
			(thermal_gap 0.5)
			(thermal_bridge_width 0.5)
			(island_removal_mode 0)
		)
		(polygon
			(pts
				(arc
					(start 306.506118 -397.156432)
					(mid 305.876198 -397.156432)
					(end 306.506118 -397.156432)
				)
			)
		)
	)
	(zone
		(layers "B.Cu" "In6.Cu" "In11.Cu" "In13.Cu" "In15.Cu")
		(hatch none 0.5)
		(connect_pads
			(clearance 0)
		)
		(min_thickness 0.25)
		(keepout
			(tracks not_allowed)
			(vias allowed)
			(pads allowed)
			(copperpour not_allowed)
			(footprints allowed)
		)
		(placement
			(enabled no)
			(sheetname "")
		)
		(fill yes
			(thermal_gap 0.5)
			(thermal_bridge_width 0.5)
			(island_removal_mode 0)
		)
		(polygon
			(pts
				(arc
					(start 379.769878 -236.384084)
					(mid 379.139958 -236.384084)
					(end 379.769878 -236.384084)
				)
			)
		)
	)
	(zone
		(layers "B.Cu" "In6.Cu" "In11.Cu" "In13.Cu" "In15.Cu")
		(hatch none 0.5)
		(connect_pads
			(clearance 0)
		)
		(min_thickness 0.25)
		(keepout
			(tracks not_allowed)
			(vias allowed)
			(pads allowed)
			(copperpour not_allowed)
			(footprints allowed)
		)
		(placement
			(enabled no)
			(sheetname "")
		)
		(fill yes
			(thermal_gap 0.5)
			(thermal_bridge_width 0.5)
			(island_removal_mode 0)
		)
		(polygon
			(pts
				(arc
					(start 435.334156 -221.13494)
					(mid 434.666136 -221.13494)
					(end 435.334156 -221.13494)
				)
			)
		)
	)
	(zone
		(layers "B.Cu" "In6.Cu" "In11.Cu" "In13.Cu" "In15.Cu")
		(hatch none 0.5)
		(connect_pads
			(clearance 0)
		)
		(min_thickness 0.25)
		(keepout
			(tracks not_allowed)
			(vias allowed)
			(pads allowed)
			(copperpour not_allowed)
			(footprints allowed)
		)
		(placement
			(enabled no)
			(sheetname "")
		)
		(fill yes
			(thermal_gap 0.5)
			(thermal_bridge_width 0.5)
			(island_removal_mode 0)
		)
		(polygon
			(pts
				(arc
					(start 133.539738 -277.326344)
					(mid 132.909818 -277.326344)
					(end 133.539738 -277.326344)
				)
			)
		)
	)
	(zone
		(layers "B.Cu" "In6.Cu" "In11.Cu" "In13.Cu" "In15.Cu")
		(hatch none 0.5)
		(connect_pads
			(clearance 0)
		)
		(min_thickness 0.25)
		(keepout
			(tracks not_allowed)
			(vias allowed)
			(pads allowed)
			(copperpour not_allowed)
			(footprints allowed)
		)
		(placement
			(enabled no)
			(sheetname "")
		)
		(fill yes
			(thermal_gap 0.5)
			(thermal_bridge_width 0.5)
			(island_removal_mode 0)
		)
		(polygon
			(pts
				(arc
					(start 390.471152 -412.84652)
					(mid 389.803132 -412.84652)
					(end 390.471152 -412.84652)
				)
			)
		)
	)
	(zone
		(layers "B.Cu" "In6.Cu" "In11.Cu" "In13.Cu" "In15.Cu")
		(hatch none 0.5)
		(connect_pads
			(clearance 0)
		)
		(min_thickness 0.25)
		(keepout
			(tracks not_allowed)
			(vias allowed)
			(pads allowed)
			(copperpour not_allowed)
			(footprints allowed)
		)
		(placement
			(enabled no)
			(sheetname "")
		)
		(fill yes
			(thermal_gap 0.5)
			(thermal_bridge_width 0.5)
			(island_removal_mode 0)
		)
		(polygon
			(pts
				(arc
					(start 155.913836 -404.46452)
					(mid 155.245816 -404.46452)
					(end 155.913836 -404.46452)
				)
			)
		)
	)
	(zone
		(layers "B.Cu" "In6.Cu" "In11.Cu" "In13.Cu" "In15.Cu")
		(hatch none 0.5)
		(connect_pads
			(clearance 0)
		)
		(min_thickness 0.25)
		(keepout
			(tracks not_allowed)
			(vias allowed)
			(pads allowed)
			(copperpour not_allowed)
			(footprints allowed)
		)
		(placement
			(enabled no)
			(sheetname "")
		)
		(fill yes
			(thermal_gap 0.5)
			(thermal_bridge_width 0.5)
			(island_removal_mode 0)
		)
		(polygon
			(pts
				(arc
					(start 187.394088 -198.185278)
					(mid 186.726068 -198.185278)
					(end 187.394088 -198.185278)
				)
			)
		)
	)
	(zone
		(layers "B.Cu" "In6.Cu" "In11.Cu" "In13.Cu" "In15.Cu")
		(hatch none 0.5)
		(connect_pads
			(clearance 0)
		)
		(min_thickness 0.25)
		(keepout
			(tracks not_allowed)
			(vias allowed)
			(pads allowed)
			(copperpour not_allowed)
			(footprints allowed)
		)
		(placement
			(enabled no)
			(sheetname "")
		)
		(fill yes
			(thermal_gap 0.5)
			(thermal_bridge_width 0.5)
			(island_removal_mode 0)
		)
		(polygon
			(pts
				(arc
					(start 323.370956 -412.84652)
					(mid 322.702936 -412.84652)
					(end 323.370956 -412.84652)
				)
			)
		)
	)
	(zone
		(layers "B.Cu" "In6.Cu" "In11.Cu" "In13.Cu" "In15.Cu")
		(hatch none 0.5)
		(connect_pads
			(clearance 0)
		)
		(min_thickness 0.25)
		(keepout
			(tracks not_allowed)
			(vias allowed)
			(pads allowed)
			(copperpour not_allowed)
			(footprints allowed)
		)
		(placement
			(enabled no)
			(sheetname "")
		)
		(fill yes
			(thermal_gap 0.5)
			(thermal_bridge_width 0.5)
			(island_removal_mode 0)
		)
		(polygon
			(pts
				(arc
					(start 131.359656 -240.434368)
					(mid 130.729736 -240.434368)
					(end 131.359656 -240.434368)
				)
			)
		)
	)
	(zone
		(layers "B.Cu" "In6.Cu" "In11.Cu" "In13.Cu" "In15.Cu")
		(hatch none 0.5)
		(connect_pads
			(clearance 0)
		)
		(min_thickness 0.25)
		(keepout
			(tracks not_allowed)
			(vias allowed)
			(pads allowed)
			(copperpour not_allowed)
			(footprints allowed)
		)
		(placement
			(enabled no)
			(sheetname "")
		)
		(fill yes
			(thermal_gap 0.5)
			(thermal_bridge_width 0.5)
			(island_removal_mode 0)
		)
		(polygon
			(pts
				(arc
					(start 395.955774 -17.61236)
					(mid 395.287754 -17.61236)
					(end 395.955774 -17.61236)
				)
			)
		)
	)
	(zone
		(layers "B.Cu" "In6.Cu" "In11.Cu" "In13.Cu" "In15.Cu")
		(hatch none 0.5)
		(connect_pads
			(clearance 0)
		)
		(min_thickness 0.25)
		(keepout
			(tracks not_allowed)
			(vias allowed)
			(pads allowed)
			(copperpour not_allowed)
			(footprints allowed)
		)
		(placement
			(enabled no)
			(sheetname "")
		)
		(fill yes
			(thermal_gap 0.5)
			(thermal_bridge_width 0.5)
			(island_removal_mode 0)
		)
		(polygon
			(pts
				(arc
					(start 119.609616 -226.66452)
					(mid 118.979696 -226.66452)
					(end 119.609616 -226.66452)
				)
			)
		)
	)
	(zone
		(layers "B.Cu" "In6.Cu" "In11.Cu" "In13.Cu" "In15.Cu")
		(hatch none 0.5)
		(connect_pads
			(clearance 0)
		)
		(min_thickness 0.25)
		(keepout
			(tracks not_allowed)
			(vias allowed)
			(pads allowed)
			(copperpour not_allowed)
			(footprints allowed)
		)
		(placement
			(enabled no)
			(sheetname "")
		)
		(fill yes
			(thermal_gap 0.5)
			(thermal_bridge_width 0.5)
			(island_removal_mode 0)
		)
		(polygon
			(pts
				(arc
					(start 93.126052 -274.08632)
					(mid 92.496132 -274.08632)
					(end 93.126052 -274.08632)
				)
			)
		)
	)
	(zone
		(layers "B.Cu" "In6.Cu" "In11.Cu" "In13.Cu" "In15.Cu")
		(hatch none 0.5)
		(connect_pads
			(clearance 0)
		)
		(min_thickness 0.25)
		(keepout
			(tracks not_allowed)
			(vias allowed)
			(pads allowed)
			(copperpour not_allowed)
			(footprints allowed)
		)
		(placement
			(enabled no)
			(sheetname "")
		)
		(fill yes
			(thermal_gap 0.5)
			(thermal_bridge_width 0.5)
			(island_removal_mode 0)
		)
		(polygon
			(pts
				(arc
					(start 187.394088 -316.33541)
					(mid 186.726068 -316.33541)
					(end 187.394088 -316.33541)
				)
			)
		)
	)
	(zone
		(layers "B.Cu" "In6.Cu" "In11.Cu" "In13.Cu" "In15.Cu")
		(hatch none 0.5)
		(connect_pads
			(clearance 0)
		)
		(min_thickness 0.25)
		(keepout
			(tracks not_allowed)
			(vias allowed)
			(pads allowed)
			(copperpour not_allowed)
			(footprints allowed)
		)
		(placement
			(enabled no)
			(sheetname "")
		)
		(fill yes
			(thermal_gap 0.5)
			(thermal_bridge_width 0.5)
			(island_removal_mode 0)
		)
		(polygon
			(pts
				(arc
					(start 392.670792 -412.84652)
					(mid 392.002772 -412.84652)
					(end 392.670792 -412.84652)
				)
			)
		)
	)
	(zone
		(layers "B.Cu" "In6.Cu" "In11.Cu" "In13.Cu" "In15.Cu")
		(hatch none 0.5)
		(connect_pads
			(clearance 0)
		)
		(min_thickness 0.25)
		(keepout
			(tracks not_allowed)
			(vias allowed)
			(pads allowed)
			(copperpour not_allowed)
			(footprints allowed)
		)
		(placement
			(enabled no)
			(sheetname "")
		)
		(fill yes
			(thermal_gap 0.5)
			(thermal_bridge_width 0.5)
			(island_removal_mode 0)
		)
		(polygon
			(pts
				(arc
					(start 152.933908 -389.467344)
					(mid 152.303988 -389.467344)
					(end 152.933908 -389.467344)
				)
			)
		)
	)
	(zone
		(layers "B.Cu" "In6.Cu" "In11.Cu" "In13.Cu" "In15.Cu")
		(hatch none 0.5)
		(connect_pads
			(clearance 0)
		)
		(min_thickness 0.25)
		(keepout
			(tracks not_allowed)
			(vias allowed)
			(pads allowed)
			(copperpour not_allowed)
			(footprints allowed)
		)
		(placement
			(enabled no)
			(sheetname "")
		)
		(fill yes
			(thermal_gap 0.5)
			(thermal_bridge_width 0.5)
			(island_removal_mode 0)
		)
		(polygon
			(pts
				(arc
					(start 379.299724 -245.29415)
					(mid 378.669804 -245.29415)
					(end 379.299724 -245.29415)
				)
			)
		)
	)
	(zone
		(layers "B.Cu" "In6.Cu" "In11.Cu" "In13.Cu" "In15.Cu")
		(hatch none 0.5)
		(connect_pads
			(clearance 0)
		)
		(min_thickness 0.25)
		(keepout
			(tracks not_allowed)
			(vias allowed)
			(pads allowed)
			(copperpour not_allowed)
			(footprints allowed)
		)
		(placement
			(enabled no)
			(sheetname "")
		)
		(fill yes
			(thermal_gap 0.5)
			(thermal_bridge_width 0.5)
			(island_removal_mode 0)
		)
		(polygon
			(pts
				(arc
					(start 163.733988 -389.467344)
					(mid 163.104068 -389.467344)
					(end 163.733988 -389.467344)
				)
			)
		)
	)
	(zone
		(layers "B.Cu" "In6.Cu" "In11.Cu" "In13.Cu" "In15.Cu")
		(hatch none 0.5)
		(connect_pads
			(clearance 0)
		)
		(min_thickness 0.25)
		(keepout
			(tracks not_allowed)
			(vias allowed)
			(pads allowed)
			(copperpour not_allowed)
			(footprints allowed)
		)
		(placement
			(enabled no)
			(sheetname "")
		)
		(fill yes
			(thermal_gap 0.5)
			(thermal_bridge_width 0.5)
			(island_removal_mode 0)
		)
		(polygon
			(pts
				(arc
					(start 280.969974 -230.485188)
					(mid 280.301954 -230.485188)
					(end 280.969974 -230.485188)
				)
			)
		)
	)
	(zone
		(layers "B.Cu" "In6.Cu" "In11.Cu" "In13.Cu" "In15.Cu")
		(hatch none 0.5)
		(connect_pads
			(clearance 0)
		)
		(min_thickness 0.25)
		(keepout
			(tracks not_allowed)
			(vias allowed)
			(pads allowed)
			(copperpour not_allowed)
			(footprints allowed)
		)
		(placement
			(enabled no)
			(sheetname "")
		)
		(fill yes
			(thermal_gap 0.5)
			(thermal_bridge_width 0.5)
			(island_removal_mode 0)
		)
		(polygon
			(pts
				(arc
					(start 285.070042 -289.135058)
					(mid 284.402022 -289.135058)
					(end 285.070042 -289.135058)
				)
			)
		)
	)
	(zone
		(layers "B.Cu" "In6.Cu" "In11.Cu" "In13.Cu" "In15.Cu")
		(hatch none 0.5)
		(connect_pads
			(clearance 0)
		)
		(min_thickness 0.25)
		(keepout
			(tracks not_allowed)
			(vias allowed)
			(pads allowed)
			(copperpour not_allowed)
			(footprints allowed)
		)
		(placement
			(enabled no)
			(sheetname "")
		)
		(fill yes
			(thermal_gap 0.5)
			(thermal_bridge_width 0.5)
			(island_removal_mode 0)
		)
		(polygon
			(pts
				(arc
					(start 41.928034 -4.963414)
					(mid 41.260014 -4.963414)
					(end 41.928034 -4.963414)
				)
			)
		)
	)
	(zone
		(layers "B.Cu" "In6.Cu" "In11.Cu" "In13.Cu" "In15.Cu")
		(hatch none 0.5)
		(connect_pads
			(clearance 0)
		)
		(min_thickness 0.25)
		(keepout
			(tracks not_allowed)
			(vias allowed)
			(pads allowed)
			(copperpour not_allowed)
			(footprints allowed)
		)
		(placement
			(enabled no)
			(sheetname "")
		)
		(fill yes
			(thermal_gap 0.5)
			(thermal_bridge_width 0.5)
			(island_removal_mode 0)
		)
		(polygon
			(pts
				(arc
					(start 280.969974 -244.934994)
					(mid 280.301954 -244.934994)
					(end 280.969974 -244.934994)
				)
			)
		)
	)
	(zone
		(layers "B.Cu" "In6.Cu" "In11.Cu" "In13.Cu" "In15.Cu")
		(hatch none 0.5)
		(connect_pads
			(clearance 0)
		)
		(min_thickness 0.25)
		(keepout
			(tracks not_allowed)
			(vias allowed)
			(pads allowed)
			(copperpour not_allowed)
			(footprints allowed)
		)
		(placement
			(enabled no)
			(sheetname "")
		)
		(fill yes
			(thermal_gap 0.5)
			(thermal_bridge_width 0.5)
			(island_removal_mode 0)
		)
		(polygon
			(pts
				(arc
					(start 131.359656 -233.95432)
					(mid 130.729736 -233.95432)
					(end 131.359656 -233.95432)
				)
			)
		)
	)
	(zone
		(layers "B.Cu" "In6.Cu" "In11.Cu" "In13.Cu" "In15.Cu")
		(hatch none 0.5)
		(connect_pads
			(clearance 0)
		)
		(min_thickness 0.25)
		(keepout
			(tracks not_allowed)
			(vias allowed)
			(pads allowed)
			(copperpour not_allowed)
			(footprints allowed)
		)
		(placement
			(enabled no)
			(sheetname "")
		)
		(fill yes
			(thermal_gap 0.5)
			(thermal_bridge_width 0.5)
			(island_removal_mode 0)
		)
		(polygon
			(pts
				(arc
					(start 439.434224 -238.985044)
					(mid 438.766204 -238.985044)
					(end 439.434224 -238.985044)
				)
			)
		)
	)
	(zone
		(layers "B.Cu" "In6.Cu" "In11.Cu" "In13.Cu" "In15.Cu")
		(hatch none 0.5)
		(connect_pads
			(clearance 0)
		)
		(min_thickness 0.25)
		(keepout
			(tracks not_allowed)
			(vias allowed)
			(pads allowed)
			(copperpour not_allowed)
			(footprints allowed)
		)
		(placement
			(enabled no)
			(sheetname "")
		)
		(fill yes
			(thermal_gap 0.5)
			(thermal_bridge_width 0.5)
			(island_removal_mode 0)
		)
		(polygon
			(pts
				(arc
					(start 381.479806 -285.42615)
					(mid 380.849886 -285.42615)
					(end 381.479806 -285.42615)
				)
			)
		)
	)
	(zone
		(layers "B.Cu" "In6.Cu" "In11.Cu" "In13.Cu" "In15.Cu")
		(hatch none 0.5)
		(connect_pads
			(clearance 0)
		)
		(min_thickness 0.25)
		(keepout
			(tracks not_allowed)
			(vias allowed)
			(pads allowed)
			(copperpour not_allowed)
			(footprints allowed)
		)
		(placement
			(enabled no)
			(sheetname "")
		)
		(fill yes
			(thermal_gap 0.5)
			(thermal_bridge_width 0.5)
			(island_removal_mode 0)
		)
		(polygon
			(pts
				(arc
					(start 91.41587 -228.284532)
					(mid 90.78595 -228.284532)
					(end 91.41587 -228.284532)
				)
			)
		)
	)
	(zone
		(layers "B.Cu" "In6.Cu" "In11.Cu" "In13.Cu" "In15.Cu")
		(hatch none 0.5)
		(connect_pads
			(clearance 0)
		)
		(min_thickness 0.25)
		(keepout
			(tracks not_allowed)
			(vias allowed)
			(pads allowed)
			(copperpour not_allowed)
			(footprints allowed)
		)
		(placement
			(enabled no)
			(sheetname "")
		)
		(fill yes
			(thermal_gap 0.5)
			(thermal_bridge_width 0.5)
			(island_removal_mode 0)
		)
		(polygon
			(pts
				(arc
					(start 191.494156 -242.385342)
					(mid 190.826136 -242.385342)
					(end 191.494156 -242.385342)
				)
			)
		)
	)
	(zone
		(layers "B.Cu" "In6.Cu" "In11.Cu" "In13.Cu" "In15.Cu")
		(hatch none 0.5)
		(connect_pads
			(clearance 0)
		)
		(min_thickness 0.25)
		(keepout
			(tracks not_allowed)
			(vias allowed)
			(pads allowed)
			(copperpour not_allowed)
			(footprints allowed)
		)
		(placement
			(enabled no)
			(sheetname "")
		)
		(fill yes
			(thermal_gap 0.5)
			(thermal_bridge_width 0.5)
			(island_removal_mode 0)
		)
		(polygon
			(pts
				(arc
					(start 379.769878 -250.964192)
					(mid 379.139958 -250.964192)
					(end 379.769878 -250.964192)
				)
			)
		)
	)
	(zone
		(layers "B.Cu" "In6.Cu" "In11.Cu" "In13.Cu" "In15.Cu")
		(hatch none 0.5)
		(connect_pads
			(clearance 0)
		)
		(min_thickness 0.25)
		(keepout
			(tracks not_allowed)
			(vias allowed)
			(pads allowed)
			(copperpour not_allowed)
			(footprints allowed)
		)
		(placement
			(enabled no)
			(sheetname "")
		)
		(fill yes
			(thermal_gap 0.5)
			(thermal_bridge_width 0.5)
			(island_removal_mode 0)
		)
		(polygon
			(pts
				(arc
					(start 348.75597 -229.904036)
					(mid 348.12605 -229.904036)
					(end 348.75597 -229.904036)
				)
			)
		)
	)
	(zone
		(layers "B.Cu" "In6.Cu" "In11.Cu" "In13.Cu" "In15.Cu")
		(hatch none 0.5)
		(connect_pads
			(clearance 0)
		)
		(min_thickness 0.25)
		(keepout
			(tracks not_allowed)
			(vias allowed)
			(pads allowed)
			(copperpour not_allowed)
			(footprints allowed)
		)
		(placement
			(enabled no)
			(sheetname "")
		)
		(fill yes
			(thermal_gap 0.5)
			(thermal_bridge_width 0.5)
			(island_removal_mode 0)
		)
		(polygon
			(pts
				(arc
					(start 341.06612 -272.466054)
					(mid 340.4362 -272.466054)
					(end 341.06612 -272.466054)
				)
			)
		)
	)
	(zone
		(layers "B.Cu" "In6.Cu" "In11.Cu" "In13.Cu" "In15.Cu")
		(hatch none 0.5)
		(connect_pads
			(clearance 0)
		)
		(min_thickness 0.25)
		(keepout
			(tracks not_allowed)
			(vias allowed)
			(pads allowed)
			(copperpour not_allowed)
			(footprints allowed)
		)
		(placement
			(enabled no)
			(sheetname "")
		)
		(fill yes
			(thermal_gap 0.5)
			(thermal_bridge_width 0.5)
			(island_removal_mode 0)
		)
		(polygon
			(pts
				(arc
					(start 128.406144 -385.31038)
					(mid 127.776224 -385.31038)
					(end 128.406144 -385.31038)
				)
			)
		)
	)
	(zone
		(layers "B.Cu" "In6.Cu" "In11.Cu" "In13.Cu" "In15.Cu")
		(hatch none 0.5)
		(connect_pads
			(clearance 0)
		)
		(min_thickness 0.25)
		(keepout
			(tracks not_allowed)
			(vias allowed)
			(pads allowed)
			(copperpour not_allowed)
			(footprints allowed)
		)
		(placement
			(enabled no)
			(sheetname "")
		)
		(fill yes
			(thermal_gap 0.5)
			(thermal_bridge_width 0.5)
			(island_removal_mode 0)
		)
		(polygon
			(pts
				(arc
					(start 415.81959 -19.13636)
					(mid 415.15157 -19.13636)
					(end 415.81959 -19.13636)
				)
			)
		)
	)
	(zone
		(layers "B.Cu" "In6.Cu" "In11.Cu" "In13.Cu" "In15.Cu")
		(hatch none 0.5)
		(connect_pads
			(clearance 0)
		)
		(min_thickness 0.25)
		(keepout
			(tracks not_allowed)
			(vias allowed)
			(pads allowed)
			(copperpour not_allowed)
			(footprints allowed)
		)
		(placement
			(enabled no)
			(sheetname "")
		)
		(fill yes
			(thermal_gap 0.5)
			(thermal_bridge_width 0.5)
			(island_removal_mode 0)
		)
		(polygon
			(pts
				(arc
					(start 308.90591 -397.156432)
					(mid 308.27599 -397.156432)
					(end 308.90591 -397.156432)
				)
			)
		)
	)
	(zone
		(layers "B.Cu" "In6.Cu" "In11.Cu" "In13.Cu" "In15.Cu")
		(hatch none 0.5)
		(connect_pads
			(clearance 0)
		)
		(min_thickness 0.25)
		(keepout
			(tracks not_allowed)
			(vias allowed)
			(pads allowed)
			(copperpour not_allowed)
			(footprints allowed)
		)
		(placement
			(enabled no)
			(sheetname "")
		)
		(fill yes
			(thermal_gap 0.5)
			(thermal_bridge_width 0.5)
			(island_removal_mode 0)
		)
		(polygon
			(pts
				(arc
					(start 92.655898 -287.856422)
					(mid 92.025978 -287.856422)
					(end 92.655898 -287.856422)
				)
			)
		)
	)
	(zone
		(layers "B.Cu" "In6.Cu" "In11.Cu" "In13.Cu" "In15.Cu")
		(hatch none 0.5)
		(connect_pads
			(clearance 0)
		)
		(min_thickness 0.25)
		(keepout
			(tracks not_allowed)
			(vias allowed)
			(pads allowed)
			(copperpour not_allowed)
			(footprints allowed)
		)
		(placement
			(enabled no)
			(sheetname "")
		)
		(fill yes
			(thermal_gap 0.5)
			(thermal_bridge_width 0.5)
			(island_removal_mode 0)
		)
		(polygon
			(pts
				(arc
					(start 367.849658 -287.856168)
					(mid 367.219738 -287.856168)
					(end 367.849658 -287.856168)
				)
			)
		)
	)
	(zone
		(layers "B.Cu" "In6.Cu" "In11.Cu" "In13.Cu" "In15.Cu")
		(hatch none 0.5)
		(connect_pads
			(clearance 0)
		)
		(min_thickness 0.25)
		(keepout
			(tracks not_allowed)
			(vias allowed)
			(pads allowed)
			(copperpour not_allowed)
			(footprints allowed)
		)
		(placement
			(enabled no)
			(sheetname "")
		)
		(fill yes
			(thermal_gap 0.5)
			(thermal_bridge_width 0.5)
			(island_removal_mode 0)
		)
		(polygon
			(pts
				(arc
					(start 280.969974 -274.684998)
					(mid 280.301954 -274.684998)
					(end 280.969974 -274.684998)
				)
			)
		)
	)
	(zone
		(layers "B.Cu" "In6.Cu" "In11.Cu" "In13.Cu" "In15.Cu")
		(hatch none 0.5)
		(connect_pads
			(clearance 0)
		)
		(min_thickness 0.25)
		(keepout
			(tracks not_allowed)
			(vias allowed)
			(pads allowed)
			(copperpour not_allowed)
			(footprints allowed)
		)
		(placement
			(enabled no)
			(sheetname "")
		)
		(fill yes
			(thermal_gap 0.5)
			(thermal_bridge_width 0.5)
			(island_removal_mode 0)
		)
		(polygon
			(pts
				(arc
					(start 345.936062 -229.904036)
					(mid 345.306142 -229.904036)
					(end 345.936062 -229.904036)
				)
			)
		)
	)
	(zone
		(layers "B.Cu" "In6.Cu" "In11.Cu" "In13.Cu" "In15.Cu")
		(hatch none 0.5)
		(connect_pads
			(clearance 0)
		)
		(min_thickness 0.25)
		(keepout
			(tracks not_allowed)
			(vias allowed)
			(pads allowed)
			(copperpour not_allowed)
			(footprints allowed)
		)
		(placement
			(enabled no)
			(sheetname "")
		)
		(fill yes
			(thermal_gap 0.5)
			(thermal_bridge_width 0.5)
			(island_removal_mode 0)
		)
		(polygon
			(pts
				(arc
					(start 386.806186 -393.69238)
					(mid 386.176266 -393.69238)
					(end 386.806186 -393.69238)
				)
			)
		)
	)
	(zone
		(layers "B.Cu" "In6.Cu" "In11.Cu" "In13.Cu" "In15.Cu")
		(hatch none 0.5)
		(connect_pads
			(clearance 0)
		)
		(min_thickness 0.25)
		(keepout
			(tracks not_allowed)
			(vias allowed)
			(pads allowed)
			(copperpour not_allowed)
			(footprints allowed)
		)
		(placement
			(enabled no)
			(sheetname "")
		)
		(fill yes
			(thermal_gap 0.5)
			(thermal_bridge_width 0.5)
			(island_removal_mode 0)
		)
		(polygon
			(pts
				(arc
					(start 133.539738 -267.606272)
					(mid 132.909818 -267.606272)
					(end 133.539738 -267.606272)
				)
			)
		)
	)
	(zone
		(layers "B.Cu" "In6.Cu" "In11.Cu" "In13.Cu" "In15.Cu")
		(hatch none 0.5)
		(connect_pads
			(clearance 0)
		)
		(min_thickness 0.25)
		(keepout
			(tracks not_allowed)
			(vias allowed)
			(pads allowed)
			(copperpour not_allowed)
			(footprints allowed)
		)
		(placement
			(enabled no)
			(sheetname "")
		)
		(fill yes
			(thermal_gap 0.5)
			(thermal_bridge_width 0.5)
			(island_removal_mode 0)
		)
		(polygon
			(pts
				(arc
					(start 33.029906 -261.935214)
					(mid 32.361886 -261.935214)
					(end 33.029906 -261.935214)
				)
			)
		)
	)
	(zone
		(layers "B.Cu" "In6.Cu" "In11.Cu" "In13.Cu" "In15.Cu")
		(hatch none 0.5)
		(connect_pads
			(clearance 0)
		)
		(min_thickness 0.25)
		(keepout
			(tracks not_allowed)
			(vias allowed)
			(pads allowed)
			(copperpour not_allowed)
			(footprints allowed)
		)
		(placement
			(enabled no)
			(sheetname "")
		)
		(fill yes
			(thermal_gap 0.5)
			(thermal_bridge_width 0.5)
			(island_removal_mode 0)
		)
		(polygon
			(pts
				(arc
					(start 363.619796 -287.045908)
					(mid 362.989876 -287.045908)
					(end 363.619796 -287.045908)
				)
			)
		)
	)
	(zone
		(layers "B.Cu" "In6.Cu" "In11.Cu" "In13.Cu" "In15.Cu")
		(hatch none 0.5)
		(connect_pads
			(clearance 0)
		)
		(min_thickness 0.25)
		(keepout
			(tracks not_allowed)
			(vias allowed)
			(pads allowed)
			(copperpour not_allowed)
			(footprints allowed)
		)
		(placement
			(enabled no)
			(sheetname "")
		)
		(fill yes
			(thermal_gap 0.5)
			(thermal_bridge_width 0.5)
			(island_removal_mode 0)
		)
		(polygon
			(pts
				(arc
					(start 391.274046 6.581648)
					(mid 390.606026 6.581648)
					(end 391.274046 6.581648)
				)
			)
		)
	)
	(zone
		(layers "B.Cu" "In6.Cu" "In11.Cu" "In13.Cu" "In15.Cu")
		(hatch none 0.5)
		(connect_pads
			(clearance 0)
		)
		(min_thickness 0.25)
		(keepout
			(tracks not_allowed)
			(vias allowed)
			(pads allowed)
			(copperpour not_allowed)
			(footprints allowed)
		)
		(placement
			(enabled no)
			(sheetname "")
		)
		(fill yes
			(thermal_gap 0.5)
			(thermal_bridge_width 0.5)
			(island_removal_mode 0)
		)
		(polygon
			(pts
				(arc
					(start 346.354654 -379.88113)
					(mid 345.686634 -379.88113)
					(end 346.354654 -379.88113)
				)
			)
		)
	)
	(zone
		(layers "B.Cu" "In6.Cu" "In11.Cu" "In13.Cu" "In15.Cu")
		(hatch none 0.5)
		(connect_pads
			(clearance 0)
		)
		(min_thickness 0.25)
		(keepout
			(tracks not_allowed)
			(vias allowed)
			(pads allowed)
			(copperpour not_allowed)
			(footprints allowed)
		)
		(placement
			(enabled no)
			(sheetname "")
		)
		(fill yes
			(thermal_gap 0.5)
			(thermal_bridge_width 0.5)
			(island_removal_mode 0)
		)
		(polygon
			(pts
				(arc
					(start 339.355938 -244.484144)
					(mid 338.726018 -244.484144)
					(end 339.355938 -244.484144)
				)
			)
		)
	)
	(zone
		(layers "B.Cu" "In6.Cu" "In11.Cu" "In13.Cu" "In15.Cu")
		(hatch none 0.5)
		(connect_pads
			(clearance 0)
		)
		(min_thickness 0.25)
		(keepout
			(tracks not_allowed)
			(vias allowed)
			(pads allowed)
			(copperpour not_allowed)
			(footprints allowed)
		)
		(placement
			(enabled no)
			(sheetname "")
		)
		(fill yes
			(thermal_gap 0.5)
			(thermal_bridge_width 0.5)
			(island_removal_mode 0)
		)
		(polygon
			(pts
				(arc
					(start 435.334156 -232.184956)
					(mid 434.666136 -232.184956)
					(end 435.334156 -232.184956)
				)
			)
		)
	)
	(zone
		(layers "B.Cu" "In6.Cu" "In11.Cu" "In13.Cu" "In15.Cu")
		(hatch none 0.5)
		(connect_pads
			(clearance 0)
		)
		(min_thickness 0.25)
		(keepout
			(tracks not_allowed)
			(vias allowed)
			(pads allowed)
			(copperpour not_allowed)
			(footprints allowed)
		)
		(placement
			(enabled no)
			(sheetname "")
		)
		(fill yes
			(thermal_gap 0.5)
			(thermal_bridge_width 0.5)
			(island_removal_mode 0)
		)
		(polygon
			(pts
				(arc
					(start 408.850592 -412.84652)
					(mid 408.182572 -412.84652)
					(end 408.850592 -412.84652)
				)
			)
		)
	)
	(zone
		(layers "B.Cu" "In6.Cu" "In11.Cu" "In13.Cu" "In15.Cu")
		(hatch none 0.5)
		(connect_pads
			(clearance 0)
		)
		(min_thickness 0.25)
		(keepout
			(tracks not_allowed)
			(vias allowed)
			(pads allowed)
			(copperpour not_allowed)
			(footprints allowed)
		)
		(placement
			(enabled no)
			(sheetname "")
		)
		(fill yes
			(thermal_gap 0.5)
			(thermal_bridge_width 0.5)
			(island_removal_mode 0)
		)
		(polygon
			(pts
				(arc
					(start 280.969974 -251.735082)
					(mid 280.301954 -251.735082)
					(end 280.969974 -251.735082)
				)
			)
		)
	)
	(zone
		(layers "B.Cu" "In6.Cu" "In11.Cu" "In13.Cu" "In15.Cu")
		(hatch none 0.5)
		(connect_pads
			(clearance 0)
		)
		(min_thickness 0.25)
		(keepout
			(tracks not_allowed)
			(vias allowed)
			(pads allowed)
			(copperpour not_allowed)
			(footprints allowed)
		)
		(placement
			(enabled no)
			(sheetname "")
		)
		(fill yes
			(thermal_gap 0.5)
			(thermal_bridge_width 0.5)
			(island_removal_mode 0)
		)
		(polygon
			(pts
				(arc
					(start 81.845912 -373.96293)
					(mid 81.177892 -373.96293)
					(end 81.845912 -373.96293)
				)
			)
		)
	)
	(zone
		(layers "B.Cu" "In6.Cu" "In11.Cu" "In13.Cu" "In15.Cu")
		(hatch none 0.5)
		(connect_pads
			(clearance 0)
		)
		(min_thickness 0.25)
		(keepout
			(tracks not_allowed)
			(vias allowed)
			(pads allowed)
			(copperpour not_allowed)
			(footprints allowed)
		)
		(placement
			(enabled no)
			(sheetname "")
		)
		(fill yes
			(thermal_gap 0.5)
			(thermal_bridge_width 0.5)
			(island_removal_mode 0)
		)
		(polygon
			(pts
				(arc
					(start 41.064434 -4.963414)
					(mid 40.396414 -4.963414)
					(end 41.064434 -4.963414)
				)
			)
		)
	)
	(zone
		(layers "B.Cu" "In6.Cu" "In11.Cu" "In13.Cu" "In15.Cu")
		(hatch none 0.5)
		(connect_pads
			(clearance 0)
		)
		(min_thickness 0.25)
		(keepout
			(tracks not_allowed)
			(vias allowed)
			(pads allowed)
			(copperpour not_allowed)
			(footprints allowed)
		)
		(placement
			(enabled no)
			(sheetname "")
		)
		(fill yes
			(thermal_gap 0.5)
			(thermal_bridge_width 0.5)
			(island_removal_mode 0)
		)
		(polygon
			(pts
				(arc
					(start 381.009906 -276.516084)
					(mid 380.379986 -276.516084)
					(end 381.009906 -276.516084)
				)
			)
		)
	)
	(zone
		(layers "B.Cu" "In6.Cu" "In11.Cu" "In13.Cu" "In15.Cu")
		(hatch none 0.5)
		(connect_pads
			(clearance 0)
		)
		(min_thickness 0.25)
		(keepout
			(tracks not_allowed)
			(vias allowed)
			(pads allowed)
			(copperpour not_allowed)
			(footprints allowed)
		)
		(placement
			(enabled no)
			(sheetname "")
		)
		(fill yes
			(thermal_gap 0.5)
			(thermal_bridge_width 0.5)
			(island_removal_mode 0)
		)
		(polygon
			(pts
				(arc
					(start 133.539738 -280.566368)
					(mid 132.909818 -280.566368)
					(end 133.539738 -280.566368)
				)
			)
		)
	)
	(zone
		(layers "B.Cu" "In6.Cu" "In11.Cu" "In13.Cu" "In15.Cu")
		(hatch none 0.5)
		(connect_pads
			(clearance 0)
		)
		(min_thickness 0.25)
		(keepout
			(tracks not_allowed)
			(vias allowed)
			(pads allowed)
			(copperpour not_allowed)
			(footprints allowed)
		)
		(placement
			(enabled no)
			(sheetname "")
		)
		(fill yes
			(thermal_gap 0.5)
			(thermal_bridge_width 0.5)
			(island_removal_mode 0)
		)
		(polygon
			(pts
				(arc
					(start 33.029906 -229.635304)
					(mid 32.361886 -229.635304)
					(end 33.029906 -229.635304)
				)
			)
		)
	)
	(zone
		(layers "B.Cu" "In6.Cu" "In11.Cu" "In13.Cu" "In15.Cu")
		(hatch none 0.5)
		(connect_pads
			(clearance 0)
		)
		(min_thickness 0.25)
		(keepout
			(tracks not_allowed)
			(vias allowed)
			(pads allowed)
			(copperpour not_allowed)
			(footprints allowed)
		)
		(placement
			(enabled no)
			(sheetname "")
		)
		(fill yes
			(thermal_gap 0.5)
			(thermal_bridge_width 0.5)
			(island_removal_mode 0)
		)
		(polygon
			(pts
				(arc
					(start 187.394088 -218.585288)
					(mid 186.726068 -218.585288)
					(end 187.394088 -218.585288)
				)
			)
		)
	)
	(zone
		(layers "B.Cu" "In6.Cu" "In11.Cu" "In13.Cu" "In15.Cu")
		(hatch none 0.5)
		(connect_pads
			(clearance 0)
		)
		(min_thickness 0.25)
		(keepout
			(tracks not_allowed)
			(vias allowed)
			(pads allowed)
			(copperpour not_allowed)
			(footprints allowed)
		)
		(placement
			(enabled no)
			(sheetname "")
		)
		(fill yes
			(thermal_gap 0.5)
			(thermal_bridge_width 0.5)
			(island_removal_mode 0)
		)
		(polygon
			(pts
				(arc
					(start 340.766146 -235.574078)
					(mid 340.136226 -235.574078)
					(end 340.766146 -235.574078)
				)
			)
		)
	)
	(zone
		(layers "B.Cu" "In6.Cu" "In11.Cu" "In13.Cu" "In15.Cu")
		(hatch none 0.5)
		(connect_pads
			(clearance 0)
		)
		(min_thickness 0.25)
		(keepout
			(tracks not_allowed)
			(vias allowed)
			(pads allowed)
			(copperpour not_allowed)
			(footprints allowed)
		)
		(placement
			(enabled no)
			(sheetname "")
		)
		(fill yes
			(thermal_gap 0.5)
			(thermal_bridge_width 0.5)
			(island_removal_mode 0)
		)
		(polygon
			(pts
				(arc
					(start 381.009906 -291.095938)
					(mid 380.379986 -291.095938)
					(end 381.009906 -291.095938)
				)
			)
		)
	)
	(zone
		(layers "B.Cu" "In6.Cu" "In11.Cu" "In13.Cu" "In15.Cu")
		(hatch none 0.5)
		(connect_pads
			(clearance 0)
		)
		(min_thickness 0.25)
		(keepout
			(tracks not_allowed)
			(vias allowed)
			(pads allowed)
			(copperpour not_allowed)
			(footprints allowed)
		)
		(placement
			(enabled no)
			(sheetname "")
		)
		(fill yes
			(thermal_gap 0.5)
			(thermal_bridge_width 0.5)
			(island_removal_mode 0)
		)
		(polygon
			(pts
				(arc
					(start 368.489738 -234.764072)
					(mid 367.859818 -234.764072)
					(end 368.489738 -234.764072)
				)
			)
		)
	)
	(zone
		(layers "B.Cu" "In6.Cu" "In11.Cu" "In13.Cu" "In15.Cu")
		(hatch none 0.5)
		(connect_pads
			(clearance 0)
		)
		(min_thickness 0.25)
		(keepout
			(tracks not_allowed)
			(vias allowed)
			(pads allowed)
			(copperpour not_allowed)
			(footprints allowed)
		)
		(placement
			(enabled no)
			(sheetname "")
		)
		(fill yes
			(thermal_gap 0.5)
			(thermal_bridge_width 0.5)
			(island_removal_mode 0)
		)
		(polygon
			(pts
				(arc
					(start 435.334156 -289.985196)
					(mid 434.666136 -289.985196)
					(end 435.334156 -289.985196)
				)
			)
		)
	)
	(zone
		(layers "B.Cu" "In6.Cu" "In11.Cu" "In13.Cu" "In15.Cu")
		(hatch none 0.5)
		(connect_pads
			(clearance 0)
		)
		(min_thickness 0.25)
		(keepout
			(tracks not_allowed)
			(vias allowed)
			(pads allowed)
			(copperpour not_allowed)
			(footprints allowed)
		)
		(placement
			(enabled no)
			(sheetname "")
		)
		(fill yes
			(thermal_gap 0.5)
			(thermal_bridge_width 0.5)
			(island_removal_mode 0)
		)
		(polygon
			(pts
				(arc
					(start 130.00609 -386.003292)
					(mid 129.37617 -386.003292)
					(end 130.00609 -386.003292)
				)
			)
		)
	)
	(zone
		(layers "B.Cu" "In6.Cu" "In11.Cu" "In13.Cu" "In15.Cu")
		(hatch none 0.5)
		(connect_pads
			(clearance 0)
		)
		(min_thickness 0.25)
		(keepout
			(tracks not_allowed)
			(vias allowed)
			(pads allowed)
			(copperpour not_allowed)
			(footprints allowed)
		)
		(placement
			(enabled no)
			(sheetname "")
		)
		(fill yes
			(thermal_gap 0.5)
			(thermal_bridge_width 0.5)
			(island_removal_mode 0)
		)
		(polygon
			(pts
				(arc
					(start 187.394088 -221.135194)
					(mid 186.726068 -221.135194)
					(end 187.394088 -221.135194)
				)
			)
		)
	)
	(zone
		(layers "B.Cu" "In6.Cu" "In11.Cu" "In13.Cu" "In15.Cu")
		(hatch none 0.5)
		(connect_pads
			(clearance 0)
		)
		(min_thickness 0.25)
		(keepout
			(tracks not_allowed)
			(vias allowed)
			(pads allowed)
			(copperpour not_allowed)
			(footprints allowed)
		)
		(placement
			(enabled no)
			(sheetname "")
		)
		(fill yes
			(thermal_gap 0.5)
			(thermal_bridge_width 0.5)
			(island_removal_mode 0)
		)
		(polygon
			(pts
				(arc
					(start 191.494156 -238.135414)
					(mid 190.826136 -238.135414)
					(end 191.494156 -238.135414)
				)
			)
		)
	)
	(zone
		(layers "B.Cu" "In6.Cu" "In11.Cu" "In13.Cu" "In15.Cu")
		(hatch none 0.5)
		(connect_pads
			(clearance 0)
		)
		(min_thickness 0.25)
		(keepout
			(tracks not_allowed)
			(vias allowed)
			(pads allowed)
			(copperpour not_allowed)
			(footprints allowed)
		)
		(placement
			(enabled no)
			(sheetname "")
		)
		(fill yes
			(thermal_gap 0.5)
			(thermal_bridge_width 0.5)
			(island_removal_mode 0)
		)
		(polygon
			(pts
				(arc
					(start 187.394088 -211.7852)
					(mid 186.726068 -211.7852)
					(end 187.394088 -211.7852)
				)
			)
		)
	)
	(zone
		(layers "B.Cu" "In6.Cu" "In11.Cu" "In13.Cu" "In15.Cu")
		(hatch none 0.5)
		(connect_pads
			(clearance 0)
		)
		(min_thickness 0.25)
		(keepout
			(tracks not_allowed)
			(vias allowed)
			(pads allowed)
			(copperpour not_allowed)
			(footprints allowed)
		)
		(placement
			(enabled no)
			(sheetname "")
		)
		(fill yes
			(thermal_gap 0.5)
			(thermal_bridge_width 0.5)
			(island_removal_mode 0)
		)
		(polygon
			(pts
				(arc
					(start 371.609874 -291.095938)
					(mid 370.979954 -291.095938)
					(end 371.609874 -291.095938)
				)
			)
		)
	)
	(zone
		(layers "B.Cu" "In6.Cu" "In11.Cu" "In13.Cu" "In15.Cu")
		(hatch none 0.5)
		(connect_pads
			(clearance 0)
		)
		(min_thickness 0.25)
		(keepout
			(tracks not_allowed)
			(vias allowed)
			(pads allowed)
			(copperpour not_allowed)
			(footprints allowed)
		)
		(placement
			(enabled no)
			(sheetname "")
		)
		(fill yes
			(thermal_gap 0.5)
			(thermal_bridge_width 0.5)
			(island_removal_mode 0)
		)
		(polygon
			(pts
				(arc
					(start 91.245944 -288.666174)
					(mid 90.616024 -288.666174)
					(end 91.245944 -288.666174)
				)
			)
		)
	)
	(zone
		(layers "B.Cu" "In6.Cu" "In11.Cu" "In13.Cu" "In15.Cu")
		(hatch none 0.5)
		(connect_pads
			(clearance 0)
		)
		(min_thickness 0.25)
		(keepout
			(tracks not_allowed)
			(vias allowed)
			(pads allowed)
			(copperpour not_allowed)
			(footprints allowed)
		)
		(placement
			(enabled no)
			(sheetname "")
		)
		(fill yes
			(thermal_gap 0.5)
			(thermal_bridge_width 0.5)
			(island_removal_mode 0)
		)
		(polygon
			(pts
				(arc
					(start 116.789708 -226.66452)
					(mid 116.159788 -226.66452)
					(end 116.789708 -226.66452)
				)
			)
		)
	)
	(zone
		(layers "B.Cu" "In6.Cu" "In11.Cu" "In13.Cu" "In15.Cu")
		(hatch none 0.5)
		(connect_pads
			(clearance 0)
		)
		(min_thickness 0.25)
		(keepout
			(tracks not_allowed)
			(vias allowed)
			(pads allowed)
			(copperpour not_allowed)
			(footprints allowed)
		)
		(placement
			(enabled no)
			(sheetname "")
		)
		(fill yes
			(thermal_gap 0.5)
			(thermal_bridge_width 0.5)
			(island_removal_mode 0)
		)
		(polygon
			(pts
				(arc
					(start 104.576118 -231.524302)
					(mid 103.946198 -231.524302)
					(end 104.576118 -231.524302)
				)
			)
		)
	)
	(zone
		(layers "B.Cu" "In6.Cu" "In11.Cu" "In13.Cu" "In15.Cu")
		(hatch none 0.5)
		(connect_pads
			(clearance 0)
		)
		(min_thickness 0.25)
		(keepout
			(tracks not_allowed)
			(vias allowed)
			(pads allowed)
			(copperpour not_allowed)
			(footprints allowed)
		)
		(placement
			(enabled no)
			(sheetname "")
		)
		(fill yes
			(thermal_gap 0.5)
			(thermal_bridge_width 0.5)
			(island_removal_mode 0)
		)
		(polygon
			(pts
				(arc
					(start 340.766146 -225.85426)
					(mid 340.136226 -225.85426)
					(end 340.766146 -225.85426)
				)
			)
		)
	)
	(zone
		(layers "B.Cu" "In6.Cu" "In11.Cu" "In13.Cu" "In15.Cu")
		(hatch none 0.5)
		(connect_pads
			(clearance 0)
		)
		(min_thickness 0.25)
		(keepout
			(tracks not_allowed)
			(vias allowed)
			(pads allowed)
			(copperpour not_allowed)
			(footprints allowed)
		)
		(placement
			(enabled no)
			(sheetname "")
		)
		(fill yes
			(thermal_gap 0.5)
			(thermal_bridge_width 0.5)
			(island_removal_mode 0)
		)
		(polygon
			(pts
				(arc
					(start 133.239764 -243.674392)
					(mid 132.609844 -243.674392)
					(end 133.239764 -243.674392)
				)
			)
		)
	)
	(zone
		(layers "B.Cu" "In6.Cu" "In11.Cu" "In13.Cu" "In15.Cu")
		(hatch none 0.5)
		(connect_pads
			(clearance 0)
		)
		(min_thickness 0.25)
		(keepout
			(tracks not_allowed)
			(vias allowed)
			(pads allowed)
			(copperpour not_allowed)
			(footprints allowed)
		)
		(placement
			(enabled no)
			(sheetname "")
		)
		(fill yes
			(thermal_gap 0.5)
			(thermal_bridge_width 0.5)
			(island_removal_mode 0)
		)
		(polygon
			(pts
				(arc
					(start 187.394088 -227.935282)
					(mid 186.726068 -227.935282)
					(end 187.394088 -227.935282)
				)
			)
		)
	)
	(zone
		(layers "B.Cu" "In6.Cu" "In11.Cu" "In13.Cu" "In15.Cu")
		(hatch none 0.5)
		(connect_pads
			(clearance 0)
		)
		(min_thickness 0.25)
		(keepout
			(tracks not_allowed)
			(vias allowed)
			(pads allowed)
			(copperpour not_allowed)
			(footprints allowed)
		)
		(placement
			(enabled no)
			(sheetname "")
		)
		(fill yes
			(thermal_gap 0.5)
			(thermal_bridge_width 0.5)
			(island_removal_mode 0)
		)
		(polygon
			(pts
				(arc
					(start 435.334156 -304.435002)
					(mid 434.666136 -304.435002)
					(end 435.334156 -304.435002)
				)
			)
		)
	)
	(zone
		(layers "B.Cu" "In6.Cu" "In11.Cu" "In13.Cu" "In15.Cu")
		(hatch none 0.5)
		(connect_pads
			(clearance 0)
		)
		(min_thickness 0.25)
		(keepout
			(tracks not_allowed)
			(vias allowed)
			(pads allowed)
			(copperpour not_allowed)
			(footprints allowed)
		)
		(placement
			(enabled no)
			(sheetname "")
		)
		(fill yes
			(thermal_gap 0.5)
			(thermal_bridge_width 0.5)
			(island_removal_mode 0)
		)
		(polygon
			(pts
				(arc
					(start 338.886038 -251.774198)
					(mid 338.256118 -251.774198)
					(end 338.886038 -251.774198)
				)
			)
		)
	)
	(zone
		(layers "B.Cu" "In6.Cu" "In11.Cu" "In13.Cu" "In15.Cu")
		(hatch none 0.5)
		(connect_pads
			(clearance 0)
		)
		(min_thickness 0.25)
		(keepout
			(tracks not_allowed)
			(vias allowed)
			(pads allowed)
			(copperpour not_allowed)
			(footprints allowed)
		)
		(placement
			(enabled no)
			(sheetname "")
		)
		(fill yes
			(thermal_gap 0.5)
			(thermal_bridge_width 0.5)
			(island_removal_mode 0)
		)
		(polygon
			(pts
				(arc
					(start 346.236036 -291.095938)
					(mid 345.606116 -291.095938)
					(end 346.236036 -291.095938)
				)
			)
		)
	)
	(zone
		(layers "B.Cu" "In6.Cu" "In11.Cu" "In13.Cu" "In15.Cu")
		(hatch none 0.5)
		(connect_pads
			(clearance 0)
		)
		(min_thickness 0.25)
		(keepout
			(tracks not_allowed)
			(vias allowed)
			(pads allowed)
			(copperpour not_allowed)
			(footprints allowed)
		)
		(placement
			(enabled no)
			(sheetname "")
		)
		(fill yes
			(thermal_gap 0.5)
			(thermal_bridge_width 0.5)
			(island_removal_mode 0)
		)
		(polygon
			(pts
				(arc
					(start 191.494156 -317.185294)
					(mid 190.826136 -317.185294)
					(end 191.494156 -317.185294)
				)
			)
		)
	)
	(zone
		(layers "B.Cu" "In6.Cu" "In11.Cu" "In13.Cu" "In15.Cu")
		(hatch none 0.5)
		(connect_pads
			(clearance 0)
		)
		(min_thickness 0.25)
		(keepout
			(tracks not_allowed)
			(vias allowed)
			(pads allowed)
			(copperpour not_allowed)
			(footprints allowed)
		)
		(placement
			(enabled no)
			(sheetname "")
		)
		(fill yes
			(thermal_gap 0.5)
			(thermal_bridge_width 0.5)
			(island_removal_mode 0)
		)
		(polygon
			(pts
				(arc
					(start 417.176712 -412.84652)
					(mid 416.508692 -412.84652)
					(end 417.176712 -412.84652)
				)
			)
		)
	)
	(zone
		(layers "B.Cu" "In6.Cu" "In11.Cu" "In13.Cu" "In15.Cu")
		(hatch none 0.5)
		(connect_pads
			(clearance 0)
		)
		(min_thickness 0.25)
		(keepout
			(tracks not_allowed)
			(vias allowed)
			(pads allowed)
			(copperpour not_allowed)
			(footprints allowed)
		)
		(placement
			(enabled no)
			(sheetname "")
		)
		(fill yes
			(thermal_gap 0.5)
			(thermal_bridge_width 0.5)
			(island_removal_mode 0)
		)
		(polygon
			(pts
				(arc
					(start 133.239764 -242.05438)
					(mid 132.609844 -242.05438)
					(end 133.239764 -242.05438)
				)
			)
		)
	)
	(zone
		(layers "B.Cu" "In6.Cu" "In11.Cu" "In13.Cu" "In15.Cu")
		(hatch none 0.5)
		(connect_pads
			(clearance 0)
		)
		(min_thickness 0.25)
		(keepout
			(tracks not_allowed)
			(vias allowed)
			(pads allowed)
			(copperpour not_allowed)
			(footprints allowed)
		)
		(placement
			(enabled no)
			(sheetname "")
		)
		(fill yes
			(thermal_gap 0.5)
			(thermal_bridge_width 0.5)
			(island_removal_mode 0)
		)
		(polygon
			(pts
				(arc
					(start 37.129974 -315.485272)
					(mid 36.461954 -315.485272)
					(end 37.129974 -315.485272)
				)
			)
		)
	)
	(zone
		(layers "B.Cu" "In6.Cu" "In11.Cu" "In13.Cu" "In15.Cu")
		(hatch none 0.5)
		(connect_pads
			(clearance 0)
		)
		(min_thickness 0.25)
		(keepout
			(tracks not_allowed)
			(vias allowed)
			(pads allowed)
			(copperpour not_allowed)
			(footprints allowed)
		)
		(placement
			(enabled no)
			(sheetname "")
		)
		(fill yes
			(thermal_gap 0.5)
			(thermal_bridge_width 0.5)
			(island_removal_mode 0)
		)
		(polygon
			(pts
				(arc
					(start 187.394088 -286.585406)
					(mid 186.726068 -286.585406)
					(end 187.394088 -286.585406)
				)
			)
		)
	)
	(zone
		(layers "B.Cu" "In6.Cu" "In11.Cu" "In13.Cu" "In15.Cu")
		(hatch none 0.5)
		(connect_pads
			(clearance 0)
		)
		(min_thickness 0.25)
		(keepout
			(tracks not_allowed)
			(vias allowed)
			(pads allowed)
			(copperpour not_allowed)
			(footprints allowed)
		)
		(placement
			(enabled no)
			(sheetname "")
		)
		(fill yes
			(thermal_gap 0.5)
			(thermal_bridge_width 0.5)
			(island_removal_mode 0)
		)
		(polygon
			(pts
				(arc
					(start 285.070042 -285.735014)
					(mid 284.402022 -285.735014)
					(end 285.070042 -285.735014)
				)
			)
		)
	)
	(zone
		(layers "B.Cu" "In6.Cu" "In11.Cu" "In13.Cu" "In15.Cu")
		(hatch none 0.5)
		(connect_pads
			(clearance 0)
		)
		(min_thickness 0.25)
		(keepout
			(tracks not_allowed)
			(vias allowed)
			(pads allowed)
			(copperpour not_allowed)
			(footprints allowed)
		)
		(placement
			(enabled no)
			(sheetname "")
		)
		(fill yes
			(thermal_gap 0.5)
			(thermal_bridge_width 0.5)
			(island_removal_mode 0)
		)
		(polygon
			(pts
				(arc
					(start 37.129974 -234.73537)
					(mid 36.461954 -234.73537)
					(end 37.129974 -234.73537)
				)
			)
		)
	)
	(zone
		(layers "B.Cu" "In6.Cu" "In11.Cu" "In13.Cu" "In15.Cu")
		(hatch none 0.5)
		(connect_pads
			(clearance 0)
		)
		(min_thickness 0.25)
		(keepout
			(tracks not_allowed)
			(vias allowed)
			(pads allowed)
			(copperpour not_allowed)
			(footprints allowed)
		)
		(placement
			(enabled no)
			(sheetname "")
		)
		(fill yes
			(thermal_gap 0.5)
			(thermal_bridge_width 0.5)
			(island_removal_mode 0)
		)
		(polygon
			(pts
				(arc
					(start 91.41587 -226.66452)
					(mid 90.78595 -226.66452)
					(end 91.41587 -226.66452)
				)
			)
		)
	)
	(zone
		(layers "B.Cu" "In6.Cu" "In11.Cu" "In13.Cu" "In15.Cu")
		(hatch none 0.5)
		(connect_pads
			(clearance 0)
		)
		(min_thickness 0.25)
		(keepout
			(tracks not_allowed)
			(vias allowed)
			(pads allowed)
			(copperpour not_allowed)
			(footprints allowed)
		)
		(placement
			(enabled no)
			(sheetname "")
		)
		(fill yes
			(thermal_gap 0.5)
			(thermal_bridge_width 0.5)
			(island_removal_mode 0)
		)
		(polygon
			(pts
				(arc
					(start 33.029906 -308.685438)
					(mid 32.361886 -308.685438)
					(end 33.029906 -308.685438)
				)
			)
		)
	)
	(zone
		(layers "B.Cu" "In6.Cu" "In11.Cu" "In13.Cu" "In15.Cu")
		(hatch none 0.5)
		(connect_pads
			(clearance 0)
		)
		(min_thickness 0.25)
		(keepout
			(tracks not_allowed)
			(vias allowed)
			(pads allowed)
			(copperpour not_allowed)
			(footprints allowed)
		)
		(placement
			(enabled no)
			(sheetname "")
		)
		(fill yes
			(thermal_gap 0.5)
			(thermal_bridge_width 0.5)
			(island_removal_mode 0)
		)
		(polygon
			(pts
				(arc
					(start 161.176716 -404.46452)
					(mid 160.508696 -404.46452)
					(end 161.176716 -404.46452)
				)
			)
		)
	)
	(zone
		(layers "B.Cu" "In6.Cu" "In11.Cu" "In13.Cu" "In15.Cu")
		(hatch none 0.5)
		(connect_pads
			(clearance 0)
		)
		(min_thickness 0.25)
		(keepout
			(tracks not_allowed)
			(vias allowed)
			(pads allowed)
			(copperpour not_allowed)
			(footprints allowed)
		)
		(placement
			(enabled no)
			(sheetname "")
		)
		(fill yes
			(thermal_gap 0.5)
			(thermal_bridge_width 0.5)
			(island_removal_mode 0)
		)
		(polygon
			(pts
				(arc
					(start 340.295992 -229.904036)
					(mid 339.666072 -229.904036)
					(end 340.295992 -229.904036)
				)
			)
		)
	)
	(zone
		(layers "B.Cu" "In6.Cu" "In11.Cu" "In13.Cu" "In15.Cu")
		(hatch none 0.5)
		(connect_pads
			(clearance 0)
		)
		(min_thickness 0.25)
		(keepout
			(tracks not_allowed)
			(vias allowed)
			(pads allowed)
			(copperpour not_allowed)
			(footprints allowed)
		)
		(placement
			(enabled no)
			(sheetname "")
		)
		(fill yes
			(thermal_gap 0.5)
			(thermal_bridge_width 0.5)
			(island_removal_mode 0)
		)
		(polygon
			(pts
				(arc
					(start 435.334156 -301.034958)
					(mid 434.666136 -301.034958)
					(end 435.334156 -301.034958)
				)
			)
		)
	)
	(zone
		(layers "B.Cu" "In6.Cu" "In11.Cu" "In13.Cu" "In15.Cu")
		(hatch none 0.5)
		(connect_pads
			(clearance 0)
		)
		(min_thickness 0.25)
		(keepout
			(tracks not_allowed)
			(vias allowed)
			(pads allowed)
			(copperpour not_allowed)
			(footprints allowed)
		)
		(placement
			(enabled no)
			(sheetname "")
		)
		(fill yes
			(thermal_gap 0.5)
			(thermal_bridge_width 0.5)
			(island_removal_mode 0)
		)
		(polygon
			(pts
				(arc
					(start 364.729776 -234.764072)
					(mid 364.099856 -234.764072)
					(end 364.729776 -234.764072)
				)
			)
		)
	)
	(zone
		(layers "B.Cu" "In6.Cu" "In11.Cu" "In13.Cu" "In15.Cu")
		(hatch none 0.5)
		(connect_pads
			(clearance 0)
		)
		(min_thickness 0.25)
		(keepout
			(tracks not_allowed)
			(vias allowed)
			(pads allowed)
			(copperpour not_allowed)
			(footprints allowed)
		)
		(placement
			(enabled no)
			(sheetname "")
		)
		(fill yes
			(thermal_gap 0.5)
			(thermal_bridge_width 0.5)
			(island_removal_mode 0)
		)
		(polygon
			(pts
				(arc
					(start 90.94597 -235.574332)
					(mid 90.31605 -235.574332)
					(end 90.94597 -235.574332)
				)
			)
		)
	)
	(zone
		(layers "B.Cu" "In6.Cu" "In11.Cu" "In13.Cu" "In15.Cu")
		(hatch none 0.5)
		(connect_pads
			(clearance 0)
		)
		(min_thickness 0.25)
		(keepout
			(tracks not_allowed)
			(vias allowed)
			(pads allowed)
			(copperpour not_allowed)
			(footprints allowed)
		)
		(placement
			(enabled no)
			(sheetname "")
		)
		(fill yes
			(thermal_gap 0.5)
			(thermal_bridge_width 0.5)
			(island_removal_mode 0)
		)
		(polygon
			(pts
				(arc
					(start 132.129784 -279.756362)
					(mid 131.499864 -279.756362)
					(end 132.129784 -279.756362)
				)
			)
		)
	)
	(zone
		(layers "B.Cu" "In6.Cu" "In11.Cu" "In13.Cu" "In15.Cu")
		(hatch none 0.5)
		(connect_pads
			(clearance 0)
		)
		(min_thickness 0.25)
		(keepout
			(tracks not_allowed)
			(vias allowed)
			(pads allowed)
			(copperpour not_allowed)
			(footprints allowed)
		)
		(placement
			(enabled no)
			(sheetname "")
		)
		(fill yes
			(thermal_gap 0.5)
			(thermal_bridge_width 0.5)
			(island_removal_mode 0)
		)
		(polygon
			(pts
				(arc
					(start 339.656166 -291.095938)
					(mid 339.026246 -291.095938)
					(end 339.656166 -291.095938)
				)
			)
		)
	)
	(zone
		(layers "B.Cu" "In6.Cu" "In11.Cu" "In13.Cu" "In15.Cu")
		(hatch none 0.5)
		(connect_pads
			(clearance 0)
		)
		(min_thickness 0.25)
		(keepout
			(tracks not_allowed)
			(vias allowed)
			(pads allowed)
			(copperpour not_allowed)
			(footprints allowed)
		)
		(placement
			(enabled no)
			(sheetname "")
		)
		(fill yes
			(thermal_gap 0.5)
			(thermal_bridge_width 0.5)
			(island_removal_mode 0)
		)
		(polygon
			(pts
				(arc
					(start 340.766146 -238.814102)
					(mid 340.136226 -238.814102)
					(end 340.766146 -238.814102)
				)
			)
		)
	)
	(zone
		(layers "B.Cu" "In6.Cu" "In11.Cu" "In13.Cu" "In15.Cu")
		(hatch none 0.5)
		(connect_pads
			(clearance 0)
		)
		(min_thickness 0.25)
		(keepout
			(tracks not_allowed)
			(vias allowed)
			(pads allowed)
			(copperpour not_allowed)
			(footprints allowed)
		)
		(placement
			(enabled no)
			(sheetname "")
		)
		(fill yes
			(thermal_gap 0.5)
			(thermal_bridge_width 0.5)
			(island_removal_mode 0)
		)
		(polygon
			(pts
				(arc
					(start 412.13405 -397.156432)
					(mid 411.50413 -397.156432)
					(end 412.13405 -397.156432)
				)
			)
		)
	)
	(zone
		(layers "B.Cu" "In6.Cu" "In11.Cu" "In13.Cu" "In15.Cu")
		(hatch none 0.5)
		(connect_pads
			(clearance 0)
		)
		(min_thickness 0.25)
		(keepout
			(tracks not_allowed)
			(vias allowed)
			(pads allowed)
			(copperpour not_allowed)
			(footprints allowed)
		)
		(placement
			(enabled no)
			(sheetname "")
		)
		(fill yes
			(thermal_gap 0.5)
			(thermal_bridge_width 0.5)
			(island_removal_mode 0)
		)
		(polygon
			(pts
				(arc
					(start 365.02975 -291.095938)
					(mid 364.39983 -291.095938)
					(end 365.02975 -291.095938)
				)
			)
		)
	)
	(zone
		(layers "B.Cu" "In6.Cu" "In11.Cu" "In13.Cu" "In15.Cu")
		(hatch none 0.5)
		(connect_pads
			(clearance 0)
		)
		(min_thickness 0.25)
		(keepout
			(tracks not_allowed)
			(vias allowed)
			(pads allowed)
			(copperpour not_allowed)
			(footprints allowed)
		)
		(placement
			(enabled no)
			(sheetname "")
		)
		(fill yes
			(thermal_gap 0.5)
			(thermal_bridge_width 0.5)
			(island_removal_mode 0)
		)
		(polygon
			(pts
				(arc
					(start 380.709678 -238.004096)
					(mid 380.079758 -238.004096)
					(end 380.709678 -238.004096)
				)
			)
		)
	)
	(zone
		(layers "B.Cu" "In6.Cu" "In11.Cu" "In13.Cu" "In15.Cu")
		(hatch none 0.5)
		(connect_pads
			(clearance 0)
		)
		(min_thickness 0.25)
		(keepout
			(tracks not_allowed)
			(vias allowed)
			(pads allowed)
			(copperpour not_allowed)
			(footprints allowed)
		)
		(placement
			(enabled no)
			(sheetname "")
		)
		(fill yes
			(thermal_gap 0.5)
			(thermal_bridge_width 0.5)
			(island_removal_mode 0)
		)
		(polygon
			(pts
				(arc
					(start 132.76961 -246.10441)
					(mid 132.13969 -246.10441)
					(end 132.76961 -246.10441)
				)
			)
		)
	)
	(zone
		(layers "B.Cu" "In6.Cu" "In11.Cu" "In13.Cu" "In15.Cu")
		(hatch none 0.5)
		(connect_pads
			(clearance 0)
		)
		(min_thickness 0.25)
		(keepout
			(tracks not_allowed)
			(vias allowed)
			(pads allowed)
			(copperpour not_allowed)
			(footprints allowed)
		)
		(placement
			(enabled no)
			(sheetname "")
		)
		(fill yes
			(thermal_gap 0.5)
			(thermal_bridge_width 0.5)
			(island_removal_mode 0)
		)
		(polygon
			(pts
				(arc
					(start 299.394626 -5.509006)
					(mid 298.726606 -5.509006)
					(end 299.394626 -5.509006)
				)
			)
		)
	)
	(zone
		(layers "B.Cu" "In6.Cu" "In11.Cu" "In13.Cu" "In15.Cu")
		(hatch none 0.5)
		(connect_pads
			(clearance 0)
		)
		(min_thickness 0.25)
		(keepout
			(tracks not_allowed)
			(vias allowed)
			(pads allowed)
			(copperpour not_allowed)
			(footprints allowed)
		)
		(placement
			(enabled no)
			(sheetname "")
		)
		(fill yes
			(thermal_gap 0.5)
			(thermal_bridge_width 0.5)
			(island_removal_mode 0)
		)
		(polygon
			(pts
				(arc
					(start 91.716098 -266.796266)
					(mid 91.086178 -266.796266)
					(end 91.716098 -266.796266)
				)
			)
		)
	)
	(zone
		(layers "B.Cu" "In6.Cu" "In11.Cu" "In13.Cu" "In15.Cu")
		(hatch none 0.5)
		(connect_pads
			(clearance 0)
		)
		(min_thickness 0.25)
		(keepout
			(tracks not_allowed)
			(vias allowed)
			(pads allowed)
			(copperpour not_allowed)
			(footprints allowed)
		)
		(placement
			(enabled no)
			(sheetname "")
		)
		(fill yes
			(thermal_gap 0.5)
			(thermal_bridge_width 0.5)
			(island_removal_mode 0)
		)
		(polygon
			(pts
				(arc
					(start 33.029906 -207.535272)
					(mid 32.361886 -207.535272)
					(end 33.029906 -207.535272)
				)
			)
		)
	)
	(zone
		(layers "B.Cu" "In6.Cu" "In11.Cu" "In13.Cu" "In15.Cu")
		(hatch none 0.5)
		(connect_pads
			(clearance 0)
		)
		(min_thickness 0.25)
		(keepout
			(tracks not_allowed)
			(vias allowed)
			(pads allowed)
			(copperpour not_allowed)
			(footprints allowed)
		)
		(placement
			(enabled no)
			(sheetname "")
		)
		(fill yes
			(thermal_gap 0.5)
			(thermal_bridge_width 0.5)
			(island_removal_mode 0)
		)
		(polygon
			(pts
				(arc
					(start 339.355938 -231.524048)
					(mid 338.726018 -231.524048)
					(end 339.355938 -231.524048)
				)
			)
		)
	)
	(zone
		(layers "B.Cu" "In6.Cu" "In11.Cu" "In13.Cu" "In15.Cu")
		(hatch none 0.5)
		(connect_pads
			(clearance 0)
		)
		(min_thickness 0.25)
		(keepout
			(tracks not_allowed)
			(vias allowed)
			(pads allowed)
			(copperpour not_allowed)
			(footprints allowed)
		)
		(placement
			(enabled no)
			(sheetname "")
		)
		(fill yes
			(thermal_gap 0.5)
			(thermal_bridge_width 0.5)
			(island_removal_mode 0)
		)
		(polygon
			(pts
				(arc
					(start 435.334156 -207.535018)
					(mid 434.666136 -207.535018)
					(end 435.334156 -207.535018)
				)
			)
		)
	)
	(zone
		(layers "B.Cu" "In6.Cu" "In11.Cu" "In13.Cu" "In15.Cu")
		(hatch none 0.5)
		(connect_pads
			(clearance 0)
		)
		(min_thickness 0.25)
		(keepout
			(tracks not_allowed)
			(vias allowed)
			(pads allowed)
			(copperpour not_allowed)
			(footprints allowed)
		)
		(placement
			(enabled no)
			(sheetname "")
		)
		(fill yes
			(thermal_gap 0.5)
			(thermal_bridge_width 0.5)
			(island_removal_mode 0)
		)
		(polygon
			(pts
				(arc
					(start 340.766146 -242.054126)
					(mid 340.136226 -242.054126)
					(end 340.766146 -242.054126)
				)
			)
		)
	)
	(zone
		(layers "B.Cu" "In6.Cu" "In11.Cu" "In13.Cu" "In15.Cu")
		(hatch none 0.5)
		(connect_pads
			(clearance 0)
		)
		(min_thickness 0.25)
		(keepout
			(tracks not_allowed)
			(vias allowed)
			(pads allowed)
			(copperpour not_allowed)
			(footprints allowed)
		)
		(placement
			(enabled no)
			(sheetname "")
		)
		(fill yes
			(thermal_gap 0.5)
			(thermal_bridge_width 0.5)
			(island_removal_mode 0)
		)
		(polygon
			(pts
				(arc
					(start 37.129974 -307.8353)
					(mid 36.461954 -307.8353)
					(end 37.129974 -307.8353)
				)
			)
		)
	)
	(zone
		(layers "B.Cu" "In6.Cu" "In11.Cu" "In13.Cu" "In15.Cu")
		(hatch none 0.5)
		(connect_pads
			(clearance 0)
		)
		(min_thickness 0.25)
		(keepout
			(tracks not_allowed)
			(vias allowed)
			(pads allowed)
			(copperpour not_allowed)
			(footprints allowed)
		)
		(placement
			(enabled no)
			(sheetname "")
		)
		(fill yes
			(thermal_gap 0.5)
			(thermal_bridge_width 0.5)
			(island_removal_mode 0)
		)
		(polygon
			(pts
				(arc
					(start 365.969804 -289.475926)
					(mid 365.339884 -289.475926)
					(end 365.969804 -289.475926)
				)
			)
		)
	)
	(zone
		(layers "B.Cu" "In6.Cu" "In11.Cu" "In13.Cu" "In15.Cu")
		(hatch none 0.5)
		(connect_pads
			(clearance 0)
		)
		(min_thickness 0.25)
		(keepout
			(tracks not_allowed)
			(vias allowed)
			(pads allowed)
			(copperpour not_allowed)
			(footprints allowed)
		)
		(placement
			(enabled no)
			(sheetname "")
		)
		(fill yes
			(thermal_gap 0.5)
			(thermal_bridge_width 0.5)
			(island_removal_mode 0)
		)
		(polygon
			(pts
				(arc
					(start 341.06612 -283.806138)
					(mid 340.4362 -283.806138)
					(end 341.06612 -283.806138)
				)
			)
		)
	)
	(zone
		(layers "B.Cu" "In6.Cu" "In11.Cu" "In13.Cu" "In15.Cu")
		(hatch none 0.5)
		(connect_pads
			(clearance 0)
		)
		(min_thickness 0.25)
		(keepout
			(tracks not_allowed)
			(vias allowed)
			(pads allowed)
			(copperpour not_allowed)
			(footprints allowed)
		)
		(placement
			(enabled no)
			(sheetname "")
		)
		(fill yes
			(thermal_gap 0.5)
			(thermal_bridge_width 0.5)
			(island_removal_mode 0)
		)
		(polygon
			(pts
				(arc
					(start 341.06612 -275.706078)
					(mid 340.4362 -275.706078)
					(end 341.06612 -275.706078)
				)
			)
		)
	)
	(zone
		(layers "B.Cu" "In6.Cu" "In11.Cu" "In13.Cu" "In15.Cu")
		(hatch none 0.5)
		(connect_pads
			(clearance 0)
		)
		(min_thickness 0.25)
		(keepout
			(tracks not_allowed)
			(vias allowed)
			(pads allowed)
			(copperpour not_allowed)
			(footprints allowed)
		)
		(placement
			(enabled no)
			(sheetname "")
		)
		(fill yes
			(thermal_gap 0.5)
			(thermal_bridge_width 0.5)
			(island_removal_mode 0)
		)
		(polygon
			(pts
				(arc
					(start 92.826078 -246.914416)
					(mid 92.196158 -246.914416)
					(end 92.826078 -246.914416)
				)
			)
		)
	)
	(zone
		(layers "B.Cu" "In6.Cu" "In11.Cu" "In13.Cu" "In15.Cu")
		(hatch none 0.5)
		(connect_pads
			(clearance 0)
		)
		(min_thickness 0.25)
		(keepout
			(tracks not_allowed)
			(vias allowed)
			(pads allowed)
			(copperpour not_allowed)
			(footprints allowed)
		)
		(placement
			(enabled no)
			(sheetname "")
		)
		(fill yes
			(thermal_gap 0.5)
			(thermal_bridge_width 0.5)
			(island_removal_mode 0)
		)
		(polygon
			(pts
				(arc
					(start 439.434224 -287.435036)
					(mid 438.766204 -287.435036)
					(end 439.434224 -287.435036)
				)
			)
		)
	)
	(zone
		(layers "B.Cu" "In6.Cu" "In11.Cu" "In13.Cu" "In15.Cu")
		(hatch none 0.5)
		(connect_pads
			(clearance 0)
		)
		(min_thickness 0.25)
		(keepout
			(tracks not_allowed)
			(vias allowed)
			(pads allowed)
			(copperpour not_allowed)
			(footprints allowed)
		)
		(placement
			(enabled no)
			(sheetname "")
		)
		(fill yes
			(thermal_gap 0.5)
			(thermal_bridge_width 0.5)
			(island_removal_mode 0)
		)
		(polygon
			(pts
				(arc
					(start 114.739674 -287.046162)
					(mid 114.109754 -287.046162)
					(end 114.739674 -287.046162)
				)
			)
		)
	)
	(zone
		(layers "B.Cu" "In6.Cu" "In11.Cu" "In13.Cu" "In15.Cu")
		(hatch none 0.5)
		(connect_pads
			(clearance 0)
		)
		(min_thickness 0.25)
		(keepout
			(tracks not_allowed)
			(vias allowed)
			(pads allowed)
			(copperpour not_allowed)
			(footprints allowed)
		)
		(placement
			(enabled no)
			(sheetname "")
		)
		(fill yes
			(thermal_gap 0.5)
			(thermal_bridge_width 0.5)
			(island_removal_mode 0)
		)
		(polygon
			(pts
				(arc
					(start 37.129974 -269.58544)
					(mid 36.461954 -269.58544)
					(end 37.129974 -269.58544)
				)
			)
		)
	)
	(zone
		(layers "B.Cu" "In6.Cu" "In11.Cu" "In13.Cu" "In15.Cu")
		(hatch none 0.5)
		(connect_pads
			(clearance 0)
		)
		(min_thickness 0.25)
		(keepout
			(tracks not_allowed)
			(vias allowed)
			(pads allowed)
			(copperpour not_allowed)
			(footprints allowed)
		)
		(placement
			(enabled no)
			(sheetname "")
		)
		(fill yes
			(thermal_gap 0.5)
			(thermal_bridge_width 0.5)
			(island_removal_mode 0)
		)
		(polygon
			(pts
				(arc
					(start 339.656166 -263.555988)
					(mid 339.026246 -263.555988)
					(end 339.656166 -263.555988)
				)
			)
		)
	)
	(zone
		(layers "B.Cu" "In6.Cu" "In11.Cu" "In13.Cu" "In15.Cu")
		(hatch none 0.5)
		(connect_pads
			(clearance 0)
		)
		(min_thickness 0.25)
		(keepout
			(tracks not_allowed)
			(vias allowed)
			(pads allowed)
			(copperpour not_allowed)
			(footprints allowed)
		)
		(placement
			(enabled no)
			(sheetname "")
		)
		(fill yes
			(thermal_gap 0.5)
			(thermal_bridge_width 0.5)
			(island_removal_mode 0)
		)
		(polygon
			(pts
				(arc
					(start 92.355924 -234.764326)
					(mid 91.726004 -234.764326)
					(end 92.355924 -234.764326)
				)
			)
		)
	)
	(zone
		(layers "B.Cu" "In6.Cu" "In11.Cu" "In13.Cu" "In15.Cu")
		(hatch none 0.5)
		(connect_pads
			(clearance 0)
		)
		(min_thickness 0.25)
		(keepout
			(tracks not_allowed)
			(vias allowed)
			(pads allowed)
			(copperpour not_allowed)
			(footprints allowed)
		)
		(placement
			(enabled no)
			(sheetname "")
		)
		(fill yes
			(thermal_gap 0.5)
			(thermal_bridge_width 0.5)
			(island_removal_mode 0)
		)
		(polygon
			(pts
				(arc
					(start 50.4698 -6.725158)
					(mid 49.80178 -6.725158)
					(end 50.4698 -6.725158)
				)
			)
		)
	)
	(zone
		(layers "B.Cu" "In6.Cu" "In11.Cu" "In13.Cu" "In15.Cu")
		(hatch none 0.5)
		(connect_pads
			(clearance 0)
		)
		(min_thickness 0.25)
		(keepout
			(tracks not_allowed)
			(vias allowed)
			(pads allowed)
			(copperpour not_allowed)
			(footprints allowed)
		)
		(placement
			(enabled no)
			(sheetname "")
		)
		(fill yes
			(thermal_gap 0.5)
			(thermal_bridge_width 0.5)
			(island_removal_mode 0)
		)
		(polygon
			(pts
				(arc
					(start 92.355924 -231.524302)
					(mid 91.726004 -231.524302)
					(end 92.355924 -231.524302)
				)
			)
		)
	)
	(zone
		(layers "B.Cu" "In6.Cu" "In11.Cu" "In13.Cu" "In15.Cu")
		(hatch none 0.5)
		(connect_pads
			(clearance 0)
		)
		(min_thickness 0.25)
		(keepout
			(tracks not_allowed)
			(vias allowed)
			(pads allowed)
			(copperpour not_allowed)
			(footprints allowed)
		)
		(placement
			(enabled no)
			(sheetname "")
		)
		(fill yes
			(thermal_gap 0.5)
			(thermal_bridge_width 0.5)
			(island_removal_mode 0)
		)
		(polygon
			(pts
				(arc
					(start 381.479806 -291.905944)
					(mid 380.849886 -291.905944)
					(end 381.479806 -291.905944)
				)
			)
		)
	)
	(zone
		(layers "B.Cu" "In6.Cu" "In11.Cu" "In13.Cu" "In15.Cu")
		(hatch none 0.5)
		(connect_pads
			(clearance 0)
		)
		(min_thickness 0.25)
		(keepout
			(tracks not_allowed)
			(vias allowed)
			(pads allowed)
			(copperpour not_allowed)
			(footprints allowed)
		)
		(placement
			(enabled no)
			(sheetname "")
		)
		(fill yes
			(thermal_gap 0.5)
			(thermal_bridge_width 0.5)
			(island_removal_mode 0)
		)
		(polygon
			(pts
				(arc
					(start 91.716098 -291.096192)
					(mid 91.086178 -291.096192)
					(end 91.716098 -291.096192)
				)
			)
		)
	)
	(zone
		(layers "B.Cu" "In6.Cu" "In11.Cu" "In13.Cu" "In15.Cu")
		(hatch none 0.5)
		(connect_pads
			(clearance 0)
		)
		(min_thickness 0.25)
		(keepout
			(tracks not_allowed)
			(vias allowed)
			(pads allowed)
			(copperpour not_allowed)
			(footprints allowed)
		)
		(placement
			(enabled no)
			(sheetname "")
		)
		(fill yes
			(thermal_gap 0.5)
			(thermal_bridge_width 0.5)
			(island_removal_mode 0)
		)
		(polygon
			(pts
				(arc
					(start 187.394088 -304.435256)
					(mid 186.726068 -304.435256)
					(end 187.394088 -304.435256)
				)
			)
		)
	)
	(zone
		(layers "B.Cu" "In6.Cu" "In11.Cu" "In13.Cu" "In15.Cu")
		(hatch none 0.5)
		(connect_pads
			(clearance 0)
		)
		(min_thickness 0.25)
		(keepout
			(tracks not_allowed)
			(vias allowed)
			(pads allowed)
			(copperpour not_allowed)
			(footprints allowed)
		)
		(placement
			(enabled no)
			(sheetname "")
		)
		(fill yes
			(thermal_gap 0.5)
			(thermal_bridge_width 0.5)
			(island_removal_mode 0)
		)
		(polygon
			(pts
				(arc
					(start 280.969974 -213.484968)
					(mid 280.301954 -213.484968)
					(end 280.969974 -213.484968)
				)
			)
		)
	)
	(zone
		(layers "B.Cu" "In6.Cu" "In11.Cu" "In13.Cu" "In15.Cu")
		(hatch none 0.5)
		(connect_pads
			(clearance 0)
		)
		(min_thickness 0.25)
		(keepout
			(tracks not_allowed)
			(vias allowed)
			(pads allowed)
			(copperpour not_allowed)
			(footprints allowed)
		)
		(placement
			(enabled no)
			(sheetname "")
		)
		(fill yes
			(thermal_gap 0.5)
			(thermal_bridge_width 0.5)
			(island_removal_mode 0)
		)
		(polygon
			(pts
				(arc
					(start 381.479806 -293.525956)
					(mid 380.849886 -293.525956)
					(end 381.479806 -293.525956)
				)
			)
		)
	)
	(zone
		(layers "B.Cu" "In6.Cu" "In11.Cu" "In13.Cu" "In15.Cu")
		(hatch none 0.5)
		(connect_pads
			(clearance 0)
		)
		(min_thickness 0.25)
		(keepout
			(tracks not_allowed)
			(vias allowed)
			(pads allowed)
			(copperpour not_allowed)
			(footprints allowed)
		)
		(placement
			(enabled no)
			(sheetname "")
		)
		(fill yes
			(thermal_gap 0.5)
			(thermal_bridge_width 0.5)
			(island_removal_mode 0)
		)
		(polygon
			(pts
				(arc
					(start 341.06612 -265.986006)
					(mid 340.4362 -265.986006)
					(end 341.06612 -265.986006)
				)
			)
		)
	)
	(zone
		(layers "B.Cu" "In6.Cu" "In11.Cu" "In13.Cu" "In15.Cu")
		(hatch none 0.5)
		(connect_pads
			(clearance 0)
		)
		(min_thickness 0.25)
		(keepout
			(tracks not_allowed)
			(vias allowed)
			(pads allowed)
			(copperpour not_allowed)
			(footprints allowed)
		)
		(placement
			(enabled no)
			(sheetname "")
		)
		(fill yes
			(thermal_gap 0.5)
			(thermal_bridge_width 0.5)
			(island_removal_mode 0)
		)
		(polygon
			(pts
				(arc
					(start 132.129784 -271.656302)
					(mid 131.499864 -271.656302)
					(end 132.129784 -271.656302)
				)
			)
		)
	)
	(zone
		(layers "B.Cu" "In6.Cu" "In11.Cu" "In13.Cu" "In15.Cu")
		(hatch none 0.5)
		(connect_pads
			(clearance 0)
		)
		(min_thickness 0.25)
		(keepout
			(tracks not_allowed)
			(vias allowed)
			(pads allowed)
			(copperpour not_allowed)
			(footprints allowed)
		)
		(placement
			(enabled no)
			(sheetname "")
		)
		(fill yes
			(thermal_gap 0.5)
			(thermal_bridge_width 0.5)
			(island_removal_mode 0)
		)
		(polygon
			(pts
				(arc
					(start 381.009906 -278.136096)
					(mid 380.379986 -278.136096)
					(end 381.009906 -278.136096)
				)
			)
		)
	)
	(zone
		(layers "B.Cu" "In6.Cu" "In11.Cu" "In13.Cu" "In15.Cu")
		(hatch none 0.5)
		(connect_pads
			(clearance 0)
		)
		(min_thickness 0.25)
		(keepout
			(tracks not_allowed)
			(vias allowed)
			(pads allowed)
			(copperpour not_allowed)
			(footprints allowed)
		)
		(placement
			(enabled no)
			(sheetname "")
		)
		(fill yes
			(thermal_gap 0.5)
			(thermal_bridge_width 0.5)
			(island_removal_mode 0)
		)
		(polygon
			(pts
				(arc
					(start 379.769878 -247.724168)
					(mid 379.139958 -247.724168)
					(end 379.769878 -247.724168)
				)
			)
		)
	)
	(zone
		(layers "B.Cu" "In6.Cu" "In11.Cu" "In13.Cu" "In15.Cu")
		(hatch none 0.5)
		(connect_pads
			(clearance 0)
		)
		(min_thickness 0.25)
		(keepout
			(tracks not_allowed)
			(vias allowed)
			(pads allowed)
			(copperpour not_allowed)
			(footprints allowed)
		)
		(placement
			(enabled no)
			(sheetname "")
		)
		(fill yes
			(thermal_gap 0.5)
			(thermal_bridge_width 0.5)
			(island_removal_mode 0)
		)
		(polygon
			(pts
				(arc
					(start 381.179832 -240.434114)
					(mid 380.549912 -240.434114)
					(end 381.179832 -240.434114)
				)
			)
		)
	)
	(zone
		(layers "B.Cu" "In6.Cu" "In11.Cu" "In13.Cu" "In15.Cu")
		(hatch none 0.5)
		(connect_pads
			(clearance 0)
		)
		(min_thickness 0.25)
		(keepout
			(tracks not_allowed)
			(vias allowed)
			(pads allowed)
			(copperpour not_allowed)
			(footprints allowed)
		)
		(placement
			(enabled no)
			(sheetname "")
		)
		(fill yes
			(thermal_gap 0.5)
			(thermal_bridge_width 0.5)
			(island_removal_mode 0)
		)
		(polygon
			(pts
				(arc
					(start 37.129974 -285.735268)
					(mid 36.461954 -285.735268)
					(end 37.129974 -285.735268)
				)
			)
		)
	)
	(zone
		(layers "B.Cu" "In6.Cu" "In11.Cu" "In13.Cu" "In15.Cu")
		(hatch none 0.5)
		(connect_pads
			(clearance 0)
		)
		(min_thickness 0.25)
		(keepout
			(tracks not_allowed)
			(vias allowed)
			(pads allowed)
			(copperpour not_allowed)
			(footprints allowed)
		)
		(placement
			(enabled no)
			(sheetname "")
		)
		(fill yes
			(thermal_gap 0.5)
			(thermal_bridge_width 0.5)
			(island_removal_mode 0)
		)
		(polygon
			(pts
				(arc
					(start 404.134066 -397.849344)
					(mid 403.504146 -397.849344)
					(end 404.134066 -397.849344)
				)
			)
		)
	)
	(zone
		(layers "B.Cu" "In6.Cu" "In11.Cu" "In13.Cu" "In15.Cu")
		(hatch none 0.5)
		(connect_pads
			(clearance 0)
		)
		(min_thickness 0.25)
		(keepout
			(tracks not_allowed)
			(vias allowed)
			(pads allowed)
			(copperpour not_allowed)
			(footprints allowed)
		)
		(placement
			(enabled no)
			(sheetname "")
		)
		(fill yes
			(thermal_gap 0.5)
			(thermal_bridge_width 0.5)
			(island_removal_mode 0)
		)
		(polygon
			(pts
				(arc
					(start 373.489728 -287.856168)
					(mid 372.859808 -287.856168)
					(end 373.489728 -287.856168)
				)
			)
		)
	)
	(zone
		(layers "B.Cu" "In6.Cu" "In11.Cu" "In13.Cu" "In15.Cu")
		(hatch none 0.5)
		(connect_pads
			(clearance 0)
		)
		(min_thickness 0.25)
		(keepout
			(tracks not_allowed)
			(vias allowed)
			(pads allowed)
			(copperpour not_allowed)
			(footprints allowed)
		)
		(placement
			(enabled no)
			(sheetname "")
		)
		(fill yes
			(thermal_gap 0.5)
			(thermal_bridge_width 0.5)
			(island_removal_mode 0)
		)
		(polygon
			(pts
				(arc
					(start 380.069852 -287.856168)
					(mid 379.439932 -287.856168)
					(end 380.069852 -287.856168)
				)
			)
		)
	)
	(zone
		(layers "B.Cu" "In6.Cu" "In11.Cu" "In13.Cu" "In15.Cu")
		(hatch none 0.5)
		(connect_pads
			(clearance 0)
		)
		(min_thickness 0.25)
		(keepout
			(tracks not_allowed)
			(vias allowed)
			(pads allowed)
			(copperpour not_allowed)
			(footprints allowed)
		)
		(placement
			(enabled no)
			(sheetname "")
		)
		(fill yes
			(thermal_gap 0.5)
			(thermal_bridge_width 0.5)
			(island_removal_mode 0)
		)
		(polygon
			(pts
				(arc
					(start 158.113476 -404.46452)
					(mid 157.445456 -404.46452)
					(end 158.113476 -404.46452)
				)
			)
		)
	)
	(zone
		(layers "B.Cu" "In6.Cu" "In11.Cu" "In13.Cu" "In15.Cu")
		(hatch none 0.5)
		(connect_pads
			(clearance 0)
		)
		(min_thickness 0.25)
		(keepout
			(tracks not_allowed)
			(vias allowed)
			(pads allowed)
			(copperpour not_allowed)
			(footprints allowed)
		)
		(placement
			(enabled no)
			(sheetname "")
		)
		(fill yes
			(thermal_gap 0.5)
			(thermal_bridge_width 0.5)
			(island_removal_mode 0)
		)
		(polygon
			(pts
				(arc
					(start 312.506106 -397.156432)
					(mid 311.876186 -397.156432)
					(end 312.506106 -397.156432)
				)
			)
		)
	)
	(zone
		(layers "B.Cu" "In6.Cu" "In11.Cu" "In13.Cu" "In15.Cu")
		(hatch none 0.5)
		(connect_pads
			(clearance 0)
		)
		(min_thickness 0.25)
		(keepout
			(tracks not_allowed)
			(vias allowed)
			(pads allowed)
			(copperpour not_allowed)
			(footprints allowed)
		)
		(placement
			(enabled no)
			(sheetname "")
		)
		(fill yes
			(thermal_gap 0.5)
			(thermal_bridge_width 0.5)
			(island_removal_mode 0)
		)
		(polygon
			(pts
				(arc
					(start 421.406574 -19.137122)
					(mid 420.738554 -19.137122)
					(end 421.406574 -19.137122)
				)
			)
		)
	)
	(zone
		(layers "B.Cu" "In6.Cu" "In11.Cu" "In13.Cu" "In15.Cu")
		(hatch none 0.5)
		(connect_pads
			(clearance 0)
		)
		(min_thickness 0.25)
		(keepout
			(tracks not_allowed)
			(vias allowed)
			(pads allowed)
			(copperpour not_allowed)
			(footprints allowed)
		)
		(placement
			(enabled no)
			(sheetname "")
		)
		(fill yes
			(thermal_gap 0.5)
			(thermal_bridge_width 0.5)
			(island_removal_mode 0)
		)
		(polygon
			(pts
				(arc
					(start 132.76961 -247.724422)
					(mid 132.13969 -247.724422)
					(end 132.76961 -247.724422)
				)
			)
		)
	)
	(zone
		(layers "B.Cu" "In6.Cu" "In11.Cu" "In13.Cu" "In15.Cu")
		(hatch none 0.5)
		(connect_pads
			(clearance 0)
		)
		(min_thickness 0.25)
		(keepout
			(tracks not_allowed)
			(vias allowed)
			(pads allowed)
			(copperpour not_allowed)
			(footprints allowed)
		)
		(placement
			(enabled no)
			(sheetname "")
		)
		(fill yes
			(thermal_gap 0.5)
			(thermal_bridge_width 0.5)
			(island_removal_mode 0)
		)
		(polygon
			(pts
				(arc
					(start 37.129974 -304.435256)
					(mid 36.461954 -304.435256)
					(end 37.129974 -304.435256)
				)
			)
		)
	)
	(zone
		(layers "B.Cu" "In6.Cu" "In11.Cu" "In13.Cu" "In15.Cu")
		(hatch none 0.5)
		(connect_pads
			(clearance 0)
		)
		(min_thickness 0.25)
		(keepout
			(tracks not_allowed)
			(vias allowed)
			(pads allowed)
			(copperpour not_allowed)
			(footprints allowed)
		)
		(placement
			(enabled no)
			(sheetname "")
		)
		(fill yes
			(thermal_gap 0.5)
			(thermal_bridge_width 0.5)
			(island_removal_mode 0)
		)
		(polygon
			(pts
				(arc
					(start 439.434224 -242.385088)
					(mid 438.766204 -242.385088)
					(end 439.434224 -242.385088)
				)
			)
		)
	)
	(zone
		(layers "B.Cu" "In6.Cu" "In11.Cu" "In13.Cu" "In15.Cu")
		(hatch none 0.5)
		(connect_pads
			(clearance 0)
		)
		(min_thickness 0.25)
		(keepout
			(tracks not_allowed)
			(vias allowed)
			(pads allowed)
			(copperpour not_allowed)
			(footprints allowed)
		)
		(placement
			(enabled no)
			(sheetname "")
		)
		(fill yes
			(thermal_gap 0.5)
			(thermal_bridge_width 0.5)
			(island_removal_mode 0)
		)
		(polygon
			(pts
				(arc
					(start 381.479806 -270.846042)
					(mid 380.849886 -270.846042)
					(end 381.479806 -270.846042)
				)
			)
		)
	)
	(zone
		(layers "B.Cu" "In6.Cu" "In11.Cu" "In13.Cu" "In15.Cu")
		(hatch none 0.5)
		(connect_pads
			(clearance 0)
		)
		(min_thickness 0.25)
		(keepout
			(tracks not_allowed)
			(vias allowed)
			(pads allowed)
			(copperpour not_allowed)
			(footprints allowed)
		)
		(placement
			(enabled no)
			(sheetname "")
		)
		(fill yes
			(thermal_gap 0.5)
			(thermal_bridge_width 0.5)
			(island_removal_mode 0)
		)
		(polygon
			(pts
				(arc
					(start 377.354592 -412.84652)
					(mid 376.686572 -412.84652)
					(end 377.354592 -412.84652)
				)
			)
		)
	)
	(zone
		(layers "B.Cu" "In6.Cu" "In11.Cu" "In13.Cu" "In15.Cu")
		(hatch none 0.5)
		(connect_pads
			(clearance 0)
		)
		(min_thickness 0.25)
		(keepout
			(tracks not_allowed)
			(vias allowed)
			(pads allowed)
			(copperpour not_allowed)
			(footprints allowed)
		)
		(placement
			(enabled no)
			(sheetname "")
		)
		(fill yes
			(thermal_gap 0.5)
			(thermal_bridge_width 0.5)
			(island_removal_mode 0)
		)
		(polygon
			(pts
				(arc
					(start 381.009906 -281.37612)
					(mid 380.379986 -281.37612)
					(end 381.009906 -281.37612)
				)
			)
		)
	)
	(zone
		(layers "B.Cu" "In6.Cu" "In11.Cu" "In13.Cu" "In15.Cu")
		(hatch none 0.5)
		(connect_pads
			(clearance 0)
		)
		(min_thickness 0.25)
		(keepout
			(tracks not_allowed)
			(vias allowed)
			(pads allowed)
			(copperpour not_allowed)
			(footprints allowed)
		)
		(placement
			(enabled no)
			(sheetname "")
		)
		(fill yes
			(thermal_gap 0.5)
			(thermal_bridge_width 0.5)
			(island_removal_mode 0)
		)
		(polygon
			(pts
				(arc
					(start 37.129974 -273.835368)
					(mid 36.461954 -273.835368)
					(end 37.129974 -273.835368)
				)
			)
		)
	)
	(zone
		(layers "B.Cu" "In6.Cu" "In11.Cu" "In13.Cu" "In15.Cu")
		(hatch none 0.5)
		(connect_pads
			(clearance 0)
		)
		(min_thickness 0.25)
		(keepout
			(tracks not_allowed)
			(vias allowed)
			(pads allowed)
			(copperpour not_allowed)
			(footprints allowed)
		)
		(placement
			(enabled no)
			(sheetname "")
		)
		(fill yes
			(thermal_gap 0.5)
			(thermal_bridge_width 0.5)
			(island_removal_mode 0)
		)
		(polygon
			(pts
				(arc
					(start 191.494156 -313.78525)
					(mid 190.826136 -313.78525)
					(end 191.494156 -313.78525)
				)
			)
		)
	)
	(zone
		(layers "B.Cu" "In6.Cu" "In11.Cu" "In13.Cu" "In15.Cu")
		(hatch none 0.5)
		(connect_pads
			(clearance 0)
		)
		(min_thickness 0.25)
		(keepout
			(tracks not_allowed)
			(vias allowed)
			(pads allowed)
			(copperpour not_allowed)
			(footprints allowed)
		)
		(placement
			(enabled no)
			(sheetname "")
		)
		(fill yes
			(thermal_gap 0.5)
			(thermal_bridge_width 0.5)
			(island_removal_mode 0)
		)
		(polygon
			(pts
				(arc
					(start 280.969974 -284.034992)
					(mid 280.301954 -284.034992)
					(end 280.969974 -284.034992)
				)
			)
		)
	)
	(zone
		(layers "B.Cu" "In6.Cu" "In11.Cu" "In13.Cu" "In15.Cu")
		(hatch none 0.5)
		(connect_pads
			(clearance 0)
		)
		(min_thickness 0.25)
		(keepout
			(tracks not_allowed)
			(vias allowed)
			(pads allowed)
			(copperpour not_allowed)
			(footprints allowed)
		)
		(placement
			(enabled no)
			(sheetname "")
		)
		(fill yes
			(thermal_gap 0.5)
			(thermal_bridge_width 0.5)
			(island_removal_mode 0)
		)
		(polygon
			(pts
				(arc
					(start 125.249686 -229.90429)
					(mid 124.619766 -229.90429)
					(end 125.249686 -229.90429)
				)
			)
		)
	)
	(zone
		(layers "B.Cu" "In6.Cu" "In11.Cu" "In13.Cu" "In15.Cu")
		(hatch none 0.5)
		(connect_pads
			(clearance 0)
		)
		(min_thickness 0.25)
		(keepout
			(tracks not_allowed)
			(vias allowed)
			(pads allowed)
			(copperpour not_allowed)
			(footprints allowed)
		)
		(placement
			(enabled no)
			(sheetname "")
		)
		(fill yes
			(thermal_gap 0.5)
			(thermal_bridge_width 0.5)
			(island_removal_mode 0)
		)
		(polygon
			(pts
				(arc
					(start 416.933888 -397.156432)
					(mid 416.303968 -397.156432)
					(end 416.933888 -397.156432)
				)
			)
		)
	)
	(zone
		(layers "B.Cu" "In6.Cu" "In11.Cu" "In13.Cu" "In15.Cu")
		(hatch none 0.5)
		(connect_pads
			(clearance 0)
		)
		(min_thickness 0.25)
		(keepout
			(tracks not_allowed)
			(vias allowed)
			(pads allowed)
			(copperpour not_allowed)
			(footprints allowed)
		)
		(placement
			(enabled no)
			(sheetname "")
		)
		(fill yes
			(thermal_gap 0.5)
			(thermal_bridge_width 0.5)
			(island_removal_mode 0)
		)
		(polygon
			(pts
				(arc
					(start 91.41587 -255.824482)
					(mid 90.78595 -255.824482)
					(end 91.41587 -255.824482)
				)
			)
		)
	)
	(zone
		(layers "B.Cu" "In6.Cu" "In11.Cu" "In13.Cu" "In15.Cu")
		(hatch none 0.5)
		(connect_pads
			(clearance 0)
		)
		(min_thickness 0.25)
		(keepout
			(tracks not_allowed)
			(vias allowed)
			(pads allowed)
			(copperpour not_allowed)
			(footprints allowed)
		)
		(placement
			(enabled no)
			(sheetname "")
		)
		(fill yes
			(thermal_gap 0.5)
			(thermal_bridge_width 0.5)
			(island_removal_mode 0)
		)
		(polygon
			(pts
				(arc
					(start 106.455972 -231.524302)
					(mid 105.826052 -231.524302)
					(end 106.455972 -231.524302)
				)
			)
		)
	)
	(zone
		(layers "B.Cu" "In6.Cu" "In11.Cu" "In13.Cu" "In15.Cu")
		(hatch none 0.5)
		(connect_pads
			(clearance 0)
		)
		(min_thickness 0.25)
		(keepout
			(tracks not_allowed)
			(vias allowed)
			(pads allowed)
			(copperpour not_allowed)
			(footprints allowed)
		)
		(placement
			(enabled no)
			(sheetname "")
		)
		(fill yes
			(thermal_gap 0.5)
			(thermal_bridge_width 0.5)
			(island_removal_mode 0)
		)
		(polygon
			(pts
				(arc
					(start 33.029906 -274.685252)
					(mid 32.361886 -274.685252)
					(end 33.029906 -274.685252)
				)
			)
		)
	)
	(zone
		(layers "B.Cu" "In6.Cu" "In11.Cu" "In13.Cu" "In15.Cu")
		(hatch none 0.5)
		(connect_pads
			(clearance 0)
		)
		(min_thickness 0.25)
		(keepout
			(tracks not_allowed)
			(vias allowed)
			(pads allowed)
			(copperpour not_allowed)
			(footprints allowed)
		)
		(placement
			(enabled no)
			(sheetname "")
		)
		(fill yes
			(thermal_gap 0.5)
			(thermal_bridge_width 0.5)
			(island_removal_mode 0)
		)
		(polygon
			(pts
				(arc
					(start 285.070042 -238.985044)
					(mid 284.402022 -238.985044)
					(end 285.070042 -238.985044)
				)
			)
		)
	)
	(zone
		(layers "B.Cu" "In6.Cu" "In11.Cu" "In13.Cu" "In15.Cu")
		(hatch none 0.5)
		(connect_pads
			(clearance 0)
		)
		(min_thickness 0.25)
		(keepout
			(tracks not_allowed)
			(vias allowed)
			(pads allowed)
			(copperpour not_allowed)
			(footprints allowed)
		)
		(placement
			(enabled no)
			(sheetname "")
		)
		(fill yes
			(thermal_gap 0.5)
			(thermal_bridge_width 0.5)
			(island_removal_mode 0)
		)
		(polygon
			(pts
				(arc
					(start 163.333938 -388.774432)
					(mid 162.704018 -388.774432)
					(end 163.333938 -388.774432)
				)
			)
		)
	)
	(zone
		(layers "B.Cu" "In6.Cu" "In11.Cu" "In13.Cu" "In15.Cu")
		(hatch none 0.5)
		(connect_pads
			(clearance 0)
		)
		(min_thickness 0.25)
		(keepout
			(tracks not_allowed)
			(vias allowed)
			(pads allowed)
			(copperpour not_allowed)
			(footprints allowed)
		)
		(placement
			(enabled no)
			(sheetname "")
		)
		(fill yes
			(thermal_gap 0.5)
			(thermal_bridge_width 0.5)
			(island_removal_mode 0)
		)
		(polygon
			(pts
				(arc
					(start 90.94597 -243.674392)
					(mid 90.31605 -243.674392)
					(end 90.94597 -243.674392)
				)
			)
		)
	)
	(zone
		(layers "B.Cu" "In6.Cu" "In11.Cu" "In13.Cu" "In15.Cu")
		(hatch none 0.5)
		(connect_pads
			(clearance 0)
		)
		(min_thickness 0.25)
		(keepout
			(tracks not_allowed)
			(vias allowed)
			(pads allowed)
			(copperpour not_allowed)
			(footprints allowed)
		)
		(placement
			(enabled no)
			(sheetname "")
		)
		(fill yes
			(thermal_gap 0.5)
			(thermal_bridge_width 0.5)
			(island_removal_mode 0)
		)
		(polygon
			(pts
				(arc
					(start 33.029906 -305.285394)
					(mid 32.361886 -305.285394)
					(end 33.029906 -305.285394)
				)
			)
		)
	)
	(zone
		(layers "B.Cu" "In6.Cu" "In11.Cu" "In13.Cu" "In15.Cu")
		(hatch none 0.5)
		(connect_pads
			(clearance 0)
		)
		(min_thickness 0.25)
		(keepout
			(tracks not_allowed)
			(vias allowed)
			(pads allowed)
			(copperpour not_allowed)
			(footprints allowed)
		)
		(placement
			(enabled no)
			(sheetname "")
		)
		(fill yes
			(thermal_gap 0.5)
			(thermal_bridge_width 0.5)
			(island_removal_mode 0)
		)
		(polygon
			(pts
				(arc
					(start 360.139234 -388.742428)
					(mid 359.471214 -388.742428)
					(end 360.139234 -388.742428)
				)
			)
		)
	)
	(zone
		(layers "B.Cu" "In6.Cu" "In11.Cu" "In13.Cu" "In15.Cu")
		(hatch none 0.5)
		(connect_pads
			(clearance 0)
		)
		(min_thickness 0.25)
		(keepout
			(tracks not_allowed)
			(vias allowed)
			(pads allowed)
			(copperpour not_allowed)
			(footprints allowed)
		)
		(placement
			(enabled no)
			(sheetname "")
		)
		(fill yes
			(thermal_gap 0.5)
			(thermal_bridge_width 0.5)
			(island_removal_mode 0)
		)
		(polygon
			(pts
				(arc
					(start 362.679742 -287.045908)
					(mid 362.049822 -287.045908)
					(end 362.679742 -287.045908)
				)
			)
		)
	)
	(zone
		(layers "B.Cu" "In6.Cu" "In11.Cu" "In13.Cu" "In15.Cu")
		(hatch none 0.5)
		(connect_pads
			(clearance 0)
		)
		(min_thickness 0.25)
		(keepout
			(tracks not_allowed)
			(vias allowed)
			(pads allowed)
			(copperpour not_allowed)
			(footprints allowed)
		)
		(placement
			(enabled no)
			(sheetname "")
		)
		(fill yes
			(thermal_gap 0.5)
			(thermal_bridge_width 0.5)
			(island_removal_mode 0)
		)
		(polygon
			(pts
				(arc
					(start 187.394088 -215.185244)
					(mid 186.726068 -215.185244)
					(end 187.394088 -215.185244)
				)
			)
		)
	)
	(zone
		(layers "B.Cu" "In6.Cu" "In11.Cu" "In13.Cu" "In15.Cu")
		(hatch none 0.5)
		(connect_pads
			(clearance 0)
		)
		(min_thickness 0.25)
		(keepout
			(tracks not_allowed)
			(vias allowed)
			(pads allowed)
			(copperpour not_allowed)
			(footprints allowed)
		)
		(placement
			(enabled no)
			(sheetname "")
		)
		(fill yes
			(thermal_gap 0.5)
			(thermal_bridge_width 0.5)
			(island_removal_mode 0)
		)
		(polygon
			(pts
				(arc
					(start 93.126052 -287.046162)
					(mid 92.496132 -287.046162)
					(end 93.126052 -287.046162)
				)
			)
		)
	)
	(zone
		(layers "B.Cu" "In6.Cu" "In11.Cu" "In13.Cu" "In15.Cu")
		(hatch none 0.5)
		(connect_pads
			(clearance 0)
		)
		(min_thickness 0.25)
		(keepout
			(tracks not_allowed)
			(vias allowed)
			(pads allowed)
			(copperpour not_allowed)
			(footprints allowed)
		)
		(placement
			(enabled no)
			(sheetname "")
		)
		(fill yes
			(thermal_gap 0.5)
			(thermal_bridge_width 0.5)
			(island_removal_mode 0)
		)
		(polygon
			(pts
				(arc
					(start 439.434224 -210.085178)
					(mid 438.766204 -210.085178)
					(end 439.434224 -210.085178)
				)
			)
		)
	)
	(zone
		(layers "B.Cu" "In6.Cu" "In11.Cu" "In13.Cu" "In15.Cu")
		(hatch none 0.5)
		(connect_pads
			(clearance 0)
		)
		(min_thickness 0.25)
		(keepout
			(tracks not_allowed)
			(vias allowed)
			(pads allowed)
			(copperpour not_allowed)
			(footprints allowed)
		)
		(placement
			(enabled no)
			(sheetname "")
		)
		(fill yes
			(thermal_gap 0.5)
			(thermal_bridge_width 0.5)
			(island_removal_mode 0)
		)
		(polygon
			(pts
				(arc
					(start 285.070042 -304.435002)
					(mid 284.402022 -304.435002)
					(end 285.070042 -304.435002)
				)
			)
		)
	)
	(zone
		(layers "B.Cu" "In6.Cu" "In11.Cu" "In13.Cu" "In15.Cu")
		(hatch none 0.5)
		(connect_pads
			(clearance 0)
		)
		(min_thickness 0.25)
		(keepout
			(tracks not_allowed)
			(vias allowed)
			(pads allowed)
			(copperpour not_allowed)
			(footprints allowed)
		)
		(placement
			(enabled no)
			(sheetname "")
		)
		(fill yes
			(thermal_gap 0.5)
			(thermal_bridge_width 0.5)
			(island_removal_mode 0)
		)
		(polygon
			(pts
				(arc
					(start 374.429782 -291.095938)
					(mid 373.799862 -291.095938)
					(end 374.429782 -291.095938)
				)
			)
		)
	)
	(zone
		(layers "B.Cu" "In6.Cu" "In11.Cu" "In13.Cu" "In15.Cu")
		(hatch none 0.5)
		(connect_pads
			(clearance 0)
		)
		(min_thickness 0.25)
		(keepout
			(tracks not_allowed)
			(vias allowed)
			(pads allowed)
			(copperpour not_allowed)
			(footprints allowed)
		)
		(placement
			(enabled no)
			(sheetname "")
		)
		(fill yes
			(thermal_gap 0.5)
			(thermal_bridge_width 0.5)
			(island_removal_mode 0)
		)
		(polygon
			(pts
				(arc
					(start 439.434224 -203.28509)
					(mid 438.766204 -203.28509)
					(end 439.434224 -203.28509)
				)
			)
		)
	)
	(zone
		(layers "B.Cu" "In6.Cu" "In11.Cu" "In13.Cu" "In15.Cu")
		(hatch none 0.5)
		(connect_pads
			(clearance 0)
		)
		(min_thickness 0.25)
		(keepout
			(tracks not_allowed)
			(vias allowed)
			(pads allowed)
			(copperpour not_allowed)
			(footprints allowed)
		)
		(placement
			(enabled no)
			(sheetname "")
		)
		(fill yes
			(thermal_gap 0.5)
			(thermal_bridge_width 0.5)
			(island_removal_mode 0)
		)
		(polygon
			(pts
				(arc
					(start 349.696024 -229.904036)
					(mid 349.066104 -229.904036)
					(end 349.696024 -229.904036)
				)
			)
		)
	)
	(zone
		(layers "B.Cu" "In6.Cu" "In11.Cu" "In13.Cu" "In15.Cu")
		(hatch none 0.5)
		(connect_pads
			(clearance 0)
		)
		(min_thickness 0.25)
		(keepout
			(tracks not_allowed)
			(vias allowed)
			(pads allowed)
			(copperpour not_allowed)
			(footprints allowed)
		)
		(placement
			(enabled no)
			(sheetname "")
		)
		(fill yes
			(thermal_gap 0.5)
			(thermal_bridge_width 0.5)
			(island_removal_mode 0)
		)
		(polygon
			(pts
				(arc
					(start 191.494156 -315.485272)
					(mid 190.826136 -315.485272)
					(end 191.494156 -315.485272)
				)
			)
		)
	)
	(zone
		(layers "B.Cu" "In6.Cu" "In11.Cu" "In13.Cu" "In15.Cu")
		(hatch none 0.5)
		(connect_pads
			(clearance 0)
		)
		(min_thickness 0.25)
		(keepout
			(tracks not_allowed)
			(vias allowed)
			(pads allowed)
			(copperpour not_allowed)
			(footprints allowed)
		)
		(placement
			(enabled no)
			(sheetname "")
		)
		(fill yes
			(thermal_gap 0.5)
			(thermal_bridge_width 0.5)
			(island_removal_mode 0)
		)
		(polygon
			(pts
				(arc
					(start 420.93388 -397.849344)
					(mid 420.30396 -397.849344)
					(end 420.93388 -397.849344)
				)
			)
		)
	)
	(zone
		(layers "B.Cu" "In6.Cu" "In11.Cu" "In13.Cu" "In15.Cu")
		(hatch none 0.5)
		(connect_pads
			(clearance 0)
		)
		(min_thickness 0.25)
		(keepout
			(tracks not_allowed)
			(vias allowed)
			(pads allowed)
			(copperpour not_allowed)
			(footprints allowed)
		)
		(placement
			(enabled no)
			(sheetname "")
		)
		(fill yes
			(thermal_gap 0.5)
			(thermal_bridge_width 0.5)
			(island_removal_mode 0)
		)
		(polygon
			(pts
				(arc
					(start 352.81616 -289.475926)
					(mid 352.18624 -289.475926)
					(end 352.81616 -289.475926)
				)
			)
		)
	)
	(zone
		(layers "B.Cu" "In6.Cu" "In11.Cu" "In13.Cu" "In15.Cu")
		(hatch none 0.5)
		(connect_pads
			(clearance 0)
		)
		(min_thickness 0.25)
		(keepout
			(tracks not_allowed)
			(vias allowed)
			(pads allowed)
			(copperpour not_allowed)
			(footprints allowed)
		)
		(placement
			(enabled no)
			(sheetname "")
		)
		(fill yes
			(thermal_gap 0.5)
			(thermal_bridge_width 0.5)
			(island_removal_mode 0)
		)
		(polygon
			(pts
				(arc
					(start 439.434224 -236.435138)
					(mid 438.766204 -236.435138)
					(end 439.434224 -236.435138)
				)
			)
		)
	)
	(zone
		(layers "B.Cu" "In6.Cu" "In11.Cu" "In13.Cu" "In15.Cu")
		(hatch none 0.5)
		(connect_pads
			(clearance 0)
		)
		(min_thickness 0.25)
		(keepout
			(tracks not_allowed)
			(vias allowed)
			(pads allowed)
			(copperpour not_allowed)
			(footprints allowed)
		)
		(placement
			(enabled no)
			(sheetname "")
		)
		(fill yes
			(thermal_gap 0.5)
			(thermal_bridge_width 0.5)
			(island_removal_mode 0)
		)
		(polygon
			(pts
				(arc
					(start 133.069838 -284.616398)
					(mid 132.439918 -284.616398)
					(end 133.069838 -284.616398)
				)
			)
		)
	)
	(zone
		(layers "B.Cu" "In6.Cu" "In11.Cu" "In13.Cu" "In15.Cu")
		(hatch none 0.5)
		(connect_pads
			(clearance 0)
		)
		(min_thickness 0.25)
		(keepout
			(tracks not_allowed)
			(vias allowed)
			(pads allowed)
			(copperpour not_allowed)
			(footprints allowed)
		)
		(placement
			(enabled no)
			(sheetname "")
		)
		(fill yes
			(thermal_gap 0.5)
			(thermal_bridge_width 0.5)
			(island_removal_mode 0)
		)
		(polygon
			(pts
				(arc
					(start 435.334156 -244.934994)
					(mid 434.666136 -244.934994)
					(end 435.334156 -244.934994)
				)
			)
		)
	)
	(zone
		(layers "B.Cu" "In6.Cu" "In11.Cu" "In13.Cu" "In15.Cu")
		(hatch none 0.5)
		(connect_pads
			(clearance 0)
		)
		(min_thickness 0.25)
		(keepout
			(tracks not_allowed)
			(vias allowed)
			(pads allowed)
			(copperpour not_allowed)
			(footprints allowed)
		)
		(placement
			(enabled no)
			(sheetname "")
		)
		(fill yes
			(thermal_gap 0.5)
			(thermal_bridge_width 0.5)
			(island_removal_mode 0)
		)
		(polygon
			(pts
				(arc
					(start 338.886038 -230.714296)
					(mid 338.256118 -230.714296)
					(end 338.886038 -230.714296)
				)
			)
		)
	)
	(zone
		(layers "B.Cu" "In6.Cu" "In11.Cu" "In13.Cu" "In15.Cu")
		(hatch none 0.5)
		(connect_pads
			(clearance 0)
		)
		(min_thickness 0.25)
		(keepout
			(tracks not_allowed)
			(vias allowed)
			(pads allowed)
			(copperpour not_allowed)
			(footprints allowed)
		)
		(placement
			(enabled no)
			(sheetname "")
		)
		(fill yes
			(thermal_gap 0.5)
			(thermal_bridge_width 0.5)
			(island_removal_mode 0)
		)
		(polygon
			(pts
				(arc
					(start 53.13807 -4.963414)
					(mid 52.47005 -4.963414)
					(end 53.13807 -4.963414)
				)
			)
		)
	)
	(zone
		(layers "B.Cu" "In6.Cu" "In11.Cu" "In13.Cu" "In15.Cu")
		(hatch none 0.5)
		(connect_pads
			(clearance 0)
		)
		(min_thickness 0.25)
		(keepout
			(tracks not_allowed)
			(vias allowed)
			(pads allowed)
			(copperpour not_allowed)
			(footprints allowed)
		)
		(placement
			(enabled no)
			(sheetname "")
		)
		(fill yes
			(thermal_gap 0.5)
			(thermal_bridge_width 0.5)
			(island_removal_mode 0)
		)
		(polygon
			(pts
				(arc
					(start 435.334156 -201.585068)
					(mid 434.666136 -201.585068)
					(end 435.334156 -201.585068)
				)
			)
		)
	)
	(zone
		(layers "B.Cu" "In6.Cu" "In11.Cu" "In13.Cu" "In15.Cu")
		(hatch none 0.5)
		(connect_pads
			(clearance 0)
		)
		(min_thickness 0.25)
		(keepout
			(tracks not_allowed)
			(vias allowed)
			(pads allowed)
			(copperpour not_allowed)
			(footprints allowed)
		)
		(placement
			(enabled no)
			(sheetname "")
		)
		(fill yes
			(thermal_gap 0.5)
			(thermal_bridge_width 0.5)
			(island_removal_mode 0)
		)
		(polygon
			(pts
				(arc
					(start 131.82981 -233.144314)
					(mid 131.19989 -233.144314)
					(end 131.82981 -233.144314)
				)
			)
		)
	)
	(zone
		(layers "B.Cu" "In6.Cu" "In11.Cu" "In13.Cu" "In15.Cu")
		(hatch none 0.5)
		(connect_pads
			(clearance 0)
		)
		(min_thickness 0.25)
		(keepout
			(tracks not_allowed)
			(vias allowed)
			(pads allowed)
			(copperpour not_allowed)
			(footprints allowed)
		)
		(placement
			(enabled no)
			(sheetname "")
		)
		(fill yes
			(thermal_gap 0.5)
			(thermal_bridge_width 0.5)
			(island_removal_mode 0)
		)
		(polygon
			(pts
				(arc
					(start 118.291356 -404.46452)
					(mid 117.623336 -404.46452)
					(end 118.291356 -404.46452)
				)
			)
		)
	)
	(zone
		(layers "B.Cu" "In6.Cu" "In11.Cu" "In13.Cu" "In15.Cu")
		(hatch none 0.5)
		(connect_pads
			(clearance 0)
		)
		(min_thickness 0.25)
		(keepout
			(tracks not_allowed)
			(vias allowed)
			(pads allowed)
			(copperpour not_allowed)
			(footprints allowed)
		)
		(placement
			(enabled no)
			(sheetname "")
		)
		(fill yes
			(thermal_gap 0.5)
			(thermal_bridge_width 0.5)
			(island_removal_mode 0)
		)
		(polygon
			(pts
				(arc
					(start 37.129974 -272.135346)
					(mid 36.461954 -272.135346)
					(end 37.129974 -272.135346)
				)
			)
		)
	)
	(zone
		(layers "B.Cu" "In6.Cu" "In11.Cu" "In13.Cu" "In15.Cu")
		(hatch none 0.5)
		(connect_pads
			(clearance 0)
		)
		(min_thickness 0.25)
		(keepout
			(tracks not_allowed)
			(vias allowed)
			(pads allowed)
			(copperpour not_allowed)
			(footprints allowed)
		)
		(placement
			(enabled no)
			(sheetname "")
		)
		(fill yes
			(thermal_gap 0.5)
			(thermal_bridge_width 0.5)
			(island_removal_mode 0)
		)
		(polygon
			(pts
				(arc
					(start 435.334156 -211.784946)
					(mid 434.666136 -211.784946)
					(end 435.334156 -211.784946)
				)
			)
		)
	)
	(zone
		(layers "B.Cu" "In6.Cu" "In11.Cu" "In13.Cu" "In15.Cu")
		(hatch none 0.5)
		(connect_pads
			(clearance 0)
		)
		(min_thickness 0.25)
		(keepout
			(tracks not_allowed)
			(vias allowed)
			(pads allowed)
			(copperpour not_allowed)
			(footprints allowed)
		)
		(placement
			(enabled no)
			(sheetname "")
		)
		(fill yes
			(thermal_gap 0.5)
			(thermal_bridge_width 0.5)
			(island_removal_mode 0)
		)
		(polygon
			(pts
				(arc
					(start 346.236036 -289.475926)
					(mid 345.606116 -289.475926)
					(end 346.236036 -289.475926)
				)
			)
		)
	)
	(zone
		(layers "B.Cu" "In6.Cu" "In11.Cu" "In13.Cu" "In15.Cu")
		(hatch none 0.5)
		(connect_pads
			(clearance 0)
		)
		(min_thickness 0.25)
		(keepout
			(tracks not_allowed)
			(vias allowed)
			(pads allowed)
			(copperpour not_allowed)
			(footprints allowed)
		)
		(placement
			(enabled no)
			(sheetname "")
		)
		(fill yes
			(thermal_gap 0.5)
			(thermal_bridge_width 0.5)
			(island_removal_mode 0)
		)
		(polygon
			(pts
				(arc
					(start 439.434224 -266.185142)
					(mid 438.766204 -266.185142)
					(end 439.434224 -266.185142)
				)
			)
		)
	)
	(zone
		(layers "B.Cu" "In6.Cu" "In11.Cu" "In13.Cu" "In15.Cu")
		(hatch none 0.5)
		(connect_pads
			(clearance 0)
		)
		(min_thickness 0.25)
		(keepout
			(tracks not_allowed)
			(vias allowed)
			(pads allowed)
			(copperpour not_allowed)
			(footprints allowed)
		)
		(placement
			(enabled no)
			(sheetname "")
		)
		(fill yes
			(thermal_gap 0.5)
			(thermal_bridge_width 0.5)
			(island_removal_mode 0)
		)
		(polygon
			(pts
				(arc
					(start 133.239764 -240.434368)
					(mid 132.609844 -240.434368)
					(end 133.239764 -240.434368)
				)
			)
		)
	)
	(zone
		(layers "B.Cu" "In6.Cu" "In11.Cu" "In13.Cu" "In15.Cu")
		(hatch none 0.5)
		(connect_pads
			(clearance 0)
		)
		(min_thickness 0.25)
		(keepout
			(tracks not_allowed)
			(vias allowed)
			(pads allowed)
			(copperpour not_allowed)
			(footprints allowed)
		)
		(placement
			(enabled no)
			(sheetname "")
		)
		(fill yes
			(thermal_gap 0.5)
			(thermal_bridge_width 0.5)
			(island_removal_mode 0)
		)
		(polygon
			(pts
				(arc
					(start 119.90959 -289.47618)
					(mid 119.27967 -289.47618)
					(end 119.90959 -289.47618)
				)
			)
		)
	)
	(zone
		(layers "B.Cu" "In6.Cu" "In11.Cu" "In13.Cu" "In15.Cu")
		(hatch none 0.5)
		(connect_pads
			(clearance 0)
		)
		(min_thickness 0.25)
		(keepout
			(tracks not_allowed)
			(vias allowed)
			(pads allowed)
			(copperpour not_allowed)
			(footprints allowed)
		)
		(placement
			(enabled no)
			(sheetname "")
		)
		(fill yes
			(thermal_gap 0.5)
			(thermal_bridge_width 0.5)
			(island_removal_mode 0)
		)
		(polygon
			(pts
				(arc
					(start 75.876912 -371.49913)
					(mid 75.208892 -371.49913)
					(end 75.876912 -371.49913)
				)
			)
		)
	)
	(zone
		(layers "B.Cu" "In6.Cu" "In11.Cu" "In13.Cu" "In15.Cu")
		(hatch none 0.5)
		(connect_pads
			(clearance 0)
		)
		(min_thickness 0.25)
		(keepout
			(tracks not_allowed)
			(vias allowed)
			(pads allowed)
			(copperpour not_allowed)
			(footprints allowed)
		)
		(placement
			(enabled no)
			(sheetname "")
		)
		(fill yes
			(thermal_gap 0.5)
			(thermal_bridge_width 0.5)
			(island_removal_mode 0)
		)
		(polygon
			(pts
				(arc
					(start 354.696014 -291.095938)
					(mid 354.066094 -291.095938)
					(end 354.696014 -291.095938)
				)
			)
		)
	)
	(zone
		(layers "B.Cu" "In6.Cu" "In11.Cu" "In13.Cu" "In15.Cu")
		(hatch none 0.5)
		(connect_pads
			(clearance 0)
		)
		(min_thickness 0.25)
		(keepout
			(tracks not_allowed)
			(vias allowed)
			(pads allowed)
			(copperpour not_allowed)
			(footprints allowed)
		)
		(placement
			(enabled no)
			(sheetname "")
		)
		(fill yes
			(thermal_gap 0.5)
			(thermal_bridge_width 0.5)
			(island_removal_mode 0)
		)
		(polygon
			(pts
				(arc
					(start 143.660876 -404.46452)
					(mid 142.992856 -404.46452)
					(end 143.660876 -404.46452)
				)
			)
		)
	)
	(zone
		(layers "B.Cu" "In6.Cu" "In11.Cu" "In13.Cu" "In15.Cu")
		(hatch none 0.5)
		(connect_pads
			(clearance 0)
		)
		(min_thickness 0.25)
		(keepout
			(tracks not_allowed)
			(vias allowed)
			(pads allowed)
			(copperpour not_allowed)
			(footprints allowed)
		)
		(placement
			(enabled no)
			(sheetname "")
		)
		(fill yes
			(thermal_gap 0.5)
			(thermal_bridge_width 0.5)
			(island_removal_mode 0)
		)
		(polygon
			(pts
				(arc
					(start 33.029906 -235.585254)
					(mid 32.361886 -235.585254)
					(end 33.029906 -235.585254)
				)
			)
		)
	)
	(zone
		(layers "B.Cu" "In6.Cu" "In11.Cu" "In13.Cu" "In15.Cu")
		(hatch none 0.5)
		(connect_pads
			(clearance 0)
		)
		(min_thickness 0.25)
		(keepout
			(tracks not_allowed)
			(vias allowed)
			(pads allowed)
			(copperpour not_allowed)
			(footprints allowed)
		)
		(placement
			(enabled no)
			(sheetname "")
		)
		(fill yes
			(thermal_gap 0.5)
			(thermal_bridge_width 0.5)
			(island_removal_mode 0)
		)
		(polygon
			(pts
				(arc
					(start 90.94597 -240.434368)
					(mid 90.31605 -240.434368)
					(end 90.94597 -240.434368)
				)
			)
		)
	)
	(zone
		(layers "B.Cu" "In6.Cu" "In11.Cu" "In13.Cu" "In15.Cu")
		(hatch none 0.5)
		(connect_pads
			(clearance 0)
		)
		(min_thickness 0.25)
		(keepout
			(tracks not_allowed)
			(vias allowed)
			(pads allowed)
			(copperpour not_allowed)
			(footprints allowed)
		)
		(placement
			(enabled no)
			(sheetname "")
		)
		(fill yes
			(thermal_gap 0.5)
			(thermal_bridge_width 0.5)
			(island_removal_mode 0)
		)
		(polygon
			(pts
				(arc
					(start 321.305936 -397.849344)
					(mid 320.676016 -397.849344)
					(end 321.305936 -397.849344)
				)
			)
		)
	)
	(zone
		(layers "B.Cu" "In6.Cu" "In11.Cu" "In13.Cu" "In15.Cu")
		(hatch none 0.5)
		(connect_pads
			(clearance 0)
		)
		(min_thickness 0.25)
		(keepout
			(tracks not_allowed)
			(vias allowed)
			(pads allowed)
			(copperpour not_allowed)
			(footprints allowed)
		)
		(placement
			(enabled no)
			(sheetname "")
		)
		(fill yes
			(thermal_gap 0.5)
			(thermal_bridge_width 0.5)
			(island_removal_mode 0)
		)
		(polygon
			(pts
				(arc
					(start 340.595966 -287.856168)
					(mid 339.966046 -287.856168)
					(end 340.595966 -287.856168)
				)
			)
		)
	)
	(zone
		(layers "B.Cu" "In6.Cu" "In11.Cu" "In13.Cu" "In15.Cu")
		(hatch none 0.5)
		(connect_pads
			(clearance 0)
		)
		(min_thickness 0.25)
		(keepout
			(tracks not_allowed)
			(vias allowed)
			(pads allowed)
			(copperpour not_allowed)
			(footprints allowed)
		)
		(placement
			(enabled no)
			(sheetname "")
		)
		(fill yes
			(thermal_gap 0.5)
			(thermal_bridge_width 0.5)
			(island_removal_mode 0)
		)
		(polygon
			(pts
				(arc
					(start 125.54966 -287.856422)
					(mid 124.91974 -287.856422)
					(end 125.54966 -287.856422)
				)
			)
		)
	)
	(zone
		(layers "B.Cu" "In6.Cu" "In11.Cu" "In13.Cu" "In15.Cu")
		(hatch none 0.5)
		(connect_pads
			(clearance 0)
		)
		(min_thickness 0.25)
		(keepout
			(tracks not_allowed)
			(vias allowed)
			(pads allowed)
			(copperpour not_allowed)
			(footprints allowed)
		)
		(placement
			(enabled no)
			(sheetname "")
		)
		(fill yes
			(thermal_gap 0.5)
			(thermal_bridge_width 0.5)
			(island_removal_mode 0)
		)
		(polygon
			(pts
				(arc
					(start 374.129808 -236.384084)
					(mid 373.499888 -236.384084)
					(end 374.129808 -236.384084)
				)
			)
		)
	)
	(zone
		(layers "B.Cu" "In6.Cu" "In11.Cu" "In13.Cu" "In15.Cu")
		(hatch none 0.5)
		(connect_pads
			(clearance 0)
		)
		(min_thickness 0.25)
		(keepout
			(tracks not_allowed)
			(vias allowed)
			(pads allowed)
			(copperpour not_allowed)
			(footprints allowed)
		)
		(placement
			(enabled no)
			(sheetname "")
		)
		(fill yes
			(thermal_gap 0.5)
			(thermal_bridge_width 0.5)
			(island_removal_mode 0)
		)
		(polygon
			(pts
				(arc
					(start 131.82981 -231.524302)
					(mid 131.19989 -231.524302)
					(end 131.82981 -231.524302)
				)
			)
		)
	)
	(zone
		(layers "B.Cu" "In6.Cu" "In11.Cu" "In13.Cu" "In15.Cu")
		(hatch none 0.5)
		(connect_pads
			(clearance 0)
		)
		(min_thickness 0.25)
		(keepout
			(tracks not_allowed)
			(vias allowed)
			(pads allowed)
			(copperpour not_allowed)
			(footprints allowed)
		)
		(placement
			(enabled no)
			(sheetname "")
		)
		(fill yes
			(thermal_gap 0.5)
			(thermal_bridge_width 0.5)
			(island_removal_mode 0)
		)
		(polygon
			(pts
				(arc
					(start 187.394088 -312.085228)
					(mid 186.726068 -312.085228)
					(end 187.394088 -312.085228)
				)
			)
		)
	)
	(zone
		(layers "B.Cu" "In6.Cu" "In11.Cu" "In13.Cu" "In15.Cu")
		(hatch none 0.5)
		(connect_pads
			(clearance 0)
		)
		(min_thickness 0.25)
		(keepout
			(tracks not_allowed)
			(vias allowed)
			(pads allowed)
			(copperpour not_allowed)
			(footprints allowed)
		)
		(placement
			(enabled no)
			(sheetname "")
		)
		(fill yes
			(thermal_gap 0.5)
			(thermal_bridge_width 0.5)
			(island_removal_mode 0)
		)
		(polygon
			(pts
				(arc
					(start 332.560676 -412.84652)
					(mid 331.892656 -412.84652)
					(end 332.560676 -412.84652)
				)
			)
		)
	)
	(zone
		(layers "B.Cu" "In6.Cu" "In11.Cu" "In13.Cu" "In15.Cu")
		(hatch none 0.5)
		(connect_pads
			(clearance 0)
		)
		(min_thickness 0.25)
		(keepout
			(tracks not_allowed)
			(vias allowed)
			(pads allowed)
			(copperpour not_allowed)
			(footprints allowed)
		)
		(placement
			(enabled no)
			(sheetname "")
		)
		(fill yes
			(thermal_gap 0.5)
			(thermal_bridge_width 0.5)
			(island_removal_mode 0)
		)
		(polygon
			(pts
				(arc
					(start 310.10606 -397.156432)
					(mid 309.47614 -397.156432)
					(end 310.10606 -397.156432)
				)
			)
		)
	)
	(zone
		(layers "B.Cu" "In6.Cu" "In11.Cu" "In13.Cu" "In15.Cu")
		(hatch none 0.5)
		(connect_pads
			(clearance 0)
		)
		(min_thickness 0.25)
		(keepout
			(tracks not_allowed)
			(vias allowed)
			(pads allowed)
			(copperpour not_allowed)
			(footprints allowed)
		)
		(placement
			(enabled no)
			(sheetname "")
		)
		(fill yes
			(thermal_gap 0.5)
			(thermal_bridge_width 0.5)
			(island_removal_mode 0)
		)
		(polygon
			(pts
				(arc
					(start 379.599698 -290.285932)
					(mid 378.969778 -290.285932)
					(end 379.599698 -290.285932)
				)
			)
		)
	)
	(zone
		(layers "B.Cu" "In6.Cu" "In11.Cu" "In13.Cu" "In15.Cu")
		(hatch none 0.5)
		(connect_pads
			(clearance 0)
		)
		(min_thickness 0.25)
		(keepout
			(tracks not_allowed)
			(vias allowed)
			(pads allowed)
			(copperpour not_allowed)
			(footprints allowed)
		)
		(placement
			(enabled no)
			(sheetname "")
		)
		(fill yes
			(thermal_gap 0.5)
			(thermal_bridge_width 0.5)
			(island_removal_mode 0)
		)
		(polygon
			(pts
				(arc
					(start 346.236036 -287.856168)
					(mid 345.606116 -287.856168)
					(end 346.236036 -287.856168)
				)
			)
		)
	)
	(zone
		(layers "B.Cu" "In6.Cu" "In11.Cu" "In13.Cu" "In15.Cu")
		(hatch none 0.5)
		(connect_pads
			(clearance 0)
		)
		(min_thickness 0.25)
		(keepout
			(tracks not_allowed)
			(vias allowed)
			(pads allowed)
			(copperpour not_allowed)
			(footprints allowed)
		)
		(placement
			(enabled no)
			(sheetname "")
		)
		(fill yes
			(thermal_gap 0.5)
			(thermal_bridge_width 0.5)
			(island_removal_mode 0)
		)
		(polygon
			(pts
				(arc
					(start 396.597632 -412.84652)
					(mid 395.929612 -412.84652)
					(end 396.597632 -412.84652)
				)
			)
		)
	)
	(zone
		(layers "B.Cu" "In6.Cu" "In11.Cu" "In13.Cu" "In15.Cu")
		(hatch none 0.5)
		(connect_pads
			(clearance 0)
		)
		(min_thickness 0.25)
		(keepout
			(tracks not_allowed)
			(vias allowed)
			(pads allowed)
			(copperpour not_allowed)
			(footprints allowed)
		)
		(placement
			(enabled no)
			(sheetname "")
		)
		(fill yes
			(thermal_gap 0.5)
			(thermal_bridge_width 0.5)
			(island_removal_mode 0)
		)
		(polygon
			(pts
				(arc
					(start 280.969974 -286.585152)
					(mid 280.301954 -286.585152)
					(end 280.969974 -286.585152)
				)
			)
		)
	)
	(zone
		(layers "B.Cu" "In6.Cu" "In11.Cu" "In13.Cu" "In15.Cu")
		(hatch none 0.5)
		(connect_pads
			(clearance 0)
		)
		(min_thickness 0.25)
		(keepout
			(tracks not_allowed)
			(vias allowed)
			(pads allowed)
			(copperpour not_allowed)
			(footprints allowed)
		)
		(placement
			(enabled no)
			(sheetname "")
		)
		(fill yes
			(thermal_gap 0.5)
			(thermal_bridge_width 0.5)
			(island_removal_mode 0)
		)
		(polygon
			(pts
				(arc
					(start 340.295992 -236.384084)
					(mid 339.666072 -236.384084)
					(end 340.295992 -236.384084)
				)
			)
		)
	)
	(zone
		(layers "B.Cu" "In6.Cu" "In11.Cu" "In13.Cu" "In15.Cu")
		(hatch none 0.5)
		(connect_pads
			(clearance 0)
		)
		(min_thickness 0.25)
		(keepout
			(tracks not_allowed)
			(vias allowed)
			(pads allowed)
			(copperpour not_allowed)
			(footprints allowed)
		)
		(placement
			(enabled no)
			(sheetname "")
		)
		(fill yes
			(thermal_gap 0.5)
			(thermal_bridge_width 0.5)
			(island_removal_mode 0)
		)
		(polygon
			(pts
				(arc
					(start 410.9339 -397.156432)
					(mid 410.30398 -397.156432)
					(end 410.9339 -397.156432)
				)
			)
		)
	)
	(zone
		(layers "B.Cu" "In6.Cu" "In11.Cu" "In13.Cu" "In15.Cu")
		(hatch none 0.5)
		(connect_pads
			(clearance 0)
		)
		(min_thickness 0.25)
		(keepout
			(tracks not_allowed)
			(vias allowed)
			(pads allowed)
			(copperpour not_allowed)
			(footprints allowed)
		)
		(placement
			(enabled no)
			(sheetname "")
		)
		(fill yes
			(thermal_gap 0.5)
			(thermal_bridge_width 0.5)
			(island_removal_mode 0)
		)
		(polygon
			(pts
				(arc
					(start 358.267254 -377.41733)
					(mid 357.599234 -377.41733)
					(end 358.267254 -377.41733)
				)
			)
		)
	)
	(zone
		(layers "B.Cu" "In6.Cu" "In11.Cu" "In13.Cu" "In15.Cu")
		(hatch none 0.5)
		(connect_pads
			(clearance 0)
		)
		(min_thickness 0.25)
		(keepout
			(tracks not_allowed)
			(vias allowed)
			(pads allowed)
			(copperpour not_allowed)
			(footprints allowed)
		)
		(placement
			(enabled no)
			(sheetname "")
		)
		(fill yes
			(thermal_gap 0.5)
			(thermal_bridge_width 0.5)
			(island_removal_mode 0)
		)
		(polygon
			(pts
				(arc
					(start 92.355924 -244.484398)
					(mid 91.726004 -244.484398)
					(end 92.355924 -244.484398)
				)
			)
		)
	)
	(zone
		(layers "B.Cu" "In6.Cu" "In11.Cu" "In13.Cu" "In15.Cu")
		(hatch none 0.5)
		(connect_pads
			(clearance 0)
		)
		(min_thickness 0.25)
		(keepout
			(tracks not_allowed)
			(vias allowed)
			(pads allowed)
			(copperpour not_allowed)
			(footprints allowed)
		)
		(placement
			(enabled no)
			(sheetname "")
		)
		(fill yes
			(thermal_gap 0.5)
			(thermal_bridge_width 0.5)
			(island_removal_mode 0)
		)
		(polygon
			(pts
				(arc
					(start 379.599698 -270.846042)
					(mid 378.969778 -270.846042)
					(end 379.599698 -270.846042)
				)
			)
		)
	)
	(zone
		(layers "B.Cu" "In6.Cu" "In11.Cu" "In13.Cu" "In15.Cu")
		(hatch none 0.5)
		(connect_pads
			(clearance 0)
		)
		(min_thickness 0.25)
		(keepout
			(tracks not_allowed)
			(vias allowed)
			(pads allowed)
			(copperpour not_allowed)
			(footprints allowed)
		)
		(placement
			(enabled no)
			(sheetname "")
		)
		(fill yes
			(thermal_gap 0.5)
			(thermal_bridge_width 0.5)
			(island_removal_mode 0)
		)
		(polygon
			(pts
				(arc
					(start 33.029906 -253.435358)
					(mid 32.361886 -253.435358)
					(end 33.029906 -253.435358)
				)
			)
		)
	)
	(zone
		(layers "B.Cu" "In6.Cu" "In11.Cu" "In13.Cu" "In15.Cu")
		(hatch none 0.5)
		(connect_pads
			(clearance 0)
		)
		(min_thickness 0.25)
		(keepout
			(tracks not_allowed)
			(vias allowed)
			(pads allowed)
			(copperpour not_allowed)
			(footprints allowed)
		)
		(placement
			(enabled no)
			(sheetname "")
		)
		(fill yes
			(thermal_gap 0.5)
			(thermal_bridge_width 0.5)
			(island_removal_mode 0)
		)
		(polygon
			(pts
				(arc
					(start 155.333954 -389.467344)
					(mid 154.704034 -389.467344)
					(end 155.333954 -389.467344)
				)
			)
		)
	)
	(zone
		(layers "B.Cu" "In6.Cu" "In11.Cu" "In13.Cu" "In15.Cu")
		(hatch none 0.5)
		(connect_pads
			(clearance 0)
		)
		(min_thickness 0.25)
		(keepout
			(tracks not_allowed)
			(vias allowed)
			(pads allowed)
			(copperpour not_allowed)
			(footprints allowed)
		)
		(placement
			(enabled no)
			(sheetname "")
		)
		(fill yes
			(thermal_gap 0.5)
			(thermal_bridge_width 0.5)
			(island_removal_mode 0)
		)
		(polygon
			(pts
				(arc
					(start 33.029906 -293.38524)
					(mid 32.361886 -293.38524)
					(end 33.029906 -293.38524)
				)
			)
		)
	)
	(zone
		(layers "B.Cu" "In6.Cu" "In11.Cu" "In13.Cu" "In15.Cu")
		(hatch none 0.5)
		(connect_pads
			(clearance 0)
		)
		(min_thickness 0.25)
		(keepout
			(tracks not_allowed)
			(vias allowed)
			(pads allowed)
			(copperpour not_allowed)
			(footprints allowed)
		)
		(placement
			(enabled no)
			(sheetname "")
		)
		(fill yes
			(thermal_gap 0.5)
			(thermal_bridge_width 0.5)
			(island_removal_mode 0)
		)
		(polygon
			(pts
				(arc
					(start 349.995998 -287.856168)
					(mid 349.366078 -287.856168)
					(end 349.995998 -287.856168)
				)
			)
		)
	)
	(zone
		(layers "B.Cu" "In6.Cu" "In11.Cu" "In13.Cu" "In15.Cu")
		(hatch none 0.5)
		(connect_pads
			(clearance 0)
		)
		(min_thickness 0.25)
		(keepout
			(tracks not_allowed)
			(vias allowed)
			(pads allowed)
			(copperpour not_allowed)
			(footprints allowed)
		)
		(placement
			(enabled no)
			(sheetname "")
		)
		(fill yes
			(thermal_gap 0.5)
			(thermal_bridge_width 0.5)
			(island_removal_mode 0)
		)
		(polygon
			(pts
				(arc
					(start 149.333966 -389.467344)
					(mid 148.704046 -389.467344)
					(end 149.333966 -389.467344)
				)
			)
		)
	)
	(zone
		(layers "B.Cu" "In6.Cu" "In11.Cu" "In13.Cu" "In15.Cu")
		(hatch none 0.5)
		(connect_pads
			(clearance 0)
		)
		(min_thickness 0.25)
		(keepout
			(tracks not_allowed)
			(vias allowed)
			(pads allowed)
			(copperpour not_allowed)
			(footprints allowed)
		)
		(placement
			(enabled no)
			(sheetname "")
		)
		(fill yes
			(thermal_gap 0.5)
			(thermal_bridge_width 0.5)
			(island_removal_mode 0)
		)
		(polygon
			(pts
				(arc
					(start 280.969974 -268.735048)
					(mid 280.301954 -268.735048)
					(end 280.969974 -268.735048)
				)
			)
		)
	)
	(zone
		(layers "B.Cu" "In6.Cu" "In11.Cu" "In13.Cu" "In15.Cu")
		(hatch none 0.5)
		(connect_pads
			(clearance 0)
		)
		(min_thickness 0.25)
		(keepout
			(tracks not_allowed)
			(vias allowed)
			(pads allowed)
			(copperpour not_allowed)
			(footprints allowed)
		)
		(placement
			(enabled no)
			(sheetname "")
		)
		(fill yes
			(thermal_gap 0.5)
			(thermal_bridge_width 0.5)
			(island_removal_mode 0)
		)
		(polygon
			(pts
				(arc
					(start 106.455972 -234.764326)
					(mid 105.826052 -234.764326)
					(end 106.455972 -234.764326)
				)
			)
		)
	)
	(zone
		(layers "B.Cu" "In6.Cu" "In11.Cu" "In13.Cu" "In15.Cu")
		(hatch none 0.5)
		(connect_pads
			(clearance 0)
		)
		(min_thickness 0.25)
		(keepout
			(tracks not_allowed)
			(vias allowed)
			(pads allowed)
			(copperpour not_allowed)
			(footprints allowed)
		)
		(placement
			(enabled no)
			(sheetname "")
		)
		(fill yes
			(thermal_gap 0.5)
			(thermal_bridge_width 0.5)
			(island_removal_mode 0)
		)
		(polygon
			(pts
				(arc
					(start 187.394088 -232.18521)
					(mid 186.726068 -232.18521)
					(end 187.394088 -232.18521)
				)
			)
		)
	)
	(zone
		(layers "B.Cu" "In6.Cu" "In11.Cu" "In13.Cu" "In15.Cu")
		(hatch none 0.5)
		(connect_pads
			(clearance 0)
		)
		(min_thickness 0.25)
		(keepout
			(tracks not_allowed)
			(vias allowed)
			(pads allowed)
			(copperpour not_allowed)
			(footprints allowed)
		)
		(placement
			(enabled no)
			(sheetname "")
		)
		(fill yes
			(thermal_gap 0.5)
			(thermal_bridge_width 0.5)
			(island_removal_mode 0)
		)
		(polygon
			(pts
				(arc
					(start 191.494156 -204.985366)
					(mid 190.826136 -204.985366)
					(end 191.494156 -204.985366)
				)
			)
		)
	)
	(zone
		(layers "B.Cu" "In6.Cu" "In11.Cu" "In13.Cu" "In15.Cu")
		(hatch none 0.5)
		(connect_pads
			(clearance 0)
		)
		(min_thickness 0.25)
		(keepout
			(tracks not_allowed)
			(vias allowed)
			(pads allowed)
			(copperpour not_allowed)
			(footprints allowed)
		)
		(placement
			(enabled no)
			(sheetname "")
		)
		(fill yes
			(thermal_gap 0.5)
			(thermal_bridge_width 0.5)
			(island_removal_mode 0)
		)
		(polygon
			(pts
				(arc
					(start 126.006098 -385.31038)
					(mid 125.376178 -385.31038)
					(end 126.006098 -385.31038)
				)
			)
		)
	)
	(zone
		(layers "B.Cu" "In6.Cu" "In11.Cu" "In13.Cu" "In15.Cu")
		(hatch none 0.5)
		(connect_pads
			(clearance 0)
		)
		(min_thickness 0.25)
		(keepout
			(tracks not_allowed)
			(vias allowed)
			(pads allowed)
			(copperpour not_allowed)
			(footprints allowed)
		)
		(placement
			(enabled no)
			(sheetname "")
		)
		(fill yes
			(thermal_gap 0.5)
			(thermal_bridge_width 0.5)
			(island_removal_mode 0)
		)
		(polygon
			(pts
				(arc
					(start 92.826078 -229.094538)
					(mid 92.196158 -229.094538)
					(end 92.826078 -229.094538)
				)
			)
		)
	)
	(zone
		(layers "B.Cu" "In6.Cu" "In11.Cu" "In13.Cu" "In15.Cu")
		(hatch none 0.5)
		(connect_pads
			(clearance 0)
		)
		(min_thickness 0.25)
		(keepout
			(tracks not_allowed)
			(vias allowed)
			(pads allowed)
			(copperpour not_allowed)
			(footprints allowed)
		)
		(placement
			(enabled no)
			(sheetname "")
		)
		(fill yes
			(thermal_gap 0.5)
			(thermal_bridge_width 0.5)
			(island_removal_mode 0)
		)
		(polygon
			(pts
				(arc
					(start 133.069838 -282.996386)
					(mid 132.439918 -282.996386)
					(end 133.069838 -282.996386)
				)
			)
		)
	)
	(zone
		(layers "B.Cu" "In6.Cu" "In11.Cu" "In13.Cu" "In15.Cu")
		(hatch none 0.5)
		(connect_pads
			(clearance 0)
		)
		(min_thickness 0.25)
		(keepout
			(tracks not_allowed)
			(vias allowed)
			(pads allowed)
			(copperpour not_allowed)
			(footprints allowed)
		)
		(placement
			(enabled no)
			(sheetname "")
		)
		(fill yes
			(thermal_gap 0.5)
			(thermal_bridge_width 0.5)
			(island_removal_mode 0)
		)
		(polygon
			(pts
				(arc
					(start 91.716098 -276.516338)
					(mid 91.086178 -276.516338)
					(end 91.716098 -276.516338)
				)
			)
		)
	)
	(zone
		(layers "B.Cu" "In6.Cu" "In11.Cu" "In13.Cu" "In15.Cu")
		(hatch none 0.5)
		(connect_pads
			(clearance 0)
		)
		(min_thickness 0.25)
		(keepout
			(tracks not_allowed)
			(vias allowed)
			(pads allowed)
			(copperpour not_allowed)
			(footprints allowed)
		)
		(placement
			(enabled no)
			(sheetname "")
		)
		(fill yes
			(thermal_gap 0.5)
			(thermal_bridge_width 0.5)
			(island_removal_mode 0)
		)
		(polygon
			(pts
				(arc
					(start 435.334156 -215.18499)
					(mid 434.666136 -215.18499)
					(end 435.334156 -215.18499)
				)
			)
		)
	)
	(zone
		(layers "B.Cu" "In6.Cu" "In11.Cu" "In13.Cu" "In15.Cu")
		(hatch none 0.5)
		(connect_pads
			(clearance 0)
		)
		(min_thickness 0.25)
		(keepout
			(tracks not_allowed)
			(vias allowed)
			(pads allowed)
			(copperpour not_allowed)
			(footprints allowed)
		)
		(placement
			(enabled no)
			(sheetname "")
		)
		(fill yes
			(thermal_gap 0.5)
			(thermal_bridge_width 0.5)
			(island_removal_mode 0)
		)
		(polygon
			(pts
				(arc
					(start 131.82981 -234.764326)
					(mid 131.19989 -234.764326)
					(end 131.82981 -234.764326)
				)
			)
		)
	)
	(zone
		(layers "B.Cu" "In6.Cu" "In11.Cu" "In13.Cu" "In15.Cu")
		(hatch none 0.5)
		(connect_pads
			(clearance 0)
		)
		(min_thickness 0.25)
		(keepout
			(tracks not_allowed)
			(vias allowed)
			(pads allowed)
			(copperpour not_allowed)
			(footprints allowed)
		)
		(placement
			(enabled no)
			(sheetname "")
		)
		(fill yes
			(thermal_gap 0.5)
			(thermal_bridge_width 0.5)
			(island_removal_mode 0)
		)
		(polygon
			(pts
				(arc
					(start 280.969974 -288.285174)
					(mid 280.301954 -288.285174)
					(end 280.969974 -288.285174)
				)
			)
		)
	)
	(zone
		(layers "B.Cu" "In6.Cu" "In11.Cu" "In13.Cu" "In15.Cu")
		(hatch none 0.5)
		(connect_pads
			(clearance 0)
		)
		(min_thickness 0.25)
		(keepout
			(tracks not_allowed)
			(vias allowed)
			(pads allowed)
			(copperpour not_allowed)
			(footprints allowed)
		)
		(placement
			(enabled no)
			(sheetname "")
		)
		(fill yes
			(thermal_gap 0.5)
			(thermal_bridge_width 0.5)
			(island_removal_mode 0)
		)
		(polygon
			(pts
				(arc
					(start 340.385654 -377.41733)
					(mid 339.717634 -377.41733)
					(end 340.385654 -377.41733)
				)
			)
		)
	)
	(zone
		(layers "B.Cu" "In6.Cu" "In11.Cu" "In13.Cu" "In15.Cu")
		(hatch none 0.5)
		(connect_pads
			(clearance 0)
		)
		(min_thickness 0.25)
		(keepout
			(tracks not_allowed)
			(vias allowed)
			(pads allowed)
			(copperpour not_allowed)
			(footprints allowed)
		)
		(placement
			(enabled no)
			(sheetname "")
		)
		(fill yes
			(thermal_gap 0.5)
			(thermal_bridge_width 0.5)
			(island_removal_mode 0)
		)
		(polygon
			(pts
				(arc
					(start 84.385912 -369.03533)
					(mid 83.717892 -369.03533)
					(end 84.385912 -369.03533)
				)
			)
		)
	)
	(zone
		(layers "B.Cu" "In6.Cu" "In11.Cu" "In13.Cu" "In15.Cu")
		(hatch none 0.5)
		(connect_pads
			(clearance 0)
		)
		(min_thickness 0.25)
		(keepout
			(tracks not_allowed)
			(vias allowed)
			(pads allowed)
			(copperpour not_allowed)
			(footprints allowed)
		)
		(placement
			(enabled no)
			(sheetname "")
		)
		(fill yes
			(thermal_gap 0.5)
			(thermal_bridge_width 0.5)
			(island_removal_mode 0)
		)
		(polygon
			(pts
				(arc
					(start 131.65963 -278.946356)
					(mid 131.02971 -278.946356)
					(end 131.65963 -278.946356)
				)
			)
		)
	)
	(zone
		(layers "B.Cu" "In6.Cu" "In11.Cu" "In13.Cu" "In15.Cu")
		(hatch none 0.5)
		(connect_pads
			(clearance 0)
		)
		(min_thickness 0.25)
		(keepout
			(tracks not_allowed)
			(vias allowed)
			(pads allowed)
			(copperpour not_allowed)
			(footprints allowed)
		)
		(placement
			(enabled no)
			(sheetname "")
		)
		(fill yes
			(thermal_gap 0.5)
			(thermal_bridge_width 0.5)
			(island_removal_mode 0)
		)
		(polygon
			(pts
				(arc
					(start 119.206264 -386.003292)
					(mid 118.576344 -386.003292)
					(end 119.206264 -386.003292)
				)
			)
		)
	)
	(zone
		(layers "B.Cu" "In6.Cu" "In11.Cu" "In13.Cu" "In15.Cu")
		(hatch none 0.5)
		(connect_pads
			(clearance 0)
		)
		(min_thickness 0.25)
		(keepout
			(tracks not_allowed)
			(vias allowed)
			(pads allowed)
			(copperpour not_allowed)
			(footprints allowed)
		)
		(placement
			(enabled no)
			(sheetname "")
		)
		(fill yes
			(thermal_gap 0.5)
			(thermal_bridge_width 0.5)
			(island_removal_mode 0)
		)
		(polygon
			(pts
				(arc
					(start 37.129974 -228.78542)
					(mid 36.461954 -228.78542)
					(end 37.129974 -228.78542)
				)
			)
		)
	)
	(zone
		(layers "B.Cu" "In6.Cu" "In11.Cu" "In13.Cu" "In15.Cu")
		(hatch none 0.5)
		(connect_pads
			(clearance 0)
		)
		(min_thickness 0.25)
		(keepout
			(tracks not_allowed)
			(vias allowed)
			(pads allowed)
			(copperpour not_allowed)
			(footprints allowed)
		)
		(placement
			(enabled no)
			(sheetname "")
		)
		(fill yes
			(thermal_gap 0.5)
			(thermal_bridge_width 0.5)
			(island_removal_mode 0)
		)
		(polygon
			(pts
				(arc
					(start 439.434224 -270.43507)
					(mid 438.766204 -270.43507)
					(end 439.434224 -270.43507)
				)
			)
		)
	)
	(zone
		(layers "B.Cu" "In6.Cu" "In11.Cu" "In13.Cu" "In15.Cu")
		(hatch none 0.5)
		(connect_pads
			(clearance 0)
		)
		(min_thickness 0.25)
		(keepout
			(tracks not_allowed)
			(vias allowed)
			(pads allowed)
			(copperpour not_allowed)
			(footprints allowed)
		)
		(placement
			(enabled no)
			(sheetname "")
		)
		(fill yes
			(thermal_gap 0.5)
			(thermal_bridge_width 0.5)
			(island_removal_mode 0)
		)
		(polygon
			(pts
				(arc
					(start 365.969804 -291.095938)
					(mid 365.339884 -291.095938)
					(end 365.969804 -291.095938)
				)
			)
		)
	)
	(zone
		(layers "B.Cu" "In6.Cu" "In11.Cu" "In13.Cu" "In15.Cu")
		(hatch none 0.5)
		(connect_pads
			(clearance 0)
		)
		(min_thickness 0.25)
		(keepout
			(tracks not_allowed)
			(vias allowed)
			(pads allowed)
			(copperpour not_allowed)
			(footprints allowed)
		)
		(placement
			(enabled no)
			(sheetname "")
		)
		(fill yes
			(thermal_gap 0.5)
			(thermal_bridge_width 0.5)
			(island_removal_mode 0)
		)
		(polygon
			(pts
				(arc
					(start 157.33395 -388.774432)
					(mid 156.70403 -388.774432)
					(end 157.33395 -388.774432)
				)
			)
		)
	)
	(zone
		(layers "B.Cu" "In6.Cu" "In11.Cu" "In13.Cu" "In15.Cu")
		(hatch none 0.5)
		(connect_pads
			(clearance 0)
		)
		(min_thickness 0.25)
		(keepout
			(tracks not_allowed)
			(vias allowed)
			(pads allowed)
			(copperpour not_allowed)
			(footprints allowed)
		)
		(placement
			(enabled no)
			(sheetname "")
		)
		(fill yes
			(thermal_gap 0.5)
			(thermal_bridge_width 0.5)
			(island_removal_mode 0)
		)
		(polygon
			(pts
				(arc
					(start 131.82981 -255.824482)
					(mid 131.19989 -255.824482)
					(end 131.82981 -255.824482)
				)
			)
		)
	)
	(zone
		(layers "B.Cu" "In6.Cu" "In11.Cu" "In13.Cu" "In15.Cu")
		(hatch none 0.5)
		(connect_pads
			(clearance 0)
		)
		(min_thickness 0.25)
		(keepout
			(tracks not_allowed)
			(vias allowed)
			(pads allowed)
			(copperpour not_allowed)
			(footprints allowed)
		)
		(placement
			(enabled no)
			(sheetname "")
		)
		(fill yes
			(thermal_gap 0.5)
			(thermal_bridge_width 0.5)
			(island_removal_mode 0)
		)
		(polygon
			(pts
				(arc
					(start 381.479806 -264.365994)
					(mid 380.849886 -264.365994)
					(end 381.479806 -264.365994)
				)
			)
		)
	)
	(zone
		(layers "B.Cu" "In6.Cu" "In11.Cu" "In13.Cu" "In15.Cu")
		(hatch none 0.5)
		(connect_pads
			(clearance 0)
		)
		(min_thickness 0.25)
		(keepout
			(tracks not_allowed)
			(vias allowed)
			(pads allowed)
			(copperpour not_allowed)
			(footprints allowed)
		)
		(placement
			(enabled no)
			(sheetname "")
		)
		(fill yes
			(thermal_gap 0.5)
			(thermal_bridge_width 0.5)
			(island_removal_mode 0)
		)
		(polygon
			(pts
				(arc
					(start 140.597636 -404.46452)
					(mid 139.929616 -404.46452)
					(end 140.597636 -404.46452)
				)
			)
		)
	)
	(zone
		(layers "B.Cu" "In6.Cu" "In11.Cu" "In13.Cu" "In15.Cu")
		(hatch none 0.5)
		(connect_pads
			(clearance 0)
		)
		(min_thickness 0.25)
		(keepout
			(tracks not_allowed)
			(vias allowed)
			(pads allowed)
			(copperpour not_allowed)
			(footprints allowed)
		)
		(placement
			(enabled no)
			(sheetname "")
		)
		(fill yes
			(thermal_gap 0.5)
			(thermal_bridge_width 0.5)
			(island_removal_mode 0)
		)
		(polygon
			(pts
				(arc
					(start 380.069852 -270.036036)
					(mid 379.439932 -270.036036)
					(end 380.069852 -270.036036)
				)
			)
		)
	)
	(zone
		(layers "B.Cu" "In6.Cu" "In11.Cu" "In13.Cu" "In15.Cu")
		(hatch none 0.5)
		(connect_pads
			(clearance 0)
		)
		(min_thickness 0.25)
		(keepout
			(tracks not_allowed)
			(vias allowed)
			(pads allowed)
			(copperpour not_allowed)
			(footprints allowed)
		)
		(placement
			(enabled no)
			(sheetname "")
		)
		(fill yes
			(thermal_gap 0.5)
			(thermal_bridge_width 0.5)
			(island_removal_mode 0)
		)
		(polygon
			(pts
				(arc
					(start 114.739674 -290.286186)
					(mid 114.109754 -290.286186)
					(end 114.739674 -290.286186)
				)
			)
		)
	)
	(zone
		(layers "B.Cu" "In6.Cu" "In11.Cu" "In13.Cu" "In15.Cu")
		(hatch none 0.5)
		(connect_pads
			(clearance 0)
		)
		(min_thickness 0.25)
		(keepout
			(tracks not_allowed)
			(vias allowed)
			(pads allowed)
			(copperpour not_allowed)
			(footprints allowed)
		)
		(placement
			(enabled no)
			(sheetname "")
		)
		(fill yes
			(thermal_gap 0.5)
			(thermal_bridge_width 0.5)
			(island_removal_mode 0)
		)
		(polygon
			(pts
				(arc
					(start 381.179832 -232.334054)
					(mid 380.549912 -232.334054)
					(end 381.179832 -232.334054)
				)
			)
		)
	)
	(zone
		(layers "B.Cu" "In6.Cu" "In11.Cu" "In13.Cu" "In15.Cu")
		(hatch none 0.5)
		(connect_pads
			(clearance 0)
		)
		(min_thickness 0.25)
		(keepout
			(tracks not_allowed)
			(vias allowed)
			(pads allowed)
			(copperpour not_allowed)
			(footprints allowed)
		)
		(placement
			(enabled no)
			(sheetname "")
		)
		(fill yes
			(thermal_gap 0.5)
			(thermal_bridge_width 0.5)
			(island_removal_mode 0)
		)
		(polygon
			(pts
				(arc
					(start 372.806214 -394.385292)
					(mid 372.176294 -394.385292)
					(end 372.806214 -394.385292)
				)
			)
		)
	)
	(zone
		(layers "B.Cu" "In6.Cu" "In11.Cu" "In13.Cu" "In15.Cu")
		(hatch none 0.5)
		(connect_pads
			(clearance 0)
		)
		(min_thickness 0.25)
		(keepout
			(tracks not_allowed)
			(vias allowed)
			(pads allowed)
			(copperpour not_allowed)
			(footprints allowed)
		)
		(placement
			(enabled no)
			(sheetname "")
		)
		(fill yes
			(thermal_gap 0.5)
			(thermal_bridge_width 0.5)
			(island_removal_mode 0)
		)
		(polygon
			(pts
				(arc
					(start 339.186012 -264.365994)
					(mid 338.556092 -264.365994)
					(end 339.186012 -264.365994)
				)
			)
		)
	)
	(zone
		(layers "B.Cu" "In6.Cu" "In11.Cu" "In13.Cu" "In15.Cu")
		(hatch none 0.5)
		(connect_pads
			(clearance 0)
		)
		(min_thickness 0.25)
		(keepout
			(tracks not_allowed)
			(vias allowed)
			(pads allowed)
			(copperpour not_allowed)
			(footprints allowed)
		)
		(placement
			(enabled no)
			(sheetname "")
		)
		(fill yes
			(thermal_gap 0.5)
			(thermal_bridge_width 0.5)
			(island_removal_mode 0)
		)
		(polygon
			(pts
				(arc
					(start 92.355924 -247.724422)
					(mid 91.726004 -247.724422)
					(end 92.355924 -247.724422)
				)
			)
		)
	)
	(zone
		(layers "B.Cu" "In6.Cu" "In11.Cu" "In13.Cu" "In15.Cu")
		(hatch none 0.5)
		(connect_pads
			(clearance 0)
		)
		(min_thickness 0.25)
		(keepout
			(tracks not_allowed)
			(vias allowed)
			(pads allowed)
			(copperpour not_allowed)
			(footprints allowed)
		)
		(placement
			(enabled no)
			(sheetname "")
		)
		(fill yes
			(thermal_gap 0.5)
			(thermal_bridge_width 0.5)
			(island_removal_mode 0)
		)
		(polygon
			(pts
				(arc
					(start 280.969974 -198.185024)
					(mid 280.301954 -198.185024)
					(end 280.969974 -198.185024)
				)
			)
		)
	)
	(zone
		(layers "B.Cu" "In6.Cu" "In11.Cu" "In13.Cu" "In15.Cu")
		(hatch none 0.5)
		(connect_pads
			(clearance 0)
		)
		(min_thickness 0.25)
		(keepout
			(tracks not_allowed)
			(vias allowed)
			(pads allowed)
			(copperpour not_allowed)
			(footprints allowed)
		)
		(placement
			(enabled no)
			(sheetname "")
		)
		(fill yes
			(thermal_gap 0.5)
			(thermal_bridge_width 0.5)
			(island_removal_mode 0)
		)
		(polygon
			(pts
				(arc
					(start 330.292202 -384.35026)
					(mid 329.624182 -384.35026)
					(end 330.292202 -384.35026)
				)
			)
		)
	)
	(zone
		(layers "B.Cu" "In6.Cu" "In11.Cu" "In13.Cu" "In15.Cu")
		(hatch none 0.5)
		(connect_pads
			(clearance 0)
		)
		(min_thickness 0.25)
		(keepout
			(tracks not_allowed)
			(vias allowed)
			(pads allowed)
			(copperpour not_allowed)
			(footprints allowed)
		)
		(placement
			(enabled no)
			(sheetname "")
		)
		(fill yes
			(thermal_gap 0.5)
			(thermal_bridge_width 0.5)
			(island_removal_mode 0)
		)
		(polygon
			(pts
				(arc
					(start 127.206248 -385.31038)
					(mid 126.576328 -385.31038)
					(end 127.206248 -385.31038)
				)
			)
		)
	)
	(zone
		(layers "B.Cu" "In6.Cu" "In11.Cu" "In13.Cu" "In15.Cu")
		(hatch none 0.5)
		(connect_pads
			(clearance 0)
		)
		(min_thickness 0.25)
		(keepout
			(tracks not_allowed)
			(vias allowed)
			(pads allowed)
			(copperpour not_allowed)
			(footprints allowed)
		)
		(placement
			(enabled no)
			(sheetname "")
		)
		(fill yes
			(thermal_gap 0.5)
			(thermal_bridge_width 0.5)
			(island_removal_mode 0)
		)
		(polygon
			(pts
				(arc
					(start 191.494156 -306.135278)
					(mid 190.826136 -306.135278)
					(end 191.494156 -306.135278)
				)
			)
		)
	)
	(zone
		(layers "B.Cu" "In6.Cu" "In11.Cu" "In13.Cu" "In15.Cu")
		(hatch none 0.5)
		(connect_pads
			(clearance 0)
		)
		(min_thickness 0.25)
		(keepout
			(tracks not_allowed)
			(vias allowed)
			(pads allowed)
			(copperpour not_allowed)
			(footprints allowed)
		)
		(placement
			(enabled no)
			(sheetname "")
		)
		(fill yes
			(thermal_gap 0.5)
			(thermal_bridge_width 0.5)
			(island_removal_mode 0)
		)
		(polygon
			(pts
				(arc
					(start 133.206236 -385.31038)
					(mid 132.576316 -385.31038)
					(end 133.206236 -385.31038)
				)
			)
		)
	)
	(zone
		(layers "B.Cu" "In6.Cu" "In11.Cu" "In13.Cu" "In15.Cu")
		(hatch none 0.5)
		(connect_pads
			(clearance 0)
		)
		(min_thickness 0.25)
		(keepout
			(tracks not_allowed)
			(vias allowed)
			(pads allowed)
			(copperpour not_allowed)
			(footprints allowed)
		)
		(placement
			(enabled no)
			(sheetname "")
		)
		(fill yes
			(thermal_gap 0.5)
			(thermal_bridge_width 0.5)
			(island_removal_mode 0)
		)
		(polygon
			(pts
				(arc
					(start 408.933904 -397.849344)
					(mid 408.303984 -397.849344)
					(end 408.933904 -397.849344)
				)
			)
		)
	)
	(zone
		(layers "B.Cu" "In6.Cu" "In11.Cu" "In13.Cu" "In15.Cu")
		(hatch none 0.5)
		(connect_pads
			(clearance 0)
		)
		(min_thickness 0.25)
		(keepout
			(tracks not_allowed)
			(vias allowed)
			(pads allowed)
			(copperpour not_allowed)
			(footprints allowed)
		)
		(placement
			(enabled no)
			(sheetname "")
		)
		(fill yes
			(thermal_gap 0.5)
			(thermal_bridge_width 0.5)
			(island_removal_mode 0)
		)
		(polygon
			(pts
				(arc
					(start 372.091712 -412.84652)
					(mid 371.423692 -412.84652)
					(end 372.091712 -412.84652)
				)
			)
		)
	)
	(zone
		(layers "B.Cu" "In6.Cu" "In11.Cu" "In13.Cu" "In15.Cu")
		(hatch none 0.5)
		(connect_pads
			(clearance 0)
		)
		(min_thickness 0.25)
		(keepout
			(tracks not_allowed)
			(vias allowed)
			(pads allowed)
			(copperpour not_allowed)
			(footprints allowed)
		)
		(placement
			(enabled no)
			(sheetname "")
		)
		(fill yes
			(thermal_gap 0.5)
			(thermal_bridge_width 0.5)
			(island_removal_mode 0)
		)
		(polygon
			(pts
				(arc
					(start 435.334156 -308.685184)
					(mid 434.666136 -308.685184)
					(end 435.334156 -308.685184)
				)
			)
		)
	)
	(zone
		(layers "B.Cu" "In6.Cu" "In11.Cu" "In13.Cu" "In15.Cu")
		(hatch none 0.5)
		(connect_pads
			(clearance 0)
		)
		(min_thickness 0.25)
		(keepout
			(tracks not_allowed)
			(vias allowed)
			(pads allowed)
			(copperpour not_allowed)
			(footprints allowed)
		)
		(placement
			(enabled no)
			(sheetname "")
		)
		(fill yes
			(thermal_gap 0.5)
			(thermal_bridge_width 0.5)
			(island_removal_mode 0)
		)
		(polygon
			(pts
				(arc
					(start 413.333946 -397.156432)
					(mid 412.704026 -397.156432)
					(end 413.333946 -397.156432)
				)
			)
		)
	)
	(zone
		(layers "B.Cu" "In6.Cu" "In11.Cu" "In13.Cu" "In15.Cu")
		(hatch none 0.5)
		(connect_pads
			(clearance 0)
		)
		(min_thickness 0.25)
		(keepout
			(tracks not_allowed)
			(vias allowed)
			(pads allowed)
			(copperpour not_allowed)
			(footprints allowed)
		)
		(placement
			(enabled no)
			(sheetname "")
		)
		(fill yes
			(thermal_gap 0.5)
			(thermal_bridge_width 0.5)
			(island_removal_mode 0)
		)
		(polygon
			(pts
				(arc
					(start 131.359656 -232.334308)
					(mid 130.729736 -232.334308)
					(end 131.359656 -232.334308)
				)
			)
		)
	)
	(zone
		(layers "B.Cu" "In6.Cu" "In11.Cu" "In13.Cu" "In15.Cu")
		(hatch none 0.5)
		(connect_pads
			(clearance 0)
		)
		(min_thickness 0.25)
		(keepout
			(tracks not_allowed)
			(vias allowed)
			(pads allowed)
			(copperpour not_allowed)
			(footprints allowed)
		)
		(placement
			(enabled no)
			(sheetname "")
		)
		(fill yes
			(thermal_gap 0.5)
			(thermal_bridge_width 0.5)
			(island_removal_mode 0)
		)
		(polygon
			(pts
				(arc
					(start 280.969974 -235.585)
					(mid 280.301954 -235.585)
					(end 280.969974 -235.585)
				)
			)
		)
	)
	(zone
		(layers "B.Cu" "In6.Cu" "In11.Cu" "In13.Cu" "In15.Cu")
		(hatch none 0.5)
		(connect_pads
			(clearance 0)
		)
		(min_thickness 0.25)
		(keepout
			(tracks not_allowed)
			(vias allowed)
			(pads allowed)
			(copperpour not_allowed)
			(footprints allowed)
		)
		(placement
			(enabled no)
			(sheetname "")
		)
		(fill yes
			(thermal_gap 0.5)
			(thermal_bridge_width 0.5)
			(island_removal_mode 0)
		)
		(polygon
			(pts
				(arc
					(start 285.070042 -290.83508)
					(mid 284.402022 -290.83508)
					(end 285.070042 -290.83508)
				)
			)
		)
	)
	(zone
		(layers "B.Cu" "In6.Cu" "In11.Cu" "In13.Cu" "In15.Cu")
		(hatch none 0.5)
		(connect_pads
			(clearance 0)
		)
		(min_thickness 0.25)
		(keepout
			(tracks not_allowed)
			(vias allowed)
			(pads allowed)
			(copperpour not_allowed)
			(footprints allowed)
		)
		(placement
			(enabled no)
			(sheetname "")
		)
		(fill yes
			(thermal_gap 0.5)
			(thermal_bridge_width 0.5)
			(island_removal_mode 0)
		)
		(polygon
			(pts
				(arc
					(start 411.33395 -397.849344)
					(mid 410.70403 -397.849344)
					(end 411.33395 -397.849344)
				)
			)
		)
	)
	(zone
		(layers "B.Cu" "In6.Cu" "In11.Cu" "In13.Cu" "In15.Cu")
		(hatch none 0.5)
		(connect_pads
			(clearance 0)
		)
		(min_thickness 0.25)
		(keepout
			(tracks not_allowed)
			(vias allowed)
			(pads allowed)
			(copperpour not_allowed)
			(footprints allowed)
		)
		(placement
			(enabled no)
			(sheetname "")
		)
		(fill yes
			(thermal_gap 0.5)
			(thermal_bridge_width 0.5)
			(island_removal_mode 0)
		)
		(polygon
			(pts
				(arc
					(start 407.130758 -17.613122)
					(mid 406.462738 -17.613122)
					(end 407.130758 -17.613122)
				)
			)
		)
	)
	(zone
		(layers "B.Cu" "In6.Cu" "In11.Cu" "In13.Cu" "In15.Cu")
		(hatch none 0.5)
		(connect_pads
			(clearance 0)
		)
		(min_thickness 0.25)
		(keepout
			(tracks not_allowed)
			(vias allowed)
			(pads allowed)
			(copperpour not_allowed)
			(footprints allowed)
		)
		(placement
			(enabled no)
			(sheetname "")
		)
		(fill yes
			(thermal_gap 0.5)
			(thermal_bridge_width 0.5)
			(island_removal_mode 0)
		)
		(polygon
			(pts
				(arc
					(start 91.716098 -281.376374)
					(mid 91.086178 -281.376374)
					(end 91.716098 -281.376374)
				)
			)
		)
	)
	(zone
		(layers "B.Cu" "In6.Cu" "In11.Cu" "In13.Cu" "In15.Cu")
		(hatch none 0.5)
		(connect_pads
			(clearance 0)
		)
		(min_thickness 0.25)
		(keepout
			(tracks not_allowed)
			(vias allowed)
			(pads allowed)
			(copperpour not_allowed)
			(footprints allowed)
		)
		(placement
			(enabled no)
			(sheetname "")
		)
		(fill yes
			(thermal_gap 0.5)
			(thermal_bridge_width 0.5)
			(island_removal_mode 0)
		)
		(polygon
			(pts
				(arc
					(start 352.81616 -291.095938)
					(mid 352.18624 -291.095938)
					(end 352.81616 -291.095938)
				)
			)
		)
	)
	(zone
		(layers "B.Cu" "In6.Cu" "In11.Cu" "In13.Cu" "In15.Cu")
		(hatch none 0.5)
		(connect_pads
			(clearance 0)
		)
		(min_thickness 0.25)
		(keepout
			(tracks not_allowed)
			(vias allowed)
			(pads allowed)
			(copperpour not_allowed)
			(footprints allowed)
		)
		(placement
			(enabled no)
			(sheetname "")
		)
		(fill yes
			(thermal_gap 0.5)
			(thermal_bridge_width 0.5)
			(island_removal_mode 0)
		)
		(polygon
			(pts
				(arc
					(start 125.54966 -291.096192)
					(mid 124.91974 -291.096192)
					(end 125.54966 -291.096192)
				)
			)
		)
	)
	(zone
		(layers "B.Cu" "In6.Cu" "In11.Cu" "In13.Cu" "In15.Cu")
		(hatch none 0.5)
		(connect_pads
			(clearance 0)
		)
		(min_thickness 0.25)
		(keepout
			(tracks not_allowed)
			(vias allowed)
			(pads allowed)
			(copperpour not_allowed)
			(footprints allowed)
		)
		(placement
			(enabled no)
			(sheetname "")
		)
		(fill yes
			(thermal_gap 0.5)
			(thermal_bridge_width 0.5)
			(island_removal_mode 0)
		)
		(polygon
			(pts
				(arc
					(start 360.139234 -384.475228)
					(mid 359.471214 -384.475228)
					(end 360.139234 -384.475228)
				)
			)
		)
	)
	(zone
		(layers "B.Cu" "In6.Cu" "In11.Cu" "In13.Cu" "In15.Cu")
		(hatch none 0.5)
		(connect_pads
			(clearance 0)
		)
		(min_thickness 0.25)
		(keepout
			(tracks not_allowed)
			(vias allowed)
			(pads allowed)
			(copperpour not_allowed)
			(footprints allowed)
		)
		(placement
			(enabled no)
			(sheetname "")
		)
		(fill yes
			(thermal_gap 0.5)
			(thermal_bridge_width 0.5)
			(island_removal_mode 0)
		)
		(polygon
			(pts
				(arc
					(start 370.369846 -236.384084)
					(mid 369.739926 -236.384084)
					(end 370.369846 -236.384084)
				)
			)
		)
	)
	(zone
		(layers "B.Cu" "In6.Cu" "In11.Cu" "In13.Cu" "In15.Cu")
		(hatch none 0.5)
		(connect_pads
			(clearance 0)
		)
		(min_thickness 0.25)
		(keepout
			(tracks not_allowed)
			(vias allowed)
			(pads allowed)
			(copperpour not_allowed)
			(footprints allowed)
		)
		(placement
			(enabled no)
			(sheetname "")
		)
		(fill yes
			(thermal_gap 0.5)
			(thermal_bridge_width 0.5)
			(island_removal_mode 0)
		)
		(polygon
			(pts
				(arc
					(start 280.969974 -304.435002)
					(mid 280.301954 -304.435002)
					(end 280.969974 -304.435002)
				)
			)
		)
	)
	(zone
		(layers "B.Cu" "In6.Cu" "In11.Cu" "In13.Cu" "In15.Cu")
		(hatch none 0.5)
		(connect_pads
			(clearance 0)
		)
		(min_thickness 0.25)
		(keepout
			(tracks not_allowed)
			(vias allowed)
			(pads allowed)
			(copperpour not_allowed)
			(footprints allowed)
		)
		(placement
			(enabled no)
			(sheetname "")
		)
		(fill yes
			(thermal_gap 0.5)
			(thermal_bridge_width 0.5)
			(island_removal_mode 0)
		)
		(polygon
			(pts
				(arc
					(start 371.309646 -234.764072)
					(mid 370.679726 -234.764072)
					(end 371.309646 -234.764072)
				)
			)
		)
	)
	(zone
		(layers "B.Cu" "In6.Cu" "In11.Cu" "In13.Cu" "In15.Cu")
		(hatch none 0.5)
		(connect_pads
			(clearance 0)
		)
		(min_thickness 0.25)
		(keepout
			(tracks not_allowed)
			(vias allowed)
			(pads allowed)
			(copperpour not_allowed)
			(footprints allowed)
		)
		(placement
			(enabled no)
			(sheetname "")
		)
		(fill yes
			(thermal_gap 0.5)
			(thermal_bridge_width 0.5)
			(island_removal_mode 0)
		)
		(polygon
			(pts
				(arc
					(start 396.819374 -17.61236)
					(mid 396.151354 -17.61236)
					(end 396.819374 -17.61236)
				)
			)
		)
	)
	(zone
		(layers "B.Cu" "In6.Cu" "In11.Cu" "In13.Cu" "In15.Cu")
		(hatch none 0.5)
		(connect_pads
			(clearance 0)
		)
		(min_thickness 0.25)
		(keepout
			(tracks not_allowed)
			(vias allowed)
			(pads allowed)
			(copperpour not_allowed)
			(footprints allowed)
		)
		(placement
			(enabled no)
			(sheetname "")
		)
		(fill yes
			(thermal_gap 0.5)
			(thermal_bridge_width 0.5)
			(island_removal_mode 0)
		)
		(polygon
			(pts
				(arc
					(start 129.606294 -385.31038)
					(mid 128.976374 -385.31038)
					(end 129.606294 -385.31038)
				)
			)
		)
	)
	(zone
		(layers "B.Cu" "In6.Cu" "In11.Cu" "In13.Cu" "In15.Cu")
		(hatch none 0.5)
		(connect_pads
			(clearance 0)
		)
		(min_thickness 0.25)
		(keepout
			(tracks not_allowed)
			(vias allowed)
			(pads allowed)
			(copperpour not_allowed)
			(footprints allowed)
		)
		(placement
			(enabled no)
			(sheetname "")
		)
		(fill yes
			(thermal_gap 0.5)
			(thermal_bridge_width 0.5)
			(island_removal_mode 0)
		)
		(polygon
			(pts
				(arc
					(start 151.333962 -388.774432)
					(mid 150.704042 -388.774432)
					(end 151.333962 -388.774432)
				)
			)
		)
	)
	(zone
		(layers "B.Cu" "In6.Cu" "In11.Cu" "In13.Cu" "In15.Cu")
		(hatch none 0.5)
		(connect_pads
			(clearance 0)
		)
		(min_thickness 0.25)
		(keepout
			(tracks not_allowed)
			(vias allowed)
			(pads allowed)
			(copperpour not_allowed)
			(footprints allowed)
		)
		(placement
			(enabled no)
			(sheetname "")
		)
		(fill yes
			(thermal_gap 0.5)
			(thermal_bridge_width 0.5)
			(island_removal_mode 0)
		)
		(polygon
			(pts
				(arc
					(start 191.494156 -229.635304)
					(mid 190.826136 -229.635304)
					(end 191.494156 -229.635304)
				)
			)
		)
	)
	(zone
		(layers "B.Cu" "In6.Cu" "In11.Cu" "In13.Cu" "In15.Cu")
		(hatch none 0.5)
		(connect_pads
			(clearance 0)
		)
		(min_thickness 0.25)
		(keepout
			(tracks not_allowed)
			(vias allowed)
			(pads allowed)
			(copperpour not_allowed)
			(footprints allowed)
		)
		(placement
			(enabled no)
			(sheetname "")
		)
		(fill yes
			(thermal_gap 0.5)
			(thermal_bridge_width 0.5)
			(island_removal_mode 0)
		)
		(polygon
			(pts
				(arc
					(start 98.936048 -234.764326)
					(mid 98.306128 -234.764326)
					(end 98.936048 -234.764326)
				)
			)
		)
	)
	(zone
		(layers "B.Cu" "In6.Cu" "In11.Cu" "In13.Cu" "In15.Cu")
		(hatch none 0.5)
		(connect_pads
			(clearance 0)
		)
		(min_thickness 0.25)
		(keepout
			(tracks not_allowed)
			(vias allowed)
			(pads allowed)
			(copperpour not_allowed)
			(footprints allowed)
		)
		(placement
			(enabled no)
			(sheetname "")
		)
		(fill yes
			(thermal_gap 0.5)
			(thermal_bridge_width 0.5)
			(island_removal_mode 0)
		)
		(polygon
			(pts
				(arc
					(start 133.069838 -276.516338)
					(mid 132.439918 -276.516338)
					(end 133.069838 -276.516338)
				)
			)
		)
	)
	(zone
		(layers "B.Cu" "In6.Cu" "In11.Cu" "In13.Cu" "In15.Cu")
		(hatch none 0.5)
		(connect_pads
			(clearance 0)
		)
		(min_thickness 0.25)
		(keepout
			(tracks not_allowed)
			(vias allowed)
			(pads allowed)
			(copperpour not_allowed)
			(footprints allowed)
		)
		(placement
			(enabled no)
			(sheetname "")
		)
		(fill yes
			(thermal_gap 0.5)
			(thermal_bridge_width 0.5)
			(island_removal_mode 0)
		)
		(polygon
			(pts
				(arc
					(start 132.76961 -250.964446)
					(mid 132.13969 -250.964446)
					(end 132.76961 -250.964446)
				)
			)
		)
	)
	(zone
		(layers "B.Cu" "In6.Cu" "In11.Cu" "In13.Cu" "In15.Cu")
		(hatch none 0.5)
		(connect_pads
			(clearance 0)
		)
		(min_thickness 0.25)
		(keepout
			(tracks not_allowed)
			(vias allowed)
			(pads allowed)
			(copperpour not_allowed)
			(footprints allowed)
		)
		(placement
			(enabled no)
			(sheetname "")
		)
		(fill yes
			(thermal_gap 0.5)
			(thermal_bridge_width 0.5)
			(island_removal_mode 0)
		)
		(polygon
			(pts
				(arc
					(start 379.599698 -287.045908)
					(mid 378.969778 -287.045908)
					(end 379.599698 -287.045908)
				)
			)
		)
	)
	(zone
		(layers "B.Cu" "In6.Cu" "In11.Cu" "In13.Cu" "In15.Cu")
		(hatch none 0.5)
		(connect_pads
			(clearance 0)
		)
		(min_thickness 0.25)
		(keepout
			(tracks not_allowed)
			(vias allowed)
			(pads allowed)
			(copperpour not_allowed)
			(footprints allowed)
		)
		(placement
			(enabled no)
			(sheetname "")
		)
		(fill yes
			(thermal_gap 0.5)
			(thermal_bridge_width 0.5)
			(island_removal_mode 0)
		)
		(polygon
			(pts
				(arc
					(start 339.656166 -265.176)
					(mid 339.026246 -265.176)
					(end 339.656166 -265.176)
				)
			)
		)
	)
	(zone
		(layers "B.Cu" "In6.Cu" "In11.Cu" "In13.Cu" "In15.Cu")
		(hatch none 0.5)
		(connect_pads
			(clearance 0)
		)
		(min_thickness 0.25)
		(keepout
			(tracks not_allowed)
			(vias allowed)
			(pads allowed)
			(copperpour not_allowed)
			(footprints allowed)
		)
		(placement
			(enabled no)
			(sheetname "")
		)
		(fill yes
			(thermal_gap 0.5)
			(thermal_bridge_width 0.5)
			(island_removal_mode 0)
		)
		(polygon
			(pts
				(arc
					(start 91.193112 -369.03533)
					(mid 90.525092 -369.03533)
					(end 91.193112 -369.03533)
				)
			)
		)
	)
	(zone
		(layers "B.Cu" "In6.Cu" "In11.Cu" "In13.Cu" "In15.Cu")
		(hatch none 0.5)
		(connect_pads
			(clearance 0)
		)
		(min_thickness 0.25)
		(keepout
			(tracks not_allowed)
			(vias allowed)
			(pads allowed)
			(copperpour not_allowed)
			(footprints allowed)
		)
		(placement
			(enabled no)
			(sheetname "")
		)
		(fill yes
			(thermal_gap 0.5)
			(thermal_bridge_width 0.5)
			(island_removal_mode 0)
		)
		(polygon
			(pts
				(arc
					(start 133.239764 -237.194344)
					(mid 132.609844 -237.194344)
					(end 133.239764 -237.194344)
				)
			)
		)
	)
	(zone
		(layers "B.Cu" "In6.Cu" "In11.Cu" "In13.Cu" "In15.Cu")
		(hatch none 0.5)
		(connect_pads
			(clearance 0)
		)
		(min_thickness 0.25)
		(keepout
			(tracks not_allowed)
			(vias allowed)
			(pads allowed)
			(copperpour not_allowed)
			(footprints allowed)
		)
		(placement
			(enabled no)
			(sheetname "")
		)
		(fill yes
			(thermal_gap 0.5)
			(thermal_bridge_width 0.5)
			(island_removal_mode 0)
		)
		(polygon
			(pts
				(arc
					(start 381.179832 -238.814102)
					(mid 380.549912 -238.814102)
					(end 381.179832 -238.814102)
				)
			)
		)
	)
	(zone
		(layers "B.Cu" "In6.Cu" "In11.Cu" "In13.Cu" "In15.Cu")
		(hatch none 0.5)
		(connect_pads
			(clearance 0)
		)
		(min_thickness 0.25)
		(keepout
			(tracks not_allowed)
			(vias allowed)
			(pads allowed)
			(copperpour not_allowed)
			(footprints allowed)
		)
		(placement
			(enabled no)
			(sheetname "")
		)
		(fill yes
			(thermal_gap 0.5)
			(thermal_bridge_width 0.5)
			(island_removal_mode 0)
		)
		(polygon
			(pts
				(arc
					(start 337.823556 -412.84652)
					(mid 337.155536 -412.84652)
					(end 337.823556 -412.84652)
				)
			)
		)
	)
	(zone
		(layers "B.Cu" "In6.Cu" "In11.Cu" "In13.Cu" "In15.Cu")
		(hatch none 0.5)
		(connect_pads
			(clearance 0)
		)
		(min_thickness 0.25)
		(keepout
			(tracks not_allowed)
			(vias allowed)
			(pads allowed)
			(copperpour not_allowed)
			(footprints allowed)
		)
		(placement
			(enabled no)
			(sheetname "")
		)
		(fill yes
			(thermal_gap 0.5)
			(thermal_bridge_width 0.5)
			(island_removal_mode 0)
		)
		(polygon
			(pts
				(arc
					(start 37.129974 -298.485306)
					(mid 36.461954 -298.485306)
					(end 37.129974 -298.485306)
				)
			)
		)
	)
	(zone
		(layers "B.Cu" "In6.Cu" "In11.Cu" "In13.Cu" "In15.Cu")
		(hatch none 0.5)
		(connect_pads
			(clearance 0)
		)
		(min_thickness 0.25)
		(keepout
			(tracks not_allowed)
			(vias allowed)
			(pads allowed)
			(copperpour not_allowed)
			(footprints allowed)
		)
		(placement
			(enabled no)
			(sheetname "")
		)
		(fill yes
			(thermal_gap 0.5)
			(thermal_bridge_width 0.5)
			(island_removal_mode 0)
		)
		(polygon
			(pts
				(arc
					(start 85.249512 -369.03533)
					(mid 84.581492 -369.03533)
					(end 85.249512 -369.03533)
				)
			)
		)
	)
	(zone
		(layers "B.Cu" "In6.Cu" "In11.Cu" "In13.Cu" "In15.Cu")
		(hatch none 0.5)
		(connect_pads
			(clearance 0)
		)
		(min_thickness 0.25)
		(keepout
			(tracks not_allowed)
			(vias allowed)
			(pads allowed)
			(copperpour not_allowed)
			(footprints allowed)
		)
		(placement
			(enabled no)
			(sheetname "")
		)
		(fill yes
			(thermal_gap 0.5)
			(thermal_bridge_width 0.5)
			(island_removal_mode 0)
		)
		(polygon
			(pts
				(arc
					(start 439.434224 -281.485086)
					(mid 438.766204 -281.485086)
					(end 439.434224 -281.485086)
				)
			)
		)
	)
	(zone
		(layers "B.Cu" "In6.Cu" "In11.Cu" "In13.Cu" "In15.Cu")
		(hatch none 0.5)
		(connect_pads
			(clearance 0)
		)
		(min_thickness 0.25)
		(keepout
			(tracks not_allowed)
			(vias allowed)
			(pads allowed)
			(copperpour not_allowed)
			(footprints allowed)
		)
		(placement
			(enabled no)
			(sheetname "")
		)
		(fill yes
			(thermal_gap 0.5)
			(thermal_bridge_width 0.5)
			(island_removal_mode 0)
		)
		(polygon
			(pts
				(arc
					(start 355.636068 -291.095938)
					(mid 355.006148 -291.095938)
					(end 355.636068 -291.095938)
				)
			)
		)
	)
	(zone
		(layers "B.Cu" "In6.Cu" "In11.Cu" "In13.Cu" "In15.Cu")
		(hatch none 0.5)
		(connect_pads
			(clearance 0)
		)
		(min_thickness 0.25)
		(keepout
			(tracks not_allowed)
			(vias allowed)
			(pads allowed)
			(copperpour not_allowed)
			(footprints allowed)
		)
		(placement
			(enabled no)
			(sheetname "")
		)
		(fill yes
			(thermal_gap 0.5)
			(thermal_bridge_width 0.5)
			(island_removal_mode 0)
		)
		(polygon
			(pts
				(arc
					(start 33.029906 -272.98523)
					(mid 32.361886 -272.98523)
					(end 33.029906 -272.98523)
				)
			)
		)
	)
	(zone
		(layers "B.Cu" "In6.Cu" "In11.Cu" "In13.Cu" "In15.Cu")
		(hatch none 0.5)
		(connect_pads
			(clearance 0)
		)
		(min_thickness 0.25)
		(keepout
			(tracks not_allowed)
			(vias allowed)
			(pads allowed)
			(copperpour not_allowed)
			(footprints allowed)
		)
		(placement
			(enabled no)
			(sheetname "")
		)
		(fill yes
			(thermal_gap 0.5)
			(thermal_bridge_width 0.5)
			(island_removal_mode 0)
		)
		(polygon
			(pts
				(arc
					(start 90.94597 -245.294404)
					(mid 90.31605 -245.294404)
					(end 90.94597 -245.294404)
				)
			)
		)
	)
	(zone
		(layers "B.Cu" "In6.Cu" "In11.Cu" "In13.Cu" "In15.Cu")
		(hatch none 0.5)
		(connect_pads
			(clearance 0)
		)
		(min_thickness 0.25)
		(keepout
			(tracks not_allowed)
			(vias allowed)
			(pads allowed)
			(copperpour not_allowed)
			(footprints allowed)
		)
		(placement
			(enabled no)
			(sheetname "")
		)
		(fill yes
			(thermal_gap 0.5)
			(thermal_bridge_width 0.5)
			(island_removal_mode 0)
		)
		(polygon
			(pts
				(arc
					(start 37.129974 -197.335394)
					(mid 36.461954 -197.335394)
					(end 37.129974 -197.335394)
				)
			)
		)
	)
	(zone
		(layers "B.Cu" "In6.Cu" "In11.Cu" "In13.Cu" "In15.Cu")
		(hatch none 0.5)
		(connect_pads
			(clearance 0)
		)
		(min_thickness 0.25)
		(keepout
			(tracks not_allowed)
			(vias allowed)
			(pads allowed)
			(copperpour not_allowed)
			(footprints allowed)
		)
		(placement
			(enabled no)
			(sheetname "")
		)
		(fill yes
			(thermal_gap 0.5)
			(thermal_bridge_width 0.5)
			(island_removal_mode 0)
		)
		(polygon
			(pts
				(arc
					(start 364.729776 -231.524048)
					(mid 364.099856 -231.524048)
					(end 364.729776 -231.524048)
				)
			)
		)
	)
	(zone
		(layers "B.Cu" "In6.Cu" "In11.Cu" "In13.Cu" "In15.Cu")
		(hatch none 0.5)
		(connect_pads
			(clearance 0)
		)
		(min_thickness 0.25)
		(keepout
			(tracks not_allowed)
			(vias allowed)
			(pads allowed)
			(copperpour not_allowed)
			(footprints allowed)
		)
		(placement
			(enabled no)
			(sheetname "")
		)
		(fill yes
			(thermal_gap 0.5)
			(thermal_bridge_width 0.5)
			(island_removal_mode 0)
		)
		(polygon
			(pts
				(arc
					(start 379.769878 -244.484144)
					(mid 379.139958 -244.484144)
					(end 379.769878 -244.484144)
				)
			)
		)
	)
	(zone
		(layers "B.Cu" "In6.Cu" "In11.Cu" "In13.Cu" "In15.Cu")
		(hatch none 0.5)
		(connect_pads
			(clearance 0)
		)
		(min_thickness 0.25)
		(keepout
			(tracks not_allowed)
			(vias allowed)
			(pads allowed)
			(copperpour not_allowed)
			(footprints allowed)
		)
		(placement
			(enabled no)
			(sheetname "")
		)
		(fill yes
			(thermal_gap 0.5)
			(thermal_bridge_width 0.5)
			(island_removal_mode 0)
		)
		(polygon
			(pts
				(arc
					(start 154.933904 -388.774432)
					(mid 154.303984 -388.774432)
					(end 154.933904 -388.774432)
				)
			)
		)
	)
	(zone
		(layers "B.Cu" "In6.Cu" "In11.Cu" "In13.Cu" "In15.Cu")
		(hatch none 0.5)
		(connect_pads
			(clearance 0)
		)
		(min_thickness 0.25)
		(keepout
			(tracks not_allowed)
			(vias allowed)
			(pads allowed)
			(copperpour not_allowed)
			(footprints allowed)
		)
		(placement
			(enabled no)
			(sheetname "")
		)
		(fill yes
			(thermal_gap 0.5)
			(thermal_bridge_width 0.5)
			(island_removal_mode 0)
		)
		(polygon
			(pts
				(arc
					(start 350.940116 -412.84652)
					(mid 350.272096 -412.84652)
					(end 350.940116 -412.84652)
				)
			)
		)
	)
	(zone
		(layers "B.Cu" "In6.Cu" "In11.Cu" "In13.Cu" "In15.Cu")
		(hatch none 0.5)
		(connect_pads
			(clearance 0)
		)
		(min_thickness 0.25)
		(keepout
			(tracks not_allowed)
			(vias allowed)
			(pads allowed)
			(copperpour not_allowed)
			(footprints allowed)
		)
		(placement
			(enabled no)
			(sheetname "")
		)
		(fill yes
			(thermal_gap 0.5)
			(thermal_bridge_width 0.5)
			(island_removal_mode 0)
		)
		(polygon
			(pts
				(arc
					(start 379.599698 -274.086066)
					(mid 378.969778 -274.086066)
					(end 379.599698 -274.086066)
				)
			)
		)
	)
	(zone
		(layers "B.Cu" "In6.Cu" "In11.Cu" "In13.Cu" "In15.Cu")
		(hatch none 0.5)
		(connect_pads
			(clearance 0)
		)
		(min_thickness 0.25)
		(keepout
			(tracks not_allowed)
			(vias allowed)
			(pads allowed)
			(copperpour not_allowed)
			(footprints allowed)
		)
		(placement
			(enabled no)
			(sheetname "")
		)
		(fill yes
			(thermal_gap 0.5)
			(thermal_bridge_width 0.5)
			(island_removal_mode 0)
		)
		(polygon
			(pts
				(arc
					(start 320.90614 -397.156432)
					(mid 320.27622 -397.156432)
					(end 320.90614 -397.156432)
				)
			)
		)
	)
	(zone
		(layers "B.Cu" "In6.Cu" "In11.Cu" "In13.Cu" "In15.Cu")
		(hatch none 0.5)
		(connect_pads
			(clearance 0)
		)
		(min_thickness 0.25)
		(keepout
			(tracks not_allowed)
			(vias allowed)
			(pads allowed)
			(copperpour not_allowed)
			(footprints allowed)
		)
		(placement
			(enabled no)
			(sheetname "")
		)
		(fill yes
			(thermal_gap 0.5)
			(thermal_bridge_width 0.5)
			(island_removal_mode 0)
		)
		(polygon
			(pts
				(arc
					(start 387.407912 -412.84652)
					(mid 386.739892 -412.84652)
					(end 387.407912 -412.84652)
				)
			)
		)
	)
	(zone
		(layers "B.Cu" "In6.Cu" "In11.Cu" "In13.Cu" "In15.Cu")
		(hatch none 0.5)
		(connect_pads
			(clearance 0)
		)
		(min_thickness 0.25)
		(keepout
			(tracks not_allowed)
			(vias allowed)
			(pads allowed)
			(copperpour not_allowed)
			(footprints allowed)
		)
		(placement
			(enabled no)
			(sheetname "")
		)
		(fill yes
			(thermal_gap 0.5)
			(thermal_bridge_width 0.5)
			(island_removal_mode 0)
		)
		(polygon
			(pts
				(arc
					(start 125.249686 -226.66452)
					(mid 124.619766 -226.66452)
					(end 125.249686 -226.66452)
				)
			)
		)
	)
	(zone
		(layers "B.Cu" "In6.Cu" "In11.Cu" "In13.Cu" "In15.Cu")
		(hatch none 0.5)
		(connect_pads
			(clearance 0)
		)
		(min_thickness 0.25)
		(keepout
			(tracks not_allowed)
			(vias allowed)
			(pads allowed)
			(copperpour not_allowed)
			(footprints allowed)
		)
		(placement
			(enabled no)
			(sheetname "")
		)
		(fill yes
			(thermal_gap 0.5)
			(thermal_bridge_width 0.5)
			(island_removal_mode 0)
		)
		(polygon
			(pts
				(arc
					(start 374.00611 -394.385292)
					(mid 373.37619 -394.385292)
					(end 374.00611 -394.385292)
				)
			)
		)
	)
	(zone
		(layers "B.Cu" "In6.Cu" "In11.Cu" "In13.Cu" "In15.Cu")
		(hatch none 0.5)
		(connect_pads
			(clearance 0)
		)
		(min_thickness 0.25)
		(keepout
			(tracks not_allowed)
			(vias allowed)
			(pads allowed)
			(copperpour not_allowed)
			(footprints allowed)
		)
		(placement
			(enabled no)
			(sheetname "")
		)
		(fill yes
			(thermal_gap 0.5)
			(thermal_bridge_width 0.5)
			(island_removal_mode 0)
		)
		(polygon
			(pts
				(arc
					(start 393.160758 -19.137122)
					(mid 392.492738 -19.137122)
					(end 393.160758 -19.137122)
				)
			)
		)
	)
	(zone
		(layers "B.Cu" "In6.Cu" "In11.Cu" "In13.Cu" "In15.Cu")
		(hatch none 0.5)
		(connect_pads
			(clearance 0)
		)
		(min_thickness 0.25)
		(keepout
			(tracks not_allowed)
			(vias allowed)
			(pads allowed)
			(copperpour not_allowed)
			(footprints allowed)
		)
		(placement
			(enabled no)
			(sheetname "")
		)
		(fill yes
			(thermal_gap 0.5)
			(thermal_bridge_width 0.5)
			(island_removal_mode 0)
		)
		(polygon
			(pts
				(arc
					(start 340.766146 -233.954066)
					(mid 340.136226 -233.954066)
					(end 340.766146 -233.954066)
				)
			)
		)
	)
	(zone
		(layers "B.Cu" "In6.Cu" "In11.Cu" "In13.Cu" "In15.Cu")
		(hatch none 0.5)
		(connect_pads
			(clearance 0)
		)
		(min_thickness 0.25)
		(keepout
			(tracks not_allowed)
			(vias allowed)
			(pads allowed)
			(copperpour not_allowed)
			(footprints allowed)
		)
		(placement
			(enabled no)
			(sheetname "")
		)
		(fill yes
			(thermal_gap 0.5)
			(thermal_bridge_width 0.5)
			(island_removal_mode 0)
		)
		(polygon
			(pts
				(arc
					(start 33.029906 -222.835216)
					(mid 32.361886 -222.835216)
					(end 33.029906 -222.835216)
				)
			)
		)
	)
	(zone
		(layers "B.Cu" "In6.Cu" "In11.Cu" "In13.Cu" "In15.Cu")
		(hatch none 0.5)
		(connect_pads
			(clearance 0)
		)
		(min_thickness 0.25)
		(keepout
			(tracks not_allowed)
			(vias allowed)
			(pads allowed)
			(copperpour not_allowed)
			(footprints allowed)
		)
		(placement
			(enabled no)
			(sheetname "")
		)
		(fill yes
			(thermal_gap 0.5)
			(thermal_bridge_width 0.5)
			(island_removal_mode 0)
		)
		(polygon
			(pts
				(arc
					(start 101.755956 -231.524302)
					(mid 101.126036 -231.524302)
					(end 101.755956 -231.524302)
				)
			)
		)
	)
	(zone
		(layers "B.Cu" "In6.Cu" "In11.Cu" "In13.Cu" "In15.Cu")
		(hatch none 0.5)
		(connect_pads
			(clearance 0)
		)
		(min_thickness 0.25)
		(keepout
			(tracks not_allowed)
			(vias allowed)
			(pads allowed)
			(copperpour not_allowed)
			(footprints allowed)
		)
		(placement
			(enabled no)
			(sheetname "")
		)
		(fill yes
			(thermal_gap 0.5)
			(thermal_bridge_width 0.5)
			(island_removal_mode 0)
		)
		(polygon
			(pts
				(arc
					(start 339.355938 -236.384084)
					(mid 338.726018 -236.384084)
					(end 339.355938 -236.384084)
				)
			)
		)
	)
	(zone
		(layers "B.Cu" "In6.Cu" "In11.Cu" "In13.Cu" "In15.Cu")
		(hatch none 0.5)
		(connect_pads
			(clearance 0)
		)
		(min_thickness 0.25)
		(keepout
			(tracks not_allowed)
			(vias allowed)
			(pads allowed)
			(copperpour not_allowed)
			(footprints allowed)
		)
		(placement
			(enabled no)
			(sheetname "")
		)
		(fill yes
			(thermal_gap 0.5)
			(thermal_bridge_width 0.5)
			(island_removal_mode 0)
		)
		(polygon
			(pts
				(arc
					(start 30.1498 -6.725158)
					(mid 29.48178 -6.725158)
					(end 30.1498 -6.725158)
				)
			)
		)
	)
	(zone
		(layers "B.Cu" "In6.Cu" "In11.Cu" "In13.Cu" "In15.Cu")
		(hatch none 0.5)
		(connect_pads
			(clearance 0)
		)
		(min_thickness 0.25)
		(keepout
			(tracks not_allowed)
			(vias allowed)
			(pads allowed)
			(copperpour not_allowed)
			(footprints allowed)
		)
		(placement
			(enabled no)
			(sheetname "")
		)
		(fill yes
			(thermal_gap 0.5)
			(thermal_bridge_width 0.5)
			(island_removal_mode 0)
		)
		(polygon
			(pts
				(arc
					(start 354.696014 -287.856168)
					(mid 354.066094 -287.856168)
					(end 354.696014 -287.856168)
				)
			)
		)
	)
	(zone
		(layers "B.Cu" "In6.Cu" "In11.Cu" "In13.Cu" "In15.Cu")
		(hatch none 0.5)
		(connect_pads
			(clearance 0)
		)
		(min_thickness 0.25)
		(keepout
			(tracks not_allowed)
			(vias allowed)
			(pads allowed)
			(copperpour not_allowed)
			(footprints allowed)
		)
		(placement
			(enabled no)
			(sheetname "")
		)
		(fill yes
			(thermal_gap 0.5)
			(thermal_bridge_width 0.5)
			(island_removal_mode 0)
		)
		(polygon
			(pts
				(arc
					(start 285.070042 -295.085008)
					(mid 284.402022 -295.085008)
					(end 285.070042 -295.085008)
				)
			)
		)
	)
	(zone
		(layers "B.Cu" "In6.Cu" "In11.Cu" "In13.Cu" "In15.Cu")
		(hatch none 0.5)
		(connect_pads
			(clearance 0)
		)
		(min_thickness 0.25)
		(keepout
			(tracks not_allowed)
			(vias allowed)
			(pads allowed)
			(copperpour not_allowed)
			(footprints allowed)
		)
		(placement
			(enabled no)
			(sheetname "")
		)
		(fill yes
			(thermal_gap 0.5)
			(thermal_bridge_width 0.5)
			(island_removal_mode 0)
		)
		(polygon
			(pts
				(arc
					(start 33.029906 -238.985298)
					(mid 32.361886 -238.985298)
					(end 33.029906 -238.985298)
				)
			)
		)
	)
	(zone
		(layers "B.Cu" "In6.Cu" "In11.Cu" "In13.Cu" "In15.Cu")
		(hatch none 0.5)
		(connect_pads
			(clearance 0)
		)
		(min_thickness 0.25)
		(keepout
			(tracks not_allowed)
			(vias allowed)
			(pads allowed)
			(copperpour not_allowed)
			(footprints allowed)
		)
		(placement
			(enabled no)
			(sheetname "")
		)
		(fill yes
			(thermal_gap 0.5)
			(thermal_bridge_width 0.5)
			(island_removal_mode 0)
		)
		(polygon
			(pts
				(arc
					(start 311.706006 -397.849344)
					(mid 311.076086 -397.849344)
					(end 311.706006 -397.849344)
				)
			)
		)
	)
	(zone
		(layers "B.Cu" "In6.Cu" "In11.Cu" "In13.Cu" "In15.Cu")
		(hatch none 0.5)
		(connect_pads
			(clearance 0)
		)
		(min_thickness 0.25)
		(keepout
			(tracks not_allowed)
			(vias allowed)
			(pads allowed)
			(copperpour not_allowed)
			(footprints allowed)
		)
		(placement
			(enabled no)
			(sheetname "")
		)
		(fill yes
			(thermal_gap 0.5)
			(thermal_bridge_width 0.5)
			(island_removal_mode 0)
		)
		(polygon
			(pts
				(arc
					(start 339.186012 -272.466054)
					(mid 338.556092 -272.466054)
					(end 339.186012 -272.466054)
				)
			)
		)
	)
	(zone
		(layers "B.Cu" "In6.Cu" "In11.Cu" "In13.Cu" "In15.Cu")
		(hatch none 0.5)
		(connect_pads
			(clearance 0)
		)
		(min_thickness 0.25)
		(keepout
			(tracks not_allowed)
			(vias allowed)
			(pads allowed)
			(copperpour not_allowed)
			(footprints allowed)
		)
		(placement
			(enabled no)
			(sheetname "")
		)
		(fill yes
			(thermal_gap 0.5)
			(thermal_bridge_width 0.5)
			(island_removal_mode 0)
		)
		(polygon
			(pts
				(arc
					(start 285.070042 -296.78503)
					(mid 284.402022 -296.78503)
					(end 285.070042 -296.78503)
				)
			)
		)
	)
	(zone
		(layers "B.Cu" "In6.Cu" "In11.Cu" "In13.Cu" "In15.Cu")
		(hatch none 0.5)
		(connect_pads
			(clearance 0)
		)
		(min_thickness 0.25)
		(keepout
			(tracks not_allowed)
			(vias allowed)
			(pads allowed)
			(copperpour not_allowed)
			(footprints allowed)
		)
		(placement
			(enabled no)
			(sheetname "")
		)
		(fill yes
			(thermal_gap 0.5)
			(thermal_bridge_width 0.5)
			(island_removal_mode 0)
		)
		(polygon
			(pts
				(arc
					(start 419.733984 -397.849344)
					(mid 419.104064 -397.849344)
					(end 419.733984 -397.849344)
				)
			)
		)
	)
	(zone
		(layers "B.Cu" "In6.Cu" "In11.Cu" "In13.Cu" "In15.Cu")
		(hatch none 0.5)
		(connect_pads
			(clearance 0)
		)
		(min_thickness 0.25)
		(keepout
			(tracks not_allowed)
			(vias allowed)
			(pads allowed)
			(copperpour not_allowed)
			(footprints allowed)
		)
		(placement
			(enabled no)
			(sheetname "")
		)
		(fill yes
			(thermal_gap 0.5)
			(thermal_bridge_width 0.5)
			(island_removal_mode 0)
		)
		(polygon
			(pts
				(arc
					(start 435.334156 -216.885012)
					(mid 434.666136 -216.885012)
					(end 435.334156 -216.885012)
				)
			)
		)
	)
	(zone
		(layers "B.Cu" "In6.Cu" "In11.Cu" "In13.Cu" "In15.Cu")
		(hatch none 0.5)
		(connect_pads
			(clearance 0)
		)
		(min_thickness 0.25)
		(keepout
			(tracks not_allowed)
			(vias allowed)
			(pads allowed)
			(copperpour not_allowed)
			(footprints allowed)
		)
		(placement
			(enabled no)
			(sheetname "")
		)
		(fill yes
			(thermal_gap 0.5)
			(thermal_bridge_width 0.5)
			(island_removal_mode 0)
		)
		(polygon
			(pts
				(arc
					(start 118.006114 -386.003292)
					(mid 117.376194 -386.003292)
					(end 118.006114 -386.003292)
				)
			)
		)
	)
	(zone
		(layers "B.Cu" "In6.Cu" "In11.Cu" "In13.Cu" "In15.Cu")
		(hatch none 0.5)
		(connect_pads
			(clearance 0)
		)
		(min_thickness 0.25)
		(keepout
			(tracks not_allowed)
			(vias allowed)
			(pads allowed)
			(copperpour not_allowed)
			(footprints allowed)
		)
		(placement
			(enabled no)
			(sheetname "")
		)
		(fill yes
			(thermal_gap 0.5)
			(thermal_bridge_width 0.5)
			(island_removal_mode 0)
		)
		(polygon
			(pts
				(arc
					(start 340.295992 -242.864132)
					(mid 339.666072 -242.864132)
					(end 340.295992 -242.864132)
				)
			)
		)
	)
	(zone
		(layers "B.Cu" "In6.Cu" "In11.Cu" "In13.Cu" "In15.Cu")
		(hatch none 0.5)
		(connect_pads
			(clearance 0)
		)
		(min_thickness 0.25)
		(keepout
			(tracks not_allowed)
			(vias allowed)
			(pads allowed)
			(copperpour not_allowed)
			(footprints allowed)
		)
		(placement
			(enabled no)
			(sheetname "")
		)
		(fill yes
			(thermal_gap 0.5)
			(thermal_bridge_width 0.5)
			(island_removal_mode 0)
		)
		(polygon
			(pts
				(arc
					(start 379.769878 -242.864132)
					(mid 379.139958 -242.864132)
					(end 379.769878 -242.864132)
				)
			)
		)
	)
	(zone
		(layers "B.Cu" "In6.Cu" "In11.Cu" "In13.Cu" "In15.Cu")
		(hatch none 0.5)
		(connect_pads
			(clearance 0)
		)
		(min_thickness 0.25)
		(keepout
			(tracks not_allowed)
			(vias allowed)
			(pads allowed)
			(copperpour not_allowed)
			(footprints allowed)
		)
		(placement
			(enabled no)
			(sheetname "")
		)
		(fill yes
			(thermal_gap 0.5)
			(thermal_bridge_width 0.5)
			(island_removal_mode 0)
		)
		(polygon
			(pts
				(arc
					(start 33.029906 -304.435256)
					(mid 32.361886 -304.435256)
					(end 33.029906 -304.435256)
				)
			)
		)
	)
	(zone
		(layers "B.Cu" "In6.Cu" "In11.Cu" "In13.Cu" "In15.Cu")
		(hatch none 0.5)
		(connect_pads
			(clearance 0)
		)
		(min_thickness 0.25)
		(keepout
			(tracks not_allowed)
			(vias allowed)
			(pads allowed)
			(copperpour not_allowed)
			(footprints allowed)
		)
		(placement
			(enabled no)
			(sheetname "")
		)
		(fill yes
			(thermal_gap 0.5)
			(thermal_bridge_width 0.5)
			(island_removal_mode 0)
		)
		(polygon
			(pts
				(arc
					(start 191.494156 -275.53539)
					(mid 190.826136 -275.53539)
					(end 191.494156 -275.53539)
				)
			)
		)
	)
	(zone
		(layers "B.Cu" "In6.Cu" "In11.Cu" "In13.Cu" "In15.Cu")
		(hatch none 0.5)
		(connect_pads
			(clearance 0)
		)
		(min_thickness 0.25)
		(keepout
			(tracks not_allowed)
			(vias allowed)
			(pads allowed)
			(copperpour not_allowed)
			(footprints allowed)
		)
		(placement
			(enabled no)
			(sheetname "")
		)
		(fill yes
			(thermal_gap 0.5)
			(thermal_bridge_width 0.5)
			(island_removal_mode 0)
		)
		(polygon
			(pts
				(arc
					(start 373.189754 -236.384084)
					(mid 372.559834 -236.384084)
					(end 373.189754 -236.384084)
				)
			)
		)
	)
	(zone
		(layers "B.Cu" "In6.Cu" "In11.Cu" "In13.Cu" "In15.Cu")
		(hatch none 0.5)
		(connect_pads
			(clearance 0)
		)
		(min_thickness 0.25)
		(keepout
			(tracks not_allowed)
			(vias allowed)
			(pads allowed)
			(copperpour not_allowed)
			(footprints allowed)
		)
		(placement
			(enabled no)
			(sheetname "")
		)
		(fill yes
			(thermal_gap 0.5)
			(thermal_bridge_width 0.5)
			(island_removal_mode 0)
		)
		(polygon
			(pts
				(arc
					(start 379.769878 -226.664266)
					(mid 379.139958 -226.664266)
					(end 379.769878 -226.664266)
				)
			)
		)
	)
	(zone
		(layers "B.Cu" "In6.Cu" "In11.Cu" "In13.Cu" "In15.Cu")
		(hatch none 0.5)
		(connect_pads
			(clearance 0)
		)
		(min_thickness 0.25)
		(keepout
			(tracks not_allowed)
			(vias allowed)
			(pads allowed)
			(copperpour not_allowed)
			(footprints allowed)
		)
		(placement
			(enabled no)
			(sheetname "")
		)
		(fill yes
			(thermal_gap 0.5)
			(thermal_bridge_width 0.5)
			(island_removal_mode 0)
		)
		(polygon
			(pts
				(arc
					(start 280.969974 -318.035178)
					(mid 280.301954 -318.035178)
					(end 280.969974 -318.035178)
				)
			)
		)
	)
	(zone
		(layers "B.Cu" "In6.Cu" "In11.Cu" "In13.Cu" "In15.Cu")
		(hatch none 0.5)
		(connect_pads
			(clearance 0)
		)
		(min_thickness 0.25)
		(keepout
			(tracks not_allowed)
			(vias allowed)
			(pads allowed)
			(copperpour not_allowed)
			(footprints allowed)
		)
		(placement
			(enabled no)
			(sheetname "")
		)
		(fill yes
			(thermal_gap 0.5)
			(thermal_bridge_width 0.5)
			(island_removal_mode 0)
		)
		(polygon
			(pts
				(arc
					(start 37.129974 -240.68532)
					(mid 36.461954 -240.68532)
					(end 37.129974 -240.68532)
				)
			)
		)
	)
	(zone
		(layers "B.Cu" "In6.Cu" "In11.Cu" "In13.Cu" "In15.Cu")
		(hatch none 0.5)
		(connect_pads
			(clearance 0)
		)
		(min_thickness 0.25)
		(keepout
			(tracks not_allowed)
			(vias allowed)
			(pads allowed)
			(copperpour not_allowed)
			(footprints allowed)
		)
		(placement
			(enabled no)
			(sheetname "")
		)
		(fill yes
			(thermal_gap 0.5)
			(thermal_bridge_width 0.5)
			(island_removal_mode 0)
		)
		(polygon
			(pts
				(arc
					(start 187.394088 -277.235412)
					(mid 186.726068 -277.235412)
					(end 187.394088 -277.235412)
				)
			)
		)
	)
	(zone
		(layers "B.Cu" "In6.Cu" "In11.Cu" "In13.Cu" "In15.Cu")
		(hatch none 0.5)
		(connect_pads
			(clearance 0)
		)
		(min_thickness 0.25)
		(keepout
			(tracks not_allowed)
			(vias allowed)
			(pads allowed)
			(copperpour not_allowed)
			(footprints allowed)
		)
		(placement
			(enabled no)
			(sheetname "")
		)
		(fill yes
			(thermal_gap 0.5)
			(thermal_bridge_width 0.5)
			(island_removal_mode 0)
		)
		(polygon
			(pts
				(arc
					(start 187.394088 -310.385206)
					(mid 186.726068 -310.385206)
					(end 187.394088 -310.385206)
				)
			)
		)
	)
	(zone
		(layers "B.Cu" "In6.Cu" "In11.Cu" "In13.Cu" "In15.Cu")
		(hatch none 0.5)
		(connect_pads
			(clearance 0)
		)
		(min_thickness 0.25)
		(keepout
			(tracks not_allowed)
			(vias allowed)
			(pads allowed)
			(copperpour not_allowed)
			(footprints allowed)
		)
		(placement
			(enabled no)
			(sheetname "")
		)
		(fill yes
			(thermal_gap 0.5)
			(thermal_bridge_width 0.5)
			(island_removal_mode 0)
		)
		(polygon
			(pts
				(arc
					(start 379.299724 -248.534174)
					(mid 378.669804 -248.534174)
					(end 379.299724 -248.534174)
				)
			)
		)
	)
	(zone
		(layers "B.Cu" "In6.Cu" "In11.Cu" "In13.Cu" "In15.Cu")
		(hatch none 0.5)
		(connect_pads
			(clearance 0)
		)
		(min_thickness 0.25)
		(keepout
			(tracks not_allowed)
			(vias allowed)
			(pads allowed)
			(copperpour not_allowed)
			(footprints allowed)
		)
		(placement
			(enabled no)
			(sheetname "")
		)
		(fill yes
			(thermal_gap 0.5)
			(thermal_bridge_width 0.5)
			(island_removal_mode 0)
		)
		(polygon
			(pts
				(arc
					(start 280.969974 -246.635016)
					(mid 280.301954 -246.635016)
					(end 280.969974 -246.635016)
				)
			)
		)
	)
	(zone
		(layers "B.Cu" "In6.Cu" "In11.Cu" "In13.Cu" "In15.Cu")
		(hatch none 0.5)
		(connect_pads
			(clearance 0)
		)
		(min_thickness 0.25)
		(keepout
			(tracks not_allowed)
			(vias allowed)
			(pads allowed)
			(copperpour not_allowed)
			(footprints allowed)
		)
		(placement
			(enabled no)
			(sheetname "")
		)
		(fill yes
			(thermal_gap 0.5)
			(thermal_bridge_width 0.5)
			(island_removal_mode 0)
		)
		(polygon
			(pts
				(arc
					(start 37.129974 -223.685354)
					(mid 36.461954 -223.685354)
					(end 37.129974 -223.685354)
				)
			)
		)
	)
	(zone
		(layers "B.Cu" "In6.Cu" "In11.Cu" "In13.Cu" "In15.Cu")
		(hatch none 0.5)
		(connect_pads
			(clearance 0)
		)
		(min_thickness 0.25)
		(keepout
			(tracks not_allowed)
			(vias allowed)
			(pads allowed)
			(copperpour not_allowed)
			(footprints allowed)
		)
		(placement
			(enabled no)
			(sheetname "")
		)
		(fill yes
			(thermal_gap 0.5)
			(thermal_bridge_width 0.5)
			(island_removal_mode 0)
		)
		(polygon
			(pts
				(arc
					(start 280.969974 -261.93496)
					(mid 280.301954 -261.93496)
					(end 280.969974 -261.93496)
				)
			)
		)
	)
	(zone
		(layers "B.Cu" "In6.Cu" "In11.Cu" "In13.Cu" "In15.Cu")
		(hatch none 0.5)
		(connect_pads
			(clearance 0)
		)
		(min_thickness 0.25)
		(keepout
			(tracks not_allowed)
			(vias allowed)
			(pads allowed)
			(copperpour not_allowed)
			(footprints allowed)
		)
		(placement
			(enabled no)
			(sheetname "")
		)
		(fill yes
			(thermal_gap 0.5)
			(thermal_bridge_width 0.5)
			(island_removal_mode 0)
		)
		(polygon
			(pts
				(arc
					(start 33.029906 -221.135194)
					(mid 32.361886 -221.135194)
					(end 33.029906 -221.135194)
				)
			)
		)
	)
	(zone
		(layers "B.Cu" "In6.Cu" "In11.Cu" "In13.Cu" "In15.Cu")
		(hatch none 0.5)
		(connect_pads
			(clearance 0)
		)
		(min_thickness 0.25)
		(keepout
			(tracks not_allowed)
			(vias allowed)
			(pads allowed)
			(copperpour not_allowed)
			(footprints allowed)
		)
		(placement
			(enabled no)
			(sheetname "")
		)
		(fill yes
			(thermal_gap 0.5)
			(thermal_bridge_width 0.5)
			(island_removal_mode 0)
		)
		(polygon
			(pts
				(arc
					(start 339.656166 -287.856168)
					(mid 339.026246 -287.856168)
					(end 339.656166 -287.856168)
				)
			)
		)
	)
	(zone
		(layers "B.Cu" "In6.Cu" "In11.Cu" "In13.Cu" "In15.Cu")
		(hatch none 0.5)
		(connect_pads
			(clearance 0)
		)
		(min_thickness 0.25)
		(keepout
			(tracks not_allowed)
			(vias allowed)
			(pads allowed)
			(copperpour not_allowed)
			(footprints allowed)
		)
		(placement
			(enabled no)
			(sheetname "")
		)
		(fill yes
			(thermal_gap 0.5)
			(thermal_bridge_width 0.5)
			(island_removal_mode 0)
		)
		(polygon
			(pts
				(arc
					(start 90.94597 -255.014476)
					(mid 90.31605 -255.014476)
					(end 90.94597 -255.014476)
				)
			)
		)
	)
	(zone
		(layers "B.Cu" "In6.Cu" "In11.Cu" "In13.Cu" "In15.Cu")
		(hatch none 0.5)
		(connect_pads
			(clearance 0)
		)
		(min_thickness 0.25)
		(keepout
			(tracks not_allowed)
			(vias allowed)
			(pads allowed)
			(copperpour not_allowed)
			(footprints allowed)
		)
		(placement
			(enabled no)
			(sheetname "")
		)
		(fill yes
			(thermal_gap 0.5)
			(thermal_bridge_width 0.5)
			(island_removal_mode 0)
		)
		(polygon
			(pts
				(arc
					(start 285.070042 -309.535068)
					(mid 284.402022 -309.535068)
					(end 285.070042 -309.535068)
				)
			)
		)
	)
	(zone
		(layers "B.Cu" "In6.Cu" "In11.Cu" "In13.Cu" "In15.Cu")
		(hatch none 0.5)
		(connect_pads
			(clearance 0)
		)
		(min_thickness 0.25)
		(keepout
			(tracks not_allowed)
			(vias allowed)
			(pads allowed)
			(copperpour not_allowed)
			(footprints allowed)
		)
		(placement
			(enabled no)
			(sheetname "")
		)
		(fill yes
			(thermal_gap 0.5)
			(thermal_bridge_width 0.5)
			(island_removal_mode 0)
		)
		(polygon
			(pts
				(arc
					(start 439.434224 -313.784996)
					(mid 438.766204 -313.784996)
					(end 439.434224 -313.784996)
				)
			)
		)
	)
	(zone
		(layers "B.Cu" "In6.Cu" "In11.Cu" "In13.Cu" "In15.Cu")
		(hatch none 0.5)
		(connect_pads
			(clearance 0)
		)
		(min_thickness 0.25)
		(keepout
			(tracks not_allowed)
			(vias allowed)
			(pads allowed)
			(copperpour not_allowed)
			(footprints allowed)
		)
		(placement
			(enabled no)
			(sheetname "")
		)
		(fill yes
			(thermal_gap 0.5)
			(thermal_bridge_width 0.5)
			(island_removal_mode 0)
		)
		(polygon
			(pts
				(arc
					(start 337.845654 -382.34493)
					(mid 337.177634 -382.34493)
					(end 337.845654 -382.34493)
				)
			)
		)
	)
	(zone
		(layers "B.Cu" "In6.Cu" "In11.Cu" "In13.Cu" "In15.Cu")
		(hatch none 0.5)
		(connect_pads
			(clearance 0)
		)
		(min_thickness 0.25)
		(keepout
			(tracks not_allowed)
			(vias allowed)
			(pads allowed)
			(copperpour not_allowed)
			(footprints allowed)
		)
		(placement
			(enabled no)
			(sheetname "")
		)
		(fill yes
			(thermal_gap 0.5)
			(thermal_bridge_width 0.5)
			(island_removal_mode 0)
		)
		(polygon
			(pts
				(arc
					(start 381.179832 -230.714296)
					(mid 380.549912 -230.714296)
					(end 381.179832 -230.714296)
				)
			)
		)
	)
	(zone
		(layers "B.Cu" "In6.Cu" "In11.Cu" "In13.Cu" "In15.Cu")
		(hatch none 0.5)
		(connect_pads
			(clearance 0)
		)
		(min_thickness 0.25)
		(keepout
			(tracks not_allowed)
			(vias allowed)
			(pads allowed)
			(copperpour not_allowed)
			(footprints allowed)
		)
		(placement
			(enabled no)
			(sheetname "")
		)
		(fill yes
			(thermal_gap 0.5)
			(thermal_bridge_width 0.5)
			(island_removal_mode 0)
		)
		(polygon
			(pts
				(arc
					(start 33.029906 -244.935248)
					(mid 32.361886 -244.935248)
					(end 33.029906 -244.935248)
				)
			)
		)
	)
	(zone
		(layers "B.Cu" "In6.Cu" "In11.Cu" "In13.Cu" "In15.Cu")
		(hatch none 0.5)
		(connect_pads
			(clearance 0)
		)
		(min_thickness 0.25)
		(keepout
			(tracks not_allowed)
			(vias allowed)
			(pads allowed)
			(copperpour not_allowed)
			(footprints allowed)
		)
		(placement
			(enabled no)
			(sheetname "")
		)
		(fill yes
			(thermal_gap 0.5)
			(thermal_bridge_width 0.5)
			(island_removal_mode 0)
		)
		(polygon
			(pts
				(arc
					(start 352.516186 -226.664266)
					(mid 351.886266 -226.664266)
					(end 352.516186 -226.664266)
				)
			)
		)
	)
	(zone
		(layers "B.Cu" "In6.Cu" "In11.Cu" "In13.Cu" "In15.Cu")
		(hatch none 0.5)
		(connect_pads
			(clearance 0)
		)
		(min_thickness 0.25)
		(keepout
			(tracks not_allowed)
			(vias allowed)
			(pads allowed)
			(copperpour not_allowed)
			(footprints allowed)
		)
		(placement
			(enabled no)
			(sheetname "")
		)
		(fill yes
			(thermal_gap 0.5)
			(thermal_bridge_width 0.5)
			(island_removal_mode 0)
		)
		(polygon
			(pts
				(arc
					(start 187.394088 -204.135228)
					(mid 186.726068 -204.135228)
					(end 187.394088 -204.135228)
				)
			)
		)
	)
	(zone
		(layers "B.Cu" "In6.Cu" "In11.Cu" "In13.Cu" "In15.Cu")
		(hatch none 0.5)
		(connect_pads
			(clearance 0)
		)
		(min_thickness 0.25)
		(keepout
			(tracks not_allowed)
			(vias allowed)
			(pads allowed)
			(copperpour not_allowed)
			(footprints allowed)
		)
		(placement
			(enabled no)
			(sheetname "")
		)
		(fill yes
			(thermal_gap 0.5)
			(thermal_bridge_width 0.5)
			(island_removal_mode 0)
		)
		(polygon
			(pts
				(arc
					(start 123.606306 -385.31038)
					(mid 122.976386 -385.31038)
					(end 123.606306 -385.31038)
				)
			)
		)
	)
	(zone
		(layers "B.Cu" "In6.Cu" "In11.Cu" "In13.Cu" "In15.Cu")
		(hatch none 0.5)
		(connect_pads
			(clearance 0)
		)
		(min_thickness 0.25)
		(keepout
			(tracks not_allowed)
			(vias allowed)
			(pads allowed)
			(copperpour not_allowed)
			(footprints allowed)
		)
		(placement
			(enabled no)
			(sheetname "")
		)
		(fill yes
			(thermal_gap 0.5)
			(thermal_bridge_width 0.5)
			(island_removal_mode 0)
		)
		(polygon
			(pts
				(arc
					(start 33.029906 -299.335444)
					(mid 32.361886 -299.335444)
					(end 33.029906 -299.335444)
				)
			)
		)
	)
	(zone
		(layers "B.Cu" "In6.Cu" "In11.Cu" "In13.Cu" "In15.Cu")
		(hatch none 0.5)
		(connect_pads
			(clearance 0)
		)
		(min_thickness 0.25)
		(keepout
			(tracks not_allowed)
			(vias allowed)
			(pads allowed)
			(copperpour not_allowed)
			(footprints allowed)
		)
		(placement
			(enabled no)
			(sheetname "")
		)
		(fill yes
			(thermal_gap 0.5)
			(thermal_bridge_width 0.5)
			(island_removal_mode 0)
		)
		(polygon
			(pts
				(arc
					(start 98.936048 -233.144314)
					(mid 98.306128 -233.144314)
					(end 98.936048 -233.144314)
				)
			)
		)
	)
	(zone
		(layers "B.Cu" "In6.Cu" "In11.Cu" "In13.Cu" "In15.Cu")
		(hatch none 0.5)
		(connect_pads
			(clearance 0)
		)
		(min_thickness 0.25)
		(keepout
			(tracks not_allowed)
			(vias allowed)
			(pads allowed)
			(copperpour not_allowed)
			(footprints allowed)
		)
		(placement
			(enabled no)
			(sheetname "")
		)
		(fill yes
			(thermal_gap 0.5)
			(thermal_bridge_width 0.5)
			(island_removal_mode 0)
		)
		(polygon
			(pts
				(arc
					(start 413.733996 -397.849344)
					(mid 413.104076 -397.849344)
					(end 413.733996 -397.849344)
				)
			)
		)
	)
	(zone
		(layers "B.Cu" "In6.Cu" "In11.Cu" "In13.Cu" "In15.Cu")
		(hatch none 0.5)
		(connect_pads
			(clearance 0)
		)
		(min_thickness 0.25)
		(keepout
			(tracks not_allowed)
			(vias allowed)
			(pads allowed)
			(copperpour not_allowed)
			(footprints allowed)
		)
		(placement
			(enabled no)
			(sheetname "")
		)
		(fill yes
			(thermal_gap 0.5)
			(thermal_bridge_width 0.5)
			(island_removal_mode 0)
		)
		(polygon
			(pts
				(arc
					(start 435.334156 -226.235006)
					(mid 434.666136 -226.235006)
					(end 435.334156 -226.235006)
				)
			)
		)
	)
	(zone
		(layers "B.Cu" "In6.Cu" "In11.Cu" "In13.Cu" "In15.Cu")
		(hatch none 0.5)
		(connect_pads
			(clearance 0)
		)
		(min_thickness 0.25)
		(keepout
			(tracks not_allowed)
			(vias allowed)
			(pads allowed)
			(copperpour not_allowed)
			(footprints allowed)
		)
		(placement
			(enabled no)
			(sheetname "")
		)
		(fill yes
			(thermal_gap 0.5)
			(thermal_bridge_width 0.5)
			(island_removal_mode 0)
		)
		(polygon
			(pts
				(arc
					(start 338.886038 -233.954066)
					(mid 338.256118 -233.954066)
					(end 338.886038 -233.954066)
				)
			)
		)
	)
	(zone
		(layers "B.Cu" "In6.Cu" "In11.Cu" "In13.Cu" "In15.Cu")
		(hatch none 0.5)
		(connect_pads
			(clearance 0)
		)
		(min_thickness 0.25)
		(keepout
			(tracks not_allowed)
			(vias allowed)
			(pads allowed)
			(copperpour not_allowed)
			(footprints allowed)
		)
		(placement
			(enabled no)
			(sheetname "")
		)
		(fill yes
			(thermal_gap 0.5)
			(thermal_bridge_width 0.5)
			(island_removal_mode 0)
		)
		(polygon
			(pts
				(arc
					(start 37.129974 -287.43529)
					(mid 36.461954 -287.43529)
					(end 37.129974 -287.43529)
				)
			)
		)
	)
	(zone
		(layers "B.Cu" "In6.Cu" "In11.Cu" "In13.Cu" "In15.Cu")
		(hatch none 0.5)
		(connect_pads
			(clearance 0)
		)
		(min_thickness 0.25)
		(keepout
			(tracks not_allowed)
			(vias allowed)
			(pads allowed)
			(copperpour not_allowed)
			(footprints allowed)
		)
		(placement
			(enabled no)
			(sheetname "")
		)
		(fill yes
			(thermal_gap 0.5)
			(thermal_bridge_width 0.5)
			(island_removal_mode 0)
		)
		(polygon
			(pts
				(arc
					(start 340.595966 -284.616144)
					(mid 339.966046 -284.616144)
					(end 340.595966 -284.616144)
				)
			)
		)
	)
	(zone
		(layers "B.Cu" "In6.Cu" "In11.Cu" "In13.Cu" "In15.Cu")
		(hatch none 0.5)
		(connect_pads
			(clearance 0)
		)
		(min_thickness 0.25)
		(keepout
			(tracks not_allowed)
			(vias allowed)
			(pads allowed)
			(copperpour not_allowed)
			(footprints allowed)
		)
		(placement
			(enabled no)
			(sheetname "")
		)
		(fill yes
			(thermal_gap 0.5)
			(thermal_bridge_width 0.5)
			(island_removal_mode 0)
		)
		(polygon
			(pts
				(arc
					(start 435.334156 -316.335156)
					(mid 434.666136 -316.335156)
					(end 435.334156 -316.335156)
				)
			)
		)
	)
	(zone
		(layers "B.Cu" "In6.Cu" "In11.Cu" "In13.Cu" "In15.Cu")
		(hatch none 0.5)
		(connect_pads
			(clearance 0)
		)
		(min_thickness 0.25)
		(keepout
			(tracks not_allowed)
			(vias allowed)
			(pads allowed)
			(copperpour not_allowed)
			(footprints allowed)
		)
		(placement
			(enabled no)
			(sheetname "")
		)
		(fill yes
			(thermal_gap 0.5)
			(thermal_bridge_width 0.5)
			(island_removal_mode 0)
		)
		(polygon
			(pts
				(arc
					(start 347.013276 -412.84652)
					(mid 346.345256 -412.84652)
					(end 347.013276 -412.84652)
				)
			)
		)
	)
	(zone
		(layers "B.Cu" "In6.Cu" "In11.Cu" "In13.Cu" "In15.Cu")
		(hatch none 0.5)
		(connect_pads
			(clearance 0)
		)
		(min_thickness 0.25)
		(keepout
			(tracks not_allowed)
			(vias allowed)
			(pads allowed)
			(copperpour not_allowed)
			(footprints allowed)
		)
		(placement
			(enabled no)
			(sheetname "")
		)
		(fill yes
			(thermal_gap 0.5)
			(thermal_bridge_width 0.5)
			(island_removal_mode 0)
		)
		(polygon
			(pts
				(arc
					(start 372.406164 -393.69238)
					(mid 371.776244 -393.69238)
					(end 372.406164 -393.69238)
				)
			)
		)
	)
	(zone
		(layers "B.Cu" "In6.Cu" "In11.Cu" "In13.Cu" "In15.Cu")
		(hatch none 0.5)
		(connect_pads
			(clearance 0)
		)
		(min_thickness 0.25)
		(keepout
			(tracks not_allowed)
			(vias allowed)
			(pads allowed)
			(copperpour not_allowed)
			(footprints allowed)
		)
		(placement
			(enabled no)
			(sheetname "")
		)
		(fill yes
			(thermal_gap 0.5)
			(thermal_bridge_width 0.5)
			(island_removal_mode 0)
		)
		(polygon
			(pts
				(arc
					(start 339.186012 -267.606018)
					(mid 338.556092 -267.606018)
					(end 339.186012 -267.606018)
				)
			)
		)
	)
	(zone
		(layers "B.Cu" "In6.Cu" "In11.Cu" "In13.Cu" "In15.Cu")
		(hatch none 0.5)
		(connect_pads
			(clearance 0)
		)
		(min_thickness 0.25)
		(keepout
			(tracks not_allowed)
			(vias allowed)
			(pads allowed)
			(copperpour not_allowed)
			(footprints allowed)
		)
		(placement
			(enabled no)
			(sheetname "")
		)
		(fill yes
			(thermal_gap 0.5)
			(thermal_bridge_width 0.5)
			(island_removal_mode 0)
		)
		(polygon
			(pts
				(arc
					(start 133.069838 -289.47618)
					(mid 132.439918 -289.47618)
					(end 133.069838 -289.47618)
				)
			)
		)
	)
	(zone
		(layers "B.Cu" "In6.Cu" "In11.Cu" "In13.Cu" "In15.Cu")
		(hatch none 0.5)
		(connect_pads
			(clearance 0)
		)
		(min_thickness 0.25)
		(keepout
			(tracks not_allowed)
			(vias allowed)
			(pads allowed)
			(copperpour not_allowed)
			(footprints allowed)
		)
		(placement
			(enabled no)
			(sheetname "")
		)
		(fill yes
			(thermal_gap 0.5)
			(thermal_bridge_width 0.5)
			(island_removal_mode 0)
		)
		(polygon
			(pts
				(arc
					(start 339.656166 -284.616144)
					(mid 339.026246 -284.616144)
					(end 339.656166 -284.616144)
				)
			)
		)
	)
	(zone
		(layers "B.Cu" "In6.Cu" "In11.Cu" "In13.Cu" "In15.Cu")
		(hatch none 0.5)
		(connect_pads
			(clearance 0)
		)
		(min_thickness 0.25)
		(keepout
			(tracks not_allowed)
			(vias allowed)
			(pads allowed)
			(copperpour not_allowed)
			(footprints allowed)
		)
		(placement
			(enabled no)
			(sheetname "")
		)
		(fill yes
			(thermal_gap 0.5)
			(thermal_bridge_width 0.5)
			(island_removal_mode 0)
		)
		(polygon
			(pts
				(arc
					(start 132.76961 -233.144314)
					(mid 132.13969 -233.144314)
					(end 132.76961 -233.144314)
				)
			)
		)
	)
	(zone
		(layers "B.Cu" "In6.Cu" "In11.Cu" "In13.Cu" "In15.Cu")
		(hatch none 0.5)
		(connect_pads
			(clearance 0)
		)
		(min_thickness 0.25)
		(keepout
			(tracks not_allowed)
			(vias allowed)
			(pads allowed)
			(copperpour not_allowed)
			(footprints allowed)
		)
		(placement
			(enabled no)
			(sheetname "")
		)
		(fill yes
			(thermal_gap 0.5)
			(thermal_bridge_width 0.5)
			(island_removal_mode 0)
		)
		(polygon
			(pts
				(arc
					(start 367.849658 -291.095938)
					(mid 367.219738 -291.095938)
					(end 367.849658 -291.095938)
				)
			)
		)
	)
	(zone
		(layers "B.Cu" "In6.Cu" "In11.Cu" "In13.Cu" "In15.Cu")
		(hatch none 0.5)
		(connect_pads
			(clearance 0)
		)
		(min_thickness 0.25)
		(keepout
			(tracks not_allowed)
			(vias allowed)
			(pads allowed)
			(copperpour not_allowed)
			(footprints allowed)
		)
		(placement
			(enabled no)
			(sheetname "")
		)
		(fill yes
			(thermal_gap 0.5)
			(thermal_bridge_width 0.5)
			(island_removal_mode 0)
		)
		(polygon
			(pts
				(arc
					(start 187.394088 -293.38524)
					(mid 186.726068 -293.38524)
					(end 187.394088 -293.38524)
				)
			)
		)
	)
	(zone
		(layers "B.Cu" "In6.Cu" "In11.Cu" "In13.Cu" "In15.Cu")
		(hatch none 0.5)
		(connect_pads
			(clearance 0)
		)
		(min_thickness 0.25)
		(keepout
			(tracks not_allowed)
			(vias allowed)
			(pads allowed)
			(copperpour not_allowed)
			(footprints allowed)
		)
		(placement
			(enabled no)
			(sheetname "")
		)
		(fill yes
			(thermal_gap 0.5)
			(thermal_bridge_width 0.5)
			(island_removal_mode 0)
		)
		(polygon
			(pts
				(arc
					(start 341.06612 -288.66592)
					(mid 340.4362 -288.66592)
					(end 341.06612 -288.66592)
				)
			)
		)
	)
	(zone
		(layers "B.Cu" "In6.Cu" "In11.Cu" "In13.Cu" "In15.Cu")
		(hatch none 0.5)
		(connect_pads
			(clearance 0)
		)
		(min_thickness 0.25)
		(keepout
			(tracks not_allowed)
			(vias allowed)
			(pads allowed)
			(copperpour not_allowed)
			(footprints allowed)
		)
		(placement
			(enabled no)
			(sheetname "")
		)
		(fill yes
			(thermal_gap 0.5)
			(thermal_bridge_width 0.5)
			(island_removal_mode 0)
		)
		(polygon
			(pts
				(arc
					(start 187.394088 -285.735268)
					(mid 186.726068 -285.735268)
					(end 187.394088 -285.735268)
				)
			)
		)
	)
	(zone
		(layers "B.Cu" "In6.Cu" "In11.Cu" "In13.Cu" "In15.Cu")
		(hatch none 0.5)
		(connect_pads
			(clearance 0)
		)
		(min_thickness 0.25)
		(keepout
			(tracks not_allowed)
			(vias allowed)
			(pads allowed)
			(copperpour not_allowed)
			(footprints allowed)
		)
		(placement
			(enabled no)
			(sheetname "")
		)
		(fill yes
			(thermal_gap 0.5)
			(thermal_bridge_width 0.5)
			(island_removal_mode 0)
		)
		(polygon
			(pts
				(arc
					(start 130.544316 -404.46452)
					(mid 129.876296 -404.46452)
					(end 130.544316 -404.46452)
				)
			)
		)
	)
	(zone
		(layers "B.Cu" "In6.Cu" "In11.Cu" "In13.Cu" "In15.Cu")
		(hatch none 0.5)
		(connect_pads
			(clearance 0)
		)
		(min_thickness 0.25)
		(keepout
			(tracks not_allowed)
			(vias allowed)
			(pads allowed)
			(copperpour not_allowed)
			(footprints allowed)
		)
		(placement
			(enabled no)
			(sheetname "")
		)
		(fill yes
			(thermal_gap 0.5)
			(thermal_bridge_width 0.5)
			(island_removal_mode 0)
		)
		(polygon
			(pts
				(arc
					(start 131.65963 -277.326344)
					(mid 131.02971 -277.326344)
					(end 131.65963 -277.326344)
				)
			)
		)
	)
	(zone
		(layers "B.Cu" "In6.Cu" "In11.Cu" "In13.Cu" "In15.Cu")
		(hatch none 0.5)
		(connect_pads
			(clearance 0)
		)
		(min_thickness 0.25)
		(keepout
			(tracks not_allowed)
			(vias allowed)
			(pads allowed)
			(copperpour not_allowed)
			(footprints allowed)
		)
		(placement
			(enabled no)
			(sheetname "")
		)
		(fill yes
			(thermal_gap 0.5)
			(thermal_bridge_width 0.5)
			(island_removal_mode 0)
		)
		(polygon
			(pts
				(arc
					(start 319.70599 -397.156432)
					(mid 319.07607 -397.156432)
					(end 319.70599 -397.156432)
				)
			)
		)
	)
	(zone
		(layers "B.Cu" "In6.Cu" "In11.Cu" "In13.Cu" "In15.Cu")
		(hatch none 0.5)
		(connect_pads
			(clearance 0)
		)
		(min_thickness 0.25)
		(keepout
			(tracks not_allowed)
			(vias allowed)
			(pads allowed)
			(copperpour not_allowed)
			(footprints allowed)
		)
		(placement
			(enabled no)
			(sheetname "")
		)
		(fill yes
			(thermal_gap 0.5)
			(thermal_bridge_width 0.5)
			(island_removal_mode 0)
		)
		(polygon
			(pts
				(arc
					(start 104.139492 -376.093228)
					(mid 103.471472 -376.093228)
					(end 104.139492 -376.093228)
				)
			)
		)
	)
	(zone
		(layers "B.Cu" "In6.Cu" "In11.Cu" "In13.Cu" "In15.Cu")
		(hatch none 0.5)
		(connect_pads
			(clearance 0)
		)
		(min_thickness 0.25)
		(keepout
			(tracks not_allowed)
			(vias allowed)
			(pads allowed)
			(copperpour not_allowed)
			(footprints allowed)
		)
		(placement
			(enabled no)
			(sheetname "")
		)
		(fill yes
			(thermal_gap 0.5)
			(thermal_bridge_width 0.5)
			(island_removal_mode 0)
		)
		(polygon
			(pts
				(arc
					(start 91.245944 -269.226284)
					(mid 90.616024 -269.226284)
					(end 91.245944 -269.226284)
				)
			)
		)
	)
	(zone
		(layers "B.Cu" "In6.Cu" "In11.Cu" "In13.Cu" "In15.Cu")
		(hatch none 0.5)
		(connect_pads
			(clearance 0)
		)
		(min_thickness 0.25)
		(keepout
			(tracks not_allowed)
			(vias allowed)
			(pads allowed)
			(copperpour not_allowed)
			(footprints allowed)
		)
		(placement
			(enabled no)
			(sheetname "")
		)
		(fill yes
			(thermal_gap 0.5)
			(thermal_bridge_width 0.5)
			(island_removal_mode 0)
		)
		(polygon
			(pts
				(arc
					(start 407.333958 -397.156432)
					(mid 406.704038 -397.156432)
					(end 407.333958 -397.156432)
				)
			)
		)
	)
	(zone
		(layers "B.Cu" "In6.Cu" "In11.Cu" "In13.Cu" "In15.Cu")
		(hatch none 0.5)
		(connect_pads
			(clearance 0)
		)
		(min_thickness 0.25)
		(keepout
			(tracks not_allowed)
			(vias allowed)
			(pads allowed)
			(copperpour not_allowed)
			(footprints allowed)
		)
		(placement
			(enabled no)
			(sheetname "")
		)
		(fill yes
			(thermal_gap 0.5)
			(thermal_bridge_width 0.5)
			(island_removal_mode 0)
		)
		(polygon
			(pts
				(arc
					(start 285.070042 -233.035094)
					(mid 284.402022 -233.035094)
					(end 285.070042 -233.035094)
				)
			)
		)
	)
	(zone
		(layers "B.Cu" "In6.Cu" "In11.Cu" "In13.Cu" "In15.Cu")
		(hatch none 0.5)
		(connect_pads
			(clearance 0)
		)
		(min_thickness 0.25)
		(keepout
			(tracks not_allowed)
			(vias allowed)
			(pads allowed)
			(copperpour not_allowed)
			(footprints allowed)
		)
		(placement
			(enabled no)
			(sheetname "")
		)
		(fill yes
			(thermal_gap 0.5)
			(thermal_bridge_width 0.5)
			(island_removal_mode 0)
		)
		(polygon
			(pts
				(arc
					(start 91.245944 -267.606272)
					(mid 90.616024 -267.606272)
					(end 91.245944 -267.606272)
				)
			)
		)
	)
	(zone
		(layers "B.Cu" "In6.Cu" "In11.Cu" "In13.Cu" "In15.Cu")
		(hatch none 0.5)
		(connect_pads
			(clearance 0)
		)
		(min_thickness 0.25)
		(keepout
			(tracks not_allowed)
			(vias allowed)
			(pads allowed)
			(copperpour not_allowed)
			(footprints allowed)
		)
		(placement
			(enabled no)
			(sheetname "")
		)
		(fill yes
			(thermal_gap 0.5)
			(thermal_bridge_width 0.5)
			(island_removal_mode 0)
		)
		(polygon
			(pts
				(arc
					(start 99.236022 -286.23641)
					(mid 98.606102 -286.23641)
					(end 99.236022 -286.23641)
				)
			)
		)
	)
	(zone
		(layers "B.Cu" "In6.Cu" "In11.Cu" "In13.Cu" "In15.Cu")
		(hatch none 0.5)
		(connect_pads
			(clearance 0)
		)
		(min_thickness 0.25)
		(keepout
			(tracks not_allowed)
			(vias allowed)
			(pads allowed)
			(copperpour not_allowed)
			(footprints allowed)
		)
		(placement
			(enabled no)
			(sheetname "")
		)
		(fill yes
			(thermal_gap 0.5)
			(thermal_bridge_width 0.5)
			(island_removal_mode 0)
		)
		(polygon
			(pts
				(arc
					(start 33.029906 -201.585322)
					(mid 32.361886 -201.585322)
					(end 33.029906 -201.585322)
				)
			)
		)
	)
	(zone
		(layers "B.Cu" "In6.Cu" "In11.Cu" "In13.Cu" "In15.Cu")
		(hatch none 0.5)
		(connect_pads
			(clearance 0)
		)
		(min_thickness 0.25)
		(keepout
			(tracks not_allowed)
			(vias allowed)
			(pads allowed)
			(copperpour not_allowed)
			(footprints allowed)
		)
		(placement
			(enabled no)
			(sheetname "")
		)
		(fill yes
			(thermal_gap 0.5)
			(thermal_bridge_width 0.5)
			(island_removal_mode 0)
		)
		(polygon
			(pts
				(arc
					(start 131.65963 -272.466308)
					(mid 131.02971 -272.466308)
					(end 131.65963 -272.466308)
				)
			)
		)
	)
	(zone
		(layers "B.Cu" "In6.Cu" "In11.Cu" "In13.Cu" "In15.Cu")
		(hatch none 0.5)
		(connect_pads
			(clearance 0)
		)
		(min_thickness 0.25)
		(keepout
			(tracks not_allowed)
			(vias allowed)
			(pads allowed)
			(copperpour not_allowed)
			(footprints allowed)
		)
		(placement
			(enabled no)
			(sheetname "")
		)
		(fill yes
			(thermal_gap 0.5)
			(thermal_bridge_width 0.5)
			(island_removal_mode 0)
		)
		(polygon
			(pts
				(arc
					(start 100.815902 -233.144314)
					(mid 100.185982 -233.144314)
					(end 100.815902 -233.144314)
				)
			)
		)
	)
	(zone
		(layers "B.Cu" "In6.Cu" "In11.Cu" "In13.Cu" "In15.Cu")
		(hatch none 0.5)
		(connect_pads
			(clearance 0)
		)
		(min_thickness 0.25)
		(keepout
			(tracks not_allowed)
			(vias allowed)
			(pads allowed)
			(copperpour not_allowed)
			(footprints allowed)
		)
		(placement
			(enabled no)
			(sheetname "")
		)
		(fill yes
			(thermal_gap 0.5)
			(thermal_bridge_width 0.5)
			(island_removal_mode 0)
		)
		(polygon
			(pts
				(arc
					(start 37.129974 -284.885384)
					(mid 36.461954 -284.885384)
					(end 37.129974 -284.885384)
				)
			)
		)
	)
	(zone
		(layers "B.Cu" "In6.Cu" "In11.Cu" "In13.Cu" "In15.Cu")
		(hatch none 0.5)
		(connect_pads
			(clearance 0)
		)
		(min_thickness 0.25)
		(keepout
			(tracks not_allowed)
			(vias allowed)
			(pads allowed)
			(copperpour not_allowed)
			(footprints allowed)
		)
		(placement
			(enabled no)
			(sheetname "")
		)
		(fill yes
			(thermal_gap 0.5)
			(thermal_bridge_width 0.5)
			(island_removal_mode 0)
		)
		(polygon
			(pts
				(arc
					(start 33.029906 -288.285428)
					(mid 32.361886 -288.285428)
					(end 33.029906 -288.285428)
				)
			)
		)
	)
	(zone
		(layers "B.Cu" "In6.Cu" "In11.Cu" "In13.Cu" "In15.Cu")
		(hatch none 0.5)
		(connect_pads
			(clearance 0)
		)
		(min_thickness 0.25)
		(keepout
			(tracks not_allowed)
			(vias allowed)
			(pads allowed)
			(copperpour not_allowed)
			(footprints allowed)
		)
		(placement
			(enabled no)
			(sheetname "")
		)
		(fill yes
			(thermal_gap 0.5)
			(thermal_bridge_width 0.5)
			(island_removal_mode 0)
		)
		(polygon
			(pts
				(arc
					(start 439.434224 -223.6851)
					(mid 438.766204 -223.6851)
					(end 439.434224 -223.6851)
				)
			)
		)
	)
	(zone
		(layers "B.Cu" "In6.Cu" "In11.Cu" "In13.Cu" "In15.Cu")
		(hatch none 0.5)
		(connect_pads
			(clearance 0)
		)
		(min_thickness 0.25)
		(keepout
			(tracks not_allowed)
			(vias allowed)
			(pads allowed)
			(copperpour not_allowed)
			(footprints allowed)
		)
		(placement
			(enabled no)
			(sheetname "")
		)
		(fill yes
			(thermal_gap 0.5)
			(thermal_bridge_width 0.5)
			(island_removal_mode 0)
		)
		(polygon
			(pts
				(arc
					(start 23.813262 -6.725158)
					(mid 23.145242 -6.725158)
					(end 23.813262 -6.725158)
				)
			)
		)
	)
	(zone
		(layers "B.Cu" "In6.Cu" "In11.Cu" "In13.Cu" "In15.Cu")
		(hatch none 0.5)
		(connect_pads
			(clearance 0)
		)
		(min_thickness 0.25)
		(keepout
			(tracks not_allowed)
			(vias allowed)
			(pads allowed)
			(copperpour not_allowed)
			(footprints allowed)
		)
		(placement
			(enabled no)
			(sheetname "")
		)
		(fill yes
			(thermal_gap 0.5)
			(thermal_bridge_width 0.5)
			(island_removal_mode 0)
		)
		(polygon
			(pts
				(arc
					(start 381.179832 -237.19409)
					(mid 380.549912 -237.19409)
					(end 381.179832 -237.19409)
				)
			)
		)
	)
	(zone
		(layers "B.Cu" "In6.Cu" "In11.Cu" "In13.Cu" "In15.Cu")
		(hatch none 0.5)
		(connect_pads
			(clearance 0)
		)
		(min_thickness 0.25)
		(keepout
			(tracks not_allowed)
			(vias allowed)
			(pads allowed)
			(copperpour not_allowed)
			(footprints allowed)
		)
		(placement
			(enabled no)
			(sheetname "")
		)
		(fill yes
			(thermal_gap 0.5)
			(thermal_bridge_width 0.5)
			(island_removal_mode 0)
		)
		(polygon
			(pts
				(arc
					(start 381.179832 -235.574078)
					(mid 380.549912 -235.574078)
					(end 381.179832 -235.574078)
				)
			)
		)
	)
	(zone
		(layers "B.Cu" "In6.Cu" "In11.Cu" "In13.Cu" "In15.Cu")
		(hatch none 0.5)
		(connect_pads
			(clearance 0)
		)
		(min_thickness 0.25)
		(keepout
			(tracks not_allowed)
			(vias allowed)
			(pads allowed)
			(copperpour not_allowed)
			(footprints allowed)
		)
		(placement
			(enabled no)
			(sheetname "")
		)
		(fill yes
			(thermal_gap 0.5)
			(thermal_bridge_width 0.5)
			(island_removal_mode 0)
		)
		(polygon
			(pts
				(arc
					(start 33.029906 -254.285242)
					(mid 32.361886 -254.285242)
					(end 33.029906 -254.285242)
				)
			)
		)
	)
	(zone
		(layers "B.Cu" "In6.Cu" "In11.Cu" "In13.Cu" "In15.Cu")
		(hatch none 0.5)
		(connect_pads
			(clearance 0)
		)
		(min_thickness 0.25)
		(keepout
			(tracks not_allowed)
			(vias allowed)
			(pads allowed)
			(copperpour not_allowed)
			(footprints allowed)
		)
		(placement
			(enabled no)
			(sheetname "")
		)
		(fill yes
			(thermal_gap 0.5)
			(thermal_bridge_width 0.5)
			(island_removal_mode 0)
		)
		(polygon
			(pts
				(arc
					(start 131.82981 -236.384338)
					(mid 131.19989 -236.384338)
					(end 131.82981 -236.384338)
				)
			)
		)
	)
	(zone
		(layers "B.Cu" "In6.Cu" "In11.Cu" "In13.Cu" "In15.Cu")
		(hatch none 0.5)
		(connect_pads
			(clearance 0)
		)
		(min_thickness 0.25)
		(keepout
			(tracks not_allowed)
			(vias allowed)
			(pads allowed)
			(copperpour not_allowed)
			(footprints allowed)
		)
		(placement
			(enabled no)
			(sheetname "")
		)
		(fill yes
			(thermal_gap 0.5)
			(thermal_bridge_width 0.5)
			(island_removal_mode 0)
		)
		(polygon
			(pts
				(arc
					(start 33.029906 -280.635202)
					(mid 32.361886 -280.635202)
					(end 33.029906 -280.635202)
				)
			)
		)
	)
	(zone
		(layers "B.Cu" "In6.Cu" "In11.Cu" "In13.Cu" "In15.Cu")
		(hatch none 0.5)
		(connect_pads
			(clearance 0)
		)
		(min_thickness 0.25)
		(keepout
			(tracks not_allowed)
			(vias allowed)
			(pads allowed)
			(copperpour not_allowed)
			(footprints allowed)
		)
		(placement
			(enabled no)
			(sheetname "")
		)
		(fill yes
			(thermal_gap 0.5)
			(thermal_bridge_width 0.5)
			(island_removal_mode 0)
		)
		(polygon
			(pts
				(arc
					(start 122.406156 -385.31038)
					(mid 121.776236 -385.31038)
					(end 122.406156 -385.31038)
				)
			)
		)
	)
	(zone
		(layers "B.Cu" "In6.Cu" "In11.Cu" "In13.Cu" "In15.Cu")
		(hatch none 0.5)
		(connect_pads
			(clearance 0)
		)
		(min_thickness 0.25)
		(keepout
			(tracks not_allowed)
			(vias allowed)
			(pads allowed)
			(copperpour not_allowed)
			(footprints allowed)
		)
		(placement
			(enabled no)
			(sheetname "")
		)
		(fill yes
			(thermal_gap 0.5)
			(thermal_bridge_width 0.5)
			(island_removal_mode 0)
		)
		(polygon
			(pts
				(arc
					(start 120.54967 -228.284532)
					(mid 119.91975 -228.284532)
					(end 120.54967 -228.284532)
				)
			)
		)
	)
	(zone
		(layers "B.Cu" "In6.Cu" "In11.Cu" "In13.Cu" "In15.Cu")
		(hatch none 0.5)
		(connect_pads
			(clearance 0)
		)
		(min_thickness 0.25)
		(keepout
			(tracks not_allowed)
			(vias allowed)
			(pads allowed)
			(copperpour not_allowed)
			(footprints allowed)
		)
		(placement
			(enabled no)
			(sheetname "")
		)
		(fill yes
			(thermal_gap 0.5)
			(thermal_bridge_width 0.5)
			(island_removal_mode 0)
		)
		(polygon
			(pts
				(arc
					(start 439.434224 -276.38502)
					(mid 438.766204 -276.38502)
					(end 439.434224 -276.38502)
				)
			)
		)
	)
	(zone
		(layers "B.Cu" "In6.Cu" "In11.Cu" "In13.Cu" "In15.Cu")
		(hatch none 0.5)
		(connect_pads
			(clearance 0)
		)
		(min_thickness 0.25)
		(keepout
			(tracks not_allowed)
			(vias allowed)
			(pads allowed)
			(copperpour not_allowed)
			(footprints allowed)
		)
		(placement
			(enabled no)
			(sheetname "")
		)
		(fill yes
			(thermal_gap 0.5)
			(thermal_bridge_width 0.5)
			(island_removal_mode 0)
		)
		(polygon
			(pts
				(arc
					(start 131.82981 -247.724422)
					(mid 131.19989 -247.724422)
					(end 131.82981 -247.724422)
				)
			)
		)
	)
	(zone
		(layers "B.Cu" "In6.Cu" "In11.Cu" "In13.Cu" "In15.Cu")
		(hatch none 0.5)
		(connect_pads
			(clearance 0)
		)
		(min_thickness 0.25)
		(keepout
			(tracks not_allowed)
			(vias allowed)
			(pads allowed)
			(copperpour not_allowed)
			(footprints allowed)
		)
		(placement
			(enabled no)
			(sheetname "")
		)
		(fill yes
			(thermal_gap 0.5)
			(thermal_bridge_width 0.5)
			(island_removal_mode 0)
		)
		(polygon
			(pts
				(arc
					(start 126.489714 -289.47618)
					(mid 125.859794 -289.47618)
					(end 126.489714 -289.47618)
				)
			)
		)
	)
	(zone
		(layers "B.Cu" "In6.Cu" "In11.Cu" "In13.Cu" "In15.Cu")
		(hatch none 0.5)
		(connect_pads
			(clearance 0)
		)
		(min_thickness 0.25)
		(keepout
			(tracks not_allowed)
			(vias allowed)
			(pads allowed)
			(copperpour not_allowed)
			(footprints allowed)
		)
		(placement
			(enabled no)
			(sheetname "")
		)
		(fill yes
			(thermal_gap 0.5)
			(thermal_bridge_width 0.5)
			(island_removal_mode 0)
		)
		(polygon
			(pts
				(arc
					(start 435.334156 -204.134974)
					(mid 434.666136 -204.134974)
					(end 435.334156 -204.134974)
				)
			)
		)
	)
	(zone
		(layers "B.Cu" "In6.Cu" "In11.Cu" "In13.Cu" "In15.Cu")
		(hatch none 0.5)
		(connect_pads
			(clearance 0)
		)
		(min_thickness 0.25)
		(keepout
			(tracks not_allowed)
			(vias allowed)
			(pads allowed)
			(copperpour not_allowed)
			(footprints allowed)
		)
		(placement
			(enabled no)
			(sheetname "")
		)
		(fill yes
			(thermal_gap 0.5)
			(thermal_bridge_width 0.5)
			(island_removal_mode 0)
		)
		(polygon
			(pts
				(arc
					(start 93.126052 -288.666174)
					(mid 92.496132 -288.666174)
					(end 93.126052 -288.666174)
				)
			)
		)
	)
	(zone
		(layers "B.Cu" "In6.Cu" "In11.Cu" "In13.Cu" "In15.Cu")
		(hatch none 0.5)
		(connect_pads
			(clearance 0)
		)
		(min_thickness 0.25)
		(keepout
			(tracks not_allowed)
			(vias allowed)
			(pads allowed)
			(copperpour not_allowed)
			(footprints allowed)
		)
		(placement
			(enabled no)
			(sheetname "")
		)
		(fill yes
			(thermal_gap 0.5)
			(thermal_bridge_width 0.5)
			(island_removal_mode 0)
		)
		(polygon
			(pts
				(arc
					(start 131.82981 -254.20447)
					(mid 131.19989 -254.20447)
					(end 131.82981 -254.20447)
				)
			)
		)
	)
	(zone
		(layers "B.Cu" "In6.Cu" "In11.Cu" "In13.Cu" "In15.Cu")
		(hatch none 0.5)
		(connect_pads
			(clearance 0)
		)
		(min_thickness 0.25)
		(keepout
			(tracks not_allowed)
			(vias allowed)
			(pads allowed)
			(copperpour not_allowed)
			(footprints allowed)
		)
		(placement
			(enabled no)
			(sheetname "")
		)
		(fill yes
			(thermal_gap 0.5)
			(thermal_bridge_width 0.5)
			(island_removal_mode 0)
		)
		(polygon
			(pts
				(arc
					(start 187.394088 -251.735336)
					(mid 186.726068 -251.735336)
					(end 187.394088 -251.735336)
				)
			)
		)
	)
	(zone
		(layers "B.Cu" "In6.Cu" "In11.Cu" "In13.Cu" "In15.Cu")
		(hatch none 0.5)
		(connect_pads
			(clearance 0)
		)
		(min_thickness 0.25)
		(keepout
			(tracks not_allowed)
			(vias allowed)
			(pads allowed)
			(copperpour not_allowed)
			(footprints allowed)
		)
		(placement
			(enabled no)
			(sheetname "")
		)
		(fill yes
			(thermal_gap 0.5)
			(thermal_bridge_width 0.5)
			(island_removal_mode 0)
		)
		(polygon
			(pts
				(arc
					(start 381.009906 -271.656048)
					(mid 380.379986 -271.656048)
					(end 381.009906 -271.656048)
				)
			)
		)
	)
	(zone
		(layers "B.Cu" "In6.Cu" "In11.Cu" "In13.Cu" "In15.Cu")
		(hatch none 0.5)
		(connect_pads
			(clearance 0)
		)
		(min_thickness 0.25)
		(keepout
			(tracks not_allowed)
			(vias allowed)
			(pads allowed)
			(copperpour not_allowed)
			(footprints allowed)
		)
		(placement
			(enabled no)
			(sheetname "")
		)
		(fill yes
			(thermal_gap 0.5)
			(thermal_bridge_width 0.5)
			(island_removal_mode 0)
		)
		(polygon
			(pts
				(arc
					(start 33.029906 -301.035212)
					(mid 32.361886 -301.035212)
					(end 33.029906 -301.035212)
				)
			)
		)
	)
	(zone
		(layers "B.Cu" "In6.Cu" "In11.Cu" "In13.Cu" "In15.Cu")
		(hatch none 0.5)
		(connect_pads
			(clearance 0)
		)
		(min_thickness 0.25)
		(keepout
			(tracks not_allowed)
			(vias allowed)
			(pads allowed)
			(copperpour not_allowed)
			(footprints allowed)
		)
		(placement
			(enabled no)
			(sheetname "")
		)
		(fill yes
			(thermal_gap 0.5)
			(thermal_bridge_width 0.5)
			(island_removal_mode 0)
		)
		(polygon
			(pts
				(arc
					(start 374.129808 -234.764072)
					(mid 373.499888 -234.764072)
					(end 374.129808 -234.764072)
				)
			)
		)
	)
	(zone
		(layers "B.Cu" "In6.Cu" "In11.Cu" "In13.Cu" "In15.Cu")
		(hatch none 0.5)
		(connect_pads
			(clearance 0)
		)
		(min_thickness 0.25)
		(keepout
			(tracks not_allowed)
			(vias allowed)
			(pads allowed)
			(copperpour not_allowed)
			(footprints allowed)
		)
		(placement
			(enabled no)
			(sheetname "")
		)
		(fill yes
			(thermal_gap 0.5)
			(thermal_bridge_width 0.5)
			(island_removal_mode 0)
		)
		(polygon
			(pts
				(arc
					(start 187.394088 -274.685252)
					(mid 186.726068 -274.685252)
					(end 187.394088 -274.685252)
				)
			)
		)
	)
	(zone
		(layers "B.Cu" "In6.Cu" "In11.Cu" "In13.Cu" "In15.Cu")
		(hatch none 0.5)
		(connect_pads
			(clearance 0)
		)
		(min_thickness 0.25)
		(keepout
			(tracks not_allowed)
			(vias allowed)
			(pads allowed)
			(copperpour not_allowed)
			(footprints allowed)
		)
		(placement
			(enabled no)
			(sheetname "")
		)
		(fill yes
			(thermal_gap 0.5)
			(thermal_bridge_width 0.5)
			(island_removal_mode 0)
		)
		(polygon
			(pts
				(arc
					(start 162.040316 -404.46452)
					(mid 161.372296 -404.46452)
					(end 162.040316 -404.46452)
				)
			)
		)
	)
	(zone
		(layers "B.Cu" "In6.Cu" "In11.Cu" "In13.Cu" "In15.Cu")
		(hatch none 0.5)
		(connect_pads
			(clearance 0)
		)
		(min_thickness 0.25)
		(keepout
			(tracks not_allowed)
			(vias allowed)
			(pads allowed)
			(copperpour not_allowed)
			(footprints allowed)
		)
		(placement
			(enabled no)
			(sheetname "")
		)
		(fill yes
			(thermal_gap 0.5)
			(thermal_bridge_width 0.5)
			(island_removal_mode 0)
		)
		(polygon
			(pts
				(arc
					(start 285.070042 -301.885096)
					(mid 284.402022 -301.885096)
					(end 285.070042 -301.885096)
				)
			)
		)
	)
	(zone
		(layers "B.Cu" "In6.Cu" "In11.Cu" "In13.Cu" "In15.Cu")
		(hatch none 0.5)
		(connect_pads
			(clearance 0)
		)
		(min_thickness 0.25)
		(keepout
			(tracks not_allowed)
			(vias allowed)
			(pads allowed)
			(copperpour not_allowed)
			(footprints allowed)
		)
		(placement
			(enabled no)
			(sheetname "")
		)
		(fill yes
			(thermal_gap 0.5)
			(thermal_bridge_width 0.5)
			(island_removal_mode 0)
		)
		(polygon
			(pts
				(arc
					(start 408.533854 -397.156432)
					(mid 407.903934 -397.156432)
					(end 408.533854 -397.156432)
				)
			)
		)
	)
	(zone
		(layers "B.Cu" "In6.Cu" "In11.Cu" "In13.Cu" "In15.Cu")
		(hatch none 0.5)
		(connect_pads
			(clearance 0)
		)
		(min_thickness 0.25)
		(keepout
			(tracks not_allowed)
			(vias allowed)
			(pads allowed)
			(copperpour not_allowed)
			(footprints allowed)
		)
		(placement
			(enabled no)
			(sheetname "")
		)
		(fill yes
			(thermal_gap 0.5)
			(thermal_bridge_width 0.5)
			(island_removal_mode 0)
		)
		(polygon
			(pts
				(arc
					(start 285.070042 -311.23509)
					(mid 284.402022 -311.23509)
					(end 285.070042 -311.23509)
				)
			)
		)
	)
	(zone
		(layers "B.Cu" "In6.Cu" "In11.Cu" "In13.Cu" "In15.Cu")
		(hatch none 0.5)
		(connect_pads
			(clearance 0)
		)
		(min_thickness 0.25)
		(keepout
			(tracks not_allowed)
			(vias allowed)
			(pads allowed)
			(copperpour not_allowed)
			(footprints allowed)
		)
		(placement
			(enabled no)
			(sheetname "")
		)
		(fill yes
			(thermal_gap 0.5)
			(thermal_bridge_width 0.5)
			(island_removal_mode 0)
		)
		(polygon
			(pts
				(arc
					(start 317.705994 -397.849344)
					(mid 317.076074 -397.849344)
					(end 317.705994 -397.849344)
				)
			)
		)
	)
	(zone
		(layers "B.Cu" "In6.Cu" "In11.Cu" "In13.Cu" "In15.Cu")
		(hatch none 0.5)
		(connect_pads
			(clearance 0)
		)
		(min_thickness 0.25)
		(keepout
			(tracks not_allowed)
			(vias allowed)
			(pads allowed)
			(copperpour not_allowed)
			(footprints allowed)
		)
		(placement
			(enabled no)
			(sheetname "")
		)
		(fill yes
			(thermal_gap 0.5)
			(thermal_bridge_width 0.5)
			(island_removal_mode 0)
		)
		(polygon
			(pts
				(arc
					(start 381.009906 -289.475926)
					(mid 380.379986 -289.475926)
					(end 381.009906 -289.475926)
				)
			)
		)
	)
	(zone
		(layers "B.Cu" "In6.Cu" "In11.Cu" "In13.Cu" "In15.Cu")
		(hatch none 0.5)
		(connect_pads
			(clearance 0)
		)
		(min_thickness 0.25)
		(keepout
			(tracks not_allowed)
			(vias allowed)
			(pads allowed)
			(copperpour not_allowed)
			(footprints allowed)
		)
		(placement
			(enabled no)
			(sheetname "")
		)
		(fill yes
			(thermal_gap 0.5)
			(thermal_bridge_width 0.5)
			(island_removal_mode 0)
		)
		(polygon
			(pts
				(arc
					(start 381.009906 -292.71595)
					(mid 380.379986 -292.71595)
					(end 381.009906 -292.71595)
				)
			)
		)
	)
	(zone
		(layers "B.Cu" "In6.Cu" "In11.Cu" "In13.Cu" "In15.Cu")
		(hatch none 0.5)
		(connect_pads
			(clearance 0)
		)
		(min_thickness 0.25)
		(keepout
			(tracks not_allowed)
			(vias allowed)
			(pads allowed)
			(copperpour not_allowed)
			(footprints allowed)
		)
		(placement
			(enabled no)
			(sheetname "")
		)
		(fill yes
			(thermal_gap 0.5)
			(thermal_bridge_width 0.5)
			(island_removal_mode 0)
		)
		(polygon
			(pts
				(arc
					(start 93.126052 -283.806392)
					(mid 92.496132 -283.806392)
					(end 93.126052 -283.806392)
				)
			)
		)
	)
	(zone
		(layers "B.Cu" "In6.Cu" "In11.Cu" "In13.Cu" "In15.Cu")
		(hatch none 0.5)
		(connect_pads
			(clearance 0)
		)
		(min_thickness 0.25)
		(keepout
			(tracks not_allowed)
			(vias allowed)
			(pads allowed)
			(copperpour not_allowed)
			(footprints allowed)
		)
		(placement
			(enabled no)
			(sheetname "")
		)
		(fill yes
			(thermal_gap 0.5)
			(thermal_bridge_width 0.5)
			(island_removal_mode 0)
		)
		(polygon
			(pts
				(arc
					(start 33.029906 -204.135228)
					(mid 32.361886 -204.135228)
					(end 33.029906 -204.135228)
				)
			)
		)
	)
	(zone
		(layers "B.Cu" "In6.Cu" "In11.Cu" "In13.Cu" "In15.Cu")
		(hatch none 0.5)
		(connect_pads
			(clearance 0)
		)
		(min_thickness 0.25)
		(keepout
			(tracks not_allowed)
			(vias allowed)
			(pads allowed)
			(copperpour not_allowed)
			(footprints allowed)
		)
		(placement
			(enabled no)
			(sheetname "")
		)
		(fill yes
			(thermal_gap 0.5)
			(thermal_bridge_width 0.5)
			(island_removal_mode 0)
		)
		(polygon
			(pts
				(arc
					(start 115.206272 -385.31038)
					(mid 114.576352 -385.31038)
					(end 115.206272 -385.31038)
				)
			)
		)
	)
	(zone
		(layers "B.Cu" "In6.Cu" "In11.Cu" "In13.Cu" "In15.Cu")
		(hatch none 0.5)
		(connect_pads
			(clearance 0)
		)
		(min_thickness 0.25)
		(keepout
			(tracks not_allowed)
			(vias allowed)
			(pads allowed)
			(copperpour not_allowed)
			(footprints allowed)
		)
		(placement
			(enabled no)
			(sheetname "")
		)
		(fill yes
			(thermal_gap 0.5)
			(thermal_bridge_width 0.5)
			(island_removal_mode 0)
		)
		(polygon
			(pts
				(arc
					(start 354.863654 -377.41733)
					(mid 354.195634 -377.41733)
					(end 354.863654 -377.41733)
				)
			)
		)
	)
	(zone
		(layers "B.Cu" "In6.Cu" "In11.Cu" "In13.Cu" "In15.Cu")
		(hatch none 0.5)
		(connect_pads
			(clearance 0)
		)
		(min_thickness 0.25)
		(keepout
			(tracks not_allowed)
			(vias allowed)
			(pads allowed)
			(copperpour not_allowed)
			(footprints allowed)
		)
		(placement
			(enabled no)
			(sheetname "")
		)
		(fill yes
			(thermal_gap 0.5)
			(thermal_bridge_width 0.5)
			(island_removal_mode 0)
		)
		(polygon
			(pts
				(arc
					(start 131.65963 -283.806392)
					(mid 131.02971 -283.806392)
					(end 131.65963 -283.806392)
				)
			)
		)
	)
	(zone
		(layers "B.Cu" "In6.Cu" "In11.Cu" "In13.Cu" "In15.Cu")
		(hatch none 0.5)
		(connect_pads
			(clearance 0)
		)
		(min_thickness 0.25)
		(keepout
			(tracks not_allowed)
			(vias allowed)
			(pads allowed)
			(copperpour not_allowed)
			(footprints allowed)
		)
		(placement
			(enabled no)
			(sheetname "")
		)
		(fill yes
			(thermal_gap 0.5)
			(thermal_bridge_width 0.5)
			(island_removal_mode 0)
		)
		(polygon
			(pts
				(arc
					(start 93.126052 -290.286186)
					(mid 92.496132 -290.286186)
					(end 93.126052 -290.286186)
				)
			)
		)
	)
	(zone
		(layers "B.Cu" "In6.Cu" "In11.Cu" "In13.Cu" "In15.Cu")
		(hatch none 0.5)
		(connect_pads
			(clearance 0)
		)
		(min_thickness 0.25)
		(keepout
			(tracks not_allowed)
			(vias allowed)
			(pads allowed)
			(copperpour not_allowed)
			(footprints allowed)
		)
		(placement
			(enabled no)
			(sheetname "")
		)
		(fill yes
			(thermal_gap 0.5)
			(thermal_bridge_width 0.5)
			(island_removal_mode 0)
		)
		(polygon
			(pts
				(arc
					(start 132.129784 -266.796266)
					(mid 131.499864 -266.796266)
					(end 132.129784 -266.796266)
				)
			)
		)
	)
	(zone
		(layers "B.Cu" "In6.Cu" "In11.Cu" "In13.Cu" "In15.Cu")
		(hatch none 0.5)
		(connect_pads
			(clearance 0)
		)
		(min_thickness 0.25)
		(keepout
			(tracks not_allowed)
			(vias allowed)
			(pads allowed)
			(copperpour not_allowed)
			(footprints allowed)
		)
		(placement
			(enabled no)
			(sheetname "")
		)
		(fill yes
			(thermal_gap 0.5)
			(thermal_bridge_width 0.5)
			(island_removal_mode 0)
		)
		(polygon
			(pts
				(arc
					(start 133.539738 -287.046162)
					(mid 132.909818 -287.046162)
					(end 133.539738 -287.046162)
				)
			)
		)
	)
	(zone
		(layers "B.Cu" "In6.Cu" "In11.Cu" "In13.Cu" "In15.Cu")
		(hatch none 0.5)
		(connect_pads
			(clearance 0)
		)
		(min_thickness 0.25)
		(keepout
			(tracks not_allowed)
			(vias allowed)
			(pads allowed)
			(copperpour not_allowed)
			(footprints allowed)
		)
		(placement
			(enabled no)
			(sheetname "")
		)
		(fill yes
			(thermal_gap 0.5)
			(thermal_bridge_width 0.5)
			(island_removal_mode 0)
		)
		(polygon
			(pts
				(arc
					(start 92.655898 -292.716204)
					(mid 92.025978 -292.716204)
					(end 92.655898 -292.716204)
				)
			)
		)
	)
	(zone
		(layers "B.Cu" "In6.Cu" "In11.Cu" "In13.Cu" "In15.Cu")
		(hatch none 0.5)
		(connect_pads
			(clearance 0)
		)
		(min_thickness 0.25)
		(keepout
			(tracks not_allowed)
			(vias allowed)
			(pads allowed)
			(copperpour not_allowed)
			(footprints allowed)
		)
		(placement
			(enabled no)
			(sheetname "")
		)
		(fill yes
			(thermal_gap 0.5)
			(thermal_bridge_width 0.5)
			(island_removal_mode 0)
		)
		(polygon
			(pts
				(arc
					(start 191.494156 -281.48534)
					(mid 190.826136 -281.48534)
					(end 191.494156 -281.48534)
				)
			)
		)
	)
	(zone
		(layers "B.Cu" "In6.Cu" "In11.Cu" "In13.Cu" "In15.Cu")
		(hatch none 0.5)
		(connect_pads
			(clearance 0)
		)
		(min_thickness 0.25)
		(keepout
			(tracks not_allowed)
			(vias allowed)
			(pads allowed)
			(copperpour not_allowed)
			(footprints allowed)
		)
		(placement
			(enabled no)
			(sheetname "")
		)
		(fill yes
			(thermal_gap 0.5)
			(thermal_bridge_width 0.5)
			(island_removal_mode 0)
		)
		(polygon
			(pts
				(arc
					(start 148.923756 -404.46452)
					(mid 148.255736 -404.46452)
					(end 148.923756 -404.46452)
				)
			)
		)
	)
	(zone
		(layers "B.Cu" "In6.Cu" "In11.Cu" "In13.Cu" "In15.Cu")
		(hatch none 0.5)
		(connect_pads
			(clearance 0)
		)
		(min_thickness 0.25)
		(keepout
			(tracks not_allowed)
			(vias allowed)
			(pads allowed)
			(copperpour not_allowed)
			(footprints allowed)
		)
		(placement
			(enabled no)
			(sheetname "")
		)
		(fill yes
			(thermal_gap 0.5)
			(thermal_bridge_width 0.5)
			(island_removal_mode 0)
		)
		(polygon
			(pts
				(arc
					(start 132.76961 -255.824482)
					(mid 132.13969 -255.824482)
					(end 132.76961 -255.824482)
				)
			)
		)
	)
	(zone
		(layers "B.Cu" "In6.Cu" "In11.Cu" "In13.Cu" "In15.Cu")
		(hatch none 0.5)
		(connect_pads
			(clearance 0)
		)
		(min_thickness 0.25)
		(keepout
			(tracks not_allowed)
			(vias allowed)
			(pads allowed)
			(copperpour not_allowed)
			(footprints allowed)
		)
		(placement
			(enabled no)
			(sheetname "")
		)
		(fill yes
			(thermal_gap 0.5)
			(thermal_bridge_width 0.5)
			(island_removal_mode 0)
		)
		(polygon
			(pts
				(arc
					(start 381.479806 -287.045908)
					(mid 380.849886 -287.045908)
					(end 381.479806 -287.045908)
				)
			)
		)
	)
	(zone
		(layers "B.Cu" "In6.Cu" "In11.Cu" "In13.Cu" "In15.Cu")
		(hatch none 0.5)
		(connect_pads
			(clearance 0)
		)
		(min_thickness 0.25)
		(keepout
			(tracks not_allowed)
			(vias allowed)
			(pads allowed)
			(copperpour not_allowed)
			(footprints allowed)
		)
		(placement
			(enabled no)
			(sheetname "")
		)
		(fill yes
			(thermal_gap 0.5)
			(thermal_bridge_width 0.5)
			(island_removal_mode 0)
		)
		(polygon
			(pts
				(arc
					(start 414.933892 -397.849344)
					(mid 414.303972 -397.849344)
					(end 414.933892 -397.849344)
				)
			)
		)
	)
	(zone
		(layers "B.Cu" "In6.Cu" "In11.Cu" "In13.Cu" "In15.Cu")
		(hatch none 0.5)
		(connect_pads
			(clearance 0)
		)
		(min_thickness 0.25)
		(keepout
			(tracks not_allowed)
			(vias allowed)
			(pads allowed)
			(copperpour not_allowed)
			(footprints allowed)
		)
		(placement
			(enabled no)
			(sheetname "")
		)
		(fill yes
			(thermal_gap 0.5)
			(thermal_bridge_width 0.5)
			(island_removal_mode 0)
		)
		(polygon
			(pts
				(arc
					(start 160.134046 -389.467344)
					(mid 159.504126 -389.467344)
					(end 160.134046 -389.467344)
				)
			)
		)
	)
	(zone
		(layers "B.Cu" "In6.Cu" "In11.Cu" "In13.Cu" "In15.Cu")
		(hatch none 0.5)
		(connect_pads
			(clearance 0)
		)
		(min_thickness 0.25)
		(keepout
			(tracks not_allowed)
			(vias allowed)
			(pads allowed)
			(copperpour not_allowed)
			(footprints allowed)
		)
		(placement
			(enabled no)
			(sheetname "")
		)
		(fill yes
			(thermal_gap 0.5)
			(thermal_bridge_width 0.5)
			(island_removal_mode 0)
		)
		(polygon
			(pts
				(arc
					(start 360.139234 -387.878828)
					(mid 359.471214 -387.878828)
					(end 360.139234 -387.878828)
				)
			)
		)
	)
	(zone
		(layers "B.Cu" "In6.Cu" "In11.Cu" "In13.Cu" "In15.Cu")
		(hatch none 0.5)
		(connect_pads
			(clearance 0)
		)
		(min_thickness 0.25)
		(keepout
			(tracks not_allowed)
			(vias allowed)
			(pads allowed)
			(copperpour not_allowed)
			(footprints allowed)
		)
		(placement
			(enabled no)
			(sheetname "")
		)
		(fill yes
			(thermal_gap 0.5)
			(thermal_bridge_width 0.5)
			(island_removal_mode 0)
		)
		(polygon
			(pts
				(arc
					(start 102.05593 -287.856422)
					(mid 101.42601 -287.856422)
					(end 102.05593 -287.856422)
				)
			)
		)
	)
	(zone
		(layers "B.Cu" "In6.Cu" "In11.Cu" "In13.Cu" "In15.Cu")
		(hatch none 0.5)
		(connect_pads
			(clearance 0)
		)
		(min_thickness 0.25)
		(keepout
			(tracks not_allowed)
			(vias allowed)
			(pads allowed)
			(copperpour not_allowed)
			(footprints allowed)
		)
		(placement
			(enabled no)
			(sheetname "")
		)
		(fill yes
			(thermal_gap 0.5)
			(thermal_bridge_width 0.5)
			(island_removal_mode 0)
		)
		(polygon
			(pts
				(arc
					(start 341.06612 -287.045908)
					(mid 340.4362 -287.045908)
					(end 341.06612 -287.045908)
				)
			)
		)
	)
	(zone
		(layers "B.Cu" "In6.Cu" "In11.Cu" "In13.Cu" "In15.Cu")
		(hatch none 0.5)
		(connect_pads
			(clearance 0)
		)
		(min_thickness 0.25)
		(keepout
			(tracks not_allowed)
			(vias allowed)
			(pads allowed)
			(copperpour not_allowed)
			(footprints allowed)
		)
		(placement
			(enabled no)
			(sheetname "")
		)
		(fill yes
			(thermal_gap 0.5)
			(thermal_bridge_width 0.5)
			(island_removal_mode 0)
		)
		(polygon
			(pts
				(arc
					(start 92.355924 -242.864386)
					(mid 91.726004 -242.864386)
					(end 92.355924 -242.864386)
				)
			)
		)
	)
	(zone
		(layers "B.Cu" "In6.Cu" "In11.Cu" "In13.Cu" "In15.Cu")
		(hatch none 0.5)
		(connect_pads
			(clearance 0)
		)
		(min_thickness 0.25)
		(keepout
			(tracks not_allowed)
			(vias allowed)
			(pads allowed)
			(copperpour not_allowed)
			(footprints allowed)
		)
		(placement
			(enabled no)
			(sheetname "")
		)
		(fill yes
			(thermal_gap 0.5)
			(thermal_bridge_width 0.5)
			(island_removal_mode 0)
		)
		(polygon
			(pts
				(arc
					(start 285.070042 -312.935112)
					(mid 284.402022 -312.935112)
					(end 285.070042 -312.935112)
				)
			)
		)
	)
	(zone
		(layers "B.Cu" "In6.Cu" "In11.Cu" "In13.Cu" "In15.Cu")
		(hatch none 0.5)
		(connect_pads
			(clearance 0)
		)
		(min_thickness 0.25)
		(keepout
			(tracks not_allowed)
			(vias allowed)
			(pads allowed)
			(copperpour not_allowed)
			(footprints allowed)
		)
		(placement
			(enabled no)
			(sheetname "")
		)
		(fill yes
			(thermal_gap 0.5)
			(thermal_bridge_width 0.5)
			(island_removal_mode 0)
		)
		(polygon
			(pts
				(arc
					(start 191.494156 -197.335394)
					(mid 190.826136 -197.335394)
					(end 191.494156 -197.335394)
				)
			)
		)
	)
	(zone
		(layers "B.Cu" "In6.Cu" "In11.Cu" "In13.Cu" "In15.Cu")
		(hatch none 0.5)
		(connect_pads
			(clearance 0)
		)
		(min_thickness 0.25)
		(keepout
			(tracks not_allowed)
			(vias allowed)
			(pads allowed)
			(copperpour not_allowed)
			(footprints allowed)
		)
		(placement
			(enabled no)
			(sheetname "")
		)
		(fill yes
			(thermal_gap 0.5)
			(thermal_bridge_width 0.5)
			(island_removal_mode 0)
		)
		(polygon
			(pts
				(arc
					(start 340.595966 -289.475926)
					(mid 339.966046 -289.475926)
					(end 340.595966 -289.475926)
				)
			)
		)
	)
	(zone
		(layers "B.Cu" "In6.Cu" "In11.Cu" "In13.Cu" "In15.Cu")
		(hatch none 0.5)
		(connect_pads
			(clearance 0)
		)
		(min_thickness 0.25)
		(keepout
			(tracks not_allowed)
			(vias allowed)
			(pads allowed)
			(copperpour not_allowed)
			(footprints allowed)
		)
		(placement
			(enabled no)
			(sheetname "")
		)
		(fill yes
			(thermal_gap 0.5)
			(thermal_bridge_width 0.5)
			(island_removal_mode 0)
		)
		(polygon
			(pts
				(arc
					(start 91.716098 -279.756362)
					(mid 91.086178 -279.756362)
					(end 91.716098 -279.756362)
				)
			)
		)
	)
	(zone
		(layers "B.Cu" "In6.Cu" "In11.Cu" "In13.Cu" "In15.Cu")
		(hatch none 0.5)
		(connect_pads
			(clearance 0)
		)
		(min_thickness 0.25)
		(keepout
			(tracks not_allowed)
			(vias allowed)
			(pads allowed)
			(copperpour not_allowed)
			(footprints allowed)
		)
		(placement
			(enabled no)
			(sheetname "")
		)
		(fill yes
			(thermal_gap 0.5)
			(thermal_bridge_width 0.5)
			(island_removal_mode 0)
		)
		(polygon
			(pts
				(arc
					(start 346.876116 -231.524048)
					(mid 346.246196 -231.524048)
					(end 346.876116 -231.524048)
				)
			)
		)
	)
	(zone
		(layers "B.Cu" "In6.Cu" "In11.Cu" "In13.Cu" "In15.Cu")
		(hatch none 0.5)
		(connect_pads
			(clearance 0)
		)
		(min_thickness 0.25)
		(keepout
			(tracks not_allowed)
			(vias allowed)
			(pads allowed)
			(copperpour not_allowed)
			(footprints allowed)
		)
		(placement
			(enabled no)
			(sheetname "")
		)
		(fill yes
			(thermal_gap 0.5)
			(thermal_bridge_width 0.5)
			(island_removal_mode 0)
		)
		(polygon
			(pts
				(arc
					(start 339.186012 -291.905944)
					(mid 338.556092 -291.905944)
					(end 339.186012 -291.905944)
				)
			)
		)
	)
	(zone
		(layers "B.Cu" "In6.Cu" "In11.Cu" "In13.Cu" "In15.Cu")
		(hatch none 0.5)
		(connect_pads
			(clearance 0)
		)
		(min_thickness 0.25)
		(keepout
			(tracks not_allowed)
			(vias allowed)
			(pads allowed)
			(copperpour not_allowed)
			(footprints allowed)
		)
		(placement
			(enabled no)
			(sheetname "")
		)
		(fill yes
			(thermal_gap 0.5)
			(thermal_bridge_width 0.5)
			(island_removal_mode 0)
		)
		(polygon
			(pts
				(arc
					(start 187.394088 -230.485442)
					(mid 186.726068 -230.485442)
					(end 187.394088 -230.485442)
				)
			)
		)
	)
	(zone
		(layers "B.Cu" "In6.Cu" "In11.Cu" "In13.Cu" "In15.Cu")
		(hatch none 0.5)
		(connect_pads
			(clearance 0)
		)
		(min_thickness 0.25)
		(keepout
			(tracks not_allowed)
			(vias allowed)
			(pads allowed)
			(copperpour not_allowed)
			(footprints allowed)
		)
		(placement
			(enabled no)
			(sheetname "")
		)
		(fill yes
			(thermal_gap 0.5)
			(thermal_bridge_width 0.5)
			(island_removal_mode 0)
		)
		(polygon
			(pts
				(arc
					(start 338.886038 -243.674138)
					(mid 338.256118 -243.674138)
					(end 338.886038 -243.674138)
				)
			)
		)
	)
	(zone
		(layers "B.Cu" "In6.Cu" "In11.Cu" "In13.Cu" "In15.Cu")
		(hatch none 0.5)
		(connect_pads
			(clearance 0)
		)
		(min_thickness 0.25)
		(keepout
			(tracks not_allowed)
			(vias allowed)
			(pads allowed)
			(copperpour not_allowed)
			(footprints allowed)
		)
		(placement
			(enabled no)
			(sheetname "")
		)
		(fill yes
			(thermal_gap 0.5)
			(thermal_bridge_width 0.5)
			(island_removal_mode 0)
		)
		(polygon
			(pts
				(arc
					(start 341.249254 -377.41733)
					(mid 340.581234 -377.41733)
					(end 341.249254 -377.41733)
				)
			)
		)
	)
	(zone
		(layers "B.Cu" "In6.Cu" "In11.Cu" "In13.Cu" "In15.Cu")
		(hatch none 0.5)
		(connect_pads
			(clearance 0)
		)
		(min_thickness 0.25)
		(keepout
			(tracks not_allowed)
			(vias allowed)
			(pads allowed)
			(copperpour not_allowed)
			(footprints allowed)
		)
		(placement
			(enabled no)
			(sheetname "")
		)
		(fill yes
			(thermal_gap 0.5)
			(thermal_bridge_width 0.5)
			(island_removal_mode 0)
		)
		(polygon
			(pts
				(arc
					(start 110.046008 -287.046162)
					(mid 109.416088 -287.046162)
					(end 110.046008 -287.046162)
				)
			)
		)
	)
	(zone
		(layers "B.Cu" "In6.Cu" "In11.Cu" "In13.Cu" "In15.Cu")
		(hatch none 0.5)
		(connect_pads
			(clearance 0)
		)
		(min_thickness 0.25)
		(keepout
			(tracks not_allowed)
			(vias allowed)
			(pads allowed)
			(copperpour not_allowed)
			(footprints allowed)
		)
		(placement
			(enabled no)
			(sheetname "")
		)
		(fill yes
			(thermal_gap 0.5)
			(thermal_bridge_width 0.5)
			(island_removal_mode 0)
		)
		(polygon
			(pts
				(arc
					(start 37.129974 -250.885198)
					(mid 36.461954 -250.885198)
					(end 37.129974 -250.885198)
				)
			)
		)
	)
	(zone
		(layers "B.Cu" "In6.Cu" "In11.Cu" "In13.Cu" "In15.Cu")
		(hatch none 0.5)
		(connect_pads
			(clearance 0)
		)
		(min_thickness 0.25)
		(keepout
			(tracks not_allowed)
			(vias allowed)
			(pads allowed)
			(copperpour not_allowed)
			(footprints allowed)
		)
		(placement
			(enabled no)
			(sheetname "")
		)
		(fill yes
			(thermal_gap 0.5)
			(thermal_bridge_width 0.5)
			(island_removal_mode 0)
		)
		(polygon
			(pts
				(arc
					(start 187.394088 -291.685218)
					(mid 186.726068 -291.685218)
					(end 187.394088 -291.685218)
				)
			)
		)
	)
	(zone
		(layers "B.Cu" "In6.Cu" "In11.Cu" "In13.Cu" "In15.Cu")
		(hatch none 0.5)
		(connect_pads
			(clearance 0)
		)
		(min_thickness 0.25)
		(keepout
			(tracks not_allowed)
			(vias allowed)
			(pads allowed)
			(copperpour not_allowed)
			(footprints allowed)
		)
		(placement
			(enabled no)
			(sheetname "")
		)
		(fill yes
			(thermal_gap 0.5)
			(thermal_bridge_width 0.5)
			(island_removal_mode 0)
		)
		(polygon
			(pts
				(arc
					(start 340.295992 -228.284278)
					(mid 339.666072 -228.284278)
					(end 340.295992 -228.284278)
				)
			)
		)
	)
	(zone
		(layers "B.Cu" "In6.Cu" "In11.Cu" "In13.Cu" "In15.Cu")
		(hatch none 0.5)
		(connect_pads
			(clearance 0)
		)
		(min_thickness 0.25)
		(keepout
			(tracks not_allowed)
			(vias allowed)
			(pads allowed)
			(copperpour not_allowed)
			(footprints allowed)
		)
		(placement
			(enabled no)
			(sheetname "")
		)
		(fill yes
			(thermal_gap 0.5)
			(thermal_bridge_width 0.5)
			(island_removal_mode 0)
		)
		(polygon
			(pts
				(arc
					(start 120.849644 -287.856422)
					(mid 120.219724 -287.856422)
					(end 120.849644 -287.856422)
				)
			)
		)
	)
	(zone
		(layers "B.Cu" "In6.Cu" "In11.Cu" "In13.Cu" "In15.Cu")
		(hatch none 0.5)
		(connect_pads
			(clearance 0)
		)
		(min_thickness 0.25)
		(keepout
			(tracks not_allowed)
			(vias allowed)
			(pads allowed)
			(copperpour not_allowed)
			(footprints allowed)
		)
		(placement
			(enabled no)
			(sheetname "")
		)
		(fill yes
			(thermal_gap 0.5)
			(thermal_bridge_width 0.5)
			(island_removal_mode 0)
		)
		(polygon
			(pts
				(arc
					(start 416.68319 -19.13636)
					(mid 416.01517 -19.13636)
					(end 416.68319 -19.13636)
				)
			)
		)
	)
	(zone
		(layers "B.Cu" "In6.Cu" "In11.Cu" "In13.Cu" "In15.Cu")
		(hatch none 0.5)
		(connect_pads
			(clearance 0)
		)
		(min_thickness 0.25)
		(keepout
			(tracks not_allowed)
			(vias allowed)
			(pads allowed)
			(copperpour not_allowed)
			(footprints allowed)
		)
		(placement
			(enabled no)
			(sheetname "")
		)
		(fill yes
			(thermal_gap 0.5)
			(thermal_bridge_width 0.5)
			(island_removal_mode 0)
		)
		(polygon
			(pts
				(arc
					(start 401.543774 -17.61236)
					(mid 400.875754 -17.61236)
					(end 401.543774 -17.61236)
				)
			)
		)
	)
	(zone
		(layers "B.Cu" "In6.Cu" "In11.Cu" "In13.Cu" "In15.Cu")
		(hatch none 0.5)
		(connect_pads
			(clearance 0)
		)
		(min_thickness 0.25)
		(keepout
			(tracks not_allowed)
			(vias allowed)
			(pads allowed)
			(copperpour not_allowed)
			(footprints allowed)
		)
		(placement
			(enabled no)
			(sheetname "")
		)
		(fill yes
			(thermal_gap 0.5)
			(thermal_bridge_width 0.5)
			(island_removal_mode 0)
		)
		(polygon
			(pts
				(arc
					(start 92.655898 -289.47618)
					(mid 92.025978 -289.47618)
					(end 92.655898 -289.47618)
				)
			)
		)
	)
	(zone
		(layers "B.Cu" "In6.Cu" "In11.Cu" "In13.Cu" "In15.Cu")
		(hatch none 0.5)
		(connect_pads
			(clearance 0)
		)
		(min_thickness 0.25)
		(keepout
			(tracks not_allowed)
			(vias allowed)
			(pads allowed)
			(copperpour not_allowed)
			(footprints allowed)
		)
		(placement
			(enabled no)
			(sheetname "")
		)
		(fill yes
			(thermal_gap 0.5)
			(thermal_bridge_width 0.5)
			(island_removal_mode 0)
		)
		(polygon
			(pts
				(arc
					(start 357.986076 -288.66592)
					(mid 357.356156 -288.66592)
					(end 357.986076 -288.66592)
				)
			)
		)
	)
	(zone
		(layers "B.Cu" "In6.Cu" "In11.Cu" "In13.Cu" "In15.Cu")
		(hatch none 0.5)
		(connect_pads
			(clearance 0)
		)
		(min_thickness 0.25)
		(keepout
			(tracks not_allowed)
			(vias allowed)
			(pads allowed)
			(copperpour not_allowed)
			(footprints allowed)
		)
		(placement
			(enabled no)
			(sheetname "")
		)
		(fill yes
			(thermal_gap 0.5)
			(thermal_bridge_width 0.5)
			(island_removal_mode 0)
		)
		(polygon
			(pts
				(arc
					(start 93.126052 -275.706332)
					(mid 92.496132 -275.706332)
					(end 93.126052 -275.706332)
				)
			)
		)
	)
	(zone
		(layers "B.Cu" "In6.Cu" "In11.Cu" "In13.Cu" "In15.Cu")
		(hatch none 0.5)
		(connect_pads
			(clearance 0)
		)
		(min_thickness 0.25)
		(keepout
			(tracks not_allowed)
			(vias allowed)
			(pads allowed)
			(copperpour not_allowed)
			(footprints allowed)
		)
		(placement
			(enabled no)
			(sheetname "")
		)
		(fill yes
			(thermal_gap 0.5)
			(thermal_bridge_width 0.5)
			(island_removal_mode 0)
		)
		(polygon
			(pts
				(arc
					(start 351.576132 -229.904036)
					(mid 350.946212 -229.904036)
					(end 351.576132 -229.904036)
				)
			)
		)
	)
	(zone
		(layers "B.Cu" "In6.Cu" "In11.Cu" "In13.Cu" "In15.Cu")
		(hatch none 0.5)
		(connect_pads
			(clearance 0)
		)
		(min_thickness 0.25)
		(keepout
			(tracks not_allowed)
			(vias allowed)
			(pads allowed)
			(copperpour not_allowed)
			(footprints allowed)
		)
		(placement
			(enabled no)
			(sheetname "")
		)
		(fill yes
			(thermal_gap 0.5)
			(thermal_bridge_width 0.5)
			(island_removal_mode 0)
		)
		(polygon
			(pts
				(arc
					(start 435.334156 -239.835182)
					(mid 434.666136 -239.835182)
					(end 435.334156 -239.835182)
				)
			)
		)
	)
	(zone
		(layers "B.Cu" "In6.Cu" "In11.Cu" "In13.Cu" "In15.Cu")
		(hatch none 0.5)
		(connect_pads
			(clearance 0)
		)
		(min_thickness 0.25)
		(keepout
			(tracks not_allowed)
			(vias allowed)
			(pads allowed)
			(copperpour not_allowed)
			(footprints allowed)
		)
		(placement
			(enabled no)
			(sheetname "")
		)
		(fill yes
			(thermal_gap 0.5)
			(thermal_bridge_width 0.5)
			(island_removal_mode 0)
		)
		(polygon
			(pts
				(arc
					(start 33.029906 -314.635388)
					(mid 32.361886 -314.635388)
					(end 33.029906 -314.635388)
				)
			)
		)
	)
	(zone
		(layers "B.Cu" "In6.Cu" "In11.Cu" "In13.Cu" "In15.Cu")
		(hatch none 0.5)
		(connect_pads
			(clearance 0)
		)
		(min_thickness 0.25)
		(keepout
			(tracks not_allowed)
			(vias allowed)
			(pads allowed)
			(copperpour not_allowed)
			(footprints allowed)
		)
		(placement
			(enabled no)
			(sheetname "")
		)
		(fill yes
			(thermal_gap 0.5)
			(thermal_bridge_width 0.5)
			(island_removal_mode 0)
		)
		(polygon
			(pts
				(arc
					(start 93.126052 -280.566368)
					(mid 92.496132 -280.566368)
					(end 93.126052 -280.566368)
				)
			)
		)
	)
	(zone
		(layers "B.Cu" "In6.Cu" "In11.Cu" "In13.Cu" "In15.Cu")
		(hatch none 0.5)
		(connect_pads
			(clearance 0)
		)
		(min_thickness 0.25)
		(keepout
			(tracks not_allowed)
			(vias allowed)
			(pads allowed)
			(copperpour not_allowed)
			(footprints allowed)
		)
		(placement
			(enabled no)
			(sheetname "")
		)
		(fill yes
			(thermal_gap 0.5)
			(thermal_bridge_width 0.5)
			(island_removal_mode 0)
		)
		(polygon
			(pts
				(arc
					(start 435.334156 -246.635016)
					(mid 434.666136 -246.635016)
					(end 435.334156 -246.635016)
				)
			)
		)
	)
	(zone
		(layers "B.Cu" "In6.Cu" "In11.Cu" "In13.Cu" "In15.Cu")
		(hatch none 0.5)
		(connect_pads
			(clearance 0)
		)
		(min_thickness 0.25)
		(keepout
			(tracks not_allowed)
			(vias allowed)
			(pads allowed)
			(copperpour not_allowed)
			(footprints allowed)
		)
		(placement
			(enabled no)
			(sheetname "")
		)
		(fill yes
			(thermal_gap 0.5)
			(thermal_bridge_width 0.5)
			(island_removal_mode 0)
		)
		(polygon
			(pts
				(arc
					(start 374.429782 -286.236156)
					(mid 373.799862 -286.236156)
					(end 374.429782 -286.236156)
				)
			)
		)
	)
	(zone
		(layers "B.Cu" "In6.Cu" "In11.Cu" "In13.Cu" "In15.Cu")
		(hatch none 0.5)
		(connect_pads
			(clearance 0)
		)
		(min_thickness 0.25)
		(keepout
			(tracks not_allowed)
			(vias allowed)
			(pads allowed)
			(copperpour not_allowed)
			(footprints allowed)
		)
		(placement
			(enabled no)
			(sheetname "")
		)
		(fill yes
			(thermal_gap 0.5)
			(thermal_bridge_width 0.5)
			(island_removal_mode 0)
		)
		(polygon
			(pts
				(arc
					(start 125.249686 -228.284532)
					(mid 124.619766 -228.284532)
					(end 125.249686 -228.284532)
				)
			)
		)
	)
	(zone
		(layers "B.Cu" "In6.Cu" "In11.Cu" "In13.Cu" "In15.Cu")
		(hatch none 0.5)
		(connect_pads
			(clearance 0)
		)
		(min_thickness 0.25)
		(keepout
			(tracks not_allowed)
			(vias allowed)
			(pads allowed)
			(copperpour not_allowed)
			(footprints allowed)
		)
		(placement
			(enabled no)
			(sheetname "")
		)
		(fill yes
			(thermal_gap 0.5)
			(thermal_bridge_width 0.5)
			(island_removal_mode 0)
		)
		(polygon
			(pts
				(arc
					(start 349.056198 -289.475926)
					(mid 348.426278 -289.475926)
					(end 349.056198 -289.475926)
				)
			)
		)
	)
	(zone
		(layers "B.Cu" "In6.Cu" "In11.Cu" "In13.Cu" "In15.Cu")
		(hatch none 0.5)
		(connect_pads
			(clearance 0)
		)
		(min_thickness 0.25)
		(keepout
			(tracks not_allowed)
			(vias allowed)
			(pads allowed)
			(copperpour not_allowed)
			(footprints allowed)
		)
		(placement
			(enabled no)
			(sheetname "")
		)
		(fill yes
			(thermal_gap 0.5)
			(thermal_bridge_width 0.5)
			(island_removal_mode 0)
		)
		(polygon
			(pts
				(arc
					(start 285.070042 -204.985112)
					(mid 284.402022 -204.985112)
					(end 285.070042 -204.985112)
				)
			)
		)
	)
	(zone
		(layers "B.Cu" "In6.Cu" "In11.Cu" "In13.Cu" "In15.Cu")
		(hatch none 0.5)
		(connect_pads
			(clearance 0)
		)
		(min_thickness 0.25)
		(keepout
			(tracks not_allowed)
			(vias allowed)
			(pads allowed)
			(copperpour not_allowed)
			(footprints allowed)
		)
		(placement
			(enabled no)
			(sheetname "")
		)
		(fill yes
			(thermal_gap 0.5)
			(thermal_bridge_width 0.5)
			(island_removal_mode 0)
		)
		(polygon
			(pts
				(arc
					(start 285.070042 -313.784996)
					(mid 284.402022 -313.784996)
					(end 285.070042 -313.784996)
				)
			)
		)
	)
	(zone
		(layers "B.Cu" "In6.Cu" "In11.Cu" "In13.Cu" "In15.Cu")
		(hatch none 0.5)
		(connect_pads
			(clearance 0)
		)
		(min_thickness 0.25)
		(keepout
			(tracks not_allowed)
			(vias allowed)
			(pads allowed)
			(copperpour not_allowed)
			(footprints allowed)
		)
		(placement
			(enabled no)
			(sheetname "")
		)
		(fill yes
			(thermal_gap 0.5)
			(thermal_bridge_width 0.5)
			(island_removal_mode 0)
		)
		(polygon
			(pts
				(arc
					(start 33.029906 -216.885266)
					(mid 32.361886 -216.885266)
					(end 33.029906 -216.885266)
				)
			)
		)
	)
	(zone
		(layers "B.Cu" "In6.Cu" "In11.Cu" "In13.Cu" "In15.Cu")
		(hatch none 0.5)
		(connect_pads
			(clearance 0)
		)
		(min_thickness 0.25)
		(keepout
			(tracks not_allowed)
			(vias allowed)
			(pads allowed)
			(copperpour not_allowed)
			(footprints allowed)
		)
		(placement
			(enabled no)
			(sheetname "")
		)
		(fill yes
			(thermal_gap 0.5)
			(thermal_bridge_width 0.5)
			(island_removal_mode 0)
		)
		(polygon
			(pts
				(arc
					(start 207.165194 -352.41103)
					(mid 206.497174 -352.41103)
					(end 207.165194 -352.41103)
				)
			)
		)
	)
	(zone
		(layers "B.Cu" "In6.Cu" "In11.Cu" "In13.Cu" "In15.Cu")
		(hatch none 0.5)
		(connect_pads
			(clearance 0)
		)
		(min_thickness 0.25)
		(keepout
			(tracks not_allowed)
			(vias allowed)
			(pads allowed)
			(copperpour not_allowed)
			(footprints allowed)
		)
		(placement
			(enabled no)
			(sheetname "")
		)
		(fill yes
			(thermal_gap 0.5)
			(thermal_bridge_width 0.5)
			(island_removal_mode 0)
		)
		(polygon
			(pts
				(arc
					(start 191.494156 -252.58522)
					(mid 190.826136 -252.58522)
					(end 191.494156 -252.58522)
				)
			)
		)
	)
	(zone
		(layers "B.Cu" "In6.Cu" "In11.Cu" "In13.Cu" "In15.Cu")
		(hatch none 0.5)
		(connect_pads
			(clearance 0)
		)
		(min_thickness 0.25)
		(keepout
			(tracks not_allowed)
			(vias allowed)
			(pads allowed)
			(copperpour not_allowed)
			(footprints allowed)
		)
		(placement
			(enabled no)
			(sheetname "")
		)
		(fill yes
			(thermal_gap 0.5)
			(thermal_bridge_width 0.5)
			(island_removal_mode 0)
		)
		(polygon
			(pts
				(arc
					(start 381.009906 -274.896072)
					(mid 380.379986 -274.896072)
					(end 381.009906 -274.896072)
				)
			)
		)
	)
	(zone
		(layers "B.Cu" "In6.Cu" "In11.Cu" "In13.Cu" "In15.Cu")
		(hatch none 0.5)
		(connect_pads
			(clearance 0)
		)
		(min_thickness 0.25)
		(keepout
			(tracks not_allowed)
			(vias allowed)
			(pads allowed)
			(copperpour not_allowed)
			(footprints allowed)
		)
		(placement
			(enabled no)
			(sheetname "")
		)
		(fill yes
			(thermal_gap 0.5)
			(thermal_bridge_width 0.5)
			(island_removal_mode 0)
		)
		(polygon
			(pts
				(arc
					(start 381.179832 -248.534174)
					(mid 380.549912 -248.534174)
					(end 381.179832 -248.534174)
				)
			)
		)
	)
	(zone
		(layers "B.Cu" "In6.Cu" "In11.Cu" "In13.Cu" "In15.Cu")
		(hatch none 0.5)
		(connect_pads
			(clearance 0)
		)
		(min_thickness 0.25)
		(keepout
			(tracks not_allowed)
			(vias allowed)
			(pads allowed)
			(copperpour not_allowed)
			(footprints allowed)
		)
		(placement
			(enabled no)
			(sheetname "")
		)
		(fill yes
			(thermal_gap 0.5)
			(thermal_bridge_width 0.5)
			(island_removal_mode 0)
		)
		(polygon
			(pts
				(arc
					(start 160.933892 -388.774432)
					(mid 160.303972 -388.774432)
					(end 160.933892 -388.774432)
				)
			)
		)
	)
	(zone
		(layers "B.Cu" "In6.Cu" "In11.Cu" "In13.Cu" "In15.Cu")
		(hatch none 0.5)
		(connect_pads
			(clearance 0)
		)
		(min_thickness 0.25)
		(keepout
			(tracks not_allowed)
			(vias allowed)
			(pads allowed)
			(copperpour not_allowed)
			(footprints allowed)
		)
		(placement
			(enabled no)
			(sheetname "")
		)
		(fill yes
			(thermal_gap 0.5)
			(thermal_bridge_width 0.5)
			(island_removal_mode 0)
		)
		(polygon
			(pts
				(arc
					(start 435.334156 -295.085008)
					(mid 434.666136 -295.085008)
					(end 435.334156 -295.085008)
				)
			)
		)
	)
	(zone
		(layers "B.Cu" "In6.Cu" "In11.Cu" "In13.Cu" "In15.Cu")
		(hatch none 0.5)
		(connect_pads
			(clearance 0)
		)
		(min_thickness 0.25)
		(keepout
			(tracks not_allowed)
			(vias allowed)
			(pads allowed)
			(copperpour not_allowed)
			(footprints allowed)
		)
		(placement
			(enabled no)
			(sheetname "")
		)
		(fill yes
			(thermal_gap 0.5)
			(thermal_bridge_width 0.5)
			(island_removal_mode 0)
		)
		(polygon
			(pts
				(arc
					(start 37.129974 -279.785318)
					(mid 36.461954 -279.785318)
					(end 37.129974 -279.785318)
				)
			)
		)
	)
	(zone
		(layers "B.Cu" "In6.Cu" "In11.Cu" "In13.Cu" "In15.Cu")
		(hatch none 0.5)
		(connect_pads
			(clearance 0)
		)
		(min_thickness 0.25)
		(keepout
			(tracks not_allowed)
			(vias allowed)
			(pads allowed)
			(copperpour not_allowed)
			(footprints allowed)
		)
		(placement
			(enabled no)
			(sheetname "")
		)
		(fill yes
			(thermal_gap 0.5)
			(thermal_bridge_width 0.5)
			(island_removal_mode 0)
		)
		(polygon
			(pts
				(arc
					(start 340.766146 -253.39421)
					(mid 340.136226 -253.39421)
					(end 340.766146 -253.39421)
				)
			)
		)
	)
	(zone
		(layers "B.Cu" "In6.Cu" "In11.Cu" "In13.Cu" "In15.Cu")
		(hatch none 0.5)
		(connect_pads
			(clearance 0)
		)
		(min_thickness 0.25)
		(keepout
			(tracks not_allowed)
			(vias allowed)
			(pads allowed)
			(copperpour not_allowed)
			(footprints allowed)
		)
		(placement
			(enabled no)
			(sheetname "")
		)
		(fill yes
			(thermal_gap 0.5)
			(thermal_bridge_width 0.5)
			(island_removal_mode 0)
		)
		(polygon
			(pts
				(arc
					(start 379.769878 -234.764072)
					(mid 379.139958 -234.764072)
					(end 379.769878 -234.764072)
				)
			)
		)
	)
	(zone
		(layers "B.Cu" "In6.Cu" "In11.Cu" "In13.Cu" "In15.Cu")
		(hatch none 0.5)
		(connect_pads
			(clearance 0)
		)
		(min_thickness 0.25)
		(keepout
			(tracks not_allowed)
			(vias allowed)
			(pads allowed)
			(copperpour not_allowed)
			(footprints allowed)
		)
		(placement
			(enabled no)
			(sheetname "")
		)
		(fill yes
			(thermal_gap 0.5)
			(thermal_bridge_width 0.5)
			(island_removal_mode 0)
		)
		(polygon
			(pts
				(arc
					(start 125.249686 -231.524302)
					(mid 124.619766 -231.524302)
					(end 125.249686 -231.524302)
				)
			)
		)
	)
	(zone
		(layers "B.Cu" "In6.Cu" "In11.Cu" "In13.Cu" "In15.Cu")
		(hatch none 0.5)
		(connect_pads
			(clearance 0)
		)
		(min_thickness 0.25)
		(keepout
			(tracks not_allowed)
			(vias allowed)
			(pads allowed)
			(copperpour not_allowed)
			(footprints allowed)
		)
		(placement
			(enabled no)
			(sheetname "")
		)
		(fill yes
			(thermal_gap 0.5)
			(thermal_bridge_width 0.5)
			(island_removal_mode 0)
		)
		(polygon
			(pts
				(arc
					(start 33.029906 -233.885232)
					(mid 32.361886 -233.885232)
					(end 33.029906 -233.885232)
				)
			)
		)
	)
	(zone
		(layers "B.Cu" "In6.Cu" "In11.Cu" "In13.Cu" "In15.Cu")
		(hatch none 0.5)
		(connect_pads
			(clearance 0)
		)
		(min_thickness 0.25)
		(keepout
			(tracks not_allowed)
			(vias allowed)
			(pads allowed)
			(copperpour not_allowed)
			(footprints allowed)
		)
		(placement
			(enabled no)
			(sheetname "")
		)
		(fill yes
			(thermal_gap 0.5)
			(thermal_bridge_width 0.5)
			(island_removal_mode 0)
		)
		(polygon
			(pts
				(arc
					(start 33.029906 -312.085228)
					(mid 32.361886 -312.085228)
					(end 33.029906 -312.085228)
				)
			)
		)
	)
	(zone
		(layers "B.Cu" "In6.Cu" "In11.Cu" "In13.Cu" "In15.Cu")
		(hatch none 0.5)
		(connect_pads
			(clearance 0)
		)
		(min_thickness 0.25)
		(keepout
			(tracks not_allowed)
			(vias allowed)
			(pads allowed)
			(copperpour not_allowed)
			(footprints allowed)
		)
		(placement
			(enabled no)
			(sheetname "")
		)
		(fill yes
			(thermal_gap 0.5)
			(thermal_bridge_width 0.5)
			(island_removal_mode 0)
		)
		(polygon
			(pts
				(arc
					(start 352.298254 -379.88113)
					(mid 351.630234 -379.88113)
					(end 352.298254 -379.88113)
				)
			)
		)
	)
	(zone
		(layers "B.Cu" "In6.Cu" "In11.Cu" "In13.Cu" "In15.Cu")
		(hatch none 0.5)
		(connect_pads
			(clearance 0)
		)
		(min_thickness 0.25)
		(keepout
			(tracks not_allowed)
			(vias allowed)
			(pads allowed)
			(copperpour not_allowed)
			(footprints allowed)
		)
		(placement
			(enabled no)
			(sheetname "")
		)
		(fill yes
			(thermal_gap 0.5)
			(thermal_bridge_width 0.5)
			(island_removal_mode 0)
		)
		(polygon
			(pts
				(arc
					(start 381.479806 -278.946102)
					(mid 380.849886 -278.946102)
					(end 381.479806 -278.946102)
				)
			)
		)
	)
	(zone
		(layers "B.Cu" "In6.Cu" "In11.Cu" "In13.Cu" "In15.Cu")
		(hatch none 0.5)
		(connect_pads
			(clearance 0)
		)
		(min_thickness 0.25)
		(keepout
			(tracks not_allowed)
			(vias allowed)
			(pads allowed)
			(copperpour not_allowed)
			(footprints allowed)
		)
		(placement
			(enabled no)
			(sheetname "")
		)
		(fill yes
			(thermal_gap 0.5)
			(thermal_bridge_width 0.5)
			(island_removal_mode 0)
		)
		(polygon
			(pts
				(arc
					(start 37.129974 -249.18543)
					(mid 36.461954 -249.18543)
					(end 37.129974 -249.18543)
				)
			)
		)
	)
	(zone
		(layers "B.Cu" "In6.Cu" "In11.Cu" "In13.Cu" "In15.Cu")
		(hatch none 0.5)
		(connect_pads
			(clearance 0)
		)
		(min_thickness 0.25)
		(keepout
			(tracks not_allowed)
			(vias allowed)
			(pads allowed)
			(copperpour not_allowed)
			(footprints allowed)
		)
		(placement
			(enabled no)
			(sheetname "")
		)
		(fill yes
			(thermal_gap 0.5)
			(thermal_bridge_width 0.5)
			(island_removal_mode 0)
		)
		(polygon
			(pts
				(arc
					(start 285.070042 -278.085042)
					(mid 284.402022 -278.085042)
					(end 285.070042 -278.085042)
				)
			)
		)
	)
	(zone
		(layers "B.Cu" "In6.Cu" "In11.Cu" "In13.Cu" "In15.Cu")
		(hatch none 0.5)
		(connect_pads
			(clearance 0)
		)
		(min_thickness 0.25)
		(keepout
			(tracks not_allowed)
			(vias allowed)
			(pads allowed)
			(copperpour not_allowed)
			(footprints allowed)
		)
		(placement
			(enabled no)
			(sheetname "")
		)
		(fill yes
			(thermal_gap 0.5)
			(thermal_bridge_width 0.5)
			(island_removal_mode 0)
		)
		(polygon
			(pts
				(arc
					(start 131.82981 -241.244374)
					(mid 131.19989 -241.244374)
					(end 131.82981 -241.244374)
				)
			)
		)
	)
	(zone
		(layers "B.Cu" "In6.Cu" "In11.Cu" "In13.Cu" "In15.Cu")
		(hatch none 0.5)
		(connect_pads
			(clearance 0)
		)
		(min_thickness 0.25)
		(keepout
			(tracks not_allowed)
			(vias allowed)
			(pads allowed)
			(copperpour not_allowed)
			(footprints allowed)
		)
		(placement
			(enabled no)
			(sheetname "")
		)
		(fill yes
			(thermal_gap 0.5)
			(thermal_bridge_width 0.5)
			(island_removal_mode 0)
		)
		(polygon
			(pts
				(arc
					(start 379.769878 -233.14406)
					(mid 379.139958 -233.14406)
					(end 379.769878 -233.14406)
				)
			)
		)
	)
	(zone
		(layers "B.Cu" "In6.Cu" "In11.Cu" "In13.Cu" "In15.Cu")
		(hatch none 0.5)
		(connect_pads
			(clearance 0)
		)
		(min_thickness 0.25)
		(keepout
			(tracks not_allowed)
			(vias allowed)
			(pads allowed)
			(copperpour not_allowed)
			(footprints allowed)
		)
		(placement
			(enabled no)
			(sheetname "")
		)
		(fill yes
			(thermal_gap 0.5)
			(thermal_bridge_width 0.5)
			(island_removal_mode 0)
		)
		(polygon
			(pts
				(arc
					(start 191.494156 -221.985332)
					(mid 190.826136 -221.985332)
					(end 191.494156 -221.985332)
				)
			)
		)
	)
	(zone
		(layers "B.Cu" "In6.Cu" "In11.Cu" "In13.Cu" "In15.Cu")
		(hatch none 0.5)
		(connect_pads
			(clearance 0)
		)
		(min_thickness 0.25)
		(keepout
			(tracks not_allowed)
			(vias allowed)
			(pads allowed)
			(copperpour not_allowed)
			(footprints allowed)
		)
		(placement
			(enabled no)
			(sheetname "")
		)
		(fill yes
			(thermal_gap 0.5)
			(thermal_bridge_width 0.5)
			(island_removal_mode 0)
		)
		(polygon
			(pts
				(arc
					(start 328.633836 -412.84652)
					(mid 327.965816 -412.84652)
					(end 328.633836 -412.84652)
				)
			)
		)
	)
	(zone
		(layers "B.Cu" "In6.Cu" "In11.Cu" "In13.Cu" "In15.Cu")
		(hatch none 0.5)
		(connect_pads
			(clearance 0)
		)
		(min_thickness 0.25)
		(keepout
			(tracks not_allowed)
			(vias allowed)
			(pads allowed)
			(copperpour not_allowed)
			(footprints allowed)
		)
		(placement
			(enabled no)
			(sheetname "")
		)
		(fill yes
			(thermal_gap 0.5)
			(thermal_bridge_width 0.5)
			(island_removal_mode 0)
		)
		(polygon
			(pts
				(arc
					(start 339.186012 -280.566114)
					(mid 338.556092 -280.566114)
					(end 339.186012 -280.566114)
				)
			)
		)
	)
	(zone
		(layers "B.Cu" "In6.Cu" "In11.Cu" "In13.Cu" "In15.Cu")
		(hatch none 0.5)
		(connect_pads
			(clearance 0)
		)
		(min_thickness 0.25)
		(keepout
			(tracks not_allowed)
			(vias allowed)
			(pads allowed)
			(copperpour not_allowed)
			(footprints allowed)
		)
		(placement
			(enabled no)
			(sheetname "")
		)
		(fill yes
			(thermal_gap 0.5)
			(thermal_bridge_width 0.5)
			(island_removal_mode 0)
		)
		(polygon
			(pts
				(arc
					(start 115.379754 -227.474526)
					(mid 114.749834 -227.474526)
					(end 115.379754 -227.474526)
				)
			)
		)
	)
	(zone
		(layers "B.Cu" "In6.Cu" "In11.Cu" "In13.Cu" "In15.Cu")
		(hatch none 0.5)
		(connect_pads
			(clearance 0)
		)
		(min_thickness 0.25)
		(keepout
			(tracks not_allowed)
			(vias allowed)
			(pads allowed)
			(copperpour not_allowed)
			(footprints allowed)
		)
		(placement
			(enabled no)
			(sheetname "")
		)
		(fill yes
			(thermal_gap 0.5)
			(thermal_bridge_width 0.5)
			(island_removal_mode 0)
		)
		(polygon
			(pts
				(arc
					(start 285.070042 -275.535136)
					(mid 284.402022 -275.535136)
					(end 285.070042 -275.535136)
				)
			)
		)
	)
	(zone
		(layers "B.Cu" "In6.Cu" "In11.Cu" "In13.Cu" "In15.Cu")
		(hatch none 0.5)
		(connect_pads
			(clearance 0)
		)
		(min_thickness 0.25)
		(keepout
			(tracks not_allowed)
			(vias allowed)
			(pads allowed)
			(copperpour not_allowed)
			(footprints allowed)
		)
		(placement
			(enabled no)
			(sheetname "")
		)
		(fill yes
			(thermal_gap 0.5)
			(thermal_bridge_width 0.5)
			(island_removal_mode 0)
		)
		(polygon
			(pts
				(arc
					(start 439.434224 -231.335072)
					(mid 438.766204 -231.335072)
					(end 439.434224 -231.335072)
				)
			)
		)
	)
	(zone
		(layers "B.Cu" "In6.Cu" "In11.Cu" "In13.Cu" "In15.Cu")
		(hatch none 0.5)
		(connect_pads
			(clearance 0)
		)
		(min_thickness 0.25)
		(keepout
			(tracks not_allowed)
			(vias allowed)
			(pads allowed)
			(copperpour not_allowed)
			(footprints allowed)
		)
		(placement
			(enabled no)
			(sheetname "")
		)
		(fill yes
			(thermal_gap 0.5)
			(thermal_bridge_width 0.5)
			(island_removal_mode 0)
		)
		(polygon
			(pts
				(arc
					(start 320.10604 -397.849344)
					(mid 319.47612 -397.849344)
					(end 320.10604 -397.849344)
				)
			)
		)
	)
	(zone
		(layers "B.Cu" "In6.Cu" "In11.Cu" "In13.Cu" "In15.Cu")
		(hatch none 0.5)
		(connect_pads
			(clearance 0)
		)
		(min_thickness 0.25)
		(keepout
			(tracks not_allowed)
			(vias allowed)
			(pads allowed)
			(copperpour not_allowed)
			(footprints allowed)
		)
		(placement
			(enabled no)
			(sheetname "")
		)
		(fill yes
			(thermal_gap 0.5)
			(thermal_bridge_width 0.5)
			(island_removal_mode 0)
		)
		(polygon
			(pts
				(arc
					(start 379.299724 -240.434114)
					(mid 378.669804 -240.434114)
					(end 379.299724 -240.434114)
				)
			)
		)
	)
	(zone
		(layers "B.Cu" "In6.Cu" "In11.Cu" "In13.Cu" "In15.Cu")
		(hatch none 0.5)
		(connect_pads
			(clearance 0)
		)
		(min_thickness 0.25)
		(keepout
			(tracks not_allowed)
			(vias allowed)
			(pads allowed)
			(copperpour not_allowed)
			(footprints allowed)
		)
		(placement
			(enabled no)
			(sheetname "")
		)
		(fill yes
			(thermal_gap 0.5)
			(thermal_bridge_width 0.5)
			(island_removal_mode 0)
		)
		(polygon
			(pts
				(arc
					(start 146.724116 -404.46452)
					(mid 146.056096 -404.46452)
					(end 146.724116 -404.46452)
				)
			)
		)
	)
	(zone
		(layers "B.Cu" "In6.Cu" "In11.Cu" "In13.Cu" "In15.Cu")
		(hatch none 0.5)
		(connect_pads
			(clearance 0)
		)
		(min_thickness 0.25)
		(keepout
			(tracks not_allowed)
			(vias allowed)
			(pads allowed)
			(copperpour not_allowed)
			(footprints allowed)
		)
		(placement
			(enabled no)
			(sheetname "")
		)
		(fill yes
			(thermal_gap 0.5)
			(thermal_bridge_width 0.5)
			(island_removal_mode 0)
		)
		(polygon
			(pts
				(arc
					(start 45.527976 -4.963414)
					(mid 44.859956 -4.963414)
					(end 45.527976 -4.963414)
				)
			)
		)
	)
	(zone
		(layers "B.Cu" "In6.Cu" "In11.Cu" "In13.Cu" "In15.Cu")
		(hatch none 0.5)
		(connect_pads
			(clearance 0)
		)
		(min_thickness 0.25)
		(keepout
			(tracks not_allowed)
			(vias allowed)
			(pads allowed)
			(copperpour not_allowed)
			(footprints allowed)
		)
		(placement
			(enabled no)
			(sheetname "")
		)
		(fill yes
			(thermal_gap 0.5)
			(thermal_bridge_width 0.5)
			(island_removal_mode 0)
		)
		(polygon
			(pts
				(arc
					(start 33.029906 -209.235294)
					(mid 32.361886 -209.235294)
					(end 33.029906 -209.235294)
				)
			)
		)
	)
	(zone
		(layers "B.Cu" "In6.Cu" "In11.Cu" "In13.Cu" "In15.Cu")
		(hatch none 0.5)
		(connect_pads
			(clearance 0)
		)
		(min_thickness 0.25)
		(keepout
			(tracks not_allowed)
			(vias allowed)
			(pads allowed)
			(copperpour not_allowed)
			(footprints allowed)
		)
		(placement
			(enabled no)
			(sheetname "")
		)
		(fill yes
			(thermal_gap 0.5)
			(thermal_bridge_width 0.5)
			(island_removal_mode 0)
		)
		(polygon
			(pts
				(arc
					(start 435.334156 -267.035026)
					(mid 434.666136 -267.035026)
					(end 435.334156 -267.035026)
				)
			)
		)
	)
	(zone
		(layers "B.Cu" "In6.Cu" "In11.Cu" "In13.Cu" "In15.Cu")
		(hatch none 0.5)
		(connect_pads
			(clearance 0)
		)
		(min_thickness 0.25)
		(keepout
			(tracks not_allowed)
			(vias allowed)
			(pads allowed)
			(copperpour not_allowed)
			(footprints allowed)
		)
		(placement
			(enabled no)
			(sheetname "")
		)
		(fill yes
			(thermal_gap 0.5)
			(thermal_bridge_width 0.5)
			(island_removal_mode 0)
		)
		(polygon
			(pts
				(arc
					(start 98.295968 -287.856422)
					(mid 97.666048 -287.856422)
					(end 98.295968 -287.856422)
				)
			)
		)
	)
	(zone
		(layers "B.Cu" "In6.Cu" "In11.Cu" "In13.Cu" "In15.Cu")
		(hatch none 0.5)
		(connect_pads
			(clearance 0)
		)
		(min_thickness 0.25)
		(keepout
			(tracks not_allowed)
			(vias allowed)
			(pads allowed)
			(copperpour not_allowed)
			(footprints allowed)
		)
		(placement
			(enabled no)
			(sheetname "")
		)
		(fill yes
			(thermal_gap 0.5)
			(thermal_bridge_width 0.5)
			(island_removal_mode 0)
		)
		(polygon
			(pts
				(arc
					(start 131.65963 -280.566368)
					(mid 131.02971 -280.566368)
					(end 131.65963 -280.566368)
				)
			)
		)
	)
	(zone
		(layers "B.Cu" "In6.Cu" "In11.Cu" "In13.Cu" "In15.Cu")
		(hatch none 0.5)
		(connect_pads
			(clearance 0)
		)
		(min_thickness 0.25)
		(keepout
			(tracks not_allowed)
			(vias allowed)
			(pads allowed)
			(copperpour not_allowed)
			(footprints allowed)
		)
		(placement
			(enabled no)
			(sheetname "")
		)
		(fill yes
			(thermal_gap 0.5)
			(thermal_bridge_width 0.5)
			(island_removal_mode 0)
		)
		(polygon
			(pts
				(arc
					(start 343.950036 -412.84652)
					(mid 343.282016 -412.84652)
					(end 343.950036 -412.84652)
				)
			)
		)
	)
	(zone
		(layers "B.Cu" "In6.Cu" "In11.Cu" "In13.Cu" "In15.Cu")
		(hatch none 0.5)
		(connect_pads
			(clearance 0)
		)
		(min_thickness 0.25)
		(keepout
			(tracks not_allowed)
			(vias allowed)
			(pads allowed)
			(copperpour not_allowed)
			(footprints allowed)
		)
		(placement
			(enabled no)
			(sheetname "")
		)
		(fill yes
			(thermal_gap 0.5)
			(thermal_bridge_width 0.5)
			(island_removal_mode 0)
		)
		(polygon
			(pts
				(arc
					(start 280.969974 -277.235158)
					(mid 280.301954 -277.235158)
					(end 280.969974 -277.235158)
				)
			)
		)
	)
	(zone
		(layers "B.Cu" "In6.Cu" "In11.Cu" "In13.Cu" "In15.Cu")
		(hatch none 0.5)
		(connect_pads
			(clearance 0)
		)
		(min_thickness 0.25)
		(keepout
			(tracks not_allowed)
			(vias allowed)
			(pads allowed)
			(copperpour not_allowed)
			(footprints allowed)
		)
		(placement
			(enabled no)
			(sheetname "")
		)
		(fill yes
			(thermal_gap 0.5)
			(thermal_bridge_width 0.5)
			(island_removal_mode 0)
		)
		(polygon
			(pts
				(arc
					(start 93.126052 -285.426404)
					(mid 92.496132 -285.426404)
					(end 93.126052 -285.426404)
				)
			)
		)
	)
	(zone
		(layers "B.Cu" "In6.Cu" "In11.Cu" "In13.Cu" "In15.Cu")
		(hatch none 0.5)
		(connect_pads
			(clearance 0)
		)
		(min_thickness 0.25)
		(keepout
			(tracks not_allowed)
			(vias allowed)
			(pads allowed)
			(copperpour not_allowed)
			(footprints allowed)
		)
		(placement
			(enabled no)
			(sheetname "")
		)
		(fill yes
			(thermal_gap 0.5)
			(thermal_bridge_width 0.5)
			(island_removal_mode 0)
		)
		(polygon
			(pts
				(arc
					(start 380.709678 -229.904036)
					(mid 380.079758 -229.904036)
					(end 380.709678 -229.904036)
				)
			)
		)
	)
	(zone
		(layers "B.Cu" "In6.Cu" "In11.Cu" "In13.Cu" "In15.Cu")
		(hatch none 0.5)
		(connect_pads
			(clearance 0)
		)
		(min_thickness 0.25)
		(keepout
			(tracks not_allowed)
			(vias allowed)
			(pads allowed)
			(copperpour not_allowed)
			(footprints allowed)
		)
		(placement
			(enabled no)
			(sheetname "")
		)
		(fill yes
			(thermal_gap 0.5)
			(thermal_bridge_width 0.5)
			(island_removal_mode 0)
		)
		(polygon
			(pts
				(arc
					(start 380.069852 -286.236156)
					(mid 379.439932 -286.236156)
					(end 380.069852 -286.236156)
				)
			)
		)
	)
	(zone
		(layers "B.Cu" "In6.Cu" "In11.Cu" "In13.Cu" "In15.Cu")
		(hatch none 0.5)
		(connect_pads
			(clearance 0)
		)
		(min_thickness 0.25)
		(keepout
			(tracks not_allowed)
			(vias allowed)
			(pads allowed)
			(copperpour not_allowed)
			(footprints allowed)
		)
		(placement
			(enabled no)
			(sheetname "")
		)
		(fill yes
			(thermal_gap 0.5)
			(thermal_bridge_width 0.5)
			(island_removal_mode 0)
		)
		(polygon
			(pts
				(arc
					(start 187.394088 -224.535238)
					(mid 186.726068 -224.535238)
					(end 187.394088 -224.535238)
				)
			)
		)
	)
	(zone
		(layers "B.Cu" "In6.Cu" "In11.Cu" "In13.Cu" "In15.Cu")
		(hatch none 0.5)
		(connect_pads
			(clearance 0)
		)
		(min_thickness 0.25)
		(keepout
			(tracks not_allowed)
			(vias allowed)
			(pads allowed)
			(copperpour not_allowed)
			(footprints allowed)
		)
		(placement
			(enabled no)
			(sheetname "")
		)
		(fill yes
			(thermal_gap 0.5)
			(thermal_bridge_width 0.5)
			(island_removal_mode 0)
		)
		(polygon
			(pts
				(arc
					(start 131.65963 -282.18638)
					(mid 131.02971 -282.18638)
					(end 131.65963 -282.18638)
				)
			)
		)
	)
	(zone
		(layers "B.Cu" "In6.Cu" "In11.Cu" "In13.Cu" "In15.Cu")
		(hatch none 0.5)
		(connect_pads
			(clearance 0)
		)
		(min_thickness 0.25)
		(keepout
			(tracks not_allowed)
			(vias allowed)
			(pads allowed)
			(copperpour not_allowed)
			(footprints allowed)
		)
		(placement
			(enabled no)
			(sheetname "")
		)
		(fill yes
			(thermal_gap 0.5)
			(thermal_bridge_width 0.5)
			(island_removal_mode 0)
		)
		(polygon
			(pts
				(arc
					(start 93.126052 -272.466308)
					(mid 92.496132 -272.466308)
					(end 93.126052 -272.466308)
				)
			)
		)
	)
	(zone
		(layers "B.Cu" "In6.Cu" "In11.Cu" "In13.Cu" "In15.Cu")
		(hatch none 0.5)
		(connect_pads
			(clearance 0)
		)
		(min_thickness 0.25)
		(keepout
			(tracks not_allowed)
			(vias allowed)
			(pads allowed)
			(copperpour not_allowed)
			(footprints allowed)
		)
		(placement
			(enabled no)
			(sheetname "")
		)
		(fill yes
			(thermal_gap 0.5)
			(thermal_bridge_width 0.5)
			(island_removal_mode 0)
		)
		(polygon
			(pts
				(arc
					(start 92.355924 -239.624362)
					(mid 91.726004 -239.624362)
					(end 92.355924 -239.624362)
				)
			)
		)
	)
	(zone
		(layers "B.Cu" "In6.Cu" "In11.Cu" "In13.Cu" "In15.Cu")
		(hatch none 0.5)
		(connect_pads
			(clearance 0)
		)
		(min_thickness 0.25)
		(keepout
			(tracks not_allowed)
			(vias allowed)
			(pads allowed)
			(copperpour not_allowed)
			(footprints allowed)
		)
		(placement
			(enabled no)
			(sheetname "")
		)
		(fill yes
			(thermal_gap 0.5)
			(thermal_bridge_width 0.5)
			(island_removal_mode 0)
		)
		(polygon
			(pts
				(arc
					(start 37.129974 -306.135278)
					(mid 36.461954 -306.135278)
					(end 37.129974 -306.135278)
				)
			)
		)
	)
	(zone
		(layers "B.Cu" "In6.Cu" "In11.Cu" "In13.Cu" "In15.Cu")
		(hatch none 0.5)
		(connect_pads
			(clearance 0)
		)
		(min_thickness 0.25)
		(keepout
			(tracks not_allowed)
			(vias allowed)
			(pads allowed)
			(copperpour not_allowed)
			(footprints allowed)
		)
		(placement
			(enabled no)
			(sheetname "")
		)
		(fill yes
			(thermal_gap 0.5)
			(thermal_bridge_width 0.5)
			(island_removal_mode 0)
		)
		(polygon
			(pts
				(arc
					(start 375.154952 -412.84652)
					(mid 374.486932 -412.84652)
					(end 375.154952 -412.84652)
				)
			)
		)
	)
	(zone
		(layers "B.Cu" "In6.Cu" "In11.Cu" "In13.Cu" "In15.Cu")
		(hatch none 0.5)
		(connect_pads
			(clearance 0)
		)
		(min_thickness 0.25)
		(keepout
			(tracks not_allowed)
			(vias allowed)
			(pads allowed)
			(copperpour not_allowed)
			(footprints allowed)
		)
		(placement
			(enabled no)
			(sheetname "")
		)
		(fill yes
			(thermal_gap 0.5)
			(thermal_bridge_width 0.5)
			(island_removal_mode 0)
		)
		(polygon
			(pts
				(arc
					(start 33.029906 -316.33541)
					(mid 32.361886 -316.33541)
					(end 33.029906 -316.33541)
				)
			)
		)
	)
	(zone
		(layers "B.Cu" "In6.Cu" "In11.Cu" "In13.Cu" "In15.Cu")
		(hatch none 0.5)
		(connect_pads
			(clearance 0)
		)
		(min_thickness 0.25)
		(keepout
			(tracks not_allowed)
			(vias allowed)
			(pads allowed)
			(copperpour not_allowed)
			(footprints allowed)
		)
		(placement
			(enabled no)
			(sheetname "")
		)
		(fill yes
			(thermal_gap 0.5)
			(thermal_bridge_width 0.5)
			(island_removal_mode 0)
		)
		(polygon
			(pts
				(arc
					(start 92.655898 -270.03629)
					(mid 92.025978 -270.03629)
					(end 92.655898 -270.03629)
				)
			)
		)
	)
	(zone
		(layers "B.Cu" "In6.Cu" "In11.Cu" "In13.Cu" "In15.Cu")
		(hatch none 0.5)
		(connect_pads
			(clearance 0)
		)
		(min_thickness 0.25)
		(keepout
			(tracks not_allowed)
			(vias allowed)
			(pads allowed)
			(copperpour not_allowed)
			(footprints allowed)
		)
		(placement
			(enabled no)
			(sheetname "")
		)
		(fill yes
			(thermal_gap 0.5)
			(thermal_bridge_width 0.5)
			(island_removal_mode 0)
		)
		(polygon
			(pts
				(arc
					(start 435.334156 -297.635168)
					(mid 434.666136 -297.635168)
					(end 435.334156 -297.635168)
				)
			)
		)
	)
	(zone
		(layers "B.Cu" "In6.Cu" "In11.Cu" "In13.Cu" "In15.Cu")
		(hatch none 0.5)
		(connect_pads
			(clearance 0)
		)
		(min_thickness 0.25)
		(keepout
			(tracks not_allowed)
			(vias allowed)
			(pads allowed)
			(copperpour not_allowed)
			(footprints allowed)
		)
		(placement
			(enabled no)
			(sheetname "")
		)
		(fill yes
			(thermal_gap 0.5)
			(thermal_bridge_width 0.5)
			(island_removal_mode 0)
		)
		(polygon
			(pts
				(arc
					(start 33.029906 -297.635422)
					(mid 32.361886 -297.635422)
					(end 33.029906 -297.635422)
				)
			)
		)
	)
	(zone
		(layers "B.Cu" "In6.Cu" "In11.Cu" "In13.Cu" "In15.Cu")
		(hatch none 0.5)
		(connect_pads
			(clearance 0)
		)
		(min_thickness 0.25)
		(keepout
			(tracks not_allowed)
			(vias allowed)
			(pads allowed)
			(copperpour not_allowed)
			(footprints allowed)
		)
		(placement
			(enabled no)
			(sheetname "")
		)
		(fill yes
			(thermal_gap 0.5)
			(thermal_bridge_width 0.5)
			(island_removal_mode 0)
		)
		(polygon
			(pts
				(arc
					(start 285.070042 -219.435172)
					(mid 284.402022 -219.435172)
					(end 285.070042 -219.435172)
				)
			)
		)
	)
	(zone
		(layers "B.Cu" "In6.Cu" "In11.Cu" "In13.Cu" "In15.Cu")
		(hatch none 0.5)
		(connect_pads
			(clearance 0)
		)
		(min_thickness 0.25)
		(keepout
			(tracks not_allowed)
			(vias allowed)
			(pads allowed)
			(copperpour not_allowed)
			(footprints allowed)
		)
		(placement
			(enabled no)
			(sheetname "")
		)
		(fill yes
			(thermal_gap 0.5)
			(thermal_bridge_width 0.5)
			(island_removal_mode 0)
		)
		(polygon
			(pts
				(arc
					(start 280.969974 -305.28514)
					(mid 280.301954 -305.28514)
					(end 280.969974 -305.28514)
				)
			)
		)
	)
	(zone
		(layers "B.Cu" "In6.Cu" "In11.Cu" "In13.Cu" "In15.Cu")
		(hatch none 0.5)
		(connect_pads
			(clearance 0)
		)
		(min_thickness 0.25)
		(keepout
			(tracks not_allowed)
			(vias allowed)
			(pads allowed)
			(copperpour not_allowed)
			(footprints allowed)
		)
		(placement
			(enabled no)
			(sheetname "")
		)
		(fill yes
			(thermal_gap 0.5)
			(thermal_bridge_width 0.5)
			(island_removal_mode 0)
		)
		(polygon
			(pts
				(arc
					(start 340.766146 -227.474272)
					(mid 340.136226 -227.474272)
					(end 340.766146 -227.474272)
				)
			)
		)
	)
	(zone
		(layers "B.Cu" "In6.Cu" "In11.Cu" "In13.Cu" "In15.Cu")
		(hatch none 0.5)
		(connect_pads
			(clearance 0)
		)
		(min_thickness 0.25)
		(keepout
			(tracks not_allowed)
			(vias allowed)
			(pads allowed)
			(copperpour not_allowed)
			(footprints allowed)
		)
		(placement
			(enabled no)
			(sheetname "")
		)
		(fill yes
			(thermal_gap 0.5)
			(thermal_bridge_width 0.5)
			(island_removal_mode 0)
		)
		(polygon
			(pts
				(arc
					(start 137.534396 -404.46452)
					(mid 136.866376 -404.46452)
					(end 137.534396 -404.46452)
				)
			)
		)
	)
	(zone
		(layers "B.Cu" "In6.Cu" "In11.Cu" "In13.Cu" "In15.Cu")
		(hatch none 0.5)
		(connect_pads
			(clearance 0)
		)
		(min_thickness 0.25)
		(keepout
			(tracks not_allowed)
			(vias allowed)
			(pads allowed)
			(copperpour not_allowed)
			(footprints allowed)
		)
		(placement
			(enabled no)
			(sheetname "")
		)
		(fill yes
			(thermal_gap 0.5)
			(thermal_bridge_width 0.5)
			(island_removal_mode 0)
		)
		(polygon
			(pts
				(arc
					(start 116.406168 -385.31038)
					(mid 115.776248 -385.31038)
					(end 116.406168 -385.31038)
				)
			)
		)
	)
	(zone
		(layers "B.Cu" "In6.Cu" "In11.Cu" "In13.Cu" "In15.Cu")
		(hatch none 0.5)
		(connect_pads
			(clearance 0)
		)
		(min_thickness 0.25)
		(keepout
			(tracks not_allowed)
			(vias allowed)
			(pads allowed)
			(copperpour not_allowed)
			(footprints allowed)
		)
		(placement
			(enabled no)
			(sheetname "")
		)
		(fill yes
			(thermal_gap 0.5)
			(thermal_bridge_width 0.5)
			(island_removal_mode 0)
		)
		(polygon
			(pts
				(arc
					(start 340.766146 -229.094284)
					(mid 340.136226 -229.094284)
					(end 340.766146 -229.094284)
				)
			)
		)
	)
	(zone
		(layers "B.Cu" "In6.Cu" "In11.Cu" "In13.Cu" "In15.Cu")
		(hatch none 0.5)
		(connect_pads
			(clearance 0)
		)
		(min_thickness 0.25)
		(keepout
			(tracks not_allowed)
			(vias allowed)
			(pads allowed)
			(copperpour not_allowed)
			(footprints allowed)
		)
		(placement
			(enabled no)
			(sheetname "")
		)
		(fill yes
			(thermal_gap 0.5)
			(thermal_bridge_width 0.5)
			(island_removal_mode 0)
		)
		(polygon
			(pts
				(arc
					(start 435.334156 -284.034992)
					(mid 434.666136 -284.034992)
					(end 435.334156 -284.034992)
				)
			)
		)
	)
	(zone
		(layers "B.Cu" "In6.Cu" "In11.Cu" "In13.Cu" "In15.Cu")
		(hatch none 0.5)
		(connect_pads
			(clearance 0)
		)
		(min_thickness 0.25)
		(keepout
			(tracks not_allowed)
			(vias allowed)
			(pads allowed)
			(copperpour not_allowed)
			(footprints allowed)
		)
		(placement
			(enabled no)
			(sheetname "")
		)
		(fill yes
			(thermal_gap 0.5)
			(thermal_bridge_width 0.5)
			(island_removal_mode 0)
		)
		(polygon
			(pts
				(arc
					(start 285.070042 -269.585186)
					(mid 284.402022 -269.585186)
					(end 285.070042 -269.585186)
				)
			)
		)
	)
	(zone
		(layers "B.Cu" "In6.Cu" "In11.Cu" "In13.Cu" "In15.Cu")
		(hatch none 0.5)
		(connect_pads
			(clearance 0)
		)
		(min_thickness 0.25)
		(keepout
			(tracks not_allowed)
			(vias allowed)
			(pads allowed)
			(copperpour not_allowed)
			(footprints allowed)
		)
		(placement
			(enabled no)
			(sheetname "")
		)
		(fill yes
			(thermal_gap 0.5)
			(thermal_bridge_width 0.5)
			(island_removal_mode 0)
		)
		(polygon
			(pts
				(arc
					(start 76.740512 -371.49913)
					(mid 76.072492 -371.49913)
					(end 76.740512 -371.49913)
				)
			)
		)
	)
	(zone
		(layers "B.Cu" "In6.Cu" "In11.Cu" "In13.Cu" "In15.Cu")
		(hatch none 0.5)
		(connect_pads
			(clearance 0)
		)
		(min_thickness 0.25)
		(keepout
			(tracks not_allowed)
			(vias allowed)
			(pads allowed)
			(copperpour not_allowed)
			(footprints allowed)
		)
		(placement
			(enabled no)
			(sheetname "")
		)
		(fill yes
			(thermal_gap 0.5)
			(thermal_bridge_width 0.5)
			(island_removal_mode 0)
		)
		(polygon
			(pts
				(arc
					(start 152.850596 -404.46452)
					(mid 152.182576 -404.46452)
					(end 152.850596 -404.46452)
				)
			)
		)
	)
	(zone
		(layers "B.Cu" "In6.Cu" "In11.Cu" "In13.Cu" "In15.Cu")
		(hatch none 0.5)
		(connect_pads
			(clearance 0)
		)
		(min_thickness 0.25)
		(keepout
			(tracks not_allowed)
			(vias allowed)
			(pads allowed)
			(copperpour not_allowed)
			(footprints allowed)
		)
		(placement
			(enabled no)
			(sheetname "")
		)
		(fill yes
			(thermal_gap 0.5)
			(thermal_bridge_width 0.5)
			(island_removal_mode 0)
		)
		(polygon
			(pts
				(arc
					(start 339.355938 -247.724168)
					(mid 338.726018 -247.724168)
					(end 339.355938 -247.724168)
				)
			)
		)
	)
	(zone
		(layers "B.Cu" "In6.Cu" "In11.Cu" "In13.Cu" "In15.Cu")
		(hatch none 0.5)
		(connect_pads
			(clearance 0)
		)
		(min_thickness 0.25)
		(keepout
			(tracks not_allowed)
			(vias allowed)
			(pads allowed)
			(copperpour not_allowed)
			(footprints allowed)
		)
		(placement
			(enabled no)
			(sheetname "")
		)
		(fill yes
			(thermal_gap 0.5)
			(thermal_bridge_width 0.5)
			(island_removal_mode 0)
		)
		(polygon
			(pts
				(arc
					(start 307.191156 -412.84652)
					(mid 306.523136 -412.84652)
					(end 307.191156 -412.84652)
				)
			)
		)
	)
	(zone
		(layers "B.Cu" "In6.Cu" "In11.Cu" "In13.Cu" "In15.Cu")
		(hatch none 0.5)
		(connect_pads
			(clearance 0)
		)
		(min_thickness 0.25)
		(keepout
			(tracks not_allowed)
			(vias allowed)
			(pads allowed)
			(copperpour not_allowed)
			(footprints allowed)
		)
		(placement
			(enabled no)
			(sheetname "")
		)
		(fill yes
			(thermal_gap 0.5)
			(thermal_bridge_width 0.5)
			(island_removal_mode 0)
		)
		(polygon
			(pts
				(arc
					(start 435.334156 -277.235158)
					(mid 434.666136 -277.235158)
					(end 435.334156 -277.235158)
				)
			)
		)
	)
	(zone
		(layers "B.Cu" "In6.Cu" "In11.Cu" "In13.Cu" "In15.Cu")
		(hatch none 0.5)
		(connect_pads
			(clearance 0)
		)
		(min_thickness 0.25)
		(keepout
			(tracks not_allowed)
			(vias allowed)
			(pads allowed)
			(copperpour not_allowed)
			(footprints allowed)
		)
		(placement
			(enabled no)
			(sheetname "")
		)
		(fill yes
			(thermal_gap 0.5)
			(thermal_bridge_width 0.5)
			(island_removal_mode 0)
		)
		(polygon
			(pts
				(arc
					(start 125.54966 -286.23641)
					(mid 124.91974 -286.23641)
					(end 125.54966 -286.23641)
				)
			)
		)
	)
	(zone
		(layers "B.Cu" "In6.Cu" "In11.Cu" "In13.Cu" "In15.Cu")
		(hatch none 0.5)
		(connect_pads
			(clearance 0)
		)
		(min_thickness 0.25)
		(keepout
			(tracks not_allowed)
			(vias allowed)
			(pads allowed)
			(copperpour not_allowed)
			(footprints allowed)
		)
		(placement
			(enabled no)
			(sheetname "")
		)
		(fill yes
			(thermal_gap 0.5)
			(thermal_bridge_width 0.5)
			(island_removal_mode 0)
		)
		(polygon
			(pts
				(arc
					(start 285.070042 -229.63505)
					(mid 284.402022 -229.63505)
					(end 285.070042 -229.63505)
				)
			)
		)
	)
	(zone
		(layers "B.Cu" "In6.Cu" "In11.Cu" "In13.Cu" "In15.Cu")
		(hatch none 0.5)
		(connect_pads
			(clearance 0)
		)
		(min_thickness 0.25)
		(keepout
			(tracks not_allowed)
			(vias allowed)
			(pads allowed)
			(copperpour not_allowed)
			(footprints allowed)
		)
		(placement
			(enabled no)
			(sheetname "")
		)
		(fill yes
			(thermal_gap 0.5)
			(thermal_bridge_width 0.5)
			(island_removal_mode 0)
		)
		(polygon
			(pts
				(arc
					(start 371.206268 -393.69238)
					(mid 370.576348 -393.69238)
					(end 371.206268 -393.69238)
				)
			)
		)
	)
	(zone
		(layers "B.Cu" "In6.Cu" "In11.Cu" "In13.Cu" "In15.Cu")
		(hatch none 0.5)
		(connect_pads
			(clearance 0)
		)
		(min_thickness 0.25)
		(keepout
			(tracks not_allowed)
			(vias allowed)
			(pads allowed)
			(copperpour not_allowed)
			(footprints allowed)
		)
		(placement
			(enabled no)
			(sheetname "")
		)
		(fill yes
			(thermal_gap 0.5)
			(thermal_bridge_width 0.5)
			(island_removal_mode 0)
		)
		(polygon
			(pts
				(arc
					(start 340.766146 -230.714296)
					(mid 340.136226 -230.714296)
					(end 340.766146 -230.714296)
				)
			)
		)
	)
	(zone
		(layers "B.Cu" "In6.Cu" "In11.Cu" "In13.Cu" "In15.Cu")
		(hatch none 0.5)
		(connect_pads
			(clearance 0)
		)
		(min_thickness 0.25)
		(keepout
			(tracks not_allowed)
			(vias allowed)
			(pads allowed)
			(copperpour not_allowed)
			(footprints allowed)
		)
		(placement
			(enabled no)
			(sheetname "")
		)
		(fill yes
			(thermal_gap 0.5)
			(thermal_bridge_width 0.5)
			(island_removal_mode 0)
		)
		(polygon
			(pts
				(arc
					(start 368.489738 -231.524048)
					(mid 367.859818 -231.524048)
					(end 368.489738 -231.524048)
				)
			)
		)
	)
	(zone
		(layers "B.Cu" "In6.Cu" "In11.Cu" "In13.Cu" "In15.Cu")
		(hatch none 0.5)
		(connect_pads
			(clearance 0)
		)
		(min_thickness 0.25)
		(keepout
			(tracks not_allowed)
			(vias allowed)
			(pads allowed)
			(copperpour not_allowed)
			(footprints allowed)
		)
		(placement
			(enabled no)
			(sheetname "")
		)
		(fill yes
			(thermal_gap 0.5)
			(thermal_bridge_width 0.5)
			(island_removal_mode 0)
		)
		(polygon
			(pts
				(arc
					(start 354.696014 -289.475926)
					(mid 354.066094 -289.475926)
					(end 354.696014 -289.475926)
				)
			)
		)
	)
	(zone
		(layers "B.Cu" "In6.Cu" "In11.Cu" "In13.Cu" "In15.Cu")
		(hatch none 0.5)
		(connect_pads
			(clearance 0)
		)
		(min_thickness 0.25)
		(keepout
			(tracks not_allowed)
			(vias allowed)
			(pads allowed)
			(copperpour not_allowed)
			(footprints allowed)
		)
		(placement
			(enabled no)
			(sheetname "")
		)
		(fill yes
			(thermal_gap 0.5)
			(thermal_bridge_width 0.5)
			(island_removal_mode 0)
		)
		(polygon
			(pts
				(arc
					(start 54.069742 -6.725158)
					(mid 53.401722 -6.725158)
					(end 54.069742 -6.725158)
				)
			)
		)
	)
	(zone
		(layers "B.Cu" "In6.Cu" "In11.Cu" "In13.Cu" "In15.Cu")
		(hatch none 0.5)
		(connect_pads
			(clearance 0)
		)
		(min_thickness 0.25)
		(keepout
			(tracks not_allowed)
			(vias allowed)
			(pads allowed)
			(copperpour not_allowed)
			(footprints allowed)
		)
		(placement
			(enabled no)
			(sheetname "")
		)
		(fill yes
			(thermal_gap 0.5)
			(thermal_bridge_width 0.5)
			(island_removal_mode 0)
		)
		(polygon
			(pts
				(arc
					(start 339.355938 -242.864132)
					(mid 338.726018 -242.864132)
					(end 339.355938 -242.864132)
				)
			)
		)
	)
	(zone
		(layers "B.Cu" "In6.Cu" "In11.Cu" "In13.Cu" "In15.Cu")
		(hatch none 0.5)
		(connect_pads
			(clearance 0)
		)
		(min_thickness 0.25)
		(keepout
			(tracks not_allowed)
			(vias allowed)
			(pads allowed)
			(copperpour not_allowed)
			(footprints allowed)
		)
		(placement
			(enabled no)
			(sheetname "")
		)
		(fill yes
			(thermal_gap 0.5)
			(thermal_bridge_width 0.5)
			(island_removal_mode 0)
		)
		(polygon
			(pts
				(arc
					(start 92.355924 -254.20447)
					(mid 91.726004 -254.20447)
					(end 92.355924 -254.20447)
				)
			)
		)
	)
	(zone
		(layers "B.Cu" "In6.Cu" "In11.Cu" "In13.Cu" "In15.Cu")
		(hatch none 0.5)
		(connect_pads
			(clearance 0)
		)
		(min_thickness 0.25)
		(keepout
			(tracks not_allowed)
			(vias allowed)
			(pads allowed)
			(copperpour not_allowed)
			(footprints allowed)
		)
		(placement
			(enabled no)
			(sheetname "")
		)
		(fill yes
			(thermal_gap 0.5)
			(thermal_bridge_width 0.5)
			(island_removal_mode 0)
		)
		(polygon
			(pts
				(arc
					(start 280.969974 -218.585034)
					(mid 280.301954 -218.585034)
					(end 280.969974 -218.585034)
				)
			)
		)
	)
	(zone
		(layers "B.Cu" "In6.Cu" "In11.Cu" "In13.Cu" "In15.Cu")
		(hatch none 0.5)
		(connect_pads
			(clearance 0)
		)
		(min_thickness 0.25)
		(keepout
			(tracks not_allowed)
			(vias allowed)
			(pads allowed)
			(copperpour not_allowed)
			(footprints allowed)
		)
		(placement
			(enabled no)
			(sheetname "")
		)
		(fill yes
			(thermal_gap 0.5)
			(thermal_bridge_width 0.5)
			(island_removal_mode 0)
		)
		(polygon
			(pts
				(arc
					(start 104.576118 -233.144314)
					(mid 103.946198 -233.144314)
					(end 104.576118 -233.144314)
				)
			)
		)
	)
	(zone
		(layers "B.Cu" "In6.Cu" "In11.Cu" "In13.Cu" "In15.Cu")
		(hatch none 0.5)
		(connect_pads
			(clearance 0)
		)
		(min_thickness 0.25)
		(keepout
			(tracks not_allowed)
			(vias allowed)
			(pads allowed)
			(copperpour not_allowed)
			(footprints allowed)
		)
		(placement
			(enabled no)
			(sheetname "")
		)
		(fill yes
			(thermal_gap 0.5)
			(thermal_bridge_width 0.5)
			(island_removal_mode 0)
		)
		(polygon
			(pts
				(arc
					(start 339.186012 -288.66592)
					(mid 338.556092 -288.66592)
					(end 339.186012 -288.66592)
				)
			)
		)
	)
	(zone
		(layers "B.Cu" "In6.Cu" "In11.Cu" "In13.Cu" "In15.Cu")
		(hatch none 0.5)
		(connect_pads
			(clearance 0)
		)
		(min_thickness 0.25)
		(keepout
			(tracks not_allowed)
			(vias allowed)
			(pads allowed)
			(copperpour not_allowed)
			(footprints allowed)
		)
		(placement
			(enabled no)
			(sheetname "")
		)
		(fill yes
			(thermal_gap 0.5)
			(thermal_bridge_width 0.5)
			(island_removal_mode 0)
		)
		(polygon
			(pts
				(arc
					(start 37.129974 -276.385274)
					(mid 36.461954 -276.385274)
					(end 37.129974 -276.385274)
				)
			)
		)
	)
	(zone
		(layers "B.Cu" "In6.Cu" "In11.Cu" "In13.Cu" "In15.Cu")
		(hatch none 0.5)
		(connect_pads
			(clearance 0)
		)
		(min_thickness 0.25)
		(keepout
			(tracks not_allowed)
			(vias allowed)
			(pads allowed)
			(copperpour not_allowed)
			(footprints allowed)
		)
		(placement
			(enabled no)
			(sheetname "")
		)
		(fill yes
			(thermal_gap 0.5)
			(thermal_bridge_width 0.5)
			(island_removal_mode 0)
		)
		(polygon
			(pts
				(arc
					(start 339.355938 -254.204216)
					(mid 338.726018 -254.204216)
					(end 339.355938 -254.204216)
				)
			)
		)
	)
	(zone
		(layers "B.Cu" "In6.Cu" "In11.Cu" "In13.Cu" "In15.Cu")
		(hatch none 0.5)
		(connect_pads
			(clearance 0)
		)
		(min_thickness 0.25)
		(keepout
			(tracks not_allowed)
			(vias allowed)
			(pads allowed)
			(copperpour not_allowed)
			(footprints allowed)
		)
		(placement
			(enabled no)
			(sheetname "")
		)
		(fill yes
			(thermal_gap 0.5)
			(thermal_bridge_width 0.5)
			(island_removal_mode 0)
		)
		(polygon
			(pts
				(arc
					(start 317.244476 -412.84652)
					(mid 316.576456 -412.84652)
					(end 317.244476 -412.84652)
				)
			)
		)
	)
	(zone
		(layers "B.Cu" "In6.Cu" "In11.Cu" "In13.Cu" "In15.Cu")
		(hatch none 0.5)
		(connect_pads
			(clearance 0)
		)
		(min_thickness 0.25)
		(keepout
			(tracks not_allowed)
			(vias allowed)
			(pads allowed)
			(copperpour not_allowed)
			(footprints allowed)
		)
		(placement
			(enabled no)
			(sheetname "")
		)
		(fill yes
			(thermal_gap 0.5)
			(thermal_bridge_width 0.5)
			(island_removal_mode 0)
		)
		(polygon
			(pts
				(arc
					(start 187.394088 -263.635236)
					(mid 186.726068 -263.635236)
					(end 187.394088 -263.635236)
				)
			)
		)
	)
	(zone
		(layers "B.Cu" "In6.Cu" "In11.Cu" "In13.Cu" "In15.Cu")
		(hatch none 0.5)
		(connect_pads
			(clearance 0)
		)
		(min_thickness 0.25)
		(keepout
			(tracks not_allowed)
			(vias allowed)
			(pads allowed)
			(copperpour not_allowed)
			(footprints allowed)
		)
		(placement
			(enabled no)
			(sheetname "")
		)
		(fill yes
			(thermal_gap 0.5)
			(thermal_bridge_width 0.5)
			(island_removal_mode 0)
		)
		(polygon
			(pts
				(arc
					(start 90.94597 -251.774452)
					(mid 90.31605 -251.774452)
					(end 90.94597 -251.774452)
				)
			)
		)
	)
	(zone
		(layers "B.Cu" "In6.Cu" "In11.Cu" "In13.Cu" "In15.Cu")
		(hatch none 0.5)
		(connect_pads
			(clearance 0)
		)
		(min_thickness 0.25)
		(keepout
			(tracks not_allowed)
			(vias allowed)
			(pads allowed)
			(copperpour not_allowed)
			(footprints allowed)
		)
		(placement
			(enabled no)
			(sheetname "")
		)
		(fill yes
			(thermal_gap 0.5)
			(thermal_bridge_width 0.5)
			(island_removal_mode 0)
		)
		(polygon
			(pts
				(arc
					(start 91.41587 -247.724422)
					(mid 90.78595 -247.724422)
					(end 91.41587 -247.724422)
				)
			)
		)
	)
	(zone
		(layers "B.Cu" "In6.Cu" "In11.Cu" "In13.Cu" "In15.Cu")
		(hatch none 0.5)
		(connect_pads
			(clearance 0)
		)
		(min_thickness 0.25)
		(keepout
			(tracks not_allowed)
			(vias allowed)
			(pads allowed)
			(copperpour not_allowed)
			(footprints allowed)
		)
		(placement
			(enabled no)
			(sheetname "")
		)
		(fill yes
			(thermal_gap 0.5)
			(thermal_bridge_width 0.5)
			(island_removal_mode 0)
		)
		(polygon
			(pts
				(arc
					(start 340.766146 -243.674138)
					(mid 340.136226 -243.674138)
					(end 340.766146 -243.674138)
				)
			)
		)
	)
	(zone
		(layers "B.Cu" "In6.Cu" "In11.Cu" "In13.Cu" "In15.Cu")
		(hatch none 0.5)
		(connect_pads
			(clearance 0)
		)
		(min_thickness 0.25)
		(keepout
			(tracks not_allowed)
			(vias allowed)
			(pads allowed)
			(copperpour not_allowed)
			(footprints allowed)
		)
		(placement
			(enabled no)
			(sheetname "")
		)
		(fill yes
			(thermal_gap 0.5)
			(thermal_bridge_width 0.5)
			(island_removal_mode 0)
		)
		(polygon
			(pts
				(arc
					(start 285.070042 -240.685066)
					(mid 284.402022 -240.685066)
					(end 285.070042 -240.685066)
				)
			)
		)
	)
	(zone
		(layers "B.Cu" "In6.Cu" "In11.Cu" "In13.Cu" "In15.Cu")
		(hatch none 0.5)
		(connect_pads
			(clearance 0)
		)
		(min_thickness 0.25)
		(keepout
			(tracks not_allowed)
			(vias allowed)
			(pads allowed)
			(copperpour not_allowed)
			(footprints allowed)
		)
		(placement
			(enabled no)
			(sheetname "")
		)
		(fill yes
			(thermal_gap 0.5)
			(thermal_bridge_width 0.5)
			(island_removal_mode 0)
		)
		(polygon
			(pts
				(arc
					(start 340.295992 -250.964192)
					(mid 339.666072 -250.964192)
					(end 340.295992 -250.964192)
				)
			)
		)
	)
	(zone
		(layers "B.Cu" "In6.Cu" "In11.Cu" "In13.Cu" "In15.Cu")
		(hatch none 0.5)
		(connect_pads
			(clearance 0)
		)
		(min_thickness 0.25)
		(keepout
			(tracks not_allowed)
			(vias allowed)
			(pads allowed)
			(copperpour not_allowed)
			(footprints allowed)
		)
		(placement
			(enabled no)
			(sheetname "")
		)
		(fill yes
			(thermal_gap 0.5)
			(thermal_bridge_width 0.5)
			(island_removal_mode 0)
		)
		(polygon
			(pts
				(arc
					(start 37.129974 -210.935316)
					(mid 36.461954 -210.935316)
					(end 37.129974 -210.935316)
				)
			)
		)
	)
	(zone
		(layers "B.Cu" "In6.Cu" "In11.Cu" "In13.Cu" "In15.Cu")
		(hatch none 0.5)
		(connect_pads
			(clearance 0)
		)
		(min_thickness 0.25)
		(keepout
			(tracks not_allowed)
			(vias allowed)
			(pads allowed)
			(copperpour not_allowed)
			(footprints allowed)
		)
		(placement
			(enabled no)
			(sheetname "")
		)
		(fill yes
			(thermal_gap 0.5)
			(thermal_bridge_width 0.5)
			(island_removal_mode 0)
		)
		(polygon
			(pts
				(arc
					(start 439.434224 -278.085042)
					(mid 438.766204 -278.085042)
					(end 439.434224 -278.085042)
				)
			)
		)
	)
	(zone
		(layers "B.Cu" "In6.Cu" "In11.Cu" "In13.Cu" "In15.Cu")
		(hatch none 0.5)
		(connect_pads
			(clearance 0)
		)
		(min_thickness 0.25)
		(keepout
			(tracks not_allowed)
			(vias allowed)
			(pads allowed)
			(copperpour not_allowed)
			(footprints allowed)
		)
		(placement
			(enabled no)
			(sheetname "")
		)
		(fill yes
			(thermal_gap 0.5)
			(thermal_bridge_width 0.5)
			(island_removal_mode 0)
		)
		(polygon
			(pts
				(arc
					(start 133.239764 -232.334308)
					(mid 132.609844 -232.334308)
					(end 133.239764 -232.334308)
				)
			)
		)
	)
	(zone
		(layers "B.Cu" "In6.Cu" "In11.Cu" "In13.Cu" "In15.Cu")
		(hatch none 0.5)
		(connect_pads
			(clearance 0)
		)
		(min_thickness 0.25)
		(keepout
			(tracks not_allowed)
			(vias allowed)
			(pads allowed)
			(copperpour not_allowed)
			(footprints allowed)
		)
		(placement
			(enabled no)
			(sheetname "")
		)
		(fill yes
			(thermal_gap 0.5)
			(thermal_bridge_width 0.5)
			(island_removal_mode 0)
		)
		(polygon
			(pts
				(arc
					(start 381.179832 -229.094284)
					(mid 380.549912 -229.094284)
					(end 381.179832 -229.094284)
				)
			)
		)
	)
	(zone
		(layers "B.Cu" "In6.Cu" "In11.Cu" "In13.Cu" "In15.Cu")
		(hatch none 0.5)
		(connect_pads
			(clearance 0)
		)
		(min_thickness 0.25)
		(keepout
			(tracks not_allowed)
			(vias allowed)
			(pads allowed)
			(copperpour not_allowed)
			(footprints allowed)
		)
		(placement
			(enabled no)
			(sheetname "")
		)
		(fill yes
			(thermal_gap 0.5)
			(thermal_bridge_width 0.5)
			(island_removal_mode 0)
		)
		(polygon
			(pts
				(arc
					(start 379.769878 -246.104156)
					(mid 379.139958 -246.104156)
					(end 379.769878 -246.104156)
				)
			)
		)
	)
	(zone
		(layers "B.Cu" "In6.Cu" "In11.Cu" "In13.Cu" "In15.Cu")
		(hatch none 0.5)
		(connect_pads
			(clearance 0)
		)
		(min_thickness 0.25)
		(keepout
			(tracks not_allowed)
			(vias allowed)
			(pads allowed)
			(copperpour not_allowed)
			(footprints allowed)
		)
		(placement
			(enabled no)
			(sheetname "")
		)
		(fill yes
			(thermal_gap 0.5)
			(thermal_bridge_width 0.5)
			(island_removal_mode 0)
		)
		(polygon
			(pts
				(arc
					(start 127.481076 -404.46452)
					(mid 126.813056 -404.46452)
					(end 127.481076 -404.46452)
				)
			)
		)
	)
	(zone
		(layers "B.Cu" "In6.Cu" "In11.Cu" "In13.Cu" "In15.Cu")
		(hatch none 0.5)
		(connect_pads
			(clearance 0)
		)
		(min_thickness 0.25)
		(keepout
			(tracks not_allowed)
			(vias allowed)
			(pads allowed)
			(copperpour not_allowed)
			(footprints allowed)
		)
		(placement
			(enabled no)
			(sheetname "")
		)
		(fill yes
			(thermal_gap 0.5)
			(thermal_bridge_width 0.5)
			(island_removal_mode 0)
		)
		(polygon
			(pts
				(arc
					(start 37.129974 -200.735438)
					(mid 36.461954 -200.735438)
					(end 37.129974 -200.735438)
				)
			)
		)
	)
	(zone
		(layers "B.Cu" "In6.Cu" "In11.Cu" "In13.Cu" "In15.Cu")
		(hatch none 0.5)
		(connect_pads
			(clearance 0)
		)
		(min_thickness 0.25)
		(keepout
			(tracks not_allowed)
			(vias allowed)
			(pads allowed)
			(copperpour not_allowed)
			(footprints allowed)
		)
		(placement
			(enabled no)
			(sheetname "")
		)
		(fill yes
			(thermal_gap 0.5)
			(thermal_bridge_width 0.5)
			(island_removal_mode 0)
		)
		(polygon
			(pts
				(arc
					(start 37.129974 -229.635304)
					(mid 36.461954 -229.635304)
					(end 37.129974 -229.635304)
				)
			)
		)
	)
	(zone
		(layers "B.Cu" "In6.Cu" "In11.Cu" "In13.Cu" "In15.Cu")
		(hatch none 0.5)
		(connect_pads
			(clearance 0)
		)
		(min_thickness 0.25)
		(keepout
			(tracks not_allowed)
			(vias allowed)
			(pads allowed)
			(copperpour not_allowed)
			(footprints allowed)
		)
		(placement
			(enabled no)
			(sheetname "")
		)
		(fill yes
			(thermal_gap 0.5)
			(thermal_bridge_width 0.5)
			(island_removal_mode 0)
		)
		(polygon
			(pts
				(arc
					(start 187.394088 -288.285428)
					(mid 186.726068 -288.285428)
					(end 187.394088 -288.285428)
				)
			)
		)
	)
	(zone
		(layers "B.Cu" "In6.Cu" "In11.Cu" "In13.Cu" "In15.Cu")
		(hatch none 0.5)
		(connect_pads
			(clearance 0)
		)
		(min_thickness 0.25)
		(keepout
			(tracks not_allowed)
			(vias allowed)
			(pads allowed)
			(copperpour not_allowed)
			(footprints allowed)
		)
		(placement
			(enabled no)
			(sheetname "")
		)
		(fill yes
			(thermal_gap 0.5)
			(thermal_bridge_width 0.5)
			(island_removal_mode 0)
		)
		(polygon
			(pts
				(arc
					(start 191.494156 -273.835368)
					(mid 190.826136 -273.835368)
					(end 191.494156 -273.835368)
				)
			)
		)
	)
	(zone
		(layers "B.Cu" "In6.Cu" "In11.Cu" "In13.Cu" "In15.Cu")
		(hatch none 0.5)
		(connect_pads
			(clearance 0)
		)
		(min_thickness 0.25)
		(keepout
			(tracks not_allowed)
			(vias allowed)
			(pads allowed)
			(copperpour not_allowed)
			(footprints allowed)
		)
		(placement
			(enabled no)
			(sheetname "")
		)
		(fill yes
			(thermal_gap 0.5)
			(thermal_bridge_width 0.5)
			(island_removal_mode 0)
		)
		(polygon
			(pts
				(arc
					(start 92.355924 -255.824482)
					(mid 91.726004 -255.824482)
					(end 92.355924 -255.824482)
				)
			)
		)
	)
	(zone
		(layers "B.Cu" "In6.Cu" "In11.Cu" "In13.Cu" "In15.Cu")
		(hatch none 0.5)
		(connect_pads
			(clearance 0)
		)
		(min_thickness 0.25)
		(keepout
			(tracks not_allowed)
			(vias allowed)
			(pads allowed)
			(copperpour not_allowed)
			(footprints allowed)
		)
		(placement
			(enabled no)
			(sheetname "")
		)
		(fill yes
			(thermal_gap 0.5)
			(thermal_bridge_width 0.5)
			(island_removal_mode 0)
		)
		(polygon
			(pts
				(arc
					(start 381.479806 -274.086066)
					(mid 380.849886 -274.086066)
					(end 381.479806 -274.086066)
				)
			)
		)
	)
	(zone
		(layers "B.Cu" "In6.Cu" "In11.Cu" "In13.Cu" "In15.Cu")
		(hatch none 0.5)
		(connect_pads
			(clearance 0)
		)
		(min_thickness 0.25)
		(keepout
			(tracks not_allowed)
			(vias allowed)
			(pads allowed)
			(copperpour not_allowed)
			(footprints allowed)
		)
		(placement
			(enabled no)
			(sheetname "")
		)
		(fill yes
			(thermal_gap 0.5)
			(thermal_bridge_width 0.5)
			(island_removal_mode 0)
		)
		(polygon
			(pts
				(arc
					(start 340.766146 -245.29415)
					(mid 340.136226 -245.29415)
					(end 340.766146 -245.29415)
				)
			)
		)
	)
	(zone
		(layers "B.Cu" "In6.Cu" "In11.Cu" "In13.Cu" "In15.Cu")
		(hatch none 0.5)
		(connect_pads
			(clearance 0)
		)
		(min_thickness 0.25)
		(keepout
			(tracks not_allowed)
			(vias allowed)
			(pads allowed)
			(copperpour not_allowed)
			(footprints allowed)
		)
		(placement
			(enabled no)
			(sheetname "")
		)
		(fill yes
			(thermal_gap 0.5)
			(thermal_bridge_width 0.5)
			(island_removal_mode 0)
		)
		(polygon
			(pts
				(arc
					(start 133.539738 -291.906198)
					(mid 132.909818 -291.906198)
					(end 133.539738 -291.906198)
				)
			)
		)
	)
	(zone
		(layers "B.Cu" "In6.Cu" "In11.Cu" "In13.Cu" "In15.Cu")
		(hatch none 0.5)
		(connect_pads
			(clearance 0)
		)
		(min_thickness 0.25)
		(keepout
			(tracks not_allowed)
			(vias allowed)
			(pads allowed)
			(copperpour not_allowed)
			(footprints allowed)
		)
		(placement
			(enabled no)
			(sheetname "")
		)
		(fill yes
			(thermal_gap 0.5)
			(thermal_bridge_width 0.5)
			(island_removal_mode 0)
		)
		(polygon
			(pts
				(arc
					(start 340.595966 -276.516084)
					(mid 339.966046 -276.516084)
					(end 340.595966 -276.516084)
				)
			)
		)
	)
	(zone
		(layers "B.Cu" "In6.Cu" "In11.Cu" "In13.Cu" "In15.Cu")
		(hatch none 0.5)
		(connect_pads
			(clearance 0)
		)
		(min_thickness 0.25)
		(keepout
			(tracks not_allowed)
			(vias allowed)
			(pads allowed)
			(copperpour not_allowed)
			(footprints allowed)
		)
		(placement
			(enabled no)
			(sheetname "")
		)
		(fill yes
			(thermal_gap 0.5)
			(thermal_bridge_width 0.5)
			(island_removal_mode 0)
		)
		(polygon
			(pts
				(arc
					(start 191.494156 -292.535356)
					(mid 190.826136 -292.535356)
					(end 191.494156 -292.535356)
				)
			)
		)
	)
	(zone
		(layers "B.Cu" "In6.Cu" "In11.Cu" "In13.Cu" "In15.Cu")
		(hatch none 0.5)
		(connect_pads
			(clearance 0)
		)
		(min_thickness 0.25)
		(keepout
			(tracks not_allowed)
			(vias allowed)
			(pads allowed)
			(copperpour not_allowed)
			(footprints allowed)
		)
		(placement
			(enabled no)
			(sheetname "")
		)
		(fill yes
			(thermal_gap 0.5)
			(thermal_bridge_width 0.5)
			(island_removal_mode 0)
		)
		(polygon
			(pts
				(arc
					(start 37.129974 -270.435324)
					(mid 36.461954 -270.435324)
					(end 37.129974 -270.435324)
				)
			)
		)
	)
	(zone
		(layers "B.Cu" "In6.Cu" "In11.Cu" "In13.Cu" "In15.Cu")
		(hatch none 0.5)
		(connect_pads
			(clearance 0)
		)
		(min_thickness 0.25)
		(keepout
			(tracks not_allowed)
			(vias allowed)
			(pads allowed)
			(copperpour not_allowed)
			(footprints allowed)
		)
		(placement
			(enabled no)
			(sheetname "")
		)
		(fill yes
			(thermal_gap 0.5)
			(thermal_bridge_width 0.5)
			(island_removal_mode 0)
		)
		(polygon
			(pts
				(arc
					(start 154.134058 -389.467344)
					(mid 153.504138 -389.467344)
					(end 154.134058 -389.467344)
				)
			)
		)
	)
	(zone
		(layers "B.Cu" "In6.Cu" "In11.Cu" "In13.Cu" "In15.Cu")
		(hatch none 0.5)
		(connect_pads
			(clearance 0)
		)
		(min_thickness 0.25)
		(keepout
			(tracks not_allowed)
			(vias allowed)
			(pads allowed)
			(copperpour not_allowed)
			(footprints allowed)
		)
		(placement
			(enabled no)
			(sheetname "")
		)
		(fill yes
			(thermal_gap 0.5)
			(thermal_bridge_width 0.5)
			(island_removal_mode 0)
		)
		(polygon
			(pts
				(arc
					(start 386.006086 -394.385292)
					(mid 385.376166 -394.385292)
					(end 386.006086 -394.385292)
				)
			)
		)
	)
	(zone
		(layers "B.Cu" "In6.Cu" "In11.Cu" "In13.Cu" "In15.Cu")
		(hatch none 0.5)
		(connect_pads
			(clearance 0)
		)
		(min_thickness 0.25)
		(keepout
			(tracks not_allowed)
			(vias allowed)
			(pads allowed)
			(copperpour not_allowed)
			(footprints allowed)
		)
		(placement
			(enabled no)
			(sheetname "")
		)
		(fill yes
			(thermal_gap 0.5)
			(thermal_bridge_width 0.5)
			(island_removal_mode 0)
		)
		(polygon
			(pts
				(arc
					(start 439.434224 -298.485052)
					(mid 438.766204 -298.485052)
					(end 439.434224 -298.485052)
				)
			)
		)
	)
	(zone
		(layers "B.Cu" "In6.Cu" "In11.Cu" "In13.Cu" "In15.Cu")
		(hatch none 0.5)
		(connect_pads
			(clearance 0)
		)
		(min_thickness 0.25)
		(keepout
			(tracks not_allowed)
			(vias allowed)
			(pads allowed)
			(copperpour not_allowed)
			(footprints allowed)
		)
		(placement
			(enabled no)
			(sheetname "")
		)
		(fill yes
			(thermal_gap 0.5)
			(thermal_bridge_width 0.5)
			(island_removal_mode 0)
		)
		(polygon
			(pts
				(arc
					(start 191.494156 -201.585322)
					(mid 190.826136 -201.585322)
					(end 191.494156 -201.585322)
				)
			)
		)
	)
	(zone
		(layers "B.Cu" "In6.Cu" "In11.Cu" "In13.Cu" "In15.Cu")
		(hatch none 0.5)
		(connect_pads
			(clearance 0)
		)
		(min_thickness 0.25)
		(keepout
			(tracks not_allowed)
			(vias allowed)
			(pads allowed)
			(copperpour not_allowed)
			(footprints allowed)
		)
		(placement
			(enabled no)
			(sheetname "")
		)
		(fill yes
			(thermal_gap 0.5)
			(thermal_bridge_width 0.5)
			(island_removal_mode 0)
		)
		(polygon
			(pts
				(arc
					(start 381.479806 -275.706078)
					(mid 380.849886 -275.706078)
					(end 381.479806 -275.706078)
				)
			)
		)
	)
	(zone
		(layers "B.Cu" "In6.Cu" "In11.Cu" "In13.Cu" "In15.Cu")
		(hatch none 0.5)
		(connect_pads
			(clearance 0)
		)
		(min_thickness 0.25)
		(keepout
			(tracks not_allowed)
			(vias allowed)
			(pads allowed)
			(copperpour not_allowed)
			(footprints allowed)
		)
		(placement
			(enabled no)
			(sheetname "")
		)
		(fill yes
			(thermal_gap 0.5)
			(thermal_bridge_width 0.5)
			(island_removal_mode 0)
		)
		(polygon
			(pts
				(arc
					(start 349.056198 -287.856168)
					(mid 348.426278 -287.856168)
					(end 349.056198 -287.856168)
				)
			)
		)
	)
	(zone
		(layers "B.Cu" "In6.Cu" "In11.Cu" "In13.Cu" "In15.Cu")
		(hatch none 0.5)
		(connect_pads
			(clearance 0)
		)
		(min_thickness 0.25)
		(keepout
			(tracks not_allowed)
			(vias allowed)
			(pads allowed)
			(copperpour not_allowed)
			(footprints allowed)
		)
		(placement
			(enabled no)
			(sheetname "")
		)
		(fill yes
			(thermal_gap 0.5)
			(thermal_bridge_width 0.5)
			(island_removal_mode 0)
		)
		(polygon
			(pts
				(arc
					(start 92.355924 -252.584458)
					(mid 91.726004 -252.584458)
					(end 92.355924 -252.584458)
				)
			)
		)
	)
	(zone
		(layers "B.Cu" "In6.Cu" "In11.Cu" "In13.Cu" "In15.Cu")
		(hatch none 0.5)
		(connect_pads
			(clearance 0)
		)
		(min_thickness 0.25)
		(keepout
			(tracks not_allowed)
			(vias allowed)
			(pads allowed)
			(copperpour not_allowed)
			(footprints allowed)
		)
		(placement
			(enabled no)
			(sheetname "")
		)
		(fill yes
			(thermal_gap 0.5)
			(thermal_bridge_width 0.5)
			(island_removal_mode 0)
		)
		(polygon
			(pts
				(arc
					(start 191.494156 -303.585372)
					(mid 190.826136 -303.585372)
					(end 191.494156 -303.585372)
				)
			)
		)
	)
	(zone
		(layers "B.Cu" "In6.Cu" "In11.Cu" "In13.Cu" "In15.Cu")
		(hatch none 0.5)
		(connect_pads
			(clearance 0)
		)
		(min_thickness 0.25)
		(keepout
			(tracks not_allowed)
			(vias allowed)
			(pads allowed)
			(copperpour not_allowed)
			(footprints allowed)
		)
		(placement
			(enabled no)
			(sheetname "")
		)
		(fill yes
			(thermal_gap 0.5)
			(thermal_bridge_width 0.5)
			(island_removal_mode 0)
		)
		(polygon
			(pts
				(arc
					(start 280.969974 -211.784946)
					(mid 280.301954 -211.784946)
					(end 280.969974 -211.784946)
				)
			)
		)
	)
	(zone
		(layers "B.Cu" "In6.Cu" "In11.Cu" "In13.Cu" "In15.Cu")
		(hatch none 0.5)
		(connect_pads
			(clearance 0)
		)
		(min_thickness 0.25)
		(keepout
			(tracks not_allowed)
			(vias allowed)
			(pads allowed)
			(copperpour not_allowed)
			(footprints allowed)
		)
		(placement
			(enabled no)
			(sheetname "")
		)
		(fill yes
			(thermal_gap 0.5)
			(thermal_bridge_width 0.5)
			(island_removal_mode 0)
		)
		(polygon
			(pts
				(arc
					(start 340.595966 -261.935976)
					(mid 339.966046 -261.935976)
					(end 340.595966 -261.935976)
				)
			)
		)
	)
	(zone
		(layers "B.Cu" "In6.Cu" "In11.Cu" "In13.Cu" "In15.Cu")
		(hatch none 0.5)
		(connect_pads
			(clearance 0)
		)
		(min_thickness 0.25)
		(keepout
			(tracks not_allowed)
			(vias allowed)
			(pads allowed)
			(copperpour not_allowed)
			(footprints allowed)
		)
		(placement
			(enabled no)
			(sheetname "")
		)
		(fill yes
			(thermal_gap 0.5)
			(thermal_bridge_width 0.5)
			(island_removal_mode 0)
		)
		(polygon
			(pts
				(arc
					(start 380.709678 -236.384084)
					(mid 380.079758 -236.384084)
					(end 380.709678 -236.384084)
				)
			)
		)
	)
	(zone
		(layers "B.Cu" "In6.Cu" "In11.Cu" "In13.Cu" "In15.Cu")
		(hatch none 0.5)
		(connect_pads
			(clearance 0)
		)
		(min_thickness 0.25)
		(keepout
			(tracks not_allowed)
			(vias allowed)
			(pads allowed)
			(copperpour not_allowed)
			(footprints allowed)
		)
		(placement
			(enabled no)
			(sheetname "")
		)
		(fill yes
			(thermal_gap 0.5)
			(thermal_bridge_width 0.5)
			(island_removal_mode 0)
		)
		(polygon
			(pts
				(arc
					(start 285.070042 -283.185108)
					(mid 284.402022 -283.185108)
					(end 285.070042 -283.185108)
				)
			)
		)
	)
	(zone
		(layers "B.Cu" "In6.Cu" "In11.Cu" "In13.Cu" "In15.Cu")
		(hatch none 0.5)
		(connect_pads
			(clearance 0)
		)
		(min_thickness 0.25)
		(keepout
			(tracks not_allowed)
			(vias allowed)
			(pads allowed)
			(copperpour not_allowed)
			(footprints allowed)
		)
		(placement
			(enabled no)
			(sheetname "")
		)
		(fill yes
			(thermal_gap 0.5)
			(thermal_bridge_width 0.5)
			(island_removal_mode 0)
		)
		(polygon
			(pts
				(arc
					(start 133.539738 -285.426404)
					(mid 132.909818 -285.426404)
					(end 133.539738 -285.426404)
				)
			)
		)
	)
	(zone
		(layers "B.Cu" "In6.Cu" "In11.Cu" "In13.Cu" "In15.Cu")
		(hatch none 0.5)
		(connect_pads
			(clearance 0)
		)
		(min_thickness 0.25)
		(keepout
			(tracks not_allowed)
			(vias allowed)
			(pads allowed)
			(copperpour not_allowed)
			(footprints allowed)
		)
		(placement
			(enabled no)
			(sheetname "")
		)
		(fill yes
			(thermal_gap 0.5)
			(thermal_bridge_width 0.5)
			(island_removal_mode 0)
		)
		(polygon
			(pts
				(arc
					(start 191.494156 -247.485408)
					(mid 190.826136 -247.485408)
					(end 191.494156 -247.485408)
				)
			)
		)
	)
	(zone
		(layers "B.Cu" "In6.Cu" "In11.Cu" "In13.Cu" "In15.Cu")
		(hatch none 0.5)
		(connect_pads
			(clearance 0)
		)
		(min_thickness 0.25)
		(keepout
			(tracks not_allowed)
			(vias allowed)
			(pads allowed)
			(copperpour not_allowed)
			(footprints allowed)
		)
		(placement
			(enabled no)
			(sheetname "")
		)
		(fill yes
			(thermal_gap 0.5)
			(thermal_bridge_width 0.5)
			(island_removal_mode 0)
		)
		(polygon
			(pts
				(arc
					(start 435.334156 -227.935028)
					(mid 434.666136 -227.935028)
					(end 435.334156 -227.935028)
				)
			)
		)
	)
	(zone
		(layers "B.Cu" "In6.Cu" "In11.Cu" "In13.Cu" "In15.Cu")
		(hatch none 0.5)
		(connect_pads
			(clearance 0)
		)
		(min_thickness 0.25)
		(keepout
			(tracks not_allowed)
			(vias allowed)
			(pads allowed)
			(copperpour not_allowed)
			(footprints allowed)
		)
		(placement
			(enabled no)
			(sheetname "")
		)
		(fill yes
			(thermal_gap 0.5)
			(thermal_bridge_width 0.5)
			(island_removal_mode 0)
		)
		(polygon
			(pts
				(arc
					(start 131.82981 -249.344434)
					(mid 131.19989 -249.344434)
					(end 131.82981 -249.344434)
				)
			)
		)
	)
	(zone
		(layers "B.Cu" "In6.Cu" "In11.Cu" "In13.Cu" "In15.Cu")
		(hatch none 0.5)
		(connect_pads
			(clearance 0)
		)
		(min_thickness 0.25)
		(keepout
			(tracks not_allowed)
			(vias allowed)
			(pads allowed)
			(copperpour not_allowed)
			(footprints allowed)
		)
		(placement
			(enabled no)
			(sheetname "")
		)
		(fill yes
			(thermal_gap 0.5)
			(thermal_bridge_width 0.5)
			(island_removal_mode 0)
		)
		(polygon
			(pts
				(arc
					(start 191.494156 -227.085398)
					(mid 190.826136 -227.085398)
					(end 191.494156 -227.085398)
				)
			)
		)
	)
	(zone
		(layers "B.Cu" "In6.Cu" "In11.Cu" "In13.Cu" "In15.Cu")
		(hatch none 0.5)
		(connect_pads
			(clearance 0)
		)
		(min_thickness 0.25)
		(keepout
			(tracks not_allowed)
			(vias allowed)
			(pads allowed)
			(copperpour not_allowed)
			(footprints allowed)
		)
		(placement
			(enabled no)
			(sheetname "")
		)
		(fill yes
			(thermal_gap 0.5)
			(thermal_bridge_width 0.5)
			(island_removal_mode 0)
		)
		(polygon
			(pts
				(arc
					(start 439.434224 -272.135092)
					(mid 438.766204 -272.135092)
					(end 439.434224 -272.135092)
				)
			)
		)
	)
	(zone
		(layers "B.Cu" "In6.Cu" "In11.Cu" "In13.Cu" "In15.Cu")
		(hatch none 0.5)
		(connect_pads
			(clearance 0)
		)
		(min_thickness 0.25)
		(keepout
			(tracks not_allowed)
			(vias allowed)
			(pads allowed)
			(copperpour not_allowed)
			(footprints allowed)
		)
		(placement
			(enabled no)
			(sheetname "")
		)
		(fill yes
			(thermal_gap 0.5)
			(thermal_bridge_width 0.5)
			(island_removal_mode 0)
		)
		(polygon
			(pts
				(arc
					(start 430.68621 -17.613122)
					(mid 430.01819 -17.613122)
					(end 430.68621 -17.613122)
				)
			)
		)
	)
	(zone
		(layers "B.Cu" "In6.Cu" "In11.Cu" "In13.Cu" "In15.Cu")
		(hatch none 0.5)
		(connect_pads
			(clearance 0)
		)
		(min_thickness 0.25)
		(keepout
			(tracks not_allowed)
			(vias allowed)
			(pads allowed)
			(copperpour not_allowed)
			(footprints allowed)
		)
		(placement
			(enabled no)
			(sheetname "")
		)
		(fill yes
			(thermal_gap 0.5)
			(thermal_bridge_width 0.5)
			(island_removal_mode 0)
		)
		(polygon
			(pts
				(arc
					(start 340.595966 -271.656048)
					(mid 339.966046 -271.656048)
					(end 340.595966 -271.656048)
				)
			)
		)
	)
	(zone
		(layers "B.Cu" "In6.Cu" "In11.Cu" "In13.Cu" "In15.Cu")
		(hatch none 0.5)
		(connect_pads
			(clearance 0)
		)
		(min_thickness 0.25)
		(keepout
			(tracks not_allowed)
			(vias allowed)
			(pads allowed)
			(copperpour not_allowed)
			(footprints allowed)
		)
		(placement
			(enabled no)
			(sheetname "")
		)
		(fill yes
			(thermal_gap 0.5)
			(thermal_bridge_width 0.5)
			(island_removal_mode 0)
		)
		(polygon
			(pts
				(arc
					(start 124.417836 -404.46452)
					(mid 123.749816 -404.46452)
					(end 124.417836 -404.46452)
				)
			)
		)
	)
	(zone
		(layers "B.Cu" "In6.Cu" "In11.Cu" "In13.Cu" "In15.Cu")
		(hatch none 0.5)
		(connect_pads
			(clearance 0)
		)
		(min_thickness 0.25)
		(keepout
			(tracks not_allowed)
			(vias allowed)
			(pads allowed)
			(copperpour not_allowed)
			(footprints allowed)
		)
		(placement
			(enabled no)
			(sheetname "")
		)
		(fill yes
			(thermal_gap 0.5)
			(thermal_bridge_width 0.5)
			(island_removal_mode 0)
		)
		(polygon
			(pts
				(arc
					(start 439.434224 -210.935062)
					(mid 438.766204 -210.935062)
					(end 439.434224 -210.935062)
				)
			)
		)
	)
	(zone
		(layers "B.Cu" "In6.Cu" "In11.Cu" "In13.Cu" "In15.Cu")
		(hatch none 0.5)
		(connect_pads
			(clearance 0)
		)
		(min_thickness 0.25)
		(keepout
			(tracks not_allowed)
			(vias allowed)
			(pads allowed)
			(copperpour not_allowed)
			(footprints allowed)
		)
		(placement
			(enabled no)
			(sheetname "")
		)
		(fill yes
			(thermal_gap 0.5)
			(thermal_bridge_width 0.5)
			(island_removal_mode 0)
		)
		(polygon
			(pts
				(arc
					(start 435.334156 -265.335004)
					(mid 434.666136 -265.335004)
					(end 435.334156 -265.335004)
				)
			)
		)
	)
	(zone
		(layers "B.Cu" "In6.Cu" "In11.Cu" "In13.Cu" "In15.Cu")
		(hatch none 0.5)
		(connect_pads
			(clearance 0)
		)
		(min_thickness 0.25)
		(keepout
			(tracks not_allowed)
			(vias allowed)
			(pads allowed)
			(copperpour not_allowed)
			(footprints allowed)
		)
		(placement
			(enabled no)
			(sheetname "")
		)
		(fill yes
			(thermal_gap 0.5)
			(thermal_bridge_width 0.5)
			(island_removal_mode 0)
		)
		(polygon
			(pts
				(arc
					(start 122.429778 -226.66452)
					(mid 121.799858 -226.66452)
					(end 122.429778 -226.66452)
				)
			)
		)
	)
	(zone
		(layers "B.Cu" "In6.Cu" "In11.Cu" "In13.Cu" "In15.Cu")
		(hatch none 0.5)
		(connect_pads
			(clearance 0)
		)
		(min_thickness 0.25)
		(keepout
			(tracks not_allowed)
			(vias allowed)
			(pads allowed)
			(copperpour not_allowed)
			(footprints allowed)
		)
		(placement
			(enabled no)
			(sheetname "")
		)
		(fill yes
			(thermal_gap 0.5)
			(thermal_bridge_width 0.5)
			(island_removal_mode 0)
		)
		(polygon
			(pts
				(arc
					(start 339.186012 -287.045908)
					(mid 338.556092 -287.045908)
					(end 339.186012 -287.045908)
				)
			)
		)
	)
	(zone
		(layers "B.Cu" "In6.Cu" "In11.Cu" "In13.Cu" "In15.Cu")
		(hatch none 0.5)
		(connect_pads
			(clearance 0)
		)
		(min_thickness 0.25)
		(keepout
			(tracks not_allowed)
			(vias allowed)
			(pads allowed)
			(copperpour not_allowed)
			(footprints allowed)
		)
		(placement
			(enabled no)
			(sheetname "")
		)
		(fill yes
			(thermal_gap 0.5)
			(thermal_bridge_width 0.5)
			(island_removal_mode 0)
		)
		(polygon
			(pts
				(arc
					(start 280.969974 -238.985044)
					(mid 280.301954 -238.985044)
					(end 280.969974 -238.985044)
				)
			)
		)
	)
	(zone
		(layers "B.Cu" "In6.Cu" "In11.Cu" "In13.Cu" "In15.Cu")
		(hatch none 0.5)
		(connect_pads
			(clearance 0)
		)
		(min_thickness 0.25)
		(keepout
			(tracks not_allowed)
			(vias allowed)
			(pads allowed)
			(copperpour not_allowed)
			(footprints allowed)
		)
		(placement
			(enabled no)
			(sheetname "")
		)
		(fill yes
			(thermal_gap 0.5)
			(thermal_bridge_width 0.5)
			(island_removal_mode 0)
		)
		(polygon
			(pts
				(arc
					(start 187.394088 -239.835436)
					(mid 186.726068 -239.835436)
					(end 187.394088 -239.835436)
				)
			)
		)
	)
	(zone
		(layers "B.Cu" "In6.Cu" "In11.Cu" "In13.Cu" "In15.Cu")
		(hatch none 0.5)
		(connect_pads
			(clearance 0)
		)
		(min_thickness 0.25)
		(keepout
			(tracks not_allowed)
			(vias allowed)
			(pads allowed)
			(copperpour not_allowed)
			(footprints allowed)
		)
		(placement
			(enabled no)
			(sheetname "")
		)
		(fill yes
			(thermal_gap 0.5)
			(thermal_bridge_width 0.5)
			(island_removal_mode 0)
		)
		(polygon
			(pts
				(arc
					(start 341.06612 -291.905944)
					(mid 340.4362 -291.905944)
					(end 341.06612 -291.905944)
				)
			)
		)
	)
	(zone
		(layers "B.Cu" "In6.Cu" "In11.Cu" "In13.Cu" "In15.Cu")
		(hatch none 0.5)
		(connect_pads
			(clearance 0)
		)
		(min_thickness 0.25)
		(keepout
			(tracks not_allowed)
			(vias allowed)
			(pads allowed)
			(copperpour not_allowed)
			(footprints allowed)
		)
		(placement
			(enabled no)
			(sheetname "")
		)
		(fill yes
			(thermal_gap 0.5)
			(thermal_bridge_width 0.5)
			(island_removal_mode 0)
		)
		(polygon
			(pts
				(arc
					(start 132.129784 -286.23641)
					(mid 131.499864 -286.23641)
					(end 132.129784 -286.23641)
				)
			)
		)
	)
	(zone
		(layers "B.Cu" "In6.Cu" "In11.Cu" "In13.Cu" "In15.Cu")
		(hatch none 0.5)
		(connect_pads
			(clearance 0)
		)
		(min_thickness 0.25)
		(keepout
			(tracks not_allowed)
			(vias allowed)
			(pads allowed)
			(copperpour not_allowed)
			(footprints allowed)
		)
		(placement
			(enabled no)
			(sheetname "")
		)
		(fill yes
			(thermal_gap 0.5)
			(thermal_bridge_width 0.5)
			(island_removal_mode 0)
		)
		(polygon
			(pts
				(arc
					(start 380.709678 -255.824228)
					(mid 380.079758 -255.824228)
					(end 380.709678 -255.824228)
				)
			)
		)
	)
	(zone
		(layers "B.Cu" "In6.Cu" "In11.Cu" "In13.Cu" "In15.Cu")
		(hatch none 0.5)
		(connect_pads
			(clearance 0)
		)
		(min_thickness 0.25)
		(keepout
			(tracks not_allowed)
			(vias allowed)
			(pads allowed)
			(copperpour not_allowed)
			(footprints allowed)
		)
		(placement
			(enabled no)
			(sheetname "")
		)
		(fill yes
			(thermal_gap 0.5)
			(thermal_bridge_width 0.5)
			(island_removal_mode 0)
		)
		(polygon
			(pts
				(arc
					(start 338.886038 -232.334054)
					(mid 338.256118 -232.334054)
					(end 338.886038 -232.334054)
				)
			)
		)
	)
	(zone
		(layers "B.Cu" "In6.Cu" "In11.Cu" "In13.Cu" "In15.Cu")
		(hatch none 0.5)
		(connect_pads
			(clearance 0)
		)
		(min_thickness 0.25)
		(keepout
			(tracks not_allowed)
			(vias allowed)
			(pads allowed)
			(copperpour not_allowed)
			(footprints allowed)
		)
		(placement
			(enabled no)
			(sheetname "")
		)
		(fill yes
			(thermal_gap 0.5)
			(thermal_bridge_width 0.5)
			(island_removal_mode 0)
		)
		(polygon
			(pts
				(arc
					(start 91.245944 -283.806392)
					(mid 90.616024 -283.806392)
					(end 91.245944 -283.806392)
				)
			)
		)
	)
	(zone
		(layers "B.Cu" "In6.Cu" "In11.Cu" "In13.Cu" "In15.Cu")
		(hatch none 0.5)
		(connect_pads
			(clearance 0)
		)
		(min_thickness 0.25)
		(keepout
			(tracks not_allowed)
			(vias allowed)
			(pads allowed)
			(copperpour not_allowed)
			(footprints allowed)
		)
		(placement
			(enabled no)
			(sheetname "")
		)
		(fill yes
			(thermal_gap 0.5)
			(thermal_bridge_width 0.5)
			(island_removal_mode 0)
		)
		(polygon
			(pts
				(arc
					(start 92.355924 -233.144314)
					(mid 91.726004 -233.144314)
					(end 92.355924 -233.144314)
				)
			)
		)
	)
	(zone
		(layers "B.Cu" "In6.Cu" "In11.Cu" "In13.Cu" "In15.Cu")
		(hatch none 0.5)
		(connect_pads
			(clearance 0)
		)
		(min_thickness 0.25)
		(keepout
			(tracks not_allowed)
			(vias allowed)
			(pads allowed)
			(copperpour not_allowed)
			(footprints allowed)
		)
		(placement
			(enabled no)
			(sheetname "")
		)
		(fill yes
			(thermal_gap 0.5)
			(thermal_bridge_width 0.5)
			(island_removal_mode 0)
		)
		(polygon
			(pts
				(arc
					(start 285.070042 -238.13516)
					(mid 284.402022 -238.13516)
					(end 285.070042 -238.13516)
				)
			)
		)
	)
	(zone
		(layers "B.Cu" "In6.Cu" "In11.Cu" "In13.Cu" "In15.Cu")
		(hatch none 0.5)
		(connect_pads
			(clearance 0)
		)
		(min_thickness 0.25)
		(keepout
			(tracks not_allowed)
			(vias allowed)
			(pads allowed)
			(copperpour not_allowed)
			(footprints allowed)
		)
		(placement
			(enabled no)
			(sheetname "")
		)
		(fill yes
			(thermal_gap 0.5)
			(thermal_bridge_width 0.5)
			(island_removal_mode 0)
		)
		(polygon
			(pts
				(arc
					(start 92.056712 -369.03533)
					(mid 91.388692 -369.03533)
					(end 92.056712 -369.03533)
				)
			)
		)
	)
	(zone
		(layers "B.Cu" "In6.Cu" "In11.Cu" "In13.Cu" "In15.Cu")
		(hatch none 0.5)
		(connect_pads
			(clearance 0)
		)
		(min_thickness 0.25)
		(keepout
			(tracks not_allowed)
			(vias allowed)
			(pads allowed)
			(copperpour not_allowed)
			(footprints allowed)
		)
		(placement
			(enabled no)
			(sheetname "")
		)
		(fill yes
			(thermal_gap 0.5)
			(thermal_bridge_width 0.5)
			(island_removal_mode 0)
		)
		(polygon
			(pts
				(arc
					(start 214.28329 -4.645406)
					(mid 213.61527 -4.645406)
					(end 214.28329 -4.645406)
				)
			)
		)
	)
	(zone
		(layers "B.Cu" "In6.Cu" "In11.Cu" "In13.Cu" "In15.Cu")
		(hatch none 0.5)
		(connect_pads
			(clearance 0)
		)
		(min_thickness 0.25)
		(keepout
			(tracks not_allowed)
			(vias allowed)
			(pads allowed)
			(copperpour not_allowed)
			(footprints allowed)
		)
		(placement
			(enabled no)
			(sheetname "")
		)
		(fill yes
			(thermal_gap 0.5)
			(thermal_bridge_width 0.5)
			(island_removal_mode 0)
		)
		(polygon
			(pts
				(arc
					(start 187.394088 -261.935214)
					(mid 186.726068 -261.935214)
					(end 187.394088 -261.935214)
				)
			)
		)
	)
	(zone
		(layers "B.Cu" "In6.Cu" "In11.Cu" "In13.Cu" "In15.Cu")
		(hatch none 0.5)
		(connect_pads
			(clearance 0)
		)
		(min_thickness 0.25)
		(keepout
			(tracks not_allowed)
			(vias allowed)
			(pads allowed)
			(copperpour not_allowed)
			(footprints allowed)
		)
		(placement
			(enabled no)
			(sheetname "")
		)
		(fill yes
			(thermal_gap 0.5)
			(thermal_bridge_width 0.5)
			(island_removal_mode 0)
		)
		(polygon
			(pts
				(arc
					(start 187.394088 -220.28531)
					(mid 186.726068 -220.28531)
					(end 187.394088 -220.28531)
				)
			)
		)
	)
	(zone
		(layers "B.Cu" "In6.Cu" "In11.Cu" "In13.Cu" "In15.Cu")
		(hatch none 0.5)
		(connect_pads
			(clearance 0)
		)
		(min_thickness 0.25)
		(keepout
			(tracks not_allowed)
			(vias allowed)
			(pads allowed)
			(copperpour not_allowed)
			(footprints allowed)
		)
		(placement
			(enabled no)
			(sheetname "")
		)
		(fill yes
			(thermal_gap 0.5)
			(thermal_bridge_width 0.5)
			(island_removal_mode 0)
		)
		(polygon
			(pts
				(arc
					(start 37.129974 -219.435426)
					(mid 36.461954 -219.435426)
					(end 37.129974 -219.435426)
				)
			)
		)
	)
	(zone
		(layers "B.Cu" "In6.Cu" "In11.Cu" "In13.Cu" "In15.Cu")
		(hatch none 0.5)
		(connect_pads
			(clearance 0)
		)
		(min_thickness 0.25)
		(keepout
			(tracks not_allowed)
			(vias allowed)
			(pads allowed)
			(copperpour not_allowed)
			(footprints allowed)
		)
		(placement
			(enabled no)
			(sheetname "")
		)
		(fill yes
			(thermal_gap 0.5)
			(thermal_bridge_width 0.5)
			(island_removal_mode 0)
		)
		(polygon
			(pts
				(arc
					(start 131.359656 -229.094538)
					(mid 130.729736 -229.094538)
					(end 131.359656 -229.094538)
				)
			)
		)
	)
	(zone
		(layers "B.Cu" "In6.Cu" "In11.Cu" "In13.Cu" "In15.Cu")
		(hatch none 0.5)
		(connect_pads
			(clearance 0)
		)
		(min_thickness 0.25)
		(keepout
			(tracks not_allowed)
			(vias allowed)
			(pads allowed)
			(copperpour not_allowed)
			(footprints allowed)
		)
		(placement
			(enabled no)
			(sheetname "")
		)
		(fill yes
			(thermal_gap 0.5)
			(thermal_bridge_width 0.5)
			(island_removal_mode 0)
		)
		(polygon
			(pts
				(arc
					(start 355.336094 -228.284278)
					(mid 354.706174 -228.284278)
					(end 355.336094 -228.284278)
				)
			)
		)
	)
	(zone
		(layers "B.Cu" "In6.Cu" "In11.Cu" "In13.Cu" "In15.Cu")
		(hatch none 0.5)
		(connect_pads
			(clearance 0)
		)
		(min_thickness 0.25)
		(keepout
			(tracks not_allowed)
			(vias allowed)
			(pads allowed)
			(copperpour not_allowed)
			(footprints allowed)
		)
		(placement
			(enabled no)
			(sheetname "")
		)
		(fill yes
			(thermal_gap 0.5)
			(thermal_bridge_width 0.5)
			(island_removal_mode 0)
		)
		(polygon
			(pts
				(arc
					(start 381.479806 -280.566114)
					(mid 380.849886 -280.566114)
					(end 381.479806 -280.566114)
				)
			)
		)
	)
	(zone
		(layers "B.Cu" "In6.Cu" "In11.Cu" "In13.Cu" "In15.Cu")
		(hatch none 0.5)
		(connect_pads
			(clearance 0)
		)
		(min_thickness 0.25)
		(keepout
			(tracks not_allowed)
			(vias allowed)
			(pads allowed)
			(copperpour not_allowed)
			(footprints allowed)
		)
		(placement
			(enabled no)
			(sheetname "")
		)
		(fill yes
			(thermal_gap 0.5)
			(thermal_bridge_width 0.5)
			(island_removal_mode 0)
		)
		(polygon
			(pts
				(arc
					(start 280.969974 -276.38502)
					(mid 280.301954 -276.38502)
					(end 280.969974 -276.38502)
				)
			)
		)
	)
	(zone
		(layers "B.Cu" "In6.Cu" "In11.Cu" "In13.Cu" "In15.Cu")
		(hatch none 0.5)
		(connect_pads
			(clearance 0)
		)
		(min_thickness 0.25)
		(keepout
			(tracks not_allowed)
			(vias allowed)
			(pads allowed)
			(copperpour not_allowed)
			(footprints allowed)
		)
		(placement
			(enabled no)
			(sheetname "")
		)
		(fill yes
			(thermal_gap 0.5)
			(thermal_bridge_width 0.5)
			(island_removal_mode 0)
		)
		(polygon
			(pts
				(arc
					(start 339.355938 -225.044254)
					(mid 338.726018 -225.044254)
					(end 339.355938 -225.044254)
				)
			)
		)
	)
	(zone
		(layers "B.Cu" "In6.Cu" "In11.Cu" "In13.Cu" "In15.Cu")
		(hatch none 0.5)
		(connect_pads
			(clearance 0)
		)
		(min_thickness 0.25)
		(keepout
			(tracks not_allowed)
			(vias allowed)
			(pads allowed)
			(copperpour not_allowed)
			(footprints allowed)
		)
		(placement
			(enabled no)
			(sheetname "")
		)
		(fill yes
			(thermal_gap 0.5)
			(thermal_bridge_width 0.5)
			(island_removal_mode 0)
		)
		(polygon
			(pts
				(arc
					(start 191.494156 -262.785352)
					(mid 190.826136 -262.785352)
					(end 191.494156 -262.785352)
				)
			)
		)
	)
	(zone
		(layers "B.Cu" "In6.Cu" "In11.Cu" "In13.Cu" "In15.Cu")
		(hatch none 0.5)
		(connect_pads
			(clearance 0)
		)
		(min_thickness 0.25)
		(keepout
			(tracks not_allowed)
			(vias allowed)
			(pads allowed)
			(copperpour not_allowed)
			(footprints allowed)
		)
		(placement
			(enabled no)
			(sheetname "")
		)
		(fill yes
			(thermal_gap 0.5)
			(thermal_bridge_width 0.5)
			(island_removal_mode 0)
		)
		(polygon
			(pts
				(arc
					(start 314.106052 -397.849344)
					(mid 313.476132 -397.849344)
					(end 314.106052 -397.849344)
				)
			)
		)
	)
	(zone
		(layers "B.Cu" "In6.Cu" "In11.Cu" "In13.Cu" "In15.Cu")
		(hatch none 0.5)
		(connect_pads
			(clearance 0)
		)
		(min_thickness 0.25)
		(keepout
			(tracks not_allowed)
			(vias allowed)
			(pads allowed)
			(copperpour not_allowed)
			(footprints allowed)
		)
		(placement
			(enabled no)
			(sheetname "")
		)
		(fill yes
			(thermal_gap 0.5)
			(thermal_bridge_width 0.5)
			(island_removal_mode 0)
		)
		(polygon
			(pts
				(arc
					(start 285.070042 -217.73515)
					(mid 284.402022 -217.73515)
					(end 285.070042 -217.73515)
				)
			)
		)
	)
	(zone
		(layers "B.Cu" "In6.Cu" "In11.Cu" "In13.Cu" "In15.Cu")
		(hatch none 0.5)
		(connect_pads
			(clearance 0)
		)
		(min_thickness 0.25)
		(keepout
			(tracks not_allowed)
			(vias allowed)
			(pads allowed)
			(copperpour not_allowed)
			(footprints allowed)
		)
		(placement
			(enabled no)
			(sheetname "")
		)
		(fill yes
			(thermal_gap 0.5)
			(thermal_bridge_width 0.5)
			(island_removal_mode 0)
		)
		(polygon
			(pts
				(arc
					(start 339.186012 -285.42615)
					(mid 338.556092 -285.42615)
					(end 339.186012 -285.42615)
				)
			)
		)
	)
	(zone
		(layers "B.Cu" "In6.Cu" "In11.Cu" "In13.Cu" "In15.Cu")
		(hatch none 0.5)
		(connect_pads
			(clearance 0)
		)
		(min_thickness 0.25)
		(keepout
			(tracks not_allowed)
			(vias allowed)
			(pads allowed)
			(copperpour not_allowed)
			(footprints allowed)
		)
		(placement
			(enabled no)
			(sheetname "")
		)
		(fill yes
			(thermal_gap 0.5)
			(thermal_bridge_width 0.5)
			(island_removal_mode 0)
		)
		(polygon
			(pts
				(arc
					(start 191.494156 -283.185362)
					(mid 190.826136 -283.185362)
					(end 191.494156 -283.185362)
				)
			)
		)
	)
	(zone
		(layers "B.Cu" "In6.Cu" "In11.Cu" "In13.Cu" "In15.Cu")
		(hatch none 0.5)
		(connect_pads
			(clearance 0)
		)
		(min_thickness 0.25)
		(keepout
			(tracks not_allowed)
			(vias allowed)
			(pads allowed)
			(copperpour not_allowed)
			(footprints allowed)
		)
		(placement
			(enabled no)
			(sheetname "")
		)
		(fill yes
			(thermal_gap 0.5)
			(thermal_bridge_width 0.5)
			(island_removal_mode 0)
		)
		(polygon
			(pts
				(arc
					(start 37.129974 -238.135414)
					(mid 36.461954 -238.135414)
					(end 37.129974 -238.135414)
				)
			)
		)
	)
	(zone
		(layers "B.Cu" "In6.Cu" "In11.Cu" "In13.Cu" "In15.Cu")
		(hatch none 0.5)
		(connect_pads
			(clearance 0)
		)
		(min_thickness 0.25)
		(keepout
			(tracks not_allowed)
			(vias allowed)
			(pads allowed)
			(copperpour not_allowed)
			(footprints allowed)
		)
		(placement
			(enabled no)
			(sheetname "")
		)
		(fill yes
			(thermal_gap 0.5)
			(thermal_bridge_width 0.5)
			(island_removal_mode 0)
		)
		(polygon
			(pts
				(arc
					(start 379.769878 -239.624108)
					(mid 379.139958 -239.624108)
					(end 379.769878 -239.624108)
				)
			)
		)
	)
	(zone
		(layers "B.Cu" "In6.Cu" "In11.Cu" "In13.Cu" "In15.Cu")
		(hatch none 0.5)
		(connect_pads
			(clearance 0)
		)
		(min_thickness 0.25)
		(keepout
			(tracks not_allowed)
			(vias allowed)
			(pads allowed)
			(copperpour not_allowed)
			(footprints allowed)
		)
		(placement
			(enabled no)
			(sheetname "")
		)
		(fill yes
			(thermal_gap 0.5)
			(thermal_bridge_width 0.5)
			(island_removal_mode 0)
		)
		(polygon
			(pts
				(arc
					(start 109.105954 -288.666174)
					(mid 108.476034 -288.666174)
					(end 109.105954 -288.666174)
				)
			)
		)
	)
	(zone
		(layers "B.Cu" "In6.Cu" "In11.Cu" "In13.Cu" "In15.Cu")
		(hatch none 0.5)
		(connect_pads
			(clearance 0)
		)
		(min_thickness 0.25)
		(keepout
			(tracks not_allowed)
			(vias allowed)
			(pads allowed)
			(copperpour not_allowed)
			(footprints allowed)
		)
		(placement
			(enabled no)
			(sheetname "")
		)
		(fill yes
			(thermal_gap 0.5)
			(thermal_bridge_width 0.5)
			(island_removal_mode 0)
		)
		(polygon
			(pts
				(arc
					(start 439.434224 -200.735184)
					(mid 438.766204 -200.735184)
					(end 439.434224 -200.735184)
				)
			)
		)
	)
	(zone
		(layers "B.Cu" "In6.Cu" "In11.Cu" "In13.Cu" "In15.Cu")
		(hatch none 0.5)
		(connect_pads
			(clearance 0)
		)
		(min_thickness 0.25)
		(keepout
			(tracks not_allowed)
			(vias allowed)
			(pads allowed)
			(copperpour not_allowed)
			(footprints allowed)
		)
		(placement
			(enabled no)
			(sheetname "")
		)
		(fill yes
			(thermal_gap 0.5)
			(thermal_bridge_width 0.5)
			(island_removal_mode 0)
		)
		(polygon
			(pts
				(arc
					(start 133.069838 -292.716204)
					(mid 132.439918 -292.716204)
					(end 133.069838 -292.716204)
				)
			)
		)
	)
	(zone
		(layers "B.Cu" "In6.Cu" "In11.Cu" "In13.Cu" "In15.Cu")
		(hatch none 0.5)
		(connect_pads
			(clearance 0)
		)
		(min_thickness 0.25)
		(keepout
			(tracks not_allowed)
			(vias allowed)
			(pads allowed)
			(copperpour not_allowed)
			(footprints allowed)
		)
		(placement
			(enabled no)
			(sheetname "")
		)
		(fill yes
			(thermal_gap 0.5)
			(thermal_bridge_width 0.5)
			(island_removal_mode 0)
		)
		(polygon
			(pts
				(arc
					(start 394.024358 -19.137122)
					(mid 393.356338 -19.137122)
					(end 394.024358 -19.137122)
				)
			)
		)
	)
	(zone
		(layers "B.Cu" "In6.Cu" "In11.Cu" "In13.Cu" "In15.Cu")
		(hatch none 0.5)
		(connect_pads
			(clearance 0)
		)
		(min_thickness 0.25)
		(keepout
			(tracks not_allowed)
			(vias allowed)
			(pads allowed)
			(copperpour not_allowed)
			(footprints allowed)
		)
		(placement
			(enabled no)
			(sheetname "")
		)
		(fill yes
			(thermal_gap 0.5)
			(thermal_bridge_width 0.5)
			(island_removal_mode 0)
		)
		(polygon
			(pts
				(arc
					(start 100.815902 -231.524302)
					(mid 100.185982 -231.524302)
					(end 100.815902 -231.524302)
				)
			)
		)
	)
	(zone
		(layers "B.Cu" "In6.Cu" "In11.Cu" "In13.Cu" "In15.Cu")
		(hatch none 0.5)
		(connect_pads
			(clearance 0)
		)
		(min_thickness 0.25)
		(keepout
			(tracks not_allowed)
			(vias allowed)
			(pads allowed)
			(copperpour not_allowed)
			(footprints allowed)
		)
		(placement
			(enabled no)
			(sheetname "")
		)
		(fill yes
			(thermal_gap 0.5)
			(thermal_bridge_width 0.5)
			(island_removal_mode 0)
		)
		(polygon
			(pts
				(arc
					(start 131.359656 -255.014476)
					(mid 130.729736 -255.014476)
					(end 131.359656 -255.014476)
				)
			)
		)
	)
	(zone
		(layers "B.Cu" "In6.Cu" "In11.Cu" "In13.Cu" "In15.Cu")
		(hatch none 0.5)
		(connect_pads
			(clearance 0)
		)
		(min_thickness 0.25)
		(keepout
			(tracks not_allowed)
			(vias allowed)
			(pads allowed)
			(copperpour not_allowed)
			(footprints allowed)
		)
		(placement
			(enabled no)
			(sheetname "")
		)
		(fill yes
			(thermal_gap 0.5)
			(thermal_bridge_width 0.5)
			(island_removal_mode 0)
		)
		(polygon
			(pts
				(arc
					(start 365.66983 -233.14406)
					(mid 365.03991 -233.14406)
					(end 365.66983 -233.14406)
				)
			)
		)
	)
	(zone
		(layers "B.Cu" "In6.Cu" "In11.Cu" "In13.Cu" "In15.Cu")
		(hatch none 0.5)
		(connect_pads
			(clearance 0)
		)
		(min_thickness 0.25)
		(keepout
			(tracks not_allowed)
			(vias allowed)
			(pads allowed)
			(copperpour not_allowed)
			(footprints allowed)
		)
		(placement
			(enabled no)
			(sheetname "")
		)
		(fill yes
			(thermal_gap 0.5)
			(thermal_bridge_width 0.5)
			(island_removal_mode 0)
		)
		(polygon
			(pts
				(arc
					(start 406.533858 -397.849344)
					(mid 405.903938 -397.849344)
					(end 406.533858 -397.849344)
				)
			)
		)
	)
	(zone
		(layers "B.Cu" "In6.Cu" "In11.Cu" "In13.Cu" "In15.Cu")
		(hatch none 0.5)
		(connect_pads
			(clearance 0)
		)
		(min_thickness 0.25)
		(keepout
			(tracks not_allowed)
			(vias allowed)
			(pads allowed)
			(copperpour not_allowed)
			(footprints allowed)
		)
		(placement
			(enabled no)
			(sheetname "")
		)
		(fill yes
			(thermal_gap 0.5)
			(thermal_bridge_width 0.5)
			(island_removal_mode 0)
		)
		(polygon
			(pts
				(arc
					(start 91.245944 -285.426404)
					(mid 90.616024 -285.426404)
					(end 91.245944 -285.426404)
				)
			)
		)
	)
	(zone
		(layers "B.Cu" "In6.Cu" "In11.Cu" "In13.Cu" "In15.Cu")
		(hatch none 0.5)
		(connect_pads
			(clearance 0)
		)
		(min_thickness 0.25)
		(keepout
			(tracks not_allowed)
			(vias allowed)
			(pads allowed)
			(copperpour not_allowed)
			(footprints allowed)
		)
		(placement
			(enabled no)
			(sheetname "")
		)
		(fill yes
			(thermal_gap 0.5)
			(thermal_bridge_width 0.5)
			(island_removal_mode 0)
		)
		(polygon
			(pts
				(arc
					(start 333.578454 -377.41733)
					(mid 332.910434 -377.41733)
					(end 333.578454 -377.41733)
				)
			)
		)
	)
	(zone
		(layers "B.Cu" "In6.Cu" "In11.Cu" "In13.Cu" "In15.Cu")
		(hatch none 0.5)
		(connect_pads
			(clearance 0)
		)
		(min_thickness 0.25)
		(keepout
			(tracks not_allowed)
			(vias allowed)
			(pads allowed)
			(copperpour not_allowed)
			(footprints allowed)
		)
		(placement
			(enabled no)
			(sheetname "")
		)
		(fill yes
			(thermal_gap 0.5)
			(thermal_bridge_width 0.5)
			(island_removal_mode 0)
		)
		(polygon
			(pts
				(arc
					(start 159.733996 -388.774432)
					(mid 159.104076 -388.774432)
					(end 159.733996 -388.774432)
				)
			)
		)
	)
	(zone
		(layers "B.Cu" "In6.Cu" "In11.Cu" "In13.Cu" "In15.Cu")
		(hatch none 0.5)
		(connect_pads
			(clearance 0)
		)
		(min_thickness 0.25)
		(keepout
			(tracks not_allowed)
			(vias allowed)
			(pads allowed)
			(copperpour not_allowed)
			(footprints allowed)
		)
		(placement
			(enabled no)
			(sheetname "")
		)
		(fill yes
			(thermal_gap 0.5)
			(thermal_bridge_width 0.5)
			(island_removal_mode 0)
		)
		(polygon
			(pts
				(arc
					(start 131.359656 -243.674392)
					(mid 130.729736 -243.674392)
					(end 131.359656 -243.674392)
				)
			)
		)
	)
	(zone
		(layers "B.Cu" "In6.Cu" "In11.Cu" "In13.Cu" "In15.Cu")
		(hatch none 0.5)
		(connect_pads
			(clearance 0)
		)
		(min_thickness 0.25)
		(keepout
			(tracks not_allowed)
			(vias allowed)
			(pads allowed)
			(copperpour not_allowed)
			(footprints allowed)
		)
		(placement
			(enabled no)
			(sheetname "")
		)
		(fill yes
			(thermal_gap 0.5)
			(thermal_bridge_width 0.5)
			(island_removal_mode 0)
		)
		(polygon
			(pts
				(arc
					(start 439.434224 -228.785166)
					(mid 438.766204 -228.785166)
					(end 439.434224 -228.785166)
				)
			)
		)
	)
	(zone
		(layers "B.Cu" "In6.Cu" "In11.Cu" "In13.Cu" "In15.Cu")
		(hatch none 0.5)
		(connect_pads
			(clearance 0)
		)
		(min_thickness 0.25)
		(keepout
			(tracks not_allowed)
			(vias allowed)
			(pads allowed)
			(copperpour not_allowed)
			(footprints allowed)
		)
		(placement
			(enabled no)
			(sheetname "")
		)
		(fill yes
			(thermal_gap 0.5)
			(thermal_bridge_width 0.5)
			(island_removal_mode 0)
		)
		(polygon
			(pts
				(arc
					(start 95.460312 -373.96293)
					(mid 94.792292 -373.96293)
					(end 95.460312 -373.96293)
				)
			)
		)
	)
	(zone
		(layers "B.Cu" "In6.Cu" "In11.Cu" "In13.Cu" "In15.Cu")
		(hatch none 0.5)
		(connect_pads
			(clearance 0)
		)
		(min_thickness 0.25)
		(keepout
			(tracks not_allowed)
			(vias allowed)
			(pads allowed)
			(copperpour not_allowed)
			(footprints allowed)
		)
		(placement
			(enabled no)
			(sheetname "")
		)
		(fill yes
			(thermal_gap 0.5)
			(thermal_bridge_width 0.5)
			(island_removal_mode 0)
		)
		(polygon
			(pts
				(arc
					(start 376.006106 -393.69238)
					(mid 375.376186 -393.69238)
					(end 376.006106 -393.69238)
				)
			)
		)
	)
	(zone
		(layers "B.Cu" "In6.Cu" "In11.Cu" "In13.Cu" "In15.Cu")
		(hatch none 0.5)
		(connect_pads
			(clearance 0)
		)
		(min_thickness 0.25)
		(keepout
			(tracks not_allowed)
			(vias allowed)
			(pads allowed)
			(copperpour not_allowed)
			(footprints allowed)
		)
		(placement
			(enabled no)
			(sheetname "")
		)
		(fill yes
			(thermal_gap 0.5)
			(thermal_bridge_width 0.5)
			(island_removal_mode 0)
		)
		(polygon
			(pts
				(arc
					(start 422.13403 -397.849344)
					(mid 421.50411 -397.849344)
					(end 422.13403 -397.849344)
				)
			)
		)
	)
	(zone
		(layers "B.Cu" "In6.Cu" "In11.Cu" "In13.Cu" "In15.Cu")
		(hatch none 0.5)
		(connect_pads
			(clearance 0)
		)
		(min_thickness 0.25)
		(keepout
			(tracks not_allowed)
			(vias allowed)
			(pads allowed)
			(copperpour not_allowed)
			(footprints allowed)
		)
		(placement
			(enabled no)
			(sheetname "")
		)
		(fill yes
			(thermal_gap 0.5)
			(thermal_bridge_width 0.5)
			(island_removal_mode 0)
		)
		(polygon
			(pts
				(arc
					(start 435.334156 -253.435104)
					(mid 434.666136 -253.435104)
					(end 435.334156 -253.435104)
				)
			)
		)
	)
	(zone
		(layers "B.Cu" "In6.Cu" "In11.Cu" "In13.Cu" "In15.Cu")
		(hatch none 0.5)
		(connect_pads
			(clearance 0)
		)
		(min_thickness 0.25)
		(keepout
			(tracks not_allowed)
			(vias allowed)
			(pads allowed)
			(copperpour not_allowed)
			(footprints allowed)
		)
		(placement
			(enabled no)
			(sheetname "")
		)
		(fill yes
			(thermal_gap 0.5)
			(thermal_bridge_width 0.5)
			(island_removal_mode 0)
		)
		(polygon
			(pts
				(arc
					(start 191.494156 -214.33536)
					(mid 190.826136 -214.33536)
					(end 191.494156 -214.33536)
				)
			)
		)
	)
	(zone
		(layers "B.Cu" "In6.Cu" "In11.Cu" "In13.Cu" "In15.Cu")
		(hatch none 0.5)
		(connect_pads
			(clearance 0)
		)
		(min_thickness 0.25)
		(keepout
			(tracks not_allowed)
			(vias allowed)
			(pads allowed)
			(copperpour not_allowed)
			(footprints allowed)
		)
		(placement
			(enabled no)
			(sheetname "")
		)
		(fill yes
			(thermal_gap 0.5)
			(thermal_bridge_width 0.5)
			(island_removal_mode 0)
		)
		(polygon
			(pts
				(arc
					(start 381.179832 -243.674138)
					(mid 380.549912 -243.674138)
					(end 381.179832 -243.674138)
				)
			)
		)
	)
	(zone
		(layers "B.Cu" "In6.Cu" "In11.Cu" "In13.Cu" "In15.Cu")
		(hatch none 0.5)
		(connect_pads
			(clearance 0)
		)
		(min_thickness 0.25)
		(keepout
			(tracks not_allowed)
			(vias allowed)
			(pads allowed)
			(copperpour not_allowed)
			(footprints allowed)
		)
		(placement
			(enabled no)
			(sheetname "")
		)
		(fill yes
			(thermal_gap 0.5)
			(thermal_bridge_width 0.5)
			(island_removal_mode 0)
		)
		(polygon
			(pts
				(arc
					(start 126.489714 -287.856422)
					(mid 125.859794 -287.856422)
					(end 126.489714 -287.856422)
				)
			)
		)
	)
	(zone
		(layers "B.Cu" "In6.Cu" "In11.Cu" "In13.Cu" "In15.Cu")
		(hatch none 0.5)
		(connect_pads
			(clearance 0)
		)
		(min_thickness 0.25)
		(keepout
			(tracks not_allowed)
			(vias allowed)
			(pads allowed)
			(copperpour not_allowed)
			(footprints allowed)
		)
		(placement
			(enabled no)
			(sheetname "")
		)
		(fill yes
			(thermal_gap 0.5)
			(thermal_bridge_width 0.5)
			(island_removal_mode 0)
		)
		(polygon
			(pts
				(arc
					(start 380.069852 -281.37612)
					(mid 379.439932 -281.37612)
					(end 380.069852 -281.37612)
				)
			)
		)
	)
	(zone
		(layers "B.Cu" "In6.Cu" "In11.Cu" "In13.Cu" "In15.Cu")
		(hatch none 0.5)
		(connect_pads
			(clearance 0)
		)
		(min_thickness 0.25)
		(keepout
			(tracks not_allowed)
			(vias allowed)
			(pads allowed)
			(copperpour not_allowed)
			(footprints allowed)
		)
		(placement
			(enabled no)
			(sheetname "")
		)
		(fill yes
			(thermal_gap 0.5)
			(thermal_bridge_width 0.5)
			(island_removal_mode 0)
		)
		(polygon
			(pts
				(arc
					(start 340.295992 -244.484144)
					(mid 339.666072 -244.484144)
					(end 340.295992 -244.484144)
				)
			)
		)
	)
	(zone
		(layers "B.Cu" "In6.Cu" "In11.Cu" "In13.Cu" "In15.Cu")
		(hatch none 0.5)
		(connect_pads
			(clearance 0)
		)
		(min_thickness 0.25)
		(keepout
			(tracks not_allowed)
			(vias allowed)
			(pads allowed)
			(copperpour not_allowed)
			(footprints allowed)
		)
		(placement
			(enabled no)
			(sheetname "")
		)
		(fill yes
			(thermal_gap 0.5)
			(thermal_bridge_width 0.5)
			(island_removal_mode 0)
		)
		(polygon
			(pts
				(arc
					(start 347.17609 -287.856168)
					(mid 346.54617 -287.856168)
					(end 347.17609 -287.856168)
				)
			)
		)
	)
	(zone
		(layers "B.Cu" "In6.Cu" "In11.Cu" "In13.Cu" "In15.Cu")
		(hatch none 0.5)
		(connect_pads
			(clearance 0)
		)
		(min_thickness 0.25)
		(keepout
			(tracks not_allowed)
			(vias allowed)
			(pads allowed)
			(copperpour not_allowed)
			(footprints allowed)
		)
		(placement
			(enabled no)
			(sheetname "")
		)
		(fill yes
			(thermal_gap 0.5)
			(thermal_bridge_width 0.5)
			(island_removal_mode 0)
		)
		(polygon
			(pts
				(arc
					(start 429.82261 -17.613122)
					(mid 429.15459 -17.613122)
					(end 429.82261 -17.613122)
				)
			)
		)
	)
	(zone
		(layers "B.Cu" "In6.Cu" "In11.Cu" "In13.Cu" "In15.Cu")
		(hatch none 0.5)
		(connect_pads
			(clearance 0)
		)
		(min_thickness 0.25)
		(keepout
			(tracks not_allowed)
			(vias allowed)
			(pads allowed)
			(copperpour not_allowed)
			(footprints allowed)
		)
		(placement
			(enabled no)
			(sheetname "")
		)
		(fill yes
			(thermal_gap 0.5)
			(thermal_bridge_width 0.5)
			(island_removal_mode 0)
		)
		(polygon
			(pts
				(arc
					(start 357.686102 -230.714296)
					(mid 357.056182 -230.714296)
					(end 357.686102 -230.714296)
				)
			)
		)
	)
	(zone
		(layers "B.Cu" "In6.Cu" "In11.Cu" "In13.Cu" "In15.Cu")
		(hatch none 0.5)
		(connect_pads
			(clearance 0)
		)
		(min_thickness 0.25)
		(keepout
			(tracks not_allowed)
			(vias allowed)
			(pads allowed)
			(copperpour not_allowed)
			(footprints allowed)
		)
		(placement
			(enabled no)
			(sheetname "")
		)
		(fill yes
			(thermal_gap 0.5)
			(thermal_bridge_width 0.5)
			(island_removal_mode 0)
		)
		(polygon
			(pts
				(arc
					(start 381.206248 -394.385292)
					(mid 380.576328 -394.385292)
					(end 381.206248 -394.385292)
				)
			)
		)
	)
	(zone
		(layers "B.Cu" "In6.Cu" "In11.Cu" "In13.Cu" "In15.Cu")
		(hatch none 0.5)
		(connect_pads
			(clearance 0)
		)
		(min_thickness 0.25)
		(keepout
			(tracks not_allowed)
			(vias allowed)
			(pads allowed)
			(copperpour not_allowed)
			(footprints allowed)
		)
		(placement
			(enabled no)
			(sheetname "")
		)
		(fill yes
			(thermal_gap 0.5)
			(thermal_bridge_width 0.5)
			(island_removal_mode 0)
		)
		(polygon
			(pts
				(arc
					(start 90.94597 -229.094538)
					(mid 90.31605 -229.094538)
					(end 90.94597 -229.094538)
				)
			)
		)
	)
	(zone
		(layers "B.Cu" "In6.Cu" "In11.Cu" "In13.Cu" "In15.Cu")
		(hatch none 0.5)
		(connect_pads
			(clearance 0)
		)
		(min_thickness 0.25)
		(keepout
			(tracks not_allowed)
			(vias allowed)
			(pads allowed)
			(copperpour not_allowed)
			(footprints allowed)
		)
		(placement
			(enabled no)
			(sheetname "")
		)
		(fill yes
			(thermal_gap 0.5)
			(thermal_bridge_width 0.5)
			(island_removal_mode 0)
		)
		(polygon
			(pts
				(arc
					(start 133.539738 -272.466308)
					(mid 132.909818 -272.466308)
					(end 133.539738 -272.466308)
				)
			)
		)
	)
	(zone
		(layers "B.Cu" "In6.Cu" "In11.Cu" "In13.Cu" "In15.Cu")
		(hatch none 0.5)
		(connect_pads
			(clearance 0)
		)
		(min_thickness 0.25)
		(keepout
			(tracks not_allowed)
			(vias allowed)
			(pads allowed)
			(copperpour not_allowed)
			(footprints allowed)
		)
		(placement
			(enabled no)
			(sheetname "")
		)
		(fill yes
			(thermal_gap 0.5)
			(thermal_bridge_width 0.5)
			(island_removal_mode 0)
		)
		(polygon
			(pts
				(arc
					(start 379.299724 -227.474272)
					(mid 378.669804 -227.474272)
					(end 379.299724 -227.474272)
				)
			)
		)
	)
	(zone
		(layers "B.Cu" "In6.Cu" "In11.Cu" "In13.Cu" "In15.Cu")
		(hatch none 0.5)
		(connect_pads
			(clearance 0)
		)
		(min_thickness 0.25)
		(keepout
			(tracks not_allowed)
			(vias allowed)
			(pads allowed)
			(copperpour not_allowed)
			(footprints allowed)
		)
		(placement
			(enabled no)
			(sheetname "")
		)
		(fill yes
			(thermal_gap 0.5)
			(thermal_bridge_width 0.5)
			(island_removal_mode 0)
		)
		(polygon
			(pts
				(arc
					(start 338.886038 -225.85426)
					(mid 338.256118 -225.85426)
					(end 338.886038 -225.85426)
				)
			)
		)
	)
	(zone
		(layers "B.Cu" "In6.Cu" "In11.Cu" "In13.Cu" "In15.Cu")
		(hatch none 0.5)
		(connect_pads
			(clearance 0)
		)
		(min_thickness 0.25)
		(keepout
			(tracks not_allowed)
			(vias allowed)
			(pads allowed)
			(copperpour not_allowed)
			(footprints allowed)
		)
		(placement
			(enabled no)
			(sheetname "")
		)
		(fill yes
			(thermal_gap 0.5)
			(thermal_bridge_width 0.5)
			(island_removal_mode 0)
		)
		(polygon
			(pts
				(arc
					(start 37.129974 -242.385342)
					(mid 36.461954 -242.385342)
					(end 37.129974 -242.385342)
				)
			)
		)
	)
	(zone
		(layers "B.Cu" "In6.Cu" "In11.Cu" "In13.Cu" "In15.Cu")
		(hatch none 0.5)
		(connect_pads
			(clearance 0)
		)
		(min_thickness 0.25)
		(keepout
			(tracks not_allowed)
			(vias allowed)
			(pads allowed)
			(copperpour not_allowed)
			(footprints allowed)
		)
		(placement
			(enabled no)
			(sheetname "")
		)
		(fill yes
			(thermal_gap 0.5)
			(thermal_bridge_width 0.5)
			(island_removal_mode 0)
		)
		(polygon
			(pts
				(arc
					(start 114.4397 -230.71455)
					(mid 113.80978 -230.71455)
					(end 114.4397 -230.71455)
				)
			)
		)
	)
	(zone
		(layers "B.Cu" "In6.Cu" "In11.Cu" "In13.Cu" "In15.Cu")
		(hatch none 0.5)
		(connect_pads
			(clearance 0)
		)
		(min_thickness 0.25)
		(keepout
			(tracks not_allowed)
			(vias allowed)
			(pads allowed)
			(copperpour not_allowed)
			(footprints allowed)
		)
		(placement
			(enabled no)
			(sheetname "")
		)
		(fill yes
			(thermal_gap 0.5)
			(thermal_bridge_width 0.5)
			(island_removal_mode 0)
		)
		(polygon
			(pts
				(arc
					(start 108.80598 -232.334308)
					(mid 108.17606 -232.334308)
					(end 108.80598 -232.334308)
				)
			)
		)
	)
	(zone
		(layers "B.Cu" "In6.Cu" "In11.Cu" "In13.Cu" "In15.Cu")
		(hatch none 0.5)
		(connect_pads
			(clearance 0)
		)
		(min_thickness 0.25)
		(keepout
			(tracks not_allowed)
			(vias allowed)
			(pads allowed)
			(copperpour not_allowed)
			(footprints allowed)
		)
		(placement
			(enabled no)
			(sheetname "")
		)
		(fill yes
			(thermal_gap 0.5)
			(thermal_bridge_width 0.5)
			(island_removal_mode 0)
		)
		(polygon
			(pts
				(arc
					(start 91.245944 -272.466308)
					(mid 90.616024 -272.466308)
					(end 91.245944 -272.466308)
				)
			)
		)
	)
	(zone
		(layers "B.Cu" "In6.Cu" "In11.Cu" "In13.Cu" "In15.Cu")
		(hatch none 0.5)
		(connect_pads
			(clearance 0)
		)
		(min_thickness 0.25)
		(keepout
			(tracks not_allowed)
			(vias allowed)
			(pads allowed)
			(copperpour not_allowed)
			(footprints allowed)
		)
		(placement
			(enabled no)
			(sheetname "")
		)
		(fill yes
			(thermal_gap 0.5)
			(thermal_bridge_width 0.5)
			(island_removal_mode 0)
		)
		(polygon
			(pts
				(arc
					(start 37.129974 -227.085398)
					(mid 36.461954 -227.085398)
					(end 37.129974 -227.085398)
				)
			)
		)
	)
	(zone
		(layers "B.Cu" "In6.Cu" "In11.Cu" "In13.Cu" "In15.Cu")
		(hatch none 0.5)
		(connect_pads
			(clearance 0)
		)
		(min_thickness 0.25)
		(keepout
			(tracks not_allowed)
			(vias allowed)
			(pads allowed)
			(copperpour not_allowed)
			(footprints allowed)
		)
		(placement
			(enabled no)
			(sheetname "")
		)
		(fill yes
			(thermal_gap 0.5)
			(thermal_bridge_width 0.5)
			(island_removal_mode 0)
		)
		(polygon
			(pts
				(arc
					(start 344.652854 -382.34493)
					(mid 343.984834 -382.34493)
					(end 344.652854 -382.34493)
				)
			)
		)
	)
	(zone
		(layers "B.Cu" "In6.Cu" "In11.Cu" "In13.Cu" "In15.Cu")
		(hatch none 0.5)
		(connect_pads
			(clearance 0)
		)
		(min_thickness 0.25)
		(keepout
			(tracks not_allowed)
			(vias allowed)
			(pads allowed)
			(copperpour not_allowed)
			(footprints allowed)
		)
		(placement
			(enabled no)
			(sheetname "")
		)
		(fill yes
			(thermal_gap 0.5)
			(thermal_bridge_width 0.5)
			(island_removal_mode 0)
		)
		(polygon
			(pts
				(arc
					(start 439.434224 -283.185108)
					(mid 438.766204 -283.185108)
					(end 439.434224 -283.185108)
				)
			)
		)
	)
	(zone
		(layers "B.Cu" "In6.Cu" "In11.Cu" "In13.Cu" "In15.Cu")
		(hatch none 0.5)
		(connect_pads
			(clearance 0)
		)
		(min_thickness 0.25)
		(keepout
			(tracks not_allowed)
			(vias allowed)
			(pads allowed)
			(copperpour not_allowed)
			(footprints allowed)
		)
		(placement
			(enabled no)
			(sheetname "")
		)
		(fill yes
			(thermal_gap 0.5)
			(thermal_bridge_width 0.5)
			(island_removal_mode 0)
		)
		(polygon
			(pts
				(arc
					(start 322.106036 -397.156432)
					(mid 321.476116 -397.156432)
					(end 322.106036 -397.156432)
				)
			)
		)
	)
	(zone
		(layers "B.Cu" "In6.Cu" "In11.Cu" "In13.Cu" "In15.Cu")
		(hatch none 0.5)
		(connect_pads
			(clearance 0)
		)
		(min_thickness 0.25)
		(keepout
			(tracks not_allowed)
			(vias allowed)
			(pads allowed)
			(copperpour not_allowed)
			(footprints allowed)
		)
		(placement
			(enabled no)
			(sheetname "")
		)
		(fill yes
			(thermal_gap 0.5)
			(thermal_bridge_width 0.5)
			(island_removal_mode 0)
		)
		(polygon
			(pts
				(arc
					(start 132.129784 -282.996386)
					(mid 131.499864 -282.996386)
					(end 132.129784 -282.996386)
				)
			)
		)
	)
	(zone
		(layers "B.Cu" "In6.Cu" "In11.Cu" "In13.Cu" "In15.Cu")
		(hatch none 0.5)
		(connect_pads
			(clearance 0)
		)
		(min_thickness 0.25)
		(keepout
			(tracks not_allowed)
			(vias allowed)
			(pads allowed)
			(copperpour not_allowed)
			(footprints allowed)
		)
		(placement
			(enabled no)
			(sheetname "")
		)
		(fill yes
			(thermal_gap 0.5)
			(thermal_bridge_width 0.5)
			(island_removal_mode 0)
		)
		(polygon
			(pts
				(arc
					(start 285.070042 -249.185176)
					(mid 284.402022 -249.185176)
					(end 285.070042 -249.185176)
				)
			)
		)
	)
	(zone
		(layers "B.Cu" "In6.Cu" "In11.Cu" "In13.Cu" "In15.Cu")
		(hatch none 0.5)
		(connect_pads
			(clearance 0)
		)
		(min_thickness 0.25)
		(keepout
			(tracks not_allowed)
			(vias allowed)
			(pads allowed)
			(copperpour not_allowed)
			(footprints allowed)
		)
		(placement
			(enabled no)
			(sheetname "")
		)
		(fill yes
			(thermal_gap 0.5)
			(thermal_bridge_width 0.5)
			(island_removal_mode 0)
		)
		(polygon
			(pts
				(arc
					(start 365.66983 -231.524048)
					(mid 365.03991 -231.524048)
					(end 365.66983 -231.524048)
				)
			)
		)
	)
	(zone
		(layers "B.Cu" "In6.Cu" "In11.Cu" "In13.Cu" "In15.Cu")
		(hatch none 0.5)
		(connect_pads
			(clearance 0)
		)
		(min_thickness 0.25)
		(keepout
			(tracks not_allowed)
			(vias allowed)
			(pads allowed)
			(copperpour not_allowed)
			(footprints allowed)
		)
		(placement
			(enabled no)
			(sheetname "")
		)
		(fill yes
			(thermal_gap 0.5)
			(thermal_bridge_width 0.5)
			(island_removal_mode 0)
		)
		(polygon
			(pts
				(arc
					(start 339.656166 -282.996132)
					(mid 339.026246 -282.996132)
					(end 339.656166 -282.996132)
				)
			)
		)
	)
	(zone
		(layers "B.Cu" "In6.Cu" "In11.Cu" "In13.Cu" "In15.Cu")
		(hatch none 0.5)
		(connect_pads
			(clearance 0)
		)
		(min_thickness 0.25)
		(keepout
			(tracks not_allowed)
			(vias allowed)
			(pads allowed)
			(copperpour not_allowed)
			(footprints allowed)
		)
		(placement
			(enabled no)
			(sheetname "")
		)
		(fill yes
			(thermal_gap 0.5)
			(thermal_bridge_width 0.5)
			(island_removal_mode 0)
		)
		(polygon
			(pts
				(arc
					(start 306.905914 -397.849344)
					(mid 306.275994 -397.849344)
					(end 306.905914 -397.849344)
				)
			)
		)
	)
	(zone
		(layers "B.Cu" "In6.Cu" "In11.Cu" "In13.Cu" "In15.Cu")
		(hatch none 0.5)
		(connect_pads
			(clearance 0)
		)
		(min_thickness 0.25)
		(keepout
			(tracks not_allowed)
			(vias allowed)
			(pads allowed)
			(copperpour not_allowed)
			(footprints allowed)
		)
		(placement
			(enabled no)
			(sheetname "")
		)
		(fill yes
			(thermal_gap 0.5)
			(thermal_bridge_width 0.5)
			(island_removal_mode 0)
		)
		(polygon
			(pts
				(arc
					(start 191.494156 -294.235378)
					(mid 190.826136 -294.235378)
					(end 191.494156 -294.235378)
				)
			)
		)
	)
	(zone
		(layers "B.Cu" "In6.Cu" "In11.Cu" "In13.Cu" "In15.Cu")
		(hatch none 0.5)
		(connect_pads
			(clearance 0)
		)
		(min_thickness 0.25)
		(keepout
			(tracks not_allowed)
			(vias allowed)
			(pads allowed)
			(copperpour not_allowed)
			(footprints allowed)
		)
		(placement
			(enabled no)
			(sheetname "")
		)
		(fill yes
			(thermal_gap 0.5)
			(thermal_bridge_width 0.5)
			(island_removal_mode 0)
		)
		(polygon
			(pts
				(arc
					(start 409.925774 -19.13636)
					(mid 409.257754 -19.13636)
					(end 409.925774 -19.13636)
				)
			)
		)
	)
	(zone
		(layers "B.Cu" "In6.Cu" "In11.Cu" "In13.Cu" "In15.Cu")
		(hatch none 0.5)
		(connect_pads
			(clearance 0)
		)
		(min_thickness 0.25)
		(keepout
			(tracks not_allowed)
			(vias allowed)
			(pads allowed)
			(copperpour not_allowed)
			(footprints allowed)
		)
		(placement
			(enabled no)
			(sheetname "")
		)
		(fill yes
			(thermal_gap 0.5)
			(thermal_bridge_width 0.5)
			(island_removal_mode 0)
		)
		(polygon
			(pts
				(arc
					(start 27.413204 -6.725158)
					(mid 26.745184 -6.725158)
					(end 27.413204 -6.725158)
				)
			)
		)
	)
	(zone
		(layers "B.Cu" "In6.Cu" "In11.Cu" "In13.Cu" "In15.Cu")
		(hatch none 0.5)
		(connect_pads
			(clearance 0)
		)
		(min_thickness 0.25)
		(keepout
			(tracks not_allowed)
			(vias allowed)
			(pads allowed)
			(copperpour not_allowed)
			(footprints allowed)
		)
		(placement
			(enabled no)
			(sheetname "")
		)
		(fill yes
			(thermal_gap 0.5)
			(thermal_bridge_width 0.5)
			(island_removal_mode 0)
		)
		(polygon
			(pts
				(arc
					(start 355.336094 -229.904036)
					(mid 354.706174 -229.904036)
					(end 355.336094 -229.904036)
				)
			)
		)
	)
	(zone
		(layers "B.Cu" "In6.Cu" "In11.Cu" "In13.Cu" "In15.Cu")
		(hatch none 0.5)
		(connect_pads
			(clearance 0)
		)
		(min_thickness 0.25)
		(keepout
			(tracks not_allowed)
			(vias allowed)
			(pads allowed)
			(copperpour not_allowed)
			(footprints allowed)
		)
		(placement
			(enabled no)
			(sheetname "")
		)
		(fill yes
			(thermal_gap 0.5)
			(thermal_bridge_width 0.5)
			(island_removal_mode 0)
		)
		(polygon
			(pts
				(arc
					(start 329.497436 -412.84652)
					(mid 328.829416 -412.84652)
					(end 329.497436 -412.84652)
				)
			)
		)
	)
	(zone
		(layers "B.Cu" "In6.Cu" "In11.Cu" "In13.Cu" "In15.Cu")
		(hatch none 0.5)
		(connect_pads
			(clearance 0)
		)
		(min_thickness 0.25)
		(keepout
			(tracks not_allowed)
			(vias allowed)
			(pads allowed)
			(copperpour not_allowed)
			(footprints allowed)
		)
		(placement
			(enabled no)
			(sheetname "")
		)
		(fill yes
			(thermal_gap 0.5)
			(thermal_bridge_width 0.5)
			(island_removal_mode 0)
		)
		(polygon
			(pts
				(arc
					(start 280.969974 -263.634982)
					(mid 280.301954 -263.634982)
					(end 280.969974 -263.634982)
				)
			)
		)
	)
	(zone
		(layers "B.Cu" "In6.Cu" "In11.Cu" "In13.Cu" "In15.Cu")
		(hatch none 0.5)
		(connect_pads
			(clearance 0)
		)
		(min_thickness 0.25)
		(keepout
			(tracks not_allowed)
			(vias allowed)
			(pads allowed)
			(copperpour not_allowed)
			(footprints allowed)
		)
		(placement
			(enabled no)
			(sheetname "")
		)
		(fill yes
			(thermal_gap 0.5)
			(thermal_bridge_width 0.5)
			(island_removal_mode 0)
		)
		(polygon
			(pts
				(arc
					(start 340.595966 -281.37612)
					(mid 339.966046 -281.37612)
					(end 340.595966 -281.37612)
				)
			)
		)
	)
	(zone
		(layers "B.Cu" "In6.Cu" "In11.Cu" "In13.Cu" "In15.Cu")
		(hatch none 0.5)
		(connect_pads
			(clearance 0)
		)
		(min_thickness 0.25)
		(keepout
			(tracks not_allowed)
			(vias allowed)
			(pads allowed)
			(copperpour not_allowed)
			(footprints allowed)
		)
		(placement
			(enabled no)
			(sheetname "")
		)
		(fill yes
			(thermal_gap 0.5)
			(thermal_bridge_width 0.5)
			(island_removal_mode 0)
		)
		(polygon
			(pts
				(arc
					(start 33.029906 -268.735302)
					(mid 32.361886 -268.735302)
					(end 33.029906 -268.735302)
				)
			)
		)
	)
	(zone
		(layers "B.Cu" "In6.Cu" "In11.Cu" "In13.Cu" "In15.Cu")
		(hatch none 0.5)
		(connect_pads
			(clearance 0)
		)
		(min_thickness 0.25)
		(keepout
			(tracks not_allowed)
			(vias allowed)
			(pads allowed)
			(copperpour not_allowed)
			(footprints allowed)
		)
		(placement
			(enabled no)
			(sheetname "")
		)
		(fill yes
			(thermal_gap 0.5)
			(thermal_bridge_width 0.5)
			(island_removal_mode 0)
		)
		(polygon
			(pts
				(arc
					(start 420.534084 -397.156432)
					(mid 419.904164 -397.156432)
					(end 420.534084 -397.156432)
				)
			)
		)
	)
	(zone
		(layers "B.Cu" "In6.Cu" "In11.Cu" "In13.Cu" "In15.Cu")
		(hatch none 0.5)
		(connect_pads
			(clearance 0)
		)
		(min_thickness 0.25)
		(keepout
			(tracks not_allowed)
			(vias allowed)
			(pads allowed)
			(copperpour not_allowed)
			(footprints allowed)
		)
		(placement
			(enabled no)
			(sheetname "")
		)
		(fill yes
			(thermal_gap 0.5)
			(thermal_bridge_width 0.5)
			(island_removal_mode 0)
		)
		(polygon
			(pts
				(arc
					(start 439.434224 -290.83508)
					(mid 438.766204 -290.83508)
					(end 439.434224 -290.83508)
				)
			)
		)
	)
	(zone
		(layers "B.Cu" "In6.Cu" "In11.Cu" "In13.Cu" "In15.Cu")
		(hatch none 0.5)
		(connect_pads
			(clearance 0)
		)
		(min_thickness 0.25)
		(keepout
			(tracks not_allowed)
			(vias allowed)
			(pads allowed)
			(copperpour not_allowed)
			(footprints allowed)
		)
		(placement
			(enabled no)
			(sheetname "")
		)
		(fill yes
			(thermal_gap 0.5)
			(thermal_bridge_width 0.5)
			(island_removal_mode 0)
		)
		(polygon
			(pts
				(arc
					(start 373.489728 -289.475926)
					(mid 372.859808 -289.475926)
					(end 373.489728 -289.475926)
				)
			)
		)
	)
	(zone
		(layers "B.Cu" "In6.Cu" "In11.Cu" "In13.Cu" "In15.Cu")
		(hatch none 0.5)
		(connect_pads
			(clearance 0)
		)
		(min_thickness 0.25)
		(keepout
			(tracks not_allowed)
			(vias allowed)
			(pads allowed)
			(copperpour not_allowed)
			(footprints allowed)
		)
		(placement
			(enabled no)
			(sheetname "")
		)
		(fill yes
			(thermal_gap 0.5)
			(thermal_bridge_width 0.5)
			(island_removal_mode 0)
		)
		(polygon
			(pts
				(arc
					(start 92.655898 -273.276314)
					(mid 92.025978 -273.276314)
					(end 92.655898 -273.276314)
				)
			)
		)
	)
	(zone
		(layers "B.Cu" "In6.Cu" "In11.Cu" "In13.Cu" "In15.Cu")
		(hatch none 0.5)
		(connect_pads
			(clearance 0)
		)
		(min_thickness 0.25)
		(keepout
			(tracks not_allowed)
			(vias allowed)
			(pads allowed)
			(copperpour not_allowed)
			(footprints allowed)
		)
		(placement
			(enabled no)
			(sheetname "")
		)
		(fill yes
			(thermal_gap 0.5)
			(thermal_bridge_width 0.5)
			(island_removal_mode 0)
		)
		(polygon
			(pts
				(arc
					(start 191.494156 -199.035416)
					(mid 190.826136 -199.035416)
					(end 191.494156 -199.035416)
				)
			)
		)
	)
	(zone
		(layers "B.Cu" "In6.Cu" "In11.Cu" "In13.Cu" "In15.Cu")
		(hatch none 0.5)
		(connect_pads
			(clearance 0)
		)
		(min_thickness 0.25)
		(keepout
			(tracks not_allowed)
			(vias allowed)
			(pads allowed)
			(copperpour not_allowed)
			(footprints allowed)
		)
		(placement
			(enabled no)
			(sheetname "")
		)
		(fill yes
			(thermal_gap 0.5)
			(thermal_bridge_width 0.5)
			(island_removal_mode 0)
		)
		(polygon
			(pts
				(arc
					(start 432.617626 -19.13636)
					(mid 431.949606 -19.13636)
					(end 432.617626 -19.13636)
				)
			)
		)
	)
	(zone
		(layers "B.Cu" "In6.Cu" "In11.Cu" "In13.Cu" "In15.Cu")
		(hatch none 0.5)
		(connect_pads
			(clearance 0)
		)
		(min_thickness 0.25)
		(keepout
			(tracks not_allowed)
			(vias allowed)
			(pads allowed)
			(copperpour not_allowed)
			(footprints allowed)
		)
		(placement
			(enabled no)
			(sheetname "")
		)
		(fill yes
			(thermal_gap 0.5)
			(thermal_bridge_width 0.5)
			(island_removal_mode 0)
		)
		(polygon
			(pts
				(arc
					(start 33.029906 -215.185244)
					(mid 32.361886 -215.185244)
					(end 33.029906 -215.185244)
				)
			)
		)
	)
	(zone
		(layers "B.Cu" "In6.Cu" "In11.Cu" "In13.Cu" "In15.Cu")
		(hatch none 0.5)
		(connect_pads
			(clearance 0)
		)
		(min_thickness 0.25)
		(keepout
			(tracks not_allowed)
			(vias allowed)
			(pads allowed)
			(copperpour not_allowed)
			(footprints allowed)
		)
		(placement
			(enabled no)
			(sheetname "")
		)
		(fill yes
			(thermal_gap 0.5)
			(thermal_bridge_width 0.5)
			(island_removal_mode 0)
		)
		(polygon
			(pts
				(arc
					(start 92.826078 -235.574332)
					(mid 92.196158 -235.574332)
					(end 92.826078 -235.574332)
				)
			)
		)
	)
	(zone
		(layers "B.Cu" "In6.Cu" "In11.Cu" "In13.Cu" "In15.Cu")
		(hatch none 0.5)
		(connect_pads
			(clearance 0)
		)
		(min_thickness 0.25)
		(keepout
			(tracks not_allowed)
			(vias allowed)
			(pads allowed)
			(copperpour not_allowed)
			(footprints allowed)
		)
		(placement
			(enabled no)
			(sheetname "")
		)
		(fill yes
			(thermal_gap 0.5)
			(thermal_bridge_width 0.5)
			(island_removal_mode 0)
		)
		(polygon
			(pts
				(arc
					(start 280.969974 -312.084974)
					(mid 280.301954 -312.084974)
					(end 280.969974 -312.084974)
				)
			)
		)
	)
	(zone
		(layers "B.Cu" "In6.Cu" "In11.Cu" "In13.Cu" "In15.Cu")
		(hatch none 0.5)
		(connect_pads
			(clearance 0)
		)
		(min_thickness 0.25)
		(keepout
			(tracks not_allowed)
			(vias allowed)
			(pads allowed)
			(copperpour not_allowed)
			(footprints allowed)
		)
		(placement
			(enabled no)
			(sheetname "")
		)
		(fill yes
			(thermal_gap 0.5)
			(thermal_bridge_width 0.5)
			(island_removal_mode 0)
		)
		(polygon
			(pts
				(arc
					(start 381.479806 -282.186126)
					(mid 380.849886 -282.186126)
					(end 381.479806 -282.186126)
				)
			)
		)
	)
	(zone
		(layers "B.Cu" "In6.Cu" "In11.Cu" "In13.Cu" "In15.Cu")
		(hatch none 0.5)
		(connect_pads
			(clearance 0)
		)
		(min_thickness 0.25)
		(keepout
			(tracks not_allowed)
			(vias allowed)
			(pads allowed)
			(copperpour not_allowed)
			(footprints allowed)
		)
		(placement
			(enabled no)
			(sheetname "")
		)
		(fill yes
			(thermal_gap 0.5)
			(thermal_bridge_width 0.5)
			(island_removal_mode 0)
		)
		(polygon
			(pts
				(arc
					(start 126.489714 -286.23641)
					(mid 125.859794 -286.23641)
					(end 126.489714 -286.23641)
				)
			)
		)
	)
	(zone
		(layers "B.Cu" "In6.Cu" "In11.Cu" "In13.Cu" "In15.Cu")
		(hatch none 0.5)
		(connect_pads
			(clearance 0)
		)
		(min_thickness 0.25)
		(keepout
			(tracks not_allowed)
			(vias allowed)
			(pads allowed)
			(copperpour not_allowed)
			(footprints allowed)
		)
		(placement
			(enabled no)
			(sheetname "")
		)
		(fill yes
			(thermal_gap 0.5)
			(thermal_bridge_width 0.5)
			(island_removal_mode 0)
		)
		(polygon
			(pts
				(arc
					(start 435.334156 -293.384986)
					(mid 434.666136 -293.384986)
					(end 435.334156 -293.384986)
				)
			)
		)
	)
	(zone
		(layers "B.Cu" "In6.Cu" "In11.Cu" "In13.Cu" "In15.Cu")
		(hatch none 0.5)
		(connect_pads
			(clearance 0)
		)
		(min_thickness 0.25)
		(keepout
			(tracks not_allowed)
			(vias allowed)
			(pads allowed)
			(copperpour not_allowed)
			(footprints allowed)
		)
		(placement
			(enabled no)
			(sheetname "")
		)
		(fill yes
			(thermal_gap 0.5)
			(thermal_bridge_width 0.5)
			(island_removal_mode 0)
		)
		(polygon
			(pts
				(arc
					(start 133.539738 -270.846296)
					(mid 132.909818 -270.846296)
					(end 133.539738 -270.846296)
				)
			)
		)
	)
	(zone
		(layers "B.Cu" "In6.Cu" "In11.Cu" "In13.Cu" "In15.Cu")
		(hatch none 0.5)
		(connect_pads
			(clearance 0)
		)
		(min_thickness 0.25)
		(keepout
			(tracks not_allowed)
			(vias allowed)
			(pads allowed)
			(copperpour not_allowed)
			(footprints allowed)
		)
		(placement
			(enabled no)
			(sheetname "")
		)
		(fill yes
			(thermal_gap 0.5)
			(thermal_bridge_width 0.5)
			(island_removal_mode 0)
		)
		(polygon
			(pts
				(arc
					(start 131.359656 -246.914416)
					(mid 130.729736 -246.914416)
					(end 131.359656 -246.914416)
				)
			)
		)
	)
	(zone
		(layers "B.Cu" "In6.Cu" "In11.Cu" "In13.Cu" "In15.Cu")
		(hatch none 0.5)
		(connect_pads
			(clearance 0)
		)
		(min_thickness 0.25)
		(keepout
			(tracks not_allowed)
			(vias allowed)
			(pads allowed)
			(copperpour not_allowed)
			(footprints allowed)
		)
		(placement
			(enabled no)
			(sheetname "")
		)
		(fill yes
			(thermal_gap 0.5)
			(thermal_bridge_width 0.5)
			(island_removal_mode 0)
		)
		(polygon
			(pts
				(arc
					(start 388.406132 -394.385292)
					(mid 387.776212 -394.385292)
					(end 388.406132 -394.385292)
				)
			)
		)
	)
	(zone
		(layers "B.Cu" "In6.Cu" "In11.Cu" "In13.Cu" "In15.Cu")
		(hatch none 0.5)
		(connect_pads
			(clearance 0)
		)
		(min_thickness 0.25)
		(keepout
			(tracks not_allowed)
			(vias allowed)
			(pads allowed)
			(copperpour not_allowed)
			(footprints allowed)
		)
		(placement
			(enabled no)
			(sheetname "")
		)
		(fill yes
			(thermal_gap 0.5)
			(thermal_bridge_width 0.5)
			(island_removal_mode 0)
		)
		(polygon
			(pts
				(arc
					(start 339.355938 -246.104156)
					(mid 338.726018 -246.104156)
					(end 339.355938 -246.104156)
				)
			)
		)
	)
	(zone
		(layers "B.Cu" "In6.Cu" "In11.Cu" "In13.Cu" "In15.Cu")
		(hatch none 0.5)
		(connect_pads
			(clearance 0)
		)
		(min_thickness 0.25)
		(keepout
			(tracks not_allowed)
			(vias allowed)
			(pads allowed)
			(copperpour not_allowed)
			(footprints allowed)
		)
		(placement
			(enabled no)
			(sheetname "")
		)
		(fill yes
			(thermal_gap 0.5)
			(thermal_bridge_width 0.5)
			(island_removal_mode 0)
		)
		(polygon
			(pts
				(arc
					(start 120.00611 -385.31038)
					(mid 119.37619 -385.31038)
					(end 120.00611 -385.31038)
				)
			)
		)
	)
	(zone
		(layers "B.Cu" "In6.Cu" "In11.Cu" "In13.Cu" "In15.Cu")
		(hatch none 0.5)
		(connect_pads
			(clearance 0)
		)
		(min_thickness 0.25)
		(keepout
			(tracks not_allowed)
			(vias allowed)
			(pads allowed)
			(copperpour not_allowed)
			(footprints allowed)
		)
		(placement
			(enabled no)
			(sheetname "")
		)
		(fill yes
			(thermal_gap 0.5)
			(thermal_bridge_width 0.5)
			(island_removal_mode 0)
		)
		(polygon
			(pts
				(arc
					(start 132.129784 -276.516338)
					(mid 131.499864 -276.516338)
					(end 132.129784 -276.516338)
				)
			)
		)
	)
	(zone
		(layers "B.Cu" "In6.Cu" "In11.Cu" "In13.Cu" "In15.Cu")
		(hatch none 0.5)
		(connect_pads
			(clearance 0)
		)
		(min_thickness 0.25)
		(keepout
			(tracks not_allowed)
			(vias allowed)
			(pads allowed)
			(copperpour not_allowed)
			(footprints allowed)
		)
		(placement
			(enabled no)
			(sheetname "")
		)
		(fill yes
			(thermal_gap 0.5)
			(thermal_bridge_width 0.5)
			(island_removal_mode 0)
		)
		(polygon
			(pts
				(arc
					(start 132.76961 -244.484398)
					(mid 132.13969 -244.484398)
					(end 132.76961 -244.484398)
				)
			)
		)
	)
	(zone
		(layers "B.Cu" "In6.Cu" "In11.Cu" "In13.Cu" "In15.Cu")
		(hatch none 0.5)
		(connect_pads
			(clearance 0)
		)
		(min_thickness 0.25)
		(keepout
			(tracks not_allowed)
			(vias allowed)
			(pads allowed)
			(copperpour not_allowed)
			(footprints allowed)
		)
		(placement
			(enabled no)
			(sheetname "")
		)
		(fill yes
			(thermal_gap 0.5)
			(thermal_bridge_width 0.5)
			(island_removal_mode 0)
		)
		(polygon
			(pts
				(arc
					(start 378.806202 -394.385292)
					(mid 378.176282 -394.385292)
					(end 378.806202 -394.385292)
				)
			)
		)
	)
	(zone
		(layers "B.Cu" "In6.Cu" "In11.Cu" "In13.Cu" "In15.Cu")
		(hatch none 0.5)
		(connect_pads
			(clearance 0)
		)
		(min_thickness 0.25)
		(keepout
			(tracks not_allowed)
			(vias allowed)
			(pads allowed)
			(copperpour not_allowed)
			(footprints allowed)
		)
		(placement
			(enabled no)
			(sheetname "")
		)
		(fill yes
			(thermal_gap 0.5)
			(thermal_bridge_width 0.5)
			(island_removal_mode 0)
		)
		(polygon
			(pts
				(arc
					(start 191.494156 -295.085262)
					(mid 190.826136 -295.085262)
					(end 191.494156 -295.085262)
				)
			)
		)
	)
	(zone
		(layers "B.Cu" "In6.Cu" "In11.Cu" "In13.Cu" "In15.Cu")
		(hatch none 0.5)
		(connect_pads
			(clearance 0)
		)
		(min_thickness 0.25)
		(keepout
			(tracks not_allowed)
			(vias allowed)
			(pads allowed)
			(copperpour not_allowed)
			(footprints allowed)
		)
		(placement
			(enabled no)
			(sheetname "")
		)
		(fill yes
			(thermal_gap 0.5)
			(thermal_bridge_width 0.5)
			(island_removal_mode 0)
		)
		(polygon
			(pts
				(arc
					(start 439.434224 -247.485154)
					(mid 438.766204 -247.485154)
					(end 439.434224 -247.485154)
				)
			)
		)
	)
	(zone
		(layers "B.Cu" "In6.Cu" "In11.Cu" "In13.Cu" "In15.Cu")
		(hatch none 0.5)
		(connect_pads
			(clearance 0)
		)
		(min_thickness 0.25)
		(keepout
			(tracks not_allowed)
			(vias allowed)
			(pads allowed)
			(copperpour not_allowed)
			(footprints allowed)
		)
		(placement
			(enabled no)
			(sheetname "")
		)
		(fill yes
			(thermal_gap 0.5)
			(thermal_bridge_width 0.5)
			(island_removal_mode 0)
		)
		(polygon
			(pts
				(arc
					(start 347.17609 -291.095938)
					(mid 346.54617 -291.095938)
					(end 347.17609 -291.095938)
				)
			)
		)
	)
	(zone
		(layers "B.Cu" "In6.Cu" "In11.Cu" "In13.Cu" "In15.Cu")
		(hatch none 0.5)
		(connect_pads
			(clearance 0)
		)
		(min_thickness 0.25)
		(keepout
			(tracks not_allowed)
			(vias allowed)
			(pads allowed)
			(copperpour not_allowed)
			(footprints allowed)
		)
		(placement
			(enabled no)
			(sheetname "")
		)
		(fill yes
			(thermal_gap 0.5)
			(thermal_bridge_width 0.5)
			(island_removal_mode 0)
		)
		(polygon
			(pts
				(arc
					(start 280.969974 -313.784996)
					(mid 280.301954 -313.784996)
					(end 280.969974 -313.784996)
				)
			)
		)
	)
	(zone
		(layers "B.Cu" "In6.Cu" "In11.Cu" "In13.Cu" "In15.Cu")
		(hatch none 0.5)
		(connect_pads
			(clearance 0)
		)
		(min_thickness 0.25)
		(keepout
			(tracks not_allowed)
			(vias allowed)
			(pads allowed)
			(copperpour not_allowed)
			(footprints allowed)
		)
		(placement
			(enabled no)
			(sheetname "")
		)
		(fill yes
			(thermal_gap 0.5)
			(thermal_bridge_width 0.5)
			(island_removal_mode 0)
		)
		(polygon
			(pts
				(arc
					(start 285.070042 -247.485154)
					(mid 284.402022 -247.485154)
					(end 285.070042 -247.485154)
				)
			)
		)
	)
	(zone
		(layers "B.Cu" "In6.Cu" "In11.Cu" "In13.Cu" "In15.Cu")
		(hatch none 0.5)
		(connect_pads
			(clearance 0)
		)
		(min_thickness 0.25)
		(keepout
			(tracks not_allowed)
			(vias allowed)
			(pads allowed)
			(copperpour not_allowed)
			(footprints allowed)
		)
		(placement
			(enabled no)
			(sheetname "")
		)
		(fill yes
			(thermal_gap 0.5)
			(thermal_bridge_width 0.5)
			(island_removal_mode 0)
		)
		(polygon
			(pts
				(arc
					(start 367.549684 -233.14406)
					(mid 366.919764 -233.14406)
					(end 367.549684 -233.14406)
				)
			)
		)
	)
	(zone
		(layers "B.Cu" "In6.Cu" "In11.Cu" "In13.Cu" "In15.Cu")
		(hatch none 0.5)
		(connect_pads
			(clearance 0)
		)
		(min_thickness 0.25)
		(keepout
			(tracks not_allowed)
			(vias allowed)
			(pads allowed)
			(copperpour not_allowed)
			(footprints allowed)
		)
		(placement
			(enabled no)
			(sheetname "")
		)
		(fill yes
			(thermal_gap 0.5)
			(thermal_bridge_width 0.5)
			(island_removal_mode 0)
		)
		(polygon
			(pts
				(arc
					(start 133.069838 -274.896326)
					(mid 132.439918 -274.896326)
					(end 133.069838 -274.896326)
				)
			)
		)
	)
	(zone
		(layers "B.Cu" "In6.Cu" "In11.Cu" "In13.Cu" "In15.Cu")
		(hatch none 0.5)
		(connect_pads
			(clearance 0)
		)
		(min_thickness 0.25)
		(keepout
			(tracks not_allowed)
			(vias allowed)
			(pads allowed)
			(copperpour not_allowed)
			(footprints allowed)
		)
		(placement
			(enabled no)
			(sheetname "")
		)
		(fill yes
			(thermal_gap 0.5)
			(thermal_bridge_width 0.5)
			(island_removal_mode 0)
		)
		(polygon
			(pts
				(arc
					(start 340.295992 -246.104156)
					(mid 339.666072 -246.104156)
					(end 340.295992 -246.104156)
				)
			)
		)
	)
	(zone
		(layers "B.Cu" "In6.Cu" "In11.Cu" "In13.Cu" "In15.Cu")
		(hatch none 0.5)
		(connect_pads
			(clearance 0)
		)
		(min_thickness 0.25)
		(keepout
			(tracks not_allowed)
			(vias allowed)
			(pads allowed)
			(copperpour not_allowed)
			(footprints allowed)
		)
		(placement
			(enabled no)
			(sheetname "")
		)
		(fill yes
			(thermal_gap 0.5)
			(thermal_bridge_width 0.5)
			(island_removal_mode 0)
		)
		(polygon
			(pts
				(arc
					(start 371.606318 -394.385292)
					(mid 370.976398 -394.385292)
					(end 371.606318 -394.385292)
				)
			)
		)
	)
	(zone
		(layers "B.Cu" "In6.Cu" "In11.Cu" "In13.Cu" "In15.Cu")
		(hatch none 0.5)
		(connect_pads
			(clearance 0)
		)
		(min_thickness 0.25)
		(keepout
			(tracks not_allowed)
			(vias allowed)
			(pads allowed)
			(copperpour not_allowed)
			(footprints allowed)
		)
		(placement
			(enabled no)
			(sheetname "")
		)
		(fill yes
			(thermal_gap 0.5)
			(thermal_bridge_width 0.5)
			(island_removal_mode 0)
		)
		(polygon
			(pts
				(arc
					(start 37.129974 -233.035348)
					(mid 36.461954 -233.035348)
					(end 37.129974 -233.035348)
				)
			)
		)
	)
	(zone
		(layers "B.Cu" "In6.Cu" "In11.Cu" "In13.Cu" "In15.Cu")
		(hatch none 0.5)
		(connect_pads
			(clearance 0)
		)
		(min_thickness 0.25)
		(keepout
			(tracks not_allowed)
			(vias allowed)
			(pads allowed)
			(copperpour not_allowed)
			(footprints allowed)
		)
		(placement
			(enabled no)
			(sheetname "")
		)
		(fill yes
			(thermal_gap 0.5)
			(thermal_bridge_width 0.5)
			(island_removal_mode 0)
		)
		(polygon
			(pts
				(arc
					(start 40.123364 -6.725158)
					(mid 39.455344 -6.725158)
					(end 40.123364 -6.725158)
				)
			)
		)
	)
	(zone
		(layers "B.Cu" "In6.Cu" "In11.Cu" "In13.Cu" "In15.Cu")
		(hatch none 0.5)
		(connect_pads
			(clearance 0)
		)
		(min_thickness 0.25)
		(keepout
			(tracks not_allowed)
			(vias allowed)
			(pads allowed)
			(copperpour not_allowed)
			(footprints allowed)
		)
		(placement
			(enabled no)
			(sheetname "")
		)
		(fill yes
			(thermal_gap 0.5)
			(thermal_bridge_width 0.5)
			(island_removal_mode 0)
		)
		(polygon
			(pts
				(arc
					(start 89.491312 -371.49913)
					(mid 88.823292 -371.49913)
					(end 89.491312 -371.49913)
				)
			)
		)
	)
	(zone
		(layers "B.Cu" "In6.Cu" "In11.Cu" "In13.Cu" "In15.Cu")
		(hatch none 0.5)
		(connect_pads
			(clearance 0)
		)
		(min_thickness 0.25)
		(keepout
			(tracks not_allowed)
			(vias allowed)
			(pads allowed)
			(copperpour not_allowed)
			(footprints allowed)
		)
		(placement
			(enabled no)
			(sheetname "")
		)
		(fill yes
			(thermal_gap 0.5)
			(thermal_bridge_width 0.5)
			(island_removal_mode 0)
		)
		(polygon
			(pts
				(arc
					(start 33.029906 -277.235412)
					(mid 32.361886 -277.235412)
					(end 33.029906 -277.235412)
				)
			)
		)
	)
	(zone
		(layers "B.Cu" "In6.Cu" "In11.Cu" "In13.Cu" "In15.Cu")
		(hatch none 0.5)
		(connect_pads
			(clearance 0)
		)
		(min_thickness 0.25)
		(keepout
			(tracks not_allowed)
			(vias allowed)
			(pads allowed)
			(copperpour not_allowed)
			(footprints allowed)
		)
		(placement
			(enabled no)
			(sheetname "")
		)
		(fill yes
			(thermal_gap 0.5)
			(thermal_bridge_width 0.5)
			(island_removal_mode 0)
		)
		(polygon
			(pts
				(arc
					(start 332.740254 -379.88113)
					(mid 332.072234 -379.88113)
					(end 332.740254 -379.88113)
				)
			)
		)
	)
	(zone
		(layers "B.Cu" "In6.Cu" "In11.Cu" "In13.Cu" "In15.Cu")
		(hatch none 0.5)
		(connect_pads
			(clearance 0)
		)
		(min_thickness 0.25)
		(keepout
			(tracks not_allowed)
			(vias allowed)
			(pads allowed)
			(copperpour not_allowed)
			(footprints allowed)
		)
		(placement
			(enabled no)
			(sheetname "")
		)
		(fill yes
			(thermal_gap 0.5)
			(thermal_bridge_width 0.5)
			(island_removal_mode 0)
		)
		(polygon
			(pts
				(arc
					(start 380.709678 -244.484144)
					(mid 380.079758 -244.484144)
					(end 380.709678 -244.484144)
				)
			)
		)
	)
	(zone
		(layers "B.Cu" "In6.Cu" "In11.Cu" "In13.Cu" "In15.Cu")
		(hatch none 0.5)
		(connect_pads
			(clearance 0)
		)
		(min_thickness 0.25)
		(keepout
			(tracks not_allowed)
			(vias allowed)
			(pads allowed)
			(copperpour not_allowed)
			(footprints allowed)
		)
		(placement
			(enabled no)
			(sheetname "")
		)
		(fill yes
			(thermal_gap 0.5)
			(thermal_bridge_width 0.5)
			(island_removal_mode 0)
		)
		(polygon
			(pts
				(arc
					(start 191.494156 -206.685388)
					(mid 190.826136 -206.685388)
					(end 191.494156 -206.685388)
				)
			)
		)
	)
	(zone
		(layers "B.Cu" "In6.Cu" "In11.Cu" "In13.Cu" "In15.Cu")
		(hatch none 0.5)
		(connect_pads
			(clearance 0)
		)
		(min_thickness 0.25)
		(keepout
			(tracks not_allowed)
			(vias allowed)
			(pads allowed)
			(copperpour not_allowed)
			(footprints allowed)
		)
		(placement
			(enabled no)
			(sheetname "")
		)
		(fill yes
			(thermal_gap 0.5)
			(thermal_bridge_width 0.5)
			(island_removal_mode 0)
		)
		(polygon
			(pts
				(arc
					(start 98.295968 -291.096192)
					(mid 97.666048 -291.096192)
					(end 98.295968 -291.096192)
				)
			)
		)
	)
	(zone
		(layers "B.Cu" "In6.Cu" "In11.Cu" "In13.Cu" "In15.Cu")
		(hatch none 0.5)
		(connect_pads
			(clearance 0)
		)
		(min_thickness 0.25)
		(keepout
			(tracks not_allowed)
			(vias allowed)
			(pads allowed)
			(copperpour not_allowed)
			(footprints allowed)
		)
		(placement
			(enabled no)
			(sheetname "")
		)
		(fill yes
			(thermal_gap 0.5)
			(thermal_bridge_width 0.5)
			(island_removal_mode 0)
		)
		(polygon
			(pts
				(arc
					(start 104.876092 -289.47618)
					(mid 104.246172 -289.47618)
					(end 104.876092 -289.47618)
				)
			)
		)
	)
	(zone
		(layers "B.Cu" "In6.Cu" "In11.Cu" "In13.Cu" "In15.Cu")
		(hatch none 0.5)
		(connect_pads
			(clearance 0)
		)
		(min_thickness 0.25)
		(keepout
			(tracks not_allowed)
			(vias allowed)
			(pads allowed)
			(copperpour not_allowed)
			(footprints allowed)
		)
		(placement
			(enabled no)
			(sheetname "")
		)
		(fill yes
			(thermal_gap 0.5)
			(thermal_bridge_width 0.5)
			(island_removal_mode 0)
		)
		(polygon
			(pts
				(arc
					(start 107.696 -291.096192)
					(mid 107.06608 -291.096192)
					(end 107.696 -291.096192)
				)
			)
		)
	)
	(zone
		(layers "B.Cu" "In6.Cu" "In11.Cu" "In13.Cu" "In15.Cu")
		(hatch none 0.5)
		(connect_pads
			(clearance 0)
		)
		(min_thickness 0.25)
		(keepout
			(tracks not_allowed)
			(vias allowed)
			(pads allowed)
			(copperpour not_allowed)
			(footprints allowed)
		)
		(placement
			(enabled no)
			(sheetname "")
		)
		(fill yes
			(thermal_gap 0.5)
			(thermal_bridge_width 0.5)
			(island_removal_mode 0)
		)
		(polygon
			(pts
				(arc
					(start 107.396026 -234.764326)
					(mid 106.766106 -234.764326)
					(end 107.396026 -234.764326)
				)
			)
		)
	)
	(zone
		(layers "B.Cu" "In6.Cu" "In11.Cu" "In13.Cu" "In15.Cu")
		(hatch none 0.5)
		(connect_pads
			(clearance 0)
		)
		(min_thickness 0.25)
		(keepout
			(tracks not_allowed)
			(vias allowed)
			(pads allowed)
			(copperpour not_allowed)
			(footprints allowed)
		)
		(placement
			(enabled no)
			(sheetname "")
		)
		(fill yes
			(thermal_gap 0.5)
			(thermal_bridge_width 0.5)
			(island_removal_mode 0)
		)
		(polygon
			(pts
				(arc
					(start 122.218196 -404.46452)
					(mid 121.550176 -404.46452)
					(end 122.218196 -404.46452)
				)
			)
		)
	)
	(zone
		(layers "B.Cu" "In6.Cu" "In11.Cu" "In13.Cu" "In15.Cu")
		(hatch none 0.5)
		(connect_pads
			(clearance 0)
		)
		(min_thickness 0.25)
		(keepout
			(tracks not_allowed)
			(vias allowed)
			(pads allowed)
			(copperpour not_allowed)
			(footprints allowed)
		)
		(placement
			(enabled no)
			(sheetname "")
		)
		(fill yes
			(thermal_gap 0.5)
			(thermal_bridge_width 0.5)
			(island_removal_mode 0)
		)
		(polygon
			(pts
				(arc
					(start 191.494156 -254.285242)
					(mid 190.826136 -254.285242)
					(end 191.494156 -254.285242)
				)
			)
		)
	)
	(zone
		(layers "B.Cu" "In6.Cu" "In11.Cu" "In13.Cu" "In15.Cu")
		(hatch none 0.5)
		(connect_pads
			(clearance 0)
		)
		(min_thickness 0.25)
		(keepout
			(tracks not_allowed)
			(vias allowed)
			(pads allowed)
			(copperpour not_allowed)
			(footprints allowed)
		)
		(placement
			(enabled no)
			(sheetname "")
		)
		(fill yes
			(thermal_gap 0.5)
			(thermal_bridge_width 0.5)
			(island_removal_mode 0)
		)
		(polygon
			(pts
				(arc
					(start 435.334156 -230.485188)
					(mid 434.666136 -230.485188)
					(end 435.334156 -230.485188)
				)
			)
		)
	)
	(zone
		(layers "B.Cu" "In6.Cu" "In11.Cu" "In13.Cu" "In15.Cu")
		(hatch none 0.5)
		(connect_pads
			(clearance 0)
		)
		(min_thickness 0.25)
		(keepout
			(tracks not_allowed)
			(vias allowed)
			(pads allowed)
			(copperpour not_allowed)
			(footprints allowed)
		)
		(placement
			(enabled no)
			(sheetname "")
		)
		(fill yes
			(thermal_gap 0.5)
			(thermal_bridge_width 0.5)
			(island_removal_mode 0)
		)
		(polygon
			(pts
				(arc
					(start 331.876654 -379.88113)
					(mid 331.208634 -379.88113)
					(end 331.876654 -379.88113)
				)
			)
		)
	)
	(zone
		(layers "B.Cu" "In6.Cu" "In11.Cu" "In13.Cu" "In15.Cu")
		(hatch none 0.5)
		(connect_pads
			(clearance 0)
		)
		(min_thickness 0.25)
		(keepout
			(tracks not_allowed)
			(vias allowed)
			(pads allowed)
			(copperpour not_allowed)
			(footprints allowed)
		)
		(placement
			(enabled no)
			(sheetname "")
		)
		(fill yes
			(thermal_gap 0.5)
			(thermal_bridge_width 0.5)
			(island_removal_mode 0)
		)
		(polygon
			(pts
				(arc
					(start 91.716098 -271.656302)
					(mid 91.086178 -271.656302)
					(end 91.716098 -271.656302)
				)
			)
		)
	)
	(zone
		(layers "B.Cu" "In6.Cu" "In11.Cu" "In13.Cu" "In15.Cu")
		(hatch none 0.5)
		(connect_pads
			(clearance 0)
		)
		(min_thickness 0.25)
		(keepout
			(tracks not_allowed)
			(vias allowed)
			(pads allowed)
			(copperpour not_allowed)
			(footprints allowed)
		)
		(placement
			(enabled no)
			(sheetname "")
		)
		(fill yes
			(thermal_gap 0.5)
			(thermal_bridge_width 0.5)
			(island_removal_mode 0)
		)
		(polygon
			(pts
				(arc
					(start 285.070042 -264.48512)
					(mid 284.402022 -264.48512)
					(end 285.070042 -264.48512)
				)
			)
		)
	)
	(zone
		(layers "B.Cu" "In6.Cu" "In11.Cu" "In13.Cu" "In15.Cu")
		(hatch none 0.5)
		(connect_pads
			(clearance 0)
		)
		(min_thickness 0.25)
		(keepout
			(tracks not_allowed)
			(vias allowed)
			(pads allowed)
			(copperpour not_allowed)
			(footprints allowed)
		)
		(placement
			(enabled no)
			(sheetname "")
		)
		(fill yes
			(thermal_gap 0.5)
			(thermal_bridge_width 0.5)
			(island_removal_mode 0)
		)
		(polygon
			(pts
				(arc
					(start 435.334156 -261.93496)
					(mid 434.666136 -261.93496)
					(end 435.334156 -261.93496)
				)
			)
		)
	)
	(zone
		(layers "B.Cu" "In6.Cu" "In11.Cu" "In13.Cu" "In15.Cu")
		(hatch none 0.5)
		(connect_pads
			(clearance 0)
		)
		(min_thickness 0.25)
		(keepout
			(tracks not_allowed)
			(vias allowed)
			(pads allowed)
			(copperpour not_allowed)
			(footprints allowed)
		)
		(placement
			(enabled no)
			(sheetname "")
		)
		(fill yes
			(thermal_gap 0.5)
			(thermal_bridge_width 0.5)
			(island_removal_mode 0)
		)
		(polygon
			(pts
				(arc
					(start 339.186012 -293.525956)
					(mid 338.556092 -293.525956)
					(end 339.186012 -293.525956)
				)
			)
		)
	)
	(zone
		(layers "B.Cu" "In6.Cu" "In11.Cu" "In13.Cu" "In15.Cu")
		(hatch none 0.5)
		(connect_pads
			(clearance 0)
		)
		(min_thickness 0.25)
		(keepout
			(tracks not_allowed)
			(vias allowed)
			(pads allowed)
			(copperpour not_allowed)
			(footprints allowed)
		)
		(placement
			(enabled no)
			(sheetname "")
		)
		(fill yes
			(thermal_gap 0.5)
			(thermal_bridge_width 0.5)
			(island_removal_mode 0)
		)
		(polygon
			(pts
				(arc
					(start 187.394088 -297.635422)
					(mid 186.726068 -297.635422)
					(end 187.394088 -297.635422)
				)
			)
		)
	)
	(zone
		(layers "B.Cu" "In6.Cu" "In11.Cu" "In13.Cu" "In15.Cu")
		(hatch none 0.5)
		(connect_pads
			(clearance 0)
		)
		(min_thickness 0.25)
		(keepout
			(tracks not_allowed)
			(vias allowed)
			(pads allowed)
			(copperpour not_allowed)
			(footprints allowed)
		)
		(placement
			(enabled no)
			(sheetname "")
		)
		(fill yes
			(thermal_gap 0.5)
			(thermal_bridge_width 0.5)
			(island_removal_mode 0)
		)
		(polygon
			(pts
				(arc
					(start 435.334156 -282.33497)
					(mid 434.666136 -282.33497)
					(end 435.334156 -282.33497)
				)
			)
		)
	)
	(zone
		(layers "B.Cu" "In6.Cu" "In11.Cu" "In13.Cu" "In15.Cu")
		(hatch none 0.5)
		(connect_pads
			(clearance 0)
		)
		(min_thickness 0.25)
		(keepout
			(tracks not_allowed)
			(vias allowed)
			(pads allowed)
			(copperpour not_allowed)
			(footprints allowed)
		)
		(placement
			(enabled no)
			(sheetname "")
		)
		(fill yes
			(thermal_gap 0.5)
			(thermal_bridge_width 0.5)
			(island_removal_mode 0)
		)
		(polygon
			(pts
				(arc
					(start 74.29246 -381.50546)
					(mid 73.62444 -381.50546)
					(end 74.29246 -381.50546)
				)
			)
		)
	)
	(zone
		(layers "B.Cu" "In6.Cu" "In11.Cu" "In13.Cu" "In15.Cu")
		(hatch none 0.5)
		(connect_pads
			(clearance 0)
		)
		(min_thickness 0.25)
		(keepout
			(tracks not_allowed)
			(vias allowed)
			(pads allowed)
			(copperpour not_allowed)
			(footprints allowed)
		)
		(placement
			(enabled no)
			(sheetname "")
		)
		(fill yes
			(thermal_gap 0.5)
			(thermal_bridge_width 0.5)
			(island_removal_mode 0)
		)
		(polygon
			(pts
				(arc
					(start 381.479806 -269.22603)
					(mid 380.849886 -269.22603)
					(end 381.479806 -269.22603)
				)
			)
		)
	)
	(zone
		(layers "B.Cu" "In6.Cu" "In11.Cu" "In13.Cu" "In15.Cu")
		(hatch none 0.5)
		(connect_pads
			(clearance 0)
		)
		(min_thickness 0.25)
		(keepout
			(tracks not_allowed)
			(vias allowed)
			(pads allowed)
			(copperpour not_allowed)
			(footprints allowed)
		)
		(placement
			(enabled no)
			(sheetname "")
		)
		(fill yes
			(thermal_gap 0.5)
			(thermal_bridge_width 0.5)
			(island_removal_mode 0)
		)
		(polygon
			(pts
				(arc
					(start 37.129974 -217.735404)
					(mid 36.461954 -217.735404)
					(end 37.129974 -217.735404)
				)
			)
		)
	)
	(zone
		(layers "B.Cu" "In6.Cu" "In11.Cu" "In13.Cu" "In15.Cu")
		(hatch none 0.5)
		(connect_pads
			(clearance 0)
		)
		(min_thickness 0.25)
		(keepout
			(tracks not_allowed)
			(vias allowed)
			(pads allowed)
			(copperpour not_allowed)
			(footprints allowed)
		)
		(placement
			(enabled no)
			(sheetname "")
		)
		(fill yes
			(thermal_gap 0.5)
			(thermal_bridge_width 0.5)
			(island_removal_mode 0)
		)
		(polygon
			(pts
				(arc
					(start 435.334156 -209.23504)
					(mid 434.666136 -209.23504)
					(end 435.334156 -209.23504)
				)
			)
		)
	)
	(zone
		(layers "B.Cu" "In6.Cu" "In11.Cu" "In13.Cu" "In15.Cu")
		(hatch none 0.5)
		(connect_pads
			(clearance 0)
		)
		(min_thickness 0.25)
		(keepout
			(tracks not_allowed)
			(vias allowed)
			(pads allowed)
			(copperpour not_allowed)
			(footprints allowed)
		)
		(placement
			(enabled no)
			(sheetname "")
		)
		(fill yes
			(thermal_gap 0.5)
			(thermal_bridge_width 0.5)
			(island_removal_mode 0)
		)
		(polygon
			(pts
				(arc
					(start 380.069852 -271.656048)
					(mid 379.439932 -271.656048)
					(end 380.069852 -271.656048)
				)
			)
		)
	)
	(zone
		(layers "B.Cu" "In6.Cu" "In11.Cu" "In13.Cu" "In15.Cu")
		(hatch none 0.5)
		(connect_pads
			(clearance 0)
		)
		(min_thickness 0.25)
		(keepout
			(tracks not_allowed)
			(vias allowed)
			(pads allowed)
			(copperpour not_allowed)
			(footprints allowed)
		)
		(placement
			(enabled no)
			(sheetname "")
		)
		(fill yes
			(thermal_gap 0.5)
			(thermal_bridge_width 0.5)
			(island_removal_mode 0)
		)
		(polygon
			(pts
				(arc
					(start 133.069838 -286.23641)
					(mid 132.439918 -286.23641)
					(end 133.069838 -286.23641)
				)
			)
		)
	)
	(zone
		(layers "B.Cu" "In6.Cu" "In11.Cu" "In13.Cu" "In15.Cu")
		(hatch none 0.5)
		(connect_pads
			(clearance 0)
		)
		(min_thickness 0.25)
		(keepout
			(tracks not_allowed)
			(vias allowed)
			(pads allowed)
			(copperpour not_allowed)
			(footprints allowed)
		)
		(placement
			(enabled no)
			(sheetname "")
		)
		(fill yes
			(thermal_gap 0.5)
			(thermal_bridge_width 0.5)
			(island_removal_mode 0)
		)
		(polygon
			(pts
				(arc
					(start 117.729762 -226.66452)
					(mid 117.099842 -226.66452)
					(end 117.729762 -226.66452)
				)
			)
		)
	)
	(zone
		(layers "B.Cu" "In6.Cu" "In11.Cu" "In13.Cu" "In15.Cu")
		(hatch none 0.5)
		(connect_pads
			(clearance 0)
		)
		(min_thickness 0.25)
		(keepout
			(tracks not_allowed)
			(vias allowed)
			(pads allowed)
			(copperpour not_allowed)
			(footprints allowed)
		)
		(placement
			(enabled no)
			(sheetname "")
		)
		(fill yes
			(thermal_gap 0.5)
			(thermal_bridge_width 0.5)
			(island_removal_mode 0)
		)
		(polygon
			(pts
				(arc
					(start 131.65963 -275.706332)
					(mid 131.02971 -275.706332)
					(end 131.65963 -275.706332)
				)
			)
		)
	)
	(zone
		(layers "B.Cu" "In6.Cu" "In11.Cu" "In13.Cu" "In15.Cu")
		(hatch none 0.5)
		(connect_pads
			(clearance 0)
		)
		(min_thickness 0.25)
		(keepout
			(tracks not_allowed)
			(vias allowed)
			(pads allowed)
			(copperpour not_allowed)
			(footprints allowed)
		)
		(placement
			(enabled no)
			(sheetname "")
		)
		(fill yes
			(thermal_gap 0.5)
			(thermal_bridge_width 0.5)
			(island_removal_mode 0)
		)
		(polygon
			(pts
				(arc
					(start 439.641488 6.581648)
					(mid 438.973468 6.581648)
					(end 439.641488 6.581648)
				)
			)
		)
	)
	(zone
		(layers "B.Cu" "In6.Cu" "In11.Cu" "In13.Cu" "In15.Cu")
		(hatch none 0.5)
		(connect_pads
			(clearance 0)
		)
		(min_thickness 0.25)
		(keepout
			(tracks not_allowed)
			(vias allowed)
			(pads allowed)
			(copperpour not_allowed)
			(footprints allowed)
		)
		(placement
			(enabled no)
			(sheetname "")
		)
		(fill yes
			(thermal_gap 0.5)
			(thermal_bridge_width 0.5)
			(island_removal_mode 0)
		)
		(polygon
			(pts
				(arc
					(start 338.886038 -235.574078)
					(mid 338.256118 -235.574078)
					(end 338.886038 -235.574078)
				)
			)
		)
	)
	(zone
		(layers "B.Cu" "In6.Cu" "In11.Cu" "In13.Cu" "In15.Cu")
		(hatch none 0.5)
		(connect_pads
			(clearance 0)
		)
		(min_thickness 0.25)
		(keepout
			(tracks not_allowed)
			(vias allowed)
			(pads allowed)
			(copperpour not_allowed)
			(footprints allowed)
		)
		(placement
			(enabled no)
			(sheetname "")
		)
		(fill yes
			(thermal_gap 0.5)
			(thermal_bridge_width 0.5)
			(island_removal_mode 0)
		)
		(polygon
			(pts
				(arc
					(start 308.054756 -412.84652)
					(mid 307.386736 -412.84652)
					(end 308.054756 -412.84652)
				)
			)
		)
	)
	(zone
		(layers "B.Cu" "In6.Cu" "In11.Cu" "In13.Cu" "In15.Cu")
		(hatch none 0.5)
		(connect_pads
			(clearance 0)
		)
		(min_thickness 0.25)
		(keepout
			(tracks not_allowed)
			(vias allowed)
			(pads allowed)
			(copperpour not_allowed)
			(footprints allowed)
		)
		(placement
			(enabled no)
			(sheetname "")
		)
		(fill yes
			(thermal_gap 0.5)
			(thermal_bridge_width 0.5)
			(island_removal_mode 0)
		)
		(polygon
			(pts
				(arc
					(start 107.396026 -233.144314)
					(mid 106.766106 -233.144314)
					(end 107.396026 -233.144314)
				)
			)
		)
	)
	(zone
		(layers "B.Cu" "In6.Cu" "In11.Cu" "In13.Cu" "In15.Cu")
		(hatch none 0.5)
		(connect_pads
			(clearance 0)
		)
		(min_thickness 0.25)
		(keepout
			(tracks not_allowed)
			(vias allowed)
			(pads allowed)
			(copperpour not_allowed)
			(footprints allowed)
		)
		(placement
			(enabled no)
			(sheetname "")
		)
		(fill yes
			(thermal_gap 0.5)
			(thermal_bridge_width 0.5)
			(island_removal_mode 0)
		)
		(polygon
			(pts
				(arc
					(start 187.394088 -306.985416)
					(mid 186.726068 -306.985416)
					(end 187.394088 -306.985416)
				)
			)
		)
	)
	(zone
		(layers "B.Cu" "In6.Cu" "In11.Cu" "In13.Cu" "In15.Cu")
		(hatch none 0.5)
		(connect_pads
			(clearance 0)
		)
		(min_thickness 0.25)
		(keepout
			(tracks not_allowed)
			(vias allowed)
			(pads allowed)
			(copperpour not_allowed)
			(footprints allowed)
		)
		(placement
			(enabled no)
			(sheetname "")
		)
		(fill yes
			(thermal_gap 0.5)
			(thermal_bridge_width 0.5)
			(island_removal_mode 0)
		)
		(polygon
			(pts
				(arc
					(start 316.380876 -412.84652)
					(mid 315.712856 -412.84652)
					(end 316.380876 -412.84652)
				)
			)
		)
	)
	(zone
		(layers "B.Cu" "In6.Cu" "In11.Cu" "In13.Cu" "In15.Cu")
		(hatch none 0.5)
		(connect_pads
			(clearance 0)
		)
		(min_thickness 0.25)
		(keepout
			(tracks not_allowed)
			(vias allowed)
			(pads allowed)
			(copperpour not_allowed)
			(footprints allowed)
		)
		(placement
			(enabled no)
			(sheetname "")
		)
		(fill yes
			(thermal_gap 0.5)
			(thermal_bridge_width 0.5)
			(island_removal_mode 0)
		)
		(polygon
			(pts
				(arc
					(start 37.129974 -221.985332)
					(mid 36.461954 -221.985332)
					(end 37.129974 -221.985332)
				)
			)
		)
	)
	(zone
		(layers "B.Cu" "In6.Cu" "In11.Cu" "In13.Cu" "In15.Cu")
		(hatch none 0.5)
		(connect_pads
			(clearance 0)
		)
		(min_thickness 0.25)
		(keepout
			(tracks not_allowed)
			(vias allowed)
			(pads allowed)
			(copperpour not_allowed)
			(footprints allowed)
		)
		(placement
			(enabled no)
			(sheetname "")
		)
		(fill yes
			(thermal_gap 0.5)
			(thermal_bridge_width 0.5)
			(island_removal_mode 0)
		)
		(polygon
			(pts
				(arc
					(start 103.936038 -289.47618)
					(mid 103.306118 -289.47618)
					(end 103.936038 -289.47618)
				)
			)
		)
	)
	(zone
		(layers "B.Cu" "In6.Cu" "In11.Cu" "In13.Cu" "In15.Cu")
		(hatch none 0.5)
		(connect_pads
			(clearance 0)
		)
		(min_thickness 0.25)
		(keepout
			(tracks not_allowed)
			(vias allowed)
			(pads allowed)
			(copperpour not_allowed)
			(footprints allowed)
		)
		(placement
			(enabled no)
			(sheetname "")
		)
		(fill yes
			(thermal_gap 0.5)
			(thermal_bridge_width 0.5)
			(island_removal_mode 0)
		)
		(polygon
			(pts
				(arc
					(start 356.746048 -230.714296)
					(mid 356.116128 -230.714296)
					(end 356.746048 -230.714296)
				)
			)
		)
	)
	(zone
		(layers "B.Cu" "In6.Cu" "In11.Cu" "In13.Cu" "In15.Cu")
		(hatch none 0.5)
		(connect_pads
			(clearance 0)
		)
		(min_thickness 0.25)
		(keepout
			(tracks not_allowed)
			(vias allowed)
			(pads allowed)
			(copperpour not_allowed)
			(footprints allowed)
		)
		(placement
			(enabled no)
			(sheetname "")
		)
		(fill yes
			(thermal_gap 0.5)
			(thermal_bridge_width 0.5)
			(island_removal_mode 0)
		)
		(polygon
			(pts
				(arc
					(start 338.886038 -256.634234)
					(mid 338.256118 -256.634234)
					(end 338.886038 -256.634234)
				)
			)
		)
	)
	(zone
		(layers "B.Cu" "In6.Cu" "In11.Cu" "In13.Cu" "In15.Cu")
		(hatch none 0.5)
		(connect_pads
			(clearance 0)
		)
		(min_thickness 0.25)
		(keepout
			(tracks not_allowed)
			(vias allowed)
			(pads allowed)
			(copperpour not_allowed)
			(footprints allowed)
		)
		(placement
			(enabled no)
			(sheetname "")
		)
		(fill yes
			(thermal_gap 0.5)
			(thermal_bridge_width 0.5)
			(island_removal_mode 0)
		)
		(polygon
			(pts
				(arc
					(start 92.355924 -238.00435)
					(mid 91.726004 -238.00435)
					(end 92.355924 -238.00435)
				)
			)
		)
	)
	(zone
		(layers "B.Cu" "In6.Cu" "In11.Cu" "In13.Cu" "In15.Cu")
		(hatch none 0.5)
		(connect_pads
			(clearance 0)
		)
		(min_thickness 0.25)
		(keepout
			(tracks not_allowed)
			(vias allowed)
			(pads allowed)
			(copperpour not_allowed)
			(footprints allowed)
		)
		(placement
			(enabled no)
			(sheetname "")
		)
		(fill yes
			(thermal_gap 0.5)
			(thermal_bridge_width 0.5)
			(island_removal_mode 0)
		)
		(polygon
			(pts
				(arc
					(start 93.126052 -291.906198)
					(mid 92.496132 -291.906198)
					(end 93.126052 -291.906198)
				)
			)
		)
	)
	(zone
		(layers "B.Cu" "In6.Cu" "In11.Cu" "In13.Cu" "In15.Cu")
		(hatch none 0.5)
		(connect_pads
			(clearance 0)
		)
		(min_thickness 0.25)
		(keepout
			(tracks not_allowed)
			(vias allowed)
			(pads allowed)
			(copperpour not_allowed)
			(footprints allowed)
		)
		(placement
			(enabled no)
			(sheetname "")
		)
		(fill yes
			(thermal_gap 0.5)
			(thermal_bridge_width 0.5)
			(island_removal_mode 0)
		)
		(polygon
			(pts
				(arc
					(start 191.494156 -264.485374)
					(mid 190.826136 -264.485374)
					(end 191.494156 -264.485374)
				)
			)
		)
	)
	(zone
		(layers "B.Cu" "In6.Cu" "In11.Cu" "In13.Cu" "In15.Cu")
		(hatch none 0.5)
		(connect_pads
			(clearance 0)
		)
		(min_thickness 0.25)
		(keepout
			(tracks not_allowed)
			(vias allowed)
			(pads allowed)
			(copperpour not_allowed)
			(footprints allowed)
		)
		(placement
			(enabled no)
			(sheetname "")
		)
		(fill yes
			(thermal_gap 0.5)
			(thermal_bridge_width 0.5)
			(island_removal_mode 0)
		)
		(polygon
			(pts
				(arc
					(start 340.766146 -232.334054)
					(mid 340.136226 -232.334054)
					(end 340.766146 -232.334054)
				)
			)
		)
	)
	(zone
		(layers "B.Cu" "In6.Cu" "In11.Cu" "In13.Cu" "In15.Cu")
		(hatch none 0.5)
		(connect_pads
			(clearance 0)
		)
		(min_thickness 0.25)
		(keepout
			(tracks not_allowed)
			(vias allowed)
			(pads allowed)
			(copperpour not_allowed)
			(footprints allowed)
		)
		(placement
			(enabled no)
			(sheetname "")
		)
		(fill yes
			(thermal_gap 0.5)
			(thermal_bridge_width 0.5)
			(island_removal_mode 0)
		)
		(polygon
			(pts
				(arc
					(start 355.636068 -287.856168)
					(mid 355.006148 -287.856168)
					(end 355.636068 -287.856168)
				)
			)
		)
	)
	(zone
		(layers "B.Cu" "In6.Cu" "In11.Cu" "In13.Cu" "In15.Cu")
		(hatch none 0.5)
		(connect_pads
			(clearance 0)
		)
		(min_thickness 0.25)
		(keepout
			(tracks not_allowed)
			(vias allowed)
			(pads allowed)
			(copperpour not_allowed)
			(footprints allowed)
		)
		(placement
			(enabled no)
			(sheetname "")
		)
		(fill yes
			(thermal_gap 0.5)
			(thermal_bridge_width 0.5)
			(island_removal_mode 0)
		)
		(polygon
			(pts
				(arc
					(start 33.029906 -278.935434)
					(mid 32.361886 -278.935434)
					(end 33.029906 -278.935434)
				)
			)
		)
	)
	(zone
		(layers "B.Cu" "In6.Cu" "In11.Cu" "In13.Cu" "In15.Cu")
		(hatch none 0.5)
		(connect_pads
			(clearance 0)
		)
		(min_thickness 0.25)
		(keepout
			(tracks not_allowed)
			(vias allowed)
			(pads allowed)
			(copperpour not_allowed)
			(footprints allowed)
		)
		(placement
			(enabled no)
			(sheetname "")
		)
		(fill yes
			(thermal_gap 0.5)
			(thermal_bridge_width 0.5)
			(island_removal_mode 0)
		)
		(polygon
			(pts
				(arc
					(start 37.129974 -281.48534)
					(mid 36.461954 -281.48534)
					(end 37.129974 -281.48534)
				)
			)
		)
	)
	(zone
		(layers "B.Cu" "In6.Cu" "In11.Cu" "In13.Cu" "In15.Cu")
		(hatch none 0.5)
		(connect_pads
			(clearance 0)
		)
		(min_thickness 0.25)
		(keepout
			(tracks not_allowed)
			(vias allowed)
			(pads allowed)
			(copperpour not_allowed)
			(footprints allowed)
		)
		(placement
			(enabled no)
			(sheetname "")
		)
		(fill yes
			(thermal_gap 0.5)
			(thermal_bridge_width 0.5)
			(island_removal_mode 0)
		)
		(polygon
			(pts
				(arc
					(start 87.789512 -373.96293)
					(mid 87.121492 -373.96293)
					(end 87.789512 -373.96293)
				)
			)
		)
	)
	(zone
		(layers "B.Cu" "In6.Cu" "In11.Cu" "In13.Cu" "In15.Cu")
		(hatch none 0.5)
		(connect_pads
			(clearance 0)
		)
		(min_thickness 0.25)
		(keepout
			(tracks not_allowed)
			(vias allowed)
			(pads allowed)
			(copperpour not_allowed)
			(footprints allowed)
		)
		(placement
			(enabled no)
			(sheetname "")
		)
		(fill yes
			(thermal_gap 0.5)
			(thermal_bridge_width 0.5)
			(island_removal_mode 0)
		)
		(polygon
			(pts
				(arc
					(start 91.716098 -278.13635)
					(mid 91.086178 -278.13635)
					(end 91.716098 -278.13635)
				)
			)
		)
	)
	(zone
		(layers "B.Cu" "In6.Cu" "In11.Cu" "In13.Cu" "In15.Cu")
		(hatch none 0.5)
		(connect_pads
			(clearance 0)
		)
		(min_thickness 0.25)
		(keepout
			(tracks not_allowed)
			(vias allowed)
			(pads allowed)
			(copperpour not_allowed)
			(footprints allowed)
		)
		(placement
			(enabled no)
			(sheetname "")
		)
		(fill yes
			(thermal_gap 0.5)
			(thermal_bridge_width 0.5)
			(island_removal_mode 0)
		)
		(polygon
			(pts
				(arc
					(start 110.046008 -290.286186)
					(mid 109.416088 -290.286186)
					(end 110.046008 -290.286186)
				)
			)
		)
	)
	(zone
		(layers "B.Cu" "In6.Cu" "In11.Cu" "In13.Cu" "In15.Cu")
		(hatch none 0.5)
		(connect_pads
			(clearance 0)
		)
		(min_thickness 0.25)
		(keepout
			(tracks not_allowed)
			(vias allowed)
			(pads allowed)
			(copperpour not_allowed)
			(footprints allowed)
		)
		(placement
			(enabled no)
			(sheetname "")
		)
		(fill yes
			(thermal_gap 0.5)
			(thermal_bridge_width 0.5)
			(island_removal_mode 0)
		)
		(polygon
			(pts
				(arc
					(start 191.494156 -266.185396)
					(mid 190.826136 -266.185396)
					(end 191.494156 -266.185396)
				)
			)
		)
	)
	(zone
		(layers "B.Cu" "In6.Cu" "In11.Cu" "In13.Cu" "In15.Cu")
		(hatch none 0.5)
		(connect_pads
			(clearance 0)
		)
		(min_thickness 0.25)
		(keepout
			(tracks not_allowed)
			(vias allowed)
			(pads allowed)
			(copperpour not_allowed)
			(footprints allowed)
		)
		(placement
			(enabled no)
			(sheetname "")
		)
		(fill yes
			(thermal_gap 0.5)
			(thermal_bridge_width 0.5)
			(island_removal_mode 0)
		)
		(polygon
			(pts
				(arc
					(start 93.126052 -262.746236)
					(mid 92.496132 -262.746236)
					(end 93.126052 -262.746236)
				)
			)
		)
	)
	(zone
		(layers "B.Cu" "In6.Cu" "In11.Cu" "In13.Cu" "In15.Cu")
		(hatch none 0.5)
		(connect_pads
			(clearance 0)
		)
		(min_thickness 0.25)
		(keepout
			(tracks not_allowed)
			(vias allowed)
			(pads allowed)
			(copperpour not_allowed)
			(footprints allowed)
		)
		(placement
			(enabled no)
			(sheetname "")
		)
		(fill yes
			(thermal_gap 0.5)
			(thermal_bridge_width 0.5)
			(island_removal_mode 0)
		)
		(polygon
			(pts
				(arc
					(start 340.295992 -234.764072)
					(mid 339.666072 -234.764072)
					(end 340.295992 -234.764072)
				)
			)
		)
	)
	(zone
		(layers "B.Cu" "In6.Cu" "In11.Cu" "In13.Cu" "In15.Cu")
		(hatch none 0.5)
		(connect_pads
			(clearance 0)
		)
		(min_thickness 0.25)
		(keepout
			(tracks not_allowed)
			(vias allowed)
			(pads allowed)
			(copperpour not_allowed)
			(footprints allowed)
		)
		(placement
			(enabled no)
			(sheetname "")
		)
		(fill yes
			(thermal_gap 0.5)
			(thermal_bridge_width 0.5)
			(island_removal_mode 0)
		)
		(polygon
			(pts
				(arc
					(start 384.80619 -394.385292)
					(mid 384.17627 -394.385292)
					(end 384.80619 -394.385292)
				)
			)
		)
	)
	(zone
		(layers "B.Cu" "In6.Cu" "In11.Cu" "In13.Cu" "In15.Cu")
		(hatch none 0.5)
		(connect_pads
			(clearance 0)
		)
		(min_thickness 0.25)
		(keepout
			(tracks not_allowed)
			(vias allowed)
			(pads allowed)
			(copperpour not_allowed)
			(footprints allowed)
		)
		(placement
			(enabled no)
			(sheetname "")
		)
		(fill yes
			(thermal_gap 0.5)
			(thermal_bridge_width 0.5)
			(island_removal_mode 0)
		)
		(polygon
			(pts
				(arc
					(start 313.706002 -397.156432)
					(mid 313.076082 -397.156432)
					(end 313.706002 -397.156432)
				)
			)
		)
	)
	(zone
		(layers "B.Cu" "In6.Cu" "In11.Cu" "In13.Cu" "In15.Cu")
		(hatch none 0.5)
		(connect_pads
			(clearance 0)
		)
		(min_thickness 0.25)
		(keepout
			(tracks not_allowed)
			(vias allowed)
			(pads allowed)
			(copperpour not_allowed)
			(footprints allowed)
		)
		(placement
			(enabled no)
			(sheetname "")
		)
		(fill yes
			(thermal_gap 0.5)
			(thermal_bridge_width 0.5)
			(island_removal_mode 0)
		)
		(polygon
			(pts
				(arc
					(start 101.11613 -291.096192)
					(mid 100.48621 -291.096192)
					(end 101.11613 -291.096192)
				)
			)
		)
	)
	(zone
		(layers "B.Cu" "In6.Cu" "In11.Cu" "In13.Cu" "In15.Cu")
		(hatch none 0.5)
		(connect_pads
			(clearance 0)
		)
		(min_thickness 0.25)
		(keepout
			(tracks not_allowed)
			(vias allowed)
			(pads allowed)
			(copperpour not_allowed)
			(footprints allowed)
		)
		(placement
			(enabled no)
			(sheetname "")
		)
		(fill yes
			(thermal_gap 0.5)
			(thermal_bridge_width 0.5)
			(island_removal_mode 0)
		)
		(polygon
			(pts
				(arc
					(start 379.599698 -272.466054)
					(mid 378.969778 -272.466054)
					(end 379.599698 -272.466054)
				)
			)
		)
	)
	(zone
		(layers "B.Cu" "In6.Cu" "In11.Cu" "In13.Cu" "In15.Cu")
		(hatch none 0.5)
		(connect_pads
			(clearance 0)
		)
		(min_thickness 0.25)
		(keepout
			(tracks not_allowed)
			(vias allowed)
			(pads allowed)
			(copperpour not_allowed)
			(footprints allowed)
		)
		(placement
			(enabled no)
			(sheetname "")
		)
		(fill yes
			(thermal_gap 0.5)
			(thermal_bridge_width 0.5)
			(island_removal_mode 0)
		)
		(polygon
			(pts
				(arc
					(start 118.029736 -289.47618)
					(mid 117.399816 -289.47618)
					(end 118.029736 -289.47618)
				)
			)
		)
	)
	(zone
		(layers "B.Cu" "In6.Cu" "In11.Cu" "In13.Cu" "In15.Cu")
		(hatch none 0.5)
		(connect_pads
			(clearance 0)
		)
		(min_thickness 0.25)
		(keepout
			(tracks not_allowed)
			(vias allowed)
			(pads allowed)
			(copperpour not_allowed)
			(footprints allowed)
		)
		(placement
			(enabled no)
			(sheetname "")
		)
		(fill yes
			(thermal_gap 0.5)
			(thermal_bridge_width 0.5)
			(island_removal_mode 0)
		)
		(polygon
			(pts
				(arc
					(start 341.750396 -412.84652)
					(mid 341.082376 -412.84652)
					(end 341.750396 -412.84652)
				)
			)
		)
	)
	(zone
		(layers "B.Cu" "In6.Cu" "In11.Cu" "In13.Cu" "In15.Cu")
		(hatch none 0.5)
		(connect_pads
			(clearance 0)
		)
		(min_thickness 0.25)
		(keepout
			(tracks not_allowed)
			(vias allowed)
			(pads allowed)
			(copperpour not_allowed)
			(footprints allowed)
		)
		(placement
			(enabled no)
			(sheetname "")
		)
		(fill yes
			(thermal_gap 0.5)
			(thermal_bridge_width 0.5)
			(island_removal_mode 0)
		)
		(polygon
			(pts
				(arc
					(start 103.936038 -287.856422)
					(mid 103.306118 -287.856422)
					(end 103.936038 -287.856422)
				)
			)
		)
	)
	(zone
		(layers "B.Cu" "In6.Cu" "In11.Cu" "In13.Cu" "In15.Cu")
		(hatch none 0.5)
		(connect_pads
			(clearance 0)
		)
		(min_thickness 0.25)
		(keepout
			(tracks not_allowed)
			(vias allowed)
			(pads allowed)
			(copperpour not_allowed)
			(footprints allowed)
		)
		(placement
			(enabled no)
			(sheetname "")
		)
		(fill yes
			(thermal_gap 0.5)
			(thermal_bridge_width 0.5)
			(island_removal_mode 0)
		)
		(polygon
			(pts
				(arc
					(start 338.687156 -412.84652)
					(mid 338.019136 -412.84652)
					(end 338.687156 -412.84652)
				)
			)
		)
	)
	(zone
		(layers "B.Cu" "In6.Cu" "In11.Cu" "In13.Cu" "In15.Cu")
		(hatch none 0.5)
		(connect_pads
			(clearance 0)
		)
		(min_thickness 0.25)
		(keepout
			(tracks not_allowed)
			(vias allowed)
			(pads allowed)
			(copperpour not_allowed)
			(footprints allowed)
		)
		(placement
			(enabled no)
			(sheetname "")
		)
		(fill yes
			(thermal_gap 0.5)
			(thermal_bridge_width 0.5)
			(island_removal_mode 0)
		)
		(polygon
			(pts
				(arc
					(start 91.245944 -287.046162)
					(mid 90.616024 -287.046162)
					(end 91.245944 -287.046162)
				)
			)
		)
	)
	(zone
		(layers "B.Cu" "In6.Cu" "In11.Cu" "In13.Cu" "In15.Cu")
		(hatch none 0.5)
		(connect_pads
			(clearance 0)
		)
		(min_thickness 0.25)
		(keepout
			(tracks not_allowed)
			(vias allowed)
			(pads allowed)
			(copperpour not_allowed)
			(footprints allowed)
		)
		(placement
			(enabled no)
			(sheetname "")
		)
		(fill yes
			(thermal_gap 0.5)
			(thermal_bridge_width 0.5)
			(island_removal_mode 0)
		)
		(polygon
			(pts
				(arc
					(start 92.826078 -227.474526)
					(mid 92.196158 -227.474526)
					(end 92.826078 -227.474526)
				)
			)
		)
	)
	(zone
		(layers "B.Cu" "In6.Cu" "In11.Cu" "In13.Cu" "In15.Cu")
		(hatch none 0.5)
		(connect_pads
			(clearance 0)
		)
		(min_thickness 0.25)
		(keepout
			(tracks not_allowed)
			(vias allowed)
			(pads allowed)
			(copperpour not_allowed)
			(footprints allowed)
		)
		(placement
			(enabled no)
			(sheetname "")
		)
		(fill yes
			(thermal_gap 0.5)
			(thermal_bridge_width 0.5)
			(island_removal_mode 0)
		)
		(polygon
			(pts
				(arc
					(start 191.494156 -304.435256)
					(mid 190.826136 -304.435256)
					(end 191.494156 -304.435256)
				)
			)
		)
	)
	(zone
		(layers "B.Cu" "In6.Cu" "In11.Cu" "In13.Cu" "In15.Cu")
		(hatch none 0.5)
		(connect_pads
			(clearance 0)
		)
		(min_thickness 0.25)
		(keepout
			(tracks not_allowed)
			(vias allowed)
			(pads allowed)
			(copperpour not_allowed)
			(footprints allowed)
		)
		(placement
			(enabled no)
			(sheetname "")
		)
		(fill yes
			(thermal_gap 0.5)
			(thermal_bridge_width 0.5)
			(island_removal_mode 0)
		)
		(polygon
			(pts
				(arc
					(start 117.089682 -289.47618)
					(mid 116.459762 -289.47618)
					(end 117.089682 -289.47618)
				)
			)
		)
	)
	(zone
		(layers "B.Cu" "In6.Cu" "In11.Cu" "In13.Cu" "In15.Cu")
		(hatch none 0.5)
		(connect_pads
			(clearance 0)
		)
		(min_thickness 0.25)
		(keepout
			(tracks not_allowed)
			(vias allowed)
			(pads allowed)
			(copperpour not_allowed)
			(footprints allowed)
		)
		(placement
			(enabled no)
			(sheetname "")
		)
		(fill yes
			(thermal_gap 0.5)
			(thermal_bridge_width 0.5)
			(island_removal_mode 0)
		)
		(polygon
			(pts
				(arc
					(start 92.655898 -284.616398)
					(mid 92.025978 -284.616398)
					(end 92.655898 -284.616398)
				)
			)
		)
	)
	(zone
		(layers "B.Cu" "In6.Cu" "In11.Cu" "In13.Cu" "In15.Cu")
		(hatch none 0.5)
		(connect_pads
			(clearance 0)
		)
		(min_thickness 0.25)
		(keepout
			(tracks not_allowed)
			(vias allowed)
			(pads allowed)
			(copperpour not_allowed)
			(footprints allowed)
		)
		(placement
			(enabled no)
			(sheetname "")
		)
		(fill yes
			(thermal_gap 0.5)
			(thermal_bridge_width 0.5)
			(island_removal_mode 0)
		)
		(polygon
			(pts
				(arc
					(start 338.886038 -237.19409)
					(mid 338.256118 -237.19409)
					(end 338.886038 -237.19409)
				)
			)
		)
	)
	(zone
		(layers "B.Cu" "In6.Cu" "In11.Cu" "In13.Cu" "In15.Cu")
		(hatch none 0.5)
		(connect_pads
			(clearance 0)
		)
		(min_thickness 0.25)
		(keepout
			(tracks not_allowed)
			(vias allowed)
			(pads allowed)
			(copperpour not_allowed)
			(footprints allowed)
		)
		(placement
			(enabled no)
			(sheetname "")
		)
		(fill yes
			(thermal_gap 0.5)
			(thermal_bridge_width 0.5)
			(island_removal_mode 0)
		)
		(polygon
			(pts
				(arc
					(start 379.606302 -393.69238)
					(mid 378.976382 -393.69238)
					(end 379.606302 -393.69238)
				)
			)
		)
	)
	(zone
		(layers "B.Cu" "In6.Cu" "In11.Cu" "In13.Cu" "In15.Cu")
		(hatch none 0.5)
		(connect_pads
			(clearance 0)
		)
		(min_thickness 0.25)
		(keepout
			(tracks not_allowed)
			(vias allowed)
			(pads allowed)
			(copperpour not_allowed)
			(footprints allowed)
		)
		(placement
			(enabled no)
			(sheetname "")
		)
		(fill yes
			(thermal_gap 0.5)
			(thermal_bridge_width 0.5)
			(island_removal_mode 0)
		)
		(polygon
			(pts
				(arc
					(start 124.006102 -386.003292)
					(mid 123.376182 -386.003292)
					(end 124.006102 -386.003292)
				)
			)
		)
	)
	(zone
		(layers "B.Cu" "In6.Cu" "In11.Cu" "In13.Cu" "In15.Cu")
		(hatch none 0.5)
		(connect_pads
			(clearance 0)
		)
		(min_thickness 0.25)
		(keepout
			(tracks not_allowed)
			(vias allowed)
			(pads allowed)
			(copperpour not_allowed)
			(footprints allowed)
		)
		(placement
			(enabled no)
			(sheetname "")
		)
		(fill yes
			(thermal_gap 0.5)
			(thermal_bridge_width 0.5)
			(island_removal_mode 0)
		)
		(polygon
			(pts
				(arc
					(start 418.134038 -397.156432)
					(mid 417.504118 -397.156432)
					(end 418.134038 -397.156432)
				)
			)
		)
	)
	(zone
		(layers "B.Cu" "In6.Cu" "In11.Cu" "In13.Cu" "In15.Cu")
		(hatch none 0.5)
		(connect_pads
			(clearance 0)
		)
		(min_thickness 0.25)
		(keepout
			(tracks not_allowed)
			(vias allowed)
			(pads allowed)
			(copperpour not_allowed)
			(footprints allowed)
		)
		(placement
			(enabled no)
			(sheetname "")
		)
		(fill yes
			(thermal_gap 0.5)
			(thermal_bridge_width 0.5)
			(island_removal_mode 0)
		)
		(polygon
			(pts
				(arc
					(start 285.070042 -216.035128)
					(mid 284.402022 -216.035128)
					(end 285.070042 -216.035128)
				)
			)
		)
	)
	(zone
		(layers "B.Cu" "In6.Cu" "In11.Cu" "In13.Cu" "In15.Cu")
		(hatch none 0.5)
		(connect_pads
			(clearance 0)
		)
		(min_thickness 0.25)
		(keepout
			(tracks not_allowed)
			(vias allowed)
			(pads allowed)
			(copperpour not_allowed)
			(footprints allowed)
		)
		(placement
			(enabled no)
			(sheetname "")
		)
		(fill yes
			(thermal_gap 0.5)
			(thermal_bridge_width 0.5)
			(island_removal_mode 0)
		)
		(polygon
			(pts
				(arc
					(start 191.494156 -261.08533)
					(mid 190.826136 -261.08533)
					(end 191.494156 -261.08533)
				)
			)
		)
	)
	(zone
		(layers "B.Cu" "In6.Cu" "In11.Cu" "In13.Cu" "In15.Cu")
		(hatch none 0.5)
		(connect_pads
			(clearance 0)
		)
		(min_thickness 0.25)
		(keepout
			(tracks not_allowed)
			(vias allowed)
			(pads allowed)
			(copperpour not_allowed)
			(footprints allowed)
		)
		(placement
			(enabled no)
			(sheetname "")
		)
		(fill yes
			(thermal_gap 0.5)
			(thermal_bridge_width 0.5)
			(island_removal_mode 0)
		)
		(polygon
			(pts
				(arc
					(start 133.539738 -293.52621)
					(mid 132.909818 -293.52621)
					(end 133.539738 -293.52621)
				)
			)
		)
	)
	(zone
		(layers "B.Cu" "In6.Cu" "In11.Cu" "In13.Cu" "In15.Cu")
		(hatch none 0.5)
		(connect_pads
			(clearance 0)
		)
		(min_thickness 0.25)
		(keepout
			(tracks not_allowed)
			(vias allowed)
			(pads allowed)
			(copperpour not_allowed)
			(footprints allowed)
		)
		(placement
			(enabled no)
			(sheetname "")
		)
		(fill yes
			(thermal_gap 0.5)
			(thermal_bridge_width 0.5)
			(island_removal_mode 0)
		)
		(polygon
			(pts
				(arc
					(start 339.656166 -271.656048)
					(mid 339.026246 -271.656048)
					(end 339.656166 -271.656048)
				)
			)
		)
	)
	(zone
		(layers "B.Cu" "In6.Cu" "In11.Cu" "In13.Cu" "In15.Cu")
		(hatch none 0.5)
		(connect_pads
			(clearance 0)
		)
		(min_thickness 0.25)
		(keepout
			(tracks not_allowed)
			(vias allowed)
			(pads allowed)
			(copperpour not_allowed)
			(footprints allowed)
		)
		(placement
			(enabled no)
			(sheetname "")
		)
		(fill yes
			(thermal_gap 0.5)
			(thermal_bridge_width 0.5)
			(island_removal_mode 0)
		)
		(polygon
			(pts
				(arc
					(start 131.359656 -248.534428)
					(mid 130.729736 -248.534428)
					(end 131.359656 -248.534428)
				)
			)
		)
	)
	(zone
		(layers "B.Cu" "In6.Cu" "In11.Cu" "In13.Cu" "In15.Cu")
		(hatch none 0.5)
		(connect_pads
			(clearance 0)
		)
		(min_thickness 0.25)
		(keepout
			(tracks not_allowed)
			(vias allowed)
			(pads allowed)
			(copperpour not_allowed)
			(footprints allowed)
		)
		(placement
			(enabled no)
			(sheetname "")
		)
		(fill yes
			(thermal_gap 0.5)
			(thermal_bridge_width 0.5)
			(island_removal_mode 0)
		)
		(polygon
			(pts
				(arc
					(start 120.849644 -289.47618)
					(mid 120.219724 -289.47618)
					(end 120.849644 -289.47618)
				)
			)
		)
	)
	(zone
		(layers "B.Cu" "In6.Cu" "In11.Cu" "In13.Cu" "In15.Cu")
		(hatch none 0.5)
		(connect_pads
			(clearance 0)
		)
		(min_thickness 0.25)
		(keepout
			(tracks not_allowed)
			(vias allowed)
			(pads allowed)
			(copperpour not_allowed)
			(footprints allowed)
		)
		(placement
			(enabled no)
			(sheetname "")
		)
		(fill yes
			(thermal_gap 0.5)
			(thermal_bridge_width 0.5)
			(island_removal_mode 0)
		)
		(polygon
			(pts
				(arc
					(start 128.806194 -386.003292)
					(mid 128.176274 -386.003292)
					(end 128.806194 -386.003292)
				)
			)
		)
	)
	(zone
		(layers "B.Cu" "In6.Cu" "In11.Cu" "In13.Cu" "In15.Cu")
		(hatch none 0.5)
		(connect_pads
			(clearance 0)
		)
		(min_thickness 0.25)
		(keepout
			(tracks not_allowed)
			(vias allowed)
			(pads allowed)
			(copperpour not_allowed)
			(footprints allowed)
		)
		(placement
			(enabled no)
			(sheetname "")
		)
		(fill yes
			(thermal_gap 0.5)
			(thermal_bridge_width 0.5)
			(island_removal_mode 0)
		)
		(polygon
			(pts
				(arc
					(start 191.494156 -210.085432)
					(mid 190.826136 -210.085432)
					(end 191.494156 -210.085432)
				)
			)
		)
	)
	(zone
		(layers "B.Cu" "In6.Cu" "In11.Cu" "In13.Cu" "In15.Cu")
		(hatch none 0.5)
		(connect_pads
			(clearance 0)
		)
		(min_thickness 0.25)
		(keepout
			(tracks not_allowed)
			(vias allowed)
			(pads allowed)
			(copperpour not_allowed)
			(footprints allowed)
		)
		(placement
			(enabled no)
			(sheetname "")
		)
		(fill yes
			(thermal_gap 0.5)
			(thermal_bridge_width 0.5)
			(island_removal_mode 0)
		)
		(polygon
			(pts
				(arc
					(start 402.407374 -17.61236)
					(mid 401.739354 -17.61236)
					(end 402.407374 -17.61236)
				)
			)
		)
	)
	(zone
		(layers "B.Cu" "In6.Cu" "In11.Cu" "In13.Cu" "In15.Cu")
		(hatch none 0.5)
		(connect_pads
			(clearance 0)
		)
		(min_thickness 0.25)
		(keepout
			(tracks not_allowed)
			(vias allowed)
			(pads allowed)
			(copperpour not_allowed)
			(footprints allowed)
		)
		(placement
			(enabled no)
			(sheetname "")
		)
		(fill yes
			(thermal_gap 0.5)
			(thermal_bridge_width 0.5)
			(island_removal_mode 0)
		)
		(polygon
			(pts
				(arc
					(start 131.65963 -290.286186)
					(mid 131.02971 -290.286186)
					(end 131.65963 -290.286186)
				)
			)
		)
	)
	(zone
		(layers "B.Cu" "In6.Cu" "In11.Cu" "In13.Cu" "In15.Cu")
		(hatch none 0.5)
		(connect_pads
			(clearance 0)
		)
		(min_thickness 0.25)
		(keepout
			(tracks not_allowed)
			(vias allowed)
			(pads allowed)
			(copperpour not_allowed)
			(footprints allowed)
		)
		(placement
			(enabled no)
			(sheetname "")
		)
		(fill yes
			(thermal_gap 0.5)
			(thermal_bridge_width 0.5)
			(island_removal_mode 0)
		)
		(polygon
			(pts
				(arc
					(start 379.599698 -291.905944)
					(mid 378.969778 -291.905944)
					(end 379.599698 -291.905944)
				)
			)
		)
	)
	(zone
		(layers "B.Cu" "In6.Cu" "In11.Cu" "In13.Cu" "In15.Cu")
		(hatch none 0.5)
		(connect_pads
			(clearance 0)
		)
		(min_thickness 0.25)
		(keepout
			(tracks not_allowed)
			(vias allowed)
			(pads allowed)
			(copperpour not_allowed)
			(footprints allowed)
		)
		(placement
			(enabled no)
			(sheetname "")
		)
		(fill yes
			(thermal_gap 0.5)
			(thermal_bridge_width 0.5)
			(island_removal_mode 0)
		)
		(polygon
			(pts
				(arc
					(start 166.449756 -361.532678)
					(mid 165.781736 -361.532678)
					(end 166.449756 -361.532678)
				)
			)
		)
	)
	(zone
		(layers "B.Cu" "In6.Cu" "In11.Cu" "In13.Cu" "In15.Cu")
		(hatch none 0.5)
		(connect_pads
			(clearance 0)
		)
		(min_thickness 0.25)
		(keepout
			(tracks not_allowed)
			(vias allowed)
			(pads allowed)
			(copperpour not_allowed)
			(footprints allowed)
		)
		(placement
			(enabled no)
			(sheetname "")
		)
		(fill yes
			(thermal_gap 0.5)
			(thermal_bridge_width 0.5)
			(island_removal_mode 0)
		)
		(polygon
			(pts
				(arc
					(start 399.660872 -412.84652)
					(mid 398.992852 -412.84652)
					(end 399.660872 -412.84652)
				)
			)
		)
	)
	(zone
		(layers "B.Cu" "In6.Cu" "In11.Cu" "In13.Cu" "In15.Cu")
		(hatch none 0.5)
		(connect_pads
			(clearance 0)
		)
		(min_thickness 0.25)
		(keepout
			(tracks not_allowed)
			(vias allowed)
			(pads allowed)
			(copperpour not_allowed)
			(footprints allowed)
		)
		(placement
			(enabled no)
			(sheetname "")
		)
		(fill yes
			(thermal_gap 0.5)
			(thermal_bridge_width 0.5)
			(island_removal_mode 0)
		)
		(polygon
			(pts
				(arc
					(start 187.394088 -284.035246)
					(mid 186.726068 -284.035246)
					(end 187.394088 -284.035246)
				)
			)
		)
	)
	(zone
		(layers "B.Cu" "In6.Cu" "In11.Cu" "In13.Cu" "In15.Cu")
		(hatch none 0.5)
		(connect_pads
			(clearance 0)
		)
		(min_thickness 0.25)
		(keepout
			(tracks not_allowed)
			(vias allowed)
			(pads allowed)
			(copperpour not_allowed)
			(footprints allowed)
		)
		(placement
			(enabled no)
			(sheetname "")
		)
		(fill yes
			(thermal_gap 0.5)
			(thermal_bridge_width 0.5)
			(island_removal_mode 0)
		)
		(polygon
			(pts
				(arc
					(start 340.295992 -231.524048)
					(mid 339.666072 -231.524048)
					(end 340.295992 -231.524048)
				)
			)
		)
	)
	(zone
		(layers "B.Cu" "In6.Cu" "In11.Cu" "In13.Cu" "In15.Cu")
		(hatch none 0.5)
		(connect_pads
			(clearance 0)
		)
		(min_thickness 0.25)
		(keepout
			(tracks not_allowed)
			(vias allowed)
			(pads allowed)
			(copperpour not_allowed)
			(footprints allowed)
		)
		(placement
			(enabled no)
			(sheetname "")
		)
		(fill yes
			(thermal_gap 0.5)
			(thermal_bridge_width 0.5)
			(island_removal_mode 0)
		)
		(polygon
			(pts
				(arc
					(start 285.070042 -273.835114)
					(mid 284.402022 -273.835114)
					(end 285.070042 -273.835114)
				)
			)
		)
	)
	(zone
		(layers "B.Cu" "In6.Cu" "In11.Cu" "In13.Cu" "In15.Cu")
		(hatch none 0.5)
		(connect_pads
			(clearance 0)
		)
		(min_thickness 0.25)
		(keepout
			(tracks not_allowed)
			(vias allowed)
			(pads allowed)
			(copperpour not_allowed)
			(footprints allowed)
		)
		(placement
			(enabled no)
			(sheetname "")
		)
		(fill yes
			(thermal_gap 0.5)
			(thermal_bridge_width 0.5)
			(island_removal_mode 0)
		)
		(polygon
			(pts
				(arc
					(start 90.94597 -230.71455)
					(mid 90.31605 -230.71455)
					(end 90.94597 -230.71455)
				)
			)
		)
	)
	(zone
		(layers "B.Cu" "In6.Cu" "In11.Cu" "In13.Cu" "In15.Cu")
		(hatch none 0.5)
		(connect_pads
			(clearance 0)
		)
		(min_thickness 0.25)
		(keepout
			(tracks not_allowed)
			(vias allowed)
			(pads allowed)
			(copperpour not_allowed)
			(footprints allowed)
		)
		(placement
			(enabled no)
			(sheetname "")
		)
		(fill yes
			(thermal_gap 0.5)
			(thermal_bridge_width 0.5)
			(island_removal_mode 0)
		)
		(polygon
			(pts
				(arc
					(start 362.679742 -290.285932)
					(mid 362.049822 -290.285932)
					(end 362.679742 -290.285932)
				)
			)
		)
	)
	(zone
		(layers "B.Cu" "In6.Cu" "In11.Cu" "In13.Cu" "In15.Cu")
		(hatch none 0.5)
		(connect_pads
			(clearance 0)
		)
		(min_thickness 0.25)
		(keepout
			(tracks not_allowed)
			(vias allowed)
			(pads allowed)
			(copperpour not_allowed)
			(footprints allowed)
		)
		(placement
			(enabled no)
			(sheetname "")
		)
		(fill yes
			(thermal_gap 0.5)
			(thermal_bridge_width 0.5)
			(island_removal_mode 0)
		)
		(polygon
			(pts
				(arc
					(start 380.069852 -279.756108)
					(mid 379.439932 -279.756108)
					(end 380.069852 -279.756108)
				)
			)
		)
	)
	(zone
		(layers "B.Cu" "In6.Cu" "In11.Cu" "In13.Cu" "In15.Cu")
		(hatch none 0.5)
		(connect_pads
			(clearance 0)
		)
		(min_thickness 0.25)
		(keepout
			(tracks not_allowed)
			(vias allowed)
			(pads allowed)
			(copperpour not_allowed)
			(footprints allowed)
		)
		(placement
			(enabled no)
			(sheetname "")
		)
		(fill yes
			(thermal_gap 0.5)
			(thermal_bridge_width 0.5)
			(island_removal_mode 0)
		)
		(polygon
			(pts
				(arc
					(start 122.429778 -229.90429)
					(mid 121.799858 -229.90429)
					(end 122.429778 -229.90429)
				)
			)
		)
	)
	(zone
		(layers "B.Cu" "In6.Cu" "In11.Cu" "In13.Cu" "In15.Cu")
		(hatch none 0.5)
		(connect_pads
			(clearance 0)
		)
		(min_thickness 0.25)
		(keepout
			(tracks not_allowed)
			(vias allowed)
			(pads allowed)
			(copperpour not_allowed)
			(footprints allowed)
		)
		(placement
			(enabled no)
			(sheetname "")
		)
		(fill yes
			(thermal_gap 0.5)
			(thermal_bridge_width 0.5)
			(island_removal_mode 0)
		)
		(polygon
			(pts
				(arc
					(start 435.334156 -235.585)
					(mid 434.666136 -235.585)
					(end 435.334156 -235.585)
				)
			)
		)
	)
	(zone
		(layers "B.Cu" "In6.Cu" "In11.Cu" "In13.Cu" "In15.Cu")
		(hatch none 0.5)
		(connect_pads
			(clearance 0)
		)
		(min_thickness 0.25)
		(keepout
			(tracks not_allowed)
			(vias allowed)
			(pads allowed)
			(copperpour not_allowed)
			(footprints allowed)
		)
		(placement
			(enabled no)
			(sheetname "")
		)
		(fill yes
			(thermal_gap 0.5)
			(thermal_bridge_width 0.5)
			(island_removal_mode 0)
		)
		(polygon
			(pts
				(arc
					(start 133.069838 -273.276314)
					(mid 132.439918 -273.276314)
					(end 133.069838 -273.276314)
				)
			)
		)
	)
	(zone
		(layers "B.Cu" "In6.Cu" "In11.Cu" "In13.Cu" "In15.Cu")
		(hatch none 0.5)
		(connect_pads
			(clearance 0)
		)
		(min_thickness 0.25)
		(keepout
			(tracks not_allowed)
			(vias allowed)
			(pads allowed)
			(copperpour not_allowed)
			(footprints allowed)
		)
		(placement
			(enabled no)
			(sheetname "")
		)
		(fill yes
			(thermal_gap 0.5)
			(thermal_bridge_width 0.5)
			(island_removal_mode 0)
		)
		(polygon
			(pts
				(arc
					(start 187.394088 -199.8853)
					(mid 186.726068 -199.8853)
					(end 187.394088 -199.8853)
				)
			)
		)
	)
	(zone
		(layers "B.Cu" "In6.Cu" "In11.Cu" "In13.Cu" "In15.Cu")
		(hatch none 0.5)
		(connect_pads
			(clearance 0)
		)
		(min_thickness 0.25)
		(keepout
			(tracks not_allowed)
			(vias allowed)
			(pads allowed)
			(copperpour not_allowed)
			(footprints allowed)
		)
		(placement
			(enabled no)
			(sheetname "")
		)
		(fill yes
			(thermal_gap 0.5)
			(thermal_bridge_width 0.5)
			(island_removal_mode 0)
		)
		(polygon
			(pts
				(arc
					(start 92.655898 -278.13635)
					(mid 92.025978 -278.13635)
					(end 92.655898 -278.13635)
				)
			)
		)
	)
	(zone
		(layers "B.Cu" "In6.Cu" "In11.Cu" "In13.Cu" "In15.Cu")
		(hatch none 0.5)
		(connect_pads
			(clearance 0)
		)
		(min_thickness 0.25)
		(keepout
			(tracks not_allowed)
			(vias allowed)
			(pads allowed)
			(copperpour not_allowed)
			(footprints allowed)
		)
		(placement
			(enabled no)
			(sheetname "")
		)
		(fill yes
			(thermal_gap 0.5)
			(thermal_bridge_width 0.5)
			(island_removal_mode 0)
		)
		(polygon
			(pts
				(arc
					(start 133.239764 -230.71455)
					(mid 132.609844 -230.71455)
					(end 133.239764 -230.71455)
				)
			)
		)
	)
	(zone
		(layers "B.Cu" "In6.Cu" "In11.Cu" "In13.Cu" "In15.Cu")
		(hatch none 0.5)
		(connect_pads
			(clearance 0)
		)
		(min_thickness 0.25)
		(keepout
			(tracks not_allowed)
			(vias allowed)
			(pads allowed)
			(copperpour not_allowed)
			(footprints allowed)
		)
		(placement
			(enabled no)
			(sheetname "")
		)
		(fill yes
			(thermal_gap 0.5)
			(thermal_bridge_width 0.5)
			(island_removal_mode 0)
		)
		(polygon
			(pts
				(arc
					(start 380.069852 -284.616144)
					(mid 379.439932 -284.616144)
					(end 380.069852 -284.616144)
				)
			)
		)
	)
	(zone
		(layers "B.Cu" "In6.Cu" "In11.Cu" "In13.Cu" "In15.Cu")
		(hatch none 0.5)
		(connect_pads
			(clearance 0)
		)
		(min_thickness 0.25)
		(keepout
			(tracks not_allowed)
			(vias allowed)
			(pads allowed)
			(copperpour not_allowed)
			(footprints allowed)
		)
		(placement
			(enabled no)
			(sheetname "")
		)
		(fill yes
			(thermal_gap 0.5)
			(thermal_bridge_width 0.5)
			(island_removal_mode 0)
		)
		(polygon
			(pts
				(arc
					(start 280.969974 -248.335038)
					(mid 280.301954 -248.335038)
					(end 280.969974 -248.335038)
				)
			)
		)
	)
	(zone
		(layers "B.Cu" "In6.Cu" "In11.Cu" "In13.Cu" "In15.Cu")
		(hatch none 0.5)
		(connect_pads
			(clearance 0)
		)
		(min_thickness 0.25)
		(keepout
			(tracks not_allowed)
			(vias allowed)
			(pads allowed)
			(copperpour not_allowed)
			(footprints allowed)
		)
		(placement
			(enabled no)
			(sheetname "")
		)
		(fill yes
			(thermal_gap 0.5)
			(thermal_bridge_width 0.5)
			(island_removal_mode 0)
		)
		(polygon
			(pts
				(arc
					(start 381.479806 -277.32609)
					(mid 380.849886 -277.32609)
					(end 381.479806 -277.32609)
				)
			)
		)
	)
	(zone
		(layers "B.Cu" "In6.Cu" "In11.Cu" "In13.Cu" "In15.Cu")
		(hatch none 0.5)
		(connect_pads
			(clearance 0)
		)
		(min_thickness 0.25)
		(keepout
			(tracks not_allowed)
			(vias allowed)
			(pads allowed)
			(copperpour not_allowed)
			(footprints allowed)
		)
		(placement
			(enabled no)
			(sheetname "")
		)
		(fill yes
			(thermal_gap 0.5)
			(thermal_bridge_width 0.5)
			(island_removal_mode 0)
		)
		(polygon
			(pts
				(arc
					(start 285.070042 -231.335072)
					(mid 284.402022 -231.335072)
					(end 285.070042 -231.335072)
				)
			)
		)
	)
	(zone
		(layers "B.Cu" "In6.Cu" "In11.Cu" "In13.Cu" "In15.Cu")
		(hatch none 0.5)
		(connect_pads
			(clearance 0)
		)
		(min_thickness 0.25)
		(keepout
			(tracks not_allowed)
			(vias allowed)
			(pads allowed)
			(copperpour not_allowed)
			(footprints allowed)
		)
		(placement
			(enabled no)
			(sheetname "")
		)
		(fill yes
			(thermal_gap 0.5)
			(thermal_bridge_width 0.5)
			(island_removal_mode 0)
		)
		(polygon
			(pts
				(arc
					(start 310.254396 -412.84652)
					(mid 309.586376 -412.84652)
					(end 310.254396 -412.84652)
				)
			)
		)
	)
	(zone
		(layers "B.Cu" "In6.Cu" "In11.Cu" "In13.Cu" "In15.Cu")
		(hatch none 0.5)
		(connect_pads
			(clearance 0)
		)
		(min_thickness 0.25)
		(keepout
			(tracks not_allowed)
			(vias allowed)
			(pads allowed)
			(copperpour not_allowed)
			(footprints allowed)
		)
		(placement
			(enabled no)
			(sheetname "")
		)
		(fill yes
			(thermal_gap 0.5)
			(thermal_bridge_width 0.5)
			(island_removal_mode 0)
		)
		(polygon
			(pts
				(arc
					(start 370.66982 -291.095938)
					(mid 370.0399 -291.095938)
					(end 370.66982 -291.095938)
				)
			)
		)
	)
	(zone
		(layers "B.Cu" "In6.Cu" "In11.Cu" "In13.Cu" "In15.Cu")
		(hatch none 0.5)
		(connect_pads
			(clearance 0)
		)
		(min_thickness 0.25)
		(keepout
			(tracks not_allowed)
			(vias allowed)
			(pads allowed)
			(copperpour not_allowed)
			(footprints allowed)
		)
		(placement
			(enabled no)
			(sheetname "")
		)
		(fill yes
			(thermal_gap 0.5)
			(thermal_bridge_width 0.5)
			(island_removal_mode 0)
		)
		(polygon
			(pts
				(arc
					(start 317.305944 -397.156432)
					(mid 316.676024 -397.156432)
					(end 317.305944 -397.156432)
				)
			)
		)
	)
	(zone
		(layers "B.Cu" "In6.Cu" "In11.Cu" "In13.Cu" "In15.Cu")
		(hatch none 0.5)
		(connect_pads
			(clearance 0)
		)
		(min_thickness 0.25)
		(keepout
			(tracks not_allowed)
			(vias allowed)
			(pads allowed)
			(copperpour not_allowed)
			(footprints allowed)
		)
		(placement
			(enabled no)
			(sheetname "")
		)
		(fill yes
			(thermal_gap 0.5)
			(thermal_bridge_width 0.5)
			(island_removal_mode 0)
		)
		(polygon
			(pts
				(arc
					(start 280.969974 -205.834996)
					(mid 280.301954 -205.834996)
					(end 280.969974 -205.834996)
				)
			)
		)
	)
	(zone
		(layers "B.Cu" "In6.Cu" "In11.Cu" "In13.Cu" "In15.Cu")
		(hatch none 0.5)
		(connect_pads
			(clearance 0)
		)
		(min_thickness 0.25)
		(keepout
			(tracks not_allowed)
			(vias allowed)
			(pads allowed)
			(copperpour not_allowed)
			(footprints allowed)
		)
		(placement
			(enabled no)
			(sheetname "")
		)
		(fill yes
			(thermal_gap 0.5)
			(thermal_bridge_width 0.5)
			(island_removal_mode 0)
		)
		(polygon
			(pts
				(arc
					(start 330.292202 -389.88746)
					(mid 329.624182 -389.88746)
					(end 330.292202 -389.88746)
				)
			)
		)
	)
	(zone
		(layers "B.Cu" "In6.Cu" "In11.Cu" "In13.Cu" "In15.Cu")
		(hatch none 0.5)
		(connect_pads
			(clearance 0)
		)
		(min_thickness 0.25)
		(keepout
			(tracks not_allowed)
			(vias allowed)
			(pads allowed)
			(copperpour not_allowed)
			(footprints allowed)
		)
		(placement
			(enabled no)
			(sheetname "")
		)
		(fill yes
			(thermal_gap 0.5)
			(thermal_bridge_width 0.5)
			(island_removal_mode 0)
		)
		(polygon
			(pts
				(arc
					(start 91.41587 -246.10441)
					(mid 90.78595 -246.10441)
					(end 91.41587 -246.10441)
				)
			)
		)
	)
	(zone
		(layers "B.Cu" "In6.Cu" "In11.Cu" "In13.Cu" "In15.Cu")
		(hatch none 0.5)
		(connect_pads
			(clearance 0)
		)
		(min_thickness 0.25)
		(keepout
			(tracks not_allowed)
			(vias allowed)
			(pads allowed)
			(copperpour not_allowed)
			(footprints allowed)
		)
		(placement
			(enabled no)
			(sheetname "")
		)
		(fill yes
			(thermal_gap 0.5)
			(thermal_bridge_width 0.5)
			(island_removal_mode 0)
		)
		(polygon
			(pts
				(arc
					(start 92.355924 -229.90429)
					(mid 91.726004 -229.90429)
					(end 92.355924 -229.90429)
				)
			)
		)
	)
	(zone
		(layers "B.Cu" "In6.Cu" "In11.Cu" "In13.Cu" "In15.Cu")
		(hatch none 0.5)
		(connect_pads
			(clearance 0)
		)
		(min_thickness 0.25)
		(keepout
			(tracks not_allowed)
			(vias allowed)
			(pads allowed)
			(copperpour not_allowed)
			(footprints allowed)
		)
		(placement
			(enabled no)
			(sheetname "")
		)
		(fill yes
			(thermal_gap 0.5)
			(thermal_bridge_width 0.5)
			(island_removal_mode 0)
		)
		(polygon
			(pts
				(arc
					(start 133.607556 -404.46452)
					(mid 132.939536 -404.46452)
					(end 133.607556 -404.46452)
				)
			)
		)
	)
	(zone
		(layers "B.Cu" "In6.Cu" "In11.Cu" "In13.Cu" "In15.Cu")
		(hatch none 0.5)
		(connect_pads
			(clearance 0)
		)
		(min_thickness 0.25)
		(keepout
			(tracks not_allowed)
			(vias allowed)
			(pads allowed)
			(copperpour not_allowed)
			(footprints allowed)
		)
		(placement
			(enabled no)
			(sheetname "")
		)
		(fill yes
			(thermal_gap 0.5)
			(thermal_bridge_width 0.5)
			(island_removal_mode 0)
		)
		(polygon
			(pts
				(arc
					(start 439.434224 -240.685066)
					(mid 438.766204 -240.685066)
					(end 439.434224 -240.685066)
				)
			)
		)
	)
	(zone
		(layers "B.Cu" "In6.Cu" "In11.Cu" "In13.Cu" "In15.Cu")
		(hatch none 0.5)
		(connect_pads
			(clearance 0)
		)
		(min_thickness 0.25)
		(keepout
			(tracks not_allowed)
			(vias allowed)
			(pads allowed)
			(copperpour not_allowed)
			(footprints allowed)
		)
		(placement
			(enabled no)
			(sheetname "")
		)
		(fill yes
			(thermal_gap 0.5)
			(thermal_bridge_width 0.5)
			(island_removal_mode 0)
		)
		(polygon
			(pts
				(arc
					(start 391.274046 5.718048)
					(mid 390.606026 5.718048)
					(end 391.274046 5.718048)
				)
			)
		)
	)
	(zone
		(layers "B.Cu" "In6.Cu" "In11.Cu" "In13.Cu" "In15.Cu")
		(hatch none 0.5)
		(connect_pads
			(clearance 0)
		)
		(min_thickness 0.25)
		(keepout
			(tracks not_allowed)
			(vias allowed)
			(pads allowed)
			(copperpour not_allowed)
			(footprints allowed)
		)
		(placement
			(enabled no)
			(sheetname "")
		)
		(fill yes
			(thermal_gap 0.5)
			(thermal_bridge_width 0.5)
			(island_removal_mode 0)
		)
		(polygon
			(pts
				(arc
					(start 357.046022 -288.66592)
					(mid 356.416102 -288.66592)
					(end 357.046022 -288.66592)
				)
			)
		)
	)
	(zone
		(layers "B.Cu" "In6.Cu" "In11.Cu" "In13.Cu" "In15.Cu")
		(hatch none 0.5)
		(connect_pads
			(clearance 0)
		)
		(min_thickness 0.25)
		(keepout
			(tracks not_allowed)
			(vias allowed)
			(pads allowed)
			(copperpour not_allowed)
			(footprints allowed)
		)
		(placement
			(enabled no)
			(sheetname "")
		)
		(fill yes
			(thermal_gap 0.5)
			(thermal_bridge_width 0.5)
			(island_removal_mode 0)
		)
		(polygon
			(pts
				(arc
					(start 92.355924 -236.384338)
					(mid 91.726004 -236.384338)
					(end 92.355924 -236.384338)
				)
			)
		)
	)
	(zone
		(layers "B.Cu" "In6.Cu" "In11.Cu" "In13.Cu" "In15.Cu")
		(hatch none 0.5)
		(connect_pads
			(clearance 0)
		)
		(min_thickness 0.25)
		(keepout
			(tracks not_allowed)
			(vias allowed)
			(pads allowed)
			(copperpour not_allowed)
			(footprints allowed)
		)
		(placement
			(enabled no)
			(sheetname "")
		)
		(fill yes
			(thermal_gap 0.5)
			(thermal_bridge_width 0.5)
			(island_removal_mode 0)
		)
		(polygon
			(pts
				(arc
					(start 351.576132 -228.284278)
					(mid 350.946212 -228.284278)
					(end 351.576132 -228.284278)
				)
			)
		)
	)
	(zone
		(layers "B.Cu" "In6.Cu" "In11.Cu" "In13.Cu" "In15.Cu")
		(hatch none 0.5)
		(connect_pads
			(clearance 0)
		)
		(min_thickness 0.25)
		(keepout
			(tracks not_allowed)
			(vias allowed)
			(pads allowed)
			(copperpour not_allowed)
			(footprints allowed)
		)
		(placement
			(enabled no)
			(sheetname "")
		)
		(fill yes
			(thermal_gap 0.5)
			(thermal_bridge_width 0.5)
			(island_removal_mode 0)
		)
		(polygon
			(pts
				(arc
					(start 37.129974 -236.435392)
					(mid 36.461954 -236.435392)
					(end 37.129974 -236.435392)
				)
			)
		)
	)
	(zone
		(layers "B.Cu" "In6.Cu" "In11.Cu" "In13.Cu" "In15.Cu")
		(hatch none 0.5)
		(connect_pads
			(clearance 0)
		)
		(min_thickness 0.25)
		(keepout
			(tracks not_allowed)
			(vias allowed)
			(pads allowed)
			(copperpour not_allowed)
			(footprints allowed)
		)
		(placement
			(enabled no)
			(sheetname "")
		)
		(fill yes
			(thermal_gap 0.5)
			(thermal_bridge_width 0.5)
			(island_removal_mode 0)
		)
		(polygon
			(pts
				(arc
					(start 418.533834 -397.849344)
					(mid 417.903914 -397.849344)
					(end 418.533834 -397.849344)
				)
			)
		)
	)
	(zone
		(layers "B.Cu" "In6.Cu" "In11.Cu" "In13.Cu" "In15.Cu")
		(hatch none 0.5)
		(connect_pads
			(clearance 0)
		)
		(min_thickness 0.25)
		(keepout
			(tracks not_allowed)
			(vias allowed)
			(pads allowed)
			(copperpour not_allowed)
			(footprints allowed)
		)
		(placement
			(enabled no)
			(sheetname "")
		)
		(fill yes
			(thermal_gap 0.5)
			(thermal_bridge_width 0.5)
			(island_removal_mode 0)
		)
		(polygon
			(pts
				(arc
					(start 37.129974 -262.785352)
					(mid 36.461954 -262.785352)
					(end 37.129974 -262.785352)
				)
			)
		)
	)
	(zone
		(layers "B.Cu" "In6.Cu" "In11.Cu" "In13.Cu" "In15.Cu")
		(hatch none 0.5)
		(connect_pads
			(clearance 0)
		)
		(min_thickness 0.25)
		(keepout
			(tracks not_allowed)
			(vias allowed)
			(pads allowed)
			(copperpour not_allowed)
			(footprints allowed)
		)
		(placement
			(enabled no)
			(sheetname "")
		)
		(fill yes
			(thermal_gap 0.5)
			(thermal_bridge_width 0.5)
			(island_removal_mode 0)
		)
		(polygon
			(pts
				(arc
					(start 380.709678 -231.524048)
					(mid 380.079758 -231.524048)
					(end 380.709678 -231.524048)
				)
			)
		)
	)
	(zone
		(layers "B.Cu" "In6.Cu" "In11.Cu" "In13.Cu" "In15.Cu")
		(hatch none 0.5)
		(connect_pads
			(clearance 0)
		)
		(min_thickness 0.25)
		(keepout
			(tracks not_allowed)
			(vias allowed)
			(pads allowed)
			(copperpour not_allowed)
			(footprints allowed)
		)
		(placement
			(enabled no)
			(sheetname "")
		)
		(fill yes
			(thermal_gap 0.5)
			(thermal_bridge_width 0.5)
			(island_removal_mode 0)
		)
		(polygon
			(pts
				(arc
					(start 285.070042 -208.385156)
					(mid 284.402022 -208.385156)
					(end 285.070042 -208.385156)
				)
			)
		)
	)
	(zone
		(layers "B.Cu" "In6.Cu" "In11.Cu" "In13.Cu" "In15.Cu")
		(hatch none 0.5)
		(connect_pads
			(clearance 0)
		)
		(min_thickness 0.25)
		(keepout
			(tracks not_allowed)
			(vias allowed)
			(pads allowed)
			(copperpour not_allowed)
			(footprints allowed)
		)
		(placement
			(enabled no)
			(sheetname "")
		)
		(fill yes
			(thermal_gap 0.5)
			(thermal_bridge_width 0.5)
			(island_removal_mode 0)
		)
		(polygon
			(pts
				(arc
					(start 363.319822 -232.334054)
					(mid 362.689902 -232.334054)
					(end 363.319822 -232.334054)
				)
			)
		)
	)
	(zone
		(layers "B.Cu" "In6.Cu" "In11.Cu" "In13.Cu" "In15.Cu")
		(hatch none 0.5)
		(connect_pads
			(clearance 0)
		)
		(min_thickness 0.25)
		(keepout
			(tracks not_allowed)
			(vias allowed)
			(pads allowed)
			(copperpour not_allowed)
			(footprints allowed)
		)
		(placement
			(enabled no)
			(sheetname "")
		)
		(fill yes
			(thermal_gap 0.5)
			(thermal_bridge_width 0.5)
			(island_removal_mode 0)
		)
		(polygon
			(pts
				(arc
					(start 187.394088 -238.985298)
					(mid 186.726068 -238.985298)
					(end 187.394088 -238.985298)
				)
			)
		)
	)
	(zone
		(layers "B.Cu" "In6.Cu" "In11.Cu" "In13.Cu" "In15.Cu")
		(hatch none 0.5)
		(connect_pads
			(clearance 0)
		)
		(min_thickness 0.25)
		(keepout
			(tracks not_allowed)
			(vias allowed)
			(pads allowed)
			(copperpour not_allowed)
			(footprints allowed)
		)
		(placement
			(enabled no)
			(sheetname "")
		)
		(fill yes
			(thermal_gap 0.5)
			(thermal_bridge_width 0.5)
			(island_removal_mode 0)
		)
		(polygon
			(pts
				(arc
					(start 380.069852 -282.996132)
					(mid 379.439932 -282.996132)
					(end 380.069852 -282.996132)
				)
			)
		)
	)
	(zone
		(layers "B.Cu" "In6.Cu" "In11.Cu" "In13.Cu" "In15.Cu")
		(hatch none 0.5)
		(connect_pads
			(clearance 0)
		)
		(min_thickness 0.25)
		(keepout
			(tracks not_allowed)
			(vias allowed)
			(pads allowed)
			(copperpour not_allowed)
			(footprints allowed)
		)
		(placement
			(enabled no)
			(sheetname "")
		)
		(fill yes
			(thermal_gap 0.5)
			(thermal_bridge_width 0.5)
			(island_removal_mode 0)
		)
		(polygon
			(pts
				(arc
					(start 435.334156 -229.63505)
					(mid 434.666136 -229.63505)
					(end 435.334156 -229.63505)
				)
			)
		)
	)
	(zone
		(layers "B.Cu" "In6.Cu" "In11.Cu" "In13.Cu" "In15.Cu")
		(hatch none 0.5)
		(connect_pads
			(clearance 0)
		)
		(min_thickness 0.25)
		(keepout
			(tracks not_allowed)
			(vias allowed)
			(pads allowed)
			(copperpour not_allowed)
			(footprints allowed)
		)
		(placement
			(enabled no)
			(sheetname "")
		)
		(fill yes
			(thermal_gap 0.5)
			(thermal_bridge_width 0.5)
			(island_removal_mode 0)
		)
		(polygon
			(pts
				(arc
					(start 280.969974 -201.585068)
					(mid 280.301954 -201.585068)
					(end 280.969974 -201.585068)
				)
			)
		)
	)
	(zone
		(layers "B.Cu" "In6.Cu" "In11.Cu" "In13.Cu" "In15.Cu")
		(hatch none 0.5)
		(connect_pads
			(clearance 0)
		)
		(min_thickness 0.25)
		(keepout
			(tracks not_allowed)
			(vias allowed)
			(pads allowed)
			(copperpour not_allowed)
			(footprints allowed)
		)
		(placement
			(enabled no)
			(sheetname "")
		)
		(fill yes
			(thermal_gap 0.5)
			(thermal_bridge_width 0.5)
			(island_removal_mode 0)
		)
		(polygon
			(pts
				(arc
					(start 341.06612 -264.365994)
					(mid 340.4362 -264.365994)
					(end 341.06612 -264.365994)
				)
			)
		)
	)
	(zone
		(layers "B.Cu" "In6.Cu" "In11.Cu" "In13.Cu" "In15.Cu")
		(hatch none 0.5)
		(connect_pads
			(clearance 0)
		)
		(min_thickness 0.25)
		(keepout
			(tracks not_allowed)
			(vias allowed)
			(pads allowed)
			(copperpour not_allowed)
			(footprints allowed)
		)
		(placement
			(enabled no)
			(sheetname "")
		)
		(fill yes
			(thermal_gap 0.5)
			(thermal_bridge_width 0.5)
			(island_removal_mode 0)
		)
		(polygon
			(pts
				(arc
					(start 91.41587 -241.244374)
					(mid 90.78595 -241.244374)
					(end 91.41587 -241.244374)
				)
			)
		)
	)
	(zone
		(layers "B.Cu" "In6.Cu" "In11.Cu" "In13.Cu" "In15.Cu")
		(hatch none 0.5)
		(connect_pads
			(clearance 0)
		)
		(min_thickness 0.25)
		(keepout
			(tracks not_allowed)
			(vias allowed)
			(pads allowed)
			(copperpour not_allowed)
			(footprints allowed)
		)
		(placement
			(enabled no)
			(sheetname "")
		)
		(fill yes
			(thermal_gap 0.5)
			(thermal_bridge_width 0.5)
			(island_removal_mode 0)
		)
		(polygon
			(pts
				(arc
					(start 381.179832 -256.634234)
					(mid 380.549912 -256.634234)
					(end 381.179832 -256.634234)
				)
			)
		)
	)
	(zone
		(layers "B.Cu" "In6.Cu" "In11.Cu" "In13.Cu" "In15.Cu")
		(hatch none 0.5)
		(connect_pads
			(clearance 0)
		)
		(min_thickness 0.25)
		(keepout
			(tracks not_allowed)
			(vias allowed)
			(pads allowed)
			(copperpour not_allowed)
			(footprints allowed)
		)
		(placement
			(enabled no)
			(sheetname "")
		)
		(fill yes
			(thermal_gap 0.5)
			(thermal_bridge_width 0.5)
			(island_removal_mode 0)
		)
		(polygon
			(pts
				(arc
					(start 91.716098 -273.276314)
					(mid 91.086178 -273.276314)
					(end 91.716098 -273.276314)
				)
			)
		)
	)
	(zone
		(layers "B.Cu" "In6.Cu" "In11.Cu" "In13.Cu" "In15.Cu")
		(hatch none 0.5)
		(connect_pads
			(clearance 0)
		)
		(min_thickness 0.25)
		(keepout
			(tracks not_allowed)
			(vias allowed)
			(pads allowed)
			(copperpour not_allowed)
			(footprints allowed)
		)
		(placement
			(enabled no)
			(sheetname "")
		)
		(fill yes
			(thermal_gap 0.5)
			(thermal_bridge_width 0.5)
			(island_removal_mode 0)
		)
		(polygon
			(pts
				(arc
					(start 340.295992 -238.004096)
					(mid 339.666072 -238.004096)
					(end 340.295992 -238.004096)
				)
			)
		)
	)
	(zone
		(layers "B.Cu" "In6.Cu" "In11.Cu" "In13.Cu" "In15.Cu")
		(hatch none 0.5)
		(connect_pads
			(clearance 0)
		)
		(min_thickness 0.25)
		(keepout
			(tracks not_allowed)
			(vias allowed)
			(pads allowed)
			(copperpour not_allowed)
			(footprints allowed)
		)
		(placement
			(enabled no)
			(sheetname "")
		)
		(fill yes
			(thermal_gap 0.5)
			(thermal_bridge_width 0.5)
			(island_removal_mode 0)
		)
		(polygon
			(pts
				(arc
					(start 122.429778 -228.284532)
					(mid 121.799858 -228.284532)
					(end 122.429778 -228.284532)
				)
			)
		)
	)
	(zone
		(layers "B.Cu" "In6.Cu" "In11.Cu" "In13.Cu" "In15.Cu")
		(hatch none 0.5)
		(connect_pads
			(clearance 0)
		)
		(min_thickness 0.25)
		(keepout
			(tracks not_allowed)
			(vias allowed)
			(pads allowed)
			(copperpour not_allowed)
			(footprints allowed)
		)
		(placement
			(enabled no)
			(sheetname "")
		)
		(fill yes
			(thermal_gap 0.5)
			(thermal_bridge_width 0.5)
			(island_removal_mode 0)
		)
		(polygon
			(pts
				(arc
					(start 92.826078 -237.194344)
					(mid 92.196158 -237.194344)
					(end 92.826078 -237.194344)
				)
			)
		)
	)
	(zone
		(layers "B.Cu" "In6.Cu" "In11.Cu" "In13.Cu" "In15.Cu")
		(hatch none 0.5)
		(connect_pads
			(clearance 0)
		)
		(min_thickness 0.25)
		(keepout
			(tracks not_allowed)
			(vias allowed)
			(pads allowed)
			(copperpour not_allowed)
			(footprints allowed)
		)
		(placement
			(enabled no)
			(sheetname "")
		)
		(fill yes
			(thermal_gap 0.5)
			(thermal_bridge_width 0.5)
			(island_removal_mode 0)
		)
		(polygon
			(pts
				(arc
					(start 379.599698 -277.32609)
					(mid 378.969778 -277.32609)
					(end 379.599698 -277.32609)
				)
			)
		)
	)
	(zone
		(layers "B.Cu" "In6.Cu" "In11.Cu" "In13.Cu" "In15.Cu")
		(hatch none 0.5)
		(connect_pads
			(clearance 0)
		)
		(min_thickness 0.25)
		(keepout
			(tracks not_allowed)
			(vias allowed)
			(pads allowed)
			(copperpour not_allowed)
			(footprints allowed)
		)
		(placement
			(enabled no)
			(sheetname "")
		)
		(fill yes
			(thermal_gap 0.5)
			(thermal_bridge_width 0.5)
			(island_removal_mode 0)
		)
		(polygon
			(pts
				(arc
					(start 187.394088 -243.235226)
					(mid 186.726068 -243.235226)
					(end 187.394088 -243.235226)
				)
			)
		)
	)
	(zone
		(layers "B.Cu" "In6.Cu" "In11.Cu" "In13.Cu" "In15.Cu")
		(hatch none 0.5)
		(connect_pads
			(clearance 0)
		)
		(min_thickness 0.25)
		(keepout
			(tracks not_allowed)
			(vias allowed)
			(pads allowed)
			(copperpour not_allowed)
			(footprints allowed)
		)
		(placement
			(enabled no)
			(sheetname "")
		)
		(fill yes
			(thermal_gap 0.5)
			(thermal_bridge_width 0.5)
			(island_removal_mode 0)
		)
		(polygon
			(pts
				(arc
					(start 362.379768 -235.574078)
					(mid 361.749848 -235.574078)
					(end 362.379768 -235.574078)
				)
			)
		)
	)
	(zone
		(layers "B.Cu" "In6.Cu" "In11.Cu" "In13.Cu" "In15.Cu")
		(hatch none 0.5)
		(connect_pads
			(clearance 0)
		)
		(min_thickness 0.25)
		(keepout
			(tracks not_allowed)
			(vias allowed)
			(pads allowed)
			(copperpour not_allowed)
			(footprints allowed)
		)
		(placement
			(enabled no)
			(sheetname "")
		)
		(fill yes
			(thermal_gap 0.5)
			(thermal_bridge_width 0.5)
			(island_removal_mode 0)
		)
		(polygon
			(pts
				(arc
					(start 131.359656 -237.194344)
					(mid 130.729736 -237.194344)
					(end 131.359656 -237.194344)
				)
			)
		)
	)
	(zone
		(layers "B.Cu" "In6.Cu" "In11.Cu" "In13.Cu" "In15.Cu")
		(hatch none 0.5)
		(connect_pads
			(clearance 0)
		)
		(min_thickness 0.25)
		(keepout
			(tracks not_allowed)
			(vias allowed)
			(pads allowed)
			(copperpour not_allowed)
			(footprints allowed)
		)
		(placement
			(enabled no)
			(sheetname "")
		)
		(fill yes
			(thermal_gap 0.5)
			(thermal_bridge_width 0.5)
			(island_removal_mode 0)
		)
		(polygon
			(pts
				(arc
					(start 187.394088 -202.435206)
					(mid 186.726068 -202.435206)
					(end 187.394088 -202.435206)
				)
			)
		)
	)
	(zone
		(layers "B.Cu" "In6.Cu" "In11.Cu" "In13.Cu" "In15.Cu")
		(hatch none 0.5)
		(connect_pads
			(clearance 0)
		)
		(min_thickness 0.25)
		(keepout
			(tracks not_allowed)
			(vias allowed)
			(pads allowed)
			(copperpour not_allowed)
			(footprints allowed)
		)
		(placement
			(enabled no)
			(sheetname "")
		)
		(fill yes
			(thermal_gap 0.5)
			(thermal_bridge_width 0.5)
			(island_removal_mode 0)
		)
		(polygon
			(pts
				(arc
					(start 33.029906 -220.28531)
					(mid 32.361886 -220.28531)
					(end 33.029906 -220.28531)
				)
			)
		)
	)
	(zone
		(layers "B.Cu" "In6.Cu" "In11.Cu" "In13.Cu" "In15.Cu")
		(hatch none 0.5)
		(connect_pads
			(clearance 0)
		)
		(min_thickness 0.25)
		(keepout
			(tracks not_allowed)
			(vias allowed)
			(pads allowed)
			(copperpour not_allowed)
			(footprints allowed)
		)
		(placement
			(enabled no)
			(sheetname "")
		)
		(fill yes
			(thermal_gap 0.5)
			(thermal_bridge_width 0.5)
			(island_removal_mode 0)
		)
		(polygon
			(pts
				(arc
					(start 379.599698 -278.946102)
					(mid 378.969778 -278.946102)
					(end 379.599698 -278.946102)
				)
			)
		)
	)
	(zone
		(layers "B.Cu" "In6.Cu" "In11.Cu" "In13.Cu" "In15.Cu")
		(hatch none 0.5)
		(connect_pads
			(clearance 0)
		)
		(min_thickness 0.25)
		(keepout
			(tracks not_allowed)
			(vias allowed)
			(pads allowed)
			(copperpour not_allowed)
			(footprints allowed)
		)
		(placement
			(enabled no)
			(sheetname "")
		)
		(fill yes
			(thermal_gap 0.5)
			(thermal_bridge_width 0.5)
			(island_removal_mode 0)
		)
		(polygon
			(pts
				(arc
					(start 380.709678 -250.964192)
					(mid 380.079758 -250.964192)
					(end 380.709678 -250.964192)
				)
			)
		)
	)
	(zone
		(layers "B.Cu" "In6.Cu" "In11.Cu" "In13.Cu" "In15.Cu")
		(hatch none 0.5)
		(connect_pads
			(clearance 0)
		)
		(min_thickness 0.25)
		(keepout
			(tracks not_allowed)
			(vias allowed)
			(pads allowed)
			(copperpour not_allowed)
			(footprints allowed)
		)
		(placement
			(enabled no)
			(sheetname "")
		)
		(fill yes
			(thermal_gap 0.5)
			(thermal_bridge_width 0.5)
			(island_removal_mode 0)
		)
		(polygon
			(pts
				(arc
					(start 416.134042 -397.849344)
					(mid 415.504122 -397.849344)
					(end 416.134042 -397.849344)
				)
			)
		)
	)
	(zone
		(layers "B.Cu" "In6.Cu" "In11.Cu" "In13.Cu" "In15.Cu")
		(hatch none 0.5)
		(connect_pads
			(clearance 0)
		)
		(min_thickness 0.25)
		(keepout
			(tracks not_allowed)
			(vias allowed)
			(pads allowed)
			(copperpour not_allowed)
			(footprints allowed)
		)
		(placement
			(enabled no)
			(sheetname "")
		)
		(fill yes
			(thermal_gap 0.5)
			(thermal_bridge_width 0.5)
			(island_removal_mode 0)
		)
		(polygon
			(pts
				(arc
					(start 91.41587 -252.584458)
					(mid 90.78595 -252.584458)
					(end 91.41587 -252.584458)
				)
			)
		)
	)
	(zone
		(layers "B.Cu" "In6.Cu" "In11.Cu" "In13.Cu" "In15.Cu")
		(hatch none 0.5)
		(connect_pads
			(clearance 0)
		)
		(min_thickness 0.25)
		(keepout
			(tracks not_allowed)
			(vias allowed)
			(pads allowed)
			(copperpour not_allowed)
			(footprints allowed)
		)
		(placement
			(enabled no)
			(sheetname "")
		)
		(fill yes
			(thermal_gap 0.5)
			(thermal_bridge_width 0.5)
			(island_removal_mode 0)
		)
		(polygon
			(pts
				(arc
					(start 381.179832 -253.39421)
					(mid 380.549912 -253.39421)
					(end 381.179832 -253.39421)
				)
			)
		)
	)
	(zone
		(layers "B.Cu" "In6.Cu" "In11.Cu" "In13.Cu" "In15.Cu")
		(hatch none 0.5)
		(connect_pads
			(clearance 0)
		)
		(min_thickness 0.25)
		(keepout
			(tracks not_allowed)
			(vias allowed)
			(pads allowed)
			(copperpour not_allowed)
			(footprints allowed)
		)
		(placement
			(enabled no)
			(sheetname "")
		)
		(fill yes
			(thermal_gap 0.5)
			(thermal_bridge_width 0.5)
			(island_removal_mode 0)
		)
		(polygon
			(pts
				(arc
					(start 307.706014 -397.156432)
					(mid 307.076094 -397.156432)
					(end 307.706014 -397.156432)
				)
			)
		)
	)
	(zone
		(layers "B.Cu" "In6.Cu" "In11.Cu" "In13.Cu" "In15.Cu")
		(hatch none 0.5)
		(connect_pads
			(clearance 0)
		)
		(min_thickness 0.25)
		(keepout
			(tracks not_allowed)
			(vias allowed)
			(pads allowed)
			(copperpour not_allowed)
			(footprints allowed)
		)
		(placement
			(enabled no)
			(sheetname "")
		)
		(fill yes
			(thermal_gap 0.5)
			(thermal_bridge_width 0.5)
			(island_removal_mode 0)
		)
		(polygon
			(pts
				(arc
					(start 352.516186 -228.284278)
					(mid 351.886266 -228.284278)
					(end 352.516186 -228.284278)
				)
			)
		)
	)
	(zone
		(layers "B.Cu" "In6.Cu" "In11.Cu" "In13.Cu" "In15.Cu")
		(hatch none 0.5)
		(connect_pads
			(clearance 0)
		)
		(min_thickness 0.25)
		(keepout
			(tracks not_allowed)
			(vias allowed)
			(pads allowed)
			(copperpour not_allowed)
			(footprints allowed)
		)
		(placement
			(enabled no)
			(sheetname "")
		)
		(fill yes
			(thermal_gap 0.5)
			(thermal_bridge_width 0.5)
			(island_removal_mode 0)
		)
		(polygon
			(pts
				(arc
					(start 380.709678 -246.104156)
					(mid 380.079758 -246.104156)
					(end 380.709678 -246.104156)
				)
			)
		)
	)
	(zone
		(layers "B.Cu" "In6.Cu" "In11.Cu" "In13.Cu" "In15.Cu")
		(hatch none 0.5)
		(connect_pads
			(clearance 0)
		)
		(min_thickness 0.25)
		(keepout
			(tracks not_allowed)
			(vias allowed)
			(pads allowed)
			(copperpour not_allowed)
			(footprints allowed)
		)
		(placement
			(enabled no)
			(sheetname "")
		)
		(fill yes
			(thermal_gap 0.5)
			(thermal_bridge_width 0.5)
			(island_removal_mode 0)
		)
		(polygon
			(pts
				(arc
					(start 304.991516 -412.84652)
					(mid 304.323496 -412.84652)
					(end 304.991516 -412.84652)
				)
			)
		)
	)
	(zone
		(layers "B.Cu" "In6.Cu" "In11.Cu" "In13.Cu" "In15.Cu")
		(hatch none 0.5)
		(connect_pads
			(clearance 0)
		)
		(min_thickness 0.25)
		(keepout
			(tracks not_allowed)
			(vias allowed)
			(pads allowed)
			(copperpour not_allowed)
			(footprints allowed)
		)
		(placement
			(enabled no)
			(sheetname "")
		)
		(fill yes
			(thermal_gap 0.5)
			(thermal_bridge_width 0.5)
			(island_removal_mode 0)
		)
		(polygon
			(pts
				(arc
					(start 33.029906 -246.63527)
					(mid 32.361886 -246.63527)
					(end 33.029906 -246.63527)
				)
			)
		)
	)
	(zone
		(layers "B.Cu" "In6.Cu" "In11.Cu" "In13.Cu" "In15.Cu")
		(hatch none 0.5)
		(connect_pads
			(clearance 0)
		)
		(min_thickness 0.25)
		(keepout
			(tracks not_allowed)
			(vias allowed)
			(pads allowed)
			(copperpour not_allowed)
			(footprints allowed)
		)
		(placement
			(enabled no)
			(sheetname "")
		)
		(fill yes
			(thermal_gap 0.5)
			(thermal_bridge_width 0.5)
			(island_removal_mode 0)
		)
		(polygon
			(pts
				(arc
					(start 132.129784 -270.03629)
					(mid 131.499864 -270.03629)
					(end 132.129784 -270.03629)
				)
			)
		)
	)
	(zone
		(layers "B.Cu" "In6.Cu" "In11.Cu" "In13.Cu" "In15.Cu")
		(hatch none 0.5)
		(connect_pads
			(clearance 0)
		)
		(min_thickness 0.25)
		(keepout
			(tracks not_allowed)
			(vias allowed)
			(pads allowed)
			(copperpour not_allowed)
			(footprints allowed)
		)
		(placement
			(enabled no)
			(sheetname "")
		)
		(fill yes
			(thermal_gap 0.5)
			(thermal_bridge_width 0.5)
			(island_removal_mode 0)
		)
		(polygon
			(pts
				(arc
					(start 380.709678 -239.624108)
					(mid 380.079758 -239.624108)
					(end 380.709678 -239.624108)
				)
			)
		)
	)
	(zone
		(layers "B.Cu" "In6.Cu" "In11.Cu" "In13.Cu" "In15.Cu")
		(hatch none 0.5)
		(connect_pads
			(clearance 0)
		)
		(min_thickness 0.25)
		(keepout
			(tracks not_allowed)
			(vias allowed)
			(pads allowed)
			(copperpour not_allowed)
			(footprints allowed)
		)
		(placement
			(enabled no)
			(sheetname "")
		)
		(fill yes
			(thermal_gap 0.5)
			(thermal_bridge_width 0.5)
			(island_removal_mode 0)
		)
		(polygon
			(pts
				(arc
					(start 123.669806 -287.856422)
					(mid 123.039886 -287.856422)
					(end 123.669806 -287.856422)
				)
			)
		)
	)
	(zone
		(layers "B.Cu" "In6.Cu" "In11.Cu" "In13.Cu" "In15.Cu")
		(hatch none 0.5)
		(connect_pads
			(clearance 0)
		)
		(min_thickness 0.25)
		(keepout
			(tracks not_allowed)
			(vias allowed)
			(pads allowed)
			(copperpour not_allowed)
			(footprints allowed)
		)
		(placement
			(enabled no)
			(sheetname "")
		)
		(fill yes
			(thermal_gap 0.5)
			(thermal_bridge_width 0.5)
			(island_removal_mode 0)
		)
		(polygon
			(pts
				(arc
					(start 285.070042 -306.135024)
					(mid 284.402022 -306.135024)
					(end 285.070042 -306.135024)
				)
			)
		)
	)
	(zone
		(layers "B.Cu" "In6.Cu" "In11.Cu" "In13.Cu" "In15.Cu")
		(hatch none 0.5)
		(connect_pads
			(clearance 0)
		)
		(min_thickness 0.25)
		(keepout
			(tracks not_allowed)
			(vias allowed)
			(pads allowed)
			(copperpour not_allowed)
			(footprints allowed)
		)
		(placement
			(enabled no)
			(sheetname "")
		)
		(fill yes
			(thermal_gap 0.5)
			(thermal_bridge_width 0.5)
			(island_removal_mode 0)
		)
		(polygon
			(pts
				(arc
					(start 176.781714 -369.598448)
					(mid 176.113694 -369.598448)
					(end 176.781714 -369.598448)
				)
			)
		)
	)
	(zone
		(layers "B.Cu" "In6.Cu" "In11.Cu" "In13.Cu" "In15.Cu")
		(hatch none 0.5)
		(connect_pads
			(clearance 0)
		)
		(min_thickness 0.25)
		(keepout
			(tracks not_allowed)
			(vias allowed)
			(pads allowed)
			(copperpour not_allowed)
			(footprints allowed)
		)
		(placement
			(enabled no)
			(sheetname "")
		)
		(fill yes
			(thermal_gap 0.5)
			(thermal_bridge_width 0.5)
			(island_removal_mode 0)
		)
		(polygon
			(pts
				(arc
					(start 19.34972 -6.725158)
					(mid 18.6817 -6.725158)
					(end 19.34972 -6.725158)
				)
			)
		)
	)
	(zone
		(layers "B.Cu" "In6.Cu" "In11.Cu" "In13.Cu" "In15.Cu")
		(hatch none 0.5)
		(connect_pads
			(clearance 0)
		)
		(min_thickness 0.25)
		(keepout
			(tracks not_allowed)
			(vias allowed)
			(pads allowed)
			(copperpour not_allowed)
			(footprints allowed)
		)
		(placement
			(enabled no)
			(sheetname "")
		)
		(fill yes
			(thermal_gap 0.5)
			(thermal_bridge_width 0.5)
			(island_removal_mode 0)
		)
		(polygon
			(pts
				(arc
					(start 285.070042 -214.335106)
					(mid 284.402022 -214.335106)
					(end 285.070042 -214.335106)
				)
			)
		)
	)
	(zone
		(layers "B.Cu" "In6.Cu" "In11.Cu" "In13.Cu" "In15.Cu")
		(hatch none 0.5)
		(connect_pads
			(clearance 0)
		)
		(min_thickness 0.25)
		(keepout
			(tracks not_allowed)
			(vias allowed)
			(pads allowed)
			(copperpour not_allowed)
			(footprints allowed)
		)
		(placement
			(enabled no)
			(sheetname "")
		)
		(fill yes
			(thermal_gap 0.5)
			(thermal_bridge_width 0.5)
			(island_removal_mode 0)
		)
		(polygon
			(pts
				(arc
					(start 339.355938 -252.584204)
					(mid 338.726018 -252.584204)
					(end 339.355938 -252.584204)
				)
			)
		)
	)
	(zone
		(layers "B.Cu" "In6.Cu" "In11.Cu" "In13.Cu" "In15.Cu")
		(hatch none 0.5)
		(connect_pads
			(clearance 0)
		)
		(min_thickness 0.25)
		(keepout
			(tracks not_allowed)
			(vias allowed)
			(pads allowed)
			(copperpour not_allowed)
			(footprints allowed)
		)
		(placement
			(enabled no)
			(sheetname "")
		)
		(fill yes
			(thermal_gap 0.5)
			(thermal_bridge_width 0.5)
			(island_removal_mode 0)
		)
		(polygon
			(pts
				(arc
					(start 109.105954 -287.046162)
					(mid 108.476034 -287.046162)
					(end 109.105954 -287.046162)
				)
			)
		)
	)
	(zone
		(layers "B.Cu" "In6.Cu" "In11.Cu" "In13.Cu" "In15.Cu")
		(hatch none 0.5)
		(connect_pads
			(clearance 0)
		)
		(min_thickness 0.25)
		(keepout
			(tracks not_allowed)
			(vias allowed)
			(pads allowed)
			(copperpour not_allowed)
			(footprints allowed)
		)
		(placement
			(enabled no)
			(sheetname "")
		)
		(fill yes
			(thermal_gap 0.5)
			(thermal_bridge_width 0.5)
			(island_removal_mode 0)
		)
		(polygon
			(pts
				(arc
					(start 98.295968 -286.23641)
					(mid 97.666048 -286.23641)
					(end 98.295968 -286.23641)
				)
			)
		)
	)
	(zone
		(layers "B.Cu" "In6.Cu" "In11.Cu" "In13.Cu" "In15.Cu")
		(hatch none 0.5)
		(connect_pads
			(clearance 0)
		)
		(min_thickness 0.25)
		(keepout
			(tracks not_allowed)
			(vias allowed)
			(pads allowed)
			(copperpour not_allowed)
			(footprints allowed)
		)
		(placement
			(enabled no)
			(sheetname "")
		)
		(fill yes
			(thermal_gap 0.5)
			(thermal_bridge_width 0.5)
			(island_removal_mode 0)
		)
		(polygon
			(pts
				(arc
					(start 191.494156 -225.385376)
					(mid 190.826136 -225.385376)
					(end 191.494156 -225.385376)
				)
			)
		)
	)
	(zone
		(layers "B.Cu" "In6.Cu" "In11.Cu" "In13.Cu" "In15.Cu")
		(hatch none 0.5)
		(connect_pads
			(clearance 0)
		)
		(min_thickness 0.25)
		(keepout
			(tracks not_allowed)
			(vias allowed)
			(pads allowed)
			(copperpour not_allowed)
			(footprints allowed)
		)
		(placement
			(enabled no)
			(sheetname "")
		)
		(fill yes
			(thermal_gap 0.5)
			(thermal_bridge_width 0.5)
			(island_removal_mode 0)
		)
		(polygon
			(pts
				(arc
					(start 379.299724 -229.094284)
					(mid 378.669804 -229.094284)
					(end 379.299724 -229.094284)
				)
			)
		)
	)
	(zone
		(layers "B.Cu" "In6.Cu" "In11.Cu" "In13.Cu" "In15.Cu")
		(hatch none 0.5)
		(connect_pads
			(clearance 0)
		)
		(min_thickness 0.25)
		(keepout
			(tracks not_allowed)
			(vias allowed)
			(pads allowed)
			(copperpour not_allowed)
			(footprints allowed)
		)
		(placement
			(enabled no)
			(sheetname "")
		)
		(fill yes
			(thermal_gap 0.5)
			(thermal_bridge_width 0.5)
			(island_removal_mode 0)
		)
		(polygon
			(pts
				(arc
					(start 379.299724 -232.334054)
					(mid 378.669804 -232.334054)
					(end 379.299724 -232.334054)
				)
			)
		)
	)
	(zone
		(layers "B.Cu" "In6.Cu" "In11.Cu" "In13.Cu" "In15.Cu")
		(hatch none 0.5)
		(connect_pads
			(clearance 0)
		)
		(min_thickness 0.25)
		(keepout
			(tracks not_allowed)
			(vias allowed)
			(pads allowed)
			(copperpour not_allowed)
			(footprints allowed)
		)
		(placement
			(enabled no)
			(sheetname "")
		)
		(fill yes
			(thermal_gap 0.5)
			(thermal_bridge_width 0.5)
			(island_removal_mode 0)
		)
		(polygon
			(pts
				(arc
					(start 33.029906 -302.735234)
					(mid 32.361886 -302.735234)
					(end 33.029906 -302.735234)
				)
			)
		)
	)
	(zone
		(layers "B.Cu" "In6.Cu" "In11.Cu" "In13.Cu" "In15.Cu")
		(hatch none 0.5)
		(connect_pads
			(clearance 0)
		)
		(min_thickness 0.25)
		(keepout
			(tracks not_allowed)
			(vias allowed)
			(pads allowed)
			(copperpour not_allowed)
			(footprints allowed)
		)
		(placement
			(enabled no)
			(sheetname "")
		)
		(fill yes
			(thermal_gap 0.5)
			(thermal_bridge_width 0.5)
			(island_removal_mode 0)
		)
		(polygon
			(pts
				(arc
					(start 316.106048 -397.156432)
					(mid 315.476128 -397.156432)
					(end 316.106048 -397.156432)
				)
			)
		)
	)
	(zone
		(layers "B.Cu" "In6.Cu" "In11.Cu" "In13.Cu" "In15.Cu")
		(hatch none 0.5)
		(connect_pads
			(clearance 0)
		)
		(min_thickness 0.25)
		(keepout
			(tracks not_allowed)
			(vias allowed)
			(pads allowed)
			(copperpour not_allowed)
			(footprints allowed)
		)
		(placement
			(enabled no)
			(sheetname "")
		)
		(fill yes
			(thermal_gap 0.5)
			(thermal_bridge_width 0.5)
			(island_removal_mode 0)
		)
		(polygon
			(pts
				(arc
					(start 280.969974 -237.285022)
					(mid 280.301954 -237.285022)
					(end 280.969974 -237.285022)
				)
			)
		)
	)
	(zone
		(layers "B.Cu" "In6.Cu" "In11.Cu" "In13.Cu" "In15.Cu")
		(hatch none 0.5)
		(connect_pads
			(clearance 0)
		)
		(min_thickness 0.25)
		(keepout
			(tracks not_allowed)
			(vias allowed)
			(pads allowed)
			(copperpour not_allowed)
			(footprints allowed)
		)
		(placement
			(enabled no)
			(sheetname "")
		)
		(fill yes
			(thermal_gap 0.5)
			(thermal_bridge_width 0.5)
			(island_removal_mode 0)
		)
		(polygon
			(pts
				(arc
					(start 339.547454 -379.88113)
					(mid 338.879434 -379.88113)
					(end 339.547454 -379.88113)
				)
			)
		)
	)
	(zone
		(layers "B.Cu" "In6.Cu" "In11.Cu" "In13.Cu" "In15.Cu")
		(hatch none 0.5)
		(connect_pads
			(clearance 0)
		)
		(min_thickness 0.25)
		(keepout
			(tracks not_allowed)
			(vias allowed)
			(pads allowed)
			(copperpour not_allowed)
			(footprints allowed)
		)
		(placement
			(enabled no)
			(sheetname "")
		)
		(fill yes
			(thermal_gap 0.5)
			(thermal_bridge_width 0.5)
			(island_removal_mode 0)
		)
		(polygon
			(pts
				(arc
					(start 435.334156 -302.73498)
					(mid 434.666136 -302.73498)
					(end 435.334156 -302.73498)
				)
			)
		)
	)
	(zone
		(layers "B.Cu" "In6.Cu" "In11.Cu" "In13.Cu" "In15.Cu")
		(hatch none 0.5)
		(connect_pads
			(clearance 0)
		)
		(min_thickness 0.25)
		(keepout
			(tracks not_allowed)
			(vias allowed)
			(pads allowed)
			(copperpour not_allowed)
			(footprints allowed)
		)
		(placement
			(enabled no)
			(sheetname "")
		)
		(fill yes
			(thermal_gap 0.5)
			(thermal_bridge_width 0.5)
			(island_removal_mode 0)
		)
		(polygon
			(pts
				(arc
					(start 371.309646 -231.524048)
					(mid 370.679726 -231.524048)
					(end 371.309646 -231.524048)
				)
			)
		)
	)
	(zone
		(layers "B.Cu" "In6.Cu" "In11.Cu" "In13.Cu" "In15.Cu")
		(hatch none 0.5)
		(connect_pads
			(clearance 0)
		)
		(min_thickness 0.25)
		(keepout
			(tracks not_allowed)
			(vias allowed)
			(pads allowed)
			(copperpour not_allowed)
			(footprints allowed)
		)
		(placement
			(enabled no)
			(sheetname "")
		)
		(fill yes
			(thermal_gap 0.5)
			(thermal_bridge_width 0.5)
			(island_removal_mode 0)
		)
		(polygon
			(pts
				(arc
					(start 33.029906 -295.085262)
					(mid 32.361886 -295.085262)
					(end 33.029906 -295.085262)
				)
			)
		)
	)
	(zone
		(layers "B.Cu" "In6.Cu" "In11.Cu" "In13.Cu" "In15.Cu")
		(hatch none 0.5)
		(connect_pads
			(clearance 0)
		)
		(min_thickness 0.25)
		(keepout
			(tracks not_allowed)
			(vias allowed)
			(pads allowed)
			(copperpour not_allowed)
			(footprints allowed)
		)
		(placement
			(enabled no)
			(sheetname "")
		)
		(fill yes
			(thermal_gap 0.5)
			(thermal_bridge_width 0.5)
			(island_removal_mode 0)
		)
		(polygon
			(pts
				(arc
					(start 191.494156 -312.935366)
					(mid 190.826136 -312.935366)
					(end 191.494156 -312.935366)
				)
			)
		)
	)
	(zone
		(layers "B.Cu" "In6.Cu" "In11.Cu" "In13.Cu" "In15.Cu")
		(hatch none 0.5)
		(connect_pads
			(clearance 0)
		)
		(min_thickness 0.25)
		(keepout
			(tracks not_allowed)
			(vias allowed)
			(pads allowed)
			(copperpour not_allowed)
			(footprints allowed)
		)
		(placement
			(enabled no)
			(sheetname "")
		)
		(fill yes
			(thermal_gap 0.5)
			(thermal_bridge_width 0.5)
			(island_removal_mode 0)
		)
		(polygon
			(pts
				(arc
					(start 122.729752 -289.47618)
					(mid 122.099832 -289.47618)
					(end 122.729752 -289.47618)
				)
			)
		)
	)
	(zone
		(layers "B.Cu" "In6.Cu" "In11.Cu" "In13.Cu" "In15.Cu")
		(hatch none 0.5)
		(connect_pads
			(clearance 0)
		)
		(min_thickness 0.25)
		(keepout
			(tracks not_allowed)
			(vias allowed)
			(pads allowed)
			(copperpour not_allowed)
			(footprints allowed)
		)
		(placement
			(enabled no)
			(sheetname "")
		)
		(fill yes
			(thermal_gap 0.5)
			(thermal_bridge_width 0.5)
			(island_removal_mode 0)
		)
		(polygon
			(pts
				(arc
					(start 37.129974 -225.385376)
					(mid 36.461954 -225.385376)
					(end 37.129974 -225.385376)
				)
			)
		)
	)
	(zone
		(layers "B.Cu" "In6.Cu" "In11.Cu" "In13.Cu" "In15.Cu")
		(hatch none 0.5)
		(connect_pads
			(clearance 0)
		)
		(min_thickness 0.25)
		(keepout
			(tracks not_allowed)
			(vias allowed)
			(pads allowed)
			(copperpour not_allowed)
			(footprints allowed)
		)
		(placement
			(enabled no)
			(sheetname "")
		)
		(fill yes
			(thermal_gap 0.5)
			(thermal_bridge_width 0.5)
			(island_removal_mode 0)
		)
		(polygon
			(pts
				(arc
					(start 133.069838 -291.096192)
					(mid 132.439918 -291.096192)
					(end 133.069838 -291.096192)
				)
			)
		)
	)
	(zone
		(layers "B.Cu" "In6.Cu" "In11.Cu" "In13.Cu" "In15.Cu")
		(hatch none 0.5)
		(connect_pads
			(clearance 0)
		)
		(min_thickness 0.25)
		(keepout
			(tracks not_allowed)
			(vias allowed)
			(pads allowed)
			(copperpour not_allowed)
			(footprints allowed)
		)
		(placement
			(enabled no)
			(sheetname "")
		)
		(fill yes
			(thermal_gap 0.5)
			(thermal_bridge_width 0.5)
			(island_removal_mode 0)
		)
		(polygon
			(pts
				(arc
					(start 439.434224 -212.635084)
					(mid 438.766204 -212.635084)
					(end 439.434224 -212.635084)
				)
			)
		)
	)
	(zone
		(layers "B.Cu" "In6.Cu" "In11.Cu" "In13.Cu" "In15.Cu")
		(hatch none 0.5)
		(connect_pads
			(clearance 0)
		)
		(min_thickness 0.25)
		(keepout
			(tracks not_allowed)
			(vias allowed)
			(pads allowed)
			(copperpour not_allowed)
			(footprints allowed)
		)
		(placement
			(enabled no)
			(sheetname "")
		)
		(fill yes
			(thermal_gap 0.5)
			(thermal_bridge_width 0.5)
			(island_removal_mode 0)
		)
		(polygon
			(pts
				(arc
					(start 435.334156 -220.285056)
					(mid 434.666136 -220.285056)
					(end 435.334156 -220.285056)
				)
			)
		)
	)
	(zone
		(layers "B.Cu" "In6.Cu" "In11.Cu" "In13.Cu" "In15.Cu")
		(hatch none 0.5)
		(connect_pads
			(clearance 0)
		)
		(min_thickness 0.25)
		(keepout
			(tracks not_allowed)
			(vias allowed)
			(pads allowed)
			(copperpour not_allowed)
			(footprints allowed)
		)
		(placement
			(enabled no)
			(sheetname "")
		)
		(fill yes
			(thermal_gap 0.5)
			(thermal_bridge_width 0.5)
			(island_removal_mode 0)
		)
		(polygon
			(pts
				(arc
					(start 98.936048 -236.384338)
					(mid 98.306128 -236.384338)
					(end 98.936048 -236.384338)
				)
			)
		)
	)
	(zone
		(layers "B.Cu" "In6.Cu" "In11.Cu" "In13.Cu" "In15.Cu")
		(hatch none 0.5)
		(connect_pads
			(clearance 0)
		)
		(min_thickness 0.25)
		(keepout
			(tracks not_allowed)
			(vias allowed)
			(pads allowed)
			(copperpour not_allowed)
			(footprints allowed)
		)
		(placement
			(enabled no)
			(sheetname "")
		)
		(fill yes
			(thermal_gap 0.5)
			(thermal_bridge_width 0.5)
			(island_removal_mode 0)
		)
		(polygon
			(pts
				(arc
					(start 381.009906 -270.036036)
					(mid 380.379986 -270.036036)
					(end 381.009906 -270.036036)
				)
			)
		)
	)
	(zone
		(layers "B.Cu" "In6.Cu" "In11.Cu" "In13.Cu" "In15.Cu")
		(hatch none 0.5)
		(connect_pads
			(clearance 0)
		)
		(min_thickness 0.25)
		(keepout
			(tracks not_allowed)
			(vias allowed)
			(pads allowed)
			(copperpour not_allowed)
			(footprints allowed)
		)
		(placement
			(enabled no)
			(sheetname "")
		)
		(fill yes
			(thermal_gap 0.5)
			(thermal_bridge_width 0.5)
			(island_removal_mode 0)
		)
		(polygon
			(pts
				(arc
					(start 83.547712 -371.49913)
					(mid 82.879692 -371.49913)
					(end 83.547712 -371.49913)
				)
			)
		)
	)
	(zone
		(layers "B.Cu" "In6.Cu" "In11.Cu" "In13.Cu" "In15.Cu")
		(hatch none 0.5)
		(connect_pads
			(clearance 0)
		)
		(min_thickness 0.25)
		(keepout
			(tracks not_allowed)
			(vias allowed)
			(pads allowed)
			(copperpour not_allowed)
			(footprints allowed)
		)
		(placement
			(enabled no)
			(sheetname "")
		)
		(fill yes
			(thermal_gap 0.5)
			(thermal_bridge_width 0.5)
			(island_removal_mode 0)
		)
		(polygon
			(pts
				(arc
					(start 132.129784 -274.896326)
					(mid 131.499864 -274.896326)
					(end 132.129784 -274.896326)
				)
			)
		)
	)
	(zone
		(layers "B.Cu" "In6.Cu" "In11.Cu" "In13.Cu" "In15.Cu")
		(hatch none 0.5)
		(connect_pads
			(clearance 0)
		)
		(min_thickness 0.25)
		(keepout
			(tracks not_allowed)
			(vias allowed)
			(pads allowed)
			(copperpour not_allowed)
			(footprints allowed)
		)
		(placement
			(enabled no)
			(sheetname "")
		)
		(fill yes
			(thermal_gap 0.5)
			(thermal_bridge_width 0.5)
			(island_removal_mode 0)
		)
		(polygon
			(pts
				(arc
					(start 33.029906 -284.035246)
					(mid 32.361886 -284.035246)
					(end 33.029906 -284.035246)
				)
			)
		)
	)
	(zone
		(layers "B.Cu" "In6.Cu" "In11.Cu" "In13.Cu" "In15.Cu")
		(hatch none 0.5)
		(connect_pads
			(clearance 0)
		)
		(min_thickness 0.25)
		(keepout
			(tracks not_allowed)
			(vias allowed)
			(pads allowed)
			(copperpour not_allowed)
			(footprints allowed)
		)
		(placement
			(enabled no)
			(sheetname "")
		)
		(fill yes
			(thermal_gap 0.5)
			(thermal_bridge_width 0.5)
			(island_removal_mode 0)
		)
		(polygon
			(pts
				(arc
					(start 115.679728 -288.666174)
					(mid 115.049808 -288.666174)
					(end 115.679728 -288.666174)
				)
			)
		)
	)
	(zone
		(layers "B.Cu" "In6.Cu" "In11.Cu" "In13.Cu" "In15.Cu")
		(hatch none 0.5)
		(connect_pads
			(clearance 0)
		)
		(min_thickness 0.25)
		(keepout
			(tracks not_allowed)
			(vias allowed)
			(pads allowed)
			(copperpour not_allowed)
			(footprints allowed)
		)
		(placement
			(enabled no)
			(sheetname "")
		)
		(fill yes
			(thermal_gap 0.5)
			(thermal_bridge_width 0.5)
			(island_removal_mode 0)
		)
		(polygon
			(pts
				(arc
					(start 133.069838 -281.376374)
					(mid 132.439918 -281.376374)
					(end 133.069838 -281.376374)
				)
			)
		)
	)
	(zone
		(layers "B.Cu" "In6.Cu" "In11.Cu" "In13.Cu" "In15.Cu")
		(hatch none 0.5)
		(connect_pads
			(clearance 0)
		)
		(min_thickness 0.25)
		(keepout
			(tracks not_allowed)
			(vias allowed)
			(pads allowed)
			(copperpour not_allowed)
			(footprints allowed)
		)
		(placement
			(enabled no)
			(sheetname "")
		)
		(fill yes
			(thermal_gap 0.5)
			(thermal_bridge_width 0.5)
			(island_removal_mode 0)
		)
		(polygon
			(pts
				(arc
					(start 349.995998 -289.475926)
					(mid 349.366078 -289.475926)
					(end 349.995998 -289.475926)
				)
			)
		)
	)
	(zone
		(layers "B.Cu" "In6.Cu" "In11.Cu" "In13.Cu" "In15.Cu")
		(hatch none 0.5)
		(connect_pads
			(clearance 0)
		)
		(min_thickness 0.25)
		(keepout
			(tracks not_allowed)
			(vias allowed)
			(pads allowed)
			(copperpour not_allowed)
			(footprints allowed)
		)
		(placement
			(enabled no)
			(sheetname "")
		)
		(fill yes
			(thermal_gap 0.5)
			(thermal_bridge_width 0.5)
			(island_removal_mode 0)
		)
		(polygon
			(pts
				(arc
					(start 367.849658 -289.475926)
					(mid 367.219738 -289.475926)
					(end 367.849658 -289.475926)
				)
			)
		)
	)
	(zone
		(layers "B.Cu" "In6.Cu" "In11.Cu" "In13.Cu" "In15.Cu")
		(hatch none 0.5)
		(connect_pads
			(clearance 0)
		)
		(min_thickness 0.25)
		(keepout
			(tracks not_allowed)
			(vias allowed)
			(pads allowed)
			(copperpour not_allowed)
			(footprints allowed)
		)
		(placement
			(enabled no)
			(sheetname "")
		)
		(fill yes
			(thermal_gap 0.5)
			(thermal_bridge_width 0.5)
			(island_removal_mode 0)
		)
		(polygon
			(pts
				(arc
					(start 133.239764 -233.95432)
					(mid 132.609844 -233.95432)
					(end 133.239764 -233.95432)
				)
			)
		)
	)
	(zone
		(layers "B.Cu" "In6.Cu" "In11.Cu" "In13.Cu" "In15.Cu")
		(hatch none 0.5)
		(connect_pads
			(clearance 0)
		)
		(min_thickness 0.25)
		(keepout
			(tracks not_allowed)
			(vias allowed)
			(pads allowed)
			(copperpour not_allowed)
			(footprints allowed)
		)
		(placement
			(enabled no)
			(sheetname "")
		)
		(fill yes
			(thermal_gap 0.5)
			(thermal_bridge_width 0.5)
			(island_removal_mode 0)
		)
		(polygon
			(pts
				(arc
					(start 131.82981 -246.10441)
					(mid 131.19989 -246.10441)
					(end 131.82981 -246.10441)
				)
			)
		)
	)
	(zone
		(layers "B.Cu" "In6.Cu" "In11.Cu" "In13.Cu" "In15.Cu")
		(hatch none 0.5)
		(connect_pads
			(clearance 0)
		)
		(min_thickness 0.25)
		(keepout
			(tracks not_allowed)
			(vias allowed)
			(pads allowed)
			(copperpour not_allowed)
			(footprints allowed)
		)
		(placement
			(enabled no)
			(sheetname "")
		)
		(fill yes
			(thermal_gap 0.5)
			(thermal_bridge_width 0.5)
			(island_removal_mode 0)
		)
		(polygon
			(pts
				(arc
					(start 315.305948 -397.849344)
					(mid 314.676028 -397.849344)
					(end 315.305948 -397.849344)
				)
			)
		)
	)
	(zone
		(layers "B.Cu" "In6.Cu" "In11.Cu" "In13.Cu" "In15.Cu")
		(hatch none 0.5)
		(connect_pads
			(clearance 0)
		)
		(min_thickness 0.25)
		(keepout
			(tracks not_allowed)
			(vias allowed)
			(pads allowed)
			(copperpour not_allowed)
			(footprints allowed)
		)
		(placement
			(enabled no)
			(sheetname "")
		)
		(fill yes
			(thermal_gap 0.5)
			(thermal_bridge_width 0.5)
			(island_removal_mode 0)
		)
		(polygon
			(pts
				(arc
					(start 339.186012 -269.22603)
					(mid 338.556092 -269.22603)
					(end 339.186012 -269.22603)
				)
			)
		)
	)
	(zone
		(layers "B.Cu" "In6.Cu" "In11.Cu" "In13.Cu" "In15.Cu")
		(hatch none 0.5)
		(connect_pads
			(clearance 0)
		)
		(min_thickness 0.25)
		(keepout
			(tracks not_allowed)
			(vias allowed)
			(pads allowed)
			(copperpour not_allowed)
			(footprints allowed)
		)
		(placement
			(enabled no)
			(sheetname "")
		)
		(fill yes
			(thermal_gap 0.5)
			(thermal_bridge_width 0.5)
			(island_removal_mode 0)
		)
		(polygon
			(pts
				(arc
					(start 339.656166 -270.036036)
					(mid 339.026246 -270.036036)
					(end 339.656166 -270.036036)
				)
			)
		)
	)
	(zone
		(layers "B.Cu" "In6.Cu" "In11.Cu" "In13.Cu" "In15.Cu")
		(hatch none 0.5)
		(connect_pads
			(clearance 0)
		)
		(min_thickness 0.25)
		(keepout
			(tracks not_allowed)
			(vias allowed)
			(pads allowed)
			(copperpour not_allowed)
			(footprints allowed)
		)
		(placement
			(enabled no)
			(sheetname "")
		)
		(fill yes
			(thermal_gap 0.5)
			(thermal_bridge_width 0.5)
			(island_removal_mode 0)
		)
		(polygon
			(pts
				(arc
					(start 339.355938 -229.904036)
					(mid 338.726018 -229.904036)
					(end 339.355938 -229.904036)
				)
			)
		)
	)
	(zone
		(layers "B.Cu" "In6.Cu" "In11.Cu" "In13.Cu" "In15.Cu")
		(hatch none 0.5)
		(connect_pads
			(clearance 0)
		)
		(min_thickness 0.25)
		(keepout
			(tracks not_allowed)
			(vias allowed)
			(pads allowed)
			(copperpour not_allowed)
			(footprints allowed)
		)
		(placement
			(enabled no)
			(sheetname "")
		)
		(fill yes
			(thermal_gap 0.5)
			(thermal_bridge_width 0.5)
			(island_removal_mode 0)
		)
		(polygon
			(pts
				(arc
					(start 150.533862 -389.467344)
					(mid 149.903942 -389.467344)
					(end 150.533862 -389.467344)
				)
			)
		)
	)
	(zone
		(layers "B.Cu" "In6.Cu" "In11.Cu" "In13.Cu" "In15.Cu")
		(hatch none 0.5)
		(connect_pads
			(clearance 0)
		)
		(min_thickness 0.25)
		(keepout
			(tracks not_allowed)
			(vias allowed)
			(pads allowed)
			(copperpour not_allowed)
			(footprints allowed)
		)
		(placement
			(enabled no)
			(sheetname "")
		)
		(fill yes
			(thermal_gap 0.5)
			(thermal_bridge_width 0.5)
			(island_removal_mode 0)
		)
		(polygon
			(pts
				(arc
					(start 395.734032 -412.84652)
					(mid 395.066012 -412.84652)
					(end 395.734032 -412.84652)
				)
			)
		)
	)
	(zone
		(layers "B.Cu" "In6.Cu" "In11.Cu" "In13.Cu" "In15.Cu")
		(hatch none 0.5)
		(connect_pads
			(clearance 0)
		)
		(min_thickness 0.25)
		(keepout
			(tracks not_allowed)
			(vias allowed)
			(pads allowed)
			(copperpour not_allowed)
			(footprints allowed)
		)
		(placement
			(enabled no)
			(sheetname "")
		)
		(fill yes
			(thermal_gap 0.5)
			(thermal_bridge_width 0.5)
			(island_removal_mode 0)
		)
		(polygon
			(pts
				(arc
					(start 37.129974 -252.58522)
					(mid 36.461954 -252.58522)
					(end 37.129974 -252.58522)
				)
			)
		)
	)
	(zone
		(layers "B.Cu" "In6.Cu" "In11.Cu" "In13.Cu" "In15.Cu")
		(hatch none 0.5)
		(connect_pads
			(clearance 0)
		)
		(min_thickness 0.25)
		(keepout
			(tracks not_allowed)
			(vias allowed)
			(pads allowed)
			(copperpour not_allowed)
			(footprints allowed)
		)
		(placement
			(enabled no)
			(sheetname "")
		)
		(fill yes
			(thermal_gap 0.5)
			(thermal_bridge_width 0.5)
			(island_removal_mode 0)
		)
		(polygon
			(pts
				(arc
					(start 148.13407 -389.467344)
					(mid 147.50415 -389.467344)
					(end 148.13407 -389.467344)
				)
			)
		)
	)
	(zone
		(layers "B.Cu" "In6.Cu" "In11.Cu" "In13.Cu" "In15.Cu")
		(hatch none 0.5)
		(connect_pads
			(clearance 0)
		)
		(min_thickness 0.25)
		(keepout
			(tracks not_allowed)
			(vias allowed)
			(pads allowed)
			(copperpour not_allowed)
			(footprints allowed)
		)
		(placement
			(enabled no)
			(sheetname "")
		)
		(fill yes
			(thermal_gap 0.5)
			(thermal_bridge_width 0.5)
			(island_removal_mode 0)
		)
		(polygon
			(pts
				(arc
					(start 77.578712 -369.03533)
					(mid 76.910692 -369.03533)
					(end 77.578712 -369.03533)
				)
			)
		)
	)
	(zone
		(layers "B.Cu" "In6.Cu" "In11.Cu" "In13.Cu" "In15.Cu")
		(hatch none 0.5)
		(connect_pads
			(clearance 0)
		)
		(min_thickness 0.25)
		(keepout
			(tracks not_allowed)
			(vias allowed)
			(pads allowed)
			(copperpour not_allowed)
			(footprints allowed)
		)
		(placement
			(enabled no)
			(sheetname "")
		)
		(fill yes
			(thermal_gap 0.5)
			(thermal_bridge_width 0.5)
			(island_removal_mode 0)
		)
		(polygon
			(pts
				(arc
					(start 347.17609 -289.475926)
					(mid 346.54617 -289.475926)
					(end 347.17609 -289.475926)
				)
			)
		)
	)
	(zone
		(layers "B.Cu" "In6.Cu" "In11.Cu" "In13.Cu" "In15.Cu")
		(hatch none 0.5)
		(connect_pads
			(clearance 0)
		)
		(min_thickness 0.25)
		(keepout
			(tracks not_allowed)
			(vias allowed)
			(pads allowed)
			(copperpour not_allowed)
			(footprints allowed)
		)
		(placement
			(enabled no)
			(sheetname "")
		)
		(fill yes
			(thermal_gap 0.5)
			(thermal_bridge_width 0.5)
			(island_removal_mode 0)
		)
		(polygon
			(pts
				(arc
					(start 126.489714 -291.096192)
					(mid 125.859794 -291.096192)
					(end 126.489714 -291.096192)
				)
			)
		)
	)
	(zone
		(layers "B.Cu" "In6.Cu" "In11.Cu" "In13.Cu" "In15.Cu")
		(hatch none 0.5)
		(connect_pads
			(clearance 0)
		)
		(min_thickness 0.25)
		(keepout
			(tracks not_allowed)
			(vias allowed)
			(pads allowed)
			(copperpour not_allowed)
			(footprints allowed)
		)
		(placement
			(enabled no)
			(sheetname "")
		)
		(fill yes
			(thermal_gap 0.5)
			(thermal_bridge_width 0.5)
			(island_removal_mode 0)
		)
		(polygon
			(pts
				(arc
					(start 285.070042 -228.785166)
					(mid 284.402022 -228.785166)
					(end 285.070042 -228.785166)
				)
			)
		)
	)
	(zone
		(layers "B.Cu" "In6.Cu" "In11.Cu" "In13.Cu" "In15.Cu")
		(hatch none 0.5)
		(connect_pads
			(clearance 0)
		)
		(min_thickness 0.25)
		(keepout
			(tracks not_allowed)
			(vias allowed)
			(pads allowed)
			(copperpour not_allowed)
			(footprints allowed)
		)
		(placement
			(enabled no)
			(sheetname "")
		)
		(fill yes
			(thermal_gap 0.5)
			(thermal_bridge_width 0.5)
			(island_removal_mode 0)
		)
		(polygon
			(pts
				(arc
					(start 340.595966 -273.27606)
					(mid 339.966046 -273.27606)
					(end 340.595966 -273.27606)
				)
			)
		)
	)
	(zone
		(layers "B.Cu" "In6.Cu" "In11.Cu" "In13.Cu" "In15.Cu")
		(hatch none 0.5)
		(connect_pads
			(clearance 0)
		)
		(min_thickness 0.25)
		(keepout
			(tracks not_allowed)
			(vias allowed)
			(pads allowed)
			(copperpour not_allowed)
			(footprints allowed)
		)
		(placement
			(enabled no)
			(sheetname "")
		)
		(fill yes
			(thermal_gap 0.5)
			(thermal_bridge_width 0.5)
			(island_removal_mode 0)
		)
		(polygon
			(pts
				(arc
					(start 411.050232 -412.84652)
					(mid 410.382212 -412.84652)
					(end 411.050232 -412.84652)
				)
			)
		)
	)
	(zone
		(layers "B.Cu" "In6.Cu" "In11.Cu" "In13.Cu" "In15.Cu")
		(hatch none 0.5)
		(connect_pads
			(clearance 0)
		)
		(min_thickness 0.25)
		(keepout
			(tracks not_allowed)
			(vias allowed)
			(pads allowed)
			(copperpour not_allowed)
			(footprints allowed)
		)
		(placement
			(enabled no)
			(sheetname "")
		)
		(fill yes
			(thermal_gap 0.5)
			(thermal_bridge_width 0.5)
			(island_removal_mode 0)
		)
		(polygon
			(pts
				(arc
					(start 339.186012 -262.745982)
					(mid 338.556092 -262.745982)
					(end 339.186012 -262.745982)
				)
			)
		)
	)
	(zone
		(layers "B.Cu" "In6.Cu" "In11.Cu" "In13.Cu" "In15.Cu")
		(hatch none 0.5)
		(connect_pads
			(clearance 0)
		)
		(min_thickness 0.25)
		(keepout
			(tracks not_allowed)
			(vias allowed)
			(pads allowed)
			(copperpour not_allowed)
			(footprints allowed)
		)
		(placement
			(enabled no)
			(sheetname "")
		)
		(fill yes
			(thermal_gap 0.5)
			(thermal_bridge_width 0.5)
			(island_removal_mode 0)
		)
		(polygon
			(pts
				(arc
					(start 379.769878 -241.24412)
					(mid 379.139958 -241.24412)
					(end 379.769878 -241.24412)
				)
			)
		)
	)
	(zone
		(layers "B.Cu" "In6.Cu" "In11.Cu" "In13.Cu" "In15.Cu")
		(hatch none 0.5)
		(connect_pads
			(clearance 0)
		)
		(min_thickness 0.25)
		(keepout
			(tracks not_allowed)
			(vias allowed)
			(pads allowed)
			(copperpour not_allowed)
			(footprints allowed)
		)
		(placement
			(enabled no)
			(sheetname "")
		)
		(fill yes
			(thermal_gap 0.5)
			(thermal_bridge_width 0.5)
			(island_removal_mode 0)
		)
		(polygon
			(pts
				(arc
					(start 131.82981 -228.284532)
					(mid 131.19989 -228.284532)
					(end 131.82981 -228.284532)
				)
			)
		)
	)
	(zone
		(layers "B.Cu" "In6.Cu" "In11.Cu" "In13.Cu" "In15.Cu")
		(hatch none 0.5)
		(connect_pads
			(clearance 0)
		)
		(min_thickness 0.25)
		(keepout
			(tracks not_allowed)
			(vias allowed)
			(pads allowed)
			(copperpour not_allowed)
			(footprints allowed)
		)
		(placement
			(enabled no)
			(sheetname "")
		)
		(fill yes
			(thermal_gap 0.5)
			(thermal_bridge_width 0.5)
			(island_removal_mode 0)
		)
		(polygon
			(pts
				(arc
					(start 124.806202 -385.31038)
					(mid 124.176282 -385.31038)
					(end 124.806202 -385.31038)
				)
			)
		)
	)
	(zone
		(layers "B.Cu" "In6.Cu" "In11.Cu" "In13.Cu" "In15.Cu")
		(hatch none 0.5)
		(connect_pads
			(clearance 0)
		)
		(min_thickness 0.25)
		(keepout
			(tracks not_allowed)
			(vias allowed)
			(pads allowed)
			(copperpour not_allowed)
			(footprints allowed)
		)
		(placement
			(enabled no)
			(sheetname "")
		)
		(fill yes
			(thermal_gap 0.5)
			(thermal_bridge_width 0.5)
			(island_removal_mode 0)
		)
		(polygon
			(pts
				(arc
					(start 299.394626 -4.645406)
					(mid 298.726606 -4.645406)
					(end 299.394626 -4.645406)
				)
			)
		)
	)
	(zone
		(layers "B.Cu" "In6.Cu" "In11.Cu" "In13.Cu" "In15.Cu")
		(hatch none 0.5)
		(connect_pads
			(clearance 0)
		)
		(min_thickness 0.25)
		(keepout
			(tracks not_allowed)
			(vias allowed)
			(pads allowed)
			(copperpour not_allowed)
			(footprints allowed)
		)
		(placement
			(enabled no)
			(sheetname "")
		)
		(fill yes
			(thermal_gap 0.5)
			(thermal_bridge_width 0.5)
			(island_removal_mode 0)
		)
		(polygon
			(pts
				(arc
					(start 340.595966 -291.095938)
					(mid 339.966046 -291.095938)
					(end 340.595966 -291.095938)
				)
			)
		)
	)
	(zone
		(layers "B.Cu" "In6.Cu" "In11.Cu" "In13.Cu" "In15.Cu")
		(hatch none 0.5)
		(connect_pads
			(clearance 0)
		)
		(min_thickness 0.25)
		(keepout
			(tracks not_allowed)
			(vias allowed)
			(pads allowed)
			(copperpour not_allowed)
			(footprints allowed)
		)
		(placement
			(enabled no)
			(sheetname "")
		)
		(fill yes
			(thermal_gap 0.5)
			(thermal_bridge_width 0.5)
			(island_removal_mode 0)
		)
		(polygon
			(pts
				(arc
					(start 103.636064 -233.144314)
					(mid 103.006144 -233.144314)
					(end 103.636064 -233.144314)
				)
			)
		)
	)
	(zone
		(layers "B.Cu" "In6.Cu" "In11.Cu" "In13.Cu" "In15.Cu")
		(hatch none 0.5)
		(connect_pads
			(clearance 0)
		)
		(min_thickness 0.25)
		(keepout
			(tracks not_allowed)
			(vias allowed)
			(pads allowed)
			(copperpour not_allowed)
			(footprints allowed)
		)
		(placement
			(enabled no)
			(sheetname "")
		)
		(fill yes
			(thermal_gap 0.5)
			(thermal_bridge_width 0.5)
			(island_removal_mode 0)
		)
		(polygon
			(pts
				(arc
					(start 280.969974 -243.234972)
					(mid 280.301954 -243.234972)
					(end 280.969974 -243.234972)
				)
			)
		)
	)
	(zone
		(layers "B.Cu" "In6.Cu" "In11.Cu" "In13.Cu" "In15.Cu")
		(hatch none 0.5)
		(connect_pads
			(clearance 0)
		)
		(min_thickness 0.25)
		(keepout
			(tracks not_allowed)
			(vias allowed)
			(pads allowed)
			(copperpour not_allowed)
			(footprints allowed)
		)
		(placement
			(enabled no)
			(sheetname "")
		)
		(fill yes
			(thermal_gap 0.5)
			(thermal_bridge_width 0.5)
			(island_removal_mode 0)
		)
		(polygon
			(pts
				(arc
					(start 351.460054 -382.34493)
					(mid 350.792034 -382.34493)
					(end 351.460054 -382.34493)
				)
			)
		)
	)
	(zone
		(layers "B.Cu" "In6.Cu" "In11.Cu" "In13.Cu" "In15.Cu")
		(hatch none 0.5)
		(connect_pads
			(clearance 0)
		)
		(min_thickness 0.25)
		(keepout
			(tracks not_allowed)
			(vias allowed)
			(pads allowed)
			(copperpour not_allowed)
			(footprints allowed)
		)
		(placement
			(enabled no)
			(sheetname "")
		)
		(fill yes
			(thermal_gap 0.5)
			(thermal_bridge_width 0.5)
			(island_removal_mode 0)
		)
		(polygon
			(pts
				(arc
					(start 439.434224 -304.435002)
					(mid 438.766204 -304.435002)
					(end 439.434224 -304.435002)
				)
			)
		)
	)
	(zone
		(layers "B.Cu" "In6.Cu" "In11.Cu" "In13.Cu" "In15.Cu")
		(hatch none 0.5)
		(connect_pads
			(clearance 0)
		)
		(min_thickness 0.25)
		(keepout
			(tracks not_allowed)
			(vias allowed)
			(pads allowed)
			(copperpour not_allowed)
			(footprints allowed)
		)
		(placement
			(enabled no)
			(sheetname "")
		)
		(fill yes
			(thermal_gap 0.5)
			(thermal_bridge_width 0.5)
			(island_removal_mode 0)
		)
		(polygon
			(pts
				(arc
					(start 439.434224 -217.73515)
					(mid 438.766204 -217.73515)
					(end 439.434224 -217.73515)
				)
			)
		)
	)
	(zone
		(layers "B.Cu" "In6.Cu" "In11.Cu" "In13.Cu" "In15.Cu")
		(hatch none 0.5)
		(connect_pads
			(clearance 0)
		)
		(min_thickness 0.25)
		(keepout
			(tracks not_allowed)
			(vias allowed)
			(pads allowed)
			(copperpour not_allowed)
			(footprints allowed)
		)
		(placement
			(enabled no)
			(sheetname "")
		)
		(fill yes
			(thermal_gap 0.5)
			(thermal_bridge_width 0.5)
			(island_removal_mode 0)
		)
		(polygon
			(pts
				(arc
					(start 187.394088 -272.98523)
					(mid 186.726068 -272.98523)
					(end 187.394088 -272.98523)
				)
			)
		)
	)
	(zone
		(layers "B.Cu" "In6.Cu" "In11.Cu" "In13.Cu" "In15.Cu")
		(hatch none 0.5)
		(connect_pads
			(clearance 0)
		)
		(min_thickness 0.25)
		(keepout
			(tracks not_allowed)
			(vias allowed)
			(pads allowed)
			(copperpour not_allowed)
			(footprints allowed)
		)
		(placement
			(enabled no)
			(sheetname "")
		)
		(fill yes
			(thermal_gap 0.5)
			(thermal_bridge_width 0.5)
			(island_removal_mode 0)
		)
		(polygon
			(pts
				(arc
					(start 33.029906 -205.83525)
					(mid 32.361886 -205.83525)
					(end 33.029906 -205.83525)
				)
			)
		)
	)
	(zone
		(layers "B.Cu" "In6.Cu" "In11.Cu" "In13.Cu" "In15.Cu")
		(hatch none 0.5)
		(connect_pads
			(clearance 0)
		)
		(min_thickness 0.25)
		(keepout
			(tracks not_allowed)
			(vias allowed)
			(pads allowed)
			(copperpour not_allowed)
			(footprints allowed)
		)
		(placement
			(enabled no)
			(sheetname "")
		)
		(fill yes
			(thermal_gap 0.5)
			(thermal_bridge_width 0.5)
			(island_removal_mode 0)
		)
		(polygon
			(pts
				(arc
					(start 280.969974 -278.93518)
					(mid 280.301954 -278.93518)
					(end 280.969974 -278.93518)
				)
			)
		)
	)
	(zone
		(layers "B.Cu" "In6.Cu" "In11.Cu" "In13.Cu" "In15.Cu")
		(hatch none 0.5)
		(connect_pads
			(clearance 0)
		)
		(min_thickness 0.25)
		(keepout
			(tracks not_allowed)
			(vias allowed)
			(pads allowed)
			(copperpour not_allowed)
			(footprints allowed)
		)
		(placement
			(enabled no)
			(sheetname "")
		)
		(fill yes
			(thermal_gap 0.5)
			(thermal_bridge_width 0.5)
			(island_removal_mode 0)
		)
		(polygon
			(pts
				(arc
					(start 191.494156 -276.385274)
					(mid 190.826136 -276.385274)
					(end 191.494156 -276.385274)
				)
			)
		)
	)
	(zone
		(layers "B.Cu" "In6.Cu" "In11.Cu" "In13.Cu" "In15.Cu")
		(hatch none 0.5)
		(connect_pads
			(clearance 0)
		)
		(min_thickness 0.25)
		(keepout
			(tracks not_allowed)
			(vias allowed)
			(pads allowed)
			(copperpour not_allowed)
			(footprints allowed)
		)
		(placement
			(enabled no)
			(sheetname "")
		)
		(fill yes
			(thermal_gap 0.5)
			(thermal_bridge_width 0.5)
			(island_removal_mode 0)
		)
		(polygon
			(pts
				(arc
					(start 351.576132 -226.664266)
					(mid 350.946212 -226.664266)
					(end 351.576132 -226.664266)
				)
			)
		)
	)
	(zone
		(layers "B.Cu" "In6.Cu" "In11.Cu" "In13.Cu" "In15.Cu")
		(hatch none 0.5)
		(connect_pads
			(clearance 0)
		)
		(min_thickness 0.25)
		(keepout
			(tracks not_allowed)
			(vias allowed)
			(pads allowed)
			(copperpour not_allowed)
			(footprints allowed)
		)
		(placement
			(enabled no)
			(sheetname "")
		)
		(fill yes
			(thermal_gap 0.5)
			(thermal_bridge_width 0.5)
			(island_removal_mode 0)
		)
		(polygon
			(pts
				(arc
					(start 435.334156 -250.03506)
					(mid 434.666136 -250.03506)
					(end 435.334156 -250.03506)
				)
			)
		)
	)
	(zone
		(layers "B.Cu" "In6.Cu" "In11.Cu" "In13.Cu" "In15.Cu")
		(hatch none 0.5)
		(connect_pads
			(clearance 0)
		)
		(min_thickness 0.25)
		(keepout
			(tracks not_allowed)
			(vias allowed)
			(pads allowed)
			(copperpour not_allowed)
			(footprints allowed)
		)
		(placement
			(enabled no)
			(sheetname "")
		)
		(fill yes
			(thermal_gap 0.5)
			(thermal_bridge_width 0.5)
			(island_removal_mode 0)
		)
		(polygon
			(pts
				(arc
					(start 340.295992 -241.24412)
					(mid 339.666072 -241.24412)
					(end 340.295992 -241.24412)
				)
			)
		)
	)
	(zone
		(layers "B.Cu" "In6.Cu" "In11.Cu" "In13.Cu" "In15.Cu")
		(hatch none 0.5)
		(connect_pads
			(clearance 0)
		)
		(min_thickness 0.25)
		(keepout
			(tracks not_allowed)
			(vias allowed)
			(pads allowed)
			(copperpour not_allowed)
			(footprints allowed)
		)
		(placement
			(enabled no)
			(sheetname "")
		)
		(fill yes
			(thermal_gap 0.5)
			(thermal_bridge_width 0.5)
			(island_removal_mode 0)
		)
		(polygon
			(pts
				(arc
					(start 92.826078 -255.014476)
					(mid 92.196158 -255.014476)
					(end 92.826078 -255.014476)
				)
			)
		)
	)
	(zone
		(layers "B.Cu" "In6.Cu" "In11.Cu" "In13.Cu" "In15.Cu")
		(hatch none 0.5)
		(connect_pads
			(clearance 0)
		)
		(min_thickness 0.25)
		(keepout
			(tracks not_allowed)
			(vias allowed)
			(pads allowed)
			(copperpour not_allowed)
			(footprints allowed)
		)
		(placement
			(enabled no)
			(sheetname "")
		)
		(fill yes
			(thermal_gap 0.5)
			(thermal_bridge_width 0.5)
			(island_removal_mode 0)
		)
		(polygon
			(pts
				(arc
					(start 37.129974 -275.53539)
					(mid 36.461954 -275.53539)
					(end 37.129974 -275.53539)
				)
			)
		)
	)
	(zone
		(layers "B.Cu" "In6.Cu" "In11.Cu" "In13.Cu" "In15.Cu")
		(hatch none 0.5)
		(connect_pads
			(clearance 0)
		)
		(min_thickness 0.25)
		(keepout
			(tracks not_allowed)
			(vias allowed)
			(pads allowed)
			(copperpour not_allowed)
			(footprints allowed)
		)
		(placement
			(enabled no)
			(sheetname "")
		)
		(fill yes
			(thermal_gap 0.5)
			(thermal_bridge_width 0.5)
			(island_removal_mode 0)
		)
		(polygon
			(pts
				(arc
					(start 357.686102 -229.094284)
					(mid 357.056182 -229.094284)
					(end 357.686102 -229.094284)
				)
			)
		)
	)
	(zone
		(layers "B.Cu" "In6.Cu" "In11.Cu" "In13.Cu" "In15.Cu")
		(hatch none 0.5)
		(connect_pads
			(clearance 0)
		)
		(min_thickness 0.25)
		(keepout
			(tracks not_allowed)
			(vias allowed)
			(pads allowed)
			(copperpour not_allowed)
			(footprints allowed)
		)
		(placement
			(enabled no)
			(sheetname "")
		)
		(fill yes
			(thermal_gap 0.5)
			(thermal_bridge_width 0.5)
			(island_removal_mode 0)
		)
		(polygon
			(pts
				(arc
					(start 439.434224 -197.33514)
					(mid 438.766204 -197.33514)
					(end 439.434224 -197.33514)
				)
			)
		)
	)
	(zone
		(layers "B.Cu" "In6.Cu" "In11.Cu" "In13.Cu" "In15.Cu")
		(hatch none 0.5)
		(connect_pads
			(clearance 0)
		)
		(min_thickness 0.25)
		(keepout
			(tracks not_allowed)
			(vias allowed)
			(pads allowed)
			(copperpour not_allowed)
			(footprints allowed)
		)
		(placement
			(enabled no)
			(sheetname "")
		)
		(fill yes
			(thermal_gap 0.5)
			(thermal_bridge_width 0.5)
			(island_removal_mode 0)
		)
		(polygon
			(pts
				(arc
					(start 338.886038 -255.014222)
					(mid 338.256118 -255.014222)
					(end 338.886038 -255.014222)
				)
			)
		)
	)
	(zone
		(layers "B.Cu" "In6.Cu" "In11.Cu" "In13.Cu" "In15.Cu")
		(hatch none 0.5)
		(connect_pads
			(clearance 0)
		)
		(min_thickness 0.25)
		(keepout
			(tracks not_allowed)
			(vias allowed)
			(pads allowed)
			(copperpour not_allowed)
			(footprints allowed)
		)
		(placement
			(enabled no)
			(sheetname "")
		)
		(fill yes
			(thermal_gap 0.5)
			(thermal_bridge_width 0.5)
			(island_removal_mode 0)
		)
		(polygon
			(pts
				(arc
					(start 379.299724 -246.914162)
					(mid 378.669804 -246.914162)
					(end 379.299724 -246.914162)
				)
			)
		)
	)
	(zone
		(layers "B.Cu" "In6.Cu" "In11.Cu" "In13.Cu" "In15.Cu")
		(hatch none 0.5)
		(connect_pads
			(clearance 0)
		)
		(min_thickness 0.25)
		(keepout
			(tracks not_allowed)
			(vias allowed)
			(pads allowed)
			(copperpour not_allowed)
			(footprints allowed)
		)
		(placement
			(enabled no)
			(sheetname "")
		)
		(fill yes
			(thermal_gap 0.5)
			(thermal_bridge_width 0.5)
			(island_removal_mode 0)
		)
		(polygon
			(pts
				(arc
					(start 330.292202 -390.75106)
					(mid 329.624182 -390.75106)
					(end 330.292202 -390.75106)
				)
			)
		)
	)
	(zone
		(layers "B.Cu" "In6.Cu" "In11.Cu" "In13.Cu" "In15.Cu")
		(hatch none 0.5)
		(connect_pads
			(clearance 0)
		)
		(min_thickness 0.25)
		(keepout
			(tracks not_allowed)
			(vias allowed)
			(pads allowed)
			(copperpour not_allowed)
			(footprints allowed)
		)
		(placement
			(enabled no)
			(sheetname "")
		)
		(fill yes
			(thermal_gap 0.5)
			(thermal_bridge_width 0.5)
			(island_removal_mode 0)
		)
		(polygon
			(pts
				(arc
					(start 280.969974 -226.235006)
					(mid 280.301954 -226.235006)
					(end 280.969974 -226.235006)
				)
			)
		)
	)
	(zone
		(layers "B.Cu" "In6.Cu" "In11.Cu" "In13.Cu" "In15.Cu")
		(hatch none 0.5)
		(connect_pads
			(clearance 0)
		)
		(min_thickness 0.25)
		(keepout
			(tracks not_allowed)
			(vias allowed)
			(pads allowed)
			(copperpour not_allowed)
			(footprints allowed)
		)
		(placement
			(enabled no)
			(sheetname "")
		)
		(fill yes
			(thermal_gap 0.5)
			(thermal_bridge_width 0.5)
			(island_removal_mode 0)
		)
		(polygon
			(pts
				(arc
					(start 118.029736 -291.096192)
					(mid 117.399816 -291.096192)
					(end 118.029736 -291.096192)
				)
			)
		)
	)
	(zone
		(layers "B.Cu" "In6.Cu" "In11.Cu" "In13.Cu" "In15.Cu")
		(hatch none 0.5)
		(connect_pads
			(clearance 0)
		)
		(min_thickness 0.25)
		(keepout
			(tracks not_allowed)
			(vias allowed)
			(pads allowed)
			(copperpour not_allowed)
			(footprints allowed)
		)
		(placement
			(enabled no)
			(sheetname "")
		)
		(fill yes
			(thermal_gap 0.5)
			(thermal_bridge_width 0.5)
			(island_removal_mode 0)
		)
		(polygon
			(pts
				(arc
					(start 187.394088 -229.635304)
					(mid 186.726068 -229.635304)
					(end 187.394088 -229.635304)
				)
			)
		)
	)
	(zone
		(layers "B.Cu" "In6.Cu" "In11.Cu" "In13.Cu" "In15.Cu")
		(hatch none 0.5)
		(connect_pads
			(clearance 0)
		)
		(min_thickness 0.25)
		(keepout
			(tracks not_allowed)
			(vias allowed)
			(pads allowed)
			(copperpour not_allowed)
			(footprints allowed)
		)
		(placement
			(enabled no)
			(sheetname "")
		)
		(fill yes
			(thermal_gap 0.5)
			(thermal_bridge_width 0.5)
			(island_removal_mode 0)
		)
		(polygon
			(pts
				(arc
					(start 435.334156 -205.834996)
					(mid 434.666136 -205.834996)
					(end 435.334156 -205.834996)
				)
			)
		)
	)
	(zone
		(layers "B.Cu" "In6.Cu" "In11.Cu" "In13.Cu" "In15.Cu")
		(hatch none 0.5)
		(connect_pads
			(clearance 0)
		)
		(min_thickness 0.25)
		(keepout
			(tracks not_allowed)
			(vias allowed)
			(pads allowed)
			(copperpour not_allowed)
			(footprints allowed)
		)
		(placement
			(enabled no)
			(sheetname "")
		)
		(fill yes
			(thermal_gap 0.5)
			(thermal_bridge_width 0.5)
			(island_removal_mode 0)
		)
		(polygon
			(pts
				(arc
					(start 363.319822 -235.574078)
					(mid 362.689902 -235.574078)
					(end 363.319822 -235.574078)
				)
			)
		)
	)
	(zone
		(layers "B.Cu" "In6.Cu" "In11.Cu" "In13.Cu" "In15.Cu")
		(hatch none 0.5)
		(connect_pads
			(clearance 0)
		)
		(min_thickness 0.25)
		(keepout
			(tracks not_allowed)
			(vias allowed)
			(pads allowed)
			(copperpour not_allowed)
			(footprints allowed)
		)
		(placement
			(enabled no)
			(sheetname "")
		)
		(fill yes
			(thermal_gap 0.5)
			(thermal_bridge_width 0.5)
			(island_removal_mode 0)
		)
		(polygon
			(pts
				(arc
					(start 37.129974 -261.08533)
					(mid 36.461954 -261.08533)
					(end 37.129974 -261.08533)
				)
			)
		)
	)
	(zone
		(layers "B.Cu" "In6.Cu" "In11.Cu" "In13.Cu" "In15.Cu")
		(hatch none 0.5)
		(connect_pads
			(clearance 0)
		)
		(min_thickness 0.25)
		(keepout
			(tracks not_allowed)
			(vias allowed)
			(pads allowed)
			(copperpour not_allowed)
			(footprints allowed)
		)
		(placement
			(enabled no)
			(sheetname "")
		)
		(fill yes
			(thermal_gap 0.5)
			(thermal_bridge_width 0.5)
			(island_removal_mode 0)
		)
		(polygon
			(pts
				(arc
					(start 405.333962 -397.849344)
					(mid 404.704042 -397.849344)
					(end 405.333962 -397.849344)
				)
			)
		)
	)
	(zone
		(layers "B.Cu" "In6.Cu" "In11.Cu" "In13.Cu" "In15.Cu")
		(hatch none 0.5)
		(connect_pads
			(clearance 0)
		)
		(min_thickness 0.25)
		(keepout
			(tracks not_allowed)
			(vias allowed)
			(pads allowed)
			(copperpour not_allowed)
			(footprints allowed)
		)
		(placement
			(enabled no)
			(sheetname "")
		)
		(fill yes
			(thermal_gap 0.5)
			(thermal_bridge_width 0.5)
			(island_removal_mode 0)
		)
		(polygon
			(pts
				(arc
					(start 131.65963 -270.846296)
					(mid 131.02971 -270.846296)
					(end 131.65963 -270.846296)
				)
			)
		)
	)
	(zone
		(layers "B.Cu" "In6.Cu" "In11.Cu" "In13.Cu" "In15.Cu")
		(hatch none 0.5)
		(connect_pads
			(clearance 0)
		)
		(min_thickness 0.25)
		(keepout
			(tracks not_allowed)
			(vias allowed)
			(pads allowed)
			(copperpour not_allowed)
			(footprints allowed)
		)
		(placement
			(enabled no)
			(sheetname "")
		)
		(fill yes
			(thermal_gap 0.5)
			(thermal_bridge_width 0.5)
			(island_removal_mode 0)
		)
		(polygon
			(pts
				(arc
					(start 439.434224 -206.685134)
					(mid 438.766204 -206.685134)
					(end 439.434224 -206.685134)
				)
			)
		)
	)
	(zone
		(layers "B.Cu" "In6.Cu" "In11.Cu" "In13.Cu" "In15.Cu")
		(hatch none 0.5)
		(connect_pads
			(clearance 0)
		)
		(min_thickness 0.25)
		(keepout
			(tracks not_allowed)
			(vias allowed)
			(pads allowed)
			(copperpour not_allowed)
			(footprints allowed)
		)
		(placement
			(enabled no)
			(sheetname "")
		)
		(fill yes
			(thermal_gap 0.5)
			(thermal_bridge_width 0.5)
			(island_removal_mode 0)
		)
		(polygon
			(pts
				(arc
					(start 368.489738 -233.14406)
					(mid 367.859818 -233.14406)
					(end 368.489738 -233.14406)
				)
			)
		)
	)
	(zone
		(layers "B.Cu" "In6.Cu" "In11.Cu" "In13.Cu" "In15.Cu")
		(hatch none 0.5)
		(connect_pads
			(clearance 0)
		)
		(min_thickness 0.25)
		(keepout
			(tracks not_allowed)
			(vias allowed)
			(pads allowed)
			(copperpour not_allowed)
			(footprints allowed)
		)
		(placement
			(enabled no)
			(sheetname "")
		)
		(fill yes
			(thermal_gap 0.5)
			(thermal_bridge_width 0.5)
			(island_removal_mode 0)
		)
		(polygon
			(pts
				(arc
					(start 33.029906 -318.035432)
					(mid 32.361886 -318.035432)
					(end 33.029906 -318.035432)
				)
			)
		)
	)
	(zone
		(layers "B.Cu" "In6.Cu" "In11.Cu" "In13.Cu" "In15.Cu")
		(hatch none 0.5)
		(connect_pads
			(clearance 0)
		)
		(min_thickness 0.25)
		(keepout
			(tracks not_allowed)
			(vias allowed)
			(pads allowed)
			(copperpour not_allowed)
			(footprints allowed)
		)
		(placement
			(enabled no)
			(sheetname "")
		)
		(fill yes
			(thermal_gap 0.5)
			(thermal_bridge_width 0.5)
			(island_removal_mode 0)
		)
		(polygon
			(pts
				(arc
					(start 373.189754 -233.14406)
					(mid 372.559834 -233.14406)
					(end 373.189754 -233.14406)
				)
			)
		)
	)
	(zone
		(layers "B.Cu" "In6.Cu" "In11.Cu" "In13.Cu" "In15.Cu")
		(hatch none 0.5)
		(connect_pads
			(clearance 0)
		)
		(min_thickness 0.25)
		(keepout
			(tracks not_allowed)
			(vias allowed)
			(pads allowed)
			(copperpour not_allowed)
			(footprints allowed)
		)
		(placement
			(enabled no)
			(sheetname "")
		)
		(fill yes
			(thermal_gap 0.5)
			(thermal_bridge_width 0.5)
			(island_removal_mode 0)
		)
		(polygon
			(pts
				(arc
					(start 120.54967 -229.90429)
					(mid 119.91975 -229.90429)
					(end 120.54967 -229.90429)
				)
			)
		)
	)
	(zone
		(layers "B.Cu" "In6.Cu" "In11.Cu" "In13.Cu" "In15.Cu")
		(hatch none 0.5)
		(connect_pads
			(clearance 0)
		)
		(min_thickness 0.25)
		(keepout
			(tracks not_allowed)
			(vias allowed)
			(pads allowed)
			(copperpour not_allowed)
			(footprints allowed)
		)
		(placement
			(enabled no)
			(sheetname "")
		)
		(fill yes
			(thermal_gap 0.5)
			(thermal_bridge_width 0.5)
			(island_removal_mode 0)
		)
		(polygon
			(pts
				(arc
					(start 191.494156 -270.435324)
					(mid 190.826136 -270.435324)
					(end 191.494156 -270.435324)
				)
			)
		)
	)
	(zone
		(layers "B.Cu" "In6.Cu" "In11.Cu" "In13.Cu" "In15.Cu")
		(hatch none 0.5)
		(connect_pads
			(clearance 0)
		)
		(min_thickness 0.25)
		(keepout
			(tracks not_allowed)
			(vias allowed)
			(pads allowed)
			(copperpour not_allowed)
			(footprints allowed)
		)
		(placement
			(enabled no)
			(sheetname "")
		)
		(fill yes
			(thermal_gap 0.5)
			(thermal_bridge_width 0.5)
			(island_removal_mode 0)
		)
		(polygon
			(pts
				(arc
					(start 92.355924 -241.244374)
					(mid 91.726004 -241.244374)
					(end 92.355924 -241.244374)
				)
			)
		)
	)
	(zone
		(layers "B.Cu" "In6.Cu" "In11.Cu" "In13.Cu" "In15.Cu")
		(hatch none 0.5)
		(connect_pads
			(clearance 0)
		)
		(min_thickness 0.25)
		(keepout
			(tracks not_allowed)
			(vias allowed)
			(pads allowed)
			(copperpour not_allowed)
			(footprints allowed)
		)
		(placement
			(enabled no)
			(sheetname "")
		)
		(fill yes
			(thermal_gap 0.5)
			(thermal_bridge_width 0.5)
			(island_removal_mode 0)
		)
		(polygon
			(pts
				(arc
					(start 187.394088 -289.98545)
					(mid 186.726068 -289.98545)
					(end 187.394088 -289.98545)
				)
			)
		)
	)
	(zone
		(layers "B.Cu" "In6.Cu" "In11.Cu" "In13.Cu" "In15.Cu")
		(hatch none 0.5)
		(connect_pads
			(clearance 0)
		)
		(min_thickness 0.25)
		(keepout
			(tracks not_allowed)
			(vias allowed)
			(pads allowed)
			(copperpour not_allowed)
			(footprints allowed)
		)
		(placement
			(enabled no)
			(sheetname "")
		)
		(fill yes
			(thermal_gap 0.5)
			(thermal_bridge_width 0.5)
			(island_removal_mode 0)
		)
		(polygon
			(pts
				(arc
					(start 120.849644 -291.096192)
					(mid 120.219724 -291.096192)
					(end 120.849644 -291.096192)
				)
			)
		)
	)
	(zone
		(layers "B.Cu" "In6.Cu" "In11.Cu" "In13.Cu" "In15.Cu")
		(hatch none 0.5)
		(connect_pads
			(clearance 0)
		)
		(min_thickness 0.25)
		(keepout
			(tracks not_allowed)
			(vias allowed)
			(pads allowed)
			(copperpour not_allowed)
			(footprints allowed)
		)
		(placement
			(enabled no)
			(sheetname "")
		)
		(fill yes
			(thermal_gap 0.5)
			(thermal_bridge_width 0.5)
			(island_removal_mode 0)
		)
		(polygon
			(pts
				(arc
					(start 149.787356 -404.46452)
					(mid 149.119336 -404.46452)
					(end 149.787356 -404.46452)
				)
			)
		)
	)
	(zone
		(layers "B.Cu" "In6.Cu" "In11.Cu" "In13.Cu" "In15.Cu")
		(hatch none 0.5)
		(connect_pads
			(clearance 0)
		)
		(min_thickness 0.25)
		(keepout
			(tracks not_allowed)
			(vias allowed)
			(pads allowed)
			(copperpour not_allowed)
			(footprints allowed)
		)
		(placement
			(enabled no)
			(sheetname "")
		)
		(fill yes
			(thermal_gap 0.5)
			(thermal_bridge_width 0.5)
			(island_removal_mode 0)
		)
		(polygon
			(pts
				(arc
					(start 344.813636 -412.84652)
					(mid 344.145616 -412.84652)
					(end 344.813636 -412.84652)
				)
			)
		)
	)
	(zone
		(layers "B.Cu" "In6.Cu" "In11.Cu" "In13.Cu" "In15.Cu")
		(hatch none 0.5)
		(connect_pads
			(clearance 0)
		)
		(min_thickness 0.25)
		(keepout
			(tracks not_allowed)
			(vias allowed)
			(pads allowed)
			(copperpour not_allowed)
			(footprints allowed)
		)
		(placement
			(enabled no)
			(sheetname "")
		)
		(fill yes
			(thermal_gap 0.5)
			(thermal_bridge_width 0.5)
			(island_removal_mode 0)
		)
		(polygon
			(pts
				(arc
					(start 119.90959 -291.096192)
					(mid 119.27967 -291.096192)
					(end 119.90959 -291.096192)
				)
			)
		)
	)
	(zone
		(layers "B.Cu" "In6.Cu" "In11.Cu" "In13.Cu" "In15.Cu")
		(hatch none 0.5)
		(connect_pads
			(clearance 0)
		)
		(min_thickness 0.25)
		(keepout
			(tracks not_allowed)
			(vias allowed)
			(pads allowed)
			(copperpour not_allowed)
			(footprints allowed)
		)
		(placement
			(enabled no)
			(sheetname "")
		)
		(fill yes
			(thermal_gap 0.5)
			(thermal_bridge_width 0.5)
			(island_removal_mode 0)
		)
		(polygon
			(pts
				(arc
					(start 439.434224 -275.535136)
					(mid 438.766204 -275.535136)
					(end 439.434224 -275.535136)
				)
			)
		)
	)
	(zone
		(layers "B.Cu" "In6.Cu" "In11.Cu" "In13.Cu" "In15.Cu")
		(hatch none 0.5)
		(connect_pads
			(clearance 0)
		)
		(min_thickness 0.25)
		(keepout
			(tracks not_allowed)
			(vias allowed)
			(pads allowed)
			(copperpour not_allowed)
			(footprints allowed)
		)
		(placement
			(enabled no)
			(sheetname "")
		)
		(fill yes
			(thermal_gap 0.5)
			(thermal_bridge_width 0.5)
			(island_removal_mode 0)
		)
		(polygon
			(pts
				(arc
					(start 90.94597 -256.634488)
					(mid 90.31605 -256.634488)
					(end 90.94597 -256.634488)
				)
			)
		)
	)
	(zone
		(layers "B.Cu" "In6.Cu" "In11.Cu" "In13.Cu" "In15.Cu")
		(hatch none 0.5)
		(connect_pads
			(clearance 0)
		)
		(min_thickness 0.25)
		(keepout
			(tracks not_allowed)
			(vias allowed)
			(pads allowed)
			(copperpour not_allowed)
			(footprints allowed)
		)
		(placement
			(enabled no)
			(sheetname "")
		)
		(fill yes
			(thermal_gap 0.5)
			(thermal_bridge_width 0.5)
			(island_removal_mode 0)
		)
		(polygon
			(pts
				(arc
					(start 439.434224 -208.385156)
					(mid 438.766204 -208.385156)
					(end 439.434224 -208.385156)
				)
			)
		)
	)
	(zone
		(layers "B.Cu" "In6.Cu" "In11.Cu" "In13.Cu" "In15.Cu")
		(hatch none 0.5)
		(connect_pads
			(clearance 0)
		)
		(min_thickness 0.25)
		(keepout
			(tracks not_allowed)
			(vias allowed)
			(pads allowed)
			(copperpour not_allowed)
			(footprints allowed)
		)
		(placement
			(enabled no)
			(sheetname "")
		)
		(fill yes
			(thermal_gap 0.5)
			(thermal_bridge_width 0.5)
			(island_removal_mode 0)
		)
		(polygon
			(pts
				(arc
					(start 37.129974 -283.185362)
					(mid 36.461954 -283.185362)
					(end 37.129974 -283.185362)
				)
			)
		)
	)
	(zone
		(layers "B.Cu" "In6.Cu" "In11.Cu" "In13.Cu" "In15.Cu")
		(hatch none 0.5)
		(connect_pads
			(clearance 0)
		)
		(min_thickness 0.25)
		(keepout
			(tracks not_allowed)
			(vias allowed)
			(pads allowed)
			(copperpour not_allowed)
			(footprints allowed)
		)
		(placement
			(enabled no)
			(sheetname "")
		)
		(fill yes
			(thermal_gap 0.5)
			(thermal_bridge_width 0.5)
			(island_removal_mode 0)
		)
		(polygon
			(pts
				(arc
					(start 133.069838 -270.03629)
					(mid 132.439918 -270.03629)
					(end 133.069838 -270.03629)
				)
			)
		)
	)
	(zone
		(layers "B.Cu" "In6.Cu" "In11.Cu" "In13.Cu" "In15.Cu")
		(hatch none 0.5)
		(connect_pads
			(clearance 0)
		)
		(min_thickness 0.25)
		(keepout
			(tracks not_allowed)
			(vias allowed)
			(pads allowed)
			(copperpour not_allowed)
			(footprints allowed)
		)
		(placement
			(enabled no)
			(sheetname "")
		)
		(fill yes
			(thermal_gap 0.5)
			(thermal_bridge_width 0.5)
			(island_removal_mode 0)
		)
		(polygon
			(pts
				(arc
					(start 191.494156 -249.18543)
					(mid 190.826136 -249.18543)
					(end 191.494156 -249.18543)
				)
			)
		)
	)
	(zone
		(layers "B.Cu" "In6.Cu" "In11.Cu" "In13.Cu" "In15.Cu")
		(hatch none 0.5)
		(connect_pads
			(clearance 0)
		)
		(min_thickness 0.25)
		(keepout
			(tracks not_allowed)
			(vias allowed)
			(pads allowed)
			(copperpour not_allowed)
			(footprints allowed)
		)
		(placement
			(enabled no)
			(sheetname "")
		)
		(fill yes
			(thermal_gap 0.5)
			(thermal_bridge_width 0.5)
			(island_removal_mode 0)
		)
		(polygon
			(pts
				(arc
					(start 373.189754 -234.764072)
					(mid 372.559834 -234.764072)
					(end 373.189754 -234.764072)
				)
			)
		)
	)
	(zone
		(layers "B.Cu" "In6.Cu" "In11.Cu" "In13.Cu" "In15.Cu")
		(hatch none 0.5)
		(connect_pads
			(clearance 0)
		)
		(min_thickness 0.25)
		(keepout
			(tracks not_allowed)
			(vias allowed)
			(pads allowed)
			(copperpour not_allowed)
			(footprints allowed)
		)
		(placement
			(enabled no)
			(sheetname "")
		)
		(fill yes
			(thermal_gap 0.5)
			(thermal_bridge_width 0.5)
			(island_removal_mode 0)
		)
		(polygon
			(pts
				(arc
					(start 383.606294 -394.385292)
					(mid 382.976374 -394.385292)
					(end 383.606294 -394.385292)
				)
			)
		)
	)
	(zone
		(layers "B.Cu" "In6.Cu" "In11.Cu" "In13.Cu" "In15.Cu")
		(hatch none 0.5)
		(connect_pads
			(clearance 0)
		)
		(min_thickness 0.25)
		(keepout
			(tracks not_allowed)
			(vias allowed)
			(pads allowed)
			(copperpour not_allowed)
			(footprints allowed)
		)
		(placement
			(enabled no)
			(sheetname "")
		)
		(fill yes
			(thermal_gap 0.5)
			(thermal_bridge_width 0.5)
			(island_removal_mode 0)
		)
		(polygon
			(pts
				(arc
					(start 374.429782 -287.856168)
					(mid 373.799862 -287.856168)
					(end 374.429782 -287.856168)
				)
			)
		)
	)
	(zone
		(layers "B.Cu" "In6.Cu" "In11.Cu" "In13.Cu" "In15.Cu")
		(hatch none 0.5)
		(connect_pads
			(clearance 0)
		)
		(min_thickness 0.25)
		(keepout
			(tracks not_allowed)
			(vias allowed)
			(pads allowed)
			(copperpour not_allowed)
			(footprints allowed)
		)
		(placement
			(enabled no)
			(sheetname "")
		)
		(fill yes
			(thermal_gap 0.5)
			(thermal_bridge_width 0.5)
			(island_removal_mode 0)
		)
		(polygon
			(pts
				(arc
					(start 131.82981 -226.66452)
					(mid 131.19989 -226.66452)
					(end 131.82981 -226.66452)
				)
			)
		)
	)
	(zone
		(layers "B.Cu" "In6.Cu" "In11.Cu" "In13.Cu" "In15.Cu")
		(hatch none 0.5)
		(connect_pads
			(clearance 0)
		)
		(min_thickness 0.25)
		(keepout
			(tracks not_allowed)
			(vias allowed)
			(pads allowed)
			(copperpour not_allowed)
			(footprints allowed)
		)
		(placement
			(enabled no)
			(sheetname "")
		)
		(fill yes
			(thermal_gap 0.5)
			(thermal_bridge_width 0.5)
			(island_removal_mode 0)
		)
		(polygon
			(pts
				(arc
					(start 33.029906 -285.735268)
					(mid 32.361886 -285.735268)
					(end 33.029906 -285.735268)
				)
			)
		)
	)
	(zone
		(layers "B.Cu" "In6.Cu" "In11.Cu" "In13.Cu" "In15.Cu")
		(hatch none 0.5)
		(connect_pads
			(clearance 0)
		)
		(min_thickness 0.25)
		(keepout
			(tracks not_allowed)
			(vias allowed)
			(pads allowed)
			(copperpour not_allowed)
			(footprints allowed)
		)
		(placement
			(enabled no)
			(sheetname "")
		)
		(fill yes
			(thermal_gap 0.5)
			(thermal_bridge_width 0.5)
			(island_removal_mode 0)
		)
		(polygon
			(pts
				(arc
					(start 285.070042 -201.585068)
					(mid 284.402022 -201.585068)
					(end 285.070042 -201.585068)
				)
			)
		)
	)
	(zone
		(layers "B.Cu" "In6.Cu" "In11.Cu" "In13.Cu" "In15.Cu")
		(hatch none 0.5)
		(connect_pads
			(clearance 0)
		)
		(min_thickness 0.25)
		(keepout
			(tracks not_allowed)
			(vias allowed)
			(pads allowed)
			(copperpour not_allowed)
			(footprints allowed)
		)
		(placement
			(enabled no)
			(sheetname "")
		)
		(fill yes
			(thermal_gap 0.5)
			(thermal_bridge_width 0.5)
			(island_removal_mode 0)
		)
		(polygon
			(pts
				(arc
					(start 131.359656 -253.394464)
					(mid 130.729736 -253.394464)
					(end 131.359656 -253.394464)
				)
			)
		)
	)
	(zone
		(layers "B.Cu" "In6.Cu" "In11.Cu" "In13.Cu" "In15.Cu")
		(hatch none 0.5)
		(connect_pads
			(clearance 0)
		)
		(min_thickness 0.25)
		(keepout
			(tracks not_allowed)
			(vias allowed)
			(pads allowed)
			(copperpour not_allowed)
			(footprints allowed)
		)
		(placement
			(enabled no)
			(sheetname "")
		)
		(fill yes
			(thermal_gap 0.5)
			(thermal_bridge_width 0.5)
			(island_removal_mode 0)
		)
		(polygon
			(pts
				(arc
					(start 131.359656 -230.71455)
					(mid 130.729736 -230.71455)
					(end 131.359656 -230.71455)
				)
			)
		)
	)
	(zone
		(layers "B.Cu" "In6.Cu" "In11.Cu" "In13.Cu" "In15.Cu")
		(hatch none 0.5)
		(connect_pads
			(clearance 0)
		)
		(min_thickness 0.25)
		(keepout
			(tracks not_allowed)
			(vias allowed)
			(pads allowed)
			(copperpour not_allowed)
			(footprints allowed)
		)
		(placement
			(enabled no)
			(sheetname "")
		)
		(fill yes
			(thermal_gap 0.5)
			(thermal_bridge_width 0.5)
			(island_removal_mode 0)
		)
		(polygon
			(pts
				(arc
					(start 346.876116 -226.664266)
					(mid 346.246196 -226.664266)
					(end 346.876116 -226.664266)
				)
			)
		)
	)
	(zone
		(layers "B.Cu" "In6.Cu" "In11.Cu" "In13.Cu" "In15.Cu")
		(hatch none 0.5)
		(connect_pads
			(clearance 0)
		)
		(min_thickness 0.25)
		(keepout
			(tracks not_allowed)
			(vias allowed)
			(pads allowed)
			(copperpour not_allowed)
			(footprints allowed)
		)
		(placement
			(enabled no)
			(sheetname "")
		)
		(fill yes
			(thermal_gap 0.5)
			(thermal_bridge_width 0.5)
			(island_removal_mode 0)
		)
		(polygon
			(pts
				(arc
					(start 191.494156 -272.135346)
					(mid 190.826136 -272.135346)
					(end 191.494156 -272.135346)
				)
			)
		)
	)
	(zone
		(layers "B.Cu" "In6.Cu" "In11.Cu" "In13.Cu" "In15.Cu")
		(hatch none 0.5)
		(connect_pads
			(clearance 0)
		)
		(min_thickness 0.25)
		(keepout
			(tracks not_allowed)
			(vias allowed)
			(pads allowed)
			(copperpour not_allowed)
			(footprints allowed)
		)
		(placement
			(enabled no)
			(sheetname "")
		)
		(fill yes
			(thermal_gap 0.5)
			(thermal_bridge_width 0.5)
			(island_removal_mode 0)
		)
		(polygon
			(pts
				(arc
					(start 280.969974 -316.335156)
					(mid 280.301954 -316.335156)
					(end 280.969974 -316.335156)
				)
			)
		)
	)
	(zone
		(layers "B.Cu" "In6.Cu" "In11.Cu" "In13.Cu" "In15.Cu")
		(hatch none 0.5)
		(connect_pads
			(clearance 0)
		)
		(min_thickness 0.25)
		(keepout
			(tracks not_allowed)
			(vias allowed)
			(pads allowed)
			(copperpour not_allowed)
			(footprints allowed)
		)
		(placement
			(enabled no)
			(sheetname "")
		)
		(fill yes
			(thermal_gap 0.5)
			(thermal_bridge_width 0.5)
			(island_removal_mode 0)
		)
		(polygon
			(pts
				(arc
					(start 51.3334 -6.725158)
					(mid 50.66538 -6.725158)
					(end 51.3334 -6.725158)
				)
			)
		)
	)
	(zone
		(layers "B.Cu" "In6.Cu" "In11.Cu" "In13.Cu" "In15.Cu")
		(hatch none 0.5)
		(connect_pads
			(clearance 0)
		)
		(min_thickness 0.25)
		(keepout
			(tracks not_allowed)
			(vias allowed)
			(pads allowed)
			(copperpour not_allowed)
			(footprints allowed)
		)
		(placement
			(enabled no)
			(sheetname "")
		)
		(fill yes
			(thermal_gap 0.5)
			(thermal_bridge_width 0.5)
			(island_removal_mode 0)
		)
		(polygon
			(pts
				(arc
					(start 191.494156 -233.035348)
					(mid 190.826136 -233.035348)
					(end 191.494156 -233.035348)
				)
			)
		)
	)
	(zone
		(layers "B.Cu" "In6.Cu" "In11.Cu" "In13.Cu" "In15.Cu")
		(hatch none 0.5)
		(connect_pads
			(clearance 0)
		)
		(min_thickness 0.25)
		(keepout
			(tracks not_allowed)
			(vias allowed)
			(pads allowed)
			(copperpour not_allowed)
			(footprints allowed)
		)
		(placement
			(enabled no)
			(sheetname "")
		)
		(fill yes
			(thermal_gap 0.5)
			(thermal_bridge_width 0.5)
			(island_removal_mode 0)
		)
		(polygon
			(pts
				(arc
					(start 103.936038 -291.096192)
					(mid 103.306118 -291.096192)
					(end 103.936038 -291.096192)
				)
			)
		)
	)
	(zone
		(layers "B.Cu" "In6.Cu" "In11.Cu" "In13.Cu" "In15.Cu")
		(hatch none 0.5)
		(connect_pads
			(clearance 0)
		)
		(min_thickness 0.25)
		(keepout
			(tracks not_allowed)
			(vias allowed)
			(pads allowed)
			(copperpour not_allowed)
			(footprints allowed)
		)
		(placement
			(enabled no)
			(sheetname "")
		)
		(fill yes
			(thermal_gap 0.5)
			(thermal_bridge_width 0.5)
			(island_removal_mode 0)
		)
		(polygon
			(pts
				(arc
					(start 37.129974 -294.235378)
					(mid 36.461954 -294.235378)
					(end 37.129974 -294.235378)
				)
			)
		)
	)
	(zone
		(layers "B.Cu" "In6.Cu" "In11.Cu" "In13.Cu" "In15.Cu")
		(hatch none 0.5)
		(connect_pads
			(clearance 0)
		)
		(min_thickness 0.25)
		(keepout
			(tracks not_allowed)
			(vias allowed)
			(pads allowed)
			(copperpour not_allowed)
			(footprints allowed)
		)
		(placement
			(enabled no)
			(sheetname "")
		)
		(fill yes
			(thermal_gap 0.5)
			(thermal_bridge_width 0.5)
			(island_removal_mode 0)
		)
		(polygon
			(pts
				(arc
					(start 340.595966 -278.136096)
					(mid 339.966046 -278.136096)
					(end 340.595966 -278.136096)
				)
			)
		)
	)
	(zone
		(layers "B.Cu" "In6.Cu" "In11.Cu" "In13.Cu" "In15.Cu")
		(hatch none 0.5)
		(connect_pads
			(clearance 0)
		)
		(min_thickness 0.25)
		(keepout
			(tracks not_allowed)
			(vias allowed)
			(pads allowed)
			(copperpour not_allowed)
			(footprints allowed)
		)
		(placement
			(enabled no)
			(sheetname "")
		)
		(fill yes
			(thermal_gap 0.5)
			(thermal_bridge_width 0.5)
			(island_removal_mode 0)
		)
		(polygon
			(pts
				(arc
					(start 280.969974 -280.634948)
					(mid 280.301954 -280.634948)
					(end 280.969974 -280.634948)
				)
			)
		)
	)
	(zone
		(layers "B.Cu" "In6.Cu" "In11.Cu" "In13.Cu" "In15.Cu")
		(hatch none 0.5)
		(connect_pads
			(clearance 0)
		)
		(min_thickness 0.25)
		(keepout
			(tracks not_allowed)
			(vias allowed)
			(pads allowed)
			(copperpour not_allowed)
			(footprints allowed)
		)
		(placement
			(enabled no)
			(sheetname "")
		)
		(fill yes
			(thermal_gap 0.5)
			(thermal_bridge_width 0.5)
			(island_removal_mode 0)
		)
		(polygon
			(pts
				(arc
					(start 280.969974 -220.285056)
					(mid 280.301954 -220.285056)
					(end 280.969974 -220.285056)
				)
			)
		)
	)
	(zone
		(layers "B.Cu" "In6.Cu" "In11.Cu" "In13.Cu" "In15.Cu")
		(hatch none 0.5)
		(connect_pads
			(clearance 0)
		)
		(min_thickness 0.25)
		(keepout
			(tracks not_allowed)
			(vias allowed)
			(pads allowed)
			(copperpour not_allowed)
			(footprints allowed)
		)
		(placement
			(enabled no)
			(sheetname "")
		)
		(fill yes
			(thermal_gap 0.5)
			(thermal_bridge_width 0.5)
			(island_removal_mode 0)
		)
		(polygon
			(pts
				(arc
					(start 90.94597 -253.394464)
					(mid 90.31605 -253.394464)
					(end 90.94597 -253.394464)
				)
			)
		)
	)
	(zone
		(layers "B.Cu" "In6.Cu" "In11.Cu" "In13.Cu" "In15.Cu")
		(hatch none 0.5)
		(connect_pads
			(clearance 0)
		)
		(min_thickness 0.25)
		(keepout
			(tracks not_allowed)
			(vias allowed)
			(pads allowed)
			(copperpour not_allowed)
			(footprints allowed)
		)
		(placement
			(enabled no)
			(sheetname "")
		)
		(fill yes
			(thermal_gap 0.5)
			(thermal_bridge_width 0.5)
			(island_removal_mode 0)
		)
		(polygon
			(pts
				(arc
					(start 280.969974 -291.684964)
					(mid 280.301954 -291.684964)
					(end 280.969974 -291.684964)
				)
			)
		)
	)
	(zone
		(layers "B.Cu" "In6.Cu" "In11.Cu" "In13.Cu" "In15.Cu")
		(hatch none 0.5)
		(connect_pads
			(clearance 0)
		)
		(min_thickness 0.25)
		(keepout
			(tracks not_allowed)
			(vias allowed)
			(pads allowed)
			(copperpour not_allowed)
			(footprints allowed)
		)
		(placement
			(enabled no)
			(sheetname "")
		)
		(fill yes
			(thermal_gap 0.5)
			(thermal_bridge_width 0.5)
			(island_removal_mode 0)
		)
		(polygon
			(pts
				(arc
					(start 413.582358 -17.613122)
					(mid 412.914338 -17.613122)
					(end 413.582358 -17.613122)
				)
			)
		)
	)
	(zone
		(layers "B.Cu" "In6.Cu" "In11.Cu" "In13.Cu" "In15.Cu")
		(hatch none 0.5)
		(connect_pads
			(clearance 0)
		)
		(min_thickness 0.25)
		(keepout
			(tracks not_allowed)
			(vias allowed)
			(pads allowed)
			(copperpour not_allowed)
			(footprints allowed)
		)
		(placement
			(enabled no)
			(sheetname "")
		)
		(fill yes
			(thermal_gap 0.5)
			(thermal_bridge_width 0.5)
			(island_removal_mode 0)
		)
		(polygon
			(pts
				(arc
					(start 33.029906 -310.385206)
					(mid 32.361886 -310.385206)
					(end 33.029906 -310.385206)
				)
			)
		)
	)
	(zone
		(layers "B.Cu" "In6.Cu" "In11.Cu" "In13.Cu" "In15.Cu")
		(hatch none 0.5)
		(connect_pads
			(clearance 0)
		)
		(min_thickness 0.25)
		(keepout
			(tracks not_allowed)
			(vias allowed)
			(pads allowed)
			(copperpour not_allowed)
			(footprints allowed)
		)
		(placement
			(enabled no)
			(sheetname "")
		)
		(fill yes
			(thermal_gap 0.5)
			(thermal_bridge_width 0.5)
			(island_removal_mode 0)
		)
		(polygon
			(pts
				(arc
					(start 435.334156 -291.684964)
					(mid 434.666136 -291.684964)
					(end 435.334156 -291.684964)
				)
			)
		)
	)
	(zone
		(layers "B.Cu" "In6.Cu" "In11.Cu" "In13.Cu" "In15.Cu")
		(hatch none 0.5)
		(connect_pads
			(clearance 0)
		)
		(min_thickness 0.25)
		(keepout
			(tracks not_allowed)
			(vias allowed)
			(pads allowed)
			(copperpour not_allowed)
			(footprints allowed)
		)
		(placement
			(enabled no)
			(sheetname "")
		)
		(fill yes
			(thermal_gap 0.5)
			(thermal_bridge_width 0.5)
			(island_removal_mode 0)
		)
		(polygon
			(pts
				(arc
					(start 380.069852 -266.796012)
					(mid 379.439932 -266.796012)
					(end 380.069852 -266.796012)
				)
			)
		)
	)
	(zone
		(layers "B.Cu" "In6.Cu" "In11.Cu" "In13.Cu" "In15.Cu")
		(hatch none 0.5)
		(connect_pads
			(clearance 0)
		)
		(min_thickness 0.25)
		(keepout
			(tracks not_allowed)
			(vias allowed)
			(pads allowed)
			(copperpour not_allowed)
			(footprints allowed)
		)
		(placement
			(enabled no)
			(sheetname "")
		)
		(fill yes
			(thermal_gap 0.5)
			(thermal_bridge_width 0.5)
			(island_removal_mode 0)
		)
		(polygon
			(pts
				(arc
					(start 379.299724 -242.054126)
					(mid 378.669804 -242.054126)
					(end 379.299724 -242.054126)
				)
			)
		)
	)
	(zone
		(layers "B.Cu" "In6.Cu" "In11.Cu" "In13.Cu" "In15.Cu")
		(hatch none 0.5)
		(connect_pads
			(clearance 0)
		)
		(min_thickness 0.25)
		(keepout
			(tracks not_allowed)
			(vias allowed)
			(pads allowed)
			(copperpour not_allowed)
			(footprints allowed)
		)
		(placement
			(enabled no)
			(sheetname "")
		)
		(fill yes
			(thermal_gap 0.5)
			(thermal_bridge_width 0.5)
			(island_removal_mode 0)
		)
		(polygon
			(pts
				(arc
					(start 130.80619 -385.31038)
					(mid 130.17627 -385.31038)
					(end 130.80619 -385.31038)
				)
			)
		)
	)
	(zone
		(layers "B.Cu" "In6.Cu" "In11.Cu" "In13.Cu" "In15.Cu")
		(hatch none 0.5)
		(connect_pads
			(clearance 0)
		)
		(min_thickness 0.25)
		(keepout
			(tracks not_allowed)
			(vias allowed)
			(pads allowed)
			(copperpour not_allowed)
			(footprints allowed)
		)
		(placement
			(enabled no)
			(sheetname "")
		)
		(fill yes
			(thermal_gap 0.5)
			(thermal_bridge_width 0.5)
			(island_removal_mode 0)
		)
		(polygon
			(pts
				(arc
					(start 119.90959 -287.856422)
					(mid 119.27967 -287.856422)
					(end 119.90959 -287.856422)
				)
			)
		)
	)
	(zone
		(layers "B.Cu" "In6.Cu" "In11.Cu" "In13.Cu" "In15.Cu")
		(hatch none 0.5)
		(connect_pads
			(clearance 0)
		)
		(min_thickness 0.25)
		(keepout
			(tracks not_allowed)
			(vias allowed)
			(pads allowed)
			(copperpour not_allowed)
			(footprints allowed)
		)
		(placement
			(enabled no)
			(sheetname "")
		)
		(fill yes
			(thermal_gap 0.5)
			(thermal_bridge_width 0.5)
			(island_removal_mode 0)
		)
		(polygon
			(pts
				(arc
					(start 427.893226 -19.13636)
					(mid 427.225206 -19.13636)
					(end 427.893226 -19.13636)
				)
			)
		)
	)
	(zone
		(layers "B.Cu" "In6.Cu" "In11.Cu" "In13.Cu" "In15.Cu")
		(hatch none 0.5)
		(connect_pads
			(clearance 0)
		)
		(min_thickness 0.25)
		(keepout
			(tracks not_allowed)
			(vias allowed)
			(pads allowed)
			(copperpour not_allowed)
			(footprints allowed)
		)
		(placement
			(enabled no)
			(sheetname "")
		)
		(fill yes
			(thermal_gap 0.5)
			(thermal_bridge_width 0.5)
			(island_removal_mode 0)
		)
		(polygon
			(pts
				(arc
					(start 91.716098 -265.176254)
					(mid 91.086178 -265.176254)
					(end 91.716098 -265.176254)
				)
			)
		)
	)
	(zone
		(layers "B.Cu" "In6.Cu" "In11.Cu" "In13.Cu" "In15.Cu")
		(hatch none 0.5)
		(connect_pads
			(clearance 0)
		)
		(min_thickness 0.25)
		(keepout
			(tracks not_allowed)
			(vias allowed)
			(pads allowed)
			(copperpour not_allowed)
			(footprints allowed)
		)
		(placement
			(enabled no)
			(sheetname "")
		)
		(fill yes
			(thermal_gap 0.5)
			(thermal_bridge_width 0.5)
			(island_removal_mode 0)
		)
		(polygon
			(pts
				(arc
					(start 33.029906 -291.685218)
					(mid 32.361886 -291.685218)
					(end 33.029906 -291.685218)
				)
			)
		)
	)
	(zone
		(layers "B.Cu" "In6.Cu" "In11.Cu" "In13.Cu" "In15.Cu")
		(hatch none 0.5)
		(connect_pads
			(clearance 0)
		)
		(min_thickness 0.25)
		(keepout
			(tracks not_allowed)
			(vias allowed)
			(pads allowed)
			(copperpour not_allowed)
			(footprints allowed)
		)
		(placement
			(enabled no)
			(sheetname "")
		)
		(fill yes
			(thermal_gap 0.5)
			(thermal_bridge_width 0.5)
			(island_removal_mode 0)
		)
		(polygon
			(pts
				(arc
					(start 339.656166 -276.516084)
					(mid 339.026246 -276.516084)
					(end 339.656166 -276.516084)
				)
			)
		)
	)
	(zone
		(layers "B.Cu" "In6.Cu" "In11.Cu" "In13.Cu" "In15.Cu")
		(hatch none 0.5)
		(connect_pads
			(clearance 0)
		)
		(min_thickness 0.25)
		(keepout
			(tracks not_allowed)
			(vias allowed)
			(pads allowed)
			(copperpour not_allowed)
			(footprints allowed)
		)
		(placement
			(enabled no)
			(sheetname "")
		)
		(fill yes
			(thermal_gap 0.5)
			(thermal_bridge_width 0.5)
			(island_removal_mode 0)
		)
		(polygon
			(pts
				(arc
					(start 21.15439 -4.963414)
					(mid 20.48637 -4.963414)
					(end 21.15439 -4.963414)
				)
			)
		)
	)
	(zone
		(layers "B.Cu" "In6.Cu" "In11.Cu" "In13.Cu" "In15.Cu")
		(hatch none 0.5)
		(connect_pads
			(clearance 0)
		)
		(min_thickness 0.25)
		(keepout
			(tracks not_allowed)
			(vias allowed)
			(pads allowed)
			(copperpour not_allowed)
			(footprints allowed)
		)
		(placement
			(enabled no)
			(sheetname "")
		)
		(fill yes
			(thermal_gap 0.5)
			(thermal_bridge_width 0.5)
			(island_removal_mode 0)
		)
		(polygon
			(pts
				(arc
					(start 345.491054 -379.88113)
					(mid 344.823034 -379.88113)
					(end 345.491054 -379.88113)
				)
			)
		)
	)
	(zone
		(layers "B.Cu" "In6.Cu" "In11.Cu" "In13.Cu" "In15.Cu")
		(hatch none 0.5)
		(connect_pads
			(clearance 0)
		)
		(min_thickness 0.25)
		(keepout
			(tracks not_allowed)
			(vias allowed)
			(pads allowed)
			(copperpour not_allowed)
			(footprints allowed)
		)
		(placement
			(enabled no)
			(sheetname "")
		)
		(fill yes
			(thermal_gap 0.5)
			(thermal_bridge_width 0.5)
			(island_removal_mode 0)
		)
		(polygon
			(pts
				(arc
					(start 280.969974 -265.335004)
					(mid 280.301954 -265.335004)
					(end 280.969974 -265.335004)
				)
			)
		)
	)
	(zone
		(layers "B.Cu" "In6.Cu" "In11.Cu" "In13.Cu" "In15.Cu")
		(hatch none 0.5)
		(connect_pads
			(clearance 0)
		)
		(min_thickness 0.25)
		(keepout
			(tracks not_allowed)
			(vias allowed)
			(pads allowed)
			(copperpour not_allowed)
			(footprints allowed)
		)
		(placement
			(enabled no)
			(sheetname "")
		)
		(fill yes
			(thermal_gap 0.5)
			(thermal_bridge_width 0.5)
			(island_removal_mode 0)
		)
		(polygon
			(pts
				(arc
					(start 380.069852 -263.555988)
					(mid 379.439932 -263.555988)
					(end 380.069852 -263.555988)
				)
			)
		)
	)
	(zone
		(layers "B.Cu" "In6.Cu" "In11.Cu" "In13.Cu" "In15.Cu")
		(hatch none 0.5)
		(connect_pads
			(clearance 0)
		)
		(min_thickness 0.25)
		(keepout
			(tracks not_allowed)
			(vias allowed)
			(pads allowed)
			(copperpour not_allowed)
			(footprints allowed)
		)
		(placement
			(enabled no)
			(sheetname "")
		)
		(fill yes
			(thermal_gap 0.5)
			(thermal_bridge_width 0.5)
			(island_removal_mode 0)
		)
		(polygon
			(pts
				(arc
					(start 101.11613 -287.856422)
					(mid 100.48621 -287.856422)
					(end 101.11613 -287.856422)
				)
			)
		)
	)
	(zone
		(layers "B.Cu" "In6.Cu" "In11.Cu" "In13.Cu" "In15.Cu")
		(hatch none 0.5)
		(connect_pads
			(clearance 0)
		)
		(min_thickness 0.25)
		(keepout
			(tracks not_allowed)
			(vias allowed)
			(pads allowed)
			(copperpour not_allowed)
			(footprints allowed)
		)
		(placement
			(enabled no)
			(sheetname "")
		)
		(fill yes
			(thermal_gap 0.5)
			(thermal_bridge_width 0.5)
			(island_removal_mode 0)
		)
		(polygon
			(pts
				(arc
					(start 24.754332 -4.963414)
					(mid 24.086312 -4.963414)
					(end 24.754332 -4.963414)
				)
			)
		)
	)
	(zone
		(layers "B.Cu" "In6.Cu" "In11.Cu" "In13.Cu" "In15.Cu")
		(hatch none 0.5)
		(connect_pads
			(clearance 0)
		)
		(min_thickness 0.25)
		(keepout
			(tracks not_allowed)
			(vias allowed)
			(pads allowed)
			(copperpour not_allowed)
			(footprints allowed)
		)
		(placement
			(enabled no)
			(sheetname "")
		)
		(fill yes
			(thermal_gap 0.5)
			(thermal_bridge_width 0.5)
			(island_removal_mode 0)
		)
		(polygon
			(pts
				(arc
					(start 308.106064 -397.849344)
					(mid 307.476144 -397.849344)
					(end 308.106064 -397.849344)
				)
			)
		)
	)
	(zone
		(layers "B.Cu" "In6.Cu" "In11.Cu" "In13.Cu" "In15.Cu")
		(hatch none 0.5)
		(connect_pads
			(clearance 0)
		)
		(min_thickness 0.25)
		(keepout
			(tracks not_allowed)
			(vias allowed)
			(pads allowed)
			(copperpour not_allowed)
			(footprints allowed)
		)
		(placement
			(enabled no)
			(sheetname "")
		)
		(fill yes
			(thermal_gap 0.5)
			(thermal_bridge_width 0.5)
			(island_removal_mode 0)
		)
		(polygon
			(pts
				(arc
					(start 91.41587 -238.00435)
					(mid 90.78595 -238.00435)
					(end 91.41587 -238.00435)
				)
			)
		)
	)
	(zone
		(layers "B.Cu" "In6.Cu" "In11.Cu" "In13.Cu" "In15.Cu")
		(hatch none 0.5)
		(connect_pads
			(clearance 0)
		)
		(min_thickness 0.25)
		(keepout
			(tracks not_allowed)
			(vias allowed)
			(pads allowed)
			(copperpour not_allowed)
			(footprints allowed)
		)
		(placement
			(enabled no)
			(sheetname "")
		)
		(fill yes
			(thermal_gap 0.5)
			(thermal_bridge_width 0.5)
			(island_removal_mode 0)
		)
		(polygon
			(pts
				(arc
					(start 335.623916 -412.84652)
					(mid 334.955896 -412.84652)
					(end 335.623916 -412.84652)
				)
			)
		)
	)
	(zone
		(layers "B.Cu" "In6.Cu" "In11.Cu" "In13.Cu" "In15.Cu")
		(hatch none 0.5)
		(connect_pads
			(clearance 0)
		)
		(min_thickness 0.25)
		(keepout
			(tracks not_allowed)
			(vias allowed)
			(pads allowed)
			(copperpour not_allowed)
			(footprints allowed)
		)
		(placement
			(enabled no)
			(sheetname "")
		)
		(fill yes
			(thermal_gap 0.5)
			(thermal_bridge_width 0.5)
			(island_removal_mode 0)
		)
		(polygon
			(pts
				(arc
					(start 133.239764 -256.634488)
					(mid 132.609844 -256.634488)
					(end 133.239764 -256.634488)
				)
			)
		)
	)
	(zone
		(layers "B.Cu" "In6.Cu" "In11.Cu" "In13.Cu" "In15.Cu")
		(hatch none 0.5)
		(connect_pads
			(clearance 0)
		)
		(min_thickness 0.25)
		(keepout
			(tracks not_allowed)
			(vias allowed)
			(pads allowed)
			(copperpour not_allowed)
			(footprints allowed)
		)
		(placement
			(enabled no)
			(sheetname "")
		)
		(fill yes
			(thermal_gap 0.5)
			(thermal_bridge_width 0.5)
			(island_removal_mode 0)
		)
		(polygon
			(pts
				(arc
					(start 439.434224 -264.48512)
					(mid 438.766204 -264.48512)
					(end 439.434224 -264.48512)
				)
			)
		)
	)
	(zone
		(layers "B.Cu" "In6.Cu" "In11.Cu" "In13.Cu" "In15.Cu")
		(hatch none 0.5)
		(connect_pads
			(clearance 0)
		)
		(min_thickness 0.25)
		(keepout
			(tracks not_allowed)
			(vias allowed)
			(pads allowed)
			(copperpour not_allowed)
			(footprints allowed)
		)
		(placement
			(enabled no)
			(sheetname "")
		)
		(fill yes
			(thermal_gap 0.5)
			(thermal_bridge_width 0.5)
			(island_removal_mode 0)
		)
		(polygon
			(pts
				(arc
					(start 115.379754 -229.094538)
					(mid 114.749834 -229.094538)
					(end 115.379754 -229.094538)
				)
			)
		)
	)
	(zone
		(layers "B.Cu" "In6.Cu" "In11.Cu" "In13.Cu" "In15.Cu")
		(hatch none 0.5)
		(connect_pads
			(clearance 0)
		)
		(min_thickness 0.25)
		(keepout
			(tracks not_allowed)
			(vias allowed)
			(pads allowed)
			(copperpour not_allowed)
			(footprints allowed)
		)
		(placement
			(enabled no)
			(sheetname "")
		)
		(fill yes
			(thermal_gap 0.5)
			(thermal_bridge_width 0.5)
			(island_removal_mode 0)
		)
		(polygon
			(pts
				(arc
					(start 92.655898 -261.93623)
					(mid 92.025978 -261.93623)
					(end 92.655898 -261.93623)
				)
			)
		)
	)
	(zone
		(layers "B.Cu" "In6.Cu" "In11.Cu" "In13.Cu" "In15.Cu")
		(hatch none 0.5)
		(connect_pads
			(clearance 0)
		)
		(min_thickness 0.25)
		(keepout
			(tracks not_allowed)
			(vias allowed)
			(pads allowed)
			(copperpour not_allowed)
			(footprints allowed)
		)
		(placement
			(enabled no)
			(sheetname "")
		)
		(fill yes
			(thermal_gap 0.5)
			(thermal_bridge_width 0.5)
			(island_removal_mode 0)
		)
		(polygon
			(pts
				(arc
					(start 338.886038 -229.094284)
					(mid 338.256118 -229.094284)
					(end 338.886038 -229.094284)
				)
			)
		)
	)
	(zone
		(layers "B.Cu" "In6.Cu" "In11.Cu" "In13.Cu" "In15.Cu")
		(hatch none 0.5)
		(connect_pads
			(clearance 0)
		)
		(min_thickness 0.25)
		(keepout
			(tracks not_allowed)
			(vias allowed)
			(pads allowed)
			(copperpour not_allowed)
			(footprints allowed)
		)
		(placement
			(enabled no)
			(sheetname "")
		)
		(fill yes
			(thermal_gap 0.5)
			(thermal_bridge_width 0.5)
			(island_removal_mode 0)
		)
		(polygon
			(pts
				(arc
					(start 439.434224 -306.135024)
					(mid 438.766204 -306.135024)
					(end 439.434224 -306.135024)
				)
			)
		)
	)
	(zone
		(layers "B.Cu" "In6.Cu" "In11.Cu" "In13.Cu" "In15.Cu")
		(hatch none 0.5)
		(connect_pads
			(clearance 0)
		)
		(min_thickness 0.25)
		(keepout
			(tracks not_allowed)
			(vias allowed)
			(pads allowed)
			(copperpour not_allowed)
			(footprints allowed)
		)
		(placement
			(enabled no)
			(sheetname "")
		)
		(fill yes
			(thermal_gap 0.5)
			(thermal_bridge_width 0.5)
			(island_removal_mode 0)
		)
		(polygon
			(pts
				(arc
					(start 340.295992 -233.14406)
					(mid 339.666072 -233.14406)
					(end 340.295992 -233.14406)
				)
			)
		)
	)
	(zone
		(layers "B.Cu" "In6.Cu" "In11.Cu" "In13.Cu" "In15.Cu")
		(hatch none 0.5)
		(connect_pads
			(clearance 0)
		)
		(min_thickness 0.25)
		(keepout
			(tracks not_allowed)
			(vias allowed)
			(pads allowed)
			(copperpour not_allowed)
			(footprints allowed)
		)
		(placement
			(enabled no)
			(sheetname "")
		)
		(fill yes
			(thermal_gap 0.5)
			(thermal_bridge_width 0.5)
			(island_removal_mode 0)
		)
		(polygon
			(pts
				(arc
					(start 91.716098 -286.23641)
					(mid 91.086178 -286.23641)
					(end 91.716098 -286.23641)
				)
			)
		)
	)
	(zone
		(layers "B.Cu" "In6.Cu" "In11.Cu" "In13.Cu" "In15.Cu")
		(hatch none 0.5)
		(connect_pads
			(clearance 0)
		)
		(min_thickness 0.25)
		(keepout
			(tracks not_allowed)
			(vias allowed)
			(pads allowed)
			(copperpour not_allowed)
			(footprints allowed)
		)
		(placement
			(enabled no)
			(sheetname "")
		)
		(fill yes
			(thermal_gap 0.5)
			(thermal_bridge_width 0.5)
			(island_removal_mode 0)
		)
		(polygon
			(pts
				(arc
					(start 311.117996 -412.84652)
					(mid 310.449976 -412.84652)
					(end 311.117996 -412.84652)
				)
			)
		)
	)
	(zone
		(layers "B.Cu" "In6.Cu" "In11.Cu" "In13.Cu" "In15.Cu")
		(hatch none 0.5)
		(connect_pads
			(clearance 0)
		)
		(min_thickness 0.25)
		(keepout
			(tracks not_allowed)
			(vias allowed)
			(pads allowed)
			(copperpour not_allowed)
			(footprints allowed)
		)
		(placement
			(enabled no)
			(sheetname "")
		)
		(fill yes
			(thermal_gap 0.5)
			(thermal_bridge_width 0.5)
			(island_removal_mode 0)
		)
		(polygon
			(pts
				(arc
					(start 91.716098 -270.03629)
					(mid 91.086178 -270.03629)
					(end 91.716098 -270.03629)
				)
			)
		)
	)
	(zone
		(layers "B.Cu" "In6.Cu" "In11.Cu" "In13.Cu" "In15.Cu")
		(hatch none 0.5)
		(connect_pads
			(clearance 0)
		)
		(min_thickness 0.25)
		(keepout
			(tracks not_allowed)
			(vias allowed)
			(pads allowed)
			(copperpour not_allowed)
			(footprints allowed)
		)
		(placement
			(enabled no)
			(sheetname "")
		)
		(fill yes
			(thermal_gap 0.5)
			(thermal_bridge_width 0.5)
			(island_removal_mode 0)
		)
		(polygon
			(pts
				(arc
					(start 435.334156 -274.684998)
					(mid 434.666136 -274.684998)
					(end 435.334156 -274.684998)
				)
			)
		)
	)
	(zone
		(layers "B.Cu" "In6.Cu" "In11.Cu" "In13.Cu" "In15.Cu")
		(hatch none 0.5)
		(connect_pads
			(clearance 0)
		)
		(min_thickness 0.25)
		(keepout
			(tracks not_allowed)
			(vias allowed)
			(pads allowed)
			(copperpour not_allowed)
			(footprints allowed)
		)
		(placement
			(enabled no)
			(sheetname "")
		)
		(fill yes
			(thermal_gap 0.5)
			(thermal_bridge_width 0.5)
			(island_removal_mode 0)
		)
		(polygon
			(pts
				(arc
					(start 285.070042 -317.18504)
					(mid 284.402022 -317.18504)
					(end 285.070042 -317.18504)
				)
			)
		)
	)
	(zone
		(layers "B.Cu" "In6.Cu" "In11.Cu" "In13.Cu" "In15.Cu")
		(hatch none 0.5)
		(connect_pads
			(clearance 0)
		)
		(min_thickness 0.25)
		(keepout
			(tracks not_allowed)
			(vias allowed)
			(pads allowed)
			(copperpour not_allowed)
			(footprints allowed)
		)
		(placement
			(enabled no)
			(sheetname "")
		)
		(fill yes
			(thermal_gap 0.5)
			(thermal_bridge_width 0.5)
			(island_removal_mode 0)
		)
		(polygon
			(pts
				(arc
					(start 117.089682 -287.856422)
					(mid 116.459762 -287.856422)
					(end 117.089682 -287.856422)
				)
			)
		)
	)
	(zone
		(layers "B.Cu" "In6.Cu" "In11.Cu" "In13.Cu" "In15.Cu")
		(hatch none 0.5)
		(connect_pads
			(clearance 0)
		)
		(min_thickness 0.25)
		(keepout
			(tracks not_allowed)
			(vias allowed)
			(pads allowed)
			(copperpour not_allowed)
			(footprints allowed)
		)
		(placement
			(enabled no)
			(sheetname "")
		)
		(fill yes
			(thermal_gap 0.5)
			(thermal_bridge_width 0.5)
			(island_removal_mode 0)
		)
		(polygon
			(pts
				(arc
					(start 435.334156 -198.185024)
					(mid 434.666136 -198.185024)
					(end 435.334156 -198.185024)
				)
			)
		)
	)
	(zone
		(layers "B.Cu" "In6.Cu" "In11.Cu" "In13.Cu" "In15.Cu")
		(hatch none 0.5)
		(connect_pads
			(clearance 0)
		)
		(min_thickness 0.25)
		(keepout
			(tracks not_allowed)
			(vias allowed)
			(pads allowed)
			(copperpour not_allowed)
			(footprints allowed)
		)
		(placement
			(enabled no)
			(sheetname "")
		)
		(fill yes
			(thermal_gap 0.5)
			(thermal_bridge_width 0.5)
			(island_removal_mode 0)
		)
		(polygon
			(pts
				(arc
					(start 339.186012 -278.946102)
					(mid 338.556092 -278.946102)
					(end 339.186012 -278.946102)
				)
			)
		)
	)
	(zone
		(layers "B.Cu" "In6.Cu" "In11.Cu" "In13.Cu" "In15.Cu")
		(hatch none 0.5)
		(connect_pads
			(clearance 0)
		)
		(min_thickness 0.25)
		(keepout
			(tracks not_allowed)
			(vias allowed)
			(pads allowed)
			(copperpour not_allowed)
			(footprints allowed)
		)
		(placement
			(enabled no)
			(sheetname "")
		)
		(fill yes
			(thermal_gap 0.5)
			(thermal_bridge_width 0.5)
			(island_removal_mode 0)
		)
		(polygon
			(pts
				(arc
					(start 339.355938 -233.14406)
					(mid 338.726018 -233.14406)
					(end 339.355938 -233.14406)
				)
			)
		)
	)
	(zone
		(layers "B.Cu" "In6.Cu" "In11.Cu" "In13.Cu" "In15.Cu")
		(hatch none 0.5)
		(connect_pads
			(clearance 0)
		)
		(min_thickness 0.25)
		(keepout
			(tracks not_allowed)
			(vias allowed)
			(pads allowed)
			(copperpour not_allowed)
			(footprints allowed)
		)
		(placement
			(enabled no)
			(sheetname "")
		)
		(fill yes
			(thermal_gap 0.5)
			(thermal_bridge_width 0.5)
			(island_removal_mode 0)
		)
		(polygon
			(pts
				(arc
					(start 123.369578 -229.90429)
					(mid 122.739658 -229.90429)
					(end 123.369578 -229.90429)
				)
			)
		)
	)
	(zone
		(layers "B.Cu" "In6.Cu" "In11.Cu" "In13.Cu" "In15.Cu")
		(hatch none 0.5)
		(connect_pads
			(clearance 0)
		)
		(min_thickness 0.25)
		(keepout
			(tracks not_allowed)
			(vias allowed)
			(pads allowed)
			(copperpour not_allowed)
			(footprints allowed)
		)
		(placement
			(enabled no)
			(sheetname "")
		)
		(fill yes
			(thermal_gap 0.5)
			(thermal_bridge_width 0.5)
			(island_removal_mode 0)
		)
		(polygon
			(pts
				(arc
					(start 378.218192 -412.84652)
					(mid 377.550172 -412.84652)
					(end 378.218192 -412.84652)
				)
			)
		)
	)
	(zone
		(layers "B.Cu" "In6.Cu" "In11.Cu" "In13.Cu" "In15.Cu")
		(hatch none 0.5)
		(connect_pads
			(clearance 0)
		)
		(min_thickness 0.25)
		(keepout
			(tracks not_allowed)
			(vias allowed)
			(pads allowed)
			(copperpour not_allowed)
			(footprints allowed)
		)
		(placement
			(enabled no)
			(sheetname "")
		)
		(fill yes
			(thermal_gap 0.5)
			(thermal_bridge_width 0.5)
			(island_removal_mode 0)
		)
		(polygon
			(pts
				(arc
					(start 368.789712 -291.095938)
					(mid 368.159792 -291.095938)
					(end 368.789712 -291.095938)
				)
			)
		)
	)
	(zone
		(layers "B.Cu" "In6.Cu" "In11.Cu" "In13.Cu" "In15.Cu")
		(hatch none 0.5)
		(connect_pads
			(clearance 0)
		)
		(min_thickness 0.25)
		(keepout
			(tracks not_allowed)
			(vias allowed)
			(pads allowed)
			(copperpour not_allowed)
			(footprints allowed)
		)
		(placement
			(enabled no)
			(sheetname "")
		)
		(fill yes
			(thermal_gap 0.5)
			(thermal_bridge_width 0.5)
			(island_removal_mode 0)
		)
		(polygon
			(pts
				(arc
					(start 280.969974 -293.384986)
					(mid 280.301954 -293.384986)
					(end 280.969974 -293.384986)
				)
			)
		)
	)
	(zone
		(layers "B.Cu" "In6.Cu" "In11.Cu" "In13.Cu" "In15.Cu")
		(hatch none 0.5)
		(connect_pads
			(clearance 0)
		)
		(min_thickness 0.25)
		(keepout
			(tracks not_allowed)
			(vias allowed)
			(pads allowed)
			(copperpour not_allowed)
			(footprints allowed)
		)
		(placement
			(enabled no)
			(sheetname "")
		)
		(fill yes
			(thermal_gap 0.5)
			(thermal_bridge_width 0.5)
			(island_removal_mode 0)
		)
		(polygon
			(pts
				(arc
					(start 345.936062 -231.524048)
					(mid 345.306142 -231.524048)
					(end 345.936062 -231.524048)
				)
			)
		)
	)
	(zone
		(layers "B.Cu" "In6.Cu" "In11.Cu" "In13.Cu" "In15.Cu")
		(hatch none 0.5)
		(connect_pads
			(clearance 0)
		)
		(min_thickness 0.25)
		(keepout
			(tracks not_allowed)
			(vias allowed)
			(pads allowed)
			(copperpour not_allowed)
			(footprints allowed)
		)
		(placement
			(enabled no)
			(sheetname "")
		)
		(fill yes
			(thermal_gap 0.5)
			(thermal_bridge_width 0.5)
			(island_removal_mode 0)
		)
		(polygon
			(pts
				(arc
					(start 92.655898 -266.796266)
					(mid 92.025978 -266.796266)
					(end 92.655898 -266.796266)
				)
			)
		)
	)
	(zone
		(layers "B.Cu" "In6.Cu" "In11.Cu" "In13.Cu" "In15.Cu")
		(hatch none 0.5)
		(connect_pads
			(clearance 0)
		)
		(min_thickness 0.25)
		(keepout
			(tracks not_allowed)
			(vias allowed)
			(pads allowed)
			(copperpour not_allowed)
			(footprints allowed)
		)
		(placement
			(enabled no)
			(sheetname "")
		)
		(fill yes
			(thermal_gap 0.5)
			(thermal_bridge_width 0.5)
			(island_removal_mode 0)
		)
		(polygon
			(pts
				(arc
					(start 94.596712 -373.96293)
					(mid 93.928692 -373.96293)
					(end 94.596712 -373.96293)
				)
			)
		)
	)
	(zone
		(layers "B.Cu" "In6.Cu" "In11.Cu" "In13.Cu" "In15.Cu")
		(hatch none 0.5)
		(connect_pads
			(clearance 0)
		)
		(min_thickness 0.25)
		(keepout
			(tracks not_allowed)
			(vias allowed)
			(pads allowed)
			(copperpour not_allowed)
			(footprints allowed)
		)
		(placement
			(enabled no)
			(sheetname "")
		)
		(fill yes
			(thermal_gap 0.5)
			(thermal_bridge_width 0.5)
			(island_removal_mode 0)
		)
		(polygon
			(pts
				(arc
					(start 90.94597 -232.334308)
					(mid 90.31605 -232.334308)
					(end 90.94597 -232.334308)
				)
			)
		)
	)
	(zone
		(layers "B.Cu" "In6.Cu" "In11.Cu" "In13.Cu" "In15.Cu")
		(hatch none 0.5)
		(connect_pads
			(clearance 0)
		)
		(min_thickness 0.25)
		(keepout
			(tracks not_allowed)
			(vias allowed)
			(pads allowed)
			(copperpour not_allowed)
			(footprints allowed)
		)
		(placement
			(enabled no)
			(sheetname "")
		)
		(fill yes
			(thermal_gap 0.5)
			(thermal_bridge_width 0.5)
			(island_removal_mode 0)
		)
		(polygon
			(pts
				(arc
					(start 285.070042 -197.33514)
					(mid 284.402022 -197.33514)
					(end 285.070042 -197.33514)
				)
			)
		)
	)
	(zone
		(layers "B.Cu" "In6.Cu" "In11.Cu" "In13.Cu" "In15.Cu")
		(hatch none 0.5)
		(connect_pads
			(clearance 0)
		)
		(min_thickness 0.25)
		(keepout
			(tracks not_allowed)
			(vias allowed)
			(pads allowed)
			(copperpour not_allowed)
			(footprints allowed)
		)
		(placement
			(enabled no)
			(sheetname "")
		)
		(fill yes
			(thermal_gap 0.5)
			(thermal_bridge_width 0.5)
			(island_removal_mode 0)
		)
		(polygon
			(pts
				(arc
					(start 439.434224 -201.585068)
					(mid 438.766204 -201.585068)
					(end 439.434224 -201.585068)
				)
			)
		)
	)
	(zone
		(layers "B.Cu" "In6.Cu" "In11.Cu" "In13.Cu" "In15.Cu")
		(hatch none 0.5)
		(connect_pads
			(clearance 0)
		)
		(min_thickness 0.25)
		(keepout
			(tracks not_allowed)
			(vias allowed)
			(pads allowed)
			(copperpour not_allowed)
			(footprints allowed)
		)
		(placement
			(enabled no)
			(sheetname "")
		)
		(fill yes
			(thermal_gap 0.5)
			(thermal_bridge_width 0.5)
			(island_removal_mode 0)
		)
		(polygon
			(pts
				(arc
					(start 107.696 -289.47618)
					(mid 107.06608 -289.47618)
					(end 107.696 -289.47618)
				)
			)
		)
	)
	(zone
		(layers "B.Cu" "In6.Cu" "In11.Cu" "In13.Cu" "In15.Cu")
		(hatch none 0.5)
		(connect_pads
			(clearance 0)
		)
		(min_thickness 0.25)
		(keepout
			(tracks not_allowed)
			(vias allowed)
			(pads allowed)
			(copperpour not_allowed)
			(footprints allowed)
		)
		(placement
			(enabled no)
			(sheetname "")
		)
		(fill yes
			(thermal_gap 0.5)
			(thermal_bridge_width 0.5)
			(island_removal_mode 0)
		)
		(polygon
			(pts
				(arc
					(start 371.609874 -289.475926)
					(mid 370.979954 -289.475926)
					(end 371.609874 -289.475926)
				)
			)
		)
	)
	(zone
		(layers "B.Cu" "In6.Cu" "In11.Cu" "In13.Cu" "In15.Cu")
		(hatch none 0.5)
		(connect_pads
			(clearance 0)
		)
		(min_thickness 0.25)
		(keepout
			(tracks not_allowed)
			(vias allowed)
			(pads allowed)
			(copperpour not_allowed)
			(footprints allowed)
		)
		(placement
			(enabled no)
			(sheetname "")
		)
		(fill yes
			(thermal_gap 0.5)
			(thermal_bridge_width 0.5)
			(island_removal_mode 0)
		)
		(polygon
			(pts
				(arc
					(start 379.299724 -225.85426)
					(mid 378.669804 -225.85426)
					(end 379.299724 -225.85426)
				)
			)
		)
	)
	(zone
		(layers "B.Cu" "In6.Cu" "In11.Cu" "In13.Cu" "In15.Cu")
		(hatch none 0.5)
		(connect_pads
			(clearance 0)
		)
		(min_thickness 0.25)
		(keepout
			(tracks not_allowed)
			(vias allowed)
			(pads allowed)
			(copperpour not_allowed)
			(footprints allowed)
		)
		(placement
			(enabled no)
			(sheetname "")
		)
		(fill yes
			(thermal_gap 0.5)
			(thermal_bridge_width 0.5)
			(island_removal_mode 0)
		)
		(polygon
			(pts
				(arc
					(start 439.434224 -296.78503)
					(mid 438.766204 -296.78503)
					(end 439.434224 -296.78503)
				)
			)
		)
	)
	(zone
		(layers "B.Cu" "In6.Cu" "In11.Cu" "In13.Cu" "In15.Cu")
		(hatch none 0.5)
		(connect_pads
			(clearance 0)
		)
		(min_thickness 0.25)
		(keepout
			(tracks not_allowed)
			(vias allowed)
			(pads allowed)
			(copperpour not_allowed)
			(footprints allowed)
		)
		(placement
			(enabled no)
			(sheetname "")
		)
		(fill yes
			(thermal_gap 0.5)
			(thermal_bridge_width 0.5)
			(island_removal_mode 0)
		)
		(polygon
			(pts
				(arc
					(start 132.76961 -226.66452)
					(mid 132.13969 -226.66452)
					(end 132.76961 -226.66452)
				)
			)
		)
	)
	(zone
		(layers "B.Cu" "In6.Cu" "In11.Cu" "In13.Cu" "In15.Cu")
		(hatch none 0.5)
		(connect_pads
			(clearance 0)
		)
		(min_thickness 0.25)
		(keepout
			(tracks not_allowed)
			(vias allowed)
			(pads allowed)
			(copperpour not_allowed)
			(footprints allowed)
		)
		(placement
			(enabled no)
			(sheetname "")
		)
		(fill yes
			(thermal_gap 0.5)
			(thermal_bridge_width 0.5)
			(island_removal_mode 0)
		)
		(polygon
			(pts
				(arc
					(start 370.369846 -233.14406)
					(mid 369.739926 -233.14406)
					(end 370.369846 -233.14406)
				)
			)
		)
	)
	(zone
		(layers "B.Cu" "In6.Cu" "In11.Cu" "In13.Cu" "In15.Cu")
		(hatch none 0.5)
		(connect_pads
			(clearance 0)
		)
		(min_thickness 0.25)
		(keepout
			(tracks not_allowed)
			(vias allowed)
			(pads allowed)
			(copperpour not_allowed)
			(footprints allowed)
		)
		(placement
			(enabled no)
			(sheetname "")
		)
		(fill yes
			(thermal_gap 0.5)
			(thermal_bridge_width 0.5)
			(island_removal_mode 0)
		)
		(polygon
			(pts
				(arc
					(start 142.797276 -404.46452)
					(mid 142.129256 -404.46452)
					(end 142.797276 -404.46452)
				)
			)
		)
	)
	(zone
		(layers "B.Cu" "In6.Cu" "In11.Cu" "In13.Cu" "In15.Cu")
		(hatch none 0.5)
		(connect_pads
			(clearance 0)
		)
		(min_thickness 0.25)
		(keepout
			(tracks not_allowed)
			(vias allowed)
			(pads allowed)
			(copperpour not_allowed)
			(footprints allowed)
		)
		(placement
			(enabled no)
			(sheetname "")
		)
		(fill yes
			(thermal_gap 0.5)
			(thermal_bridge_width 0.5)
			(island_removal_mode 0)
		)
		(polygon
			(pts
				(arc
					(start 121.354596 -404.46452)
					(mid 120.686576 -404.46452)
					(end 121.354596 -404.46452)
				)
			)
		)
	)
	(zone
		(layers "B.Cu" "In6.Cu" "In11.Cu" "In13.Cu" "In15.Cu")
		(hatch none 0.5)
		(connect_pads
			(clearance 0)
		)
		(min_thickness 0.25)
		(keepout
			(tracks not_allowed)
			(vias allowed)
			(pads allowed)
			(copperpour not_allowed)
			(footprints allowed)
		)
		(placement
			(enabled no)
			(sheetname "")
		)
		(fill yes
			(thermal_gap 0.5)
			(thermal_bridge_width 0.5)
			(island_removal_mode 0)
		)
		(polygon
			(pts
				(arc
					(start 439.434224 -216.035128)
					(mid 438.766204 -216.035128)
					(end 439.434224 -216.035128)
				)
			)
		)
	)
	(zone
		(layers "B.Cu" "In6.Cu" "In11.Cu" "In13.Cu" "In15.Cu")
		(hatch none 0.5)
		(connect_pads
			(clearance 0)
		)
		(min_thickness 0.25)
		(keepout
			(tracks not_allowed)
			(vias allowed)
			(pads allowed)
			(copperpour not_allowed)
			(footprints allowed)
		)
		(placement
			(enabled no)
			(sheetname "")
		)
		(fill yes
			(thermal_gap 0.5)
			(thermal_bridge_width 0.5)
			(island_removal_mode 0)
		)
		(polygon
			(pts
				(arc
					(start 380.069852 -292.71595)
					(mid 379.439932 -292.71595)
					(end 380.069852 -292.71595)
				)
			)
		)
	)
	(zone
		(layers "B.Cu" "In6.Cu" "In11.Cu" "In13.Cu" "In15.Cu")
		(hatch none 0.5)
		(connect_pads
			(clearance 0)
		)
		(min_thickness 0.25)
		(keepout
			(tracks not_allowed)
			(vias allowed)
			(pads allowed)
			(copperpour not_allowed)
			(footprints allowed)
		)
		(placement
			(enabled no)
			(sheetname "")
		)
		(fill yes
			(thermal_gap 0.5)
			(thermal_bridge_width 0.5)
			(island_removal_mode 0)
		)
		(polygon
			(pts
				(arc
					(start 165.733984 -388.774432)
					(mid 165.104064 -388.774432)
					(end 165.733984 -388.774432)
				)
			)
		)
	)
	(zone
		(layers "B.Cu" "In6.Cu" "In11.Cu" "In13.Cu" "In15.Cu")
		(hatch none 0.5)
		(connect_pads
			(clearance 0)
		)
		(min_thickness 0.25)
		(keepout
			(tracks not_allowed)
			(vias allowed)
			(pads allowed)
			(copperpour not_allowed)
			(footprints allowed)
		)
		(placement
			(enabled no)
			(sheetname "")
		)
		(fill yes
			(thermal_gap 0.5)
			(thermal_bridge_width 0.5)
			(island_removal_mode 0)
		)
		(polygon
			(pts
				(arc
					(start 187.394088 -314.635388)
					(mid 186.726068 -314.635388)
					(end 187.394088 -314.635388)
				)
			)
		)
	)
	(zone
		(layers "B.Cu" "In6.Cu" "In11.Cu" "In13.Cu" "In15.Cu")
		(hatch none 0.5)
		(connect_pads
			(clearance 0)
		)
		(min_thickness 0.25)
		(keepout
			(tracks not_allowed)
			(vias allowed)
			(pads allowed)
			(copperpour not_allowed)
			(footprints allowed)
		)
		(placement
			(enabled no)
			(sheetname "")
		)
		(fill yes
			(thermal_gap 0.5)
			(thermal_bridge_width 0.5)
			(island_removal_mode 0)
		)
		(polygon
			(pts
				(arc
					(start 191.494156 -307.8353)
					(mid 190.826136 -307.8353)
					(end 191.494156 -307.8353)
				)
			)
		)
	)
	(zone
		(layers "B.Cu" "In6.Cu" "In11.Cu" "In13.Cu" "In15.Cu")
		(hatch none 0.5)
		(connect_pads
			(clearance 0)
		)
		(min_thickness 0.25)
		(keepout
			(tracks not_allowed)
			(vias allowed)
			(pads allowed)
			(copperpour not_allowed)
			(footprints allowed)
		)
		(placement
			(enabled no)
			(sheetname "")
		)
		(fill yes
			(thermal_gap 0.5)
			(thermal_bridge_width 0.5)
			(island_removal_mode 0)
		)
		(polygon
			(pts
				(arc
					(start 352.516186 -229.904036)
					(mid 351.886266 -229.904036)
					(end 352.516186 -229.904036)
				)
			)
		)
	)
	(zone
		(layers "B.Cu" "In6.Cu" "In11.Cu" "In13.Cu" "In15.Cu")
		(hatch none 0.5)
		(connect_pads
			(clearance 0)
		)
		(min_thickness 0.25)
		(keepout
			(tracks not_allowed)
			(vias allowed)
			(pads allowed)
			(copperpour not_allowed)
			(footprints allowed)
		)
		(placement
			(enabled no)
			(sheetname "")
		)
		(fill yes
			(thermal_gap 0.5)
			(thermal_bridge_width 0.5)
			(island_removal_mode 0)
		)
		(polygon
			(pts
				(arc
					(start 381.009906 -273.27606)
					(mid 380.379986 -273.27606)
					(end 381.009906 -273.27606)
				)
			)
		)
	)
	(zone
		(layers "B.Cu" "In6.Cu" "In11.Cu" "In13.Cu" "In15.Cu")
		(hatch none 0.5)
		(connect_pads
			(clearance 0)
		)
		(min_thickness 0.25)
		(keepout
			(tracks not_allowed)
			(vias allowed)
			(pads allowed)
			(copperpour not_allowed)
			(footprints allowed)
		)
		(placement
			(enabled no)
			(sheetname "")
		)
		(fill yes
			(thermal_gap 0.5)
			(thermal_bridge_width 0.5)
			(island_removal_mode 0)
		)
		(polygon
			(pts
				(arc
					(start 379.599698 -283.806138)
					(mid 378.969778 -283.806138)
					(end 379.599698 -283.806138)
				)
			)
		)
	)
	(zone
		(layers "B.Cu" "In6.Cu" "In11.Cu" "In13.Cu" "In15.Cu")
		(hatch none 0.5)
		(connect_pads
			(clearance 0)
		)
		(min_thickness 0.25)
		(keepout
			(tracks not_allowed)
			(vias allowed)
			(pads allowed)
			(copperpour not_allowed)
			(footprints allowed)
		)
		(placement
			(enabled no)
			(sheetname "")
		)
		(fill yes
			(thermal_gap 0.5)
			(thermal_bridge_width 0.5)
			(island_removal_mode 0)
		)
		(polygon
			(pts
				(arc
					(start 33.029906 -226.23526)
					(mid 32.361886 -226.23526)
					(end 33.029906 -226.23526)
				)
			)
		)
	)
	(zone
		(layers "B.Cu" "In6.Cu" "In11.Cu" "In13.Cu" "In15.Cu")
		(hatch none 0.5)
		(connect_pads
			(clearance 0)
		)
		(min_thickness 0.25)
		(keepout
			(tracks not_allowed)
			(vias allowed)
			(pads allowed)
			(copperpour not_allowed)
			(footprints allowed)
		)
		(placement
			(enabled no)
			(sheetname "")
		)
		(fill yes
			(thermal_gap 0.5)
			(thermal_bridge_width 0.5)
			(island_removal_mode 0)
		)
		(polygon
			(pts
				(arc
					(start 384.40614 -393.69238)
					(mid 383.77622 -393.69238)
					(end 384.40614 -393.69238)
				)
			)
		)
	)
	(zone
		(layers "B.Cu" "In6.Cu" "In11.Cu" "In13.Cu" "In15.Cu")
		(hatch none 0.5)
		(connect_pads
			(clearance 0)
		)
		(min_thickness 0.25)
		(keepout
			(tracks not_allowed)
			(vias allowed)
			(pads allowed)
			(copperpour not_allowed)
			(footprints allowed)
		)
		(placement
			(enabled no)
			(sheetname "")
		)
		(fill yes
			(thermal_gap 0.5)
			(thermal_bridge_width 0.5)
			(island_removal_mode 0)
		)
		(polygon
			(pts
				(arc
					(start 285.070042 -267.885164)
					(mid 284.402022 -267.885164)
					(end 285.070042 -267.885164)
				)
			)
		)
	)
	(zone
		(layers "B.Cu" "In6.Cu" "In11.Cu" "In13.Cu" "In15.Cu")
		(hatch none 0.5)
		(connect_pads
			(clearance 0)
		)
		(min_thickness 0.25)
		(keepout
			(tracks not_allowed)
			(vias allowed)
			(pads allowed)
			(copperpour not_allowed)
			(footprints allowed)
		)
		(placement
			(enabled no)
			(sheetname "")
		)
		(fill yes
			(thermal_gap 0.5)
			(thermal_bridge_width 0.5)
			(island_removal_mode 0)
		)
		(polygon
			(pts
				(arc
					(start 340.595966 -282.996132)
					(mid 339.966046 -282.996132)
					(end 340.595966 -282.996132)
				)
			)
		)
	)
	(zone
		(layers "B.Cu" "In6.Cu" "In11.Cu" "In13.Cu" "In15.Cu")
		(hatch none 0.5)
		(connect_pads
			(clearance 0)
		)
		(min_thickness 0.25)
		(keepout
			(tracks not_allowed)
			(vias allowed)
			(pads allowed)
			(copperpour not_allowed)
			(footprints allowed)
		)
		(placement
			(enabled no)
			(sheetname "")
		)
		(fill yes
			(thermal_gap 0.5)
			(thermal_bridge_width 0.5)
			(island_removal_mode 0)
		)
		(polygon
			(pts
				(arc
					(start 37.129974 -267.885418)
					(mid 36.461954 -267.885418)
					(end 37.129974 -267.885418)
				)
			)
		)
	)
	(zone
		(layers "B.Cu" "In6.Cu" "In11.Cu" "In13.Cu" "In15.Cu")
		(hatch none 0.5)
		(connect_pads
			(clearance 0)
		)
		(min_thickness 0.25)
		(keepout
			(tracks not_allowed)
			(vias allowed)
			(pads allowed)
			(copperpour not_allowed)
			(footprints allowed)
		)
		(placement
			(enabled no)
			(sheetname "")
		)
		(fill yes
			(thermal_gap 0.5)
			(thermal_bridge_width 0.5)
			(island_removal_mode 0)
		)
		(polygon
			(pts
				(arc
					(start 381.479806 -272.466054)
					(mid 380.849886 -272.466054)
					(end 381.479806 -272.466054)
				)
			)
		)
	)
	(zone
		(layers "B.Cu" "In6.Cu" "In11.Cu" "In13.Cu" "In15.Cu")
		(hatch none 0.5)
		(connect_pads
			(clearance 0)
		)
		(min_thickness 0.25)
		(keepout
			(tracks not_allowed)
			(vias allowed)
			(pads allowed)
			(copperpour not_allowed)
			(footprints allowed)
		)
		(placement
			(enabled no)
			(sheetname "")
		)
		(fill yes
			(thermal_gap 0.5)
			(thermal_bridge_width 0.5)
			(island_removal_mode 0)
		)
		(polygon
			(pts
				(arc
					(start 104.139492 -379.496828)
					(mid 103.471472 -379.496828)
					(end 104.139492 -379.496828)
				)
			)
		)
	)
	(zone
		(layers "B.Cu" "In6.Cu" "In11.Cu" "In13.Cu" "In15.Cu")
		(hatch none 0.5)
		(connect_pads
			(clearance 0)
		)
		(min_thickness 0.25)
		(keepout
			(tracks not_allowed)
			(vias allowed)
			(pads allowed)
			(copperpour not_allowed)
			(footprints allowed)
		)
		(placement
			(enabled no)
			(sheetname "")
		)
		(fill yes
			(thermal_gap 0.5)
			(thermal_bridge_width 0.5)
			(island_removal_mode 0)
		)
		(polygon
			(pts
				(arc
					(start 349.696024 -226.664266)
					(mid 349.066104 -226.664266)
					(end 349.696024 -226.664266)
				)
			)
		)
	)
	(zone
		(layers "B.Cu" "In6.Cu" "In11.Cu" "In13.Cu" "In15.Cu")
		(hatch none 0.5)
		(connect_pads
			(clearance 0)
		)
		(min_thickness 0.25)
		(keepout
			(tracks not_allowed)
			(vias allowed)
			(pads allowed)
			(copperpour not_allowed)
			(footprints allowed)
		)
		(placement
			(enabled no)
			(sheetname "")
		)
		(fill yes
			(thermal_gap 0.5)
			(thermal_bridge_width 0.5)
			(island_removal_mode 0)
		)
		(polygon
			(pts
				(arc
					(start 314.905898 -397.156432)
					(mid 314.275978 -397.156432)
					(end 314.905898 -397.156432)
				)
			)
		)
	)
	(zone
		(layers "B.Cu" "In6.Cu" "In11.Cu" "In13.Cu" "In15.Cu")
		(hatch none 0.5)
		(connect_pads
			(clearance 0)
		)
		(min_thickness 0.25)
		(keepout
			(tracks not_allowed)
			(vias allowed)
			(pads allowed)
			(copperpour not_allowed)
			(footprints allowed)
		)
		(placement
			(enabled no)
			(sheetname "")
		)
		(fill yes
			(thermal_gap 0.5)
			(thermal_bridge_width 0.5)
			(island_removal_mode 0)
		)
		(polygon
			(pts
				(arc
					(start 285.070042 -199.035162)
					(mid 284.402022 -199.035162)
					(end 285.070042 -199.035162)
				)
			)
		)
	)
	(zone
		(layers "B.Cu" "In6.Cu" "In11.Cu" "In13.Cu" "In15.Cu")
		(hatch none 0.5)
		(connect_pads
			(clearance 0)
		)
		(min_thickness 0.25)
		(keepout
			(tracks not_allowed)
			(vias allowed)
			(pads allowed)
			(copperpour not_allowed)
			(footprints allowed)
		)
		(placement
			(enabled no)
			(sheetname "")
		)
		(fill yes
			(thermal_gap 0.5)
			(thermal_bridge_width 0.5)
			(island_removal_mode 0)
		)
		(polygon
			(pts
				(arc
					(start 187.394088 -301.035212)
					(mid 186.726068 -301.035212)
					(end 187.394088 -301.035212)
				)
			)
		)
	)
	(zone
		(layers "B.Cu" "In6.Cu" "In11.Cu" "In13.Cu" "In15.Cu")
		(hatch none 0.5)
		(connect_pads
			(clearance 0)
		)
		(min_thickness 0.25)
		(keepout
			(tracks not_allowed)
			(vias allowed)
			(pads allowed)
			(copperpour not_allowed)
			(footprints allowed)
		)
		(placement
			(enabled no)
			(sheetname "")
		)
		(fill yes
			(thermal_gap 0.5)
			(thermal_bridge_width 0.5)
			(island_removal_mode 0)
		)
		(polygon
			(pts
				(arc
					(start 336.982054 -382.34493)
					(mid 336.314034 -382.34493)
					(end 336.982054 -382.34493)
				)
			)
		)
	)
	(zone
		(layers "B.Cu" "In6.Cu" "In11.Cu" "In13.Cu" "In15.Cu")
		(hatch none 0.5)
		(connect_pads
			(clearance 0)
		)
		(min_thickness 0.25)
		(keepout
			(tracks not_allowed)
			(vias allowed)
			(pads allowed)
			(copperpour not_allowed)
			(footprints allowed)
		)
		(placement
			(enabled no)
			(sheetname "")
		)
		(fill yes
			(thermal_gap 0.5)
			(thermal_bridge_width 0.5)
			(island_removal_mode 0)
		)
		(polygon
			(pts
				(arc
					(start 380.709678 -233.14406)
					(mid 380.079758 -233.14406)
					(end 380.709678 -233.14406)
				)
			)
		)
	)
	(zone
		(layers "B.Cu" "In6.Cu" "In11.Cu" "In13.Cu" "In15.Cu")
		(hatch none 0.5)
		(connect_pads
			(clearance 0)
		)
		(min_thickness 0.25)
		(keepout
			(tracks not_allowed)
			(vias allowed)
			(pads allowed)
			(copperpour not_allowed)
			(footprints allowed)
		)
		(placement
			(enabled no)
			(sheetname "")
		)
		(fill yes
			(thermal_gap 0.5)
			(thermal_bridge_width 0.5)
			(island_removal_mode 0)
		)
		(polygon
			(pts
				(arc
					(start 439.434224 -311.23509)
					(mid 438.766204 -311.23509)
					(end 439.434224 -311.23509)
				)
			)
		)
	)
	(zone
		(layers "B.Cu" "In6.Cu" "In11.Cu" "In13.Cu" "In15.Cu")
		(hatch none 0.5)
		(connect_pads
			(clearance 0)
		)
		(min_thickness 0.25)
		(keepout
			(tracks not_allowed)
			(vias allowed)
			(pads allowed)
			(copperpour not_allowed)
			(footprints allowed)
		)
		(placement
			(enabled no)
			(sheetname "")
		)
		(fill yes
			(thermal_gap 0.5)
			(thermal_bridge_width 0.5)
			(island_removal_mode 0)
		)
		(polygon
			(pts
				(arc
					(start 117.606318 -385.31038)
					(mid 116.976398 -385.31038)
					(end 117.606318 -385.31038)
				)
			)
		)
	)
	(zone
		(layers "B.Cu" "In6.Cu" "In11.Cu" "In13.Cu" "In15.Cu")
		(hatch none 0.5)
		(connect_pads
			(clearance 0)
		)
		(min_thickness 0.25)
		(keepout
			(tracks not_allowed)
			(vias allowed)
			(pads allowed)
			(copperpour not_allowed)
			(footprints allowed)
		)
		(placement
			(enabled no)
			(sheetname "")
		)
		(fill yes
			(thermal_gap 0.5)
			(thermal_bridge_width 0.5)
			(island_removal_mode 0)
		)
		(polygon
			(pts
				(arc
					(start 166.134034 -389.467344)
					(mid 165.504114 -389.467344)
					(end 166.134034 -389.467344)
				)
			)
		)
	)
	(zone
		(layers "B.Cu" "In6.Cu" "In11.Cu" "In13.Cu" "In15.Cu")
		(hatch none 0.5)
		(connect_pads
			(clearance 0)
		)
		(min_thickness 0.25)
		(keepout
			(tracks not_allowed)
			(vias allowed)
			(pads allowed)
			(copperpour not_allowed)
			(footprints allowed)
		)
		(placement
			(enabled no)
			(sheetname "")
		)
		(fill yes
			(thermal_gap 0.5)
			(thermal_bridge_width 0.5)
			(island_removal_mode 0)
		)
		(polygon
			(pts
				(arc
					(start 373.606314 -393.69238)
					(mid 372.976394 -393.69238)
					(end 373.606314 -393.69238)
				)
			)
		)
	)
	(zone
		(layers "B.Cu" "In6.Cu" "In11.Cu" "In13.Cu" "In15.Cu")
		(hatch none 0.5)
		(connect_pads
			(clearance 0)
		)
		(min_thickness 0.25)
		(keepout
			(tracks not_allowed)
			(vias allowed)
			(pads allowed)
			(copperpour not_allowed)
			(footprints allowed)
		)
		(placement
			(enabled no)
			(sheetname "")
		)
		(fill yes
			(thermal_gap 0.5)
			(thermal_bridge_width 0.5)
			(island_removal_mode 0)
		)
		(polygon
			(pts
				(arc
					(start 122.729752 -287.856422)
					(mid 122.099832 -287.856422)
					(end 122.729752 -287.856422)
				)
			)
		)
	)
	(zone
		(layers "B.Cu" "In6.Cu" "In11.Cu" "In13.Cu" "In15.Cu")
		(hatch none 0.5)
		(connect_pads
			(clearance 0)
		)
		(min_thickness 0.25)
		(keepout
			(tracks not_allowed)
			(vias allowed)
			(pads allowed)
			(copperpour not_allowed)
			(footprints allowed)
		)
		(placement
			(enabled no)
			(sheetname "")
		)
		(fill yes
			(thermal_gap 0.5)
			(thermal_bridge_width 0.5)
			(island_removal_mode 0)
		)
		(polygon
			(pts
				(arc
					(start 31.0134 -6.725158)
					(mid 30.34538 -6.725158)
					(end 31.0134 -6.725158)
				)
			)
		)
	)
	(zone
		(layers "B.Cu" "In6.Cu" "In11.Cu" "In13.Cu" "In15.Cu")
		(hatch none 0.5)
		(connect_pads
			(clearance 0)
		)
		(min_thickness 0.25)
		(keepout
			(tracks not_allowed)
			(vias allowed)
			(pads allowed)
			(copperpour not_allowed)
			(footprints allowed)
		)
		(placement
			(enabled no)
			(sheetname "")
		)
		(fill yes
			(thermal_gap 0.5)
			(thermal_bridge_width 0.5)
			(island_removal_mode 0)
		)
		(polygon
			(pts
				(arc
					(start 92.355924 -228.284532)
					(mid 91.726004 -228.284532)
					(end 92.355924 -228.284532)
				)
			)
		)
	)
	(zone
		(layers "B.Cu" "In6.Cu" "In11.Cu" "In13.Cu" "In15.Cu")
		(hatch none 0.5)
		(connect_pads
			(clearance 0)
		)
		(min_thickness 0.25)
		(keepout
			(tracks not_allowed)
			(vias allowed)
			(pads allowed)
			(copperpour not_allowed)
			(footprints allowed)
		)
		(placement
			(enabled no)
			(sheetname "")
		)
		(fill yes
			(thermal_gap 0.5)
			(thermal_bridge_width 0.5)
			(island_removal_mode 0)
		)
		(polygon
			(pts
				(arc
					(start 439.434224 -284.88513)
					(mid 438.766204 -284.88513)
					(end 439.434224 -284.88513)
				)
			)
		)
	)
	(zone
		(layers "B.Cu" "In6.Cu" "In11.Cu" "In13.Cu" "In15.Cu")
		(hatch none 0.5)
		(connect_pads
			(clearance 0)
		)
		(min_thickness 0.25)
		(keepout
			(tracks not_allowed)
			(vias allowed)
			(pads allowed)
			(copperpour not_allowed)
			(footprints allowed)
		)
		(placement
			(enabled no)
			(sheetname "")
		)
		(fill yes
			(thermal_gap 0.5)
			(thermal_bridge_width 0.5)
			(island_removal_mode 0)
		)
		(polygon
			(pts
				(arc
					(start 127.606298 -386.003292)
					(mid 126.976378 -386.003292)
					(end 127.606298 -386.003292)
				)
			)
		)
	)
	(zone
		(layers "B.Cu" "In6.Cu" "In11.Cu" "In13.Cu" "In15.Cu")
		(hatch none 0.5)
		(connect_pads
			(clearance 0)
		)
		(min_thickness 0.25)
		(keepout
			(tracks not_allowed)
			(vias allowed)
			(pads allowed)
			(copperpour not_allowed)
			(footprints allowed)
		)
		(placement
			(enabled no)
			(sheetname "")
		)
		(fill yes
			(thermal_gap 0.5)
			(thermal_bridge_width 0.5)
			(island_removal_mode 0)
		)
		(polygon
			(pts
				(arc
					(start 389.206232 -393.69238)
					(mid 388.576312 -393.69238)
					(end 389.206232 -393.69238)
				)
			)
		)
	)
	(zone
		(layers "B.Cu" "In6.Cu" "In11.Cu" "In13.Cu" "In15.Cu")
		(hatch none 0.5)
		(connect_pads
			(clearance 0)
		)
		(min_thickness 0.25)
		(keepout
			(tracks not_allowed)
			(vias allowed)
			(pads allowed)
			(copperpour not_allowed)
			(footprints allowed)
		)
		(placement
			(enabled no)
			(sheetname "")
		)
		(fill yes
			(thermal_gap 0.5)
			(thermal_bridge_width 0.5)
			(island_removal_mode 0)
		)
		(polygon
			(pts
				(arc
					(start 107.696 -287.856422)
					(mid 107.06608 -287.856422)
					(end 107.696 -287.856422)
				)
			)
		)
	)
	(zone
		(layers "B.Cu" "In6.Cu" "In11.Cu" "In13.Cu" "In15.Cu")
		(hatch none 0.5)
		(connect_pads
			(clearance 0)
		)
		(min_thickness 0.25)
		(keepout
			(tracks not_allowed)
			(vias allowed)
			(pads allowed)
			(copperpour not_allowed)
			(footprints allowed)
		)
		(placement
			(enabled no)
			(sheetname "")
		)
		(fill yes
			(thermal_gap 0.5)
			(thermal_bridge_width 0.5)
			(island_removal_mode 0)
		)
		(polygon
			(pts
				(arc
					(start 147.73402 -388.774432)
					(mid 147.1041 -388.774432)
					(end 147.73402 -388.774432)
				)
			)
		)
	)
	(zone
		(layers "B.Cu" "In6.Cu" "In11.Cu" "In13.Cu" "In15.Cu")
		(hatch none 0.5)
		(connect_pads
			(clearance 0)
		)
		(min_thickness 0.25)
		(keepout
			(tracks not_allowed)
			(vias allowed)
			(pads allowed)
			(copperpour not_allowed)
			(footprints allowed)
		)
		(placement
			(enabled no)
			(sheetname "")
		)
		(fill yes
			(thermal_gap 0.5)
			(thermal_bridge_width 0.5)
			(island_removal_mode 0)
		)
		(polygon
			(pts
				(arc
					(start 285.070042 -303.585118)
					(mid 284.402022 -303.585118)
					(end 285.070042 -303.585118)
				)
			)
		)
	)
	(zone
		(layers "B.Cu" "In6.Cu" "In11.Cu" "In13.Cu" "In15.Cu")
		(hatch none 0.5)
		(connect_pads
			(clearance 0)
		)
		(min_thickness 0.25)
		(keepout
			(tracks not_allowed)
			(vias allowed)
			(pads allowed)
			(copperpour not_allowed)
			(footprints allowed)
		)
		(placement
			(enabled no)
			(sheetname "")
		)
		(fill yes
			(thermal_gap 0.5)
			(thermal_bridge_width 0.5)
			(island_removal_mode 0)
		)
		(polygon
			(pts
				(arc
					(start 435.334156 -286.585152)
					(mid 434.666136 -286.585152)
					(end 435.334156 -286.585152)
				)
			)
		)
	)
	(zone
		(layers "B.Cu" "In6.Cu" "In11.Cu" "In13.Cu" "In15.Cu")
		(hatch none 0.5)
		(connect_pads
			(clearance 0)
		)
		(min_thickness 0.25)
		(keepout
			(tracks not_allowed)
			(vias allowed)
			(pads allowed)
			(copperpour not_allowed)
			(footprints allowed)
		)
		(placement
			(enabled no)
			(sheetname "")
		)
		(fill yes
			(thermal_gap 0.5)
			(thermal_bridge_width 0.5)
			(island_removal_mode 0)
		)
		(polygon
			(pts
				(arc
					(start 285.070042 -252.584966)
					(mid 284.402022 -252.584966)
					(end 285.070042 -252.584966)
				)
			)
		)
	)
	(zone
		(layers "B.Cu" "In6.Cu" "In11.Cu" "In13.Cu" "In15.Cu")
		(hatch none 0.5)
		(connect_pads
			(clearance 0)
		)
		(min_thickness 0.25)
		(keepout
			(tracks not_allowed)
			(vias allowed)
			(pads allowed)
			(copperpour not_allowed)
			(footprints allowed)
		)
		(placement
			(enabled no)
			(sheetname "")
		)
		(fill yes
			(thermal_gap 0.5)
			(thermal_bridge_width 0.5)
			(island_removal_mode 0)
		)
		(polygon
			(pts
				(arc
					(start 33.029906 -232.18521)
					(mid 32.361886 -232.18521)
					(end 33.029906 -232.18521)
				)
			)
		)
	)
	(zone
		(layers "B.Cu" "In6.Cu" "In11.Cu" "In13.Cu" "In15.Cu")
		(hatch none 0.5)
		(connect_pads
			(clearance 0)
		)
		(min_thickness 0.25)
		(keepout
			(tracks not_allowed)
			(vias allowed)
			(pads allowed)
			(copperpour not_allowed)
			(footprints allowed)
		)
		(placement
			(enabled no)
			(sheetname "")
		)
		(fill yes
			(thermal_gap 0.5)
			(thermal_bridge_width 0.5)
			(island_removal_mode 0)
		)
		(polygon
			(pts
				(arc
					(start 191.494156 -296.785284)
					(mid 190.826136 -296.785284)
					(end 191.494156 -296.785284)
				)
			)
		)
	)
	(zone
		(layers "B.Cu" "In6.Cu" "In11.Cu" "In13.Cu" "In15.Cu")
		(hatch none 0.5)
		(connect_pads
			(clearance 0)
		)
		(min_thickness 0.25)
		(keepout
			(tracks not_allowed)
			(vias allowed)
			(pads allowed)
			(copperpour not_allowed)
			(footprints allowed)
		)
		(placement
			(enabled no)
			(sheetname "")
		)
		(fill yes
			(thermal_gap 0.5)
			(thermal_bridge_width 0.5)
			(island_removal_mode 0)
		)
		(polygon
			(pts
				(arc
					(start 43.723306 -6.725158)
					(mid 43.055286 -6.725158)
					(end 43.723306 -6.725158)
				)
			)
		)
	)
	(zone
		(layers "B.Cu" "In6.Cu" "In11.Cu" "In13.Cu" "In15.Cu")
		(hatch none 0.5)
		(connect_pads
			(clearance 0)
		)
		(min_thickness 0.25)
		(keepout
			(tracks not_allowed)
			(vias allowed)
			(pads allowed)
			(copperpour not_allowed)
			(footprints allowed)
		)
		(placement
			(enabled no)
			(sheetname "")
		)
		(fill yes
			(thermal_gap 0.5)
			(thermal_bridge_width 0.5)
			(island_removal_mode 0)
		)
		(polygon
			(pts
				(arc
					(start 92.826078 -230.71455)
					(mid 92.196158 -230.71455)
					(end 92.826078 -230.71455)
				)
			)
		)
	)
	(zone
		(layers "B.Cu" "In6.Cu" "In11.Cu" "In13.Cu" "In15.Cu")
		(hatch none 0.5)
		(connect_pads
			(clearance 0)
		)
		(min_thickness 0.25)
		(keepout
			(tracks not_allowed)
			(vias allowed)
			(pads allowed)
			(copperpour not_allowed)
			(footprints allowed)
		)
		(placement
			(enabled no)
			(sheetname "")
		)
		(fill yes
			(thermal_gap 0.5)
			(thermal_bridge_width 0.5)
			(island_removal_mode 0)
		)
		(polygon
			(pts
				(arc
					(start 37.129974 -311.235344)
					(mid 36.461954 -311.235344)
					(end 37.129974 -311.235344)
				)
			)
		)
	)
	(zone
		(layers "B.Cu" "In6.Cu" "In11.Cu" "In13.Cu" "In15.Cu")
		(hatch none 0.5)
		(connect_pads
			(clearance 0)
		)
		(min_thickness 0.25)
		(keepout
			(tracks not_allowed)
			(vias allowed)
			(pads allowed)
			(copperpour not_allowed)
			(footprints allowed)
		)
		(placement
			(enabled no)
			(sheetname "")
		)
		(fill yes
			(thermal_gap 0.5)
			(thermal_bridge_width 0.5)
			(island_removal_mode 0)
		)
		(polygon
			(pts
				(arc
					(start 380.709678 -254.204216)
					(mid 380.079758 -254.204216)
					(end 380.709678 -254.204216)
				)
			)
		)
	)
	(zone
		(layers "B.Cu" "In6.Cu" "In11.Cu" "In13.Cu" "In15.Cu")
		(hatch none 0.5)
		(connect_pads
			(clearance 0)
		)
		(min_thickness 0.25)
		(keepout
			(tracks not_allowed)
			(vias allowed)
			(pads allowed)
			(copperpour not_allowed)
			(footprints allowed)
		)
		(placement
			(enabled no)
			(sheetname "")
		)
		(fill yes
			(thermal_gap 0.5)
			(thermal_bridge_width 0.5)
			(island_removal_mode 0)
		)
		(polygon
			(pts
				(arc
					(start 348.056454 -377.41733)
					(mid 347.388434 -377.41733)
					(end 348.056454 -377.41733)
				)
			)
		)
	)
	(zone
		(layers "B.Cu" "In6.Cu" "In11.Cu" "In13.Cu" "In15.Cu")
		(hatch none 0.5)
		(connect_pads
			(clearance 0)
		)
		(min_thickness 0.25)
		(keepout
			(tracks not_allowed)
			(vias allowed)
			(pads allowed)
			(copperpour not_allowed)
			(footprints allowed)
		)
		(placement
			(enabled no)
			(sheetname "")
		)
		(fill yes
			(thermal_gap 0.5)
			(thermal_bridge_width 0.5)
			(island_removal_mode 0)
		)
		(polygon
			(pts
				(arc
					(start 373.489728 -286.236156)
					(mid 372.859808 -286.236156)
					(end 373.489728 -286.236156)
				)
			)
		)
	)
	(zone
		(layers "B.Cu" "In6.Cu" "In11.Cu" "In13.Cu" "In15.Cu")
		(hatch none 0.5)
		(connect_pads
			(clearance 0)
		)
		(min_thickness 0.25)
		(keepout
			(tracks not_allowed)
			(vias allowed)
			(pads allowed)
			(copperpour not_allowed)
			(footprints allowed)
		)
		(placement
			(enabled no)
			(sheetname "")
		)
		(fill yes
			(thermal_gap 0.5)
			(thermal_bridge_width 0.5)
			(island_removal_mode 0)
		)
		(polygon
			(pts
				(arc
					(start 435.334156 -305.28514)
					(mid 434.666136 -305.28514)
					(end 435.334156 -305.28514)
				)
			)
		)
	)
	(zone
		(layers "B.Cu" "In6.Cu" "In11.Cu" "In13.Cu" "In15.Cu")
		(hatch none 0.5)
		(connect_pads
			(clearance 0)
		)
		(min_thickness 0.25)
		(keepout
			(tracks not_allowed)
			(vias allowed)
			(pads allowed)
			(copperpour not_allowed)
			(footprints allowed)
		)
		(placement
			(enabled no)
			(sheetname "")
		)
		(fill yes
			(thermal_gap 0.5)
			(thermal_bridge_width 0.5)
			(island_removal_mode 0)
		)
		(polygon
			(pts
				(arc
					(start 107.396026 -231.524302)
					(mid 106.766106 -231.524302)
					(end 107.396026 -231.524302)
				)
			)
		)
	)
	(zone
		(layers "B.Cu" "In6.Cu" "In11.Cu" "In13.Cu" "In15.Cu")
		(hatch none 0.5)
		(connect_pads
			(clearance 0)
		)
		(min_thickness 0.25)
		(keepout
			(tracks not_allowed)
			(vias allowed)
			(pads allowed)
			(copperpour not_allowed)
			(footprints allowed)
		)
		(placement
			(enabled no)
			(sheetname "")
		)
		(fill yes
			(thermal_gap 0.5)
			(thermal_bridge_width 0.5)
			(island_removal_mode 0)
		)
		(polygon
			(pts
				(arc
					(start 341.06612 -282.186126)
					(mid 340.4362 -282.186126)
					(end 341.06612 -282.186126)
				)
			)
		)
	)
	(zone
		(layers "B.Cu" "In6.Cu" "In11.Cu" "In13.Cu" "In15.Cu")
		(hatch none 0.5)
		(connect_pads
			(clearance 0)
		)
		(min_thickness 0.25)
		(keepout
			(tracks not_allowed)
			(vias allowed)
			(pads allowed)
			(copperpour not_allowed)
			(footprints allowed)
		)
		(placement
			(enabled no)
			(sheetname "")
		)
		(fill yes
			(thermal_gap 0.5)
			(thermal_bridge_width 0.5)
			(island_removal_mode 0)
		)
		(polygon
			(pts
				(arc
					(start 91.716098 -289.47618)
					(mid 91.086178 -289.47618)
					(end 91.716098 -289.47618)
				)
			)
		)
	)
	(zone
		(layers "B.Cu" "In6.Cu" "In11.Cu" "In13.Cu" "In15.Cu")
		(hatch none 0.5)
		(connect_pads
			(clearance 0)
		)
		(min_thickness 0.25)
		(keepout
			(tracks not_allowed)
			(vias allowed)
			(pads allowed)
			(copperpour not_allowed)
			(footprints allowed)
		)
		(placement
			(enabled no)
			(sheetname "")
		)
		(fill yes
			(thermal_gap 0.5)
			(thermal_bridge_width 0.5)
			(island_removal_mode 0)
		)
		(polygon
			(pts
				(arc
					(start 304.127916 -412.84652)
					(mid 303.459896 -412.84652)
					(end 304.127916 -412.84652)
				)
			)
		)
	)
	(zone
		(layers "B.Cu" "In6.Cu" "In11.Cu" "In13.Cu" "In15.Cu")
		(hatch none 0.5)
		(connect_pads
			(clearance 0)
		)
		(min_thickness 0.25)
		(keepout
			(tracks not_allowed)
			(vias allowed)
			(pads allowed)
			(copperpour not_allowed)
			(footprints allowed)
		)
		(placement
			(enabled no)
			(sheetname "")
		)
		(fill yes
			(thermal_gap 0.5)
			(thermal_bridge_width 0.5)
			(island_removal_mode 0)
		)
		(polygon
			(pts
				(arc
					(start 131.20624 -386.003292)
					(mid 130.57632 -386.003292)
					(end 131.20624 -386.003292)
				)
			)
		)
	)
	(zone
		(layers "B.Cu" "In6.Cu" "In11.Cu" "In13.Cu" "In15.Cu")
		(hatch none 0.5)
		(connect_pads
			(clearance 0)
		)
		(min_thickness 0.25)
		(keepout
			(tracks not_allowed)
			(vias allowed)
			(pads allowed)
			(copperpour not_allowed)
			(footprints allowed)
		)
		(placement
			(enabled no)
			(sheetname "")
		)
		(fill yes
			(thermal_gap 0.5)
			(thermal_bridge_width 0.5)
			(island_removal_mode 0)
		)
		(polygon
			(pts
				(arc
					(start 285.070042 -254.284988)
					(mid 284.402022 -254.284988)
					(end 285.070042 -254.284988)
				)
			)
		)
	)
	(zone
		(layers "B.Cu" "In6.Cu" "In11.Cu" "In13.Cu" "In15.Cu")
		(hatch none 0.5)
		(connect_pads
			(clearance 0)
		)
		(min_thickness 0.25)
		(keepout
			(tracks not_allowed)
			(vias allowed)
			(pads allowed)
			(copperpour not_allowed)
			(footprints allowed)
		)
		(placement
			(enabled no)
			(sheetname "")
		)
		(fill yes
			(thermal_gap 0.5)
			(thermal_bridge_width 0.5)
			(island_removal_mode 0)
		)
		(polygon
			(pts
				(arc
					(start 379.599698 -282.186126)
					(mid 378.969778 -282.186126)
					(end 379.599698 -282.186126)
				)
			)
		)
	)
	(zone
		(layers "B.Cu" "In6.Cu" "In11.Cu" "In13.Cu" "In15.Cu")
		(hatch none 0.5)
		(connect_pads
			(clearance 0)
		)
		(min_thickness 0.25)
		(keepout
			(tracks not_allowed)
			(vias allowed)
			(pads allowed)
			(copperpour not_allowed)
			(footprints allowed)
		)
		(placement
			(enabled no)
			(sheetname "")
		)
		(fill yes
			(thermal_gap 0.5)
			(thermal_bridge_width 0.5)
			(island_removal_mode 0)
		)
		(polygon
			(pts
				(arc
					(start 119.609616 -229.90429)
					(mid 118.979696 -229.90429)
					(end 119.609616 -229.90429)
				)
			)
		)
	)
	(zone
		(layers "B.Cu" "In6.Cu" "In11.Cu" "In13.Cu" "In15.Cu")
		(hatch none 0.5)
		(connect_pads
			(clearance 0)
		)
		(min_thickness 0.25)
		(keepout
			(tracks not_allowed)
			(vias allowed)
			(pads allowed)
			(copperpour not_allowed)
			(footprints allowed)
		)
		(placement
			(enabled no)
			(sheetname "")
		)
		(fill yes
			(thermal_gap 0.5)
			(thermal_bridge_width 0.5)
			(island_removal_mode 0)
		)
		(polygon
			(pts
				(arc
					(start 380.417832 -412.84652)
					(mid 379.749812 -412.84652)
					(end 380.417832 -412.84652)
				)
			)
		)
	)
	(zone
		(layers "B.Cu" "In6.Cu" "In11.Cu" "In13.Cu" "In15.Cu")
		(hatch none 0.5)
		(connect_pads
			(clearance 0)
		)
		(min_thickness 0.25)
		(keepout
			(tracks not_allowed)
			(vias allowed)
			(pads allowed)
			(copperpour not_allowed)
			(footprints allowed)
		)
		(placement
			(enabled no)
			(sheetname "")
		)
		(fill yes
			(thermal_gap 0.5)
			(thermal_bridge_width 0.5)
			(island_removal_mode 0)
		)
		(polygon
			(pts
				(arc
					(start 349.696024 -228.284278)
					(mid 349.066104 -228.284278)
					(end 349.696024 -228.284278)
				)
			)
		)
	)
	(zone
		(layers "B.Cu" "In6.Cu" "In11.Cu" "In13.Cu" "In15.Cu")
		(hatch none 0.5)
		(connect_pads
			(clearance 0)
		)
		(min_thickness 0.25)
		(keepout
			(tracks not_allowed)
			(vias allowed)
			(pads allowed)
			(copperpour not_allowed)
			(footprints allowed)
		)
		(placement
			(enabled no)
			(sheetname "")
		)
		(fill yes
			(thermal_gap 0.5)
			(thermal_bridge_width 0.5)
			(island_removal_mode 0)
		)
		(polygon
			(pts
				(arc
					(start 117.089682 -291.096192)
					(mid 116.459762 -291.096192)
					(end 117.089682 -291.096192)
				)
			)
		)
	)
	(zone
		(layers "B.Cu" "In6.Cu" "In11.Cu" "In13.Cu" "In15.Cu")
		(hatch none 0.5)
		(connect_pads
			(clearance 0)
		)
		(min_thickness 0.25)
		(keepout
			(tracks not_allowed)
			(vias allowed)
			(pads allowed)
			(copperpour not_allowed)
			(footprints allowed)
		)
		(placement
			(enabled no)
			(sheetname "")
		)
		(fill yes
			(thermal_gap 0.5)
			(thermal_bridge_width 0.5)
			(island_removal_mode 0)
		)
		(polygon
			(pts
				(arc
					(start 379.599698 -280.566114)
					(mid 378.969778 -280.566114)
					(end 379.599698 -280.566114)
				)
			)
		)
	)
	(zone
		(layers "B.Cu" "In6.Cu" "In11.Cu" "In13.Cu" "In15.Cu")
		(hatch none 0.5)
		(connect_pads
			(clearance 0)
		)
		(min_thickness 0.25)
		(keepout
			(tracks not_allowed)
			(vias allowed)
			(pads allowed)
			(copperpour not_allowed)
			(footprints allowed)
		)
		(placement
			(enabled no)
			(sheetname "")
		)
		(fill yes
			(thermal_gap 0.5)
			(thermal_bridge_width 0.5)
			(island_removal_mode 0)
		)
		(polygon
			(pts
				(arc
					(start 309.30596 -397.849344)
					(mid 308.67604 -397.849344)
					(end 309.30596 -397.849344)
				)
			)
		)
	)
	(zone
		(layers "B.Cu" "In6.Cu" "In11.Cu" "In13.Cu" "In15.Cu")
		(hatch none 0.5)
		(connect_pads
			(clearance 0)
		)
		(min_thickness 0.25)
		(keepout
			(tracks not_allowed)
			(vias allowed)
			(pads allowed)
			(copperpour not_allowed)
			(footprints allowed)
		)
		(placement
			(enabled no)
			(sheetname "")
		)
		(fill yes
			(thermal_gap 0.5)
			(thermal_bridge_width 0.5)
			(island_removal_mode 0)
		)
		(polygon
			(pts
				(arc
					(start 378.406152 -393.69238)
					(mid 377.776232 -393.69238)
					(end 378.406152 -393.69238)
				)
			)
		)
	)
	(zone
		(layers "B.Cu" "In6.Cu" "In11.Cu" "In13.Cu" "In15.Cu")
		(hatch none 0.5)
		(connect_pads
			(clearance 0)
		)
		(min_thickness 0.25)
		(keepout
			(tracks not_allowed)
			(vias allowed)
			(pads allowed)
			(copperpour not_allowed)
			(footprints allowed)
		)
		(placement
			(enabled no)
			(sheetname "")
		)
		(fill yes
			(thermal_gap 0.5)
			(thermal_bridge_width 0.5)
			(island_removal_mode 0)
		)
		(polygon
			(pts
				(arc
					(start 285.070042 -227.085144)
					(mid 284.402022 -227.085144)
					(end 285.070042 -227.085144)
				)
			)
		)
	)
	(zone
		(layers "B.Cu" "In6.Cu" "In11.Cu" "In13.Cu" "In15.Cu")
		(hatch none 0.5)
		(connect_pads
			(clearance 0)
		)
		(min_thickness 0.25)
		(keepout
			(tracks not_allowed)
			(vias allowed)
			(pads allowed)
			(copperpour not_allowed)
			(footprints allowed)
		)
		(placement
			(enabled no)
			(sheetname "")
		)
		(fill yes
			(thermal_gap 0.5)
			(thermal_bridge_width 0.5)
			(island_removal_mode 0)
		)
		(polygon
			(pts
				(arc
					(start 325.570596 -412.84652)
					(mid 324.902576 -412.84652)
					(end 325.570596 -412.84652)
				)
			)
		)
	)
	(zone
		(layers "B.Cu" "In6.Cu" "In11.Cu" "In13.Cu" "In15.Cu")
		(hatch none 0.5)
		(connect_pads
			(clearance 0)
		)
		(min_thickness 0.25)
		(keepout
			(tracks not_allowed)
			(vias allowed)
			(pads allowed)
			(copperpour not_allowed)
			(footprints allowed)
		)
		(placement
			(enabled no)
			(sheetname "")
		)
		(fill yes
			(thermal_gap 0.5)
			(thermal_bridge_width 0.5)
			(island_removal_mode 0)
		)
		(polygon
			(pts
				(arc
					(start 191.494156 -203.285344)
					(mid 190.826136 -203.285344)
					(end 191.494156 -203.285344)
				)
			)
		)
	)
	(zone
		(layers "B.Cu" "In6.Cu" "In11.Cu" "In13.Cu" "In15.Cu")
		(hatch none 0.5)
		(connect_pads
			(clearance 0)
		)
		(min_thickness 0.25)
		(keepout
			(tracks not_allowed)
			(vias allowed)
			(pads allowed)
			(copperpour not_allowed)
			(footprints allowed)
		)
		(placement
			(enabled no)
			(sheetname "")
		)
		(fill yes
			(thermal_gap 0.5)
			(thermal_bridge_width 0.5)
			(island_removal_mode 0)
		)
		(polygon
			(pts
				(arc
					(start 341.06612 -290.285932)
					(mid 340.4362 -290.285932)
					(end 341.06612 -290.285932)
				)
			)
		)
	)
	(zone
		(layers "B.Cu" "In6.Cu" "In11.Cu" "In13.Cu" "In15.Cu")
		(hatch none 0.5)
		(connect_pads
			(clearance 0)
		)
		(min_thickness 0.25)
		(keepout
			(tracks not_allowed)
			(vias allowed)
			(pads allowed)
			(copperpour not_allowed)
			(footprints allowed)
		)
		(placement
			(enabled no)
			(sheetname "")
		)
		(fill yes
			(thermal_gap 0.5)
			(thermal_bridge_width 0.5)
			(island_removal_mode 0)
		)
		(polygon
			(pts
				(arc
					(start 191.494156 -219.435426)
					(mid 190.826136 -219.435426)
					(end 191.494156 -219.435426)
				)
			)
		)
	)
	(zone
		(layers "B.Cu" "In6.Cu" "In11.Cu" "In13.Cu" "In15.Cu")
		(hatch none 0.5)
		(connect_pads
			(clearance 0)
		)
		(min_thickness 0.25)
		(keepout
			(tracks not_allowed)
			(vias allowed)
			(pads allowed)
			(copperpour not_allowed)
			(footprints allowed)
		)
		(placement
			(enabled no)
			(sheetname "")
		)
		(fill yes
			(thermal_gap 0.5)
			(thermal_bridge_width 0.5)
			(island_removal_mode 0)
		)
		(polygon
			(pts
				(arc
					(start 348.75597 -226.664266)
					(mid 348.12605 -226.664266)
					(end 348.75597 -226.664266)
				)
			)
		)
	)
	(zone
		(layers "B.Cu" "In6.Cu" "In11.Cu" "In13.Cu" "In15.Cu")
		(hatch none 0.5)
		(connect_pads
			(clearance 0)
		)
		(min_thickness 0.25)
		(keepout
			(tracks not_allowed)
			(vias allowed)
			(pads allowed)
			(copperpour not_allowed)
			(footprints allowed)
		)
		(placement
			(enabled no)
			(sheetname "")
		)
		(fill yes
			(thermal_gap 0.5)
			(thermal_bridge_width 0.5)
			(island_removal_mode 0)
		)
		(polygon
			(pts
				(arc
					(start 131.65963 -265.98626)
					(mid 131.02971 -265.98626)
					(end 131.65963 -265.98626)
				)
			)
		)
	)
	(zone
		(layers "B.Cu" "In6.Cu" "In11.Cu" "In13.Cu" "In15.Cu")
		(hatch none 0.5)
		(connect_pads
			(clearance 0)
		)
		(min_thickness 0.25)
		(keepout
			(tracks not_allowed)
			(vias allowed)
			(pads allowed)
			(copperpour not_allowed)
			(footprints allowed)
		)
		(placement
			(enabled no)
			(sheetname "")
		)
		(fill yes
			(thermal_gap 0.5)
			(thermal_bridge_width 0.5)
			(island_removal_mode 0)
		)
		(polygon
			(pts
				(arc
					(start 341.06612 -280.566114)
					(mid 340.4362 -280.566114)
					(end 341.06612 -280.566114)
				)
			)
		)
	)
	(zone
		(layers "B.Cu" "In6.Cu" "In11.Cu" "In13.Cu" "In15.Cu")
		(hatch none 0.5)
		(connect_pads
			(clearance 0)
		)
		(min_thickness 0.25)
		(keepout
			(tracks not_allowed)
			(vias allowed)
			(pads allowed)
			(copperpour not_allowed)
			(footprints allowed)
		)
		(placement
			(enabled no)
			(sheetname "")
		)
		(fill yes
			(thermal_gap 0.5)
			(thermal_bridge_width 0.5)
			(island_removal_mode 0)
		)
		(polygon
			(pts
				(arc
					(start 37.129974 -204.985366)
					(mid 36.461954 -204.985366)
					(end 37.129974 -204.985366)
				)
			)
		)
	)
	(zone
		(layers "B.Cu" "In6.Cu" "In11.Cu" "In13.Cu" "In15.Cu")
		(hatch none 0.5)
		(connect_pads
			(clearance 0)
		)
		(min_thickness 0.25)
		(keepout
			(tracks not_allowed)
			(vias allowed)
			(pads allowed)
			(copperpour not_allowed)
			(footprints allowed)
		)
		(placement
			(enabled no)
			(sheetname "")
		)
		(fill yes
			(thermal_gap 0.5)
			(thermal_bridge_width 0.5)
			(island_removal_mode 0)
		)
		(polygon
			(pts
				(arc
					(start 439.434224 -204.985112)
					(mid 438.766204 -204.985112)
					(end 439.434224 -204.985112)
				)
			)
		)
	)
	(zone
		(layers "B.Cu" "In6.Cu" "In11.Cu" "In13.Cu" "In15.Cu")
		(hatch none 0.5)
		(connect_pads
			(clearance 0)
		)
		(min_thickness 0.25)
		(keepout
			(tracks not_allowed)
			(vias allowed)
			(pads allowed)
			(copperpour not_allowed)
			(footprints allowed)
		)
		(placement
			(enabled no)
			(sheetname "")
		)
		(fill yes
			(thermal_gap 0.5)
			(thermal_bridge_width 0.5)
			(island_removal_mode 0)
		)
		(polygon
			(pts
				(arc
					(start 214.28329 -5.509006)
					(mid 213.61527 -5.509006)
					(end 214.28329 -5.509006)
				)
			)
		)
	)
	(zone
		(layers "B.Cu" "In6.Cu" "In11.Cu" "In13.Cu" "In15.Cu")
		(hatch none 0.5)
		(connect_pads
			(clearance 0)
		)
		(min_thickness 0.25)
		(keepout
			(tracks not_allowed)
			(vias allowed)
			(pads allowed)
			(copperpour not_allowed)
			(footprints allowed)
		)
		(placement
			(enabled no)
			(sheetname "")
		)
		(fill yes
			(thermal_gap 0.5)
			(thermal_bridge_width 0.5)
			(island_removal_mode 0)
		)
		(polygon
			(pts
				(arc
					(start 405.201374 -19.13636)
					(mid 404.533354 -19.13636)
					(end 405.201374 -19.13636)
				)
			)
		)
	)
	(zone
		(layers "B.Cu" "In6.Cu" "In11.Cu" "In13.Cu" "In15.Cu")
		(hatch none 0.5)
		(connect_pads
			(clearance 0)
		)
		(min_thickness 0.25)
		(keepout
			(tracks not_allowed)
			(vias allowed)
			(pads allowed)
			(copperpour not_allowed)
			(footprints allowed)
		)
		(placement
			(enabled no)
			(sheetname "")
		)
		(fill yes
			(thermal_gap 0.5)
			(thermal_bridge_width 0.5)
			(island_removal_mode 0)
		)
		(polygon
			(pts
				(arc
					(start 33.029906 -202.435206)
					(mid 32.361886 -202.435206)
					(end 33.029906 -202.435206)
				)
			)
		)
	)
	(zone
		(layers "B.Cu" "In6.Cu" "In11.Cu" "In13.Cu" "In15.Cu")
		(hatch none 0.5)
		(connect_pads
			(clearance 0)
		)
		(min_thickness 0.25)
		(keepout
			(tracks not_allowed)
			(vias allowed)
			(pads allowed)
			(copperpour not_allowed)
			(footprints allowed)
		)
		(placement
			(enabled no)
			(sheetname "")
		)
		(fill yes
			(thermal_gap 0.5)
			(thermal_bridge_width 0.5)
			(island_removal_mode 0)
		)
		(polygon
			(pts
				(arc
					(start 280.969974 -299.33519)
					(mid 280.301954 -299.33519)
					(end 280.969974 -299.33519)
				)
			)
		)
	)
	(zone
		(layers "B.Cu" "In6.Cu" "In11.Cu" "In13.Cu" "In15.Cu")
		(hatch none 0.5)
		(connect_pads
			(clearance 0)
		)
		(min_thickness 0.25)
		(keepout
			(tracks not_allowed)
			(vias allowed)
			(pads allowed)
			(copperpour not_allowed)
			(footprints allowed)
		)
		(placement
			(enabled no)
			(sheetname "")
		)
		(fill yes
			(thermal_gap 0.5)
			(thermal_bridge_width 0.5)
			(island_removal_mode 0)
		)
		(polygon
			(pts
				(arc
					(start 158.977076 -404.46452)
					(mid 158.309056 -404.46452)
					(end 158.977076 -404.46452)
				)
			)
		)
	)
	(zone
		(layers "B.Cu" "In6.Cu" "In11.Cu" "In13.Cu" "In15.Cu")
		(hatch none 0.5)
		(connect_pads
			(clearance 0)
		)
		(min_thickness 0.25)
		(keepout
			(tracks not_allowed)
			(vias allowed)
			(pads allowed)
			(copperpour not_allowed)
			(footprints allowed)
		)
		(placement
			(enabled no)
			(sheetname "")
		)
		(fill yes
			(thermal_gap 0.5)
			(thermal_bridge_width 0.5)
			(island_removal_mode 0)
		)
		(polygon
			(pts
				(arc
					(start 91.716098 -282.996386)
					(mid 91.086178 -282.996386)
					(end 91.716098 -282.996386)
				)
			)
		)
	)
	(zone
		(layers "B.Cu" "In6.Cu" "In11.Cu" "In13.Cu" "In15.Cu")
		(hatch none 0.5)
		(connect_pads
			(clearance 0)
		)
		(min_thickness 0.25)
		(keepout
			(tracks not_allowed)
			(vias allowed)
			(pads allowed)
			(copperpour not_allowed)
			(footprints allowed)
		)
		(placement
			(enabled no)
			(sheetname "")
		)
		(fill yes
			(thermal_gap 0.5)
			(thermal_bridge_width 0.5)
			(island_removal_mode 0)
		)
		(polygon
			(pts
				(arc
					(start 285.070042 -225.385122)
					(mid 284.402022 -225.385122)
					(end 285.070042 -225.385122)
				)
			)
		)
	)
	(zone
		(layers "B.Cu" "In6.Cu" "In11.Cu" "In13.Cu" "In15.Cu")
		(hatch none 0.5)
		(connect_pads
			(clearance 0)
		)
		(min_thickness 0.25)
		(keepout
			(tracks not_allowed)
			(vias allowed)
			(pads allowed)
			(copperpour not_allowed)
			(footprints allowed)
		)
		(placement
			(enabled no)
			(sheetname "")
		)
		(fill yes
			(thermal_gap 0.5)
			(thermal_bridge_width 0.5)
			(island_removal_mode 0)
		)
		(polygon
			(pts
				(arc
					(start 280.969974 -302.73498)
					(mid 280.301954 -302.73498)
					(end 280.969974 -302.73498)
				)
			)
		)
	)
	(zone
		(layers "B.Cu" "In6.Cu" "In11.Cu" "In13.Cu" "In15.Cu")
		(hatch none 0.5)
		(connect_pads
			(clearance 0)
		)
		(min_thickness 0.25)
		(keepout
			(tracks not_allowed)
			(vias allowed)
			(pads allowed)
			(copperpour not_allowed)
			(footprints allowed)
		)
		(placement
			(enabled no)
			(sheetname "")
		)
		(fill yes
			(thermal_gap 0.5)
			(thermal_bridge_width 0.5)
			(island_removal_mode 0)
		)
		(polygon
			(pts
				(arc
					(start 101.755956 -233.144314)
					(mid 101.126036 -233.144314)
					(end 101.755956 -233.144314)
				)
			)
		)
	)
	(zone
		(layers "B.Cu" "In6.Cu" "In11.Cu" "In13.Cu" "In15.Cu")
		(hatch none 0.5)
		(connect_pads
			(clearance 0)
		)
		(min_thickness 0.25)
		(keepout
			(tracks not_allowed)
			(vias allowed)
			(pads allowed)
			(copperpour not_allowed)
			(footprints allowed)
		)
		(placement
			(enabled no)
			(sheetname "")
		)
		(fill yes
			(thermal_gap 0.5)
			(thermal_bridge_width 0.5)
			(island_removal_mode 0)
		)
		(polygon
			(pts
				(arc
					(start 285.070042 -270.43507)
					(mid 284.402022 -270.43507)
					(end 285.070042 -270.43507)
				)
			)
		)
	)
	(zone
		(layers "B.Cu" "In6.Cu" "In11.Cu" "In13.Cu" "In15.Cu")
		(hatch none 0.5)
		(connect_pads
			(clearance 0)
		)
		(min_thickness 0.25)
		(keepout
			(tracks not_allowed)
			(vias allowed)
			(pads allowed)
			(copperpour not_allowed)
			(footprints allowed)
		)
		(placement
			(enabled no)
			(sheetname "")
		)
		(fill yes
			(thermal_gap 0.5)
			(thermal_bridge_width 0.5)
			(island_removal_mode 0)
		)
		(polygon
			(pts
				(arc
					(start 37.129974 -206.685388)
					(mid 36.461954 -206.685388)
					(end 37.129974 -206.685388)
				)
			)
		)
	)
	(zone
		(layers "B.Cu" "In6.Cu" "In11.Cu" "In13.Cu" "In15.Cu")
		(hatch none 0.5)
		(connect_pads
			(clearance 0)
		)
		(min_thickness 0.25)
		(keepout
			(tracks not_allowed)
			(vias allowed)
			(pads allowed)
			(copperpour not_allowed)
			(footprints allowed)
		)
		(placement
			(enabled no)
			(sheetname "")
		)
		(fill yes
			(thermal_gap 0.5)
			(thermal_bridge_width 0.5)
			(island_removal_mode 0)
		)
		(polygon
			(pts
				(arc
					(start 133.239764 -255.014476)
					(mid 132.609844 -255.014476)
					(end 133.239764 -255.014476)
				)
			)
		)
	)
	(zone
		(layers "B.Cu" "In6.Cu" "In11.Cu" "In13.Cu" "In15.Cu")
		(hatch none 0.5)
		(connect_pads
			(clearance 0)
		)
		(min_thickness 0.25)
		(keepout
			(tracks not_allowed)
			(vias allowed)
			(pads allowed)
			(copperpour not_allowed)
			(footprints allowed)
		)
		(placement
			(enabled no)
			(sheetname "")
		)
		(fill yes
			(thermal_gap 0.5)
			(thermal_bridge_width 0.5)
			(island_removal_mode 0)
		)
		(polygon
			(pts
				(arc
					(start 131.359656 -227.474526)
					(mid 130.729736 -227.474526)
					(end 131.359656 -227.474526)
				)
			)
		)
	)
	(zone
		(layers "B.Cu" "In6.Cu" "In11.Cu" "In13.Cu" "In15.Cu")
		(hatch none 0.5)
		(connect_pads
			(clearance 0)
		)
		(min_thickness 0.25)
		(keepout
			(tracks not_allowed)
			(vias allowed)
			(pads allowed)
			(copperpour not_allowed)
			(footprints allowed)
		)
		(placement
			(enabled no)
			(sheetname "")
		)
		(fill yes
			(thermal_gap 0.5)
			(thermal_bridge_width 0.5)
			(island_removal_mode 0)
		)
		(polygon
			(pts
				(arc
					(start 136.670796 -404.46452)
					(mid 136.002776 -404.46452)
					(end 136.670796 -404.46452)
				)
			)
		)
	)
	(zone
		(layers "B.Cu" "In6.Cu" "In11.Cu" "In13.Cu" "In15.Cu")
		(hatch none 0.5)
		(connect_pads
			(clearance 0)
		)
		(min_thickness 0.25)
		(keepout
			(tracks not_allowed)
			(vias allowed)
			(pads allowed)
			(copperpour not_allowed)
			(footprints allowed)
		)
		(placement
			(enabled no)
			(sheetname "")
		)
		(fill yes
			(thermal_gap 0.5)
			(thermal_bridge_width 0.5)
			(island_removal_mode 0)
		)
		(polygon
			(pts
				(arc
					(start 339.656166 -292.71595)
					(mid 339.026246 -292.71595)
					(end 339.656166 -292.71595)
				)
			)
		)
	)
	(zone
		(layers "B.Cu" "In6.Cu" "In11.Cu" "In13.Cu" "In15.Cu")
		(hatch none 0.5)
		(connect_pads
			(clearance 0)
		)
		(min_thickness 0.25)
		(keepout
			(tracks not_allowed)
			(vias allowed)
			(pads allowed)
			(copperpour not_allowed)
			(footprints allowed)
		)
		(placement
			(enabled no)
			(sheetname "")
		)
		(fill yes
			(thermal_gap 0.5)
			(thermal_bridge_width 0.5)
			(island_removal_mode 0)
		)
		(polygon
			(pts
				(arc
					(start 435.334156 -199.885046)
					(mid 434.666136 -199.885046)
					(end 435.334156 -199.885046)
				)
			)
		)
	)
	(zone
		(layers "B.Cu" "In6.Cu" "In11.Cu" "In13.Cu" "In15.Cu")
		(hatch none 0.5)
		(connect_pads
			(clearance 0)
		)
		(min_thickness 0.25)
		(keepout
			(tracks not_allowed)
			(vias allowed)
			(pads allowed)
			(copperpour not_allowed)
			(footprints allowed)
		)
		(placement
			(enabled no)
			(sheetname "")
		)
		(fill yes
			(thermal_gap 0.5)
			(thermal_bridge_width 0.5)
			(island_removal_mode 0)
		)
		(polygon
			(pts
				(arc
					(start 98.295968 -289.47618)
					(mid 97.666048 -289.47618)
					(end 98.295968 -289.47618)
				)
			)
		)
	)
	(zone
		(layers "B.Cu" "In6.Cu" "In11.Cu" "In13.Cu" "In15.Cu")
		(hatch none 0.5)
		(connect_pads
			(clearance 0)
		)
		(min_thickness 0.25)
		(keepout
			(tracks not_allowed)
			(vias allowed)
			(pads allowed)
			(copperpour not_allowed)
			(footprints allowed)
		)
		(placement
			(enabled no)
			(sheetname "")
		)
		(fill yes
			(thermal_gap 0.5)
			(thermal_bridge_width 0.5)
			(island_removal_mode 0)
		)
		(polygon
			(pts
				(arc
					(start 402.724112 -412.84652)
					(mid 402.056092 -412.84652)
					(end 402.724112 -412.84652)
				)
			)
		)
	)
	(zone
		(layers "B.Cu" "In6.Cu" "In11.Cu" "In13.Cu" "In15.Cu")
		(hatch none 0.5)
		(connect_pads
			(clearance 0)
		)
		(min_thickness 0.25)
		(keepout
			(tracks not_allowed)
			(vias allowed)
			(pads allowed)
			(copperpour not_allowed)
			(footprints allowed)
		)
		(placement
			(enabled no)
			(sheetname "")
		)
		(fill yes
			(thermal_gap 0.5)
			(thermal_bridge_width 0.5)
			(island_removal_mode 0)
		)
		(polygon
			(pts
				(arc
					(start 380.709678 -241.24412)
					(mid 380.079758 -241.24412)
					(end 380.709678 -241.24412)
				)
			)
		)
	)
	(zone
		(layers "B.Cu" "In6.Cu" "In11.Cu" "In13.Cu" "In15.Cu")
		(hatch none 0.5)
		(connect_pads
			(clearance 0)
		)
		(min_thickness 0.25)
		(keepout
			(tracks not_allowed)
			(vias allowed)
			(pads allowed)
			(copperpour not_allowed)
			(footprints allowed)
		)
		(placement
			(enabled no)
			(sheetname "")
		)
		(fill yes
			(thermal_gap 0.5)
			(thermal_bridge_width 0.5)
			(island_removal_mode 0)
		)
		(polygon
			(pts
				(arc
					(start 126.18974 -229.90429)
					(mid 125.55982 -229.90429)
					(end 126.18974 -229.90429)
				)
			)
		)
	)
	(zone
		(layers "B.Cu" "In6.Cu" "In11.Cu" "In13.Cu" "In15.Cu")
		(hatch none 0.5)
		(connect_pads
			(clearance 0)
		)
		(min_thickness 0.25)
		(keepout
			(tracks not_allowed)
			(vias allowed)
			(pads allowed)
			(copperpour not_allowed)
			(footprints allowed)
		)
		(placement
			(enabled no)
			(sheetname "")
		)
		(fill yes
			(thermal_gap 0.5)
			(thermal_bridge_width 0.5)
			(island_removal_mode 0)
		)
		(polygon
			(pts
				(arc
					(start 379.299724 -230.714296)
					(mid 378.669804 -230.714296)
					(end 379.299724 -230.714296)
				)
			)
		)
	)
	(zone
		(layers "B.Cu" "In6.Cu" "In11.Cu" "In13.Cu" "In15.Cu")
		(hatch none 0.5)
		(connect_pads
			(clearance 0)
		)
		(min_thickness 0.25)
		(keepout
			(tracks not_allowed)
			(vias allowed)
			(pads allowed)
			(copperpour not_allowed)
			(footprints allowed)
		)
		(placement
			(enabled no)
			(sheetname "")
		)
		(fill yes
			(thermal_gap 0.5)
			(thermal_bridge_width 0.5)
			(island_removal_mode 0)
		)
		(polygon
			(pts
				(arc
					(start 280.969974 -239.835182)
					(mid 280.301954 -239.835182)
					(end 280.969974 -239.835182)
				)
			)
		)
	)
	(zone
		(layers "B.Cu" "In6.Cu" "In11.Cu" "In13.Cu" "In15.Cu")
		(hatch none 0.5)
		(connect_pads
			(clearance 0)
		)
		(min_thickness 0.25)
		(keepout
			(tracks not_allowed)
			(vias allowed)
			(pads allowed)
			(copperpour not_allowed)
			(footprints allowed)
		)
		(placement
			(enabled no)
			(sheetname "")
		)
		(fill yes
			(thermal_gap 0.5)
			(thermal_bridge_width 0.5)
			(island_removal_mode 0)
		)
		(polygon
			(pts
				(arc
					(start 37.129974 -303.585372)
					(mid 36.461954 -303.585372)
					(end 37.129974 -303.585372)
				)
			)
		)
	)
	(zone
		(layers "B.Cu" "In6.Cu" "In11.Cu" "In13.Cu" "In15.Cu")
		(hatch none 0.5)
		(connect_pads
			(clearance 0)
		)
		(min_thickness 0.25)
		(keepout
			(tracks not_allowed)
			(vias allowed)
			(pads allowed)
			(copperpour not_allowed)
			(footprints allowed)
		)
		(placement
			(enabled no)
			(sheetname "")
		)
		(fill yes
			(thermal_gap 0.5)
			(thermal_bridge_width 0.5)
			(island_removal_mode 0)
		)
		(polygon
			(pts
				(arc
					(start 106.755946 -291.096192)
					(mid 106.126026 -291.096192)
					(end 106.755946 -291.096192)
				)
			)
		)
	)
	(zone
		(layers "B.Cu" "In6.Cu" "In11.Cu" "In13.Cu" "In15.Cu")
		(hatch none 0.5)
		(connect_pads
			(clearance 0)
		)
		(min_thickness 0.25)
		(keepout
			(tracks not_allowed)
			(vias allowed)
			(pads allowed)
			(copperpour not_allowed)
			(footprints allowed)
		)
		(placement
			(enabled no)
			(sheetname "")
		)
		(fill yes
			(thermal_gap 0.5)
			(thermal_bridge_width 0.5)
			(island_removal_mode 0)
		)
		(polygon
			(pts
				(arc
					(start 403.734016 -397.156432)
					(mid 403.104096 -397.156432)
					(end 403.734016 -397.156432)
				)
			)
		)
	)
	(zone
		(layers "B.Cu" "In6.Cu" "In11.Cu" "In13.Cu" "In15.Cu")
		(hatch none 0.5)
		(connect_pads
			(clearance 0)
		)
		(min_thickness 0.25)
		(keepout
			(tracks not_allowed)
			(vias allowed)
			(pads allowed)
			(copperpour not_allowed)
			(footprints allowed)
		)
		(placement
			(enabled no)
			(sheetname "")
		)
		(fill yes
			(thermal_gap 0.5)
			(thermal_bridge_width 0.5)
			(island_removal_mode 0)
		)
		(polygon
			(pts
				(arc
					(start 381.179832 -246.914162)
					(mid 380.549912 -246.914162)
					(end 381.179832 -246.914162)
				)
			)
		)
	)
	(zone
		(layers "B.Cu" "In6.Cu" "In11.Cu" "In13.Cu" "In15.Cu")
		(hatch none 0.5)
		(connect_pads
			(clearance 0)
		)
		(min_thickness 0.25)
		(keepout
			(tracks not_allowed)
			(vias allowed)
			(pads allowed)
			(copperpour not_allowed)
			(footprints allowed)
		)
		(placement
			(enabled no)
			(sheetname "")
		)
		(fill yes
			(thermal_gap 0.5)
			(thermal_bridge_width 0.5)
			(island_removal_mode 0)
		)
		(polygon
			(pts
				(arc
					(start 439.434224 -219.435172)
					(mid 438.766204 -219.435172)
					(end 439.434224 -219.435172)
				)
			)
		)
	)
	(zone
		(layers "B.Cu" "In6.Cu" "In11.Cu" "In13.Cu" "In15.Cu")
		(hatch none 0.5)
		(connect_pads
			(clearance 0)
		)
		(min_thickness 0.25)
		(keepout
			(tracks not_allowed)
			(vias allowed)
			(pads allowed)
			(copperpour not_allowed)
			(footprints allowed)
		)
		(placement
			(enabled no)
			(sheetname "")
		)
		(fill yes
			(thermal_gap 0.5)
			(thermal_bridge_width 0.5)
			(island_removal_mode 0)
		)
		(polygon
			(pts
				(arc
					(start 37.129974 -220.28531)
					(mid 36.461954 -220.28531)
					(end 37.129974 -220.28531)
				)
			)
		)
	)
	(zone
		(layers "B.Cu" "In6.Cu" "In11.Cu" "In13.Cu" "In15.Cu")
		(hatch none 0.5)
		(connect_pads
			(clearance 0)
		)
		(min_thickness 0.25)
		(keepout
			(tracks not_allowed)
			(vias allowed)
			(pads allowed)
			(copperpour not_allowed)
			(footprints allowed)
		)
		(placement
			(enabled no)
			(sheetname "")
		)
		(fill yes
			(thermal_gap 0.5)
			(thermal_bridge_width 0.5)
			(island_removal_mode 0)
		)
		(polygon
			(pts
				(arc
					(start 355.336094 -226.664266)
					(mid 354.706174 -226.664266)
					(end 355.336094 -226.664266)
				)
			)
		)
	)
	(zone
		(layers "B.Cu" "In6.Cu" "In11.Cu" "In13.Cu" "In15.Cu")
		(hatch none 0.5)
		(connect_pads
			(clearance 0)
		)
		(min_thickness 0.25)
		(keepout
			(tracks not_allowed)
			(vias allowed)
			(pads allowed)
			(copperpour not_allowed)
			(footprints allowed)
		)
		(placement
			(enabled no)
			(sheetname "")
		)
		(fill yes
			(thermal_gap 0.5)
			(thermal_bridge_width 0.5)
			(island_removal_mode 0)
		)
		(polygon
			(pts
				(arc
					(start 92.655898 -286.23641)
					(mid 92.025978 -286.23641)
					(end 92.655898 -286.23641)
				)
			)
		)
	)
	(zone
		(layers "B.Cu" "In6.Cu" "In11.Cu" "In13.Cu" "In15.Cu")
		(hatch none 0.5)
		(connect_pads
			(clearance 0)
		)
		(min_thickness 0.25)
		(keepout
			(tracks not_allowed)
			(vias allowed)
			(pads allowed)
			(copperpour not_allowed)
			(footprints allowed)
		)
		(placement
			(enabled no)
			(sheetname "")
		)
		(fill yes
			(thermal_gap 0.5)
			(thermal_bridge_width 0.5)
			(island_removal_mode 0)
		)
		(polygon
			(pts
				(arc
					(start 285.070042 -300.185074)
					(mid 284.402022 -300.185074)
					(end 285.070042 -300.185074)
				)
			)
		)
	)
	(zone
		(layers "B.Cu" "In6.Cu" "In11.Cu" "In13.Cu" "In15.Cu")
		(hatch none 0.5)
		(connect_pads
			(clearance 0)
		)
		(min_thickness 0.25)
		(keepout
			(tracks not_allowed)
			(vias allowed)
			(pads allowed)
			(copperpour not_allowed)
			(footprints allowed)
		)
		(placement
			(enabled no)
			(sheetname "")
		)
		(fill yes
			(thermal_gap 0.5)
			(thermal_bridge_width 0.5)
			(island_removal_mode 0)
		)
		(polygon
			(pts
				(arc
					(start 187.394088 -305.285394)
					(mid 186.726068 -305.285394)
					(end 187.394088 -305.285394)
				)
			)
		)
	)
	(zone
		(layers "B.Cu" "In6.Cu" "In11.Cu" "In13.Cu" "In15.Cu")
		(hatch none 0.5)
		(connect_pads
			(clearance 0)
		)
		(min_thickness 0.25)
		(keepout
			(tracks not_allowed)
			(vias allowed)
			(pads allowed)
			(copperpour not_allowed)
			(footprints allowed)
		)
		(placement
			(enabled no)
			(sheetname "")
		)
		(fill yes
			(thermal_gap 0.5)
			(thermal_bridge_width 0.5)
			(island_removal_mode 0)
		)
		(polygon
			(pts
				(arc
					(start 340.595966 -263.555988)
					(mid 339.966046 -263.555988)
					(end 340.595966 -263.555988)
				)
			)
		)
	)
	(zone
		(layers "B.Cu" "In6.Cu" "In11.Cu" "In13.Cu" "In15.Cu")
		(hatch none 0.5)
		(connect_pads
			(clearance 0)
		)
		(min_thickness 0.25)
		(keepout
			(tracks not_allowed)
			(vias allowed)
			(pads allowed)
			(copperpour not_allowed)
			(footprints allowed)
		)
		(placement
			(enabled no)
			(sheetname "")
		)
		(fill yes
			(thermal_gap 0.5)
			(thermal_bridge_width 0.5)
			(island_removal_mode 0)
		)
		(polygon
			(pts
				(arc
					(start 285.070042 -206.685134)
					(mid 284.402022 -206.685134)
					(end 285.070042 -206.685134)
				)
			)
		)
	)
	(zone
		(layers "B.Cu" "In6.Cu" "In11.Cu" "In13.Cu" "In15.Cu")
		(hatch none 0.5)
		(connect_pads
			(clearance 0)
		)
		(min_thickness 0.25)
		(keepout
			(tracks not_allowed)
			(vias allowed)
			(pads allowed)
			(copperpour not_allowed)
			(footprints allowed)
		)
		(placement
			(enabled no)
			(sheetname "")
		)
		(fill yes
			(thermal_gap 0.5)
			(thermal_bridge_width 0.5)
			(island_removal_mode 0)
		)
		(polygon
			(pts
				(arc
					(start 410.134054 -397.849344)
					(mid 409.504134 -397.849344)
					(end 410.134054 -397.849344)
				)
			)
		)
	)
	(zone
		(layers "B.Cu" "In6.Cu" "In11.Cu" "In13.Cu" "In15.Cu")
		(hatch none 0.5)
		(connect_pads
			(clearance 0)
		)
		(min_thickness 0.25)
		(keepout
			(tracks not_allowed)
			(vias allowed)
			(pads allowed)
			(copperpour not_allowed)
			(footprints allowed)
		)
		(placement
			(enabled no)
			(sheetname "")
		)
		(fill yes
			(thermal_gap 0.5)
			(thermal_bridge_width 0.5)
			(island_removal_mode 0)
		)
		(polygon
			(pts
				(arc
					(start 132.76961 -229.90429)
					(mid 132.13969 -229.90429)
					(end 132.76961 -229.90429)
				)
			)
		)
	)
	(zone
		(layers "B.Cu" "In6.Cu" "In11.Cu" "In13.Cu" "In15.Cu")
		(hatch none 0.5)
		(connect_pads
			(clearance 0)
		)
		(min_thickness 0.25)
		(keepout
			(tracks not_allowed)
			(vias allowed)
			(pads allowed)
			(copperpour not_allowed)
			(footprints allowed)
		)
		(placement
			(enabled no)
			(sheetname "")
		)
		(fill yes
			(thermal_gap 0.5)
			(thermal_bridge_width 0.5)
			(island_removal_mode 0)
		)
		(polygon
			(pts
				(arc
					(start 133.539738 -288.666174)
					(mid 132.909818 -288.666174)
					(end 133.539738 -288.666174)
				)
			)
		)
	)
	(zone
		(layers "B.Cu" "In6.Cu" "In11.Cu" "In13.Cu" "In15.Cu")
		(hatch none 0.5)
		(connect_pads
			(clearance 0)
		)
		(min_thickness 0.25)
		(keepout
			(tracks not_allowed)
			(vias allowed)
			(pads allowed)
			(copperpour not_allowed)
			(footprints allowed)
		)
		(placement
			(enabled no)
			(sheetname "")
		)
		(fill yes
			(thermal_gap 0.5)
			(thermal_bridge_width 0.5)
			(island_removal_mode 0)
		)
		(polygon
			(pts
				(arc
					(start 191.494156 -245.785386)
					(mid 190.826136 -245.785386)
					(end 191.494156 -245.785386)
				)
			)
		)
	)
	(zone
		(layers "B.Cu" "In6.Cu" "In11.Cu" "In13.Cu" "In15.Cu")
		(hatch none 0.5)
		(connect_pads
			(clearance 0)
		)
		(min_thickness 0.25)
		(keepout
			(tracks not_allowed)
			(vias allowed)
			(pads allowed)
			(copperpour not_allowed)
			(footprints allowed)
		)
		(placement
			(enabled no)
			(sheetname "")
		)
		(fill yes
			(thermal_gap 0.5)
			(thermal_bridge_width 0.5)
			(island_removal_mode 0)
		)
		(polygon
			(pts
				(arc
					(start 115.606322 -386.003292)
					(mid 114.976402 -386.003292)
					(end 115.606322 -386.003292)
				)
			)
		)
	)
	(zone
		(layers "B.Cu" "In6.Cu" "In11.Cu" "In13.Cu" "In15.Cu")
		(hatch none 0.5)
		(connect_pads
			(clearance 0)
		)
		(min_thickness 0.25)
		(keepout
			(tracks not_allowed)
			(vias allowed)
			(pads allowed)
			(copperpour not_allowed)
			(footprints allowed)
		)
		(placement
			(enabled no)
			(sheetname "")
		)
		(fill yes
			(thermal_gap 0.5)
			(thermal_bridge_width 0.5)
			(island_removal_mode 0)
		)
		(polygon
			(pts
				(arc
					(start 125.281436 -404.46452)
					(mid 124.613416 -404.46452)
					(end 125.281436 -404.46452)
				)
			)
		)
	)
	(zone
		(layers "B.Cu" "In6.Cu" "In11.Cu" "In13.Cu" "In15.Cu")
		(hatch none 0.5)
		(connect_pads
			(clearance 0)
		)
		(min_thickness 0.25)
		(keepout
			(tracks not_allowed)
			(vias allowed)
			(pads allowed)
			(copperpour not_allowed)
			(footprints allowed)
		)
		(placement
			(enabled no)
			(sheetname "")
		)
		(fill yes
			(thermal_gap 0.5)
			(thermal_bridge_width 0.5)
			(island_removal_mode 0)
		)
		(polygon
			(pts
				(arc
					(start 341.06612 -270.846042)
					(mid 340.4362 -270.846042)
					(end 341.06612 -270.846042)
				)
			)
		)
	)
	(zone
		(layers "B.Cu" "In6.Cu" "In11.Cu" "In13.Cu" "In15.Cu")
		(hatch none 0.5)
		(connect_pads
			(clearance 0)
		)
		(min_thickness 0.25)
		(keepout
			(tracks not_allowed)
			(vias allowed)
			(pads allowed)
			(copperpour not_allowed)
			(footprints allowed)
		)
		(placement
			(enabled no)
			(sheetname "")
		)
		(fill yes
			(thermal_gap 0.5)
			(thermal_bridge_width 0.5)
			(island_removal_mode 0)
		)
		(polygon
			(pts
				(arc
					(start 280.969974 -224.534984)
					(mid 280.301954 -224.534984)
					(end 280.969974 -224.534984)
				)
			)
		)
	)
	(zone
		(layers "B.Cu" "In6.Cu" "In11.Cu" "In13.Cu" "In15.Cu")
		(hatch none 0.5)
		(connect_pads
			(clearance 0)
		)
		(min_thickness 0.25)
		(keepout
			(tracks not_allowed)
			(vias allowed)
			(pads allowed)
			(copperpour not_allowed)
			(footprints allowed)
		)
		(placement
			(enabled no)
			(sheetname "")
		)
		(fill yes
			(thermal_gap 0.5)
			(thermal_bridge_width 0.5)
			(island_removal_mode 0)
		)
		(polygon
			(pts
				(arc
					(start 133.069838 -278.13635)
					(mid 132.439918 -278.13635)
					(end 133.069838 -278.13635)
				)
			)
		)
	)
	(zone
		(layers "B.Cu" "In6.Cu" "In11.Cu" "In13.Cu" "In15.Cu")
		(hatch none 0.5)
		(connect_pads
			(clearance 0)
		)
		(min_thickness 0.25)
		(keepout
			(tracks not_allowed)
			(vias allowed)
			(pads allowed)
			(copperpour not_allowed)
			(footprints allowed)
		)
		(placement
			(enabled no)
			(sheetname "")
		)
		(fill yes
			(thermal_gap 0.5)
			(thermal_bridge_width 0.5)
			(island_removal_mode 0)
		)
		(polygon
			(pts
				(arc
					(start 439.434224 -273.835114)
					(mid 438.766204 -273.835114)
					(end 439.434224 -273.835114)
				)
			)
		)
	)
	(zone
		(layers "B.Cu" "In6.Cu" "In11.Cu" "In13.Cu" "In15.Cu")
		(hatch none 0.5)
		(connect_pads
			(clearance 0)
		)
		(min_thickness 0.25)
		(keepout
			(tracks not_allowed)
			(vias allowed)
			(pads allowed)
			(copperpour not_allowed)
			(footprints allowed)
		)
		(placement
			(enabled no)
			(sheetname "")
		)
		(fill yes
			(thermal_gap 0.5)
			(thermal_bridge_width 0.5)
			(island_removal_mode 0)
		)
		(polygon
			(pts
				(arc
					(start 365.02975 -287.856168)
					(mid 364.39983 -287.856168)
					(end 365.02975 -287.856168)
				)
			)
		)
	)
	(zone
		(layers "B.Cu" "In6.Cu" "In11.Cu" "In13.Cu" "In15.Cu")
		(hatch none 0.5)
		(connect_pads
			(clearance 0)
		)
		(min_thickness 0.25)
		(keepout
			(tracks not_allowed)
			(vias allowed)
			(pads allowed)
			(copperpour not_allowed)
			(footprints allowed)
		)
		(placement
			(enabled no)
			(sheetname "")
		)
		(fill yes
			(thermal_gap 0.5)
			(thermal_bridge_width 0.5)
			(island_removal_mode 0)
		)
		(polygon
			(pts
				(arc
					(start 379.769878 -229.904036)
					(mid 379.139958 -229.904036)
					(end 379.769878 -229.904036)
				)
			)
		)
	)
	(zone
		(layers "B.Cu" "In6.Cu" "In11.Cu" "In13.Cu" "In15.Cu")
		(hatch none 0.5)
		(connect_pads
			(clearance 0)
		)
		(min_thickness 0.25)
		(keepout
			(tracks not_allowed)
			(vias allowed)
			(pads allowed)
			(copperpour not_allowed)
			(footprints allowed)
		)
		(placement
			(enabled no)
			(sheetname "")
		)
		(fill yes
			(thermal_gap 0.5)
			(thermal_bridge_width 0.5)
			(island_removal_mode 0)
		)
		(polygon
			(pts
				(arc
					(start 340.595966 -279.756108)
					(mid 339.966046 -279.756108)
					(end 340.595966 -279.756108)
				)
			)
		)
	)
	(zone
		(layers "B.Cu" "In6.Cu" "In11.Cu" "In13.Cu" "In15.Cu")
		(hatch none 0.5)
		(connect_pads
			(clearance 0)
		)
		(min_thickness 0.25)
		(keepout
			(tracks not_allowed)
			(vias allowed)
			(pads allowed)
			(copperpour not_allowed)
			(footprints allowed)
		)
		(placement
			(enabled no)
			(sheetname "")
		)
		(fill yes
			(thermal_gap 0.5)
			(thermal_bridge_width 0.5)
			(island_removal_mode 0)
		)
		(polygon
			(pts
				(arc
					(start 151.734012 -389.467344)
					(mid 151.104092 -389.467344)
					(end 151.734012 -389.467344)
				)
			)
		)
	)
	(zone
		(layers "B.Cu" "In6.Cu" "In11.Cu" "In13.Cu" "In15.Cu")
		(hatch none 0.5)
		(connect_pads
			(clearance 0)
		)
		(min_thickness 0.25)
		(keepout
			(tracks not_allowed)
			(vias allowed)
			(pads allowed)
			(copperpour not_allowed)
			(footprints allowed)
		)
		(placement
			(enabled no)
			(sheetname "")
		)
		(fill yes
			(thermal_gap 0.5)
			(thermal_bridge_width 0.5)
			(island_removal_mode 0)
		)
		(polygon
			(pts
				(arc
					(start 191.494156 -279.785318)
					(mid 190.826136 -279.785318)
					(end 191.494156 -279.785318)
				)
			)
		)
	)
	(zone
		(layers "B.Cu" "In6.Cu" "In11.Cu" "In13.Cu" "In15.Cu")
		(hatch none 0.5)
		(connect_pads
			(clearance 0)
		)
		(min_thickness 0.25)
		(keepout
			(tracks not_allowed)
			(vias allowed)
			(pads allowed)
			(copperpour not_allowed)
			(footprints allowed)
		)
		(placement
			(enabled no)
			(sheetname "")
		)
		(fill yes
			(thermal_gap 0.5)
			(thermal_bridge_width 0.5)
			(island_removal_mode 0)
		)
		(polygon
			(pts
				(arc
					(start 187.394088 -254.285242)
					(mid 186.726068 -254.285242)
					(end 187.394088 -254.285242)
				)
			)
		)
	)
	(zone
		(layers "B.Cu" "In6.Cu" "In11.Cu" "In13.Cu" "In15.Cu")
		(hatch none 0.5)
		(connect_pads
			(clearance 0)
		)
		(min_thickness 0.25)
		(keepout
			(tracks not_allowed)
			(vias allowed)
			(pads allowed)
			(copperpour not_allowed)
			(footprints allowed)
		)
		(placement
			(enabled no)
			(sheetname "")
		)
		(fill yes
			(thermal_gap 0.5)
			(thermal_bridge_width 0.5)
			(island_removal_mode 0)
		)
		(polygon
			(pts
				(arc
					(start 435.334156 -312.084974)
					(mid 434.666136 -312.084974)
					(end 435.334156 -312.084974)
				)
			)
		)
	)
	(zone
		(layers "B.Cu" "In6.Cu" "In11.Cu" "In13.Cu" "In15.Cu")
		(hatch none 0.5)
		(connect_pads
			(clearance 0)
		)
		(min_thickness 0.25)
		(keepout
			(tracks not_allowed)
			(vias allowed)
			(pads allowed)
			(copperpour not_allowed)
			(footprints allowed)
		)
		(placement
			(enabled no)
			(sheetname "")
		)
		(fill yes
			(thermal_gap 0.5)
			(thermal_bridge_width 0.5)
			(island_removal_mode 0)
		)
		(polygon
			(pts
				(arc
					(start 285.070042 -266.185142)
					(mid 284.402022 -266.185142)
					(end 285.070042 -266.185142)
				)
			)
		)
	)
	(zone
		(layers "B.Cu" "In6.Cu" "In11.Cu" "In13.Cu" "In15.Cu")
		(hatch none 0.5)
		(connect_pads
			(clearance 0)
		)
		(min_thickness 0.25)
		(keepout
			(tracks not_allowed)
			(vias allowed)
			(pads allowed)
			(copperpour not_allowed)
			(footprints allowed)
		)
		(placement
			(enabled no)
			(sheetname "")
		)
		(fill yes
			(thermal_gap 0.5)
			(thermal_bridge_width 0.5)
			(island_removal_mode 0)
		)
		(polygon
			(pts
				(arc
					(start 368.789712 -289.475926)
					(mid 368.159792 -289.475926)
					(end 368.789712 -289.475926)
				)
			)
		)
	)
	(zone
		(layers "B.Cu" "In6.Cu" "In11.Cu" "In13.Cu" "In15.Cu")
		(hatch none 0.5)
		(connect_pads
			(clearance 0)
		)
		(min_thickness 0.25)
		(keepout
			(tracks not_allowed)
			(vias allowed)
			(pads allowed)
			(copperpour not_allowed)
			(footprints allowed)
		)
		(placement
			(enabled no)
			(sheetname "")
		)
		(fill yes
			(thermal_gap 0.5)
			(thermal_bridge_width 0.5)
			(island_removal_mode 0)
		)
		(polygon
			(pts
				(arc
					(start 133.539738 -264.366248)
					(mid 132.909818 -264.366248)
					(end 133.539738 -264.366248)
				)
			)
		)
	)
	(zone
		(layers "B.Cu" "In6.Cu" "In11.Cu" "In13.Cu" "In15.Cu")
		(hatch none 0.5)
		(connect_pads
			(clearance 0)
		)
		(min_thickness 0.25)
		(keepout
			(tracks not_allowed)
			(vias allowed)
			(pads allowed)
			(copperpour not_allowed)
			(footprints allowed)
		)
		(placement
			(enabled no)
			(sheetname "")
		)
		(fill yes
			(thermal_gap 0.5)
			(thermal_bridge_width 0.5)
			(island_removal_mode 0)
		)
		(polygon
			(pts
				(arc
					(start 117.729762 -229.90429)
					(mid 117.099842 -229.90429)
					(end 117.729762 -229.90429)
				)
			)
		)
	)
	(zone
		(layers "B.Cu" "In6.Cu" "In11.Cu" "In13.Cu" "In15.Cu")
		(hatch none 0.5)
		(connect_pads
			(clearance 0)
		)
		(min_thickness 0.25)
		(keepout
			(tracks not_allowed)
			(vias allowed)
			(pads allowed)
			(copperpour not_allowed)
			(footprints allowed)
		)
		(placement
			(enabled no)
			(sheetname "")
		)
		(fill yes
			(thermal_gap 0.5)
			(thermal_bridge_width 0.5)
			(island_removal_mode 0)
		)
		(polygon
			(pts
				(arc
					(start 187.394088 -201.585322)
					(mid 186.726068 -201.585322)
					(end 187.394088 -201.585322)
				)
			)
		)
	)
	(zone
		(layers "B.Cu" "In6.Cu" "In11.Cu" "In13.Cu" "In15.Cu")
		(hatch none 0.5)
		(connect_pads
			(clearance 0)
		)
		(min_thickness 0.25)
		(keepout
			(tracks not_allowed)
			(vias allowed)
			(pads allowed)
			(copperpour not_allowed)
			(footprints allowed)
		)
		(placement
			(enabled no)
			(sheetname "")
		)
		(fill yes
			(thermal_gap 0.5)
			(thermal_bridge_width 0.5)
			(island_removal_mode 0)
		)
		(polygon
			(pts
				(arc
					(start 435.334156 -222.834962)
					(mid 434.666136 -222.834962)
					(end 435.334156 -222.834962)
				)
			)
		)
	)
	(zone
		(layers "B.Cu" "In6.Cu" "In11.Cu" "In13.Cu" "In15.Cu")
		(hatch none 0.5)
		(connect_pads
			(clearance 0)
		)
		(min_thickness 0.25)
		(keepout
			(tracks not_allowed)
			(vias allowed)
			(pads allowed)
			(copperpour not_allowed)
			(footprints allowed)
		)
		(placement
			(enabled no)
			(sheetname "")
		)
		(fill yes
			(thermal_gap 0.5)
			(thermal_bridge_width 0.5)
			(island_removal_mode 0)
		)
		(polygon
			(pts
				(arc
					(start 435.334156 -243.234972)
					(mid 434.666136 -243.234972)
					(end 435.334156 -243.234972)
				)
			)
		)
	)
	(zone
		(layers "B.Cu" "In6.Cu" "In11.Cu" "In13.Cu" "In15.Cu")
		(hatch none 0.5)
		(connect_pads
			(clearance 0)
		)
		(min_thickness 0.25)
		(keepout
			(tracks not_allowed)
			(vias allowed)
			(pads allowed)
			(copperpour not_allowed)
			(footprints allowed)
		)
		(placement
			(enabled no)
			(sheetname "")
		)
		(fill yes
			(thermal_gap 0.5)
			(thermal_bridge_width 0.5)
			(island_removal_mode 0)
		)
		(polygon
			(pts
				(arc
					(start 32.81807 -4.963414)
					(mid 32.15005 -4.963414)
					(end 32.81807 -4.963414)
				)
			)
		)
	)
	(zone
		(layers "B.Cu" "In6.Cu" "In11.Cu" "In13.Cu" "In15.Cu")
		(hatch none 0.5)
		(connect_pads
			(clearance 0)
		)
		(min_thickness 0.25)
		(keepout
			(tracks not_allowed)
			(vias allowed)
			(pads allowed)
			(copperpour not_allowed)
			(footprints allowed)
		)
		(placement
			(enabled no)
			(sheetname "")
		)
		(fill yes
			(thermal_gap 0.5)
			(thermal_bridge_width 0.5)
			(island_removal_mode 0)
		)
		(polygon
			(pts
				(arc
					(start 381.009906 -287.856168)
					(mid 380.379986 -287.856168)
					(end 381.009906 -287.856168)
				)
			)
		)
	)
	(zone
		(layers "B.Cu" "In6.Cu" "In11.Cu" "In13.Cu" "In15.Cu")
		(hatch none 0.5)
		(connect_pads
			(clearance 0)
		)
		(min_thickness 0.25)
		(keepout
			(tracks not_allowed)
			(vias allowed)
			(pads allowed)
			(copperpour not_allowed)
			(footprints allowed)
		)
		(placement
			(enabled no)
			(sheetname "")
		)
		(fill yes
			(thermal_gap 0.5)
			(thermal_bridge_width 0.5)
			(island_removal_mode 0)
		)
		(polygon
			(pts
				(arc
					(start 439.434224 -227.085144)
					(mid 438.766204 -227.085144)
					(end 439.434224 -227.085144)
				)
			)
		)
	)
	(zone
		(layers "B.Cu" "In6.Cu" "In11.Cu" "In13.Cu" "In15.Cu")
		(hatch none 0.5)
		(connect_pads
			(clearance 0)
		)
		(min_thickness 0.25)
		(keepout
			(tracks not_allowed)
			(vias allowed)
			(pads allowed)
			(copperpour not_allowed)
			(footprints allowed)
		)
		(placement
			(enabled no)
			(sheetname "")
		)
		(fill yes
			(thermal_gap 0.5)
			(thermal_bridge_width 0.5)
			(island_removal_mode 0)
		)
		(polygon
			(pts
				(arc
					(start 371.309646 -233.14406)
					(mid 370.679726 -233.14406)
					(end 371.309646 -233.14406)
				)
			)
		)
	)
	(zone
		(layers "B.Cu" "In6.Cu" "In11.Cu" "In13.Cu" "In15.Cu")
		(hatch none 0.5)
		(connect_pads
			(clearance 0)
		)
		(min_thickness 0.25)
		(keepout
			(tracks not_allowed)
			(vias allowed)
			(pads allowed)
			(copperpour not_allowed)
			(footprints allowed)
		)
		(placement
			(enabled no)
			(sheetname "")
		)
		(fill yes
			(thermal_gap 0.5)
			(thermal_bridge_width 0.5)
			(island_removal_mode 0)
		)
		(polygon
			(pts
				(arc
					(start 435.334156 -263.634982)
					(mid 434.666136 -263.634982)
					(end 435.334156 -263.634982)
				)
			)
		)
	)
	(zone
		(layers "B.Cu" "In6.Cu" "In11.Cu" "In13.Cu" "In15.Cu")
		(hatch none 0.5)
		(connect_pads
			(clearance 0)
		)
		(min_thickness 0.25)
		(keepout
			(tracks not_allowed)
			(vias allowed)
			(pads allowed)
			(copperpour not_allowed)
			(footprints allowed)
		)
		(placement
			(enabled no)
			(sheetname "")
		)
		(fill yes
			(thermal_gap 0.5)
			(thermal_bridge_width 0.5)
			(island_removal_mode 0)
		)
		(polygon
			(pts
				(arc
					(start 355.636068 -289.475926)
					(mid 355.006148 -289.475926)
					(end 355.636068 -289.475926)
				)
			)
		)
	)
	(zone
		(layers "B.Cu" "In6.Cu" "In11.Cu" "In13.Cu" "In15.Cu")
		(hatch none 0.5)
		(connect_pads
			(clearance 0)
		)
		(min_thickness 0.25)
		(keepout
			(tracks not_allowed)
			(vias allowed)
			(pads allowed)
			(copperpour not_allowed)
			(footprints allowed)
		)
		(placement
			(enabled no)
			(sheetname "")
		)
		(fill yes
			(thermal_gap 0.5)
			(thermal_bridge_width 0.5)
			(island_removal_mode 0)
		)
		(polygon
			(pts
				(arc
					(start 187.394088 -205.83525)
					(mid 186.726068 -205.83525)
					(end 187.394088 -205.83525)
				)
			)
		)
	)
	(zone
		(layers "B.Cu" "In6.Cu" "In11.Cu" "In13.Cu" "In15.Cu")
		(hatch none 0.5)
		(connect_pads
			(clearance 0)
		)
		(min_thickness 0.25)
		(keepout
			(tracks not_allowed)
			(vias allowed)
			(pads allowed)
			(copperpour not_allowed)
			(footprints allowed)
		)
		(placement
			(enabled no)
			(sheetname "")
		)
		(fill yes
			(thermal_gap 0.5)
			(thermal_bridge_width 0.5)
			(island_removal_mode 0)
		)
		(polygon
			(pts
				(arc
					(start 151.986996 -404.46452)
					(mid 151.318976 -404.46452)
					(end 151.986996 -404.46452)
				)
			)
		)
	)
	(zone
		(layers "B.Cu" "In6.Cu" "In11.Cu" "In13.Cu" "In15.Cu")
		(hatch none 0.5)
		(connect_pads
			(clearance 0)
		)
		(min_thickness 0.25)
		(keepout
			(tracks not_allowed)
			(vias allowed)
			(pads allowed)
			(copperpour not_allowed)
			(footprints allowed)
		)
		(placement
			(enabled no)
			(sheetname "")
		)
		(fill yes
			(thermal_gap 0.5)
			(thermal_bridge_width 0.5)
			(island_removal_mode 0)
		)
		(polygon
			(pts
				(arc
					(start 339.656166 -278.136096)
					(mid 339.026246 -278.136096)
					(end 339.656166 -278.136096)
				)
			)
		)
	)
	(zone
		(layers "B.Cu" "In6.Cu" "In11.Cu" "In13.Cu" "In15.Cu")
		(hatch none 0.5)
		(connect_pads
			(clearance 0)
		)
		(min_thickness 0.25)
		(keepout
			(tracks not_allowed)
			(vias allowed)
			(pads allowed)
			(copperpour not_allowed)
			(footprints allowed)
		)
		(placement
			(enabled no)
			(sheetname "")
		)
		(fill yes
			(thermal_gap 0.5)
			(thermal_bridge_width 0.5)
			(island_removal_mode 0)
		)
		(polygon
			(pts
				(arc
					(start 362.379768 -233.954066)
					(mid 361.749848 -233.954066)
					(end 362.379768 -233.954066)
				)
			)
		)
	)
	(zone
		(layers "B.Cu" "In6.Cu" "In11.Cu" "In13.Cu" "In15.Cu")
		(hatch none 0.5)
		(connect_pads
			(clearance 0)
		)
		(min_thickness 0.25)
		(keepout
			(tracks not_allowed)
			(vias allowed)
			(pads allowed)
			(copperpour not_allowed)
			(footprints allowed)
		)
		(placement
			(enabled no)
			(sheetname "")
		)
		(fill yes
			(thermal_gap 0.5)
			(thermal_bridge_width 0.5)
			(island_removal_mode 0)
		)
		(polygon
			(pts
				(arc
					(start 33.029906 -265.335258)
					(mid 32.361886 -265.335258)
					(end 33.029906 -265.335258)
				)
			)
		)
	)
	(zone
		(layers "B.Cu" "In6.Cu" "In11.Cu" "In13.Cu" "In15.Cu")
		(hatch none 0.5)
		(connect_pads
			(clearance 0)
		)
		(min_thickness 0.25)
		(keepout
			(tracks not_allowed)
			(vias allowed)
			(pads allowed)
			(copperpour not_allowed)
			(footprints allowed)
		)
		(placement
			(enabled no)
			(sheetname "")
		)
		(fill yes
			(thermal_gap 0.5)
			(thermal_bridge_width 0.5)
			(island_removal_mode 0)
		)
		(polygon
			(pts
				(arc
					(start 280.969974 -209.23504)
					(mid 280.301954 -209.23504)
					(end 280.969974 -209.23504)
				)
			)
		)
	)
	(zone
		(layers "B.Cu" "In6.Cu" "In11.Cu" "In13.Cu" "In15.Cu")
		(hatch none 0.5)
		(connect_pads
			(clearance 0)
		)
		(min_thickness 0.25)
		(keepout
			(tracks not_allowed)
			(vias allowed)
			(pads allowed)
			(copperpour not_allowed)
			(footprints allowed)
		)
		(placement
			(enabled no)
			(sheetname "")
		)
		(fill yes
			(thermal_gap 0.5)
			(thermal_bridge_width 0.5)
			(island_removal_mode 0)
		)
		(polygon
			(pts
				(arc
					(start 285.070042 -245.785132)
					(mid 284.402022 -245.785132)
					(end 285.070042 -245.785132)
				)
			)
		)
	)
	(zone
		(layers "B.Cu" "In6.Cu" "In11.Cu" "In13.Cu" "In15.Cu")
		(hatch none 0.5)
		(connect_pads
			(clearance 0)
		)
		(min_thickness 0.25)
		(keepout
			(tracks not_allowed)
			(vias allowed)
			(pads allowed)
			(copperpour not_allowed)
			(footprints allowed)
		)
		(placement
			(enabled no)
			(sheetname "")
		)
		(fill yes
			(thermal_gap 0.5)
			(thermal_bridge_width 0.5)
			(island_removal_mode 0)
		)
		(polygon
			(pts
				(arc
					(start 346.236036 -286.236156)
					(mid 345.606116 -286.236156)
					(end 346.236036 -286.236156)
				)
			)
		)
	)
	(zone
		(layers "B.Cu" "In6.Cu" "In11.Cu" "In13.Cu" "In15.Cu")
		(hatch none 0.5)
		(connect_pads
			(clearance 0)
		)
		(min_thickness 0.25)
		(keepout
			(tracks not_allowed)
			(vias allowed)
			(pads allowed)
			(copperpour not_allowed)
			(footprints allowed)
		)
		(placement
			(enabled no)
			(sheetname "")
		)
		(fill yes
			(thermal_gap 0.5)
			(thermal_bridge_width 0.5)
			(island_removal_mode 0)
		)
		(polygon
			(pts
				(arc
					(start 132.406136 -386.003292)
					(mid 131.776216 -386.003292)
					(end 132.406136 -386.003292)
				)
			)
		)
	)
	(zone
		(layers "B.Cu" "In6.Cu" "In11.Cu" "In13.Cu" "In15.Cu")
		(hatch none 0.5)
		(connect_pads
			(clearance 0)
		)
		(min_thickness 0.25)
		(keepout
			(tracks not_allowed)
			(vias allowed)
			(pads allowed)
			(copperpour not_allowed)
			(footprints allowed)
		)
		(placement
			(enabled no)
			(sheetname "")
		)
		(fill yes
			(thermal_gap 0.5)
			(thermal_bridge_width 0.5)
			(island_removal_mode 0)
		)
		(polygon
			(pts
				(arc
					(start 285.070042 -307.835046)
					(mid 284.402022 -307.835046)
					(end 285.070042 -307.835046)
				)
			)
		)
	)
	(zone
		(layers "B.Cu" "In6.Cu" "In11.Cu" "In13.Cu" "In15.Cu")
		(hatch none 0.5)
		(connect_pads
			(clearance 0)
		)
		(min_thickness 0.25)
		(keepout
			(tracks not_allowed)
			(vias allowed)
			(pads allowed)
			(copperpour not_allowed)
			(footprints allowed)
		)
		(placement
			(enabled no)
			(sheetname "")
		)
		(fill yes
			(thermal_gap 0.5)
			(thermal_bridge_width 0.5)
			(island_removal_mode 0)
		)
		(polygon
			(pts
				(arc
					(start 340.295992 -254.204216)
					(mid 339.666072 -254.204216)
					(end 340.295992 -254.204216)
				)
			)
		)
	)
	(zone
		(layers "B.Cu" "In6.Cu" "In11.Cu" "In13.Cu" "In15.Cu")
		(hatch none 0.5)
		(connect_pads
			(clearance 0)
		)
		(min_thickness 0.25)
		(keepout
			(tracks not_allowed)
			(vias allowed)
			(pads allowed)
			(copperpour not_allowed)
			(footprints allowed)
		)
		(placement
			(enabled no)
			(sheetname "")
		)
		(fill yes
			(thermal_gap 0.5)
			(thermal_bridge_width 0.5)
			(island_removal_mode 0)
		)
		(polygon
			(pts
				(arc
					(start 435.334156 -272.984976)
					(mid 434.666136 -272.984976)
					(end 435.334156 -272.984976)
				)
			)
		)
	)
	(zone
		(layers "B.Cu" "In6.Cu" "In11.Cu" "In13.Cu" "In15.Cu")
		(hatch none 0.5)
		(connect_pads
			(clearance 0)
		)
		(min_thickness 0.25)
		(keepout
			(tracks not_allowed)
			(vias allowed)
			(pads allowed)
			(copperpour not_allowed)
			(footprints allowed)
		)
		(placement
			(enabled no)
			(sheetname "")
		)
		(fill yes
			(thermal_gap 0.5)
			(thermal_bridge_width 0.5)
			(island_removal_mode 0)
		)
		(polygon
			(pts
				(arc
					(start 280.969974 -199.885046)
					(mid 280.301954 -199.885046)
					(end 280.969974 -199.885046)
				)
			)
		)
	)
	(zone
		(layers "B.Cu" "In6.Cu" "In11.Cu" "In13.Cu" "In15.Cu")
		(hatch none 0.5)
		(connect_pads
			(clearance 0)
		)
		(min_thickness 0.25)
		(keepout
			(tracks not_allowed)
			(vias allowed)
			(pads allowed)
			(copperpour not_allowed)
			(footprints allowed)
		)
		(placement
			(enabled no)
			(sheetname "")
		)
		(fill yes
			(thermal_gap 0.5)
			(thermal_bridge_width 0.5)
			(island_removal_mode 0)
		)
		(polygon
			(pts
				(arc
					(start 102.05593 -291.096192)
					(mid 101.42601 -291.096192)
					(end 102.05593 -291.096192)
				)
			)
		)
	)
	(zone
		(layers "B.Cu" "In6.Cu" "In11.Cu" "In13.Cu" "In15.Cu")
		(hatch none 0.5)
		(connect_pads
			(clearance 0)
		)
		(min_thickness 0.25)
		(keepout
			(tracks not_allowed)
			(vias allowed)
			(pads allowed)
			(copperpour not_allowed)
			(footprints allowed)
		)
		(placement
			(enabled no)
			(sheetname "")
		)
		(fill yes
			(thermal_gap 0.5)
			(thermal_bridge_width 0.5)
			(island_removal_mode 0)
		)
		(polygon
			(pts
				(arc
					(start 365.66983 -234.764072)
					(mid 365.03991 -234.764072)
					(end 365.66983 -234.764072)
				)
			)
		)
	)
	(zone
		(layers "B.Cu" "In6.Cu" "In11.Cu" "In13.Cu" "In15.Cu")
		(hatch none 0.5)
		(connect_pads
			(clearance 0)
		)
		(min_thickness 0.25)
		(keepout
			(tracks not_allowed)
			(vias allowed)
			(pads allowed)
			(copperpour not_allowed)
			(footprints allowed)
		)
		(placement
			(enabled no)
			(sheetname "")
		)
		(fill yes
			(thermal_gap 0.5)
			(thermal_bridge_width 0.5)
			(island_removal_mode 0)
		)
		(polygon
			(pts
				(arc
					(start 412.533846 -397.849344)
					(mid 411.903926 -397.849344)
					(end 412.533846 -397.849344)
				)
			)
		)
	)
	(zone
		(layers "B.Cu" "In6.Cu" "In11.Cu" "In13.Cu" "In15.Cu")
		(hatch none 0.5)
		(connect_pads
			(clearance 0)
		)
		(min_thickness 0.25)
		(keepout
			(tracks not_allowed)
			(vias allowed)
			(pads allowed)
			(copperpour not_allowed)
			(footprints allowed)
		)
		(placement
			(enabled no)
			(sheetname "")
		)
		(fill yes
			(thermal_gap 0.5)
			(thermal_bridge_width 0.5)
			(island_removal_mode 0)
		)
		(polygon
			(pts
				(arc
					(start 381.009906 -263.555988)
					(mid 380.379986 -263.555988)
					(end 381.009906 -263.555988)
				)
			)
		)
	)
	(zone
		(layers "B.Cu" "In6.Cu" "In11.Cu" "In13.Cu" "In15.Cu")
		(hatch none 0.5)
		(connect_pads
			(clearance 0)
		)
		(min_thickness 0.25)
		(keepout
			(tracks not_allowed)
			(vias allowed)
			(pads allowed)
			(copperpour not_allowed)
			(footprints allowed)
		)
		(placement
			(enabled no)
			(sheetname "")
		)
		(fill yes
			(thermal_gap 0.5)
			(thermal_bridge_width 0.5)
			(island_removal_mode 0)
		)
		(polygon
			(pts
				(arc
					(start 285.070042 -220.285056)
					(mid 284.402022 -220.285056)
					(end 285.070042 -220.285056)
				)
			)
		)
	)
	(zone
		(layers "B.Cu" "In6.Cu" "In11.Cu" "In13.Cu" "In15.Cu")
		(hatch none 0.5)
		(connect_pads
			(clearance 0)
		)
		(min_thickness 0.25)
		(keepout
			(tracks not_allowed)
			(vias allowed)
			(pads allowed)
			(copperpour not_allowed)
			(footprints allowed)
		)
		(placement
			(enabled no)
			(sheetname "")
		)
		(fill yes
			(thermal_gap 0.5)
			(thermal_bridge_width 0.5)
			(island_removal_mode 0)
		)
		(polygon
			(pts
				(arc
					(start 37.129974 -278.085296)
					(mid 36.461954 -278.085296)
					(end 37.129974 -278.085296)
				)
			)
		)
	)
	(zone
		(layers "B.Cu" "In6.Cu" "In11.Cu" "In13.Cu" "In15.Cu")
		(hatch none 0.5)
		(connect_pads
			(clearance 0)
		)
		(min_thickness 0.25)
		(keepout
			(tracks not_allowed)
			(vias allowed)
			(pads allowed)
			(copperpour not_allowed)
			(footprints allowed)
		)
		(placement
			(enabled no)
			(sheetname "")
		)
		(fill yes
			(thermal_gap 0.5)
			(thermal_bridge_width 0.5)
			(island_removal_mode 0)
		)
		(polygon
			(pts
				(arc
					(start 134.471156 -404.46452)
					(mid 133.803136 -404.46452)
					(end 134.471156 -404.46452)
				)
			)
		)
	)
	(zone
		(layers "B.Cu" "In6.Cu" "In11.Cu" "In13.Cu" "In15.Cu")
		(hatch none 0.5)
		(connect_pads
			(clearance 0)
		)
		(min_thickness 0.25)
		(keepout
			(tracks not_allowed)
			(vias allowed)
			(pads allowed)
			(copperpour not_allowed)
			(footprints allowed)
		)
		(placement
			(enabled no)
			(sheetname "")
		)
		(fill yes
			(thermal_gap 0.5)
			(thermal_bridge_width 0.5)
			(island_removal_mode 0)
		)
		(polygon
			(pts
				(arc
					(start 439.434224 -225.385122)
					(mid 438.766204 -225.385122)
					(end 439.434224 -225.385122)
				)
			)
		)
	)
	(zone
		(layers "B.Cu" "In6.Cu" "In11.Cu" "In13.Cu" "In15.Cu")
		(hatch none 0.5)
		(connect_pads
			(clearance 0)
		)
		(min_thickness 0.25)
		(keepout
			(tracks not_allowed)
			(vias allowed)
			(pads allowed)
			(copperpour not_allowed)
			(footprints allowed)
		)
		(placement
			(enabled no)
			(sheetname "")
		)
		(fill yes
			(thermal_gap 0.5)
			(thermal_bridge_width 0.5)
			(island_removal_mode 0)
		)
		(polygon
			(pts
				(arc
					(start 339.656166 -281.37612)
					(mid 339.026246 -281.37612)
					(end 339.656166 -281.37612)
				)
			)
		)
	)
	(zone
		(layers "B.Cu" "In6.Cu" "In11.Cu" "In13.Cu" "In15.Cu")
		(hatch none 0.5)
		(connect_pads
			(clearance 0)
		)
		(min_thickness 0.25)
		(keepout
			(tracks not_allowed)
			(vias allowed)
			(pads allowed)
			(copperpour not_allowed)
			(footprints allowed)
		)
		(placement
			(enabled no)
			(sheetname "")
		)
		(fill yes
			(thermal_gap 0.5)
			(thermal_bridge_width 0.5)
			(island_removal_mode 0)
		)
		(polygon
			(pts
				(arc
					(start 435.334156 -248.335038)
					(mid 434.666136 -248.335038)
					(end 435.334156 -248.335038)
				)
			)
		)
	)
	(zone
		(layers "B.Cu" "In6.Cu" "In11.Cu" "In13.Cu" "In15.Cu")
		(hatch none 0.5)
		(connect_pads
			(clearance 0)
		)
		(min_thickness 0.25)
		(keepout
			(tracks not_allowed)
			(vias allowed)
			(pads allowed)
			(copperpour not_allowed)
			(footprints allowed)
		)
		(placement
			(enabled no)
			(sheetname "")
		)
		(fill yes
			(thermal_gap 0.5)
			(thermal_bridge_width 0.5)
			(island_removal_mode 0)
		)
		(polygon
			(pts
				(arc
					(start 439.434224 -220.285056)
					(mid 438.766204 -220.285056)
					(end 439.434224 -220.285056)
				)
			)
		)
	)
	(zone
		(layers "B.Cu" "In6.Cu" "In11.Cu" "In13.Cu" "In15.Cu")
		(hatch none 0.5)
		(connect_pads
			(clearance 0)
		)
		(min_thickness 0.25)
		(keepout
			(tracks not_allowed)
			(vias allowed)
			(pads allowed)
			(copperpour not_allowed)
			(footprints allowed)
		)
		(placement
			(enabled no)
			(sheetname "")
		)
		(fill yes
			(thermal_gap 0.5)
			(thermal_bridge_width 0.5)
			(island_removal_mode 0)
		)
		(polygon
			(pts
				(arc
					(start 91.245944 -274.08632)
					(mid 90.616024 -274.08632)
					(end 91.245944 -274.08632)
				)
			)
		)
	)
	(zone
		(layers "B.Cu" "In6.Cu" "In11.Cu" "In13.Cu" "In15.Cu")
		(hatch none 0.5)
		(connect_pads
			(clearance 0)
		)
		(min_thickness 0.25)
		(keepout
			(tracks not_allowed)
			(vias allowed)
			(pads allowed)
			(copperpour not_allowed)
			(footprints allowed)
		)
		(placement
			(enabled no)
			(sheetname "")
		)
		(fill yes
			(thermal_gap 0.5)
			(thermal_bridge_width 0.5)
			(island_removal_mode 0)
		)
		(polygon
			(pts
				(arc
					(start 31.95447 -4.963414)
					(mid 31.28645 -4.963414)
					(end 31.95447 -4.963414)
				)
			)
		)
	)
	(zone
		(layers "B.Cu" "In6.Cu" "In11.Cu" "In13.Cu" "In15.Cu")
		(hatch none 0.5)
		(connect_pads
			(clearance 0)
		)
		(min_thickness 0.25)
		(keepout
			(tracks not_allowed)
			(vias allowed)
			(pads allowed)
			(copperpour not_allowed)
			(footprints allowed)
		)
		(placement
			(enabled no)
			(sheetname "")
		)
		(fill yes
			(thermal_gap 0.5)
			(thermal_bridge_width 0.5)
			(island_removal_mode 0)
		)
		(polygon
			(pts
				(arc
					(start 406.134062 -397.156432)
					(mid 405.504142 -397.156432)
					(end 406.134062 -397.156432)
				)
			)
		)
	)
	(zone
		(layers "B.Cu" "In6.Cu" "In11.Cu" "In13.Cu" "In15.Cu")
		(hatch none 0.5)
		(connect_pads
			(clearance 0)
		)
		(min_thickness 0.25)
		(keepout
			(tracks not_allowed)
			(vias allowed)
			(pads allowed)
			(copperpour not_allowed)
			(footprints allowed)
		)
		(placement
			(enabled no)
			(sheetname "")
		)
		(fill yes
			(thermal_gap 0.5)
			(thermal_bridge_width 0.5)
			(island_removal_mode 0)
		)
		(polygon
			(pts
				(arc
					(start 33.029906 -227.935282)
					(mid 32.361886 -227.935282)
					(end 33.029906 -227.935282)
				)
			)
		)
	)
	(zone
		(layers "B.Cu" "In6.Cu" "In11.Cu" "In13.Cu" "In15.Cu")
		(hatch none 0.5)
		(connect_pads
			(clearance 0)
		)
		(min_thickness 0.25)
		(keepout
			(tracks not_allowed)
			(vias allowed)
			(pads allowed)
			(copperpour not_allowed)
			(footprints allowed)
		)
		(placement
			(enabled no)
			(sheetname "")
		)
		(fill yes
			(thermal_gap 0.5)
			(thermal_bridge_width 0.5)
			(island_removal_mode 0)
		)
		(polygon
			(pts
				(arc
					(start 380.069852 -276.516084)
					(mid 379.439932 -276.516084)
					(end 380.069852 -276.516084)
				)
			)
		)
	)
	(zone
		(layers "B.Cu" "In6.Cu" "In11.Cu" "In13.Cu" "In15.Cu")
		(hatch none 0.5)
		(connect_pads
			(clearance 0)
		)
		(min_thickness 0.25)
		(keepout
			(tracks not_allowed)
			(vias allowed)
			(pads allowed)
			(copperpour not_allowed)
			(footprints allowed)
		)
		(placement
			(enabled no)
			(sheetname "")
		)
		(fill yes
			(thermal_gap 0.5)
			(thermal_bridge_width 0.5)
			(island_removal_mode 0)
		)
		(polygon
			(pts
				(arc
					(start 381.479806 -262.745982)
					(mid 380.849886 -262.745982)
					(end 381.479806 -262.745982)
				)
			)
		)
	)
	(zone
		(layers "B.Cu" "In6.Cu" "In11.Cu" "In13.Cu" "In15.Cu")
		(hatch none 0.5)
		(connect_pads
			(clearance 0)
		)
		(min_thickness 0.25)
		(keepout
			(tracks not_allowed)
			(vias allowed)
			(pads allowed)
			(copperpour not_allowed)
			(footprints allowed)
		)
		(placement
			(enabled no)
			(sheetname "")
		)
		(fill yes
			(thermal_gap 0.5)
			(thermal_bridge_width 0.5)
			(island_removal_mode 0)
		)
		(polygon
			(pts
				(arc
					(start 132.129784 -289.47618)
					(mid 131.499864 -289.47618)
					(end 132.129784 -289.47618)
				)
			)
		)
	)
	(zone
		(layers "B.Cu" "In6.Cu" "In11.Cu" "In13.Cu" "In15.Cu")
		(hatch none 0.5)
		(connect_pads
			(clearance 0)
		)
		(min_thickness 0.25)
		(keepout
			(tracks not_allowed)
			(vias allowed)
			(pads allowed)
			(copperpour not_allowed)
			(footprints allowed)
		)
		(placement
			(enabled no)
			(sheetname "")
		)
		(fill yes
			(thermal_gap 0.5)
			(thermal_bridge_width 0.5)
			(island_removal_mode 0)
		)
		(polygon
			(pts
				(arc
					(start 92.826078 -242.05438)
					(mid 92.196158 -242.05438)
					(end 92.826078 -242.05438)
				)
			)
		)
	)
	(zone
		(layers "B.Cu" "In6.Cu" "In11.Cu" "In13.Cu" "In15.Cu")
		(hatch none 0.5)
		(connect_pads
			(clearance 0)
		)
		(min_thickness 0.25)
		(keepout
			(tracks not_allowed)
			(vias allowed)
			(pads allowed)
			(copperpour not_allowed)
			(footprints allowed)
		)
		(placement
			(enabled no)
			(sheetname "")
		)
		(fill yes
			(thermal_gap 0.5)
			(thermal_bridge_width 0.5)
			(island_removal_mode 0)
		)
		(polygon
			(pts
				(arc
					(start 187.394088 -226.23526)
					(mid 186.726068 -226.23526)
					(end 187.394088 -226.23526)
				)
			)
		)
	)
	(zone
		(layers "B.Cu" "In6.Cu" "In11.Cu" "In13.Cu" "In15.Cu")
		(hatch none 0.5)
		(connect_pads
			(clearance 0)
		)
		(min_thickness 0.25)
		(keepout
			(tracks not_allowed)
			(vias allowed)
			(pads allowed)
			(copperpour not_allowed)
			(footprints allowed)
		)
		(placement
			(enabled no)
			(sheetname "")
		)
		(fill yes
			(thermal_gap 0.5)
			(thermal_bridge_width 0.5)
			(island_removal_mode 0)
		)
		(polygon
			(pts
				(arc
					(start 131.82981 -244.484398)
					(mid 131.19989 -244.484398)
					(end 131.82981 -244.484398)
				)
			)
		)
	)
	(zone
		(layers "B.Cu" "In6.Cu" "In11.Cu" "In13.Cu" "In15.Cu")
		(hatch none 0.5)
		(connect_pads
			(clearance 0)
		)
		(min_thickness 0.25)
		(keepout
			(tracks not_allowed)
			(vias allowed)
			(pads allowed)
			(copperpour not_allowed)
			(footprints allowed)
		)
		(placement
			(enabled no)
			(sheetname "")
		)
		(fill yes
			(thermal_gap 0.5)
			(thermal_bridge_width 0.5)
			(island_removal_mode 0)
		)
		(polygon
			(pts
				(arc
					(start 153.734008 -388.774432)
					(mid 153.104088 -388.774432)
					(end 153.734008 -388.774432)
				)
			)
		)
	)
	(zone
		(layers "B.Cu" "In6.Cu" "In11.Cu" "In13.Cu" "In15.Cu")
		(hatch none 0.5)
		(connect_pads
			(clearance 0)
		)
		(min_thickness 0.25)
		(keepout
			(tracks not_allowed)
			(vias allowed)
			(pads allowed)
			(copperpour not_allowed)
			(footprints allowed)
		)
		(placement
			(enabled no)
			(sheetname "")
		)
		(fill yes
			(thermal_gap 0.5)
			(thermal_bridge_width 0.5)
			(island_removal_mode 0)
		)
		(polygon
			(pts
				(arc
					(start 364.729776 -233.14406)
					(mid 364.099856 -233.14406)
					(end 364.729776 -233.14406)
				)
			)
		)
	)
	(zone
		(layers "B.Cu" "In6.Cu" "In11.Cu" "In13.Cu" "In15.Cu")
		(hatch none 0.5)
		(connect_pads
			(clearance 0)
		)
		(min_thickness 0.25)
		(keepout
			(tracks not_allowed)
			(vias allowed)
			(pads allowed)
			(copperpour not_allowed)
			(footprints allowed)
		)
		(placement
			(enabled no)
			(sheetname "")
		)
		(fill yes
			(thermal_gap 0.5)
			(thermal_bridge_width 0.5)
			(island_removal_mode 0)
		)
		(polygon
			(pts
				(arc
					(start 191.494156 -267.885418)
					(mid 190.826136 -267.885418)
					(end 191.494156 -267.885418)
				)
			)
		)
	)
	(zone
		(layers "B.Cu" "In6.Cu" "In11.Cu" "In13.Cu" "In15.Cu")
		(hatch none 0.5)
		(connect_pads
			(clearance 0)
		)
		(min_thickness 0.25)
		(keepout
			(tracks not_allowed)
			(vias allowed)
			(pads allowed)
			(copperpour not_allowed)
			(footprints allowed)
		)
		(placement
			(enabled no)
			(sheetname "")
		)
		(fill yes
			(thermal_gap 0.5)
			(thermal_bridge_width 0.5)
			(island_removal_mode 0)
		)
		(polygon
			(pts
				(arc
					(start 175.918114 -369.598448)
					(mid 175.250094 -369.598448)
					(end 175.918114 -369.598448)
				)
			)
		)
	)
	(zone
		(layers "B.Cu" "In6.Cu" "In11.Cu" "In13.Cu" "In15.Cu")
		(hatch none 0.5)
		(connect_pads
			(clearance 0)
		)
		(min_thickness 0.25)
		(keepout
			(tracks not_allowed)
			(vias allowed)
			(pads allowed)
			(copperpour not_allowed)
			(footprints allowed)
		)
		(placement
			(enabled no)
			(sheetname "")
		)
		(fill yes
			(thermal_gap 0.5)
			(thermal_bridge_width 0.5)
			(island_removal_mode 0)
		)
		(polygon
			(pts
				(arc
					(start 338.683854 -379.88113)
					(mid 338.015834 -379.88113)
					(end 338.683854 -379.88113)
				)
			)
		)
	)
	(zone
		(layers "B.Cu" "In6.Cu" "In11.Cu" "In13.Cu" "In15.Cu")
		(hatch none 0.5)
		(connect_pads
			(clearance 0)
		)
		(min_thickness 0.25)
		(keepout
			(tracks not_allowed)
			(vias allowed)
			(pads allowed)
			(copperpour not_allowed)
			(footprints allowed)
		)
		(placement
			(enabled no)
			(sheetname "")
		)
		(fill yes
			(thermal_gap 0.5)
			(thermal_bridge_width 0.5)
			(island_removal_mode 0)
		)
		(polygon
			(pts
				(arc
					(start 435.334156 -295.935146)
					(mid 434.666136 -295.935146)
					(end 435.334156 -295.935146)
				)
			)
		)
	)
	(zone
		(layers "B.Cu" "In6.Cu" "In11.Cu" "In13.Cu" "In15.Cu")
		(hatch none 0.5)
		(connect_pads
			(clearance 0)
		)
		(min_thickness 0.25)
		(keepout
			(tracks not_allowed)
			(vias allowed)
			(pads allowed)
			(copperpour not_allowed)
			(footprints allowed)
		)
		(placement
			(enabled no)
			(sheetname "")
		)
		(fill yes
			(thermal_gap 0.5)
			(thermal_bridge_width 0.5)
			(island_removal_mode 0)
		)
		(polygon
			(pts
				(arc
					(start 399.613374 -19.13636)
					(mid 398.945354 -19.13636)
					(end 399.613374 -19.13636)
				)
			)
		)
	)
	(zone
		(layers "B.Cu" "In6.Cu" "In11.Cu" "In13.Cu" "In15.Cu")
		(hatch none 0.5)
		(connect_pads
			(clearance 0)
		)
		(min_thickness 0.25)
		(keepout
			(tracks not_allowed)
			(vias allowed)
			(pads allowed)
			(copperpour not_allowed)
			(footprints allowed)
		)
		(placement
			(enabled no)
			(sheetname "")
		)
		(fill yes
			(thermal_gap 0.5)
			(thermal_bridge_width 0.5)
			(island_removal_mode 0)
		)
		(polygon
			(pts
				(arc
					(start 191.494156 -238.985298)
					(mid 190.826136 -238.985298)
					(end 191.494156 -238.985298)
				)
			)
		)
	)
	(zone
		(layers "B.Cu" "In6.Cu" "In11.Cu" "In13.Cu" "In15.Cu")
		(hatch none 0.5)
		(connect_pads
			(clearance 0)
		)
		(min_thickness 0.25)
		(keepout
			(tracks not_allowed)
			(vias allowed)
			(pads allowed)
			(copperpour not_allowed)
			(footprints allowed)
		)
		(placement
			(enabled no)
			(sheetname "")
		)
		(fill yes
			(thermal_gap 0.5)
			(thermal_bridge_width 0.5)
			(island_removal_mode 0)
		)
		(polygon
			(pts
				(arc
					(start 379.299724 -237.19409)
					(mid 378.669804 -237.19409)
					(end 379.299724 -237.19409)
				)
			)
		)
	)
	(zone
		(layers "B.Cu" "In6.Cu" "In11.Cu" "In13.Cu" "In15.Cu")
		(hatch none 0.5)
		(connect_pads
			(clearance 0)
		)
		(min_thickness 0.25)
		(keepout
			(tracks not_allowed)
			(vias allowed)
			(pads allowed)
			(copperpour not_allowed)
			(footprints allowed)
		)
		(placement
			(enabled no)
			(sheetname "")
		)
		(fill yes
			(thermal_gap 0.5)
			(thermal_bridge_width 0.5)
			(island_removal_mode 0)
		)
		(polygon
			(pts
				(arc
					(start 352.81616 -287.856168)
					(mid 352.18624 -287.856168)
					(end 352.81616 -287.856168)
				)
			)
		)
	)
	(zone
		(layers "B.Cu" "In6.Cu" "In11.Cu" "In13.Cu" "In15.Cu")
		(hatch none 0.5)
		(connect_pads
			(clearance 0)
		)
		(min_thickness 0.25)
		(keepout
			(tracks not_allowed)
			(vias allowed)
			(pads allowed)
			(copperpour not_allowed)
			(footprints allowed)
		)
		(placement
			(enabled no)
			(sheetname "")
		)
		(fill yes
			(thermal_gap 0.5)
			(thermal_bridge_width 0.5)
			(island_removal_mode 0)
		)
		(polygon
			(pts
				(arc
					(start 379.299724 -250.154186)
					(mid 378.669804 -250.154186)
					(end 379.299724 -250.154186)
				)
			)
		)
	)
	(zone
		(layers "B.Cu" "In6.Cu" "In11.Cu" "In13.Cu" "In15.Cu")
		(hatch none 0.5)
		(connect_pads
			(clearance 0)
		)
		(min_thickness 0.25)
		(keepout
			(tracks not_allowed)
			(vias allowed)
			(pads allowed)
			(copperpour not_allowed)
			(footprints allowed)
		)
		(placement
			(enabled no)
			(sheetname "")
		)
		(fill yes
			(thermal_gap 0.5)
			(thermal_bridge_width 0.5)
			(island_removal_mode 0)
		)
		(polygon
			(pts
				(arc
					(start 37.129974 -301.88535)
					(mid 36.461954 -301.88535)
					(end 37.129974 -301.88535)
				)
			)
		)
	)
	(zone
		(layers "B.Cu" "In6.Cu" "In11.Cu" "In13.Cu" "In15.Cu")
		(hatch none 0.5)
		(connect_pads
			(clearance 0)
		)
		(min_thickness 0.25)
		(keepout
			(tracks not_allowed)
			(vias allowed)
			(pads allowed)
			(copperpour not_allowed)
			(footprints allowed)
		)
		(placement
			(enabled no)
			(sheetname "")
		)
		(fill yes
			(thermal_gap 0.5)
			(thermal_bridge_width 0.5)
			(island_removal_mode 0)
		)
		(polygon
			(pts
				(arc
					(start 139.734036 -404.46452)
					(mid 139.066016 -404.46452)
					(end 139.734036 -404.46452)
				)
			)
		)
	)
	(zone
		(layers "B.Cu" "In6.Cu" "In11.Cu" "In13.Cu" "In15.Cu")
		(hatch none 0.5)
		(connect_pads
			(clearance 0)
		)
		(min_thickness 0.25)
		(keepout
			(tracks not_allowed)
			(vias allowed)
			(pads allowed)
			(copperpour not_allowed)
			(footprints allowed)
		)
		(placement
			(enabled no)
			(sheetname "")
		)
		(fill yes
			(thermal_gap 0.5)
			(thermal_bridge_width 0.5)
			(island_removal_mode 0)
		)
		(polygon
			(pts
				(arc
					(start 131.359656 -250.15444)
					(mid 130.729736 -250.15444)
					(end 131.359656 -250.15444)
				)
			)
		)
	)
	(zone
		(layers "B.Cu" "In6.Cu" "In11.Cu" "In13.Cu" "In15.Cu")
		(hatch none 0.5)
		(connect_pads
			(clearance 0)
		)
		(min_thickness 0.25)
		(keepout
			(tracks not_allowed)
			(vias allowed)
			(pads allowed)
			(copperpour not_allowed)
			(footprints allowed)
		)
		(placement
			(enabled no)
			(sheetname "")
		)
		(fill yes
			(thermal_gap 0.5)
			(thermal_bridge_width 0.5)
			(island_removal_mode 0)
		)
		(polygon
			(pts
				(arc
					(start 338.886038 -248.534174)
					(mid 338.256118 -248.534174)
					(end 338.886038 -248.534174)
				)
			)
		)
	)
	(zone
		(layers "B.Cu" "In6.Cu" "In11.Cu" "In13.Cu" "In15.Cu")
		(hatch none 0.5)
		(connect_pads
			(clearance 0)
		)
		(min_thickness 0.25)
		(keepout
			(tracks not_allowed)
			(vias allowed)
			(pads allowed)
			(copperpour not_allowed)
			(footprints allowed)
		)
		(placement
			(enabled no)
			(sheetname "")
		)
		(fill yes
			(thermal_gap 0.5)
			(thermal_bridge_width 0.5)
			(island_removal_mode 0)
		)
		(polygon
			(pts
				(arc
					(start 280.969974 -215.18499)
					(mid 280.301954 -215.18499)
					(end 280.969974 -215.18499)
				)
			)
		)
	)
	(zone
		(layers "B.Cu" "In6.Cu" "In11.Cu" "In13.Cu" "In15.Cu")
		(hatch none 0.5)
		(connect_pads
			(clearance 0)
		)
		(min_thickness 0.25)
		(keepout
			(tracks not_allowed)
			(vias allowed)
			(pads allowed)
			(copperpour not_allowed)
			(footprints allowed)
		)
		(placement
			(enabled no)
			(sheetname "")
		)
		(fill yes
			(thermal_gap 0.5)
			(thermal_bridge_width 0.5)
			(island_removal_mode 0)
		)
		(polygon
			(pts
				(arc
					(start 380.806198 -393.69238)
					(mid 380.176278 -393.69238)
					(end 380.806198 -393.69238)
				)
			)
		)
	)
	(zone
		(layers "B.Cu" "In6.Cu" "In11.Cu" "In13.Cu" "In15.Cu")
		(hatch none 0.5)
		(connect_pads
			(clearance 0)
		)
		(min_thickness 0.25)
		(keepout
			(tracks not_allowed)
			(vias allowed)
			(pads allowed)
			(copperpour not_allowed)
			(footprints allowed)
		)
		(placement
			(enabled no)
			(sheetname "")
		)
		(fill yes
			(thermal_gap 0.5)
			(thermal_bridge_width 0.5)
			(island_removal_mode 0)
		)
		(polygon
			(pts
				(arc
					(start 320.307716 -412.84652)
					(mid 319.639696 -412.84652)
					(end 320.307716 -412.84652)
				)
			)
		)
	)
	(zone
		(layers "B.Cu" "In6.Cu" "In11.Cu" "In13.Cu" "In15.Cu")
		(hatch none 0.5)
		(connect_pads
			(clearance 0)
		)
		(min_thickness 0.25)
		(keepout
			(tracks not_allowed)
			(vias allowed)
			(pads allowed)
			(copperpour not_allowed)
			(footprints allowed)
		)
		(placement
			(enabled no)
			(sheetname "")
		)
		(fill yes
			(thermal_gap 0.5)
			(thermal_bridge_width 0.5)
			(island_removal_mode 0)
		)
		(polygon
			(pts
				(arc
					(start 92.826078 -233.95432)
					(mid 92.196158 -233.95432)
					(end 92.826078 -233.95432)
				)
			)
		)
	)
	(zone
		(layers "B.Cu" "In6.Cu" "In11.Cu" "In13.Cu" "In15.Cu")
		(hatch none 0.5)
		(connect_pads
			(clearance 0)
		)
		(min_thickness 0.25)
		(keepout
			(tracks not_allowed)
			(vias allowed)
			(pads allowed)
			(copperpour not_allowed)
			(footprints allowed)
		)
		(placement
			(enabled no)
			(sheetname "")
		)
		(fill yes
			(thermal_gap 0.5)
			(thermal_bridge_width 0.5)
			(island_removal_mode 0)
		)
		(polygon
			(pts
				(arc
					(start 363.619796 -288.66592)
					(mid 362.989876 -288.66592)
					(end 363.619796 -288.66592)
				)
			)
		)
	)
	(zone
		(layers "B.Cu" "In6.Cu" "In11.Cu" "In13.Cu" "In15.Cu")
		(hatch none 0.5)
		(connect_pads
			(clearance 0)
		)
		(min_thickness 0.25)
		(keepout
			(tracks not_allowed)
			(vias allowed)
			(pads allowed)
			(copperpour not_allowed)
			(footprints allowed)
		)
		(placement
			(enabled no)
			(sheetname "")
		)
		(fill yes
			(thermal_gap 0.5)
			(thermal_bridge_width 0.5)
			(island_removal_mode 0)
		)
		(polygon
			(pts
				(arc
					(start 435.334156 -202.434952)
					(mid 434.666136 -202.434952)
					(end 435.334156 -202.434952)
				)
			)
		)
	)
	(zone
		(layers "B.Cu" "In6.Cu" "In11.Cu" "In13.Cu" "In15.Cu")
		(hatch none 0.5)
		(connect_pads
			(clearance 0)
		)
		(min_thickness 0.25)
		(keepout
			(tracks not_allowed)
			(vias allowed)
			(pads allowed)
			(copperpour not_allowed)
			(footprints allowed)
		)
		(placement
			(enabled no)
			(sheetname "")
		)
		(fill yes
			(thermal_gap 0.5)
			(thermal_bridge_width 0.5)
			(island_removal_mode 0)
		)
		(polygon
			(pts
				(arc
					(start 22.01799 -4.963414)
					(mid 21.34997 -4.963414)
					(end 22.01799 -4.963414)
				)
			)
		)
	)
	(zone
		(layers "B.Cu" "In6.Cu" "In11.Cu" "In13.Cu" "In15.Cu")
		(hatch none 0.5)
		(connect_pads
			(clearance 0)
		)
		(min_thickness 0.25)
		(keepout
			(tracks not_allowed)
			(vias allowed)
			(pads allowed)
			(copperpour not_allowed)
			(footprints allowed)
		)
		(placement
			(enabled no)
			(sheetname "")
		)
		(fill yes
			(thermal_gap 0.5)
			(thermal_bridge_width 0.5)
			(island_removal_mode 0)
		)
		(polygon
			(pts
				(arc
					(start 37.129974 -216.035382)
					(mid 36.461954 -216.035382)
					(end 37.129974 -216.035382)
				)
			)
		)
	)
	(zone
		(layers "B.Cu" "In6.Cu" "In11.Cu" "In13.Cu" "In15.Cu")
		(hatch none 0.5)
		(connect_pads
			(clearance 0)
		)
		(min_thickness 0.25)
		(keepout
			(tracks not_allowed)
			(vias allowed)
			(pads allowed)
			(copperpour not_allowed)
			(footprints allowed)
		)
		(placement
			(enabled no)
			(sheetname "")
		)
		(fill yes
			(thermal_gap 0.5)
			(thermal_bridge_width 0.5)
			(island_removal_mode 0)
		)
		(polygon
			(pts
				(arc
					(start 379.769878 -238.004096)
					(mid 379.139958 -238.004096)
					(end 379.769878 -238.004096)
				)
			)
		)
	)
	(zone
		(layers "B.Cu" "In6.Cu" "In11.Cu" "In13.Cu" "In15.Cu")
		(hatch none 0.5)
		(connect_pads
			(clearance 0)
		)
		(min_thickness 0.25)
		(keepout
			(tracks not_allowed)
			(vias allowed)
			(pads allowed)
			(copperpour not_allowed)
			(footprints allowed)
		)
		(placement
			(enabled no)
			(sheetname "")
		)
		(fill yes
			(thermal_gap 0.5)
			(thermal_bridge_width 0.5)
			(island_removal_mode 0)
		)
		(polygon
			(pts
				(arc
					(start 439.434224 -214.335106)
					(mid 438.766204 -214.335106)
					(end 439.434224 -214.335106)
				)
			)
		)
	)
	(zone
		(layers "B.Cu" "In6.Cu" "In11.Cu" "In13.Cu" "In15.Cu")
		(hatch none 0.5)
		(connect_pads
			(clearance 0)
		)
		(min_thickness 0.25)
		(keepout
			(tracks not_allowed)
			(vias allowed)
			(pads allowed)
			(copperpour not_allowed)
			(footprints allowed)
		)
		(placement
			(enabled no)
			(sheetname "")
		)
		(fill yes
			(thermal_gap 0.5)
			(thermal_bridge_width 0.5)
			(island_removal_mode 0)
		)
		(polygon
			(pts
				(arc
					(start 380.709678 -247.724168)
					(mid 380.079758 -247.724168)
					(end 380.709678 -247.724168)
				)
			)
		)
	)
	(zone
		(layers "B.Cu" "In6.Cu" "In11.Cu" "In13.Cu" "In15.Cu")
		(hatch none 0.5)
		(connect_pads
			(clearance 0)
		)
		(min_thickness 0.25)
		(keepout
			(tracks not_allowed)
			(vias allowed)
			(pads allowed)
			(copperpour not_allowed)
			(footprints allowed)
		)
		(placement
			(enabled no)
			(sheetname "")
		)
		(fill yes
			(thermal_gap 0.5)
			(thermal_bridge_width 0.5)
			(island_removal_mode 0)
		)
		(polygon
			(pts
				(arc
					(start 123.669806 -291.096192)
					(mid 123.039886 -291.096192)
					(end 123.669806 -291.096192)
				)
			)
		)
	)
	(zone
		(layers "B.Cu" "In6.Cu" "In11.Cu" "In13.Cu" "In15.Cu")
		(hatch none 0.5)
		(connect_pads
			(clearance 0)
		)
		(min_thickness 0.25)
		(keepout
			(tracks not_allowed)
			(vias allowed)
			(pads allowed)
			(copperpour not_allowed)
			(footprints allowed)
		)
		(placement
			(enabled no)
			(sheetname "")
		)
		(fill yes
			(thermal_gap 0.5)
			(thermal_bridge_width 0.5)
			(island_removal_mode 0)
		)
		(polygon
			(pts
				(arc
					(start 285.070042 -234.735116)
					(mid 284.402022 -234.735116)
					(end 285.070042 -234.735116)
				)
			)
		)
	)
	(zone
		(layers "B.Cu" "In6.Cu" "In11.Cu" "In13.Cu" "In15.Cu")
		(hatch none 0.5)
		(connect_pads
			(clearance 0)
		)
		(min_thickness 0.25)
		(keepout
			(tracks not_allowed)
			(vias allowed)
			(pads allowed)
			(copperpour not_allowed)
			(footprints allowed)
		)
		(placement
			(enabled no)
			(sheetname "")
		)
		(fill yes
			(thermal_gap 0.5)
			(thermal_bridge_width 0.5)
			(island_removal_mode 0)
		)
		(polygon
			(pts
				(arc
					(start 339.355938 -241.24412)
					(mid 338.726018 -241.24412)
					(end 339.355938 -241.24412)
				)
			)
		)
	)
	(zone
		(layers "B.Cu" "In6.Cu" "In11.Cu" "In13.Cu" "In15.Cu")
		(hatch none 0.5)
		(connect_pads
			(clearance 0)
		)
		(min_thickness 0.25)
		(keepout
			(tracks not_allowed)
			(vias allowed)
			(pads allowed)
			(copperpour not_allowed)
			(footprints allowed)
		)
		(placement
			(enabled no)
			(sheetname "")
		)
		(fill yes
			(thermal_gap 0.5)
			(thermal_bridge_width 0.5)
			(island_removal_mode 0)
		)
		(polygon
			(pts
				(arc
					(start 435.334156 -210.935062)
					(mid 434.666136 -210.935062)
					(end 435.334156 -210.935062)
				)
			)
		)
	)
	(zone
		(layers "B.Cu" "In6.Cu" "In11.Cu" "In13.Cu" "In15.Cu")
		(hatch none 0.5)
		(connect_pads
			(clearance 0)
		)
		(min_thickness 0.25)
		(keepout
			(tracks not_allowed)
			(vias allowed)
			(pads allowed)
			(copperpour not_allowed)
			(footprints allowed)
		)
		(placement
			(enabled no)
			(sheetname "")
		)
		(fill yes
			(thermal_gap 0.5)
			(thermal_bridge_width 0.5)
			(island_removal_mode 0)
		)
		(polygon
			(pts
				(arc
					(start 373.489728 -291.095938)
					(mid 372.859808 -291.095938)
					(end 373.489728 -291.095938)
				)
			)
		)
	)
	(zone
		(layers "B.Cu" "In6.Cu" "In11.Cu" "In13.Cu" "In15.Cu")
		(hatch none 0.5)
		(connect_pads
			(clearance 0)
		)
		(min_thickness 0.25)
		(keepout
			(tracks not_allowed)
			(vias allowed)
			(pads allowed)
			(copperpour not_allowed)
			(footprints allowed)
		)
		(placement
			(enabled no)
			(sheetname "")
		)
		(fill yes
			(thermal_gap 0.5)
			(thermal_bridge_width 0.5)
			(island_removal_mode 0)
		)
		(polygon
			(pts
				(arc
					(start 382.006094 -393.69238)
					(mid 381.376174 -393.69238)
					(end 382.006094 -393.69238)
				)
			)
		)
	)
	(zone
		(layers "B.Cu" "In6.Cu" "In11.Cu" "In13.Cu" "In15.Cu")
		(hatch none 0.5)
		(connect_pads
			(clearance 0)
		)
		(min_thickness 0.25)
		(keepout
			(tracks not_allowed)
			(vias allowed)
			(pads allowed)
			(copperpour not_allowed)
			(footprints allowed)
		)
		(placement
			(enabled no)
			(sheetname "")
		)
		(fill yes
			(thermal_gap 0.5)
			(thermal_bridge_width 0.5)
			(island_removal_mode 0)
		)
		(polygon
			(pts
				(arc
					(start 340.295992 -226.664266)
					(mid 339.666072 -226.664266)
					(end 340.295992 -226.664266)
				)
			)
		)
	)
	(zone
		(layers "B.Cu" "In6.Cu" "In11.Cu" "In13.Cu" "In15.Cu")
		(hatch none 0.5)
		(connect_pads
			(clearance 0)
		)
		(min_thickness 0.25)
		(keepout
			(tracks not_allowed)
			(vias allowed)
			(pads allowed)
			(copperpour not_allowed)
			(footprints allowed)
		)
		(placement
			(enabled no)
			(sheetname "")
		)
		(fill yes
			(thermal_gap 0.5)
			(thermal_bridge_width 0.5)
			(island_removal_mode 0)
		)
		(polygon
			(pts
				(arc
					(start 187.394088 -302.735234)
					(mid 186.726068 -302.735234)
					(end 187.394088 -302.735234)
				)
			)
		)
	)
	(zone
		(layers "B.Cu" "In6.Cu" "In11.Cu" "In13.Cu" "In15.Cu")
		(hatch none 0.5)
		(connect_pads
			(clearance 0)
		)
		(min_thickness 0.25)
		(keepout
			(tracks not_allowed)
			(vias allowed)
			(pads allowed)
			(copperpour not_allowed)
			(footprints allowed)
		)
		(placement
			(enabled no)
			(sheetname "")
		)
		(fill yes
			(thermal_gap 0.5)
			(thermal_bridge_width 0.5)
			(island_removal_mode 0)
		)
		(polygon
			(pts
				(arc
					(start 280.969974 -282.33497)
					(mid 280.301954 -282.33497)
					(end 280.969974 -282.33497)
				)
			)
		)
	)
	(zone
		(layers "B.Cu" "In6.Cu" "In11.Cu" "In13.Cu" "In15.Cu")
		(hatch none 0.5)
		(connect_pads
			(clearance 0)
		)
		(min_thickness 0.25)
		(keepout
			(tracks not_allowed)
			(vias allowed)
			(pads allowed)
			(copperpour not_allowed)
			(footprints allowed)
		)
		(placement
			(enabled no)
			(sheetname "")
		)
		(fill yes
			(thermal_gap 0.5)
			(thermal_bridge_width 0.5)
			(island_removal_mode 0)
		)
		(polygon
			(pts
				(arc
					(start 101.403912 -369.03533)
					(mid 100.735892 -369.03533)
					(end 101.403912 -369.03533)
				)
			)
		)
	)
	(zone
		(layers "B.Cu" "In6.Cu" "In11.Cu" "In13.Cu" "In15.Cu")
		(hatch none 0.5)
		(connect_pads
			(clearance 0)
		)
		(min_thickness 0.25)
		(keepout
			(tracks not_allowed)
			(vias allowed)
			(pads allowed)
			(copperpour not_allowed)
			(footprints allowed)
		)
		(placement
			(enabled no)
			(sheetname "")
		)
		(fill yes
			(thermal_gap 0.5)
			(thermal_bridge_width 0.5)
			(island_removal_mode 0)
		)
		(polygon
			(pts
				(arc
					(start 340.295992 -249.34418)
					(mid 339.666072 -249.34418)
					(end 340.295992 -249.34418)
				)
			)
		)
	)
	(zone
		(layers "B.Cu" "In6.Cu" "In11.Cu" "In13.Cu" "In15.Cu")
		(hatch none 0.5)
		(connect_pads
			(clearance 0)
		)
		(min_thickness 0.25)
		(keepout
			(tracks not_allowed)
			(vias allowed)
			(pads allowed)
			(copperpour not_allowed)
			(footprints allowed)
		)
		(placement
			(enabled no)
			(sheetname "")
		)
		(fill yes
			(thermal_gap 0.5)
			(thermal_bridge_width 0.5)
			(island_removal_mode 0)
		)
		(polygon
			(pts
				(arc
					(start 133.539738 -269.226284)
					(mid 132.909818 -269.226284)
					(end 133.539738 -269.226284)
				)
			)
		)
	)
	(zone
		(layers "B.Cu" "In6.Cu" "In11.Cu" "In13.Cu" "In15.Cu")
		(hatch none 0.5)
		(connect_pads
			(clearance 0)
		)
		(min_thickness 0.25)
		(keepout
			(tracks not_allowed)
			(vias allowed)
			(pads allowed)
			(copperpour not_allowed)
			(footprints allowed)
		)
		(placement
			(enabled no)
			(sheetname "")
		)
		(fill yes
			(thermal_gap 0.5)
			(thermal_bridge_width 0.5)
			(island_removal_mode 0)
		)
		(polygon
			(pts
				(arc
					(start 109.746034 -233.95432)
					(mid 109.116114 -233.95432)
					(end 109.746034 -233.95432)
				)
			)
		)
	)
	(zone
		(layers "B.Cu" "In6.Cu" "In11.Cu" "In13.Cu" "In15.Cu")
		(hatch none 0.5)
		(connect_pads
			(clearance 0)
		)
		(min_thickness 0.25)
		(keepout
			(tracks not_allowed)
			(vias allowed)
			(pads allowed)
			(copperpour not_allowed)
			(footprints allowed)
		)
		(placement
			(enabled no)
			(sheetname "")
		)
		(fill yes
			(thermal_gap 0.5)
			(thermal_bridge_width 0.5)
			(island_removal_mode 0)
		)
		(polygon
			(pts
				(arc
					(start 133.239764 -229.094538)
					(mid 132.609844 -229.094538)
					(end 133.239764 -229.094538)
				)
			)
		)
	)
	(zone
		(layers "B.Cu" "In6.Cu" "In11.Cu" "In13.Cu" "In15.Cu")
		(hatch none 0.5)
		(connect_pads
			(clearance 0)
		)
		(min_thickness 0.25)
		(keepout
			(tracks not_allowed)
			(vias allowed)
			(pads allowed)
			(copperpour not_allowed)
			(footprints allowed)
		)
		(placement
			(enabled no)
			(sheetname "")
		)
		(fill yes
			(thermal_gap 0.5)
			(thermal_bridge_width 0.5)
			(island_removal_mode 0)
		)
		(polygon
			(pts
				(arc
					(start 435.334156 -310.384952)
					(mid 434.666136 -310.384952)
					(end 435.334156 -310.384952)
				)
			)
		)
	)
	(zone
		(layers "B.Cu" "In6.Cu" "In11.Cu" "In13.Cu" "In15.Cu")
		(hatch none 0.5)
		(connect_pads
			(clearance 0)
		)
		(min_thickness 0.25)
		(keepout
			(tracks not_allowed)
			(vias allowed)
			(pads allowed)
			(copperpour not_allowed)
			(footprints allowed)
		)
		(placement
			(enabled no)
			(sheetname "")
		)
		(fill yes
			(thermal_gap 0.5)
			(thermal_bridge_width 0.5)
			(island_removal_mode 0)
		)
		(polygon
			(pts
				(arc
					(start 191.494156 -212.635338)
					(mid 190.826136 -212.635338)
					(end 191.494156 -212.635338)
				)
			)
		)
	)
	(zone
		(layers "B.Cu" "In6.Cu" "In11.Cu" "In13.Cu" "In15.Cu")
		(hatch none 0.5)
		(connect_pads
			(clearance 0)
		)
		(min_thickness 0.25)
		(keepout
			(tracks not_allowed)
			(vias allowed)
			(pads allowed)
			(copperpour not_allowed)
			(footprints allowed)
		)
		(placement
			(enabled no)
			(sheetname "")
		)
		(fill yes
			(thermal_gap 0.5)
			(thermal_bridge_width 0.5)
			(island_removal_mode 0)
		)
		(polygon
			(pts
				(arc
					(start 133.069838 -266.796266)
					(mid 132.439918 -266.796266)
					(end 133.069838 -266.796266)
				)
			)
		)
	)
	(zone
		(layers "B.Cu" "In6.Cu" "In11.Cu" "In13.Cu" "In15.Cu")
		(hatch none 0.5)
		(connect_pads
			(clearance 0)
		)
		(min_thickness 0.25)
		(keepout
			(tracks not_allowed)
			(vias allowed)
			(pads allowed)
			(copperpour not_allowed)
			(footprints allowed)
		)
		(placement
			(enabled no)
			(sheetname "")
		)
		(fill yes
			(thermal_gap 0.5)
			(thermal_bridge_width 0.5)
			(island_removal_mode 0)
		)
		(polygon
			(pts
				(arc
					(start 164.933884 -389.467344)
					(mid 164.303964 -389.467344)
					(end 164.933884 -389.467344)
				)
			)
		)
	)
	(zone
		(layers "B.Cu" "In6.Cu" "In11.Cu" "In13.Cu" "In15.Cu")
		(hatch none 0.5)
		(connect_pads
			(clearance 0)
		)
		(min_thickness 0.25)
		(keepout
			(tracks not_allowed)
			(vias allowed)
			(pads allowed)
			(copperpour not_allowed)
			(footprints allowed)
		)
		(placement
			(enabled no)
			(sheetname "")
		)
		(fill yes
			(thermal_gap 0.5)
			(thermal_bridge_width 0.5)
			(island_removal_mode 0)
		)
		(polygon
			(pts
				(arc
					(start 123.669806 -289.47618)
					(mid 123.039886 -289.47618)
					(end 123.669806 -289.47618)
				)
			)
		)
	)
	(zone
		(layers "B.Cu" "In6.Cu" "In11.Cu" "In13.Cu" "In15.Cu")
		(hatch none 0.5)
		(connect_pads
			(clearance 0)
		)
		(min_thickness 0.25)
		(keepout
			(tracks not_allowed)
			(vias allowed)
			(pads allowed)
			(copperpour not_allowed)
			(footprints allowed)
		)
		(placement
			(enabled no)
			(sheetname "")
		)
		(fill yes
			(thermal_gap 0.5)
			(thermal_bridge_width 0.5)
			(island_removal_mode 0)
		)
		(polygon
			(pts
				(arc
					(start 339.656166 -289.475926)
					(mid 339.026246 -289.475926)
					(end 339.656166 -289.475926)
				)
			)
		)
	)
	(zone
		(layers "B.Cu" "In6.Cu" "In11.Cu" "In13.Cu" "In15.Cu")
		(hatch none 0.5)
		(connect_pads
			(clearance 0)
		)
		(min_thickness 0.25)
		(keepout
			(tracks not_allowed)
			(vias allowed)
			(pads allowed)
			(copperpour not_allowed)
			(footprints allowed)
		)
		(placement
			(enabled no)
			(sheetname "")
		)
		(fill yes
			(thermal_gap 0.5)
			(thermal_bridge_width 0.5)
			(island_removal_mode 0)
		)
		(polygon
			(pts
				(arc
					(start 100.815902 -234.764326)
					(mid 100.185982 -234.764326)
					(end 100.815902 -234.764326)
				)
			)
		)
	)
	(zone
		(layers "B.Cu" "In6.Cu" "In11.Cu" "In13.Cu" "In15.Cu")
		(hatch none 0.5)
		(connect_pads
			(clearance 0)
		)
		(min_thickness 0.25)
		(keepout
			(tracks not_allowed)
			(vias allowed)
			(pads allowed)
			(copperpour not_allowed)
			(footprints allowed)
		)
		(placement
			(enabled no)
			(sheetname "")
		)
		(fill yes
			(thermal_gap 0.5)
			(thermal_bridge_width 0.5)
			(island_removal_mode 0)
		)
		(polygon
			(pts
				(arc
					(start 123.369578 -228.284532)
					(mid 122.739658 -228.284532)
					(end 123.369578 -228.284532)
				)
			)
		)
	)
	(zone
		(layers "B.Cu" "In6.Cu" "In11.Cu" "In13.Cu" "In15.Cu")
		(hatch none 0.5)
		(connect_pads
			(clearance 0)
		)
		(min_thickness 0.25)
		(keepout
			(tracks not_allowed)
			(vias allowed)
			(pads allowed)
			(copperpour not_allowed)
			(footprints allowed)
		)
		(placement
			(enabled no)
			(sheetname "")
		)
		(fill yes
			(thermal_gap 0.5)
			(thermal_bridge_width 0.5)
			(island_removal_mode 0)
		)
		(polygon
			(pts
				(arc
					(start 427.029626 -19.13636)
					(mid 426.361606 -19.13636)
					(end 427.029626 -19.13636)
				)
			)
		)
	)
	(zone
		(layers "B.Cu" "In6.Cu" "In11.Cu" "In13.Cu" "In15.Cu")
		(hatch none 0.5)
		(connect_pads
			(clearance 0)
		)
		(min_thickness 0.25)
		(keepout
			(tracks not_allowed)
			(vias allowed)
			(pads allowed)
			(copperpour not_allowed)
			(footprints allowed)
		)
		(placement
			(enabled no)
			(sheetname "")
		)
		(fill yes
			(thermal_gap 0.5)
			(thermal_bridge_width 0.5)
			(island_removal_mode 0)
		)
		(polygon
			(pts
				(arc
					(start 187.394088 -282.335224)
					(mid 186.726068 -282.335224)
					(end 187.394088 -282.335224)
				)
			)
		)
	)
	(zone
		(layers "B.Cu" "In6.Cu" "In11.Cu" "In13.Cu" "In15.Cu")
		(hatch none 0.5)
		(connect_pads
			(clearance 0)
		)
		(min_thickness 0.25)
		(keepout
			(tracks not_allowed)
			(vias allowed)
			(pads allowed)
			(copperpour not_allowed)
			(footprints allowed)
		)
		(placement
			(enabled no)
			(sheetname "")
		)
		(fill yes
			(thermal_gap 0.5)
			(thermal_bridge_width 0.5)
			(island_removal_mode 0)
		)
		(polygon
			(pts
				(arc
					(start 390.367774 -17.61236)
					(mid 389.699754 -17.61236)
					(end 390.367774 -17.61236)
				)
			)
		)
	)
	(zone
		(layers "B.Cu" "In6.Cu" "In11.Cu" "In13.Cu" "In15.Cu")
		(hatch none 0.5)
		(connect_pads
			(clearance 0)
		)
		(min_thickness 0.25)
		(keepout
			(tracks not_allowed)
			(vias allowed)
			(pads allowed)
			(copperpour not_allowed)
			(footprints allowed)
		)
		(placement
			(enabled no)
			(sheetname "")
		)
		(fill yes
			(thermal_gap 0.5)
			(thermal_bridge_width 0.5)
			(island_removal_mode 0)
		)
		(polygon
			(pts
				(arc
					(start 93.126052 -282.18638)
					(mid 92.496132 -282.18638)
					(end 93.126052 -282.18638)
				)
			)
		)
	)
	(zone
		(layers "B.Cu" "In6.Cu" "In11.Cu" "In13.Cu" "In15.Cu")
		(hatch none 0.5)
		(connect_pads
			(clearance 0)
		)
		(min_thickness 0.25)
		(keepout
			(tracks not_allowed)
			(vias allowed)
			(pads allowed)
			(copperpour not_allowed)
			(footprints allowed)
		)
		(placement
			(enabled no)
			(sheetname "")
		)
		(fill yes
			(thermal_gap 0.5)
			(thermal_bridge_width 0.5)
			(island_removal_mode 0)
		)
		(polygon
			(pts
				(arc
					(start 80.982312 -373.96293)
					(mid 80.314292 -373.96293)
					(end 80.982312 -373.96293)
				)
			)
		)
	)
	(zone
		(layers "B.Cu" "In6.Cu" "In11.Cu" "In13.Cu" "In15.Cu")
		(hatch none 0.5)
		(connect_pads
			(clearance 0)
		)
		(min_thickness 0.25)
		(keepout
			(tracks not_allowed)
			(vias allowed)
			(pads allowed)
			(copperpour not_allowed)
			(footprints allowed)
		)
		(placement
			(enabled no)
			(sheetname "")
		)
		(fill yes
			(thermal_gap 0.5)
			(thermal_bridge_width 0.5)
			(island_removal_mode 0)
		)
		(polygon
			(pts
				(arc
					(start 28.354274 -4.963414)
					(mid 27.686254 -4.963414)
					(end 28.354274 -4.963414)
				)
			)
		)
	)
	(zone
		(layers "B.Cu" "In6.Cu" "In11.Cu" "In13.Cu" "In15.Cu")
		(hatch none 0.5)
		(connect_pads
			(clearance 0)
		)
		(min_thickness 0.25)
		(keepout
			(tracks not_allowed)
			(vias allowed)
			(pads allowed)
			(copperpour not_allowed)
			(footprints allowed)
		)
		(placement
			(enabled no)
			(sheetname "")
		)
		(fill yes
			(thermal_gap 0.5)
			(thermal_bridge_width 0.5)
			(island_removal_mode 0)
		)
		(polygon
			(pts
				(arc
					(start 381.281432 -412.84652)
					(mid 380.613412 -412.84652)
					(end 381.281432 -412.84652)
				)
			)
		)
	)
	(zone
		(layers "B.Cu" "In6.Cu" "In11.Cu" "In13.Cu" "In15.Cu")
		(hatch none 0.5)
		(connect_pads
			(clearance 0)
		)
		(min_thickness 0.25)
		(keepout
			(tracks not_allowed)
			(vias allowed)
			(pads allowed)
			(copperpour not_allowed)
			(footprints allowed)
		)
		(placement
			(enabled no)
			(sheetname "")
		)
		(fill yes
			(thermal_gap 0.5)
			(thermal_bridge_width 0.5)
			(island_removal_mode 0)
		)
		(polygon
			(pts
				(arc
					(start 354.39604 -229.904036)
					(mid 353.76612 -229.904036)
					(end 354.39604 -229.904036)
				)
			)
		)
	)
	(zone
		(layers "B.Cu" "In6.Cu" "In11.Cu" "In13.Cu" "In15.Cu")
		(hatch none 0.5)
		(connect_pads
			(clearance 0)
		)
		(min_thickness 0.25)
		(keepout
			(tracks not_allowed)
			(vias allowed)
			(pads allowed)
			(copperpour not_allowed)
			(footprints allowed)
		)
		(placement
			(enabled no)
			(sheetname "")
		)
		(fill yes
			(thermal_gap 0.5)
			(thermal_bridge_width 0.5)
			(island_removal_mode 0)
		)
		(polygon
			(pts
				(arc
					(start 92.655898 -271.656302)
					(mid 92.025978 -271.656302)
					(end 92.655898 -271.656302)
				)
			)
		)
	)
	(zone
		(layers "B.Cu" "In6.Cu" "In11.Cu" "In13.Cu" "In15.Cu")
		(hatch none 0.5)
		(connect_pads
			(clearance 0)
		)
		(min_thickness 0.25)
		(keepout
			(tracks not_allowed)
			(vias allowed)
			(pads allowed)
			(copperpour not_allowed)
			(footprints allowed)
		)
		(placement
			(enabled no)
			(sheetname "")
		)
		(fill yes
			(thermal_gap 0.5)
			(thermal_bridge_width 0.5)
			(island_removal_mode 0)
		)
		(polygon
			(pts
				(arc
					(start 133.069838 -279.756362)
					(mid 132.439918 -279.756362)
					(end 133.069838 -279.756362)
				)
			)
		)
	)
	(zone
		(layers "B.Cu" "In6.Cu" "In11.Cu" "In13.Cu" "In15.Cu")
		(hatch none 0.5)
		(connect_pads
			(clearance 0)
		)
		(min_thickness 0.25)
		(keepout
			(tracks not_allowed)
			(vias allowed)
			(pads allowed)
			(copperpour not_allowed)
			(footprints allowed)
		)
		(placement
			(enabled no)
			(sheetname "")
		)
		(fill yes
			(thermal_gap 0.5)
			(thermal_bridge_width 0.5)
			(island_removal_mode 0)
		)
		(polygon
			(pts
				(arc
					(start 92.826078 -240.434368)
					(mid 92.196158 -240.434368)
					(end 92.826078 -240.434368)
				)
			)
		)
	)
	(zone
		(layers "B.Cu" "In6.Cu" "In11.Cu" "In13.Cu" "In15.Cu")
		(hatch none 0.5)
		(connect_pads
			(clearance 0)
		)
		(min_thickness 0.25)
		(keepout
			(tracks not_allowed)
			(vias allowed)
			(pads allowed)
			(copperpour not_allowed)
			(footprints allowed)
		)
		(placement
			(enabled no)
			(sheetname "")
		)
		(fill yes
			(thermal_gap 0.5)
			(thermal_bridge_width 0.5)
			(island_removal_mode 0)
		)
		(polygon
			(pts
				(arc
					(start 92.355924 -246.10441)
					(mid 91.726004 -246.10441)
					(end 92.355924 -246.10441)
				)
			)
		)
	)
	(zone
		(layers "B.Cu" "In6.Cu" "In11.Cu" "In13.Cu" "In15.Cu")
		(hatch none 0.5)
		(connect_pads
			(clearance 0)
		)
		(min_thickness 0.25)
		(keepout
			(tracks not_allowed)
			(vias allowed)
			(pads allowed)
			(copperpour not_allowed)
			(footprints allowed)
		)
		(placement
			(enabled no)
			(sheetname "")
		)
		(fill yes
			(thermal_gap 0.5)
			(thermal_bridge_width 0.5)
			(island_removal_mode 0)
		)
		(polygon
			(pts
				(arc
					(start 404.923752 -412.84652)
					(mid 404.255732 -412.84652)
					(end 404.923752 -412.84652)
				)
			)
		)
	)
	(zone
		(layers "B.Cu" "In6.Cu" "In11.Cu" "In13.Cu" "In15.Cu")
		(hatch none 0.5)
		(connect_pads
			(clearance 0)
		)
		(min_thickness 0.25)
		(keepout
			(tracks not_allowed)
			(vias allowed)
			(pads allowed)
			(copperpour not_allowed)
			(footprints allowed)
		)
		(placement
			(enabled no)
			(sheetname "")
		)
		(fill yes
			(thermal_gap 0.5)
			(thermal_bridge_width 0.5)
			(island_removal_mode 0)
		)
		(polygon
			(pts
				(arc
					(start 351.876106 -291.095938)
					(mid 351.246186 -291.095938)
					(end 351.876106 -291.095938)
				)
			)
		)
	)
	(zone
		(layers "B.Cu" "In6.Cu" "In11.Cu" "In13.Cu" "In15.Cu")
		(hatch none 0.5)
		(connect_pads
			(clearance 0)
		)
		(min_thickness 0.25)
		(keepout
			(tracks not_allowed)
			(vias allowed)
			(pads allowed)
			(copperpour not_allowed)
			(footprints allowed)
		)
		(placement
			(enabled no)
			(sheetname "")
		)
		(fill yes
			(thermal_gap 0.5)
			(thermal_bridge_width 0.5)
			(island_removal_mode 0)
		)
		(polygon
			(pts
				(arc
					(start 339.355938 -255.824228)
					(mid 338.726018 -255.824228)
					(end 339.355938 -255.824228)
				)
			)
		)
	)
	(zone
		(layers "B.Cu" "In6.Cu" "In11.Cu" "In13.Cu" "In15.Cu")
		(hatch none 0.5)
		(connect_pads
			(clearance 0)
		)
		(min_thickness 0.25)
		(keepout
			(tracks not_allowed)
			(vias allowed)
			(pads allowed)
			(copperpour not_allowed)
			(footprints allowed)
		)
		(placement
			(enabled no)
			(sheetname "")
		)
		(fill yes
			(thermal_gap 0.5)
			(thermal_bridge_width 0.5)
			(island_removal_mode 0)
		)
		(polygon
			(pts
				(arc
					(start 33.029906 -282.335224)
					(mid 32.361886 -282.335224)
					(end 33.029906 -282.335224)
				)
			)
		)
	)
	(zone
		(layers "B.Cu" "In6.Cu" "In11.Cu" "In13.Cu" "In15.Cu")
		(hatch none 0.5)
		(connect_pads
			(clearance 0)
		)
		(min_thickness 0.25)
		(keepout
			(tracks not_allowed)
			(vias allowed)
			(pads allowed)
			(copperpour not_allowed)
			(footprints allowed)
		)
		(placement
			(enabled no)
			(sheetname "")
		)
		(fill yes
			(thermal_gap 0.5)
			(thermal_bridge_width 0.5)
			(island_removal_mode 0)
		)
		(polygon
			(pts
				(arc
					(start 382.406144 -394.385292)
					(mid 381.776224 -394.385292)
					(end 382.406144 -394.385292)
				)
			)
		)
	)
	(zone
		(layers "B.Cu" "In6.Cu" "In11.Cu" "In13.Cu" "In15.Cu")
		(hatch none 0.5)
		(connect_pads
			(clearance 0)
		)
		(min_thickness 0.25)
		(keepout
			(tracks not_allowed)
			(vias allowed)
			(pads allowed)
			(copperpour not_allowed)
			(footprints allowed)
		)
		(placement
			(enabled no)
			(sheetname "")
		)
		(fill yes
			(thermal_gap 0.5)
			(thermal_bridge_width 0.5)
			(island_removal_mode 0)
		)
		(polygon
			(pts
				(arc
					(start 339.186012 -275.706078)
					(mid 338.556092 -275.706078)
					(end 339.186012 -275.706078)
				)
			)
		)
	)
	(zone
		(layers "B.Cu" "In6.Cu" "In11.Cu" "In13.Cu" "In15.Cu")
		(hatch none 0.5)
		(connect_pads
			(clearance 0)
		)
		(min_thickness 0.25)
		(keepout
			(tracks not_allowed)
			(vias allowed)
			(pads allowed)
			(copperpour not_allowed)
			(footprints allowed)
		)
		(placement
			(enabled no)
			(sheetname "")
		)
		(fill yes
			(thermal_gap 0.5)
			(thermal_bridge_width 0.5)
			(island_removal_mode 0)
		)
		(polygon
			(pts
				(arc
					(start 418.61359 -17.61236)
					(mid 417.94557 -17.61236)
					(end 418.61359 -17.61236)
				)
			)
		)
	)
	(zone
		(layers "B.Cu" "In6.Cu" "In11.Cu" "In13.Cu" "In15.Cu")
		(hatch none 0.5)
		(connect_pads
			(clearance 0)
		)
		(min_thickness 0.25)
		(keepout
			(tracks not_allowed)
			(vias allowed)
			(pads allowed)
			(copperpour not_allowed)
			(footprints allowed)
		)
		(placement
			(enabled no)
			(sheetname "")
		)
		(fill yes
			(thermal_gap 0.5)
			(thermal_bridge_width 0.5)
			(island_removal_mode 0)
		)
		(polygon
			(pts
				(arc
					(start 92.355924 -226.66452)
					(mid 91.726004 -226.66452)
					(end 92.355924 -226.66452)
				)
			)
		)
	)
	(zone
		(layers "B.Cu" "In6.Cu" "In11.Cu" "In13.Cu" "In15.Cu")
		(hatch none 0.5)
		(connect_pads
			(clearance 0)
		)
		(min_thickness 0.25)
		(keepout
			(tracks not_allowed)
			(vias allowed)
			(pads allowed)
			(copperpour not_allowed)
			(footprints allowed)
		)
		(placement
			(enabled no)
			(sheetname "")
		)
		(fill yes
			(thermal_gap 0.5)
			(thermal_bridge_width 0.5)
			(island_removal_mode 0)
		)
		(polygon
			(pts
				(arc
					(start 100.815902 -236.384338)
					(mid 100.185982 -236.384338)
					(end 100.815902 -236.384338)
				)
			)
		)
	)
	(zone
		(layers "B.Cu" "In6.Cu" "In11.Cu" "In13.Cu" "In15.Cu")
		(hatch none 0.5)
		(connect_pads
			(clearance 0)
		)
		(min_thickness 0.25)
		(keepout
			(tracks not_allowed)
			(vias allowed)
			(pads allowed)
			(copperpour not_allowed)
			(footprints allowed)
		)
		(placement
			(enabled no)
			(sheetname "")
		)
		(fill yes
			(thermal_gap 0.5)
			(thermal_bridge_width 0.5)
			(island_removal_mode 0)
		)
		(polygon
			(pts
				(arc
					(start 131.65963 -291.906198)
					(mid 131.02971 -291.906198)
					(end 131.65963 -291.906198)
				)
			)
		)
	)
	(zone
		(layers "B.Cu" "In6.Cu" "In11.Cu" "In13.Cu" "In15.Cu")
		(hatch none 0.5)
		(connect_pads
			(clearance 0)
		)
		(min_thickness 0.25)
		(keepout
			(tracks not_allowed)
			(vias allowed)
			(pads allowed)
			(copperpour not_allowed)
			(footprints allowed)
		)
		(placement
			(enabled no)
			(sheetname "")
		)
		(fill yes
			(thermal_gap 0.5)
			(thermal_bridge_width 0.5)
			(island_removal_mode 0)
		)
		(polygon
			(pts
				(arc
					(start 362.379768 -232.334054)
					(mid 361.749848 -232.334054)
					(end 362.379768 -232.334054)
				)
			)
		)
	)
	(zone
		(layers "B.Cu" "In6.Cu" "In11.Cu" "In13.Cu" "In15.Cu")
		(hatch none 0.5)
		(connect_pads
			(clearance 0)
		)
		(min_thickness 0.25)
		(keepout
			(tracks not_allowed)
			(vias allowed)
			(pads allowed)
			(copperpour not_allowed)
			(footprints allowed)
		)
		(placement
			(enabled no)
			(sheetname "")
		)
		(fill yes
			(thermal_gap 0.5)
			(thermal_bridge_width 0.5)
			(island_removal_mode 0)
		)
		(polygon
			(pts
				(arc
					(start 114.739674 -288.666174)
					(mid 114.109754 -288.666174)
					(end 114.739674 -288.666174)
				)
			)
		)
	)
	(zone
		(layers "B.Cu" "In6.Cu" "In11.Cu" "In13.Cu" "In15.Cu")
		(hatch none 0.5)
		(connect_pads
			(clearance 0)
		)
		(min_thickness 0.25)
		(keepout
			(tracks not_allowed)
			(vias allowed)
			(pads allowed)
			(copperpour not_allowed)
			(footprints allowed)
		)
		(placement
			(enabled no)
			(sheetname "")
		)
		(fill yes
			(thermal_gap 0.5)
			(thermal_bridge_width 0.5)
			(island_removal_mode 0)
		)
		(polygon
			(pts
				(arc
					(start 131.65963 -287.046162)
					(mid 131.02971 -287.046162)
					(end 131.65963 -287.046162)
				)
			)
		)
	)
	(zone
		(layers "B.Cu" "In6.Cu" "In11.Cu" "In13.Cu" "In15.Cu")
		(hatch none 0.5)
		(connect_pads
			(clearance 0)
		)
		(min_thickness 0.25)
		(keepout
			(tracks not_allowed)
			(vias allowed)
			(pads allowed)
			(copperpour not_allowed)
			(footprints allowed)
		)
		(placement
			(enabled no)
			(sheetname "")
		)
		(fill yes
			(thermal_gap 0.5)
			(thermal_bridge_width 0.5)
			(island_removal_mode 0)
		)
		(polygon
			(pts
				(arc
					(start 433.481226 -19.13636)
					(mid 432.813206 -19.13636)
					(end 433.481226 -19.13636)
				)
			)
		)
	)
	(zone
		(layers "B.Cu" "In6.Cu" "In11.Cu" "In13.Cu" "In15.Cu")
		(hatch none 0.5)
		(connect_pads
			(clearance 0)
		)
		(min_thickness 0.25)
		(keepout
			(tracks not_allowed)
			(vias allowed)
			(pads allowed)
			(copperpour not_allowed)
			(footprints allowed)
		)
		(placement
			(enabled no)
			(sheetname "")
		)
		(fill yes
			(thermal_gap 0.5)
			(thermal_bridge_width 0.5)
			(island_removal_mode 0)
		)
		(polygon
			(pts
				(arc
					(start 133.069838 -287.856422)
					(mid 132.439918 -287.856422)
					(end 133.069838 -287.856422)
				)
			)
		)
	)
	(zone
		(layers "B.Cu" "In6.Cu" "In11.Cu" "In13.Cu" "In15.Cu")
		(hatch none 0.5)
		(connect_pads
			(clearance 0)
		)
		(min_thickness 0.25)
		(keepout
			(tracks not_allowed)
			(vias allowed)
			(pads allowed)
			(copperpour not_allowed)
			(footprints allowed)
		)
		(placement
			(enabled no)
			(sheetname "")
		)
		(fill yes
			(thermal_gap 0.5)
			(thermal_bridge_width 0.5)
			(island_removal_mode 0)
		)
		(polygon
			(pts
				(arc
					(start 377.606306 -394.385292)
					(mid 376.976386 -394.385292)
					(end 377.606306 -394.385292)
				)
			)
		)
	)
	(zone
		(layers "B.Cu" "In6.Cu" "In11.Cu" "In13.Cu" "In15.Cu")
		(hatch none 0.5)
		(connect_pads
			(clearance 0)
		)
		(min_thickness 0.25)
		(keepout
			(tracks not_allowed)
			(vias allowed)
			(pads allowed)
			(copperpour not_allowed)
			(footprints allowed)
		)
		(placement
			(enabled no)
			(sheetname "")
		)
		(fill yes
			(thermal_gap 0.5)
			(thermal_bridge_width 0.5)
			(island_removal_mode 0)
		)
		(polygon
			(pts
				(arc
					(start 435.334156 -241.53495)
					(mid 434.666136 -241.53495)
					(end 435.334156 -241.53495)
				)
			)
		)
	)
	(zone
		(layers "B.Cu" "In6.Cu" "In11.Cu" "In13.Cu" "In15.Cu")
		(hatch none 0.5)
		(connect_pads
			(clearance 0)
		)
		(min_thickness 0.25)
		(keepout
			(tracks not_allowed)
			(vias allowed)
			(pads allowed)
			(copperpour not_allowed)
			(footprints allowed)
		)
		(placement
			(enabled no)
			(sheetname "")
		)
		(fill yes
			(thermal_gap 0.5)
			(thermal_bridge_width 0.5)
			(island_removal_mode 0)
		)
		(polygon
			(pts
				(arc
					(start 370.369846 -234.764072)
					(mid 369.739926 -234.764072)
					(end 370.369846 -234.764072)
				)
			)
		)
	)
	(zone
		(layers "B.Cu" "In6.Cu" "In11.Cu" "In13.Cu" "In15.Cu")
		(hatch none 0.5)
		(connect_pads
			(clearance 0)
		)
		(min_thickness 0.25)
		(keepout
			(tracks not_allowed)
			(vias allowed)
			(pads allowed)
			(copperpour not_allowed)
			(footprints allowed)
		)
		(placement
			(enabled no)
			(sheetname "")
		)
		(fill yes
			(thermal_gap 0.5)
			(thermal_bridge_width 0.5)
			(island_removal_mode 0)
		)
		(polygon
			(pts
				(arc
					(start 132.129784 -287.856422)
					(mid 131.499864 -287.856422)
					(end 132.129784 -287.856422)
				)
			)
		)
	)
	(zone
		(layers "B.Cu" "In6.Cu" "In11.Cu" "In13.Cu" "In15.Cu")
		(hatch none 0.5)
		(connect_pads
			(clearance 0)
		)
		(min_thickness 0.25)
		(keepout
			(tracks not_allowed)
			(vias allowed)
			(pads allowed)
			(copperpour not_allowed)
			(footprints allowed)
		)
		(placement
			(enabled no)
			(sheetname "")
		)
		(fill yes
			(thermal_gap 0.5)
			(thermal_bridge_width 0.5)
			(island_removal_mode 0)
		)
		(polygon
			(pts
				(arc
					(start 191.494156 -236.435392)
					(mid 190.826136 -236.435392)
					(end 191.494156 -236.435392)
				)
			)
		)
	)
	(zone
		(layers "B.Cu" "In6.Cu" "In11.Cu" "In13.Cu" "In15.Cu")
		(hatch none 0.5)
		(connect_pads
			(clearance 0)
		)
		(min_thickness 0.25)
		(keepout
			(tracks not_allowed)
			(vias allowed)
			(pads allowed)
			(copperpour not_allowed)
			(footprints allowed)
		)
		(placement
			(enabled no)
			(sheetname "")
		)
		(fill yes
			(thermal_gap 0.5)
			(thermal_bridge_width 0.5)
			(island_removal_mode 0)
		)
		(polygon
			(pts
				(arc
					(start 435.334156 -299.33519)
					(mid 434.666136 -299.33519)
					(end 435.334156 -299.33519)
				)
			)
		)
	)
	(zone
		(layers "B.Cu" "In6.Cu" "In11.Cu" "In13.Cu" "In15.Cu")
		(hatch none 0.5)
		(connect_pads
			(clearance 0)
		)
		(min_thickness 0.25)
		(keepout
			(tracks not_allowed)
			(vias allowed)
			(pads allowed)
			(copperpour not_allowed)
			(footprints allowed)
		)
		(placement
			(enabled no)
			(sheetname "")
		)
		(fill yes
			(thermal_gap 0.5)
			(thermal_bridge_width 0.5)
			(island_removal_mode 0)
		)
		(polygon
			(pts
				(arc
					(start 110.046008 -288.666174)
					(mid 109.416088 -288.666174)
					(end 110.046008 -288.666174)
				)
			)
		)
	)
	(zone
		(layers "B.Cu" "In6.Cu" "In11.Cu" "In13.Cu" "In15.Cu")
		(hatch none 0.5)
		(connect_pads
			(clearance 0)
		)
		(min_thickness 0.25)
		(keepout
			(tracks not_allowed)
			(vias allowed)
			(pads allowed)
			(copperpour not_allowed)
			(footprints allowed)
		)
		(placement
			(enabled no)
			(sheetname "")
		)
		(fill yes
			(thermal_gap 0.5)
			(thermal_bridge_width 0.5)
			(island_removal_mode 0)
		)
		(polygon
			(pts
				(arc
					(start 349.056198 -291.095938)
					(mid 348.426278 -291.095938)
					(end 349.056198 -291.095938)
				)
			)
		)
	)
	(zone
		(layers "B.Cu" "In6.Cu" "In11.Cu" "In13.Cu" "In15.Cu")
		(hatch none 0.5)
		(connect_pads
			(clearance 0)
		)
		(min_thickness 0.25)
		(keepout
			(tracks not_allowed)
			(vias allowed)
			(pads allowed)
			(copperpour not_allowed)
			(footprints allowed)
		)
		(placement
			(enabled no)
			(sheetname "")
		)
		(fill yes
			(thermal_gap 0.5)
			(thermal_bridge_width 0.5)
			(island_removal_mode 0)
		)
		(polygon
			(pts
				(arc
					(start 368.789712 -287.856168)
					(mid 368.159792 -287.856168)
					(end 368.789712 -287.856168)
				)
			)
		)
	)
	(zone
		(layers "B.Cu" "In6.Cu" "In11.Cu" "In13.Cu" "In15.Cu")
		(hatch none 0.5)
		(connect_pads
			(clearance 0)
		)
		(min_thickness 0.25)
		(keepout
			(tracks not_allowed)
			(vias allowed)
			(pads allowed)
			(copperpour not_allowed)
			(footprints allowed)
		)
		(placement
			(enabled no)
			(sheetname "")
		)
		(fill yes
			(thermal_gap 0.5)
			(thermal_bridge_width 0.5)
			(island_removal_mode 0)
		)
		(polygon
			(pts
				(arc
					(start 330.292202 -385.21386)
					(mid 329.624182 -385.21386)
					(end 330.292202 -385.21386)
				)
			)
		)
	)
	(zone
		(layers "B.Cu" "In6.Cu" "In11.Cu" "In13.Cu" "In15.Cu")
		(hatch none 0.5)
		(connect_pads
			(clearance 0)
		)
		(min_thickness 0.25)
		(keepout
			(tracks not_allowed)
			(vias allowed)
			(pads allowed)
			(copperpour not_allowed)
			(footprints allowed)
		)
		(placement
			(enabled no)
			(sheetname "")
		)
		(fill yes
			(thermal_gap 0.5)
			(thermal_bridge_width 0.5)
			(island_removal_mode 0)
		)
		(polygon
			(pts
				(arc
					(start 52.27447 -4.963414)
					(mid 51.60645 -4.963414)
					(end 52.27447 -4.963414)
				)
			)
		)
	)
	(zone
		(layers "B.Cu" "In6.Cu" "In11.Cu" "In13.Cu" "In15.Cu")
		(hatch none 0.5)
		(connect_pads
			(clearance 0)
		)
		(min_thickness 0.25)
		(keepout
			(tracks not_allowed)
			(vias allowed)
			(pads allowed)
			(copperpour not_allowed)
			(footprints allowed)
		)
		(placement
			(enabled no)
			(sheetname "")
		)
		(fill yes
			(thermal_gap 0.5)
			(thermal_bridge_width 0.5)
			(island_removal_mode 0)
		)
		(polygon
			(pts
				(arc
					(start 285.070042 -281.485086)
					(mid 284.402022 -281.485086)
					(end 285.070042 -281.485086)
				)
			)
		)
	)
	(zone
		(layers "B.Cu" "In6.Cu" "In11.Cu" "In13.Cu" "In15.Cu")
		(hatch none 0.5)
		(connect_pads
			(clearance 0)
		)
		(min_thickness 0.25)
		(keepout
			(tracks not_allowed)
			(vias allowed)
			(pads allowed)
			(copperpour not_allowed)
			(footprints allowed)
		)
		(placement
			(enabled no)
			(sheetname "")
		)
		(fill yes
			(thermal_gap 0.5)
			(thermal_bridge_width 0.5)
			(island_removal_mode 0)
		)
		(polygon
			(pts
				(arc
					(start 161.333942 -389.467344)
					(mid 160.704022 -389.467344)
					(end 161.333942 -389.467344)
				)
			)
		)
	)
	(zone
		(layers "B.Cu" "In6.Cu" "In11.Cu" "In13.Cu" "In15.Cu")
		(hatch none 0.5)
		(connect_pads
			(clearance 0)
		)
		(min_thickness 0.25)
		(keepout
			(tracks not_allowed)
			(vias allowed)
			(pads allowed)
			(copperpour not_allowed)
			(footprints allowed)
		)
		(placement
			(enabled no)
			(sheetname "")
		)
		(fill yes
			(thermal_gap 0.5)
			(thermal_bridge_width 0.5)
			(island_removal_mode 0)
		)
		(polygon
			(pts
				(arc
					(start 379.599698 -264.365994)
					(mid 378.969778 -264.365994)
					(end 379.599698 -264.365994)
				)
			)
		)
	)
	(zone
		(layers "B.Cu" "In6.Cu" "In11.Cu" "In13.Cu" "In15.Cu")
		(hatch none 0.5)
		(connect_pads
			(clearance 0)
		)
		(min_thickness 0.25)
		(keepout
			(tracks not_allowed)
			(vias allowed)
			(pads allowed)
			(copperpour not_allowed)
			(footprints allowed)
		)
		(placement
			(enabled no)
			(sheetname "")
		)
		(fill yes
			(thermal_gap 0.5)
			(thermal_bridge_width 0.5)
			(island_removal_mode 0)
		)
		(polygon
			(pts
				(arc
					(start 381.479806 -288.66592)
					(mid 380.849886 -288.66592)
					(end 381.479806 -288.66592)
				)
			)
		)
	)
	(zone
		(layers "B.Cu" "In6.Cu" "In11.Cu" "In13.Cu" "In15.Cu")
		(hatch none 0.5)
		(connect_pads
			(clearance 0)
		)
		(min_thickness 0.25)
		(keepout
			(tracks not_allowed)
			(vias allowed)
			(pads allowed)
			(copperpour not_allowed)
			(footprints allowed)
		)
		(placement
			(enabled no)
			(sheetname "")
		)
		(fill yes
			(thermal_gap 0.5)
			(thermal_bridge_width 0.5)
			(island_removal_mode 0)
		)
		(polygon
			(pts
				(arc
					(start 92.355924 -249.344434)
					(mid 91.726004 -249.344434)
					(end 92.355924 -249.344434)
				)
			)
		)
	)
	(zone
		(layers "B.Cu" "In6.Cu" "In11.Cu" "In13.Cu" "In15.Cu")
		(hatch none 0.5)
		(connect_pads
			(clearance 0)
		)
		(min_thickness 0.25)
		(keepout
			(tracks not_allowed)
			(vias allowed)
			(pads allowed)
			(copperpour not_allowed)
			(footprints allowed)
		)
		(placement
			(enabled no)
			(sheetname "")
		)
		(fill yes
			(thermal_gap 0.5)
			(thermal_bridge_width 0.5)
			(island_removal_mode 0)
		)
		(polygon
			(pts
				(arc
					(start 132.129784 -265.176254)
					(mid 131.499864 -265.176254)
					(end 132.129784 -265.176254)
				)
			)
		)
	)
	(zone
		(layers "B.Cu" "In6.Cu" "In11.Cu" "In13.Cu" "In15.Cu")
		(hatch none 0.5)
		(connect_pads
			(clearance 0)
		)
		(min_thickness 0.25)
		(keepout
			(tracks not_allowed)
			(vias allowed)
			(pads allowed)
			(copperpour not_allowed)
			(footprints allowed)
		)
		(placement
			(enabled no)
			(sheetname "")
		)
		(fill yes
			(thermal_gap 0.5)
			(thermal_bridge_width 0.5)
			(island_removal_mode 0)
		)
		(polygon
			(pts
				(arc
					(start 280.969974 -229.63505)
					(mid 280.301954 -229.63505)
					(end 280.969974 -229.63505)
				)
			)
		)
	)
	(zone
		(layers "B.Cu" "In6.Cu" "In11.Cu" "In13.Cu" "In15.Cu")
		(hatch none 0.5)
		(connect_pads
			(clearance 0)
		)
		(min_thickness 0.25)
		(keepout
			(tracks not_allowed)
			(vias allowed)
			(pads allowed)
			(copperpour not_allowed)
			(footprints allowed)
		)
		(placement
			(enabled no)
			(sheetname "")
		)
		(fill yes
			(thermal_gap 0.5)
			(thermal_bridge_width 0.5)
			(island_removal_mode 0)
		)
		(polygon
			(pts
				(arc
					(start 187.394088 -308.685438)
					(mid 186.726068 -308.685438)
					(end 187.394088 -308.685438)
				)
			)
		)
	)
	(zone
		(layers "B.Cu" "In6.Cu" "In11.Cu" "In13.Cu" "In15.Cu")
		(hatch none 0.5)
		(connect_pads
			(clearance 0)
		)
		(min_thickness 0.25)
		(keepout
			(tracks not_allowed)
			(vias allowed)
			(pads allowed)
			(copperpour not_allowed)
			(footprints allowed)
		)
		(placement
			(enabled no)
			(sheetname "")
		)
		(fill yes
			(thermal_gap 0.5)
			(thermal_bridge_width 0.5)
			(island_removal_mode 0)
		)
		(polygon
			(pts
				(arc
					(start 131.359656 -235.574332)
					(mid 130.729736 -235.574332)
					(end 131.359656 -235.574332)
				)
			)
		)
	)
	(zone
		(layers "B.Cu" "In6.Cu" "In11.Cu" "In13.Cu" "In15.Cu")
		(hatch none 0.5)
		(connect_pads
			(clearance 0)
		)
		(min_thickness 0.25)
		(keepout
			(tracks not_allowed)
			(vias allowed)
			(pads allowed)
			(copperpour not_allowed)
			(footprints allowed)
		)
		(placement
			(enabled no)
			(sheetname "")
		)
		(fill yes
			(thermal_gap 0.5)
			(thermal_bridge_width 0.5)
			(island_removal_mode 0)
		)
		(polygon
			(pts
				(arc
					(start 191.494156 -300.185328)
					(mid 190.826136 -300.185328)
					(end 191.494156 -300.185328)
				)
			)
		)
	)
	(zone
		(layers "B.Cu" "In6.Cu" "In11.Cu" "In13.Cu" "In15.Cu")
		(hatch none 0.5)
		(connect_pads
			(clearance 0)
		)
		(min_thickness 0.25)
		(keepout
			(tracks not_allowed)
			(vias allowed)
			(pads allowed)
			(copperpour not_allowed)
			(footprints allowed)
		)
		(placement
			(enabled no)
			(sheetname "")
		)
		(fill yes
			(thermal_gap 0.5)
			(thermal_bridge_width 0.5)
			(island_removal_mode 0)
		)
		(polygon
			(pts
				(arc
					(start 421.73398 -397.156432)
					(mid 421.10406 -397.156432)
					(end 421.73398 -397.156432)
				)
			)
		)
	)
	(zone
		(layers "B.Cu" "In6.Cu" "In11.Cu" "In13.Cu" "In15.Cu")
		(hatch none 0.5)
		(connect_pads
			(clearance 0)
		)
		(min_thickness 0.25)
		(keepout
			(tracks not_allowed)
			(vias allowed)
			(pads allowed)
			(copperpour not_allowed)
			(footprints allowed)
		)
		(placement
			(enabled no)
			(sheetname "")
		)
		(fill yes
			(thermal_gap 0.5)
			(thermal_bridge_width 0.5)
			(island_removal_mode 0)
		)
		(polygon
			(pts
				(arc
					(start 157.734 -389.467344)
					(mid 157.10408 -389.467344)
					(end 157.734 -389.467344)
				)
			)
		)
	)
	(zone
		(layers "B.Cu" "In6.Cu" "In11.Cu" "In13.Cu" "In15.Cu")
		(hatch none 0.5)
		(connect_pads
			(clearance 0)
		)
		(min_thickness 0.25)
		(keepout
			(tracks not_allowed)
			(vias allowed)
			(pads allowed)
			(copperpour not_allowed)
			(footprints allowed)
		)
		(placement
			(enabled no)
			(sheetname "")
		)
		(fill yes
			(thermal_gap 0.5)
			(thermal_bridge_width 0.5)
			(island_removal_mode 0)
		)
		(polygon
			(pts
				(arc
					(start 339.656166 -273.27606)
					(mid 339.026246 -273.27606)
					(end 339.656166 -273.27606)
				)
			)
		)
	)
	(zone
		(layers "B.Cu" "In6.Cu" "In11.Cu" "In13.Cu" "In15.Cu")
		(hatch none 0.5)
		(connect_pads
			(clearance 0)
		)
		(min_thickness 0.25)
		(keepout
			(tracks not_allowed)
			(vias allowed)
			(pads allowed)
			(copperpour not_allowed)
			(footprints allowed)
		)
		(placement
			(enabled no)
			(sheetname "")
		)
		(fill yes
			(thermal_gap 0.5)
			(thermal_bridge_width 0.5)
			(island_removal_mode 0)
		)
		(polygon
			(pts
				(arc
					(start 191.494156 -284.885384)
					(mid 190.826136 -284.885384)
					(end 191.494156 -284.885384)
				)
			)
		)
	)
	(zone
		(layers "B.Cu" "In6.Cu" "In11.Cu" "In13.Cu" "In15.Cu")
		(hatch none 0.5)
		(connect_pads
			(clearance 0)
		)
		(min_thickness 0.25)
		(keepout
			(tracks not_allowed)
			(vias allowed)
			(pads allowed)
			(copperpour not_allowed)
			(footprints allowed)
		)
		(placement
			(enabled no)
			(sheetname "")
		)
		(fill yes
			(thermal_gap 0.5)
			(thermal_bridge_width 0.5)
			(island_removal_mode 0)
		)
		(polygon
			(pts
				(arc
					(start 356.746048 -227.474272)
					(mid 356.116128 -227.474272)
					(end 356.746048 -227.474272)
				)
			)
		)
	)
	(zone
		(layers "B.Cu" "In6.Cu" "In11.Cu" "In13.Cu" "In15.Cu")
		(hatch none 0.5)
		(connect_pads
			(clearance 0)
		)
		(min_thickness 0.25)
		(keepout
			(tracks not_allowed)
			(vias allowed)
			(pads allowed)
			(copperpour not_allowed)
			(footprints allowed)
		)
		(placement
			(enabled no)
			(sheetname "")
		)
		(fill yes
			(thermal_gap 0.5)
			(thermal_bridge_width 0.5)
			(island_removal_mode 0)
		)
		(polygon
			(pts
				(arc
					(start 33.029906 -295.9354)
					(mid 32.361886 -295.9354)
					(end 33.029906 -295.9354)
				)
			)
		)
	)
	(zone
		(layers "B.Cu" "In6.Cu" "In11.Cu" "In13.Cu" "In15.Cu")
		(hatch none 0.5)
		(connect_pads
			(clearance 0)
		)
		(min_thickness 0.25)
		(keepout
			(tracks not_allowed)
			(vias allowed)
			(pads allowed)
			(copperpour not_allowed)
			(footprints allowed)
		)
		(placement
			(enabled no)
			(sheetname "")
		)
		(fill yes
			(thermal_gap 0.5)
			(thermal_bridge_width 0.5)
			(island_removal_mode 0)
		)
		(polygon
			(pts
				(arc
					(start 33.029906 -276.385274)
					(mid 32.361886 -276.385274)
					(end 33.029906 -276.385274)
				)
			)
		)
	)
	(zone
		(layers "B.Cu" "In6.Cu" "In11.Cu" "In13.Cu" "In15.Cu")
		(hatch none 0.5)
		(connect_pads
			(clearance 0)
		)
		(min_thickness 0.25)
		(keepout
			(tracks not_allowed)
			(vias allowed)
			(pads allowed)
			(copperpour not_allowed)
			(footprints allowed)
		)
		(placement
			(enabled no)
			(sheetname "")
		)
		(fill yes
			(thermal_gap 0.5)
			(thermal_bridge_width 0.5)
			(island_removal_mode 0)
		)
		(polygon
			(pts
				(arc
					(start 285.070042 -284.88513)
					(mid 284.402022 -284.88513)
					(end 285.070042 -284.88513)
				)
			)
		)
	)
	(zone
		(layers "B.Cu" "In6.Cu" "In11.Cu" "In13.Cu" "In15.Cu")
		(hatch none 0.5)
		(connect_pads
			(clearance 0)
		)
		(min_thickness 0.25)
		(keepout
			(tracks not_allowed)
			(vias allowed)
			(pads allowed)
			(copperpour not_allowed)
			(footprints allowed)
		)
		(placement
			(enabled no)
			(sheetname "")
		)
		(fill yes
			(thermal_gap 0.5)
			(thermal_bridge_width 0.5)
			(island_removal_mode 0)
		)
		(polygon
			(pts
				(arc
					(start 132.76961 -239.624362)
					(mid 132.13969 -239.624362)
					(end 132.76961 -239.624362)
				)
			)
		)
	)
	(zone
		(layers "B.Cu" "In6.Cu" "In11.Cu" "In13.Cu" "In15.Cu")
		(hatch none 0.5)
		(connect_pads
			(clearance 0)
		)
		(min_thickness 0.25)
		(keepout
			(tracks not_allowed)
			(vias allowed)
			(pads allowed)
			(copperpour not_allowed)
			(footprints allowed)
		)
		(placement
			(enabled no)
			(sheetname "")
		)
		(fill yes
			(thermal_gap 0.5)
			(thermal_bridge_width 0.5)
			(island_removal_mode 0)
		)
		(polygon
			(pts
				(arc
					(start 37.129974 -292.535356)
					(mid 36.461954 -292.535356)
					(end 37.129974 -292.535356)
				)
			)
		)
	)
	(zone
		(layers "B.Cu" "In6.Cu" "In11.Cu" "In13.Cu" "In15.Cu")
		(hatch none 0.5)
		(connect_pads
			(clearance 0)
		)
		(min_thickness 0.25)
		(keepout
			(tracks not_allowed)
			(vias allowed)
			(pads allowed)
			(copperpour not_allowed)
			(footprints allowed)
		)
		(placement
			(enabled no)
			(sheetname "")
		)
		(fill yes
			(thermal_gap 0.5)
			(thermal_bridge_width 0.5)
			(island_removal_mode 0)
		)
		(polygon
			(pts
				(arc
					(start 380.069852 -261.935976)
					(mid 379.439932 -261.935976)
					(end 380.069852 -261.935976)
				)
			)
		)
	)
	(zone
		(layers "B.Cu" "In6.Cu" "In11.Cu" "In13.Cu" "In15.Cu")
		(hatch none 0.5)
		(connect_pads
			(clearance 0)
		)
		(min_thickness 0.25)
		(keepout
			(tracks not_allowed)
			(vias allowed)
			(pads allowed)
			(copperpour not_allowed)
			(footprints allowed)
		)
		(placement
			(enabled no)
			(sheetname "")
		)
		(fill yes
			(thermal_gap 0.5)
			(thermal_bridge_width 0.5)
			(island_removal_mode 0)
		)
		(polygon
			(pts
				(arc
					(start 280.969974 -210.935062)
					(mid 280.301954 -210.935062)
					(end 280.969974 -210.935062)
				)
			)
		)
	)
	(zone
		(layers "B.Cu" "In6.Cu" "In11.Cu" "In13.Cu" "In15.Cu")
		(hatch none 0.5)
		(connect_pads
			(clearance 0)
		)
		(min_thickness 0.25)
		(keepout
			(tracks not_allowed)
			(vias allowed)
			(pads allowed)
			(copperpour not_allowed)
			(footprints allowed)
		)
		(placement
			(enabled no)
			(sheetname "")
		)
		(fill yes
			(thermal_gap 0.5)
			(thermal_bridge_width 0.5)
			(island_removal_mode 0)
		)
		(polygon
			(pts
				(arc
					(start 37.129974 -264.485374)
					(mid 36.461954 -264.485374)
					(end 37.129974 -264.485374)
				)
			)
		)
	)
	(zone
		(layers "B.Cu" "In6.Cu" "In11.Cu" "In13.Cu" "In15.Cu")
		(hatch none 0.5)
		(connect_pads
			(clearance 0)
		)
		(min_thickness 0.25)
		(keepout
			(tracks not_allowed)
			(vias allowed)
			(pads allowed)
			(copperpour not_allowed)
			(footprints allowed)
		)
		(placement
			(enabled no)
			(sheetname "")
		)
		(fill yes
			(thermal_gap 0.5)
			(thermal_bridge_width 0.5)
			(island_removal_mode 0)
		)
		(polygon
			(pts
				(arc
					(start 280.969974 -253.435104)
					(mid 280.301954 -253.435104)
					(end 280.969974 -253.435104)
				)
			)
		)
	)
	(zone
		(layers "B.Cu" "In6.Cu" "In11.Cu" "In13.Cu" "In15.Cu")
		(hatch none 0.5)
		(connect_pads
			(clearance 0)
		)
		(min_thickness 0.25)
		(keepout
			(tracks not_allowed)
			(vias allowed)
			(pads allowed)
			(copperpour not_allowed)
			(footprints allowed)
		)
		(placement
			(enabled no)
			(sheetname "")
		)
		(fill yes
			(thermal_gap 0.5)
			(thermal_bridge_width 0.5)
			(island_removal_mode 0)
		)
		(polygon
			(pts
				(arc
					(start 379.299724 -235.574078)
					(mid 378.669804 -235.574078)
					(end 379.299724 -235.574078)
				)
			)
		)
	)
	(zone
		(layers "B.Cu" "In6.Cu" "In11.Cu" "In13.Cu" "In15.Cu")
		(hatch none 0.5)
		(connect_pads
			(clearance 0)
		)
		(min_thickness 0.25)
		(keepout
			(tracks not_allowed)
			(vias allowed)
			(pads allowed)
			(copperpour not_allowed)
			(footprints allowed)
		)
		(placement
			(enabled no)
			(sheetname "")
		)
		(fill yes
			(thermal_gap 0.5)
			(thermal_bridge_width 0.5)
			(island_removal_mode 0)
		)
		(polygon
			(pts
				(arc
					(start 280.969974 -233.884978)
					(mid 280.301954 -233.884978)
					(end 280.969974 -233.884978)
				)
			)
		)
	)
	(zone
		(layers "B.Cu" "In6.Cu" "In11.Cu" "In13.Cu" "In15.Cu")
		(hatch none 0.5)
		(connect_pads
			(clearance 0)
		)
		(min_thickness 0.25)
		(keepout
			(tracks not_allowed)
			(vias allowed)
			(pads allowed)
			(copperpour not_allowed)
			(footprints allowed)
		)
		(placement
			(enabled no)
			(sheetname "")
		)
		(fill yes
			(thermal_gap 0.5)
			(thermal_bridge_width 0.5)
			(island_removal_mode 0)
		)
		(polygon
			(pts
				(arc
					(start 187.394088 -318.035432)
					(mid 186.726068 -318.035432)
					(end 187.394088 -318.035432)
				)
			)
		)
	)
	(zone
		(layers "B.Cu" "In6.Cu" "In11.Cu" "In13.Cu" "In15.Cu")
		(hatch none 0.5)
		(connect_pads
			(clearance 0)
		)
		(min_thickness 0.25)
		(keepout
			(tracks not_allowed)
			(vias allowed)
			(pads allowed)
			(copperpour not_allowed)
			(footprints allowed)
		)
		(placement
			(enabled no)
			(sheetname "")
		)
		(fill yes
			(thermal_gap 0.5)
			(thermal_bridge_width 0.5)
			(island_removal_mode 0)
		)
		(polygon
			(pts
				(arc
					(start 351.876106 -289.475926)
					(mid 351.246186 -289.475926)
					(end 351.876106 -289.475926)
				)
			)
		)
	)
	(zone
		(layers "B.Cu" "In6.Cu" "In11.Cu" "In13.Cu" "In15.Cu")
		(hatch none 0.5)
		(connect_pads
			(clearance 0)
		)
		(min_thickness 0.25)
		(keepout
			(tracks not_allowed)
			(vias allowed)
			(pads allowed)
			(copperpour not_allowed)
			(footprints allowed)
		)
		(placement
			(enabled no)
			(sheetname "")
		)
		(fill yes
			(thermal_gap 0.5)
			(thermal_bridge_width 0.5)
			(island_removal_mode 0)
		)
		(polygon
			(pts
				(arc
					(start 339.186012 -283.806138)
					(mid 338.556092 -283.806138)
					(end 339.186012 -283.806138)
				)
			)
		)
	)
	(zone
		(layers "B.Cu" "In6.Cu" "In11.Cu" "In13.Cu" "In15.Cu")
		(hatch none 0.5)
		(connect_pads
			(clearance 0)
		)
		(min_thickness 0.25)
		(keepout
			(tracks not_allowed)
			(vias allowed)
			(pads allowed)
			(copperpour not_allowed)
			(footprints allowed)
		)
		(placement
			(enabled no)
			(sheetname "")
		)
		(fill yes
			(thermal_gap 0.5)
			(thermal_bridge_width 0.5)
			(island_removal_mode 0)
		)
		(polygon
			(pts
				(arc
					(start 158.533846 -388.774432)
					(mid 157.903926 -388.774432)
					(end 158.533846 -388.774432)
				)
			)
		)
	)
	(zone
		(layers "B.Cu" "In6.Cu" "In11.Cu" "In13.Cu" "In15.Cu")
		(hatch none 0.5)
		(connect_pads
			(clearance 0)
		)
		(min_thickness 0.25)
		(keepout
			(tracks not_allowed)
			(vias allowed)
			(pads allowed)
			(copperpour not_allowed)
			(footprints allowed)
		)
		(placement
			(enabled no)
			(sheetname "")
		)
		(fill yes
			(thermal_gap 0.5)
			(thermal_bridge_width 0.5)
			(island_removal_mode 0)
		)
		(polygon
			(pts
				(arc
					(start 340.595966 -270.036036)
					(mid 339.966046 -270.036036)
					(end 340.595966 -270.036036)
				)
			)
		)
	)
	(zone
		(layers "B.Cu" "In6.Cu" "In11.Cu" "In13.Cu" "In15.Cu")
		(hatch none 0.5)
		(connect_pads
			(clearance 0)
		)
		(min_thickness 0.25)
		(keepout
			(tracks not_allowed)
			(vias allowed)
			(pads allowed)
			(copperpour not_allowed)
			(footprints allowed)
		)
		(placement
			(enabled no)
			(sheetname "")
		)
		(fill yes
			(thermal_gap 0.5)
			(thermal_bridge_width 0.5)
			(island_removal_mode 0)
		)
		(polygon
			(pts
				(arc
					(start 191.494156 -298.485306)
					(mid 190.826136 -298.485306)
					(end 191.494156 -298.485306)
				)
			)
		)
	)
	(zone
		(layers "B.Cu" "In6.Cu" "In11.Cu" "In13.Cu" "In15.Cu")
		(hatch none 0.5)
		(connect_pads
			(clearance 0)
		)
		(min_thickness 0.25)
		(keepout
			(tracks not_allowed)
			(vias allowed)
			(pads allowed)
			(copperpour not_allowed)
			(footprints allowed)
		)
		(placement
			(enabled no)
			(sheetname "")
		)
		(fill yes
			(thermal_gap 0.5)
			(thermal_bridge_width 0.5)
			(island_removal_mode 0)
		)
		(polygon
			(pts
				(arc
					(start 326.434196 -412.84652)
					(mid 325.766176 -412.84652)
					(end 326.434196 -412.84652)
				)
			)
		)
	)
	(zone
		(layers "B.Cu" "In6.Cu" "In11.Cu" "In13.Cu" "In15.Cu")
		(hatch none 0.5)
		(connect_pads
			(clearance 0)
		)
		(min_thickness 0.25)
		(keepout
			(tracks not_allowed)
			(vias allowed)
			(pads allowed)
			(copperpour not_allowed)
			(footprints allowed)
		)
		(placement
			(enabled no)
			(sheetname "")
		)
		(fill yes
			(thermal_gap 0.5)
			(thermal_bridge_width 0.5)
			(island_removal_mode 0)
		)
		(polygon
			(pts
				(arc
					(start 91.716098 -287.856422)
					(mid 91.086178 -287.856422)
					(end 91.716098 -287.856422)
				)
			)
		)
	)
	(zone
		(layers "B.Cu" "In6.Cu" "In11.Cu" "In13.Cu" "In15.Cu")
		(hatch none 0.5)
		(connect_pads
			(clearance 0)
		)
		(min_thickness 0.25)
		(keepout
			(tracks not_allowed)
			(vias allowed)
			(pads allowed)
			(copperpour not_allowed)
			(footprints allowed)
		)
		(placement
			(enabled no)
			(sheetname "")
		)
		(fill yes
			(thermal_gap 0.5)
			(thermal_bridge_width 0.5)
			(island_removal_mode 0)
		)
		(polygon
			(pts
				(arc
					(start 435.334156 -313.784996)
					(mid 434.666136 -313.784996)
					(end 435.334156 -313.784996)
				)
			)
		)
	)
	(zone
		(layers "B.Cu" "In6.Cu" "In11.Cu" "In13.Cu" "In15.Cu")
		(hatch none 0.5)
		(connect_pads
			(clearance 0)
		)
		(min_thickness 0.25)
		(keepout
			(tracks not_allowed)
			(vias allowed)
			(pads allowed)
			(copperpour not_allowed)
			(footprints allowed)
		)
		(placement
			(enabled no)
			(sheetname "")
		)
		(fill yes
			(thermal_gap 0.5)
			(thermal_bridge_width 0.5)
			(island_removal_mode 0)
		)
		(polygon
			(pts
				(arc
					(start 191.494156 -200.735438)
					(mid 190.826136 -200.735438)
					(end 191.494156 -200.735438)
				)
			)
		)
	)
	(zone
		(layers "B.Cu" "In6.Cu" "In11.Cu" "In13.Cu" "In15.Cu")
		(hatch none 0.5)
		(connect_pads
			(clearance 0)
		)
		(min_thickness 0.25)
		(keepout
			(tracks not_allowed)
			(vias allowed)
			(pads allowed)
			(copperpour not_allowed)
			(footprints allowed)
		)
		(placement
			(enabled no)
			(sheetname "")
		)
		(fill yes
			(thermal_gap 0.5)
			(thermal_bridge_width 0.5)
			(island_removal_mode 0)
		)
		(polygon
			(pts
				(arc
					(start 411.913832 -412.84652)
					(mid 411.245812 -412.84652)
					(end 411.913832 -412.84652)
				)
			)
		)
	)
	(zone
		(layers "B.Cu" "In6.Cu" "In11.Cu" "In13.Cu" "In15.Cu")
		(hatch none 0.5)
		(connect_pads
			(clearance 0)
		)
		(min_thickness 0.25)
		(keepout
			(tracks not_allowed)
			(vias allowed)
			(pads allowed)
			(copperpour not_allowed)
			(footprints allowed)
		)
		(placement
			(enabled no)
			(sheetname "")
		)
		(fill yes
			(thermal_gap 0.5)
			(thermal_bridge_width 0.5)
			(island_removal_mode 0)
		)
		(polygon
			(pts
				(arc
					(start 404.337774 -19.13636)
					(mid 403.669754 -19.13636)
					(end 404.337774 -19.13636)
				)
			)
		)
	)
	(zone
		(layers "B.Cu" "In6.Cu" "In11.Cu" "In13.Cu" "In15.Cu")
		(hatch none 0.5)
		(connect_pads
			(clearance 0)
		)
		(min_thickness 0.25)
		(keepout
			(tracks not_allowed)
			(vias allowed)
			(pads allowed)
			(copperpour not_allowed)
			(footprints allowed)
		)
		(placement
			(enabled no)
			(sheetname "")
		)
		(fill yes
			(thermal_gap 0.5)
			(thermal_bridge_width 0.5)
			(island_removal_mode 0)
		)
		(polygon
			(pts
				(arc
					(start 132.129784 -263.556242)
					(mid 131.499864 -263.556242)
					(end 132.129784 -263.556242)
				)
			)
		)
	)
	(zone
		(layers "B.Cu" "In6.Cu" "In11.Cu" "In13.Cu" "In15.Cu")
		(hatch none 0.5)
		(connect_pads
			(clearance 0)
		)
		(min_thickness 0.25)
		(keepout
			(tracks not_allowed)
			(vias allowed)
			(pads allowed)
			(copperpour not_allowed)
			(footprints allowed)
		)
		(placement
			(enabled no)
			(sheetname "")
		)
		(fill yes
			(thermal_gap 0.5)
			(thermal_bridge_width 0.5)
			(island_removal_mode 0)
		)
		(polygon
			(pts
				(arc
					(start 33.029906 -243.235226)
					(mid 32.361886 -243.235226)
					(end 33.029906 -243.235226)
				)
			)
		)
	)
	(zone
		(layers "B.Cu" "In6.Cu" "In11.Cu" "In13.Cu" "In15.Cu")
		(hatch none 0.5)
		(connect_pads
			(clearance 0)
		)
		(min_thickness 0.25)
		(keepout
			(tracks not_allowed)
			(vias allowed)
			(pads allowed)
			(copperpour not_allowed)
			(footprints allowed)
		)
		(placement
			(enabled no)
			(sheetname "")
		)
		(fill yes
			(thermal_gap 0.5)
			(thermal_bridge_width 0.5)
			(island_removal_mode 0)
		)
		(polygon
			(pts
				(arc
					(start 280.969974 -250.03506)
					(mid 280.301954 -250.03506)
					(end 280.969974 -250.03506)
				)
			)
		)
	)
	(zone
		(layers "B.Cu" "In6.Cu" "In11.Cu" "In13.Cu" "In15.Cu")
		(hatch none 0.5)
		(connect_pads
			(clearance 0)
		)
		(min_thickness 0.25)
		(keepout
			(tracks not_allowed)
			(vias allowed)
			(pads allowed)
			(copperpour not_allowed)
			(footprints allowed)
		)
		(placement
			(enabled no)
			(sheetname "")
		)
		(fill yes
			(thermal_gap 0.5)
			(thermal_bridge_width 0.5)
			(island_removal_mode 0)
		)
		(polygon
			(pts
				(arc
					(start 99.236022 -287.856422)
					(mid 98.606102 -287.856422)
					(end 99.236022 -287.856422)
				)
			)
		)
	)
	(zone
		(layers "B.Cu" "In6.Cu" "In11.Cu" "In13.Cu" "In15.Cu")
		(hatch none 0.5)
		(connect_pads
			(clearance 0)
		)
		(min_thickness 0.25)
		(keepout
			(tracks not_allowed)
			(vias allowed)
			(pads allowed)
			(copperpour not_allowed)
			(footprints allowed)
		)
		(placement
			(enabled no)
			(sheetname "")
		)
		(fill yes
			(thermal_gap 0.5)
			(thermal_bridge_width 0.5)
			(island_removal_mode 0)
		)
		(polygon
			(pts
				(arc
					(start 285.070042 -261.085076)
					(mid 284.402022 -261.085076)
					(end 285.070042 -261.085076)
				)
			)
		)
	)
	(zone
		(layers "B.Cu" "In6.Cu" "In11.Cu" "In13.Cu" "In15.Cu")
		(hatch none 0.5)
		(connect_pads
			(clearance 0)
		)
		(min_thickness 0.25)
		(keepout
			(tracks not_allowed)
			(vias allowed)
			(pads allowed)
			(copperpour not_allowed)
			(footprints allowed)
		)
		(placement
			(enabled no)
			(sheetname "")
		)
		(fill yes
			(thermal_gap 0.5)
			(thermal_bridge_width 0.5)
			(island_removal_mode 0)
		)
		(polygon
			(pts
				(arc
					(start 152.533858 -388.774432)
					(mid 151.903938 -388.774432)
					(end 152.533858 -388.774432)
				)
			)
		)
	)
	(zone
		(layers "B.Cu" "In6.Cu" "In11.Cu" "In13.Cu" "In15.Cu")
		(hatch none 0.5)
		(connect_pads
			(clearance 0)
		)
		(min_thickness 0.25)
		(keepout
			(tracks not_allowed)
			(vias allowed)
			(pads allowed)
			(copperpour not_allowed)
			(footprints allowed)
		)
		(placement
			(enabled no)
			(sheetname "")
		)
		(fill yes
			(thermal_gap 0.5)
			(thermal_bridge_width 0.5)
			(island_removal_mode 0)
		)
		(polygon
			(pts
				(arc
					(start 101.755956 -236.384338)
					(mid 101.126036 -236.384338)
					(end 101.755956 -236.384338)
				)
			)
		)
	)
	(zone
		(layers "B.Cu" "In6.Cu" "In11.Cu" "In13.Cu" "In15.Cu")
		(hatch none 0.5)
		(connect_pads
			(clearance 0)
		)
		(min_thickness 0.25)
		(keepout
			(tracks not_allowed)
			(vias allowed)
			(pads allowed)
			(copperpour not_allowed)
			(footprints allowed)
		)
		(placement
			(enabled no)
			(sheetname "")
		)
		(fill yes
			(thermal_gap 0.5)
			(thermal_bridge_width 0.5)
			(island_removal_mode 0)
		)
		(polygon
			(pts
				(arc
					(start 280.969974 -202.434952)
					(mid 280.301954 -202.434952)
					(end 280.969974 -202.434952)
				)
			)
		)
	)
	(zone
		(layers "B.Cu" "In6.Cu" "In11.Cu" "In13.Cu" "In15.Cu")
		(hatch none 0.5)
		(connect_pads
			(clearance 0)
		)
		(min_thickness 0.25)
		(keepout
			(tracks not_allowed)
			(vias allowed)
			(pads allowed)
			(copperpour not_allowed)
			(footprints allowed)
		)
		(placement
			(enabled no)
			(sheetname "")
		)
		(fill yes
			(thermal_gap 0.5)
			(thermal_bridge_width 0.5)
			(island_removal_mode 0)
		)
		(polygon
			(pts
				(arc
					(start 280.969974 -285.735014)
					(mid 280.301954 -285.735014)
					(end 280.969974 -285.735014)
				)
			)
		)
	)
	(zone
		(layers "B.Cu" "In6.Cu" "In11.Cu" "In13.Cu" "In15.Cu")
		(hatch none 0.5)
		(connect_pads
			(clearance 0)
		)
		(min_thickness 0.25)
		(keepout
			(tracks not_allowed)
			(vias allowed)
			(pads allowed)
			(copperpour not_allowed)
			(footprints allowed)
		)
		(placement
			(enabled no)
			(sheetname "")
		)
		(fill yes
			(thermal_gap 0.5)
			(thermal_bridge_width 0.5)
			(island_removal_mode 0)
		)
		(polygon
			(pts
				(arc
					(start 33.029906 -218.585288)
					(mid 32.361886 -218.585288)
					(end 33.029906 -218.585288)
				)
			)
		)
	)
	(zone
		(layers "B.Cu" "In6.Cu" "In11.Cu" "In13.Cu" "In15.Cu")
		(hatch none 0.5)
		(connect_pads
			(clearance 0)
		)
		(min_thickness 0.25)
		(keepout
			(tracks not_allowed)
			(vias allowed)
			(pads allowed)
			(copperpour not_allowed)
			(footprints allowed)
		)
		(placement
			(enabled no)
			(sheetname "")
		)
		(fill yes
			(thermal_gap 0.5)
			(thermal_bridge_width 0.5)
			(island_removal_mode 0)
		)
		(polygon
			(pts
				(arc
					(start 340.766146 -250.154186)
					(mid 340.136226 -250.154186)
					(end 340.766146 -250.154186)
				)
			)
		)
	)
	(zone
		(layers "B.Cu" "In6.Cu" "In11.Cu" "In13.Cu" "In15.Cu")
		(hatch none 0.5)
		(connect_pads
			(clearance 0)
		)
		(min_thickness 0.25)
		(keepout
			(tracks not_allowed)
			(vias allowed)
			(pads allowed)
			(copperpour not_allowed)
			(footprints allowed)
		)
		(placement
			(enabled no)
			(sheetname "")
		)
		(fill yes
			(thermal_gap 0.5)
			(thermal_bridge_width 0.5)
			(island_removal_mode 0)
		)
		(polygon
			(pts
				(arc
					(start 191.494156 -231.335326)
					(mid 190.826136 -231.335326)
					(end 191.494156 -231.335326)
				)
			)
		)
	)
	(zone
		(layers "B.Cu" "In6.Cu" "In11.Cu" "In13.Cu" "In15.Cu")
		(hatch none 0.5)
		(connect_pads
			(clearance 0)
		)
		(min_thickness 0.25)
		(keepout
			(tracks not_allowed)
			(vias allowed)
			(pads allowed)
			(copperpour not_allowed)
			(footprints allowed)
		)
		(placement
			(enabled no)
			(sheetname "")
		)
		(fill yes
			(thermal_gap 0.5)
			(thermal_bridge_width 0.5)
			(island_removal_mode 0)
		)
		(polygon
			(pts
				(arc
					(start 131.65963 -262.746236)
					(mid 131.02971 -262.746236)
					(end 131.65963 -262.746236)
				)
			)
		)
	)
	(zone
		(layers "B.Cu" "In6.Cu" "In11.Cu" "In13.Cu" "In15.Cu")
		(hatch none 0.5)
		(connect_pads
			(clearance 0)
		)
		(min_thickness 0.25)
		(keepout
			(tracks not_allowed)
			(vias allowed)
			(pads allowed)
			(copperpour not_allowed)
			(footprints allowed)
		)
		(placement
			(enabled no)
			(sheetname "")
		)
		(fill yes
			(thermal_gap 0.5)
			(thermal_bridge_width 0.5)
			(island_removal_mode 0)
		)
		(polygon
			(pts
				(arc
					(start 92.655898 -274.896326)
					(mid 92.025978 -274.896326)
					(end 92.655898 -274.896326)
				)
			)
		)
	)
	(zone
		(layers "B.Cu" "In6.Cu" "In11.Cu" "In13.Cu" "In15.Cu")
		(hatch none 0.5)
		(connect_pads
			(clearance 0)
		)
		(min_thickness 0.25)
		(keepout
			(tracks not_allowed)
			(vias allowed)
			(pads allowed)
			(copperpour not_allowed)
			(footprints allowed)
		)
		(placement
			(enabled no)
			(sheetname "")
		)
		(fill yes
			(thermal_gap 0.5)
			(thermal_bridge_width 0.5)
			(island_removal_mode 0)
		)
		(polygon
			(pts
				(arc
					(start 370.369846 -231.524048)
					(mid 369.739926 -231.524048)
					(end 370.369846 -231.524048)
				)
			)
		)
	)
	(zone
		(layers "B.Cu" "In6.Cu" "In11.Cu" "In13.Cu" "In15.Cu")
		(hatch none 0.5)
		(connect_pads
			(clearance 0)
		)
		(min_thickness 0.25)
		(keepout
			(tracks not_allowed)
			(vias allowed)
			(pads allowed)
			(copperpour not_allowed)
			(footprints allowed)
		)
		(placement
			(enabled no)
			(sheetname "")
		)
		(fill yes
			(thermal_gap 0.5)
			(thermal_bridge_width 0.5)
			(island_removal_mode 0)
		)
		(polygon
			(pts
				(arc
					(start 404.933912 -397.156432)
					(mid 404.303992 -397.156432)
					(end 404.933912 -397.156432)
				)
			)
		)
	)
	(zone
		(layers "B.Cu" "In6.Cu" "In11.Cu" "In13.Cu" "In15.Cu")
		(hatch none 0.5)
		(connect_pads
			(clearance 0)
		)
		(min_thickness 0.25)
		(keepout
			(tracks not_allowed)
			(vias allowed)
			(pads allowed)
			(copperpour not_allowed)
			(footprints allowed)
		)
		(placement
			(enabled no)
			(sheetname "")
		)
		(fill yes
			(thermal_gap 0.5)
			(thermal_bridge_width 0.5)
			(island_removal_mode 0)
		)
		(polygon
			(pts
				(arc
					(start 340.295992 -239.624108)
					(mid 339.666072 -239.624108)
					(end 340.295992 -239.624108)
				)
			)
		)
	)
	(zone
		(layers "B.Cu" "In6.Cu" "In11.Cu" "In13.Cu" "In15.Cu")
		(hatch none 0.5)
		(connect_pads
			(clearance 0)
		)
		(min_thickness 0.25)
		(keepout
			(tracks not_allowed)
			(vias allowed)
			(pads allowed)
			(copperpour not_allowed)
			(footprints allowed)
		)
		(placement
			(enabled no)
			(sheetname "")
		)
		(fill yes
			(thermal_gap 0.5)
			(thermal_bridge_width 0.5)
			(island_removal_mode 0)
		)
		(polygon
			(pts
				(arc
					(start 122.729752 -291.096192)
					(mid 122.099832 -291.096192)
					(end 122.729752 -291.096192)
				)
			)
		)
	)
	(zone
		(layers "B.Cu" "In6.Cu" "In11.Cu" "In13.Cu" "In15.Cu")
		(hatch none 0.5)
		(connect_pads
			(clearance 0)
		)
		(min_thickness 0.25)
		(keepout
			(tracks not_allowed)
			(vias allowed)
			(pads allowed)
			(copperpour not_allowed)
			(footprints allowed)
		)
		(placement
			(enabled no)
			(sheetname "")
		)
		(fill yes
			(thermal_gap 0.5)
			(thermal_bridge_width 0.5)
			(island_removal_mode 0)
		)
		(polygon
			(pts
				(arc
					(start 439.434224 -279.785064)
					(mid 438.766204 -279.785064)
					(end 439.434224 -279.785064)
				)
			)
		)
	)
	(zone
		(layers "B.Cu" "In6.Cu" "In11.Cu" "In13.Cu" "In15.Cu")
		(hatch none 0.5)
		(connect_pads
			(clearance 0)
		)
		(min_thickness 0.25)
		(keepout
			(tracks not_allowed)
			(vias allowed)
			(pads allowed)
			(copperpour not_allowed)
			(footprints allowed)
		)
		(placement
			(enabled no)
			(sheetname "")
		)
		(fill yes
			(thermal_gap 0.5)
			(thermal_bridge_width 0.5)
			(island_removal_mode 0)
		)
		(polygon
			(pts
				(arc
					(start 380.069852 -289.475926)
					(mid 379.439932 -289.475926)
					(end 380.069852 -289.475926)
				)
			)
		)
	)
	(zone
		(layers "B.Cu" "In6.Cu" "In11.Cu" "In13.Cu" "In15.Cu")
		(hatch none 0.5)
		(connect_pads
			(clearance 0)
		)
		(min_thickness 0.25)
		(keepout
			(tracks not_allowed)
			(vias allowed)
			(pads allowed)
			(copperpour not_allowed)
			(footprints allowed)
		)
		(placement
			(enabled no)
			(sheetname "")
		)
		(fill yes
			(thermal_gap 0.5)
			(thermal_bridge_width 0.5)
			(island_removal_mode 0)
		)
		(polygon
			(pts
				(arc
					(start 354.39604 -228.284278)
					(mid 353.76612 -228.284278)
					(end 354.39604 -228.284278)
				)
			)
		)
	)
	(zone
		(layers "B.Cu" "In6.Cu" "In11.Cu" "In13.Cu" "In15.Cu")
		(hatch none 0.5)
		(connect_pads
			(clearance 0)
		)
		(min_thickness 0.25)
		(keepout
			(tracks not_allowed)
			(vias allowed)
			(pads allowed)
			(copperpour not_allowed)
			(footprints allowed)
		)
		(placement
			(enabled no)
			(sheetname "")
		)
		(fill yes
			(thermal_gap 0.5)
			(thermal_bridge_width 0.5)
			(island_removal_mode 0)
		)
		(polygon
			(pts
				(arc
					(start 318.506094 -397.156432)
					(mid 317.876174 -397.156432)
					(end 318.506094 -397.156432)
				)
			)
		)
	)
	(zone
		(layers "B.Cu" "In6.Cu" "In11.Cu" "In13.Cu" "In15.Cu")
		(hatch none 0.5)
		(connect_pads
			(clearance 0)
		)
		(min_thickness 0.25)
		(keepout
			(tracks not_allowed)
			(vias allowed)
			(pads allowed)
			(copperpour not_allowed)
			(footprints allowed)
		)
		(placement
			(enabled no)
			(sheetname "")
		)
		(fill yes
			(thermal_gap 0.5)
			(thermal_bridge_width 0.5)
			(island_removal_mode 0)
		)
		(polygon
			(pts
				(arc
					(start 187.394088 -250.035314)
					(mid 186.726068 -250.035314)
					(end 187.394088 -250.035314)
				)
			)
		)
	)
	(zone
		(layers "B.Cu" "In6.Cu" "In11.Cu" "In13.Cu" "In15.Cu")
		(hatch none 0.5)
		(connect_pads
			(clearance 0)
		)
		(min_thickness 0.25)
		(keepout
			(tracks not_allowed)
			(vias allowed)
			(pads allowed)
			(copperpour not_allowed)
			(footprints allowed)
		)
		(placement
			(enabled no)
			(sheetname "")
		)
		(fill yes
			(thermal_gap 0.5)
			(thermal_bridge_width 0.5)
			(island_removal_mode 0)
		)
		(polygon
			(pts
				(arc
					(start 371.228112 -412.84652)
					(mid 370.560092 -412.84652)
					(end 371.228112 -412.84652)
				)
			)
		)
	)
	(zone
		(layers "B.Cu" "In6.Cu" "In11.Cu" "In13.Cu" "In15.Cu")
		(hatch none 0.5)
		(connect_pads
			(clearance 0)
		)
		(min_thickness 0.25)
		(keepout
			(tracks not_allowed)
			(vias allowed)
			(pads allowed)
			(copperpour not_allowed)
			(footprints allowed)
		)
		(placement
			(enabled no)
			(sheetname "")
		)
		(fill yes
			(thermal_gap 0.5)
			(thermal_bridge_width 0.5)
			(island_removal_mode 0)
		)
		(polygon
			(pts
				(arc
					(start 133.539738 -283.806392)
					(mid 132.909818 -283.806392)
					(end 133.539738 -283.806392)
				)
			)
		)
	)
	(zone
		(layers "B.Cu" "In6.Cu" "In11.Cu" "In13.Cu" "In15.Cu")
		(hatch none 0.5)
		(connect_pads
			(clearance 0)
		)
		(min_thickness 0.25)
		(keepout
			(tracks not_allowed)
			(vias allowed)
			(pads allowed)
			(copperpour not_allowed)
			(footprints allowed)
		)
		(placement
			(enabled no)
			(sheetname "")
		)
		(fill yes
			(thermal_gap 0.5)
			(thermal_bridge_width 0.5)
			(island_removal_mode 0)
		)
		(polygon
			(pts
				(arc
					(start 187.394088 -209.235294)
					(mid 186.726068 -209.235294)
					(end 187.394088 -209.235294)
				)
			)
		)
	)
	(zone
		(layers "B.Cu" "In6.Cu" "In11.Cu" "In13.Cu" "In15.Cu")
		(hatch none 0.5)
		(connect_pads
			(clearance 0)
		)
		(min_thickness 0.25)
		(keepout
			(tracks not_allowed)
			(vias allowed)
			(pads allowed)
			(copperpour not_allowed)
			(footprints allowed)
		)
		(placement
			(enabled no)
			(sheetname "")
		)
		(fill yes
			(thermal_gap 0.5)
			(thermal_bridge_width 0.5)
			(island_removal_mode 0)
		)
		(polygon
			(pts
				(arc
					(start 91.716098 -274.896326)
					(mid 91.086178 -274.896326)
					(end 91.716098 -274.896326)
				)
			)
		)
	)
	(zone
		(layers "B.Cu" "In6.Cu" "In11.Cu" "In13.Cu" "In15.Cu")
		(hatch none 0.5)
		(connect_pads
			(clearance 0)
		)
		(min_thickness 0.25)
		(keepout
			(tracks not_allowed)
			(vias allowed)
			(pads allowed)
			(copperpour not_allowed)
			(footprints allowed)
		)
		(placement
			(enabled no)
			(sheetname "")
		)
		(fill yes
			(thermal_gap 0.5)
			(thermal_bridge_width 0.5)
			(island_removal_mode 0)
		)
		(polygon
			(pts
				(arc
					(start 187.394088 -246.63527)
					(mid 186.726068 -246.63527)
					(end 187.394088 -246.63527)
				)
			)
		)
	)
	(zone
		(layers "B.Cu" "In6.Cu" "In11.Cu" "In13.Cu" "In15.Cu")
		(hatch none 0.5)
		(connect_pads
			(clearance 0)
		)
		(min_thickness 0.25)
		(keepout
			(tracks not_allowed)
			(vias allowed)
			(pads allowed)
			(copperpour not_allowed)
			(footprints allowed)
		)
		(placement
			(enabled no)
			(sheetname "")
		)
		(fill yes
			(thermal_gap 0.5)
			(thermal_bridge_width 0.5)
			(island_removal_mode 0)
		)
		(polygon
			(pts
				(arc
					(start 133.539738 -274.08632)
					(mid 132.909818 -274.08632)
					(end 133.539738 -274.08632)
				)
			)
		)
	)
	(zone
		(layers "B.Cu" "In6.Cu" "In11.Cu" "In13.Cu" "In15.Cu")
		(hatch none 0.5)
		(connect_pads
			(clearance 0)
		)
		(min_thickness 0.25)
		(keepout
			(tracks not_allowed)
			(vias allowed)
			(pads allowed)
			(copperpour not_allowed)
			(footprints allowed)
		)
		(placement
			(enabled no)
			(sheetname "")
		)
		(fill yes
			(thermal_gap 0.5)
			(thermal_bridge_width 0.5)
			(island_removal_mode 0)
		)
		(polygon
			(pts
				(arc
					(start 439.434224 -262.785098)
					(mid 438.766204 -262.785098)
					(end 439.434224 -262.785098)
				)
			)
		)
	)
	(zone
		(layers "B.Cu" "In6.Cu" "In11.Cu" "In13.Cu" "In15.Cu")
		(hatch none 0.5)
		(connect_pads
			(clearance 0)
		)
		(min_thickness 0.25)
		(keepout
			(tracks not_allowed)
			(vias allowed)
			(pads allowed)
			(copperpour not_allowed)
			(footprints allowed)
		)
		(placement
			(enabled no)
			(sheetname "")
		)
		(fill yes
			(thermal_gap 0.5)
			(thermal_bridge_width 0.5)
			(island_removal_mode 0)
		)
		(polygon
			(pts
				(arc
					(start 187.394088 -237.285276)
					(mid 186.726068 -237.285276)
					(end 187.394088 -237.285276)
				)
			)
		)
	)
	(zone
		(layers "B.Cu" "In6.Cu" "In11.Cu" "In13.Cu" "In15.Cu")
		(hatch none 0.5)
		(connect_pads
			(clearance 0)
		)
		(min_thickness 0.25)
		(keepout
			(tracks not_allowed)
			(vias allowed)
			(pads allowed)
			(copperpour not_allowed)
			(footprints allowed)
		)
		(placement
			(enabled no)
			(sheetname "")
		)
		(fill yes
			(thermal_gap 0.5)
			(thermal_bridge_width 0.5)
			(island_removal_mode 0)
		)
		(polygon
			(pts
				(arc
					(start 379.599698 -275.706078)
					(mid 378.969778 -275.706078)
					(end 379.599698 -275.706078)
				)
			)
		)
	)
	(zone
		(layers "B.Cu" "In6.Cu" "In11.Cu" "In13.Cu" "In15.Cu")
		(hatch none 0.5)
		(connect_pads
			(clearance 0)
		)
		(min_thickness 0.25)
		(keepout
			(tracks not_allowed)
			(vias allowed)
			(pads allowed)
			(copperpour not_allowed)
			(footprints allowed)
		)
		(placement
			(enabled no)
			(sheetname "")
		)
		(fill yes
			(thermal_gap 0.5)
			(thermal_bridge_width 0.5)
			(island_removal_mode 0)
		)
		(polygon
			(pts
				(arc
					(start 350.076516 -412.84652)
					(mid 349.408496 -412.84652)
					(end 350.076516 -412.84652)
				)
			)
		)
	)
	(zone
		(layers "B.Cu" "In6.Cu" "In11.Cu" "In13.Cu" "In15.Cu")
		(hatch none 0.5)
		(connect_pads
			(clearance 0)
		)
		(min_thickness 0.25)
		(keepout
			(tracks not_allowed)
			(vias allowed)
			(pads allowed)
			(copperpour not_allowed)
			(footprints allowed)
		)
		(placement
			(enabled no)
			(sheetname "")
		)
		(fill yes
			(thermal_gap 0.5)
			(thermal_bridge_width 0.5)
			(island_removal_mode 0)
		)
		(polygon
			(pts
				(arc
					(start 285.070042 -200.735184)
					(mid 284.402022 -200.735184)
					(end 285.070042 -200.735184)
				)
			)
		)
	)
	(zone
		(layers "B.Cu" "In6.Cu" "In11.Cu" "In13.Cu" "In15.Cu")
		(hatch none 0.5)
		(connect_pads
			(clearance 0)
		)
		(min_thickness 0.25)
		(keepout
			(tracks not_allowed)
			(vias allowed)
			(pads allowed)
			(copperpour not_allowed)
			(footprints allowed)
		)
		(placement
			(enabled no)
			(sheetname "")
		)
		(fill yes
			(thermal_gap 0.5)
			(thermal_bridge_width 0.5)
			(island_removal_mode 0)
		)
		(polygon
			(pts
				(arc
					(start 118.029736 -287.856422)
					(mid 117.399816 -287.856422)
					(end 118.029736 -287.856422)
				)
			)
		)
	)
	(zone
		(layers "B.Cu" "In6.Cu" "In11.Cu" "In13.Cu" "In15.Cu")
		(hatch none 0.5)
		(connect_pads
			(clearance 0)
		)
		(min_thickness 0.25)
		(keepout
			(tracks not_allowed)
			(vias allowed)
			(pads allowed)
			(copperpour not_allowed)
			(footprints allowed)
		)
		(placement
			(enabled no)
			(sheetname "")
		)
		(fill yes
			(thermal_gap 0.5)
			(thermal_bridge_width 0.5)
			(island_removal_mode 0)
		)
		(polygon
			(pts
				(arc
					(start 91.245944 -280.566368)
					(mid 90.616024 -280.566368)
					(end 91.245944 -280.566368)
				)
			)
		)
	)
	(zone
		(layers "B.Cu" "In6.Cu" "In11.Cu" "In13.Cu" "In15.Cu")
		(hatch none 0.5)
		(connect_pads
			(clearance 0)
		)
		(min_thickness 0.25)
		(keepout
			(tracks not_allowed)
			(vias allowed)
			(pads allowed)
			(copperpour not_allowed)
			(footprints allowed)
		)
		(placement
			(enabled no)
			(sheetname "")
		)
		(fill yes
			(thermal_gap 0.5)
			(thermal_bridge_width 0.5)
			(island_removal_mode 0)
		)
		(polygon
			(pts
				(arc
					(start 191.494156 -289.135312)
					(mid 190.826136 -289.135312)
					(end 191.494156 -289.135312)
				)
			)
		)
	)
	(zone
		(layers "B.Cu" "In6.Cu" "In11.Cu" "In13.Cu" "In15.Cu")
		(hatch none 0.5)
		(connect_pads
			(clearance 0)
		)
		(min_thickness 0.25)
		(keepout
			(tracks not_allowed)
			(vias allowed)
			(pads allowed)
			(copperpour not_allowed)
			(footprints allowed)
		)
		(placement
			(enabled no)
			(sheetname "")
		)
		(fill yes
			(thermal_gap 0.5)
			(thermal_bridge_width 0.5)
			(island_removal_mode 0)
		)
		(polygon
			(pts
				(arc
					(start 285.070042 -276.38502)
					(mid 284.402022 -276.38502)
					(end 285.070042 -276.38502)
				)
			)
		)
	)
	(zone
		(layers "B.Cu" "In6.Cu" "In11.Cu" "In13.Cu" "In15.Cu")
		(hatch none 0.5)
		(connect_pads
			(clearance 0)
		)
		(min_thickness 0.25)
		(keepout
			(tracks not_allowed)
			(vias allowed)
			(pads allowed)
			(copperpour not_allowed)
			(footprints allowed)
		)
		(placement
			(enabled no)
			(sheetname "")
		)
		(fill yes
			(thermal_gap 0.5)
			(thermal_bridge_width 0.5)
			(island_removal_mode 0)
		)
		(polygon
			(pts
				(arc
					(start 25.617932 -4.963414)
					(mid 24.949912 -4.963414)
					(end 25.617932 -4.963414)
				)
			)
		)
	)
	(zone
		(layers "B.Cu" "In6.Cu" "In11.Cu" "In13.Cu" "In15.Cu")
		(hatch none 0.5)
		(connect_pads
			(clearance 0)
		)
		(min_thickness 0.25)
		(keepout
			(tracks not_allowed)
			(vias allowed)
			(pads allowed)
			(copperpour not_allowed)
			(footprints allowed)
		)
		(placement
			(enabled no)
			(sheetname "")
		)
		(fill yes
			(thermal_gap 0.5)
			(thermal_bridge_width 0.5)
			(island_removal_mode 0)
		)
		(polygon
			(pts
				(arc
					(start 340.886796 -412.84652)
					(mid 340.218776 -412.84652)
					(end 340.886796 -412.84652)
				)
			)
		)
	)
	(zone
		(layers "B.Cu" "In6.Cu" "In11.Cu" "In13.Cu" "In15.Cu")
		(hatch none 0.5)
		(connect_pads
			(clearance 0)
		)
		(min_thickness 0.25)
		(keepout
			(tracks not_allowed)
			(vias allowed)
			(pads allowed)
			(copperpour not_allowed)
			(footprints allowed)
		)
		(placement
			(enabled no)
			(sheetname "")
		)
		(fill yes
			(thermal_gap 0.5)
			(thermal_bridge_width 0.5)
			(island_removal_mode 0)
		)
		(polygon
			(pts
				(arc
					(start 93.126052 -265.98626)
					(mid 92.496132 -265.98626)
					(end 93.126052 -265.98626)
				)
			)
		)
	)
	(zone
		(layers "B.Cu" "In6.Cu" "In11.Cu" "In13.Cu" "In15.Cu")
		(hatch none 0.5)
		(connect_pads
			(clearance 0)
		)
		(min_thickness 0.25)
		(keepout
			(tracks not_allowed)
			(vias allowed)
			(pads allowed)
			(copperpour not_allowed)
			(footprints allowed)
		)
		(placement
			(enabled no)
			(sheetname "")
		)
		(fill yes
			(thermal_gap 0.5)
			(thermal_bridge_width 0.5)
			(island_removal_mode 0)
		)
		(polygon
			(pts
				(arc
					(start 319.444116 -412.84652)
					(mid 318.776096 -412.84652)
					(end 319.444116 -412.84652)
				)
			)
		)
	)
	(zone
		(layers "B.Cu" "In6.Cu" "In11.Cu" "In13.Cu" "In15.Cu")
		(hatch none 0.5)
		(connect_pads
			(clearance 0)
		)
		(min_thickness 0.25)
		(keepout
			(tracks not_allowed)
			(vias allowed)
			(pads allowed)
			(copperpour not_allowed)
			(footprints allowed)
		)
		(placement
			(enabled no)
			(sheetname "")
		)
		(fill yes
			(thermal_gap 0.5)
			(thermal_bridge_width 0.5)
			(island_removal_mode 0)
		)
		(polygon
			(pts
				(arc
					(start 339.186012 -290.285932)
					(mid 338.556092 -290.285932)
					(end 339.186012 -290.285932)
				)
			)
		)
	)
	(zone
		(layers "B.Cu" "In6.Cu" "In11.Cu" "In13.Cu" "In15.Cu")
		(hatch none 0.5)
		(connect_pads
			(clearance 0)
		)
		(min_thickness 0.25)
		(keepout
			(tracks not_allowed)
			(vias allowed)
			(pads allowed)
			(copperpour not_allowed)
			(footprints allowed)
		)
		(placement
			(enabled no)
			(sheetname "")
		)
		(fill yes
			(thermal_gap 0.5)
			(thermal_bridge_width 0.5)
			(island_removal_mode 0)
		)
		(polygon
			(pts
				(arc
					(start 158.933896 -389.467344)
					(mid 158.303976 -389.467344)
					(end 158.933896 -389.467344)
				)
			)
		)
	)
	(zone
		(layers "B.Cu" "In6.Cu" "In11.Cu" "In13.Cu" "In15.Cu")
		(hatch none 0.5)
		(connect_pads
			(clearance 0)
		)
		(min_thickness 0.25)
		(keepout
			(tracks not_allowed)
			(vias allowed)
			(pads allowed)
			(copperpour not_allowed)
			(footprints allowed)
		)
		(placement
			(enabled no)
			(sheetname "")
		)
		(fill yes
			(thermal_gap 0.5)
			(thermal_bridge_width 0.5)
			(island_removal_mode 0)
		)
		(polygon
			(pts
				(arc
					(start 435.334156 -276.38502)
					(mid 434.666136 -276.38502)
					(end 435.334156 -276.38502)
				)
			)
		)
	)
	(zone
		(layers "B.Cu" "In6.Cu" "In11.Cu" "In13.Cu" "In15.Cu")
		(hatch none 0.5)
		(connect_pads
			(clearance 0)
		)
		(min_thickness 0.25)
		(keepout
			(tracks not_allowed)
			(vias allowed)
			(pads allowed)
			(copperpour not_allowed)
			(footprints allowed)
		)
		(placement
			(enabled no)
			(sheetname "")
		)
		(fill yes
			(thermal_gap 0.5)
			(thermal_bridge_width 0.5)
			(island_removal_mode 0)
		)
		(polygon
			(pts
				(arc
					(start 121.20626 -385.31038)
					(mid 120.57634 -385.31038)
					(end 121.20626 -385.31038)
				)
			)
		)
	)
	(zone
		(layers "B.Cu" "In6.Cu" "In11.Cu" "In13.Cu" "In15.Cu")
		(hatch none 0.5)
		(connect_pads
			(clearance 0)
		)
		(min_thickness 0.25)
		(keepout
			(tracks not_allowed)
			(vias allowed)
			(pads allowed)
			(copperpour not_allowed)
			(footprints allowed)
		)
		(placement
			(enabled no)
			(sheetname "")
		)
		(fill yes
			(thermal_gap 0.5)
			(thermal_bridge_width 0.5)
			(island_removal_mode 0)
		)
		(polygon
			(pts
				(arc
					(start 385.60629 -393.69238)
					(mid 384.97637 -393.69238)
					(end 385.60629 -393.69238)
				)
			)
		)
	)
	(zone
		(layers "B.Cu" "In6.Cu" "In11.Cu" "In13.Cu" "In15.Cu")
		(hatch none 0.5)
		(connect_pads
			(clearance 0)
		)
		(min_thickness 0.25)
		(keepout
			(tracks not_allowed)
			(vias allowed)
			(pads allowed)
			(copperpour not_allowed)
			(footprints allowed)
		)
		(placement
			(enabled no)
			(sheetname "")
		)
		(fill yes
			(thermal_gap 0.5)
			(thermal_bridge_width 0.5)
			(island_removal_mode 0)
		)
		(polygon
			(pts
				(arc
					(start 380.069852 -278.136096)
					(mid 379.439932 -278.136096)
					(end 380.069852 -278.136096)
				)
			)
		)
	)
	(zone
		(layers "B.Cu" "In6.Cu" "In11.Cu" "In13.Cu" "In15.Cu")
		(hatch none 0.5)
		(connect_pads
			(clearance 0)
		)
		(min_thickness 0.25)
		(keepout
			(tracks not_allowed)
			(vias allowed)
			(pads allowed)
			(copperpour not_allowed)
			(footprints allowed)
		)
		(placement
			(enabled no)
			(sheetname "")
		)
		(fill yes
			(thermal_gap 0.5)
			(thermal_bridge_width 0.5)
			(island_removal_mode 0)
		)
		(polygon
			(pts
				(arc
					(start 131.65963 -288.666174)
					(mid 131.02971 -288.666174)
					(end 131.65963 -288.666174)
				)
			)
		)
	)
	(zone
		(layers "B.Cu" "In6.Cu" "In11.Cu" "In13.Cu" "In15.Cu")
		(hatch none 0.5)
		(connect_pads
			(clearance 0)
		)
		(min_thickness 0.25)
		(keepout
			(tracks not_allowed)
			(vias allowed)
			(pads allowed)
			(copperpour not_allowed)
			(footprints allowed)
		)
		(placement
			(enabled no)
			(sheetname "")
		)
		(fill yes
			(thermal_gap 0.5)
			(thermal_bridge_width 0.5)
			(island_removal_mode 0)
		)
		(polygon
			(pts
				(arc
					(start 33.029906 -211.7852)
					(mid 32.361886 -211.7852)
					(end 33.029906 -211.7852)
				)
			)
		)
	)
	(zone
		(layers "B.Cu" "In6.Cu" "In11.Cu" "In13.Cu" "In15.Cu")
		(hatch none 0.5)
		(connect_pads
			(clearance 0)
		)
		(min_thickness 0.25)
		(keepout
			(tracks not_allowed)
			(vias allowed)
			(pads allowed)
			(copperpour not_allowed)
			(footprints allowed)
		)
		(placement
			(enabled no)
			(sheetname "")
		)
		(fill yes
			(thermal_gap 0.5)
			(thermal_bridge_width 0.5)
			(island_removal_mode 0)
		)
		(polygon
			(pts
				(arc
					(start 91.41587 -239.624362)
					(mid 90.78595 -239.624362)
					(end 91.41587 -239.624362)
				)
			)
		)
	)
	(zone
		(layers "B.Cu" "In6.Cu" "In11.Cu" "In13.Cu" "In15.Cu")
		(hatch none 0.5)
		(connect_pads
			(clearance 0)
		)
		(min_thickness 0.25)
		(keepout
			(tracks not_allowed)
			(vias allowed)
			(pads allowed)
			(copperpour not_allowed)
			(footprints allowed)
		)
		(placement
			(enabled no)
			(sheetname "")
		)
		(fill yes
			(thermal_gap 0.5)
			(thermal_bridge_width 0.5)
			(island_removal_mode 0)
		)
		(polygon
			(pts
				(arc
					(start 191.494156 -240.68532)
					(mid 190.826136 -240.68532)
					(end 191.494156 -240.68532)
				)
			)
		)
	)
	(zone
		(layers "B.Cu" "In6.Cu" "In11.Cu" "In13.Cu" "In15.Cu")
		(hatch none 0.5)
		(connect_pads
			(clearance 0)
		)
		(min_thickness 0.25)
		(keepout
			(tracks not_allowed)
			(vias allowed)
			(pads allowed)
			(copperpour not_allowed)
			(footprints allowed)
		)
		(placement
			(enabled no)
			(sheetname "")
		)
		(fill yes
			(thermal_gap 0.5)
			(thermal_bridge_width 0.5)
			(island_removal_mode 0)
		)
		(polygon
			(pts
				(arc
					(start 131.82981 -242.864386)
					(mid 131.19989 -242.864386)
					(end 131.82981 -242.864386)
				)
			)
		)
	)
	(zone
		(layers "B.Cu" "In6.Cu" "In11.Cu" "In13.Cu" "In15.Cu")
		(hatch none 0.5)
		(connect_pads
			(clearance 0)
		)
		(min_thickness 0.25)
		(keepout
			(tracks not_allowed)
			(vias allowed)
			(pads allowed)
			(copperpour not_allowed)
			(footprints allowed)
		)
		(placement
			(enabled no)
			(sheetname "")
		)
		(fill yes
			(thermal_gap 0.5)
			(thermal_bridge_width 0.5)
			(island_removal_mode 0)
		)
		(polygon
			(pts
				(arc
					(start 381.179832 -255.014222)
					(mid 380.549912 -255.014222)
					(end 381.179832 -255.014222)
				)
			)
		)
	)
	(zone
		(layers "B.Cu" "In6.Cu" "In11.Cu" "In13.Cu" "In15.Cu")
		(hatch none 0.5)
		(connect_pads
			(clearance 0)
		)
		(min_thickness 0.25)
		(keepout
			(tracks not_allowed)
			(vias allowed)
			(pads allowed)
			(copperpour not_allowed)
			(footprints allowed)
		)
		(placement
			(enabled no)
			(sheetname "")
		)
		(fill yes
			(thermal_gap 0.5)
			(thermal_bridge_width 0.5)
			(island_removal_mode 0)
		)
		(polygon
			(pts
				(arc
					(start 339.355938 -238.004096)
					(mid 338.726018 -238.004096)
					(end 339.355938 -238.004096)
				)
			)
		)
	)
	(zone
		(layers "B.Cu" "In6.Cu" "In11.Cu" "In13.Cu" "In15.Cu")
		(hatch none 0.5)
		(connect_pads
			(clearance 0)
		)
		(min_thickness 0.25)
		(keepout
			(tracks not_allowed)
			(vias allowed)
			(pads allowed)
			(copperpour not_allowed)
			(footprints allowed)
		)
		(placement
			(enabled no)
			(sheetname "")
		)
		(fill yes
			(thermal_gap 0.5)
			(thermal_bridge_width 0.5)
			(island_removal_mode 0)
		)
		(polygon
			(pts
				(arc
					(start 37.129974 -238.985298)
					(mid 36.461954 -238.985298)
					(end 37.129974 -238.985298)
				)
			)
		)
	)
	(zone
		(layers "B.Cu" "In6.Cu" "In11.Cu" "In13.Cu" "In15.Cu")
		(hatch none 0.5)
		(connect_pads
			(clearance 0)
		)
		(min_thickness 0.25)
		(keepout
			(tracks not_allowed)
			(vias allowed)
			(pads allowed)
			(copperpour not_allowed)
			(footprints allowed)
		)
		(placement
			(enabled no)
			(sheetname "")
		)
		(fill yes
			(thermal_gap 0.5)
			(thermal_bridge_width 0.5)
			(island_removal_mode 0)
		)
		(polygon
			(pts
				(arc
					(start 379.299724 -233.954066)
					(mid 378.669804 -233.954066)
					(end 379.299724 -233.954066)
				)
			)
		)
	)
	(zone
		(layers "B.Cu" "In6.Cu" "In11.Cu" "In13.Cu" "In15.Cu")
		(hatch none 0.5)
		(connect_pads
			(clearance 0)
		)
		(min_thickness 0.25)
		(keepout
			(tracks not_allowed)
			(vias allowed)
			(pads allowed)
			(copperpour not_allowed)
			(footprints allowed)
		)
		(placement
			(enabled no)
			(sheetname "")
		)
		(fill yes
			(thermal_gap 0.5)
			(thermal_bridge_width 0.5)
			(island_removal_mode 0)
		)
		(polygon
			(pts
				(arc
					(start 92.655898 -282.996386)
					(mid 92.025978 -282.996386)
					(end 92.655898 -282.996386)
				)
			)
		)
	)
	(zone
		(layers "B.Cu" "In6.Cu" "In11.Cu" "In13.Cu" "In15.Cu")
		(hatch none 0.5)
		(connect_pads
			(clearance 0)
		)
		(min_thickness 0.25)
		(keepout
			(tracks not_allowed)
			(vias allowed)
			(pads allowed)
			(copperpour not_allowed)
			(footprints allowed)
		)
		(placement
			(enabled no)
			(sheetname "")
		)
		(fill yes
			(thermal_gap 0.5)
			(thermal_bridge_width 0.5)
			(island_removal_mode 0)
		)
		(polygon
			(pts
				(arc
					(start 191.494156 -278.085296)
					(mid 190.826136 -278.085296)
					(end 191.494156 -278.085296)
				)
			)
		)
	)
	(zone
		(layers "B.Cu" "In6.Cu" "In11.Cu" "In13.Cu" "In15.Cu")
		(hatch none 0.5)
		(connect_pads
			(clearance 0)
		)
		(min_thickness 0.25)
		(keepout
			(tracks not_allowed)
			(vias allowed)
			(pads allowed)
			(copperpour not_allowed)
			(footprints allowed)
		)
		(placement
			(enabled no)
			(sheetname "")
		)
		(fill yes
			(thermal_gap 0.5)
			(thermal_bridge_width 0.5)
			(island_removal_mode 0)
		)
		(polygon
			(pts
				(arc
					(start 379.299724 -238.814102)
					(mid 378.669804 -238.814102)
					(end 379.299724 -238.814102)
				)
			)
		)
	)
	(zone
		(layers "B.Cu" "In6.Cu" "In11.Cu" "In13.Cu" "In15.Cu")
		(hatch none 0.5)
		(connect_pads
			(clearance 0)
		)
		(min_thickness 0.25)
		(keepout
			(tracks not_allowed)
			(vias allowed)
			(pads allowed)
			(copperpour not_allowed)
			(footprints allowed)
		)
		(placement
			(enabled no)
			(sheetname "")
		)
		(fill yes
			(thermal_gap 0.5)
			(thermal_bridge_width 0.5)
			(island_removal_mode 0)
		)
		(polygon
			(pts
				(arc
					(start 33.029906 -263.635236)
					(mid 32.361886 -263.635236)
					(end 33.029906 -263.635236)
				)
			)
		)
	)
	(zone
		(layers "B.Cu" "In6.Cu" "In11.Cu" "In13.Cu" "In15.Cu")
		(hatch none 0.5)
		(connect_pads
			(clearance 0)
		)
		(min_thickness 0.25)
		(keepout
			(tracks not_allowed)
			(vias allowed)
			(pads allowed)
			(copperpour not_allowed)
			(footprints allowed)
		)
		(placement
			(enabled no)
			(sheetname "")
		)
		(fill yes
			(thermal_gap 0.5)
			(thermal_bridge_width 0.5)
			(island_removal_mode 0)
		)
		(polygon
			(pts
				(arc
					(start 133.069838 -263.556242)
					(mid 132.439918 -263.556242)
					(end 133.069838 -263.556242)
				)
			)
		)
	)
	(zone
		(layers "B.Cu" "In6.Cu" "In11.Cu" "In13.Cu" "In15.Cu")
		(hatch none 0.5)
		(connect_pads
			(clearance 0)
		)
		(min_thickness 0.25)
		(keepout
			(tracks not_allowed)
			(vias allowed)
			(pads allowed)
			(copperpour not_allowed)
			(footprints allowed)
		)
		(placement
			(enabled no)
			(sheetname "")
		)
		(fill yes
			(thermal_gap 0.5)
			(thermal_bridge_width 0.5)
			(island_removal_mode 0)
		)
		(polygon
			(pts
				(arc
					(start 91.716098 -284.616398)
					(mid 91.086178 -284.616398)
					(end 91.716098 -284.616398)
				)
			)
		)
	)
	(zone
		(layers "B.Cu" "In6.Cu" "In11.Cu" "In13.Cu" "In15.Cu")
		(hatch none 0.5)
		(connect_pads
			(clearance 0)
		)
		(min_thickness 0.25)
		(keepout
			(tracks not_allowed)
			(vias allowed)
			(pads allowed)
			(copperpour not_allowed)
			(footprints allowed)
		)
		(placement
			(enabled no)
			(sheetname "")
		)
		(fill yes
			(thermal_gap 0.5)
			(thermal_bridge_width 0.5)
			(island_removal_mode 0)
		)
		(polygon
			(pts
				(arc
					(start 131.82981 -238.00435)
					(mid 131.19989 -238.00435)
					(end 131.82981 -238.00435)
				)
			)
		)
	)
	(zone
		(layers "B.Cu" "In6.Cu" "In11.Cu" "In13.Cu" "In15.Cu")
		(hatch none 0.5)
		(connect_pads
			(clearance 0)
		)
		(min_thickness 0.25)
		(keepout
			(tracks not_allowed)
			(vias allowed)
			(pads allowed)
			(copperpour not_allowed)
			(footprints allowed)
		)
		(placement
			(enabled no)
			(sheetname "")
		)
		(fill yes
			(thermal_gap 0.5)
			(thermal_bridge_width 0.5)
			(island_removal_mode 0)
		)
		(polygon
			(pts
				(arc
					(start 101.11613 -289.47618)
					(mid 100.48621 -289.47618)
					(end 101.11613 -289.47618)
				)
			)
		)
	)
	(zone
		(layers "B.Cu" "In6.Cu" "In11.Cu" "In13.Cu" "In15.Cu")
		(hatch none 0.5)
		(connect_pads
			(clearance 0)
		)
		(min_thickness 0.25)
		(keepout
			(tracks not_allowed)
			(vias allowed)
			(pads allowed)
			(copperpour not_allowed)
			(footprints allowed)
		)
		(placement
			(enabled no)
			(sheetname "")
		)
		(fill yes
			(thermal_gap 0.5)
			(thermal_bridge_width 0.5)
			(island_removal_mode 0)
		)
		(polygon
			(pts
				(arc
					(start 132.76961 -241.244374)
					(mid 132.13969 -241.244374)
					(end 132.76961 -241.244374)
				)
			)
		)
	)
	(zone
		(layers "B.Cu" "In6.Cu" "In11.Cu" "In13.Cu" "In15.Cu")
		(hatch none 0.5)
		(connect_pads
			(clearance 0)
		)
		(min_thickness 0.25)
		(keepout
			(tracks not_allowed)
			(vias allowed)
			(pads allowed)
			(copperpour not_allowed)
			(footprints allowed)
		)
		(placement
			(enabled no)
			(sheetname "")
		)
		(fill yes
			(thermal_gap 0.5)
			(thermal_bridge_width 0.5)
			(island_removal_mode 0)
		)
		(polygon
			(pts
				(arc
					(start 381.009906 -286.236156)
					(mid 380.379986 -286.236156)
					(end 381.009906 -286.236156)
				)
			)
		)
	)
	(zone
		(layers "B.Cu" "In6.Cu" "In11.Cu" "In13.Cu" "In15.Cu")
		(hatch none 0.5)
		(connect_pads
			(clearance 0)
		)
		(min_thickness 0.25)
		(keepout
			(tracks not_allowed)
			(vias allowed)
			(pads allowed)
			(copperpour not_allowed)
			(footprints allowed)
		)
		(placement
			(enabled no)
			(sheetname "")
		)
		(fill yes
			(thermal_gap 0.5)
			(thermal_bridge_width 0.5)
			(island_removal_mode 0)
		)
		(polygon
			(pts
				(arc
					(start 339.186012 -270.846042)
					(mid 338.556092 -270.846042)
					(end 339.186012 -270.846042)
				)
			)
		)
	)
	(zone
		(layers "B.Cu" "In6.Cu" "In11.Cu" "In13.Cu" "In15.Cu")
		(hatch none 0.5)
		(connect_pads
			(clearance 0)
		)
		(min_thickness 0.25)
		(keepout
			(tracks not_allowed)
			(vias allowed)
			(pads allowed)
			(copperpour not_allowed)
			(footprints allowed)
		)
		(placement
			(enabled no)
			(sheetname "")
		)
		(fill yes
			(thermal_gap 0.5)
			(thermal_bridge_width 0.5)
			(island_removal_mode 0)
		)
		(polygon
			(pts
				(arc
					(start 280.969974 -222.834962)
					(mid 280.301954 -222.834962)
					(end 280.969974 -222.834962)
				)
			)
		)
	)
	(zone
		(layers "B.Cu" "In6.Cu" "In11.Cu" "In13.Cu" "In15.Cu")
		(hatch none 0.5)
		(connect_pads
			(clearance 0)
		)
		(min_thickness 0.25)
		(keepout
			(tracks not_allowed)
			(vias allowed)
			(pads allowed)
			(copperpour not_allowed)
			(footprints allowed)
		)
		(placement
			(enabled no)
			(sheetname "")
		)
		(fill yes
			(thermal_gap 0.5)
			(thermal_bridge_width 0.5)
			(island_removal_mode 0)
		)
		(polygon
			(pts
				(arc
					(start 280.969974 -254.284988)
					(mid 280.301954 -254.284988)
					(end 280.969974 -254.284988)
				)
			)
		)
	)
	(zone
		(layers "B.Cu" "In6.Cu" "In11.Cu" "In13.Cu" "In15.Cu")
		(hatch none 0.5)
		(connect_pads
			(clearance 0)
		)
		(min_thickness 0.25)
		(keepout
			(tracks not_allowed)
			(vias allowed)
			(pads allowed)
			(copperpour not_allowed)
			(footprints allowed)
		)
		(placement
			(enabled no)
			(sheetname "")
		)
		(fill yes
			(thermal_gap 0.5)
			(thermal_bridge_width 0.5)
			(island_removal_mode 0)
		)
		(polygon
			(pts
				(arc
					(start 133.239764 -225.854514)
					(mid 132.609844 -225.854514)
					(end 133.239764 -225.854514)
				)
			)
		)
	)
	(zone
		(layers "B.Cu" "In6.Cu" "In11.Cu" "In13.Cu" "In15.Cu")
		(hatch none 0.5)
		(connect_pads
			(clearance 0)
		)
		(min_thickness 0.25)
		(keepout
			(tracks not_allowed)
			(vias allowed)
			(pads allowed)
			(copperpour not_allowed)
			(footprints allowed)
		)
		(placement
			(enabled no)
			(sheetname "")
		)
		(fill yes
			(thermal_gap 0.5)
			(thermal_bridge_width 0.5)
			(island_removal_mode 0)
		)
		(polygon
			(pts
				(arc
					(start 439.434224 -249.185176)
					(mid 438.766204 -249.185176)
					(end 439.434224 -249.185176)
				)
			)
		)
	)
	(zone
		(layers "B.Cu" "In6.Cu" "In11.Cu" "In13.Cu" "In15.Cu")
		(hatch none 0.5)
		(connect_pads
			(clearance 0)
		)
		(min_thickness 0.25)
		(keepout
			(tracks not_allowed)
			(vias allowed)
			(pads allowed)
			(copperpour not_allowed)
			(footprints allowed)
		)
		(placement
			(enabled no)
			(sheetname "")
		)
		(fill yes
			(thermal_gap 0.5)
			(thermal_bridge_width 0.5)
			(island_removal_mode 0)
		)
		(polygon
			(pts
				(arc
					(start 92.826078 -248.534428)
					(mid 92.196158 -248.534428)
					(end 92.826078 -248.534428)
				)
			)
		)
	)
	(zone
		(layers "B.Cu" "In6.Cu" "In11.Cu" "In13.Cu" "In15.Cu")
		(hatch none 0.5)
		(connect_pads
			(clearance 0)
		)
		(min_thickness 0.25)
		(keepout
			(tracks not_allowed)
			(vias allowed)
			(pads allowed)
			(copperpour not_allowed)
			(footprints allowed)
		)
		(placement
			(enabled no)
			(sheetname "")
		)
		(fill yes
			(thermal_gap 0.5)
			(thermal_bridge_width 0.5)
			(island_removal_mode 0)
		)
		(polygon
			(pts
				(arc
					(start 356.746048 -229.094284)
					(mid 356.116128 -229.094284)
					(end 356.746048 -229.094284)
				)
			)
		)
	)
	(zone
		(layers "B.Cu" "In6.Cu" "In11.Cu" "In13.Cu" "In15.Cu")
		(hatch none 0.5)
		(connect_pads
			(clearance 0)
		)
		(min_thickness 0.25)
		(keepout
			(tracks not_allowed)
			(vias allowed)
			(pads allowed)
			(copperpour not_allowed)
			(footprints allowed)
		)
		(placement
			(enabled no)
			(sheetname "")
		)
		(fill yes
			(thermal_gap 0.5)
			(thermal_bridge_width 0.5)
			(island_removal_mode 0)
		)
		(polygon
			(pts
				(arc
					(start 98.863912 -369.03533)
					(mid 98.195892 -369.03533)
					(end 98.863912 -369.03533)
				)
			)
		)
	)
	(zone
		(layers "B.Cu" "In6.Cu" "In11.Cu" "In13.Cu" "In15.Cu")
		(hatch none 0.5)
		(connect_pads
			(clearance 0)
		)
		(min_thickness 0.25)
		(keepout
			(tracks not_allowed)
			(vias allowed)
			(pads allowed)
			(copperpour not_allowed)
			(footprints allowed)
		)
		(placement
			(enabled no)
			(sheetname "")
		)
		(fill yes
			(thermal_gap 0.5)
			(thermal_bridge_width 0.5)
			(island_removal_mode 0)
		)
		(polygon
			(pts
				(arc
					(start 285.070042 -242.385088)
					(mid 284.402022 -242.385088)
					(end 285.070042 -242.385088)
				)
			)
		)
	)
	(zone
		(layers "B.Cu" "In6.Cu" "In11.Cu" "In13.Cu" "In15.Cu")
		(hatch none 0.5)
		(connect_pads
			(clearance 0)
		)
		(min_thickness 0.25)
		(keepout
			(tracks not_allowed)
			(vias allowed)
			(pads allowed)
			(copperpour not_allowed)
			(footprints allowed)
		)
		(placement
			(enabled no)
			(sheetname "")
		)
		(fill yes
			(thermal_gap 0.5)
			(thermal_bridge_width 0.5)
			(island_removal_mode 0)
		)
		(polygon
			(pts
				(arc
					(start 131.82981 -250.964446)
					(mid 131.19989 -250.964446)
					(end 131.82981 -250.964446)
				)
			)
		)
	)
	(zone
		(layers "B.Cu" "In6.Cu" "In11.Cu" "In13.Cu" "In15.Cu")
		(hatch none 0.5)
		(connect_pads
			(clearance 0)
		)
		(min_thickness 0.25)
		(keepout
			(tracks not_allowed)
			(vias allowed)
			(pads allowed)
			(copperpour not_allowed)
			(footprints allowed)
		)
		(placement
			(enabled no)
			(sheetname "")
		)
		(fill yes
			(thermal_gap 0.5)
			(thermal_bridge_width 0.5)
			(island_removal_mode 0)
		)
		(polygon
			(pts
				(arc
					(start 133.239764 -245.294404)
					(mid 132.609844 -245.294404)
					(end 133.239764 -245.294404)
				)
			)
		)
	)
	(zone
		(layers "B.Cu" "In6.Cu" "In11.Cu" "In13.Cu" "In15.Cu")
		(hatch none 0.5)
		(connect_pads
			(clearance 0)
		)
		(min_thickness 0.25)
		(keepout
			(tracks not_allowed)
			(vias allowed)
			(pads allowed)
			(copperpour not_allowed)
			(footprints allowed)
		)
		(placement
			(enabled no)
			(sheetname "")
		)
		(fill yes
			(thermal_gap 0.5)
			(thermal_bridge_width 0.5)
			(island_removal_mode 0)
		)
		(polygon
			(pts
				(arc
					(start 187.394088 -222.835216)
					(mid 186.726068 -222.835216)
					(end 187.394088 -222.835216)
				)
			)
		)
	)
	(zone
		(layers "B.Cu" "In6.Cu" "In11.Cu" "In13.Cu" "In15.Cu")
		(hatch none 0.5)
		(connect_pads
			(clearance 0)
		)
		(min_thickness 0.25)
		(keepout
			(tracks not_allowed)
			(vias allowed)
			(pads allowed)
			(copperpour not_allowed)
			(footprints allowed)
		)
		(placement
			(enabled no)
			(sheetname "")
		)
		(fill yes
			(thermal_gap 0.5)
			(thermal_bridge_width 0.5)
			(island_removal_mode 0)
		)
		(polygon
			(pts
				(arc
					(start 191.494156 -208.38541)
					(mid 190.826136 -208.38541)
					(end 191.494156 -208.38541)
				)
			)
		)
	)
	(zone
		(layers "B.Cu" "In6.Cu" "In11.Cu" "In13.Cu" "In15.Cu")
		(hatch none 0.5)
		(connect_pads
			(clearance 0)
		)
		(min_thickness 0.25)
		(keepout
			(tracks not_allowed)
			(vias allowed)
			(pads allowed)
			(copperpour not_allowed)
			(footprints allowed)
		)
		(placement
			(enabled no)
			(sheetname "")
		)
		(fill yes
			(thermal_gap 0.5)
			(thermal_bridge_width 0.5)
			(island_removal_mode 0)
		)
		(polygon
			(pts
				(arc
					(start 389.606282 -394.385292)
					(mid 388.976362 -394.385292)
					(end 389.606282 -394.385292)
				)
			)
		)
	)
	(zone
		(layers "B.Cu" "In6.Cu" "In11.Cu" "In13.Cu" "In15.Cu")
		(hatch none 0.5)
		(connect_pads
			(clearance 0)
		)
		(min_thickness 0.25)
		(keepout
			(tracks not_allowed)
			(vias allowed)
			(pads allowed)
			(copperpour not_allowed)
			(footprints allowed)
		)
		(placement
			(enabled no)
			(sheetname "")
		)
		(fill yes
			(thermal_gap 0.5)
			(thermal_bridge_width 0.5)
			(island_removal_mode 0)
		)
		(polygon
			(pts
				(arc
					(start 285.070042 -279.785064)
					(mid 284.402022 -279.785064)
					(end 285.070042 -279.785064)
				)
			)
		)
	)
	(zone
		(layers "B.Cu" "In6.Cu" "In11.Cu" "In13.Cu" "In15.Cu")
		(hatch none 0.5)
		(connect_pads
			(clearance 0)
		)
		(min_thickness 0.25)
		(keepout
			(tracks not_allowed)
			(vias allowed)
			(pads allowed)
			(copperpour not_allowed)
			(footprints allowed)
		)
		(placement
			(enabled no)
			(sheetname "")
		)
		(fill yes
			(thermal_gap 0.5)
			(thermal_bridge_width 0.5)
			(island_removal_mode 0)
		)
		(polygon
			(pts
				(arc
					(start 114.4397 -229.094538)
					(mid 113.80978 -229.094538)
					(end 114.4397 -229.094538)
				)
			)
		)
	)
	(zone
		(layers "B.Cu" "In6.Cu" "In11.Cu" "In13.Cu" "In15.Cu")
		(hatch none 0.5)
		(connect_pads
			(clearance 0)
		)
		(min_thickness 0.25)
		(keepout
			(tracks not_allowed)
			(vias allowed)
			(pads allowed)
			(copperpour not_allowed)
			(footprints allowed)
		)
		(placement
			(enabled no)
			(sheetname "")
		)
		(fill yes
			(thermal_gap 0.5)
			(thermal_bridge_width 0.5)
			(island_removal_mode 0)
		)
		(polygon
			(pts
				(arc
					(start 285.070042 -294.235124)
					(mid 284.402022 -294.235124)
					(end 285.070042 -294.235124)
				)
			)
		)
	)
	(zone
		(layers "B.Cu" "In6.Cu" "In11.Cu" "In13.Cu" "In15.Cu")
		(hatch none 0.5)
		(connect_pads
			(clearance 0)
		)
		(min_thickness 0.25)
		(keepout
			(tracks not_allowed)
			(vias allowed)
			(pads allowed)
			(copperpour not_allowed)
			(footprints allowed)
		)
		(placement
			(enabled no)
			(sheetname "")
		)
		(fill yes
			(thermal_gap 0.5)
			(thermal_bridge_width 0.5)
			(island_removal_mode 0)
		)
		(polygon
			(pts
				(arc
					(start 132.76961 -225.044508)
					(mid 132.13969 -225.044508)
					(end 132.76961 -225.044508)
				)
			)
		)
	)
	(zone
		(layers "B.Cu" "In6.Cu" "In11.Cu" "In13.Cu" "In15.Cu")
		(hatch none 0.5)
		(connect_pads
			(clearance 0)
		)
		(min_thickness 0.25)
		(keepout
			(tracks not_allowed)
			(vias allowed)
			(pads allowed)
			(copperpour not_allowed)
			(footprints allowed)
		)
		(placement
			(enabled no)
			(sheetname "")
		)
		(fill yes
			(thermal_gap 0.5)
			(thermal_bridge_width 0.5)
			(island_removal_mode 0)
		)
		(polygon
			(pts
				(arc
					(start 91.41587 -242.864386)
					(mid 90.78595 -242.864386)
					(end 91.41587 -242.864386)
				)
			)
		)
	)
	(zone
		(layers "B.Cu" "In6.Cu" "In11.Cu" "In13.Cu" "In15.Cu")
		(hatch none 0.5)
		(connect_pads
			(clearance 0)
		)
		(min_thickness 0.25)
		(keepout
			(tracks not_allowed)
			(vias allowed)
			(pads allowed)
			(copperpour not_allowed)
			(footprints allowed)
		)
		(placement
			(enabled no)
			(sheetname "")
		)
		(fill yes
			(thermal_gap 0.5)
			(thermal_bridge_width 0.5)
			(island_removal_mode 0)
		)
		(polygon
			(pts
				(arc
					(start 92.826078 -253.394464)
					(mid 92.196158 -253.394464)
					(end 92.826078 -253.394464)
				)
			)
		)
	)
	(zone
		(layers "B.Cu" "In6.Cu" "In11.Cu" "In13.Cu" "In15.Cu")
		(hatch none 0.5)
		(connect_pads
			(clearance 0)
		)
		(min_thickness 0.25)
		(keepout
			(tracks not_allowed)
			(vias allowed)
			(pads allowed)
			(copperpour not_allowed)
			(footprints allowed)
		)
		(placement
			(enabled no)
			(sheetname "")
		)
		(fill yes
			(thermal_gap 0.5)
			(thermal_bridge_width 0.5)
			(island_removal_mode 0)
		)
		(polygon
			(pts
				(arc
					(start 187.394088 -295.9354)
					(mid 186.726068 -295.9354)
					(end 187.394088 -295.9354)
				)
			)
		)
	)
	(zone
		(layers "B.Cu" "In6.Cu" "In11.Cu" "In13.Cu" "In15.Cu")
		(hatch none 0.5)
		(connect_pads
			(clearance 0)
		)
		(min_thickness 0.25)
		(keepout
			(tracks not_allowed)
			(vias allowed)
			(pads allowed)
			(copperpour not_allowed)
			(footprints allowed)
		)
		(placement
			(enabled no)
			(sheetname "")
		)
		(fill yes
			(thermal_gap 0.5)
			(thermal_bridge_width 0.5)
			(island_removal_mode 0)
		)
		(polygon
			(pts
				(arc
					(start 280.969974 -221.13494)
					(mid 280.301954 -221.13494)
					(end 280.969974 -221.13494)
				)
			)
		)
	)
	(zone
		(layers "B.Cu" "In6.Cu" "In11.Cu" "In13.Cu" "In15.Cu")
		(hatch none 0.5)
		(connect_pads
			(clearance 0)
		)
		(min_thickness 0.25)
		(keepout
			(tracks not_allowed)
			(vias allowed)
			(pads allowed)
			(copperpour not_allowed)
			(footprints allowed)
		)
		(placement
			(enabled no)
			(sheetname "")
		)
		(fill yes
			(thermal_gap 0.5)
			(thermal_bridge_width 0.5)
			(island_removal_mode 0)
		)
		(polygon
			(pts
				(arc
					(start 132.76961 -252.584458)
					(mid 132.13969 -252.584458)
					(end 132.76961 -252.584458)
				)
			)
		)
	)
	(zone
		(layers "B.Cu" "In6.Cu" "In11.Cu" "In13.Cu" "In15.Cu")
		(hatch none 0.5)
		(connect_pads
			(clearance 0)
		)
		(min_thickness 0.25)
		(keepout
			(tracks not_allowed)
			(vias allowed)
			(pads allowed)
			(copperpour not_allowed)
			(footprints allowed)
		)
		(placement
			(enabled no)
			(sheetname "")
		)
		(fill yes
			(thermal_gap 0.5)
			(thermal_bridge_width 0.5)
			(island_removal_mode 0)
		)
		(polygon
			(pts
				(arc
					(start 340.595966 -292.71595)
					(mid 339.966046 -292.71595)
					(end 340.595966 -292.71595)
				)
			)
		)
	)
	(zone
		(layers "B.Cu" "In6.Cu" "In11.Cu" "In13.Cu" "In15.Cu")
		(hatch none 0.5)
		(connect_pads
			(clearance 0)
		)
		(min_thickness 0.25)
		(keepout
			(tracks not_allowed)
			(vias allowed)
			(pads allowed)
			(copperpour not_allowed)
			(footprints allowed)
		)
		(placement
			(enabled no)
			(sheetname "")
		)
		(fill yes
			(thermal_gap 0.5)
			(thermal_bridge_width 0.5)
			(island_removal_mode 0)
		)
		(polygon
			(pts
				(arc
					(start 340.766146 -248.534174)
					(mid 340.136226 -248.534174)
					(end 340.766146 -248.534174)
				)
			)
		)
	)
	(zone
		(layers "B.Cu" "In6.Cu" "In11.Cu" "In13.Cu" "In15.Cu")
		(hatch none 0.5)
		(connect_pads
			(clearance 0)
		)
		(min_thickness 0.25)
		(keepout
			(tracks not_allowed)
			(vias allowed)
			(pads allowed)
			(copperpour not_allowed)
			(footprints allowed)
		)
		(placement
			(enabled no)
			(sheetname "")
		)
		(fill yes
			(thermal_gap 0.5)
			(thermal_bridge_width 0.5)
			(island_removal_mode 0)
		)
		(polygon
			(pts
				(arc
					(start 338.886038 -242.054126)
					(mid 338.256118 -242.054126)
					(end 338.886038 -242.054126)
				)
			)
		)
	)
	(zone
		(layers "B.Cu" "In6.Cu" "In11.Cu" "In13.Cu" "In15.Cu")
		(hatch none 0.5)
		(connect_pads
			(clearance 0)
		)
		(min_thickness 0.25)
		(keepout
			(tracks not_allowed)
			(vias allowed)
			(pads allowed)
			(copperpour not_allowed)
			(footprints allowed)
		)
		(placement
			(enabled no)
			(sheetname "")
		)
		(fill yes
			(thermal_gap 0.5)
			(thermal_bridge_width 0.5)
			(island_removal_mode 0)
		)
		(polygon
			(pts
				(arc
					(start 131.359656 -225.854514)
					(mid 130.729736 -225.854514)
					(end 131.359656 -225.854514)
				)
			)
		)
	)
	(zone
		(layers "B.Cu" "In6.Cu" "In11.Cu" "In13.Cu" "In15.Cu")
		(hatch none 0.5)
		(connect_pads
			(clearance 0)
		)
		(min_thickness 0.25)
		(keepout
			(tracks not_allowed)
			(vias allowed)
			(pads allowed)
			(copperpour not_allowed)
			(footprints allowed)
		)
		(placement
			(enabled no)
			(sheetname "")
		)
		(fill yes
			(thermal_gap 0.5)
			(thermal_bridge_width 0.5)
			(island_removal_mode 0)
		)
		(polygon
			(pts
				(arc
					(start 375.20626 -394.385292)
					(mid 374.57634 -394.385292)
					(end 375.20626 -394.385292)
				)
			)
		)
	)
	(zone
		(layers "B.Cu" "In6.Cu" "In11.Cu" "In13.Cu" "In15.Cu")
		(hatch none 0.5)
		(connect_pads
			(clearance 0)
		)
		(min_thickness 0.25)
		(keepout
			(tracks not_allowed)
			(vias allowed)
			(pads allowed)
			(copperpour not_allowed)
			(footprints allowed)
		)
		(placement
			(enabled no)
			(sheetname "")
		)
		(fill yes
			(thermal_gap 0.5)
			(thermal_bridge_width 0.5)
			(island_removal_mode 0)
		)
		(polygon
			(pts
				(arc
					(start 56.738012 -4.963414)
					(mid 56.069992 -4.963414)
					(end 56.738012 -4.963414)
				)
			)
		)
	)
	(zone
		(layers "B.Cu" "In6.Cu" "In11.Cu" "In13.Cu" "In15.Cu")
		(hatch none 0.5)
		(connect_pads
			(clearance 0)
		)
		(min_thickness 0.25)
		(keepout
			(tracks not_allowed)
			(vias allowed)
			(pads allowed)
			(copperpour not_allowed)
			(footprints allowed)
		)
		(placement
			(enabled no)
			(sheetname "")
		)
		(fill yes
			(thermal_gap 0.5)
			(thermal_bridge_width 0.5)
			(island_removal_mode 0)
		)
		(polygon
			(pts
				(arc
					(start 132.129784 -261.93623)
					(mid 131.499864 -261.93623)
					(end 132.129784 -261.93623)
				)
			)
		)
	)
	(zone
		(layers "B.Cu" "In6.Cu" "In11.Cu" "In13.Cu" "In15.Cu")
		(hatch none 0.5)
		(connect_pads
			(clearance 0)
		)
		(min_thickness 0.25)
		(keepout
			(tracks not_allowed)
			(vias allowed)
			(pads allowed)
			(copperpour not_allowed)
			(footprints allowed)
		)
		(placement
			(enabled no)
			(sheetname "")
		)
		(fill yes
			(thermal_gap 0.5)
			(thermal_bridge_width 0.5)
			(island_removal_mode 0)
		)
		(polygon
			(pts
				(arc
					(start 340.595966 -286.236156)
					(mid 339.966046 -286.236156)
					(end 340.595966 -286.236156)
				)
			)
		)
	)
	(zone
		(layers "B.Cu" "In6.Cu" "In11.Cu" "In13.Cu" "In15.Cu")
		(hatch none 0.5)
		(connect_pads
			(clearance 0)
		)
		(min_thickness 0.25)
		(keepout
			(tracks not_allowed)
			(vias allowed)
			(pads allowed)
			(copperpour not_allowed)
			(footprints allowed)
		)
		(placement
			(enabled no)
			(sheetname "")
		)
		(fill yes
			(thermal_gap 0.5)
			(thermal_bridge_width 0.5)
			(island_removal_mode 0)
		)
		(polygon
			(pts
				(arc
					(start 419.47719 -17.61236)
					(mid 418.80917 -17.61236)
					(end 419.47719 -17.61236)
				)
			)
		)
	)
	(zone
		(layers "B.Cu" "In6.Cu" "In11.Cu" "In13.Cu" "In15.Cu")
		(hatch none 0.5)
		(connect_pads
			(clearance 0)
		)
		(min_thickness 0.25)
		(keepout
			(tracks not_allowed)
			(vias allowed)
			(pads allowed)
			(copperpour not_allowed)
			(footprints allowed)
		)
		(placement
			(enabled no)
			(sheetname "")
		)
		(fill yes
			(thermal_gap 0.5)
			(thermal_bridge_width 0.5)
			(island_removal_mode 0)
		)
		(polygon
			(pts
				(arc
					(start 339.186012 -274.086066)
					(mid 338.556092 -274.086066)
					(end 339.186012 -274.086066)
				)
			)
		)
	)
	(zone
		(layers "B.Cu" "In6.Cu" "In11.Cu" "In13.Cu" "In15.Cu")
		(hatch none 0.5)
		(connect_pads
			(clearance 0)
		)
		(min_thickness 0.25)
		(keepout
			(tracks not_allowed)
			(vias allowed)
			(pads allowed)
			(copperpour not_allowed)
			(footprints allowed)
		)
		(placement
			(enabled no)
			(sheetname "")
		)
		(fill yes
			(thermal_gap 0.5)
			(thermal_bridge_width 0.5)
			(island_removal_mode 0)
		)
		(polygon
			(pts
				(arc
					(start 187.394088 -253.435358)
					(mid 186.726068 -253.435358)
					(end 187.394088 -253.435358)
				)
			)
		)
	)
	(zone
		(layers "B.Cu" "In6.Cu" "In11.Cu" "In13.Cu" "In15.Cu")
		(hatch none 0.5)
		(connect_pads
			(clearance 0)
		)
		(min_thickness 0.25)
		(keepout
			(tracks not_allowed)
			(vias allowed)
			(pads allowed)
			(copperpour not_allowed)
			(footprints allowed)
		)
		(placement
			(enabled no)
			(sheetname "")
		)
		(fill yes
			(thermal_gap 0.5)
			(thermal_bridge_width 0.5)
			(island_removal_mode 0)
		)
		(polygon
			(pts
				(arc
					(start 439.434224 -309.535068)
					(mid 438.766204 -309.535068)
					(end 439.434224 -309.535068)
				)
			)
		)
	)
	(zone
		(layers "B.Cu" "In6.Cu" "In11.Cu" "In13.Cu" "In15.Cu")
		(hatch none 0.5)
		(connect_pads
			(clearance 0)
		)
		(min_thickness 0.25)
		(keepout
			(tracks not_allowed)
			(vias allowed)
			(pads allowed)
			(copperpour not_allowed)
			(footprints allowed)
		)
		(placement
			(enabled no)
			(sheetname "")
		)
		(fill yes
			(thermal_gap 0.5)
			(thermal_bridge_width 0.5)
			(island_removal_mode 0)
		)
		(polygon
			(pts
				(arc
					(start 381.479806 -290.285932)
					(mid 380.849886 -290.285932)
					(end 381.479806 -290.285932)
				)
			)
		)
	)
	(zone
		(layers "B.Cu" "In6.Cu" "In11.Cu" "In13.Cu" "In15.Cu")
		(hatch none 0.5)
		(connect_pads
			(clearance 0)
		)
		(min_thickness 0.25)
		(keepout
			(tracks not_allowed)
			(vias allowed)
			(pads allowed)
			(copperpour not_allowed)
			(footprints allowed)
		)
		(placement
			(enabled no)
			(sheetname "")
		)
		(fill yes
			(thermal_gap 0.5)
			(thermal_bridge_width 0.5)
			(island_removal_mode 0)
		)
		(polygon
			(pts
				(arc
					(start 409.734004 -397.156432)
					(mid 409.104084 -397.156432)
					(end 409.734004 -397.156432)
				)
			)
		)
	)
	(zone
		(layers "B.Cu" "In6.Cu" "In11.Cu" "In13.Cu" "In15.Cu")
		(hatch none 0.5)
		(connect_pads
			(clearance 0)
		)
		(min_thickness 0.25)
		(keepout
			(tracks not_allowed)
			(vias allowed)
			(pads allowed)
			(copperpour not_allowed)
			(footprints allowed)
		)
		(placement
			(enabled no)
			(sheetname "")
		)
		(fill yes
			(thermal_gap 0.5)
			(thermal_bridge_width 0.5)
			(island_removal_mode 0)
		)
		(polygon
			(pts
				(arc
					(start 126.18974 -231.524302)
					(mid 125.55982 -231.524302)
					(end 126.18974 -231.524302)
				)
			)
		)
	)
	(zone
		(layers "B.Cu" "In6.Cu" "In11.Cu" "In13.Cu" "In15.Cu")
		(hatch none 0.5)
		(connect_pads
			(clearance 0)
		)
		(min_thickness 0.25)
		(keepout
			(tracks not_allowed)
			(vias allowed)
			(pads allowed)
			(copperpour not_allowed)
			(footprints allowed)
		)
		(placement
			(enabled no)
			(sheetname "")
		)
		(fill yes
			(thermal_gap 0.5)
			(thermal_bridge_width 0.5)
			(island_removal_mode 0)
		)
		(polygon
			(pts
				(arc
					(start 187.394088 -267.03528)
					(mid 186.726068 -267.03528)
					(end 187.394088 -267.03528)
				)
			)
		)
	)
	(zone
		(layers "B.Cu" "In6.Cu" "In11.Cu" "In13.Cu" "In15.Cu")
		(hatch none 0.5)
		(connect_pads
			(clearance 0)
		)
		(min_thickness 0.25)
		(keepout
			(tracks not_allowed)
			(vias allowed)
			(pads allowed)
			(copperpour not_allowed)
			(footprints allowed)
		)
		(placement
			(enabled no)
			(sheetname "")
		)
		(fill yes
			(thermal_gap 0.5)
			(thermal_bridge_width 0.5)
			(island_removal_mode 0)
		)
		(polygon
			(pts
				(arc
					(start 116.789708 -228.284532)
					(mid 116.159788 -228.284532)
					(end 116.789708 -228.284532)
				)
			)
		)
	)
	(zone
		(layers "B.Cu" "In6.Cu" "In11.Cu" "In13.Cu" "In15.Cu")
		(hatch none 0.5)
		(connect_pads
			(clearance 0)
		)
		(min_thickness 0.25)
		(keepout
			(tracks not_allowed)
			(vias allowed)
			(pads allowed)
			(copperpour not_allowed)
			(footprints allowed)
		)
		(placement
			(enabled no)
			(sheetname "")
		)
		(fill yes
			(thermal_gap 0.5)
			(thermal_bridge_width 0.5)
			(island_removal_mode 0)
		)
		(polygon
			(pts
				(arc
					(start 22.949662 -6.725158)
					(mid 22.281642 -6.725158)
					(end 22.949662 -6.725158)
				)
			)
		)
	)
	(zone
		(layers "B.Cu" "In6.Cu" "In11.Cu" "In13.Cu" "In15.Cu")
		(hatch none 0.5)
		(connect_pads
			(clearance 0)
		)
		(min_thickness 0.25)
		(keepout
			(tracks not_allowed)
			(vias allowed)
			(pads allowed)
			(copperpour not_allowed)
			(footprints allowed)
		)
		(placement
			(enabled no)
			(sheetname "")
		)
		(fill yes
			(thermal_gap 0.5)
			(thermal_bridge_width 0.5)
			(island_removal_mode 0)
		)
		(polygon
			(pts
				(arc
					(start 339.656166 -286.236156)
					(mid 339.026246 -286.236156)
					(end 339.656166 -286.236156)
				)
			)
		)
	)
	(zone
		(layers "B.Cu" "In6.Cu" "In11.Cu" "In13.Cu" "In15.Cu")
		(hatch none 0.5)
		(connect_pads
			(clearance 0)
		)
		(min_thickness 0.25)
		(keepout
			(tracks not_allowed)
			(vias allowed)
			(pads allowed)
			(copperpour not_allowed)
			(footprints allowed)
		)
		(placement
			(enabled no)
			(sheetname "")
		)
		(fill yes
			(thermal_gap 0.5)
			(thermal_bridge_width 0.5)
			(island_removal_mode 0)
		)
		(polygon
			(pts
				(arc
					(start 380.709678 -226.664266)
					(mid 380.079758 -226.664266)
					(end 380.709678 -226.664266)
				)
			)
		)
	)
	(zone
		(layers "B.Cu" "In6.Cu" "In11.Cu" "In13.Cu" "In15.Cu")
		(hatch none 0.5)
		(connect_pads
			(clearance 0)
		)
		(min_thickness 0.25)
		(keepout
			(tracks not_allowed)
			(vias allowed)
			(pads allowed)
			(copperpour not_allowed)
			(footprints allowed)
		)
		(placement
			(enabled no)
			(sheetname "")
		)
		(fill yes
			(thermal_gap 0.5)
			(thermal_bridge_width 0.5)
			(island_removal_mode 0)
		)
		(polygon
			(pts
				(arc
					(start 97.995994 -233.144314)
					(mid 97.366074 -233.144314)
					(end 97.995994 -233.144314)
				)
			)
		)
	)
	(zone
		(layers "B.Cu" "In6.Cu" "In11.Cu" "In13.Cu" "In15.Cu")
		(hatch none 0.5)
		(connect_pads
			(clearance 0)
		)
		(min_thickness 0.25)
		(keepout
			(tracks not_allowed)
			(vias allowed)
			(pads allowed)
			(copperpour not_allowed)
			(footprints allowed)
		)
		(placement
			(enabled no)
			(sheetname "")
		)
		(fill yes
			(thermal_gap 0.5)
			(thermal_bridge_width 0.5)
			(island_removal_mode 0)
		)
		(polygon
			(pts
				(arc
					(start 132.129784 -278.13635)
					(mid 131.499864 -278.13635)
					(end 132.129784 -278.13635)
				)
			)
		)
	)
	(zone
		(layers "B.Cu" "In6.Cu" "In11.Cu" "In13.Cu" "In15.Cu")
		(hatch none 0.5)
		(connect_pads
			(clearance 0)
		)
		(min_thickness 0.25)
		(keepout
			(tracks not_allowed)
			(vias allowed)
			(pads allowed)
			(copperpour not_allowed)
			(footprints allowed)
		)
		(placement
			(enabled no)
			(sheetname "")
		)
		(fill yes
			(thermal_gap 0.5)
			(thermal_bridge_width 0.5)
			(island_removal_mode 0)
		)
		(polygon
			(pts
				(arc
					(start 131.65963 -285.426404)
					(mid 131.02971 -285.426404)
					(end 131.65963 -285.426404)
				)
			)
		)
	)
	(zone
		(layers "B.Cu" "In6.Cu" "In11.Cu" "In13.Cu" "In15.Cu")
		(hatch none 0.5)
		(connect_pads
			(clearance 0)
		)
		(min_thickness 0.25)
		(keepout
			(tracks not_allowed)
			(vias allowed)
			(pads allowed)
			(copperpour not_allowed)
			(footprints allowed)
		)
		(placement
			(enabled no)
			(sheetname "")
		)
		(fill yes
			(thermal_gap 0.5)
			(thermal_bridge_width 0.5)
			(island_removal_mode 0)
		)
		(polygon
			(pts
				(arc
					(start 191.494156 -210.935316)
					(mid 190.826136 -210.935316)
					(end 191.494156 -210.935316)
				)
			)
		)
	)
	(zone
		(layers "B.Cu" "In6.Cu" "In11.Cu" "In13.Cu" "In15.Cu")
		(hatch none 0.5)
		(connect_pads
			(clearance 0)
		)
		(min_thickness 0.25)
		(keepout
			(tracks not_allowed)
			(vias allowed)
			(pads allowed)
			(copperpour not_allowed)
			(footprints allowed)
		)
		(placement
			(enabled no)
			(sheetname "")
		)
		(fill yes
			(thermal_gap 0.5)
			(thermal_bridge_width 0.5)
			(island_removal_mode 0)
		)
		(polygon
			(pts
				(arc
					(start 33.029906 -230.485442)
					(mid 32.361886 -230.485442)
					(end 33.029906 -230.485442)
				)
			)
		)
	)
	(zone
		(layers "B.Cu" "In6.Cu" "In11.Cu" "In13.Cu" "In15.Cu")
		(hatch none 0.5)
		(connect_pads
			(clearance 0)
		)
		(min_thickness 0.25)
		(keepout
			(tracks not_allowed)
			(vias allowed)
			(pads allowed)
			(copperpour not_allowed)
			(footprints allowed)
		)
		(placement
			(enabled no)
			(sheetname "")
		)
		(fill yes
			(thermal_gap 0.5)
			(thermal_bridge_width 0.5)
			(island_removal_mode 0)
		)
		(polygon
			(pts
				(arc
					(start 121.60631 -386.003292)
					(mid 120.97639 -386.003292)
					(end 121.60631 -386.003292)
				)
			)
		)
	)
	(zone
		(layers "B.Cu" "In6.Cu" "In11.Cu" "In13.Cu" "In15.Cu")
		(hatch none 0.5)
		(connect_pads
			(clearance 0)
		)
		(min_thickness 0.25)
		(keepout
			(tracks not_allowed)
			(vias allowed)
			(pads allowed)
			(copperpour not_allowed)
			(footprints allowed)
		)
		(placement
			(enabled no)
			(sheetname "")
		)
		(fill yes
			(thermal_gap 0.5)
			(thermal_bridge_width 0.5)
			(island_removal_mode 0)
		)
		(polygon
			(pts
				(arc
					(start 90.94597 -248.534428)
					(mid 90.31605 -248.534428)
					(end 90.94597 -248.534428)
				)
			)
		)
	)
	(zone
		(layers "B.Cu" "In6.Cu" "In11.Cu" "In13.Cu" "In15.Cu")
		(hatch none 0.5)
		(connect_pads
			(clearance 0)
		)
		(min_thickness 0.25)
		(keepout
			(tracks not_allowed)
			(vias allowed)
			(pads allowed)
			(copperpour not_allowed)
			(footprints allowed)
		)
		(placement
			(enabled no)
			(sheetname "")
		)
		(fill yes
			(thermal_gap 0.5)
			(thermal_bridge_width 0.5)
			(island_removal_mode 0)
		)
		(polygon
			(pts
				(arc
					(start 439.434224 -238.13516)
					(mid 438.766204 -238.13516)
					(end 439.434224 -238.13516)
				)
			)
		)
	)
	(zone
		(layers "B.Cu" "In6.Cu" "In11.Cu" "In13.Cu" "In15.Cu")
		(hatch none 0.5)
		(connect_pads
			(clearance 0)
		)
		(min_thickness 0.25)
		(keepout
			(tracks not_allowed)
			(vias allowed)
			(pads allowed)
			(copperpour not_allowed)
			(footprints allowed)
		)
		(placement
			(enabled no)
			(sheetname "")
		)
		(fill yes
			(thermal_gap 0.5)
			(thermal_bridge_width 0.5)
			(island_removal_mode 0)
		)
		(polygon
			(pts
				(arc
					(start 435.334156 -318.035178)
					(mid 434.666136 -318.035178)
					(end 435.334156 -318.035178)
				)
			)
		)
	)
	(zone
		(layers "B.Cu" "In6.Cu" "In11.Cu" "In13.Cu" "In15.Cu")
		(hatch none 0.5)
		(connect_pads
			(clearance 0)
		)
		(min_thickness 0.25)
		(keepout
			(tracks not_allowed)
			(vias allowed)
			(pads allowed)
			(copperpour not_allowed)
			(footprints allowed)
		)
		(placement
			(enabled no)
			(sheetname "")
		)
		(fill yes
			(thermal_gap 0.5)
			(thermal_bridge_width 0.5)
			(island_removal_mode 0)
		)
		(polygon
			(pts
				(arc
					(start 371.609874 -287.856168)
					(mid 370.979954 -287.856168)
					(end 371.609874 -287.856168)
				)
			)
		)
	)
	(zone
		(layers "B.Cu" "In6.Cu" "In11.Cu" "In13.Cu" "In15.Cu")
		(hatch none 0.5)
		(connect_pads
			(clearance 0)
		)
		(min_thickness 0.25)
		(keepout
			(tracks not_allowed)
			(vias allowed)
			(pads allowed)
			(copperpour not_allowed)
			(footprints allowed)
		)
		(placement
			(enabled no)
			(sheetname "")
		)
		(fill yes
			(thermal_gap 0.5)
			(thermal_bridge_width 0.5)
			(island_removal_mode 0)
		)
		(polygon
			(pts
				(arc
					(start 387.206236 -394.385292)
					(mid 386.576316 -394.385292)
					(end 387.206236 -394.385292)
				)
			)
		)
	)
	(zone
		(layers "B.Cu" "In6.Cu" "In11.Cu" "In13.Cu" "In15.Cu")
		(hatch none 0.5)
		(connect_pads
			(clearance 0)
		)
		(min_thickness 0.25)
		(keepout
			(tracks not_allowed)
			(vias allowed)
			(pads allowed)
			(copperpour not_allowed)
			(footprints allowed)
		)
		(placement
			(enabled no)
			(sheetname "")
		)
		(fill yes
			(thermal_gap 0.5)
			(thermal_bridge_width 0.5)
			(island_removal_mode 0)
		)
		(polygon
			(pts
				(arc
					(start 339.355938 -239.624108)
					(mid 338.726018 -239.624108)
					(end 339.355938 -239.624108)
				)
			)
		)
	)
	(zone
		(layers "B.Cu" "In6.Cu" "In11.Cu" "In13.Cu" "In15.Cu")
		(hatch none 0.5)
		(connect_pads
			(clearance 0)
		)
		(min_thickness 0.25)
		(keepout
			(tracks not_allowed)
			(vias allowed)
			(pads allowed)
			(copperpour not_allowed)
			(footprints allowed)
		)
		(placement
			(enabled no)
			(sheetname "")
		)
		(fill yes
			(thermal_gap 0.5)
			(thermal_bridge_width 0.5)
			(island_removal_mode 0)
		)
		(polygon
			(pts
				(arc
					(start 118.806214 -385.31038)
					(mid 118.176294 -385.31038)
					(end 118.806214 -385.31038)
				)
			)
		)
	)
	(zone
		(layers "B.Cu" "In6.Cu" "In11.Cu" "In13.Cu" "In15.Cu")
		(hatch none 0.5)
		(connect_pads
			(clearance 0)
		)
		(min_thickness 0.25)
		(keepout
			(tracks not_allowed)
			(vias allowed)
			(pads allowed)
			(copperpour not_allowed)
			(footprints allowed)
		)
		(placement
			(enabled no)
			(sheetname "")
		)
		(fill yes
			(thermal_gap 0.5)
			(thermal_bridge_width 0.5)
			(island_removal_mode 0)
		)
		(polygon
			(pts
				(arc
					(start 435.334156 -280.634948)
					(mid 434.666136 -280.634948)
					(end 435.334156 -280.634948)
				)
			)
		)
	)
	(zone
		(layers "B.Cu" "In6.Cu" "In11.Cu" "In13.Cu" "In15.Cu")
		(hatch none 0.5)
		(connect_pads
			(clearance 0)
		)
		(min_thickness 0.25)
		(keepout
			(tracks not_allowed)
			(vias allowed)
			(pads allowed)
			(copperpour not_allowed)
			(footprints allowed)
		)
		(placement
			(enabled no)
			(sheetname "")
		)
		(fill yes
			(thermal_gap 0.5)
			(thermal_bridge_width 0.5)
			(island_removal_mode 0)
		)
		(polygon
			(pts
				(arc
					(start 116.806218 -386.003292)
					(mid 116.176298 -386.003292)
					(end 116.806218 -386.003292)
				)
			)
		)
	)
	(zone
		(layers "B.Cu" "In6.Cu" "In11.Cu" "In13.Cu" "In15.Cu")
		(hatch none 0.5)
		(connect_pads
			(clearance 0)
		)
		(min_thickness 0.25)
		(keepout
			(tracks not_allowed)
			(vias allowed)
			(pads allowed)
			(copperpour not_allowed)
			(footprints allowed)
		)
		(placement
			(enabled no)
			(sheetname "")
		)
		(fill yes
			(thermal_gap 0.5)
			(thermal_bridge_width 0.5)
			(island_removal_mode 0)
		)
		(polygon
			(pts
				(arc
					(start 424.20159 -17.61236)
					(mid 423.53357 -17.61236)
					(end 424.20159 -17.61236)
				)
			)
		)
	)
	(zone
		(layers "B.Cu" "In6.Cu" "In11.Cu" "In13.Cu" "In15.Cu")
		(hatch none 0.5)
		(connect_pads
			(clearance 0)
		)
		(min_thickness 0.25)
		(keepout
			(tracks not_allowed)
			(vias allowed)
			(pads allowed)
			(copperpour not_allowed)
			(footprints allowed)
		)
		(placement
			(enabled no)
			(sheetname "")
		)
		(fill yes
			(thermal_gap 0.5)
			(thermal_bridge_width 0.5)
			(island_removal_mode 0)
		)
		(polygon
			(pts
				(arc
					(start 103.636064 -234.764326)
					(mid 103.006144 -234.764326)
					(end 103.636064 -234.764326)
				)
			)
		)
	)
	(zone
		(layers "B.Cu" "In6.Cu" "In11.Cu" "In13.Cu" "In15.Cu")
		(hatch none 0.5)
		(connect_pads
			(clearance 0)
		)
		(min_thickness 0.25)
		(keepout
			(tracks not_allowed)
			(vias allowed)
			(pads allowed)
			(copperpour not_allowed)
			(footprints allowed)
		)
		(placement
			(enabled no)
			(sheetname "")
		)
		(fill yes
			(thermal_gap 0.5)
			(thermal_bridge_width 0.5)
			(island_removal_mode 0)
		)
		(polygon
			(pts
				(arc
					(start 340.295992 -252.584204)
					(mid 339.666072 -252.584204)
					(end 340.295992 -252.584204)
				)
			)
		)
	)
	(zone
		(layers "B.Cu" "In6.Cu" "In11.Cu" "In13.Cu" "In15.Cu")
		(hatch none 0.5)
		(connect_pads
			(clearance 0)
		)
		(min_thickness 0.25)
		(keepout
			(tracks not_allowed)
			(vias allowed)
			(pads allowed)
			(copperpour not_allowed)
			(footprints allowed)
		)
		(placement
			(enabled no)
			(sheetname "")
		)
		(fill yes
			(thermal_gap 0.5)
			(thermal_bridge_width 0.5)
			(island_removal_mode 0)
		)
		(polygon
			(pts
				(arc
					(start 435.334156 -285.735014)
					(mid 434.666136 -285.735014)
					(end 435.334156 -285.735014)
				)
			)
		)
	)
	(zone
		(layers "B.Cu" "In6.Cu" "In11.Cu" "In13.Cu" "In15.Cu")
		(hatch none 0.5)
		(connect_pads
			(clearance 0)
		)
		(min_thickness 0.25)
		(keepout
			(tracks not_allowed)
			(vias allowed)
			(pads allowed)
			(copperpour not_allowed)
			(footprints allowed)
		)
		(placement
			(enabled no)
			(sheetname "")
		)
		(fill yes
			(thermal_gap 0.5)
			(thermal_bridge_width 0.5)
			(island_removal_mode 0)
		)
		(polygon
			(pts
				(arc
					(start 187.394088 -213.485222)
					(mid 186.726068 -213.485222)
					(end 187.394088 -213.485222)
				)
			)
		)
	)
	(zone
		(layers "B.Cu" "In6.Cu" "In11.Cu" "In13.Cu" "In15.Cu")
		(hatch none 0.5)
		(connect_pads
			(clearance 0)
		)
		(min_thickness 0.25)
		(keepout
			(tracks not_allowed)
			(vias allowed)
			(pads allowed)
			(copperpour not_allowed)
			(footprints allowed)
		)
		(placement
			(enabled no)
			(sheetname "")
		)
		(fill yes
			(thermal_gap 0.5)
			(thermal_bridge_width 0.5)
			(island_removal_mode 0)
		)
		(polygon
			(pts
				(arc
					(start 187.394088 -207.535272)
					(mid 186.726068 -207.535272)
					(end 187.394088 -207.535272)
				)
			)
		)
	)
	(zone
		(layers "B.Cu" "In6.Cu" "In11.Cu" "In13.Cu" "In15.Cu")
		(hatch none 0.5)
		(connect_pads
			(clearance 0)
		)
		(min_thickness 0.25)
		(keepout
			(tracks not_allowed)
			(vias allowed)
			(pads allowed)
			(copperpour not_allowed)
			(footprints allowed)
		)
		(placement
			(enabled no)
			(sheetname "")
		)
		(fill yes
			(thermal_gap 0.5)
			(thermal_bridge_width 0.5)
			(island_removal_mode 0)
		)
		(polygon
			(pts
				(arc
					(start 365.02975 -289.475926)
					(mid 364.39983 -289.475926)
					(end 365.02975 -289.475926)
				)
			)
		)
	)
	(zone
		(layers "B.Cu" "In6.Cu" "In11.Cu" "In13.Cu" "In15.Cu")
		(hatch none 0.5)
		(connect_pads
			(clearance 0)
		)
		(min_thickness 0.25)
		(keepout
			(tracks not_allowed)
			(vias allowed)
			(pads allowed)
			(copperpour not_allowed)
			(footprints allowed)
		)
		(placement
			(enabled no)
			(sheetname "")
		)
		(fill yes
			(thermal_gap 0.5)
			(thermal_bridge_width 0.5)
			(island_removal_mode 0)
		)
		(polygon
			(pts
				(arc
					(start 91.245944 -270.846296)
					(mid 90.616024 -270.846296)
					(end 91.245944 -270.846296)
				)
			)
		)
	)
	(zone
		(layers "B.Cu" "In6.Cu" "In11.Cu" "In13.Cu" "In15.Cu")
		(hatch none 0.5)
		(connect_pads
			(clearance 0)
		)
		(min_thickness 0.25)
		(keepout
			(tracks not_allowed)
			(vias allowed)
			(pads allowed)
			(copperpour not_allowed)
			(footprints allowed)
		)
		(placement
			(enabled no)
			(sheetname "")
		)
		(fill yes
			(thermal_gap 0.5)
			(thermal_bridge_width 0.5)
			(island_removal_mode 0)
		)
		(polygon
			(pts
				(arc
					(start 131.82981 -239.624362)
					(mid 131.19989 -239.624362)
					(end 131.82981 -239.624362)
				)
			)
		)
	)
	(zone
		(layers "B.Cu" "In6.Cu" "In11.Cu" "In13.Cu" "In15.Cu")
		(hatch none 0.5)
		(connect_pads
			(clearance 0)
		)
		(min_thickness 0.25)
		(keepout
			(tracks not_allowed)
			(vias allowed)
			(pads allowed)
			(copperpour not_allowed)
			(footprints allowed)
		)
		(placement
			(enabled no)
			(sheetname "")
		)
		(fill yes
			(thermal_gap 0.5)
			(thermal_bridge_width 0.5)
			(island_removal_mode 0)
		)
		(polygon
			(pts
				(arc
					(start 125.206252 -386.003292)
					(mid 124.576332 -386.003292)
					(end 125.206252 -386.003292)
				)
			)
		)
	)
	(zone
		(layers "B.Cu" "In6.Cu" "In11.Cu" "In13.Cu" "In15.Cu")
		(hatch none 0.5)
		(connect_pads
			(clearance 0)
		)
		(min_thickness 0.25)
		(keepout
			(tracks not_allowed)
			(vias allowed)
			(pads allowed)
			(copperpour not_allowed)
			(footprints allowed)
		)
		(placement
			(enabled no)
			(sheetname "")
		)
		(fill yes
			(thermal_gap 0.5)
			(thermal_bridge_width 0.5)
			(island_removal_mode 0)
		)
		(polygon
			(pts
				(arc
					(start 338.886038 -253.39421)
					(mid 338.256118 -253.39421)
					(end 338.886038 -253.39421)
				)
			)
		)
	)
	(zone
		(layers "B.Cu" "In6.Cu" "In11.Cu" "In13.Cu" "In15.Cu")
		(hatch none 0.5)
		(connect_pads
			(clearance 0)
		)
		(min_thickness 0.25)
		(keepout
			(tracks not_allowed)
			(vias allowed)
			(pads allowed)
			(copperpour not_allowed)
			(footprints allowed)
		)
		(placement
			(enabled no)
			(sheetname "")
		)
		(fill yes
			(thermal_gap 0.5)
			(thermal_bridge_width 0.5)
			(island_removal_mode 0)
		)
		(polygon
			(pts
				(arc
					(start 280.969974 -232.184956)
					(mid 280.301954 -232.184956)
					(end 280.969974 -232.184956)
				)
			)
		)
	)
	(zone
		(layers "B.Cu" "In6.Cu" "In11.Cu" "In13.Cu" "In15.Cu")
		(hatch none 0.5)
		(connect_pads
			(clearance 0)
		)
		(min_thickness 0.25)
		(keepout
			(tracks not_allowed)
			(vias allowed)
			(pads allowed)
			(copperpour not_allowed)
			(footprints allowed)
		)
		(placement
			(enabled no)
			(sheetname "")
		)
		(fill yes
			(thermal_gap 0.5)
			(thermal_bridge_width 0.5)
			(island_removal_mode 0)
		)
		(polygon
			(pts
				(arc
					(start 92.826078 -238.814356)
					(mid 92.196158 -238.814356)
					(end 92.826078 -238.814356)
				)
			)
		)
	)
	(zone
		(layers "B.Cu" "In6.Cu" "In11.Cu" "In13.Cu" "In15.Cu")
		(hatch none 0.5)
		(connect_pads
			(clearance 0)
		)
		(min_thickness 0.25)
		(keepout
			(tracks not_allowed)
			(vias allowed)
			(pads allowed)
			(copperpour not_allowed)
			(footprints allowed)
		)
		(placement
			(enabled no)
			(sheetname "")
		)
		(fill yes
			(thermal_gap 0.5)
			(thermal_bridge_width 0.5)
			(island_removal_mode 0)
		)
		(polygon
			(pts
				(arc
					(start 131.407916 -404.46452)
					(mid 130.739896 -404.46452)
					(end 131.407916 -404.46452)
				)
			)
		)
	)
	(zone
		(layers "B.Cu" "In6.Cu" "In11.Cu" "In13.Cu" "In15.Cu")
		(hatch none 0.5)
		(connect_pads
			(clearance 0)
		)
		(min_thickness 0.25)
		(keepout
			(tracks not_allowed)
			(vias allowed)
			(pads allowed)
			(copperpour not_allowed)
			(footprints allowed)
		)
		(placement
			(enabled no)
			(sheetname "")
		)
		(fill yes
			(thermal_gap 0.5)
			(thermal_bridge_width 0.5)
			(island_removal_mode 0)
		)
		(polygon
			(pts
				(arc
					(start 131.359656 -251.774452)
					(mid 130.729736 -251.774452)
					(end 131.359656 -251.774452)
				)
			)
		)
	)
	(zone
		(layers "B.Cu" "In6.Cu" "In11.Cu" "In13.Cu" "In15.Cu")
		(hatch none 0.5)
		(connect_pads
			(clearance 0)
		)
		(min_thickness 0.25)
		(keepout
			(tracks not_allowed)
			(vias allowed)
			(pads allowed)
			(copperpour not_allowed)
			(footprints allowed)
		)
		(placement
			(enabled no)
			(sheetname "")
		)
		(fill yes
			(thermal_gap 0.5)
			(thermal_bridge_width 0.5)
			(island_removal_mode 0)
		)
		(polygon
			(pts
				(arc
					(start 439.434224 -245.785132)
					(mid 438.766204 -245.785132)
					(end 439.434224 -245.785132)
				)
			)
		)
	)
	(zone
		(layers "B.Cu" "In6.Cu" "In11.Cu" "In13.Cu" "In15.Cu")
		(hatch none 0.5)
		(connect_pads
			(clearance 0)
		)
		(min_thickness 0.25)
		(keepout
			(tracks not_allowed)
			(vias allowed)
			(pads allowed)
			(copperpour not_allowed)
			(footprints allowed)
		)
		(placement
			(enabled no)
			(sheetname "")
		)
		(fill yes
			(thermal_gap 0.5)
			(thermal_bridge_width 0.5)
			(island_removal_mode 0)
		)
		(polygon
			(pts
				(arc
					(start 132.129784 -281.376374)
					(mid 131.499864 -281.376374)
					(end 132.129784 -281.376374)
				)
			)
		)
	)
	(zone
		(layers "B.Cu" "In6.Cu" "In11.Cu" "In13.Cu" "In15.Cu")
		(hatch none 0.5)
		(connect_pads
			(clearance 0)
		)
		(min_thickness 0.25)
		(keepout
			(tracks not_allowed)
			(vias allowed)
			(pads allowed)
			(copperpour not_allowed)
			(footprints allowed)
		)
		(placement
			(enabled no)
			(sheetname "")
		)
		(fill yes
			(thermal_gap 0.5)
			(thermal_bridge_width 0.5)
			(island_removal_mode 0)
		)
		(polygon
			(pts
				(arc
					(start 398.797272 -412.84652)
					(mid 398.129252 -412.84652)
					(end 398.797272 -412.84652)
				)
			)
		)
	)
	(zone
		(layers "B.Cu" "In6.Cu" "In11.Cu" "In13.Cu" "In15.Cu")
		(hatch none 0.5)
		(connect_pads
			(clearance 0)
		)
		(min_thickness 0.25)
		(keepout
			(tracks not_allowed)
			(vias allowed)
			(pads allowed)
			(copperpour not_allowed)
			(footprints allowed)
		)
		(placement
			(enabled no)
			(sheetname "")
		)
		(fill yes
			(thermal_gap 0.5)
			(thermal_bridge_width 0.5)
			(island_removal_mode 0)
		)
		(polygon
			(pts
				(arc
					(start 380.709678 -242.864132)
					(mid 380.079758 -242.864132)
					(end 380.709678 -242.864132)
				)
			)
		)
	)
	(zone
		(layers "B.Cu" "In6.Cu" "In11.Cu" "In13.Cu" "In15.Cu")
		(hatch none 0.5)
		(connect_pads
			(clearance 0)
		)
		(min_thickness 0.25)
		(keepout
			(tracks not_allowed)
			(vias allowed)
			(pads allowed)
			(copperpour not_allowed)
			(footprints allowed)
		)
		(placement
			(enabled no)
			(sheetname "")
		)
		(fill yes
			(thermal_gap 0.5)
			(thermal_bridge_width 0.5)
			(island_removal_mode 0)
		)
		(polygon
			(pts
				(arc
					(start 133.606286 -386.003292)
					(mid 132.976366 -386.003292)
					(end 133.606286 -386.003292)
				)
			)
		)
	)
	(zone
		(layers "B.Cu" "In6.Cu" "In11.Cu" "In13.Cu" "In15.Cu")
		(hatch none 0.5)
		(connect_pads
			(clearance 0)
		)
		(min_thickness 0.25)
		(keepout
			(tracks not_allowed)
			(vias allowed)
			(pads allowed)
			(copperpour not_allowed)
			(footprints allowed)
		)
		(placement
			(enabled no)
			(sheetname "")
		)
		(fill yes
			(thermal_gap 0.5)
			(thermal_bridge_width 0.5)
			(island_removal_mode 0)
		)
		(polygon
			(pts
				(arc
					(start 37.129974 -290.835334)
					(mid 36.461954 -290.835334)
					(end 37.129974 -290.835334)
				)
			)
		)
	)
	(zone
		(layers "B.Cu" "In6.Cu" "In11.Cu" "In13.Cu" "In15.Cu")
		(hatch none 0.5)
		(connect_pads
			(clearance 0)
		)
		(min_thickness 0.25)
		(keepout
			(tracks not_allowed)
			(vias allowed)
			(pads allowed)
			(copperpour not_allowed)
			(footprints allowed)
		)
		(placement
			(enabled no)
			(sheetname "")
		)
		(fill yes
			(thermal_gap 0.5)
			(thermal_bridge_width 0.5)
			(island_removal_mode 0)
		)
		(polygon
			(pts
				(arc
					(start 350.596454 -382.34493)
					(mid 349.928434 -382.34493)
					(end 350.596454 -382.34493)
				)
			)
		)
	)
	(zone
		(layers "B.Cu" "In6.Cu" "In11.Cu" "In13.Cu" "In15.Cu")
		(hatch none 0.5)
		(connect_pads
			(clearance 0)
		)
		(min_thickness 0.25)
		(keepout
			(tracks not_allowed)
			(vias allowed)
			(pads allowed)
			(copperpour not_allowed)
			(footprints allowed)
		)
		(placement
			(enabled no)
			(sheetname "")
		)
		(fill yes
			(thermal_gap 0.5)
			(thermal_bridge_width 0.5)
			(island_removal_mode 0)
		)
		(polygon
			(pts
				(arc
					(start 132.129784 -284.616398)
					(mid 131.499864 -284.616398)
					(end 132.129784 -284.616398)
				)
			)
		)
	)
	(zone
		(layers "B.Cu" "In6.Cu" "In11.Cu" "In13.Cu" "In15.Cu")
		(hatch none 0.5)
		(connect_pads
			(clearance 0)
		)
		(min_thickness 0.25)
		(keepout
			(tracks not_allowed)
			(vias allowed)
			(pads allowed)
			(copperpour not_allowed)
			(footprints allowed)
		)
		(placement
			(enabled no)
			(sheetname "")
		)
		(fill yes
			(thermal_gap 0.5)
			(thermal_bridge_width 0.5)
			(island_removal_mode 0)
		)
		(polygon
			(pts
				(arc
					(start 340.766146 -255.014222)
					(mid 340.136226 -255.014222)
					(end 340.766146 -255.014222)
				)
			)
		)
	)
	(zone
		(layers "B.Cu" "In6.Cu" "In11.Cu" "In13.Cu" "In15.Cu")
		(hatch none 0.5)
		(connect_pads
			(clearance 0)
		)
		(min_thickness 0.25)
		(keepout
			(tracks not_allowed)
			(vias allowed)
			(pads allowed)
			(copperpour not_allowed)
			(footprints allowed)
		)
		(placement
			(enabled no)
			(sheetname "")
		)
		(fill yes
			(thermal_gap 0.5)
			(thermal_bridge_width 0.5)
			(island_removal_mode 0)
		)
		(polygon
			(pts
				(arc
					(start 407.994358 -17.613122)
					(mid 407.326338 -17.613122)
					(end 407.994358 -17.613122)
				)
			)
		)
	)
	(zone
		(layers "B.Cu" "In6.Cu" "In11.Cu" "In13.Cu" "In15.Cu")
		(hatch none 0.5)
		(connect_pads
			(clearance 0)
		)
		(min_thickness 0.25)
		(keepout
			(tracks not_allowed)
			(vias allowed)
			(pads allowed)
			(copperpour not_allowed)
			(footprints allowed)
		)
		(placement
			(enabled no)
			(sheetname "")
		)
		(fill yes
			(thermal_gap 0.5)
			(thermal_bridge_width 0.5)
			(island_removal_mode 0)
		)
		(polygon
			(pts
				(arc
					(start 340.766146 -240.434114)
					(mid 340.136226 -240.434114)
					(end 340.766146 -240.434114)
				)
			)
		)
	)
	(zone
		(layers "B.Cu" "In6.Cu" "In11.Cu" "In13.Cu" "In15.Cu")
		(hatch none 0.5)
		(connect_pads
			(clearance 0)
		)
		(min_thickness 0.25)
		(keepout
			(tracks not_allowed)
			(vias allowed)
			(pads allowed)
			(copperpour not_allowed)
			(footprints allowed)
		)
		(placement
			(enabled no)
			(sheetname "")
		)
		(fill yes
			(thermal_gap 0.5)
			(thermal_bridge_width 0.5)
			(island_removal_mode 0)
		)
		(polygon
			(pts
				(arc
					(start 316.506098 -397.849344)
					(mid 315.876178 -397.849344)
					(end 316.506098 -397.849344)
				)
			)
		)
	)
	(zone
		(layers "B.Cu" "In6.Cu" "In11.Cu" "In13.Cu" "In15.Cu")
		(hatch none 0.5)
		(connect_pads
			(clearance 0)
		)
		(min_thickness 0.25)
		(keepout
			(tracks not_allowed)
			(vias allowed)
			(pads allowed)
			(copperpour not_allowed)
			(footprints allowed)
		)
		(placement
			(enabled no)
			(sheetname "")
		)
		(fill yes
			(thermal_gap 0.5)
			(thermal_bridge_width 0.5)
			(island_removal_mode 0)
		)
		(polygon
			(pts
				(arc
					(start 380.709678 -228.284278)
					(mid 380.079758 -228.284278)
					(end 380.709678 -228.284278)
				)
			)
		)
	)
	(zone
		(layers "B.Cu" "In6.Cu" "In11.Cu" "In13.Cu" "In15.Cu")
		(hatch none 0.5)
		(connect_pads
			(clearance 0)
		)
		(min_thickness 0.25)
		(keepout
			(tracks not_allowed)
			(vias allowed)
			(pads allowed)
			(copperpour not_allowed)
			(footprints allowed)
		)
		(placement
			(enabled no)
			(sheetname "")
		)
		(fill yes
			(thermal_gap 0.5)
			(thermal_bridge_width 0.5)
			(island_removal_mode 0)
		)
		(polygon
			(pts
				(arc
					(start 104.139492 -376.956828)
					(mid 103.471472 -376.956828)
					(end 104.139492 -376.956828)
				)
			)
		)
	)
	(zone
		(layers "B.Cu" "In6.Cu" "In11.Cu" "In13.Cu" "In15.Cu")
		(hatch none 0.5)
		(connect_pads
			(clearance 0)
		)
		(min_thickness 0.25)
		(keepout
			(tracks not_allowed)
			(vias allowed)
			(pads allowed)
			(copperpour not_allowed)
			(footprints allowed)
		)
		(placement
			(enabled no)
			(sheetname "")
		)
		(fill yes
			(thermal_gap 0.5)
			(thermal_bridge_width 0.5)
			(island_removal_mode 0)
		)
		(polygon
			(pts
				(arc
					(start 380.069852 -274.896072)
					(mid 379.439932 -274.896072)
					(end 380.069852 -274.896072)
				)
			)
		)
	)
	(zone
		(layers "B.Cu" "In6.Cu" "In11.Cu" "In13.Cu" "In15.Cu")
		(hatch none 0.5)
		(connect_pads
			(clearance 0)
		)
		(min_thickness 0.25)
		(keepout
			(tracks not_allowed)
			(vias allowed)
			(pads allowed)
			(copperpour not_allowed)
			(footprints allowed)
		)
		(placement
			(enabled no)
			(sheetname "")
		)
		(fill yes
			(thermal_gap 0.5)
			(thermal_bridge_width 0.5)
			(island_removal_mode 0)
		)
		(polygon
			(pts
				(arc
					(start 37.129974 -266.185396)
					(mid 36.461954 -266.185396)
					(end 37.129974 -266.185396)
				)
			)
		)
	)
	(zone
		(layers "B.Cu" "In6.Cu" "In11.Cu" "In13.Cu" "In15.Cu")
		(hatch none 0.5)
		(connect_pads
			(clearance 0)
		)
		(min_thickness 0.25)
		(keepout
			(tracks not_allowed)
			(vias allowed)
			(pads allowed)
			(copperpour not_allowed)
			(footprints allowed)
		)
		(placement
			(enabled no)
			(sheetname "")
		)
		(fill yes
			(thermal_gap 0.5)
			(thermal_bridge_width 0.5)
			(island_removal_mode 0)
		)
		(polygon
			(pts
				(arc
					(start 82.684112 -371.49913)
					(mid 82.016092 -371.49913)
					(end 82.684112 -371.49913)
				)
			)
		)
	)
	(zone
		(layers "B.Cu" "In6.Cu" "In11.Cu" "In13.Cu" "In15.Cu")
		(hatch none 0.5)
		(connect_pads
			(clearance 0)
		)
		(min_thickness 0.25)
		(keepout
			(tracks not_allowed)
			(vias allowed)
			(pads allowed)
			(copperpour not_allowed)
			(footprints allowed)
		)
		(placement
			(enabled no)
			(sheetname "")
		)
		(fill yes
			(thermal_gap 0.5)
			(thermal_bridge_width 0.5)
			(island_removal_mode 0)
		)
		(polygon
			(pts
				(arc
					(start 187.394088 -278.935434)
					(mid 186.726068 -278.935434)
					(end 187.394088 -278.935434)
				)
			)
		)
	)
	(zone
		(layers "B.Cu" "In6.Cu" "In11.Cu" "In13.Cu" "In15.Cu")
		(hatch none 0.5)
		(connect_pads
			(clearance 0)
		)
		(min_thickness 0.25)
		(keepout
			(tracks not_allowed)
			(vias allowed)
			(pads allowed)
			(copperpour not_allowed)
			(footprints allowed)
		)
		(placement
			(enabled no)
			(sheetname "")
		)
		(fill yes
			(thermal_gap 0.5)
			(thermal_bridge_width 0.5)
			(island_removal_mode 0)
		)
		(polygon
			(pts
				(arc
					(start 91.41587 -254.20447)
					(mid 90.78595 -254.20447)
					(end 91.41587 -254.20447)
				)
			)
		)
	)
	(zone
		(layers "B.Cu" "In6.Cu" "In11.Cu" "In13.Cu" "In15.Cu")
		(hatch none 0.5)
		(connect_pads
			(clearance 0)
		)
		(min_thickness 0.25)
		(keepout
			(tracks not_allowed)
			(vias allowed)
			(pads allowed)
			(copperpour not_allowed)
			(footprints allowed)
		)
		(placement
			(enabled no)
			(sheetname "")
		)
		(fill yes
			(thermal_gap 0.5)
			(thermal_bridge_width 0.5)
			(island_removal_mode 0)
		)
		(polygon
			(pts
				(arc
					(start 109.746034 -235.574332)
					(mid 109.116114 -235.574332)
					(end 109.746034 -235.574332)
				)
			)
		)
	)
	(zone
		(layers "B.Cu" "In6.Cu" "In11.Cu" "In13.Cu" "In15.Cu")
		(hatch none 0.5)
		(connect_pads
			(clearance 0)
		)
		(min_thickness 0.25)
		(keepout
			(tracks not_allowed)
			(vias allowed)
			(pads allowed)
			(copperpour not_allowed)
			(footprints allowed)
		)
		(placement
			(enabled no)
			(sheetname "")
		)
		(fill yes
			(thermal_gap 0.5)
			(thermal_bridge_width 0.5)
			(island_removal_mode 0)
		)
		(polygon
			(pts
				(arc
					(start 339.186012 -277.32609)
					(mid 338.556092 -277.32609)
					(end 339.186012 -277.32609)
				)
			)
		)
	)
	(zone
		(layers "B.Cu" "In6.Cu" "In11.Cu" "In13.Cu" "In15.Cu")
		(hatch none 0.5)
		(connect_pads
			(clearance 0)
		)
		(min_thickness 0.25)
		(keepout
			(tracks not_allowed)
			(vias allowed)
			(pads allowed)
			(copperpour not_allowed)
			(footprints allowed)
		)
		(placement
			(enabled no)
			(sheetname "")
		)
		(fill yes
			(thermal_gap 0.5)
			(thermal_bridge_width 0.5)
			(island_removal_mode 0)
		)
		(polygon
			(pts
				(arc
					(start 285.070042 -298.485052)
					(mid 284.402022 -298.485052)
					(end 285.070042 -298.485052)
				)
			)
		)
	)
	(zone
		(layers "B.Cu" "In6.Cu" "In11.Cu" "In13.Cu" "In15.Cu")
		(hatch none 0.5)
		(connect_pads
			(clearance 0)
		)
		(min_thickness 0.25)
		(keepout
			(tracks not_allowed)
			(vias allowed)
			(pads allowed)
			(copperpour not_allowed)
			(footprints allowed)
		)
		(placement
			(enabled no)
			(sheetname "")
		)
		(fill yes
			(thermal_gap 0.5)
			(thermal_bridge_width 0.5)
			(island_removal_mode 0)
		)
		(polygon
			(pts
				(arc
					(start 104.576118 -234.764326)
					(mid 103.946198 -234.764326)
					(end 104.576118 -234.764326)
				)
			)
		)
	)
	(zone
		(layers "B.Cu" "In6.Cu" "In11.Cu" "In13.Cu" "In15.Cu")
		(hatch none 0.5)
		(connect_pads
			(clearance 0)
		)
		(min_thickness 0.25)
		(keepout
			(tracks not_allowed)
			(vias allowed)
			(pads allowed)
			(copperpour not_allowed)
			(footprints allowed)
		)
		(placement
			(enabled no)
			(sheetname "")
		)
		(fill yes
			(thermal_gap 0.5)
			(thermal_bridge_width 0.5)
			(island_removal_mode 0)
		)
		(polygon
			(pts
				(arc
					(start 314.181236 -412.84652)
					(mid 313.513216 -412.84652)
					(end 314.181236 -412.84652)
				)
			)
		)
	)
	(zone
		(layers "B.Cu" "In6.Cu" "In11.Cu" "In13.Cu" "In15.Cu")
		(hatch none 0.5)
		(connect_pads
			(clearance 0)
		)
		(min_thickness 0.25)
		(keepout
			(tracks not_allowed)
			(vias allowed)
			(pads allowed)
			(copperpour not_allowed)
			(footprints allowed)
		)
		(placement
			(enabled no)
			(sheetname "")
		)
		(fill yes
			(thermal_gap 0.5)
			(thermal_bridge_width 0.5)
			(island_removal_mode 0)
		)
		(polygon
			(pts
				(arc
					(start 133.069838 -271.656302)
					(mid 132.439918 -271.656302)
					(end 133.069838 -271.656302)
				)
			)
		)
	)
	(zone
		(layers "B.Cu" "In6.Cu" "In11.Cu" "In13.Cu" "In15.Cu")
		(hatch none 0.5)
		(connect_pads
			(clearance 0)
		)
		(min_thickness 0.25)
		(keepout
			(tracks not_allowed)
			(vias allowed)
			(pads allowed)
			(copperpour not_allowed)
			(footprints allowed)
		)
		(placement
			(enabled no)
			(sheetname "")
		)
		(fill yes
			(thermal_gap 0.5)
			(thermal_bridge_width 0.5)
			(island_removal_mode 0)
		)
		(polygon
			(pts
				(arc
					(start 98.000312 -369.03533)
					(mid 97.332292 -369.03533)
					(end 98.000312 -369.03533)
				)
			)
		)
	)
	(zone
		(layers "B.Cu" "In6.Cu" "In11.Cu" "In13.Cu" "In15.Cu")
		(hatch none 0.5)
		(connect_pads
			(clearance 0)
		)
		(min_thickness 0.25)
		(keepout
			(tracks not_allowed)
			(vias allowed)
			(pads allowed)
			(copperpour not_allowed)
			(footprints allowed)
		)
		(placement
			(enabled no)
			(sheetname "")
		)
		(fill yes
			(thermal_gap 0.5)
			(thermal_bridge_width 0.5)
			(island_removal_mode 0)
		)
		(polygon
			(pts
				(arc
					(start 439.434224 -229.63505)
					(mid 438.766204 -229.63505)
					(end 439.434224 -229.63505)
				)
			)
		)
	)
	(zone
		(layers "B.Cu" "In6.Cu" "In11.Cu" "In13.Cu" "In15.Cu")
		(hatch none 0.5)
		(connect_pads
			(clearance 0)
		)
		(min_thickness 0.25)
		(keepout
			(tracks not_allowed)
			(vias allowed)
			(pads allowed)
			(copperpour not_allowed)
			(footprints allowed)
		)
		(placement
			(enabled no)
			(sheetname "")
		)
		(fill yes
			(thermal_gap 0.5)
			(thermal_bridge_width 0.5)
			(island_removal_mode 0)
		)
		(polygon
			(pts
				(arc
					(start 357.046022 -290.285932)
					(mid 356.416102 -290.285932)
					(end 357.046022 -290.285932)
				)
			)
		)
	)
	(zone
		(layers "B.Cu" "In6.Cu" "In11.Cu" "In13.Cu" "In15.Cu")
		(hatch none 0.5)
		(connect_pads
			(clearance 0)
		)
		(min_thickness 0.25)
		(keepout
			(tracks not_allowed)
			(vias allowed)
			(pads allowed)
			(copperpour not_allowed)
			(footprints allowed)
		)
		(placement
			(enabled no)
			(sheetname "")
		)
		(fill yes
			(thermal_gap 0.5)
			(thermal_bridge_width 0.5)
			(island_removal_mode 0)
		)
		(polygon
			(pts
				(arc
					(start 91.41587 -225.044508)
					(mid 90.78595 -225.044508)
					(end 91.41587 -225.044508)
				)
			)
		)
	)
	(zone
		(layers "B.Cu" "In6.Cu" "In11.Cu" "In13.Cu" "In15.Cu")
		(hatch none 0.5)
		(connect_pads
			(clearance 0)
		)
		(min_thickness 0.25)
		(keepout
			(tracks not_allowed)
			(vias allowed)
			(pads allowed)
			(copperpour not_allowed)
			(footprints allowed)
		)
		(placement
			(enabled no)
			(sheetname "")
		)
		(fill yes
			(thermal_gap 0.5)
			(thermal_bridge_width 0.5)
			(island_removal_mode 0)
		)
		(polygon
			(pts
				(arc
					(start 33.029906 -210.935316)
					(mid 32.361886 -210.935316)
					(end 33.029906 -210.935316)
				)
			)
		)
	)
	(zone
		(layers "B.Cu" "In6.Cu" "In11.Cu" "In13.Cu" "In15.Cu")
		(hatch none 0.5)
		(connect_pads
			(clearance 0)
		)
		(min_thickness 0.25)
		(keepout
			(tracks not_allowed)
			(vias allowed)
			(pads allowed)
			(copperpour not_allowed)
			(footprints allowed)
		)
		(placement
			(enabled no)
			(sheetname "")
		)
		(fill yes
			(thermal_gap 0.5)
			(thermal_bridge_width 0.5)
			(island_removal_mode 0)
		)
		(polygon
			(pts
				(arc
					(start 37.129974 -312.935366)
					(mid 36.461954 -312.935366)
					(end 37.129974 -312.935366)
				)
			)
		)
	)
	(zone
		(layers "B.Cu" "In6.Cu" "In11.Cu" "In13.Cu" "In15.Cu")
		(hatch none 0.5)
		(connect_pads
			(clearance 0)
		)
		(min_thickness 0.25)
		(keepout
			(tracks not_allowed)
			(vias allowed)
			(pads allowed)
			(copperpour not_allowed)
			(footprints allowed)
		)
		(placement
			(enabled no)
			(sheetname "")
		)
		(fill yes
			(thermal_gap 0.5)
			(thermal_bridge_width 0.5)
			(island_removal_mode 0)
		)
		(polygon
			(pts
				(arc
					(start 132.129784 -292.716204)
					(mid 131.499864 -292.716204)
					(end 132.129784 -292.716204)
				)
			)
		)
	)
	(zone
		(layers "B.Cu" "In6.Cu" "In11.Cu" "In13.Cu" "In15.Cu")
		(hatch none 0.5)
		(connect_pads
			(clearance 0)
		)
		(min_thickness 0.25)
		(keepout
			(tracks not_allowed)
			(vias allowed)
			(pads allowed)
			(copperpour not_allowed)
			(footprints allowed)
		)
		(placement
			(enabled no)
			(sheetname "")
		)
		(fill yes
			(thermal_gap 0.5)
			(thermal_bridge_width 0.5)
			(island_removal_mode 0)
		)
		(polygon
			(pts
				(arc
					(start 37.129974 -208.38541)
					(mid 36.461954 -208.38541)
					(end 37.129974 -208.38541)
				)
			)
		)
	)
	(zone
		(layers "B.Cu" "In6.Cu" "In11.Cu" "In13.Cu" "In15.Cu")
		(hatch none 0.5)
		(connect_pads
			(clearance 0)
		)
		(min_thickness 0.25)
		(keepout
			(tracks not_allowed)
			(vias allowed)
			(pads allowed)
			(copperpour not_allowed)
			(footprints allowed)
		)
		(placement
			(enabled no)
			(sheetname "")
		)
		(fill yes
			(thermal_gap 0.5)
			(thermal_bridge_width 0.5)
			(island_removal_mode 0)
		)
		(polygon
			(pts
				(arc
					(start 414.533842 -397.156432)
					(mid 413.903922 -397.156432)
					(end 414.533842 -397.156432)
				)
			)
		)
	)
	(zone
		(layers "B.Cu" "In6.Cu" "In11.Cu" "In13.Cu" "In15.Cu")
		(hatch none 0.5)
		(connect_pads
			(clearance 0)
		)
		(min_thickness 0.25)
		(keepout
			(tracks not_allowed)
			(vias allowed)
			(pads allowed)
			(copperpour not_allowed)
			(footprints allowed)
		)
		(placement
			(enabled no)
			(sheetname "")
		)
		(fill yes
			(thermal_gap 0.5)
			(thermal_bridge_width 0.5)
			(island_removal_mode 0)
		)
		(polygon
			(pts
				(arc
					(start 191.494156 -220.28531)
					(mid 190.826136 -220.28531)
					(end 191.494156 -220.28531)
				)
			)
		)
	)
	(zone
		(layers "B.Cu" "In11.Cu" "In13.Cu" "In15.Cu")
		(hatch none 0.5)
		(connect_pads
			(clearance 0)
		)
		(min_thickness 0.25)
		(keepout
			(tracks not_allowed)
			(vias allowed)
			(pads allowed)
			(copperpour not_allowed)
			(footprints allowed)
		)
		(placement
			(enabled no)
			(sheetname "")
		)
		(fill yes
			(thermal_gap 0.5)
			(thermal_bridge_width 0.5)
			(island_removal_mode 0)
		)
		(polygon
			(pts
				(arc
					(start 390.579864 -253.39421)
					(mid 389.949944 -253.39421)
					(end 390.579864 -253.39421)
				)
			)
		)
	)
	(zone
		(layers "B.Cu" "In11.Cu" "In13.Cu" "In15.Cu")
		(hatch none 0.5)
		(connect_pads
			(clearance 0)
		)
		(min_thickness 0.25)
		(keepout
			(tracks not_allowed)
			(vias allowed)
			(pads allowed)
			(copperpour not_allowed)
			(footprints allowed)
		)
		(placement
			(enabled no)
			(sheetname "")
		)
		(fill yes
			(thermal_gap 0.5)
			(thermal_bridge_width 0.5)
			(island_removal_mode 0)
		)
		(polygon
			(pts
				(arc
					(start 141.229842 -231.524302)
					(mid 140.599922 -231.524302)
					(end 141.229842 -231.524302)
				)
			)
		)
	)
	(zone
		(layers "B.Cu" "In11.Cu" "In13.Cu" "In15.Cu")
		(hatch none 0.5)
		(connect_pads
			(clearance 0)
		)
		(min_thickness 0.25)
		(keepout
			(tracks not_allowed)
			(vias allowed)
			(pads allowed)
			(copperpour not_allowed)
			(footprints allowed)
		)
		(placement
			(enabled no)
			(sheetname "")
		)
		(fill yes
			(thermal_gap 0.5)
			(thermal_bridge_width 0.5)
			(island_removal_mode 0)
		)
		(polygon
			(pts
				(arc
					(start 194.938142 -265.335258)
					(mid 194.270122 -265.335258)
					(end 194.938142 -265.335258)
				)
			)
		)
	)
	(zone
		(layers "B.Cu" "In11.Cu" "In13.Cu" "In15.Cu")
		(hatch none 0.5)
		(connect_pads
			(clearance 0)
		)
		(min_thickness 0.25)
		(keepout
			(tracks not_allowed)
			(vias allowed)
			(pads allowed)
			(copperpour not_allowed)
			(footprints allowed)
		)
		(placement
			(enabled no)
			(sheetname "")
		)
		(fill yes
			(thermal_gap 0.5)
			(thermal_bridge_width 0.5)
			(island_removal_mode 0)
		)
		(polygon
			(pts
				(arc
					(start 104.576118 -241.244374)
					(mid 103.946198 -241.244374)
					(end 104.576118 -241.244374)
				)
			)
		)
	)
	(zone
		(layers "B.Cu" "In11.Cu" "In13.Cu" "In15.Cu")
		(hatch none 0.5)
		(connect_pads
			(clearance 0)
		)
		(min_thickness 0.25)
		(keepout
			(tracks not_allowed)
			(vias allowed)
			(pads allowed)
			(copperpour not_allowed)
			(footprints allowed)
		)
		(placement
			(enabled no)
			(sheetname "")
		)
		(fill yes
			(thermal_gap 0.5)
			(thermal_bridge_width 0.5)
			(island_removal_mode 0)
		)
		(polygon
			(pts
				(arc
					(start 384.1369 -427.089824)
					(mid 383.362708 -427.089824)
					(end 384.1369 -427.089824)
				)
			)
		)
	)
	(zone
		(layers "B.Cu" "In11.Cu" "In13.Cu" "In15.Cu")
		(hatch none 0.5)
		(connect_pads
			(clearance 0)
		)
		(min_thickness 0.25)
		(keepout
			(tracks not_allowed)
			(vias allowed)
			(pads allowed)
			(copperpour not_allowed)
			(footprints allowed)
		)
		(placement
			(enabled no)
			(sheetname "")
		)
		(fill yes
			(thermal_gap 0.5)
			(thermal_bridge_width 0.5)
			(island_removal_mode 0)
		)
		(polygon
			(pts
				(arc
					(start 67.03695 -427.289976)
					(mid 66.262758 -427.289976)
					(end 67.03695 -427.289976)
				)
			)
		)
	)
	(zone
		(layers "B.Cu" "In11.Cu" "In13.Cu" "In15.Cu")
		(hatch none 0.5)
		(connect_pads
			(clearance 0)
		)
		(min_thickness 0.25)
		(keepout
			(tracks not_allowed)
			(vias allowed)
			(pads allowed)
			(copperpour not_allowed)
			(footprints allowed)
		)
		(placement
			(enabled no)
			(sheetname "")
		)
		(fill yes
			(thermal_gap 0.5)
			(thermal_bridge_width 0.5)
			(island_removal_mode 0)
		)
		(polygon
			(pts
				(arc
					(start 390.579864 -248.534174)
					(mid 389.949944 -248.534174)
					(end 390.579864 -248.534174)
				)
			)
		)
	)
	(zone
		(layers "B.Cu" "In11.Cu" "In13.Cu" "In15.Cu")
		(hatch none 0.5)
		(connect_pads
			(clearance 0)
		)
		(min_thickness 0.25)
		(keepout
			(tracks not_allowed)
			(vias allowed)
			(pads allowed)
			(copperpour not_allowed)
			(footprints allowed)
		)
		(placement
			(enabled no)
			(sheetname "")
		)
		(fill yes
			(thermal_gap 0.5)
			(thermal_bridge_width 0.5)
			(island_removal_mode 0)
		)
		(polygon
			(pts
				(arc
					(start 349.995998 -286.236156)
					(mid 349.366078 -286.236156)
					(end 349.995998 -286.236156)
				)
			)
		)
	)
	(zone
		(layers "B.Cu" "In11.Cu" "In13.Cu" "In15.Cu")
		(hatch none 0.5)
		(connect_pads
			(clearance 0)
		)
		(min_thickness 0.25)
		(keepout
			(tracks not_allowed)
			(vias allowed)
			(pads allowed)
			(copperpour not_allowed)
			(footprints allowed)
		)
		(placement
			(enabled no)
			(sheetname "")
		)
		(fill yes
			(thermal_gap 0.5)
			(thermal_bridge_width 0.5)
			(island_removal_mode 0)
		)
		(polygon
			(pts
				(arc
					(start 442.87821 -268.735048)
					(mid 442.21019 -268.735048)
					(end 442.87821 -268.735048)
				)
			)
		)
	)
	(zone
		(layers "B.Cu" "In11.Cu" "In13.Cu" "In15.Cu")
		(hatch none 0.5)
		(connect_pads
			(clearance 0)
		)
		(min_thickness 0.25)
		(keepout
			(tracks not_allowed)
			(vias allowed)
			(pads allowed)
			(copperpour not_allowed)
			(footprints allowed)
		)
		(placement
			(enabled no)
			(sheetname "")
		)
		(fill yes
			(thermal_gap 0.5)
			(thermal_bridge_width 0.5)
			(island_removal_mode 0)
		)
		(polygon
			(pts
				(arc
					(start 410.134054 -394.385292)
					(mid 409.504134 -394.385292)
					(end 410.134054 -394.385292)
				)
			)
		)
	)
	(zone
		(layers "B.Cu" "In11.Cu" "In13.Cu" "In15.Cu")
		(hatch none 0.5)
		(connect_pads
			(clearance 0)
		)
		(min_thickness 0.25)
		(keepout
			(tracks not_allowed)
			(vias allowed)
			(pads allowed)
			(copperpour not_allowed)
			(footprints allowed)
		)
		(placement
			(enabled no)
			(sheetname "")
		)
		(fill yes
			(thermal_gap 0.5)
			(thermal_bridge_width 0.5)
			(island_removal_mode 0)
		)
		(polygon
			(pts
				(arc
					(start 277.526242 -309.535068)
					(mid 276.858222 -309.535068)
					(end 277.526242 -309.535068)
				)
			)
		)
	)
	(zone
		(layers "B.Cu" "In11.Cu" "In13.Cu" "In15.Cu")
		(hatch none 0.5)
		(connect_pads
			(clearance 0)
		)
		(min_thickness 0.25)
		(keepout
			(tracks not_allowed)
			(vias allowed)
			(pads allowed)
			(copperpour not_allowed)
			(footprints allowed)
		)
		(placement
			(enabled no)
			(sheetname "")
		)
		(fill yes
			(thermal_gap 0.5)
			(thermal_bridge_width 0.5)
			(island_removal_mode 0)
		)
		(polygon
			(pts
				(arc
					(start 321.472306 -377.41733)
					(mid 320.804286 -377.41733)
					(end 321.472306 -377.41733)
				)
			)
		)
	)
	(zone
		(layers "B.Cu" "In11.Cu" "In13.Cu" "In15.Cu")
		(hatch none 0.5)
		(connect_pads
			(clearance 0)
		)
		(min_thickness 0.25)
		(keepout
			(tracks not_allowed)
			(vias allowed)
			(pads allowed)
			(copperpour not_allowed)
			(footprints allowed)
		)
		(placement
			(enabled no)
			(sheetname "")
		)
		(fill yes
			(thermal_gap 0.5)
			(thermal_bridge_width 0.5)
			(island_removal_mode 0)
		)
		(polygon
			(pts
				(arc
					(start 277.526242 -317.18504)
					(mid 276.858222 -317.18504)
					(end 277.526242 -317.18504)
				)
			)
		)
	)
	(zone
		(layers "B.Cu" "In11.Cu" "In13.Cu" "In15.Cu")
		(hatch none 0.5)
		(connect_pads
			(clearance 0)
		)
		(min_thickness 0.25)
		(keepout
			(tracks not_allowed)
			(vias allowed)
			(pads allowed)
			(copperpour not_allowed)
			(footprints allowed)
		)
		(placement
			(enabled no)
			(sheetname "")
		)
		(fill yes
			(thermal_gap 0.5)
			(thermal_bridge_width 0.5)
			(island_removal_mode 0)
		)
		(polygon
			(pts
				(arc
					(start 132.406136 -389.467344)
					(mid 131.776216 -389.467344)
					(end 132.406136 -389.467344)
				)
			)
		)
	)
	(zone
		(layers "B.Cu" "In11.Cu" "In13.Cu" "In15.Cu")
		(hatch none 0.5)
		(connect_pads
			(clearance 0)
		)
		(min_thickness 0.25)
		(keepout
			(tracks not_allowed)
			(vias allowed)
			(pads allowed)
			(copperpour not_allowed)
			(footprints allowed)
		)
		(placement
			(enabled no)
			(sheetname "")
		)
		(fill yes
			(thermal_gap 0.5)
			(thermal_bridge_width 0.5)
			(island_removal_mode 0)
		)
		(polygon
			(pts
				(arc
					(start 329.016106 -225.044254)
					(mid 328.386186 -225.044254)
					(end 329.016106 -225.044254)
				)
			)
		)
	)
	(zone
		(layers "B.Cu" "In11.Cu" "In13.Cu" "In15.Cu")
		(hatch none 0.5)
		(connect_pads
			(clearance 0)
		)
		(min_thickness 0.25)
		(keepout
			(tracks not_allowed)
			(vias allowed)
			(pads allowed)
			(copperpour not_allowed)
			(footprints allowed)
		)
		(placement
			(enabled no)
			(sheetname "")
		)
		(fill yes
			(thermal_gap 0.5)
			(thermal_bridge_width 0.5)
			(island_removal_mode 0)
		)
		(polygon
			(pts
				(arc
					(start 199.03821 -262.785352)
					(mid 198.37019 -262.785352)
					(end 199.03821 -262.785352)
				)
			)
		)
	)
	(zone
		(layers "B.Cu" "In11.Cu" "In13.Cu" "In15.Cu")
		(hatch none 0.5)
		(connect_pads
			(clearance 0)
		)
		(min_thickness 0.25)
		(keepout
			(tracks not_allowed)
			(vias allowed)
			(pads allowed)
			(copperpour not_allowed)
			(footprints allowed)
		)
		(placement
			(enabled no)
			(sheetname "")
		)
		(fill yes
			(thermal_gap 0.5)
			(thermal_bridge_width 0.5)
			(island_removal_mode 0)
		)
		(polygon
			(pts
				(arc
					(start 182.375556 -44.980098)
					(mid 181.707536 -44.980098)
					(end 182.375556 -44.980098)
				)
			)
		)
	)
	(zone
		(layers "B.Cu" "In11.Cu" "In13.Cu" "In15.Cu")
		(hatch none 0.5)
		(connect_pads
			(clearance 0)
		)
		(min_thickness 0.25)
		(keepout
			(tracks not_allowed)
			(vias allowed)
			(pads allowed)
			(copperpour not_allowed)
			(footprints allowed)
		)
		(placement
			(enabled no)
			(sheetname "")
		)
		(fill yes
			(thermal_gap 0.5)
			(thermal_bridge_width 0.5)
			(island_removal_mode 0)
		)
		(polygon
			(pts
				(arc
					(start 25.486106 -232.18521)
					(mid 24.818086 -232.18521)
					(end 25.486106 -232.18521)
				)
			)
		)
	)
	(zone
		(layers "B.Cu" "In11.Cu" "In13.Cu" "In15.Cu")
		(hatch none 0.5)
		(connect_pads
			(clearance 0)
		)
		(min_thickness 0.25)
		(keepout
			(tracks not_allowed)
			(vias allowed)
			(pads allowed)
			(copperpour not_allowed)
			(footprints allowed)
		)
		(placement
			(enabled no)
			(sheetname "")
		)
		(fill yes
			(thermal_gap 0.5)
			(thermal_bridge_width 0.5)
			(island_removal_mode 0)
		)
		(polygon
			(pts
				(arc
					(start 442.87821 -276.38502)
					(mid 442.21019 -276.38502)
					(end 442.87821 -276.38502)
				)
			)
		)
	)
	(zone
		(layers "B.Cu" "In11.Cu" "In13.Cu" "In15.Cu")
		(hatch none 0.5)
		(connect_pads
			(clearance 0)
		)
		(min_thickness 0.25)
		(keepout
			(tracks not_allowed)
			(vias allowed)
			(pads allowed)
			(copperpour not_allowed)
			(footprints allowed)
		)
		(placement
			(enabled no)
			(sheetname "")
		)
		(fill yes
			(thermal_gap 0.5)
			(thermal_bridge_width 0.5)
			(island_removal_mode 0)
		)
		(polygon
			(pts
				(arc
					(start 127.606298 -389.467344)
					(mid 126.976378 -389.467344)
					(end 127.606298 -389.467344)
				)
			)
		)
	)
	(zone
		(layers "B.Cu" "In11.Cu" "In13.Cu" "In15.Cu")
		(hatch none 0.5)
		(connect_pads
			(clearance 0)
		)
		(min_thickness 0.25)
		(keepout
			(tracks not_allowed)
			(vias allowed)
			(pads allowed)
			(copperpour not_allowed)
			(footprints allowed)
		)
		(placement
			(enabled no)
			(sheetname "")
		)
		(fill yes
			(thermal_gap 0.5)
			(thermal_bridge_width 0.5)
			(island_removal_mode 0)
		)
		(polygon
			(pts
				(arc
					(start 330.726034 -282.186126)
					(mid 330.096114 -282.186126)
					(end 330.726034 -282.186126)
				)
			)
		)
	)
	(zone
		(layers "B.Cu" "In11.Cu" "In13.Cu" "In15.Cu")
		(hatch none 0.5)
		(connect_pads
			(clearance 0)
		)
		(min_thickness 0.25)
		(keepout
			(tracks not_allowed)
			(vias allowed)
			(pads allowed)
			(copperpour not_allowed)
			(footprints allowed)
		)
		(placement
			(enabled no)
			(sheetname "")
		)
		(fill yes
			(thermal_gap 0.5)
			(thermal_bridge_width 0.5)
			(island_removal_mode 0)
		)
		(polygon
			(pts
				(arc
					(start 141.229842 -233.144314)
					(mid 140.599922 -233.144314)
					(end 141.229842 -233.144314)
				)
			)
		)
	)
	(zone
		(layers "B.Cu" "In11.Cu" "In13.Cu" "In15.Cu")
		(hatch none 0.5)
		(connect_pads
			(clearance 0)
		)
		(min_thickness 0.25)
		(keepout
			(tracks not_allowed)
			(vias allowed)
			(pads allowed)
			(copperpour not_allowed)
			(footprints allowed)
		)
		(placement
			(enabled no)
			(sheetname "")
		)
		(fill yes
			(thermal_gap 0.5)
			(thermal_bridge_width 0.5)
			(island_removal_mode 0)
		)
		(polygon
			(pts
				(arc
					(start 331.195934 -263.555988)
					(mid 330.566014 -263.555988)
					(end 331.195934 -263.555988)
				)
			)
		)
	)
	(zone
		(layers "B.Cu" "In11.Cu" "In13.Cu" "In15.Cu")
		(hatch none 0.5)
		(connect_pads
			(clearance 0)
		)
		(min_thickness 0.25)
		(keepout
			(tracks not_allowed)
			(vias allowed)
			(pads allowed)
			(copperpour not_allowed)
			(footprints allowed)
		)
		(placement
			(enabled no)
			(sheetname "")
		)
		(fill yes
			(thermal_gap 0.5)
			(thermal_bridge_width 0.5)
			(island_removal_mode 0)
		)
		(polygon
			(pts
				(arc
					(start 375.20626 -397.849344)
					(mid 374.57634 -397.849344)
					(end 375.20626 -397.849344)
				)
			)
		)
	)
	(zone
		(layers "B.Cu" "In11.Cu" "In13.Cu" "In15.Cu")
		(hatch none 0.5)
		(connect_pads
			(clearance 0)
		)
		(min_thickness 0.25)
		(keepout
			(tracks not_allowed)
			(vias allowed)
			(pads allowed)
			(copperpour not_allowed)
			(footprints allowed)
		)
		(placement
			(enabled no)
			(sheetname "")
		)
		(fill yes
			(thermal_gap 0.5)
			(thermal_bridge_width 0.5)
			(island_removal_mode 0)
		)
		(polygon
			(pts
				(arc
					(start 141.229842 -242.864386)
					(mid 140.599922 -242.864386)
					(end 141.229842 -242.864386)
				)
			)
		)
	)
	(zone
		(layers "B.Cu" "In11.Cu" "In13.Cu" "In15.Cu")
		(hatch none 0.5)
		(connect_pads
			(clearance 0)
		)
		(min_thickness 0.25)
		(keepout
			(tracks not_allowed)
			(vias allowed)
			(pads allowed)
			(copperpour not_allowed)
			(footprints allowed)
		)
		(placement
			(enabled no)
			(sheetname "")
		)
		(fill yes
			(thermal_gap 0.5)
			(thermal_bridge_width 0.5)
			(island_removal_mode 0)
		)
		(polygon
			(pts
				(arc
					(start 163.333938 -385.31038)
					(mid 162.704018 -385.31038)
					(end 163.333938 -385.31038)
				)
			)
		)
	)
	(zone
		(layers "B.Cu" "In11.Cu" "In13.Cu" "In15.Cu")
		(hatch none 0.5)
		(connect_pads
			(clearance 0)
		)
		(min_thickness 0.25)
		(keepout
			(tracks not_allowed)
			(vias allowed)
			(pads allowed)
			(copperpour not_allowed)
			(footprints allowed)
		)
		(placement
			(enabled no)
			(sheetname "")
		)
		(fill yes
			(thermal_gap 0.5)
			(thermal_bridge_width 0.5)
			(island_removal_mode 0)
		)
		(polygon
			(pts
				(arc
					(start 83.255866 -279.756362)
					(mid 82.625946 -279.756362)
					(end 83.255866 -279.756362)
				)
			)
		)
	)
	(zone
		(layers "B.Cu" "In11.Cu" "In13.Cu" "In15.Cu")
		(hatch none 0.5)
		(connect_pads
			(clearance 0)
		)
		(min_thickness 0.25)
		(keepout
			(tracks not_allowed)
			(vias allowed)
			(pads allowed)
			(copperpour not_allowed)
			(footprints allowed)
		)
		(placement
			(enabled no)
			(sheetname "")
		)
		(fill yes
			(thermal_gap 0.5)
			(thermal_bridge_width 0.5)
			(island_removal_mode 0)
		)
		(polygon
			(pts
				(arc
					(start 319.0367 -427.289976)
					(mid 318.262508 -427.289976)
					(end 319.0367 -427.289976)
				)
			)
		)
	)
	(zone
		(layers "B.Cu" "In11.Cu" "In13.Cu" "In15.Cu")
		(hatch none 0.5)
		(connect_pads
			(clearance 0)
		)
		(min_thickness 0.25)
		(keepout
			(tracks not_allowed)
			(vias allowed)
			(pads allowed)
			(copperpour not_allowed)
			(footprints allowed)
		)
		(placement
			(enabled no)
			(sheetname "")
		)
		(fill yes
			(thermal_gap 0.5)
			(thermal_bridge_width 0.5)
			(island_removal_mode 0)
		)
		(polygon
			(pts
				(arc
					(start 101.11613 -284.616398)
					(mid 100.48621 -284.616398)
					(end 101.11613 -284.616398)
				)
			)
		)
	)
	(zone
		(layers "B.Cu" "In11.Cu" "In13.Cu" "In15.Cu")
		(hatch none 0.5)
		(connect_pads
			(clearance 0)
		)
		(min_thickness 0.25)
		(keepout
			(tracks not_allowed)
			(vias allowed)
			(pads allowed)
			(copperpour not_allowed)
			(footprints allowed)
		)
		(placement
			(enabled no)
			(sheetname "")
		)
		(fill yes
			(thermal_gap 0.5)
			(thermal_bridge_width 0.5)
			(island_removal_mode 0)
		)
		(polygon
			(pts
				(arc
					(start 142.639796 -255.014476)
					(mid 142.009876 -255.014476)
					(end 142.639796 -255.014476)
				)
			)
		)
	)
	(zone
		(layers "B.Cu" "In11.Cu" "In13.Cu" "In15.Cu")
		(hatch none 0.5)
		(connect_pads
			(clearance 0)
		)
		(min_thickness 0.25)
		(keepout
			(tracks not_allowed)
			(vias allowed)
			(pads allowed)
			(copperpour not_allowed)
			(footprints allowed)
		)
		(placement
			(enabled no)
			(sheetname "")
		)
		(fill yes
			(thermal_gap 0.5)
			(thermal_bridge_width 0.5)
			(island_removal_mode 0)
		)
		(polygon
			(pts
				(arc
					(start 151.333962 -385.31038)
					(mid 150.704042 -385.31038)
					(end 151.333962 -385.31038)
				)
			)
		)
	)
	(zone
		(layers "B.Cu" "In11.Cu" "In13.Cu" "In15.Cu")
		(hatch none 0.5)
		(connect_pads
			(clearance 0)
		)
		(min_thickness 0.25)
		(keepout
			(tracks not_allowed)
			(vias allowed)
			(pads allowed)
			(copperpour not_allowed)
			(footprints allowed)
		)
		(placement
			(enabled no)
			(sheetname "")
		)
		(fill yes
			(thermal_gap 0.5)
			(thermal_bridge_width 0.5)
			(island_removal_mode 0)
		)
		(polygon
			(pts
				(arc
					(start 199.03821 -290.835334)
					(mid 198.37019 -290.835334)
					(end 199.03821 -290.835334)
				)
			)
		)
	)
	(zone
		(layers "B.Cu" "In11.Cu" "In13.Cu" "In15.Cu")
		(hatch none 0.5)
		(connect_pads
			(clearance 0)
		)
		(min_thickness 0.25)
		(keepout
			(tracks not_allowed)
			(vias allowed)
			(pads allowed)
			(copperpour not_allowed)
			(footprints allowed)
		)
		(placement
			(enabled no)
			(sheetname "")
		)
		(fill yes
			(thermal_gap 0.5)
			(thermal_bridge_width 0.5)
			(island_removal_mode 0)
		)
		(polygon
			(pts
				(arc
					(start 389.63981 -245.29415)
					(mid 389.00989 -245.29415)
					(end 389.63981 -245.29415)
				)
			)
		)
	)
	(zone
		(layers "B.Cu" "In11.Cu" "In13.Cu" "In15.Cu")
		(hatch none 0.5)
		(connect_pads
			(clearance 0)
		)
		(min_thickness 0.25)
		(keepout
			(tracks not_allowed)
			(vias allowed)
			(pads allowed)
			(copperpour not_allowed)
			(footprints allowed)
		)
		(placement
			(enabled no)
			(sheetname "")
		)
		(fill yes
			(thermal_gap 0.5)
			(thermal_bridge_width 0.5)
			(island_removal_mode 0)
		)
		(polygon
			(pts
				(arc
					(start 50.906172 -389.467344)
					(mid 50.276252 -389.467344)
					(end 50.906172 -389.467344)
				)
			)
		)
	)
	(zone
		(layers "B.Cu" "In11.Cu" "In13.Cu" "In15.Cu")
		(hatch none 0.5)
		(connect_pads
			(clearance 0)
		)
		(min_thickness 0.25)
		(keepout
			(tracks not_allowed)
			(vias allowed)
			(pads allowed)
			(copperpour not_allowed)
			(footprints allowed)
		)
		(placement
			(enabled no)
			(sheetname "")
		)
		(fill yes
			(thermal_gap 0.5)
			(thermal_bridge_width 0.5)
			(island_removal_mode 0)
		)
		(polygon
			(pts
				(arc
					(start 350.233742 -397.849344)
					(mid 349.603822 -397.849344)
					(end 350.233742 -397.849344)
				)
			)
		)
	)
	(zone
		(layers "B.Cu" "In11.Cu" "In13.Cu" "In15.Cu")
		(hatch none 0.5)
		(connect_pads
			(clearance 0)
		)
		(min_thickness 0.25)
		(keepout
			(tracks not_allowed)
			(vias allowed)
			(pads allowed)
			(copperpour not_allowed)
			(footprints allowed)
		)
		(placement
			(enabled no)
			(sheetname "")
		)
		(fill yes
			(thermal_gap 0.5)
			(thermal_bridge_width 0.5)
			(island_removal_mode 0)
		)
		(polygon
			(pts
				(arc
					(start 29.586174 -276.385274)
					(mid 28.918154 -276.385274)
					(end 29.586174 -276.385274)
				)
			)
		)
	)
	(zone
		(layers "B.Cu" "In11.Cu" "In13.Cu" "In15.Cu")
		(hatch none 0.5)
		(connect_pads
			(clearance 0)
		)
		(min_thickness 0.25)
		(keepout
			(tracks not_allowed)
			(vias allowed)
			(pads allowed)
			(copperpour not_allowed)
			(footprints allowed)
		)
		(placement
			(enabled no)
			(sheetname "")
		)
		(fill yes
			(thermal_gap 0.5)
			(thermal_bridge_width 0.5)
			(island_removal_mode 0)
		)
		(polygon
			(pts
				(arc
					(start 325.036688 -427.089824)
					(mid 324.262496 -427.089824)
					(end 325.036688 -427.089824)
				)
			)
		)
	)
	(zone
		(layers "B.Cu" "In11.Cu" "In13.Cu" "In15.Cu")
		(hatch none 0.5)
		(connect_pads
			(clearance 0)
		)
		(min_thickness 0.25)
		(keepout
			(tracks not_allowed)
			(vias allowed)
			(pads allowed)
			(copperpour not_allowed)
			(footprints allowed)
		)
		(placement
			(enabled no)
			(sheetname "")
		)
		(fill yes
			(thermal_gap 0.5)
			(thermal_bridge_width 0.5)
			(island_removal_mode 0)
		)
		(polygon
			(pts
				(arc
					(start 125.206252 -389.467344)
					(mid 124.576332 -389.467344)
					(end 125.206252 -389.467344)
				)
			)
		)
	)
	(zone
		(layers "B.Cu" "In11.Cu" "In13.Cu" "In15.Cu")
		(hatch none 0.5)
		(connect_pads
			(clearance 0)
		)
		(min_thickness 0.25)
		(keepout
			(tracks not_allowed)
			(vias allowed)
			(pads allowed)
			(copperpour not_allowed)
			(footprints allowed)
		)
		(placement
			(enabled no)
			(sheetname "")
		)
		(fill yes
			(thermal_gap 0.5)
			(thermal_bridge_width 0.5)
			(island_removal_mode 0)
		)
		(polygon
			(pts
				(arc
					(start 374.80621 -397.156432)
					(mid 374.17629 -397.156432)
					(end 374.80621 -397.156432)
				)
			)
		)
	)
	(zone
		(layers "B.Cu" "In11.Cu" "In13.Cu" "In15.Cu")
		(hatch none 0.5)
		(connect_pads
			(clearance 0)
		)
		(min_thickness 0.25)
		(keepout
			(tracks not_allowed)
			(vias allowed)
			(pads allowed)
			(copperpour not_allowed)
			(footprints allowed)
		)
		(placement
			(enabled no)
			(sheetname "")
		)
		(fill yes
			(thermal_gap 0.5)
			(thermal_bridge_width 0.5)
			(island_removal_mode 0)
		)
		(polygon
			(pts
				(arc
					(start 141.699742 -230.71455)
					(mid 141.069822 -230.71455)
					(end 141.699742 -230.71455)
				)
			)
		)
	)
	(zone
		(layers "B.Cu" "In11.Cu" "In13.Cu" "In15.Cu")
		(hatch none 0.5)
		(connect_pads
			(clearance 0)
		)
		(min_thickness 0.25)
		(keepout
			(tracks not_allowed)
			(vias allowed)
			(pads allowed)
			(copperpour not_allowed)
			(footprints allowed)
		)
		(placement
			(enabled no)
			(sheetname "")
		)
		(fill yes
			(thermal_gap 0.5)
			(thermal_bridge_width 0.5)
			(island_removal_mode 0)
		)
		(polygon
			(pts
				(arc
					(start 82.485992 -253.394464)
					(mid 81.856072 -253.394464)
					(end 82.485992 -253.394464)
				)
			)
		)
	)
	(zone
		(layers "B.Cu" "In11.Cu" "In13.Cu" "In15.Cu")
		(hatch none 0.5)
		(connect_pads
			(clearance 0)
		)
		(min_thickness 0.25)
		(keepout
			(tracks not_allowed)
			(vias allowed)
			(pads allowed)
			(copperpour not_allowed)
			(footprints allowed)
		)
		(placement
			(enabled no)
			(sheetname "")
		)
		(fill yes
			(thermal_gap 0.5)
			(thermal_bridge_width 0.5)
			(island_removal_mode 0)
		)
		(polygon
			(pts
				(arc
					(start 81.545938 -251.774452)
					(mid 80.916018 -251.774452)
					(end 81.545938 -251.774452)
				)
			)
		)
	)
	(zone
		(layers "B.Cu" "In11.Cu" "In13.Cu" "In15.Cu")
		(hatch none 0.5)
		(connect_pads
			(clearance 0)
		)
		(min_thickness 0.25)
		(keepout
			(tracks not_allowed)
			(vias allowed)
			(pads allowed)
			(copperpour not_allowed)
			(footprints allowed)
		)
		(placement
			(enabled no)
			(sheetname "")
		)
		(fill yes
			(thermal_gap 0.5)
			(thermal_bridge_width 0.5)
			(island_removal_mode 0)
		)
		(polygon
			(pts
				(arc
					(start 277.526242 -287.435036)
					(mid 276.858222 -287.435036)
					(end 277.526242 -287.435036)
				)
			)
		)
	)
	(zone
		(layers "B.Cu" "In11.Cu" "In13.Cu" "In15.Cu")
		(hatch none 0.5)
		(connect_pads
			(clearance 0)
		)
		(min_thickness 0.25)
		(keepout
			(tracks not_allowed)
			(vias allowed)
			(pads allowed)
			(copperpour not_allowed)
			(footprints allowed)
		)
		(placement
			(enabled no)
			(sheetname "")
		)
		(fill yes
			(thermal_gap 0.5)
			(thermal_bridge_width 0.5)
			(island_removal_mode 0)
		)
		(polygon
			(pts
				(arc
					(start 299.394626 5.514594)
					(mid 298.726606 5.514594)
					(end 299.394626 5.514594)
				)
			)
		)
	)
	(zone
		(layers "B.Cu" "In11.Cu" "In13.Cu" "In15.Cu")
		(hatch none 0.5)
		(connect_pads
			(clearance 0)
		)
		(min_thickness 0.25)
		(keepout
			(tracks not_allowed)
			(vias allowed)
			(pads allowed)
			(copperpour not_allowed)
			(footprints allowed)
		)
		(placement
			(enabled no)
			(sheetname "")
		)
		(fill yes
			(thermal_gap 0.5)
			(thermal_bridge_width 0.5)
			(island_removal_mode 0)
		)
		(polygon
			(pts
				(arc
					(start 365.66983 -238.004096)
					(mid 365.03991 -238.004096)
					(end 365.66983 -238.004096)
				)
			)
		)
	)
	(zone
		(layers "B.Cu" "In11.Cu" "In13.Cu" "In15.Cu")
		(hatch none 0.5)
		(connect_pads
			(clearance 0)
		)
		(min_thickness 0.25)
		(keepout
			(tracks not_allowed)
			(vias allowed)
			(pads allowed)
			(copperpour not_allowed)
			(footprints allowed)
		)
		(placement
			(enabled no)
			(sheetname "")
		)
		(fill yes
			(thermal_gap 0.5)
			(thermal_bridge_width 0.5)
			(island_removal_mode 0)
		)
		(polygon
			(pts
				(arc
					(start 29.586174 -270.435324)
					(mid 28.918154 -270.435324)
					(end 29.586174 -270.435324)
				)
			)
		)
	)
	(zone
		(layers "B.Cu" "In11.Cu" "In13.Cu" "In15.Cu")
		(hatch none 0.5)
		(connect_pads
			(clearance 0)
		)
		(min_thickness 0.25)
		(keepout
			(tracks not_allowed)
			(vias allowed)
			(pads allowed)
			(copperpour not_allowed)
			(footprints allowed)
		)
		(placement
			(enabled no)
			(sheetname "")
		)
		(fill yes
			(thermal_gap 0.5)
			(thermal_bridge_width 0.5)
			(island_removal_mode 0)
		)
		(polygon
			(pts
				(arc
					(start 362.379768 -238.814102)
					(mid 361.749848 -238.814102)
					(end 362.379768 -238.814102)
				)
			)
		)
	)
	(zone
		(layers "B.Cu" "In11.Cu" "In13.Cu" "In15.Cu")
		(hatch none 0.5)
		(connect_pads
			(clearance 0)
		)
		(min_thickness 0.25)
		(keepout
			(tracks not_allowed)
			(vias allowed)
			(pads allowed)
			(copperpour not_allowed)
			(footprints allowed)
		)
		(placement
			(enabled no)
			(sheetname "")
		)
		(fill yes
			(thermal_gap 0.5)
			(thermal_bridge_width 0.5)
			(island_removal_mode 0)
		)
		(polygon
			(pts
				(arc
					(start 143.109696 -233.144314)
					(mid 142.479776 -233.144314)
					(end 143.109696 -233.144314)
				)
			)
		)
	)
	(zone
		(layers "B.Cu" "In11.Cu" "In13.Cu" "In15.Cu")
		(hatch none 0.5)
		(connect_pads
			(clearance 0)
		)
		(min_thickness 0.25)
		(keepout
			(tracks not_allowed)
			(vias allowed)
			(pads allowed)
			(copperpour not_allowed)
			(footprints allowed)
		)
		(placement
			(enabled no)
			(sheetname "")
		)
		(fill yes
			(thermal_gap 0.5)
			(thermal_bridge_width 0.5)
			(island_removal_mode 0)
		)
		(polygon
			(pts
				(arc
					(start 330.89596 -250.964192)
					(mid 330.26604 -250.964192)
					(end 330.89596 -250.964192)
				)
			)
		)
	)
	(zone
		(layers "B.Cu" "In11.Cu" "In13.Cu" "In15.Cu")
		(hatch none 0.5)
		(connect_pads
			(clearance 0)
		)
		(min_thickness 0.25)
		(keepout
			(tracks not_allowed)
			(vias allowed)
			(pads allowed)
			(copperpour not_allowed)
			(footprints allowed)
		)
		(placement
			(enabled no)
			(sheetname "")
		)
		(fill yes
			(thermal_gap 0.5)
			(thermal_bridge_width 0.5)
			(island_removal_mode 0)
		)
		(polygon
			(pts
				(arc
					(start 25.486106 -308.685438)
					(mid 24.818086 -308.685438)
					(end 25.486106 -308.685438)
				)
			)
		)
	)
	(zone
		(layers "B.Cu" "In11.Cu" "In13.Cu" "In15.Cu")
		(hatch none 0.5)
		(connect_pads
			(clearance 0)
		)
		(min_thickness 0.25)
		(keepout
			(tracks not_allowed)
			(vias allowed)
			(pads allowed)
			(copperpour not_allowed)
			(footprints allowed)
		)
		(placement
			(enabled no)
			(sheetname "")
		)
		(fill yes
			(thermal_gap 0.5)
			(thermal_bridge_width 0.5)
			(island_removal_mode 0)
		)
		(polygon
			(pts
				(arc
					(start 81.376012 -284.616398)
					(mid 80.746092 -284.616398)
					(end 81.376012 -284.616398)
				)
			)
		)
	)
	(zone
		(layers "B.Cu" "In11.Cu" "In13.Cu" "In15.Cu")
		(hatch none 0.5)
		(connect_pads
			(clearance 0)
		)
		(min_thickness 0.25)
		(keepout
			(tracks not_allowed)
			(vias allowed)
			(pads allowed)
			(copperpour not_allowed)
			(footprints allowed)
		)
		(placement
			(enabled no)
			(sheetname "")
		)
		(fill yes
			(thermal_gap 0.5)
			(thermal_bridge_width 0.5)
			(island_removal_mode 0)
		)
		(polygon
			(pts
				(arc
					(start 25.486106 -285.735268)
					(mid 24.818086 -285.735268)
					(end 25.486106 -285.735268)
				)
			)
		)
	)
	(zone
		(layers "B.Cu" "In11.Cu" "In13.Cu" "In15.Cu")
		(hatch none 0.5)
		(connect_pads
			(clearance 0)
		)
		(min_thickness 0.25)
		(keepout
			(tracks not_allowed)
			(vias allowed)
			(pads allowed)
			(copperpour not_allowed)
			(footprints allowed)
		)
		(placement
			(enabled no)
			(sheetname "")
		)
		(fill yes
			(thermal_gap 0.5)
			(thermal_bridge_width 0.5)
			(island_removal_mode 0)
		)
		(polygon
			(pts
				(arc
					(start 83.255866 -289.47618)
					(mid 82.625946 -289.47618)
					(end 83.255866 -289.47618)
				)
			)
		)
	)
	(zone
		(layers "B.Cu" "In11.Cu" "In13.Cu" "In15.Cu")
		(hatch none 0.5)
		(connect_pads
			(clearance 0)
		)
		(min_thickness 0.25)
		(keepout
			(tracks not_allowed)
			(vias allowed)
			(pads allowed)
			(copperpour not_allowed)
			(footprints allowed)
		)
		(placement
			(enabled no)
			(sheetname "")
		)
		(fill yes
			(thermal_gap 0.5)
			(thermal_bridge_width 0.5)
			(island_removal_mode 0)
		)
		(polygon
			(pts
				(arc
					(start 143.40967 -274.896326)
					(mid 142.77975 -274.896326)
					(end 143.40967 -274.896326)
				)
			)
		)
	)
	(zone
		(layers "B.Cu" "In11.Cu" "In13.Cu" "In15.Cu")
		(hatch none 0.5)
		(connect_pads
			(clearance 0)
		)
		(min_thickness 0.25)
		(keepout
			(tracks not_allowed)
			(vias allowed)
			(pads allowed)
			(copperpour not_allowed)
			(footprints allowed)
		)
		(placement
			(enabled no)
			(sheetname "")
		)
		(fill yes
			(thermal_gap 0.5)
			(thermal_bridge_width 0.5)
			(island_removal_mode 0)
		)
		(polygon
			(pts
				(arc
					(start 120.40616 -389.467344)
					(mid 119.77624 -389.467344)
					(end 120.40616 -389.467344)
				)
			)
		)
	)
	(zone
		(layers "B.Cu" "In11.Cu" "In13.Cu" "In15.Cu")
		(hatch none 0.5)
		(connect_pads
			(clearance 0)
		)
		(min_thickness 0.25)
		(keepout
			(tracks not_allowed)
			(vias allowed)
			(pads allowed)
			(copperpour not_allowed)
			(footprints allowed)
		)
		(placement
			(enabled no)
			(sheetname "")
		)
		(fill yes
			(thermal_gap 0.5)
			(thermal_bridge_width 0.5)
			(island_removal_mode 0)
		)
		(polygon
			(pts
				(arc
					(start 406.134062 -393.69238)
					(mid 405.504142 -393.69238)
					(end 406.134062 -393.69238)
				)
			)
		)
	)
	(zone
		(layers "B.Cu" "In11.Cu" "In13.Cu" "In15.Cu")
		(hatch none 0.5)
		(connect_pads
			(clearance 0)
		)
		(min_thickness 0.25)
		(keepout
			(tracks not_allowed)
			(vias allowed)
			(pads allowed)
			(copperpour not_allowed)
			(footprints allowed)
		)
		(placement
			(enabled no)
			(sheetname "")
		)
		(fill yes
			(thermal_gap 0.5)
			(thermal_bridge_width 0.5)
			(island_removal_mode 0)
		)
		(polygon
			(pts
				(arc
					(start 362.679742 -283.806138)
					(mid 362.049822 -283.806138)
					(end 362.679742 -283.806138)
				)
			)
		)
	)
	(zone
		(layers "B.Cu" "In11.Cu" "In13.Cu" "In15.Cu")
		(hatch none 0.5)
		(connect_pads
			(clearance 0)
		)
		(min_thickness 0.25)
		(keepout
			(tracks not_allowed)
			(vias allowed)
			(pads allowed)
			(copperpour not_allowed)
			(footprints allowed)
		)
		(placement
			(enabled no)
			(sheetname "")
		)
		(fill yes
			(thermal_gap 0.5)
			(thermal_bridge_width 0.5)
			(island_removal_mode 0)
		)
		(polygon
			(pts
				(arc
					(start 141.229842 -239.624362)
					(mid 140.599922 -239.624362)
					(end 141.229842 -239.624362)
				)
			)
		)
	)
	(zone
		(layers "B.Cu" "In11.Cu" "In13.Cu" "In15.Cu")
		(hatch none 0.5)
		(connect_pads
			(clearance 0)
		)
		(min_thickness 0.25)
		(keepout
			(tracks not_allowed)
			(vias allowed)
			(pads allowed)
			(copperpour not_allowed)
			(footprints allowed)
		)
		(placement
			(enabled no)
			(sheetname "")
		)
		(fill yes
			(thermal_gap 0.5)
			(thermal_bridge_width 0.5)
			(island_removal_mode 0)
		)
		(polygon
			(pts
				(arc
					(start 141.999716 -277.326344)
					(mid 141.369796 -277.326344)
					(end 141.999716 -277.326344)
				)
			)
		)
	)
	(zone
		(layers "B.Cu" "In11.Cu" "In13.Cu" "In15.Cu")
		(hatch none 0.5)
		(connect_pads
			(clearance 0)
		)
		(min_thickness 0.25)
		(keepout
			(tracks not_allowed)
			(vias allowed)
			(pads allowed)
			(copperpour not_allowed)
			(footprints allowed)
		)
		(placement
			(enabled no)
			(sheetname "")
		)
		(fill yes
			(thermal_gap 0.5)
			(thermal_bridge_width 0.5)
			(island_removal_mode 0)
		)
		(polygon
			(pts
				(arc
					(start 273.426174 -295.935146)
					(mid 272.758154 -295.935146)
					(end 273.426174 -295.935146)
				)
			)
		)
	)
	(zone
		(layers "B.Cu" "In11.Cu" "In13.Cu" "In15.Cu")
		(hatch none 0.5)
		(connect_pads
			(clearance 0)
		)
		(min_thickness 0.25)
		(keepout
			(tracks not_allowed)
			(vias allowed)
			(pads allowed)
			(copperpour not_allowed)
			(footprints allowed)
		)
		(placement
			(enabled no)
			(sheetname "")
		)
		(fill yes
			(thermal_gap 0.5)
			(thermal_bridge_width 0.5)
			(island_removal_mode 0)
		)
		(polygon
			(pts
				(arc
					(start 67.371214 -404.46452)
					(mid 66.703194 -404.46452)
					(end 67.371214 -404.46452)
				)
			)
		)
	)
	(zone
		(layers "B.Cu" "In11.Cu" "In13.Cu" "In15.Cu")
		(hatch none 0.5)
		(connect_pads
			(clearance 0)
		)
		(min_thickness 0.25)
		(keepout
			(tracks not_allowed)
			(vias allowed)
			(pads allowed)
			(copperpour not_allowed)
			(footprints allowed)
		)
		(placement
			(enabled no)
			(sheetname "")
		)
		(fill yes
			(thermal_gap 0.5)
			(thermal_bridge_width 0.5)
			(island_removal_mode 0)
		)
		(polygon
			(pts
				(arc
					(start 29.586174 -281.48534)
					(mid 28.918154 -281.48534)
					(end 29.586174 -281.48534)
				)
			)
		)
	)
	(zone
		(layers "B.Cu" "In11.Cu" "In13.Cu" "In15.Cu")
		(hatch none 0.5)
		(connect_pads
			(clearance 0)
		)
		(min_thickness 0.25)
		(keepout
			(tracks not_allowed)
			(vias allowed)
			(pads allowed)
			(copperpour not_allowed)
			(footprints allowed)
		)
		(placement
			(enabled no)
			(sheetname "")
		)
		(fill yes
			(thermal_gap 0.5)
			(thermal_bridge_width 0.5)
			(island_removal_mode 0)
		)
		(polygon
			(pts
				(arc
					(start 330.42606 -250.154186)
					(mid 329.79614 -250.154186)
					(end 330.42606 -250.154186)
				)
			)
		)
	)
	(zone
		(layers "B.Cu" "In11.Cu" "In13.Cu" "In15.Cu")
		(hatch none 0.5)
		(connect_pads
			(clearance 0)
		)
		(min_thickness 0.25)
		(keepout
			(tracks not_allowed)
			(vias allowed)
			(pads allowed)
			(copperpour not_allowed)
			(footprints allowed)
		)
		(placement
			(enabled no)
			(sheetname "")
		)
		(fill yes
			(thermal_gap 0.5)
			(thermal_bridge_width 0.5)
			(island_removal_mode 0)
		)
		(polygon
			(pts
				(arc
					(start 389.63981 -230.714296)
					(mid 389.00989 -230.714296)
					(end 389.63981 -230.714296)
				)
			)
		)
	)
	(zone
		(layers "B.Cu" "In11.Cu" "In13.Cu" "In15.Cu")
		(hatch none 0.5)
		(connect_pads
			(clearance 0)
		)
		(min_thickness 0.25)
		(keepout
			(tracks not_allowed)
			(vias allowed)
			(pads allowed)
			(copperpour not_allowed)
			(footprints allowed)
		)
		(placement
			(enabled no)
			(sheetname "")
		)
		(fill yes
			(thermal_gap 0.5)
			(thermal_bridge_width 0.5)
			(island_removal_mode 0)
		)
		(polygon
			(pts
				(arc
					(start 199.03821 -284.885384)
					(mid 198.37019 -284.885384)
					(end 199.03821 -284.885384)
				)
			)
		)
	)
	(zone
		(layers "B.Cu" "In11.Cu" "In13.Cu" "In15.Cu")
		(hatch none 0.5)
		(connect_pads
			(clearance 0)
		)
		(min_thickness 0.25)
		(keepout
			(tracks not_allowed)
			(vias allowed)
			(pads allowed)
			(copperpour not_allowed)
			(footprints allowed)
		)
		(placement
			(enabled no)
			(sheetname "")
		)
		(fill yes
			(thermal_gap 0.5)
			(thermal_bridge_width 0.5)
			(island_removal_mode 0)
		)
		(polygon
			(pts
				(arc
					(start 66.506344 -389.467344)
					(mid 65.876424 -389.467344)
					(end 66.506344 -389.467344)
				)
			)
		)
	)
	(zone
		(layers "B.Cu" "In11.Cu" "In13.Cu" "In15.Cu")
		(hatch none 0.5)
		(connect_pads
			(clearance 0)
		)
		(min_thickness 0.25)
		(keepout
			(tracks not_allowed)
			(vias allowed)
			(pads allowed)
			(copperpour not_allowed)
			(footprints allowed)
		)
		(placement
			(enabled no)
			(sheetname "")
		)
		(fill yes
			(thermal_gap 0.5)
			(thermal_bridge_width 0.5)
			(island_removal_mode 0)
		)
		(polygon
			(pts
				(arc
					(start 330.42606 -229.094284)
					(mid 329.79614 -229.094284)
					(end 330.42606 -229.094284)
				)
			)
		)
	)
	(zone
		(layers "B.Cu" "In11.Cu" "In13.Cu" "In15.Cu")
		(hatch none 0.5)
		(connect_pads
			(clearance 0)
		)
		(min_thickness 0.25)
		(keepout
			(tracks not_allowed)
			(vias allowed)
			(pads allowed)
			(copperpour not_allowed)
			(footprints allowed)
		)
		(placement
			(enabled no)
			(sheetname "")
		)
		(fill yes
			(thermal_gap 0.5)
			(thermal_bridge_width 0.5)
			(island_removal_mode 0)
		)
		(polygon
			(pts
				(arc
					(start 364.729776 -242.864132)
					(mid 364.099856 -242.864132)
					(end 364.729776 -242.864132)
				)
			)
		)
	)
	(zone
		(layers "B.Cu" "In11.Cu" "In13.Cu" "In15.Cu")
		(hatch none 0.5)
		(connect_pads
			(clearance 0)
		)
		(min_thickness 0.25)
		(keepout
			(tracks not_allowed)
			(vias allowed)
			(pads allowed)
			(copperpour not_allowed)
			(footprints allowed)
		)
		(placement
			(enabled no)
			(sheetname "")
		)
		(fill yes
			(thermal_gap 0.5)
			(thermal_bridge_width 0.5)
			(island_removal_mode 0)
		)
		(polygon
			(pts
				(arc
					(start 273.426174 -221.13494)
					(mid 272.758154 -221.13494)
					(end 273.426174 -221.13494)
				)
			)
		)
	)
	(zone
		(layers "B.Cu" "In11.Cu" "In13.Cu" "In15.Cu")
		(hatch none 0.5)
		(connect_pads
			(clearance 0)
		)
		(min_thickness 0.25)
		(keepout
			(tracks not_allowed)
			(vias allowed)
			(pads allowed)
			(copperpour not_allowed)
			(footprints allowed)
		)
		(placement
			(enabled no)
			(sheetname "")
		)
		(fill yes
			(thermal_gap 0.5)
			(thermal_bridge_width 0.5)
			(island_removal_mode 0)
		)
		(polygon
			(pts
				(arc
					(start 118.006114 -389.467344)
					(mid 117.376194 -389.467344)
					(end 118.006114 -389.467344)
				)
			)
		)
	)
	(zone
		(layers "B.Cu" "In11.Cu" "In13.Cu" "In15.Cu")
		(hatch none 0.5)
		(connect_pads
			(clearance 0)
		)
		(min_thickness 0.25)
		(keepout
			(tracks not_allowed)
			(vias allowed)
			(pads allowed)
			(copperpour not_allowed)
			(footprints allowed)
		)
		(placement
			(enabled no)
			(sheetname "")
		)
		(fill yes
			(thermal_gap 0.5)
			(thermal_bridge_width 0.5)
			(island_removal_mode 0)
		)
		(polygon
			(pts
				(arc
					(start 304.454306 -382.34493)
					(mid 303.786286 -382.34493)
					(end 304.454306 -382.34493)
				)
			)
		)
	)
	(zone
		(layers "B.Cu" "In11.Cu" "In13.Cu" "In15.Cu")
		(hatch none 0.5)
		(connect_pads
			(clearance 0)
		)
		(min_thickness 0.25)
		(keepout
			(tracks not_allowed)
			(vias allowed)
			(pads allowed)
			(copperpour not_allowed)
			(footprints allowed)
		)
		(placement
			(enabled no)
			(sheetname "")
		)
		(fill yes
			(thermal_gap 0.5)
			(thermal_bridge_width 0.5)
			(island_removal_mode 0)
		)
		(polygon
			(pts
				(arc
					(start 69.036946 -427.089824)
					(mid 68.262754 -427.089824)
					(end 69.036946 -427.089824)
				)
			)
		)
	)
	(zone
		(layers "B.Cu" "In11.Cu" "In13.Cu" "In15.Cu")
		(hatch none 0.5)
		(connect_pads
			(clearance 0)
		)
		(min_thickness 0.25)
		(keepout
			(tracks not_allowed)
			(vias allowed)
			(pads allowed)
			(copperpour not_allowed)
			(footprints allowed)
		)
		(placement
			(enabled no)
			(sheetname "")
		)
		(fill yes
			(thermal_gap 0.5)
			(thermal_bridge_width 0.5)
			(island_removal_mode 0)
		)
		(polygon
			(pts
				(arc
					(start 389.469884 -292.71595)
					(mid 388.839964 -292.71595)
					(end 389.469884 -292.71595)
				)
			)
		)
	)
	(zone
		(layers "B.Cu" "In11.Cu" "In13.Cu" "In15.Cu")
		(hatch none 0.5)
		(connect_pads
			(clearance 0)
		)
		(min_thickness 0.25)
		(keepout
			(tracks not_allowed)
			(vias allowed)
			(pads allowed)
			(copperpour not_allowed)
			(footprints allowed)
		)
		(placement
			(enabled no)
			(sheetname "")
		)
		(fill yes
			(thermal_gap 0.5)
			(thermal_bridge_width 0.5)
			(island_removal_mode 0)
		)
		(polygon
			(pts
				(arc
					(start 273.426174 -280.634948)
					(mid 272.758154 -280.634948)
					(end 273.426174 -280.634948)
				)
			)
		)
	)
	(zone
		(layers "B.Cu" "In11.Cu" "In13.Cu" "In15.Cu")
		(hatch none 0.5)
		(connect_pads
			(clearance 0)
		)
		(min_thickness 0.25)
		(keepout
			(tracks not_allowed)
			(vias allowed)
			(pads allowed)
			(copperpour not_allowed)
			(footprints allowed)
		)
		(placement
			(enabled no)
			(sheetname "")
		)
		(fill yes
			(thermal_gap 0.5)
			(thermal_bridge_width 0.5)
			(island_removal_mode 0)
		)
		(polygon
			(pts
				(arc
					(start 390.579864 -246.914162)
					(mid 389.949944 -246.914162)
					(end 390.579864 -246.914162)
				)
			)
		)
	)
	(zone
		(layers "B.Cu" "In11.Cu" "In13.Cu" "In15.Cu")
		(hatch none 0.5)
		(connect_pads
			(clearance 0)
		)
		(min_thickness 0.25)
		(keepout
			(tracks not_allowed)
			(vias allowed)
			(pads allowed)
			(copperpour not_allowed)
			(footprints allowed)
		)
		(placement
			(enabled no)
			(sheetname "")
		)
		(fill yes
			(thermal_gap 0.5)
			(thermal_bridge_width 0.5)
			(island_removal_mode 0)
		)
		(polygon
			(pts
				(arc
					(start 147.13712 -427.289976)
					(mid 146.362928 -427.289976)
					(end 147.13712 -427.289976)
				)
			)
		)
	)
	(zone
		(layers "B.Cu" "In11.Cu" "In13.Cu" "In15.Cu")
		(hatch none 0.5)
		(connect_pads
			(clearance 0)
		)
		(min_thickness 0.25)
		(keepout
			(tracks not_allowed)
			(vias allowed)
			(pads allowed)
			(copperpour not_allowed)
			(footprints allowed)
		)
		(placement
			(enabled no)
			(sheetname "")
		)
		(fill yes
			(thermal_gap 0.5)
			(thermal_bridge_width 0.5)
			(island_removal_mode 0)
		)
		(polygon
			(pts
				(arc
					(start 392.136884 -427.089824)
					(mid 391.362692 -427.089824)
					(end 392.136884 -427.089824)
				)
			)
		)
	)
	(zone
		(layers "B.Cu" "In11.Cu" "In13.Cu" "In15.Cu")
		(hatch none 0.5)
		(connect_pads
			(clearance 0)
		)
		(min_thickness 0.25)
		(keepout
			(tracks not_allowed)
			(vias allowed)
			(pads allowed)
			(copperpour not_allowed)
			(footprints allowed)
		)
		(placement
			(enabled no)
			(sheetname "")
		)
		(fill yes
			(thermal_gap 0.5)
			(thermal_bridge_width 0.5)
			(island_removal_mode 0)
		)
		(polygon
			(pts
				(arc
					(start 102.05593 -286.23641)
					(mid 101.42601 -286.23641)
					(end 102.05593 -286.23641)
				)
			)
		)
	)
	(zone
		(layers "B.Cu" "In11.Cu" "In13.Cu" "In15.Cu")
		(hatch none 0.5)
		(connect_pads
			(clearance 0)
		)
		(min_thickness 0.25)
		(keepout
			(tracks not_allowed)
			(vias allowed)
			(pads allowed)
			(copperpour not_allowed)
			(footprints allowed)
		)
		(placement
			(enabled no)
			(sheetname "")
		)
		(fill yes
			(thermal_gap 0.5)
			(thermal_bridge_width 0.5)
			(island_removal_mode 0)
		)
		(polygon
			(pts
				(arc
					(start 81.845912 -278.946356)
					(mid 81.215992 -278.946356)
					(end 81.845912 -278.946356)
				)
			)
		)
	)
	(zone
		(layers "B.Cu" "In11.Cu" "In13.Cu" "In15.Cu")
		(hatch none 0.5)
		(connect_pads
			(clearance 0)
		)
		(min_thickness 0.25)
		(keepout
			(tracks not_allowed)
			(vias allowed)
			(pads allowed)
			(copperpour not_allowed)
			(footprints allowed)
		)
		(placement
			(enabled no)
			(sheetname "")
		)
		(fill yes
			(thermal_gap 0.5)
			(thermal_bridge_width 0.5)
			(island_removal_mode 0)
		)
		(polygon
			(pts
				(arc
					(start 399.137124 -427.289976)
					(mid 398.362932 -427.289976)
					(end 399.137124 -427.289976)
				)
			)
		)
	)
	(zone
		(layers "B.Cu" "In11.Cu" "In13.Cu" "In15.Cu")
		(hatch none 0.5)
		(connect_pads
			(clearance 0)
		)
		(min_thickness 0.25)
		(keepout
			(tracks not_allowed)
			(vias allowed)
			(pads allowed)
			(copperpour not_allowed)
			(footprints allowed)
		)
		(placement
			(enabled no)
			(sheetname "")
		)
		(fill yes
			(thermal_gap 0.5)
			(thermal_bridge_width 0.5)
			(island_removal_mode 0)
		)
		(polygon
			(pts
				(arc
					(start 446.978278 -210.935062)
					(mid 446.310258 -210.935062)
					(end 446.978278 -210.935062)
				)
			)
		)
	)
	(zone
		(layers "B.Cu" "In11.Cu" "In13.Cu" "In15.Cu")
		(hatch none 0.5)
		(connect_pads
			(clearance 0)
		)
		(min_thickness 0.25)
		(keepout
			(tracks not_allowed)
			(vias allowed)
			(pads allowed)
			(copperpour not_allowed)
			(footprints allowed)
		)
		(placement
			(enabled no)
			(sheetname "")
		)
		(fill yes
			(thermal_gap 0.5)
			(thermal_bridge_width 0.5)
			(island_removal_mode 0)
		)
		(polygon
			(pts
				(arc
					(start 417.333938 -394.385292)
					(mid 416.704018 -394.385292)
					(end 417.333938 -394.385292)
				)
			)
		)
	)
	(zone
		(layers "B.Cu" "In11.Cu" "In13.Cu" "In15.Cu")
		(hatch none 0.5)
		(connect_pads
			(clearance 0)
		)
		(min_thickness 0.25)
		(keepout
			(tracks not_allowed)
			(vias allowed)
			(pads allowed)
			(copperpour not_allowed)
			(footprints allowed)
		)
		(placement
			(enabled no)
			(sheetname "")
		)
		(fill yes
			(thermal_gap 0.5)
			(thermal_bridge_width 0.5)
			(island_removal_mode 0)
		)
		(polygon
			(pts
				(arc
					(start 446.978278 -249.185176)
					(mid 446.310258 -249.185176)
					(end 446.978278 -249.185176)
				)
			)
		)
	)
	(zone
		(layers "B.Cu" "In11.Cu" "In13.Cu" "In15.Cu")
		(hatch none 0.5)
		(connect_pads
			(clearance 0)
		)
		(min_thickness 0.25)
		(keepout
			(tracks not_allowed)
			(vias allowed)
			(pads allowed)
			(copperpour not_allowed)
			(footprints allowed)
		)
		(placement
			(enabled no)
			(sheetname "")
		)
		(fill yes
			(thermal_gap 0.5)
			(thermal_bridge_width 0.5)
			(island_removal_mode 0)
		)
		(polygon
			(pts
				(arc
					(start 277.526242 -219.435172)
					(mid 276.858222 -219.435172)
					(end 277.526242 -219.435172)
				)
			)
		)
	)
	(zone
		(layers "B.Cu" "In11.Cu" "In13.Cu" "In15.Cu")
		(hatch none 0.5)
		(connect_pads
			(clearance 0)
		)
		(min_thickness 0.25)
		(keepout
			(tracks not_allowed)
			(vias allowed)
			(pads allowed)
			(copperpour not_allowed)
			(footprints allowed)
		)
		(placement
			(enabled no)
			(sheetname "")
		)
		(fill yes
			(thermal_gap 0.5)
			(thermal_bridge_width 0.5)
			(island_removal_mode 0)
		)
		(polygon
			(pts
				(arc
					(start 442.87821 -218.585034)
					(mid 442.21019 -218.585034)
					(end 442.87821 -218.585034)
				)
			)
		)
	)
	(zone
		(layers "B.Cu" "In11.Cu" "In13.Cu" "In15.Cu")
		(hatch none 0.5)
		(connect_pads
			(clearance 0)
		)
		(min_thickness 0.25)
		(keepout
			(tracks not_allowed)
			(vias allowed)
			(pads allowed)
			(copperpour not_allowed)
			(footprints allowed)
		)
		(placement
			(enabled no)
			(sheetname "")
		)
		(fill yes
			(thermal_gap 0.5)
			(thermal_bridge_width 0.5)
			(island_removal_mode 0)
		)
		(polygon
			(pts
				(arc
					(start 141.529816 -270.03629)
					(mid 140.899896 -270.03629)
					(end 141.529816 -270.03629)
				)
			)
		)
	)
	(zone
		(layers "B.Cu" "In11.Cu" "In13.Cu" "In15.Cu")
		(hatch none 0.5)
		(connect_pads
			(clearance 0)
		)
		(min_thickness 0.25)
		(keepout
			(tracks not_allowed)
			(vias allowed)
			(pads allowed)
			(copperpour not_allowed)
			(footprints allowed)
		)
		(placement
			(enabled no)
			(sheetname "")
		)
		(fill yes
			(thermal_gap 0.5)
			(thermal_bridge_width 0.5)
			(island_removal_mode 0)
		)
		(polygon
			(pts
				(arc
					(start 329.31608 -278.136096)
					(mid 328.68616 -278.136096)
					(end 329.31608 -278.136096)
				)
			)
		)
	)
	(zone
		(layers "B.Cu" "In11.Cu" "In13.Cu" "In15.Cu")
		(hatch none 0.5)
		(connect_pads
			(clearance 0)
		)
		(min_thickness 0.25)
		(keepout
			(tracks not_allowed)
			(vias allowed)
			(pads allowed)
			(copperpour not_allowed)
			(footprints allowed)
		)
		(placement
			(enabled no)
			(sheetname "")
		)
		(fill yes
			(thermal_gap 0.5)
			(thermal_bridge_width 0.5)
			(island_removal_mode 0)
		)
		(polygon
			(pts
				(arc
					(start 25.486106 -201.585322)
					(mid 24.818086 -201.585322)
					(end 25.486106 -201.585322)
				)
			)
		)
	)
	(zone
		(layers "B.Cu" "In11.Cu" "In13.Cu" "In15.Cu")
		(hatch none 0.5)
		(connect_pads
			(clearance 0)
		)
		(min_thickness 0.25)
		(keepout
			(tracks not_allowed)
			(vias allowed)
			(pads allowed)
			(copperpour not_allowed)
			(footprints allowed)
		)
		(placement
			(enabled no)
			(sheetname "")
		)
		(fill yes
			(thermal_gap 0.5)
			(thermal_bridge_width 0.5)
			(island_removal_mode 0)
		)
		(polygon
			(pts
				(arc
					(start 273.426174 -232.184956)
					(mid 272.758154 -232.184956)
					(end 273.426174 -232.184956)
				)
			)
		)
	)
	(zone
		(layers "B.Cu" "In11.Cu" "In13.Cu" "In15.Cu")
		(hatch none 0.5)
		(connect_pads
			(clearance 0)
		)
		(min_thickness 0.25)
		(keepout
			(tracks not_allowed)
			(vias allowed)
			(pads allowed)
			(copperpour not_allowed)
			(footprints allowed)
		)
		(placement
			(enabled no)
			(sheetname "")
		)
		(fill yes
			(thermal_gap 0.5)
			(thermal_bridge_width 0.5)
			(island_removal_mode 0)
		)
		(polygon
			(pts
				(arc
					(start 446.978278 -203.28509)
					(mid 446.310258 -203.28509)
					(end 446.978278 -203.28509)
				)
			)
		)
	)
	(zone
		(layers "B.Cu" "In11.Cu" "In13.Cu" "In15.Cu")
		(hatch none 0.5)
		(connect_pads
			(clearance 0)
		)
		(min_thickness 0.25)
		(keepout
			(tracks not_allowed)
			(vias allowed)
			(pads allowed)
			(copperpour not_allowed)
			(footprints allowed)
		)
		(placement
			(enabled no)
			(sheetname "")
		)
		(fill yes
			(thermal_gap 0.5)
			(thermal_bridge_width 0.5)
			(island_removal_mode 0)
		)
		(polygon
			(pts
				(arc
					(start 142.639796 -246.914416)
					(mid 142.009876 -246.914416)
					(end 142.639796 -246.914416)
				)
			)
		)
	)
	(zone
		(layers "B.Cu" "In11.Cu" "In13.Cu" "In15.Cu")
		(hatch none 0.5)
		(connect_pads
			(clearance 0)
		)
		(min_thickness 0.25)
		(keepout
			(tracks not_allowed)
			(vias allowed)
			(pads allowed)
			(copperpour not_allowed)
			(footprints allowed)
		)
		(placement
			(enabled no)
			(sheetname "")
		)
		(fill yes
			(thermal_gap 0.5)
			(thermal_bridge_width 0.5)
			(island_removal_mode 0)
		)
		(polygon
			(pts
				(arc
					(start 273.426174 -285.735014)
					(mid 272.758154 -285.735014)
					(end 273.426174 -285.735014)
				)
			)
		)
	)
	(zone
		(layers "B.Cu" "In11.Cu" "In13.Cu" "In15.Cu")
		(hatch none 0.5)
		(connect_pads
			(clearance 0)
		)
		(min_thickness 0.25)
		(keepout
			(tracks not_allowed)
			(vias allowed)
			(pads allowed)
			(copperpour not_allowed)
			(footprints allowed)
		)
		(placement
			(enabled no)
			(sheetname "")
		)
		(fill yes
			(thermal_gap 0.5)
			(thermal_bridge_width 0.5)
			(island_removal_mode 0)
		)
		(polygon
			(pts
				(arc
					(start 277.526242 -203.28509)
					(mid 276.858222 -203.28509)
					(end 277.526242 -203.28509)
				)
			)
		)
	)
	(zone
		(layers "B.Cu" "In11.Cu" "In13.Cu" "In15.Cu")
		(hatch none 0.5)
		(connect_pads
			(clearance 0)
		)
		(min_thickness 0.25)
		(keepout
			(tracks not_allowed)
			(vias allowed)
			(pads allowed)
			(copperpour not_allowed)
			(footprints allowed)
		)
		(placement
			(enabled no)
			(sheetname "")
		)
		(fill yes
			(thermal_gap 0.5)
			(thermal_bridge_width 0.5)
			(island_removal_mode 0)
		)
		(polygon
			(pts
				(arc
					(start 114.739674 -282.18638)
					(mid 114.109754 -282.18638)
					(end 114.739674 -282.18638)
				)
			)
		)
	)
	(zone
		(layers "B.Cu" "In11.Cu" "In13.Cu" "In15.Cu")
		(hatch none 0.5)
		(connect_pads
			(clearance 0)
		)
		(min_thickness 0.25)
		(keepout
			(tracks not_allowed)
			(vias allowed)
			(pads allowed)
			(copperpour not_allowed)
			(footprints allowed)
		)
		(placement
			(enabled no)
			(sheetname "")
		)
		(fill yes
			(thermal_gap 0.5)
			(thermal_bridge_width 0.5)
			(island_removal_mode 0)
		)
		(polygon
			(pts
				(arc
					(start 55.306214 -388.774432)
					(mid 54.676294 -388.774432)
					(end 55.306214 -388.774432)
				)
			)
		)
	)
	(zone
		(layers "B.Cu" "In11.Cu" "In13.Cu" "In15.Cu")
		(hatch none 0.5)
		(connect_pads
			(clearance 0)
		)
		(min_thickness 0.25)
		(keepout
			(tracks not_allowed)
			(vias allowed)
			(pads allowed)
			(copperpour not_allowed)
			(footprints allowed)
		)
		(placement
			(enabled no)
			(sheetname "")
		)
		(fill yes
			(thermal_gap 0.5)
			(thermal_bridge_width 0.5)
			(island_removal_mode 0)
		)
		(polygon
			(pts
				(arc
					(start 126.489714 -281.376374)
					(mid 125.859794 -281.376374)
					(end 126.489714 -281.376374)
				)
			)
		)
	)
	(zone
		(layers "B.Cu" "In11.Cu" "In13.Cu" "In15.Cu")
		(hatch none 0.5)
		(connect_pads
			(clearance 0)
		)
		(min_thickness 0.25)
		(keepout
			(tracks not_allowed)
			(vias allowed)
			(pads allowed)
			(copperpour not_allowed)
			(footprints allowed)
		)
		(placement
			(enabled no)
			(sheetname "")
		)
		(fill yes
			(thermal_gap 0.5)
			(thermal_bridge_width 0.5)
			(island_removal_mode 0)
		)
		(polygon
			(pts
				(arc
					(start 29.586174 -234.73537)
					(mid 28.918154 -234.73537)
					(end 29.586174 -234.73537)
				)
			)
		)
	)
	(zone
		(layers "B.Cu" "In11.Cu" "In13.Cu" "In15.Cu")
		(hatch none 0.5)
		(connect_pads
			(clearance 0)
		)
		(min_thickness 0.25)
		(keepout
			(tracks not_allowed)
			(vias allowed)
			(pads allowed)
			(copperpour not_allowed)
			(footprints allowed)
		)
		(placement
			(enabled no)
			(sheetname "")
		)
		(fill yes
			(thermal_gap 0.5)
			(thermal_bridge_width 0.5)
			(island_removal_mode 0)
		)
		(polygon
			(pts
				(arc
					(start 25.486106 -216.885266)
					(mid 24.818086 -216.885266)
					(end 25.486106 -216.885266)
				)
			)
		)
	)
	(zone
		(layers "B.Cu" "In11.Cu" "In13.Cu" "In15.Cu")
		(hatch none 0.5)
		(connect_pads
			(clearance 0)
		)
		(min_thickness 0.25)
		(keepout
			(tracks not_allowed)
			(vias allowed)
			(pads allowed)
			(copperpour not_allowed)
			(footprints allowed)
		)
		(placement
			(enabled no)
			(sheetname "")
		)
		(fill yes
			(thermal_gap 0.5)
			(thermal_bridge_width 0.5)
			(island_removal_mode 0)
		)
		(polygon
			(pts
				(arc
					(start 390.579864 -256.634234)
					(mid 389.949944 -256.634234)
					(end 390.579864 -256.634234)
				)
			)
		)
	)
	(zone
		(layers "B.Cu" "In11.Cu" "In13.Cu" "In15.Cu")
		(hatch none 0.5)
		(connect_pads
			(clearance 0)
		)
		(min_thickness 0.25)
		(keepout
			(tracks not_allowed)
			(vias allowed)
			(pads allowed)
			(copperpour not_allowed)
			(footprints allowed)
		)
		(placement
			(enabled no)
			(sheetname "")
		)
		(fill yes
			(thermal_gap 0.5)
			(thermal_bridge_width 0.5)
			(island_removal_mode 0)
		)
		(polygon
			(pts
				(arc
					(start 145.137124 -428.28972)
					(mid 144.362932 -428.28972)
					(end 145.137124 -428.28972)
				)
			)
		)
	)
	(zone
		(layers "B.Cu" "In11.Cu" "In13.Cu" "In15.Cu")
		(hatch none 0.5)
		(connect_pads
			(clearance 0)
		)
		(min_thickness 0.25)
		(keepout
			(tracks not_allowed)
			(vias allowed)
			(pads allowed)
			(copperpour not_allowed)
			(footprints allowed)
		)
		(placement
			(enabled no)
			(sheetname "")
		)
		(fill yes
			(thermal_gap 0.5)
			(thermal_bridge_width 0.5)
			(island_removal_mode 0)
		)
		(polygon
			(pts
				(arc
					(start 199.03821 -228.78542)
					(mid 198.37019 -228.78542)
					(end 199.03821 -228.78542)
				)
			)
		)
	)
	(zone
		(layers "B.Cu" "In11.Cu" "In13.Cu" "In15.Cu")
		(hatch none 0.5)
		(connect_pads
			(clearance 0)
		)
		(min_thickness 0.25)
		(keepout
			(tracks not_allowed)
			(vias allowed)
			(pads allowed)
			(copperpour not_allowed)
			(footprints allowed)
		)
		(placement
			(enabled no)
			(sheetname "")
		)
		(fill yes
			(thermal_gap 0.5)
			(thermal_bridge_width 0.5)
			(island_removal_mode 0)
		)
		(polygon
			(pts
				(arc
					(start 390.879838 -290.285932)
					(mid 390.249918 -290.285932)
					(end 390.879838 -290.285932)
				)
			)
		)
	)
	(zone
		(layers "B.Cu" "In11.Cu" "In13.Cu" "In15.Cu")
		(hatch none 0.5)
		(connect_pads
			(clearance 0)
		)
		(min_thickness 0.25)
		(keepout
			(tracks not_allowed)
			(vias allowed)
			(pads allowed)
			(copperpour not_allowed)
			(footprints allowed)
		)
		(placement
			(enabled no)
			(sheetname "")
		)
		(fill yes
			(thermal_gap 0.5)
			(thermal_bridge_width 0.5)
			(island_removal_mode 0)
		)
		(polygon
			(pts
				(arc
					(start 83.255866 -292.716204)
					(mid 82.625946 -292.716204)
					(end 83.255866 -292.716204)
				)
			)
		)
	)
	(zone
		(layers "B.Cu" "In11.Cu" "In13.Cu" "In15.Cu")
		(hatch none 0.5)
		(connect_pads
			(clearance 0)
		)
		(min_thickness 0.25)
		(keepout
			(tracks not_allowed)
			(vias allowed)
			(pads allowed)
			(copperpour not_allowed)
			(footprints allowed)
		)
		(placement
			(enabled no)
			(sheetname "")
		)
		(fill yes
			(thermal_gap 0.5)
			(thermal_bridge_width 0.5)
			(island_removal_mode 0)
		)
		(polygon
			(pts
				(arc
					(start 446.978278 -208.385156)
					(mid 446.310258 -208.385156)
					(end 446.978278 -208.385156)
				)
			)
		)
	)
	(zone
		(layers "B.Cu" "In11.Cu" "In13.Cu" "In15.Cu")
		(hatch none 0.5)
		(connect_pads
			(clearance 0)
		)
		(min_thickness 0.25)
		(keepout
			(tracks not_allowed)
			(vias allowed)
			(pads allowed)
			(copperpour not_allowed)
			(footprints allowed)
		)
		(placement
			(enabled no)
			(sheetname "")
		)
		(fill yes
			(thermal_gap 0.5)
			(thermal_bridge_width 0.5)
			(island_removal_mode 0)
		)
		(polygon
			(pts
				(arc
					(start 390.879838 -272.466054)
					(mid 390.249918 -272.466054)
					(end 390.879838 -272.466054)
				)
			)
		)
	)
	(zone
		(layers "B.Cu" "In11.Cu" "In13.Cu" "In15.Cu")
		(hatch none 0.5)
		(connect_pads
			(clearance 0)
		)
		(min_thickness 0.25)
		(keepout
			(tracks not_allowed)
			(vias allowed)
			(pads allowed)
			(copperpour not_allowed)
			(footprints allowed)
		)
		(placement
			(enabled no)
			(sheetname "")
		)
		(fill yes
			(thermal_gap 0.5)
			(thermal_bridge_width 0.5)
			(island_removal_mode 0)
		)
		(polygon
			(pts
				(arc
					(start 153.137108 -427.089824)
					(mid 152.362916 -427.089824)
					(end 153.137108 -427.089824)
				)
			)
		)
	)
	(zone
		(layers "B.Cu" "In11.Cu" "In13.Cu" "In15.Cu")
		(hatch none 0.5)
		(connect_pads
			(clearance 0)
		)
		(min_thickness 0.25)
		(keepout
			(tracks not_allowed)
			(vias allowed)
			(pads allowed)
			(copperpour not_allowed)
			(footprints allowed)
		)
		(placement
			(enabled no)
			(sheetname "")
		)
		(fill yes
			(thermal_gap 0.5)
			(thermal_bridge_width 0.5)
			(island_removal_mode 0)
		)
		(polygon
			(pts
				(arc
					(start 446.978278 -292.535102)
					(mid 446.310258 -292.535102)
					(end 446.978278 -292.535102)
				)
			)
		)
	)
	(zone
		(layers "B.Cu" "In11.Cu" "In13.Cu" "In15.Cu")
		(hatch none 0.5)
		(connect_pads
			(clearance 0)
		)
		(min_thickness 0.25)
		(keepout
			(tracks not_allowed)
			(vias allowed)
			(pads allowed)
			(copperpour not_allowed)
			(footprints allowed)
		)
		(placement
			(enabled no)
			(sheetname "")
		)
		(fill yes
			(thermal_gap 0.5)
			(thermal_bridge_width 0.5)
			(island_removal_mode 0)
		)
		(polygon
			(pts
				(arc
					(start 391.049764 -244.484144)
					(mid 390.419844 -244.484144)
					(end 391.049764 -244.484144)
				)
			)
		)
	)
	(zone
		(layers "B.Cu" "In11.Cu" "In13.Cu" "In15.Cu")
		(hatch none 0.5)
		(connect_pads
			(clearance 0)
		)
		(min_thickness 0.25)
		(keepout
			(tracks not_allowed)
			(vias allowed)
			(pads allowed)
			(copperpour not_allowed)
			(footprints allowed)
		)
		(placement
			(enabled no)
			(sheetname "")
		)
		(fill yes
			(thermal_gap 0.5)
			(thermal_bridge_width 0.5)
			(island_removal_mode 0)
		)
		(polygon
			(pts
				(arc
					(start 97.995994 -239.624362)
					(mid 97.366074 -239.624362)
					(end 97.995994 -239.624362)
				)
			)
		)
	)
	(zone
		(layers "B.Cu" "In11.Cu" "In13.Cu" "In15.Cu")
		(hatch none 0.5)
		(connect_pads
			(clearance 0)
		)
		(min_thickness 0.25)
		(keepout
			(tracks not_allowed)
			(vias allowed)
			(pads allowed)
			(copperpour not_allowed)
			(footprints allowed)
		)
		(placement
			(enabled no)
			(sheetname "")
		)
		(fill yes
			(thermal_gap 0.5)
			(thermal_bridge_width 0.5)
			(island_removal_mode 0)
		)
		(polygon
			(pts
				(arc
					(start 138.136884 -426.089826)
					(mid 137.362692 -426.089826)
					(end 138.136884 -426.089826)
				)
			)
		)
	)
	(zone
		(layers "B.Cu" "In11.Cu" "In13.Cu" "In15.Cu")
		(hatch none 0.5)
		(connect_pads
			(clearance 0)
		)
		(min_thickness 0.25)
		(keepout
			(tracks not_allowed)
			(vias allowed)
			(pads allowed)
			(copperpour not_allowed)
			(footprints allowed)
		)
		(placement
			(enabled no)
			(sheetname "")
		)
		(fill yes
			(thermal_gap 0.5)
			(thermal_bridge_width 0.5)
			(island_removal_mode 0)
		)
		(polygon
			(pts
				(arc
					(start 329.78598 -291.905944)
					(mid 329.15606 -291.905944)
					(end 329.78598 -291.905944)
				)
			)
		)
	)
	(zone
		(layers "B.Cu" "In11.Cu" "In13.Cu" "In15.Cu")
		(hatch none 0.5)
		(connect_pads
			(clearance 0)
		)
		(min_thickness 0.25)
		(keepout
			(tracks not_allowed)
			(vias allowed)
			(pads allowed)
			(copperpour not_allowed)
			(footprints allowed)
		)
		(placement
			(enabled no)
			(sheetname "")
		)
		(fill yes
			(thermal_gap 0.5)
			(thermal_bridge_width 0.5)
			(island_removal_mode 0)
		)
		(polygon
			(pts
				(arc
					(start 273.426174 -241.53495)
					(mid 272.758154 -241.53495)
					(end 273.426174 -241.53495)
				)
			)
		)
	)
	(zone
		(layers "B.Cu" "In11.Cu" "In13.Cu" "In15.Cu")
		(hatch none 0.5)
		(connect_pads
			(clearance 0)
		)
		(min_thickness 0.25)
		(keepout
			(tracks not_allowed)
			(vias allowed)
			(pads allowed)
			(copperpour not_allowed)
			(footprints allowed)
		)
		(placement
			(enabled no)
			(sheetname "")
		)
		(fill yes
			(thermal_gap 0.5)
			(thermal_bridge_width 0.5)
			(island_removal_mode 0)
		)
		(polygon
			(pts
				(arc
					(start 82.955892 -246.10441)
					(mid 82.325972 -246.10441)
					(end 82.955892 -246.10441)
				)
			)
		)
	)
	(zone
		(layers "B.Cu" "In11.Cu" "In13.Cu" "In15.Cu")
		(hatch none 0.5)
		(connect_pads
			(clearance 0)
		)
		(min_thickness 0.25)
		(keepout
			(tracks not_allowed)
			(vias allowed)
			(pads allowed)
			(copperpour not_allowed)
			(footprints allowed)
		)
		(placement
			(enabled no)
			(sheetname "")
		)
		(fill yes
			(thermal_gap 0.5)
			(thermal_bridge_width 0.5)
			(island_removal_mode 0)
		)
		(polygon
			(pts
				(arc
					(start 194.938142 -209.235294)
					(mid 194.270122 -209.235294)
					(end 194.938142 -209.235294)
				)
			)
		)
	)
	(zone
		(layers "B.Cu" "In11.Cu" "In13.Cu" "In15.Cu")
		(hatch none 0.5)
		(connect_pads
			(clearance 0)
		)
		(min_thickness 0.25)
		(keepout
			(tracks not_allowed)
			(vias allowed)
			(pads allowed)
			(copperpour not_allowed)
			(footprints allowed)
		)
		(placement
			(enabled no)
			(sheetname "")
		)
		(fill yes
			(thermal_gap 0.5)
			(thermal_bridge_width 0.5)
			(island_removal_mode 0)
		)
		(polygon
			(pts
				(arc
					(start 299.394626 4.650994)
					(mid 298.726606 4.650994)
					(end 299.394626 4.650994)
				)
			)
		)
	)
	(zone
		(layers "B.Cu" "In11.Cu" "In13.Cu" "In15.Cu")
		(hatch none 0.5)
		(connect_pads
			(clearance 0)
		)
		(min_thickness 0.25)
		(keepout
			(tracks not_allowed)
			(vias allowed)
			(pads allowed)
			(copperpour not_allowed)
			(footprints allowed)
		)
		(placement
			(enabled no)
			(sheetname "")
		)
		(fill yes
			(thermal_gap 0.5)
			(thermal_bridge_width 0.5)
			(island_removal_mode 0)
		)
		(polygon
			(pts
				(arc
					(start 141.699742 -253.394464)
					(mid 141.069822 -253.394464)
					(end 141.699742 -253.394464)
				)
			)
		)
	)
	(zone
		(layers "B.Cu" "In11.Cu" "In13.Cu" "In15.Cu")
		(hatch none 0.5)
		(connect_pads
			(clearance 0)
		)
		(min_thickness 0.25)
		(keepout
			(tracks not_allowed)
			(vias allowed)
			(pads allowed)
			(copperpour not_allowed)
			(footprints allowed)
		)
		(placement
			(enabled no)
			(sheetname "")
		)
		(fill yes
			(thermal_gap 0.5)
			(thermal_bridge_width 0.5)
			(island_removal_mode 0)
		)
		(polygon
			(pts
				(arc
					(start 329.31608 -276.516084)
					(mid 328.68616 -276.516084)
					(end 329.31608 -276.516084)
				)
			)
		)
	)
	(zone
		(layers "B.Cu" "In11.Cu" "In13.Cu" "In15.Cu")
		(hatch none 0.5)
		(connect_pads
			(clearance 0)
		)
		(min_thickness 0.25)
		(keepout
			(tracks not_allowed)
			(vias allowed)
			(pads allowed)
			(copperpour not_allowed)
			(footprints allowed)
		)
		(placement
			(enabled no)
			(sheetname "")
		)
		(fill yes
			(thermal_gap 0.5)
			(thermal_bridge_width 0.5)
			(island_removal_mode 0)
		)
		(polygon
			(pts
				(arc
					(start 389.469884 -279.756108)
					(mid 388.839964 -279.756108)
					(end 389.469884 -279.756108)
				)
			)
		)
	)
	(zone
		(layers "B.Cu" "In11.Cu" "In13.Cu" "In15.Cu")
		(hatch none 0.5)
		(connect_pads
			(clearance 0)
		)
		(min_thickness 0.25)
		(keepout
			(tracks not_allowed)
			(vias allowed)
			(pads allowed)
			(copperpour not_allowed)
			(footprints allowed)
		)
		(placement
			(enabled no)
			(sheetname "")
		)
		(fill yes
			(thermal_gap 0.5)
			(thermal_bridge_width 0.5)
			(island_removal_mode 0)
		)
		(polygon
			(pts
				(arc
					(start 300.212506 -379.88113)
					(mid 299.544486 -379.88113)
					(end 300.212506 -379.88113)
				)
			)
		)
	)
	(zone
		(layers "B.Cu" "In11.Cu" "In13.Cu" "In15.Cu")
		(hatch none 0.5)
		(connect_pads
			(clearance 0)
		)
		(min_thickness 0.25)
		(keepout
			(tracks not_allowed)
			(vias allowed)
			(pads allowed)
			(copperpour not_allowed)
			(footprints allowed)
		)
		(placement
			(enabled no)
			(sheetname "")
		)
		(fill yes
			(thermal_gap 0.5)
			(thermal_bridge_width 0.5)
			(island_removal_mode 0)
		)
		(polygon
			(pts
				(arc
					(start 391.049764 -254.204216)
					(mid 390.419844 -254.204216)
					(end 391.049764 -254.204216)
				)
			)
		)
	)
	(zone
		(layers "B.Cu" "In11.Cu" "In13.Cu" "In15.Cu")
		(hatch none 0.5)
		(connect_pads
			(clearance 0)
		)
		(min_thickness 0.25)
		(keepout
			(tracks not_allowed)
			(vias allowed)
			(pads allowed)
			(copperpour not_allowed)
			(footprints allowed)
		)
		(placement
			(enabled no)
			(sheetname "")
		)
		(fill yes
			(thermal_gap 0.5)
			(thermal_bridge_width 0.5)
			(island_removal_mode 0)
		)
		(polygon
			(pts
				(arc
					(start 141.229842 -249.344434)
					(mid 140.599922 -249.344434)
					(end 141.229842 -249.344434)
				)
			)
		)
	)
	(zone
		(layers "B.Cu" "In11.Cu" "In13.Cu" "In15.Cu")
		(hatch none 0.5)
		(connect_pads
			(clearance 0)
		)
		(min_thickness 0.25)
		(keepout
			(tracks not_allowed)
			(vias allowed)
			(pads allowed)
			(copperpour not_allowed)
			(footprints allowed)
		)
		(placement
			(enabled no)
			(sheetname "")
		)
		(fill yes
			(thermal_gap 0.5)
			(thermal_bridge_width 0.5)
			(island_removal_mode 0)
		)
		(polygon
			(pts
				(arc
					(start 330.42606 -225.85426)
					(mid 329.79614 -225.85426)
					(end 330.42606 -225.85426)
				)
			)
		)
	)
	(zone
		(layers "B.Cu" "In11.Cu" "In13.Cu" "In15.Cu")
		(hatch none 0.5)
		(connect_pads
			(clearance 0)
		)
		(min_thickness 0.25)
		(keepout
			(tracks not_allowed)
			(vias allowed)
			(pads allowed)
			(copperpour not_allowed)
			(footprints allowed)
		)
		(placement
			(enabled no)
			(sheetname "")
		)
		(fill yes
			(thermal_gap 0.5)
			(thermal_bridge_width 0.5)
			(island_removal_mode 0)
		)
		(polygon
			(pts
				(arc
					(start 147.73402 -385.31038)
					(mid 147.1041 -385.31038)
					(end 147.73402 -385.31038)
				)
			)
		)
	)
	(zone
		(layers "B.Cu" "In11.Cu" "In13.Cu" "In15.Cu")
		(hatch none 0.5)
		(connect_pads
			(clearance 0)
		)
		(min_thickness 0.25)
		(keepout
			(tracks not_allowed)
			(vias allowed)
			(pads allowed)
			(copperpour not_allowed)
			(footprints allowed)
		)
		(placement
			(enabled no)
			(sheetname "")
		)
		(fill yes
			(thermal_gap 0.5)
			(thermal_bridge_width 0.5)
			(island_removal_mode 0)
		)
		(polygon
			(pts
				(arc
					(start 142.639796 -238.814356)
					(mid 142.009876 -238.814356)
					(end 142.639796 -238.814356)
				)
			)
		)
	)
	(zone
		(layers "B.Cu" "In11.Cu" "In13.Cu" "In15.Cu")
		(hatch none 0.5)
		(connect_pads
			(clearance 0)
		)
		(min_thickness 0.25)
		(keepout
			(tracks not_allowed)
			(vias allowed)
			(pads allowed)
			(copperpour not_allowed)
			(footprints allowed)
		)
		(placement
			(enabled no)
			(sheetname "")
		)
		(fill yes
			(thermal_gap 0.5)
			(thermal_bridge_width 0.5)
			(island_removal_mode 0)
		)
		(polygon
			(pts
				(arc
					(start 141.999716 -290.286186)
					(mid 141.369796 -290.286186)
					(end 141.999716 -290.286186)
				)
			)
		)
	)
	(zone
		(layers "B.Cu" "In11.Cu" "In13.Cu" "In15.Cu")
		(hatch none 0.5)
		(connect_pads
			(clearance 0)
		)
		(min_thickness 0.25)
		(keepout
			(tracks not_allowed)
			(vias allowed)
			(pads allowed)
			(copperpour not_allowed)
			(footprints allowed)
		)
		(placement
			(enabled no)
			(sheetname "")
		)
		(fill yes
			(thermal_gap 0.5)
			(thermal_bridge_width 0.5)
			(island_removal_mode 0)
		)
		(polygon
			(pts
				(arc
					(start 59.306206 -389.467344)
					(mid 58.676286 -389.467344)
					(end 59.306206 -389.467344)
				)
			)
		)
	)
	(zone
		(layers "B.Cu" "In11.Cu" "In13.Cu" "In15.Cu")
		(hatch none 0.5)
		(connect_pads
			(clearance 0)
		)
		(min_thickness 0.25)
		(keepout
			(tracks not_allowed)
			(vias allowed)
			(pads allowed)
			(copperpour not_allowed)
			(footprints allowed)
		)
		(placement
			(enabled no)
			(sheetname "")
		)
		(fill yes
			(thermal_gap 0.5)
			(thermal_bridge_width 0.5)
			(island_removal_mode 0)
		)
		(polygon
			(pts
				(arc
					(start 60.506356 -389.467344)
					(mid 59.876436 -389.467344)
					(end 60.506356 -389.467344)
				)
			)
		)
	)
	(zone
		(layers "B.Cu" "In11.Cu" "In13.Cu" "In15.Cu")
		(hatch none 0.5)
		(connect_pads
			(clearance 0)
		)
		(min_thickness 0.25)
		(keepout
			(tracks not_allowed)
			(vias allowed)
			(pads allowed)
			(copperpour not_allowed)
			(footprints allowed)
		)
		(placement
			(enabled no)
			(sheetname "")
		)
		(fill yes
			(thermal_gap 0.5)
			(thermal_bridge_width 0.5)
			(island_removal_mode 0)
		)
		(polygon
			(pts
				(arc
					(start 389.16991 -239.624108)
					(mid 388.53999 -239.624108)
					(end 389.16991 -239.624108)
				)
			)
		)
	)
	(zone
		(layers "B.Cu" "In11.Cu" "In13.Cu" "In15.Cu")
		(hatch none 0.5)
		(connect_pads
			(clearance 0)
		)
		(min_thickness 0.25)
		(keepout
			(tracks not_allowed)
			(vias allowed)
			(pads allowed)
			(copperpour not_allowed)
			(footprints allowed)
		)
		(placement
			(enabled no)
			(sheetname "")
		)
		(fill yes
			(thermal_gap 0.5)
			(thermal_bridge_width 0.5)
			(island_removal_mode 0)
		)
		(polygon
			(pts
				(arc
					(start 104.876092 -286.23641)
					(mid 104.246172 -286.23641)
					(end 104.876092 -286.23641)
				)
			)
		)
	)
	(zone
		(layers "B.Cu" "In11.Cu" "In13.Cu" "In15.Cu")
		(hatch none 0.5)
		(connect_pads
			(clearance 0)
		)
		(min_thickness 0.25)
		(keepout
			(tracks not_allowed)
			(vias allowed)
			(pads allowed)
			(copperpour not_allowed)
			(footprints allowed)
		)
		(placement
			(enabled no)
			(sheetname "")
		)
		(fill yes
			(thermal_gap 0.5)
			(thermal_bridge_width 0.5)
			(island_removal_mode 0)
		)
		(polygon
			(pts
				(arc
					(start 155.333954 -386.003292)
					(mid 154.704034 -386.003292)
					(end 155.333954 -386.003292)
				)
			)
		)
	)
	(zone
		(layers "B.Cu" "In11.Cu" "In13.Cu" "In15.Cu")
		(hatch none 0.5)
		(connect_pads
			(clearance 0)
		)
		(min_thickness 0.25)
		(keepout
			(tracks not_allowed)
			(vias allowed)
			(pads allowed)
			(copperpour not_allowed)
			(footprints allowed)
		)
		(placement
			(enabled no)
			(sheetname "")
		)
		(fill yes
			(thermal_gap 0.5)
			(thermal_bridge_width 0.5)
			(island_removal_mode 0)
		)
		(polygon
			(pts
				(arc
					(start 141.999716 -282.18638)
					(mid 141.369796 -282.18638)
					(end 141.999716 -282.18638)
				)
			)
		)
	)
	(zone
		(layers "B.Cu" "In11.Cu" "In13.Cu" "In15.Cu")
		(hatch none 0.5)
		(connect_pads
			(clearance 0)
		)
		(min_thickness 0.25)
		(keepout
			(tracks not_allowed)
			(vias allowed)
			(pads allowed)
			(copperpour not_allowed)
			(footprints allowed)
		)
		(placement
			(enabled no)
			(sheetname "")
		)
		(fill yes
			(thermal_gap 0.5)
			(thermal_bridge_width 0.5)
			(island_removal_mode 0)
		)
		(polygon
			(pts
				(arc
					(start 273.426174 -295.085008)
					(mid 272.758154 -295.085008)
					(end 273.426174 -295.085008)
				)
			)
		)
	)
	(zone
		(layers "B.Cu" "In11.Cu" "In13.Cu" "In15.Cu")
		(hatch none 0.5)
		(connect_pads
			(clearance 0)
		)
		(min_thickness 0.25)
		(keepout
			(tracks not_allowed)
			(vias allowed)
			(pads allowed)
			(copperpour not_allowed)
			(footprints allowed)
		)
		(placement
			(enabled no)
			(sheetname "")
		)
		(fill yes
			(thermal_gap 0.5)
			(thermal_bridge_width 0.5)
			(island_removal_mode 0)
		)
		(polygon
			(pts
				(arc
					(start 79.624174 -404.46452)
					(mid 78.956154 -404.46452)
					(end 79.624174 -404.46452)
				)
			)
		)
	)
	(zone
		(layers "B.Cu" "In11.Cu" "In13.Cu" "In15.Cu")
		(hatch none 0.5)
		(connect_pads
			(clearance 0)
		)
		(min_thickness 0.25)
		(keepout
			(tracks not_allowed)
			(vias allowed)
			(pads allowed)
			(copperpour not_allowed)
			(footprints allowed)
		)
		(placement
			(enabled no)
			(sheetname "")
		)
		(fill yes
			(thermal_gap 0.5)
			(thermal_bridge_width 0.5)
			(island_removal_mode 0)
		)
		(polygon
			(pts
				(arc
					(start 342.633808 -397.156432)
					(mid 342.003888 -397.156432)
					(end 342.633808 -397.156432)
				)
			)
		)
	)
	(zone
		(layers "B.Cu" "In11.Cu" "In13.Cu" "In15.Cu")
		(hatch none 0.5)
		(connect_pads
			(clearance 0)
		)
		(min_thickness 0.25)
		(keepout
			(tracks not_allowed)
			(vias allowed)
			(pads allowed)
			(copperpour not_allowed)
			(footprints allowed)
		)
		(placement
			(enabled no)
			(sheetname "")
		)
		(fill yes
			(thermal_gap 0.5)
			(thermal_bridge_width 0.5)
			(island_removal_mode 0)
		)
		(polygon
			(pts
				(arc
					(start 370.66982 -284.616144)
					(mid 370.0399 -284.616144)
					(end 370.66982 -284.616144)
				)
			)
		)
	)
	(zone
		(layers "B.Cu" "In11.Cu" "In13.Cu" "In15.Cu")
		(hatch none 0.5)
		(connect_pads
			(clearance 0)
		)
		(min_thickness 0.25)
		(keepout
			(tracks not_allowed)
			(vias allowed)
			(pads allowed)
			(copperpour not_allowed)
			(footprints allowed)
		)
		(placement
			(enabled no)
			(sheetname "")
		)
		(fill yes
			(thermal_gap 0.5)
			(thermal_bridge_width 0.5)
			(island_removal_mode 0)
		)
		(polygon
			(pts
				(arc
					(start 349.056198 -284.616144)
					(mid 348.426278 -284.616144)
					(end 349.056198 -284.616144)
				)
			)
		)
	)
	(zone
		(layers "B.Cu" "In11.Cu" "In13.Cu" "In15.Cu")
		(hatch none 0.5)
		(connect_pads
			(clearance 0)
		)
		(min_thickness 0.25)
		(keepout
			(tracks not_allowed)
			(vias allowed)
			(pads allowed)
			(copperpour not_allowed)
			(footprints allowed)
		)
		(placement
			(enabled no)
			(sheetname "")
		)
		(fill yes
			(thermal_gap 0.5)
			(thermal_bridge_width 0.5)
			(island_removal_mode 0)
		)
		(polygon
			(pts
				(arc
					(start 420.534084 -393.69238)
					(mid 419.904164 -393.69238)
					(end 420.534084 -393.69238)
				)
			)
		)
	)
	(zone
		(layers "B.Cu" "In11.Cu" "In13.Cu" "In15.Cu")
		(hatch none 0.5)
		(connect_pads
			(clearance 0)
		)
		(min_thickness 0.25)
		(keepout
			(tracks not_allowed)
			(vias allowed)
			(pads allowed)
			(copperpour not_allowed)
			(footprints allowed)
		)
		(placement
			(enabled no)
			(sheetname "")
		)
		(fill yes
			(thermal_gap 0.5)
			(thermal_bridge_width 0.5)
			(island_removal_mode 0)
		)
		(polygon
			(pts
				(arc
					(start 442.87821 -291.684964)
					(mid 442.21019 -291.684964)
					(end 442.87821 -291.684964)
				)
			)
		)
	)
	(zone
		(layers "B.Cu" "In11.Cu" "In13.Cu" "In15.Cu")
		(hatch none 0.5)
		(connect_pads
			(clearance 0)
		)
		(min_thickness 0.25)
		(keepout
			(tracks not_allowed)
			(vias allowed)
			(pads allowed)
			(copperpour not_allowed)
			(footprints allowed)
		)
		(placement
			(enabled no)
			(sheetname "")
		)
		(fill yes
			(thermal_gap 0.5)
			(thermal_bridge_width 0.5)
			(island_removal_mode 0)
		)
		(polygon
			(pts
				(arc
					(start 142.93977 -275.706332)
					(mid 142.30985 -275.706332)
					(end 142.93977 -275.706332)
				)
			)
		)
	)
	(zone
		(layers "B.Cu" "In11.Cu" "In13.Cu" "In15.Cu")
		(hatch none 0.5)
		(connect_pads
			(clearance 0)
		)
		(min_thickness 0.25)
		(keepout
			(tracks not_allowed)
			(vias allowed)
			(pads allowed)
			(copperpour not_allowed)
			(footprints allowed)
		)
		(placement
			(enabled no)
			(sheetname "")
		)
		(fill yes
			(thermal_gap 0.5)
			(thermal_bridge_width 0.5)
			(island_removal_mode 0)
		)
		(polygon
			(pts
				(arc
					(start 389.16991 -254.204216)
					(mid 388.53999 -254.204216)
					(end 389.16991 -254.204216)
				)
			)
		)
	)
	(zone
		(layers "B.Cu" "In11.Cu" "In13.Cu" "In15.Cu")
		(hatch none 0.5)
		(connect_pads
			(clearance 0)
		)
		(min_thickness 0.25)
		(keepout
			(tracks not_allowed)
			(vias allowed)
			(pads allowed)
			(copperpour not_allowed)
			(footprints allowed)
		)
		(placement
			(enabled no)
			(sheetname "")
		)
		(fill yes
			(thermal_gap 0.5)
			(thermal_bridge_width 0.5)
			(island_removal_mode 0)
		)
		(polygon
			(pts
				(arc
					(start 365.02975 -286.236156)
					(mid 364.39983 -286.236156)
					(end 365.02975 -286.236156)
				)
			)
		)
	)
	(zone
		(layers "B.Cu" "In11.Cu" "In13.Cu" "In15.Cu")
		(hatch none 0.5)
		(connect_pads
			(clearance 0)
		)
		(min_thickness 0.25)
		(keepout
			(tracks not_allowed)
			(vias allowed)
			(pads allowed)
			(copperpour not_allowed)
			(footprints allowed)
		)
		(placement
			(enabled no)
			(sheetname "")
		)
		(fill yes
			(thermal_gap 0.5)
			(thermal_bridge_width 0.5)
			(island_removal_mode 0)
		)
		(polygon
			(pts
				(arc
					(start 277.526242 -311.23509)
					(mid 276.858222 -311.23509)
					(end 277.526242 -311.23509)
				)
			)
		)
	)
	(zone
		(layers "B.Cu" "In11.Cu" "In13.Cu" "In15.Cu")
		(hatch none 0.5)
		(connect_pads
			(clearance 0)
		)
		(min_thickness 0.25)
		(keepout
			(tracks not_allowed)
			(vias allowed)
			(pads allowed)
			(copperpour not_allowed)
			(footprints allowed)
		)
		(placement
			(enabled no)
			(sheetname "")
		)
		(fill yes
			(thermal_gap 0.5)
			(thermal_bridge_width 0.5)
			(island_removal_mode 0)
		)
		(polygon
			(pts
				(arc
					(start 379.606302 -397.156432)
					(mid 378.976382 -397.156432)
					(end 379.606302 -397.156432)
				)
			)
		)
	)
	(zone
		(layers "B.Cu" "In11.Cu" "In13.Cu" "In15.Cu")
		(hatch none 0.5)
		(connect_pads
			(clearance 0)
		)
		(min_thickness 0.25)
		(keepout
			(tracks not_allowed)
			(vias allowed)
			(pads allowed)
			(copperpour not_allowed)
			(footprints allowed)
		)
		(placement
			(enabled no)
			(sheetname "")
		)
		(fill yes
			(thermal_gap 0.5)
			(thermal_bridge_width 0.5)
			(island_removal_mode 0)
		)
		(polygon
			(pts
				(arc
					(start 355.636068 -286.236156)
					(mid 355.006148 -286.236156)
					(end 355.636068 -286.236156)
				)
			)
		)
	)
	(zone
		(layers "B.Cu" "In11.Cu" "In13.Cu" "In15.Cu")
		(hatch none 0.5)
		(connect_pads
			(clearance 0)
		)
		(min_thickness 0.25)
		(keepout
			(tracks not_allowed)
			(vias allowed)
			(pads allowed)
			(copperpour not_allowed)
			(footprints allowed)
		)
		(placement
			(enabled no)
			(sheetname "")
		)
		(fill yes
			(thermal_gap 0.5)
			(thermal_bridge_width 0.5)
			(island_removal_mode 0)
		)
		(polygon
			(pts
				(arc
					(start 149.333966 -386.003292)
					(mid 148.704046 -386.003292)
					(end 149.333966 -386.003292)
				)
			)
		)
	)
	(zone
		(layers "B.Cu" "In11.Cu" "In13.Cu" "In15.Cu")
		(hatch none 0.5)
		(connect_pads
			(clearance 0)
		)
		(min_thickness 0.25)
		(keepout
			(tracks not_allowed)
			(vias allowed)
			(pads allowed)
			(copperpour not_allowed)
			(footprints allowed)
		)
		(placement
			(enabled no)
			(sheetname "")
		)
		(fill yes
			(thermal_gap 0.5)
			(thermal_bridge_width 0.5)
			(island_removal_mode 0)
		)
		(polygon
			(pts
				(arc
					(start 446.978278 -217.73515)
					(mid 446.310258 -217.73515)
					(end 446.978278 -217.73515)
				)
			)
		)
	)
	(zone
		(layers "B.Cu" "In11.Cu" "In13.Cu" "In15.Cu")
		(hatch none 0.5)
		(connect_pads
			(clearance 0)
		)
		(min_thickness 0.25)
		(keepout
			(tracks not_allowed)
			(vias allowed)
			(pads allowed)
			(copperpour not_allowed)
			(footprints allowed)
		)
		(placement
			(enabled no)
			(sheetname "")
		)
		(fill yes
			(thermal_gap 0.5)
			(thermal_bridge_width 0.5)
			(island_removal_mode 0)
		)
		(polygon
			(pts
				(arc
					(start 199.03821 -247.485408)
					(mid 198.37019 -247.485408)
					(end 199.03821 -247.485408)
				)
			)
		)
	)
	(zone
		(layers "B.Cu" "In11.Cu" "In13.Cu" "In15.Cu")
		(hatch none 0.5)
		(connect_pads
			(clearance 0)
		)
		(min_thickness 0.25)
		(keepout
			(tracks not_allowed)
			(vias allowed)
			(pads allowed)
			(copperpour not_allowed)
			(footprints allowed)
		)
		(placement
			(enabled no)
			(sheetname "")
		)
		(fill yes
			(thermal_gap 0.5)
			(thermal_bridge_width 0.5)
			(island_removal_mode 0)
		)
		(polygon
			(pts
				(arc
					(start 442.87821 -295.935146)
					(mid 442.21019 -295.935146)
					(end 442.87821 -295.935146)
				)
			)
		)
	)
	(zone
		(layers "B.Cu" "In11.Cu" "In13.Cu" "In15.Cu")
		(hatch none 0.5)
		(connect_pads
			(clearance 0)
		)
		(min_thickness 0.25)
		(keepout
			(tracks not_allowed)
			(vias allowed)
			(pads allowed)
			(copperpour not_allowed)
			(footprints allowed)
		)
		(placement
			(enabled no)
			(sheetname "")
		)
		(fill yes
			(thermal_gap 0.5)
			(thermal_bridge_width 0.5)
			(island_removal_mode 0)
		)
		(polygon
			(pts
				(arc
					(start 119.90959 -282.996386)
					(mid 119.27967 -282.996386)
					(end 119.90959 -282.996386)
				)
			)
		)
	)
	(zone
		(layers "B.Cu" "In11.Cu" "In13.Cu" "In15.Cu")
		(hatch none 0.5)
		(connect_pads
			(clearance 0)
		)
		(min_thickness 0.25)
		(keepout
			(tracks not_allowed)
			(vias allowed)
			(pads allowed)
			(copperpour not_allowed)
			(footprints allowed)
		)
		(placement
			(enabled no)
			(sheetname "")
		)
		(fill yes
			(thermal_gap 0.5)
			(thermal_bridge_width 0.5)
			(island_removal_mode 0)
		)
		(polygon
			(pts
				(arc
					(start 82.785966 -291.906198)
					(mid 82.156046 -291.906198)
					(end 82.785966 -291.906198)
				)
			)
		)
	)
	(zone
		(layers "B.Cu" "In11.Cu" "In13.Cu" "In15.Cu")
		(hatch none 0.5)
		(connect_pads
			(clearance 0)
		)
		(min_thickness 0.25)
		(keepout
			(tracks not_allowed)
			(vias allowed)
			(pads allowed)
			(copperpour not_allowed)
			(footprints allowed)
		)
		(placement
			(enabled no)
			(sheetname "")
		)
		(fill yes
			(thermal_gap 0.5)
			(thermal_bridge_width 0.5)
			(island_removal_mode 0)
		)
		(polygon
			(pts
				(arc
					(start 199.03821 -275.53539)
					(mid 198.37019 -275.53539)
					(end 199.03821 -275.53539)
				)
			)
		)
	)
	(zone
		(layers "B.Cu" "In11.Cu" "In13.Cu" "In15.Cu")
		(hatch none 0.5)
		(connect_pads
			(clearance 0)
		)
		(min_thickness 0.25)
		(keepout
			(tracks not_allowed)
			(vias allowed)
			(pads allowed)
			(copperpour not_allowed)
			(footprints allowed)
		)
		(placement
			(enabled no)
			(sheetname "")
		)
		(fill yes
			(thermal_gap 0.5)
			(thermal_bridge_width 0.5)
			(island_removal_mode 0)
		)
		(polygon
			(pts
				(arc
					(start 390.879838 -283.806138)
					(mid 390.249918 -283.806138)
					(end 390.879838 -283.806138)
				)
			)
		)
	)
	(zone
		(layers "B.Cu" "In11.Cu" "In13.Cu" "In15.Cu")
		(hatch none 0.5)
		(connect_pads
			(clearance 0)
		)
		(min_thickness 0.25)
		(keepout
			(tracks not_allowed)
			(vias allowed)
			(pads allowed)
			(copperpour not_allowed)
			(footprints allowed)
		)
		(placement
			(enabled no)
			(sheetname "")
		)
		(fill yes
			(thermal_gap 0.5)
			(thermal_bridge_width 0.5)
			(island_removal_mode 0)
		)
		(polygon
			(pts
				(arc
					(start 94.82201 -214.128858)
					(mid 94.15399 -214.128858)
					(end 94.82201 -214.128858)
				)
			)
		)
	)
	(zone
		(layers "B.Cu" "In11.Cu" "In13.Cu" "In15.Cu")
		(hatch none 0.5)
		(connect_pads
			(clearance 0)
		)
		(min_thickness 0.25)
		(keepout
			(tracks not_allowed)
			(vias allowed)
			(pads allowed)
			(copperpour not_allowed)
			(footprints allowed)
		)
		(placement
			(enabled no)
			(sheetname "")
		)
		(fill yes
			(thermal_gap 0.5)
			(thermal_bridge_width 0.5)
			(island_removal_mode 0)
		)
		(polygon
			(pts
				(arc
					(start 390.579864 -242.054126)
					(mid 389.949944 -242.054126)
					(end 390.579864 -242.054126)
				)
			)
		)
	)
	(zone
		(layers "B.Cu" "In11.Cu" "In13.Cu" "In15.Cu")
		(hatch none 0.5)
		(connect_pads
			(clearance 0)
		)
		(min_thickness 0.25)
		(keepout
			(tracks not_allowed)
			(vias allowed)
			(pads allowed)
			(copperpour not_allowed)
			(footprints allowed)
		)
		(placement
			(enabled no)
			(sheetname "")
		)
		(fill yes
			(thermal_gap 0.5)
			(thermal_bridge_width 0.5)
			(island_removal_mode 0)
		)
		(polygon
			(pts
				(arc
					(start 277.526242 -267.885164)
					(mid 276.858222 -267.885164)
					(end 277.526242 -267.885164)
				)
			)
		)
	)
	(zone
		(layers "B.Cu" "In11.Cu" "In13.Cu" "In15.Cu")
		(hatch none 0.5)
		(connect_pads
			(clearance 0)
		)
		(min_thickness 0.25)
		(keepout
			(tracks not_allowed)
			(vias allowed)
			(pads allowed)
			(copperpour not_allowed)
			(footprints allowed)
		)
		(placement
			(enabled no)
			(sheetname "")
		)
		(fill yes
			(thermal_gap 0.5)
			(thermal_bridge_width 0.5)
			(island_removal_mode 0)
		)
		(polygon
			(pts
				(arc
					(start 141.699742 -238.814356)
					(mid 141.069822 -238.814356)
					(end 141.699742 -238.814356)
				)
			)
		)
	)
	(zone
		(layers "B.Cu" "In11.Cu" "In13.Cu" "In15.Cu")
		(hatch none 0.5)
		(connect_pads
			(clearance 0)
		)
		(min_thickness 0.25)
		(keepout
			(tracks not_allowed)
			(vias allowed)
			(pads allowed)
			(copperpour not_allowed)
			(footprints allowed)
		)
		(placement
			(enabled no)
			(sheetname "")
		)
		(fill yes
			(thermal_gap 0.5)
			(thermal_bridge_width 0.5)
			(island_removal_mode 0)
		)
		(polygon
			(pts
				(arc
					(start 107.696 -282.996386)
					(mid 107.06608 -282.996386)
					(end 107.696 -282.996386)
				)
			)
		)
	)
	(zone
		(layers "B.Cu" "In11.Cu" "In13.Cu" "In15.Cu")
		(hatch none 0.5)
		(connect_pads
			(clearance 0)
		)
		(min_thickness 0.25)
		(keepout
			(tracks not_allowed)
			(vias allowed)
			(pads allowed)
			(copperpour not_allowed)
			(footprints allowed)
		)
		(placement
			(enabled no)
			(sheetname "")
		)
		(fill yes
			(thermal_gap 0.5)
			(thermal_bridge_width 0.5)
			(island_removal_mode 0)
		)
		(polygon
			(pts
				(arc
					(start 388.136892 -428.28972)
					(mid 387.3627 -428.28972)
					(end 388.136892 -428.28972)
				)
			)
		)
	)
	(zone
		(layers "B.Cu" "In11.Cu" "In13.Cu" "In15.Cu")
		(hatch none 0.5)
		(connect_pads
			(clearance 0)
		)
		(min_thickness 0.25)
		(keepout
			(tracks not_allowed)
			(vias allowed)
			(pads allowed)
			(copperpour not_allowed)
			(footprints allowed)
		)
		(placement
			(enabled no)
			(sheetname "")
		)
		(fill yes
			(thermal_gap 0.5)
			(thermal_bridge_width 0.5)
			(island_removal_mode 0)
		)
		(polygon
			(pts
				(arc
					(start 364.729776 -238.004096)
					(mid 364.099856 -238.004096)
					(end 364.729776 -238.004096)
				)
			)
		)
	)
	(zone
		(layers "B.Cu" "In11.Cu" "In13.Cu" "In15.Cu")
		(hatch none 0.5)
		(connect_pads
			(clearance 0)
		)
		(min_thickness 0.25)
		(keepout
			(tracks not_allowed)
			(vias allowed)
			(pads allowed)
			(copperpour not_allowed)
			(footprints allowed)
		)
		(placement
			(enabled no)
			(sheetname "")
		)
		(fill yes
			(thermal_gap 0.5)
			(thermal_bridge_width 0.5)
			(island_removal_mode 0)
		)
		(polygon
			(pts
				(arc
					(start 194.938142 -235.585254)
					(mid 194.270122 -235.585254)
					(end 194.938142 -235.585254)
				)
			)
		)
	)
	(zone
		(layers "B.Cu" "In11.Cu" "In13.Cu" "In15.Cu")
		(hatch none 0.5)
		(connect_pads
			(clearance 0)
		)
		(min_thickness 0.25)
		(keepout
			(tracks not_allowed)
			(vias allowed)
			(pads allowed)
			(copperpour not_allowed)
			(footprints allowed)
		)
		(placement
			(enabled no)
			(sheetname "")
		)
		(fill yes
			(thermal_gap 0.5)
			(thermal_bridge_width 0.5)
			(island_removal_mode 0)
		)
		(polygon
			(pts
				(arc
					(start 86.037166 -428.28972)
					(mid 85.262974 -428.28972)
					(end 86.037166 -428.28972)
				)
			)
		)
	)
	(zone
		(layers "B.Cu" "In11.Cu" "In13.Cu" "In15.Cu")
		(hatch none 0.5)
		(connect_pads
			(clearance 0)
		)
		(min_thickness 0.25)
		(keepout
			(tracks not_allowed)
			(vias allowed)
			(pads allowed)
			(copperpour not_allowed)
			(footprints allowed)
		)
		(placement
			(enabled no)
			(sheetname "")
		)
		(fill yes
			(thermal_gap 0.5)
			(thermal_bridge_width 0.5)
			(island_removal_mode 0)
		)
		(polygon
			(pts
				(arc
					(start 25.486106 -282.335224)
					(mid 24.818086 -282.335224)
					(end 25.486106 -282.335224)
				)
			)
		)
	)
	(zone
		(layers "B.Cu" "In11.Cu" "In13.Cu" "In15.Cu")
		(hatch none 0.5)
		(connect_pads
			(clearance 0)
		)
		(min_thickness 0.25)
		(keepout
			(tracks not_allowed)
			(vias allowed)
			(pads allowed)
			(copperpour not_allowed)
			(footprints allowed)
		)
		(placement
			(enabled no)
			(sheetname "")
		)
		(fill yes
			(thermal_gap 0.5)
			(thermal_bridge_width 0.5)
			(island_removal_mode 0)
		)
		(polygon
			(pts
				(arc
					(start 82.785966 -282.18638)
					(mid 82.156046 -282.18638)
					(end 82.785966 -282.18638)
				)
			)
		)
	)
	(zone
		(layers "B.Cu" "In11.Cu" "In13.Cu" "In15.Cu")
		(hatch none 0.5)
		(connect_pads
			(clearance 0)
		)
		(min_thickness 0.25)
		(keepout
			(tracks not_allowed)
			(vias allowed)
			(pads allowed)
			(copperpour not_allowed)
			(footprints allowed)
		)
		(placement
			(enabled no)
			(sheetname "")
		)
		(fill yes
			(thermal_gap 0.5)
			(thermal_bridge_width 0.5)
			(island_removal_mode 0)
		)
		(polygon
			(pts
				(arc
					(start 141.529816 -282.996386)
					(mid 140.899896 -282.996386)
					(end 141.529816 -282.996386)
				)
			)
		)
	)
	(zone
		(layers "B.Cu" "In11.Cu" "In13.Cu" "In15.Cu")
		(hatch none 0.5)
		(connect_pads
			(clearance 0)
		)
		(min_thickness 0.25)
		(keepout
			(tracks not_allowed)
			(vias allowed)
			(pads allowed)
			(copperpour not_allowed)
			(footprints allowed)
		)
		(placement
			(enabled no)
			(sheetname "")
		)
		(fill yes
			(thermal_gap 0.5)
			(thermal_bridge_width 0.5)
			(island_removal_mode 0)
		)
		(polygon
			(pts
				(arc
					(start 446.978278 -197.33514)
					(mid 446.310258 -197.33514)
					(end 446.978278 -197.33514)
				)
			)
		)
	)
	(zone
		(layers "B.Cu" "In11.Cu" "In13.Cu" "In15.Cu")
		(hatch none 0.5)
		(connect_pads
			(clearance 0)
		)
		(min_thickness 0.25)
		(keepout
			(tracks not_allowed)
			(vias allowed)
			(pads allowed)
			(copperpour not_allowed)
			(footprints allowed)
		)
		(placement
			(enabled no)
			(sheetname "")
		)
		(fill yes
			(thermal_gap 0.5)
			(thermal_bridge_width 0.5)
			(island_removal_mode 0)
		)
		(polygon
			(pts
				(arc
					(start 442.87821 -272.984976)
					(mid 442.21019 -272.984976)
					(end 442.87821 -272.984976)
				)
			)
		)
	)
	(zone
		(layers "B.Cu" "In11.Cu" "In13.Cu" "In15.Cu")
		(hatch none 0.5)
		(connect_pads
			(clearance 0)
		)
		(min_thickness 0.25)
		(keepout
			(tracks not_allowed)
			(vias allowed)
			(pads allowed)
			(copperpour not_allowed)
			(footprints allowed)
		)
		(placement
			(enabled no)
			(sheetname "")
		)
		(fill yes
			(thermal_gap 0.5)
			(thermal_bridge_width 0.5)
			(island_removal_mode 0)
		)
		(polygon
			(pts
				(arc
					(start 25.486106 -304.435256)
					(mid 24.818086 -304.435256)
					(end 25.486106 -304.435256)
				)
			)
		)
	)
	(zone
		(layers "B.Cu" "In11.Cu" "In13.Cu" "In15.Cu")
		(hatch none 0.5)
		(connect_pads
			(clearance 0)
		)
		(min_thickness 0.25)
		(keepout
			(tracks not_allowed)
			(vias allowed)
			(pads allowed)
			(copperpour not_allowed)
			(footprints allowed)
		)
		(placement
			(enabled no)
			(sheetname "")
		)
		(fill yes
			(thermal_gap 0.5)
			(thermal_bridge_width 0.5)
			(island_removal_mode 0)
		)
		(polygon
			(pts
				(arc
					(start 142.93977 -288.666174)
					(mid 142.30985 -288.666174)
					(end 142.93977 -288.666174)
				)
			)
		)
	)
	(zone
		(layers "B.Cu" "In11.Cu" "In13.Cu" "In15.Cu")
		(hatch none 0.5)
		(connect_pads
			(clearance 0)
		)
		(min_thickness 0.25)
		(keepout
			(tracks not_allowed)
			(vias allowed)
			(pads allowed)
			(copperpour not_allowed)
			(footprints allowed)
		)
		(placement
			(enabled no)
			(sheetname "")
		)
		(fill yes
			(thermal_gap 0.5)
			(thermal_bridge_width 0.5)
			(island_removal_mode 0)
		)
		(polygon
			(pts
				(arc
					(start 330.42606 -230.714296)
					(mid 329.79614 -230.714296)
					(end 330.42606 -230.714296)
				)
			)
		)
	)
	(zone
		(layers "B.Cu" "In11.Cu" "In13.Cu" "In15.Cu")
		(hatch none 0.5)
		(connect_pads
			(clearance 0)
		)
		(min_thickness 0.25)
		(keepout
			(tracks not_allowed)
			(vias allowed)
			(pads allowed)
			(copperpour not_allowed)
			(footprints allowed)
		)
		(placement
			(enabled no)
			(sheetname "")
		)
		(fill yes
			(thermal_gap 0.5)
			(thermal_bridge_width 0.5)
			(island_removal_mode 0)
		)
		(polygon
			(pts
				(arc
					(start 363.319822 -242.054126)
					(mid 362.689902 -242.054126)
					(end 363.319822 -242.054126)
				)
			)
		)
	)
	(zone
		(layers "B.Cu" "In11.Cu" "In13.Cu" "In15.Cu")
		(hatch none 0.5)
		(connect_pads
			(clearance 0)
		)
		(min_thickness 0.25)
		(keepout
			(tracks not_allowed)
			(vias allowed)
			(pads allowed)
			(copperpour not_allowed)
			(footprints allowed)
		)
		(placement
			(enabled no)
			(sheetname "")
		)
		(fill yes
			(thermal_gap 0.5)
			(thermal_bridge_width 0.5)
			(island_removal_mode 0)
		)
		(polygon
			(pts
				(arc
					(start 29.586174 -289.135312)
					(mid 28.918154 -289.135312)
					(end 29.586174 -289.135312)
				)
			)
		)
	)
	(zone
		(layers "B.Cu" "In11.Cu" "In13.Cu" "In15.Cu")
		(hatch none 0.5)
		(connect_pads
			(clearance 0)
		)
		(min_thickness 0.25)
		(keepout
			(tracks not_allowed)
			(vias allowed)
			(pads allowed)
			(copperpour not_allowed)
			(footprints allowed)
		)
		(placement
			(enabled no)
			(sheetname "")
		)
		(fill yes
			(thermal_gap 0.5)
			(thermal_bridge_width 0.5)
			(island_removal_mode 0)
		)
		(polygon
			(pts
				(arc
					(start 94.82201 -214.992458)
					(mid 94.15399 -214.992458)
					(end 94.82201 -214.992458)
				)
			)
		)
	)
	(zone
		(layers "B.Cu" "In11.Cu" "In13.Cu" "In15.Cu")
		(hatch none 0.5)
		(connect_pads
			(clearance 0)
		)
		(min_thickness 0.25)
		(keepout
			(tracks not_allowed)
			(vias allowed)
			(pads allowed)
			(copperpour not_allowed)
			(footprints allowed)
		)
		(placement
			(enabled no)
			(sheetname "")
		)
		(fill yes
			(thermal_gap 0.5)
			(thermal_bridge_width 0.5)
			(island_removal_mode 0)
		)
		(polygon
			(pts
				(arc
					(start 329.31608 -282.996132)
					(mid 328.68616 -282.996132)
					(end 329.31608 -282.996132)
				)
			)
		)
	)
	(zone
		(layers "B.Cu" "In11.Cu" "In13.Cu" "In15.Cu")
		(hatch none 0.5)
		(connect_pads
			(clearance 0)
		)
		(min_thickness 0.25)
		(keepout
			(tracks not_allowed)
			(vias allowed)
			(pads allowed)
			(copperpour not_allowed)
			(footprints allowed)
		)
		(placement
			(enabled no)
			(sheetname "")
		)
		(fill yes
			(thermal_gap 0.5)
			(thermal_bridge_width 0.5)
			(island_removal_mode 0)
		)
		(polygon
			(pts
				(arc
					(start 446.978278 -264.48512)
					(mid 446.310258 -264.48512)
					(end 446.978278 -264.48512)
				)
			)
		)
	)
	(zone
		(layers "B.Cu" "In11.Cu" "In13.Cu" "In15.Cu")
		(hatch none 0.5)
		(connect_pads
			(clearance 0)
		)
		(min_thickness 0.25)
		(keepout
			(tracks not_allowed)
			(vias allowed)
			(pads allowed)
			(copperpour not_allowed)
			(footprints allowed)
		)
		(placement
			(enabled no)
			(sheetname "")
		)
		(fill yes
			(thermal_gap 0.5)
			(thermal_bridge_width 0.5)
			(island_removal_mode 0)
		)
		(polygon
			(pts
				(arc
					(start 194.938142 -220.28531)
					(mid 194.270122 -220.28531)
					(end 194.938142 -220.28531)
				)
			)
		)
	)
	(zone
		(layers "B.Cu" "In11.Cu" "In13.Cu" "In15.Cu")
		(hatch none 0.5)
		(connect_pads
			(clearance 0)
		)
		(min_thickness 0.25)
		(keepout
			(tracks not_allowed)
			(vias allowed)
			(pads allowed)
			(copperpour not_allowed)
			(footprints allowed)
		)
		(placement
			(enabled no)
			(sheetname "")
		)
		(fill yes
			(thermal_gap 0.5)
			(thermal_bridge_width 0.5)
			(island_removal_mode 0)
		)
		(polygon
			(pts
				(arc
					(start 143.40967 -270.03629)
					(mid 142.77975 -270.03629)
					(end 143.40967 -270.03629)
				)
			)
		)
	)
	(zone
		(layers "B.Cu" "In11.Cu" "In13.Cu" "In15.Cu")
		(hatch none 0.5)
		(connect_pads
			(clearance 0)
		)
		(min_thickness 0.25)
		(keepout
			(tracks not_allowed)
			(vias allowed)
			(pads allowed)
			(copperpour not_allowed)
			(footprints allowed)
		)
		(placement
			(enabled no)
			(sheetname "")
		)
		(fill yes
			(thermal_gap 0.5)
			(thermal_bridge_width 0.5)
			(island_removal_mode 0)
		)
		(polygon
			(pts
				(arc
					(start 29.586174 -210.085432)
					(mid 28.918154 -210.085432)
					(end 29.586174 -210.085432)
				)
			)
		)
	)
	(zone
		(layers "B.Cu" "In11.Cu" "In13.Cu" "In15.Cu")
		(hatch none 0.5)
		(connect_pads
			(clearance 0)
		)
		(min_thickness 0.25)
		(keepout
			(tracks not_allowed)
			(vias allowed)
			(pads allowed)
			(copperpour not_allowed)
			(footprints allowed)
		)
		(placement
			(enabled no)
			(sheetname "")
		)
		(fill yes
			(thermal_gap 0.5)
			(thermal_bridge_width 0.5)
			(island_removal_mode 0)
		)
		(polygon
			(pts
				(arc
					(start 29.586174 -240.68532)
					(mid 28.918154 -240.68532)
					(end 29.586174 -240.68532)
				)
			)
		)
	)
	(zone
		(layers "B.Cu" "In11.Cu" "In13.Cu" "In15.Cu")
		(hatch none 0.5)
		(connect_pads
			(clearance 0)
		)
		(min_thickness 0.25)
		(keepout
			(tracks not_allowed)
			(vias allowed)
			(pads allowed)
			(copperpour not_allowed)
			(footprints allowed)
		)
		(placement
			(enabled no)
			(sheetname "")
		)
		(fill yes
			(thermal_gap 0.5)
			(thermal_bridge_width 0.5)
			(island_removal_mode 0)
		)
		(polygon
			(pts
				(arc
					(start 82.485992 -235.574332)
					(mid 81.856072 -235.574332)
					(end 82.485992 -235.574332)
				)
			)
		)
	)
	(zone
		(layers "B.Cu" "In11.Cu" "In13.Cu" "In15.Cu")
		(hatch none 0.5)
		(connect_pads
			(clearance 0)
		)
		(min_thickness 0.25)
		(keepout
			(tracks not_allowed)
			(vias allowed)
			(pads allowed)
			(copperpour not_allowed)
			(footprints allowed)
		)
		(placement
			(enabled no)
			(sheetname "")
		)
		(fill yes
			(thermal_gap 0.5)
			(thermal_bridge_width 0.5)
			(island_removal_mode 0)
		)
		(polygon
			(pts
				(arc
					(start 446.978278 -300.185074)
					(mid 446.310258 -300.185074)
					(end 446.978278 -300.185074)
				)
			)
		)
	)
	(zone
		(layers "B.Cu" "In11.Cu" "In13.Cu" "In15.Cu")
		(hatch none 0.5)
		(connect_pads
			(clearance 0)
		)
		(min_thickness 0.25)
		(keepout
			(tracks not_allowed)
			(vias allowed)
			(pads allowed)
			(copperpour not_allowed)
			(footprints allowed)
		)
		(placement
			(enabled no)
			(sheetname "")
		)
		(fill yes
			(thermal_gap 0.5)
			(thermal_bridge_width 0.5)
			(island_removal_mode 0)
		)
		(polygon
			(pts
				(arc
					(start 390.879838 -280.566114)
					(mid 390.249918 -280.566114)
					(end 390.879838 -280.566114)
				)
			)
		)
	)
	(zone
		(layers "B.Cu" "In11.Cu" "In13.Cu" "In15.Cu")
		(hatch none 0.5)
		(connect_pads
			(clearance 0)
		)
		(min_thickness 0.25)
		(keepout
			(tracks not_allowed)
			(vias allowed)
			(pads allowed)
			(copperpour not_allowed)
			(footprints allowed)
		)
		(placement
			(enabled no)
			(sheetname "")
		)
		(fill yes
			(thermal_gap 0.5)
			(thermal_bridge_width 0.5)
			(island_removal_mode 0)
		)
		(polygon
			(pts
				(arc
					(start 416.134042 -394.385292)
					(mid 415.504122 -394.385292)
					(end 416.134042 -394.385292)
				)
			)
		)
	)
	(zone
		(layers "B.Cu" "In11.Cu" "In13.Cu" "In15.Cu")
		(hatch none 0.5)
		(connect_pads
			(clearance 0)
		)
		(min_thickness 0.25)
		(keepout
			(tracks not_allowed)
			(vias allowed)
			(pads allowed)
			(copperpour not_allowed)
			(footprints allowed)
		)
		(placement
			(enabled no)
			(sheetname "")
		)
		(fill yes
			(thermal_gap 0.5)
			(thermal_bridge_width 0.5)
			(island_removal_mode 0)
		)
		(polygon
			(pts
				(arc
					(start 160.134046 -386.003292)
					(mid 159.504126 -386.003292)
					(end 160.134046 -386.003292)
				)
			)
		)
	)
	(zone
		(layers "B.Cu" "In11.Cu" "In13.Cu" "In15.Cu")
		(hatch none 0.5)
		(connect_pads
			(clearance 0)
		)
		(min_thickness 0.25)
		(keepout
			(tracks not_allowed)
			(vias allowed)
			(pads allowed)
			(copperpour not_allowed)
			(footprints allowed)
		)
		(placement
			(enabled no)
			(sheetname "")
		)
		(fill yes
			(thermal_gap 0.5)
			(thermal_bridge_width 0.5)
			(island_removal_mode 0)
		)
		(polygon
			(pts
				(arc
					(start 329.016106 -244.484144)
					(mid 328.386186 -244.484144)
					(end 329.016106 -244.484144)
				)
			)
		)
	)
	(zone
		(layers "B.Cu" "In11.Cu" "In13.Cu" "In15.Cu")
		(hatch none 0.5)
		(connect_pads
			(clearance 0)
		)
		(min_thickness 0.25)
		(keepout
			(tracks not_allowed)
			(vias allowed)
			(pads allowed)
			(copperpour not_allowed)
			(footprints allowed)
		)
		(placement
			(enabled no)
			(sheetname "")
		)
		(fill yes
			(thermal_gap 0.5)
			(thermal_bridge_width 0.5)
			(island_removal_mode 0)
		)
		(polygon
			(pts
				(arc
					(start 81.545938 -232.334308)
					(mid 80.916018 -232.334308)
					(end 81.545938 -232.334308)
				)
			)
		)
	)
	(zone
		(layers "B.Cu" "In11.Cu" "In13.Cu" "In15.Cu")
		(hatch none 0.5)
		(connect_pads
			(clearance 0)
		)
		(min_thickness 0.25)
		(keepout
			(tracks not_allowed)
			(vias allowed)
			(pads allowed)
			(copperpour not_allowed)
			(footprints allowed)
		)
		(placement
			(enabled no)
			(sheetname "")
		)
		(fill yes
			(thermal_gap 0.5)
			(thermal_bridge_width 0.5)
			(island_removal_mode 0)
		)
		(polygon
			(pts
				(arc
					(start 117.606318 -388.774432)
					(mid 116.976398 -388.774432)
					(end 117.606318 -388.774432)
				)
			)
		)
	)
	(zone
		(layers "B.Cu" "In11.Cu" "In13.Cu" "In15.Cu")
		(hatch none 0.5)
		(connect_pads
			(clearance 0)
		)
		(min_thickness 0.25)
		(keepout
			(tracks not_allowed)
			(vias allowed)
			(pads allowed)
			(copperpour not_allowed)
			(footprints allowed)
		)
		(placement
			(enabled no)
			(sheetname "")
		)
		(fill yes
			(thermal_gap 0.5)
			(thermal_bridge_width 0.5)
			(island_removal_mode 0)
		)
		(polygon
			(pts
				(arc
					(start 25.486106 -218.585288)
					(mid 24.818086 -218.585288)
					(end 25.486106 -218.585288)
				)
			)
		)
	)
	(zone
		(layers "B.Cu" "In11.Cu" "In13.Cu" "In15.Cu")
		(hatch none 0.5)
		(connect_pads
			(clearance 0)
		)
		(min_thickness 0.25)
		(keepout
			(tracks not_allowed)
			(vias allowed)
			(pads allowed)
			(copperpour not_allowed)
			(footprints allowed)
		)
		(placement
			(enabled no)
			(sheetname "")
		)
		(fill yes
			(thermal_gap 0.5)
			(thermal_bridge_width 0.5)
			(island_removal_mode 0)
		)
		(polygon
			(pts
				(arc
					(start 442.87821 -220.285056)
					(mid 442.21019 -220.285056)
					(end 442.87821 -220.285056)
				)
			)
		)
	)
	(zone
		(layers "B.Cu" "In11.Cu" "In13.Cu" "In15.Cu")
		(hatch none 0.5)
		(connect_pads
			(clearance 0)
		)
		(min_thickness 0.25)
		(keepout
			(tracks not_allowed)
			(vias allowed)
			(pads allowed)
			(copperpour not_allowed)
			(footprints allowed)
		)
		(placement
			(enabled no)
			(sheetname "")
		)
		(fill yes
			(thermal_gap 0.5)
			(thermal_bridge_width 0.5)
			(island_removal_mode 0)
		)
		(polygon
			(pts
				(arc
					(start 142.639796 -225.854514)
					(mid 142.009876 -225.854514)
					(end 142.639796 -225.854514)
				)
			)
		)
	)
	(zone
		(layers "B.Cu" "In11.Cu" "In13.Cu" "In15.Cu")
		(hatch none 0.5)
		(connect_pads
			(clearance 0)
		)
		(min_thickness 0.25)
		(keepout
			(tracks not_allowed)
			(vias allowed)
			(pads allowed)
			(copperpour not_allowed)
			(footprints allowed)
		)
		(placement
			(enabled no)
			(sheetname "")
		)
		(fill yes
			(thermal_gap 0.5)
			(thermal_bridge_width 0.5)
			(island_removal_mode 0)
		)
		(polygon
			(pts
				(arc
					(start 71.036942 -420.089838)
					(mid 70.26275 -420.089838)
					(end 71.036942 -420.089838)
				)
			)
		)
	)
	(zone
		(layers "B.Cu" "In11.Cu" "In13.Cu" "In15.Cu")
		(hatch none 0.5)
		(connect_pads
			(clearance 0)
		)
		(min_thickness 0.25)
		(keepout
			(tracks not_allowed)
			(vias allowed)
			(pads allowed)
			(copperpour not_allowed)
			(footprints allowed)
		)
		(placement
			(enabled no)
			(sheetname "")
		)
		(fill yes
			(thermal_gap 0.5)
			(thermal_bridge_width 0.5)
			(island_removal_mode 0)
		)
		(polygon
			(pts
				(arc
					(start 277.526242 -233.035094)
					(mid 276.858222 -233.035094)
					(end 277.526242 -233.035094)
				)
			)
		)
	)
	(zone
		(layers "B.Cu" "In11.Cu" "In13.Cu" "In15.Cu")
		(hatch none 0.5)
		(connect_pads
			(clearance 0)
		)
		(min_thickness 0.25)
		(keepout
			(tracks not_allowed)
			(vias allowed)
			(pads allowed)
			(copperpour not_allowed)
			(footprints allowed)
		)
		(placement
			(enabled no)
			(sheetname "")
		)
		(fill yes
			(thermal_gap 0.5)
			(thermal_bridge_width 0.5)
			(island_removal_mode 0)
		)
		(polygon
			(pts
				(arc
					(start 329.78598 -270.846042)
					(mid 329.15606 -270.846042)
					(end 329.78598 -270.846042)
				)
			)
		)
	)
	(zone
		(layers "B.Cu" "In11.Cu" "In13.Cu" "In15.Cu")
		(hatch none 0.5)
		(connect_pads
			(clearance 0)
		)
		(min_thickness 0.25)
		(keepout
			(tracks not_allowed)
			(vias allowed)
			(pads allowed)
			(copperpour not_allowed)
			(footprints allowed)
		)
		(placement
			(enabled no)
			(sheetname "")
		)
		(fill yes
			(thermal_gap 0.5)
			(thermal_bridge_width 0.5)
			(island_removal_mode 0)
		)
		(polygon
			(pts
				(arc
					(start 199.03821 -206.685388)
					(mid 198.37019 -206.685388)
					(end 199.03821 -206.685388)
				)
			)
		)
	)
	(zone
		(layers "B.Cu" "In11.Cu" "In13.Cu" "In15.Cu")
		(hatch none 0.5)
		(connect_pads
			(clearance 0)
		)
		(min_thickness 0.25)
		(keepout
			(tracks not_allowed)
			(vias allowed)
			(pads allowed)
			(copperpour not_allowed)
			(footprints allowed)
		)
		(placement
			(enabled no)
			(sheetname "")
		)
		(fill yes
			(thermal_gap 0.5)
			(thermal_bridge_width 0.5)
			(island_removal_mode 0)
		)
		(polygon
			(pts
				(arc
					(start 391.349738 -291.095938)
					(mid 390.719818 -291.095938)
					(end 391.349738 -291.095938)
				)
			)
		)
	)
	(zone
		(layers "B.Cu" "In11.Cu" "In13.Cu" "In15.Cu")
		(hatch none 0.5)
		(connect_pads
			(clearance 0)
		)
		(min_thickness 0.25)
		(keepout
			(tracks not_allowed)
			(vias allowed)
			(pads allowed)
			(copperpour not_allowed)
			(footprints allowed)
		)
		(placement
			(enabled no)
			(sheetname "")
		)
		(fill yes
			(thermal_gap 0.5)
			(thermal_bridge_width 0.5)
			(island_removal_mode 0)
		)
		(polygon
			(pts
				(arc
					(start 81.076038 -239.624362)
					(mid 80.446118 -239.624362)
					(end 81.076038 -239.624362)
				)
			)
		)
	)
	(zone
		(layers "B.Cu" "In11.Cu" "In13.Cu" "In15.Cu")
		(hatch none 0.5)
		(connect_pads
			(clearance 0)
		)
		(min_thickness 0.25)
		(keepout
			(tracks not_allowed)
			(vias allowed)
			(pads allowed)
			(copperpour not_allowed)
			(footprints allowed)
		)
		(placement
			(enabled no)
			(sheetname "")
		)
		(fill yes
			(thermal_gap 0.5)
			(thermal_bridge_width 0.5)
			(island_removal_mode 0)
		)
		(polygon
			(pts
				(arc
					(start 390.579864 -237.19409)
					(mid 389.949944 -237.19409)
					(end 390.579864 -237.19409)
				)
			)
		)
	)
	(zone
		(layers "B.Cu" "In11.Cu" "In13.Cu" "In15.Cu")
		(hatch none 0.5)
		(connect_pads
			(clearance 0)
		)
		(min_thickness 0.25)
		(keepout
			(tracks not_allowed)
			(vias allowed)
			(pads allowed)
			(copperpour not_allowed)
			(footprints allowed)
		)
		(placement
			(enabled no)
			(sheetname "")
		)
		(fill yes
			(thermal_gap 0.5)
			(thermal_bridge_width 0.5)
			(island_removal_mode 0)
		)
		(polygon
			(pts
				(arc
					(start 407.137108 -426.089826)
					(mid 406.362916 -426.089826)
					(end 407.137108 -426.089826)
				)
			)
		)
	)
	(zone
		(layers "B.Cu" "In11.Cu" "In13.Cu" "In15.Cu")
		(hatch none 0.5)
		(connect_pads
			(clearance 0)
		)
		(min_thickness 0.25)
		(keepout
			(tracks not_allowed)
			(vias allowed)
			(pads allowed)
			(copperpour not_allowed)
			(footprints allowed)
		)
		(placement
			(enabled no)
			(sheetname "")
		)
		(fill yes
			(thermal_gap 0.5)
			(thermal_bridge_width 0.5)
			(island_removal_mode 0)
		)
		(polygon
			(pts
				(arc
					(start 143.109696 -236.384338)
					(mid 142.479776 -236.384338)
					(end 143.109696 -236.384338)
				)
			)
		)
	)
	(zone
		(layers "B.Cu" "In11.Cu" "In13.Cu" "In15.Cu")
		(hatch none 0.5)
		(connect_pads
			(clearance 0)
		)
		(min_thickness 0.25)
		(keepout
			(tracks not_allowed)
			(vias allowed)
			(pads allowed)
			(copperpour not_allowed)
			(footprints allowed)
		)
		(placement
			(enabled no)
			(sheetname "")
		)
		(fill yes
			(thermal_gap 0.5)
			(thermal_bridge_width 0.5)
			(island_removal_mode 0)
		)
		(polygon
			(pts
				(arc
					(start 73.036938 -423.489882)
					(mid 72.262746 -423.489882)
					(end 73.036938 -423.489882)
				)
			)
		)
	)
	(zone
		(layers "B.Cu" "In11.Cu" "In13.Cu" "In15.Cu")
		(hatch none 0.5)
		(connect_pads
			(clearance 0)
		)
		(min_thickness 0.25)
		(keepout
			(tracks not_allowed)
			(vias allowed)
			(pads allowed)
			(copperpour not_allowed)
			(footprints allowed)
		)
		(placement
			(enabled no)
			(sheetname "")
		)
		(fill yes
			(thermal_gap 0.5)
			(thermal_bridge_width 0.5)
			(island_removal_mode 0)
		)
		(polygon
			(pts
				(arc
					(start 163.733988 -386.003292)
					(mid 163.104068 -386.003292)
					(end 163.733988 -386.003292)
				)
			)
		)
	)
	(zone
		(layers "B.Cu" "In11.Cu" "In13.Cu" "In15.Cu")
		(hatch none 0.5)
		(connect_pads
			(clearance 0)
		)
		(min_thickness 0.25)
		(keepout
			(tracks not_allowed)
			(vias allowed)
			(pads allowed)
			(copperpour not_allowed)
			(footprints allowed)
		)
		(placement
			(enabled no)
			(sheetname "")
		)
		(fill yes
			(thermal_gap 0.5)
			(thermal_bridge_width 0.5)
			(island_removal_mode 0)
		)
		(polygon
			(pts
				(arc
					(start 82.785966 -264.366248)
					(mid 82.156046 -264.366248)
					(end 82.785966 -264.366248)
				)
			)
		)
	)
	(zone
		(layers "B.Cu" "In11.Cu" "In13.Cu" "In15.Cu")
		(hatch none 0.5)
		(connect_pads
			(clearance 0)
		)
		(min_thickness 0.25)
		(keepout
			(tracks not_allowed)
			(vias allowed)
			(pads allowed)
			(copperpour not_allowed)
			(footprints allowed)
		)
		(placement
			(enabled no)
			(sheetname "")
		)
		(fill yes
			(thermal_gap 0.5)
			(thermal_bridge_width 0.5)
			(island_removal_mode 0)
		)
		(polygon
			(pts
				(arc
					(start 330.726034 -270.846042)
					(mid 330.096114 -270.846042)
					(end 330.726034 -270.846042)
				)
			)
		)
	)
	(zone
		(layers "B.Cu" "In11.Cu" "In13.Cu" "In15.Cu")
		(hatch none 0.5)
		(connect_pads
			(clearance 0)
		)
		(min_thickness 0.25)
		(keepout
			(tracks not_allowed)
			(vias allowed)
			(pads allowed)
			(copperpour not_allowed)
			(footprints allowed)
		)
		(placement
			(enabled no)
			(sheetname "")
		)
		(fill yes
			(thermal_gap 0.5)
			(thermal_bridge_width 0.5)
			(island_removal_mode 0)
		)
		(polygon
			(pts
				(arc
					(start 194.938142 -244.935248)
					(mid 194.270122 -244.935248)
					(end 194.938142 -244.935248)
				)
			)
		)
	)
	(zone
		(layers "B.Cu" "In11.Cu" "In13.Cu" "In15.Cu")
		(hatch none 0.5)
		(connect_pads
			(clearance 0)
		)
		(min_thickness 0.25)
		(keepout
			(tracks not_allowed)
			(vias allowed)
			(pads allowed)
			(copperpour not_allowed)
			(footprints allowed)
		)
		(placement
			(enabled no)
			(sheetname "")
		)
		(fill yes
			(thermal_gap 0.5)
			(thermal_bridge_width 0.5)
			(island_removal_mode 0)
		)
		(polygon
			(pts
				(arc
					(start 389.469884 -274.896072)
					(mid 388.839964 -274.896072)
					(end 389.469884 -274.896072)
				)
			)
		)
	)
	(zone
		(layers "B.Cu" "In11.Cu" "In13.Cu" "In15.Cu")
		(hatch none 0.5)
		(connect_pads
			(clearance 0)
		)
		(min_thickness 0.25)
		(keepout
			(tracks not_allowed)
			(vias allowed)
			(pads allowed)
			(copperpour not_allowed)
			(footprints allowed)
		)
		(placement
			(enabled no)
			(sheetname "")
		)
		(fill yes
			(thermal_gap 0.5)
			(thermal_bridge_width 0.5)
			(island_removal_mode 0)
		)
		(polygon
			(pts
				(arc
					(start 194.938142 -202.435206)
					(mid 194.270122 -202.435206)
					(end 194.938142 -202.435206)
				)
			)
		)
	)
	(zone
		(layers "B.Cu" "In11.Cu" "In13.Cu" "In15.Cu")
		(hatch none 0.5)
		(connect_pads
			(clearance 0)
		)
		(min_thickness 0.25)
		(keepout
			(tracks not_allowed)
			(vias allowed)
			(pads allowed)
			(copperpour not_allowed)
			(footprints allowed)
		)
		(placement
			(enabled no)
			(sheetname "")
		)
		(fill yes
			(thermal_gap 0.5)
			(thermal_bridge_width 0.5)
			(island_removal_mode 0)
		)
		(polygon
			(pts
				(arc
					(start 390.579864 -255.014222)
					(mid 389.949944 -255.014222)
					(end 390.579864 -255.014222)
				)
			)
		)
	)
	(zone
		(layers "B.Cu" "In11.Cu" "In13.Cu" "In15.Cu")
		(hatch none 0.5)
		(connect_pads
			(clearance 0)
		)
		(min_thickness 0.25)
		(keepout
			(tracks not_allowed)
			(vias allowed)
			(pads allowed)
			(copperpour not_allowed)
			(footprints allowed)
		)
		(placement
			(enabled no)
			(sheetname "")
		)
		(fill yes
			(thermal_gap 0.5)
			(thermal_bridge_width 0.5)
			(island_removal_mode 0)
		)
		(polygon
			(pts
				(arc
					(start 273.426174 -288.285174)
					(mid 272.758154 -288.285174)
					(end 273.426174 -288.285174)
				)
			)
		)
	)
	(zone
		(layers "B.Cu" "In11.Cu" "In13.Cu" "In15.Cu")
		(hatch none 0.5)
		(connect_pads
			(clearance 0)
		)
		(min_thickness 0.25)
		(keepout
			(tracks not_allowed)
			(vias allowed)
			(pads allowed)
			(copperpour not_allowed)
			(footprints allowed)
		)
		(placement
			(enabled no)
			(sheetname "")
		)
		(fill yes
			(thermal_gap 0.5)
			(thermal_bridge_width 0.5)
			(island_removal_mode 0)
		)
		(polygon
			(pts
				(arc
					(start 81.845912 -275.706332)
					(mid 81.215992 -275.706332)
					(end 81.845912 -275.706332)
				)
			)
		)
	)
	(zone
		(layers "B.Cu" "In11.Cu" "In13.Cu" "In15.Cu")
		(hatch none 0.5)
		(connect_pads
			(clearance 0)
		)
		(min_thickness 0.25)
		(keepout
			(tracks not_allowed)
			(vias allowed)
			(pads allowed)
			(copperpour not_allowed)
			(footprints allowed)
		)
		(placement
			(enabled no)
			(sheetname "")
		)
		(fill yes
			(thermal_gap 0.5)
			(thermal_bridge_width 0.5)
			(island_removal_mode 0)
		)
		(polygon
			(pts
				(arc
					(start 141.229842 -226.66452)
					(mid 140.599922 -226.66452)
					(end 141.229842 -226.66452)
				)
			)
		)
	)
	(zone
		(layers "B.Cu" "In11.Cu" "In13.Cu" "In15.Cu")
		(hatch none 0.5)
		(connect_pads
			(clearance 0)
		)
		(min_thickness 0.25)
		(keepout
			(tracks not_allowed)
			(vias allowed)
			(pads allowed)
			(copperpour not_allowed)
			(footprints allowed)
		)
		(placement
			(enabled no)
			(sheetname "")
		)
		(fill yes
			(thermal_gap 0.5)
			(thermal_bridge_width 0.5)
			(island_removal_mode 0)
		)
		(polygon
			(pts
				(arc
					(start 446.978278 -272.135092)
					(mid 446.310258 -272.135092)
					(end 446.978278 -272.135092)
				)
			)
		)
	)
	(zone
		(layers "B.Cu" "In11.Cu" "In13.Cu" "In15.Cu")
		(hatch none 0.5)
		(connect_pads
			(clearance 0)
		)
		(min_thickness 0.25)
		(keepout
			(tracks not_allowed)
			(vias allowed)
			(pads allowed)
			(copperpour not_allowed)
			(footprints allowed)
		)
		(placement
			(enabled no)
			(sheetname "")
		)
		(fill yes
			(thermal_gap 0.5)
			(thermal_bridge_width 0.5)
			(island_removal_mode 0)
		)
		(polygon
			(pts
				(arc
					(start 351.033842 -397.156432)
					(mid 350.403922 -397.156432)
					(end 351.033842 -397.156432)
				)
			)
		)
	)
	(zone
		(layers "B.Cu" "In11.Cu" "In13.Cu" "In15.Cu")
		(hatch none 0.5)
		(connect_pads
			(clearance 0)
		)
		(min_thickness 0.25)
		(keepout
			(tracks not_allowed)
			(vias allowed)
			(pads allowed)
			(copperpour not_allowed)
			(footprints allowed)
		)
		(placement
			(enabled no)
			(sheetname "")
		)
		(fill yes
			(thermal_gap 0.5)
			(thermal_bridge_width 0.5)
			(island_removal_mode 0)
		)
		(polygon
			(pts
				(arc
					(start 442.87821 -280.634948)
					(mid 442.21019 -280.634948)
					(end 442.87821 -280.634948)
				)
			)
		)
	)
	(zone
		(layers "B.Cu" "In11.Cu" "In13.Cu" "In15.Cu")
		(hatch none 0.5)
		(connect_pads
			(clearance 0)
		)
		(min_thickness 0.25)
		(keepout
			(tracks not_allowed)
			(vias allowed)
			(pads allowed)
			(copperpour not_allowed)
			(footprints allowed)
		)
		(placement
			(enabled no)
			(sheetname "")
		)
		(fill yes
			(thermal_gap 0.5)
			(thermal_bridge_width 0.5)
			(island_removal_mode 0)
		)
		(polygon
			(pts
				(arc
					(start 25.486106 -284.035246)
					(mid 24.818086 -284.035246)
					(end 25.486106 -284.035246)
				)
			)
		)
	)
	(zone
		(layers "B.Cu" "In11.Cu" "In13.Cu" "In15.Cu")
		(hatch none 0.5)
		(connect_pads
			(clearance 0)
		)
		(min_thickness 0.25)
		(keepout
			(tracks not_allowed)
			(vias allowed)
			(pads allowed)
			(copperpour not_allowed)
			(footprints allowed)
		)
		(placement
			(enabled no)
			(sheetname "")
		)
		(fill yes
			(thermal_gap 0.5)
			(thermal_bridge_width 0.5)
			(island_removal_mode 0)
		)
		(polygon
			(pts
				(arc
					(start 442.87821 -312.084974)
					(mid 442.21019 -312.084974)
					(end 442.87821 -312.084974)
				)
			)
		)
	)
	(zone
		(layers "B.Cu" "In11.Cu" "In13.Cu" "In15.Cu")
		(hatch none 0.5)
		(connect_pads
			(clearance 0)
		)
		(min_thickness 0.25)
		(keepout
			(tracks not_allowed)
			(vias allowed)
			(pads allowed)
			(copperpour not_allowed)
			(footprints allowed)
		)
		(placement
			(enabled no)
			(sheetname "")
		)
		(fill yes
			(thermal_gap 0.5)
			(thermal_bridge_width 0.5)
			(island_removal_mode 0)
		)
		(polygon
			(pts
				(arc
					(start 108.80598 -240.434368)
					(mid 108.17606 -240.434368)
					(end 108.80598 -240.434368)
				)
			)
		)
	)
	(zone
		(layers "B.Cu" "In11.Cu" "In13.Cu" "In15.Cu")
		(hatch none 0.5)
		(connect_pads
			(clearance 0)
		)
		(min_thickness 0.25)
		(keepout
			(tracks not_allowed)
			(vias allowed)
			(pads allowed)
			(copperpour not_allowed)
			(footprints allowed)
		)
		(placement
			(enabled no)
			(sheetname "")
		)
		(fill yes
			(thermal_gap 0.5)
			(thermal_bridge_width 0.5)
			(island_removal_mode 0)
		)
		(polygon
			(pts
				(arc
					(start 273.426174 -289.985196)
					(mid 272.758154 -289.985196)
					(end 273.426174 -289.985196)
				)
			)
		)
	)
	(zone
		(layers "B.Cu" "In11.Cu" "In13.Cu" "In15.Cu")
		(hatch none 0.5)
		(connect_pads
			(clearance 0)
		)
		(min_thickness 0.25)
		(keepout
			(tracks not_allowed)
			(vias allowed)
			(pads allowed)
			(copperpour not_allowed)
			(footprints allowed)
		)
		(placement
			(enabled no)
			(sheetname "")
		)
		(fill yes
			(thermal_gap 0.5)
			(thermal_bridge_width 0.5)
			(island_removal_mode 0)
		)
		(polygon
			(pts
				(arc
					(start 55.118254 -404.46452)
					(mid 54.450234 -404.46452)
					(end 55.118254 -404.46452)
				)
			)
		)
	)
	(zone
		(layers "B.Cu" "In11.Cu" "In13.Cu" "In15.Cu")
		(hatch none 0.5)
		(connect_pads
			(clearance 0)
		)
		(min_thickness 0.25)
		(keepout
			(tracks not_allowed)
			(vias allowed)
			(pads allowed)
			(copperpour not_allowed)
			(footprints allowed)
		)
		(placement
			(enabled no)
			(sheetname "")
		)
		(fill yes
			(thermal_gap 0.5)
			(thermal_bridge_width 0.5)
			(island_removal_mode 0)
		)
		(polygon
			(pts
				(arc
					(start 103.636064 -239.624362)
					(mid 103.006144 -239.624362)
					(end 103.636064 -239.624362)
				)
			)
		)
	)
	(zone
		(layers "B.Cu" "In11.Cu" "In13.Cu" "In15.Cu")
		(hatch none 0.5)
		(connect_pads
			(clearance 0)
		)
		(min_thickness 0.25)
		(keepout
			(tracks not_allowed)
			(vias allowed)
			(pads allowed)
			(copperpour not_allowed)
			(footprints allowed)
		)
		(placement
			(enabled no)
			(sheetname "")
		)
		(fill yes
			(thermal_gap 0.5)
			(thermal_bridge_width 0.5)
			(island_removal_mode 0)
		)
		(polygon
			(pts
				(arc
					(start 372.806214 -397.849344)
					(mid 372.176294 -397.849344)
					(end 372.806214 -397.849344)
				)
			)
		)
	)
	(zone
		(layers "B.Cu" "In11.Cu" "In13.Cu" "In15.Cu")
		(hatch none 0.5)
		(connect_pads
			(clearance 0)
		)
		(min_thickness 0.25)
		(keepout
			(tracks not_allowed)
			(vias allowed)
			(pads allowed)
			(copperpour not_allowed)
			(footprints allowed)
		)
		(placement
			(enabled no)
			(sheetname "")
		)
		(fill yes
			(thermal_gap 0.5)
			(thermal_bridge_width 0.5)
			(island_removal_mode 0)
		)
		(polygon
			(pts
				(arc
					(start 355.636068 -282.996132)
					(mid 355.006148 -282.996132)
					(end 355.636068 -282.996132)
				)
			)
		)
	)
	(zone
		(layers "B.Cu" "In11.Cu" "In13.Cu" "In15.Cu")
		(hatch none 0.5)
		(connect_pads
			(clearance 0)
		)
		(min_thickness 0.25)
		(keepout
			(tracks not_allowed)
			(vias allowed)
			(pads allowed)
			(copperpour not_allowed)
			(footprints allowed)
		)
		(placement
			(enabled no)
			(sheetname "")
		)
		(fill yes
			(thermal_gap 0.5)
			(thermal_bridge_width 0.5)
			(island_removal_mode 0)
		)
		(polygon
			(pts
				(arc
					(start 81.376012 -271.656302)
					(mid 80.746092 -271.656302)
					(end 81.376012 -271.656302)
				)
			)
		)
	)
	(zone
		(layers "B.Cu" "In11.Cu" "In13.Cu" "In15.Cu")
		(hatch none 0.5)
		(connect_pads
			(clearance 0)
		)
		(min_thickness 0.25)
		(keepout
			(tracks not_allowed)
			(vias allowed)
			(pads allowed)
			(copperpour not_allowed)
			(footprints allowed)
		)
		(placement
			(enabled no)
			(sheetname "")
		)
		(fill yes
			(thermal_gap 0.5)
			(thermal_bridge_width 0.5)
			(island_removal_mode 0)
		)
		(polygon
			(pts
				(arc
					(start 87.950294 -404.46452)
					(mid 87.282274 -404.46452)
					(end 87.950294 -404.46452)
				)
			)
		)
	)
	(zone
		(layers "B.Cu" "In11.Cu" "In13.Cu" "In15.Cu")
		(hatch none 0.5)
		(connect_pads
			(clearance 0)
		)
		(min_thickness 0.25)
		(keepout
			(tracks not_allowed)
			(vias allowed)
			(pads allowed)
			(copperpour not_allowed)
			(footprints allowed)
		)
		(placement
			(enabled no)
			(sheetname "")
		)
		(fill yes
			(thermal_gap 0.5)
			(thermal_bridge_width 0.5)
			(island_removal_mode 0)
		)
		(polygon
			(pts
				(arc
					(start 154.134058 -386.003292)
					(mid 153.504138 -386.003292)
					(end 154.134058 -386.003292)
				)
			)
		)
	)
	(zone
		(layers "B.Cu" "In11.Cu" "In13.Cu" "In15.Cu")
		(hatch none 0.5)
		(connect_pads
			(clearance 0)
		)
		(min_thickness 0.25)
		(keepout
			(tracks not_allowed)
			(vias allowed)
			(pads allowed)
			(copperpour not_allowed)
			(footprints allowed)
		)
		(placement
			(enabled no)
			(sheetname "")
		)
		(fill yes
			(thermal_gap 0.5)
			(thermal_bridge_width 0.5)
			(island_removal_mode 0)
		)
		(polygon
			(pts
				(arc
					(start 442.87821 -286.585152)
					(mid 442.21019 -286.585152)
					(end 442.87821 -286.585152)
				)
			)
		)
	)
	(zone
		(layers "B.Cu" "In11.Cu" "In13.Cu" "In15.Cu")
		(hatch none 0.5)
		(connect_pads
			(clearance 0)
		)
		(min_thickness 0.25)
		(keepout
			(tracks not_allowed)
			(vias allowed)
			(pads allowed)
			(copperpour not_allowed)
			(footprints allowed)
		)
		(placement
			(enabled no)
			(sheetname "")
		)
		(fill yes
			(thermal_gap 0.5)
			(thermal_bridge_width 0.5)
			(island_removal_mode 0)
		)
		(polygon
			(pts
				(arc
					(start 313.826906 -379.88113)
					(mid 313.158886 -379.88113)
					(end 313.826906 -379.88113)
				)
			)
		)
	)
	(zone
		(layers "B.Cu" "In11.Cu" "In13.Cu" "In15.Cu")
		(hatch none 0.5)
		(connect_pads
			(clearance 0)
		)
		(min_thickness 0.25)
		(keepout
			(tracks not_allowed)
			(vias allowed)
			(pads allowed)
			(copperpour not_allowed)
			(footprints allowed)
		)
		(placement
			(enabled no)
			(sheetname "")
		)
		(fill yes
			(thermal_gap 0.5)
			(thermal_bridge_width 0.5)
			(island_removal_mode 0)
		)
		(polygon
			(pts
				(arc
					(start 330.726034 -288.66592)
					(mid 330.096114 -288.66592)
					(end 330.726034 -288.66592)
				)
			)
		)
	)
	(zone
		(layers "B.Cu" "In11.Cu" "In13.Cu" "In15.Cu")
		(hatch none 0.5)
		(connect_pads
			(clearance 0)
		)
		(min_thickness 0.25)
		(keepout
			(tracks not_allowed)
			(vias allowed)
			(pads allowed)
			(copperpour not_allowed)
			(footprints allowed)
		)
		(placement
			(enabled no)
			(sheetname "")
		)
		(fill yes
			(thermal_gap 0.5)
			(thermal_bridge_width 0.5)
			(island_removal_mode 0)
		)
		(polygon
			(pts
				(arc
					(start 411.1371 -427.289976)
					(mid 410.362908 -427.289976)
					(end 411.1371 -427.289976)
				)
			)
		)
	)
	(zone
		(layers "B.Cu" "In11.Cu" "In13.Cu" "In15.Cu")
		(hatch none 0.5)
		(connect_pads
			(clearance 0)
		)
		(min_thickness 0.25)
		(keepout
			(tracks not_allowed)
			(vias allowed)
			(pads allowed)
			(copperpour not_allowed)
			(footprints allowed)
		)
		(placement
			(enabled no)
			(sheetname "")
		)
		(fill yes
			(thermal_gap 0.5)
			(thermal_bridge_width 0.5)
			(island_removal_mode 0)
		)
		(polygon
			(pts
				(arc
					(start 43.349164 -371.49913)
					(mid 42.681144 -371.49913)
					(end 43.349164 -371.49913)
				)
			)
		)
	)
	(zone
		(layers "B.Cu" "In11.Cu" "In13.Cu" "In15.Cu")
		(hatch none 0.5)
		(connect_pads
			(clearance 0)
		)
		(min_thickness 0.25)
		(keepout
			(tracks not_allowed)
			(vias allowed)
			(pads allowed)
			(copperpour not_allowed)
			(footprints allowed)
		)
		(placement
			(enabled no)
			(sheetname "")
		)
		(fill yes
			(thermal_gap 0.5)
			(thermal_bridge_width 0.5)
			(island_removal_mode 0)
		)
		(polygon
			(pts
				(arc
					(start 352.81616 -282.996132)
					(mid 352.18624 -282.996132)
					(end 352.81616 -282.996132)
				)
			)
		)
	)
	(zone
		(layers "B.Cu" "In11.Cu" "In13.Cu" "In15.Cu")
		(hatch none 0.5)
		(connect_pads
			(clearance 0)
		)
		(min_thickness 0.25)
		(keepout
			(tracks not_allowed)
			(vias allowed)
			(pads allowed)
			(copperpour not_allowed)
			(footprints allowed)
		)
		(placement
			(enabled no)
			(sheetname "")
		)
		(fill yes
			(thermal_gap 0.5)
			(thermal_bridge_width 0.5)
			(island_removal_mode 0)
		)
		(polygon
			(pts
				(arc
					(start 29.586174 -311.235344)
					(mid 28.918154 -311.235344)
					(end 29.586174 -311.235344)
				)
			)
		)
	)
	(zone
		(layers "B.Cu" "In11.Cu" "In13.Cu" "In15.Cu")
		(hatch none 0.5)
		(connect_pads
			(clearance 0)
		)
		(min_thickness 0.25)
		(keepout
			(tracks not_allowed)
			(vias allowed)
			(pads allowed)
			(copperpour not_allowed)
			(footprints allowed)
		)
		(placement
			(enabled no)
			(sheetname "")
		)
		(fill yes
			(thermal_gap 0.5)
			(thermal_bridge_width 0.5)
			(island_removal_mode 0)
		)
		(polygon
			(pts
				(arc
					(start 446.978278 -304.435002)
					(mid 446.310258 -304.435002)
					(end 446.978278 -304.435002)
				)
			)
		)
	)
	(zone
		(layers "B.Cu" "In11.Cu" "In13.Cu" "In15.Cu")
		(hatch none 0.5)
		(connect_pads
			(clearance 0)
		)
		(min_thickness 0.25)
		(keepout
			(tracks not_allowed)
			(vias allowed)
			(pads allowed)
			(copperpour not_allowed)
			(footprints allowed)
		)
		(placement
			(enabled no)
			(sheetname "")
		)
		(fill yes
			(thermal_gap 0.5)
			(thermal_bridge_width 0.5)
			(island_removal_mode 0)
		)
		(polygon
			(pts
				(arc
					(start 312.963306 -379.88113)
					(mid 312.295286 -379.88113)
					(end 312.963306 -379.88113)
				)
			)
		)
	)
	(zone
		(layers "B.Cu" "In11.Cu" "In13.Cu" "In15.Cu")
		(hatch none 0.5)
		(connect_pads
			(clearance 0)
		)
		(min_thickness 0.25)
		(keepout
			(tracks not_allowed)
			(vias allowed)
			(pads allowed)
			(copperpour not_allowed)
			(footprints allowed)
		)
		(placement
			(enabled no)
			(sheetname "")
		)
		(fill yes
			(thermal_gap 0.5)
			(thermal_bridge_width 0.5)
			(island_removal_mode 0)
		)
		(polygon
			(pts
				(arc
					(start 341.433658 -397.156432)
					(mid 340.803738 -397.156432)
					(end 341.433658 -397.156432)
				)
			)
		)
	)
	(zone
		(layers "B.Cu" "In11.Cu" "In13.Cu" "In15.Cu")
		(hatch none 0.5)
		(connect_pads
			(clearance 0)
		)
		(min_thickness 0.25)
		(keepout
			(tracks not_allowed)
			(vias allowed)
			(pads allowed)
			(copperpour not_allowed)
			(footprints allowed)
		)
		(placement
			(enabled no)
			(sheetname "")
		)
		(fill yes
			(thermal_gap 0.5)
			(thermal_bridge_width 0.5)
			(island_removal_mode 0)
		)
		(polygon
			(pts
				(arc
					(start 141.529816 -291.096192)
					(mid 140.899896 -291.096192)
					(end 141.529816 -291.096192)
				)
			)
		)
	)
	(zone
		(layers "B.Cu" "In11.Cu" "In13.Cu" "In15.Cu")
		(hatch none 0.5)
		(connect_pads
			(clearance 0)
		)
		(min_thickness 0.25)
		(keepout
			(tracks not_allowed)
			(vias allowed)
			(pads allowed)
			(copperpour not_allowed)
			(footprints allowed)
		)
		(placement
			(enabled no)
			(sheetname "")
		)
		(fill yes
			(thermal_gap 0.5)
			(thermal_bridge_width 0.5)
			(island_removal_mode 0)
		)
		(polygon
			(pts
				(arc
					(start 128.806194 -389.467344)
					(mid 128.176274 -389.467344)
					(end 128.806194 -389.467344)
				)
			)
		)
	)
	(zone
		(layers "B.Cu" "In11.Cu" "In13.Cu" "In15.Cu")
		(hatch none 0.5)
		(connect_pads
			(clearance 0)
		)
		(min_thickness 0.25)
		(keepout
			(tracks not_allowed)
			(vias allowed)
			(pads allowed)
			(copperpour not_allowed)
			(footprints allowed)
		)
		(placement
			(enabled no)
			(sheetname "")
		)
		(fill yes
			(thermal_gap 0.5)
			(thermal_bridge_width 0.5)
			(island_removal_mode 0)
		)
		(polygon
			(pts
				(arc
					(start 371.609874 -284.616144)
					(mid 370.979954 -284.616144)
					(end 371.609874 -284.616144)
				)
			)
		)
	)
	(zone
		(layers "B.Cu" "In11.Cu" "In13.Cu" "In15.Cu")
		(hatch none 0.5)
		(connect_pads
			(clearance 0)
		)
		(min_thickness 0.25)
		(keepout
			(tracks not_allowed)
			(vias allowed)
			(pads allowed)
			(copperpour not_allowed)
			(footprints allowed)
		)
		(placement
			(enabled no)
			(sheetname "")
		)
		(fill yes
			(thermal_gap 0.5)
			(thermal_bridge_width 0.5)
			(island_removal_mode 0)
		)
		(polygon
			(pts
				(arc
					(start 273.426174 -210.935062)
					(mid 272.758154 -210.935062)
					(end 273.426174 -210.935062)
				)
			)
		)
	)
	(zone
		(layers "B.Cu" "In11.Cu" "In13.Cu" "In15.Cu")
		(hatch none 0.5)
		(connect_pads
			(clearance 0)
		)
		(min_thickness 0.25)
		(keepout
			(tracks not_allowed)
			(vias allowed)
			(pads allowed)
			(copperpour not_allowed)
			(footprints allowed)
		)
		(placement
			(enabled no)
			(sheetname "")
		)
		(fill yes
			(thermal_gap 0.5)
			(thermal_bridge_width 0.5)
			(island_removal_mode 0)
		)
		(polygon
			(pts
				(arc
					(start 277.526242 -313.784996)
					(mid 276.858222 -313.784996)
					(end 277.526242 -313.784996)
				)
			)
		)
	)
	(zone
		(layers "B.Cu" "In11.Cu" "In13.Cu" "In15.Cu")
		(hatch none 0.5)
		(connect_pads
			(clearance 0)
		)
		(min_thickness 0.25)
		(keepout
			(tracks not_allowed)
			(vias allowed)
			(pads allowed)
			(copperpour not_allowed)
			(footprints allowed)
		)
		(placement
			(enabled no)
			(sheetname "")
		)
		(fill yes
			(thermal_gap 0.5)
			(thermal_bridge_width 0.5)
			(island_removal_mode 0)
		)
		(polygon
			(pts
				(arc
					(start 104.876092 -284.616398)
					(mid 104.246172 -284.616398)
					(end 104.876092 -284.616398)
				)
			)
		)
	)
	(zone
		(layers "B.Cu" "In11.Cu" "In13.Cu" "In15.Cu")
		(hatch none 0.5)
		(connect_pads
			(clearance 0)
		)
		(min_thickness 0.25)
		(keepout
			(tracks not_allowed)
			(vias allowed)
			(pads allowed)
			(copperpour not_allowed)
			(footprints allowed)
		)
		(placement
			(enabled no)
			(sheetname "")
		)
		(fill yes
			(thermal_gap 0.5)
			(thermal_bridge_width 0.5)
			(island_removal_mode 0)
		)
		(polygon
			(pts
				(arc
					(start 277.526242 -220.285056)
					(mid 276.858222 -220.285056)
					(end 277.526242 -220.285056)
				)
			)
		)
	)
	(zone
		(layers "B.Cu" "In11.Cu" "In13.Cu" "In15.Cu")
		(hatch none 0.5)
		(connect_pads
			(clearance 0)
		)
		(min_thickness 0.25)
		(keepout
			(tracks not_allowed)
			(vias allowed)
			(pads allowed)
			(copperpour not_allowed)
			(footprints allowed)
		)
		(placement
			(enabled no)
			(sheetname "")
		)
		(fill yes
			(thermal_gap 0.5)
			(thermal_bridge_width 0.5)
			(island_removal_mode 0)
		)
		(polygon
			(pts
				(arc
					(start 374.129808 -239.624108)
					(mid 373.499888 -239.624108)
					(end 374.129808 -239.624108)
				)
			)
		)
	)
	(zone
		(layers "B.Cu" "In11.Cu" "In13.Cu" "In15.Cu")
		(hatch none 0.5)
		(connect_pads
			(clearance 0)
		)
		(min_thickness 0.25)
		(keepout
			(tracks not_allowed)
			(vias allowed)
			(pads allowed)
			(copperpour not_allowed)
			(footprints allowed)
		)
		(placement
			(enabled no)
			(sheetname "")
		)
		(fill yes
			(thermal_gap 0.5)
			(thermal_bridge_width 0.5)
			(island_removal_mode 0)
		)
		(polygon
			(pts
				(arc
					(start 442.87821 -210.935062)
					(mid 442.21019 -210.935062)
					(end 442.87821 -210.935062)
				)
			)
		)
	)
	(zone
		(layers "B.Cu" "In11.Cu" "In13.Cu" "In15.Cu")
		(hatch none 0.5)
		(connect_pads
			(clearance 0)
		)
		(min_thickness 0.25)
		(keepout
			(tracks not_allowed)
			(vias allowed)
			(pads allowed)
			(copperpour not_allowed)
			(footprints allowed)
		)
		(placement
			(enabled no)
			(sheetname "")
		)
		(fill yes
			(thermal_gap 0.5)
			(thermal_bridge_width 0.5)
			(island_removal_mode 0)
		)
		(polygon
			(pts
				(arc
					(start 392.136884 -428.28972)
					(mid 391.362692 -428.28972)
					(end 392.136884 -428.28972)
				)
			)
		)
	)
	(zone
		(layers "B.Cu" "In11.Cu" "In13.Cu" "In15.Cu")
		(hatch none 0.5)
		(connect_pads
			(clearance 0)
		)
		(min_thickness 0.25)
		(keepout
			(tracks not_allowed)
			(vias allowed)
			(pads allowed)
			(copperpour not_allowed)
			(footprints allowed)
		)
		(placement
			(enabled no)
			(sheetname "")
		)
		(fill yes
			(thermal_gap 0.5)
			(thermal_bridge_width 0.5)
			(island_removal_mode 0)
		)
		(polygon
			(pts
				(arc
					(start 194.938142 -226.23526)
					(mid 194.270122 -226.23526)
					(end 194.938142 -226.23526)
				)
			)
		)
	)
	(zone
		(layers "B.Cu" "In11.Cu" "In13.Cu" "In15.Cu")
		(hatch none 0.5)
		(connect_pads
			(clearance 0)
		)
		(min_thickness 0.25)
		(keepout
			(tracks not_allowed)
			(vias allowed)
			(pads allowed)
			(copperpour not_allowed)
			(footprints allowed)
		)
		(placement
			(enabled no)
			(sheetname "")
		)
		(fill yes
			(thermal_gap 0.5)
			(thermal_bridge_width 0.5)
			(island_removal_mode 0)
		)
		(polygon
			(pts
				(arc
					(start 273.426174 -239.835182)
					(mid 272.758154 -239.835182)
					(end 273.426174 -239.835182)
				)
			)
		)
	)
	(zone
		(layers "B.Cu" "In11.Cu" "In13.Cu" "In15.Cu")
		(hatch none 0.5)
		(connect_pads
			(clearance 0)
		)
		(min_thickness 0.25)
		(keepout
			(tracks not_allowed)
			(vias allowed)
			(pads allowed)
			(copperpour not_allowed)
			(footprints allowed)
		)
		(placement
			(enabled no)
			(sheetname "")
		)
		(fill yes
			(thermal_gap 0.5)
			(thermal_bridge_width 0.5)
			(island_removal_mode 0)
		)
		(polygon
			(pts
				(arc
					(start 98.936048 -239.624362)
					(mid 98.306128 -239.624362)
					(end 98.936048 -239.624362)
				)
			)
		)
	)
	(zone
		(layers "B.Cu" "In11.Cu" "In13.Cu" "In15.Cu")
		(hatch none 0.5)
		(connect_pads
			(clearance 0)
		)
		(min_thickness 0.25)
		(keepout
			(tracks not_allowed)
			(vias allowed)
			(pads allowed)
			(copperpour not_allowed)
			(footprints allowed)
		)
		(placement
			(enabled no)
			(sheetname "")
		)
		(fill yes
			(thermal_gap 0.5)
			(thermal_bridge_width 0.5)
			(island_removal_mode 0)
		)
		(polygon
			(pts
				(arc
					(start 446.978278 -295.085008)
					(mid 446.310258 -295.085008)
					(end 446.978278 -295.085008)
				)
			)
		)
	)
	(zone
		(layers "B.Cu" "In11.Cu" "In13.Cu" "In15.Cu")
		(hatch none 0.5)
		(connect_pads
			(clearance 0)
		)
		(min_thickness 0.25)
		(keepout
			(tracks not_allowed)
			(vias allowed)
			(pads allowed)
			(copperpour not_allowed)
			(footprints allowed)
		)
		(placement
			(enabled no)
			(sheetname "")
		)
		(fill yes
			(thermal_gap 0.5)
			(thermal_bridge_width 0.5)
			(island_removal_mode 0)
		)
		(polygon
			(pts
				(arc
					(start 273.426174 -199.885046)
					(mid 272.758154 -199.885046)
					(end 273.426174 -199.885046)
				)
			)
		)
	)
	(zone
		(layers "B.Cu" "In11.Cu" "In13.Cu" "In15.Cu")
		(hatch none 0.5)
		(connect_pads
			(clearance 0)
		)
		(min_thickness 0.25)
		(keepout
			(tracks not_allowed)
			(vias allowed)
			(pads allowed)
			(copperpour not_allowed)
			(footprints allowed)
		)
		(placement
			(enabled no)
			(sheetname "")
		)
		(fill yes
			(thermal_gap 0.5)
			(thermal_bridge_width 0.5)
			(island_removal_mode 0)
		)
		(polygon
			(pts
				(arc
					(start 134.05485 -25.62733)
					(mid 133.38683 -25.62733)
					(end 134.05485 -25.62733)
				)
			)
		)
	)
	(zone
		(layers "B.Cu" "In11.Cu" "In13.Cu" "In15.Cu")
		(hatch none 0.5)
		(connect_pads
			(clearance 0)
		)
		(min_thickness 0.25)
		(keepout
			(tracks not_allowed)
			(vias allowed)
			(pads allowed)
			(copperpour not_allowed)
			(footprints allowed)
		)
		(placement
			(enabled no)
			(sheetname "")
		)
		(fill yes
			(thermal_gap 0.5)
			(thermal_bridge_width 0.5)
			(island_removal_mode 0)
		)
		(polygon
			(pts
				(arc
					(start 330.89596 -234.764072)
					(mid 330.26604 -234.764072)
					(end 330.89596 -234.764072)
				)
			)
		)
	)
	(zone
		(layers "B.Cu" "In11.Cu" "In13.Cu" "In15.Cu")
		(hatch none 0.5)
		(connect_pads
			(clearance 0)
		)
		(min_thickness 0.25)
		(keepout
			(tracks not_allowed)
			(vias allowed)
			(pads allowed)
			(copperpour not_allowed)
			(footprints allowed)
		)
		(placement
			(enabled no)
			(sheetname "")
		)
		(fill yes
			(thermal_gap 0.5)
			(thermal_bridge_width 0.5)
			(island_removal_mode 0)
		)
		(polygon
			(pts
				(arc
					(start 142.639796 -256.634488)
					(mid 142.009876 -256.634488)
					(end 142.639796 -256.634488)
				)
			)
		)
	)
	(zone
		(layers "B.Cu" "In11.Cu" "In13.Cu" "In15.Cu")
		(hatch none 0.5)
		(connect_pads
			(clearance 0)
		)
		(min_thickness 0.25)
		(keepout
			(tracks not_allowed)
			(vias allowed)
			(pads allowed)
			(copperpour not_allowed)
			(footprints allowed)
		)
		(placement
			(enabled no)
			(sheetname "")
		)
		(fill yes
			(thermal_gap 0.5)
			(thermal_bridge_width 0.5)
			(island_removal_mode 0)
		)
		(polygon
			(pts
				(arc
					(start 81.545938 -227.474526)
					(mid 80.916018 -227.474526)
					(end 81.545938 -227.474526)
				)
			)
		)
	)
	(zone
		(layers "B.Cu" "In11.Cu" "In13.Cu" "In15.Cu")
		(hatch none 0.5)
		(connect_pads
			(clearance 0)
		)
		(min_thickness 0.25)
		(keepout
			(tracks not_allowed)
			(vias allowed)
			(pads allowed)
			(copperpour not_allowed)
			(footprints allowed)
		)
		(placement
			(enabled no)
			(sheetname "")
		)
		(fill yes
			(thermal_gap 0.5)
			(thermal_bridge_width 0.5)
			(island_removal_mode 0)
		)
		(polygon
			(pts
				(arc
					(start 48.50638 -389.467344)
					(mid 47.87646 -389.467344)
					(end 48.50638 -389.467344)
				)
			)
		)
	)
	(zone
		(layers "B.Cu" "In11.Cu" "In13.Cu" "In15.Cu")
		(hatch none 0.5)
		(connect_pads
			(clearance 0)
		)
		(min_thickness 0.25)
		(keepout
			(tracks not_allowed)
			(vias allowed)
			(pads allowed)
			(copperpour not_allowed)
			(footprints allowed)
		)
		(placement
			(enabled no)
			(sheetname "")
		)
		(fill yes
			(thermal_gap 0.5)
			(thermal_bridge_width 0.5)
			(island_removal_mode 0)
		)
		(polygon
			(pts
				(arc
					(start 349.995998 -282.996132)
					(mid 349.366078 -282.996132)
					(end 349.995998 -282.996132)
				)
			)
		)
	)
	(zone
		(layers "B.Cu" "In11.Cu" "In13.Cu" "In15.Cu")
		(hatch none 0.5)
		(connect_pads
			(clearance 0)
		)
		(min_thickness 0.25)
		(keepout
			(tracks not_allowed)
			(vias allowed)
			(pads allowed)
			(copperpour not_allowed)
			(footprints allowed)
		)
		(placement
			(enabled no)
			(sheetname "")
		)
		(fill yes
			(thermal_gap 0.5)
			(thermal_bridge_width 0.5)
			(island_removal_mode 0)
		)
		(polygon
			(pts
				(arc
					(start 332.036928 -426.089826)
					(mid 331.262736 -426.089826)
					(end 332.036928 -426.089826)
				)
			)
		)
	)
	(zone
		(layers "B.Cu" "In11.Cu" "In13.Cu" "In15.Cu")
		(hatch none 0.5)
		(connect_pads
			(clearance 0)
		)
		(min_thickness 0.25)
		(keepout
			(tracks not_allowed)
			(vias allowed)
			(pads allowed)
			(copperpour not_allowed)
			(footprints allowed)
		)
		(placement
			(enabled no)
			(sheetname "")
		)
		(fill yes
			(thermal_gap 0.5)
			(thermal_bridge_width 0.5)
			(island_removal_mode 0)
		)
		(polygon
			(pts
				(arc
					(start 277.526242 -283.185108)
					(mid 276.858222 -283.185108)
					(end 277.526242 -283.185108)
				)
			)
		)
	)
	(zone
		(layers "B.Cu" "In11.Cu" "In13.Cu" "In15.Cu")
		(hatch none 0.5)
		(connect_pads
			(clearance 0)
		)
		(min_thickness 0.25)
		(keepout
			(tracks not_allowed)
			(vias allowed)
			(pads allowed)
			(copperpour not_allowed)
			(footprints allowed)
		)
		(placement
			(enabled no)
			(sheetname "")
		)
		(fill yes
			(thermal_gap 0.5)
			(thermal_bridge_width 0.5)
			(island_removal_mode 0)
		)
		(polygon
			(pts
				(arc
					(start 442.87821 -267.035026)
					(mid 442.21019 -267.035026)
					(end 442.87821 -267.035026)
				)
			)
		)
	)
	(zone
		(layers "B.Cu" "In11.Cu" "In13.Cu" "In15.Cu")
		(hatch none 0.5)
		(connect_pads
			(clearance 0)
		)
		(min_thickness 0.25)
		(keepout
			(tracks not_allowed)
			(vias allowed)
			(pads allowed)
			(copperpour not_allowed)
			(footprints allowed)
		)
		(placement
			(enabled no)
			(sheetname "")
		)
		(fill yes
			(thermal_gap 0.5)
			(thermal_bridge_width 0.5)
			(island_removal_mode 0)
		)
		(polygon
			(pts
				(arc
					(start 100.815902 -239.624362)
					(mid 100.185982 -239.624362)
					(end 100.815902 -239.624362)
				)
			)
		)
	)
	(zone
		(layers "B.Cu" "In11.Cu" "In13.Cu" "In15.Cu")
		(hatch none 0.5)
		(connect_pads
			(clearance 0)
		)
		(min_thickness 0.25)
		(keepout
			(tracks not_allowed)
			(vias allowed)
			(pads allowed)
			(copperpour not_allowed)
			(footprints allowed)
		)
		(placement
			(enabled no)
			(sheetname "")
		)
		(fill yes
			(thermal_gap 0.5)
			(thermal_bridge_width 0.5)
			(island_removal_mode 0)
		)
		(polygon
			(pts
				(arc
					(start 143.109696 -254.20447)
					(mid 142.479776 -254.20447)
					(end 143.109696 -254.20447)
				)
			)
		)
	)
	(zone
		(layers "B.Cu" "In11.Cu" "In13.Cu" "In15.Cu")
		(hatch none 0.5)
		(connect_pads
			(clearance 0)
		)
		(min_thickness 0.25)
		(keepout
			(tracks not_allowed)
			(vias allowed)
			(pads allowed)
			(copperpour not_allowed)
			(footprints allowed)
		)
		(placement
			(enabled no)
			(sheetname "")
		)
		(fill yes
			(thermal_gap 0.5)
			(thermal_bridge_width 0.5)
			(island_removal_mode 0)
		)
		(polygon
			(pts
				(arc
					(start 141.999716 -291.906198)
					(mid 141.369796 -291.906198)
					(end 141.999716 -291.906198)
				)
			)
		)
	)
	(zone
		(layers "B.Cu" "In11.Cu" "In13.Cu" "In15.Cu")
		(hatch none 0.5)
		(connect_pads
			(clearance 0)
		)
		(min_thickness 0.25)
		(keepout
			(tracks not_allowed)
			(vias allowed)
			(pads allowed)
			(copperpour not_allowed)
			(footprints allowed)
		)
		(placement
			(enabled no)
			(sheetname "")
		)
		(fill yes
			(thermal_gap 0.5)
			(thermal_bridge_width 0.5)
			(island_removal_mode 0)
		)
		(polygon
			(pts
				(arc
					(start 73.036938 -421.089836)
					(mid 72.262746 -421.089836)
					(end 73.036938 -421.089836)
				)
			)
		)
	)
	(zone
		(layers "B.Cu" "In11.Cu" "In13.Cu" "In15.Cu")
		(hatch none 0.5)
		(connect_pads
			(clearance 0)
		)
		(min_thickness 0.25)
		(keepout
			(tracks not_allowed)
			(vias allowed)
			(pads allowed)
			(copperpour not_allowed)
			(footprints allowed)
		)
		(placement
			(enabled no)
			(sheetname "")
		)
		(fill yes
			(thermal_gap 0.5)
			(thermal_bridge_width 0.5)
			(island_removal_mode 0)
		)
		(polygon
			(pts
				(arc
					(start 63.706248 -388.774432)
					(mid 63.076328 -388.774432)
					(end 63.706248 -388.774432)
				)
			)
		)
	)
	(zone
		(layers "B.Cu" "In11.Cu" "In13.Cu" "In15.Cu")
		(hatch none 0.5)
		(connect_pads
			(clearance 0)
		)
		(min_thickness 0.25)
		(keepout
			(tracks not_allowed)
			(vias allowed)
			(pads allowed)
			(copperpour not_allowed)
			(footprints allowed)
		)
		(placement
			(enabled no)
			(sheetname "")
		)
		(fill yes
			(thermal_gap 0.5)
			(thermal_bridge_width 0.5)
			(island_removal_mode 0)
		)
		(polygon
			(pts
				(arc
					(start 389.63981 -240.434114)
					(mid 389.00989 -240.434114)
					(end 389.63981 -240.434114)
				)
			)
		)
	)
	(zone
		(layers "B.Cu" "In11.Cu" "In13.Cu" "In15.Cu")
		(hatch none 0.5)
		(connect_pads
			(clearance 0)
		)
		(min_thickness 0.25)
		(keepout
			(tracks not_allowed)
			(vias allowed)
			(pads allowed)
			(copperpour not_allowed)
			(footprints allowed)
		)
		(placement
			(enabled no)
			(sheetname "")
		)
		(fill yes
			(thermal_gap 0.5)
			(thermal_bridge_width 0.5)
			(island_removal_mode 0)
		)
		(polygon
			(pts
				(arc
					(start 141.529816 -284.616398)
					(mid 140.899896 -284.616398)
					(end 141.529816 -284.616398)
				)
			)
		)
	)
	(zone
		(layers "B.Cu" "In11.Cu" "In13.Cu" "In15.Cu")
		(hatch none 0.5)
		(connect_pads
			(clearance 0)
		)
		(min_thickness 0.25)
		(keepout
			(tracks not_allowed)
			(vias allowed)
			(pads allowed)
			(copperpour not_allowed)
			(footprints allowed)
		)
		(placement
			(enabled no)
			(sheetname "")
		)
		(fill yes
			(thermal_gap 0.5)
			(thermal_bridge_width 0.5)
			(island_removal_mode 0)
		)
		(polygon
			(pts
				(arc
					(start 81.845912 -288.666174)
					(mid 81.215992 -288.666174)
					(end 81.845912 -288.666174)
				)
			)
		)
	)
	(zone
		(layers "B.Cu" "In11.Cu" "In13.Cu" "In15.Cu")
		(hatch none 0.5)
		(connect_pads
			(clearance 0)
		)
		(min_thickness 0.25)
		(keepout
			(tracks not_allowed)
			(vias allowed)
			(pads allowed)
			(copperpour not_allowed)
			(footprints allowed)
		)
		(placement
			(enabled no)
			(sheetname "")
		)
		(fill yes
			(thermal_gap 0.5)
			(thermal_bridge_width 0.5)
			(island_removal_mode 0)
		)
		(polygon
			(pts
				(arc
					(start 446.978278 -219.435172)
					(mid 446.310258 -219.435172)
					(end 446.978278 -219.435172)
				)
			)
		)
	)
	(zone
		(layers "B.Cu" "In11.Cu" "In13.Cu" "In15.Cu")
		(hatch none 0.5)
		(connect_pads
			(clearance 0)
		)
		(min_thickness 0.25)
		(keepout
			(tracks not_allowed)
			(vias allowed)
			(pads allowed)
			(copperpour not_allowed)
			(footprints allowed)
		)
		(placement
			(enabled no)
			(sheetname "")
		)
		(fill yes
			(thermal_gap 0.5)
			(thermal_bridge_width 0.5)
			(island_removal_mode 0)
		)
		(polygon
			(pts
				(arc
					(start 394.13688 -427.289976)
					(mid 393.362688 -427.289976)
					(end 394.13688 -427.289976)
				)
			)
		)
	)
	(zone
		(layers "B.Cu" "In11.Cu" "In13.Cu" "In15.Cu")
		(hatch none 0.5)
		(connect_pads
			(clearance 0)
		)
		(min_thickness 0.25)
		(keepout
			(tracks not_allowed)
			(vias allowed)
			(pads allowed)
			(copperpour not_allowed)
			(footprints allowed)
		)
		(placement
			(enabled no)
			(sheetname "")
		)
		(fill yes
			(thermal_gap 0.5)
			(thermal_bridge_width 0.5)
			(island_removal_mode 0)
		)
		(polygon
			(pts
				(arc
					(start 194.938142 -304.435256)
					(mid 194.270122 -304.435256)
					(end 194.938142 -304.435256)
				)
			)
		)
	)
	(zone
		(layers "B.Cu" "In11.Cu" "In13.Cu" "In15.Cu")
		(hatch none 0.5)
		(connect_pads
			(clearance 0)
		)
		(min_thickness 0.25)
		(keepout
			(tracks not_allowed)
			(vias allowed)
			(pads allowed)
			(copperpour not_allowed)
			(footprints allowed)
		)
		(placement
			(enabled no)
			(sheetname "")
		)
		(fill yes
			(thermal_gap 0.5)
			(thermal_bridge_width 0.5)
			(island_removal_mode 0)
		)
		(polygon
			(pts
				(arc
					(start 71.036942 -423.68978)
					(mid 70.26275 -423.68978)
					(end 71.036942 -423.68978)
				)
			)
		)
	)
	(zone
		(layers "B.Cu" "In11.Cu" "In13.Cu" "In15.Cu")
		(hatch none 0.5)
		(connect_pads
			(clearance 0)
		)
		(min_thickness 0.25)
		(keepout
			(tracks not_allowed)
			(vias allowed)
			(pads allowed)
			(copperpour not_allowed)
			(footprints allowed)
		)
		(placement
			(enabled no)
			(sheetname "")
		)
		(fill yes
			(thermal_gap 0.5)
			(thermal_bridge_width 0.5)
			(island_removal_mode 0)
		)
		(polygon
			(pts
				(arc
					(start 48.10633 -388.774432)
					(mid 47.47641 -388.774432)
					(end 48.10633 -388.774432)
				)
			)
		)
	)
	(zone
		(layers "B.Cu" "In11.Cu" "In13.Cu" "In15.Cu")
		(hatch none 0.5)
		(connect_pads
			(clearance 0)
		)
		(min_thickness 0.25)
		(keepout
			(tracks not_allowed)
			(vias allowed)
			(pads allowed)
			(copperpour not_allowed)
			(footprints allowed)
		)
		(placement
			(enabled no)
			(sheetname "")
		)
		(fill yes
			(thermal_gap 0.5)
			(thermal_bridge_width 0.5)
			(island_removal_mode 0)
		)
		(polygon
			(pts
				(arc
					(start 315.036708 -426.089826)
					(mid 314.262516 -426.089826)
					(end 315.036708 -426.089826)
				)
			)
		)
	)
	(zone
		(layers "B.Cu" "In11.Cu" "In13.Cu" "In15.Cu")
		(hatch none 0.5)
		(connect_pads
			(clearance 0)
		)
		(min_thickness 0.25)
		(keepout
			(tracks not_allowed)
			(vias allowed)
			(pads allowed)
			(copperpour not_allowed)
			(footprints allowed)
		)
		(placement
			(enabled no)
			(sheetname "")
		)
		(fill yes
			(thermal_gap 0.5)
			(thermal_bridge_width 0.5)
			(island_removal_mode 0)
		)
		(polygon
			(pts
				(arc
					(start 330.89596 -252.584204)
					(mid 330.26604 -252.584204)
					(end 330.89596 -252.584204)
				)
			)
		)
	)
	(zone
		(layers "B.Cu" "In11.Cu" "In13.Cu" "In15.Cu")
		(hatch none 0.5)
		(connect_pads
			(clearance 0)
		)
		(min_thickness 0.25)
		(keepout
			(tracks not_allowed)
			(vias allowed)
			(pads allowed)
			(copperpour not_allowed)
			(footprints allowed)
		)
		(placement
			(enabled no)
			(sheetname "")
		)
		(fill yes
			(thermal_gap 0.5)
			(thermal_bridge_width 0.5)
			(island_removal_mode 0)
		)
		(polygon
			(pts
				(arc
					(start 365.144812 -0.429006)
					(mid 364.476792 -0.429006)
					(end 365.144812 -0.429006)
				)
			)
		)
	)
	(zone
		(layers "B.Cu" "In11.Cu" "In13.Cu" "In15.Cu")
		(hatch none 0.5)
		(connect_pads
			(clearance 0)
		)
		(min_thickness 0.25)
		(keepout
			(tracks not_allowed)
			(vias allowed)
			(pads allowed)
			(copperpour not_allowed)
			(footprints allowed)
		)
		(placement
			(enabled no)
			(sheetname "")
		)
		(fill yes
			(thermal_gap 0.5)
			(thermal_bridge_width 0.5)
			(island_removal_mode 0)
		)
		(polygon
			(pts
				(arc
					(start 62.068964 -373.96293)
					(mid 61.400944 -373.96293)
					(end 62.068964 -373.96293)
				)
			)
		)
	)
	(zone
		(layers "B.Cu" "In11.Cu" "In13.Cu" "In15.Cu")
		(hatch none 0.5)
		(connect_pads
			(clearance 0)
		)
		(min_thickness 0.25)
		(keepout
			(tracks not_allowed)
			(vias allowed)
			(pads allowed)
			(copperpour not_allowed)
			(footprints allowed)
		)
		(placement
			(enabled no)
			(sheetname "")
		)
		(fill yes
			(thermal_gap 0.5)
			(thermal_bridge_width 0.5)
			(island_removal_mode 0)
		)
		(polygon
			(pts
				(arc
					(start 29.586174 -228.78542)
					(mid 28.918154 -228.78542)
					(end 29.586174 -228.78542)
				)
			)
		)
	)
	(zone
		(layers "B.Cu" "In11.Cu" "In13.Cu" "In15.Cu")
		(hatch none 0.5)
		(connect_pads
			(clearance 0)
		)
		(min_thickness 0.25)
		(keepout
			(tracks not_allowed)
			(vias allowed)
			(pads allowed)
			(copperpour not_allowed)
			(footprints allowed)
		)
		(placement
			(enabled no)
			(sheetname "")
		)
		(fill yes
			(thermal_gap 0.5)
			(thermal_bridge_width 0.5)
			(island_removal_mode 0)
		)
		(polygon
			(pts
				(arc
					(start 108.80598 -238.814356)
					(mid 108.17606 -238.814356)
					(end 108.80598 -238.814356)
				)
			)
		)
	)
	(zone
		(layers "B.Cu" "In11.Cu" "In13.Cu" "In15.Cu")
		(hatch none 0.5)
		(connect_pads
			(clearance 0)
		)
		(min_thickness 0.25)
		(keepout
			(tracks not_allowed)
			(vias allowed)
			(pads allowed)
			(copperpour not_allowed)
			(footprints allowed)
		)
		(placement
			(enabled no)
			(sheetname "")
		)
		(fill yes
			(thermal_gap 0.5)
			(thermal_bridge_width 0.5)
			(island_removal_mode 0)
		)
		(polygon
			(pts
				(arc
					(start 102.05593 -282.996386)
					(mid 101.42601 -282.996386)
					(end 102.05593 -282.996386)
				)
			)
		)
	)
	(zone
		(layers "B.Cu" "In11.Cu" "In13.Cu" "In15.Cu")
		(hatch none 0.5)
		(connect_pads
			(clearance 0)
		)
		(min_thickness 0.25)
		(keepout
			(tracks not_allowed)
			(vias allowed)
			(pads allowed)
			(copperpour not_allowed)
			(footprints allowed)
		)
		(placement
			(enabled no)
			(sheetname "")
		)
		(fill yes
			(thermal_gap 0.5)
			(thermal_bridge_width 0.5)
			(island_removal_mode 0)
		)
		(polygon
			(pts
				(arc
					(start 199.03821 -220.28531)
					(mid 198.37019 -220.28531)
					(end 199.03821 -220.28531)
				)
			)
		)
	)
	(zone
		(layers "B.Cu" "In11.Cu" "In13.Cu" "In15.Cu")
		(hatch none 0.5)
		(connect_pads
			(clearance 0)
		)
		(min_thickness 0.25)
		(keepout
			(tracks not_allowed)
			(vias allowed)
			(pads allowed)
			(copperpour not_allowed)
			(footprints allowed)
		)
		(placement
			(enabled no)
			(sheetname "")
		)
		(fill yes
			(thermal_gap 0.5)
			(thermal_bridge_width 0.5)
			(island_removal_mode 0)
		)
		(polygon
			(pts
				(arc
					(start 329.31608 -270.036036)
					(mid 328.68616 -270.036036)
					(end 329.31608 -270.036036)
				)
			)
		)
	)
	(zone
		(layers "B.Cu" "In11.Cu" "In13.Cu" "In15.Cu")
		(hatch none 0.5)
		(connect_pads
			(clearance 0)
		)
		(min_thickness 0.25)
		(keepout
			(tracks not_allowed)
			(vias allowed)
			(pads allowed)
			(copperpour not_allowed)
			(footprints allowed)
		)
		(placement
			(enabled no)
			(sheetname "")
		)
		(fill yes
			(thermal_gap 0.5)
			(thermal_bridge_width 0.5)
			(island_removal_mode 0)
		)
		(polygon
			(pts
				(arc
					(start 329.016106 -231.524048)
					(mid 328.386186 -231.524048)
					(end 329.016106 -231.524048)
				)
			)
		)
	)
	(zone
		(layers "B.Cu" "In11.Cu" "In13.Cu" "In15.Cu")
		(hatch none 0.5)
		(connect_pads
			(clearance 0)
		)
		(min_thickness 0.25)
		(keepout
			(tracks not_allowed)
			(vias allowed)
			(pads allowed)
			(copperpour not_allowed)
			(footprints allowed)
		)
		(placement
			(enabled no)
			(sheetname "")
		)
		(fill yes
			(thermal_gap 0.5)
			(thermal_bridge_width 0.5)
			(island_removal_mode 0)
		)
		(polygon
			(pts
				(arc
					(start 329.486006 -240.434114)
					(mid 328.856086 -240.434114)
					(end 329.486006 -240.434114)
				)
			)
		)
	)
	(zone
		(layers "B.Cu" "In11.Cu" "In13.Cu" "In15.Cu")
		(hatch none 0.5)
		(connect_pads
			(clearance 0)
		)
		(min_thickness 0.25)
		(keepout
			(tracks not_allowed)
			(vias allowed)
			(pads allowed)
			(copperpour not_allowed)
			(footprints allowed)
		)
		(placement
			(enabled no)
			(sheetname "")
		)
		(fill yes
			(thermal_gap 0.5)
			(thermal_bridge_width 0.5)
			(island_removal_mode 0)
		)
		(polygon
			(pts
				(arc
					(start 143.109696 -228.284532)
					(mid 142.479776 -228.284532)
					(end 143.109696 -228.284532)
				)
			)
		)
	)
	(zone
		(layers "B.Cu" "In11.Cu" "In13.Cu" "In15.Cu")
		(hatch none 0.5)
		(connect_pads
			(clearance 0)
		)
		(min_thickness 0.25)
		(keepout
			(tracks not_allowed)
			(vias allowed)
			(pads allowed)
			(copperpour not_allowed)
			(footprints allowed)
		)
		(placement
			(enabled no)
			(sheetname "")
		)
		(fill yes
			(thermal_gap 0.5)
			(thermal_bridge_width 0.5)
			(island_removal_mode 0)
		)
		(polygon
			(pts
				(arc
					(start 155.137104 -427.289976)
					(mid 154.362912 -427.289976)
					(end 155.137104 -427.289976)
				)
			)
		)
	)
	(zone
		(layers "B.Cu" "In11.Cu" "In13.Cu" "In15.Cu")
		(hatch none 0.5)
		(connect_pads
			(clearance 0)
		)
		(min_thickness 0.25)
		(keepout
			(tracks not_allowed)
			(vias allowed)
			(pads allowed)
			(copperpour not_allowed)
			(footprints allowed)
		)
		(placement
			(enabled no)
			(sheetname "")
		)
		(fill yes
			(thermal_gap 0.5)
			(thermal_bridge_width 0.5)
			(island_removal_mode 0)
		)
		(polygon
			(pts
				(arc
					(start 124.006102 -389.467344)
					(mid 123.376182 -389.467344)
					(end 124.006102 -389.467344)
				)
			)
		)
	)
	(zone
		(layers "B.Cu" "In11.Cu" "In13.Cu" "In15.Cu")
		(hatch none 0.5)
		(connect_pads
			(clearance 0)
		)
		(min_thickness 0.25)
		(keepout
			(tracks not_allowed)
			(vias allowed)
			(pads allowed)
			(copperpour not_allowed)
			(footprints allowed)
		)
		(placement
			(enabled no)
			(sheetname "")
		)
		(fill yes
			(thermal_gap 0.5)
			(thermal_bridge_width 0.5)
			(island_removal_mode 0)
		)
		(polygon
			(pts
				(arc
					(start 391.349738 -286.236156)
					(mid 390.719818 -286.236156)
					(end 391.349738 -286.236156)
				)
			)
		)
	)
	(zone
		(layers "B.Cu" "In11.Cu" "In13.Cu" "In15.Cu")
		(hatch none 0.5)
		(connect_pads
			(clearance 0)
		)
		(min_thickness 0.25)
		(keepout
			(tracks not_allowed)
			(vias allowed)
			(pads allowed)
			(copperpour not_allowed)
			(footprints allowed)
		)
		(placement
			(enabled no)
			(sheetname "")
		)
		(fill yes
			(thermal_gap 0.5)
			(thermal_bridge_width 0.5)
			(island_removal_mode 0)
		)
		(polygon
			(pts
				(arc
					(start 29.586174 -264.485374)
					(mid 28.918154 -264.485374)
					(end 29.586174 -264.485374)
				)
			)
		)
	)
	(zone
		(layers "B.Cu" "In11.Cu" "In13.Cu" "In15.Cu")
		(hatch none 0.5)
		(connect_pads
			(clearance 0)
		)
		(min_thickness 0.25)
		(keepout
			(tracks not_allowed)
			(vias allowed)
			(pads allowed)
			(copperpour not_allowed)
			(footprints allowed)
		)
		(placement
			(enabled no)
			(sheetname "")
		)
		(fill yes
			(thermal_gap 0.5)
			(thermal_bridge_width 0.5)
			(island_removal_mode 0)
		)
		(polygon
			(pts
				(arc
					(start 446.978278 -261.085076)
					(mid 446.310258 -261.085076)
					(end 446.978278 -261.085076)
				)
			)
		)
	)
	(zone
		(layers "B.Cu" "In11.Cu" "In13.Cu" "In15.Cu")
		(hatch none 0.5)
		(connect_pads
			(clearance 0)
		)
		(min_thickness 0.25)
		(keepout
			(tracks not_allowed)
			(vias allowed)
			(pads allowed)
			(copperpour not_allowed)
			(footprints allowed)
		)
		(placement
			(enabled no)
			(sheetname "")
		)
		(fill yes
			(thermal_gap 0.5)
			(thermal_bridge_width 0.5)
			(island_removal_mode 0)
		)
		(polygon
			(pts
				(arc
					(start 109.746034 -240.434368)
					(mid 109.116114 -240.434368)
					(end 109.746034 -240.434368)
				)
			)
		)
	)
	(zone
		(layers "B.Cu" "In11.Cu" "In13.Cu" "In15.Cu")
		(hatch none 0.5)
		(connect_pads
			(clearance 0)
		)
		(min_thickness 0.25)
		(keepout
			(tracks not_allowed)
			(vias allowed)
			(pads allowed)
			(copperpour not_allowed)
			(footprints allowed)
		)
		(placement
			(enabled no)
			(sheetname "")
		)
		(fill yes
			(thermal_gap 0.5)
			(thermal_bridge_width 0.5)
			(island_removal_mode 0)
		)
		(polygon
			(pts
				(arc
					(start 82.785966 -283.806392)
					(mid 82.156046 -283.806392)
					(end 82.785966 -283.806392)
				)
			)
		)
	)
	(zone
		(layers "B.Cu" "In11.Cu" "In13.Cu" "In15.Cu")
		(hatch none 0.5)
		(connect_pads
			(clearance 0)
		)
		(min_thickness 0.25)
		(keepout
			(tracks not_allowed)
			(vias allowed)
			(pads allowed)
			(copperpour not_allowed)
			(footprints allowed)
		)
		(placement
			(enabled no)
			(sheetname "")
		)
		(fill yes
			(thermal_gap 0.5)
			(thermal_bridge_width 0.5)
			(island_removal_mode 0)
		)
		(polygon
			(pts
				(arc
					(start 110.046008 -282.18638)
					(mid 109.416088 -282.18638)
					(end 110.046008 -282.18638)
				)
			)
		)
	)
	(zone
		(layers "B.Cu" "In11.Cu" "In13.Cu" "In15.Cu")
		(hatch none 0.5)
		(connect_pads
			(clearance 0)
		)
		(min_thickness 0.25)
		(keepout
			(tracks not_allowed)
			(vias allowed)
			(pads allowed)
			(copperpour not_allowed)
			(footprints allowed)
		)
		(placement
			(enabled no)
			(sheetname "")
		)
		(fill yes
			(thermal_gap 0.5)
			(thermal_bridge_width 0.5)
			(island_removal_mode 0)
		)
		(polygon
			(pts
				(arc
					(start 141.699742 -225.854514)
					(mid 141.069822 -225.854514)
					(end 141.699742 -225.854514)
				)
			)
		)
	)
	(zone
		(layers "B.Cu" "In11.Cu" "In13.Cu" "In15.Cu")
		(hatch none 0.5)
		(connect_pads
			(clearance 0)
		)
		(min_thickness 0.25)
		(keepout
			(tracks not_allowed)
			(vias allowed)
			(pads allowed)
			(copperpour not_allowed)
			(footprints allowed)
		)
		(placement
			(enabled no)
			(sheetname "")
		)
		(fill yes
			(thermal_gap 0.5)
			(thermal_bridge_width 0.5)
			(island_removal_mode 0)
		)
		(polygon
			(pts
				(arc
					(start 83.255866 -276.516338)
					(mid 82.625946 -276.516338)
					(end 83.255866 -276.516338)
				)
			)
		)
	)
	(zone
		(layers "B.Cu" "In11.Cu" "In13.Cu" "In15.Cu")
		(hatch none 0.5)
		(connect_pads
			(clearance 0)
		)
		(min_thickness 0.25)
		(keepout
			(tracks not_allowed)
			(vias allowed)
			(pads allowed)
			(copperpour not_allowed)
			(footprints allowed)
		)
		(placement
			(enabled no)
			(sheetname "")
		)
		(fill yes
			(thermal_gap 0.5)
			(thermal_bridge_width 0.5)
			(island_removal_mode 0)
		)
		(polygon
			(pts
				(arc
					(start 330.726034 -287.045908)
					(mid 330.096114 -287.045908)
					(end 330.726034 -287.045908)
				)
			)
		)
	)
	(zone
		(layers "B.Cu" "In11.Cu" "In13.Cu" "In15.Cu")
		(hatch none 0.5)
		(connect_pads
			(clearance 0)
		)
		(min_thickness 0.25)
		(keepout
			(tracks not_allowed)
			(vias allowed)
			(pads allowed)
			(copperpour not_allowed)
			(footprints allowed)
		)
		(placement
			(enabled no)
			(sheetname "")
		)
		(fill yes
			(thermal_gap 0.5)
			(thermal_bridge_width 0.5)
			(island_removal_mode 0)
		)
		(polygon
			(pts
				(arc
					(start 389.63981 -233.954066)
					(mid 389.00989 -233.954066)
					(end 389.63981 -233.954066)
				)
			)
		)
	)
	(zone
		(layers "B.Cu" "In11.Cu" "In13.Cu" "In15.Cu")
		(hatch none 0.5)
		(connect_pads
			(clearance 0)
		)
		(min_thickness 0.25)
		(keepout
			(tracks not_allowed)
			(vias allowed)
			(pads allowed)
			(copperpour not_allowed)
			(footprints allowed)
		)
		(placement
			(enabled no)
			(sheetname "")
		)
		(fill yes
			(thermal_gap 0.5)
			(thermal_bridge_width 0.5)
			(island_removal_mode 0)
		)
		(polygon
			(pts
				(arc
					(start 116.806218 -389.467344)
					(mid 116.176298 -389.467344)
					(end 116.806218 -389.467344)
				)
			)
		)
	)
	(zone
		(layers "B.Cu" "In11.Cu" "In13.Cu" "In15.Cu")
		(hatch none 0.5)
		(connect_pads
			(clearance 0)
		)
		(min_thickness 0.25)
		(keepout
			(tracks not_allowed)
			(vias allowed)
			(pads allowed)
			(copperpour not_allowed)
			(footprints allowed)
		)
		(placement
			(enabled no)
			(sheetname "")
		)
		(fill yes
			(thermal_gap 0.5)
			(thermal_bridge_width 0.5)
			(island_removal_mode 0)
		)
		(polygon
			(pts
				(arc
					(start 29.586174 -238.985298)
					(mid 28.918154 -238.985298)
					(end 29.586174 -238.985298)
				)
			)
		)
	)
	(zone
		(layers "B.Cu" "In11.Cu" "In13.Cu" "In15.Cu")
		(hatch none 0.5)
		(connect_pads
			(clearance 0)
		)
		(min_thickness 0.25)
		(keepout
			(tracks not_allowed)
			(vias allowed)
			(pads allowed)
			(copperpour not_allowed)
			(footprints allowed)
		)
		(placement
			(enabled no)
			(sheetname "")
		)
		(fill yes
			(thermal_gap 0.5)
			(thermal_bridge_width 0.5)
			(island_removal_mode 0)
		)
		(polygon
			(pts
				(arc
					(start 82.955892 -236.384338)
					(mid 82.325972 -236.384338)
					(end 82.955892 -236.384338)
				)
			)
		)
	)
	(zone
		(layers "B.Cu" "In11.Cu" "In13.Cu" "In15.Cu")
		(hatch none 0.5)
		(connect_pads
			(clearance 0)
		)
		(min_thickness 0.25)
		(keepout
			(tracks not_allowed)
			(vias allowed)
			(pads allowed)
			(copperpour not_allowed)
			(footprints allowed)
		)
		(placement
			(enabled no)
			(sheetname "")
		)
		(fill yes
			(thermal_gap 0.5)
			(thermal_bridge_width 0.5)
			(island_removal_mode 0)
		)
		(polygon
			(pts
				(arc
					(start 115.679728 -285.426404)
					(mid 115.049808 -285.426404)
					(end 115.679728 -285.426404)
				)
			)
		)
	)
	(zone
		(layers "B.Cu" "In11.Cu" "In13.Cu" "In15.Cu")
		(hatch none 0.5)
		(connect_pads
			(clearance 0)
		)
		(min_thickness 0.25)
		(keepout
			(tracks not_allowed)
			(vias allowed)
			(pads allowed)
			(copperpour not_allowed)
			(footprints allowed)
		)
		(placement
			(enabled no)
			(sheetname "")
		)
		(fill yes
			(thermal_gap 0.5)
			(thermal_bridge_width 0.5)
			(island_removal_mode 0)
		)
		(polygon
			(pts
				(arc
					(start 347.17609 -284.616144)
					(mid 346.54617 -284.616144)
					(end 347.17609 -284.616144)
				)
			)
		)
	)
	(zone
		(layers "B.Cu" "In11.Cu" "In13.Cu" "In15.Cu")
		(hatch none 0.5)
		(connect_pads
			(clearance 0)
		)
		(min_thickness 0.25)
		(keepout
			(tracks not_allowed)
			(vias allowed)
			(pads allowed)
			(copperpour not_allowed)
			(footprints allowed)
		)
		(placement
			(enabled no)
			(sheetname "")
		)
		(fill yes
			(thermal_gap 0.5)
			(thermal_bridge_width 0.5)
			(island_removal_mode 0)
		)
		(polygon
			(pts
				(arc
					(start 199.03821 -269.58544)
					(mid 198.37019 -269.58544)
					(end 199.03821 -269.58544)
				)
			)
		)
	)
	(zone
		(layers "B.Cu" "In11.Cu" "In13.Cu" "In15.Cu")
		(hatch none 0.5)
		(connect_pads
			(clearance 0)
		)
		(min_thickness 0.25)
		(keepout
			(tracks not_allowed)
			(vias allowed)
			(pads allowed)
			(copperpour not_allowed)
			(footprints allowed)
		)
		(placement
			(enabled no)
			(sheetname "")
		)
		(fill yes
			(thermal_gap 0.5)
			(thermal_bridge_width 0.5)
			(island_removal_mode 0)
		)
		(polygon
			(pts
				(arc
					(start 199.03821 -217.735404)
					(mid 198.37019 -217.735404)
					(end 199.03821 -217.735404)
				)
			)
		)
	)
	(zone
		(layers "B.Cu" "In11.Cu" "In13.Cu" "In15.Cu")
		(hatch none 0.5)
		(connect_pads
			(clearance 0)
		)
		(min_thickness 0.25)
		(keepout
			(tracks not_allowed)
			(vias allowed)
			(pads allowed)
			(copperpour not_allowed)
			(footprints allowed)
		)
		(placement
			(enabled no)
			(sheetname "")
		)
		(fill yes
			(thermal_gap 0.5)
			(thermal_bridge_width 0.5)
			(island_removal_mode 0)
		)
		(polygon
			(pts
				(arc
					(start 106.755946 -282.996386)
					(mid 106.126026 -282.996386)
					(end 106.755946 -282.996386)
				)
			)
		)
	)
	(zone
		(layers "B.Cu" "In11.Cu" "In13.Cu" "In15.Cu")
		(hatch none 0.5)
		(connect_pads
			(clearance 0)
		)
		(min_thickness 0.25)
		(keepout
			(tracks not_allowed)
			(vias allowed)
			(pads allowed)
			(copperpour not_allowed)
			(footprints allowed)
		)
		(placement
			(enabled no)
			(sheetname "")
		)
		(fill yes
			(thermal_gap 0.5)
			(thermal_bridge_width 0.5)
			(island_removal_mode 0)
		)
		(polygon
			(pts
				(arc
					(start 120.00611 -388.774432)
					(mid 119.37619 -388.774432)
					(end 120.00611 -388.774432)
				)
			)
		)
	)
	(zone
		(layers "B.Cu" "In11.Cu" "In13.Cu" "In15.Cu")
		(hatch none 0.5)
		(connect_pads
			(clearance 0)
		)
		(min_thickness 0.25)
		(keepout
			(tracks not_allowed)
			(vias allowed)
			(pads allowed)
			(copperpour not_allowed)
			(footprints allowed)
		)
		(placement
			(enabled no)
			(sheetname "")
		)
		(fill yes
			(thermal_gap 0.5)
			(thermal_bridge_width 0.5)
			(island_removal_mode 0)
		)
		(polygon
			(pts
				(arc
					(start 25.486106 -227.935282)
					(mid 24.818086 -227.935282)
					(end 25.486106 -227.935282)
				)
			)
		)
	)
	(zone
		(layers "B.Cu" "In11.Cu" "In13.Cu" "In15.Cu")
		(hatch none 0.5)
		(connect_pads
			(clearance 0)
		)
		(min_thickness 0.25)
		(keepout
			(tracks not_allowed)
			(vias allowed)
			(pads allowed)
			(copperpour not_allowed)
			(footprints allowed)
		)
		(placement
			(enabled no)
			(sheetname "")
		)
		(fill yes
			(thermal_gap 0.5)
			(thermal_bridge_width 0.5)
			(island_removal_mode 0)
		)
		(polygon
			(pts
				(arc
					(start 404.933912 -393.69238)
					(mid 404.303992 -393.69238)
					(end 404.933912 -393.69238)
				)
			)
		)
	)
	(zone
		(layers "B.Cu" "In11.Cu" "In13.Cu" "In15.Cu")
		(hatch none 0.5)
		(connect_pads
			(clearance 0)
		)
		(min_thickness 0.25)
		(keepout
			(tracks not_allowed)
			(vias allowed)
			(pads allowed)
			(copperpour not_allowed)
			(footprints allowed)
		)
		(placement
			(enabled no)
			(sheetname "")
		)
		(fill yes
			(thermal_gap 0.5)
			(thermal_bridge_width 0.5)
			(island_removal_mode 0)
		)
		(polygon
			(pts
				(arc
					(start 109.746034 -242.05438)
					(mid 109.116114 -242.05438)
					(end 109.746034 -242.05438)
				)
			)
		)
	)
	(zone
		(layers "B.Cu" "In11.Cu" "In13.Cu" "In15.Cu")
		(hatch none 0.5)
		(connect_pads
			(clearance 0)
		)
		(min_thickness 0.25)
		(keepout
			(tracks not_allowed)
			(vias allowed)
			(pads allowed)
			(copperpour not_allowed)
			(footprints allowed)
		)
		(placement
			(enabled no)
			(sheetname "")
		)
		(fill yes
			(thermal_gap 0.5)
			(thermal_bridge_width 0.5)
			(island_removal_mode 0)
		)
		(polygon
			(pts
				(arc
					(start 199.03821 -278.085296)
					(mid 198.37019 -278.085296)
					(end 199.03821 -278.085296)
				)
			)
		)
	)
	(zone
		(layers "B.Cu" "In11.Cu" "In13.Cu" "In15.Cu")
		(hatch none 0.5)
		(connect_pads
			(clearance 0)
		)
		(min_thickness 0.25)
		(keepout
			(tracks not_allowed)
			(vias allowed)
			(pads allowed)
			(copperpour not_allowed)
			(footprints allowed)
		)
		(placement
			(enabled no)
			(sheetname "")
		)
		(fill yes
			(thermal_gap 0.5)
			(thermal_bridge_width 0.5)
			(island_removal_mode 0)
		)
		(polygon
			(pts
				(arc
					(start 442.87821 -289.985196)
					(mid 442.21019 -289.985196)
					(end 442.87821 -289.985196)
				)
			)
		)
	)
	(zone
		(layers "B.Cu" "In11.Cu" "In13.Cu" "In15.Cu")
		(hatch none 0.5)
		(connect_pads
			(clearance 0)
		)
		(min_thickness 0.25)
		(keepout
			(tracks not_allowed)
			(vias allowed)
			(pads allowed)
			(copperpour not_allowed)
			(footprints allowed)
		)
		(placement
			(enabled no)
			(sheetname "")
		)
		(fill yes
			(thermal_gap 0.5)
			(thermal_bridge_width 0.5)
			(island_removal_mode 0)
		)
		(polygon
			(pts
				(arc
					(start 29.586174 -309.535322)
					(mid 28.918154 -309.535322)
					(end 29.586174 -309.535322)
				)
			)
		)
	)
	(zone
		(layers "B.Cu" "In11.Cu" "In13.Cu" "In15.Cu")
		(hatch none 0.5)
		(connect_pads
			(clearance 0)
		)
		(min_thickness 0.25)
		(keepout
			(tracks not_allowed)
			(vias allowed)
			(pads allowed)
			(copperpour not_allowed)
			(footprints allowed)
		)
		(placement
			(enabled no)
			(sheetname "")
		)
		(fill yes
			(thermal_gap 0.5)
			(thermal_bridge_width 0.5)
			(island_removal_mode 0)
		)
		(polygon
			(pts
				(arc
					(start 273.426174 -213.484968)
					(mid 272.758154 -213.484968)
					(end 273.426174 -213.484968)
				)
			)
		)
	)
	(zone
		(layers "B.Cu" "In11.Cu" "In13.Cu" "In15.Cu")
		(hatch none 0.5)
		(connect_pads
			(clearance 0)
		)
		(min_thickness 0.25)
		(keepout
			(tracks not_allowed)
			(vias allowed)
			(pads allowed)
			(copperpour not_allowed)
			(footprints allowed)
		)
		(placement
			(enabled no)
			(sheetname "")
		)
		(fill yes
			(thermal_gap 0.5)
			(thermal_bridge_width 0.5)
			(island_removal_mode 0)
		)
		(polygon
			(pts
				(arc
					(start 301.050706 -377.41733)
					(mid 300.382686 -377.41733)
					(end 301.050706 -377.41733)
				)
			)
		)
	)
	(zone
		(layers "B.Cu" "In11.Cu" "In13.Cu" "In15.Cu")
		(hatch none 0.5)
		(connect_pads
			(clearance 0)
		)
		(min_thickness 0.25)
		(keepout
			(tracks not_allowed)
			(vias allowed)
			(pads allowed)
			(copperpour not_allowed)
			(footprints allowed)
		)
		(placement
			(enabled no)
			(sheetname "")
		)
		(fill yes
			(thermal_gap 0.5)
			(thermal_bridge_width 0.5)
			(island_removal_mode 0)
		)
		(polygon
			(pts
				(arc
					(start 143.109696 -234.764326)
					(mid 142.479776 -234.764326)
					(end 143.109696 -234.764326)
				)
			)
		)
	)
	(zone
		(layers "B.Cu" "In11.Cu" "In13.Cu" "In15.Cu")
		(hatch none 0.5)
		(connect_pads
			(clearance 0)
		)
		(min_thickness 0.25)
		(keepout
			(tracks not_allowed)
			(vias allowed)
			(pads allowed)
			(copperpour not_allowed)
			(footprints allowed)
		)
		(placement
			(enabled no)
			(sheetname "")
		)
		(fill yes
			(thermal_gap 0.5)
			(thermal_bridge_width 0.5)
			(island_removal_mode 0)
		)
		(polygon
			(pts
				(arc
					(start 391.049764 -252.584204)
					(mid 390.419844 -252.584204)
					(end 391.049764 -252.584204)
				)
			)
		)
	)
	(zone
		(layers "B.Cu" "In11.Cu" "In13.Cu" "In15.Cu")
		(hatch none 0.5)
		(connect_pads
			(clearance 0)
		)
		(min_thickness 0.25)
		(keepout
			(tracks not_allowed)
			(vias allowed)
			(pads allowed)
			(copperpour not_allowed)
			(footprints allowed)
		)
		(placement
			(enabled no)
			(sheetname "")
		)
		(fill yes
			(thermal_gap 0.5)
			(thermal_bridge_width 0.5)
			(island_removal_mode 0)
		)
		(polygon
			(pts
				(arc
					(start 367.549684 -242.864132)
					(mid 366.919764 -242.864132)
					(end 367.549684 -242.864132)
				)
			)
		)
	)
	(zone
		(layers "B.Cu" "In11.Cu" "In13.Cu" "In15.Cu")
		(hatch none 0.5)
		(connect_pads
			(clearance 0)
		)
		(min_thickness 0.25)
		(keepout
			(tracks not_allowed)
			(vias allowed)
			(pads allowed)
			(copperpour not_allowed)
			(footprints allowed)
		)
		(placement
			(enabled no)
			(sheetname "")
		)
		(fill yes
			(thermal_gap 0.5)
			(thermal_bridge_width 0.5)
			(island_removal_mode 0)
		)
		(polygon
			(pts
				(arc
					(start 109.105954 -282.18638)
					(mid 108.476034 -282.18638)
					(end 109.105954 -282.18638)
				)
			)
		)
	)
	(zone
		(layers "B.Cu" "In11.Cu" "In13.Cu" "In15.Cu")
		(hatch none 0.5)
		(connect_pads
			(clearance 0)
		)
		(min_thickness 0.25)
		(keepout
			(tracks not_allowed)
			(vias allowed)
			(pads allowed)
			(copperpour not_allowed)
			(footprints allowed)
		)
		(placement
			(enabled no)
			(sheetname "")
		)
		(fill yes
			(thermal_gap 0.5)
			(thermal_bridge_width 0.5)
			(island_removal_mode 0)
		)
		(polygon
			(pts
				(arc
					(start 143.109696 -250.964446)
					(mid 142.479776 -250.964446)
					(end 143.109696 -250.964446)
				)
			)
		)
	)
	(zone
		(layers "B.Cu" "In11.Cu" "In13.Cu" "In15.Cu")
		(hatch none 0.5)
		(connect_pads
			(clearance 0)
		)
		(min_thickness 0.25)
		(keepout
			(tracks not_allowed)
			(vias allowed)
			(pads allowed)
			(copperpour not_allowed)
			(footprints allowed)
		)
		(placement
			(enabled no)
			(sheetname "")
		)
		(fill yes
			(thermal_gap 0.5)
			(thermal_bridge_width 0.5)
			(island_removal_mode 0)
		)
		(polygon
			(pts
				(arc
					(start 442.87821 -302.73498)
					(mid 442.21019 -302.73498)
					(end 442.87821 -302.73498)
				)
			)
		)
	)
	(zone
		(layers "B.Cu" "In11.Cu" "In13.Cu" "In15.Cu")
		(hatch none 0.5)
		(connect_pads
			(clearance 0)
		)
		(min_thickness 0.25)
		(keepout
			(tracks not_allowed)
			(vias allowed)
			(pads allowed)
			(copperpour not_allowed)
			(footprints allowed)
		)
		(placement
			(enabled no)
			(sheetname "")
		)
		(fill yes
			(thermal_gap 0.5)
			(thermal_bridge_width 0.5)
			(island_removal_mode 0)
		)
		(polygon
			(pts
				(arc
					(start 330.42606 -253.39421)
					(mid 329.79614 -253.39421)
					(end 330.42606 -253.39421)
				)
			)
		)
	)
	(zone
		(layers "B.Cu" "In11.Cu" "In13.Cu" "In15.Cu")
		(hatch none 0.5)
		(connect_pads
			(clearance 0)
		)
		(min_thickness 0.25)
		(keepout
			(tracks not_allowed)
			(vias allowed)
			(pads allowed)
			(copperpour not_allowed)
			(footprints allowed)
		)
		(placement
			(enabled no)
			(sheetname "")
		)
		(fill yes
			(thermal_gap 0.5)
			(thermal_bridge_width 0.5)
			(island_removal_mode 0)
		)
		(polygon
			(pts
				(arc
					(start 143.40967 -263.556242)
					(mid 142.77975 -263.556242)
					(end 143.40967 -263.556242)
				)
			)
		)
	)
	(zone
		(layers "B.Cu" "In11.Cu" "In13.Cu" "In15.Cu")
		(hatch none 0.5)
		(connect_pads
			(clearance 0)
		)
		(min_thickness 0.25)
		(keepout
			(tracks not_allowed)
			(vias allowed)
			(pads allowed)
			(copperpour not_allowed)
			(footprints allowed)
		)
		(placement
			(enabled no)
			(sheetname "")
		)
		(fill yes
			(thermal_gap 0.5)
			(thermal_bridge_width 0.5)
			(island_removal_mode 0)
		)
		(polygon
			(pts
				(arc
					(start 132.00634 -388.774432)
					(mid 131.37642 -388.774432)
					(end 132.00634 -388.774432)
				)
			)
		)
	)
	(zone
		(layers "B.Cu" "In11.Cu" "In13.Cu" "In15.Cu")
		(hatch none 0.5)
		(connect_pads
			(clearance 0)
		)
		(min_thickness 0.25)
		(keepout
			(tracks not_allowed)
			(vias allowed)
			(pads allowed)
			(copperpour not_allowed)
			(footprints allowed)
		)
		(placement
			(enabled no)
			(sheetname "")
		)
		(fill yes
			(thermal_gap 0.5)
			(thermal_bridge_width 0.5)
			(island_removal_mode 0)
		)
		(polygon
			(pts
				(arc
					(start 126.136908 -426.089826)
					(mid 125.362716 -426.089826)
					(end 126.136908 -426.089826)
				)
			)
		)
	)
	(zone
		(layers "B.Cu" "In11.Cu" "In13.Cu" "In15.Cu")
		(hatch none 0.5)
		(connect_pads
			(clearance 0)
		)
		(min_thickness 0.25)
		(keepout
			(tracks not_allowed)
			(vias allowed)
			(pads allowed)
			(copperpour not_allowed)
			(footprints allowed)
		)
		(placement
			(enabled no)
			(sheetname "")
		)
		(fill yes
			(thermal_gap 0.5)
			(thermal_bridge_width 0.5)
			(island_removal_mode 0)
		)
		(polygon
			(pts
				(arc
					(start 83.255866 -291.096192)
					(mid 82.625946 -291.096192)
					(end 83.255866 -291.096192)
				)
			)
		)
	)
	(zone
		(layers "B.Cu" "In11.Cu" "In13.Cu" "In15.Cu")
		(hatch none 0.5)
		(connect_pads
			(clearance 0)
		)
		(min_thickness 0.25)
		(keepout
			(tracks not_allowed)
			(vias allowed)
			(pads allowed)
			(copperpour not_allowed)
			(footprints allowed)
		)
		(placement
			(enabled no)
			(sheetname "")
		)
		(fill yes
			(thermal_gap 0.5)
			(thermal_bridge_width 0.5)
			(island_removal_mode 0)
		)
		(polygon
			(pts
				(arc
					(start 407.137108 -427.289976)
					(mid 406.362916 -427.289976)
					(end 407.137108 -427.289976)
				)
			)
		)
	)
	(zone
		(layers "B.Cu" "In11.Cu" "In13.Cu" "In15.Cu")
		(hatch none 0.5)
		(connect_pads
			(clearance 0)
		)
		(min_thickness 0.25)
		(keepout
			(tracks not_allowed)
			(vias allowed)
			(pads allowed)
			(copperpour not_allowed)
			(footprints allowed)
		)
		(placement
			(enabled no)
			(sheetname "")
		)
		(fill yes
			(thermal_gap 0.5)
			(thermal_bridge_width 0.5)
			(island_removal_mode 0)
		)
		(polygon
			(pts
				(arc
					(start 365.969804 -286.236156)
					(mid 365.339884 -286.236156)
					(end 365.969804 -286.236156)
				)
			)
		)
	)
	(zone
		(layers "B.Cu" "In11.Cu" "In13.Cu" "In15.Cu")
		(hatch none 0.5)
		(connect_pads
			(clearance 0)
		)
		(min_thickness 0.25)
		(keepout
			(tracks not_allowed)
			(vias allowed)
			(pads allowed)
			(copperpour not_allowed)
			(footprints allowed)
		)
		(placement
			(enabled no)
			(sheetname "")
		)
		(fill yes
			(thermal_gap 0.5)
			(thermal_bridge_width 0.5)
			(island_removal_mode 0)
		)
		(polygon
			(pts
				(arc
					(start 56.125364 -373.96293)
					(mid 55.457344 -373.96293)
					(end 56.125364 -373.96293)
				)
			)
		)
	)
	(zone
		(layers "B.Cu" "In11.Cu" "In13.Cu" "In15.Cu")
		(hatch none 0.5)
		(connect_pads
			(clearance 0)
		)
		(min_thickness 0.25)
		(keepout
			(tracks not_allowed)
			(vias allowed)
			(pads allowed)
			(copperpour not_allowed)
			(footprints allowed)
		)
		(placement
			(enabled no)
			(sheetname "")
		)
		(fill yes
			(thermal_gap 0.5)
			(thermal_bridge_width 0.5)
			(island_removal_mode 0)
		)
		(polygon
			(pts
				(arc
					(start 199.03821 -315.485272)
					(mid 198.37019 -315.485272)
					(end 199.03821 -315.485272)
				)
			)
		)
	)
	(zone
		(layers "B.Cu" "In11.Cu" "In13.Cu" "In15.Cu")
		(hatch none 0.5)
		(connect_pads
			(clearance 0)
		)
		(min_thickness 0.25)
		(keepout
			(tracks not_allowed)
			(vias allowed)
			(pads allowed)
			(copperpour not_allowed)
			(footprints allowed)
		)
		(placement
			(enabled no)
			(sheetname "")
		)
		(fill yes
			(thermal_gap 0.5)
			(thermal_bridge_width 0.5)
			(island_removal_mode 0)
		)
		(polygon
			(pts
				(arc
					(start 368.489738 -241.24412)
					(mid 367.859818 -241.24412)
					(end 368.489738 -241.24412)
				)
			)
		)
	)
	(zone
		(layers "B.Cu" "In11.Cu" "In13.Cu" "In15.Cu")
		(hatch none 0.5)
		(connect_pads
			(clearance 0)
		)
		(min_thickness 0.25)
		(keepout
			(tracks not_allowed)
			(vias allowed)
			(pads allowed)
			(copperpour not_allowed)
			(footprints allowed)
		)
		(placement
			(enabled no)
			(sheetname "")
		)
		(fill yes
			(thermal_gap 0.5)
			(thermal_bridge_width 0.5)
			(island_removal_mode 0)
		)
		(polygon
			(pts
				(arc
					(start 143.109696 -231.524302)
					(mid 142.479776 -231.524302)
					(end 143.109696 -231.524302)
				)
			)
		)
	)
	(zone
		(layers "B.Cu" "In11.Cu" "In13.Cu" "In15.Cu")
		(hatch none 0.5)
		(connect_pads
			(clearance 0)
		)
		(min_thickness 0.25)
		(keepout
			(tracks not_allowed)
			(vias allowed)
			(pads allowed)
			(copperpour not_allowed)
			(footprints allowed)
		)
		(placement
			(enabled no)
			(sheetname "")
		)
		(fill yes
			(thermal_gap 0.5)
			(thermal_bridge_width 0.5)
			(island_removal_mode 0)
		)
		(polygon
			(pts
				(arc
					(start 277.526242 -266.185142)
					(mid 276.858222 -266.185142)
					(end 277.526242 -266.185142)
				)
			)
		)
	)
	(zone
		(layers "B.Cu" "In11.Cu" "In13.Cu" "In15.Cu")
		(hatch none 0.5)
		(connect_pads
			(clearance 0)
		)
		(min_thickness 0.25)
		(keepout
			(tracks not_allowed)
			(vias allowed)
			(pads allowed)
			(copperpour not_allowed)
			(footprints allowed)
		)
		(placement
			(enabled no)
			(sheetname "")
		)
		(fill yes
			(thermal_gap 0.5)
			(thermal_bridge_width 0.5)
			(island_removal_mode 0)
		)
		(polygon
			(pts
				(arc
					(start 25.486106 -276.385274)
					(mid 24.818086 -276.385274)
					(end 25.486106 -276.385274)
				)
			)
		)
	)
	(zone
		(layers "B.Cu" "In11.Cu" "In13.Cu" "In15.Cu")
		(hatch none 0.5)
		(connect_pads
			(clearance 0)
		)
		(min_thickness 0.25)
		(keepout
			(tracks not_allowed)
			(vias allowed)
			(pads allowed)
			(copperpour not_allowed)
			(footprints allowed)
		)
		(placement
			(enabled no)
			(sheetname "")
		)
		(fill yes
			(thermal_gap 0.5)
			(thermal_bridge_width 0.5)
			(island_removal_mode 0)
		)
		(polygon
			(pts
				(arc
					(start 29.586174 -242.385342)
					(mid 28.918154 -242.385342)
					(end 29.586174 -242.385342)
				)
			)
		)
	)
	(zone
		(layers "B.Cu" "In11.Cu" "In13.Cu" "In15.Cu")
		(hatch none 0.5)
		(connect_pads
			(clearance 0)
		)
		(min_thickness 0.25)
		(keepout
			(tracks not_allowed)
			(vias allowed)
			(pads allowed)
			(copperpour not_allowed)
			(footprints allowed)
		)
		(placement
			(enabled no)
			(sheetname "")
		)
		(fill yes
			(thermal_gap 0.5)
			(thermal_bridge_width 0.5)
			(island_removal_mode 0)
		)
		(polygon
			(pts
				(arc
					(start 273.426174 -220.285056)
					(mid 272.758154 -220.285056)
					(end 273.426174 -220.285056)
				)
			)
		)
	)
	(zone
		(layers "B.Cu" "In11.Cu" "In13.Cu" "In15.Cu")
		(hatch none 0.5)
		(connect_pads
			(clearance 0)
		)
		(min_thickness 0.25)
		(keepout
			(tracks not_allowed)
			(vias allowed)
			(pads allowed)
			(copperpour not_allowed)
			(footprints allowed)
		)
		(placement
			(enabled no)
			(sheetname "")
		)
		(fill yes
			(thermal_gap 0.5)
			(thermal_bridge_width 0.5)
			(island_removal_mode 0)
		)
		(polygon
			(pts
				(arc
					(start 141.229842 -229.90429)
					(mid 140.599922 -229.90429)
					(end 141.229842 -229.90429)
				)
			)
		)
	)
	(zone
		(layers "B.Cu" "In11.Cu" "In13.Cu" "In15.Cu")
		(hatch none 0.5)
		(connect_pads
			(clearance 0)
		)
		(min_thickness 0.25)
		(keepout
			(tracks not_allowed)
			(vias allowed)
			(pads allowed)
			(copperpour not_allowed)
			(footprints allowed)
		)
		(placement
			(enabled no)
			(sheetname "")
		)
		(fill yes
			(thermal_gap 0.5)
			(thermal_bridge_width 0.5)
			(island_removal_mode 0)
		)
		(polygon
			(pts
				(arc
					(start 446.978278 -199.035162)
					(mid 446.310258 -199.035162)
					(end 446.978278 -199.035162)
				)
			)
		)
	)
	(zone
		(layers "B.Cu" "In11.Cu" "In13.Cu" "In15.Cu")
		(hatch none 0.5)
		(connect_pads
			(clearance 0)
		)
		(min_thickness 0.25)
		(keepout
			(tracks not_allowed)
			(vias allowed)
			(pads allowed)
			(copperpour not_allowed)
			(footprints allowed)
		)
		(placement
			(enabled no)
			(sheetname "")
		)
		(fill yes
			(thermal_gap 0.5)
			(thermal_bridge_width 0.5)
			(island_removal_mode 0)
		)
		(polygon
			(pts
				(arc
					(start 152.533858 -385.31038)
					(mid 151.903938 -385.31038)
					(end 152.533858 -385.31038)
				)
			)
		)
	)
	(zone
		(layers "B.Cu" "In11.Cu" "In13.Cu" "In15.Cu")
		(hatch none 0.5)
		(connect_pads
			(clearance 0)
		)
		(min_thickness 0.25)
		(keepout
			(tracks not_allowed)
			(vias allowed)
			(pads allowed)
			(copperpour not_allowed)
			(footprints allowed)
		)
		(placement
			(enabled no)
			(sheetname "")
		)
		(fill yes
			(thermal_gap 0.5)
			(thermal_bridge_width 0.5)
			(island_removal_mode 0)
		)
		(polygon
			(pts
				(arc
					(start 301.914306 -377.41733)
					(mid 301.246286 -377.41733)
					(end 301.914306 -377.41733)
				)
			)
		)
	)
	(zone
		(layers "B.Cu" "In11.Cu" "In13.Cu" "In15.Cu")
		(hatch none 0.5)
		(connect_pads
			(clearance 0)
		)
		(min_thickness 0.25)
		(keepout
			(tracks not_allowed)
			(vias allowed)
			(pads allowed)
			(copperpour not_allowed)
			(footprints allowed)
		)
		(placement
			(enabled no)
			(sheetname "")
		)
		(fill yes
			(thermal_gap 0.5)
			(thermal_bridge_width 0.5)
			(island_removal_mode 0)
		)
		(polygon
			(pts
				(arc
					(start 83.255866 -282.996386)
					(mid 82.625946 -282.996386)
					(end 83.255866 -282.996386)
				)
			)
		)
	)
	(zone
		(layers "B.Cu" "In11.Cu" "In13.Cu" "In15.Cu")
		(hatch none 0.5)
		(connect_pads
			(clearance 0)
		)
		(min_thickness 0.25)
		(keepout
			(tracks not_allowed)
			(vias allowed)
			(pads allowed)
			(copperpour not_allowed)
			(footprints allowed)
		)
		(placement
			(enabled no)
			(sheetname "")
		)
		(fill yes
			(thermal_gap 0.5)
			(thermal_bridge_width 0.5)
			(island_removal_mode 0)
		)
		(polygon
			(pts
				(arc
					(start 389.469884 -286.236156)
					(mid 388.839964 -286.236156)
					(end 389.469884 -286.236156)
				)
			)
		)
	)
	(zone
		(layers "B.Cu" "In11.Cu" "In13.Cu" "In15.Cu")
		(hatch none 0.5)
		(connect_pads
			(clearance 0)
		)
		(min_thickness 0.25)
		(keepout
			(tracks not_allowed)
			(vias allowed)
			(pads allowed)
			(copperpour not_allowed)
			(footprints allowed)
		)
		(placement
			(enabled no)
			(sheetname "")
		)
		(fill yes
			(thermal_gap 0.5)
			(thermal_bridge_width 0.5)
			(island_removal_mode 0)
		)
		(polygon
			(pts
				(arc
					(start 199.03821 -292.535356)
					(mid 198.37019 -292.535356)
					(end 199.03821 -292.535356)
				)
			)
		)
	)
	(zone
		(layers "B.Cu" "In11.Cu" "In13.Cu" "In15.Cu")
		(hatch none 0.5)
		(connect_pads
			(clearance 0)
		)
		(min_thickness 0.25)
		(keepout
			(tracks not_allowed)
			(vias allowed)
			(pads allowed)
			(copperpour not_allowed)
			(footprints allowed)
		)
		(placement
			(enabled no)
			(sheetname "")
		)
		(fill yes
			(thermal_gap 0.5)
			(thermal_bridge_width 0.5)
			(island_removal_mode 0)
		)
		(polygon
			(pts
				(arc
					(start 446.978278 -303.585118)
					(mid 446.310258 -303.585118)
					(end 446.978278 -303.585118)
				)
			)
		)
	)
	(zone
		(layers "B.Cu" "In11.Cu" "In13.Cu" "In15.Cu")
		(hatch none 0.5)
		(connect_pads
			(clearance 0)
		)
		(min_thickness 0.25)
		(keepout
			(tracks not_allowed)
			(vias allowed)
			(pads allowed)
			(copperpour not_allowed)
			(footprints allowed)
		)
		(placement
			(enabled no)
			(sheetname "")
		)
		(fill yes
			(thermal_gap 0.5)
			(thermal_bridge_width 0.5)
			(island_removal_mode 0)
		)
		(polygon
			(pts
				(arc
					(start 58.906156 -388.774432)
					(mid 58.276236 -388.774432)
					(end 58.906156 -388.774432)
				)
			)
		)
	)
	(zone
		(layers "B.Cu" "In11.Cu" "In13.Cu" "In15.Cu")
		(hatch none 0.5)
		(connect_pads
			(clearance 0)
		)
		(min_thickness 0.25)
		(keepout
			(tracks not_allowed)
			(vias allowed)
			(pads allowed)
			(copperpour not_allowed)
			(footprints allowed)
		)
		(placement
			(enabled no)
			(sheetname "")
		)
		(fill yes
			(thermal_gap 0.5)
			(thermal_bridge_width 0.5)
			(island_removal_mode 0)
		)
		(polygon
			(pts
				(arc
					(start 442.87821 -250.03506)
					(mid 442.21019 -250.03506)
					(end 442.87821 -250.03506)
				)
			)
		)
	)
	(zone
		(layers "B.Cu" "In11.Cu" "In13.Cu" "In15.Cu")
		(hatch none 0.5)
		(connect_pads
			(clearance 0)
		)
		(min_thickness 0.25)
		(keepout
			(tracks not_allowed)
			(vias allowed)
			(pads allowed)
			(copperpour not_allowed)
			(footprints allowed)
		)
		(placement
			(enabled no)
			(sheetname "")
		)
		(fill yes
			(thermal_gap 0.5)
			(thermal_bridge_width 0.5)
			(island_removal_mode 0)
		)
		(polygon
			(pts
				(arc
					(start 277.526242 -296.78503)
					(mid 276.858222 -296.78503)
					(end 277.526242 -296.78503)
				)
			)
		)
	)
	(zone
		(layers "B.Cu" "In11.Cu" "In13.Cu" "In15.Cu")
		(hatch none 0.5)
		(connect_pads
			(clearance 0)
		)
		(min_thickness 0.25)
		(keepout
			(tracks not_allowed)
			(vias allowed)
			(pads allowed)
			(copperpour not_allowed)
			(footprints allowed)
		)
		(placement
			(enabled no)
			(sheetname "")
		)
		(fill yes
			(thermal_gap 0.5)
			(thermal_bridge_width 0.5)
			(island_removal_mode 0)
		)
		(polygon
			(pts
				(arc
					(start 25.486106 -278.935434)
					(mid 24.818086 -278.935434)
					(end 25.486106 -278.935434)
				)
			)
		)
	)
	(zone
		(layers "B.Cu" "In11.Cu" "In13.Cu" "In15.Cu")
		(hatch none 0.5)
		(connect_pads
			(clearance 0)
		)
		(min_thickness 0.25)
		(keepout
			(tracks not_allowed)
			(vias allowed)
			(pads allowed)
			(copperpour not_allowed)
			(footprints allowed)
		)
		(placement
			(enabled no)
			(sheetname "")
		)
		(fill yes
			(thermal_gap 0.5)
			(thermal_bridge_width 0.5)
			(island_removal_mode 0)
		)
		(polygon
			(pts
				(arc
					(start 374.00611 -397.849344)
					(mid 373.37619 -397.849344)
					(end 374.00611 -397.849344)
				)
			)
		)
	)
	(zone
		(layers "B.Cu" "In11.Cu" "In13.Cu" "In15.Cu")
		(hatch none 0.5)
		(connect_pads
			(clearance 0)
		)
		(min_thickness 0.25)
		(keepout
			(tracks not_allowed)
			(vias allowed)
			(pads allowed)
			(copperpour not_allowed)
			(footprints allowed)
		)
		(placement
			(enabled no)
			(sheetname "")
		)
		(fill yes
			(thermal_gap 0.5)
			(thermal_bridge_width 0.5)
			(island_removal_mode 0)
		)
		(polygon
			(pts
				(arc
					(start 367.549684 -239.624108)
					(mid 366.919764 -239.624108)
					(end 367.549684 -239.624108)
				)
			)
		)
	)
	(zone
		(layers "B.Cu" "In11.Cu" "In13.Cu" "In15.Cu")
		(hatch none 0.5)
		(connect_pads
			(clearance 0)
		)
		(min_thickness 0.25)
		(keepout
			(tracks not_allowed)
			(vias allowed)
			(pads allowed)
			(copperpour not_allowed)
			(footprints allowed)
		)
		(placement
			(enabled no)
			(sheetname "")
		)
		(fill yes
			(thermal_gap 0.5)
			(thermal_bridge_width 0.5)
			(island_removal_mode 0)
		)
		(polygon
			(pts
				(arc
					(start 142.93977 -270.846296)
					(mid 142.30985 -270.846296)
					(end 142.93977 -270.846296)
				)
			)
		)
	)
	(zone
		(layers "B.Cu" "In11.Cu" "In13.Cu" "In15.Cu")
		(hatch none 0.5)
		(connect_pads
			(clearance 0)
		)
		(min_thickness 0.25)
		(keepout
			(tracks not_allowed)
			(vias allowed)
			(pads allowed)
			(copperpour not_allowed)
			(footprints allowed)
		)
		(placement
			(enabled no)
			(sheetname "")
		)
		(fill yes
			(thermal_gap 0.5)
			(thermal_bridge_width 0.5)
			(island_removal_mode 0)
		)
		(polygon
			(pts
				(arc
					(start 25.486106 -295.085262)
					(mid 24.818086 -295.085262)
					(end 25.486106 -295.085262)
				)
			)
		)
	)
	(zone
		(layers "B.Cu" "In11.Cu" "In13.Cu" "In15.Cu")
		(hatch none 0.5)
		(connect_pads
			(clearance 0)
		)
		(min_thickness 0.25)
		(keepout
			(tracks not_allowed)
			(vias allowed)
			(pads allowed)
			(copperpour not_allowed)
			(footprints allowed)
		)
		(placement
			(enabled no)
			(sheetname "")
		)
		(fill yes
			(thermal_gap 0.5)
			(thermal_bridge_width 0.5)
			(island_removal_mode 0)
		)
		(polygon
			(pts
				(arc
					(start 273.426174 -278.93518)
					(mid 272.758154 -278.93518)
					(end 273.426174 -278.93518)
				)
			)
		)
	)
	(zone
		(layers "B.Cu" "In11.Cu" "In13.Cu" "In15.Cu")
		(hatch none 0.5)
		(connect_pads
			(clearance 0)
		)
		(min_thickness 0.25)
		(keepout
			(tracks not_allowed)
			(vias allowed)
			(pads allowed)
			(copperpour not_allowed)
			(footprints allowed)
		)
		(placement
			(enabled no)
			(sheetname "")
		)
		(fill yes
			(thermal_gap 0.5)
			(thermal_bridge_width 0.5)
			(island_removal_mode 0)
		)
		(polygon
			(pts
				(arc
					(start 126.489714 -284.616398)
					(mid 125.859794 -284.616398)
					(end 126.489714 -284.616398)
				)
			)
		)
	)
	(zone
		(layers "B.Cu" "In11.Cu" "In13.Cu" "In15.Cu")
		(hatch none 0.5)
		(connect_pads
			(clearance 0)
		)
		(min_thickness 0.25)
		(keepout
			(tracks not_allowed)
			(vias allowed)
			(pads allowed)
			(copperpour not_allowed)
			(footprints allowed)
		)
		(placement
			(enabled no)
			(sheetname "")
		)
		(fill yes
			(thermal_gap 0.5)
			(thermal_bridge_width 0.5)
			(island_removal_mode 0)
		)
		(polygon
			(pts
				(arc
					(start 446.978278 -221.985078)
					(mid 446.310258 -221.985078)
					(end 446.978278 -221.985078)
				)
			)
		)
	)
	(zone
		(layers "B.Cu" "In11.Cu" "In13.Cu" "In15.Cu")
		(hatch none 0.5)
		(connect_pads
			(clearance 0)
		)
		(min_thickness 0.25)
		(keepout
			(tracks not_allowed)
			(vias allowed)
			(pads allowed)
			(copperpour not_allowed)
			(footprints allowed)
		)
		(placement
			(enabled no)
			(sheetname "")
		)
		(fill yes
			(thermal_gap 0.5)
			(thermal_bridge_width 0.5)
			(island_removal_mode 0)
		)
		(polygon
			(pts
				(arc
					(start 346.236036 -282.996132)
					(mid 345.606116 -282.996132)
					(end 346.236036 -282.996132)
				)
			)
		)
	)
	(zone
		(layers "B.Cu" "In11.Cu" "In13.Cu" "In15.Cu")
		(hatch none 0.5)
		(connect_pads
			(clearance 0)
		)
		(min_thickness 0.25)
		(keepout
			(tracks not_allowed)
			(vias allowed)
			(pads allowed)
			(copperpour not_allowed)
			(footprints allowed)
		)
		(placement
			(enabled no)
			(sheetname "")
		)
		(fill yes
			(thermal_gap 0.5)
			(thermal_bridge_width 0.5)
			(island_removal_mode 0)
		)
		(polygon
			(pts
				(arc
					(start 29.586174 -236.435392)
					(mid 28.918154 -236.435392)
					(end 29.586174 -236.435392)
				)
			)
		)
	)
	(zone
		(layers "B.Cu" "In11.Cu" "In13.Cu" "In15.Cu")
		(hatch none 0.5)
		(connect_pads
			(clearance 0)
		)
		(min_thickness 0.25)
		(keepout
			(tracks not_allowed)
			(vias allowed)
			(pads allowed)
			(copperpour not_allowed)
			(footprints allowed)
		)
		(placement
			(enabled no)
			(sheetname "")
		)
		(fill yes
			(thermal_gap 0.5)
			(thermal_bridge_width 0.5)
			(island_removal_mode 0)
		)
		(polygon
			(pts
				(arc
					(start 141.529816 -263.556242)
					(mid 140.899896 -263.556242)
					(end 141.529816 -263.556242)
				)
			)
		)
	)
	(zone
		(layers "B.Cu" "In11.Cu" "In13.Cu" "In15.Cu")
		(hatch none 0.5)
		(connect_pads
			(clearance 0)
		)
		(min_thickness 0.25)
		(keepout
			(tracks not_allowed)
			(vias allowed)
			(pads allowed)
			(copperpour not_allowed)
			(footprints allowed)
		)
		(placement
			(enabled no)
			(sheetname "")
		)
		(fill yes
			(thermal_gap 0.5)
			(thermal_bridge_width 0.5)
			(island_removal_mode 0)
		)
		(polygon
			(pts
				(arc
					(start 70.434454 -404.46452)
					(mid 69.766434 -404.46452)
					(end 70.434454 -404.46452)
				)
			)
		)
	)
	(zone
		(layers "B.Cu" "In11.Cu" "In13.Cu" "In15.Cu")
		(hatch none 0.5)
		(connect_pads
			(clearance 0)
		)
		(min_thickness 0.25)
		(keepout
			(tracks not_allowed)
			(vias allowed)
			(pads allowed)
			(copperpour not_allowed)
			(footprints allowed)
		)
		(placement
			(enabled no)
			(sheetname "")
		)
		(fill yes
			(thermal_gap 0.5)
			(thermal_bridge_width 0.5)
			(island_removal_mode 0)
		)
		(polygon
			(pts
				(arc
					(start 25.486106 -235.585254)
					(mid 24.818086 -235.585254)
					(end 25.486106 -235.585254)
				)
			)
		)
	)
	(zone
		(layers "B.Cu" "In11.Cu" "In13.Cu" "In15.Cu")
		(hatch none 0.5)
		(connect_pads
			(clearance 0)
		)
		(min_thickness 0.25)
		(keepout
			(tracks not_allowed)
			(vias allowed)
			(pads allowed)
			(copperpour not_allowed)
			(footprints allowed)
		)
		(placement
			(enabled no)
			(sheetname "")
		)
		(fill yes
			(thermal_gap 0.5)
			(thermal_bridge_width 0.5)
			(island_removal_mode 0)
		)
		(polygon
			(pts
				(arc
					(start 59.036966 -423.68978)
					(mid 58.262774 -423.68978)
					(end 59.036966 -423.68978)
				)
			)
		)
	)
	(zone
		(layers "B.Cu" "In11.Cu" "In13.Cu" "In15.Cu")
		(hatch none 0.5)
		(connect_pads
			(clearance 0)
		)
		(min_thickness 0.25)
		(keepout
			(tracks not_allowed)
			(vias allowed)
			(pads allowed)
			(copperpour not_allowed)
			(footprints allowed)
		)
		(placement
			(enabled no)
			(sheetname "")
		)
		(fill yes
			(thermal_gap 0.5)
			(thermal_bridge_width 0.5)
			(island_removal_mode 0)
		)
		(polygon
			(pts
				(arc
					(start 194.938142 -243.235226)
					(mid 194.270122 -243.235226)
					(end 194.938142 -243.235226)
				)
			)
		)
	)
	(zone
		(layers "B.Cu" "In11.Cu" "In13.Cu" "In15.Cu")
		(hatch none 0.5)
		(connect_pads
			(clearance 0)
		)
		(min_thickness 0.25)
		(keepout
			(tracks not_allowed)
			(vias allowed)
			(pads allowed)
			(copperpour not_allowed)
			(footprints allowed)
		)
		(placement
			(enabled no)
			(sheetname "")
		)
		(fill yes
			(thermal_gap 0.5)
			(thermal_bridge_width 0.5)
			(island_removal_mode 0)
		)
		(polygon
			(pts
				(arc
					(start 199.03821 -238.985298)
					(mid 198.37019 -238.985298)
					(end 199.03821 -238.985298)
				)
			)
		)
	)
	(zone
		(layers "B.Cu" "In11.Cu" "In13.Cu" "In15.Cu")
		(hatch none 0.5)
		(connect_pads
			(clearance 0)
		)
		(min_thickness 0.25)
		(keepout
			(tracks not_allowed)
			(vias allowed)
			(pads allowed)
			(copperpour not_allowed)
			(footprints allowed)
		)
		(placement
			(enabled no)
			(sheetname "")
		)
		(fill yes
			(thermal_gap 0.5)
			(thermal_bridge_width 0.5)
			(island_removal_mode 0)
		)
		(polygon
			(pts
				(arc
					(start 54.254654 -404.46452)
					(mid 53.586634 -404.46452)
					(end 54.254654 -404.46452)
				)
			)
		)
	)
	(zone
		(layers "B.Cu" "In11.Cu" "In13.Cu" "In15.Cu")
		(hatch none 0.5)
		(connect_pads
			(clearance 0)
		)
		(min_thickness 0.25)
		(keepout
			(tracks not_allowed)
			(vias allowed)
			(pads allowed)
			(copperpour not_allowed)
			(footprints allowed)
		)
		(placement
			(enabled no)
			(sheetname "")
		)
		(fill yes
			(thermal_gap 0.5)
			(thermal_bridge_width 0.5)
			(island_removal_mode 0)
		)
		(polygon
			(pts
				(arc
					(start 107.396026 -241.244374)
					(mid 106.766106 -241.244374)
					(end 107.396026 -241.244374)
				)
			)
		)
	)
	(zone
		(layers "B.Cu" "In11.Cu" "In13.Cu" "In15.Cu")
		(hatch none 0.5)
		(connect_pads
			(clearance 0)
		)
		(min_thickness 0.25)
		(keepout
			(tracks not_allowed)
			(vias allowed)
			(pads allowed)
			(copperpour not_allowed)
			(footprints allowed)
		)
		(placement
			(enabled no)
			(sheetname "")
		)
		(fill yes
			(thermal_gap 0.5)
			(thermal_bridge_width 0.5)
			(island_removal_mode 0)
		)
		(polygon
			(pts
				(arc
					(start 273.426174 -250.03506)
					(mid 272.758154 -250.03506)
					(end 273.426174 -250.03506)
				)
			)
		)
	)
	(zone
		(layers "B.Cu" "In11.Cu" "In13.Cu" "In15.Cu")
		(hatch none 0.5)
		(connect_pads
			(clearance 0)
		)
		(min_thickness 0.25)
		(keepout
			(tracks not_allowed)
			(vias allowed)
			(pads allowed)
			(copperpour not_allowed)
			(footprints allowed)
		)
		(placement
			(enabled no)
			(sheetname "")
		)
		(fill yes
			(thermal_gap 0.5)
			(thermal_bridge_width 0.5)
			(island_removal_mode 0)
		)
		(polygon
			(pts
				(arc
					(start 194.938142 -295.9354)
					(mid 194.270122 -295.9354)
					(end 194.938142 -295.9354)
				)
			)
		)
	)
	(zone
		(layers "B.Cu" "In11.Cu" "In13.Cu" "In15.Cu")
		(hatch none 0.5)
		(connect_pads
			(clearance 0)
		)
		(min_thickness 0.25)
		(keepout
			(tracks not_allowed)
			(vias allowed)
			(pads allowed)
			(copperpour not_allowed)
			(footprints allowed)
		)
		(placement
			(enabled no)
			(sheetname "")
		)
		(fill yes
			(thermal_gap 0.5)
			(thermal_bridge_width 0.5)
			(island_removal_mode 0)
		)
		(polygon
			(pts
				(arc
					(start 25.486106 -268.735302)
					(mid 24.818086 -268.735302)
					(end 25.486106 -268.735302)
				)
			)
		)
	)
	(zone
		(layers "B.Cu" "In11.Cu" "In13.Cu" "In15.Cu")
		(hatch none 0.5)
		(connect_pads
			(clearance 0)
		)
		(min_thickness 0.25)
		(keepout
			(tracks not_allowed)
			(vias allowed)
			(pads allowed)
			(copperpour not_allowed)
			(footprints allowed)
		)
		(placement
			(enabled no)
			(sheetname "")
		)
		(fill yes
			(thermal_gap 0.5)
			(thermal_bridge_width 0.5)
			(island_removal_mode 0)
		)
		(polygon
			(pts
				(arc
					(start 29.586174 -225.385376)
					(mid 28.918154 -225.385376)
					(end 29.586174 -225.385376)
				)
			)
		)
	)
	(zone
		(layers "B.Cu" "In11.Cu" "In13.Cu" "In15.Cu")
		(hatch none 0.5)
		(connect_pads
			(clearance 0)
		)
		(min_thickness 0.25)
		(keepout
			(tracks not_allowed)
			(vias allowed)
			(pads allowed)
			(copperpour not_allowed)
			(footprints allowed)
		)
		(placement
			(enabled no)
			(sheetname "")
		)
		(fill yes
			(thermal_gap 0.5)
			(thermal_bridge_width 0.5)
			(island_removal_mode 0)
		)
		(polygon
			(pts
				(arc
					(start 446.978278 -309.535068)
					(mid 446.310258 -309.535068)
					(end 446.978278 -309.535068)
				)
			)
		)
	)
	(zone
		(layers "B.Cu" "In11.Cu" "In13.Cu" "In15.Cu")
		(hatch none 0.5)
		(connect_pads
			(clearance 0)
		)
		(min_thickness 0.25)
		(keepout
			(tracks not_allowed)
			(vias allowed)
			(pads allowed)
			(copperpour not_allowed)
			(footprints allowed)
		)
		(placement
			(enabled no)
			(sheetname "")
		)
		(fill yes
			(thermal_gap 0.5)
			(thermal_bridge_width 0.5)
			(island_removal_mode 0)
		)
		(polygon
			(pts
				(arc
					(start 141.999716 -283.806392)
					(mid 141.369796 -283.806392)
					(end 141.999716 -283.806392)
				)
			)
		)
	)
	(zone
		(layers "B.Cu" "In11.Cu" "In13.Cu" "In15.Cu")
		(hatch none 0.5)
		(connect_pads
			(clearance 0)
		)
		(min_thickness 0.25)
		(keepout
			(tracks not_allowed)
			(vias allowed)
			(pads allowed)
			(copperpour not_allowed)
			(footprints allowed)
		)
		(placement
			(enabled no)
			(sheetname "")
		)
		(fill yes
			(thermal_gap 0.5)
			(thermal_bridge_width 0.5)
			(island_removal_mode 0)
		)
		(polygon
			(pts
				(arc
					(start 141.529816 -274.896326)
					(mid 140.899896 -274.896326)
					(end 141.529816 -274.896326)
				)
			)
		)
	)
	(zone
		(layers "B.Cu" "In11.Cu" "In13.Cu" "In15.Cu")
		(hatch none 0.5)
		(connect_pads
			(clearance 0)
		)
		(min_thickness 0.25)
		(keepout
			(tracks not_allowed)
			(vias allowed)
			(pads allowed)
			(copperpour not_allowed)
			(footprints allowed)
		)
		(placement
			(enabled no)
			(sheetname "")
		)
		(fill yes
			(thermal_gap 0.5)
			(thermal_bridge_width 0.5)
			(island_removal_mode 0)
		)
		(polygon
			(pts
				(arc
					(start 442.87821 -299.33519)
					(mid 442.21019 -299.33519)
					(end 442.87821 -299.33519)
				)
			)
		)
	)
	(zone
		(layers "B.Cu" "In11.Cu" "In13.Cu" "In15.Cu")
		(hatch none 0.5)
		(connect_pads
			(clearance 0)
		)
		(min_thickness 0.25)
		(keepout
			(tracks not_allowed)
			(vias allowed)
			(pads allowed)
			(copperpour not_allowed)
			(footprints allowed)
		)
		(placement
			(enabled no)
			(sheetname "")
		)
		(fill yes
			(thermal_gap 0.5)
			(thermal_bridge_width 0.5)
			(island_removal_mode 0)
		)
		(polygon
			(pts
				(arc
					(start 199.03821 -295.085262)
					(mid 198.37019 -295.085262)
					(end 199.03821 -295.085262)
				)
			)
		)
	)
	(zone
		(layers "B.Cu" "In11.Cu" "In13.Cu" "In15.Cu")
		(hatch none 0.5)
		(connect_pads
			(clearance 0)
		)
		(min_thickness 0.25)
		(keepout
			(tracks not_allowed)
			(vias allowed)
			(pads allowed)
			(copperpour not_allowed)
			(footprints allowed)
		)
		(placement
			(enabled no)
			(sheetname "")
		)
		(fill yes
			(thermal_gap 0.5)
			(thermal_bridge_width 0.5)
			(island_removal_mode 0)
		)
		(polygon
			(pts
				(arc
					(start 329.31608 -279.756108)
					(mid 328.68616 -279.756108)
					(end 329.31608 -279.756108)
				)
			)
		)
	)
	(zone
		(layers "B.Cu" "In11.Cu" "In13.Cu" "In15.Cu")
		(hatch none 0.5)
		(connect_pads
			(clearance 0)
		)
		(min_thickness 0.25)
		(keepout
			(tracks not_allowed)
			(vias allowed)
			(pads allowed)
			(copperpour not_allowed)
			(footprints allowed)
		)
		(placement
			(enabled no)
			(sheetname "")
		)
		(fill yes
			(thermal_gap 0.5)
			(thermal_bridge_width 0.5)
			(island_removal_mode 0)
		)
		(polygon
			(pts
				(arc
					(start 384.1369 -428.28972)
					(mid 383.362708 -428.28972)
					(end 384.1369 -428.28972)
				)
			)
		)
	)
	(zone
		(layers "B.Cu" "In11.Cu" "In13.Cu" "In15.Cu")
		(hatch none 0.5)
		(connect_pads
			(clearance 0)
		)
		(min_thickness 0.25)
		(keepout
			(tracks not_allowed)
			(vias allowed)
			(pads allowed)
			(copperpour not_allowed)
			(footprints allowed)
		)
		(placement
			(enabled no)
			(sheetname "")
		)
		(fill yes
			(thermal_gap 0.5)
			(thermal_bridge_width 0.5)
			(island_removal_mode 0)
		)
		(polygon
			(pts
				(arc
					(start 122.729752 -286.23641)
					(mid 122.099832 -286.23641)
					(end 122.729752 -286.23641)
				)
			)
		)
	)
	(zone
		(layers "B.Cu" "In11.Cu" "In13.Cu" "In15.Cu")
		(hatch none 0.5)
		(connect_pads
			(clearance 0)
		)
		(min_thickness 0.25)
		(keepout
			(tracks not_allowed)
			(vias allowed)
			(pads allowed)
			(copperpour not_allowed)
			(footprints allowed)
		)
		(placement
			(enabled no)
			(sheetname "")
		)
		(fill yes
			(thermal_gap 0.5)
			(thermal_bridge_width 0.5)
			(island_removal_mode 0)
		)
		(polygon
			(pts
				(arc
					(start 103.636064 -241.244374)
					(mid 103.006144 -241.244374)
					(end 103.636064 -241.244374)
				)
			)
		)
	)
	(zone
		(layers "B.Cu" "In11.Cu" "In13.Cu" "In15.Cu")
		(hatch none 0.5)
		(connect_pads
			(clearance 0)
		)
		(min_thickness 0.25)
		(keepout
			(tracks not_allowed)
			(vias allowed)
			(pads allowed)
			(copperpour not_allowed)
			(footprints allowed)
		)
		(placement
			(enabled no)
			(sheetname "")
		)
		(fill yes
			(thermal_gap 0.5)
			(thermal_bridge_width 0.5)
			(island_removal_mode 0)
		)
		(polygon
			(pts
				(arc
					(start 329.78598 -267.606018)
					(mid 329.15606 -267.606018)
					(end 329.78598 -267.606018)
				)
			)
		)
	)
	(zone
		(layers "B.Cu" "In11.Cu" "In13.Cu" "In15.Cu")
		(hatch none 0.5)
		(connect_pads
			(clearance 0)
		)
		(min_thickness 0.25)
		(keepout
			(tracks not_allowed)
			(vias allowed)
			(pads allowed)
			(copperpour not_allowed)
			(footprints allowed)
		)
		(placement
			(enabled no)
			(sheetname "")
		)
		(fill yes
			(thermal_gap 0.5)
			(thermal_bridge_width 0.5)
			(island_removal_mode 0)
		)
		(polygon
			(pts
				(arc
					(start 71.036942 -426.089826)
					(mid 70.26275 -426.089826)
					(end 71.036942 -426.089826)
				)
			)
		)
	)
	(zone
		(layers "B.Cu" "In11.Cu" "In13.Cu" "In15.Cu")
		(hatch none 0.5)
		(connect_pads
			(clearance 0)
		)
		(min_thickness 0.25)
		(keepout
			(tracks not_allowed)
			(vias allowed)
			(pads allowed)
			(copperpour not_allowed)
			(footprints allowed)
		)
		(placement
			(enabled no)
			(sheetname "")
		)
		(fill yes
			(thermal_gap 0.5)
			(thermal_bridge_width 0.5)
			(island_removal_mode 0)
		)
		(polygon
			(pts
				(arc
					(start 25.486106 -248.335292)
					(mid 24.818086 -248.335292)
					(end 25.486106 -248.335292)
				)
			)
		)
	)
	(zone
		(layers "B.Cu" "In11.Cu" "In13.Cu" "In15.Cu")
		(hatch none 0.5)
		(connect_pads
			(clearance 0)
		)
		(min_thickness 0.25)
		(keepout
			(tracks not_allowed)
			(vias allowed)
			(pads allowed)
			(copperpour not_allowed)
			(footprints allowed)
		)
		(placement
			(enabled no)
			(sheetname "")
		)
		(fill yes
			(thermal_gap 0.5)
			(thermal_bridge_width 0.5)
			(island_removal_mode 0)
		)
		(polygon
			(pts
				(arc
					(start 389.63981 -232.334054)
					(mid 389.00989 -232.334054)
					(end 389.63981 -232.334054)
				)
			)
		)
	)
	(zone
		(layers "B.Cu" "In11.Cu" "In13.Cu" "In15.Cu")
		(hatch none 0.5)
		(connect_pads
			(clearance 0)
		)
		(min_thickness 0.25)
		(keepout
			(tracks not_allowed)
			(vias allowed)
			(pads allowed)
			(copperpour not_allowed)
			(footprints allowed)
		)
		(placement
			(enabled no)
			(sheetname "")
		)
		(fill yes
			(thermal_gap 0.5)
			(thermal_bridge_width 0.5)
			(island_removal_mode 0)
		)
		(polygon
			(pts
				(arc
					(start 82.955892 -228.284532)
					(mid 82.325972 -228.284532)
					(end 82.955892 -228.284532)
				)
			)
		)
	)
	(zone
		(layers "B.Cu" "In11.Cu" "In13.Cu" "In15.Cu")
		(hatch none 0.5)
		(connect_pads
			(clearance 0)
		)
		(min_thickness 0.25)
		(keepout
			(tracks not_allowed)
			(vias allowed)
			(pads allowed)
			(copperpour not_allowed)
			(footprints allowed)
		)
		(placement
			(enabled no)
			(sheetname "")
		)
		(fill yes
			(thermal_gap 0.5)
			(thermal_bridge_width 0.5)
			(island_removal_mode 0)
		)
		(polygon
			(pts
				(arc
					(start 329.016106 -236.384084)
					(mid 328.386186 -236.384084)
					(end 329.016106 -236.384084)
				)
			)
		)
	)
	(zone
		(layers "B.Cu" "In11.Cu" "In13.Cu" "In15.Cu")
		(hatch none 0.5)
		(connect_pads
			(clearance 0)
		)
		(min_thickness 0.25)
		(keepout
			(tracks not_allowed)
			(vias allowed)
			(pads allowed)
			(copperpour not_allowed)
			(footprints allowed)
		)
		(placement
			(enabled no)
			(sheetname "")
		)
		(fill yes
			(thermal_gap 0.5)
			(thermal_bridge_width 0.5)
			(island_removal_mode 0)
		)
		(polygon
			(pts
				(arc
					(start 29.586174 -238.135414)
					(mid 28.918154 -238.135414)
					(end 29.586174 -238.135414)
				)
			)
		)
	)
	(zone
		(layers "B.Cu" "In11.Cu" "In13.Cu" "In15.Cu")
		(hatch none 0.5)
		(connect_pads
			(clearance 0)
		)
		(min_thickness 0.25)
		(keepout
			(tracks not_allowed)
			(vias allowed)
			(pads allowed)
			(copperpour not_allowed)
			(footprints allowed)
		)
		(placement
			(enabled no)
			(sheetname "")
		)
		(fill yes
			(thermal_gap 0.5)
			(thermal_bridge_width 0.5)
			(island_removal_mode 0)
		)
		(polygon
			(pts
				(arc
					(start 277.526242 -238.985044)
					(mid 276.858222 -238.985044)
					(end 277.526242 -238.985044)
				)
			)
		)
	)
	(zone
		(layers "B.Cu" "In11.Cu" "In13.Cu" "In15.Cu")
		(hatch none 0.5)
		(connect_pads
			(clearance 0)
		)
		(min_thickness 0.25)
		(keepout
			(tracks not_allowed)
			(vias allowed)
			(pads allowed)
			(copperpour not_allowed)
			(footprints allowed)
		)
		(placement
			(enabled no)
			(sheetname "")
		)
		(fill yes
			(thermal_gap 0.5)
			(thermal_bridge_width 0.5)
			(island_removal_mode 0)
		)
		(polygon
			(pts
				(arc
					(start 199.03821 -203.285344)
					(mid 198.37019 -203.285344)
					(end 199.03821 -203.285344)
				)
			)
		)
	)
	(zone
		(layers "B.Cu" "In11.Cu" "In13.Cu" "In15.Cu")
		(hatch none 0.5)
		(connect_pads
			(clearance 0)
		)
		(min_thickness 0.25)
		(keepout
			(tracks not_allowed)
			(vias allowed)
			(pads allowed)
			(copperpour not_allowed)
			(footprints allowed)
		)
		(placement
			(enabled no)
			(sheetname "")
		)
		(fill yes
			(thermal_gap 0.5)
			(thermal_bridge_width 0.5)
			(island_removal_mode 0)
		)
		(polygon
			(pts
				(arc
					(start 277.526242 -208.385156)
					(mid 276.858222 -208.385156)
					(end 277.526242 -208.385156)
				)
			)
		)
	)
	(zone
		(layers "B.Cu" "In11.Cu" "In13.Cu" "In15.Cu")
		(hatch none 0.5)
		(connect_pads
			(clearance 0)
		)
		(min_thickness 0.25)
		(keepout
			(tracks not_allowed)
			(vias allowed)
			(pads allowed)
			(copperpour not_allowed)
			(footprints allowed)
		)
		(placement
			(enabled no)
			(sheetname "")
		)
		(fill yes
			(thermal_gap 0.5)
			(thermal_bridge_width 0.5)
			(island_removal_mode 0)
		)
		(polygon
			(pts
				(arc
					(start 150.134066 -385.31038)
					(mid 149.504146 -385.31038)
					(end 150.134066 -385.31038)
				)
			)
		)
	)
	(zone
		(layers "B.Cu" "In11.Cu" "In13.Cu" "In15.Cu")
		(hatch none 0.5)
		(connect_pads
			(clearance 0)
		)
		(min_thickness 0.25)
		(keepout
			(tracks not_allowed)
			(vias allowed)
			(pads allowed)
			(copperpour not_allowed)
			(footprints allowed)
		)
		(placement
			(enabled no)
			(sheetname "")
		)
		(fill yes
			(thermal_gap 0.5)
			(thermal_bridge_width 0.5)
			(island_removal_mode 0)
		)
		(polygon
			(pts
				(arc
					(start 273.426174 -215.18499)
					(mid 272.758154 -215.18499)
					(end 273.426174 -215.18499)
				)
			)
		)
	)
	(zone
		(layers "B.Cu" "In11.Cu" "In13.Cu" "In15.Cu")
		(hatch none 0.5)
		(connect_pads
			(clearance 0)
		)
		(min_thickness 0.25)
		(keepout
			(tracks not_allowed)
			(vias allowed)
			(pads allowed)
			(copperpour not_allowed)
			(footprints allowed)
		)
		(placement
			(enabled no)
			(sheetname "")
		)
		(fill yes
			(thermal_gap 0.5)
			(thermal_bridge_width 0.5)
			(island_removal_mode 0)
		)
		(polygon
			(pts
				(arc
					(start 273.426174 -293.384986)
					(mid 272.758154 -293.384986)
					(end 273.426174 -293.384986)
				)
			)
		)
	)
	(zone
		(layers "B.Cu" "In11.Cu" "In13.Cu" "In15.Cu")
		(hatch none 0.5)
		(connect_pads
			(clearance 0)
		)
		(min_thickness 0.25)
		(keepout
			(tracks not_allowed)
			(vias allowed)
			(pads allowed)
			(copperpour not_allowed)
			(footprints allowed)
		)
		(placement
			(enabled no)
			(sheetname "")
		)
		(fill yes
			(thermal_gap 0.5)
			(thermal_bridge_width 0.5)
			(island_removal_mode 0)
		)
		(polygon
			(pts
				(arc
					(start 136.136888 -427.089824)
					(mid 135.362696 -427.089824)
					(end 136.136888 -427.089824)
				)
			)
		)
	)
	(zone
		(layers "B.Cu" "In11.Cu" "In13.Cu" "In15.Cu")
		(hatch none 0.5)
		(connect_pads
			(clearance 0)
		)
		(min_thickness 0.25)
		(keepout
			(tracks not_allowed)
			(vias allowed)
			(pads allowed)
			(copperpour not_allowed)
			(footprints allowed)
		)
		(placement
			(enabled no)
			(sheetname "")
		)
		(fill yes
			(thermal_gap 0.5)
			(thermal_bridge_width 0.5)
			(island_removal_mode 0)
		)
		(polygon
			(pts
				(arc
					(start 365.66983 -239.624108)
					(mid 365.03991 -239.624108)
					(end 365.66983 -239.624108)
				)
			)
		)
	)
	(zone
		(layers "B.Cu" "In11.Cu" "In13.Cu" "In15.Cu")
		(hatch none 0.5)
		(connect_pads
			(clearance 0)
		)
		(min_thickness 0.25)
		(keepout
			(tracks not_allowed)
			(vias allowed)
			(pads allowed)
			(copperpour not_allowed)
			(footprints allowed)
		)
		(placement
			(enabled no)
			(sheetname "")
		)
		(fill yes
			(thermal_gap 0.5)
			(thermal_bridge_width 0.5)
			(island_removal_mode 0)
		)
		(polygon
			(pts
				(arc
					(start 273.426174 -286.585152)
					(mid 272.758154 -286.585152)
					(end 273.426174 -286.585152)
				)
			)
		)
	)
	(zone
		(layers "B.Cu" "In11.Cu" "In13.Cu" "In15.Cu")
		(hatch none 0.5)
		(connect_pads
			(clearance 0)
		)
		(min_thickness 0.25)
		(keepout
			(tracks not_allowed)
			(vias allowed)
			(pads allowed)
			(copperpour not_allowed)
			(footprints allowed)
		)
		(placement
			(enabled no)
			(sheetname "")
		)
		(fill yes
			(thermal_gap 0.5)
			(thermal_bridge_width 0.5)
			(island_removal_mode 0)
		)
		(polygon
			(pts
				(arc
					(start 374.429782 -284.616144)
					(mid 373.799862 -284.616144)
					(end 374.429782 -284.616144)
				)
			)
		)
	)
	(zone
		(layers "B.Cu" "In11.Cu" "In13.Cu" "In15.Cu")
		(hatch none 0.5)
		(connect_pads
			(clearance 0)
		)
		(min_thickness 0.25)
		(keepout
			(tracks not_allowed)
			(vias allowed)
			(pads allowed)
			(copperpour not_allowed)
			(footprints allowed)
		)
		(placement
			(enabled no)
			(sheetname "")
		)
		(fill yes
			(thermal_gap 0.5)
			(thermal_bridge_width 0.5)
			(island_removal_mode 0)
		)
		(polygon
			(pts
				(arc
					(start 82.955892 -252.584458)
					(mid 82.325972 -252.584458)
					(end 82.955892 -252.584458)
				)
			)
		)
	)
	(zone
		(layers "B.Cu" "In11.Cu" "In13.Cu" "In15.Cu")
		(hatch none 0.5)
		(connect_pads
			(clearance 0)
		)
		(min_thickness 0.25)
		(keepout
			(tracks not_allowed)
			(vias allowed)
			(pads allowed)
			(copperpour not_allowed)
			(footprints allowed)
		)
		(placement
			(enabled no)
			(sheetname "")
		)
		(fill yes
			(thermal_gap 0.5)
			(thermal_bridge_width 0.5)
			(island_removal_mode 0)
		)
		(polygon
			(pts
				(arc
					(start 327.036684 -427.289976)
					(mid 326.262492 -427.289976)
					(end 327.036684 -427.289976)
				)
			)
		)
	)
	(zone
		(layers "B.Cu" "In11.Cu" "In13.Cu" "In15.Cu")
		(hatch none 0.5)
		(connect_pads
			(clearance 0)
		)
		(min_thickness 0.25)
		(keepout
			(tracks not_allowed)
			(vias allowed)
			(pads allowed)
			(copperpour not_allowed)
			(footprints allowed)
		)
		(placement
			(enabled no)
			(sheetname "")
		)
		(fill yes
			(thermal_gap 0.5)
			(thermal_bridge_width 0.5)
			(island_removal_mode 0)
		)
		(polygon
			(pts
				(arc
					(start 277.526242 -199.035162)
					(mid 276.858222 -199.035162)
					(end 277.526242 -199.035162)
				)
			)
		)
	)
	(zone
		(layers "B.Cu" "In11.Cu" "In13.Cu" "In15.Cu")
		(hatch none 0.5)
		(connect_pads
			(clearance 0)
		)
		(min_thickness 0.25)
		(keepout
			(tracks not_allowed)
			(vias allowed)
			(pads allowed)
			(copperpour not_allowed)
			(footprints allowed)
		)
		(placement
			(enabled no)
			(sheetname "")
		)
		(fill yes
			(thermal_gap 0.5)
			(thermal_bridge_width 0.5)
			(island_removal_mode 0)
		)
		(polygon
			(pts
				(arc
					(start 76.560934 -404.46452)
					(mid 75.892914 -404.46452)
					(end 76.560934 -404.46452)
				)
			)
		)
	)
	(zone
		(layers "B.Cu" "In11.Cu" "In13.Cu" "In15.Cu")
		(hatch none 0.5)
		(connect_pads
			(clearance 0)
		)
		(min_thickness 0.25)
		(keepout
			(tracks not_allowed)
			(vias allowed)
			(pads allowed)
			(copperpour not_allowed)
			(footprints allowed)
		)
		(placement
			(enabled no)
			(sheetname "")
		)
		(fill yes
			(thermal_gap 0.5)
			(thermal_bridge_width 0.5)
			(island_removal_mode 0)
		)
		(polygon
			(pts
				(arc
					(start 64.106298 -389.467344)
					(mid 63.476378 -389.467344)
					(end 64.106298 -389.467344)
				)
			)
		)
	)
	(zone
		(layers "B.Cu" "In11.Cu" "In13.Cu" "In15.Cu")
		(hatch none 0.5)
		(connect_pads
			(clearance 0)
		)
		(min_thickness 0.25)
		(keepout
			(tracks not_allowed)
			(vias allowed)
			(pads allowed)
			(copperpour not_allowed)
			(footprints allowed)
		)
		(placement
			(enabled no)
			(sheetname "")
		)
		(fill yes
			(thermal_gap 0.5)
			(thermal_bridge_width 0.5)
			(island_removal_mode 0)
		)
		(polygon
			(pts
				(arc
					(start 306.156106 -379.88113)
					(mid 305.488086 -379.88113)
					(end 306.156106 -379.88113)
				)
			)
		)
	)
	(zone
		(layers "B.Cu" "In11.Cu" "In13.Cu" "In15.Cu")
		(hatch none 0.5)
		(connect_pads
			(clearance 0)
		)
		(min_thickness 0.25)
		(keepout
			(tracks not_allowed)
			(vias allowed)
			(pads allowed)
			(copperpour not_allowed)
			(footprints allowed)
		)
		(placement
			(enabled no)
			(sheetname "")
		)
		(fill yes
			(thermal_gap 0.5)
			(thermal_bridge_width 0.5)
			(island_removal_mode 0)
		)
		(polygon
			(pts
				(arc
					(start 81.076038 -233.144314)
					(mid 80.446118 -233.144314)
					(end 81.076038 -233.144314)
				)
			)
		)
	)
	(zone
		(layers "B.Cu" "In11.Cu" "In13.Cu" "In15.Cu")
		(hatch none 0.5)
		(connect_pads
			(clearance 0)
		)
		(min_thickness 0.25)
		(keepout
			(tracks not_allowed)
			(vias allowed)
			(pads allowed)
			(copperpour not_allowed)
			(footprints allowed)
		)
		(placement
			(enabled no)
			(sheetname "")
		)
		(fill yes
			(thermal_gap 0.5)
			(thermal_bridge_width 0.5)
			(island_removal_mode 0)
		)
		(polygon
			(pts
				(arc
					(start 329.016106 -241.24412)
					(mid 328.386186 -241.24412)
					(end 329.016106 -241.24412)
				)
			)
		)
	)
	(zone
		(layers "B.Cu" "In11.Cu" "In13.Cu" "In15.Cu")
		(hatch none 0.5)
		(connect_pads
			(clearance 0)
		)
		(min_thickness 0.25)
		(keepout
			(tracks not_allowed)
			(vias allowed)
			(pads allowed)
			(copperpour not_allowed)
			(footprints allowed)
		)
		(placement
			(enabled no)
			(sheetname "")
		)
		(fill yes
			(thermal_gap 0.5)
			(thermal_bridge_width 0.5)
			(island_removal_mode 0)
		)
		(polygon
			(pts
				(arc
					(start 29.586174 -285.735268)
					(mid 28.918154 -285.735268)
					(end 29.586174 -285.735268)
				)
			)
		)
	)
	(zone
		(layers "B.Cu" "In11.Cu" "In13.Cu" "In15.Cu")
		(hatch none 0.5)
		(connect_pads
			(clearance 0)
		)
		(min_thickness 0.25)
		(keepout
			(tracks not_allowed)
			(vias allowed)
			(pads allowed)
			(copperpour not_allowed)
			(footprints allowed)
		)
		(placement
			(enabled no)
			(sheetname "")
		)
		(fill yes
			(thermal_gap 0.5)
			(thermal_bridge_width 0.5)
			(island_removal_mode 0)
		)
		(polygon
			(pts
				(arc
					(start 81.845912 -267.606272)
					(mid 81.215992 -267.606272)
					(end 81.845912 -267.606272)
				)
			)
		)
	)
	(zone
		(layers "B.Cu" "In11.Cu" "In13.Cu" "In15.Cu")
		(hatch none 0.5)
		(connect_pads
			(clearance 0)
		)
		(min_thickness 0.25)
		(keepout
			(tracks not_allowed)
			(vias allowed)
			(pads allowed)
			(copperpour not_allowed)
			(footprints allowed)
		)
		(placement
			(enabled no)
			(sheetname "")
		)
		(fill yes
			(thermal_gap 0.5)
			(thermal_bridge_width 0.5)
			(island_removal_mode 0)
		)
		(polygon
			(pts
				(arc
					(start 194.938142 -218.585288)
					(mid 194.270122 -218.585288)
					(end 194.938142 -218.585288)
				)
			)
		)
	)
	(zone
		(layers "B.Cu" "In11.Cu" "In13.Cu" "In15.Cu")
		(hatch none 0.5)
		(connect_pads
			(clearance 0)
		)
		(min_thickness 0.25)
		(keepout
			(tracks not_allowed)
			(vias allowed)
			(pads allowed)
			(copperpour not_allowed)
			(footprints allowed)
		)
		(placement
			(enabled no)
			(sheetname "")
		)
		(fill yes
			(thermal_gap 0.5)
			(thermal_bridge_width 0.5)
			(island_removal_mode 0)
		)
		(polygon
			(pts
				(arc
					(start 442.87821 -305.28514)
					(mid 442.21019 -305.28514)
					(end 442.87821 -305.28514)
				)
			)
		)
	)
	(zone
		(layers "B.Cu" "In11.Cu" "In13.Cu" "In15.Cu")
		(hatch none 0.5)
		(connect_pads
			(clearance 0)
		)
		(min_thickness 0.25)
		(keepout
			(tracks not_allowed)
			(vias allowed)
			(pads allowed)
			(copperpour not_allowed)
			(footprints allowed)
		)
		(placement
			(enabled no)
			(sheetname "")
		)
		(fill yes
			(thermal_gap 0.5)
			(thermal_bridge_width 0.5)
			(island_removal_mode 0)
		)
		(polygon
			(pts
				(arc
					(start 389.939784 -283.806138)
					(mid 389.309864 -283.806138)
					(end 389.939784 -283.806138)
				)
			)
		)
	)
	(zone
		(layers "B.Cu" "In11.Cu" "In13.Cu" "In15.Cu")
		(hatch none 0.5)
		(connect_pads
			(clearance 0)
		)
		(min_thickness 0.25)
		(keepout
			(tracks not_allowed)
			(vias allowed)
			(pads allowed)
			(copperpour not_allowed)
			(footprints allowed)
		)
		(placement
			(enabled no)
			(sheetname "")
		)
		(fill yes
			(thermal_gap 0.5)
			(thermal_bridge_width 0.5)
			(island_removal_mode 0)
		)
		(polygon
			(pts
				(arc
					(start 29.586174 -245.785386)
					(mid 28.918154 -245.785386)
					(end 29.586174 -245.785386)
				)
			)
		)
	)
	(zone
		(layers "B.Cu" "In11.Cu" "In13.Cu" "In15.Cu")
		(hatch none 0.5)
		(connect_pads
			(clearance 0)
		)
		(min_thickness 0.25)
		(keepout
			(tracks not_allowed)
			(vias allowed)
			(pads allowed)
			(copperpour not_allowed)
			(footprints allowed)
		)
		(placement
			(enabled no)
			(sheetname "")
		)
		(fill yes
			(thermal_gap 0.5)
			(thermal_bridge_width 0.5)
			(island_removal_mode 0)
		)
		(polygon
			(pts
				(arc
					(start 120.849644 -286.23641)
					(mid 120.219724 -286.23641)
					(end 120.849644 -286.23641)
				)
			)
		)
	)
	(zone
		(layers "B.Cu" "In11.Cu" "In13.Cu" "In15.Cu")
		(hatch none 0.5)
		(connect_pads
			(clearance 0)
		)
		(min_thickness 0.25)
		(keepout
			(tracks not_allowed)
			(vias allowed)
			(pads allowed)
			(copperpour not_allowed)
			(footprints allowed)
		)
		(placement
			(enabled no)
			(sheetname "")
		)
		(fill yes
			(thermal_gap 0.5)
			(thermal_bridge_width 0.5)
			(island_removal_mode 0)
		)
		(polygon
			(pts
				(arc
					(start 83.255866 -273.276314)
					(mid 82.625946 -273.276314)
					(end 83.255866 -273.276314)
				)
			)
		)
	)
	(zone
		(layers "B.Cu" "In11.Cu" "In13.Cu" "In15.Cu")
		(hatch none 0.5)
		(connect_pads
			(clearance 0)
		)
		(min_thickness 0.25)
		(keepout
			(tracks not_allowed)
			(vias allowed)
			(pads allowed)
			(copperpour not_allowed)
			(footprints allowed)
		)
		(placement
			(enabled no)
			(sheetname "")
		)
		(fill yes
			(thermal_gap 0.5)
			(thermal_bridge_width 0.5)
			(island_removal_mode 0)
		)
		(polygon
			(pts
				(arc
					(start 442.87821 -201.585068)
					(mid 442.21019 -201.585068)
					(end 442.87821 -201.585068)
				)
			)
		)
	)
	(zone
		(layers "B.Cu" "In11.Cu" "In13.Cu" "In15.Cu")
		(hatch none 0.5)
		(connect_pads
			(clearance 0)
		)
		(min_thickness 0.25)
		(keepout
			(tracks not_allowed)
			(vias allowed)
			(pads allowed)
			(copperpour not_allowed)
			(footprints allowed)
		)
		(placement
			(enabled no)
			(sheetname "")
		)
		(fill yes
			(thermal_gap 0.5)
			(thermal_bridge_width 0.5)
			(island_removal_mode 0)
		)
		(polygon
			(pts
				(arc
					(start 319.0367 -426.089826)
					(mid 318.262508 -426.089826)
					(end 319.0367 -426.089826)
				)
			)
		)
	)
	(zone
		(layers "B.Cu" "In11.Cu" "In13.Cu" "In15.Cu")
		(hatch none 0.5)
		(connect_pads
			(clearance 0)
		)
		(min_thickness 0.25)
		(keepout
			(tracks not_allowed)
			(vias allowed)
			(pads allowed)
			(copperpour not_allowed)
			(footprints allowed)
		)
		(placement
			(enabled no)
			(sheetname "")
		)
		(fill yes
			(thermal_gap 0.5)
			(thermal_bridge_width 0.5)
			(island_removal_mode 0)
		)
		(polygon
			(pts
				(arc
					(start 25.486106 -210.935316)
					(mid 24.818086 -210.935316)
					(end 25.486106 -210.935316)
				)
			)
		)
	)
	(zone
		(layers "B.Cu" "In11.Cu" "In13.Cu" "In15.Cu")
		(hatch none 0.5)
		(connect_pads
			(clearance 0)
		)
		(min_thickness 0.25)
		(keepout
			(tracks not_allowed)
			(vias allowed)
			(pads allowed)
			(copperpour not_allowed)
			(footprints allowed)
		)
		(placement
			(enabled no)
			(sheetname "")
		)
		(fill yes
			(thermal_gap 0.5)
			(thermal_bridge_width 0.5)
			(island_removal_mode 0)
		)
		(polygon
			(pts
				(arc
					(start 153.137108 -428.28972)
					(mid 152.362916 -428.28972)
					(end 153.137108 -428.28972)
				)
			)
		)
	)
	(zone
		(layers "B.Cu" "In11.Cu" "In13.Cu" "In15.Cu")
		(hatch none 0.5)
		(connect_pads
			(clearance 0)
		)
		(min_thickness 0.25)
		(keepout
			(tracks not_allowed)
			(vias allowed)
			(pads allowed)
			(copperpour not_allowed)
			(footprints allowed)
		)
		(placement
			(enabled no)
			(sheetname "")
		)
		(fill yes
			(thermal_gap 0.5)
			(thermal_bridge_width 0.5)
			(island_removal_mode 0)
		)
		(polygon
			(pts
				(arc
					(start 101.755956 -239.624362)
					(mid 101.126036 -239.624362)
					(end 101.755956 -239.624362)
				)
			)
		)
	)
	(zone
		(layers "B.Cu" "In11.Cu" "In13.Cu" "In15.Cu")
		(hatch none 0.5)
		(connect_pads
			(clearance 0)
		)
		(min_thickness 0.25)
		(keepout
			(tracks not_allowed)
			(vias allowed)
			(pads allowed)
			(copperpour not_allowed)
			(footprints allowed)
		)
		(placement
			(enabled no)
			(sheetname "")
		)
		(fill yes
			(thermal_gap 0.5)
			(thermal_bridge_width 0.5)
			(island_removal_mode 0)
		)
		(polygon
			(pts
				(arc
					(start 25.486106 -211.7852)
					(mid 24.818086 -211.7852)
					(end 25.486106 -211.7852)
				)
			)
		)
	)
	(zone
		(layers "B.Cu" "In11.Cu" "In13.Cu" "In15.Cu")
		(hatch none 0.5)
		(connect_pads
			(clearance 0)
		)
		(min_thickness 0.25)
		(keepout
			(tracks not_allowed)
			(vias allowed)
			(pads allowed)
			(copperpour not_allowed)
			(footprints allowed)
		)
		(placement
			(enabled no)
			(sheetname "")
		)
		(fill yes
			(thermal_gap 0.5)
			(thermal_bridge_width 0.5)
			(island_removal_mode 0)
		)
		(polygon
			(pts
				(arc
					(start 386.136896 -427.289976)
					(mid 385.362704 -427.289976)
					(end 386.136896 -427.289976)
				)
			)
		)
	)
	(zone
		(layers "B.Cu" "In11.Cu" "In13.Cu" "In15.Cu")
		(hatch none 0.5)
		(connect_pads
			(clearance 0)
		)
		(min_thickness 0.25)
		(keepout
			(tracks not_allowed)
			(vias allowed)
			(pads allowed)
			(copperpour not_allowed)
			(footprints allowed)
		)
		(placement
			(enabled no)
			(sheetname "")
		)
		(fill yes
			(thermal_gap 0.5)
			(thermal_bridge_width 0.5)
			(island_removal_mode 0)
		)
		(polygon
			(pts
				(arc
					(start 103.357934 -31.95701)
					(mid 102.689914 -31.95701)
					(end 103.357934 -31.95701)
				)
			)
		)
	)
	(zone
		(layers "B.Cu" "In11.Cu" "In13.Cu" "In15.Cu")
		(hatch none 0.5)
		(connect_pads
			(clearance 0)
		)
		(min_thickness 0.25)
		(keepout
			(tracks not_allowed)
			(vias allowed)
			(pads allowed)
			(copperpour not_allowed)
			(footprints allowed)
		)
		(placement
			(enabled no)
			(sheetname "")
		)
		(fill yes
			(thermal_gap 0.5)
			(thermal_bridge_width 0.5)
			(island_removal_mode 0)
		)
		(polygon
			(pts
				(arc
					(start 337.03387 -397.849344)
					(mid 336.40395 -397.849344)
					(end 337.03387 -397.849344)
				)
			)
		)
	)
	(zone
		(layers "B.Cu" "In11.Cu" "In13.Cu" "In15.Cu")
		(hatch none 0.5)
		(connect_pads
			(clearance 0)
		)
		(min_thickness 0.25)
		(keepout
			(tracks not_allowed)
			(vias allowed)
			(pads allowed)
			(copperpour not_allowed)
			(footprints allowed)
		)
		(placement
			(enabled no)
			(sheetname "")
		)
		(fill yes
			(thermal_gap 0.5)
			(thermal_bridge_width 0.5)
			(island_removal_mode 0)
		)
		(polygon
			(pts
				(arc
					(start 25.486106 -265.335258)
					(mid 24.818086 -265.335258)
					(end 25.486106 -265.335258)
				)
			)
		)
	)
	(zone
		(layers "B.Cu" "In11.Cu" "In13.Cu" "In15.Cu")
		(hatch none 0.5)
		(connect_pads
			(clearance 0)
		)
		(min_thickness 0.25)
		(keepout
			(tracks not_allowed)
			(vias allowed)
			(pads allowed)
			(copperpour not_allowed)
			(footprints allowed)
		)
		(placement
			(enabled no)
			(sheetname "")
		)
		(fill yes
			(thermal_gap 0.5)
			(thermal_bridge_width 0.5)
			(island_removal_mode 0)
		)
		(polygon
			(pts
				(arc
					(start 29.586174 -233.035348)
					(mid 28.918154 -233.035348)
					(end 29.586174 -233.035348)
				)
			)
		)
	)
	(zone
		(layers "B.Cu" "In11.Cu" "In13.Cu" "In15.Cu")
		(hatch none 0.5)
		(connect_pads
			(clearance 0)
		)
		(min_thickness 0.25)
		(keepout
			(tracks not_allowed)
			(vias allowed)
			(pads allowed)
			(copperpour not_allowed)
			(footprints allowed)
		)
		(placement
			(enabled no)
			(sheetname "")
		)
		(fill yes
			(thermal_gap 0.5)
			(thermal_bridge_width 0.5)
			(island_removal_mode 0)
		)
		(polygon
			(pts
				(arc
					(start 141.229842 -238.00435)
					(mid 140.599922 -238.00435)
					(end 141.229842 -238.00435)
				)
			)
		)
	)
	(zone
		(layers "B.Cu" "In11.Cu" "In13.Cu" "In15.Cu")
		(hatch none 0.5)
		(connect_pads
			(clearance 0)
		)
		(min_thickness 0.25)
		(keepout
			(tracks not_allowed)
			(vias allowed)
			(pads allowed)
			(copperpour not_allowed)
			(footprints allowed)
		)
		(placement
			(enabled no)
			(sheetname "")
		)
		(fill yes
			(thermal_gap 0.5)
			(thermal_bridge_width 0.5)
			(island_removal_mode 0)
		)
		(polygon
			(pts
				(arc
					(start 152.933908 -386.003292)
					(mid 152.303988 -386.003292)
					(end 152.933908 -386.003292)
				)
			)
		)
	)
	(zone
		(layers "B.Cu" "In11.Cu" "In13.Cu" "In15.Cu")
		(hatch none 0.5)
		(connect_pads
			(clearance 0)
		)
		(min_thickness 0.25)
		(keepout
			(tracks not_allowed)
			(vias allowed)
			(pads allowed)
			(copperpour not_allowed)
			(footprints allowed)
		)
		(placement
			(enabled no)
			(sheetname "")
		)
		(fill yes
			(thermal_gap 0.5)
			(thermal_bridge_width 0.5)
			(island_removal_mode 0)
		)
		(polygon
			(pts
				(arc
					(start 370.369846 -241.24412)
					(mid 369.739926 -241.24412)
					(end 370.369846 -241.24412)
				)
			)
		)
	)
	(zone
		(layers "B.Cu" "In11.Cu" "In13.Cu" "In15.Cu")
		(hatch none 0.5)
		(connect_pads
			(clearance 0)
		)
		(min_thickness 0.25)
		(keepout
			(tracks not_allowed)
			(vias allowed)
			(pads allowed)
			(copperpour not_allowed)
			(footprints allowed)
		)
		(placement
			(enabled no)
			(sheetname "")
		)
		(fill yes
			(thermal_gap 0.5)
			(thermal_bridge_width 0.5)
			(island_removal_mode 0)
		)
		(polygon
			(pts
				(arc
					(start 442.87821 -278.93518)
					(mid 442.21019 -278.93518)
					(end 442.87821 -278.93518)
				)
			)
		)
	)
	(zone
		(layers "B.Cu" "In11.Cu" "In13.Cu" "In15.Cu")
		(hatch none 0.5)
		(connect_pads
			(clearance 0)
		)
		(min_thickness 0.25)
		(keepout
			(tracks not_allowed)
			(vias allowed)
			(pads allowed)
			(copperpour not_allowed)
			(footprints allowed)
		)
		(placement
			(enabled no)
			(sheetname "")
		)
		(fill yes
			(thermal_gap 0.5)
			(thermal_bridge_width 0.5)
			(island_removal_mode 0)
		)
		(polygon
			(pts
				(arc
					(start 331.195934 -276.516084)
					(mid 330.566014 -276.516084)
					(end 331.195934 -276.516084)
				)
			)
		)
	)
	(zone
		(layers "B.Cu" "In11.Cu" "In13.Cu" "In15.Cu")
		(hatch none 0.5)
		(connect_pads
			(clearance 0)
		)
		(min_thickness 0.25)
		(keepout
			(tracks not_allowed)
			(vias allowed)
			(pads allowed)
			(copperpour not_allowed)
			(footprints allowed)
		)
		(placement
			(enabled no)
			(sheetname "")
		)
		(fill yes
			(thermal_gap 0.5)
			(thermal_bridge_width 0.5)
			(island_removal_mode 0)
		)
		(polygon
			(pts
				(arc
					(start 166.134034 -386.003292)
					(mid 165.504114 -386.003292)
					(end 166.134034 -386.003292)
				)
			)
		)
	)
	(zone
		(layers "B.Cu" "In11.Cu" "In13.Cu" "In15.Cu")
		(hatch none 0.5)
		(connect_pads
			(clearance 0)
		)
		(min_thickness 0.25)
		(keepout
			(tracks not_allowed)
			(vias allowed)
			(pads allowed)
			(copperpour not_allowed)
			(footprints allowed)
		)
		(placement
			(enabled no)
			(sheetname "")
		)
		(fill yes
			(thermal_gap 0.5)
			(thermal_bridge_width 0.5)
			(island_removal_mode 0)
		)
		(polygon
			(pts
				(arc
					(start 368.789712 -286.236156)
					(mid 368.159792 -286.236156)
					(end 368.789712 -286.236156)
				)
			)
		)
	)
	(zone
		(layers "B.Cu" "In11.Cu" "In13.Cu" "In15.Cu")
		(hatch none 0.5)
		(connect_pads
			(clearance 0)
		)
		(min_thickness 0.25)
		(keepout
			(tracks not_allowed)
			(vias allowed)
			(pads allowed)
			(copperpour not_allowed)
			(footprints allowed)
		)
		(placement
			(enabled no)
			(sheetname "")
		)
		(fill yes
			(thermal_gap 0.5)
			(thermal_bridge_width 0.5)
			(island_removal_mode 0)
		)
		(polygon
			(pts
				(arc
					(start 370.369846 -242.864132)
					(mid 369.739926 -242.864132)
					(end 370.369846 -242.864132)
				)
			)
		)
	)
	(zone
		(layers "B.Cu" "In11.Cu" "In13.Cu" "In15.Cu")
		(hatch none 0.5)
		(connect_pads
			(clearance 0)
		)
		(min_thickness 0.25)
		(keepout
			(tracks not_allowed)
			(vias allowed)
			(pads allowed)
			(copperpour not_allowed)
			(footprints allowed)
		)
		(placement
			(enabled no)
			(sheetname "")
		)
		(fill yes
			(thermal_gap 0.5)
			(thermal_bridge_width 0.5)
			(island_removal_mode 0)
		)
		(polygon
			(pts
				(arc
					(start 194.938142 -308.685438)
					(mid 194.270122 -308.685438)
					(end 194.938142 -308.685438)
				)
			)
		)
	)
	(zone
		(layers "B.Cu" "In11.Cu" "In13.Cu" "In15.Cu")
		(hatch none 0.5)
		(connect_pads
			(clearance 0)
		)
		(min_thickness 0.25)
		(keepout
			(tracks not_allowed)
			(vias allowed)
			(pads allowed)
			(copperpour not_allowed)
			(footprints allowed)
		)
		(placement
			(enabled no)
			(sheetname "")
		)
		(fill yes
			(thermal_gap 0.5)
			(thermal_bridge_width 0.5)
			(island_removal_mode 0)
		)
		(polygon
			(pts
				(arc
					(start 367.849658 -284.616144)
					(mid 367.219738 -284.616144)
					(end 367.849658 -284.616144)
				)
			)
		)
	)
	(zone
		(layers "B.Cu" "In11.Cu" "In13.Cu" "In15.Cu")
		(hatch none 0.5)
		(connect_pads
			(clearance 0)
		)
		(min_thickness 0.25)
		(keepout
			(tracks not_allowed)
			(vias allowed)
			(pads allowed)
			(copperpour not_allowed)
			(footprints allowed)
		)
		(placement
			(enabled no)
			(sheetname "")
		)
		(fill yes
			(thermal_gap 0.5)
			(thermal_bridge_width 0.5)
			(island_removal_mode 0)
		)
		(polygon
			(pts
				(arc
					(start 389.16991 -250.964192)
					(mid 388.53999 -250.964192)
					(end 389.16991 -250.964192)
				)
			)
		)
	)
	(zone
		(layers "B.Cu" "In11.Cu" "In13.Cu" "In15.Cu")
		(hatch none 0.5)
		(connect_pads
			(clearance 0)
		)
		(min_thickness 0.25)
		(keepout
			(tracks not_allowed)
			(vias allowed)
			(pads allowed)
			(copperpour not_allowed)
			(footprints allowed)
		)
		(placement
			(enabled no)
			(sheetname "")
		)
		(fill yes
			(thermal_gap 0.5)
			(thermal_bridge_width 0.5)
			(island_removal_mode 0)
		)
		(polygon
			(pts
				(arc
					(start 141.229842 -246.10441)
					(mid 140.599922 -246.10441)
					(end 141.229842 -246.10441)
				)
			)
		)
	)
	(zone
		(layers "B.Cu" "In11.Cu" "In13.Cu" "In15.Cu")
		(hatch none 0.5)
		(connect_pads
			(clearance 0)
		)
		(min_thickness 0.25)
		(keepout
			(tracks not_allowed)
			(vias allowed)
			(pads allowed)
			(copperpour not_allowed)
			(footprints allowed)
		)
		(placement
			(enabled no)
			(sheetname "")
		)
		(fill yes
			(thermal_gap 0.5)
			(thermal_bridge_width 0.5)
			(island_removal_mode 0)
		)
		(polygon
			(pts
				(arc
					(start 81.845912 -283.806392)
					(mid 81.215992 -283.806392)
					(end 81.845912 -283.806392)
				)
			)
		)
	)
	(zone
		(layers "B.Cu" "In11.Cu" "In13.Cu" "In15.Cu")
		(hatch none 0.5)
		(connect_pads
			(clearance 0)
		)
		(min_thickness 0.25)
		(keepout
			(tracks not_allowed)
			(vias allowed)
			(pads allowed)
			(copperpour not_allowed)
			(footprints allowed)
		)
		(placement
			(enabled no)
			(sheetname "")
		)
		(fill yes
			(thermal_gap 0.5)
			(thermal_bridge_width 0.5)
			(island_removal_mode 0)
		)
		(polygon
			(pts
				(arc
					(start 59.036966 -420.089838)
					(mid 58.262774 -420.089838)
					(end 59.036966 -420.089838)
				)
			)
		)
	)
	(zone
		(layers "B.Cu" "In11.Cu" "In13.Cu" "In15.Cu")
		(hatch none 0.5)
		(connect_pads
			(clearance 0)
		)
		(min_thickness 0.25)
		(keepout
			(tracks not_allowed)
			(vias allowed)
			(pads allowed)
			(copperpour not_allowed)
			(footprints allowed)
		)
		(placement
			(enabled no)
			(sheetname "")
		)
		(fill yes
			(thermal_gap 0.5)
			(thermal_bridge_width 0.5)
			(island_removal_mode 0)
		)
		(polygon
			(pts
				(arc
					(start 329.016106 -239.624108)
					(mid 328.386186 -239.624108)
					(end 329.016106 -239.624108)
				)
			)
		)
	)
	(zone
		(layers "B.Cu" "In11.Cu" "In13.Cu" "In15.Cu")
		(hatch none 0.5)
		(connect_pads
			(clearance 0)
		)
		(min_thickness 0.25)
		(keepout
			(tracks not_allowed)
			(vias allowed)
			(pads allowed)
			(copperpour not_allowed)
			(footprints allowed)
		)
		(placement
			(enabled no)
			(sheetname "")
		)
		(fill yes
			(thermal_gap 0.5)
			(thermal_bridge_width 0.5)
			(island_removal_mode 0)
		)
		(polygon
			(pts
				(arc
					(start 182.375556 -53.091334)
					(mid 181.707536 -53.091334)
					(end 182.375556 -53.091334)
				)
			)
		)
	)
	(zone
		(layers "B.Cu" "In11.Cu" "In13.Cu" "In15.Cu")
		(hatch none 0.5)
		(connect_pads
			(clearance 0)
		)
		(min_thickness 0.25)
		(keepout
			(tracks not_allowed)
			(vias allowed)
			(pads allowed)
			(copperpour not_allowed)
			(footprints allowed)
		)
		(placement
			(enabled no)
			(sheetname "")
		)
		(fill yes
			(thermal_gap 0.5)
			(thermal_bridge_width 0.5)
			(island_removal_mode 0)
		)
		(polygon
			(pts
				(arc
					(start 199.03821 -272.135346)
					(mid 198.37019 -272.135346)
					(end 199.03821 -272.135346)
				)
			)
		)
	)
	(zone
		(layers "B.Cu" "In11.Cu" "In13.Cu" "In15.Cu")
		(hatch none 0.5)
		(connect_pads
			(clearance 0)
		)
		(min_thickness 0.25)
		(keepout
			(tracks not_allowed)
			(vias allowed)
			(pads allowed)
			(copperpour not_allowed)
			(footprints allowed)
		)
		(placement
			(enabled no)
			(sheetname "")
		)
		(fill yes
			(thermal_gap 0.5)
			(thermal_bridge_width 0.5)
			(island_removal_mode 0)
		)
		(polygon
			(pts
				(arc
					(start 421.73398 -393.69238)
					(mid 421.10406 -393.69238)
					(end 421.73398 -393.69238)
				)
			)
		)
	)
	(zone
		(layers "B.Cu" "In11.Cu" "In13.Cu" "In15.Cu")
		(hatch none 0.5)
		(connect_pads
			(clearance 0)
		)
		(min_thickness 0.25)
		(keepout
			(tracks not_allowed)
			(vias allowed)
			(pads allowed)
			(copperpour not_allowed)
			(footprints allowed)
		)
		(placement
			(enabled no)
			(sheetname "")
		)
		(fill yes
			(thermal_gap 0.5)
			(thermal_bridge_width 0.5)
			(island_removal_mode 0)
		)
		(polygon
			(pts
				(arc
					(start 151.734012 -386.003292)
					(mid 151.104092 -386.003292)
					(end 151.734012 -386.003292)
				)
			)
		)
	)
	(zone
		(layers "B.Cu" "In11.Cu" "In13.Cu" "In15.Cu")
		(hatch none 0.5)
		(connect_pads
			(clearance 0)
		)
		(min_thickness 0.25)
		(keepout
			(tracks not_allowed)
			(vias allowed)
			(pads allowed)
			(copperpour not_allowed)
			(footprints allowed)
		)
		(placement
			(enabled no)
			(sheetname "")
		)
		(fill yes
			(thermal_gap 0.5)
			(thermal_bridge_width 0.5)
			(island_removal_mode 0)
		)
		(polygon
			(pts
				(arc
					(start 273.426174 -261.93496)
					(mid 272.758154 -261.93496)
					(end 273.426174 -261.93496)
				)
			)
		)
	)
	(zone
		(layers "B.Cu" "In11.Cu" "In13.Cu" "In15.Cu")
		(hatch none 0.5)
		(connect_pads
			(clearance 0)
		)
		(min_thickness 0.25)
		(keepout
			(tracks not_allowed)
			(vias allowed)
			(pads allowed)
			(copperpour not_allowed)
			(footprints allowed)
		)
		(placement
			(enabled no)
			(sheetname "")
		)
		(fill yes
			(thermal_gap 0.5)
			(thermal_bridge_width 0.5)
			(island_removal_mode 0)
		)
		(polygon
			(pts
				(arc
					(start 81.076038 -226.66452)
					(mid 80.446118 -226.66452)
					(end 81.076038 -226.66452)
				)
			)
		)
	)
	(zone
		(layers "B.Cu" "In11.Cu" "In13.Cu" "In15.Cu")
		(hatch none 0.5)
		(connect_pads
			(clearance 0)
		)
		(min_thickness 0.25)
		(keepout
			(tracks not_allowed)
			(vias allowed)
			(pads allowed)
			(copperpour not_allowed)
			(footprints allowed)
		)
		(placement
			(enabled no)
			(sheetname "")
		)
		(fill yes
			(thermal_gap 0.5)
			(thermal_bridge_width 0.5)
			(island_removal_mode 0)
		)
		(polygon
			(pts
				(arc
					(start 141.699742 -240.434368)
					(mid 141.069822 -240.434368)
					(end 141.699742 -240.434368)
				)
			)
		)
	)
	(zone
		(layers "B.Cu" "In11.Cu" "In13.Cu" "In15.Cu")
		(hatch none 0.5)
		(connect_pads
			(clearance 0)
		)
		(min_thickness 0.25)
		(keepout
			(tracks not_allowed)
			(vias allowed)
			(pads allowed)
			(copperpour not_allowed)
			(footprints allowed)
		)
		(placement
			(enabled no)
			(sheetname "")
		)
		(fill yes
			(thermal_gap 0.5)
			(thermal_bridge_width 0.5)
			(island_removal_mode 0)
		)
		(polygon
			(pts
				(arc
					(start 56.90616 -389.467344)
					(mid 56.27624 -389.467344)
					(end 56.90616 -389.467344)
				)
			)
		)
	)
	(zone
		(layers "B.Cu" "In11.Cu" "In13.Cu" "In15.Cu")
		(hatch none 0.5)
		(connect_pads
			(clearance 0)
		)
		(min_thickness 0.25)
		(keepout
			(tracks not_allowed)
			(vias allowed)
			(pads allowed)
			(copperpour not_allowed)
			(footprints allowed)
		)
		(placement
			(enabled no)
			(sheetname "")
		)
		(fill yes
			(thermal_gap 0.5)
			(thermal_bridge_width 0.5)
			(island_removal_mode 0)
		)
		(polygon
			(pts
				(arc
					(start 118.029736 -284.616398)
					(mid 117.399816 -284.616398)
					(end 118.029736 -284.616398)
				)
			)
		)
	)
	(zone
		(layers "B.Cu" "In11.Cu" "In13.Cu" "In15.Cu")
		(hatch none 0.5)
		(connect_pads
			(clearance 0)
		)
		(min_thickness 0.25)
		(keepout
			(tracks not_allowed)
			(vias allowed)
			(pads allowed)
			(copperpour not_allowed)
			(footprints allowed)
		)
		(placement
			(enabled no)
			(sheetname "")
		)
		(fill yes
			(thermal_gap 0.5)
			(thermal_bridge_width 0.5)
			(island_removal_mode 0)
		)
		(polygon
			(pts
				(arc
					(start 199.03821 -250.885198)
					(mid 198.37019 -250.885198)
					(end 199.03821 -250.885198)
				)
			)
		)
	)
	(zone
		(layers "B.Cu" "In11.Cu" "In13.Cu" "In15.Cu")
		(hatch none 0.5)
		(connect_pads
			(clearance 0)
		)
		(min_thickness 0.25)
		(keepout
			(tracks not_allowed)
			(vias allowed)
			(pads allowed)
			(copperpour not_allowed)
			(footprints allowed)
		)
		(placement
			(enabled no)
			(sheetname "")
		)
		(fill yes
			(thermal_gap 0.5)
			(thermal_bridge_width 0.5)
			(island_removal_mode 0)
		)
		(polygon
			(pts
				(arc
					(start 67.03695 -426.089826)
					(mid 66.262758 -426.089826)
					(end 67.03695 -426.089826)
				)
			)
		)
	)
	(zone
		(layers "B.Cu" "In11.Cu" "In13.Cu" "In15.Cu")
		(hatch none 0.5)
		(connect_pads
			(clearance 0)
		)
		(min_thickness 0.25)
		(keepout
			(tracks not_allowed)
			(vias allowed)
			(pads allowed)
			(copperpour not_allowed)
			(footprints allowed)
		)
		(placement
			(enabled no)
			(sheetname "")
		)
		(fill yes
			(thermal_gap 0.5)
			(thermal_bridge_width 0.5)
			(island_removal_mode 0)
		)
		(polygon
			(pts
				(arc
					(start 142.639796 -227.474526)
					(mid 142.009876 -227.474526)
					(end 142.639796 -227.474526)
				)
			)
		)
	)
	(zone
		(layers "B.Cu" "In11.Cu" "In13.Cu" "In15.Cu")
		(hatch none 0.5)
		(connect_pads
			(clearance 0)
		)
		(min_thickness 0.25)
		(keepout
			(tracks not_allowed)
			(vias allowed)
			(pads allowed)
			(copperpour not_allowed)
			(footprints allowed)
		)
		(placement
			(enabled no)
			(sheetname "")
		)
		(fill yes
			(thermal_gap 0.5)
			(thermal_bridge_width 0.5)
			(island_removal_mode 0)
		)
		(polygon
			(pts
				(arc
					(start 81.545938 -255.014476)
					(mid 80.916018 -255.014476)
					(end 81.545938 -255.014476)
				)
			)
		)
	)
	(zone
		(layers "B.Cu" "In11.Cu" "In13.Cu" "In15.Cu")
		(hatch none 0.5)
		(connect_pads
			(clearance 0)
		)
		(min_thickness 0.25)
		(keepout
			(tracks not_allowed)
			(vias allowed)
			(pads allowed)
			(copperpour not_allowed)
			(footprints allowed)
		)
		(placement
			(enabled no)
			(sheetname "")
		)
		(fill yes
			(thermal_gap 0.5)
			(thermal_bridge_width 0.5)
			(island_removal_mode 0)
		)
		(polygon
			(pts
				(arc
					(start 29.586174 -279.785318)
					(mid 28.918154 -279.785318)
					(end 29.586174 -279.785318)
				)
			)
		)
	)
	(zone
		(layers "B.Cu" "In11.Cu" "In13.Cu" "In15.Cu")
		(hatch none 0.5)
		(connect_pads
			(clearance 0)
		)
		(min_thickness 0.25)
		(keepout
			(tracks not_allowed)
			(vias allowed)
			(pads allowed)
			(copperpour not_allowed)
			(footprints allowed)
		)
		(placement
			(enabled no)
			(sheetname "")
		)
		(fill yes
			(thermal_gap 0.5)
			(thermal_bridge_width 0.5)
			(island_removal_mode 0)
		)
		(polygon
			(pts
				(arc
					(start 442.87821 -237.285022)
					(mid 442.21019 -237.285022)
					(end 442.87821 -237.285022)
				)
			)
		)
	)
	(zone
		(layers "B.Cu" "In11.Cu" "In13.Cu" "In15.Cu")
		(hatch none 0.5)
		(connect_pads
			(clearance 0)
		)
		(min_thickness 0.25)
		(keepout
			(tracks not_allowed)
			(vias allowed)
			(pads allowed)
			(copperpour not_allowed)
			(footprints allowed)
		)
		(placement
			(enabled no)
			(sheetname "")
		)
		(fill yes
			(thermal_gap 0.5)
			(thermal_bridge_width 0.5)
			(island_removal_mode 0)
		)
		(polygon
			(pts
				(arc
					(start 29.586174 -262.785352)
					(mid 28.918154 -262.785352)
					(end 29.586174 -262.785352)
				)
			)
		)
	)
	(zone
		(layers "B.Cu" "In11.Cu" "In13.Cu" "In15.Cu")
		(hatch none 0.5)
		(connect_pads
			(clearance 0)
		)
		(min_thickness 0.25)
		(keepout
			(tracks not_allowed)
			(vias allowed)
			(pads allowed)
			(copperpour not_allowed)
			(footprints allowed)
		)
		(placement
			(enabled no)
			(sheetname "")
		)
		(fill yes
			(thermal_gap 0.5)
			(thermal_bridge_width 0.5)
			(island_removal_mode 0)
		)
		(polygon
			(pts
				(arc
					(start 331.195934 -289.475926)
					(mid 330.566014 -289.475926)
					(end 331.195934 -289.475926)
				)
			)
		)
	)
	(zone
		(layers "B.Cu" "In11.Cu" "In13.Cu" "In15.Cu")
		(hatch none 0.5)
		(connect_pads
			(clearance 0)
		)
		(min_thickness 0.25)
		(keepout
			(tracks not_allowed)
			(vias allowed)
			(pads allowed)
			(copperpour not_allowed)
			(footprints allowed)
		)
		(placement
			(enabled no)
			(sheetname "")
		)
		(fill yes
			(thermal_gap 0.5)
			(thermal_bridge_width 0.5)
			(island_removal_mode 0)
		)
		(polygon
			(pts
				(arc
					(start 194.938142 -301.035212)
					(mid 194.270122 -301.035212)
					(end 194.938142 -301.035212)
				)
			)
		)
	)
	(zone
		(layers "B.Cu" "In11.Cu" "In13.Cu" "In15.Cu")
		(hatch none 0.5)
		(connect_pads
			(clearance 0)
		)
		(min_thickness 0.25)
		(keepout
			(tracks not_allowed)
			(vias allowed)
			(pads allowed)
			(copperpour not_allowed)
			(footprints allowed)
		)
		(placement
			(enabled no)
			(sheetname "")
		)
		(fill yes
			(thermal_gap 0.5)
			(thermal_bridge_width 0.5)
			(island_removal_mode 0)
		)
		(polygon
			(pts
				(arc
					(start 408.933904 -394.385292)
					(mid 408.303984 -394.385292)
					(end 408.933904 -394.385292)
				)
			)
		)
	)
	(zone
		(layers "B.Cu" "In11.Cu" "In13.Cu" "In15.Cu")
		(hatch none 0.5)
		(connect_pads
			(clearance 0)
		)
		(min_thickness 0.25)
		(keepout
			(tracks not_allowed)
			(vias allowed)
			(pads allowed)
			(copperpour not_allowed)
			(footprints allowed)
		)
		(placement
			(enabled no)
			(sheetname "")
		)
		(fill yes
			(thermal_gap 0.5)
			(thermal_bridge_width 0.5)
			(island_removal_mode 0)
		)
		(polygon
			(pts
				(arc
					(start 83.255866 -270.03629)
					(mid 82.625946 -270.03629)
					(end 83.255866 -270.03629)
				)
			)
		)
	)
	(zone
		(layers "B.Cu" "In11.Cu" "In13.Cu" "In15.Cu")
		(hatch none 0.5)
		(connect_pads
			(clearance 0)
		)
		(min_thickness 0.25)
		(keepout
			(tracks not_allowed)
			(vias allowed)
			(pads allowed)
			(copperpour not_allowed)
			(footprints allowed)
		)
		(placement
			(enabled no)
			(sheetname "")
		)
		(fill yes
			(thermal_gap 0.5)
			(thermal_bridge_width 0.5)
			(island_removal_mode 0)
		)
		(polygon
			(pts
				(arc
					(start 104.576118 -242.864386)
					(mid 103.946198 -242.864386)
					(end 104.576118 -242.864386)
				)
			)
		)
	)
	(zone
		(layers "B.Cu" "In11.Cu" "In13.Cu" "In15.Cu")
		(hatch none 0.5)
		(connect_pads
			(clearance 0)
		)
		(min_thickness 0.25)
		(keepout
			(tracks not_allowed)
			(vias allowed)
			(pads allowed)
			(copperpour not_allowed)
			(footprints allowed)
		)
		(placement
			(enabled no)
			(sheetname "")
		)
		(fill yes
			(thermal_gap 0.5)
			(thermal_bridge_width 0.5)
			(island_removal_mode 0)
		)
		(polygon
			(pts
				(arc
					(start 382.406144 -397.849344)
					(mid 381.776224 -397.849344)
					(end 382.406144 -397.849344)
				)
			)
		)
	)
	(zone
		(layers "B.Cu" "In11.Cu" "In13.Cu" "In15.Cu")
		(hatch none 0.5)
		(connect_pads
			(clearance 0)
		)
		(min_thickness 0.25)
		(keepout
			(tracks not_allowed)
			(vias allowed)
			(pads allowed)
			(copperpour not_allowed)
			(footprints allowed)
		)
		(placement
			(enabled no)
			(sheetname "")
		)
		(fill yes
			(thermal_gap 0.5)
			(thermal_bridge_width 0.5)
			(island_removal_mode 0)
		)
		(polygon
			(pts
				(arc
					(start 446.978278 -238.13516)
					(mid 446.310258 -238.13516)
					(end 446.978278 -238.13516)
				)
			)
		)
	)
	(zone
		(layers "B.Cu" "In11.Cu" "In13.Cu" "In15.Cu")
		(hatch none 0.5)
		(connect_pads
			(clearance 0)
		)
		(min_thickness 0.25)
		(keepout
			(tracks not_allowed)
			(vias allowed)
			(pads allowed)
			(copperpour not_allowed)
			(footprints allowed)
		)
		(placement
			(enabled no)
			(sheetname "")
		)
		(fill yes
			(thermal_gap 0.5)
			(thermal_bridge_width 0.5)
			(island_removal_mode 0)
		)
		(polygon
			(pts
				(arc
					(start 446.978278 -262.785098)
					(mid 446.310258 -262.785098)
					(end 446.978278 -262.785098)
				)
			)
		)
	)
	(zone
		(layers "B.Cu" "In11.Cu" "In13.Cu" "In15.Cu")
		(hatch none 0.5)
		(connect_pads
			(clearance 0)
		)
		(min_thickness 0.25)
		(keepout
			(tracks not_allowed)
			(vias allowed)
			(pads allowed)
			(copperpour not_allowed)
			(footprints allowed)
		)
		(placement
			(enabled no)
			(sheetname "")
		)
		(fill yes
			(thermal_gap 0.5)
			(thermal_bridge_width 0.5)
			(island_removal_mode 0)
		)
		(polygon
			(pts
				(arc
					(start 277.526242 -238.13516)
					(mid 276.858222 -238.13516)
					(end 277.526242 -238.13516)
				)
			)
		)
	)
	(zone
		(layers "B.Cu" "In11.Cu" "In13.Cu" "In15.Cu")
		(hatch none 0.5)
		(connect_pads
			(clearance 0)
		)
		(min_thickness 0.25)
		(keepout
			(tracks not_allowed)
			(vias allowed)
			(pads allowed)
			(copperpour not_allowed)
			(footprints allowed)
		)
		(placement
			(enabled no)
			(sheetname "")
		)
		(fill yes
			(thermal_gap 0.5)
			(thermal_bridge_width 0.5)
			(island_removal_mode 0)
		)
		(polygon
			(pts
				(arc
					(start 391.349738 -284.616144)
					(mid 390.719818 -284.616144)
					(end 391.349738 -284.616144)
				)
			)
		)
	)
	(zone
		(layers "B.Cu" "In11.Cu" "In13.Cu" "In15.Cu")
		(hatch none 0.5)
		(connect_pads
			(clearance 0)
		)
		(min_thickness 0.25)
		(keepout
			(tracks not_allowed)
			(vias allowed)
			(pads allowed)
			(copperpour not_allowed)
			(footprints allowed)
		)
		(placement
			(enabled no)
			(sheetname "")
		)
		(fill yes
			(thermal_gap 0.5)
			(thermal_bridge_width 0.5)
			(island_removal_mode 0)
		)
		(polygon
			(pts
				(arc
					(start 141.529816 -279.756362)
					(mid 140.899896 -279.756362)
					(end 141.529816 -279.756362)
				)
			)
		)
	)
	(zone
		(layers "B.Cu" "In11.Cu" "In13.Cu" "In15.Cu")
		(hatch none 0.5)
		(connect_pads
			(clearance 0)
		)
		(min_thickness 0.25)
		(keepout
			(tracks not_allowed)
			(vias allowed)
			(pads allowed)
			(copperpour not_allowed)
			(footprints allowed)
		)
		(placement
			(enabled no)
			(sheetname "")
		)
		(fill yes
			(thermal_gap 0.5)
			(thermal_bridge_width 0.5)
			(island_removal_mode 0)
		)
		(polygon
			(pts
				(arc
					(start 82.485992 -238.814356)
					(mid 81.856072 -238.814356)
					(end 82.485992 -238.814356)
				)
			)
		)
	)
	(zone
		(layers "B.Cu" "In11.Cu" "In13.Cu" "In15.Cu")
		(hatch none 0.5)
		(connect_pads
			(clearance 0)
		)
		(min_thickness 0.25)
		(keepout
			(tracks not_allowed)
			(vias allowed)
			(pads allowed)
			(copperpour not_allowed)
			(footprints allowed)
		)
		(placement
			(enabled no)
			(sheetname "")
		)
		(fill yes
			(thermal_gap 0.5)
			(thermal_bridge_width 0.5)
			(island_removal_mode 0)
		)
		(polygon
			(pts
				(arc
					(start 389.16991 -247.724168)
					(mid 388.53999 -247.724168)
					(end 389.16991 -247.724168)
				)
			)
		)
	)
	(zone
		(layers "B.Cu" "In11.Cu" "In13.Cu" "In15.Cu")
		(hatch none 0.5)
		(connect_pads
			(clearance 0)
		)
		(min_thickness 0.25)
		(keepout
			(tracks not_allowed)
			(vias allowed)
			(pads allowed)
			(copperpour not_allowed)
			(footprints allowed)
		)
		(placement
			(enabled no)
			(sheetname "")
		)
		(fill yes
			(thermal_gap 0.5)
			(thermal_bridge_width 0.5)
			(island_removal_mode 0)
		)
		(polygon
			(pts
				(arc
					(start 29.586174 -315.485272)
					(mid 28.918154 -315.485272)
					(end 29.586174 -315.485272)
				)
			)
		)
	)
	(zone
		(layers "B.Cu" "In11.Cu" "In13.Cu" "In15.Cu")
		(hatch none 0.5)
		(connect_pads
			(clearance 0)
		)
		(min_thickness 0.25)
		(keepout
			(tracks not_allowed)
			(vias allowed)
			(pads allowed)
			(copperpour not_allowed)
			(footprints allowed)
		)
		(placement
			(enabled no)
			(sheetname "")
		)
		(fill yes
			(thermal_gap 0.5)
			(thermal_bridge_width 0.5)
			(island_removal_mode 0)
		)
		(polygon
			(pts
				(arc
					(start 199.03821 -201.585322)
					(mid 198.37019 -201.585322)
					(end 199.03821 -201.585322)
				)
			)
		)
	)
	(zone
		(layers "B.Cu" "In11.Cu" "In13.Cu" "In15.Cu")
		(hatch none 0.5)
		(connect_pads
			(clearance 0)
		)
		(min_thickness 0.25)
		(keepout
			(tracks not_allowed)
			(vias allowed)
			(pads allowed)
			(copperpour not_allowed)
			(footprints allowed)
		)
		(placement
			(enabled no)
			(sheetname "")
		)
		(fill yes
			(thermal_gap 0.5)
			(thermal_bridge_width 0.5)
			(island_removal_mode 0)
		)
		(polygon
			(pts
				(arc
					(start 273.426174 -205.834996)
					(mid 272.758154 -205.834996)
					(end 273.426174 -205.834996)
				)
			)
		)
	)
	(zone
		(layers "B.Cu" "In11.Cu" "In13.Cu" "In15.Cu")
		(hatch none 0.5)
		(connect_pads
			(clearance 0)
		)
		(min_thickness 0.25)
		(keepout
			(tracks not_allowed)
			(vias allowed)
			(pads allowed)
			(copperpour not_allowed)
			(footprints allowed)
		)
		(placement
			(enabled no)
			(sheetname "")
		)
		(fill yes
			(thermal_gap 0.5)
			(thermal_bridge_width 0.5)
			(island_removal_mode 0)
		)
		(polygon
			(pts
				(arc
					(start 382.136904 -427.289976)
					(mid 381.362712 -427.289976)
					(end 382.136904 -427.289976)
				)
			)
		)
	)
	(zone
		(layers "B.Cu" "In11.Cu" "In13.Cu" "In15.Cu")
		(hatch none 0.5)
		(connect_pads
			(clearance 0)
		)
		(min_thickness 0.25)
		(keepout
			(tracks not_allowed)
			(vias allowed)
			(pads allowed)
			(copperpour not_allowed)
			(footprints allowed)
		)
		(placement
			(enabled no)
			(sheetname "")
		)
		(fill yes
			(thermal_gap 0.5)
			(thermal_bridge_width 0.5)
			(island_removal_mode 0)
		)
		(polygon
			(pts
				(arc
					(start 29.586174 -231.335326)
					(mid 28.918154 -231.335326)
					(end 29.586174 -231.335326)
				)
			)
		)
	)
	(zone
		(layers "B.Cu" "In11.Cu" "In13.Cu" "In15.Cu")
		(hatch none 0.5)
		(connect_pads
			(clearance 0)
		)
		(min_thickness 0.25)
		(keepout
			(tracks not_allowed)
			(vias allowed)
			(pads allowed)
			(copperpour not_allowed)
			(footprints allowed)
		)
		(placement
			(enabled no)
			(sheetname "")
		)
		(fill yes
			(thermal_gap 0.5)
			(thermal_bridge_width 0.5)
			(island_removal_mode 0)
		)
		(polygon
			(pts
				(arc
					(start 162.134042 -385.31038)
					(mid 161.504122 -385.31038)
					(end 162.134042 -385.31038)
				)
			)
		)
	)
	(zone
		(layers "B.Cu" "In11.Cu" "In13.Cu" "In15.Cu")
		(hatch none 0.5)
		(connect_pads
			(clearance 0)
		)
		(min_thickness 0.25)
		(keepout
			(tracks not_allowed)
			(vias allowed)
			(pads allowed)
			(copperpour not_allowed)
			(footprints allowed)
		)
		(placement
			(enabled no)
			(sheetname "")
		)
		(fill yes
			(thermal_gap 0.5)
			(thermal_bridge_width 0.5)
			(island_removal_mode 0)
		)
		(polygon
			(pts
				(arc
					(start 199.03821 -234.73537)
					(mid 198.37019 -234.73537)
					(end 199.03821 -234.73537)
				)
			)
		)
	)
	(zone
		(layers "B.Cu" "In11.Cu" "In13.Cu" "In15.Cu")
		(hatch none 0.5)
		(connect_pads
			(clearance 0)
		)
		(min_thickness 0.25)
		(keepout
			(tracks not_allowed)
			(vias allowed)
			(pads allowed)
			(copperpour not_allowed)
			(footprints allowed)
		)
		(placement
			(enabled no)
			(sheetname "")
		)
		(fill yes
			(thermal_gap 0.5)
			(thermal_bridge_width 0.5)
			(island_removal_mode 0)
		)
		(polygon
			(pts
				(arc
					(start 81.376012 -282.996386)
					(mid 80.746092 -282.996386)
					(end 81.376012 -282.996386)
				)
			)
		)
	)
	(zone
		(layers "B.Cu" "In11.Cu" "In13.Cu" "In15.Cu")
		(hatch none 0.5)
		(connect_pads
			(clearance 0)
		)
		(min_thickness 0.25)
		(keepout
			(tracks not_allowed)
			(vias allowed)
			(pads allowed)
			(copperpour not_allowed)
			(footprints allowed)
		)
		(placement
			(enabled no)
			(sheetname "")
		)
		(fill yes
			(thermal_gap 0.5)
			(thermal_bridge_width 0.5)
			(island_removal_mode 0)
		)
		(polygon
			(pts
				(arc
					(start 81.845912 -274.08632)
					(mid 81.215992 -274.08632)
					(end 81.845912 -274.08632)
				)
			)
		)
	)
	(zone
		(layers "B.Cu" "In11.Cu" "In13.Cu" "In15.Cu")
		(hatch none 0.5)
		(connect_pads
			(clearance 0)
		)
		(min_thickness 0.25)
		(keepout
			(tracks not_allowed)
			(vias allowed)
			(pads allowed)
			(copperpour not_allowed)
			(footprints allowed)
		)
		(placement
			(enabled no)
			(sheetname "")
		)
		(fill yes
			(thermal_gap 0.5)
			(thermal_bridge_width 0.5)
			(island_removal_mode 0)
		)
		(polygon
			(pts
				(arc
					(start 29.586174 -272.135346)
					(mid 28.918154 -272.135346)
					(end 29.586174 -272.135346)
				)
			)
		)
	)
	(zone
		(layers "B.Cu" "In11.Cu" "In13.Cu" "In15.Cu")
		(hatch none 0.5)
		(connect_pads
			(clearance 0)
		)
		(min_thickness 0.25)
		(keepout
			(tracks not_allowed)
			(vias allowed)
			(pads allowed)
			(copperpour not_allowed)
			(footprints allowed)
		)
		(placement
			(enabled no)
			(sheetname "")
		)
		(fill yes
			(thermal_gap 0.5)
			(thermal_bridge_width 0.5)
			(island_removal_mode 0)
		)
		(polygon
			(pts
				(arc
					(start 81.545938 -243.674392)
					(mid 80.916018 -243.674392)
					(end 81.545938 -243.674392)
				)
			)
		)
	)
	(zone
		(layers "B.Cu" "In11.Cu" "In13.Cu" "In15.Cu")
		(hatch none 0.5)
		(connect_pads
			(clearance 0)
		)
		(min_thickness 0.25)
		(keepout
			(tracks not_allowed)
			(vias allowed)
			(pads allowed)
			(copperpour not_allowed)
			(footprints allowed)
		)
		(placement
			(enabled no)
			(sheetname "")
		)
		(fill yes
			(thermal_gap 0.5)
			(thermal_bridge_width 0.5)
			(island_removal_mode 0)
		)
		(polygon
			(pts
				(arc
					(start 149.137116 -428.28972)
					(mid 148.362924 -428.28972)
					(end 149.137116 -428.28972)
				)
			)
		)
	)
	(zone
		(layers "B.Cu" "In11.Cu" "In13.Cu" "In15.Cu")
		(hatch none 0.5)
		(connect_pads
			(clearance 0)
		)
		(min_thickness 0.25)
		(keepout
			(tracks not_allowed)
			(vias allowed)
			(pads allowed)
			(copperpour not_allowed)
			(footprints allowed)
		)
		(placement
			(enabled no)
			(sheetname "")
		)
		(fill yes
			(thermal_gap 0.5)
			(thermal_bridge_width 0.5)
			(island_removal_mode 0)
		)
		(polygon
			(pts
				(arc
					(start 81.376012 -281.376374)
					(mid 80.746092 -281.376374)
					(end 81.376012 -281.376374)
				)
			)
		)
	)
	(zone
		(layers "B.Cu" "In11.Cu" "In13.Cu" "In15.Cu")
		(hatch none 0.5)
		(connect_pads
			(clearance 0)
		)
		(min_thickness 0.25)
		(keepout
			(tracks not_allowed)
			(vias allowed)
			(pads allowed)
			(copperpour not_allowed)
			(footprints allowed)
		)
		(placement
			(enabled no)
			(sheetname "")
		)
		(fill yes
			(thermal_gap 0.5)
			(thermal_bridge_width 0.5)
			(island_removal_mode 0)
		)
		(polygon
			(pts
				(arc
					(start 199.03821 -294.235378)
					(mid 198.37019 -294.235378)
					(end 199.03821 -294.235378)
				)
			)
		)
	)
	(zone
		(layers "B.Cu" "In11.Cu" "In13.Cu" "In15.Cu")
		(hatch none 0.5)
		(connect_pads
			(clearance 0)
		)
		(min_thickness 0.25)
		(keepout
			(tracks not_allowed)
			(vias allowed)
			(pads allowed)
			(copperpour not_allowed)
			(footprints allowed)
		)
		(placement
			(enabled no)
			(sheetname "")
		)
		(fill yes
			(thermal_gap 0.5)
			(thermal_bridge_width 0.5)
			(island_removal_mode 0)
		)
		(polygon
			(pts
				(arc
					(start 115.679728 -282.18638)
					(mid 115.049808 -282.18638)
					(end 115.679728 -282.18638)
				)
			)
		)
	)
	(zone
		(layers "B.Cu" "In11.Cu" "In13.Cu" "In15.Cu")
		(hatch none 0.5)
		(connect_pads
			(clearance 0)
		)
		(min_thickness 0.25)
		(keepout
			(tracks not_allowed)
			(vias allowed)
			(pads allowed)
			(copperpour not_allowed)
			(footprints allowed)
		)
		(placement
			(enabled no)
			(sheetname "")
		)
		(fill yes
			(thermal_gap 0.5)
			(thermal_bridge_width 0.5)
			(island_removal_mode 0)
		)
		(polygon
			(pts
				(arc
					(start 329.486006 -237.19409)
					(mid 328.856086 -237.19409)
					(end 329.486006 -237.19409)
				)
			)
		)
	)
	(zone
		(layers "B.Cu" "In11.Cu" "In13.Cu" "In15.Cu")
		(hatch none 0.5)
		(connect_pads
			(clearance 0)
		)
		(min_thickness 0.25)
		(keepout
			(tracks not_allowed)
			(vias allowed)
			(pads allowed)
			(copperpour not_allowed)
			(footprints allowed)
		)
		(placement
			(enabled no)
			(sheetname "")
		)
		(fill yes
			(thermal_gap 0.5)
			(thermal_bridge_width 0.5)
			(island_removal_mode 0)
		)
		(polygon
			(pts
				(arc
					(start 384.40614 -397.156432)
					(mid 383.77622 -397.156432)
					(end 384.40614 -397.156432)
				)
			)
		)
	)
	(zone
		(layers "B.Cu" "In11.Cu" "In13.Cu" "In15.Cu")
		(hatch none 0.5)
		(connect_pads
			(clearance 0)
		)
		(min_thickness 0.25)
		(keepout
			(tracks not_allowed)
			(vias allowed)
			(pads allowed)
			(copperpour not_allowed)
			(footprints allowed)
		)
		(placement
			(enabled no)
			(sheetname "")
		)
		(fill yes
			(thermal_gap 0.5)
			(thermal_bridge_width 0.5)
			(island_removal_mode 0)
		)
		(polygon
			(pts
				(arc
					(start 63.770764 -371.49913)
					(mid 63.102744 -371.49913)
					(end 63.770764 -371.49913)
				)
			)
		)
	)
	(zone
		(layers "B.Cu" "In11.Cu" "In13.Cu" "In15.Cu")
		(hatch none 0.5)
		(connect_pads
			(clearance 0)
		)
		(min_thickness 0.25)
		(keepout
			(tracks not_allowed)
			(vias allowed)
			(pads allowed)
			(copperpour not_allowed)
			(footprints allowed)
		)
		(placement
			(enabled no)
			(sheetname "")
		)
		(fill yes
			(thermal_gap 0.5)
			(thermal_bridge_width 0.5)
			(island_removal_mode 0)
		)
		(polygon
			(pts
				(arc
					(start 349.056198 -281.37612)
					(mid 348.426278 -281.37612)
					(end 349.056198 -281.37612)
				)
			)
		)
	)
	(zone
		(layers "B.Cu" "In11.Cu" "In13.Cu" "In15.Cu")
		(hatch none 0.5)
		(connect_pads
			(clearance 0)
		)
		(min_thickness 0.25)
		(keepout
			(tracks not_allowed)
			(vias allowed)
			(pads allowed)
			(copperpour not_allowed)
			(footprints allowed)
		)
		(placement
			(enabled no)
			(sheetname "")
		)
		(fill yes
			(thermal_gap 0.5)
			(thermal_bridge_width 0.5)
			(island_removal_mode 0)
		)
		(polygon
			(pts
				(arc
					(start 182.375556 -50.085498)
					(mid 181.707536 -50.085498)
					(end 182.375556 -50.085498)
				)
			)
		)
	)
	(zone
		(layers "B.Cu" "In11.Cu" "In13.Cu" "In15.Cu")
		(hatch none 0.5)
		(connect_pads
			(clearance 0)
		)
		(min_thickness 0.25)
		(keepout
			(tracks not_allowed)
			(vias allowed)
			(pads allowed)
			(copperpour not_allowed)
			(footprints allowed)
		)
		(placement
			(enabled no)
			(sheetname "")
		)
		(fill yes
			(thermal_gap 0.5)
			(thermal_bridge_width 0.5)
			(island_removal_mode 0)
		)
		(polygon
			(pts
				(arc
					(start 273.426174 -299.33519)
					(mid 272.758154 -299.33519)
					(end 273.426174 -299.33519)
				)
			)
		)
	)
	(zone
		(layers "B.Cu" "In11.Cu" "In13.Cu" "In15.Cu")
		(hatch none 0.5)
		(connect_pads
			(clearance 0)
		)
		(min_thickness 0.25)
		(keepout
			(tracks not_allowed)
			(vias allowed)
			(pads allowed)
			(copperpour not_allowed)
			(footprints allowed)
		)
		(placement
			(enabled no)
			(sheetname "")
		)
		(fill yes
			(thermal_gap 0.5)
			(thermal_bridge_width 0.5)
			(island_removal_mode 0)
		)
		(polygon
			(pts
				(arc
					(start 391.049764 -246.104156)
					(mid 390.419844 -246.104156)
					(end 391.049764 -246.104156)
				)
			)
		)
	)
	(zone
		(layers "B.Cu" "In11.Cu" "In13.Cu" "In15.Cu")
		(hatch none 0.5)
		(connect_pads
			(clearance 0)
		)
		(min_thickness 0.25)
		(keepout
			(tracks not_allowed)
			(vias allowed)
			(pads allowed)
			(copperpour not_allowed)
			(footprints allowed)
		)
		(placement
			(enabled no)
			(sheetname "")
		)
		(fill yes
			(thermal_gap 0.5)
			(thermal_bridge_width 0.5)
			(island_removal_mode 0)
		)
		(polygon
			(pts
				(arc
					(start 81.545938 -240.434368)
					(mid 80.916018 -240.434368)
					(end 81.545938 -240.434368)
				)
			)
		)
	)
	(zone
		(layers "B.Cu" "In11.Cu" "In13.Cu" "In15.Cu")
		(hatch none 0.5)
		(connect_pads
			(clearance 0)
		)
		(min_thickness 0.25)
		(keepout
			(tracks not_allowed)
			(vias allowed)
			(pads allowed)
			(copperpour not_allowed)
			(footprints allowed)
		)
		(placement
			(enabled no)
			(sheetname "")
		)
		(fill yes
			(thermal_gap 0.5)
			(thermal_bridge_width 0.5)
			(island_removal_mode 0)
		)
		(polygon
			(pts
				(arc
					(start 391.049764 -250.964192)
					(mid 390.419844 -250.964192)
					(end 391.049764 -250.964192)
				)
			)
		)
	)
	(zone
		(layers "B.Cu" "In11.Cu" "In13.Cu" "In15.Cu")
		(hatch none 0.5)
		(connect_pads
			(clearance 0)
		)
		(min_thickness 0.25)
		(keepout
			(tracks not_allowed)
			(vias allowed)
			(pads allowed)
			(copperpour not_allowed)
			(footprints allowed)
		)
		(placement
			(enabled no)
			(sheetname "")
		)
		(fill yes
			(thermal_gap 0.5)
			(thermal_bridge_width 0.5)
			(island_removal_mode 0)
		)
		(polygon
			(pts
				(arc
					(start 371.609874 -286.236156)
					(mid 370.979954 -286.236156)
					(end 371.609874 -286.236156)
				)
			)
		)
	)
	(zone
		(layers "B.Cu" "In11.Cu" "In13.Cu" "In15.Cu")
		(hatch none 0.5)
		(connect_pads
			(clearance 0)
		)
		(min_thickness 0.25)
		(keepout
			(tracks not_allowed)
			(vias allowed)
			(pads allowed)
			(copperpour not_allowed)
			(footprints allowed)
		)
		(placement
			(enabled no)
			(sheetname "")
		)
		(fill yes
			(thermal_gap 0.5)
			(thermal_bridge_width 0.5)
			(island_removal_mode 0)
		)
		(polygon
			(pts
				(arc
					(start 442.87821 -263.634982)
					(mid 442.21019 -263.634982)
					(end 442.87821 -263.634982)
				)
			)
		)
	)
	(zone
		(layers "B.Cu" "In11.Cu" "In13.Cu" "In15.Cu")
		(hatch none 0.5)
		(connect_pads
			(clearance 0)
		)
		(min_thickness 0.25)
		(keepout
			(tracks not_allowed)
			(vias allowed)
			(pads allowed)
			(copperpour not_allowed)
			(footprints allowed)
		)
		(placement
			(enabled no)
			(sheetname "")
		)
		(fill yes
			(thermal_gap 0.5)
			(thermal_bridge_width 0.5)
			(island_removal_mode 0)
		)
		(polygon
			(pts
				(arc
					(start 81.376012 -273.276314)
					(mid 80.746092 -273.276314)
					(end 81.376012 -273.276314)
				)
			)
		)
	)
	(zone
		(layers "B.Cu" "In11.Cu" "In13.Cu" "In15.Cu")
		(hatch none 0.5)
		(connect_pads
			(clearance 0)
		)
		(min_thickness 0.25)
		(keepout
			(tracks not_allowed)
			(vias allowed)
			(pads allowed)
			(copperpour not_allowed)
			(footprints allowed)
		)
		(placement
			(enabled no)
			(sheetname "")
		)
		(fill yes
			(thermal_gap 0.5)
			(thermal_bridge_width 0.5)
			(island_removal_mode 0)
		)
		(polygon
			(pts
				(arc
					(start 55.261764 -373.96293)
					(mid 54.593744 -373.96293)
					(end 55.261764 -373.96293)
				)
			)
		)
	)
	(zone
		(layers "B.Cu" "In11.Cu" "In13.Cu" "In15.Cu")
		(hatch none 0.5)
		(connect_pads
			(clearance 0)
		)
		(min_thickness 0.25)
		(keepout
			(tracks not_allowed)
			(vias allowed)
			(pads allowed)
			(copperpour not_allowed)
			(footprints allowed)
		)
		(placement
			(enabled no)
			(sheetname "")
		)
		(fill yes
			(thermal_gap 0.5)
			(thermal_bridge_width 0.5)
			(island_removal_mode 0)
		)
		(polygon
			(pts
				(arc
					(start 389.16991 -238.004096)
					(mid 388.53999 -238.004096)
					(end 389.16991 -238.004096)
				)
			)
		)
	)
	(zone
		(layers "B.Cu" "In11.Cu" "In13.Cu" "In15.Cu")
		(hatch none 0.5)
		(connect_pads
			(clearance 0)
		)
		(min_thickness 0.25)
		(keepout
			(tracks not_allowed)
			(vias allowed)
			(pads allowed)
			(copperpour not_allowed)
			(footprints allowed)
		)
		(placement
			(enabled no)
			(sheetname "")
		)
		(fill yes
			(thermal_gap 0.5)
			(thermal_bridge_width 0.5)
			(island_removal_mode 0)
		)
		(polygon
			(pts
				(arc
					(start 82.785966 -280.566368)
					(mid 82.156046 -280.566368)
					(end 82.785966 -280.566368)
				)
			)
		)
	)
	(zone
		(layers "B.Cu" "In11.Cu" "In13.Cu" "In15.Cu")
		(hatch none 0.5)
		(connect_pads
			(clearance 0)
		)
		(min_thickness 0.25)
		(keepout
			(tracks not_allowed)
			(vias allowed)
			(pads allowed)
			(copperpour not_allowed)
			(footprints allowed)
		)
		(placement
			(enabled no)
			(sheetname "")
		)
		(fill yes
			(thermal_gap 0.5)
			(thermal_bridge_width 0.5)
			(island_removal_mode 0)
		)
		(polygon
			(pts
				(arc
					(start 277.526242 -278.085042)
					(mid 276.858222 -278.085042)
					(end 277.526242 -278.085042)
				)
			)
		)
	)
	(zone
		(layers "B.Cu" "In11.Cu" "In13.Cu" "In15.Cu")
		(hatch none 0.5)
		(connect_pads
			(clearance 0)
		)
		(min_thickness 0.25)
		(keepout
			(tracks not_allowed)
			(vias allowed)
			(pads allowed)
			(copperpour not_allowed)
			(footprints allowed)
		)
		(placement
			(enabled no)
			(sheetname "")
		)
		(fill yes
			(thermal_gap 0.5)
			(thermal_bridge_width 0.5)
			(island_removal_mode 0)
		)
		(polygon
			(pts
				(arc
					(start 106.455972 -238.00435)
					(mid 105.826052 -238.00435)
					(end 106.455972 -238.00435)
				)
			)
		)
	)
	(zone
		(layers "B.Cu" "In11.Cu" "In13.Cu" "In15.Cu")
		(hatch none 0.5)
		(connect_pads
			(clearance 0)
		)
		(min_thickness 0.25)
		(keepout
			(tracks not_allowed)
			(vias allowed)
			(pads allowed)
			(copperpour not_allowed)
			(footprints allowed)
		)
		(placement
			(enabled no)
			(sheetname "")
		)
		(fill yes
			(thermal_gap 0.5)
			(thermal_bridge_width 0.5)
			(island_removal_mode 0)
		)
		(polygon
			(pts
				(arc
					(start 273.426174 -254.284988)
					(mid 272.758154 -254.284988)
					(end 273.426174 -254.284988)
				)
			)
		)
	)
	(zone
		(layers "B.Cu" "In11.Cu" "In13.Cu" "In15.Cu")
		(hatch none 0.5)
		(connect_pads
			(clearance 0)
		)
		(min_thickness 0.25)
		(keepout
			(tracks not_allowed)
			(vias allowed)
			(pads allowed)
			(copperpour not_allowed)
			(footprints allowed)
		)
		(placement
			(enabled no)
			(sheetname "")
		)
		(fill yes
			(thermal_gap 0.5)
			(thermal_bridge_width 0.5)
			(island_removal_mode 0)
		)
		(polygon
			(pts
				(arc
					(start 69.036946 -428.28972)
					(mid 68.262754 -428.28972)
					(end 69.036946 -428.28972)
				)
			)
		)
	)
	(zone
		(layers "B.Cu" "In11.Cu" "In13.Cu" "In15.Cu")
		(hatch none 0.5)
		(connect_pads
			(clearance 0)
		)
		(min_thickness 0.25)
		(keepout
			(tracks not_allowed)
			(vias allowed)
			(pads allowed)
			(copperpour not_allowed)
			(footprints allowed)
		)
		(placement
			(enabled no)
			(sheetname "")
		)
		(fill yes
			(thermal_gap 0.5)
			(thermal_bridge_width 0.5)
			(island_removal_mode 0)
		)
		(polygon
			(pts
				(arc
					(start 143.40967 -289.47618)
					(mid 142.77975 -289.47618)
					(end 143.40967 -289.47618)
				)
			)
		)
	)
	(zone
		(layers "B.Cu" "In11.Cu" "In13.Cu" "In15.Cu")
		(hatch none 0.5)
		(connect_pads
			(clearance 0)
		)
		(min_thickness 0.25)
		(keepout
			(tracks not_allowed)
			(vias allowed)
			(pads allowed)
			(copperpour not_allowed)
			(footprints allowed)
		)
		(placement
			(enabled no)
			(sheetname "")
		)
		(fill yes
			(thermal_gap 0.5)
			(thermal_bridge_width 0.5)
			(island_removal_mode 0)
		)
		(polygon
			(pts
				(arc
					(start 81.076038 -252.584458)
					(mid 80.446118 -252.584458)
					(end 81.076038 -252.584458)
				)
			)
		)
	)
	(zone
		(layers "B.Cu" "In11.Cu" "In13.Cu" "In15.Cu")
		(hatch none 0.5)
		(connect_pads
			(clearance 0)
		)
		(min_thickness 0.25)
		(keepout
			(tracks not_allowed)
			(vias allowed)
			(pads allowed)
			(copperpour not_allowed)
			(footprints allowed)
		)
		(placement
			(enabled no)
			(sheetname "")
		)
		(fill yes
			(thermal_gap 0.5)
			(thermal_bridge_width 0.5)
			(island_removal_mode 0)
		)
		(polygon
			(pts
				(arc
					(start 371.609874 -281.37612)
					(mid 370.979954 -281.37612)
					(end 371.609874 -281.37612)
				)
			)
		)
	)
	(zone
		(layers "B.Cu" "In11.Cu" "In13.Cu" "In15.Cu")
		(hatch none 0.5)
		(connect_pads
			(clearance 0)
		)
		(min_thickness 0.25)
		(keepout
			(tracks not_allowed)
			(vias allowed)
			(pads allowed)
			(copperpour not_allowed)
			(footprints allowed)
		)
		(placement
			(enabled no)
			(sheetname "")
		)
		(fill yes
			(thermal_gap 0.5)
			(thermal_bridge_width 0.5)
			(island_removal_mode 0)
		)
		(polygon
			(pts
				(arc
					(start 51.706272 -388.774432)
					(mid 51.076352 -388.774432)
					(end 51.706272 -388.774432)
				)
			)
		)
	)
	(zone
		(layers "B.Cu" "In11.Cu" "In13.Cu" "In15.Cu")
		(hatch none 0.5)
		(connect_pads
			(clearance 0)
		)
		(min_thickness 0.25)
		(keepout
			(tracks not_allowed)
			(vias allowed)
			(pads allowed)
			(copperpour not_allowed)
			(footprints allowed)
		)
		(placement
			(enabled no)
			(sheetname "")
		)
		(fill yes
			(thermal_gap 0.5)
			(thermal_bridge_width 0.5)
			(island_removal_mode 0)
		)
		(polygon
			(pts
				(arc
					(start 446.978278 -245.785132)
					(mid 446.310258 -245.785132)
					(end 446.978278 -245.785132)
				)
			)
		)
	)
	(zone
		(layers "B.Cu" "In11.Cu" "In13.Cu" "In15.Cu")
		(hatch none 0.5)
		(connect_pads
			(clearance 0)
		)
		(min_thickness 0.25)
		(keepout
			(tracks not_allowed)
			(vias allowed)
			(pads allowed)
			(copperpour not_allowed)
			(footprints allowed)
		)
		(placement
			(enabled no)
			(sheetname "")
		)
		(fill yes
			(thermal_gap 0.5)
			(thermal_bridge_width 0.5)
			(island_removal_mode 0)
		)
		(polygon
			(pts
				(arc
					(start 98.124264 -206.635858)
					(mid 97.456244 -206.635858)
					(end 98.124264 -206.635858)
				)
			)
		)
	)
	(zone
		(layers "B.Cu" "In11.Cu" "In13.Cu" "In15.Cu")
		(hatch none 0.5)
		(connect_pads
			(clearance 0)
		)
		(min_thickness 0.25)
		(keepout
			(tracks not_allowed)
			(vias allowed)
			(pads allowed)
			(copperpour not_allowed)
			(footprints allowed)
		)
		(placement
			(enabled no)
			(sheetname "")
		)
		(fill yes
			(thermal_gap 0.5)
			(thermal_bridge_width 0.5)
			(island_removal_mode 0)
		)
		(polygon
			(pts
				(arc
					(start 199.03821 -212.635338)
					(mid 198.37019 -212.635338)
					(end 199.03821 -212.635338)
				)
			)
		)
	)
	(zone
		(layers "B.Cu" "In11.Cu" "In13.Cu" "In15.Cu")
		(hatch none 0.5)
		(connect_pads
			(clearance 0)
		)
		(min_thickness 0.25)
		(keepout
			(tracks not_allowed)
			(vias allowed)
			(pads allowed)
			(copperpour not_allowed)
			(footprints allowed)
		)
		(placement
			(enabled no)
			(sheetname "")
		)
		(fill yes
			(thermal_gap 0.5)
			(thermal_bridge_width 0.5)
			(island_removal_mode 0)
		)
		(polygon
			(pts
				(arc
					(start 29.586174 -283.185362)
					(mid 28.918154 -283.185362)
					(end 29.586174 -283.185362)
				)
			)
		)
	)
	(zone
		(layers "B.Cu" "In11.Cu" "In13.Cu" "In15.Cu")
		(hatch none 0.5)
		(connect_pads
			(clearance 0)
		)
		(min_thickness 0.25)
		(keepout
			(tracks not_allowed)
			(vias allowed)
			(pads allowed)
			(copperpour not_allowed)
			(footprints allowed)
		)
		(placement
			(enabled no)
			(sheetname "")
		)
		(fill yes
			(thermal_gap 0.5)
			(thermal_bridge_width 0.5)
			(island_removal_mode 0)
		)
		(polygon
			(pts
				(arc
					(start 353.433888 -397.156432)
					(mid 352.803968 -397.156432)
					(end 353.433888 -397.156432)
				)
			)
		)
	)
	(zone
		(layers "B.Cu" "In11.Cu" "In13.Cu" "In15.Cu")
		(hatch none 0.5)
		(connect_pads
			(clearance 0)
		)
		(min_thickness 0.25)
		(keepout
			(tracks not_allowed)
			(vias allowed)
			(pads allowed)
			(copperpour not_allowed)
			(footprints allowed)
		)
		(placement
			(enabled no)
			(sheetname "")
		)
		(fill yes
			(thermal_gap 0.5)
			(thermal_bridge_width 0.5)
			(island_removal_mode 0)
		)
		(polygon
			(pts
				(arc
					(start 63.036958 -423.68978)
					(mid 62.262766 -423.68978)
					(end 63.036958 -423.68978)
				)
			)
		)
	)
	(zone
		(layers "B.Cu" "In11.Cu" "In13.Cu" "In15.Cu")
		(hatch none 0.5)
		(connect_pads
			(clearance 0)
		)
		(min_thickness 0.25)
		(keepout
			(tracks not_allowed)
			(vias allowed)
			(pads allowed)
			(copperpour not_allowed)
			(footprints allowed)
		)
		(placement
			(enabled no)
			(sheetname "")
		)
		(fill yes
			(thermal_gap 0.5)
			(thermal_bridge_width 0.5)
			(island_removal_mode 0)
		)
		(polygon
			(pts
				(arc
					(start 81.376012 -278.13635)
					(mid 80.746092 -278.13635)
					(end 81.376012 -278.13635)
				)
			)
		)
	)
	(zone
		(layers "B.Cu" "In11.Cu" "In13.Cu" "In15.Cu")
		(hatch none 0.5)
		(connect_pads
			(clearance 0)
		)
		(min_thickness 0.25)
		(keepout
			(tracks not_allowed)
			(vias allowed)
			(pads allowed)
			(copperpour not_allowed)
			(footprints allowed)
		)
		(placement
			(enabled no)
			(sheetname "")
		)
		(fill yes
			(thermal_gap 0.5)
			(thermal_bridge_width 0.5)
			(island_removal_mode 0)
		)
		(polygon
			(pts
				(arc
					(start 347.17609 -282.996132)
					(mid 346.54617 -282.996132)
					(end 347.17609 -282.996132)
				)
			)
		)
	)
	(zone
		(layers "B.Cu" "In11.Cu" "In13.Cu" "In15.Cu")
		(hatch none 0.5)
		(connect_pads
			(clearance 0)
		)
		(min_thickness 0.25)
		(keepout
			(tracks not_allowed)
			(vias allowed)
			(pads allowed)
			(copperpour not_allowed)
			(footprints allowed)
		)
		(placement
			(enabled no)
			(sheetname "")
		)
		(fill yes
			(thermal_gap 0.5)
			(thermal_bridge_width 0.5)
			(island_removal_mode 0)
		)
		(polygon
			(pts
				(arc
					(start 44.212764 -371.49913)
					(mid 43.544744 -371.49913)
					(end 44.212764 -371.49913)
				)
			)
		)
	)
	(zone
		(layers "B.Cu" "In11.Cu" "In13.Cu" "In15.Cu")
		(hatch none 0.5)
		(connect_pads
			(clearance 0)
		)
		(min_thickness 0.25)
		(keepout
			(tracks not_allowed)
			(vias allowed)
			(pads allowed)
			(copperpour not_allowed)
			(footprints allowed)
		)
		(placement
			(enabled no)
			(sheetname "")
		)
		(fill yes
			(thermal_gap 0.5)
			(thermal_bridge_width 0.5)
			(island_removal_mode 0)
		)
		(polygon
			(pts
				(arc
					(start 446.978278 -200.735184)
					(mid 446.310258 -200.735184)
					(end 446.978278 -200.735184)
				)
			)
		)
	)
	(zone
		(layers "B.Cu" "In11.Cu" "In13.Cu" "In15.Cu")
		(hatch none 0.5)
		(connect_pads
			(clearance 0)
		)
		(min_thickness 0.25)
		(keepout
			(tracks not_allowed)
			(vias allowed)
			(pads allowed)
			(copperpour not_allowed)
			(footprints allowed)
		)
		(placement
			(enabled no)
			(sheetname "")
		)
		(fill yes
			(thermal_gap 0.5)
			(thermal_bridge_width 0.5)
			(island_removal_mode 0)
		)
		(polygon
			(pts
				(arc
					(start 330.89596 -228.284278)
					(mid 330.26604 -228.284278)
					(end 330.89596 -228.284278)
				)
			)
		)
	)
	(zone
		(layers "B.Cu" "In11.Cu" "In13.Cu" "In15.Cu")
		(hatch none 0.5)
		(connect_pads
			(clearance 0)
		)
		(min_thickness 0.25)
		(keepout
			(tracks not_allowed)
			(vias allowed)
			(pads allowed)
			(copperpour not_allowed)
			(footprints allowed)
		)
		(placement
			(enabled no)
			(sheetname "")
		)
		(fill yes
			(thermal_gap 0.5)
			(thermal_bridge_width 0.5)
			(island_removal_mode 0)
		)
		(polygon
			(pts
				(arc
					(start 143.109696 -247.724422)
					(mid 142.479776 -247.724422)
					(end 143.109696 -247.724422)
				)
			)
		)
	)
	(zone
		(layers "B.Cu" "In11.Cu" "In13.Cu" "In15.Cu")
		(hatch none 0.5)
		(connect_pads
			(clearance 0)
		)
		(min_thickness 0.25)
		(keepout
			(tracks not_allowed)
			(vias allowed)
			(pads allowed)
			(copperpour not_allowed)
			(footprints allowed)
		)
		(placement
			(enabled no)
			(sheetname "")
		)
		(fill yes
			(thermal_gap 0.5)
			(thermal_bridge_width 0.5)
			(island_removal_mode 0)
		)
		(polygon
			(pts
				(arc
					(start 329.03668 -427.089824)
					(mid 328.262488 -427.089824)
					(end 329.03668 -427.089824)
				)
			)
		)
	)
	(zone
		(layers "B.Cu" "In11.Cu" "In13.Cu" "In15.Cu")
		(hatch none 0.5)
		(connect_pads
			(clearance 0)
		)
		(min_thickness 0.25)
		(keepout
			(tracks not_allowed)
			(vias allowed)
			(pads allowed)
			(copperpour not_allowed)
			(footprints allowed)
		)
		(placement
			(enabled no)
			(sheetname "")
		)
		(fill yes
			(thermal_gap 0.5)
			(thermal_bridge_width 0.5)
			(island_removal_mode 0)
		)
		(polygon
			(pts
				(arc
					(start 141.529816 -266.796266)
					(mid 140.899896 -266.796266)
					(end 141.529816 -266.796266)
				)
			)
		)
	)
	(zone
		(layers "B.Cu" "In11.Cu" "In13.Cu" "In15.Cu")
		(hatch none 0.5)
		(connect_pads
			(clearance 0)
		)
		(min_thickness 0.25)
		(keepout
			(tracks not_allowed)
			(vias allowed)
			(pads allowed)
			(copperpour not_allowed)
			(footprints allowed)
		)
		(placement
			(enabled no)
			(sheetname "")
		)
		(fill yes
			(thermal_gap 0.5)
			(thermal_bridge_width 0.5)
			(island_removal_mode 0)
		)
		(polygon
			(pts
				(arc
					(start 277.526242 -210.085178)
					(mid 276.858222 -210.085178)
					(end 277.526242 -210.085178)
				)
			)
		)
	)
	(zone
		(layers "B.Cu" "In11.Cu" "In13.Cu" "In15.Cu")
		(hatch none 0.5)
		(connect_pads
			(clearance 0)
		)
		(min_thickness 0.25)
		(keepout
			(tracks not_allowed)
			(vias allowed)
			(pads allowed)
			(copperpour not_allowed)
			(footprints allowed)
		)
		(placement
			(enabled no)
			(sheetname "")
		)
		(fill yes
			(thermal_gap 0.5)
			(thermal_bridge_width 0.5)
			(island_removal_mode 0)
		)
		(polygon
			(pts
				(arc
					(start 389.16991 -233.14406)
					(mid 388.53999 -233.14406)
					(end 389.16991 -233.14406)
				)
			)
		)
	)
	(zone
		(layers "B.Cu" "In11.Cu" "In13.Cu" "In15.Cu")
		(hatch none 0.5)
		(connect_pads
			(clearance 0)
		)
		(min_thickness 0.25)
		(keepout
			(tracks not_allowed)
			(vias allowed)
			(pads allowed)
			(copperpour not_allowed)
			(footprints allowed)
		)
		(placement
			(enabled no)
			(sheetname "")
		)
		(fill yes
			(thermal_gap 0.5)
			(thermal_bridge_width 0.5)
			(island_removal_mode 0)
		)
		(polygon
			(pts
				(arc
					(start 337.833716 -397.156432)
					(mid 337.203796 -397.156432)
					(end 337.833716 -397.156432)
				)
			)
		)
	)
	(zone
		(layers "B.Cu" "In11.Cu" "In13.Cu" "In15.Cu")
		(hatch none 0.5)
		(connect_pads
			(clearance 0)
		)
		(min_thickness 0.25)
		(keepout
			(tracks not_allowed)
			(vias allowed)
			(pads allowed)
			(copperpour not_allowed)
			(footprints allowed)
		)
		(placement
			(enabled no)
			(sheetname "")
		)
		(fill yes
			(thermal_gap 0.5)
			(thermal_bridge_width 0.5)
			(island_removal_mode 0)
		)
		(polygon
			(pts
				(arc
					(start 25.486106 -202.435206)
					(mid 24.818086 -202.435206)
					(end 25.486106 -202.435206)
				)
			)
		)
	)
	(zone
		(layers "B.Cu" "In11.Cu" "In13.Cu" "In15.Cu")
		(hatch none 0.5)
		(connect_pads
			(clearance 0)
		)
		(min_thickness 0.25)
		(keepout
			(tracks not_allowed)
			(vias allowed)
			(pads allowed)
			(copperpour not_allowed)
			(footprints allowed)
		)
		(placement
			(enabled no)
			(sheetname "")
		)
		(fill yes
			(thermal_gap 0.5)
			(thermal_bridge_width 0.5)
			(island_removal_mode 0)
		)
		(polygon
			(pts
				(arc
					(start 52.721764 -369.03533)
					(mid 52.053744 -369.03533)
					(end 52.721764 -369.03533)
				)
			)
		)
	)
	(zone
		(layers "B.Cu" "In11.Cu" "In13.Cu" "In15.Cu")
		(hatch none 0.5)
		(connect_pads
			(clearance 0)
		)
		(min_thickness 0.25)
		(keepout
			(tracks not_allowed)
			(vias allowed)
			(pads allowed)
			(copperpour not_allowed)
			(footprints allowed)
		)
		(placement
			(enabled no)
			(sheetname "")
		)
		(fill yes
			(thermal_gap 0.5)
			(thermal_bridge_width 0.5)
			(island_removal_mode 0)
		)
		(polygon
			(pts
				(arc
					(start 442.87821 -295.085008)
					(mid 442.21019 -295.085008)
					(end 442.87821 -295.085008)
				)
			)
		)
	)
	(zone
		(layers "B.Cu" "In11.Cu" "In13.Cu" "In15.Cu")
		(hatch none 0.5)
		(connect_pads
			(clearance 0)
		)
		(min_thickness 0.25)
		(keepout
			(tracks not_allowed)
			(vias allowed)
			(pads allowed)
			(copperpour not_allowed)
			(footprints allowed)
		)
		(placement
			(enabled no)
			(sheetname "")
		)
		(fill yes
			(thermal_gap 0.5)
			(thermal_bridge_width 0.5)
			(island_removal_mode 0)
		)
		(polygon
			(pts
				(arc
					(start 362.379768 -242.054126)
					(mid 361.749848 -242.054126)
					(end 362.379768 -242.054126)
				)
			)
		)
	)
	(zone
		(layers "B.Cu" "In11.Cu" "In13.Cu" "In15.Cu")
		(hatch none 0.5)
		(connect_pads
			(clearance 0)
		)
		(min_thickness 0.25)
		(keepout
			(tracks not_allowed)
			(vias allowed)
			(pads allowed)
			(copperpour not_allowed)
			(footprints allowed)
		)
		(placement
			(enabled no)
			(sheetname "")
		)
		(fill yes
			(thermal_gap 0.5)
			(thermal_bridge_width 0.5)
			(island_removal_mode 0)
		)
		(polygon
			(pts
				(arc
					(start 99.236022 -281.376374)
					(mid 98.606102 -281.376374)
					(end 99.236022 -281.376374)
				)
			)
		)
	)
	(zone
		(layers "B.Cu" "In11.Cu" "In13.Cu" "In15.Cu")
		(hatch none 0.5)
		(connect_pads
			(clearance 0)
		)
		(min_thickness 0.25)
		(keepout
			(tracks not_allowed)
			(vias allowed)
			(pads allowed)
			(copperpour not_allowed)
			(footprints allowed)
		)
		(placement
			(enabled no)
			(sheetname "")
		)
		(fill yes
			(thermal_gap 0.5)
			(thermal_bridge_width 0.5)
			(island_removal_mode 0)
		)
		(polygon
			(pts
				(arc
					(start 122.729752 -282.996386)
					(mid 122.099832 -282.996386)
					(end 122.729752 -282.996386)
				)
			)
		)
	)
	(zone
		(layers "B.Cu" "In11.Cu" "In13.Cu" "In15.Cu")
		(hatch none 0.5)
		(connect_pads
			(clearance 0)
		)
		(min_thickness 0.25)
		(keepout
			(tracks not_allowed)
			(vias allowed)
			(pads allowed)
			(copperpour not_allowed)
			(footprints allowed)
		)
		(placement
			(enabled no)
			(sheetname "")
		)
		(fill yes
			(thermal_gap 0.5)
			(thermal_bridge_width 0.5)
			(island_removal_mode 0)
		)
		(polygon
			(pts
				(arc
					(start 29.586174 -219.435426)
					(mid 28.918154 -219.435426)
					(end 29.586174 -219.435426)
				)
			)
		)
	)
	(zone
		(layers "B.Cu" "In11.Cu" "In13.Cu" "In15.Cu")
		(hatch none 0.5)
		(connect_pads
			(clearance 0)
		)
		(min_thickness 0.25)
		(keepout
			(tracks not_allowed)
			(vias allowed)
			(pads allowed)
			(copperpour not_allowed)
			(footprints allowed)
		)
		(placement
			(enabled no)
			(sheetname "")
		)
		(fill yes
			(thermal_gap 0.5)
			(thermal_bridge_width 0.5)
			(island_removal_mode 0)
		)
		(polygon
			(pts
				(arc
					(start 132.136896 -428.28972)
					(mid 131.362704 -428.28972)
					(end 132.136896 -428.28972)
				)
			)
		)
	)
	(zone
		(layers "B.Cu" "In11.Cu" "In13.Cu" "In15.Cu")
		(hatch none 0.5)
		(connect_pads
			(clearance 0)
		)
		(min_thickness 0.25)
		(keepout
			(tracks not_allowed)
			(vias allowed)
			(pads allowed)
			(copperpour not_allowed)
			(footprints allowed)
		)
		(placement
			(enabled no)
			(sheetname "")
		)
		(fill yes
			(thermal_gap 0.5)
			(thermal_bridge_width 0.5)
			(island_removal_mode 0)
		)
		(polygon
			(pts
				(arc
					(start 45.914564 -369.03533)
					(mid 45.246544 -369.03533)
					(end 45.914564 -369.03533)
				)
			)
		)
	)
	(zone
		(layers "B.Cu" "In11.Cu" "In13.Cu" "In15.Cu")
		(hatch none 0.5)
		(connect_pads
			(clearance 0)
		)
		(min_thickness 0.25)
		(keepout
			(tracks not_allowed)
			(vias allowed)
			(pads allowed)
			(copperpour not_allowed)
			(footprints allowed)
		)
		(placement
			(enabled no)
			(sheetname "")
		)
		(fill yes
			(thermal_gap 0.5)
			(thermal_bridge_width 0.5)
			(island_removal_mode 0)
		)
		(polygon
			(pts
				(arc
					(start 365.02975 -284.616144)
					(mid 364.39983 -284.616144)
					(end 365.02975 -284.616144)
				)
			)
		)
	)
	(zone
		(layers "B.Cu" "In11.Cu" "In13.Cu" "In15.Cu")
		(hatch none 0.5)
		(connect_pads
			(clearance 0)
		)
		(min_thickness 0.25)
		(keepout
			(tracks not_allowed)
			(vias allowed)
			(pads allowed)
			(copperpour not_allowed)
			(footprints allowed)
		)
		(placement
			(enabled no)
			(sheetname "")
		)
		(fill yes
			(thermal_gap 0.5)
			(thermal_bridge_width 0.5)
			(island_removal_mode 0)
		)
		(polygon
			(pts
				(arc
					(start 102.042214 -28.65501)
					(mid 101.374194 -28.65501)
					(end 102.042214 -28.65501)
				)
			)
		)
	)
	(zone
		(layers "B.Cu" "In11.Cu" "In13.Cu" "In15.Cu")
		(hatch none 0.5)
		(connect_pads
			(clearance 0)
		)
		(min_thickness 0.25)
		(keepout
			(tracks not_allowed)
			(vias allowed)
			(pads allowed)
			(copperpour not_allowed)
			(footprints allowed)
		)
		(placement
			(enabled no)
			(sheetname "")
		)
		(fill yes
			(thermal_gap 0.5)
			(thermal_bridge_width 0.5)
			(island_removal_mode 0)
		)
		(polygon
			(pts
				(arc
					(start 29.586174 -278.085296)
					(mid 28.918154 -278.085296)
					(end 29.586174 -278.085296)
				)
			)
		)
	)
	(zone
		(layers "B.Cu" "In11.Cu" "In13.Cu" "In15.Cu")
		(hatch none 0.5)
		(connect_pads
			(clearance 0)
		)
		(min_thickness 0.25)
		(keepout
			(tracks not_allowed)
			(vias allowed)
			(pads allowed)
			(copperpour not_allowed)
			(footprints allowed)
		)
		(placement
			(enabled no)
			(sheetname "")
		)
		(fill yes
			(thermal_gap 0.5)
			(thermal_bridge_width 0.5)
			(island_removal_mode 0)
		)
		(polygon
			(pts
				(arc
					(start 277.526242 -228.785166)
					(mid 276.858222 -228.785166)
					(end 277.526242 -228.785166)
				)
			)
		)
	)
	(zone
		(layers "B.Cu" "In11.Cu" "In13.Cu" "In15.Cu")
		(hatch none 0.5)
		(connect_pads
			(clearance 0)
		)
		(min_thickness 0.25)
		(keepout
			(tracks not_allowed)
			(vias allowed)
			(pads allowed)
			(copperpour not_allowed)
			(footprints allowed)
		)
		(placement
			(enabled no)
			(sheetname "")
		)
		(fill yes
			(thermal_gap 0.5)
			(thermal_bridge_width 0.5)
			(island_removal_mode 0)
		)
		(polygon
			(pts
				(arc
					(start 329.486006 -245.29415)
					(mid 328.856086 -245.29415)
					(end 329.486006 -245.29415)
				)
			)
		)
	)
	(zone
		(layers "B.Cu" "In11.Cu" "In13.Cu" "In15.Cu")
		(hatch none 0.5)
		(connect_pads
			(clearance 0)
		)
		(min_thickness 0.25)
		(keepout
			(tracks not_allowed)
			(vias allowed)
			(pads allowed)
			(copperpour not_allowed)
			(footprints allowed)
		)
		(placement
			(enabled no)
			(sheetname "")
		)
		(fill yes
			(thermal_gap 0.5)
			(thermal_bridge_width 0.5)
			(island_removal_mode 0)
		)
		(polygon
			(pts
				(arc
					(start 194.938142 -227.935282)
					(mid 194.270122 -227.935282)
					(end 194.938142 -227.935282)
				)
			)
		)
	)
	(zone
		(layers "B.Cu" "In11.Cu" "In13.Cu" "In15.Cu")
		(hatch none 0.5)
		(connect_pads
			(clearance 0)
		)
		(min_thickness 0.25)
		(keepout
			(tracks not_allowed)
			(vias allowed)
			(pads allowed)
			(copperpour not_allowed)
			(footprints allowed)
		)
		(placement
			(enabled no)
			(sheetname "")
		)
		(fill yes
			(thermal_gap 0.5)
			(thermal_bridge_width 0.5)
			(island_removal_mode 0)
		)
		(polygon
			(pts
				(arc
					(start 368.789712 -284.616144)
					(mid 368.159792 -284.616144)
					(end 368.789712 -284.616144)
				)
			)
		)
	)
	(zone
		(layers "B.Cu" "In11.Cu" "In13.Cu" "In15.Cu")
		(hatch none 0.5)
		(connect_pads
			(clearance 0)
		)
		(min_thickness 0.25)
		(keepout
			(tracks not_allowed)
			(vias allowed)
			(pads allowed)
			(copperpour not_allowed)
			(footprints allowed)
		)
		(placement
			(enabled no)
			(sheetname "")
		)
		(fill yes
			(thermal_gap 0.5)
			(thermal_bridge_width 0.5)
			(island_removal_mode 0)
		)
		(polygon
			(pts
				(arc
					(start 329.016106 -233.14406)
					(mid 328.386186 -233.14406)
					(end 329.016106 -233.14406)
				)
			)
		)
	)
	(zone
		(layers "B.Cu" "In11.Cu" "In13.Cu" "In15.Cu")
		(hatch none 0.5)
		(connect_pads
			(clearance 0)
		)
		(min_thickness 0.25)
		(keepout
			(tracks not_allowed)
			(vias allowed)
			(pads allowed)
			(copperpour not_allowed)
			(footprints allowed)
		)
		(placement
			(enabled no)
			(sheetname "")
		)
		(fill yes
			(thermal_gap 0.5)
			(thermal_bridge_width 0.5)
			(island_removal_mode 0)
		)
		(polygon
			(pts
				(arc
					(start 194.938142 -305.285394)
					(mid 194.270122 -305.285394)
					(end 194.938142 -305.285394)
				)
			)
		)
	)
	(zone
		(layers "B.Cu" "In11.Cu" "In13.Cu" "In15.Cu")
		(hatch none 0.5)
		(connect_pads
			(clearance 0)
		)
		(min_thickness 0.25)
		(keepout
			(tracks not_allowed)
			(vias allowed)
			(pads allowed)
			(copperpour not_allowed)
			(footprints allowed)
		)
		(placement
			(enabled no)
			(sheetname "")
		)
		(fill yes
			(thermal_gap 0.5)
			(thermal_bridge_width 0.5)
			(island_removal_mode 0)
		)
		(polygon
			(pts
				(arc
					(start 141.529816 -271.656302)
					(mid 140.899896 -271.656302)
					(end 141.529816 -271.656302)
				)
			)
		)
	)
	(zone
		(layers "B.Cu" "In11.Cu" "In13.Cu" "In15.Cu")
		(hatch none 0.5)
		(connect_pads
			(clearance 0)
		)
		(min_thickness 0.25)
		(keepout
			(tracks not_allowed)
			(vias allowed)
			(pads allowed)
			(copperpour not_allowed)
			(footprints allowed)
		)
		(placement
			(enabled no)
			(sheetname "")
		)
		(fill yes
			(thermal_gap 0.5)
			(thermal_bridge_width 0.5)
			(island_removal_mode 0)
		)
		(polygon
			(pts
				(arc
					(start 330.42606 -255.014222)
					(mid 329.79614 -255.014222)
					(end 330.42606 -255.014222)
				)
			)
		)
	)
	(zone
		(layers "B.Cu" "In11.Cu" "In13.Cu" "In15.Cu")
		(hatch none 0.5)
		(connect_pads
			(clearance 0)
		)
		(min_thickness 0.25)
		(keepout
			(tracks not_allowed)
			(vias allowed)
			(pads allowed)
			(copperpour not_allowed)
			(footprints allowed)
		)
		(placement
			(enabled no)
			(sheetname "")
		)
		(fill yes
			(thermal_gap 0.5)
			(thermal_bridge_width 0.5)
			(island_removal_mode 0)
		)
		(polygon
			(pts
				(arc
					(start 273.426174 -246.635016)
					(mid 272.758154 -246.635016)
					(end 273.426174 -246.635016)
				)
			)
		)
	)
	(zone
		(layers "B.Cu" "In11.Cu" "In13.Cu" "In15.Cu")
		(hatch none 0.5)
		(connect_pads
			(clearance 0)
		)
		(min_thickness 0.25)
		(keepout
			(tracks not_allowed)
			(vias allowed)
			(pads allowed)
			(copperpour not_allowed)
			(footprints allowed)
		)
		(placement
			(enabled no)
			(sheetname "")
		)
		(fill yes
			(thermal_gap 0.5)
			(thermal_bridge_width 0.5)
			(island_removal_mode 0)
		)
		(polygon
			(pts
				(arc
					(start 101.11613 -282.996386)
					(mid 100.48621 -282.996386)
					(end 101.11613 -282.996386)
				)
			)
		)
	)
	(zone
		(layers "B.Cu" "In11.Cu" "In13.Cu" "In15.Cu")
		(hatch none 0.5)
		(connect_pads
			(clearance 0)
		)
		(min_thickness 0.25)
		(keepout
			(tracks not_allowed)
			(vias allowed)
			(pads allowed)
			(copperpour not_allowed)
			(footprints allowed)
		)
		(placement
			(enabled no)
			(sheetname "")
		)
		(fill yes
			(thermal_gap 0.5)
			(thermal_bridge_width 0.5)
			(island_removal_mode 0)
		)
		(polygon
			(pts
				(arc
					(start 446.978278 -228.785166)
					(mid 446.310258 -228.785166)
					(end 446.978278 -228.785166)
				)
			)
		)
	)
	(zone
		(layers "B.Cu" "In11.Cu" "In13.Cu" "In15.Cu")
		(hatch none 0.5)
		(connect_pads
			(clearance 0)
		)
		(min_thickness 0.25)
		(keepout
			(tracks not_allowed)
			(vias allowed)
			(pads allowed)
			(copperpour not_allowed)
			(footprints allowed)
		)
		(placement
			(enabled no)
			(sheetname "")
		)
		(fill yes
			(thermal_gap 0.5)
			(thermal_bridge_width 0.5)
			(island_removal_mode 0)
		)
		(polygon
			(pts
				(arc
					(start 277.526242 -216.035128)
					(mid 276.858222 -216.035128)
					(end 277.526242 -216.035128)
				)
			)
		)
	)
	(zone
		(layers "B.Cu" "In11.Cu" "In13.Cu" "In15.Cu")
		(hatch none 0.5)
		(connect_pads
			(clearance 0)
		)
		(min_thickness 0.25)
		(keepout
			(tracks not_allowed)
			(vias allowed)
			(pads allowed)
			(copperpour not_allowed)
			(footprints allowed)
		)
		(placement
			(enabled no)
			(sheetname "")
		)
		(fill yes
			(thermal_gap 0.5)
			(thermal_bridge_width 0.5)
			(island_removal_mode 0)
		)
		(polygon
			(pts
				(arc
					(start 141.529816 -265.176254)
					(mid 140.899896 -265.176254)
					(end 141.529816 -265.176254)
				)
			)
		)
	)
	(zone
		(layers "B.Cu" "In11.Cu" "In13.Cu" "In15.Cu")
		(hatch none 0.5)
		(connect_pads
			(clearance 0)
		)
		(min_thickness 0.25)
		(keepout
			(tracks not_allowed)
			(vias allowed)
			(pads allowed)
			(copperpour not_allowed)
			(footprints allowed)
		)
		(placement
			(enabled no)
			(sheetname "")
		)
		(fill yes
			(thermal_gap 0.5)
			(thermal_bridge_width 0.5)
			(island_removal_mode 0)
		)
		(polygon
			(pts
				(arc
					(start 82.955892 -247.724422)
					(mid 82.325972 -247.724422)
					(end 82.955892 -247.724422)
				)
			)
		)
	)
	(zone
		(layers "B.Cu" "In11.Cu" "In13.Cu" "In15.Cu")
		(hatch none 0.5)
		(connect_pads
			(clearance 0)
		)
		(min_thickness 0.25)
		(keepout
			(tracks not_allowed)
			(vias allowed)
			(pads allowed)
			(copperpour not_allowed)
			(footprints allowed)
		)
		(placement
			(enabled no)
			(sheetname "")
		)
		(fill yes
			(thermal_gap 0.5)
			(thermal_bridge_width 0.5)
			(island_removal_mode 0)
		)
		(polygon
			(pts
				(arc
					(start 277.526242 -298.485052)
					(mid 276.858222 -298.485052)
					(end 277.526242 -298.485052)
				)
			)
		)
	)
	(zone
		(layers "B.Cu" "In11.Cu" "In13.Cu" "In15.Cu")
		(hatch none 0.5)
		(connect_pads
			(clearance 0)
		)
		(min_thickness 0.25)
		(keepout
			(tracks not_allowed)
			(vias allowed)
			(pads allowed)
			(copperpour not_allowed)
			(footprints allowed)
		)
		(placement
			(enabled no)
			(sheetname "")
		)
		(fill yes
			(thermal_gap 0.5)
			(thermal_bridge_width 0.5)
			(island_removal_mode 0)
		)
		(polygon
			(pts
				(arc
					(start 49.706276 -389.467344)
					(mid 49.076356 -389.467344)
					(end 49.706276 -389.467344)
				)
			)
		)
	)
	(zone
		(layers "B.Cu" "In11.Cu" "In13.Cu" "In15.Cu")
		(hatch none 0.5)
		(connect_pads
			(clearance 0)
		)
		(min_thickness 0.25)
		(keepout
			(tracks not_allowed)
			(vias allowed)
			(pads allowed)
			(copperpour not_allowed)
			(footprints allowed)
		)
		(placement
			(enabled no)
			(sheetname "")
		)
		(fill yes
			(thermal_gap 0.5)
			(thermal_bridge_width 0.5)
			(island_removal_mode 0)
		)
		(polygon
			(pts
				(arc
					(start 98.936048 -242.864386)
					(mid 98.306128 -242.864386)
					(end 98.936048 -242.864386)
				)
			)
		)
	)
	(zone
		(layers "B.Cu" "In11.Cu" "In13.Cu" "In15.Cu")
		(hatch none 0.5)
		(connect_pads
			(clearance 0)
		)
		(min_thickness 0.25)
		(keepout
			(tracks not_allowed)
			(vias allowed)
			(pads allowed)
			(copperpour not_allowed)
			(footprints allowed)
		)
		(placement
			(enabled no)
			(sheetname "")
		)
		(fill yes
			(thermal_gap 0.5)
			(thermal_bridge_width 0.5)
			(island_removal_mode 0)
		)
		(polygon
			(pts
				(arc
					(start 383.606294 -397.849344)
					(mid 382.976374 -397.849344)
					(end 383.606294 -397.849344)
				)
			)
		)
	)
	(zone
		(layers "B.Cu" "In11.Cu" "In13.Cu" "In15.Cu")
		(hatch none 0.5)
		(connect_pads
			(clearance 0)
		)
		(min_thickness 0.25)
		(keepout
			(tracks not_allowed)
			(vias allowed)
			(pads allowed)
			(copperpour not_allowed)
			(footprints allowed)
		)
		(placement
			(enabled no)
			(sheetname "")
		)
		(fill yes
			(thermal_gap 0.5)
			(thermal_bridge_width 0.5)
			(island_removal_mode 0)
		)
		(polygon
			(pts
				(arc
					(start 143.109696 -246.10441)
					(mid 142.479776 -246.10441)
					(end 143.109696 -246.10441)
				)
			)
		)
	)
	(zone
		(layers "B.Cu" "In11.Cu" "In13.Cu" "In15.Cu")
		(hatch none 0.5)
		(connect_pads
			(clearance 0)
		)
		(min_thickness 0.25)
		(keepout
			(tracks not_allowed)
			(vias allowed)
			(pads allowed)
			(copperpour not_allowed)
			(footprints allowed)
		)
		(placement
			(enabled no)
			(sheetname "")
		)
		(fill yes
			(thermal_gap 0.5)
			(thermal_bridge_width 0.5)
			(island_removal_mode 0)
		)
		(polygon
			(pts
				(arc
					(start 199.03821 -210.935316)
					(mid 198.37019 -210.935316)
					(end 199.03821 -210.935316)
				)
			)
		)
	)
	(zone
		(layers "B.Cu" "In11.Cu" "In13.Cu" "In15.Cu")
		(hatch none 0.5)
		(connect_pads
			(clearance 0)
		)
		(min_thickness 0.25)
		(keepout
			(tracks not_allowed)
			(vias allowed)
			(pads allowed)
			(copperpour not_allowed)
			(footprints allowed)
		)
		(placement
			(enabled no)
			(sheetname "")
		)
		(fill yes
			(thermal_gap 0.5)
			(thermal_bridge_width 0.5)
			(island_removal_mode 0)
		)
		(polygon
			(pts
				(arc
					(start 446.978278 -266.185142)
					(mid 446.310258 -266.185142)
					(end 446.978278 -266.185142)
				)
			)
		)
	)
	(zone
		(layers "B.Cu" "In11.Cu" "In13.Cu" "In15.Cu")
		(hatch none 0.5)
		(connect_pads
			(clearance 0)
		)
		(min_thickness 0.25)
		(keepout
			(tracks not_allowed)
			(vias allowed)
			(pads allowed)
			(copperpour not_allowed)
			(footprints allowed)
		)
		(placement
			(enabled no)
			(sheetname "")
		)
		(fill yes
			(thermal_gap 0.5)
			(thermal_bridge_width 0.5)
			(island_removal_mode 0)
		)
		(polygon
			(pts
				(arc
					(start 446.978278 -290.83508)
					(mid 446.310258 -290.83508)
					(end 446.978278 -290.83508)
				)
			)
		)
	)
	(zone
		(layers "B.Cu" "In11.Cu" "In13.Cu" "In15.Cu")
		(hatch none 0.5)
		(connect_pads
			(clearance 0)
		)
		(min_thickness 0.25)
		(keepout
			(tracks not_allowed)
			(vias allowed)
			(pads allowed)
			(copperpour not_allowed)
			(footprints allowed)
		)
		(placement
			(enabled no)
			(sheetname "")
		)
		(fill yes
			(thermal_gap 0.5)
			(thermal_bridge_width 0.5)
			(island_removal_mode 0)
		)
		(polygon
			(pts
				(arc
					(start 25.486106 -272.98523)
					(mid 24.818086 -272.98523)
					(end 25.486106 -272.98523)
				)
			)
		)
	)
	(zone
		(layers "B.Cu" "In11.Cu" "In13.Cu" "In15.Cu")
		(hatch none 0.5)
		(connect_pads
			(clearance 0)
		)
		(min_thickness 0.25)
		(keepout
			(tracks not_allowed)
			(vias allowed)
			(pads allowed)
			(copperpour not_allowed)
			(footprints allowed)
		)
		(placement
			(enabled no)
			(sheetname "")
		)
		(fill yes
			(thermal_gap 0.5)
			(thermal_bridge_width 0.5)
			(island_removal_mode 0)
		)
		(polygon
			(pts
				(arc
					(start 371.309646 -241.24412)
					(mid 370.679726 -241.24412)
					(end 371.309646 -241.24412)
				)
			)
		)
	)
	(zone
		(layers "B.Cu" "In11.Cu" "In13.Cu" "In15.Cu")
		(hatch none 0.5)
		(connect_pads
			(clearance 0)
		)
		(min_thickness 0.25)
		(keepout
			(tracks not_allowed)
			(vias allowed)
			(pads allowed)
			(copperpour not_allowed)
			(footprints allowed)
		)
		(placement
			(enabled no)
			(sheetname "")
		)
		(fill yes
			(thermal_gap 0.5)
			(thermal_bridge_width 0.5)
			(island_removal_mode 0)
		)
		(polygon
			(pts
				(arc
					(start 25.486106 -204.135228)
					(mid 24.818086 -204.135228)
					(end 25.486106 -204.135228)
				)
			)
		)
	)
	(zone
		(layers "B.Cu" "In11.Cu" "In13.Cu" "In15.Cu")
		(hatch none 0.5)
		(connect_pads
			(clearance 0)
		)
		(min_thickness 0.25)
		(keepout
			(tracks not_allowed)
			(vias allowed)
			(pads allowed)
			(copperpour not_allowed)
			(footprints allowed)
		)
		(placement
			(enabled no)
			(sheetname "")
		)
		(fill yes
			(thermal_gap 0.5)
			(thermal_bridge_width 0.5)
			(island_removal_mode 0)
		)
		(polygon
			(pts
				(arc
					(start 194.938142 -268.735302)
					(mid 194.270122 -268.735302)
					(end 194.938142 -268.735302)
				)
			)
		)
	)
	(zone
		(layers "B.Cu" "In11.Cu" "In13.Cu" "In15.Cu")
		(hatch none 0.5)
		(connect_pads
			(clearance 0)
		)
		(min_thickness 0.25)
		(keepout
			(tracks not_allowed)
			(vias allowed)
			(pads allowed)
			(copperpour not_allowed)
			(footprints allowed)
		)
		(placement
			(enabled no)
			(sheetname "")
		)
		(fill yes
			(thermal_gap 0.5)
			(thermal_bridge_width 0.5)
			(island_removal_mode 0)
		)
		(polygon
			(pts
				(arc
					(start 199.03821 -236.435392)
					(mid 198.37019 -236.435392)
					(end 199.03821 -236.435392)
				)
			)
		)
	)
	(zone
		(layers "B.Cu" "In11.Cu" "In13.Cu" "In15.Cu")
		(hatch none 0.5)
		(connect_pads
			(clearance 0)
		)
		(min_thickness 0.25)
		(keepout
			(tracks not_allowed)
			(vias allowed)
			(pads allowed)
			(copperpour not_allowed)
			(footprints allowed)
		)
		(placement
			(enabled no)
			(sheetname "")
		)
		(fill yes
			(thermal_gap 0.5)
			(thermal_bridge_width 0.5)
			(island_removal_mode 0)
		)
		(polygon
			(pts
				(arc
					(start 316.77737 -0.429006)
					(mid 316.10935 -0.429006)
					(end 316.77737 -0.429006)
				)
			)
		)
	)
	(zone
		(layers "B.Cu" "In11.Cu" "In13.Cu" "In15.Cu")
		(hatch none 0.5)
		(connect_pads
			(clearance 0)
		)
		(min_thickness 0.25)
		(keepout
			(tracks not_allowed)
			(vias allowed)
			(pads allowed)
			(copperpour not_allowed)
			(footprints allowed)
		)
		(placement
			(enabled no)
			(sheetname "")
		)
		(fill yes
			(thermal_gap 0.5)
			(thermal_bridge_width 0.5)
			(island_removal_mode 0)
		)
		(polygon
			(pts
				(arc
					(start 277.526242 -261.085076)
					(mid 276.858222 -261.085076)
					(end 277.526242 -261.085076)
				)
			)
		)
	)
	(zone
		(layers "B.Cu" "In11.Cu" "In13.Cu" "In15.Cu")
		(hatch none 0.5)
		(connect_pads
			(clearance 0)
		)
		(min_thickness 0.25)
		(keepout
			(tracks not_allowed)
			(vias allowed)
			(pads allowed)
			(copperpour not_allowed)
			(footprints allowed)
		)
		(placement
			(enabled no)
			(sheetname "")
		)
		(fill yes
			(thermal_gap 0.5)
			(thermal_bridge_width 0.5)
			(island_removal_mode 0)
		)
		(polygon
			(pts
				(arc
					(start 363.619796 -283.806138)
					(mid 362.989876 -283.806138)
					(end 363.619796 -283.806138)
				)
			)
		)
	)
	(zone
		(layers "B.Cu" "In11.Cu" "In13.Cu" "In15.Cu")
		(hatch none 0.5)
		(connect_pads
			(clearance 0)
		)
		(min_thickness 0.25)
		(keepout
			(tracks not_allowed)
			(vias allowed)
			(pads allowed)
			(copperpour not_allowed)
			(footprints allowed)
		)
		(placement
			(enabled no)
			(sheetname "")
		)
		(fill yes
			(thermal_gap 0.5)
			(thermal_bridge_width 0.5)
			(island_removal_mode 0)
		)
		(polygon
			(pts
				(arc
					(start 442.87821 -248.335038)
					(mid 442.21019 -248.335038)
					(end 442.87821 -248.335038)
				)
			)
		)
	)
	(zone
		(layers "B.Cu" "In11.Cu" "In13.Cu" "In15.Cu")
		(hatch none 0.5)
		(connect_pads
			(clearance 0)
		)
		(min_thickness 0.25)
		(keepout
			(tracks not_allowed)
			(vias allowed)
			(pads allowed)
			(copperpour not_allowed)
			(footprints allowed)
		)
		(placement
			(enabled no)
			(sheetname "")
		)
		(fill yes
			(thermal_gap 0.5)
			(thermal_bridge_width 0.5)
			(island_removal_mode 0)
		)
		(polygon
			(pts
				(arc
					(start 130.80619 -388.774432)
					(mid 130.17627 -388.774432)
					(end 130.80619 -388.774432)
				)
			)
		)
	)
	(zone
		(layers "B.Cu" "In11.Cu" "In13.Cu" "In15.Cu")
		(hatch none 0.5)
		(connect_pads
			(clearance 0)
		)
		(min_thickness 0.25)
		(keepout
			(tracks not_allowed)
			(vias allowed)
			(pads allowed)
			(copperpour not_allowed)
			(footprints allowed)
		)
		(placement
			(enabled no)
			(sheetname "")
		)
		(fill yes
			(thermal_gap 0.5)
			(thermal_bridge_width 0.5)
			(island_removal_mode 0)
		)
		(polygon
			(pts
				(arc
					(start 73.497694 -404.46452)
					(mid 72.829674 -404.46452)
					(end 73.497694 -404.46452)
				)
			)
		)
	)
	(zone
		(layers "B.Cu" "In11.Cu" "In13.Cu" "In15.Cu")
		(hatch none 0.5)
		(connect_pads
			(clearance 0)
		)
		(min_thickness 0.25)
		(keepout
			(tracks not_allowed)
			(vias allowed)
			(pads allowed)
			(copperpour not_allowed)
			(footprints allowed)
		)
		(placement
			(enabled no)
			(sheetname "")
		)
		(fill yes
			(thermal_gap 0.5)
			(thermal_bridge_width 0.5)
			(island_removal_mode 0)
		)
		(polygon
			(pts
				(arc
					(start 141.999716 -272.466308)
					(mid 141.369796 -272.466308)
					(end 141.999716 -272.466308)
				)
			)
		)
	)
	(zone
		(layers "B.Cu" "In11.Cu" "In13.Cu" "In15.Cu")
		(hatch none 0.5)
		(connect_pads
			(clearance 0)
		)
		(min_thickness 0.25)
		(keepout
			(tracks not_allowed)
			(vias allowed)
			(pads allowed)
			(copperpour not_allowed)
			(footprints allowed)
		)
		(placement
			(enabled no)
			(sheetname "")
		)
		(fill yes
			(thermal_gap 0.5)
			(thermal_bridge_width 0.5)
			(island_removal_mode 0)
		)
		(polygon
			(pts
				(arc
					(start 446.978278 -240.685066)
					(mid 446.310258 -240.685066)
					(end 446.978278 -240.685066)
				)
			)
		)
	)
	(zone
		(layers "B.Cu" "In11.Cu" "In13.Cu" "In15.Cu")
		(hatch none 0.5)
		(connect_pads
			(clearance 0)
		)
		(min_thickness 0.25)
		(keepout
			(tracks not_allowed)
			(vias allowed)
			(pads allowed)
			(copperpour not_allowed)
			(footprints allowed)
		)
		(placement
			(enabled no)
			(sheetname "")
		)
		(fill yes
			(thermal_gap 0.5)
			(thermal_bridge_width 0.5)
			(island_removal_mode 0)
		)
		(polygon
			(pts
				(arc
					(start 61.306202 -388.774432)
					(mid 60.676282 -388.774432)
					(end 61.306202 -388.774432)
				)
			)
		)
	)
	(zone
		(layers "B.Cu" "In11.Cu" "In13.Cu" "In15.Cu")
		(hatch none 0.5)
		(connect_pads
			(clearance 0)
		)
		(min_thickness 0.25)
		(keepout
			(tracks not_allowed)
			(vias allowed)
			(pads allowed)
			(copperpour not_allowed)
			(footprints allowed)
		)
		(placement
			(enabled no)
			(sheetname "")
		)
		(fill yes
			(thermal_gap 0.5)
			(thermal_bridge_width 0.5)
			(island_removal_mode 0)
		)
		(polygon
			(pts
				(arc
					(start 194.938142 -302.735234)
					(mid 194.270122 -302.735234)
					(end 194.938142 -302.735234)
				)
			)
		)
	)
	(zone
		(layers "B.Cu" "In11.Cu" "In13.Cu" "In15.Cu")
		(hatch none 0.5)
		(connect_pads
			(clearance 0)
		)
		(min_thickness 0.25)
		(keepout
			(tracks not_allowed)
			(vias allowed)
			(pads allowed)
			(copperpour not_allowed)
			(footprints allowed)
		)
		(placement
			(enabled no)
			(sheetname "")
		)
		(fill yes
			(thermal_gap 0.5)
			(thermal_bridge_width 0.5)
			(island_removal_mode 0)
		)
		(polygon
			(pts
				(arc
					(start 273.426174 -291.684964)
					(mid 272.758154 -291.684964)
					(end 273.426174 -291.684964)
				)
			)
		)
	)
	(zone
		(layers "B.Cu" "In11.Cu" "In13.Cu" "In15.Cu")
		(hatch none 0.5)
		(connect_pads
			(clearance 0)
		)
		(min_thickness 0.25)
		(keepout
			(tracks not_allowed)
			(vias allowed)
			(pads allowed)
			(copperpour not_allowed)
			(footprints allowed)
		)
		(placement
			(enabled no)
			(sheetname "")
		)
		(fill yes
			(thermal_gap 0.5)
			(thermal_bridge_width 0.5)
			(island_removal_mode 0)
		)
		(polygon
			(pts
				(arc
					(start 145.137124 -427.089824)
					(mid 144.362932 -427.089824)
					(end 145.137124 -427.089824)
				)
			)
		)
	)
	(zone
		(layers "B.Cu" "In11.Cu" "In13.Cu" "In15.Cu")
		(hatch none 0.5)
		(connect_pads
			(clearance 0)
		)
		(min_thickness 0.25)
		(keepout
			(tracks not_allowed)
			(vias allowed)
			(pads allowed)
			(copperpour not_allowed)
			(footprints allowed)
		)
		(placement
			(enabled no)
			(sheetname "")
		)
		(fill yes
			(thermal_gap 0.5)
			(thermal_bridge_width 0.5)
			(island_removal_mode 0)
		)
		(polygon
			(pts
				(arc
					(start 446.978278 -250.884944)
					(mid 446.310258 -250.884944)
					(end 446.978278 -250.884944)
				)
			)
		)
	)
	(zone
		(layers "B.Cu" "In11.Cu" "In13.Cu" "In15.Cu")
		(hatch none 0.5)
		(connect_pads
			(clearance 0)
		)
		(min_thickness 0.25)
		(keepout
			(tracks not_allowed)
			(vias allowed)
			(pads allowed)
			(copperpour not_allowed)
			(footprints allowed)
		)
		(placement
			(enabled no)
			(sheetname "")
		)
		(fill yes
			(thermal_gap 0.5)
			(thermal_bridge_width 0.5)
			(island_removal_mode 0)
		)
		(polygon
			(pts
				(arc
					(start 367.549684 -241.24412)
					(mid 366.919764 -241.24412)
					(end 367.549684 -241.24412)
				)
			)
		)
	)
	(zone
		(layers "B.Cu" "In11.Cu" "In13.Cu" "In15.Cu")
		(hatch none 0.5)
		(connect_pads
			(clearance 0)
		)
		(min_thickness 0.25)
		(keepout
			(tracks not_allowed)
			(vias allowed)
			(pads allowed)
			(copperpour not_allowed)
			(footprints allowed)
		)
		(placement
			(enabled no)
			(sheetname "")
		)
		(fill yes
			(thermal_gap 0.5)
			(thermal_bridge_width 0.5)
			(island_removal_mode 0)
		)
		(polygon
			(pts
				(arc
					(start 446.978278 -247.485154)
					(mid 446.310258 -247.485154)
					(end 446.978278 -247.485154)
				)
			)
		)
	)
	(zone
		(layers "B.Cu" "In11.Cu" "In13.Cu" "In15.Cu")
		(hatch none 0.5)
		(connect_pads
			(clearance 0)
		)
		(min_thickness 0.25)
		(keepout
			(tracks not_allowed)
			(vias allowed)
			(pads allowed)
			(copperpour not_allowed)
			(footprints allowed)
		)
		(placement
			(enabled no)
			(sheetname "")
		)
		(fill yes
			(thermal_gap 0.5)
			(thermal_bridge_width 0.5)
			(island_removal_mode 0)
		)
		(polygon
			(pts
				(arc
					(start 273.426174 -314.635134)
					(mid 272.758154 -314.635134)
					(end 273.426174 -314.635134)
				)
			)
		)
	)
	(zone
		(layers "B.Cu" "In11.Cu" "In13.Cu" "In15.Cu")
		(hatch none 0.5)
		(connect_pads
			(clearance 0)
		)
		(min_thickness 0.25)
		(keepout
			(tracks not_allowed)
			(vias allowed)
			(pads allowed)
			(copperpour not_allowed)
			(footprints allowed)
		)
		(placement
			(enabled no)
			(sheetname "")
		)
		(fill yes
			(thermal_gap 0.5)
			(thermal_bridge_width 0.5)
			(island_removal_mode 0)
		)
		(polygon
			(pts
				(arc
					(start 390.879838 -288.66592)
					(mid 390.249918 -288.66592)
					(end 390.879838 -288.66592)
				)
			)
		)
	)
	(zone
		(layers "B.Cu" "In11.Cu" "In13.Cu" "In15.Cu")
		(hatch none 0.5)
		(connect_pads
			(clearance 0)
		)
		(min_thickness 0.25)
		(keepout
			(tracks not_allowed)
			(vias allowed)
			(pads allowed)
			(copperpour not_allowed)
			(footprints allowed)
		)
		(placement
			(enabled no)
			(sheetname "")
		)
		(fill yes
			(thermal_gap 0.5)
			(thermal_bridge_width 0.5)
			(island_removal_mode 0)
		)
		(polygon
			(pts
				(arc
					(start 410.9339 -393.69238)
					(mid 410.30398 -393.69238)
					(end 410.9339 -393.69238)
				)
			)
		)
	)
	(zone
		(layers "B.Cu" "In11.Cu" "In13.Cu" "In15.Cu")
		(hatch none 0.5)
		(connect_pads
			(clearance 0)
		)
		(min_thickness 0.25)
		(keepout
			(tracks not_allowed)
			(vias allowed)
			(pads allowed)
			(copperpour not_allowed)
			(footprints allowed)
		)
		(placement
			(enabled no)
			(sheetname "")
		)
		(fill yes
			(thermal_gap 0.5)
			(thermal_bridge_width 0.5)
			(island_removal_mode 0)
		)
		(polygon
			(pts
				(arc
					(start 318.068706 -382.34493)
					(mid 317.400686 -382.34493)
					(end 318.068706 -382.34493)
				)
			)
		)
	)
	(zone
		(layers "B.Cu" "In11.Cu" "In13.Cu" "In15.Cu")
		(hatch none 0.5)
		(connect_pads
			(clearance 0)
		)
		(min_thickness 0.25)
		(keepout
			(tracks not_allowed)
			(vias allowed)
			(pads allowed)
			(copperpour not_allowed)
			(footprints allowed)
		)
		(placement
			(enabled no)
			(sheetname "")
		)
		(fill yes
			(thermal_gap 0.5)
			(thermal_bridge_width 0.5)
			(island_removal_mode 0)
		)
		(polygon
			(pts
				(arc
					(start 49.318164 -373.96293)
					(mid 48.650144 -373.96293)
					(end 49.318164 -373.96293)
				)
			)
		)
	)
	(zone
		(layers "B.Cu" "In11.Cu" "In13.Cu" "In15.Cu")
		(hatch none 0.5)
		(connect_pads
			(clearance 0)
		)
		(min_thickness 0.25)
		(keepout
			(tracks not_allowed)
			(vias allowed)
			(pads allowed)
			(copperpour not_allowed)
			(footprints allowed)
		)
		(placement
			(enabled no)
			(sheetname "")
		)
		(fill yes
			(thermal_gap 0.5)
			(thermal_bridge_width 0.5)
			(island_removal_mode 0)
		)
		(polygon
			(pts
				(arc
					(start 81.845912 -280.566368)
					(mid 81.215992 -280.566368)
					(end 81.845912 -280.566368)
				)
			)
		)
	)
	(zone
		(layers "B.Cu" "In11.Cu" "In13.Cu" "In15.Cu")
		(hatch none 0.5)
		(connect_pads
			(clearance 0)
		)
		(min_thickness 0.25)
		(keepout
			(tracks not_allowed)
			(vias allowed)
			(pads allowed)
			(copperpour not_allowed)
			(footprints allowed)
		)
		(placement
			(enabled no)
			(sheetname "")
		)
		(fill yes
			(thermal_gap 0.5)
			(thermal_bridge_width 0.5)
			(island_removal_mode 0)
		)
		(polygon
			(pts
				(arc
					(start 82.955892 -249.344434)
					(mid 82.325972 -249.344434)
					(end 82.955892 -249.344434)
				)
			)
		)
	)
	(zone
		(layers "B.Cu" "In11.Cu" "In13.Cu" "In15.Cu")
		(hatch none 0.5)
		(connect_pads
			(clearance 0)
		)
		(min_thickness 0.25)
		(keepout
			(tracks not_allowed)
			(vias allowed)
			(pads allowed)
			(copperpour not_allowed)
			(footprints allowed)
		)
		(placement
			(enabled no)
			(sheetname "")
		)
		(fill yes
			(thermal_gap 0.5)
			(thermal_bridge_width 0.5)
			(island_removal_mode 0)
		)
		(polygon
			(pts
				(arc
					(start 88.037162 -427.289976)
					(mid 87.26297 -427.289976)
					(end 88.037162 -427.289976)
				)
			)
		)
	)
	(zone
		(layers "B.Cu" "In11.Cu" "In13.Cu" "In15.Cu")
		(hatch none 0.5)
		(connect_pads
			(clearance 0)
		)
		(min_thickness 0.25)
		(keepout
			(tracks not_allowed)
			(vias allowed)
			(pads allowed)
			(copperpour not_allowed)
			(footprints allowed)
		)
		(placement
			(enabled no)
			(sheetname "")
		)
		(fill yes
			(thermal_gap 0.5)
			(thermal_bridge_width 0.5)
			(island_removal_mode 0)
		)
		(polygon
			(pts
				(arc
					(start 194.938142 -222.835216)
					(mid 194.270122 -222.835216)
					(end 194.938142 -222.835216)
				)
			)
		)
	)
	(zone
		(layers "B.Cu" "In11.Cu" "In13.Cu" "In15.Cu")
		(hatch none 0.5)
		(connect_pads
			(clearance 0)
		)
		(min_thickness 0.25)
		(keepout
			(tracks not_allowed)
			(vias allowed)
			(pads allowed)
			(copperpour not_allowed)
			(footprints allowed)
		)
		(placement
			(enabled no)
			(sheetname "")
		)
		(fill yes
			(thermal_gap 0.5)
			(thermal_bridge_width 0.5)
			(island_removal_mode 0)
		)
		(polygon
			(pts
				(arc
					(start 404.134066 -394.385292)
					(mid 403.504146 -394.385292)
					(end 404.134066 -394.385292)
				)
			)
		)
	)
	(zone
		(layers "B.Cu" "In11.Cu" "In13.Cu" "In15.Cu")
		(hatch none 0.5)
		(connect_pads
			(clearance 0)
		)
		(min_thickness 0.25)
		(keepout
			(tracks not_allowed)
			(vias allowed)
			(pads allowed)
			(copperpour not_allowed)
			(footprints allowed)
		)
		(placement
			(enabled no)
			(sheetname "")
		)
		(fill yes
			(thermal_gap 0.5)
			(thermal_bridge_width 0.5)
			(island_removal_mode 0)
		)
		(polygon
			(pts
				(arc
					(start 83.255866 -274.896326)
					(mid 82.625946 -274.896326)
					(end 83.255866 -274.896326)
				)
			)
		)
	)
	(zone
		(layers "B.Cu" "In11.Cu" "In13.Cu" "In15.Cu")
		(hatch none 0.5)
		(connect_pads
			(clearance 0)
		)
		(min_thickness 0.25)
		(keepout
			(tracks not_allowed)
			(vias allowed)
			(pads allowed)
			(copperpour not_allowed)
			(footprints allowed)
		)
		(placement
			(enabled no)
			(sheetname "")
		)
		(fill yes
			(thermal_gap 0.5)
			(thermal_bridge_width 0.5)
			(island_removal_mode 0)
		)
		(polygon
			(pts
				(arc
					(start 52.106322 -389.467344)
					(mid 51.476402 -389.467344)
					(end 52.106322 -389.467344)
				)
			)
		)
	)
	(zone
		(layers "B.Cu" "In11.Cu" "In13.Cu" "In15.Cu")
		(hatch none 0.5)
		(connect_pads
			(clearance 0)
		)
		(min_thickness 0.25)
		(keepout
			(tracks not_allowed)
			(vias allowed)
			(pads allowed)
			(copperpour not_allowed)
			(footprints allowed)
		)
		(placement
			(enabled no)
			(sheetname "")
		)
		(fill yes
			(thermal_gap 0.5)
			(thermal_bridge_width 0.5)
			(island_removal_mode 0)
		)
		(polygon
			(pts
				(arc
					(start 389.939784 -288.66592)
					(mid 389.309864 -288.66592)
					(end 389.939784 -288.66592)
				)
			)
		)
	)
	(zone
		(layers "B.Cu" "In11.Cu" "In13.Cu" "In15.Cu")
		(hatch none 0.5)
		(connect_pads
			(clearance 0)
		)
		(min_thickness 0.25)
		(keepout
			(tracks not_allowed)
			(vias allowed)
			(pads allowed)
			(copperpour not_allowed)
			(footprints allowed)
		)
		(placement
			(enabled no)
			(sheetname "")
		)
		(fill yes
			(thermal_gap 0.5)
			(thermal_bridge_width 0.5)
			(island_removal_mode 0)
		)
		(polygon
			(pts
				(arc
					(start 329.78598 -278.946102)
					(mid 329.15606 -278.946102)
					(end 329.78598 -278.946102)
				)
			)
		)
	)
	(zone
		(layers "B.Cu" "In11.Cu" "In13.Cu" "In15.Cu")
		(hatch none 0.5)
		(connect_pads
			(clearance 0)
		)
		(min_thickness 0.25)
		(keepout
			(tracks not_allowed)
			(vias allowed)
			(pads allowed)
			(copperpour not_allowed)
			(footprints allowed)
		)
		(placement
			(enabled no)
			(sheetname "")
		)
		(fill yes
			(thermal_gap 0.5)
			(thermal_bridge_width 0.5)
			(island_removal_mode 0)
		)
		(polygon
			(pts
				(arc
					(start 277.526242 -273.835114)
					(mid 276.858222 -273.835114)
					(end 277.526242 -273.835114)
				)
			)
		)
	)
	(zone
		(layers "B.Cu" "In11.Cu" "In13.Cu" "In15.Cu")
		(hatch none 0.5)
		(connect_pads
			(clearance 0)
		)
		(min_thickness 0.25)
		(keepout
			(tracks not_allowed)
			(vias allowed)
			(pads allowed)
			(copperpour not_allowed)
			(footprints allowed)
		)
		(placement
			(enabled no)
			(sheetname "")
		)
		(fill yes
			(thermal_gap 0.5)
			(thermal_bridge_width 0.5)
			(island_removal_mode 0)
		)
		(polygon
			(pts
				(arc
					(start 29.586174 -249.18543)
					(mid 28.918154 -249.18543)
					(end 29.586174 -249.18543)
				)
			)
		)
	)
	(zone
		(layers "B.Cu" "In11.Cu" "In13.Cu" "In15.Cu")
		(hatch none 0.5)
		(connect_pads
			(clearance 0)
		)
		(min_thickness 0.25)
		(keepout
			(tracks not_allowed)
			(vias allowed)
			(pads allowed)
			(copperpour not_allowed)
			(footprints allowed)
		)
		(placement
			(enabled no)
			(sheetname "")
		)
		(fill yes
			(thermal_gap 0.5)
			(thermal_bridge_width 0.5)
			(island_removal_mode 0)
		)
		(polygon
			(pts
				(arc
					(start 391.349738 -289.475926)
					(mid 390.719818 -289.475926)
					(end 391.349738 -289.475926)
				)
			)
		)
	)
	(zone
		(layers "B.Cu" "In11.Cu" "In13.Cu" "In15.Cu")
		(hatch none 0.5)
		(connect_pads
			(clearance 0)
		)
		(min_thickness 0.25)
		(keepout
			(tracks not_allowed)
			(vias allowed)
			(pads allowed)
			(copperpour not_allowed)
			(footprints allowed)
		)
		(placement
			(enabled no)
			(sheetname "")
		)
		(fill yes
			(thermal_gap 0.5)
			(thermal_bridge_width 0.5)
			(island_removal_mode 0)
		)
		(polygon
			(pts
				(arc
					(start 389.469884 -266.796012)
					(mid 388.839964 -266.796012)
					(end 389.469884 -266.796012)
				)
			)
		)
	)
	(zone
		(layers "B.Cu" "In11.Cu" "In13.Cu" "In15.Cu")
		(hatch none 0.5)
		(connect_pads
			(clearance 0)
		)
		(min_thickness 0.25)
		(keepout
			(tracks not_allowed)
			(vias allowed)
			(pads allowed)
			(copperpour not_allowed)
			(footprints allowed)
		)
		(placement
			(enabled no)
			(sheetname "")
		)
		(fill yes
			(thermal_gap 0.5)
			(thermal_bridge_width 0.5)
			(island_removal_mode 0)
		)
		(polygon
			(pts
				(arc
					(start 164.534088 -385.31038)
					(mid 163.904168 -385.31038)
					(end 164.534088 -385.31038)
				)
			)
		)
	)
	(zone
		(layers "B.Cu" "In11.Cu" "In13.Cu" "In15.Cu")
		(hatch none 0.5)
		(connect_pads
			(clearance 0)
		)
		(min_thickness 0.25)
		(keepout
			(tracks not_allowed)
			(vias allowed)
			(pads allowed)
			(copperpour not_allowed)
			(footprints allowed)
		)
		(placement
			(enabled no)
			(sheetname "")
		)
		(fill yes
			(thermal_gap 0.5)
			(thermal_bridge_width 0.5)
			(island_removal_mode 0)
		)
		(polygon
			(pts
				(arc
					(start 390.579864 -227.474272)
					(mid 389.949944 -227.474272)
					(end 390.579864 -227.474272)
				)
			)
		)
	)
	(zone
		(layers "B.Cu" "In11.Cu" "In13.Cu" "In15.Cu")
		(hatch none 0.5)
		(connect_pads
			(clearance 0)
		)
		(min_thickness 0.25)
		(keepout
			(tracks not_allowed)
			(vias allowed)
			(pads allowed)
			(copperpour not_allowed)
			(footprints allowed)
		)
		(placement
			(enabled no)
			(sheetname "")
		)
		(fill yes
			(thermal_gap 0.5)
			(thermal_bridge_width 0.5)
			(island_removal_mode 0)
		)
		(polygon
			(pts
				(arc
					(start 108.80598 -242.05438)
					(mid 108.17606 -242.05438)
					(end 108.80598 -242.05438)
				)
			)
		)
	)
	(zone
		(layers "B.Cu" "In11.Cu" "In13.Cu" "In15.Cu")
		(hatch none 0.5)
		(connect_pads
			(clearance 0)
		)
		(min_thickness 0.25)
		(keepout
			(tracks not_allowed)
			(vias allowed)
			(pads allowed)
			(copperpour not_allowed)
			(footprints allowed)
		)
		(placement
			(enabled no)
			(sheetname "")
		)
		(fill yes
			(thermal_gap 0.5)
			(thermal_bridge_width 0.5)
			(island_removal_mode 0)
		)
		(polygon
			(pts
				(arc
					(start 329.78598 -285.42615)
					(mid 329.15606 -285.42615)
					(end 329.78598 -285.42615)
				)
			)
		)
	)
	(zone
		(layers "B.Cu" "In11.Cu" "In13.Cu" "In15.Cu")
		(hatch none 0.5)
		(connect_pads
			(clearance 0)
		)
		(min_thickness 0.25)
		(keepout
			(tracks not_allowed)
			(vias allowed)
			(pads allowed)
			(copperpour not_allowed)
			(footprints allowed)
		)
		(placement
			(enabled no)
			(sheetname "")
		)
		(fill yes
			(thermal_gap 0.5)
			(thermal_bridge_width 0.5)
			(island_removal_mode 0)
		)
		(polygon
			(pts
				(arc
					(start 115.679728 -283.806392)
					(mid 115.049808 -283.806392)
					(end 115.679728 -283.806392)
				)
			)
		)
	)
	(zone
		(layers "B.Cu" "In11.Cu" "In13.Cu" "In15.Cu")
		(hatch none 0.5)
		(connect_pads
			(clearance 0)
		)
		(min_thickness 0.25)
		(keepout
			(tracks not_allowed)
			(vias allowed)
			(pads allowed)
			(copperpour not_allowed)
			(footprints allowed)
		)
		(placement
			(enabled no)
			(sheetname "")
		)
		(fill yes
			(thermal_gap 0.5)
			(thermal_bridge_width 0.5)
			(island_removal_mode 0)
		)
		(polygon
			(pts
				(arc
					(start 65.036954 -428.28972)
					(mid 64.262762 -428.28972)
					(end 65.036954 -428.28972)
				)
			)
		)
	)
	(zone
		(layers "B.Cu" "In11.Cu" "In13.Cu" "In15.Cu")
		(hatch none 0.5)
		(connect_pads
			(clearance 0)
		)
		(min_thickness 0.25)
		(keepout
			(tracks not_allowed)
			(vias allowed)
			(pads allowed)
			(copperpour not_allowed)
			(footprints allowed)
		)
		(placement
			(enabled no)
			(sheetname "")
		)
		(fill yes
			(thermal_gap 0.5)
			(thermal_bridge_width 0.5)
			(island_removal_mode 0)
		)
		(polygon
			(pts
				(arc
					(start 76.037186 -427.289976)
					(mid 75.262994 -427.289976)
					(end 76.037186 -427.289976)
				)
			)
		)
	)
	(zone
		(layers "B.Cu" "In11.Cu" "In13.Cu" "In15.Cu")
		(hatch none 0.5)
		(connect_pads
			(clearance 0)
		)
		(min_thickness 0.25)
		(keepout
			(tracks not_allowed)
			(vias allowed)
			(pads allowed)
			(copperpour not_allowed)
			(footprints allowed)
		)
		(placement
			(enabled no)
			(sheetname "")
		)
		(fill yes
			(thermal_gap 0.5)
			(thermal_bridge_width 0.5)
			(island_removal_mode 0)
		)
		(polygon
			(pts
				(arc
					(start 331.195934 -279.756108)
					(mid 330.566014 -279.756108)
					(end 331.195934 -279.756108)
				)
			)
		)
	)
	(zone
		(layers "B.Cu" "In11.Cu" "In13.Cu" "In15.Cu")
		(hatch none 0.5)
		(connect_pads
			(clearance 0)
		)
		(min_thickness 0.25)
		(keepout
			(tracks not_allowed)
			(vias allowed)
			(pads allowed)
			(copperpour not_allowed)
			(footprints allowed)
		)
		(placement
			(enabled no)
			(sheetname "")
		)
		(fill yes
			(thermal_gap 0.5)
			(thermal_bridge_width 0.5)
			(island_removal_mode 0)
		)
		(polygon
			(pts
				(arc
					(start 103.636064 -242.864386)
					(mid 103.006144 -242.864386)
					(end 103.636064 -242.864386)
				)
			)
		)
	)
	(zone
		(layers "B.Cu" "In11.Cu" "In13.Cu" "In15.Cu")
		(hatch none 0.5)
		(connect_pads
			(clearance 0)
		)
		(min_thickness 0.25)
		(keepout
			(tracks not_allowed)
			(vias allowed)
			(pads allowed)
			(copperpour not_allowed)
			(footprints allowed)
		)
		(placement
			(enabled no)
			(sheetname "")
		)
		(fill yes
			(thermal_gap 0.5)
			(thermal_bridge_width 0.5)
			(island_removal_mode 0)
		)
		(polygon
			(pts
				(arc
					(start 140.13688 -428.28972)
					(mid 139.362688 -428.28972)
					(end 140.13688 -428.28972)
				)
			)
		)
	)
	(zone
		(layers "B.Cu" "In11.Cu" "In13.Cu" "In15.Cu")
		(hatch none 0.5)
		(connect_pads
			(clearance 0)
		)
		(min_thickness 0.25)
		(keepout
			(tracks not_allowed)
			(vias allowed)
			(pads allowed)
			(copperpour not_allowed)
			(footprints allowed)
		)
		(placement
			(enabled no)
			(sheetname "")
		)
		(fill yes
			(thermal_gap 0.5)
			(thermal_bridge_width 0.5)
			(island_removal_mode 0)
		)
		(polygon
			(pts
				(arc
					(start 403.734016 -393.69238)
					(mid 403.104096 -393.69238)
					(end 403.734016 -393.69238)
				)
			)
		)
	)
	(zone
		(layers "B.Cu" "In11.Cu" "In13.Cu" "In15.Cu")
		(hatch none 0.5)
		(connect_pads
			(clearance 0)
		)
		(min_thickness 0.25)
		(keepout
			(tracks not_allowed)
			(vias allowed)
			(pads allowed)
			(copperpour not_allowed)
			(footprints allowed)
		)
		(placement
			(enabled no)
			(sheetname "")
		)
		(fill yes
			(thermal_gap 0.5)
			(thermal_bridge_width 0.5)
			(island_removal_mode 0)
		)
		(polygon
			(pts
				(arc
					(start 315.036708 -427.289976)
					(mid 314.262516 -427.289976)
					(end 315.036708 -427.289976)
				)
			)
		)
	)
	(zone
		(layers "B.Cu" "In11.Cu" "In13.Cu" "In15.Cu")
		(hatch none 0.5)
		(connect_pads
			(clearance 0)
		)
		(min_thickness 0.25)
		(keepout
			(tracks not_allowed)
			(vias allowed)
			(pads allowed)
			(copperpour not_allowed)
			(footprints allowed)
		)
		(placement
			(enabled no)
			(sheetname "")
		)
		(fill yes
			(thermal_gap 0.5)
			(thermal_bridge_width 0.5)
			(island_removal_mode 0)
		)
		(polygon
			(pts
				(arc
					(start 48.991774 -404.46452)
					(mid 48.323754 -404.46452)
					(end 48.991774 -404.46452)
				)
			)
		)
	)
	(zone
		(layers "B.Cu" "In11.Cu" "In13.Cu" "In15.Cu")
		(hatch none 0.5)
		(connect_pads
			(clearance 0)
		)
		(min_thickness 0.25)
		(keepout
			(tracks not_allowed)
			(vias allowed)
			(pads allowed)
			(copperpour not_allowed)
			(footprints allowed)
		)
		(placement
			(enabled no)
			(sheetname "")
		)
		(fill yes
			(thermal_gap 0.5)
			(thermal_bridge_width 0.5)
			(island_removal_mode 0)
		)
		(polygon
			(pts
				(arc
					(start 29.586174 -296.785284)
					(mid 28.918154 -296.785284)
					(end 29.586174 -296.785284)
				)
			)
		)
	)
	(zone
		(layers "B.Cu" "In11.Cu" "In13.Cu" "In15.Cu")
		(hatch none 0.5)
		(connect_pads
			(clearance 0)
		)
		(min_thickness 0.25)
		(keepout
			(tracks not_allowed)
			(vias allowed)
			(pads allowed)
			(copperpour not_allowed)
			(footprints allowed)
		)
		(placement
			(enabled no)
			(sheetname "")
		)
		(fill yes
			(thermal_gap 0.5)
			(thermal_bridge_width 0.5)
			(island_removal_mode 0)
		)
		(polygon
			(pts
				(arc
					(start 81.076038 -247.724422)
					(mid 80.446118 -247.724422)
					(end 81.076038 -247.724422)
				)
			)
		)
	)
	(zone
		(layers "B.Cu" "In11.Cu" "In13.Cu" "In15.Cu")
		(hatch none 0.5)
		(connect_pads
			(clearance 0)
		)
		(min_thickness 0.25)
		(keepout
			(tracks not_allowed)
			(vias allowed)
			(pads allowed)
			(copperpour not_allowed)
			(footprints allowed)
		)
		(placement
			(enabled no)
			(sheetname "")
		)
		(fill yes
			(thermal_gap 0.5)
			(thermal_bridge_width 0.5)
			(island_removal_mode 0)
		)
		(polygon
			(pts
				(arc
					(start 103.936038 -284.616398)
					(mid 103.306118 -284.616398)
					(end 103.936038 -284.616398)
				)
			)
		)
	)
	(zone
		(layers "B.Cu" "In11.Cu" "In13.Cu" "In15.Cu")
		(hatch none 0.5)
		(connect_pads
			(clearance 0)
		)
		(min_thickness 0.25)
		(keepout
			(tracks not_allowed)
			(vias allowed)
			(pads allowed)
			(copperpour not_allowed)
			(footprints allowed)
		)
		(placement
			(enabled no)
			(sheetname "")
		)
		(fill yes
			(thermal_gap 0.5)
			(thermal_bridge_width 0.5)
			(island_removal_mode 0)
		)
		(polygon
			(pts
				(arc
					(start 330.89596 -255.824228)
					(mid 330.26604 -255.824228)
					(end 330.89596 -255.824228)
				)
			)
		)
	)
	(zone
		(layers "B.Cu" "In11.Cu" "In13.Cu" "In15.Cu")
		(hatch none 0.5)
		(connect_pads
			(clearance 0)
		)
		(min_thickness 0.25)
		(keepout
			(tracks not_allowed)
			(vias allowed)
			(pads allowed)
			(copperpour not_allowed)
			(footprints allowed)
		)
		(placement
			(enabled no)
			(sheetname "")
		)
		(fill yes
			(thermal_gap 0.5)
			(thermal_bridge_width 0.5)
			(island_removal_mode 0)
		)
		(polygon
			(pts
				(arc
					(start 329.31608 -274.896072)
					(mid 328.68616 -274.896072)
					(end 329.31608 -274.896072)
				)
			)
		)
	)
	(zone
		(layers "B.Cu" "In11.Cu" "In13.Cu" "In15.Cu")
		(hatch none 0.5)
		(connect_pads
			(clearance 0)
		)
		(min_thickness 0.25)
		(keepout
			(tracks not_allowed)
			(vias allowed)
			(pads allowed)
			(copperpour not_allowed)
			(footprints allowed)
		)
		(placement
			(enabled no)
			(sheetname "")
		)
		(fill yes
			(thermal_gap 0.5)
			(thermal_bridge_width 0.5)
			(island_removal_mode 0)
		)
		(polygon
			(pts
				(arc
					(start 329.016106 -229.904036)
					(mid 328.386186 -229.904036)
					(end 329.016106 -229.904036)
				)
			)
		)
	)
	(zone
		(layers "B.Cu" "In11.Cu" "In13.Cu" "In15.Cu")
		(hatch none 0.5)
		(connect_pads
			(clearance 0)
		)
		(min_thickness 0.25)
		(keepout
			(tracks not_allowed)
			(vias allowed)
			(pads allowed)
			(copperpour not_allowed)
			(footprints allowed)
		)
		(placement
			(enabled no)
			(sheetname "")
		)
		(fill yes
			(thermal_gap 0.5)
			(thermal_bridge_width 0.5)
			(island_removal_mode 0)
		)
		(polygon
			(pts
				(arc
					(start 446.978278 -252.584966)
					(mid 446.310258 -252.584966)
					(end 446.978278 -252.584966)
				)
			)
		)
	)
	(zone
		(layers "B.Cu" "In11.Cu" "In13.Cu" "In15.Cu")
		(hatch none 0.5)
		(connect_pads
			(clearance 0)
		)
		(min_thickness 0.25)
		(keepout
			(tracks not_allowed)
			(vias allowed)
			(pads allowed)
			(copperpour not_allowed)
			(footprints allowed)
		)
		(placement
			(enabled no)
			(sheetname "")
		)
		(fill yes
			(thermal_gap 0.5)
			(thermal_bridge_width 0.5)
			(island_removal_mode 0)
		)
		(polygon
			(pts
				(arc
					(start 273.426174 -237.285022)
					(mid 272.758154 -237.285022)
					(end 273.426174 -237.285022)
				)
			)
		)
	)
	(zone
		(layers "B.Cu" "In11.Cu" "In13.Cu" "In15.Cu")
		(hatch none 0.5)
		(connect_pads
			(clearance 0)
		)
		(min_thickness 0.25)
		(keepout
			(tracks not_allowed)
			(vias allowed)
			(pads allowed)
			(copperpour not_allowed)
			(footprints allowed)
		)
		(placement
			(enabled no)
			(sheetname "")
		)
		(fill yes
			(thermal_gap 0.5)
			(thermal_bridge_width 0.5)
			(island_removal_mode 0)
		)
		(polygon
			(pts
				(arc
					(start 141.999716 -293.52621)
					(mid 141.369796 -293.52621)
					(end 141.999716 -293.52621)
				)
			)
		)
	)
	(zone
		(layers "B.Cu" "In11.Cu" "In13.Cu" "In15.Cu")
		(hatch none 0.5)
		(connect_pads
			(clearance 0)
		)
		(min_thickness 0.25)
		(keepout
			(tracks not_allowed)
			(vias allowed)
			(pads allowed)
			(copperpour not_allowed)
			(footprints allowed)
		)
		(placement
			(enabled no)
			(sheetname "")
		)
		(fill yes
			(thermal_gap 0.5)
			(thermal_bridge_width 0.5)
			(island_removal_mode 0)
		)
		(polygon
			(pts
				(arc
					(start 141.229842 -255.824482)
					(mid 140.599922 -255.824482)
					(end 141.229842 -255.824482)
				)
			)
		)
	)
	(zone
		(layers "B.Cu" "In11.Cu" "In13.Cu" "In15.Cu")
		(hatch none 0.5)
		(connect_pads
			(clearance 0)
		)
		(min_thickness 0.25)
		(keepout
			(tracks not_allowed)
			(vias allowed)
			(pads allowed)
			(copperpour not_allowed)
			(footprints allowed)
		)
		(placement
			(enabled no)
			(sheetname "")
		)
		(fill yes
			(thermal_gap 0.5)
			(thermal_bridge_width 0.5)
			(island_removal_mode 0)
		)
		(polygon
			(pts
				(arc
					(start 419.333934 -393.69238)
					(mid 418.704014 -393.69238)
					(end 419.333934 -393.69238)
				)
			)
		)
	)
	(zone
		(layers "B.Cu" "In11.Cu" "In13.Cu" "In15.Cu")
		(hatch none 0.5)
		(connect_pads
			(clearance 0)
		)
		(min_thickness 0.25)
		(keepout
			(tracks not_allowed)
			(vias allowed)
			(pads allowed)
			(copperpour not_allowed)
			(footprints allowed)
		)
		(placement
			(enabled no)
			(sheetname "")
		)
		(fill yes
			(thermal_gap 0.5)
			(thermal_bridge_width 0.5)
			(island_removal_mode 0)
		)
		(polygon
			(pts
				(arc
					(start 446.978278 -278.085042)
					(mid 446.310258 -278.085042)
					(end 446.978278 -278.085042)
				)
			)
		)
	)
	(zone
		(layers "B.Cu" "In11.Cu" "In13.Cu" "In15.Cu")
		(hatch none 0.5)
		(connect_pads
			(clearance 0)
		)
		(min_thickness 0.25)
		(keepout
			(tracks not_allowed)
			(vias allowed)
			(pads allowed)
			(copperpour not_allowed)
			(footprints allowed)
		)
		(placement
			(enabled no)
			(sheetname "")
		)
		(fill yes
			(thermal_gap 0.5)
			(thermal_bridge_width 0.5)
			(island_removal_mode 0)
		)
		(polygon
			(pts
				(arc
					(start 446.978278 -281.485086)
					(mid 446.310258 -281.485086)
					(end 446.978278 -281.485086)
				)
			)
		)
	)
	(zone
		(layers "B.Cu" "In11.Cu" "In13.Cu" "In15.Cu")
		(hatch none 0.5)
		(connect_pads
			(clearance 0)
		)
		(min_thickness 0.25)
		(keepout
			(tracks not_allowed)
			(vias allowed)
			(pads allowed)
			(copperpour not_allowed)
			(footprints allowed)
		)
		(placement
			(enabled no)
			(sheetname "")
		)
		(fill yes
			(thermal_gap 0.5)
			(thermal_bridge_width 0.5)
			(island_removal_mode 0)
		)
		(polygon
			(pts
				(arc
					(start 25.486106 -221.135194)
					(mid 24.818086 -221.135194)
					(end 25.486106 -221.135194)
				)
			)
		)
	)
	(zone
		(layers "B.Cu" "In11.Cu" "In13.Cu" "In15.Cu")
		(hatch none 0.5)
		(connect_pads
			(clearance 0)
		)
		(min_thickness 0.25)
		(keepout
			(tracks not_allowed)
			(vias allowed)
			(pads allowed)
			(copperpour not_allowed)
			(footprints allowed)
		)
		(placement
			(enabled no)
			(sheetname "")
		)
		(fill yes
			(thermal_gap 0.5)
			(thermal_bridge_width 0.5)
			(island_removal_mode 0)
		)
		(polygon
			(pts
				(arc
					(start 442.87821 -306.985162)
					(mid 442.21019 -306.985162)
					(end 442.87821 -306.985162)
				)
			)
		)
	)
	(zone
		(layers "B.Cu" "In11.Cu" "In13.Cu" "In15.Cu")
		(hatch none 0.5)
		(connect_pads
			(clearance 0)
		)
		(min_thickness 0.25)
		(keepout
			(tracks not_allowed)
			(vias allowed)
			(pads allowed)
			(copperpour not_allowed)
			(footprints allowed)
		)
		(placement
			(enabled no)
			(sheetname "")
		)
		(fill yes
			(thermal_gap 0.5)
			(thermal_bridge_width 0.5)
			(island_removal_mode 0)
		)
		(polygon
			(pts
				(arc
					(start 194.938142 -251.735336)
					(mid 194.270122 -251.735336)
					(end 194.938142 -251.735336)
				)
			)
		)
	)
	(zone
		(layers "B.Cu" "In11.Cu" "In13.Cu" "In15.Cu")
		(hatch none 0.5)
		(connect_pads
			(clearance 0)
		)
		(min_thickness 0.25)
		(keepout
			(tracks not_allowed)
			(vias allowed)
			(pads allowed)
			(copperpour not_allowed)
			(footprints allowed)
		)
		(placement
			(enabled no)
			(sheetname "")
		)
		(fill yes
			(thermal_gap 0.5)
			(thermal_bridge_width 0.5)
			(island_removal_mode 0)
		)
		(polygon
			(pts
				(arc
					(start 25.486106 -233.885232)
					(mid 24.818086 -233.885232)
					(end 25.486106 -233.885232)
				)
			)
		)
	)
	(zone
		(layers "B.Cu" "In11.Cu" "In13.Cu" "In15.Cu")
		(hatch none 0.5)
		(connect_pads
			(clearance 0)
		)
		(min_thickness 0.25)
		(keepout
			(tracks not_allowed)
			(vias allowed)
			(pads allowed)
			(copperpour not_allowed)
			(footprints allowed)
		)
		(placement
			(enabled no)
			(sheetname "")
		)
		(fill yes
			(thermal_gap 0.5)
			(thermal_bridge_width 0.5)
			(island_removal_mode 0)
		)
		(polygon
			(pts
				(arc
					(start 82.485992 -250.15444)
					(mid 81.856072 -250.15444)
					(end 82.485992 -250.15444)
				)
			)
		)
	)
	(zone
		(layers "B.Cu" "In11.Cu" "In13.Cu" "In15.Cu")
		(hatch none 0.5)
		(connect_pads
			(clearance 0)
		)
		(min_thickness 0.25)
		(keepout
			(tracks not_allowed)
			(vias allowed)
			(pads allowed)
			(copperpour not_allowed)
			(footprints allowed)
		)
		(placement
			(enabled no)
			(sheetname "")
		)
		(fill yes
			(thermal_gap 0.5)
			(thermal_bridge_width 0.5)
			(island_removal_mode 0)
		)
		(polygon
			(pts
				(arc
					(start 81.545938 -248.534428)
					(mid 80.916018 -248.534428)
					(end 81.545938 -248.534428)
				)
			)
		)
	)
	(zone
		(layers "B.Cu" "In11.Cu" "In13.Cu" "In15.Cu")
		(hatch none 0.5)
		(connect_pads
			(clearance 0)
		)
		(min_thickness 0.25)
		(keepout
			(tracks not_allowed)
			(vias allowed)
			(pads allowed)
			(copperpour not_allowed)
			(footprints allowed)
		)
		(placement
			(enabled no)
			(sheetname "")
		)
		(fill yes
			(thermal_gap 0.5)
			(thermal_bridge_width 0.5)
			(island_removal_mode 0)
		)
		(polygon
			(pts
				(arc
					(start 346.236036 -284.616144)
					(mid 345.606116 -284.616144)
					(end 346.236036 -284.616144)
				)
			)
		)
	)
	(zone
		(layers "B.Cu" "In11.Cu" "In13.Cu" "In15.Cu")
		(hatch none 0.5)
		(connect_pads
			(clearance 0)
		)
		(min_thickness 0.25)
		(keepout
			(tracks not_allowed)
			(vias allowed)
			(pads allowed)
			(copperpour not_allowed)
			(footprints allowed)
		)
		(placement
			(enabled no)
			(sheetname "")
		)
		(fill yes
			(thermal_gap 0.5)
			(thermal_bridge_width 0.5)
			(island_removal_mode 0)
		)
		(polygon
			(pts
				(arc
					(start 349.056198 -286.236156)
					(mid 348.426278 -286.236156)
					(end 349.056198 -286.236156)
				)
			)
		)
	)
	(zone
		(layers "B.Cu" "In11.Cu" "In13.Cu" "In15.Cu")
		(hatch none 0.5)
		(connect_pads
			(clearance 0)
		)
		(min_thickness 0.25)
		(keepout
			(tracks not_allowed)
			(vias allowed)
			(pads allowed)
			(copperpour not_allowed)
			(footprints allowed)
		)
		(placement
			(enabled no)
			(sheetname "")
		)
		(fill yes
			(thermal_gap 0.5)
			(thermal_bridge_width 0.5)
			(island_removal_mode 0)
		)
		(polygon
			(pts
				(arc
					(start 343.033858 -397.849344)
					(mid 342.403938 -397.849344)
					(end 343.033858 -397.849344)
				)
			)
		)
	)
	(zone
		(layers "B.Cu" "In11.Cu" "In13.Cu" "In15.Cu")
		(hatch none 0.5)
		(connect_pads
			(clearance 0)
		)
		(min_thickness 0.25)
		(keepout
			(tracks not_allowed)
			(vias allowed)
			(pads allowed)
			(copperpour not_allowed)
			(footprints allowed)
		)
		(placement
			(enabled no)
			(sheetname "")
		)
		(fill yes
			(thermal_gap 0.5)
			(thermal_bridge_width 0.5)
			(island_removal_mode 0)
		)
		(polygon
			(pts
				(arc
					(start 373.489728 -281.37612)
					(mid 372.859808 -281.37612)
					(end 373.489728 -281.37612)
				)
			)
		)
	)
	(zone
		(layers "B.Cu" "In11.Cu" "In13.Cu" "In15.Cu")
		(hatch none 0.5)
		(connect_pads
			(clearance 0)
		)
		(min_thickness 0.25)
		(keepout
			(tracks not_allowed)
			(vias allowed)
			(pads allowed)
			(copperpour not_allowed)
			(footprints allowed)
		)
		(placement
			(enabled no)
			(sheetname "")
		)
		(fill yes
			(thermal_gap 0.5)
			(thermal_bridge_width 0.5)
			(island_removal_mode 0)
		)
		(polygon
			(pts
				(arc
					(start 101.755956 -241.244374)
					(mid 101.126036 -241.244374)
					(end 101.755956 -241.244374)
				)
			)
		)
	)
	(zone
		(layers "B.Cu" "In11.Cu" "In13.Cu" "In15.Cu")
		(hatch none 0.5)
		(connect_pads
			(clearance 0)
		)
		(min_thickness 0.25)
		(keepout
			(tracks not_allowed)
			(vias allowed)
			(pads allowed)
			(copperpour not_allowed)
			(footprints allowed)
		)
		(placement
			(enabled no)
			(sheetname "")
		)
		(fill yes
			(thermal_gap 0.5)
			(thermal_bridge_width 0.5)
			(island_removal_mode 0)
		)
		(polygon
			(pts
				(arc
					(start 160.933892 -385.31038)
					(mid 160.303972 -385.31038)
					(end 160.933892 -385.31038)
				)
			)
		)
	)
	(zone
		(layers "B.Cu" "In11.Cu" "In13.Cu" "In15.Cu")
		(hatch none 0.5)
		(connect_pads
			(clearance 0)
		)
		(min_thickness 0.25)
		(keepout
			(tracks not_allowed)
			(vias allowed)
			(pads allowed)
			(copperpour not_allowed)
			(footprints allowed)
		)
		(placement
			(enabled no)
			(sheetname "")
		)
		(fill yes
			(thermal_gap 0.5)
			(thermal_bridge_width 0.5)
			(island_removal_mode 0)
		)
		(polygon
			(pts
				(arc
					(start 332.036928 -427.289976)
					(mid 331.262736 -427.289976)
					(end 332.036928 -427.289976)
				)
			)
		)
	)
	(zone
		(layers "B.Cu" "In11.Cu" "In13.Cu" "In15.Cu")
		(hatch none 0.5)
		(connect_pads
			(clearance 0)
		)
		(min_thickness 0.25)
		(keepout
			(tracks not_allowed)
			(vias allowed)
			(pads allowed)
			(copperpour not_allowed)
			(footprints allowed)
		)
		(placement
			(enabled no)
			(sheetname "")
		)
		(fill yes
			(thermal_gap 0.5)
			(thermal_bridge_width 0.5)
			(island_removal_mode 0)
		)
		(polygon
			(pts
				(arc
					(start 330.726034 -272.466054)
					(mid 330.096114 -272.466054)
					(end 330.726034 -272.466054)
				)
			)
		)
	)
	(zone
		(layers "B.Cu" "In11.Cu" "In13.Cu" "In15.Cu")
		(hatch none 0.5)
		(connect_pads
			(clearance 0)
		)
		(min_thickness 0.25)
		(keepout
			(tracks not_allowed)
			(vias allowed)
			(pads allowed)
			(copperpour not_allowed)
			(footprints allowed)
		)
		(placement
			(enabled no)
			(sheetname "")
		)
		(fill yes
			(thermal_gap 0.5)
			(thermal_bridge_width 0.5)
			(island_removal_mode 0)
		)
		(polygon
			(pts
				(arc
					(start 142.93977 -291.906198)
					(mid 142.30985 -291.906198)
					(end 142.93977 -291.906198)
				)
			)
		)
	)
	(zone
		(layers "B.Cu" "In11.Cu" "In13.Cu" "In15.Cu")
		(hatch none 0.5)
		(connect_pads
			(clearance 0)
		)
		(min_thickness 0.25)
		(keepout
			(tracks not_allowed)
			(vias allowed)
			(pads allowed)
			(copperpour not_allowed)
			(footprints allowed)
		)
		(placement
			(enabled no)
			(sheetname "")
		)
		(fill yes
			(thermal_gap 0.5)
			(thermal_bridge_width 0.5)
			(island_removal_mode 0)
		)
		(polygon
			(pts
				(arc
					(start 25.486106 -239.835436)
					(mid 24.818086 -239.835436)
					(end 25.486106 -239.835436)
				)
			)
		)
	)
	(zone
		(layers "B.Cu" "In11.Cu" "In13.Cu" "In15.Cu")
		(hatch none 0.5)
		(connect_pads
			(clearance 0)
		)
		(min_thickness 0.25)
		(keepout
			(tracks not_allowed)
			(vias allowed)
			(pads allowed)
			(copperpour not_allowed)
			(footprints allowed)
		)
		(placement
			(enabled no)
			(sheetname "")
		)
		(fill yes
			(thermal_gap 0.5)
			(thermal_bridge_width 0.5)
			(island_removal_mode 0)
		)
		(polygon
			(pts
				(arc
					(start 389.939784 -278.946102)
					(mid 389.309864 -278.946102)
					(end 389.939784 -278.946102)
				)
			)
		)
	)
	(zone
		(layers "B.Cu" "In11.Cu" "In13.Cu" "In15.Cu")
		(hatch none 0.5)
		(connect_pads
			(clearance 0)
		)
		(min_thickness 0.25)
		(keepout
			(tracks not_allowed)
			(vias allowed)
			(pads allowed)
			(copperpour not_allowed)
			(footprints allowed)
		)
		(placement
			(enabled no)
			(sheetname "")
		)
		(fill yes
			(thermal_gap 0.5)
			(thermal_bridge_width 0.5)
			(island_removal_mode 0)
		)
		(polygon
			(pts
				(arc
					(start 355.636068 -284.616144)
					(mid 355.006148 -284.616144)
					(end 355.636068 -284.616144)
				)
			)
		)
	)
	(zone
		(layers "B.Cu" "In11.Cu" "In13.Cu" "In15.Cu")
		(hatch none 0.5)
		(connect_pads
			(clearance 0)
		)
		(min_thickness 0.25)
		(keepout
			(tracks not_allowed)
			(vias allowed)
			(pads allowed)
			(copperpour not_allowed)
			(footprints allowed)
		)
		(placement
			(enabled no)
			(sheetname "")
		)
		(fill yes
			(thermal_gap 0.5)
			(thermal_bridge_width 0.5)
			(island_removal_mode 0)
		)
		(polygon
			(pts
				(arc
					(start 142.639796 -230.71455)
					(mid 142.009876 -230.71455)
					(end 142.639796 -230.71455)
				)
			)
		)
	)
	(zone
		(layers "B.Cu" "In11.Cu" "In13.Cu" "In15.Cu")
		(hatch none 0.5)
		(connect_pads
			(clearance 0)
		)
		(min_thickness 0.25)
		(keepout
			(tracks not_allowed)
			(vias allowed)
			(pads allowed)
			(copperpour not_allowed)
			(footprints allowed)
		)
		(placement
			(enabled no)
			(sheetname "")
		)
		(fill yes
			(thermal_gap 0.5)
			(thermal_bridge_width 0.5)
			(island_removal_mode 0)
		)
		(polygon
			(pts
				(arc
					(start 390.579864 -229.094284)
					(mid 389.949944 -229.094284)
					(end 390.579864 -229.094284)
				)
			)
		)
	)
	(zone
		(layers "B.Cu" "In11.Cu" "In13.Cu" "In15.Cu")
		(hatch none 0.5)
		(connect_pads
			(clearance 0)
		)
		(min_thickness 0.25)
		(keepout
			(tracks not_allowed)
			(vias allowed)
			(pads allowed)
			(copperpour not_allowed)
			(footprints allowed)
		)
		(placement
			(enabled no)
			(sheetname "")
		)
		(fill yes
			(thermal_gap 0.5)
			(thermal_bridge_width 0.5)
			(island_removal_mode 0)
		)
		(polygon
			(pts
				(arc
					(start 273.426174 -222.834962)
					(mid 272.758154 -222.834962)
					(end 273.426174 -222.834962)
				)
			)
		)
	)
	(zone
		(layers "B.Cu" "In11.Cu" "In13.Cu" "In15.Cu")
		(hatch none 0.5)
		(connect_pads
			(clearance 0)
		)
		(min_thickness 0.25)
		(keepout
			(tracks not_allowed)
			(vias allowed)
			(pads allowed)
			(copperpour not_allowed)
			(footprints allowed)
		)
		(placement
			(enabled no)
			(sheetname "")
		)
		(fill yes
			(thermal_gap 0.5)
			(thermal_bridge_width 0.5)
			(island_removal_mode 0)
		)
		(polygon
			(pts
				(arc
					(start 25.486106 -230.485442)
					(mid 24.818086 -230.485442)
					(end 25.486106 -230.485442)
				)
			)
		)
	)
	(zone
		(layers "B.Cu" "In11.Cu" "In13.Cu" "In15.Cu")
		(hatch none 0.5)
		(connect_pads
			(clearance 0)
		)
		(min_thickness 0.25)
		(keepout
			(tracks not_allowed)
			(vias allowed)
			(pads allowed)
			(copperpour not_allowed)
			(footprints allowed)
		)
		(placement
			(enabled no)
			(sheetname "")
		)
		(fill yes
			(thermal_gap 0.5)
			(thermal_bridge_width 0.5)
			(island_removal_mode 0)
		)
		(polygon
			(pts
				(arc
					(start 143.40967 -286.23641)
					(mid 142.77975 -286.23641)
					(end 143.40967 -286.23641)
				)
			)
		)
	)
	(zone
		(layers "B.Cu" "In11.Cu" "In13.Cu" "In15.Cu")
		(hatch none 0.5)
		(connect_pads
			(clearance 0)
		)
		(min_thickness 0.25)
		(keepout
			(tracks not_allowed)
			(vias allowed)
			(pads allowed)
			(copperpour not_allowed)
			(footprints allowed)
		)
		(placement
			(enabled no)
			(sheetname "")
		)
		(fill yes
			(thermal_gap 0.5)
			(thermal_bridge_width 0.5)
			(island_removal_mode 0)
		)
		(polygon
			(pts
				(arc
					(start 59.036966 -418.889942)
					(mid 58.262774 -418.889942)
					(end 59.036966 -418.889942)
				)
			)
		)
	)
	(zone
		(layers "B.Cu" "In11.Cu" "In13.Cu" "In15.Cu")
		(hatch none 0.5)
		(connect_pads
			(clearance 0)
		)
		(min_thickness 0.25)
		(keepout
			(tracks not_allowed)
			(vias allowed)
			(pads allowed)
			(copperpour not_allowed)
			(footprints allowed)
		)
		(placement
			(enabled no)
			(sheetname "")
		)
		(fill yes
			(thermal_gap 0.5)
			(thermal_bridge_width 0.5)
			(island_removal_mode 0)
		)
		(polygon
			(pts
				(arc
					(start 141.229842 -228.284532)
					(mid 140.599922 -228.284532)
					(end 141.229842 -228.284532)
				)
			)
		)
	)
	(zone
		(layers "B.Cu" "In11.Cu" "In13.Cu" "In15.Cu")
		(hatch none 0.5)
		(connect_pads
			(clearance 0)
		)
		(min_thickness 0.25)
		(keepout
			(tracks not_allowed)
			(vias allowed)
			(pads allowed)
			(copperpour not_allowed)
			(footprints allowed)
		)
		(placement
			(enabled no)
			(sheetname "")
		)
		(fill yes
			(thermal_gap 0.5)
			(thermal_bridge_width 0.5)
			(island_removal_mode 0)
		)
		(polygon
			(pts
				(arc
					(start 25.486106 -263.635236)
					(mid 24.818086 -263.635236)
					(end 25.486106 -263.635236)
				)
			)
		)
	)
	(zone
		(layers "B.Cu" "In11.Cu" "In13.Cu" "In15.Cu")
		(hatch none 0.5)
		(connect_pads
			(clearance 0)
		)
		(min_thickness 0.25)
		(keepout
			(tracks not_allowed)
			(vias allowed)
			(pads allowed)
			(copperpour not_allowed)
			(footprints allowed)
		)
		(placement
			(enabled no)
			(sheetname "")
		)
		(fill yes
			(thermal_gap 0.5)
			(thermal_bridge_width 0.5)
			(island_removal_mode 0)
		)
		(polygon
			(pts
				(arc
					(start 322.335906 -377.41733)
					(mid 321.667886 -377.41733)
					(end 322.335906 -377.41733)
				)
			)
		)
	)
	(zone
		(layers "B.Cu" "In11.Cu" "In13.Cu" "In15.Cu")
		(hatch none 0.5)
		(connect_pads
			(clearance 0)
		)
		(min_thickness 0.25)
		(keepout
			(tracks not_allowed)
			(vias allowed)
			(pads allowed)
			(copperpour not_allowed)
			(footprints allowed)
		)
		(placement
			(enabled no)
			(sheetname "")
		)
		(fill yes
			(thermal_gap 0.5)
			(thermal_bridge_width 0.5)
			(island_removal_mode 0)
		)
		(polygon
			(pts
				(arc
					(start 61.706252 -389.467344)
					(mid 61.076332 -389.467344)
					(end 61.706252 -389.467344)
				)
			)
		)
	)
	(zone
		(layers "B.Cu" "In11.Cu" "In13.Cu" "In15.Cu")
		(hatch none 0.5)
		(connect_pads
			(clearance 0)
		)
		(min_thickness 0.25)
		(keepout
			(tracks not_allowed)
			(vias allowed)
			(pads allowed)
			(copperpour not_allowed)
			(footprints allowed)
		)
		(placement
			(enabled no)
			(sheetname "")
		)
		(fill yes
			(thermal_gap 0.5)
			(thermal_bridge_width 0.5)
			(island_removal_mode 0)
		)
		(polygon
			(pts
				(arc
					(start 151.137112 -426.089826)
					(mid 150.36292 -426.089826)
					(end 151.137112 -426.089826)
				)
			)
		)
	)
	(zone
		(layers "B.Cu" "In11.Cu" "In13.Cu" "In15.Cu")
		(hatch none 0.5)
		(connect_pads
			(clearance 0)
		)
		(min_thickness 0.25)
		(keepout
			(tracks not_allowed)
			(vias allowed)
			(pads allowed)
			(copperpour not_allowed)
			(footprints allowed)
		)
		(placement
			(enabled no)
			(sheetname "")
		)
		(fill yes
			(thermal_gap 0.5)
			(thermal_bridge_width 0.5)
			(island_removal_mode 0)
		)
		(polygon
			(pts
				(arc
					(start 446.978278 -276.38502)
					(mid 446.310258 -276.38502)
					(end 446.978278 -276.38502)
				)
			)
		)
	)
	(zone
		(layers "B.Cu" "In11.Cu" "In13.Cu" "In15.Cu")
		(hatch none 0.5)
		(connect_pads
			(clearance 0)
		)
		(min_thickness 0.25)
		(keepout
			(tracks not_allowed)
			(vias allowed)
			(pads allowed)
			(copperpour not_allowed)
			(footprints allowed)
		)
		(placement
			(enabled no)
			(sheetname "")
		)
		(fill yes
			(thermal_gap 0.5)
			(thermal_bridge_width 0.5)
			(island_removal_mode 0)
		)
		(polygon
			(pts
				(arc
					(start 390.879838 -277.32609)
					(mid 390.249918 -277.32609)
					(end 390.879838 -277.32609)
				)
			)
		)
	)
	(zone
		(layers "B.Cu" "In11.Cu" "In13.Cu" "In15.Cu")
		(hatch none 0.5)
		(connect_pads
			(clearance 0)
		)
		(min_thickness 0.25)
		(keepout
			(tracks not_allowed)
			(vias allowed)
			(pads allowed)
			(copperpour not_allowed)
			(footprints allowed)
		)
		(placement
			(enabled no)
			(sheetname "")
		)
		(fill yes
			(thermal_gap 0.5)
			(thermal_bridge_width 0.5)
			(island_removal_mode 0)
		)
		(polygon
			(pts
				(arc
					(start 199.03821 -252.58522)
					(mid 198.37019 -252.58522)
					(end 199.03821 -252.58522)
				)
			)
		)
	)
	(zone
		(layers "B.Cu" "In11.Cu" "In13.Cu" "In15.Cu")
		(hatch none 0.5)
		(connect_pads
			(clearance 0)
		)
		(min_thickness 0.25)
		(keepout
			(tracks not_allowed)
			(vias allowed)
			(pads allowed)
			(copperpour not_allowed)
			(footprints allowed)
		)
		(placement
			(enabled no)
			(sheetname "")
		)
		(fill yes
			(thermal_gap 0.5)
			(thermal_bridge_width 0.5)
			(island_removal_mode 0)
		)
		(polygon
			(pts
				(arc
					(start 82.785966 -290.286186)
					(mid 82.156046 -290.286186)
					(end 82.785966 -290.286186)
				)
			)
		)
	)
	(zone
		(layers "B.Cu" "In11.Cu" "In13.Cu" "In15.Cu")
		(hatch none 0.5)
		(connect_pads
			(clearance 0)
		)
		(min_thickness 0.25)
		(keepout
			(tracks not_allowed)
			(vias allowed)
			(pads allowed)
			(copperpour not_allowed)
			(footprints allowed)
		)
		(placement
			(enabled no)
			(sheetname "")
		)
		(fill yes
			(thermal_gap 0.5)
			(thermal_bridge_width 0.5)
			(island_removal_mode 0)
		)
		(polygon
			(pts
				(arc
					(start 329.486006 -248.534174)
					(mid 328.856086 -248.534174)
					(end 329.486006 -248.534174)
				)
			)
		)
	)
	(zone
		(layers "B.Cu" "In11.Cu" "In13.Cu" "In15.Cu")
		(hatch none 0.5)
		(connect_pads
			(clearance 0)
		)
		(min_thickness 0.25)
		(keepout
			(tracks not_allowed)
			(vias allowed)
			(pads allowed)
			(copperpour not_allowed)
			(footprints allowed)
		)
		(placement
			(enabled no)
			(sheetname "")
		)
		(fill yes
			(thermal_gap 0.5)
			(thermal_bridge_width 0.5)
			(island_removal_mode 0)
		)
		(polygon
			(pts
				(arc
					(start 329.78598 -262.745982)
					(mid 329.15606 -262.745982)
					(end 329.78598 -262.745982)
				)
			)
		)
	)
	(zone
		(layers "B.Cu" "In11.Cu" "In13.Cu" "In15.Cu")
		(hatch none 0.5)
		(connect_pads
			(clearance 0)
		)
		(min_thickness 0.25)
		(keepout
			(tracks not_allowed)
			(vias allowed)
			(pads allowed)
			(copperpour not_allowed)
			(footprints allowed)
		)
		(placement
			(enabled no)
			(sheetname "")
		)
		(fill yes
			(thermal_gap 0.5)
			(thermal_bridge_width 0.5)
			(island_removal_mode 0)
		)
		(polygon
			(pts
				(arc
					(start 129.606294 -388.774432)
					(mid 128.976374 -388.774432)
					(end 129.606294 -388.774432)
				)
			)
		)
	)
	(zone
		(layers "B.Cu" "In11.Cu" "In13.Cu" "In15.Cu")
		(hatch none 0.5)
		(connect_pads
			(clearance 0)
		)
		(min_thickness 0.25)
		(keepout
			(tracks not_allowed)
			(vias allowed)
			(pads allowed)
			(copperpour not_allowed)
			(footprints allowed)
		)
		(placement
			(enabled no)
			(sheetname "")
		)
		(fill yes
			(thermal_gap 0.5)
			(thermal_bridge_width 0.5)
			(island_removal_mode 0)
		)
		(polygon
			(pts
				(arc
					(start 389.939784 -264.365994)
					(mid 389.309864 -264.365994)
					(end 389.939784 -264.365994)
				)
			)
		)
	)
	(zone
		(layers "B.Cu" "In11.Cu" "In13.Cu" "In15.Cu")
		(hatch none 0.5)
		(connect_pads
			(clearance 0)
		)
		(min_thickness 0.25)
		(keepout
			(tracks not_allowed)
			(vias allowed)
			(pads allowed)
			(copperpour not_allowed)
			(footprints allowed)
		)
		(placement
			(enabled no)
			(sheetname "")
		)
		(fill yes
			(thermal_gap 0.5)
			(thermal_bridge_width 0.5)
			(island_removal_mode 0)
		)
		(polygon
			(pts
				(arc
					(start 143.40967 -278.13635)
					(mid 142.77975 -278.13635)
					(end 143.40967 -278.13635)
				)
			)
		)
	)
	(zone
		(layers "B.Cu" "In11.Cu" "In13.Cu" "In15.Cu")
		(hatch none 0.5)
		(connect_pads
			(clearance 0)
		)
		(min_thickness 0.25)
		(keepout
			(tracks not_allowed)
			(vias allowed)
			(pads allowed)
			(copperpour not_allowed)
			(footprints allowed)
		)
		(placement
			(enabled no)
			(sheetname "")
		)
		(fill yes
			(thermal_gap 0.5)
			(thermal_bridge_width 0.5)
			(island_removal_mode 0)
		)
		(polygon
			(pts
				(arc
					(start 330.42606 -246.914162)
					(mid 329.79614 -246.914162)
					(end 330.42606 -246.914162)
				)
			)
		)
	)
	(zone
		(layers "B.Cu" "In11.Cu" "In13.Cu" "In15.Cu")
		(hatch none 0.5)
		(connect_pads
			(clearance 0)
		)
		(min_thickness 0.25)
		(keepout
			(tracks not_allowed)
			(vias allowed)
			(pads allowed)
			(copperpour not_allowed)
			(footprints allowed)
		)
		(placement
			(enabled no)
			(sheetname "")
		)
		(fill yes
			(thermal_gap 0.5)
			(thermal_bridge_width 0.5)
			(island_removal_mode 0)
		)
		(polygon
			(pts
				(arc
					(start 199.03821 -313.78525)
					(mid 198.37019 -313.78525)
					(end 199.03821 -313.78525)
				)
			)
		)
	)
	(zone
		(layers "B.Cu" "In11.Cu" "In13.Cu" "In15.Cu")
		(hatch none 0.5)
		(connect_pads
			(clearance 0)
		)
		(min_thickness 0.25)
		(keepout
			(tracks not_allowed)
			(vias allowed)
			(pads allowed)
			(copperpour not_allowed)
			(footprints allowed)
		)
		(placement
			(enabled no)
			(sheetname "")
		)
		(fill yes
			(thermal_gap 0.5)
			(thermal_bridge_width 0.5)
			(island_removal_mode 0)
		)
		(polygon
			(pts
				(arc
					(start 329.31608 -266.796012)
					(mid 328.68616 -266.796012)
					(end 329.31608 -266.796012)
				)
			)
		)
	)
	(zone
		(layers "B.Cu" "In11.Cu" "In13.Cu" "In15.Cu")
		(hatch none 0.5)
		(connect_pads
			(clearance 0)
		)
		(min_thickness 0.25)
		(keepout
			(tracks not_allowed)
			(vias allowed)
			(pads allowed)
			(copperpour not_allowed)
			(footprints allowed)
		)
		(placement
			(enabled no)
			(sheetname "")
		)
		(fill yes
			(thermal_gap 0.5)
			(thermal_bridge_width 0.5)
			(island_removal_mode 0)
		)
		(polygon
			(pts
				(arc
					(start 357.986076 -282.186126)
					(mid 357.356156 -282.186126)
					(end 357.986076 -282.186126)
				)
			)
		)
	)
	(zone
		(layers "B.Cu" "In11.Cu" "In13.Cu" "In15.Cu")
		(hatch none 0.5)
		(connect_pads
			(clearance 0)
		)
		(min_thickness 0.25)
		(keepout
			(tracks not_allowed)
			(vias allowed)
			(pads allowed)
			(copperpour not_allowed)
			(footprints allowed)
		)
		(placement
			(enabled no)
			(sheetname "")
		)
		(fill yes
			(thermal_gap 0.5)
			(thermal_bridge_width 0.5)
			(island_removal_mode 0)
		)
		(polygon
			(pts
				(arc
					(start 81.076038 -238.00435)
					(mid 80.446118 -238.00435)
					(end 81.076038 -238.00435)
				)
			)
		)
	)
	(zone
		(layers "B.Cu" "In11.Cu" "In13.Cu" "In15.Cu")
		(hatch none 0.5)
		(connect_pads
			(clearance 0)
		)
		(min_thickness 0.25)
		(keepout
			(tracks not_allowed)
			(vias allowed)
			(pads allowed)
			(copperpour not_allowed)
			(footprints allowed)
		)
		(placement
			(enabled no)
			(sheetname "")
		)
		(fill yes
			(thermal_gap 0.5)
			(thermal_bridge_width 0.5)
			(island_removal_mode 0)
		)
		(polygon
			(pts
				(arc
					(start 83.255866 -278.13635)
					(mid 82.625946 -278.13635)
					(end 83.255866 -278.13635)
				)
			)
		)
	)
	(zone
		(layers "B.Cu" "In11.Cu" "In13.Cu" "In15.Cu")
		(hatch none 0.5)
		(connect_pads
			(clearance 0)
		)
		(min_thickness 0.25)
		(keepout
			(tracks not_allowed)
			(vias allowed)
			(pads allowed)
			(copperpour not_allowed)
			(footprints allowed)
		)
		(placement
			(enabled no)
			(sheetname "")
		)
		(fill yes
			(thermal_gap 0.5)
			(thermal_bridge_width 0.5)
			(island_removal_mode 0)
		)
		(polygon
			(pts
				(arc
					(start 351.876106 -284.616144)
					(mid 351.246186 -284.616144)
					(end 351.876106 -284.616144)
				)
			)
		)
	)
	(zone
		(layers "B.Cu" "In11.Cu" "In13.Cu" "In15.Cu")
		(hatch none 0.5)
		(connect_pads
			(clearance 0)
		)
		(min_thickness 0.25)
		(keepout
			(tracks not_allowed)
			(vias allowed)
			(pads allowed)
			(copperpour not_allowed)
			(footprints allowed)
		)
		(placement
			(enabled no)
			(sheetname "")
		)
		(fill yes
			(thermal_gap 0.5)
			(thermal_bridge_width 0.5)
			(island_removal_mode 0)
		)
		(polygon
			(pts
				(arc
					(start 81.076038 -254.20447)
					(mid 80.446118 -254.20447)
					(end 81.076038 -254.20447)
				)
			)
		)
	)
	(zone
		(layers "B.Cu" "In11.Cu" "In13.Cu" "In15.Cu")
		(hatch none 0.5)
		(connect_pads
			(clearance 0)
		)
		(min_thickness 0.25)
		(keepout
			(tracks not_allowed)
			(vias allowed)
			(pads allowed)
			(copperpour not_allowed)
			(footprints allowed)
		)
		(placement
			(enabled no)
			(sheetname "")
		)
		(fill yes
			(thermal_gap 0.5)
			(thermal_bridge_width 0.5)
			(island_removal_mode 0)
		)
		(polygon
			(pts
				(arc
					(start 141.699742 -245.294404)
					(mid 141.069822 -245.294404)
					(end 141.699742 -245.294404)
				)
			)
		)
	)
	(zone
		(layers "B.Cu" "In11.Cu" "In13.Cu" "In15.Cu")
		(hatch none 0.5)
		(connect_pads
			(clearance 0)
		)
		(min_thickness 0.25)
		(keepout
			(tracks not_allowed)
			(vias allowed)
			(pads allowed)
			(copperpour not_allowed)
			(footprints allowed)
		)
		(placement
			(enabled no)
			(sheetname "")
		)
		(fill yes
			(thermal_gap 0.5)
			(thermal_bridge_width 0.5)
			(island_removal_mode 0)
		)
		(polygon
			(pts
				(arc
					(start 94.82201 -212.140038)
					(mid 94.15399 -212.140038)
					(end 94.82201 -212.140038)
				)
			)
		)
	)
	(zone
		(layers "B.Cu" "In11.Cu" "In13.Cu" "In15.Cu")
		(hatch none 0.5)
		(connect_pads
			(clearance 0)
		)
		(min_thickness 0.25)
		(keepout
			(tracks not_allowed)
			(vias allowed)
			(pads allowed)
			(copperpour not_allowed)
			(footprints allowed)
		)
		(placement
			(enabled no)
			(sheetname "")
		)
		(fill yes
			(thermal_gap 0.5)
			(thermal_bridge_width 0.5)
			(island_removal_mode 0)
		)
		(polygon
			(pts
				(arc
					(start 199.03821 -312.935366)
					(mid 198.37019 -312.935366)
					(end 199.03821 -312.935366)
				)
			)
		)
	)
	(zone
		(layers "B.Cu" "In11.Cu" "In13.Cu" "In15.Cu")
		(hatch none 0.5)
		(connect_pads
			(clearance 0)
		)
		(min_thickness 0.25)
		(keepout
			(tracks not_allowed)
			(vias allowed)
			(pads allowed)
			(copperpour not_allowed)
			(footprints allowed)
		)
		(placement
			(enabled no)
			(sheetname "")
		)
		(fill yes
			(thermal_gap 0.5)
			(thermal_bridge_width 0.5)
			(island_removal_mode 0)
		)
		(polygon
			(pts
				(arc
					(start 118.029736 -286.23641)
					(mid 117.399816 -286.23641)
					(end 118.029736 -286.23641)
				)
			)
		)
	)
	(zone
		(layers "B.Cu" "In11.Cu" "In13.Cu" "In15.Cu")
		(hatch none 0.5)
		(connect_pads
			(clearance 0)
		)
		(min_thickness 0.25)
		(keepout
			(tracks not_allowed)
			(vias allowed)
			(pads allowed)
			(copperpour not_allowed)
			(footprints allowed)
		)
		(placement
			(enabled no)
			(sheetname "")
		)
		(fill yes
			(thermal_gap 0.5)
			(thermal_bridge_width 0.5)
			(island_removal_mode 0)
		)
		(polygon
			(pts
				(arc
					(start 81.076038 -236.384338)
					(mid 80.446118 -236.384338)
					(end 81.076038 -236.384338)
				)
			)
		)
	)
	(zone
		(layers "B.Cu" "In11.Cu" "In13.Cu" "In15.Cu")
		(hatch none 0.5)
		(connect_pads
			(clearance 0)
		)
		(min_thickness 0.25)
		(keepout
			(tracks not_allowed)
			(vias allowed)
			(pads allowed)
			(copperpour not_allowed)
			(footprints allowed)
		)
		(placement
			(enabled no)
			(sheetname "")
		)
		(fill yes
			(thermal_gap 0.5)
			(thermal_bridge_width 0.5)
			(island_removal_mode 0)
		)
		(polygon
			(pts
				(arc
					(start 340.233762 -397.156432)
					(mid 339.603842 -397.156432)
					(end 340.233762 -397.156432)
				)
			)
		)
	)
	(zone
		(layers "B.Cu" "In11.Cu" "In13.Cu" "In15.Cu")
		(hatch none 0.5)
		(connect_pads
			(clearance 0)
		)
		(min_thickness 0.25)
		(keepout
			(tracks not_allowed)
			(vias allowed)
			(pads allowed)
			(copperpour not_allowed)
			(footprints allowed)
		)
		(placement
			(enabled no)
			(sheetname "")
		)
		(fill yes
			(thermal_gap 0.5)
			(thermal_bridge_width 0.5)
			(island_removal_mode 0)
		)
		(polygon
			(pts
				(arc
					(start 29.586174 -206.685388)
					(mid 28.918154 -206.685388)
					(end 29.586174 -206.685388)
				)
			)
		)
	)
	(zone
		(layers "B.Cu" "In11.Cu" "In13.Cu" "In15.Cu")
		(hatch none 0.5)
		(connect_pads
			(clearance 0)
		)
		(min_thickness 0.25)
		(keepout
			(tracks not_allowed)
			(vias allowed)
			(pads allowed)
			(copperpour not_allowed)
			(footprints allowed)
		)
		(placement
			(enabled no)
			(sheetname "")
		)
		(fill yes
			(thermal_gap 0.5)
			(thermal_bridge_width 0.5)
			(island_removal_mode 0)
		)
		(polygon
			(pts
				(arc
					(start 365.02975 -282.996132)
					(mid 364.39983 -282.996132)
					(end 365.02975 -282.996132)
				)
			)
		)
	)
	(zone
		(layers "B.Cu" "In11.Cu" "In13.Cu" "In15.Cu")
		(hatch none 0.5)
		(connect_pads
			(clearance 0)
		)
		(min_thickness 0.25)
		(keepout
			(tracks not_allowed)
			(vias allowed)
			(pads allowed)
			(copperpour not_allowed)
			(footprints allowed)
		)
		(placement
			(enabled no)
			(sheetname "")
		)
		(fill yes
			(thermal_gap 0.5)
			(thermal_bridge_width 0.5)
			(island_removal_mode 0)
		)
		(polygon
			(pts
				(arc
					(start 143.40967 -273.276314)
					(mid 142.77975 -273.276314)
					(end 143.40967 -273.276314)
				)
			)
		)
	)
	(zone
		(layers "B.Cu" "In11.Cu" "In13.Cu" "In15.Cu")
		(hatch none 0.5)
		(connect_pads
			(clearance 0)
		)
		(min_thickness 0.25)
		(keepout
			(tracks not_allowed)
			(vias allowed)
			(pads allowed)
			(copperpour not_allowed)
			(footprints allowed)
		)
		(placement
			(enabled no)
			(sheetname "")
		)
		(fill yes
			(thermal_gap 0.5)
			(thermal_bridge_width 0.5)
			(island_removal_mode 0)
		)
		(polygon
			(pts
				(arc
					(start 162.533838 -386.003292)
					(mid 161.903918 -386.003292)
					(end 162.533838 -386.003292)
				)
			)
		)
	)
	(zone
		(layers "B.Cu" "In11.Cu" "In13.Cu" "In15.Cu")
		(hatch none 0.5)
		(connect_pads
			(clearance 0)
		)
		(min_thickness 0.25)
		(keepout
			(tracks not_allowed)
			(vias allowed)
			(pads allowed)
			(copperpour not_allowed)
			(footprints allowed)
		)
		(placement
			(enabled no)
			(sheetname "")
		)
		(fill yes
			(thermal_gap 0.5)
			(thermal_bridge_width 0.5)
			(island_removal_mode 0)
		)
		(polygon
			(pts
				(arc
					(start 100.815902 -242.864386)
					(mid 100.185982 -242.864386)
					(end 100.815902 -242.864386)
				)
			)
		)
	)
	(zone
		(layers "B.Cu" "In11.Cu" "In13.Cu" "In15.Cu")
		(hatch none 0.5)
		(connect_pads
			(clearance 0)
		)
		(min_thickness 0.25)
		(keepout
			(tracks not_allowed)
			(vias allowed)
			(pads allowed)
			(copperpour not_allowed)
			(footprints allowed)
		)
		(placement
			(enabled no)
			(sheetname "")
		)
		(fill yes
			(thermal_gap 0.5)
			(thermal_bridge_width 0.5)
			(island_removal_mode 0)
		)
		(polygon
			(pts
				(arc
					(start 131.20624 -389.467344)
					(mid 130.57632 -389.467344)
					(end 131.20624 -389.467344)
				)
			)
		)
	)
	(zone
		(layers "B.Cu" "In11.Cu" "In13.Cu" "In15.Cu")
		(hatch none 0.5)
		(connect_pads
			(clearance 0)
		)
		(min_thickness 0.25)
		(keepout
			(tracks not_allowed)
			(vias allowed)
			(pads allowed)
			(copperpour not_allowed)
			(footprints allowed)
		)
		(placement
			(enabled no)
			(sheetname "")
		)
		(fill yes
			(thermal_gap 0.5)
			(thermal_bridge_width 0.5)
			(island_removal_mode 0)
		)
		(polygon
			(pts
				(arc
					(start 338.233766 -397.849344)
					(mid 337.603846 -397.849344)
					(end 338.233766 -397.849344)
				)
			)
		)
	)
	(zone
		(layers "B.Cu" "In11.Cu" "In13.Cu" "In15.Cu")
		(hatch none 0.5)
		(connect_pads
			(clearance 0)
		)
		(min_thickness 0.25)
		(keepout
			(tracks not_allowed)
			(vias allowed)
			(pads allowed)
			(copperpour not_allowed)
			(footprints allowed)
		)
		(placement
			(enabled no)
			(sheetname "")
		)
		(fill yes
			(thermal_gap 0.5)
			(thermal_bridge_width 0.5)
			(island_removal_mode 0)
		)
		(polygon
			(pts
				(arc
					(start 63.444374 -404.46452)
					(mid 62.776354 -404.46452)
					(end 63.444374 -404.46452)
				)
			)
		)
	)
	(zone
		(layers "B.Cu" "In11.Cu" "In13.Cu" "In15.Cu")
		(hatch none 0.5)
		(connect_pads
			(clearance 0)
		)
		(min_thickness 0.25)
		(keepout
			(tracks not_allowed)
			(vias allowed)
			(pads allowed)
			(copperpour not_allowed)
			(footprints allowed)
		)
		(placement
			(enabled no)
			(sheetname "")
		)
		(fill yes
			(thermal_gap 0.5)
			(thermal_bridge_width 0.5)
			(island_removal_mode 0)
		)
		(polygon
			(pts
				(arc
					(start 329.486006 -253.39421)
					(mid 328.856086 -253.39421)
					(end 329.486006 -253.39421)
				)
			)
		)
	)
	(zone
		(layers "B.Cu" "In11.Cu" "In13.Cu" "In15.Cu")
		(hatch none 0.5)
		(connect_pads
			(clearance 0)
		)
		(min_thickness 0.25)
		(keepout
			(tracks not_allowed)
			(vias allowed)
			(pads allowed)
			(copperpour not_allowed)
			(footprints allowed)
		)
		(placement
			(enabled no)
			(sheetname "")
		)
		(fill yes
			(thermal_gap 0.5)
			(thermal_bridge_width 0.5)
			(island_removal_mode 0)
		)
		(polygon
			(pts
				(arc
					(start 141.699742 -227.474526)
					(mid 141.069822 -227.474526)
					(end 141.699742 -227.474526)
				)
			)
		)
	)
	(zone
		(layers "B.Cu" "In11.Cu" "In13.Cu" "In15.Cu")
		(hatch none 0.5)
		(connect_pads
			(clearance 0)
		)
		(min_thickness 0.25)
		(keepout
			(tracks not_allowed)
			(vias allowed)
			(pads allowed)
			(copperpour not_allowed)
			(footprints allowed)
		)
		(placement
			(enabled no)
			(sheetname "")
		)
		(fill yes
			(thermal_gap 0.5)
			(thermal_bridge_width 0.5)
			(island_removal_mode 0)
		)
		(polygon
			(pts
				(arc
					(start 142.639796 -245.294404)
					(mid 142.009876 -245.294404)
					(end 142.639796 -245.294404)
				)
			)
		)
	)
	(zone
		(layers "B.Cu" "In11.Cu" "In13.Cu" "In15.Cu")
		(hatch none 0.5)
		(connect_pads
			(clearance 0)
		)
		(min_thickness 0.25)
		(keepout
			(tracks not_allowed)
			(vias allowed)
			(pads allowed)
			(copperpour not_allowed)
			(footprints allowed)
		)
		(placement
			(enabled no)
			(sheetname "")
		)
		(fill yes
			(thermal_gap 0.5)
			(thermal_bridge_width 0.5)
			(island_removal_mode 0)
		)
		(polygon
			(pts
				(arc
					(start 29.586174 -313.78525)
					(mid 28.918154 -313.78525)
					(end 29.586174 -313.78525)
				)
			)
		)
	)
	(zone
		(layers "B.Cu" "In11.Cu" "In13.Cu" "In15.Cu")
		(hatch none 0.5)
		(connect_pads
			(clearance 0)
		)
		(min_thickness 0.25)
		(keepout
			(tracks not_allowed)
			(vias allowed)
			(pads allowed)
			(copperpour not_allowed)
			(footprints allowed)
		)
		(placement
			(enabled no)
			(sheetname "")
		)
		(fill yes
			(thermal_gap 0.5)
			(thermal_bridge_width 0.5)
			(island_removal_mode 0)
		)
		(polygon
			(pts
				(arc
					(start 107.396026 -242.864386)
					(mid 106.766106 -242.864386)
					(end 107.396026 -242.864386)
				)
			)
		)
	)
	(zone
		(layers "B.Cu" "In11.Cu" "In13.Cu" "In15.Cu")
		(hatch none 0.5)
		(connect_pads
			(clearance 0)
		)
		(min_thickness 0.25)
		(keepout
			(tracks not_allowed)
			(vias allowed)
			(pads allowed)
			(copperpour not_allowed)
			(footprints allowed)
		)
		(placement
			(enabled no)
			(sheetname "")
		)
		(fill yes
			(thermal_gap 0.5)
			(thermal_bridge_width 0.5)
			(island_removal_mode 0)
		)
		(polygon
			(pts
				(arc
					(start 25.486106 -289.98545)
					(mid 24.818086 -289.98545)
					(end 25.486106 -289.98545)
				)
			)
		)
	)
	(zone
		(layers "B.Cu" "In11.Cu" "In13.Cu" "In15.Cu")
		(hatch none 0.5)
		(connect_pads
			(clearance 0)
		)
		(min_thickness 0.25)
		(keepout
			(tracks not_allowed)
			(vias allowed)
			(pads allowed)
			(copperpour not_allowed)
			(footprints allowed)
		)
		(placement
			(enabled no)
			(sheetname "")
		)
		(fill yes
			(thermal_gap 0.5)
			(thermal_bridge_width 0.5)
			(island_removal_mode 0)
		)
		(polygon
			(pts
				(arc
					(start 277.526242 -249.185176)
					(mid 276.858222 -249.185176)
					(end 277.526242 -249.185176)
				)
			)
		)
	)
	(zone
		(layers "B.Cu" "In11.Cu" "In13.Cu" "In15.Cu")
		(hatch none 0.5)
		(connect_pads
			(clearance 0)
		)
		(min_thickness 0.25)
		(keepout
			(tracks not_allowed)
			(vias allowed)
			(pads allowed)
			(copperpour not_allowed)
			(footprints allowed)
		)
		(placement
			(enabled no)
			(sheetname "")
		)
		(fill yes
			(thermal_gap 0.5)
			(thermal_bridge_width 0.5)
			(island_removal_mode 0)
		)
		(polygon
			(pts
				(arc
					(start 329.78598 -282.186126)
					(mid 329.15606 -282.186126)
					(end 329.78598 -282.186126)
				)
			)
		)
	)
	(zone
		(layers "B.Cu" "In11.Cu" "In13.Cu" "In15.Cu")
		(hatch none 0.5)
		(connect_pads
			(clearance 0)
		)
		(min_thickness 0.25)
		(keepout
			(tracks not_allowed)
			(vias allowed)
			(pads allowed)
			(copperpour not_allowed)
			(footprints allowed)
		)
		(placement
			(enabled no)
			(sheetname "")
		)
		(fill yes
			(thermal_gap 0.5)
			(thermal_bridge_width 0.5)
			(island_removal_mode 0)
		)
		(polygon
			(pts
				(arc
					(start 277.526242 -290.83508)
					(mid 276.858222 -290.83508)
					(end 277.526242 -290.83508)
				)
			)
		)
	)
	(zone
		(layers "B.Cu" "In11.Cu" "In13.Cu" "In15.Cu")
		(hatch none 0.5)
		(connect_pads
			(clearance 0)
		)
		(min_thickness 0.25)
		(keepout
			(tracks not_allowed)
			(vias allowed)
			(pads allowed)
			(copperpour not_allowed)
			(footprints allowed)
		)
		(placement
			(enabled no)
			(sheetname "")
		)
		(fill yes
			(thermal_gap 0.5)
			(thermal_bridge_width 0.5)
			(island_removal_mode 0)
		)
		(polygon
			(pts
				(arc
					(start 390.579864 -245.29415)
					(mid 389.949944 -245.29415)
					(end 390.579864 -245.29415)
				)
			)
		)
	)
	(zone
		(layers "B.Cu" "In11.Cu" "In13.Cu" "In15.Cu")
		(hatch none 0.5)
		(connect_pads
			(clearance 0)
		)
		(min_thickness 0.25)
		(keepout
			(tracks not_allowed)
			(vias allowed)
			(pads allowed)
			(copperpour not_allowed)
			(footprints allowed)
		)
		(placement
			(enabled no)
			(sheetname "")
		)
		(fill yes
			(thermal_gap 0.5)
			(thermal_bridge_width 0.5)
			(island_removal_mode 0)
		)
		(polygon
			(pts
				(arc
					(start 399.137124 -426.089826)
					(mid 398.362932 -426.089826)
					(end 399.137124 -426.089826)
				)
			)
		)
	)
	(zone
		(layers "B.Cu" "In11.Cu" "In13.Cu" "In15.Cu")
		(hatch none 0.5)
		(connect_pads
			(clearance 0)
		)
		(min_thickness 0.25)
		(keepout
			(tracks not_allowed)
			(vias allowed)
			(pads allowed)
			(copperpour not_allowed)
			(footprints allowed)
		)
		(placement
			(enabled no)
			(sheetname "")
		)
		(fill yes
			(thermal_gap 0.5)
			(thermal_bridge_width 0.5)
			(island_removal_mode 0)
		)
		(polygon
			(pts
				(arc
					(start 391.349738 -270.036036)
					(mid 390.719818 -270.036036)
					(end 391.349738 -270.036036)
				)
			)
		)
	)
	(zone
		(layers "B.Cu" "In11.Cu" "In13.Cu" "In15.Cu")
		(hatch none 0.5)
		(connect_pads
			(clearance 0)
		)
		(min_thickness 0.25)
		(keepout
			(tracks not_allowed)
			(vias allowed)
			(pads allowed)
			(copperpour not_allowed)
			(footprints allowed)
		)
		(placement
			(enabled no)
			(sheetname "")
		)
		(fill yes
			(thermal_gap 0.5)
			(thermal_bridge_width 0.5)
			(island_removal_mode 0)
		)
		(polygon
			(pts
				(arc
					(start 331.195934 -271.656048)
					(mid 330.566014 -271.656048)
					(end 331.195934 -271.656048)
				)
			)
		)
	)
	(zone
		(layers "B.Cu" "In11.Cu" "In13.Cu" "In15.Cu")
		(hatch none 0.5)
		(connect_pads
			(clearance 0)
		)
		(min_thickness 0.25)
		(keepout
			(tracks not_allowed)
			(vias allowed)
			(pads allowed)
			(copperpour not_allowed)
			(footprints allowed)
		)
		(placement
			(enabled no)
			(sheetname "")
		)
		(fill yes
			(thermal_gap 0.5)
			(thermal_bridge_width 0.5)
			(island_removal_mode 0)
		)
		(polygon
			(pts
				(arc
					(start 391.349738 -276.516084)
					(mid 390.719818 -276.516084)
					(end 391.349738 -276.516084)
				)
			)
		)
	)
	(zone
		(layers "B.Cu" "In11.Cu" "In13.Cu" "In15.Cu")
		(hatch none 0.5)
		(connect_pads
			(clearance 0)
		)
		(min_thickness 0.25)
		(keepout
			(tracks not_allowed)
			(vias allowed)
			(pads allowed)
			(copperpour not_allowed)
			(footprints allowed)
		)
		(placement
			(enabled no)
			(sheetname "")
		)
		(fill yes
			(thermal_gap 0.5)
			(thermal_bridge_width 0.5)
			(island_removal_mode 0)
		)
		(polygon
			(pts
				(arc
					(start 199.03821 -208.38541)
					(mid 198.37019 -208.38541)
					(end 199.03821 -208.38541)
				)
			)
		)
	)
	(zone
		(layers "B.Cu" "In11.Cu" "In13.Cu" "In15.Cu")
		(hatch none 0.5)
		(connect_pads
			(clearance 0)
		)
		(min_thickness 0.25)
		(keepout
			(tracks not_allowed)
			(vias allowed)
			(pads allowed)
			(copperpour not_allowed)
			(footprints allowed)
		)
		(placement
			(enabled no)
			(sheetname "")
		)
		(fill yes
			(thermal_gap 0.5)
			(thermal_bridge_width 0.5)
			(island_removal_mode 0)
		)
		(polygon
			(pts
				(arc
					(start 403.137116 -426.089826)
					(mid 402.362924 -426.089826)
					(end 403.137116 -426.089826)
				)
			)
		)
	)
	(zone
		(layers "B.Cu" "In11.Cu" "In13.Cu" "In15.Cu")
		(hatch none 0.5)
		(connect_pads
			(clearance 0)
		)
		(min_thickness 0.25)
		(keepout
			(tracks not_allowed)
			(vias allowed)
			(pads allowed)
			(copperpour not_allowed)
			(footprints allowed)
		)
		(placement
			(enabled no)
			(sheetname "")
		)
		(fill yes
			(thermal_gap 0.5)
			(thermal_bridge_width 0.5)
			(island_removal_mode 0)
		)
		(polygon
			(pts
				(arc
					(start 331.195934 -284.616144)
					(mid 330.566014 -284.616144)
					(end 331.195934 -284.616144)
				)
			)
		)
	)
	(zone
		(layers "B.Cu" "In11.Cu" "In13.Cu" "In15.Cu")
		(hatch none 0.5)
		(connect_pads
			(clearance 0)
		)
		(min_thickness 0.25)
		(keepout
			(tracks not_allowed)
			(vias allowed)
			(pads allowed)
			(copperpour not_allowed)
			(footprints allowed)
		)
		(placement
			(enabled no)
			(sheetname "")
		)
		(fill yes
			(thermal_gap 0.5)
			(thermal_bridge_width 0.5)
			(island_removal_mode 0)
		)
		(polygon
			(pts
				(arc
					(start 357.986076 -285.42615)
					(mid 357.356156 -285.42615)
					(end 357.986076 -285.42615)
				)
			)
		)
	)
	(zone
		(layers "B.Cu" "In11.Cu" "In13.Cu" "In15.Cu")
		(hatch none 0.5)
		(connect_pads
			(clearance 0)
		)
		(min_thickness 0.25)
		(keepout
			(tracks not_allowed)
			(vias allowed)
			(pads allowed)
			(copperpour not_allowed)
			(footprints allowed)
		)
		(placement
			(enabled no)
			(sheetname "")
		)
		(fill yes
			(thermal_gap 0.5)
			(thermal_bridge_width 0.5)
			(island_removal_mode 0)
		)
		(polygon
			(pts
				(arc
					(start 324.875906 -377.41733)
					(mid 324.207886 -377.41733)
					(end 324.875906 -377.41733)
				)
			)
		)
	)
	(zone
		(layers "B.Cu" "In11.Cu" "In13.Cu" "In15.Cu")
		(hatch none 0.5)
		(connect_pads
			(clearance 0)
		)
		(min_thickness 0.25)
		(keepout
			(tracks not_allowed)
			(vias allowed)
			(pads allowed)
			(copperpour not_allowed)
			(footprints allowed)
		)
		(placement
			(enabled no)
			(sheetname "")
		)
		(fill yes
			(thermal_gap 0.5)
			(thermal_bridge_width 0.5)
			(island_removal_mode 0)
		)
		(polygon
			(pts
				(arc
					(start 330.42606 -232.334054)
					(mid 329.79614 -232.334054)
					(end 330.42606 -232.334054)
				)
			)
		)
	)
	(zone
		(layers "B.Cu" "In11.Cu" "In13.Cu" "In15.Cu")
		(hatch none 0.5)
		(connect_pads
			(clearance 0)
		)
		(min_thickness 0.25)
		(keepout
			(tracks not_allowed)
			(vias allowed)
			(pads allowed)
			(copperpour not_allowed)
			(footprints allowed)
		)
		(placement
			(enabled no)
			(sheetname "")
		)
		(fill yes
			(thermal_gap 0.5)
			(thermal_bridge_width 0.5)
			(island_removal_mode 0)
		)
		(polygon
			(pts
				(arc
					(start 141.999716 -264.366248)
					(mid 141.369796 -264.366248)
					(end 141.999716 -264.366248)
				)
			)
		)
	)
	(zone
		(layers "B.Cu" "In11.Cu" "In13.Cu" "In15.Cu")
		(hatch none 0.5)
		(connect_pads
			(clearance 0)
		)
		(min_thickness 0.25)
		(keepout
			(tracks not_allowed)
			(vias allowed)
			(pads allowed)
			(copperpour not_allowed)
			(footprints allowed)
		)
		(placement
			(enabled no)
			(sheetname "")
		)
		(fill yes
			(thermal_gap 0.5)
			(thermal_bridge_width 0.5)
			(island_removal_mode 0)
		)
		(polygon
			(pts
				(arc
					(start 199.03821 -287.43529)
					(mid 198.37019 -287.43529)
					(end 199.03821 -287.43529)
				)
			)
		)
	)
	(zone
		(layers "B.Cu" "In11.Cu" "In13.Cu" "In15.Cu")
		(hatch none 0.5)
		(connect_pads
			(clearance 0)
		)
		(min_thickness 0.25)
		(keepout
			(tracks not_allowed)
			(vias allowed)
			(pads allowed)
			(copperpour not_allowed)
			(footprints allowed)
		)
		(placement
			(enabled no)
			(sheetname "")
		)
		(fill yes
			(thermal_gap 0.5)
			(thermal_bridge_width 0.5)
			(island_removal_mode 0)
		)
		(polygon
			(pts
				(arc
					(start 344.036904 -427.289976)
					(mid 343.262712 -427.289976)
					(end 344.036904 -427.289976)
				)
			)
		)
	)
	(zone
		(layers "B.Cu" "In11.Cu" "In13.Cu" "In15.Cu")
		(hatch none 0.5)
		(connect_pads
			(clearance 0)
		)
		(min_thickness 0.25)
		(keepout
			(tracks not_allowed)
			(vias allowed)
			(pads allowed)
			(copperpour not_allowed)
			(footprints allowed)
		)
		(placement
			(enabled no)
			(sheetname "")
		)
		(fill yes
			(thermal_gap 0.5)
			(thermal_bridge_width 0.5)
			(island_removal_mode 0)
		)
		(polygon
			(pts
				(arc
					(start 442.87821 -213.484968)
					(mid 442.21019 -213.484968)
					(end 442.87821 -213.484968)
				)
			)
		)
	)
	(zone
		(layers "B.Cu" "In11.Cu" "In13.Cu" "In15.Cu")
		(hatch none 0.5)
		(connect_pads
			(clearance 0)
		)
		(min_thickness 0.25)
		(keepout
			(tracks not_allowed)
			(vias allowed)
			(pads allowed)
			(copperpour not_allowed)
			(footprints allowed)
		)
		(placement
			(enabled no)
			(sheetname "")
		)
		(fill yes
			(thermal_gap 0.5)
			(thermal_bridge_width 0.5)
			(island_removal_mode 0)
		)
		(polygon
			(pts
				(arc
					(start 357.046022 -285.42615)
					(mid 356.416102 -285.42615)
					(end 357.046022 -285.42615)
				)
			)
		)
	)
	(zone
		(layers "B.Cu" "In11.Cu" "In13.Cu" "In15.Cu")
		(hatch none 0.5)
		(connect_pads
			(clearance 0)
		)
		(min_thickness 0.25)
		(keepout
			(tracks not_allowed)
			(vias allowed)
			(pads allowed)
			(copperpour not_allowed)
			(footprints allowed)
		)
		(placement
			(enabled no)
			(sheetname "")
		)
		(fill yes
			(thermal_gap 0.5)
			(thermal_bridge_width 0.5)
			(island_removal_mode 0)
		)
		(polygon
			(pts
				(arc
					(start 446.978278 -279.785064)
					(mid 446.310258 -279.785064)
					(end 446.978278 -279.785064)
				)
			)
		)
	)
	(zone
		(layers "B.Cu" "In11.Cu" "In13.Cu" "In15.Cu")
		(hatch none 0.5)
		(connect_pads
			(clearance 0)
		)
		(min_thickness 0.25)
		(keepout
			(tracks not_allowed)
			(vias allowed)
			(pads allowed)
			(copperpour not_allowed)
			(footprints allowed)
		)
		(placement
			(enabled no)
			(sheetname "")
		)
		(fill yes
			(thermal_gap 0.5)
			(thermal_bridge_width 0.5)
			(island_removal_mode 0)
		)
		(polygon
			(pts
				(arc
					(start 351.876106 -282.996132)
					(mid 351.246186 -282.996132)
					(end 351.876106 -282.996132)
				)
			)
		)
	)
	(zone
		(layers "B.Cu" "In11.Cu" "In13.Cu" "In15.Cu")
		(hatch none 0.5)
		(connect_pads
			(clearance 0)
		)
		(min_thickness 0.25)
		(keepout
			(tracks not_allowed)
			(vias allowed)
			(pads allowed)
			(copperpour not_allowed)
			(footprints allowed)
		)
		(placement
			(enabled no)
			(sheetname "")
		)
		(fill yes
			(thermal_gap 0.5)
			(thermal_bridge_width 0.5)
			(island_removal_mode 0)
		)
		(polygon
			(pts
				(arc
					(start 446.978278 -306.135024)
					(mid 446.310258 -306.135024)
					(end 446.978278 -306.135024)
				)
			)
		)
	)
	(zone
		(layers "B.Cu" "In11.Cu" "In13.Cu" "In15.Cu")
		(hatch none 0.5)
		(connect_pads
			(clearance 0)
		)
		(min_thickness 0.25)
		(keepout
			(tracks not_allowed)
			(vias allowed)
			(pads allowed)
			(copperpour not_allowed)
			(footprints allowed)
		)
		(placement
			(enabled no)
			(sheetname "")
		)
		(fill yes
			(thermal_gap 0.5)
			(thermal_bridge_width 0.5)
			(island_removal_mode 0)
		)
		(polygon
			(pts
				(arc
					(start 194.938142 -253.435358)
					(mid 194.270122 -253.435358)
					(end 194.938142 -253.435358)
				)
			)
		)
	)
	(zone
		(layers "B.Cu" "In11.Cu" "In13.Cu" "In15.Cu")
		(hatch none 0.5)
		(connect_pads
			(clearance 0)
		)
		(min_thickness 0.25)
		(keepout
			(tracks not_allowed)
			(vias allowed)
			(pads allowed)
			(copperpour not_allowed)
			(footprints allowed)
		)
		(placement
			(enabled no)
			(sheetname "")
		)
		(fill yes
			(thermal_gap 0.5)
			(thermal_bridge_width 0.5)
			(island_removal_mode 0)
		)
		(polygon
			(pts
				(arc
					(start 317.036704 -427.089824)
					(mid 316.262512 -427.089824)
					(end 317.036704 -427.089824)
				)
			)
		)
	)
	(zone
		(layers "B.Cu" "In11.Cu" "In13.Cu" "In15.Cu")
		(hatch none 0.5)
		(connect_pads
			(clearance 0)
		)
		(min_thickness 0.25)
		(keepout
			(tracks not_allowed)
			(vias allowed)
			(pads allowed)
			(copperpour not_allowed)
			(footprints allowed)
		)
		(placement
			(enabled no)
			(sheetname "")
		)
		(fill yes
			(thermal_gap 0.5)
			(thermal_bridge_width 0.5)
			(island_removal_mode 0)
		)
		(polygon
			(pts
				(arc
					(start 58.181494 -404.46452)
					(mid 57.513474 -404.46452)
					(end 58.181494 -404.46452)
				)
			)
		)
	)
	(zone
		(layers "B.Cu" "In11.Cu" "In13.Cu" "In15.Cu")
		(hatch none 0.5)
		(connect_pads
			(clearance 0)
		)
		(min_thickness 0.25)
		(keepout
			(tracks not_allowed)
			(vias allowed)
			(pads allowed)
			(copperpour not_allowed)
			(footprints allowed)
		)
		(placement
			(enabled no)
			(sheetname "")
		)
		(fill yes
			(thermal_gap 0.5)
			(thermal_bridge_width 0.5)
			(island_removal_mode 0)
		)
		(polygon
			(pts
				(arc
					(start 199.03821 -197.335394)
					(mid 198.37019 -197.335394)
					(end 199.03821 -197.335394)
				)
			)
		)
	)
	(zone
		(layers "B.Cu" "In11.Cu" "In13.Cu" "In15.Cu")
		(hatch none 0.5)
		(connect_pads
			(clearance 0)
		)
		(min_thickness 0.25)
		(keepout
			(tracks not_allowed)
			(vias allowed)
			(pads allowed)
			(copperpour not_allowed)
			(footprints allowed)
		)
		(placement
			(enabled no)
			(sheetname "")
		)
		(fill yes
			(thermal_gap 0.5)
			(thermal_bridge_width 0.5)
			(island_removal_mode 0)
		)
		(polygon
			(pts
				(arc
					(start 82.785966 -275.706332)
					(mid 82.156046 -275.706332)
					(end 82.785966 -275.706332)
				)
			)
		)
	)
	(zone
		(layers "B.Cu" "In11.Cu" "In13.Cu" "In15.Cu")
		(hatch none 0.5)
		(connect_pads
			(clearance 0)
		)
		(min_thickness 0.25)
		(keepout
			(tracks not_allowed)
			(vias allowed)
			(pads allowed)
			(copperpour not_allowed)
			(footprints allowed)
		)
		(placement
			(enabled no)
			(sheetname "")
		)
		(fill yes
			(thermal_gap 0.5)
			(thermal_bridge_width 0.5)
			(island_removal_mode 0)
		)
		(polygon
			(pts
				(arc
					(start 103.936038 -282.996386)
					(mid 103.306118 -282.996386)
					(end 103.936038 -282.996386)
				)
			)
		)
	)
	(zone
		(layers "B.Cu" "In11.Cu" "In13.Cu" "In15.Cu")
		(hatch none 0.5)
		(connect_pads
			(clearance 0)
		)
		(min_thickness 0.25)
		(keepout
			(tracks not_allowed)
			(vias allowed)
			(pads allowed)
			(copperpour not_allowed)
			(footprints allowed)
		)
		(placement
			(enabled no)
			(sheetname "")
		)
		(fill yes
			(thermal_gap 0.5)
			(thermal_bridge_width 0.5)
			(island_removal_mode 0)
		)
		(polygon
			(pts
				(arc
					(start 199.03821 -304.435256)
					(mid 198.37019 -304.435256)
					(end 199.03821 -304.435256)
				)
			)
		)
	)
	(zone
		(layers "B.Cu" "In11.Cu" "In13.Cu" "In15.Cu")
		(hatch none 0.5)
		(connect_pads
			(clearance 0)
		)
		(min_thickness 0.25)
		(keepout
			(tracks not_allowed)
			(vias allowed)
			(pads allowed)
			(copperpour not_allowed)
			(footprints allowed)
		)
		(placement
			(enabled no)
			(sheetname "")
		)
		(fill yes
			(thermal_gap 0.5)
			(thermal_bridge_width 0.5)
			(island_removal_mode 0)
		)
		(polygon
			(pts
				(arc
					(start 442.87821 -222.834962)
					(mid 442.21019 -222.834962)
					(end 442.87821 -222.834962)
				)
			)
		)
	)
	(zone
		(layers "B.Cu" "In11.Cu" "In13.Cu" "In15.Cu")
		(hatch none 0.5)
		(connect_pads
			(clearance 0)
		)
		(min_thickness 0.25)
		(keepout
			(tracks not_allowed)
			(vias allowed)
			(pads allowed)
			(copperpour not_allowed)
			(footprints allowed)
		)
		(placement
			(enabled no)
			(sheetname "")
		)
		(fill yes
			(thermal_gap 0.5)
			(thermal_bridge_width 0.5)
			(island_removal_mode 0)
		)
		(polygon
			(pts
				(arc
					(start 446.978278 -312.935112)
					(mid 446.310258 -312.935112)
					(end 446.978278 -312.935112)
				)
			)
		)
	)
	(zone
		(layers "B.Cu" "In11.Cu" "In13.Cu" "In15.Cu")
		(hatch none 0.5)
		(connect_pads
			(clearance 0)
		)
		(min_thickness 0.25)
		(keepout
			(tracks not_allowed)
			(vias allowed)
			(pads allowed)
			(copperpour not_allowed)
			(footprints allowed)
		)
		(placement
			(enabled no)
			(sheetname "")
		)
		(fill yes
			(thermal_gap 0.5)
			(thermal_bridge_width 0.5)
			(island_removal_mode 0)
		)
		(polygon
			(pts
				(arc
					(start 101.755956 -242.864386)
					(mid 101.126036 -242.864386)
					(end 101.755956 -242.864386)
				)
			)
		)
	)
	(zone
		(layers "B.Cu" "In11.Cu" "In13.Cu" "In15.Cu")
		(hatch none 0.5)
		(connect_pads
			(clearance 0)
		)
		(min_thickness 0.25)
		(keepout
			(tracks not_allowed)
			(vias allowed)
			(pads allowed)
			(copperpour not_allowed)
			(footprints allowed)
		)
		(placement
			(enabled no)
			(sheetname "")
		)
		(fill yes
			(thermal_gap 0.5)
			(thermal_bridge_width 0.5)
			(island_removal_mode 0)
		)
		(polygon
			(pts
				(arc
					(start 363.619796 -285.42615)
					(mid 362.989876 -285.42615)
					(end 363.619796 -285.42615)
				)
			)
		)
	)
	(zone
		(layers "B.Cu" "In11.Cu" "In13.Cu" "In15.Cu")
		(hatch none 0.5)
		(connect_pads
			(clearance 0)
		)
		(min_thickness 0.25)
		(keepout
			(tracks not_allowed)
			(vias allowed)
			(pads allowed)
			(copperpour not_allowed)
			(footprints allowed)
		)
		(placement
			(enabled no)
			(sheetname "")
		)
		(fill yes
			(thermal_gap 0.5)
			(thermal_bridge_width 0.5)
			(island_removal_mode 0)
		)
		(polygon
			(pts
				(arc
					(start 123.669806 -281.376374)
					(mid 123.039886 -281.376374)
					(end 123.669806 -281.376374)
				)
			)
		)
	)
	(zone
		(layers "B.Cu" "In11.Cu" "In13.Cu" "In15.Cu")
		(hatch none 0.5)
		(connect_pads
			(clearance 0)
		)
		(min_thickness 0.25)
		(keepout
			(tracks not_allowed)
			(vias allowed)
			(pads allowed)
			(copperpour not_allowed)
			(footprints allowed)
		)
		(placement
			(enabled no)
			(sheetname "")
		)
		(fill yes
			(thermal_gap 0.5)
			(thermal_bridge_width 0.5)
			(island_removal_mode 0)
		)
		(polygon
			(pts
				(arc
					(start 194.938142 -248.335292)
					(mid 194.270122 -248.335292)
					(end 194.938142 -248.335292)
				)
			)
		)
	)
	(zone
		(layers "B.Cu" "In11.Cu" "In13.Cu" "In15.Cu")
		(hatch none 0.5)
		(connect_pads
			(clearance 0)
		)
		(min_thickness 0.25)
		(keepout
			(tracks not_allowed)
			(vias allowed)
			(pads allowed)
			(copperpour not_allowed)
			(footprints allowed)
		)
		(placement
			(enabled no)
			(sheetname "")
		)
		(fill yes
			(thermal_gap 0.5)
			(thermal_bridge_width 0.5)
			(island_removal_mode 0)
		)
		(polygon
			(pts
				(arc
					(start 123.606306 -388.774432)
					(mid 122.976386 -388.774432)
					(end 123.606306 -388.774432)
				)
			)
		)
	)
	(zone
		(layers "B.Cu" "In11.Cu" "In13.Cu" "In15.Cu")
		(hatch none 0.5)
		(connect_pads
			(clearance 0)
		)
		(min_thickness 0.25)
		(keepout
			(tracks not_allowed)
			(vias allowed)
			(pads allowed)
			(copperpour not_allowed)
			(footprints allowed)
		)
		(placement
			(enabled no)
			(sheetname "")
		)
		(fill yes
			(thermal_gap 0.5)
			(thermal_bridge_width 0.5)
			(island_removal_mode 0)
		)
		(polygon
			(pts
				(arc
					(start 104.576118 -239.624362)
					(mid 103.946198 -239.624362)
					(end 104.576118 -239.624362)
				)
			)
		)
	)
	(zone
		(layers "B.Cu" "In11.Cu" "In13.Cu" "In15.Cu")
		(hatch none 0.5)
		(connect_pads
			(clearance 0)
		)
		(min_thickness 0.25)
		(keepout
			(tracks not_allowed)
			(vias allowed)
			(pads allowed)
			(copperpour not_allowed)
			(footprints allowed)
		)
		(placement
			(enabled no)
			(sheetname "")
		)
		(fill yes
			(thermal_gap 0.5)
			(thermal_bridge_width 0.5)
			(island_removal_mode 0)
		)
		(polygon
			(pts
				(arc
					(start 382.006094 -397.156432)
					(mid 381.376174 -397.156432)
					(end 382.006094 -397.156432)
				)
			)
		)
	)
	(zone
		(layers "B.Cu" "In11.Cu" "In13.Cu" "In15.Cu")
		(hatch none 0.5)
		(connect_pads
			(clearance 0)
		)
		(min_thickness 0.25)
		(keepout
			(tracks not_allowed)
			(vias allowed)
			(pads allowed)
			(copperpour not_allowed)
			(footprints allowed)
		)
		(placement
			(enabled no)
			(sheetname "")
		)
		(fill yes
			(thermal_gap 0.5)
			(thermal_bridge_width 0.5)
			(island_removal_mode 0)
		)
		(polygon
			(pts
				(arc
					(start 194.938142 -233.885232)
					(mid 194.270122 -233.885232)
					(end 194.938142 -233.885232)
				)
			)
		)
	)
	(zone
		(layers "B.Cu" "In11.Cu" "In13.Cu" "In15.Cu")
		(hatch none 0.5)
		(connect_pads
			(clearance 0)
		)
		(min_thickness 0.25)
		(keepout
			(tracks not_allowed)
			(vias allowed)
			(pads allowed)
			(copperpour not_allowed)
			(footprints allowed)
		)
		(placement
			(enabled no)
			(sheetname "")
		)
		(fill yes
			(thermal_gap 0.5)
			(thermal_bridge_width 0.5)
			(island_removal_mode 0)
		)
		(polygon
			(pts
				(arc
					(start 199.03821 -219.435426)
					(mid 198.37019 -219.435426)
					(end 199.03821 -219.435426)
				)
			)
		)
	)
	(zone
		(layers "B.Cu" "In11.Cu" "In13.Cu" "In15.Cu")
		(hatch none 0.5)
		(connect_pads
			(clearance 0)
		)
		(min_thickness 0.25)
		(keepout
			(tracks not_allowed)
			(vias allowed)
			(pads allowed)
			(copperpour not_allowed)
			(footprints allowed)
		)
		(placement
			(enabled no)
			(sheetname "")
		)
		(fill yes
			(thermal_gap 0.5)
			(thermal_bridge_width 0.5)
			(island_removal_mode 0)
		)
		(polygon
			(pts
				(arc
					(start 446.978278 -294.235124)
					(mid 446.310258 -294.235124)
					(end 446.978278 -294.235124)
				)
			)
		)
	)
	(zone
		(layers "B.Cu" "In11.Cu" "In13.Cu" "In15.Cu")
		(hatch none 0.5)
		(connect_pads
			(clearance 0)
		)
		(min_thickness 0.25)
		(keepout
			(tracks not_allowed)
			(vias allowed)
			(pads allowed)
			(copperpour not_allowed)
			(footprints allowed)
		)
		(placement
			(enabled no)
			(sheetname "")
		)
		(fill yes
			(thermal_gap 0.5)
			(thermal_bridge_width 0.5)
			(island_removal_mode 0)
		)
		(polygon
			(pts
				(arc
					(start 75.697334 -404.46452)
					(mid 75.029314 -404.46452)
					(end 75.697334 -404.46452)
				)
			)
		)
	)
	(zone
		(layers "B.Cu" "In11.Cu" "In13.Cu" "In15.Cu")
		(hatch none 0.5)
		(connect_pads
			(clearance 0)
		)
		(min_thickness 0.25)
		(keepout
			(tracks not_allowed)
			(vias allowed)
			(pads allowed)
			(copperpour not_allowed)
			(footprints allowed)
		)
		(placement
			(enabled no)
			(sheetname "")
		)
		(fill yes
			(thermal_gap 0.5)
			(thermal_bridge_width 0.5)
			(island_removal_mode 0)
		)
		(polygon
			(pts
				(arc
					(start 401.13712 -427.089824)
					(mid 400.362928 -427.089824)
					(end 401.13712 -427.089824)
				)
			)
		)
	)
	(zone
		(layers "B.Cu" "In11.Cu" "In13.Cu" "In15.Cu")
		(hatch none 0.5)
		(connect_pads
			(clearance 0)
		)
		(min_thickness 0.25)
		(keepout
			(tracks not_allowed)
			(vias allowed)
			(pads allowed)
			(copperpour not_allowed)
			(footprints allowed)
		)
		(placement
			(enabled no)
			(sheetname "")
		)
		(fill yes
			(thermal_gap 0.5)
			(thermal_bridge_width 0.5)
			(island_removal_mode 0)
		)
		(polygon
			(pts
				(arc
					(start 142.93977 -283.806392)
					(mid 142.30985 -283.806392)
					(end 142.93977 -283.806392)
				)
			)
		)
	)
	(zone
		(layers "B.Cu" "In11.Cu" "In13.Cu" "In15.Cu")
		(hatch none 0.5)
		(connect_pads
			(clearance 0)
		)
		(min_thickness 0.25)
		(keepout
			(tracks not_allowed)
			(vias allowed)
			(pads allowed)
			(copperpour not_allowed)
			(footprints allowed)
		)
		(placement
			(enabled no)
			(sheetname "")
		)
		(fill yes
			(thermal_gap 0.5)
			(thermal_bridge_width 0.5)
			(island_removal_mode 0)
		)
		(polygon
			(pts
				(arc
					(start 61.244734 -404.46452)
					(mid 60.576714 -404.46452)
					(end 61.244734 -404.46452)
				)
			)
		)
	)
	(zone
		(layers "B.Cu" "In11.Cu" "In13.Cu" "In15.Cu")
		(hatch none 0.5)
		(connect_pads
			(clearance 0)
		)
		(min_thickness 0.25)
		(keepout
			(tracks not_allowed)
			(vias allowed)
			(pads allowed)
			(copperpour not_allowed)
			(footprints allowed)
		)
		(placement
			(enabled no)
			(sheetname "")
		)
		(fill yes
			(thermal_gap 0.5)
			(thermal_bridge_width 0.5)
			(island_removal_mode 0)
		)
		(polygon
			(pts
				(arc
					(start 389.469884 -278.136096)
					(mid 388.839964 -278.136096)
					(end 389.469884 -278.136096)
				)
			)
		)
	)
	(zone
		(layers "B.Cu" "In11.Cu" "In13.Cu" "In15.Cu")
		(hatch none 0.5)
		(connect_pads
			(clearance 0)
		)
		(min_thickness 0.25)
		(keepout
			(tracks not_allowed)
			(vias allowed)
			(pads allowed)
			(copperpour not_allowed)
			(footprints allowed)
		)
		(placement
			(enabled no)
			(sheetname "")
		)
		(fill yes
			(thermal_gap 0.5)
			(thermal_bridge_width 0.5)
			(island_removal_mode 0)
		)
		(polygon
			(pts
				(arc
					(start 51.191414 -404.46452)
					(mid 50.523394 -404.46452)
					(end 51.191414 -404.46452)
				)
			)
		)
	)
	(zone
		(layers "B.Cu" "In11.Cu" "In13.Cu" "In15.Cu")
		(hatch none 0.5)
		(connect_pads
			(clearance 0)
		)
		(min_thickness 0.25)
		(keepout
			(tracks not_allowed)
			(vias allowed)
			(pads allowed)
			(copperpour not_allowed)
			(footprints allowed)
		)
		(placement
			(enabled no)
			(sheetname "")
		)
		(fill yes
			(thermal_gap 0.5)
			(thermal_bridge_width 0.5)
			(island_removal_mode 0)
		)
		(polygon
			(pts
				(arc
					(start 199.03821 -223.685354)
					(mid 198.37019 -223.685354)
					(end 199.03821 -223.685354)
				)
			)
		)
	)
	(zone
		(layers "B.Cu" "In11.Cu" "In13.Cu" "In15.Cu")
		(hatch none 0.5)
		(connect_pads
			(clearance 0)
		)
		(min_thickness 0.25)
		(keepout
			(tracks not_allowed)
			(vias allowed)
			(pads allowed)
			(copperpour not_allowed)
			(footprints allowed)
		)
		(placement
			(enabled no)
			(sheetname "")
		)
		(fill yes
			(thermal_gap 0.5)
			(thermal_bridge_width 0.5)
			(island_removal_mode 0)
		)
		(polygon
			(pts
				(arc
					(start 51.019964 -371.49913)
					(mid 50.351944 -371.49913)
					(end 51.019964 -371.49913)
				)
			)
		)
	)
	(zone
		(layers "B.Cu" "In11.Cu" "In13.Cu" "In15.Cu")
		(hatch none 0.5)
		(connect_pads
			(clearance 0)
		)
		(min_thickness 0.25)
		(keepout
			(tracks not_allowed)
			(vias allowed)
			(pads allowed)
			(copperpour not_allowed)
			(footprints allowed)
		)
		(placement
			(enabled no)
			(sheetname "")
		)
		(fill yes
			(thermal_gap 0.5)
			(thermal_bridge_width 0.5)
			(island_removal_mode 0)
		)
		(polygon
			(pts
				(arc
					(start 81.076038 -225.044508)
					(mid 80.446118 -225.044508)
					(end 81.076038 -225.044508)
				)
			)
		)
	)
	(zone
		(layers "B.Cu" "In11.Cu" "In13.Cu" "In15.Cu")
		(hatch none 0.5)
		(connect_pads
			(clearance 0)
		)
		(min_thickness 0.25)
		(keepout
			(tracks not_allowed)
			(vias allowed)
			(pads allowed)
			(copperpour not_allowed)
			(footprints allowed)
		)
		(placement
			(enabled no)
			(sheetname "")
		)
		(fill yes
			(thermal_gap 0.5)
			(thermal_bridge_width 0.5)
			(island_removal_mode 0)
		)
		(polygon
			(pts
				(arc
					(start 83.255866 -261.93623)
					(mid 82.625946 -261.93623)
					(end 83.255866 -261.93623)
				)
			)
		)
	)
	(zone
		(layers "B.Cu" "In11.Cu" "In13.Cu" "In15.Cu")
		(hatch none 0.5)
		(connect_pads
			(clearance 0)
		)
		(min_thickness 0.25)
		(keepout
			(tracks not_allowed)
			(vias allowed)
			(pads allowed)
			(copperpour not_allowed)
			(footprints allowed)
		)
		(placement
			(enabled no)
			(sheetname "")
		)
		(fill yes
			(thermal_gap 0.5)
			(thermal_bridge_width 0.5)
			(island_removal_mode 0)
		)
		(polygon
			(pts
				(arc
					(start 83.255866 -287.856422)
					(mid 82.625946 -287.856422)
					(end 83.255866 -287.856422)
				)
			)
		)
	)
	(zone
		(layers "B.Cu" "In11.Cu" "In13.Cu" "In15.Cu")
		(hatch none 0.5)
		(connect_pads
			(clearance 0)
		)
		(min_thickness 0.25)
		(keepout
			(tracks not_allowed)
			(vias allowed)
			(pads allowed)
			(copperpour not_allowed)
			(footprints allowed)
		)
		(placement
			(enabled no)
			(sheetname "")
		)
		(fill yes
			(thermal_gap 0.5)
			(thermal_bridge_width 0.5)
			(island_removal_mode 0)
		)
		(polygon
			(pts
				(arc
					(start 442.87821 -243.234972)
					(mid 442.21019 -243.234972)
					(end 442.87821 -243.234972)
				)
			)
		)
	)
	(zone
		(layers "B.Cu" "In11.Cu" "In13.Cu" "In15.Cu")
		(hatch none 0.5)
		(connect_pads
			(clearance 0)
		)
		(min_thickness 0.25)
		(keepout
			(tracks not_allowed)
			(vias allowed)
			(pads allowed)
			(copperpour not_allowed)
			(footprints allowed)
		)
		(placement
			(enabled no)
			(sheetname "")
		)
		(fill yes
			(thermal_gap 0.5)
			(thermal_bridge_width 0.5)
			(island_removal_mode 0)
		)
		(polygon
			(pts
				(arc
					(start 446.978278 -284.88513)
					(mid 446.310258 -284.88513)
					(end 446.978278 -284.88513)
				)
			)
		)
	)
	(zone
		(layers "B.Cu" "In11.Cu" "In13.Cu" "In15.Cu")
		(hatch none 0.5)
		(connect_pads
			(clearance 0)
		)
		(min_thickness 0.25)
		(keepout
			(tracks not_allowed)
			(vias allowed)
			(pads allowed)
			(copperpour not_allowed)
			(footprints allowed)
		)
		(placement
			(enabled no)
			(sheetname "")
		)
		(fill yes
			(thermal_gap 0.5)
			(thermal_bridge_width 0.5)
			(island_removal_mode 0)
		)
		(polygon
			(pts
				(arc
					(start 81.376012 -286.23641)
					(mid 80.746092 -286.23641)
					(end 81.376012 -286.23641)
				)
			)
		)
	)
	(zone
		(layers "B.Cu" "In11.Cu" "In13.Cu" "In15.Cu")
		(hatch none 0.5)
		(connect_pads
			(clearance 0)
		)
		(min_thickness 0.25)
		(keepout
			(tracks not_allowed)
			(vias allowed)
			(pads allowed)
			(copperpour not_allowed)
			(footprints allowed)
		)
		(placement
			(enabled no)
			(sheetname "")
		)
		(fill yes
			(thermal_gap 0.5)
			(thermal_bridge_width 0.5)
			(island_removal_mode 0)
		)
		(polygon
			(pts
				(arc
					(start 143.109696 -225.044508)
					(mid 142.479776 -225.044508)
					(end 143.109696 -225.044508)
				)
			)
		)
	)
	(zone
		(layers "B.Cu" "In11.Cu" "In13.Cu" "In15.Cu")
		(hatch none 0.5)
		(connect_pads
			(clearance 0)
		)
		(min_thickness 0.25)
		(keepout
			(tracks not_allowed)
			(vias allowed)
			(pads allowed)
			(copperpour not_allowed)
			(footprints allowed)
		)
		(placement
			(enabled no)
			(sheetname "")
		)
		(fill yes
			(thermal_gap 0.5)
			(thermal_bridge_width 0.5)
			(island_removal_mode 0)
		)
		(polygon
			(pts
				(arc
					(start 330.42606 -237.19409)
					(mid 329.79614 -237.19409)
					(end 330.42606 -237.19409)
				)
			)
		)
	)
	(zone
		(layers "B.Cu" "In11.Cu" "In13.Cu" "In15.Cu")
		(hatch none 0.5)
		(connect_pads
			(clearance 0)
		)
		(min_thickness 0.25)
		(keepout
			(tracks not_allowed)
			(vias allowed)
			(pads allowed)
			(copperpour not_allowed)
			(footprints allowed)
		)
		(placement
			(enabled no)
			(sheetname "")
		)
		(fill yes
			(thermal_gap 0.5)
			(thermal_bridge_width 0.5)
			(island_removal_mode 0)
		)
		(polygon
			(pts
				(arc
					(start 315.528706 -377.41733)
					(mid 314.860686 -377.41733)
					(end 315.528706 -377.41733)
				)
			)
		)
	)
	(zone
		(layers "B.Cu" "In11.Cu" "In13.Cu" "In15.Cu")
		(hatch none 0.5)
		(connect_pads
			(clearance 0)
		)
		(min_thickness 0.25)
		(keepout
			(tracks not_allowed)
			(vias allowed)
			(pads allowed)
			(copperpour not_allowed)
			(footprints allowed)
		)
		(placement
			(enabled no)
			(sheetname "")
		)
		(fill yes
			(thermal_gap 0.5)
			(thermal_bridge_width 0.5)
			(island_removal_mode 0)
		)
		(polygon
			(pts
				(arc
					(start 58.665364 -369.03533)
					(mid 57.997344 -369.03533)
					(end 58.665364 -369.03533)
				)
			)
		)
	)
	(zone
		(layers "B.Cu" "In11.Cu" "In13.Cu" "In15.Cu")
		(hatch none 0.5)
		(connect_pads
			(clearance 0)
		)
		(min_thickness 0.25)
		(keepout
			(tracks not_allowed)
			(vias allowed)
			(pads allowed)
			(copperpour not_allowed)
			(footprints allowed)
		)
		(placement
			(enabled no)
			(sheetname "")
		)
		(fill yes
			(thermal_gap 0.5)
			(thermal_bridge_width 0.5)
			(island_removal_mode 0)
		)
		(polygon
			(pts
				(arc
					(start 158.933896 -386.003292)
					(mid 158.303976 -386.003292)
					(end 158.933896 -386.003292)
				)
			)
		)
	)
	(zone
		(layers "B.Cu" "In11.Cu" "In13.Cu" "In15.Cu")
		(hatch none 0.5)
		(connect_pads
			(clearance 0)
		)
		(min_thickness 0.25)
		(keepout
			(tracks not_allowed)
			(vias allowed)
			(pads allowed)
			(copperpour not_allowed)
			(footprints allowed)
		)
		(placement
			(enabled no)
			(sheetname "")
		)
		(fill yes
			(thermal_gap 0.5)
			(thermal_bridge_width 0.5)
			(island_removal_mode 0)
		)
		(polygon
			(pts
				(arc
					(start 25.486106 -241.535204)
					(mid 24.818086 -241.535204)
					(end 25.486106 -241.535204)
				)
			)
		)
	)
	(zone
		(layers "B.Cu" "In11.Cu" "In13.Cu" "In15.Cu")
		(hatch none 0.5)
		(connect_pads
			(clearance 0)
		)
		(min_thickness 0.25)
		(keepout
			(tracks not_allowed)
			(vias allowed)
			(pads allowed)
			(copperpour not_allowed)
			(footprints allowed)
		)
		(placement
			(enabled no)
			(sheetname "")
		)
		(fill yes
			(thermal_gap 0.5)
			(thermal_bridge_width 0.5)
			(island_removal_mode 0)
		)
		(polygon
			(pts
				(arc
					(start 442.87821 -285.735014)
					(mid 442.21019 -285.735014)
					(end 442.87821 -285.735014)
				)
			)
		)
	)
	(zone
		(layers "B.Cu" "In11.Cu" "In13.Cu" "In15.Cu")
		(hatch none 0.5)
		(connect_pads
			(clearance 0)
		)
		(min_thickness 0.25)
		(keepout
			(tracks not_allowed)
			(vias allowed)
			(pads allowed)
			(copperpour not_allowed)
			(footprints allowed)
		)
		(placement
			(enabled no)
			(sheetname "")
		)
		(fill yes
			(thermal_gap 0.5)
			(thermal_bridge_width 0.5)
			(island_removal_mode 0)
		)
		(polygon
			(pts
				(arc
					(start 29.586174 -290.835334)
					(mid 28.918154 -290.835334)
					(end 29.586174 -290.835334)
				)
			)
		)
	)
	(zone
		(layers "B.Cu" "In11.Cu" "In13.Cu" "In15.Cu")
		(hatch none 0.5)
		(connect_pads
			(clearance 0)
		)
		(min_thickness 0.25)
		(keepout
			(tracks not_allowed)
			(vias allowed)
			(pads allowed)
			(copperpour not_allowed)
			(footprints allowed)
		)
		(placement
			(enabled no)
			(sheetname "")
		)
		(fill yes
			(thermal_gap 0.5)
			(thermal_bridge_width 0.5)
			(island_removal_mode 0)
		)
		(polygon
			(pts
				(arc
					(start 442.87821 -238.985044)
					(mid 442.21019 -238.985044)
					(end 442.87821 -238.985044)
				)
			)
		)
	)
	(zone
		(layers "B.Cu" "In11.Cu" "In13.Cu" "In15.Cu")
		(hatch none 0.5)
		(connect_pads
			(clearance 0)
		)
		(min_thickness 0.25)
		(keepout
			(tracks not_allowed)
			(vias allowed)
			(pads allowed)
			(copperpour not_allowed)
			(footprints allowed)
		)
		(placement
			(enabled no)
			(sheetname "")
		)
		(fill yes
			(thermal_gap 0.5)
			(thermal_bridge_width 0.5)
			(island_removal_mode 0)
		)
		(polygon
			(pts
				(arc
					(start 141.229842 -247.724422)
					(mid 140.599922 -247.724422)
					(end 141.229842 -247.724422)
				)
			)
		)
	)
	(zone
		(layers "B.Cu" "In11.Cu" "In13.Cu" "In15.Cu")
		(hatch none 0.5)
		(connect_pads
			(clearance 0)
		)
		(min_thickness 0.25)
		(keepout
			(tracks not_allowed)
			(vias allowed)
			(pads allowed)
			(copperpour not_allowed)
			(footprints allowed)
		)
		(placement
			(enabled no)
			(sheetname "")
		)
		(fill yes
			(thermal_gap 0.5)
			(thermal_bridge_width 0.5)
			(island_removal_mode 0)
		)
		(polygon
			(pts
				(arc
					(start 391.049764 -229.904036)
					(mid 390.419844 -229.904036)
					(end 391.049764 -229.904036)
				)
			)
		)
	)
	(zone
		(layers "B.Cu" "In11.Cu" "In13.Cu" "In15.Cu")
		(hatch none 0.5)
		(connect_pads
			(clearance 0)
		)
		(min_thickness 0.25)
		(keepout
			(tracks not_allowed)
			(vias allowed)
			(pads allowed)
			(copperpour not_allowed)
			(footprints allowed)
		)
		(placement
			(enabled no)
			(sheetname "")
		)
		(fill yes
			(thermal_gap 0.5)
			(thermal_bridge_width 0.5)
			(island_removal_mode 0)
		)
		(polygon
			(pts
				(arc
					(start 143.40967 -281.376374)
					(mid 142.77975 -281.376374)
					(end 143.40967 -281.376374)
				)
			)
		)
	)
	(zone
		(layers "B.Cu" "In11.Cu" "In13.Cu" "In15.Cu")
		(hatch none 0.5)
		(connect_pads
			(clearance 0)
		)
		(min_thickness 0.25)
		(keepout
			(tracks not_allowed)
			(vias allowed)
			(pads allowed)
			(copperpour not_allowed)
			(footprints allowed)
		)
		(placement
			(enabled no)
			(sheetname "")
		)
		(fill yes
			(thermal_gap 0.5)
			(thermal_bridge_width 0.5)
			(island_removal_mode 0)
		)
		(polygon
			(pts
				(arc
					(start 66.106294 -388.774432)
					(mid 65.476374 -388.774432)
					(end 66.106294 -388.774432)
				)
			)
		)
	)
	(zone
		(layers "B.Cu" "In11.Cu" "In13.Cu" "In15.Cu")
		(hatch none 0.5)
		(connect_pads
			(clearance 0)
		)
		(min_thickness 0.25)
		(keepout
			(tracks not_allowed)
			(vias allowed)
			(pads allowed)
			(copperpour not_allowed)
			(footprints allowed)
		)
		(placement
			(enabled no)
			(sheetname "")
		)
		(fill yes
			(thermal_gap 0.5)
			(thermal_bridge_width 0.5)
			(island_removal_mode 0)
		)
		(polygon
			(pts
				(arc
					(start 63.036958 -422.489884)
					(mid 62.262766 -422.489884)
					(end 63.036958 -422.489884)
				)
			)
		)
	)
	(zone
		(layers "B.Cu" "In11.Cu" "In13.Cu" "In15.Cu")
		(hatch none 0.5)
		(connect_pads
			(clearance 0)
		)
		(min_thickness 0.25)
		(keepout
			(tracks not_allowed)
			(vias allowed)
			(pads allowed)
			(copperpour not_allowed)
			(footprints allowed)
		)
		(placement
			(enabled no)
			(sheetname "")
		)
		(fill yes
			(thermal_gap 0.5)
			(thermal_bridge_width 0.5)
			(island_removal_mode 0)
		)
		(polygon
			(pts
				(arc
					(start 121.60631 -389.467344)
					(mid 120.97639 -389.467344)
					(end 121.60631 -389.467344)
				)
			)
		)
	)
	(zone
		(layers "B.Cu" "In11.Cu" "In13.Cu" "In15.Cu")
		(hatch none 0.5)
		(connect_pads
			(clearance 0)
		)
		(min_thickness 0.25)
		(keepout
			(tracks not_allowed)
			(vias allowed)
			(pads allowed)
			(copperpour not_allowed)
			(footprints allowed)
		)
		(placement
			(enabled no)
			(sheetname "")
		)
		(fill yes
			(thermal_gap 0.5)
			(thermal_bridge_width 0.5)
			(island_removal_mode 0)
		)
		(polygon
			(pts
				(arc
					(start 374.429782 -281.37612)
					(mid 373.799862 -281.37612)
					(end 374.429782 -281.37612)
				)
			)
		)
	)
	(zone
		(layers "B.Cu" "In11.Cu" "In13.Cu" "In15.Cu")
		(hatch none 0.5)
		(connect_pads
			(clearance 0)
		)
		(min_thickness 0.25)
		(keepout
			(tracks not_allowed)
			(vias allowed)
			(pads allowed)
			(copperpour not_allowed)
			(footprints allowed)
		)
		(placement
			(enabled no)
			(sheetname "")
		)
		(fill yes
			(thermal_gap 0.5)
			(thermal_bridge_width 0.5)
			(island_removal_mode 0)
		)
		(polygon
			(pts
				(arc
					(start 446.978278 -313.784996)
					(mid 446.310258 -313.784996)
					(end 446.978278 -313.784996)
				)
			)
		)
	)
	(zone
		(layers "B.Cu" "In11.Cu" "In13.Cu" "In15.Cu")
		(hatch none 0.5)
		(connect_pads
			(clearance 0)
		)
		(min_thickness 0.25)
		(keepout
			(tracks not_allowed)
			(vias allowed)
			(pads allowed)
			(copperpour not_allowed)
			(footprints allowed)
		)
		(placement
			(enabled no)
			(sheetname "")
		)
		(fill yes
			(thermal_gap 0.5)
			(thermal_bridge_width 0.5)
			(island_removal_mode 0)
		)
		(polygon
			(pts
				(arc
					(start 390.879838 -267.606018)
					(mid 390.249918 -267.606018)
					(end 390.879838 -267.606018)
				)
			)
		)
	)
	(zone
		(layers "B.Cu" "In11.Cu" "In13.Cu" "In15.Cu")
		(hatch none 0.5)
		(connect_pads
			(clearance 0)
		)
		(min_thickness 0.25)
		(keepout
			(tracks not_allowed)
			(vias allowed)
			(pads allowed)
			(copperpour not_allowed)
			(footprints allowed)
		)
		(placement
			(enabled no)
			(sheetname "")
		)
		(fill yes
			(thermal_gap 0.5)
			(thermal_bridge_width 0.5)
			(island_removal_mode 0)
		)
		(polygon
			(pts
				(arc
					(start 349.056198 -282.996132)
					(mid 348.426278 -282.996132)
					(end 349.056198 -282.996132)
				)
			)
		)
	)
	(zone
		(layers "B.Cu" "In11.Cu" "In13.Cu" "In15.Cu")
		(hatch none 0.5)
		(connect_pads
			(clearance 0)
		)
		(min_thickness 0.25)
		(keepout
			(tracks not_allowed)
			(vias allowed)
			(pads allowed)
			(copperpour not_allowed)
			(footprints allowed)
		)
		(placement
			(enabled no)
			(sheetname "")
		)
		(fill yes
			(thermal_gap 0.5)
			(thermal_bridge_width 0.5)
			(island_removal_mode 0)
		)
		(polygon
			(pts
				(arc
					(start 194.938142 -201.585322)
					(mid 194.270122 -201.585322)
					(end 194.938142 -201.585322)
				)
			)
		)
	)
	(zone
		(layers "B.Cu" "In11.Cu" "In13.Cu" "In15.Cu")
		(hatch none 0.5)
		(connect_pads
			(clearance 0)
		)
		(min_thickness 0.25)
		(keepout
			(tracks not_allowed)
			(vias allowed)
			(pads allowed)
			(copperpour not_allowed)
			(footprints allowed)
		)
		(placement
			(enabled no)
			(sheetname "")
		)
		(fill yes
			(thermal_gap 0.5)
			(thermal_bridge_width 0.5)
			(island_removal_mode 0)
		)
		(polygon
			(pts
				(arc
					(start 330.726034 -274.086066)
					(mid 330.096114 -274.086066)
					(end 330.726034 -274.086066)
				)
			)
		)
	)
	(zone
		(layers "B.Cu" "In11.Cu" "In13.Cu" "In15.Cu")
		(hatch none 0.5)
		(connect_pads
			(clearance 0)
		)
		(min_thickness 0.25)
		(keepout
			(tracks not_allowed)
			(vias allowed)
			(pads allowed)
			(copperpour not_allowed)
			(footprints allowed)
		)
		(placement
			(enabled no)
			(sheetname "")
		)
		(fill yes
			(thermal_gap 0.5)
			(thermal_bridge_width 0.5)
			(island_removal_mode 0)
		)
		(polygon
			(pts
				(arc
					(start 389.63981 -250.154186)
					(mid 389.00989 -250.154186)
					(end 389.63981 -250.154186)
				)
			)
		)
	)
	(zone
		(layers "B.Cu" "In11.Cu" "In13.Cu" "In15.Cu")
		(hatch none 0.5)
		(connect_pads
			(clearance 0)
		)
		(min_thickness 0.25)
		(keepout
			(tracks not_allowed)
			(vias allowed)
			(pads allowed)
			(copperpour not_allowed)
			(footprints allowed)
		)
		(placement
			(enabled no)
			(sheetname "")
		)
		(fill yes
			(thermal_gap 0.5)
			(thermal_bridge_width 0.5)
			(island_removal_mode 0)
		)
		(polygon
			(pts
				(arc
					(start 82.955892 -231.524302)
					(mid 82.325972 -231.524302)
					(end 82.955892 -231.524302)
				)
			)
		)
	)
	(zone
		(layers "B.Cu" "In11.Cu" "In13.Cu" "In15.Cu")
		(hatch none 0.5)
		(connect_pads
			(clearance 0)
		)
		(min_thickness 0.25)
		(keepout
			(tracks not_allowed)
			(vias allowed)
			(pads allowed)
			(copperpour not_allowed)
			(footprints allowed)
		)
		(placement
			(enabled no)
			(sheetname "")
		)
		(fill yes
			(thermal_gap 0.5)
			(thermal_bridge_width 0.5)
			(island_removal_mode 0)
		)
		(polygon
			(pts
				(arc
					(start 371.206268 -397.156432)
					(mid 370.576348 -397.156432)
					(end 371.206268 -397.156432)
				)
			)
		)
	)
	(zone
		(layers "B.Cu" "In11.Cu" "In13.Cu" "In15.Cu")
		(hatch none 0.5)
		(connect_pads
			(clearance 0)
		)
		(min_thickness 0.25)
		(keepout
			(tracks not_allowed)
			(vias allowed)
			(pads allowed)
			(copperpour not_allowed)
			(footprints allowed)
		)
		(placement
			(enabled no)
			(sheetname "")
		)
		(fill yes
			(thermal_gap 0.5)
			(thermal_bridge_width 0.5)
			(island_removal_mode 0)
		)
		(polygon
			(pts
				(arc
					(start 390.879838 -291.905944)
					(mid 390.249918 -291.905944)
					(end 390.879838 -291.905944)
				)
			)
		)
	)
	(zone
		(layers "B.Cu" "In11.Cu" "In13.Cu" "In15.Cu")
		(hatch none 0.5)
		(connect_pads
			(clearance 0)
		)
		(min_thickness 0.25)
		(keepout
			(tracks not_allowed)
			(vias allowed)
			(pads allowed)
			(copperpour not_allowed)
			(footprints allowed)
		)
		(placement
			(enabled no)
			(sheetname "")
		)
		(fill yes
			(thermal_gap 0.5)
			(thermal_bridge_width 0.5)
			(island_removal_mode 0)
		)
		(polygon
			(pts
				(arc
					(start 329.016106 -246.104156)
					(mid 328.386186 -246.104156)
					(end 329.016106 -246.104156)
				)
			)
		)
	)
	(zone
		(layers "B.Cu" "In11.Cu" "In13.Cu" "In15.Cu")
		(hatch none 0.5)
		(connect_pads
			(clearance 0)
		)
		(min_thickness 0.25)
		(keepout
			(tracks not_allowed)
			(vias allowed)
			(pads allowed)
			(copperpour not_allowed)
			(footprints allowed)
		)
		(placement
			(enabled no)
			(sheetname "")
		)
		(fill yes
			(thermal_gap 0.5)
			(thermal_bridge_width 0.5)
			(island_removal_mode 0)
		)
		(polygon
			(pts
				(arc
					(start 446.978278 -231.335072)
					(mid 446.310258 -231.335072)
					(end 446.978278 -231.335072)
				)
			)
		)
	)
	(zone
		(layers "B.Cu" "In11.Cu" "In13.Cu" "In15.Cu")
		(hatch none 0.5)
		(connect_pads
			(clearance 0)
		)
		(min_thickness 0.25)
		(keepout
			(tracks not_allowed)
			(vias allowed)
			(pads allowed)
			(copperpour not_allowed)
			(footprints allowed)
		)
		(placement
			(enabled no)
			(sheetname "")
		)
		(fill yes
			(thermal_gap 0.5)
			(thermal_bridge_width 0.5)
			(island_removal_mode 0)
		)
		(polygon
			(pts
				(arc
					(start 329.78598 -288.66592)
					(mid 329.15606 -288.66592)
					(end 329.78598 -288.66592)
				)
			)
		)
	)
	(zone
		(layers "B.Cu" "In11.Cu" "In13.Cu" "In15.Cu")
		(hatch none 0.5)
		(connect_pads
			(clearance 0)
		)
		(min_thickness 0.25)
		(keepout
			(tracks not_allowed)
			(vias allowed)
			(pads allowed)
			(copperpour not_allowed)
			(footprints allowed)
		)
		(placement
			(enabled no)
			(sheetname "")
		)
		(fill yes
			(thermal_gap 0.5)
			(thermal_bridge_width 0.5)
			(island_removal_mode 0)
		)
		(polygon
			(pts
				(arc
					(start 81.076038 -241.244374)
					(mid 80.446118 -241.244374)
					(end 81.076038 -241.244374)
				)
			)
		)
	)
	(zone
		(layers "B.Cu" "In11.Cu" "In13.Cu" "In15.Cu")
		(hatch none 0.5)
		(connect_pads
			(clearance 0)
		)
		(min_thickness 0.25)
		(keepout
			(tracks not_allowed)
			(vias allowed)
			(pads allowed)
			(copperpour not_allowed)
			(footprints allowed)
		)
		(placement
			(enabled no)
			(sheetname "")
		)
		(fill yes
			(thermal_gap 0.5)
			(thermal_bridge_width 0.5)
			(island_removal_mode 0)
		)
		(polygon
			(pts
				(arc
					(start 142.93977 -269.226284)
					(mid 142.30985 -269.226284)
					(end 142.93977 -269.226284)
				)
			)
		)
	)
	(zone
		(layers "B.Cu" "In11.Cu" "In13.Cu" "In15.Cu")
		(hatch none 0.5)
		(connect_pads
			(clearance 0)
		)
		(min_thickness 0.25)
		(keepout
			(tracks not_allowed)
			(vias allowed)
			(pads allowed)
			(copperpour not_allowed)
			(footprints allowed)
		)
		(placement
			(enabled no)
			(sheetname "")
		)
		(fill yes
			(thermal_gap 0.5)
			(thermal_bridge_width 0.5)
			(island_removal_mode 0)
		)
		(polygon
			(pts
				(arc
					(start 357.046022 -283.806138)
					(mid 356.416102 -283.806138)
					(end 357.046022 -283.806138)
				)
			)
		)
	)
	(zone
		(layers "B.Cu" "In11.Cu" "In13.Cu" "In15.Cu")
		(hatch none 0.5)
		(connect_pads
			(clearance 0)
		)
		(min_thickness 0.25)
		(keepout
			(tracks not_allowed)
			(vias allowed)
			(pads allowed)
			(copperpour not_allowed)
			(footprints allowed)
		)
		(placement
			(enabled no)
			(sheetname "")
		)
		(fill yes
			(thermal_gap 0.5)
			(thermal_bridge_width 0.5)
			(island_removal_mode 0)
		)
		(polygon
			(pts
				(arc
					(start 338.036916 -427.089824)
					(mid 337.262724 -427.089824)
					(end 338.036916 -427.089824)
				)
			)
		)
	)
	(zone
		(layers "B.Cu" "In11.Cu" "In13.Cu" "In15.Cu")
		(hatch none 0.5)
		(connect_pads
			(clearance 0)
		)
		(min_thickness 0.25)
		(keepout
			(tracks not_allowed)
			(vias allowed)
			(pads allowed)
			(copperpour not_allowed)
			(footprints allowed)
		)
		(placement
			(enabled no)
			(sheetname "")
		)
		(fill yes
			(thermal_gap 0.5)
			(thermal_bridge_width 0.5)
			(island_removal_mode 0)
		)
		(polygon
			(pts
				(arc
					(start 142.93977 -278.946356)
					(mid 142.30985 -278.946356)
					(end 142.93977 -278.946356)
				)
			)
		)
	)
	(zone
		(layers "B.Cu" "In11.Cu" "In13.Cu" "In15.Cu")
		(hatch none 0.5)
		(connect_pads
			(clearance 0)
		)
		(min_thickness 0.25)
		(keepout
			(tracks not_allowed)
			(vias allowed)
			(pads allowed)
			(copperpour not_allowed)
			(footprints allowed)
		)
		(placement
			(enabled no)
			(sheetname "")
		)
		(fill yes
			(thermal_gap 0.5)
			(thermal_bridge_width 0.5)
			(island_removal_mode 0)
		)
		(polygon
			(pts
				(arc
					(start 406.533858 -394.385292)
					(mid 405.903938 -394.385292)
					(end 406.533858 -394.385292)
				)
			)
		)
	)
	(zone
		(layers "B.Cu" "In11.Cu" "In13.Cu" "In15.Cu")
		(hatch none 0.5)
		(connect_pads
			(clearance 0)
		)
		(min_thickness 0.25)
		(keepout
			(tracks not_allowed)
			(vias allowed)
			(pads allowed)
			(copperpour not_allowed)
			(footprints allowed)
		)
		(placement
			(enabled no)
			(sheetname "")
		)
		(fill yes
			(thermal_gap 0.5)
			(thermal_bridge_width 0.5)
			(island_removal_mode 0)
		)
		(polygon
			(pts
				(arc
					(start 56.963564 -371.49913)
					(mid 56.295544 -371.49913)
					(end 56.963564 -371.49913)
				)
			)
		)
	)
	(zone
		(layers "B.Cu" "In11.Cu" "In13.Cu" "In15.Cu")
		(hatch none 0.5)
		(connect_pads
			(clearance 0)
		)
		(min_thickness 0.25)
		(keepout
			(tracks not_allowed)
			(vias allowed)
			(pads allowed)
			(copperpour not_allowed)
			(footprints allowed)
		)
		(placement
			(enabled no)
			(sheetname "")
		)
		(fill yes
			(thermal_gap 0.5)
			(thermal_bridge_width 0.5)
			(island_removal_mode 0)
		)
		(polygon
			(pts
				(arc
					(start 391.349738 -263.555988)
					(mid 390.719818 -263.555988)
					(end 391.349738 -263.555988)
				)
			)
		)
	)
	(zone
		(layers "B.Cu" "In11.Cu" "In13.Cu" "In15.Cu")
		(hatch none 0.5)
		(connect_pads
			(clearance 0)
		)
		(min_thickness 0.25)
		(keepout
			(tracks not_allowed)
			(vias allowed)
			(pads allowed)
			(copperpour not_allowed)
			(footprints allowed)
		)
		(placement
			(enabled no)
			(sheetname "")
		)
		(fill yes
			(thermal_gap 0.5)
			(thermal_bridge_width 0.5)
			(island_removal_mode 0)
		)
		(polygon
			(pts
				(arc
					(start 194.938142 -316.33541)
					(mid 194.270122 -316.33541)
					(end 194.938142 -316.33541)
				)
			)
		)
	)
	(zone
		(layers "B.Cu" "In11.Cu" "In13.Cu" "In15.Cu")
		(hatch none 0.5)
		(connect_pads
			(clearance 0)
		)
		(min_thickness 0.25)
		(keepout
			(tracks not_allowed)
			(vias allowed)
			(pads allowed)
			(copperpour not_allowed)
			(footprints allowed)
		)
		(placement
			(enabled no)
			(sheetname "")
		)
		(fill yes
			(thermal_gap 0.5)
			(thermal_bridge_width 0.5)
			(island_removal_mode 0)
		)
		(polygon
			(pts
				(arc
					(start 409.734004 -393.69238)
					(mid 409.104084 -393.69238)
					(end 409.734004 -393.69238)
				)
			)
		)
	)
	(zone
		(layers "B.Cu" "In11.Cu" "In13.Cu" "In15.Cu")
		(hatch none 0.5)
		(connect_pads
			(clearance 0)
		)
		(min_thickness 0.25)
		(keepout
			(tracks not_allowed)
			(vias allowed)
			(pads allowed)
			(copperpour not_allowed)
			(footprints allowed)
		)
		(placement
			(enabled no)
			(sheetname "")
		)
		(fill yes
			(thermal_gap 0.5)
			(thermal_bridge_width 0.5)
			(island_removal_mode 0)
		)
		(polygon
			(pts
				(arc
					(start 390.579864 -233.954066)
					(mid 389.949944 -233.954066)
					(end 390.579864 -233.954066)
				)
			)
		)
	)
	(zone
		(layers "B.Cu" "In11.Cu" "In13.Cu" "In15.Cu")
		(hatch none 0.5)
		(connect_pads
			(clearance 0)
		)
		(min_thickness 0.25)
		(keepout
			(tracks not_allowed)
			(vias allowed)
			(pads allowed)
			(copperpour not_allowed)
			(footprints allowed)
		)
		(placement
			(enabled no)
			(sheetname "")
		)
		(fill yes
			(thermal_gap 0.5)
			(thermal_bridge_width 0.5)
			(island_removal_mode 0)
		)
		(polygon
			(pts
				(arc
					(start 277.526242 -225.385122)
					(mid 276.858222 -225.385122)
					(end 277.526242 -225.385122)
				)
			)
		)
	)
	(zone
		(layers "B.Cu" "In11.Cu" "In13.Cu" "In15.Cu")
		(hatch none 0.5)
		(connect_pads
			(clearance 0)
		)
		(min_thickness 0.25)
		(keepout
			(tracks not_allowed)
			(vias allowed)
			(pads allowed)
			(copperpour not_allowed)
			(footprints allowed)
		)
		(placement
			(enabled no)
			(sheetname "")
		)
		(fill yes
			(thermal_gap 0.5)
			(thermal_bridge_width 0.5)
			(island_removal_mode 0)
		)
		(polygon
			(pts
				(arc
					(start 389.469884 -281.37612)
					(mid 388.839964 -281.37612)
					(end 389.469884 -281.37612)
				)
			)
		)
	)
	(zone
		(layers "B.Cu" "In11.Cu" "In13.Cu" "In15.Cu")
		(hatch none 0.5)
		(connect_pads
			(clearance 0)
		)
		(min_thickness 0.25)
		(keepout
			(tracks not_allowed)
			(vias allowed)
			(pads allowed)
			(copperpour not_allowed)
			(footprints allowed)
		)
		(placement
			(enabled no)
			(sheetname "")
		)
		(fill yes
			(thermal_gap 0.5)
			(thermal_bridge_width 0.5)
			(island_removal_mode 0)
		)
		(polygon
			(pts
				(arc
					(start 373.189754 -241.24412)
					(mid 372.559834 -241.24412)
					(end 373.189754 -241.24412)
				)
			)
		)
	)
	(zone
		(layers "B.Cu" "In11.Cu" "In13.Cu" "In15.Cu")
		(hatch none 0.5)
		(connect_pads
			(clearance 0)
		)
		(min_thickness 0.25)
		(keepout
			(tracks not_allowed)
			(vias allowed)
			(pads allowed)
			(copperpour not_allowed)
			(footprints allowed)
		)
		(placement
			(enabled no)
			(sheetname "")
		)
		(fill yes
			(thermal_gap 0.5)
			(thermal_bridge_width 0.5)
			(island_removal_mode 0)
		)
		(polygon
			(pts
				(arc
					(start 389.939784 -285.42615)
					(mid 389.309864 -285.42615)
					(end 389.939784 -285.42615)
				)
			)
		)
	)
	(zone
		(layers "B.Cu" "In11.Cu" "In13.Cu" "In15.Cu")
		(hatch none 0.5)
		(connect_pads
			(clearance 0)
		)
		(min_thickness 0.25)
		(keepout
			(tracks not_allowed)
			(vias allowed)
			(pads allowed)
			(copperpour not_allowed)
			(footprints allowed)
		)
		(placement
			(enabled no)
			(sheetname "")
		)
		(fill yes
			(thermal_gap 0.5)
			(thermal_bridge_width 0.5)
			(island_removal_mode 0)
		)
		(polygon
			(pts
				(arc
					(start 82.485992 -237.194344)
					(mid 81.856072 -237.194344)
					(end 82.485992 -237.194344)
				)
			)
		)
	)
	(zone
		(layers "B.Cu" "In11.Cu" "In13.Cu" "In15.Cu")
		(hatch none 0.5)
		(connect_pads
			(clearance 0)
		)
		(min_thickness 0.25)
		(keepout
			(tracks not_allowed)
			(vias allowed)
			(pads allowed)
			(copperpour not_allowed)
			(footprints allowed)
		)
		(placement
			(enabled no)
			(sheetname "")
		)
		(fill yes
			(thermal_gap 0.5)
			(thermal_bridge_width 0.5)
			(island_removal_mode 0)
		)
		(polygon
			(pts
				(arc
					(start 329.78598 -280.566114)
					(mid 329.15606 -280.566114)
					(end 329.78598 -280.566114)
				)
			)
		)
	)
	(zone
		(layers "B.Cu" "In11.Cu" "In13.Cu" "In15.Cu")
		(hatch none 0.5)
		(connect_pads
			(clearance 0)
		)
		(min_thickness 0.25)
		(keepout
			(tracks not_allowed)
			(vias allowed)
			(pads allowed)
			(copperpour not_allowed)
			(footprints allowed)
		)
		(placement
			(enabled no)
			(sheetname "")
		)
		(fill yes
			(thermal_gap 0.5)
			(thermal_bridge_width 0.5)
			(island_removal_mode 0)
		)
		(polygon
			(pts
				(arc
					(start 307.019706 -379.88113)
					(mid 306.351686 -379.88113)
					(end 307.019706 -379.88113)
				)
			)
		)
	)
	(zone
		(layers "B.Cu" "In11.Cu" "In13.Cu" "In15.Cu")
		(hatch none 0.5)
		(connect_pads
			(clearance 0)
		)
		(min_thickness 0.25)
		(keepout
			(tracks not_allowed)
			(vias allowed)
			(pads allowed)
			(copperpour not_allowed)
			(footprints allowed)
		)
		(placement
			(enabled no)
			(sheetname "")
		)
		(fill yes
			(thermal_gap 0.5)
			(thermal_bridge_width 0.5)
			(island_removal_mode 0)
		)
		(polygon
			(pts
				(arc
					(start 391.049764 -226.664266)
					(mid 390.419844 -226.664266)
					(end 391.049764 -226.664266)
				)
			)
		)
	)
	(zone
		(layers "B.Cu" "In11.Cu" "In13.Cu" "In15.Cu")
		(hatch none 0.5)
		(connect_pads
			(clearance 0)
		)
		(min_thickness 0.25)
		(keepout
			(tracks not_allowed)
			(vias allowed)
			(pads allowed)
			(copperpour not_allowed)
			(footprints allowed)
		)
		(placement
			(enabled no)
			(sheetname "")
		)
		(fill yes
			(thermal_gap 0.5)
			(thermal_bridge_width 0.5)
			(island_removal_mode 0)
		)
		(polygon
			(pts
				(arc
					(start 389.63981 -243.674138)
					(mid 389.00989 -243.674138)
					(end 389.63981 -243.674138)
				)
			)
		)
	)
	(zone
		(layers "B.Cu" "In11.Cu" "In13.Cu" "In15.Cu")
		(hatch none 0.5)
		(connect_pads
			(clearance 0)
		)
		(min_thickness 0.25)
		(keepout
			(tracks not_allowed)
			(vias allowed)
			(pads allowed)
			(copperpour not_allowed)
			(footprints allowed)
		)
		(placement
			(enabled no)
			(sheetname "")
		)
		(fill yes
			(thermal_gap 0.5)
			(thermal_bridge_width 0.5)
			(island_removal_mode 0)
		)
		(polygon
			(pts
				(arc
					(start 82.785966 -285.426404)
					(mid 82.156046 -285.426404)
					(end 82.785966 -285.426404)
				)
			)
		)
	)
	(zone
		(layers "B.Cu" "In11.Cu" "In13.Cu" "In15.Cu")
		(hatch none 0.5)
		(connect_pads
			(clearance 0)
		)
		(min_thickness 0.25)
		(keepout
			(tracks not_allowed)
			(vias allowed)
			(pads allowed)
			(copperpour not_allowed)
			(footprints allowed)
		)
		(placement
			(enabled no)
			(sheetname "")
		)
		(fill yes
			(thermal_gap 0.5)
			(thermal_bridge_width 0.5)
			(island_removal_mode 0)
		)
		(polygon
			(pts
				(arc
					(start 277.526242 -312.935112)
					(mid 276.858222 -312.935112)
					(end 277.526242 -312.935112)
				)
			)
		)
	)
	(zone
		(layers "B.Cu" "In11.Cu" "In13.Cu" "In15.Cu")
		(hatch none 0.5)
		(connect_pads
			(clearance 0)
		)
		(min_thickness 0.25)
		(keepout
			(tracks not_allowed)
			(vias allowed)
			(pads allowed)
			(copperpour not_allowed)
			(footprints allowed)
		)
		(placement
			(enabled no)
			(sheetname "")
		)
		(fill yes
			(thermal_gap 0.5)
			(thermal_bridge_width 0.5)
			(island_removal_mode 0)
		)
		(polygon
			(pts
				(arc
					(start 81.545938 -242.05438)
					(mid 80.916018 -242.05438)
					(end 81.545938 -242.05438)
				)
			)
		)
	)
	(zone
		(layers "B.Cu" "In11.Cu" "In13.Cu" "In15.Cu")
		(hatch none 0.5)
		(connect_pads
			(clearance 0)
		)
		(min_thickness 0.25)
		(keepout
			(tracks not_allowed)
			(vias allowed)
			(pads allowed)
			(copperpour not_allowed)
			(footprints allowed)
		)
		(placement
			(enabled no)
			(sheetname "")
		)
		(fill yes
			(thermal_gap 0.5)
			(thermal_bridge_width 0.5)
			(island_removal_mode 0)
		)
		(polygon
			(pts
				(arc
					(start 446.978278 -287.435036)
					(mid 446.310258 -287.435036)
					(end 446.978278 -287.435036)
				)
			)
		)
	)
	(zone
		(layers "B.Cu" "In11.Cu" "In13.Cu" "In15.Cu")
		(hatch none 0.5)
		(connect_pads
			(clearance 0)
		)
		(min_thickness 0.25)
		(keepout
			(tracks not_allowed)
			(vias allowed)
			(pads allowed)
			(copperpour not_allowed)
			(footprints allowed)
		)
		(placement
			(enabled no)
			(sheetname "")
		)
		(fill yes
			(thermal_gap 0.5)
			(thermal_bridge_width 0.5)
			(island_removal_mode 0)
		)
		(polygon
			(pts
				(arc
					(start 25.486106 -301.035212)
					(mid 24.818086 -301.035212)
					(end 25.486106 -301.035212)
				)
			)
		)
	)
	(zone
		(layers "B.Cu" "In11.Cu" "In13.Cu" "In15.Cu")
		(hatch none 0.5)
		(connect_pads
			(clearance 0)
		)
		(min_thickness 0.25)
		(keepout
			(tracks not_allowed)
			(vias allowed)
			(pads allowed)
			(copperpour not_allowed)
			(footprints allowed)
		)
		(placement
			(enabled no)
			(sheetname "")
		)
		(fill yes
			(thermal_gap 0.5)
			(thermal_bridge_width 0.5)
			(island_removal_mode 0)
		)
		(polygon
			(pts
				(arc
					(start 347.17609 -281.37612)
					(mid 346.54617 -281.37612)
					(end 347.17609 -281.37612)
				)
			)
		)
	)
	(zone
		(layers "B.Cu" "In11.Cu" "In13.Cu" "In15.Cu")
		(hatch none 0.5)
		(connect_pads
			(clearance 0)
		)
		(min_thickness 0.25)
		(keepout
			(tracks not_allowed)
			(vias allowed)
			(pads allowed)
			(copperpour not_allowed)
			(footprints allowed)
		)
		(placement
			(enabled no)
			(sheetname "")
		)
		(fill yes
			(thermal_gap 0.5)
			(thermal_bridge_width 0.5)
			(island_removal_mode 0)
		)
		(polygon
			(pts
				(arc
					(start 82.955892 -241.244374)
					(mid 82.325972 -241.244374)
					(end 82.955892 -241.244374)
				)
			)
		)
	)
	(zone
		(layers "B.Cu" "In11.Cu" "In13.Cu" "In15.Cu")
		(hatch none 0.5)
		(connect_pads
			(clearance 0)
		)
		(min_thickness 0.25)
		(keepout
			(tracks not_allowed)
			(vias allowed)
			(pads allowed)
			(copperpour not_allowed)
			(footprints allowed)
		)
		(placement
			(enabled no)
			(sheetname "")
		)
		(fill yes
			(thermal_gap 0.5)
			(thermal_bridge_width 0.5)
			(island_removal_mode 0)
		)
		(polygon
			(pts
				(arc
					(start 81.076038 -244.484398)
					(mid 80.446118 -244.484398)
					(end 81.076038 -244.484398)
				)
			)
		)
	)
	(zone
		(layers "B.Cu" "In11.Cu" "In13.Cu" "In15.Cu")
		(hatch none 0.5)
		(connect_pads
			(clearance 0)
		)
		(min_thickness 0.25)
		(keepout
			(tracks not_allowed)
			(vias allowed)
			(pads allowed)
			(copperpour not_allowed)
			(footprints allowed)
		)
		(placement
			(enabled no)
			(sheetname "")
		)
		(fill yes
			(thermal_gap 0.5)
			(thermal_bridge_width 0.5)
			(island_removal_mode 0)
		)
		(polygon
			(pts
				(arc
					(start 141.229842 -244.484398)
					(mid 140.599922 -244.484398)
					(end 141.229842 -244.484398)
				)
			)
		)
	)
	(zone
		(layers "B.Cu" "In11.Cu" "In13.Cu" "In15.Cu")
		(hatch none 0.5)
		(connect_pads
			(clearance 0)
		)
		(min_thickness 0.25)
		(keepout
			(tracks not_allowed)
			(vias allowed)
			(pads allowed)
			(copperpour not_allowed)
			(footprints allowed)
		)
		(placement
			(enabled no)
			(sheetname "")
		)
		(fill yes
			(thermal_gap 0.5)
			(thermal_bridge_width 0.5)
			(island_removal_mode 0)
		)
		(polygon
			(pts
				(arc
					(start 81.845912 -291.906198)
					(mid 81.215992 -291.906198)
					(end 81.845912 -291.906198)
				)
			)
		)
	)
	(zone
		(layers "B.Cu" "In11.Cu" "In13.Cu" "In15.Cu")
		(hatch none 0.5)
		(connect_pads
			(clearance 0)
		)
		(min_thickness 0.25)
		(keepout
			(tracks not_allowed)
			(vias allowed)
			(pads allowed)
			(copperpour not_allowed)
			(footprints allowed)
		)
		(placement
			(enabled no)
			(sheetname "")
		)
		(fill yes
			(thermal_gap 0.5)
			(thermal_bridge_width 0.5)
			(island_removal_mode 0)
		)
		(polygon
			(pts
				(arc
					(start 330.89596 -244.484144)
					(mid 330.26604 -244.484144)
					(end 330.89596 -244.484144)
				)
			)
		)
	)
	(zone
		(layers "B.Cu" "In11.Cu" "In13.Cu" "In15.Cu")
		(hatch none 0.5)
		(connect_pads
			(clearance 0)
		)
		(min_thickness 0.25)
		(keepout
			(tracks not_allowed)
			(vias allowed)
			(pads allowed)
			(copperpour not_allowed)
			(footprints allowed)
		)
		(placement
			(enabled no)
			(sheetname "")
		)
		(fill yes
			(thermal_gap 0.5)
			(thermal_bridge_width 0.5)
			(island_removal_mode 0)
		)
		(polygon
			(pts
				(arc
					(start 194.938142 -221.135194)
					(mid 194.270122 -221.135194)
					(end 194.938142 -221.135194)
				)
			)
		)
	)
	(zone
		(layers "B.Cu" "In11.Cu" "In13.Cu" "In15.Cu")
		(hatch none 0.5)
		(connect_pads
			(clearance 0)
		)
		(min_thickness 0.25)
		(keepout
			(tracks not_allowed)
			(vias allowed)
			(pads allowed)
			(copperpour not_allowed)
			(footprints allowed)
		)
		(placement
			(enabled no)
			(sheetname "")
		)
		(fill yes
			(thermal_gap 0.5)
			(thermal_bridge_width 0.5)
			(island_removal_mode 0)
		)
		(polygon
			(pts
				(arc
					(start 418.134038 -393.69238)
					(mid 417.504118 -393.69238)
					(end 418.134038 -393.69238)
				)
			)
		)
	)
	(zone
		(layers "B.Cu" "In11.Cu" "In13.Cu" "In15.Cu")
		(hatch none 0.5)
		(connect_pads
			(clearance 0)
		)
		(min_thickness 0.25)
		(keepout
			(tracks not_allowed)
			(vias allowed)
			(pads allowed)
			(copperpour not_allowed)
			(footprints allowed)
		)
		(placement
			(enabled no)
			(sheetname "")
		)
		(fill yes
			(thermal_gap 0.5)
			(thermal_bridge_width 0.5)
			(island_removal_mode 0)
		)
		(polygon
			(pts
				(arc
					(start 329.486006 -256.634234)
					(mid 328.856086 -256.634234)
					(end 329.486006 -256.634234)
				)
			)
		)
	)
	(zone
		(layers "B.Cu" "In11.Cu" "In13.Cu" "In15.Cu")
		(hatch none 0.5)
		(connect_pads
			(clearance 0)
		)
		(min_thickness 0.25)
		(keepout
			(tracks not_allowed)
			(vias allowed)
			(pads allowed)
			(copperpour not_allowed)
			(footprints allowed)
		)
		(placement
			(enabled no)
			(sheetname "")
		)
		(fill yes
			(thermal_gap 0.5)
			(thermal_bridge_width 0.5)
			(island_removal_mode 0)
		)
		(polygon
			(pts
				(arc
					(start 194.938142 -211.7852)
					(mid 194.270122 -211.7852)
					(end 194.938142 -211.7852)
				)
			)
		)
	)
	(zone
		(layers "B.Cu" "In11.Cu" "In13.Cu" "In15.Cu")
		(hatch none 0.5)
		(connect_pads
			(clearance 0)
		)
		(min_thickness 0.25)
		(keepout
			(tracks not_allowed)
			(vias allowed)
			(pads allowed)
			(copperpour not_allowed)
			(footprints allowed)
		)
		(placement
			(enabled no)
			(sheetname "")
		)
		(fill yes
			(thermal_gap 0.5)
			(thermal_bridge_width 0.5)
			(island_removal_mode 0)
		)
		(polygon
			(pts
				(arc
					(start 125.54966 -282.996386)
					(mid 124.91974 -282.996386)
					(end 125.54966 -282.996386)
				)
			)
		)
	)
	(zone
		(layers "B.Cu" "In11.Cu" "In13.Cu" "In15.Cu")
		(hatch none 0.5)
		(connect_pads
			(clearance 0)
		)
		(min_thickness 0.25)
		(keepout
			(tracks not_allowed)
			(vias allowed)
			(pads allowed)
			(copperpour not_allowed)
			(footprints allowed)
		)
		(placement
			(enabled no)
			(sheetname "")
		)
		(fill yes
			(thermal_gap 0.5)
			(thermal_bridge_width 0.5)
			(island_removal_mode 0)
		)
		(polygon
			(pts
				(arc
					(start 305.317906 -382.34493)
					(mid 304.649886 -382.34493)
					(end 305.317906 -382.34493)
				)
			)
		)
	)
	(zone
		(layers "B.Cu" "In11.Cu" "In13.Cu" "In15.Cu")
		(hatch none 0.5)
		(connect_pads
			(clearance 0)
		)
		(min_thickness 0.25)
		(keepout
			(tracks not_allowed)
			(vias allowed)
			(pads allowed)
			(copperpour not_allowed)
			(footprints allowed)
		)
		(placement
			(enabled no)
			(sheetname "")
		)
		(fill yes
			(thermal_gap 0.5)
			(thermal_bridge_width 0.5)
			(island_removal_mode 0)
		)
		(polygon
			(pts
				(arc
					(start 199.03821 -307.8353)
					(mid 198.37019 -307.8353)
					(end 199.03821 -307.8353)
				)
			)
		)
	)
	(zone
		(layers "B.Cu" "In11.Cu" "In13.Cu" "In15.Cu")
		(hatch none 0.5)
		(connect_pads
			(clearance 0)
		)
		(min_thickness 0.25)
		(keepout
			(tracks not_allowed)
			(vias allowed)
			(pads allowed)
			(copperpour not_allowed)
			(footprints allowed)
		)
		(placement
			(enabled no)
			(sheetname "")
		)
		(fill yes
			(thermal_gap 0.5)
			(thermal_bridge_width 0.5)
			(island_removal_mode 0)
		)
		(polygon
			(pts
				(arc
					(start 330.726034 -283.806138)
					(mid 330.096114 -283.806138)
					(end 330.726034 -283.806138)
				)
			)
		)
	)
	(zone
		(layers "B.Cu" "In11.Cu" "In13.Cu" "In15.Cu")
		(hatch none 0.5)
		(connect_pads
			(clearance 0)
		)
		(min_thickness 0.25)
		(keepout
			(tracks not_allowed)
			(vias allowed)
			(pads allowed)
			(copperpour not_allowed)
			(footprints allowed)
		)
		(placement
			(enabled no)
			(sheetname "")
		)
		(fill yes
			(thermal_gap 0.5)
			(thermal_bridge_width 0.5)
			(island_removal_mode 0)
		)
		(polygon
			(pts
				(arc
					(start 194.938142 -241.535204)
					(mid 194.270122 -241.535204)
					(end 194.938142 -241.535204)
				)
			)
		)
	)
	(zone
		(layers "B.Cu" "In11.Cu" "In13.Cu" "In15.Cu")
		(hatch none 0.5)
		(connect_pads
			(clearance 0)
		)
		(min_thickness 0.25)
		(keepout
			(tracks not_allowed)
			(vias allowed)
			(pads allowed)
			(copperpour not_allowed)
			(footprints allowed)
		)
		(placement
			(enabled no)
			(sheetname "")
		)
		(fill yes
			(thermal_gap 0.5)
			(thermal_bridge_width 0.5)
			(island_removal_mode 0)
		)
		(polygon
			(pts
				(arc
					(start 390.579864 -240.434114)
					(mid 389.949944 -240.434114)
					(end 390.579864 -240.434114)
				)
			)
		)
	)
	(zone
		(layers "B.Cu" "In11.Cu" "In13.Cu" "In15.Cu")
		(hatch none 0.5)
		(connect_pads
			(clearance 0)
		)
		(min_thickness 0.25)
		(keepout
			(tracks not_allowed)
			(vias allowed)
			(pads allowed)
			(copperpour not_allowed)
			(footprints allowed)
		)
		(placement
			(enabled no)
			(sheetname "")
		)
		(fill yes
			(thermal_gap 0.5)
			(thermal_bridge_width 0.5)
			(island_removal_mode 0)
		)
		(polygon
			(pts
				(arc
					(start 380.006098 -397.849344)
					(mid 379.376178 -397.849344)
					(end 380.006098 -397.849344)
				)
			)
		)
	)
	(zone
		(layers "B.Cu" "In11.Cu" "In13.Cu" "In15.Cu")
		(hatch none 0.5)
		(connect_pads
			(clearance 0)
		)
		(min_thickness 0.25)
		(keepout
			(tracks not_allowed)
			(vias allowed)
			(pads allowed)
			(copperpour not_allowed)
			(footprints allowed)
		)
		(placement
			(enabled no)
			(sheetname "")
		)
		(fill yes
			(thermal_gap 0.5)
			(thermal_bridge_width 0.5)
			(island_removal_mode 0)
		)
		(polygon
			(pts
				(arc
					(start 94.821756 -208.159858)
					(mid 94.153736 -208.159858)
					(end 94.821756 -208.159858)
				)
			)
		)
	)
	(zone
		(layers "B.Cu" "In11.Cu" "In13.Cu" "In15.Cu")
		(hatch none 0.5)
		(connect_pads
			(clearance 0)
		)
		(min_thickness 0.25)
		(keepout
			(tracks not_allowed)
			(vias allowed)
			(pads allowed)
			(copperpour not_allowed)
			(footprints allowed)
		)
		(placement
			(enabled no)
			(sheetname "")
		)
		(fill yes
			(thermal_gap 0.5)
			(thermal_bridge_width 0.5)
			(island_removal_mode 0)
		)
		(polygon
			(pts
				(arc
					(start 365.66983 -242.864132)
					(mid 365.03991 -242.864132)
					(end 365.66983 -242.864132)
				)
			)
		)
	)
	(zone
		(layers "B.Cu" "In11.Cu" "In13.Cu" "In15.Cu")
		(hatch none 0.5)
		(connect_pads
			(clearance 0)
		)
		(min_thickness 0.25)
		(keepout
			(tracks not_allowed)
			(vias allowed)
			(pads allowed)
			(copperpour not_allowed)
			(footprints allowed)
		)
		(placement
			(enabled no)
			(sheetname "")
		)
		(fill yes
			(thermal_gap 0.5)
			(thermal_bridge_width 0.5)
			(island_removal_mode 0)
		)
		(polygon
			(pts
				(arc
					(start 142.639796 -233.95432)
					(mid 142.009876 -233.95432)
					(end 142.639796 -233.95432)
				)
			)
		)
	)
	(zone
		(layers "B.Cu" "In11.Cu" "In13.Cu" "In15.Cu")
		(hatch none 0.5)
		(connect_pads
			(clearance 0)
		)
		(min_thickness 0.25)
		(keepout
			(tracks not_allowed)
			(vias allowed)
			(pads allowed)
			(copperpour not_allowed)
			(footprints allowed)
		)
		(placement
			(enabled no)
			(sheetname "")
		)
		(fill yes
			(thermal_gap 0.5)
			(thermal_bridge_width 0.5)
			(island_removal_mode 0)
		)
		(polygon
			(pts
				(arc
					(start 277.526242 -281.485086)
					(mid 276.858222 -281.485086)
					(end 277.526242 -281.485086)
				)
			)
		)
	)
	(zone
		(layers "B.Cu" "In11.Cu" "In13.Cu" "In15.Cu")
		(hatch none 0.5)
		(connect_pads
			(clearance 0)
		)
		(min_thickness 0.25)
		(keepout
			(tracks not_allowed)
			(vias allowed)
			(pads allowed)
			(copperpour not_allowed)
			(footprints allowed)
		)
		(placement
			(enabled no)
			(sheetname "")
		)
		(fill yes
			(thermal_gap 0.5)
			(thermal_bridge_width 0.5)
			(island_removal_mode 0)
		)
		(polygon
			(pts
				(arc
					(start 354.696014 -286.236156)
					(mid 354.066094 -286.236156)
					(end 354.696014 -286.236156)
				)
			)
		)
	)
	(zone
		(layers "B.Cu" "In11.Cu" "In13.Cu" "In15.Cu")
		(hatch none 0.5)
		(connect_pads
			(clearance 0)
		)
		(min_thickness 0.25)
		(keepout
			(tracks not_allowed)
			(vias allowed)
			(pads allowed)
			(copperpour not_allowed)
			(footprints allowed)
		)
		(placement
			(enabled no)
			(sheetname "")
		)
		(fill yes
			(thermal_gap 0.5)
			(thermal_bridge_width 0.5)
			(island_removal_mode 0)
		)
		(polygon
			(pts
				(arc
					(start 273.426174 -251.735082)
					(mid 272.758154 -251.735082)
					(end 273.426174 -251.735082)
				)
			)
		)
	)
	(zone
		(layers "B.Cu" "In11.Cu" "In13.Cu" "In15.Cu")
		(hatch none 0.5)
		(connect_pads
			(clearance 0)
		)
		(min_thickness 0.25)
		(keepout
			(tracks not_allowed)
			(vias allowed)
			(pads allowed)
			(copperpour not_allowed)
			(footprints allowed)
		)
		(placement
			(enabled no)
			(sheetname "")
		)
		(fill yes
			(thermal_gap 0.5)
			(thermal_bridge_width 0.5)
			(island_removal_mode 0)
		)
		(polygon
			(pts
				(arc
					(start 446.978278 -236.435138)
					(mid 446.310258 -236.435138)
					(end 446.978278 -236.435138)
				)
			)
		)
	)
	(zone
		(layers "B.Cu" "In11.Cu" "In13.Cu" "In15.Cu")
		(hatch none 0.5)
		(connect_pads
			(clearance 0)
		)
		(min_thickness 0.25)
		(keepout
			(tracks not_allowed)
			(vias allowed)
			(pads allowed)
			(copperpour not_allowed)
			(footprints allowed)
		)
		(placement
			(enabled no)
			(sheetname "")
		)
		(fill yes
			(thermal_gap 0.5)
			(thermal_bridge_width 0.5)
			(island_removal_mode 0)
		)
		(polygon
			(pts
				(arc
					(start 81.845912 -264.366248)
					(mid 81.215992 -264.366248)
					(end 81.845912 -264.366248)
				)
			)
		)
	)
	(zone
		(layers "B.Cu" "In11.Cu" "In13.Cu" "In15.Cu")
		(hatch none 0.5)
		(connect_pads
			(clearance 0)
		)
		(min_thickness 0.25)
		(keepout
			(tracks not_allowed)
			(vias allowed)
			(pads allowed)
			(copperpour not_allowed)
			(footprints allowed)
		)
		(placement
			(enabled no)
			(sheetname "")
		)
		(fill yes
			(thermal_gap 0.5)
			(thermal_bridge_width 0.5)
			(island_removal_mode 0)
		)
		(polygon
			(pts
				(arc
					(start 69.739764 -369.03533)
					(mid 69.071744 -369.03533)
					(end 69.739764 -369.03533)
				)
			)
		)
	)
	(zone
		(layers "B.Cu" "In11.Cu" "In13.Cu" "In15.Cu")
		(hatch none 0.5)
		(connect_pads
			(clearance 0)
		)
		(min_thickness 0.25)
		(keepout
			(tracks not_allowed)
			(vias allowed)
			(pads allowed)
			(copperpour not_allowed)
			(footprints allowed)
		)
		(placement
			(enabled no)
			(sheetname "")
		)
		(fill yes
			(thermal_gap 0.5)
			(thermal_bridge_width 0.5)
			(island_removal_mode 0)
		)
		(polygon
			(pts
				(arc
					(start 69.036946 -424.689778)
					(mid 68.262754 -424.689778)
					(end 69.036946 -424.689778)
				)
			)
		)
	)
	(zone
		(layers "B.Cu" "In11.Cu" "In13.Cu" "In15.Cu")
		(hatch none 0.5)
		(connect_pads
			(clearance 0)
		)
		(min_thickness 0.25)
		(keepout
			(tracks not_allowed)
			(vias allowed)
			(pads allowed)
			(copperpour not_allowed)
			(footprints allowed)
		)
		(placement
			(enabled no)
			(sheetname "")
		)
		(fill yes
			(thermal_gap 0.5)
			(thermal_bridge_width 0.5)
			(island_removal_mode 0)
		)
		(polygon
			(pts
				(arc
					(start 104.876092 -282.996386)
					(mid 104.246172 -282.996386)
					(end 104.876092 -282.996386)
				)
			)
		)
	)
	(zone
		(layers "B.Cu" "In11.Cu" "In13.Cu" "In15.Cu")
		(hatch none 0.5)
		(connect_pads
			(clearance 0)
		)
		(min_thickness 0.25)
		(keepout
			(tracks not_allowed)
			(vias allowed)
			(pads allowed)
			(copperpour not_allowed)
			(footprints allowed)
		)
		(placement
			(enabled no)
			(sheetname "")
		)
		(fill yes
			(thermal_gap 0.5)
			(thermal_bridge_width 0.5)
			(island_removal_mode 0)
		)
		(polygon
			(pts
				(arc
					(start 391.049764 -239.624108)
					(mid 390.419844 -239.624108)
					(end 391.049764 -239.624108)
				)
			)
		)
	)
	(zone
		(layers "B.Cu" "In11.Cu" "In13.Cu" "In15.Cu")
		(hatch none 0.5)
		(connect_pads
			(clearance 0)
		)
		(min_thickness 0.25)
		(keepout
			(tracks not_allowed)
			(vias allowed)
			(pads allowed)
			(copperpour not_allowed)
			(footprints allowed)
		)
		(placement
			(enabled no)
			(sheetname "")
		)
		(fill yes
			(thermal_gap 0.5)
			(thermal_bridge_width 0.5)
			(island_removal_mode 0)
		)
		(polygon
			(pts
				(arc
					(start 194.938142 -314.635388)
					(mid 194.270122 -314.635388)
					(end 194.938142 -314.635388)
				)
			)
		)
	)
	(zone
		(layers "B.Cu" "In11.Cu" "In13.Cu" "In15.Cu")
		(hatch none 0.5)
		(connect_pads
			(clearance 0)
		)
		(min_thickness 0.25)
		(keepout
			(tracks not_allowed)
			(vias allowed)
			(pads allowed)
			(copperpour not_allowed)
			(footprints allowed)
		)
		(placement
			(enabled no)
			(sheetname "")
		)
		(fill yes
			(thermal_gap 0.5)
			(thermal_bridge_width 0.5)
			(island_removal_mode 0)
		)
		(polygon
			(pts
				(arc
					(start 29.586174 -312.935366)
					(mid 28.918154 -312.935366)
					(end 29.586174 -312.935366)
				)
			)
		)
	)
	(zone
		(layers "B.Cu" "In11.Cu" "In13.Cu" "In15.Cu")
		(hatch none 0.5)
		(connect_pads
			(clearance 0)
		)
		(min_thickness 0.25)
		(keepout
			(tracks not_allowed)
			(vias allowed)
			(pads allowed)
			(copperpour not_allowed)
			(footprints allowed)
		)
		(placement
			(enabled no)
			(sheetname "")
		)
		(fill yes
			(thermal_gap 0.5)
			(thermal_bridge_width 0.5)
			(island_removal_mode 0)
		)
		(polygon
			(pts
				(arc
					(start 389.939784 -287.045908)
					(mid 389.309864 -287.045908)
					(end 389.939784 -287.045908)
				)
			)
		)
	)
	(zone
		(layers "B.Cu" "In11.Cu" "In13.Cu" "In15.Cu")
		(hatch none 0.5)
		(connect_pads
			(clearance 0)
		)
		(min_thickness 0.25)
		(keepout
			(tracks not_allowed)
			(vias allowed)
			(pads allowed)
			(copperpour not_allowed)
			(footprints allowed)
		)
		(placement
			(enabled no)
			(sheetname "")
		)
		(fill yes
			(thermal_gap 0.5)
			(thermal_bridge_width 0.5)
			(island_removal_mode 0)
		)
		(polygon
			(pts
				(arc
					(start 329.486006 -243.674138)
					(mid 328.856086 -243.674138)
					(end 329.486006 -243.674138)
				)
			)
		)
	)
	(zone
		(layers "B.Cu" "In11.Cu" "In13.Cu" "In15.Cu")
		(hatch none 0.5)
		(connect_pads
			(clearance 0)
		)
		(min_thickness 0.25)
		(keepout
			(tracks not_allowed)
			(vias allowed)
			(pads allowed)
			(copperpour not_allowed)
			(footprints allowed)
		)
		(placement
			(enabled no)
			(sheetname "")
		)
		(fill yes
			(thermal_gap 0.5)
			(thermal_bridge_width 0.5)
			(island_removal_mode 0)
		)
		(polygon
			(pts
				(arc
					(start 442.87821 -230.485188)
					(mid 442.21019 -230.485188)
					(end 442.87821 -230.485188)
				)
			)
		)
	)
	(zone
		(layers "B.Cu" "In11.Cu" "In13.Cu" "In15.Cu")
		(hatch none 0.5)
		(connect_pads
			(clearance 0)
		)
		(min_thickness 0.25)
		(keepout
			(tracks not_allowed)
			(vias allowed)
			(pads allowed)
			(copperpour not_allowed)
			(footprints allowed)
		)
		(placement
			(enabled no)
			(sheetname "")
		)
		(fill yes
			(thermal_gap 0.5)
			(thermal_bridge_width 0.5)
			(island_removal_mode 0)
		)
		(polygon
			(pts
				(arc
					(start 442.87821 -232.184956)
					(mid 442.21019 -232.184956)
					(end 442.87821 -232.184956)
				)
			)
		)
	)
	(zone
		(layers "B.Cu" "In11.Cu" "In13.Cu" "In15.Cu")
		(hatch none 0.5)
		(connect_pads
			(clearance 0)
		)
		(min_thickness 0.25)
		(keepout
			(tracks not_allowed)
			(vias allowed)
			(pads allowed)
			(copperpour not_allowed)
			(footprints allowed)
		)
		(placement
			(enabled no)
			(sheetname "")
		)
		(fill yes
			(thermal_gap 0.5)
			(thermal_bridge_width 0.5)
			(island_removal_mode 0)
		)
		(polygon
			(pts
				(arc
					(start 277.526242 -307.835046)
					(mid 276.858222 -307.835046)
					(end 277.526242 -307.835046)
				)
			)
		)
	)
	(zone
		(layers "B.Cu" "In11.Cu" "In13.Cu" "In15.Cu")
		(hatch none 0.5)
		(connect_pads
			(clearance 0)
		)
		(min_thickness 0.25)
		(keepout
			(tracks not_allowed)
			(vias allowed)
			(pads allowed)
			(copperpour not_allowed)
			(footprints allowed)
		)
		(placement
			(enabled no)
			(sheetname "")
		)
		(fill yes
			(thermal_gap 0.5)
			(thermal_bridge_width 0.5)
			(island_removal_mode 0)
		)
		(polygon
			(pts
				(arc
					(start 311.261506 -382.34493)
					(mid 310.593486 -382.34493)
					(end 311.261506 -382.34493)
				)
			)
		)
	)
	(zone
		(layers "B.Cu" "In11.Cu" "In13.Cu" "In15.Cu")
		(hatch none 0.5)
		(connect_pads
			(clearance 0)
		)
		(min_thickness 0.25)
		(keepout
			(tracks not_allowed)
			(vias allowed)
			(pads allowed)
			(copperpour not_allowed)
			(footprints allowed)
		)
		(placement
			(enabled no)
			(sheetname "")
		)
		(fill yes
			(thermal_gap 0.5)
			(thermal_bridge_width 0.5)
			(island_removal_mode 0)
		)
		(polygon
			(pts
				(arc
					(start 389.16991 -242.864132)
					(mid 388.53999 -242.864132)
					(end 389.16991 -242.864132)
				)
			)
		)
	)
	(zone
		(layers "B.Cu" "In11.Cu" "In13.Cu" "In15.Cu")
		(hatch none 0.5)
		(connect_pads
			(clearance 0)
		)
		(min_thickness 0.25)
		(keepout
			(tracks not_allowed)
			(vias allowed)
			(pads allowed)
			(copperpour not_allowed)
			(footprints allowed)
		)
		(placement
			(enabled no)
			(sheetname "")
		)
		(fill yes
			(thermal_gap 0.5)
			(thermal_bridge_width 0.5)
			(island_removal_mode 0)
		)
		(polygon
			(pts
				(arc
					(start 81.545938 -238.814356)
					(mid 80.916018 -238.814356)
					(end 81.545938 -238.814356)
				)
			)
		)
	)
	(zone
		(layers "B.Cu" "In11.Cu" "In13.Cu" "In15.Cu")
		(hatch none 0.5)
		(connect_pads
			(clearance 0)
		)
		(min_thickness 0.25)
		(keepout
			(tracks not_allowed)
			(vias allowed)
			(pads allowed)
			(copperpour not_allowed)
			(footprints allowed)
		)
		(placement
			(enabled no)
			(sheetname "")
		)
		(fill yes
			(thermal_gap 0.5)
			(thermal_bridge_width 0.5)
			(island_removal_mode 0)
		)
		(polygon
			(pts
				(arc
					(start 273.426174 -226.235006)
					(mid 272.758154 -226.235006)
					(end 273.426174 -226.235006)
				)
			)
		)
	)
	(zone
		(layers "B.Cu" "In11.Cu" "In13.Cu" "In15.Cu")
		(hatch none 0.5)
		(connect_pads
			(clearance 0)
		)
		(min_thickness 0.25)
		(keepout
			(tracks not_allowed)
			(vias allowed)
			(pads allowed)
			(copperpour not_allowed)
			(footprints allowed)
		)
		(placement
			(enabled no)
			(sheetname "")
		)
		(fill yes
			(thermal_gap 0.5)
			(thermal_bridge_width 0.5)
			(island_removal_mode 0)
		)
		(polygon
			(pts
				(arc
					(start 390.136888 -426.089826)
					(mid 389.362696 -426.089826)
					(end 390.136888 -426.089826)
				)
			)
		)
	)
	(zone
		(layers "B.Cu" "In11.Cu" "In13.Cu" "In15.Cu")
		(hatch none 0.5)
		(connect_pads
			(clearance 0)
		)
		(min_thickness 0.25)
		(keepout
			(tracks not_allowed)
			(vias allowed)
			(pads allowed)
			(copperpour not_allowed)
			(footprints allowed)
		)
		(placement
			(enabled no)
			(sheetname "")
		)
		(fill yes
			(thermal_gap 0.5)
			(thermal_bridge_width 0.5)
			(island_removal_mode 0)
		)
		(polygon
			(pts
				(arc
					(start 142.639796 -232.334308)
					(mid 142.009876 -232.334308)
					(end 142.639796 -232.334308)
				)
			)
		)
	)
	(zone
		(layers "B.Cu" "In11.Cu" "In13.Cu" "In15.Cu")
		(hatch none 0.5)
		(connect_pads
			(clearance 0)
		)
		(min_thickness 0.25)
		(keepout
			(tracks not_allowed)
			(vias allowed)
			(pads allowed)
			(copperpour not_allowed)
			(footprints allowed)
		)
		(placement
			(enabled no)
			(sheetname "")
		)
		(fill yes
			(thermal_gap 0.5)
			(thermal_bridge_width 0.5)
			(island_removal_mode 0)
		)
		(polygon
			(pts
				(arc
					(start 390.579864 -225.85426)
					(mid 389.949944 -225.85426)
					(end 390.579864 -225.85426)
				)
			)
		)
	)
	(zone
		(layers "B.Cu" "In11.Cu" "In13.Cu" "In15.Cu")
		(hatch none 0.5)
		(connect_pads
			(clearance 0)
		)
		(min_thickness 0.25)
		(keepout
			(tracks not_allowed)
			(vias allowed)
			(pads allowed)
			(copperpour not_allowed)
			(footprints allowed)
		)
		(placement
			(enabled no)
			(sheetname "")
		)
		(fill yes
			(thermal_gap 0.5)
			(thermal_bridge_width 0.5)
			(island_removal_mode 0)
		)
		(polygon
			(pts
				(arc
					(start 52.055014 -404.46452)
					(mid 51.386994 -404.46452)
					(end 52.055014 -404.46452)
				)
			)
		)
	)
	(zone
		(layers "B.Cu" "In11.Cu" "In13.Cu" "In15.Cu")
		(hatch none 0.5)
		(connect_pads
			(clearance 0)
		)
		(min_thickness 0.25)
		(keepout
			(tracks not_allowed)
			(vias allowed)
			(pads allowed)
			(copperpour not_allowed)
			(footprints allowed)
		)
		(placement
			(enabled no)
			(sheetname "")
		)
		(fill yes
			(thermal_gap 0.5)
			(thermal_bridge_width 0.5)
			(island_removal_mode 0)
		)
		(polygon
			(pts
				(arc
					(start 277.526242 -223.6851)
					(mid 276.858222 -223.6851)
					(end 277.526242 -223.6851)
				)
			)
		)
	)
	(zone
		(layers "B.Cu" "In11.Cu" "In13.Cu" "In15.Cu")
		(hatch none 0.5)
		(connect_pads
			(clearance 0)
		)
		(min_thickness 0.25)
		(keepout
			(tracks not_allowed)
			(vias allowed)
			(pads allowed)
			(copperpour not_allowed)
			(footprints allowed)
		)
		(placement
			(enabled no)
			(sheetname "")
		)
		(fill yes
			(thermal_gap 0.5)
			(thermal_bridge_width 0.5)
			(island_removal_mode 0)
		)
		(polygon
			(pts
				(arc
					(start 194.938142 -199.8853)
					(mid 194.270122 -199.8853)
					(end 194.938142 -199.8853)
				)
			)
		)
	)
	(zone
		(layers "B.Cu" "In11.Cu" "In13.Cu" "In15.Cu")
		(hatch none 0.5)
		(connect_pads
			(clearance 0)
		)
		(min_thickness 0.25)
		(keepout
			(tracks not_allowed)
			(vias allowed)
			(pads allowed)
			(copperpour not_allowed)
			(footprints allowed)
		)
		(placement
			(enabled no)
			(sheetname "")
		)
		(fill yes
			(thermal_gap 0.5)
			(thermal_bridge_width 0.5)
			(island_removal_mode 0)
		)
		(polygon
			(pts
				(arc
					(start 62.932564 -373.96293)
					(mid 62.264544 -373.96293)
					(end 62.932564 -373.96293)
				)
			)
		)
	)
	(zone
		(layers "B.Cu" "In11.Cu" "In13.Cu" "In15.Cu")
		(hatch none 0.5)
		(connect_pads
			(clearance 0)
		)
		(min_thickness 0.25)
		(keepout
			(tracks not_allowed)
			(vias allowed)
			(pads allowed)
			(copperpour not_allowed)
			(footprints allowed)
		)
		(placement
			(enabled no)
			(sheetname "")
		)
		(fill yes
			(thermal_gap 0.5)
			(thermal_bridge_width 0.5)
			(island_removal_mode 0)
		)
		(polygon
			(pts
				(arc
					(start 141.999716 -287.046162)
					(mid 141.369796 -287.046162)
					(end 141.999716 -287.046162)
				)
			)
		)
	)
	(zone
		(layers "B.Cu" "In11.Cu" "In13.Cu" "In15.Cu")
		(hatch none 0.5)
		(connect_pads
			(clearance 0)
		)
		(min_thickness 0.25)
		(keepout
			(tracks not_allowed)
			(vias allowed)
			(pads allowed)
			(copperpour not_allowed)
			(footprints allowed)
		)
		(placement
			(enabled no)
			(sheetname "")
		)
		(fill yes
			(thermal_gap 0.5)
			(thermal_bridge_width 0.5)
			(island_removal_mode 0)
		)
		(polygon
			(pts
				(arc
					(start 141.229842 -254.20447)
					(mid 140.599922 -254.20447)
					(end 141.229842 -254.20447)
				)
			)
		)
	)
	(zone
		(layers "B.Cu" "In11.Cu" "In13.Cu" "In15.Cu")
		(hatch none 0.5)
		(connect_pads
			(clearance 0)
		)
		(min_thickness 0.25)
		(keepout
			(tracks not_allowed)
			(vias allowed)
			(pads allowed)
			(copperpour not_allowed)
			(footprints allowed)
		)
		(placement
			(enabled no)
			(sheetname "")
		)
		(fill yes
			(thermal_gap 0.5)
			(thermal_bridge_width 0.5)
			(island_removal_mode 0)
		)
		(polygon
			(pts
				(arc
					(start 73.036938 -428.28972)
					(mid 72.262746 -428.28972)
					(end 73.036938 -428.28972)
				)
			)
		)
	)
	(zone
		(layers "B.Cu" "In11.Cu" "In13.Cu" "In15.Cu")
		(hatch none 0.5)
		(connect_pads
			(clearance 0)
		)
		(min_thickness 0.25)
		(keepout
			(tracks not_allowed)
			(vias allowed)
			(pads allowed)
			(copperpour not_allowed)
			(footprints allowed)
		)
		(placement
			(enabled no)
			(sheetname "")
		)
		(fill yes
			(thermal_gap 0.5)
			(thermal_bridge_width 0.5)
			(island_removal_mode 0)
		)
		(polygon
			(pts
				(arc
					(start 344.233754 -397.849344)
					(mid 343.603834 -397.849344)
					(end 344.233754 -397.849344)
				)
			)
		)
	)
	(zone
		(layers "B.Cu" "In11.Cu" "In13.Cu" "In15.Cu")
		(hatch none 0.5)
		(connect_pads
			(clearance 0)
		)
		(min_thickness 0.25)
		(keepout
			(tracks not_allowed)
			(vias allowed)
			(pads allowed)
			(copperpour not_allowed)
			(footprints allowed)
		)
		(placement
			(enabled no)
			(sheetname "")
		)
		(fill yes
			(thermal_gap 0.5)
			(thermal_bridge_width 0.5)
			(island_removal_mode 0)
		)
		(polygon
			(pts
				(arc
					(start 273.426174 -233.884978)
					(mid 272.758154 -233.884978)
					(end 273.426174 -233.884978)
				)
			)
		)
	)
	(zone
		(layers "B.Cu" "In11.Cu" "In13.Cu" "In15.Cu")
		(hatch none 0.5)
		(connect_pads
			(clearance 0)
		)
		(min_thickness 0.25)
		(keepout
			(tracks not_allowed)
			(vias allowed)
			(pads allowed)
			(copperpour not_allowed)
			(footprints allowed)
		)
		(placement
			(enabled no)
			(sheetname "")
		)
		(fill yes
			(thermal_gap 0.5)
			(thermal_bridge_width 0.5)
			(island_removal_mode 0)
		)
		(polygon
			(pts
				(arc
					(start 142.337536 -25.90419)
					(mid 141.669516 -25.90419)
					(end 142.337536 -25.90419)
				)
			)
		)
	)
	(zone
		(layers "B.Cu" "In11.Cu" "In13.Cu" "In15.Cu")
		(hatch none 0.5)
		(connect_pads
			(clearance 0)
		)
		(min_thickness 0.25)
		(keepout
			(tracks not_allowed)
			(vias allowed)
			(pads allowed)
			(copperpour not_allowed)
			(footprints allowed)
		)
		(placement
			(enabled no)
			(sheetname "")
		)
		(fill yes
			(thermal_gap 0.5)
			(thermal_bridge_width 0.5)
			(island_removal_mode 0)
		)
		(polygon
			(pts
				(arc
					(start 130.1369 -426.089826)
					(mid 129.362708 -426.089826)
					(end 130.1369 -426.089826)
				)
			)
		)
	)
	(zone
		(layers "B.Cu" "In11.Cu" "In13.Cu" "In15.Cu")
		(hatch none 0.5)
		(connect_pads
			(clearance 0)
		)
		(min_thickness 0.25)
		(keepout
			(tracks not_allowed)
			(vias allowed)
			(pads allowed)
			(copperpour not_allowed)
			(footprints allowed)
		)
		(placement
			(enabled no)
			(sheetname "")
		)
		(fill yes
			(thermal_gap 0.5)
			(thermal_bridge_width 0.5)
			(island_removal_mode 0)
		)
		(polygon
			(pts
				(arc
					(start 199.03821 -214.33536)
					(mid 198.37019 -214.33536)
					(end 199.03821 -214.33536)
				)
			)
		)
	)
	(zone
		(layers "B.Cu" "In11.Cu" "In13.Cu" "In15.Cu")
		(hatch none 0.5)
		(connect_pads
			(clearance 0)
		)
		(min_thickness 0.25)
		(keepout
			(tracks not_allowed)
			(vias allowed)
			(pads allowed)
			(copperpour not_allowed)
			(footprints allowed)
		)
		(placement
			(enabled no)
			(sheetname "")
		)
		(fill yes
			(thermal_gap 0.5)
			(thermal_bridge_width 0.5)
			(island_removal_mode 0)
		)
		(polygon
			(pts
				(arc
					(start 94.940374 -404.46452)
					(mid 94.272354 -404.46452)
					(end 94.940374 -404.46452)
				)
			)
		)
	)
	(zone
		(layers "B.Cu" "In11.Cu" "In13.Cu" "In15.Cu")
		(hatch none 0.5)
		(connect_pads
			(clearance 0)
		)
		(min_thickness 0.25)
		(keepout
			(tracks not_allowed)
			(vias allowed)
			(pads allowed)
			(copperpour not_allowed)
			(footprints allowed)
		)
		(placement
			(enabled no)
			(sheetname "")
		)
		(fill yes
			(thermal_gap 0.5)
			(thermal_bridge_width 0.5)
			(island_removal_mode 0)
		)
		(polygon
			(pts
				(arc
					(start 446.978278 -206.685134)
					(mid 446.310258 -206.685134)
					(end 446.978278 -206.685134)
				)
			)
		)
	)
	(zone
		(layers "B.Cu" "In11.Cu" "In13.Cu" "In15.Cu")
		(hatch none 0.5)
		(connect_pads
			(clearance 0)
		)
		(min_thickness 0.25)
		(keepout
			(tracks not_allowed)
			(vias allowed)
			(pads allowed)
			(copperpour not_allowed)
			(footprints allowed)
		)
		(placement
			(enabled no)
			(sheetname "")
		)
		(fill yes
			(thermal_gap 0.5)
			(thermal_bridge_width 0.5)
			(island_removal_mode 0)
		)
		(polygon
			(pts
				(arc
					(start 71.611744 -376.956828)
					(mid 70.943724 -376.956828)
					(end 71.611744 -376.956828)
				)
			)
		)
	)
	(zone
		(layers "B.Cu" "In11.Cu" "In13.Cu" "In15.Cu")
		(hatch none 0.5)
		(connect_pads
			(clearance 0)
		)
		(min_thickness 0.25)
		(keepout
			(tracks not_allowed)
			(vias allowed)
			(pads allowed)
			(copperpour not_allowed)
			(footprints allowed)
		)
		(placement
			(enabled no)
			(sheetname "")
		)
		(fill yes
			(thermal_gap 0.5)
			(thermal_bridge_width 0.5)
			(island_removal_mode 0)
		)
		(polygon
			(pts
				(arc
					(start 371.309646 -242.864132)
					(mid 370.679726 -242.864132)
					(end 371.309646 -242.864132)
				)
			)
		)
	)
	(zone
		(layers "B.Cu" "In11.Cu" "In13.Cu" "In15.Cu")
		(hatch none 0.5)
		(connect_pads
			(clearance 0)
		)
		(min_thickness 0.25)
		(keepout
			(tracks not_allowed)
			(vias allowed)
			(pads allowed)
			(copperpour not_allowed)
			(footprints allowed)
		)
		(placement
			(enabled no)
			(sheetname "")
		)
		(fill yes
			(thermal_gap 0.5)
			(thermal_bridge_width 0.5)
			(island_removal_mode 0)
		)
		(polygon
			(pts
				(arc
					(start 54.106318 -388.774432)
					(mid 53.476398 -388.774432)
					(end 54.106318 -388.774432)
				)
			)
		)
	)
	(zone
		(layers "B.Cu" "In11.Cu" "In13.Cu" "In15.Cu")
		(hatch none 0.5)
		(connect_pads
			(clearance 0)
		)
		(min_thickness 0.25)
		(keepout
			(tracks not_allowed)
			(vias allowed)
			(pads allowed)
			(copperpour not_allowed)
			(footprints allowed)
		)
		(placement
			(enabled no)
			(sheetname "")
		)
		(fill yes
			(thermal_gap 0.5)
			(thermal_bridge_width 0.5)
			(island_removal_mode 0)
		)
		(polygon
			(pts
				(arc
					(start 100.815902 -241.244374)
					(mid 100.185982 -241.244374)
					(end 100.815902 -241.244374)
				)
			)
		)
	)
	(zone
		(layers "B.Cu" "In11.Cu" "In13.Cu" "In15.Cu")
		(hatch none 0.5)
		(connect_pads
			(clearance 0)
		)
		(min_thickness 0.25)
		(keepout
			(tracks not_allowed)
			(vias allowed)
			(pads allowed)
			(copperpour not_allowed)
			(footprints allowed)
		)
		(placement
			(enabled no)
			(sheetname "")
		)
		(fill yes
			(thermal_gap 0.5)
			(thermal_bridge_width 0.5)
			(island_removal_mode 0)
		)
		(polygon
			(pts
				(arc
					(start 442.87821 -282.33497)
					(mid 442.21019 -282.33497)
					(end 442.87821 -282.33497)
				)
			)
		)
	)
	(zone
		(layers "B.Cu" "In11.Cu" "In13.Cu" "In15.Cu")
		(hatch none 0.5)
		(connect_pads
			(clearance 0)
		)
		(min_thickness 0.25)
		(keepout
			(tracks not_allowed)
			(vias allowed)
			(pads allowed)
			(copperpour not_allowed)
			(footprints allowed)
		)
		(placement
			(enabled no)
			(sheetname "")
		)
		(fill yes
			(thermal_gap 0.5)
			(thermal_bridge_width 0.5)
			(island_removal_mode 0)
		)
		(polygon
			(pts
				(arc
					(start 194.938142 -207.535272)
					(mid 194.270122 -207.535272)
					(end 194.938142 -207.535272)
				)
			)
		)
	)
	(zone
		(layers "B.Cu" "In11.Cu" "In13.Cu" "In15.Cu")
		(hatch none 0.5)
		(connect_pads
			(clearance 0)
		)
		(min_thickness 0.25)
		(keepout
			(tracks not_allowed)
			(vias allowed)
			(pads allowed)
			(copperpour not_allowed)
			(footprints allowed)
		)
		(placement
			(enabled no)
			(sheetname "")
		)
		(fill yes
			(thermal_gap 0.5)
			(thermal_bridge_width 0.5)
			(island_removal_mode 0)
		)
		(polygon
			(pts
				(arc
					(start 390.579864 -230.714296)
					(mid 389.949944 -230.714296)
					(end 390.579864 -230.714296)
				)
			)
		)
	)
	(zone
		(layers "B.Cu" "In11.Cu" "In13.Cu" "In15.Cu")
		(hatch none 0.5)
		(connect_pads
			(clearance 0)
		)
		(min_thickness 0.25)
		(keepout
			(tracks not_allowed)
			(vias allowed)
			(pads allowed)
			(copperpour not_allowed)
			(footprints allowed)
		)
		(placement
			(enabled no)
			(sheetname "")
		)
		(fill yes
			(thermal_gap 0.5)
			(thermal_bridge_width 0.5)
			(island_removal_mode 0)
		)
		(polygon
			(pts
				(arc
					(start 69.036946 -421.089836)
					(mid 68.262754 -421.089836)
					(end 69.036946 -421.089836)
				)
			)
		)
	)
	(zone
		(layers "B.Cu" "In11.Cu" "In13.Cu" "In15.Cu")
		(hatch none 0.5)
		(connect_pads
			(clearance 0)
		)
		(min_thickness 0.25)
		(keepout
			(tracks not_allowed)
			(vias allowed)
			(pads allowed)
			(copperpour not_allowed)
			(footprints allowed)
		)
		(placement
			(enabled no)
			(sheetname "")
		)
		(fill yes
			(thermal_gap 0.5)
			(thermal_bridge_width 0.5)
			(island_removal_mode 0)
		)
		(polygon
			(pts
				(arc
					(start 388.136892 -427.089824)
					(mid 387.3627 -427.089824)
					(end 388.136892 -427.089824)
				)
			)
		)
	)
	(zone
		(layers "B.Cu" "In11.Cu" "In13.Cu" "In15.Cu")
		(hatch none 0.5)
		(connect_pads
			(clearance 0)
		)
		(min_thickness 0.25)
		(keepout
			(tracks not_allowed)
			(vias allowed)
			(pads allowed)
			(copperpour not_allowed)
			(footprints allowed)
		)
		(placement
			(enabled no)
			(sheetname "")
		)
		(fill yes
			(thermal_gap 0.5)
			(thermal_bridge_width 0.5)
			(island_removal_mode 0)
		)
		(polygon
			(pts
				(arc
					(start 60.381134 -404.46452)
					(mid 59.713114 -404.46452)
					(end 60.381134 -404.46452)
				)
			)
		)
	)
	(zone
		(layers "B.Cu" "In11.Cu" "In13.Cu" "In15.Cu")
		(hatch none 0.5)
		(connect_pads
			(clearance 0)
		)
		(min_thickness 0.25)
		(keepout
			(tracks not_allowed)
			(vias allowed)
			(pads allowed)
			(copperpour not_allowed)
			(footprints allowed)
		)
		(placement
			(enabled no)
			(sheetname "")
		)
		(fill yes
			(thermal_gap 0.5)
			(thermal_bridge_width 0.5)
			(island_removal_mode 0)
		)
		(polygon
			(pts
				(arc
					(start 325.739506 -377.41733)
					(mid 325.071486 -377.41733)
					(end 325.739506 -377.41733)
				)
			)
		)
	)
	(zone
		(layers "B.Cu" "In11.Cu" "In13.Cu" "In15.Cu")
		(hatch none 0.5)
		(connect_pads
			(clearance 0)
		)
		(min_thickness 0.25)
		(keepout
			(tracks not_allowed)
			(vias allowed)
			(pads allowed)
			(copperpour not_allowed)
			(footprints allowed)
		)
		(placement
			(enabled no)
			(sheetname "")
		)
		(fill yes
			(thermal_gap 0.5)
			(thermal_bridge_width 0.5)
			(island_removal_mode 0)
		)
		(polygon
			(pts
				(arc
					(start 331.195934 -286.236156)
					(mid 330.566014 -286.236156)
					(end 331.195934 -286.236156)
				)
			)
		)
	)
	(zone
		(layers "B.Cu" "In11.Cu" "In13.Cu" "In15.Cu")
		(hatch none 0.5)
		(connect_pads
			(clearance 0)
		)
		(min_thickness 0.25)
		(keepout
			(tracks not_allowed)
			(vias allowed)
			(pads allowed)
			(copperpour not_allowed)
			(footprints allowed)
		)
		(placement
			(enabled no)
			(sheetname "")
		)
		(fill yes
			(thermal_gap 0.5)
			(thermal_bridge_width 0.5)
			(island_removal_mode 0)
		)
		(polygon
			(pts
				(arc
					(start 329.486006 -255.014222)
					(mid 328.856086 -255.014222)
					(end 329.486006 -255.014222)
				)
			)
		)
	)
	(zone
		(layers "B.Cu" "In11.Cu" "In13.Cu" "In15.Cu")
		(hatch none 0.5)
		(connect_pads
			(clearance 0)
		)
		(min_thickness 0.25)
		(keepout
			(tracks not_allowed)
			(vias allowed)
			(pads allowed)
			(copperpour not_allowed)
			(footprints allowed)
		)
		(placement
			(enabled no)
			(sheetname "")
		)
		(fill yes
			(thermal_gap 0.5)
			(thermal_bridge_width 0.5)
			(island_removal_mode 0)
		)
		(polygon
			(pts
				(arc
					(start 199.03821 -225.385376)
					(mid 198.37019 -225.385376)
					(end 199.03821 -225.385376)
				)
			)
		)
	)
	(zone
		(layers "B.Cu" "In11.Cu" "In13.Cu" "In15.Cu")
		(hatch none 0.5)
		(connect_pads
			(clearance 0)
		)
		(min_thickness 0.25)
		(keepout
			(tracks not_allowed)
			(vias allowed)
			(pads allowed)
			(copperpour not_allowed)
			(footprints allowed)
		)
		(placement
			(enabled no)
			(sheetname "")
		)
		(fill yes
			(thermal_gap 0.5)
			(thermal_bridge_width 0.5)
			(island_removal_mode 0)
		)
		(polygon
			(pts
				(arc
					(start 362.679742 -285.42615)
					(mid 362.049822 -285.42615)
					(end 362.679742 -285.42615)
				)
			)
		)
	)
	(zone
		(layers "B.Cu" "In11.Cu" "In13.Cu" "In15.Cu")
		(hatch none 0.5)
		(connect_pads
			(clearance 0)
		)
		(min_thickness 0.25)
		(keepout
			(tracks not_allowed)
			(vias allowed)
			(pads allowed)
			(copperpour not_allowed)
			(footprints allowed)
		)
		(placement
			(enabled no)
			(sheetname "")
		)
		(fill yes
			(thermal_gap 0.5)
			(thermal_bridge_width 0.5)
			(island_removal_mode 0)
		)
		(polygon
			(pts
				(arc
					(start 330.42606 -240.434114)
					(mid 329.79614 -240.434114)
					(end 330.42606 -240.434114)
				)
			)
		)
	)
	(zone
		(layers "B.Cu" "In11.Cu" "In13.Cu" "In15.Cu")
		(hatch none 0.5)
		(connect_pads
			(clearance 0)
		)
		(min_thickness 0.25)
		(keepout
			(tracks not_allowed)
			(vias allowed)
			(pads allowed)
			(copperpour not_allowed)
			(footprints allowed)
		)
		(placement
			(enabled no)
			(sheetname "")
		)
		(fill yes
			(thermal_gap 0.5)
			(thermal_bridge_width 0.5)
			(island_removal_mode 0)
		)
		(polygon
			(pts
				(arc
					(start 199.03821 -281.48534)
					(mid 198.37019 -281.48534)
					(end 199.03821 -281.48534)
				)
			)
		)
	)
	(zone
		(layers "B.Cu" "In11.Cu" "In13.Cu" "In15.Cu")
		(hatch none 0.5)
		(connect_pads
			(clearance 0)
		)
		(min_thickness 0.25)
		(keepout
			(tracks not_allowed)
			(vias allowed)
			(pads allowed)
			(copperpour not_allowed)
			(footprints allowed)
		)
		(placement
			(enabled no)
			(sheetname "")
		)
		(fill yes
			(thermal_gap 0.5)
			(thermal_bridge_width 0.5)
			(island_removal_mode 0)
		)
		(polygon
			(pts
				(arc
					(start 331.195934 -270.036036)
					(mid 330.566014 -270.036036)
					(end 331.195934 -270.036036)
				)
			)
		)
	)
	(zone
		(layers "B.Cu" "In11.Cu" "In13.Cu" "In15.Cu")
		(hatch none 0.5)
		(connect_pads
			(clearance 0)
		)
		(min_thickness 0.25)
		(keepout
			(tracks not_allowed)
			(vias allowed)
			(pads allowed)
			(copperpour not_allowed)
			(footprints allowed)
		)
		(placement
			(enabled no)
			(sheetname "")
		)
		(fill yes
			(thermal_gap 0.5)
			(thermal_bridge_width 0.5)
			(island_removal_mode 0)
		)
		(polygon
			(pts
				(arc
					(start 199.03821 -317.185294)
					(mid 198.37019 -317.185294)
					(end 199.03821 -317.185294)
				)
			)
		)
	)
	(zone
		(layers "B.Cu" "In11.Cu" "In13.Cu" "In15.Cu")
		(hatch none 0.5)
		(connect_pads
			(clearance 0)
		)
		(min_thickness 0.25)
		(keepout
			(tracks not_allowed)
			(vias allowed)
			(pads allowed)
			(copperpour not_allowed)
			(footprints allowed)
		)
		(placement
			(enabled no)
			(sheetname "")
		)
		(fill yes
			(thermal_gap 0.5)
			(thermal_bridge_width 0.5)
			(island_removal_mode 0)
		)
		(polygon
			(pts
				(arc
					(start 141.699742 -243.674392)
					(mid 141.069822 -243.674392)
					(end 141.699742 -243.674392)
				)
			)
		)
	)
	(zone
		(layers "B.Cu" "In11.Cu" "In13.Cu" "In15.Cu")
		(hatch none 0.5)
		(connect_pads
			(clearance 0)
		)
		(min_thickness 0.25)
		(keepout
			(tracks not_allowed)
			(vias allowed)
			(pads allowed)
			(copperpour not_allowed)
			(footprints allowed)
		)
		(placement
			(enabled no)
			(sheetname "")
		)
		(fill yes
			(thermal_gap 0.5)
			(thermal_bridge_width 0.5)
			(island_removal_mode 0)
		)
		(polygon
			(pts
				(arc
					(start 331.195934 -291.095938)
					(mid 330.566014 -291.095938)
					(end 331.195934 -291.095938)
				)
			)
		)
	)
	(zone
		(layers "B.Cu" "In11.Cu" "In13.Cu" "In15.Cu")
		(hatch none 0.5)
		(connect_pads
			(clearance 0)
		)
		(min_thickness 0.25)
		(keepout
			(tracks not_allowed)
			(vias allowed)
			(pads allowed)
			(copperpour not_allowed)
			(footprints allowed)
		)
		(placement
			(enabled no)
			(sheetname "")
		)
		(fill yes
			(thermal_gap 0.5)
			(thermal_bridge_width 0.5)
			(island_removal_mode 0)
		)
		(polygon
			(pts
				(arc
					(start 81.545938 -245.294404)
					(mid 80.916018 -245.294404)
					(end 81.545938 -245.294404)
				)
			)
		)
	)
	(zone
		(layers "B.Cu" "In11.Cu" "In13.Cu" "In15.Cu")
		(hatch none 0.5)
		(connect_pads
			(clearance 0)
		)
		(min_thickness 0.25)
		(keepout
			(tracks not_allowed)
			(vias allowed)
			(pads allowed)
			(copperpour not_allowed)
			(footprints allowed)
		)
		(placement
			(enabled no)
			(sheetname "")
		)
		(fill yes
			(thermal_gap 0.5)
			(thermal_bridge_width 0.5)
			(island_removal_mode 0)
		)
		(polygon
			(pts
				(arc
					(start 81.845912 -290.286186)
					(mid 81.215992 -290.286186)
					(end 81.845912 -290.286186)
				)
			)
		)
	)
	(zone
		(layers "B.Cu" "In11.Cu" "In13.Cu" "In15.Cu")
		(hatch none 0.5)
		(connect_pads
			(clearance 0)
		)
		(min_thickness 0.25)
		(keepout
			(tracks not_allowed)
			(vias allowed)
			(pads allowed)
			(copperpour not_allowed)
			(footprints allowed)
		)
		(placement
			(enabled no)
			(sheetname "")
		)
		(fill yes
			(thermal_gap 0.5)
			(thermal_bridge_width 0.5)
			(island_removal_mode 0)
		)
		(polygon
			(pts
				(arc
					(start 29.586174 -227.085398)
					(mid 28.918154 -227.085398)
					(end 29.586174 -227.085398)
				)
			)
		)
	)
	(zone
		(layers "B.Cu" "In11.Cu" "In13.Cu" "In15.Cu")
		(hatch none 0.5)
		(connect_pads
			(clearance 0)
		)
		(min_thickness 0.25)
		(keepout
			(tracks not_allowed)
			(vias allowed)
			(pads allowed)
			(copperpour not_allowed)
			(footprints allowed)
		)
		(placement
			(enabled no)
			(sheetname "")
		)
		(fill yes
			(thermal_gap 0.5)
			(thermal_bridge_width 0.5)
			(island_removal_mode 0)
		)
		(polygon
			(pts
				(arc
					(start 390.879838 -274.086066)
					(mid 390.249918 -274.086066)
					(end 390.879838 -274.086066)
				)
			)
		)
	)
	(zone
		(layers "B.Cu" "In11.Cu" "In13.Cu" "In15.Cu")
		(hatch none 0.5)
		(connect_pads
			(clearance 0)
		)
		(min_thickness 0.25)
		(keepout
			(tracks not_allowed)
			(vias allowed)
			(pads allowed)
			(copperpour not_allowed)
			(footprints allowed)
		)
		(placement
			(enabled no)
			(sheetname "")
		)
		(fill yes
			(thermal_gap 0.5)
			(thermal_bridge_width 0.5)
			(island_removal_mode 0)
		)
		(polygon
			(pts
				(arc
					(start 199.03821 -279.785318)
					(mid 198.37019 -279.785318)
					(end 199.03821 -279.785318)
				)
			)
		)
	)
	(zone
		(layers "B.Cu" "In11.Cu" "In13.Cu" "In15.Cu")
		(hatch none 0.5)
		(connect_pads
			(clearance 0)
		)
		(min_thickness 0.25)
		(keepout
			(tracks not_allowed)
			(vias allowed)
			(pads allowed)
			(copperpour not_allowed)
			(footprints allowed)
		)
		(placement
			(enabled no)
			(sheetname "")
		)
		(fill yes
			(thermal_gap 0.5)
			(thermal_bridge_width 0.5)
			(island_removal_mode 0)
		)
		(polygon
			(pts
				(arc
					(start 101.11613 -281.376374)
					(mid 100.48621 -281.376374)
					(end 101.11613 -281.376374)
				)
			)
		)
	)
	(zone
		(layers "B.Cu" "In11.Cu" "In13.Cu" "In15.Cu")
		(hatch none 0.5)
		(connect_pads
			(clearance 0)
		)
		(min_thickness 0.25)
		(keepout
			(tracks not_allowed)
			(vias allowed)
			(pads allowed)
			(copperpour not_allowed)
			(footprints allowed)
		)
		(placement
			(enabled no)
			(sheetname "")
		)
		(fill yes
			(thermal_gap 0.5)
			(thermal_bridge_width 0.5)
			(island_removal_mode 0)
		)
		(polygon
			(pts
				(arc
					(start 143.109696 -229.90429)
					(mid 142.479776 -229.90429)
					(end 143.109696 -229.90429)
				)
			)
		)
	)
	(zone
		(layers "B.Cu" "In11.Cu" "In13.Cu" "In15.Cu")
		(hatch none 0.5)
		(connect_pads
			(clearance 0)
		)
		(min_thickness 0.25)
		(keepout
			(tracks not_allowed)
			(vias allowed)
			(pads allowed)
			(copperpour not_allowed)
			(footprints allowed)
		)
		(placement
			(enabled no)
			(sheetname "")
		)
		(fill yes
			(thermal_gap 0.5)
			(thermal_bridge_width 0.5)
			(island_removal_mode 0)
		)
		(polygon
			(pts
				(arc
					(start 352.233738 -397.156432)
					(mid 351.603818 -397.156432)
					(end 352.233738 -397.156432)
				)
			)
		)
	)
	(zone
		(layers "B.Cu" "In11.Cu" "In13.Cu" "In15.Cu")
		(hatch none 0.5)
		(connect_pads
			(clearance 0)
		)
		(min_thickness 0.25)
		(keepout
			(tracks not_allowed)
			(vias allowed)
			(pads allowed)
			(copperpour not_allowed)
			(footprints allowed)
		)
		(placement
			(enabled no)
			(sheetname "")
		)
		(fill yes
			(thermal_gap 0.5)
			(thermal_bridge_width 0.5)
			(island_removal_mode 0)
		)
		(polygon
			(pts
				(arc
					(start 352.81616 -284.616144)
					(mid 352.18624 -284.616144)
					(end 352.81616 -284.616144)
				)
			)
		)
	)
	(zone
		(layers "B.Cu" "In11.Cu" "In13.Cu" "In15.Cu")
		(hatch none 0.5)
		(connect_pads
			(clearance 0)
		)
		(min_thickness 0.25)
		(keepout
			(tracks not_allowed)
			(vias allowed)
			(pads allowed)
			(copperpour not_allowed)
			(footprints allowed)
		)
		(placement
			(enabled no)
			(sheetname "")
		)
		(fill yes
			(thermal_gap 0.5)
			(thermal_bridge_width 0.5)
			(island_removal_mode 0)
		)
		(polygon
			(pts
				(arc
					(start 49.306226 -388.774432)
					(mid 48.676306 -388.774432)
					(end 49.306226 -388.774432)
				)
			)
		)
	)
	(zone
		(layers "B.Cu" "In11.Cu" "In13.Cu" "In15.Cu")
		(hatch none 0.5)
		(connect_pads
			(clearance 0)
		)
		(min_thickness 0.25)
		(keepout
			(tracks not_allowed)
			(vias allowed)
			(pads allowed)
			(copperpour not_allowed)
			(footprints allowed)
		)
		(placement
			(enabled no)
			(sheetname "")
		)
		(fill yes
			(thermal_gap 0.5)
			(thermal_bridge_width 0.5)
			(island_removal_mode 0)
		)
		(polygon
			(pts
				(arc
					(start 199.03821 -242.385342)
					(mid 198.37019 -242.385342)
					(end 199.03821 -242.385342)
				)
			)
		)
	)
	(zone
		(layers "B.Cu" "In11.Cu" "In13.Cu" "In15.Cu")
		(hatch none 0.5)
		(connect_pads
			(clearance 0)
		)
		(min_thickness 0.25)
		(keepout
			(tracks not_allowed)
			(vias allowed)
			(pads allowed)
			(copperpour not_allowed)
			(footprints allowed)
		)
		(placement
			(enabled no)
			(sheetname "")
		)
		(fill yes
			(thermal_gap 0.5)
			(thermal_bridge_width 0.5)
			(island_removal_mode 0)
		)
		(polygon
			(pts
				(arc
					(start 442.87821 -293.384986)
					(mid 442.21019 -293.384986)
					(end 442.87821 -293.384986)
				)
			)
		)
	)
	(zone
		(layers "B.Cu" "In11.Cu" "In13.Cu" "In15.Cu")
		(hatch none 0.5)
		(connect_pads
			(clearance 0)
		)
		(min_thickness 0.25)
		(keepout
			(tracks not_allowed)
			(vias allowed)
			(pads allowed)
			(copperpour not_allowed)
			(footprints allowed)
		)
		(placement
			(enabled no)
			(sheetname "")
		)
		(fill yes
			(thermal_gap 0.5)
			(thermal_bridge_width 0.5)
			(island_removal_mode 0)
		)
		(polygon
			(pts
				(arc
					(start 64.307974 -404.46452)
					(mid 63.639954 -404.46452)
					(end 64.307974 -404.46452)
				)
			)
		)
	)
	(zone
		(layers "B.Cu" "In11.Cu" "In13.Cu" "In15.Cu")
		(hatch none 0.5)
		(connect_pads
			(clearance 0)
		)
		(min_thickness 0.25)
		(keepout
			(tracks not_allowed)
			(vias allowed)
			(pads allowed)
			(copperpour not_allowed)
			(footprints allowed)
		)
		(placement
			(enabled no)
			(sheetname "")
		)
		(fill yes
			(thermal_gap 0.5)
			(thermal_bridge_width 0.5)
			(island_removal_mode 0)
		)
		(polygon
			(pts
				(arc
					(start 57.827164 -371.49913)
					(mid 57.159144 -371.49913)
					(end 57.827164 -371.49913)
				)
			)
		)
	)
	(zone
		(layers "B.Cu" "In11.Cu" "In13.Cu" "In15.Cu")
		(hatch none 0.5)
		(connect_pads
			(clearance 0)
		)
		(min_thickness 0.25)
		(keepout
			(tracks not_allowed)
			(vias allowed)
			(pads allowed)
			(copperpour not_allowed)
			(footprints allowed)
		)
		(placement
			(enabled no)
			(sheetname "")
		)
		(fill yes
			(thermal_gap 0.5)
			(thermal_bridge_width 0.5)
			(island_removal_mode 0)
		)
		(polygon
			(pts
				(arc
					(start 78.037182 -428.28972)
					(mid 77.26299 -428.28972)
					(end 78.037182 -428.28972)
				)
			)
		)
	)
	(zone
		(layers "B.Cu" "In11.Cu" "In13.Cu" "In15.Cu")
		(hatch none 0.5)
		(connect_pads
			(clearance 0)
		)
		(min_thickness 0.25)
		(keepout
			(tracks not_allowed)
			(vias allowed)
			(pads allowed)
			(copperpour not_allowed)
			(footprints allowed)
		)
		(placement
			(enabled no)
			(sheetname "")
		)
		(fill yes
			(thermal_gap 0.5)
			(thermal_bridge_width 0.5)
			(island_removal_mode 0)
		)
		(polygon
			(pts
				(arc
					(start 25.486106 -250.035314)
					(mid 24.818086 -250.035314)
					(end 25.486106 -250.035314)
				)
			)
		)
	)
	(zone
		(layers "B.Cu" "In11.Cu" "In13.Cu" "In15.Cu")
		(hatch none 0.5)
		(connect_pads
			(clearance 0)
		)
		(min_thickness 0.25)
		(keepout
			(tracks not_allowed)
			(vias allowed)
			(pads allowed)
			(copperpour not_allowed)
			(footprints allowed)
		)
		(placement
			(enabled no)
			(sheetname "")
		)
		(fill yes
			(thermal_gap 0.5)
			(thermal_bridge_width 0.5)
			(island_removal_mode 0)
		)
		(polygon
			(pts
				(arc
					(start 277.526242 -197.33514)
					(mid 276.858222 -197.33514)
					(end 277.526242 -197.33514)
				)
			)
		)
	)
	(zone
		(layers "B.Cu" "In11.Cu" "In13.Cu" "In15.Cu")
		(hatch none 0.5)
		(connect_pads
			(clearance 0)
		)
		(min_thickness 0.25)
		(keepout
			(tracks not_allowed)
			(vias allowed)
			(pads allowed)
			(copperpour not_allowed)
			(footprints allowed)
		)
		(placement
			(enabled no)
			(sheetname "")
		)
		(fill yes
			(thermal_gap 0.5)
			(thermal_bridge_width 0.5)
			(island_removal_mode 0)
		)
		(polygon
			(pts
				(arc
					(start 65.472564 -369.03533)
					(mid 64.804544 -369.03533)
					(end 65.472564 -369.03533)
				)
			)
		)
	)
	(zone
		(layers "B.Cu" "In11.Cu" "In13.Cu" "In15.Cu")
		(hatch none 0.5)
		(connect_pads
			(clearance 0)
		)
		(min_thickness 0.25)
		(keepout
			(tracks not_allowed)
			(vias allowed)
			(pads allowed)
			(copperpour not_allowed)
			(footprints allowed)
		)
		(placement
			(enabled no)
			(sheetname "")
		)
		(fill yes
			(thermal_gap 0.5)
			(thermal_bridge_width 0.5)
			(island_removal_mode 0)
		)
		(polygon
			(pts
				(arc
					(start 25.486106 -318.035432)
					(mid 24.818086 -318.035432)
					(end 25.486106 -318.035432)
				)
			)
		)
	)
	(zone
		(layers "B.Cu" "In11.Cu" "In13.Cu" "In15.Cu")
		(hatch none 0.5)
		(connect_pads
			(clearance 0)
		)
		(min_thickness 0.25)
		(keepout
			(tracks not_allowed)
			(vias allowed)
			(pads allowed)
			(copperpour not_allowed)
			(footprints allowed)
		)
		(placement
			(enabled no)
			(sheetname "")
		)
		(fill yes
			(thermal_gap 0.5)
			(thermal_bridge_width 0.5)
			(island_removal_mode 0)
		)
		(polygon
			(pts
				(arc
					(start 106.455972 -242.864386)
					(mid 105.826052 -242.864386)
					(end 106.455972 -242.864386)
				)
			)
		)
	)
	(zone
		(layers "B.Cu" "In11.Cu" "In13.Cu" "In15.Cu")
		(hatch none 0.5)
		(connect_pads
			(clearance 0)
		)
		(min_thickness 0.25)
		(keepout
			(tracks not_allowed)
			(vias allowed)
			(pads allowed)
			(copperpour not_allowed)
			(footprints allowed)
		)
		(placement
			(enabled no)
			(sheetname "")
		)
		(fill yes
			(thermal_gap 0.5)
			(thermal_bridge_width 0.5)
			(island_removal_mode 0)
		)
		(polygon
			(pts
				(arc
					(start 199.03821 -267.885418)
					(mid 198.37019 -267.885418)
					(end 199.03821 -267.885418)
				)
			)
		)
	)
	(zone
		(layers "B.Cu" "In11.Cu" "In13.Cu" "In15.Cu")
		(hatch none 0.5)
		(connect_pads
			(clearance 0)
		)
		(min_thickness 0.25)
		(keepout
			(tracks not_allowed)
			(vias allowed)
			(pads allowed)
			(copperpour not_allowed)
			(footprints allowed)
		)
		(placement
			(enabled no)
			(sheetname "")
		)
		(fill yes
			(thermal_gap 0.5)
			(thermal_bridge_width 0.5)
			(island_removal_mode 0)
		)
		(polygon
			(pts
				(arc
					(start 376.006106 -397.156432)
					(mid 375.376186 -397.156432)
					(end 376.006106 -397.156432)
				)
			)
		)
	)
	(zone
		(layers "B.Cu" "In11.Cu" "In13.Cu" "In15.Cu")
		(hatch none 0.5)
		(connect_pads
			(clearance 0)
		)
		(min_thickness 0.25)
		(keepout
			(tracks not_allowed)
			(vias allowed)
			(pads allowed)
			(copperpour not_allowed)
			(footprints allowed)
		)
		(placement
			(enabled no)
			(sheetname "")
		)
		(fill yes
			(thermal_gap 0.5)
			(thermal_bridge_width 0.5)
			(island_removal_mode 0)
		)
		(polygon
			(pts
				(arc
					(start 277.526242 -289.135058)
					(mid 276.858222 -289.135058)
					(end 277.526242 -289.135058)
				)
			)
		)
	)
	(zone
		(layers "B.Cu" "In11.Cu" "In13.Cu" "In15.Cu")
		(hatch none 0.5)
		(connect_pads
			(clearance 0)
		)
		(min_thickness 0.25)
		(keepout
			(tracks not_allowed)
			(vias allowed)
			(pads allowed)
			(copperpour not_allowed)
			(footprints allowed)
		)
		(placement
			(enabled no)
			(sheetname "")
		)
		(fill yes
			(thermal_gap 0.5)
			(thermal_bridge_width 0.5)
			(island_removal_mode 0)
		)
		(polygon
			(pts
				(arc
					(start 331.195934 -266.796012)
					(mid 330.566014 -266.796012)
					(end 331.195934 -266.796012)
				)
			)
		)
	)
	(zone
		(layers "B.Cu" "In11.Cu" "In13.Cu" "In15.Cu")
		(hatch none 0.5)
		(connect_pads
			(clearance 0)
		)
		(min_thickness 0.25)
		(keepout
			(tracks not_allowed)
			(vias allowed)
			(pads allowed)
			(copperpour not_allowed)
			(footprints allowed)
		)
		(placement
			(enabled no)
			(sheetname "")
		)
		(fill yes
			(thermal_gap 0.5)
			(thermal_bridge_width 0.5)
			(island_removal_mode 0)
		)
		(polygon
			(pts
				(arc
					(start 323.036692 -426.089826)
					(mid 322.2625 -426.089826)
					(end 323.036692 -426.089826)
				)
			)
		)
	)
	(zone
		(layers "B.Cu" "In11.Cu" "In13.Cu" "In15.Cu")
		(hatch none 0.5)
		(connect_pads
			(clearance 0)
		)
		(min_thickness 0.25)
		(keepout
			(tracks not_allowed)
			(vias allowed)
			(pads allowed)
			(copperpour not_allowed)
			(footprints allowed)
		)
		(placement
			(enabled no)
			(sheetname "")
		)
		(fill yes
			(thermal_gap 0.5)
			(thermal_bridge_width 0.5)
			(island_removal_mode 0)
		)
		(polygon
			(pts
				(arc
					(start 53.306218 -389.467344)
					(mid 52.676298 -389.467344)
					(end 53.306218 -389.467344)
				)
			)
		)
	)
	(zone
		(layers "B.Cu" "In11.Cu" "In13.Cu" "In15.Cu")
		(hatch none 0.5)
		(connect_pads
			(clearance 0)
		)
		(min_thickness 0.25)
		(keepout
			(tracks not_allowed)
			(vias allowed)
			(pads allowed)
			(copperpour not_allowed)
			(footprints allowed)
		)
		(placement
			(enabled no)
			(sheetname "")
		)
		(fill yes
			(thermal_gap 0.5)
			(thermal_bridge_width 0.5)
			(island_removal_mode 0)
		)
		(polygon
			(pts
				(arc
					(start 194.938142 -204.135228)
					(mid 194.270122 -204.135228)
					(end 194.938142 -204.135228)
				)
			)
		)
	)
	(zone
		(layers "B.Cu" "In11.Cu" "In13.Cu" "In15.Cu")
		(hatch none 0.5)
		(connect_pads
			(clearance 0)
		)
		(min_thickness 0.25)
		(keepout
			(tracks not_allowed)
			(vias allowed)
			(pads allowed)
			(copperpour not_allowed)
			(footprints allowed)
		)
		(placement
			(enabled no)
			(sheetname "")
		)
		(fill yes
			(thermal_gap 0.5)
			(thermal_bridge_width 0.5)
			(island_removal_mode 0)
		)
		(polygon
			(pts
				(arc
					(start 134.136892 -427.289976)
					(mid 133.3627 -427.289976)
					(end 134.136892 -427.289976)
				)
			)
		)
	)
	(zone
		(layers "B.Cu" "In11.Cu" "In13.Cu" "In15.Cu")
		(hatch none 0.5)
		(connect_pads
			(clearance 0)
		)
		(min_thickness 0.25)
		(keepout
			(tracks not_allowed)
			(vias allowed)
			(pads allowed)
			(copperpour not_allowed)
			(footprints allowed)
		)
		(placement
			(enabled no)
			(sheetname "")
		)
		(fill yes
			(thermal_gap 0.5)
			(thermal_bridge_width 0.5)
			(island_removal_mode 0)
		)
		(polygon
			(pts
				(arc
					(start 29.586174 -306.135278)
					(mid 28.918154 -306.135278)
					(end 29.586174 -306.135278)
				)
			)
		)
	)
	(zone
		(layers "B.Cu" "In11.Cu" "In13.Cu" "In15.Cu")
		(hatch none 0.5)
		(connect_pads
			(clearance 0)
		)
		(min_thickness 0.25)
		(keepout
			(tracks not_allowed)
			(vias allowed)
			(pads allowed)
			(copperpour not_allowed)
			(footprints allowed)
		)
		(placement
			(enabled no)
			(sheetname "")
		)
		(fill yes
			(thermal_gap 0.5)
			(thermal_bridge_width 0.5)
			(island_removal_mode 0)
		)
		(polygon
			(pts
				(arc
					(start 273.426174 -235.585)
					(mid 272.758154 -235.585)
					(end 273.426174 -235.585)
				)
			)
		)
	)
	(zone
		(layers "B.Cu" "In11.Cu" "In13.Cu" "In15.Cu")
		(hatch none 0.5)
		(connect_pads
			(clearance 0)
		)
		(min_thickness 0.25)
		(keepout
			(tracks not_allowed)
			(vias allowed)
			(pads allowed)
			(copperpour not_allowed)
			(footprints allowed)
		)
		(placement
			(enabled no)
			(sheetname "")
		)
		(fill yes
			(thermal_gap 0.5)
			(thermal_bridge_width 0.5)
			(island_removal_mode 0)
		)
		(polygon
			(pts
				(arc
					(start 405.333962 -394.385292)
					(mid 404.704042 -394.385292)
					(end 405.333962 -394.385292)
				)
			)
		)
	)
	(zone
		(layers "B.Cu" "In11.Cu" "In13.Cu" "In15.Cu")
		(hatch none 0.5)
		(connect_pads
			(clearance 0)
		)
		(min_thickness 0.25)
		(keepout
			(tracks not_allowed)
			(vias allowed)
			(pads allowed)
			(copperpour not_allowed)
			(footprints allowed)
		)
		(placement
			(enabled no)
			(sheetname "")
		)
		(fill yes
			(thermal_gap 0.5)
			(thermal_bridge_width 0.5)
			(island_removal_mode 0)
		)
		(polygon
			(pts
				(arc
					(start 81.545938 -246.914416)
					(mid 80.916018 -246.914416)
					(end 81.545938 -246.914416)
				)
			)
		)
	)
	(zone
		(layers "B.Cu" "In11.Cu" "In13.Cu" "In15.Cu")
		(hatch none 0.5)
		(connect_pads
			(clearance 0)
		)
		(min_thickness 0.25)
		(keepout
			(tracks not_allowed)
			(vias allowed)
			(pads allowed)
			(copperpour not_allowed)
			(footprints allowed)
		)
		(placement
			(enabled no)
			(sheetname "")
		)
		(fill yes
			(thermal_gap 0.5)
			(thermal_bridge_width 0.5)
			(island_removal_mode 0)
		)
		(polygon
			(pts
				(arc
					(start 194.938142 -278.935434)
					(mid 194.270122 -278.935434)
					(end 194.938142 -278.935434)
				)
			)
		)
	)
	(zone
		(layers "B.Cu" "In11.Cu" "In13.Cu" "In15.Cu")
		(hatch none 0.5)
		(connect_pads
			(clearance 0)
		)
		(min_thickness 0.25)
		(keepout
			(tracks not_allowed)
			(vias allowed)
			(pads allowed)
			(copperpour not_allowed)
			(footprints allowed)
		)
		(placement
			(enabled no)
			(sheetname "")
		)
		(fill yes
			(thermal_gap 0.5)
			(thermal_bridge_width 0.5)
			(island_removal_mode 0)
		)
		(polygon
			(pts
				(arc
					(start 389.206232 -397.156432)
					(mid 388.576312 -397.156432)
					(end 389.206232 -397.156432)
				)
			)
		)
	)
	(zone
		(layers "B.Cu" "In11.Cu" "In13.Cu" "In15.Cu")
		(hatch none 0.5)
		(connect_pads
			(clearance 0)
		)
		(min_thickness 0.25)
		(keepout
			(tracks not_allowed)
			(vias allowed)
			(pads allowed)
			(copperpour not_allowed)
			(footprints allowed)
		)
		(placement
			(enabled no)
			(sheetname "")
		)
		(fill yes
			(thermal_gap 0.5)
			(thermal_bridge_width 0.5)
			(island_removal_mode 0)
		)
		(polygon
			(pts
				(arc
					(start 130.95097 -24.675084)
					(mid 130.28295 -24.675084)
					(end 130.95097 -24.675084)
				)
			)
		)
	)
	(zone
		(layers "B.Cu" "In11.Cu" "In13.Cu" "In15.Cu")
		(hatch none 0.5)
		(connect_pads
			(clearance 0)
		)
		(min_thickness 0.25)
		(keepout
			(tracks not_allowed)
			(vias allowed)
			(pads allowed)
			(copperpour not_allowed)
			(footprints allowed)
		)
		(placement
			(enabled no)
			(sheetname "")
		)
		(fill yes
			(thermal_gap 0.5)
			(thermal_bridge_width 0.5)
			(island_removal_mode 0)
		)
		(polygon
			(pts
				(arc
					(start 277.526242 -231.335072)
					(mid 276.858222 -231.335072)
					(end 277.526242 -231.335072)
				)
			)
		)
	)
	(zone
		(layers "B.Cu" "In11.Cu" "In13.Cu" "In15.Cu")
		(hatch none 0.5)
		(connect_pads
			(clearance 0)
		)
		(min_thickness 0.25)
		(keepout
			(tracks not_allowed)
			(vias allowed)
			(pads allowed)
			(copperpour not_allowed)
			(footprints allowed)
		)
		(placement
			(enabled no)
			(sheetname "")
		)
		(fill yes
			(thermal_gap 0.5)
			(thermal_bridge_width 0.5)
			(island_removal_mode 0)
		)
		(polygon
			(pts
				(arc
					(start 327.036684 -426.089826)
					(mid 326.262492 -426.089826)
					(end 327.036684 -426.089826)
				)
			)
		)
	)
	(zone
		(layers "B.Cu" "In11.Cu" "In13.Cu" "In15.Cu")
		(hatch none 0.5)
		(connect_pads
			(clearance 0)
		)
		(min_thickness 0.25)
		(keepout
			(tracks not_allowed)
			(vias allowed)
			(pads allowed)
			(copperpour not_allowed)
			(footprints allowed)
		)
		(placement
			(enabled no)
			(sheetname "")
		)
		(fill yes
			(thermal_gap 0.5)
			(thermal_bridge_width 0.5)
			(island_removal_mode 0)
		)
		(polygon
			(pts
				(arc
					(start 143.109696 -252.584458)
					(mid 142.479776 -252.584458)
					(end 143.109696 -252.584458)
				)
			)
		)
	)
	(zone
		(layers "B.Cu" "In11.Cu" "In13.Cu" "In15.Cu")
		(hatch none 0.5)
		(connect_pads
			(clearance 0)
		)
		(min_thickness 0.25)
		(keepout
			(tracks not_allowed)
			(vias allowed)
			(pads allowed)
			(copperpour not_allowed)
			(footprints allowed)
		)
		(placement
			(enabled no)
			(sheetname "")
		)
		(fill yes
			(thermal_gap 0.5)
			(thermal_bridge_width 0.5)
			(island_removal_mode 0)
		)
		(polygon
			(pts
				(arc
					(start 194.938142 -267.03528)
					(mid 194.270122 -267.03528)
					(end 194.938142 -267.03528)
				)
			)
		)
	)
	(zone
		(layers "B.Cu" "In11.Cu" "In13.Cu" "In15.Cu")
		(hatch none 0.5)
		(connect_pads
			(clearance 0)
		)
		(min_thickness 0.25)
		(keepout
			(tracks not_allowed)
			(vias allowed)
			(pads allowed)
			(copperpour not_allowed)
			(footprints allowed)
		)
		(placement
			(enabled no)
			(sheetname "")
		)
		(fill yes
			(thermal_gap 0.5)
			(thermal_bridge_width 0.5)
			(island_removal_mode 0)
		)
		(polygon
			(pts
				(arc
					(start 69.570854 -404.46452)
					(mid 68.902834 -404.46452)
					(end 69.570854 -404.46452)
				)
			)
		)
	)
	(zone
		(layers "B.Cu" "In11.Cu" "In13.Cu" "In15.Cu")
		(hatch none 0.5)
		(connect_pads
			(clearance 0)
		)
		(min_thickness 0.25)
		(keepout
			(tracks not_allowed)
			(vias allowed)
			(pads allowed)
			(copperpour not_allowed)
			(footprints allowed)
		)
		(placement
			(enabled no)
			(sheetname "")
		)
		(fill yes
			(thermal_gap 0.5)
			(thermal_bridge_width 0.5)
			(island_removal_mode 0)
		)
		(polygon
			(pts
				(arc
					(start 123.669806 -284.616398)
					(mid 123.039886 -284.616398)
					(end 123.669806 -284.616398)
				)
			)
		)
	)
	(zone
		(layers "B.Cu" "In11.Cu" "In13.Cu" "In15.Cu")
		(hatch none 0.5)
		(connect_pads
			(clearance 0)
		)
		(min_thickness 0.25)
		(keepout
			(tracks not_allowed)
			(vias allowed)
			(pads allowed)
			(copperpour not_allowed)
			(footprints allowed)
		)
		(placement
			(enabled no)
			(sheetname "")
		)
		(fill yes
			(thermal_gap 0.5)
			(thermal_bridge_width 0.5)
			(island_removal_mode 0)
		)
		(polygon
			(pts
				(arc
					(start 194.938142 -313.78525)
					(mid 194.270122 -313.78525)
					(end 194.938142 -313.78525)
				)
			)
		)
	)
	(zone
		(layers "B.Cu" "In11.Cu" "In13.Cu" "In15.Cu")
		(hatch none 0.5)
		(connect_pads
			(clearance 0)
		)
		(min_thickness 0.25)
		(keepout
			(tracks not_allowed)
			(vias allowed)
			(pads allowed)
			(copperpour not_allowed)
			(footprints allowed)
		)
		(placement
			(enabled no)
			(sheetname "")
		)
		(fill yes
			(thermal_gap 0.5)
			(thermal_bridge_width 0.5)
			(island_removal_mode 0)
		)
		(polygon
			(pts
				(arc
					(start 349.833692 -397.156432)
					(mid 349.203772 -397.156432)
					(end 349.833692 -397.156432)
				)
			)
		)
	)
	(zone
		(layers "B.Cu" "In11.Cu" "In13.Cu" "In15.Cu")
		(hatch none 0.5)
		(connect_pads
			(clearance 0)
		)
		(min_thickness 0.25)
		(keepout
			(tracks not_allowed)
			(vias allowed)
			(pads allowed)
			(copperpour not_allowed)
			(footprints allowed)
		)
		(placement
			(enabled no)
			(sheetname "")
		)
		(fill yes
			(thermal_gap 0.5)
			(thermal_bridge_width 0.5)
			(island_removal_mode 0)
		)
		(polygon
			(pts
				(arc
					(start 391.349738 -282.996132)
					(mid 390.719818 -282.996132)
					(end 391.349738 -282.996132)
				)
			)
		)
	)
	(zone
		(layers "B.Cu" "In11.Cu" "In13.Cu" "In15.Cu")
		(hatch none 0.5)
		(connect_pads
			(clearance 0)
		)
		(min_thickness 0.25)
		(keepout
			(tracks not_allowed)
			(vias allowed)
			(pads allowed)
			(copperpour not_allowed)
			(footprints allowed)
		)
		(placement
			(enabled no)
			(sheetname "")
		)
		(fill yes
			(thermal_gap 0.5)
			(thermal_bridge_width 0.5)
			(island_removal_mode 0)
		)
		(polygon
			(pts
				(arc
					(start 329.78598 -290.285932)
					(mid 329.15606 -290.285932)
					(end 329.78598 -290.285932)
				)
			)
		)
	)
	(zone
		(layers "B.Cu" "In11.Cu" "In13.Cu" "In15.Cu")
		(hatch none 0.5)
		(connect_pads
			(clearance 0)
		)
		(min_thickness 0.25)
		(keepout
			(tracks not_allowed)
			(vias allowed)
			(pads allowed)
			(copperpour not_allowed)
			(footprints allowed)
		)
		(placement
			(enabled no)
			(sheetname "")
		)
		(fill yes
			(thermal_gap 0.5)
			(thermal_bridge_width 0.5)
			(island_removal_mode 0)
		)
		(polygon
			(pts
				(arc
					(start 446.978278 -283.185108)
					(mid 446.310258 -283.185108)
					(end 446.978278 -283.185108)
				)
			)
		)
	)
	(zone
		(layers "B.Cu" "In11.Cu" "In13.Cu" "In15.Cu")
		(hatch none 0.5)
		(connect_pads
			(clearance 0)
		)
		(min_thickness 0.25)
		(keepout
			(tracks not_allowed)
			(vias allowed)
			(pads allowed)
			(copperpour not_allowed)
			(footprints allowed)
		)
		(placement
			(enabled no)
			(sheetname "")
		)
		(fill yes
			(thermal_gap 0.5)
			(thermal_bridge_width 0.5)
			(island_removal_mode 0)
		)
		(polygon
			(pts
				(arc
					(start 442.87821 -318.035178)
					(mid 442.21019 -318.035178)
					(end 442.87821 -318.035178)
				)
			)
		)
	)
	(zone
		(layers "B.Cu" "In11.Cu" "In13.Cu" "In15.Cu")
		(hatch none 0.5)
		(connect_pads
			(clearance 0)
		)
		(min_thickness 0.25)
		(keepout
			(tracks not_allowed)
			(vias allowed)
			(pads allowed)
			(copperpour not_allowed)
			(footprints allowed)
		)
		(placement
			(enabled no)
			(sheetname "")
		)
		(fill yes
			(thermal_gap 0.5)
			(thermal_bridge_width 0.5)
			(island_removal_mode 0)
		)
		(polygon
			(pts
				(arc
					(start 339.033866 -397.156432)
					(mid 338.403946 -397.156432)
					(end 339.033866 -397.156432)
				)
			)
		)
	)
	(zone
		(layers "B.Cu" "In11.Cu" "In13.Cu" "In15.Cu")
		(hatch none 0.5)
		(connect_pads
			(clearance 0)
		)
		(min_thickness 0.25)
		(keepout
			(tracks not_allowed)
			(vias allowed)
			(pads allowed)
			(copperpour not_allowed)
			(footprints allowed)
		)
		(placement
			(enabled no)
			(sheetname "")
		)
		(fill yes
			(thermal_gap 0.5)
			(thermal_bridge_width 0.5)
			(island_removal_mode 0)
		)
		(polygon
			(pts
				(arc
					(start 29.586174 -199.035416)
					(mid 28.918154 -199.035416)
					(end 29.586174 -199.035416)
				)
			)
		)
	)
	(zone
		(layers "B.Cu" "In11.Cu" "In13.Cu" "In15.Cu")
		(hatch none 0.5)
		(connect_pads
			(clearance 0)
		)
		(min_thickness 0.25)
		(keepout
			(tracks not_allowed)
			(vias allowed)
			(pads allowed)
			(copperpour not_allowed)
			(footprints allowed)
		)
		(placement
			(enabled no)
			(sheetname "")
		)
		(fill yes
			(thermal_gap 0.5)
			(thermal_bridge_width 0.5)
			(island_removal_mode 0)
		)
		(polygon
			(pts
				(arc
					(start 59.036966 -426.089826)
					(mid 58.262774 -426.089826)
					(end 59.036966 -426.089826)
				)
			)
		)
	)
	(zone
		(layers "B.Cu" "In11.Cu" "In13.Cu" "In15.Cu")
		(hatch none 0.5)
		(connect_pads
			(clearance 0)
		)
		(min_thickness 0.25)
		(keepout
			(tracks not_allowed)
			(vias allowed)
			(pads allowed)
			(copperpour not_allowed)
			(footprints allowed)
		)
		(placement
			(enabled no)
			(sheetname "")
		)
		(fill yes
			(thermal_gap 0.5)
			(thermal_bridge_width 0.5)
			(island_removal_mode 0)
		)
		(polygon
			(pts
				(arc
					(start 148.13407 -386.003292)
					(mid 147.50415 -386.003292)
					(end 148.13407 -386.003292)
				)
			)
		)
	)
	(zone
		(layers "B.Cu" "In11.Cu" "In13.Cu" "In15.Cu")
		(hatch none 0.5)
		(connect_pads
			(clearance 0)
		)
		(min_thickness 0.25)
		(keepout
			(tracks not_allowed)
			(vias allowed)
			(pads allowed)
			(copperpour not_allowed)
			(footprints allowed)
		)
		(placement
			(enabled no)
			(sheetname "")
		)
		(fill yes
			(thermal_gap 0.5)
			(thermal_bridge_width 0.5)
			(island_removal_mode 0)
		)
		(polygon
			(pts
				(arc
					(start 199.03821 -300.185328)
					(mid 198.37019 -300.185328)
					(end 199.03821 -300.185328)
				)
			)
		)
	)
	(zone
		(layers "B.Cu" "In11.Cu" "In13.Cu" "In15.Cu")
		(hatch none 0.5)
		(connect_pads
			(clearance 0)
		)
		(min_thickness 0.25)
		(keepout
			(tracks not_allowed)
			(vias allowed)
			(pads allowed)
			(copperpour not_allowed)
			(footprints allowed)
		)
		(placement
			(enabled no)
			(sheetname "")
		)
		(fill yes
			(thermal_gap 0.5)
			(thermal_bridge_width 0.5)
			(island_removal_mode 0)
		)
		(polygon
			(pts
				(arc
					(start 446.978278 -315.485018)
					(mid 446.310258 -315.485018)
					(end 446.978278 -315.485018)
				)
			)
		)
	)
	(zone
		(layers "B.Cu" "In11.Cu" "In13.Cu" "In15.Cu")
		(hatch none 0.5)
		(connect_pads
			(clearance 0)
		)
		(min_thickness 0.25)
		(keepout
			(tracks not_allowed)
			(vias allowed)
			(pads allowed)
			(copperpour not_allowed)
			(footprints allowed)
		)
		(placement
			(enabled no)
			(sheetname "")
		)
		(fill yes
			(thermal_gap 0.5)
			(thermal_bridge_width 0.5)
			(island_removal_mode 0)
		)
		(polygon
			(pts
				(arc
					(start 446.978278 -233.035094)
					(mid 446.310258 -233.035094)
					(end 446.978278 -233.035094)
				)
			)
		)
	)
	(zone
		(layers "B.Cu" "In11.Cu" "In13.Cu" "In15.Cu")
		(hatch none 0.5)
		(connect_pads
			(clearance 0)
		)
		(min_thickness 0.25)
		(keepout
			(tracks not_allowed)
			(vias allowed)
			(pads allowed)
			(copperpour not_allowed)
			(footprints allowed)
		)
		(placement
			(enabled no)
			(sheetname "")
		)
		(fill yes
			(thermal_gap 0.5)
			(thermal_bridge_width 0.5)
			(island_removal_mode 0)
		)
		(polygon
			(pts
				(arc
					(start 29.586174 -229.635304)
					(mid 28.918154 -229.635304)
					(end 29.586174 -229.635304)
				)
			)
		)
	)
	(zone
		(layers "B.Cu" "In11.Cu" "In13.Cu" "In15.Cu")
		(hatch none 0.5)
		(connect_pads
			(clearance 0)
		)
		(min_thickness 0.25)
		(keepout
			(tracks not_allowed)
			(vias allowed)
			(pads allowed)
			(copperpour not_allowed)
			(footprints allowed)
		)
		(placement
			(enabled no)
			(sheetname "")
		)
		(fill yes
			(thermal_gap 0.5)
			(thermal_bridge_width 0.5)
			(island_removal_mode 0)
		)
		(polygon
			(pts
				(arc
					(start 330.42606 -233.954066)
					(mid 329.79614 -233.954066)
					(end 330.42606 -233.954066)
				)
			)
		)
	)
	(zone
		(layers "B.Cu" "In11.Cu" "In13.Cu" "In15.Cu")
		(hatch none 0.5)
		(connect_pads
			(clearance 0)
		)
		(min_thickness 0.25)
		(keepout
			(tracks not_allowed)
			(vias allowed)
			(pads allowed)
			(copperpour not_allowed)
			(footprints allowed)
		)
		(placement
			(enabled no)
			(sheetname "")
		)
		(fill yes
			(thermal_gap 0.5)
			(thermal_bridge_width 0.5)
			(island_removal_mode 0)
		)
		(polygon
			(pts
				(arc
					(start 357.986076 -283.806138)
					(mid 357.356156 -283.806138)
					(end 357.986076 -283.806138)
				)
			)
		)
	)
	(zone
		(layers "B.Cu" "In11.Cu" "In13.Cu" "In15.Cu")
		(hatch none 0.5)
		(connect_pads
			(clearance 0)
		)
		(min_thickness 0.25)
		(keepout
			(tracks not_allowed)
			(vias allowed)
			(pads allowed)
			(copperpour not_allowed)
			(footprints allowed)
		)
		(placement
			(enabled no)
			(sheetname "")
		)
		(fill yes
			(thermal_gap 0.5)
			(thermal_bridge_width 0.5)
			(island_removal_mode 0)
		)
		(polygon
			(pts
				(arc
					(start 329.016106 -238.004096)
					(mid 328.386186 -238.004096)
					(end 329.016106 -238.004096)
				)
			)
		)
	)
	(zone
		(layers "B.Cu" "In11.Cu" "In13.Cu" "In15.Cu")
		(hatch none 0.5)
		(connect_pads
			(clearance 0)
		)
		(min_thickness 0.25)
		(keepout
			(tracks not_allowed)
			(vias allowed)
			(pads allowed)
			(copperpour not_allowed)
			(footprints allowed)
		)
		(placement
			(enabled no)
			(sheetname "")
		)
		(fill yes
			(thermal_gap 0.5)
			(thermal_bridge_width 0.5)
			(island_removal_mode 0)
		)
		(polygon
			(pts
				(arc
					(start 389.63981 -255.014222)
					(mid 389.00989 -255.014222)
					(end 389.63981 -255.014222)
				)
			)
		)
	)
	(zone
		(layers "B.Cu" "In11.Cu" "In13.Cu" "In15.Cu")
		(hatch none 0.5)
		(connect_pads
			(clearance 0)
		)
		(min_thickness 0.25)
		(keepout
			(tracks not_allowed)
			(vias allowed)
			(pads allowed)
			(copperpour not_allowed)
			(footprints allowed)
		)
		(placement
			(enabled no)
			(sheetname "")
		)
		(fill yes
			(thermal_gap 0.5)
			(thermal_bridge_width 0.5)
			(island_removal_mode 0)
		)
		(polygon
			(pts
				(arc
					(start 161.333942 -386.003292)
					(mid 160.704022 -386.003292)
					(end 161.333942 -386.003292)
				)
			)
		)
	)
	(zone
		(layers "B.Cu" "In11.Cu" "In13.Cu" "In15.Cu")
		(hatch none 0.5)
		(connect_pads
			(clearance 0)
		)
		(min_thickness 0.25)
		(keepout
			(tracks not_allowed)
			(vias allowed)
			(pads allowed)
			(copperpour not_allowed)
			(footprints allowed)
		)
		(placement
			(enabled no)
			(sheetname "")
		)
		(fill yes
			(thermal_gap 0.5)
			(thermal_bridge_width 0.5)
			(island_removal_mode 0)
		)
		(polygon
			(pts
				(arc
					(start 83.255866 -284.616398)
					(mid 82.625946 -284.616398)
					(end 83.255866 -284.616398)
				)
			)
		)
	)
	(zone
		(layers "B.Cu" "In11.Cu" "In13.Cu" "In15.Cu")
		(hatch none 0.5)
		(connect_pads
			(clearance 0)
		)
		(min_thickness 0.25)
		(keepout
			(tracks not_allowed)
			(vias allowed)
			(pads allowed)
			(copperpour not_allowed)
			(footprints allowed)
		)
		(placement
			(enabled no)
			(sheetname "")
		)
		(fill yes
			(thermal_gap 0.5)
			(thermal_bridge_width 0.5)
			(island_removal_mode 0)
		)
		(polygon
			(pts
				(arc
					(start 277.526242 -227.085144)
					(mid 276.858222 -227.085144)
					(end 277.526242 -227.085144)
				)
			)
		)
	)
	(zone
		(layers "B.Cu" "In11.Cu" "In13.Cu" "In15.Cu")
		(hatch none 0.5)
		(connect_pads
			(clearance 0)
		)
		(min_thickness 0.25)
		(keepout
			(tracks not_allowed)
			(vias allowed)
			(pads allowed)
			(copperpour not_allowed)
			(footprints allowed)
		)
		(placement
			(enabled no)
			(sheetname "")
		)
		(fill yes
			(thermal_gap 0.5)
			(thermal_bridge_width 0.5)
			(island_removal_mode 0)
		)
		(polygon
			(pts
				(arc
					(start 29.586174 -214.33536)
					(mid 28.918154 -214.33536)
					(end 29.586174 -214.33536)
				)
			)
		)
	)
	(zone
		(layers "B.Cu" "In11.Cu" "In13.Cu" "In15.Cu")
		(hatch none 0.5)
		(connect_pads
			(clearance 0)
		)
		(min_thickness 0.25)
		(keepout
			(tracks not_allowed)
			(vias allowed)
			(pads allowed)
			(copperpour not_allowed)
			(footprints allowed)
		)
		(placement
			(enabled no)
			(sheetname "")
		)
		(fill yes
			(thermal_gap 0.5)
			(thermal_bridge_width 0.5)
			(island_removal_mode 0)
		)
		(polygon
			(pts
				(arc
					(start 199.03821 -238.135414)
					(mid 198.37019 -238.135414)
					(end 199.03821 -238.135414)
				)
			)
		)
	)
	(zone
		(layers "B.Cu" "In11.Cu" "In13.Cu" "In15.Cu")
		(hatch none 0.5)
		(connect_pads
			(clearance 0)
		)
		(min_thickness 0.25)
		(keepout
			(tracks not_allowed)
			(vias allowed)
			(pads allowed)
			(copperpour not_allowed)
			(footprints allowed)
		)
		(placement
			(enabled no)
			(sheetname "")
		)
		(fill yes
			(thermal_gap 0.5)
			(thermal_bridge_width 0.5)
			(island_removal_mode 0)
		)
		(polygon
			(pts
				(arc
					(start 273.426174 -313.784996)
					(mid 272.758154 -313.784996)
					(end 273.426174 -313.784996)
				)
			)
		)
	)
	(zone
		(layers "B.Cu" "In11.Cu" "In13.Cu" "In15.Cu")
		(hatch none 0.5)
		(connect_pads
			(clearance 0)
		)
		(min_thickness 0.25)
		(keepout
			(tracks not_allowed)
			(vias allowed)
			(pads allowed)
			(copperpour not_allowed)
			(footprints allowed)
		)
		(placement
			(enabled no)
			(sheetname "")
		)
		(fill yes
			(thermal_gap 0.5)
			(thermal_bridge_width 0.5)
			(island_removal_mode 0)
		)
		(polygon
			(pts
				(arc
					(start 131.81457 -24.675084)
					(mid 131.14655 -24.675084)
					(end 131.81457 -24.675084)
				)
			)
		)
	)
	(zone
		(layers "B.Cu" "In11.Cu" "In13.Cu" "In15.Cu")
		(hatch none 0.5)
		(connect_pads
			(clearance 0)
		)
		(min_thickness 0.25)
		(keepout
			(tracks not_allowed)
			(vias allowed)
			(pads allowed)
			(copperpour not_allowed)
			(footprints allowed)
		)
		(placement
			(enabled no)
			(sheetname "")
		)
		(fill yes
			(thermal_gap 0.5)
			(thermal_bridge_width 0.5)
			(island_removal_mode 0)
		)
		(polygon
			(pts
				(arc
					(start 194.938142 -250.035314)
					(mid 194.270122 -250.035314)
					(end 194.938142 -250.035314)
				)
			)
		)
	)
	(zone
		(layers "B.Cu" "In11.Cu" "In13.Cu" "In15.Cu")
		(hatch none 0.5)
		(connect_pads
			(clearance 0)
		)
		(min_thickness 0.25)
		(keepout
			(tracks not_allowed)
			(vias allowed)
			(pads allowed)
			(copperpour not_allowed)
			(footprints allowed)
		)
		(placement
			(enabled no)
			(sheetname "")
		)
		(fill yes
			(thermal_gap 0.5)
			(thermal_bridge_width 0.5)
			(island_removal_mode 0)
		)
		(polygon
			(pts
				(arc
					(start 273.426174 -267.035026)
					(mid 272.758154 -267.035026)
					(end 273.426174 -267.035026)
				)
			)
		)
	)
	(zone
		(layers "B.Cu" "In11.Cu" "In13.Cu" "In15.Cu")
		(hatch none 0.5)
		(connect_pads
			(clearance 0)
		)
		(min_thickness 0.25)
		(keepout
			(tracks not_allowed)
			(vias allowed)
			(pads allowed)
			(copperpour not_allowed)
			(footprints allowed)
		)
		(placement
			(enabled no)
			(sheetname "")
		)
		(fill yes
			(thermal_gap 0.5)
			(thermal_bridge_width 0.5)
			(island_removal_mode 0)
		)
		(polygon
			(pts
				(arc
					(start 150.533862 -386.003292)
					(mid 149.903942 -386.003292)
					(end 150.533862 -386.003292)
				)
			)
		)
	)
	(zone
		(layers "B.Cu" "In11.Cu" "In13.Cu" "In15.Cu")
		(hatch none 0.5)
		(connect_pads
			(clearance 0)
		)
		(min_thickness 0.25)
		(keepout
			(tracks not_allowed)
			(vias allowed)
			(pads allowed)
			(copperpour not_allowed)
			(footprints allowed)
		)
		(placement
			(enabled no)
			(sheetname "")
		)
		(fill yes
			(thermal_gap 0.5)
			(thermal_bridge_width 0.5)
			(island_removal_mode 0)
		)
		(polygon
			(pts
				(arc
					(start 154.933904 -385.31038)
					(mid 154.303984 -385.31038)
					(end 154.933904 -385.31038)
				)
			)
		)
	)
	(zone
		(layers "B.Cu" "In11.Cu" "In13.Cu" "In15.Cu")
		(hatch none 0.5)
		(connect_pads
			(clearance 0)
		)
		(min_thickness 0.25)
		(keepout
			(tracks not_allowed)
			(vias allowed)
			(pads allowed)
			(copperpour not_allowed)
			(footprints allowed)
		)
		(placement
			(enabled no)
			(sheetname "")
		)
		(fill yes
			(thermal_gap 0.5)
			(thermal_bridge_width 0.5)
			(island_removal_mode 0)
		)
		(polygon
			(pts
				(arc
					(start 98.124264 -207.499458)
					(mid 97.456244 -207.499458)
					(end 98.124264 -207.499458)
				)
			)
		)
	)
	(zone
		(layers "B.Cu" "In11.Cu" "In13.Cu" "In15.Cu")
		(hatch none 0.5)
		(connect_pads
			(clearance 0)
		)
		(min_thickness 0.25)
		(keepout
			(tracks not_allowed)
			(vias allowed)
			(pads allowed)
			(copperpour not_allowed)
			(footprints allowed)
		)
		(placement
			(enabled no)
			(sheetname "")
		)
		(fill yes
			(thermal_gap 0.5)
			(thermal_bridge_width 0.5)
			(island_removal_mode 0)
		)
		(polygon
			(pts
				(arc
					(start 82.785966 -278.946356)
					(mid 82.156046 -278.946356)
					(end 82.785966 -278.946356)
				)
			)
		)
	)
	(zone
		(layers "B.Cu" "In11.Cu" "In13.Cu" "In15.Cu")
		(hatch none 0.5)
		(connect_pads
			(clearance 0)
		)
		(min_thickness 0.25)
		(keepout
			(tracks not_allowed)
			(vias allowed)
			(pads allowed)
			(copperpour not_allowed)
			(footprints allowed)
		)
		(placement
			(enabled no)
			(sheetname "")
		)
		(fill yes
			(thermal_gap 0.5)
			(thermal_bridge_width 0.5)
			(island_removal_mode 0)
		)
		(polygon
			(pts
				(arc
					(start 411.1371 -426.089826)
					(mid 410.362908 -426.089826)
					(end 411.1371 -426.089826)
				)
			)
		)
	)
	(zone
		(layers "B.Cu" "In11.Cu" "In13.Cu" "In15.Cu")
		(hatch none 0.5)
		(connect_pads
			(clearance 0)
		)
		(min_thickness 0.25)
		(keepout
			(tracks not_allowed)
			(vias allowed)
			(pads allowed)
			(copperpour not_allowed)
			(footprints allowed)
		)
		(placement
			(enabled no)
			(sheetname "")
		)
		(fill yes
			(thermal_gap 0.5)
			(thermal_bridge_width 0.5)
			(island_removal_mode 0)
		)
		(polygon
			(pts
				(arc
					(start 199.03821 -229.635304)
					(mid 198.37019 -229.635304)
					(end 199.03821 -229.635304)
				)
			)
		)
	)
	(zone
		(layers "B.Cu" "In11.Cu" "In13.Cu" "In15.Cu")
		(hatch none 0.5)
		(connect_pads
			(clearance 0)
		)
		(min_thickness 0.25)
		(keepout
			(tracks not_allowed)
			(vias allowed)
			(pads allowed)
			(copperpour not_allowed)
			(footprints allowed)
		)
		(placement
			(enabled no)
			(sheetname "")
		)
		(fill yes
			(thermal_gap 0.5)
			(thermal_bridge_width 0.5)
			(island_removal_mode 0)
		)
		(polygon
			(pts
				(arc
					(start 71.036942 -422.489884)
					(mid 70.26275 -422.489884)
					(end 71.036942 -422.489884)
				)
			)
		)
	)
	(zone
		(layers "B.Cu" "In11.Cu" "In13.Cu" "In15.Cu")
		(hatch none 0.5)
		(connect_pads
			(clearance 0)
		)
		(min_thickness 0.25)
		(keepout
			(tracks not_allowed)
			(vias allowed)
			(pads allowed)
			(copperpour not_allowed)
			(footprints allowed)
		)
		(placement
			(enabled no)
			(sheetname "")
		)
		(fill yes
			(thermal_gap 0.5)
			(thermal_bridge_width 0.5)
			(island_removal_mode 0)
		)
		(polygon
			(pts
				(arc
					(start 331.195934 -287.856168)
					(mid 330.566014 -287.856168)
					(end 331.195934 -287.856168)
				)
			)
		)
	)
	(zone
		(layers "B.Cu" "In11.Cu" "In13.Cu" "In15.Cu")
		(hatch none 0.5)
		(connect_pads
			(clearance 0)
		)
		(min_thickness 0.25)
		(keepout
			(tracks not_allowed)
			(vias allowed)
			(pads allowed)
			(copperpour not_allowed)
			(footprints allowed)
		)
		(placement
			(enabled no)
			(sheetname "")
		)
		(fill yes
			(thermal_gap 0.5)
			(thermal_bridge_width 0.5)
			(island_removal_mode 0)
		)
		(polygon
			(pts
				(arc
					(start 368.489738 -242.864132)
					(mid 367.859818 -242.864132)
					(end 368.489738 -242.864132)
				)
			)
		)
	)
	(zone
		(layers "B.Cu" "In11.Cu" "In13.Cu" "In15.Cu")
		(hatch none 0.5)
		(connect_pads
			(clearance 0)
		)
		(min_thickness 0.25)
		(keepout
			(tracks not_allowed)
			(vias allowed)
			(pads allowed)
			(copperpour not_allowed)
			(footprints allowed)
		)
		(placement
			(enabled no)
			(sheetname "")
		)
		(fill yes
			(thermal_gap 0.5)
			(thermal_bridge_width 0.5)
			(island_removal_mode 0)
		)
		(polygon
			(pts
				(arc
					(start 327.611486 -387.878828)
					(mid 326.943466 -387.878828)
					(end 327.611486 -387.878828)
				)
			)
		)
	)
	(zone
		(layers "B.Cu" "In11.Cu" "In13.Cu" "In15.Cu")
		(hatch none 0.5)
		(connect_pads
			(clearance 0)
		)
		(min_thickness 0.25)
		(keepout
			(tracks not_allowed)
			(vias allowed)
			(pads allowed)
			(copperpour not_allowed)
			(footprints allowed)
		)
		(placement
			(enabled no)
			(sheetname "")
		)
		(fill yes
			(thermal_gap 0.5)
			(thermal_bridge_width 0.5)
			(island_removal_mode 0)
		)
		(polygon
			(pts
				(arc
					(start 273.426174 -276.38502)
					(mid 272.758154 -276.38502)
					(end 273.426174 -276.38502)
				)
			)
		)
	)
	(zone
		(layers "B.Cu" "In11.Cu" "In13.Cu" "In15.Cu")
		(hatch none 0.5)
		(connect_pads
			(clearance 0)
		)
		(min_thickness 0.25)
		(keepout
			(tracks not_allowed)
			(vias allowed)
			(pads allowed)
			(copperpour not_allowed)
			(footprints allowed)
		)
		(placement
			(enabled no)
			(sheetname "")
		)
		(fill yes
			(thermal_gap 0.5)
			(thermal_bridge_width 0.5)
			(island_removal_mode 0)
		)
		(polygon
			(pts
				(arc
					(start 81.545938 -256.634488)
					(mid 80.916018 -256.634488)
					(end 81.545938 -256.634488)
				)
			)
		)
	)
	(zone
		(layers "B.Cu" "In11.Cu" "In13.Cu" "In15.Cu")
		(hatch none 0.5)
		(connect_pads
			(clearance 0)
		)
		(min_thickness 0.25)
		(keepout
			(tracks not_allowed)
			(vias allowed)
			(pads allowed)
			(copperpour not_allowed)
			(footprints allowed)
		)
		(placement
			(enabled no)
			(sheetname "")
		)
		(fill yes
			(thermal_gap 0.5)
			(thermal_bridge_width 0.5)
			(island_removal_mode 0)
		)
		(polygon
			(pts
				(arc
					(start 386.136896 -426.089826)
					(mid 385.362704 -426.089826)
					(end 386.136896 -426.089826)
				)
			)
		)
	)
	(zone
		(layers "B.Cu" "In11.Cu" "In13.Cu" "In15.Cu")
		(hatch none 0.5)
		(connect_pads
			(clearance 0)
		)
		(min_thickness 0.25)
		(keepout
			(tracks not_allowed)
			(vias allowed)
			(pads allowed)
			(copperpour not_allowed)
			(footprints allowed)
		)
		(placement
			(enabled no)
			(sheetname "")
		)
		(fill yes
			(thermal_gap 0.5)
			(thermal_bridge_width 0.5)
			(island_removal_mode 0)
		)
		(polygon
			(pts
				(arc
					(start 81.545938 -253.394464)
					(mid 80.916018 -253.394464)
					(end 81.545938 -253.394464)
				)
			)
		)
	)
	(zone
		(layers "B.Cu" "In11.Cu" "In13.Cu" "In15.Cu")
		(hatch none 0.5)
		(connect_pads
			(clearance 0)
		)
		(min_thickness 0.25)
		(keepout
			(tracks not_allowed)
			(vias allowed)
			(pads allowed)
			(copperpour not_allowed)
			(footprints allowed)
		)
		(placement
			(enabled no)
			(sheetname "")
		)
		(fill yes
			(thermal_gap 0.5)
			(thermal_bridge_width 0.5)
			(island_removal_mode 0)
		)
		(polygon
			(pts
				(arc
					(start 29.586174 -275.53539)
					(mid 28.918154 -275.53539)
					(end 29.586174 -275.53539)
				)
			)
		)
	)
	(zone
		(layers "B.Cu" "In11.Cu" "In13.Cu" "In15.Cu")
		(hatch none 0.5)
		(connect_pads
			(clearance 0)
		)
		(min_thickness 0.25)
		(keepout
			(tracks not_allowed)
			(vias allowed)
			(pads allowed)
			(copperpour not_allowed)
			(footprints allowed)
		)
		(placement
			(enabled no)
			(sheetname "")
		)
		(fill yes
			(thermal_gap 0.5)
			(thermal_bridge_width 0.5)
			(island_removal_mode 0)
		)
		(polygon
			(pts
				(arc
					(start 141.529816 -287.856422)
					(mid 140.899896 -287.856422)
					(end 141.529816 -287.856422)
				)
			)
		)
	)
	(zone
		(layers "B.Cu" "In11.Cu" "In13.Cu" "In15.Cu")
		(hatch none 0.5)
		(connect_pads
			(clearance 0)
		)
		(min_thickness 0.25)
		(keepout
			(tracks not_allowed)
			(vias allowed)
			(pads allowed)
			(copperpour not_allowed)
			(footprints allowed)
		)
		(placement
			(enabled no)
			(sheetname "")
		)
		(fill yes
			(thermal_gap 0.5)
			(thermal_bridge_width 0.5)
			(island_removal_mode 0)
		)
		(polygon
			(pts
				(arc
					(start 273.426174 -243.234972)
					(mid 272.758154 -243.234972)
					(end 273.426174 -243.234972)
				)
			)
		)
	)
	(zone
		(layers "B.Cu" "In11.Cu" "In13.Cu" "In15.Cu")
		(hatch none 0.5)
		(connect_pads
			(clearance 0)
		)
		(min_thickness 0.25)
		(keepout
			(tracks not_allowed)
			(vias allowed)
			(pads allowed)
			(copperpour not_allowed)
			(footprints allowed)
		)
		(placement
			(enabled no)
			(sheetname "")
		)
		(fill yes
			(thermal_gap 0.5)
			(thermal_bridge_width 0.5)
			(island_removal_mode 0)
		)
		(polygon
			(pts
				(arc
					(start 142.639796 -229.094538)
					(mid 142.009876 -229.094538)
					(end 142.639796 -229.094538)
				)
			)
		)
	)
	(zone
		(layers "B.Cu" "In11.Cu" "In13.Cu" "In15.Cu")
		(hatch none 0.5)
		(connect_pads
			(clearance 0)
		)
		(min_thickness 0.25)
		(keepout
			(tracks not_allowed)
			(vias allowed)
			(pads allowed)
			(copperpour not_allowed)
			(footprints allowed)
		)
		(placement
			(enabled no)
			(sheetname "")
		)
		(fill yes
			(thermal_gap 0.5)
			(thermal_bridge_width 0.5)
			(island_removal_mode 0)
		)
		(polygon
			(pts
				(arc
					(start 82.785966 -287.046162)
					(mid 82.156046 -287.046162)
					(end 82.785966 -287.046162)
				)
			)
		)
	)
	(zone
		(layers "B.Cu" "In11.Cu" "In13.Cu" "In15.Cu")
		(hatch none 0.5)
		(connect_pads
			(clearance 0)
		)
		(min_thickness 0.25)
		(keepout
			(tracks not_allowed)
			(vias allowed)
			(pads allowed)
			(copperpour not_allowed)
			(footprints allowed)
		)
		(placement
			(enabled no)
			(sheetname "")
		)
		(fill yes
			(thermal_gap 0.5)
			(thermal_bridge_width 0.5)
			(island_removal_mode 0)
		)
		(polygon
			(pts
				(arc
					(start 81.376012 -287.856422)
					(mid 80.746092 -287.856422)
					(end 81.376012 -287.856422)
				)
			)
		)
	)
	(zone
		(layers "B.Cu" "In11.Cu" "In13.Cu" "In15.Cu")
		(hatch none 0.5)
		(connect_pads
			(clearance 0)
		)
		(min_thickness 0.25)
		(keepout
			(tracks not_allowed)
			(vias allowed)
			(pads allowed)
			(copperpour not_allowed)
			(footprints allowed)
		)
		(placement
			(enabled no)
			(sheetname "")
		)
		(fill yes
			(thermal_gap 0.5)
			(thermal_bridge_width 0.5)
			(island_removal_mode 0)
		)
		(polygon
			(pts
				(arc
					(start 388.406132 -397.849344)
					(mid 387.776212 -397.849344)
					(end 388.406132 -397.849344)
				)
			)
		)
	)
	(zone
		(layers "B.Cu" "In11.Cu" "In13.Cu" "In15.Cu")
		(hatch none 0.5)
		(connect_pads
			(clearance 0)
		)
		(min_thickness 0.25)
		(keepout
			(tracks not_allowed)
			(vias allowed)
			(pads allowed)
			(copperpour not_allowed)
			(footprints allowed)
		)
		(placement
			(enabled no)
			(sheetname "")
		)
		(fill yes
			(thermal_gap 0.5)
			(thermal_bridge_width 0.5)
			(island_removal_mode 0)
		)
		(polygon
			(pts
				(arc
					(start 347.433646 -397.156432)
					(mid 346.803726 -397.156432)
					(end 347.433646 -397.156432)
				)
			)
		)
	)
	(zone
		(layers "B.Cu" "In11.Cu" "In13.Cu" "In15.Cu")
		(hatch none 0.5)
		(connect_pads
			(clearance 0)
		)
		(min_thickness 0.25)
		(keepout
			(tracks not_allowed)
			(vias allowed)
			(pads allowed)
			(copperpour not_allowed)
			(footprints allowed)
		)
		(placement
			(enabled no)
			(sheetname "")
		)
		(fill yes
			(thermal_gap 0.5)
			(thermal_bridge_width 0.5)
			(island_removal_mode 0)
		)
		(polygon
			(pts
				(arc
					(start 414.533842 -393.69238)
					(mid 413.903922 -393.69238)
					(end 414.533842 -393.69238)
				)
			)
		)
	)
	(zone
		(layers "B.Cu" "In11.Cu" "In13.Cu" "In15.Cu")
		(hatch none 0.5)
		(connect_pads
			(clearance 0)
		)
		(min_thickness 0.25)
		(keepout
			(tracks not_allowed)
			(vias allowed)
			(pads allowed)
			(copperpour not_allowed)
			(footprints allowed)
		)
		(placement
			(enabled no)
			(sheetname "")
		)
		(fill yes
			(thermal_gap 0.5)
			(thermal_bridge_width 0.5)
			(island_removal_mode 0)
		)
		(polygon
			(pts
				(arc
					(start 94.076774 -404.46452)
					(mid 93.408754 -404.46452)
					(end 94.076774 -404.46452)
				)
			)
		)
	)
	(zone
		(layers "B.Cu" "In11.Cu" "In13.Cu" "In15.Cu")
		(hatch none 0.5)
		(connect_pads
			(clearance 0)
		)
		(min_thickness 0.25)
		(keepout
			(tracks not_allowed)
			(vias allowed)
			(pads allowed)
			(copperpour not_allowed)
			(footprints allowed)
		)
		(placement
			(enabled no)
			(sheetname "")
		)
		(fill yes
			(thermal_gap 0.5)
			(thermal_bridge_width 0.5)
			(island_removal_mode 0)
		)
		(polygon
			(pts
				(arc
					(start 29.586174 -210.935316)
					(mid 28.918154 -210.935316)
					(end 29.586174 -210.935316)
				)
			)
		)
	)
	(zone
		(layers "B.Cu" "In11.Cu" "In13.Cu" "In15.Cu")
		(hatch none 0.5)
		(connect_pads
			(clearance 0)
		)
		(min_thickness 0.25)
		(keepout
			(tracks not_allowed)
			(vias allowed)
			(pads allowed)
			(copperpour not_allowed)
			(footprints allowed)
		)
		(placement
			(enabled no)
			(sheetname "")
		)
		(fill yes
			(thermal_gap 0.5)
			(thermal_bridge_width 0.5)
			(island_removal_mode 0)
		)
		(polygon
			(pts
				(arc
					(start 29.586174 -266.185396)
					(mid 28.918154 -266.185396)
					(end 29.586174 -266.185396)
				)
			)
		)
	)
	(zone
		(layers "B.Cu" "In11.Cu" "In13.Cu" "In15.Cu")
		(hatch none 0.5)
		(connect_pads
			(clearance 0)
		)
		(min_thickness 0.25)
		(keepout
			(tracks not_allowed)
			(vias allowed)
			(pads allowed)
			(copperpour not_allowed)
			(footprints allowed)
		)
		(placement
			(enabled no)
			(sheetname "")
		)
		(fill yes
			(thermal_gap 0.5)
			(thermal_bridge_width 0.5)
			(island_removal_mode 0)
		)
		(polygon
			(pts
				(arc
					(start 66.507614 -404.46452)
					(mid 65.839594 -404.46452)
					(end 66.507614 -404.46452)
				)
			)
		)
	)
	(zone
		(layers "B.Cu" "In11.Cu" "In13.Cu" "In15.Cu")
		(hatch none 0.5)
		(connect_pads
			(clearance 0)
		)
		(min_thickness 0.25)
		(keepout
			(tracks not_allowed)
			(vias allowed)
			(pads allowed)
			(copperpour not_allowed)
			(footprints allowed)
		)
		(placement
			(enabled no)
			(sheetname "")
		)
		(fill yes
			(thermal_gap 0.5)
			(thermal_bridge_width 0.5)
			(island_removal_mode 0)
		)
		(polygon
			(pts
				(arc
					(start 442.87821 -209.23504)
					(mid 442.21019 -209.23504)
					(end 442.87821 -209.23504)
				)
			)
		)
	)
	(zone
		(layers "B.Cu" "In11.Cu" "In13.Cu" "In15.Cu")
		(hatch none 0.5)
		(connect_pads
			(clearance 0)
		)
		(min_thickness 0.25)
		(keepout
			(tracks not_allowed)
			(vias allowed)
			(pads allowed)
			(copperpour not_allowed)
			(footprints allowed)
		)
		(placement
			(enabled no)
			(sheetname "")
		)
		(fill yes
			(thermal_gap 0.5)
			(thermal_bridge_width 0.5)
			(island_removal_mode 0)
		)
		(polygon
			(pts
				(arc
					(start 82.485992 -243.674392)
					(mid 81.856072 -243.674392)
					(end 82.485992 -243.674392)
				)
			)
		)
	)
	(zone
		(layers "B.Cu" "In11.Cu" "In13.Cu" "In15.Cu")
		(hatch none 0.5)
		(connect_pads
			(clearance 0)
		)
		(min_thickness 0.25)
		(keepout
			(tracks not_allowed)
			(vias allowed)
			(pads allowed)
			(copperpour not_allowed)
			(footprints allowed)
		)
		(placement
			(enabled no)
			(sheetname "")
		)
		(fill yes
			(thermal_gap 0.5)
			(thermal_bridge_width 0.5)
			(island_removal_mode 0)
		)
		(polygon
			(pts
				(arc
					(start 277.526242 -214.335106)
					(mid 276.858222 -214.335106)
					(end 277.526242 -214.335106)
				)
			)
		)
	)
	(zone
		(layers "B.Cu" "In11.Cu" "In13.Cu" "In15.Cu")
		(hatch none 0.5)
		(connect_pads
			(clearance 0)
		)
		(min_thickness 0.25)
		(keepout
			(tracks not_allowed)
			(vias allowed)
			(pads allowed)
			(copperpour not_allowed)
			(footprints allowed)
		)
		(placement
			(enabled no)
			(sheetname "")
		)
		(fill yes
			(thermal_gap 0.5)
			(thermal_bridge_width 0.5)
			(island_removal_mode 0)
		)
		(polygon
			(pts
				(arc
					(start 63.036958 -426.089826)
					(mid 62.262766 -426.089826)
					(end 63.036958 -426.089826)
				)
			)
		)
	)
	(zone
		(layers "B.Cu" "In11.Cu" "In13.Cu" "In15.Cu")
		(hatch none 0.5)
		(connect_pads
			(clearance 0)
		)
		(min_thickness 0.25)
		(keepout
			(tracks not_allowed)
			(vias allowed)
			(pads allowed)
			(copperpour not_allowed)
			(footprints allowed)
		)
		(placement
			(enabled no)
			(sheetname "")
		)
		(fill yes
			(thermal_gap 0.5)
			(thermal_bridge_width 0.5)
			(island_removal_mode 0)
		)
		(polygon
			(pts
				(arc
					(start 143.109696 -239.624362)
					(mid 142.479776 -239.624362)
					(end 143.109696 -239.624362)
				)
			)
		)
	)
	(zone
		(layers "B.Cu" "In11.Cu" "In13.Cu" "In15.Cu")
		(hatch none 0.5)
		(connect_pads
			(clearance 0)
		)
		(min_thickness 0.25)
		(keepout
			(tracks not_allowed)
			(vias allowed)
			(pads allowed)
			(copperpour not_allowed)
			(footprints allowed)
		)
		(placement
			(enabled no)
			(sheetname "")
		)
		(fill yes
			(thermal_gap 0.5)
			(thermal_bridge_width 0.5)
			(island_removal_mode 0)
		)
		(polygon
			(pts
				(arc
					(start 362.679742 -282.186126)
					(mid 362.049822 -282.186126)
					(end 362.679742 -282.186126)
				)
			)
		)
	)
	(zone
		(layers "B.Cu" "In11.Cu" "In13.Cu" "In15.Cu")
		(hatch none 0.5)
		(connect_pads
			(clearance 0)
		)
		(min_thickness 0.25)
		(keepout
			(tracks not_allowed)
			(vias allowed)
			(pads allowed)
			(copperpour not_allowed)
			(footprints allowed)
		)
		(placement
			(enabled no)
			(sheetname "")
		)
		(fill yes
			(thermal_gap 0.5)
			(thermal_bridge_width 0.5)
			(island_removal_mode 0)
		)
		(polygon
			(pts
				(arc
					(start 140.13688 -427.089824)
					(mid 139.362688 -427.089824)
					(end 140.13688 -427.089824)
				)
			)
		)
	)
	(zone
		(layers "B.Cu" "In11.Cu" "In13.Cu" "In15.Cu")
		(hatch none 0.5)
		(connect_pads
			(clearance 0)
		)
		(min_thickness 0.25)
		(keepout
			(tracks not_allowed)
			(vias allowed)
			(pads allowed)
			(copperpour not_allowed)
			(footprints allowed)
		)
		(placement
			(enabled no)
			(sheetname "")
		)
		(fill yes
			(thermal_gap 0.5)
			(thermal_bridge_width 0.5)
			(island_removal_mode 0)
		)
		(polygon
			(pts
				(arc
					(start 25.486106 -229.635304)
					(mid 24.818086 -229.635304)
					(end 25.486106 -229.635304)
				)
			)
		)
	)
	(zone
		(layers "B.Cu" "In11.Cu" "In13.Cu" "In15.Cu")
		(hatch none 0.5)
		(connect_pads
			(clearance 0)
		)
		(min_thickness 0.25)
		(keepout
			(tracks not_allowed)
			(vias allowed)
			(pads allowed)
			(copperpour not_allowed)
			(footprints allowed)
		)
		(placement
			(enabled no)
			(sheetname "")
		)
		(fill yes
			(thermal_gap 0.5)
			(thermal_bridge_width 0.5)
			(island_removal_mode 0)
		)
		(polygon
			(pts
				(arc
					(start 446.978278 -234.735116)
					(mid 446.310258 -234.735116)
					(end 446.978278 -234.735116)
				)
			)
		)
	)
	(zone
		(layers "B.Cu" "In11.Cu" "In13.Cu" "In15.Cu")
		(hatch none 0.5)
		(connect_pads
			(clearance 0)
		)
		(min_thickness 0.25)
		(keepout
			(tracks not_allowed)
			(vias allowed)
			(pads allowed)
			(copperpour not_allowed)
			(footprints allowed)
		)
		(placement
			(enabled no)
			(sheetname "")
		)
		(fill yes
			(thermal_gap 0.5)
			(thermal_bridge_width 0.5)
			(island_removal_mode 0)
		)
		(polygon
			(pts
				(arc
					(start 82.955892 -254.20447)
					(mid 82.325972 -254.20447)
					(end 82.955892 -254.20447)
				)
			)
		)
	)
	(zone
		(layers "B.Cu" "In11.Cu" "In13.Cu" "In15.Cu")
		(hatch none 0.5)
		(connect_pads
			(clearance 0)
		)
		(min_thickness 0.25)
		(keepout
			(tracks not_allowed)
			(vias allowed)
			(pads allowed)
			(copperpour not_allowed)
			(footprints allowed)
		)
		(placement
			(enabled no)
			(sheetname "")
		)
		(fill yes
			(thermal_gap 0.5)
			(thermal_bridge_width 0.5)
			(island_removal_mode 0)
		)
		(polygon
			(pts
				(arc
					(start 130.00609 -389.467344)
					(mid 129.37617 -389.467344)
					(end 130.00609 -389.467344)
				)
			)
		)
	)
	(zone
		(layers "B.Cu" "In11.Cu" "In13.Cu" "In15.Cu")
		(hatch none 0.5)
		(connect_pads
			(clearance 0)
		)
		(min_thickness 0.25)
		(keepout
			(tracks not_allowed)
			(vias allowed)
			(pads allowed)
			(copperpour not_allowed)
			(footprints allowed)
		)
		(placement
			(enabled no)
			(sheetname "")
		)
		(fill yes
			(thermal_gap 0.5)
			(thermal_bridge_width 0.5)
			(island_removal_mode 0)
		)
		(polygon
			(pts
				(arc
					(start 25.486106 -299.335444)
					(mid 24.818086 -299.335444)
					(end 25.486106 -299.335444)
				)
			)
		)
	)
	(zone
		(layers "B.Cu" "In11.Cu" "In13.Cu" "In15.Cu")
		(hatch none 0.5)
		(connect_pads
			(clearance 0)
		)
		(min_thickness 0.25)
		(keepout
			(tracks not_allowed)
			(vias allowed)
			(pads allowed)
			(copperpour not_allowed)
			(footprints allowed)
		)
		(placement
			(enabled no)
			(sheetname "")
		)
		(fill yes
			(thermal_gap 0.5)
			(thermal_bridge_width 0.5)
			(island_removal_mode 0)
		)
		(polygon
			(pts
				(arc
					(start 442.87821 -199.885046)
					(mid 442.21019 -199.885046)
					(end 442.87821 -199.885046)
				)
			)
		)
	)
	(zone
		(layers "B.Cu" "In11.Cu" "In13.Cu" "In15.Cu")
		(hatch none 0.5)
		(connect_pads
			(clearance 0)
		)
		(min_thickness 0.25)
		(keepout
			(tracks not_allowed)
			(vias allowed)
			(pads allowed)
			(copperpour not_allowed)
			(footprints allowed)
		)
		(placement
			(enabled no)
			(sheetname "")
		)
		(fill yes
			(thermal_gap 0.5)
			(thermal_bridge_width 0.5)
			(island_removal_mode 0)
		)
		(polygon
			(pts
				(arc
					(start 342.036908 -428.28972)
					(mid 341.262716 -428.28972)
					(end 342.036908 -428.28972)
				)
			)
		)
	)
	(zone
		(layers "B.Cu" "In11.Cu" "In13.Cu" "In15.Cu")
		(hatch none 0.5)
		(connect_pads
			(clearance 0)
		)
		(min_thickness 0.25)
		(keepout
			(tracks not_allowed)
			(vias allowed)
			(pads allowed)
			(copperpour not_allowed)
			(footprints allowed)
		)
		(placement
			(enabled no)
			(sheetname "")
		)
		(fill yes
			(thermal_gap 0.5)
			(thermal_bridge_width 0.5)
			(island_removal_mode 0)
		)
		(polygon
			(pts
				(arc
					(start 329.486006 -229.094284)
					(mid 328.856086 -229.094284)
					(end 329.486006 -229.094284)
				)
			)
		)
	)
	(zone
		(layers "B.Cu" "In11.Cu" "In13.Cu" "In15.Cu")
		(hatch none 0.5)
		(connect_pads
			(clearance 0)
		)
		(min_thickness 0.25)
		(keepout
			(tracks not_allowed)
			(vias allowed)
			(pads allowed)
			(copperpour not_allowed)
			(footprints allowed)
		)
		(placement
			(enabled no)
			(sheetname "")
		)
		(fill yes
			(thermal_gap 0.5)
			(thermal_bridge_width 0.5)
			(island_removal_mode 0)
		)
		(polygon
			(pts
				(arc
					(start 277.526242 -306.135024)
					(mid 276.858222 -306.135024)
					(end 277.526242 -306.135024)
				)
			)
		)
	)
	(zone
		(layers "B.Cu" "In11.Cu" "In13.Cu" "In15.Cu")
		(hatch none 0.5)
		(connect_pads
			(clearance 0)
		)
		(min_thickness 0.25)
		(keepout
			(tracks not_allowed)
			(vias allowed)
			(pads allowed)
			(copperpour not_allowed)
			(footprints allowed)
		)
		(placement
			(enabled no)
			(sheetname "")
		)
		(fill yes
			(thermal_gap 0.5)
			(thermal_bridge_width 0.5)
			(island_removal_mode 0)
		)
		(polygon
			(pts
				(arc
					(start 109.105954 -283.806392)
					(mid 108.476034 -283.806392)
					(end 109.105954 -283.806392)
				)
			)
		)
	)
	(zone
		(layers "B.Cu" "In11.Cu" "In13.Cu" "In15.Cu")
		(hatch none 0.5)
		(connect_pads
			(clearance 0)
		)
		(min_thickness 0.25)
		(keepout
			(tracks not_allowed)
			(vias allowed)
			(pads allowed)
			(copperpour not_allowed)
			(footprints allowed)
		)
		(placement
			(enabled no)
			(sheetname "")
		)
		(fill yes
			(thermal_gap 0.5)
			(thermal_bridge_width 0.5)
			(island_removal_mode 0)
		)
		(polygon
			(pts
				(arc
					(start 389.16991 -244.484144)
					(mid 388.53999 -244.484144)
					(end 389.16991 -244.484144)
				)
			)
		)
	)
	(zone
		(layers "B.Cu" "In11.Cu" "In13.Cu" "In15.Cu")
		(hatch none 0.5)
		(connect_pads
			(clearance 0)
		)
		(min_thickness 0.25)
		(keepout
			(tracks not_allowed)
			(vias allowed)
			(pads allowed)
			(copperpour not_allowed)
			(footprints allowed)
		)
		(placement
			(enabled no)
			(sheetname "")
		)
		(fill yes
			(thermal_gap 0.5)
			(thermal_bridge_width 0.5)
			(island_removal_mode 0)
		)
		(polygon
			(pts
				(arc
					(start 83.255866 -266.796266)
					(mid 82.625946 -266.796266)
					(end 83.255866 -266.796266)
				)
			)
		)
	)
	(zone
		(layers "B.Cu" "In11.Cu" "In13.Cu" "In15.Cu")
		(hatch none 0.5)
		(connect_pads
			(clearance 0)
		)
		(min_thickness 0.25)
		(keepout
			(tracks not_allowed)
			(vias allowed)
			(pads allowed)
			(copperpour not_allowed)
			(footprints allowed)
		)
		(placement
			(enabled no)
			(sheetname "")
		)
		(fill yes
			(thermal_gap 0.5)
			(thermal_bridge_width 0.5)
			(island_removal_mode 0)
		)
		(polygon
			(pts
				(arc
					(start 81.845912 -282.18638)
					(mid 81.215992 -282.18638)
					(end 81.845912 -282.18638)
				)
			)
		)
	)
	(zone
		(layers "B.Cu" "In11.Cu" "In13.Cu" "In15.Cu")
		(hatch none 0.5)
		(connect_pads
			(clearance 0)
		)
		(min_thickness 0.25)
		(keepout
			(tracks not_allowed)
			(vias allowed)
			(pads allowed)
			(copperpour not_allowed)
			(footprints allowed)
		)
		(placement
			(enabled no)
			(sheetname "")
		)
		(fill yes
			(thermal_gap 0.5)
			(thermal_bridge_width 0.5)
			(island_removal_mode 0)
		)
		(polygon
			(pts
				(arc
					(start 29.586174 -220.28531)
					(mid 28.918154 -220.28531)
					(end 29.586174 -220.28531)
				)
			)
		)
	)
	(zone
		(layers "B.Cu" "In11.Cu" "In13.Cu" "In15.Cu")
		(hatch none 0.5)
		(connect_pads
			(clearance 0)
		)
		(min_thickness 0.25)
		(keepout
			(tracks not_allowed)
			(vias allowed)
			(pads allowed)
			(copperpour not_allowed)
			(footprints allowed)
		)
		(placement
			(enabled no)
			(sheetname "")
		)
		(fill yes
			(thermal_gap 0.5)
			(thermal_bridge_width 0.5)
			(island_removal_mode 0)
		)
		(polygon
			(pts
				(arc
					(start 338.036916 -428.28972)
					(mid 337.262724 -428.28972)
					(end 338.036916 -428.28972)
				)
			)
		)
	)
	(zone
		(layers "B.Cu" "In11.Cu" "In13.Cu" "In15.Cu")
		(hatch none 0.5)
		(connect_pads
			(clearance 0)
		)
		(min_thickness 0.25)
		(keepout
			(tracks not_allowed)
			(vias allowed)
			(pads allowed)
			(copperpour not_allowed)
			(footprints allowed)
		)
		(placement
			(enabled no)
			(sheetname "")
		)
		(fill yes
			(thermal_gap 0.5)
			(thermal_bridge_width 0.5)
			(island_removal_mode 0)
		)
		(polygon
			(pts
				(arc
					(start 182.375556 -48.028098)
					(mid 181.707536 -48.028098)
					(end 182.375556 -48.028098)
				)
			)
		)
	)
	(zone
		(layers "B.Cu" "In11.Cu" "In13.Cu" "In15.Cu")
		(hatch none 0.5)
		(connect_pads
			(clearance 0)
		)
		(min_thickness 0.25)
		(keepout
			(tracks not_allowed)
			(vias allowed)
			(pads allowed)
			(copperpour not_allowed)
			(footprints allowed)
		)
		(placement
			(enabled no)
			(sheetname "")
		)
		(fill yes
			(thermal_gap 0.5)
			(thermal_bridge_width 0.5)
			(island_removal_mode 0)
		)
		(polygon
			(pts
				(arc
					(start 389.939784 -293.525956)
					(mid 389.309864 -293.525956)
					(end 389.939784 -293.525956)
				)
			)
		)
	)
	(zone
		(layers "B.Cu" "In11.Cu" "In13.Cu" "In15.Cu")
		(hatch none 0.5)
		(connect_pads
			(clearance 0)
		)
		(min_thickness 0.25)
		(keepout
			(tracks not_allowed)
			(vias allowed)
			(pads allowed)
			(copperpour not_allowed)
			(footprints allowed)
		)
		(placement
			(enabled no)
			(sheetname "")
		)
		(fill yes
			(thermal_gap 0.5)
			(thermal_bridge_width 0.5)
			(island_removal_mode 0)
		)
		(polygon
			(pts
				(arc
					(start 391.349738 -287.856168)
					(mid 390.719818 -287.856168)
					(end 391.349738 -287.856168)
				)
			)
		)
	)
	(zone
		(layers "B.Cu" "In11.Cu" "In13.Cu" "In15.Cu")
		(hatch none 0.5)
		(connect_pads
			(clearance 0)
		)
		(min_thickness 0.25)
		(keepout
			(tracks not_allowed)
			(vias allowed)
			(pads allowed)
			(copperpour not_allowed)
			(footprints allowed)
		)
		(placement
			(enabled no)
			(sheetname "")
		)
		(fill yes
			(thermal_gap 0.5)
			(thermal_bridge_width 0.5)
			(island_removal_mode 0)
		)
		(polygon
			(pts
				(arc
					(start 277.526242 -264.48512)
					(mid 276.858222 -264.48512)
					(end 277.526242 -264.48512)
				)
			)
		)
	)
	(zone
		(layers "B.Cu" "In11.Cu" "In13.Cu" "In15.Cu")
		(hatch none 0.5)
		(connect_pads
			(clearance 0)
		)
		(min_thickness 0.25)
		(keepout
			(tracks not_allowed)
			(vias allowed)
			(pads allowed)
			(copperpour not_allowed)
			(footprints allowed)
		)
		(placement
			(enabled no)
			(sheetname "")
		)
		(fill yes
			(thermal_gap 0.5)
			(thermal_bridge_width 0.5)
			(island_removal_mode 0)
		)
		(polygon
			(pts
				(arc
					(start 25.486106 -224.535238)
					(mid 24.818086 -224.535238)
					(end 25.486106 -224.535238)
				)
			)
		)
	)
	(zone
		(layers "B.Cu" "In11.Cu" "In13.Cu" "In15.Cu")
		(hatch none 0.5)
		(connect_pads
			(clearance 0)
		)
		(min_thickness 0.25)
		(keepout
			(tracks not_allowed)
			(vias allowed)
			(pads allowed)
			(copperpour not_allowed)
			(footprints allowed)
		)
		(placement
			(enabled no)
			(sheetname "")
		)
		(fill yes
			(thermal_gap 0.5)
			(thermal_bridge_width 0.5)
			(island_removal_mode 0)
		)
		(polygon
			(pts
				(arc
					(start 389.16991 -236.384084)
					(mid 388.53999 -236.384084)
					(end 389.16991 -236.384084)
				)
			)
		)
	)
	(zone
		(layers "B.Cu" "In11.Cu" "In13.Cu" "In15.Cu")
		(hatch none 0.5)
		(connect_pads
			(clearance 0)
		)
		(min_thickness 0.25)
		(keepout
			(tracks not_allowed)
			(vias allowed)
			(pads allowed)
			(copperpour not_allowed)
			(footprints allowed)
		)
		(placement
			(enabled no)
			(sheetname "")
		)
		(fill yes
			(thermal_gap 0.5)
			(thermal_bridge_width 0.5)
			(island_removal_mode 0)
		)
		(polygon
			(pts
				(arc
					(start 143.40967 -292.716204)
					(mid 142.77975 -292.716204)
					(end 143.40967 -292.716204)
				)
			)
		)
	)
	(zone
		(layers "B.Cu" "In11.Cu" "In13.Cu" "In15.Cu")
		(hatch none 0.5)
		(connect_pads
			(clearance 0)
		)
		(min_thickness 0.25)
		(keepout
			(tracks not_allowed)
			(vias allowed)
			(pads allowed)
			(copperpour not_allowed)
			(footprints allowed)
		)
		(placement
			(enabled no)
			(sheetname "")
		)
		(fill yes
			(thermal_gap 0.5)
			(thermal_bridge_width 0.5)
			(island_removal_mode 0)
		)
		(polygon
			(pts
				(arc
					(start 25.486106 -277.235412)
					(mid 24.818086 -277.235412)
					(end 25.486106 -277.235412)
				)
			)
		)
	)
	(zone
		(layers "B.Cu" "In11.Cu" "In13.Cu" "In15.Cu")
		(hatch none 0.5)
		(connect_pads
			(clearance 0)
		)
		(min_thickness 0.25)
		(keepout
			(tracks not_allowed)
			(vias allowed)
			(pads allowed)
			(copperpour not_allowed)
			(footprints allowed)
		)
		(placement
			(enabled no)
			(sheetname "")
		)
		(fill yes
			(thermal_gap 0.5)
			(thermal_bridge_width 0.5)
			(island_removal_mode 0)
		)
		(polygon
			(pts
				(arc
					(start 442.87821 -211.784946)
					(mid 442.21019 -211.784946)
					(end 442.87821 -211.784946)
				)
			)
		)
	)
	(zone
		(layers "B.Cu" "In11.Cu" "In13.Cu" "In15.Cu")
		(hatch none 0.5)
		(connect_pads
			(clearance 0)
		)
		(min_thickness 0.25)
		(keepout
			(tracks not_allowed)
			(vias allowed)
			(pads allowed)
			(copperpour not_allowed)
			(footprints allowed)
		)
		(placement
			(enabled no)
			(sheetname "")
		)
		(fill yes
			(thermal_gap 0.5)
			(thermal_bridge_width 0.5)
			(island_removal_mode 0)
		)
		(polygon
			(pts
				(arc
					(start 277.526242 -201.585068)
					(mid 276.858222 -201.585068)
					(end 277.526242 -201.585068)
				)
			)
		)
	)
	(zone
		(layers "B.Cu" "In11.Cu" "In13.Cu" "In15.Cu")
		(hatch none 0.5)
		(connect_pads
			(clearance 0)
		)
		(min_thickness 0.25)
		(keepout
			(tracks not_allowed)
			(vias allowed)
			(pads allowed)
			(copperpour not_allowed)
			(footprints allowed)
		)
		(placement
			(enabled no)
			(sheetname "")
		)
		(fill yes
			(thermal_gap 0.5)
			(thermal_bridge_width 0.5)
			(island_removal_mode 0)
		)
		(polygon
			(pts
				(arc
					(start 82.485992 -232.334308)
					(mid 81.856072 -232.334308)
					(end 82.485992 -232.334308)
				)
			)
		)
	)
	(zone
		(layers "B.Cu" "In11.Cu" "In13.Cu" "In15.Cu")
		(hatch none 0.5)
		(connect_pads
			(clearance 0)
		)
		(min_thickness 0.25)
		(keepout
			(tracks not_allowed)
			(vias allowed)
			(pads allowed)
			(copperpour not_allowed)
			(footprints allowed)
		)
		(placement
			(enabled no)
			(sheetname "")
		)
		(fill yes
			(thermal_gap 0.5)
			(thermal_bridge_width 0.5)
			(island_removal_mode 0)
		)
		(polygon
			(pts
				(arc
					(start 391.049764 -231.524048)
					(mid 390.419844 -231.524048)
					(end 391.049764 -231.524048)
				)
			)
		)
	)
	(zone
		(layers "B.Cu" "In11.Cu" "In13.Cu" "In15.Cu")
		(hatch none 0.5)
		(connect_pads
			(clearance 0)
		)
		(min_thickness 0.25)
		(keepout
			(tracks not_allowed)
			(vias allowed)
			(pads allowed)
			(copperpour not_allowed)
			(footprints allowed)
		)
		(placement
			(enabled no)
			(sheetname "")
		)
		(fill yes
			(thermal_gap 0.5)
			(thermal_bridge_width 0.5)
			(island_removal_mode 0)
		)
		(polygon
			(pts
				(arc
					(start 138.136884 -427.289976)
					(mid 137.362692 -427.289976)
					(end 138.136884 -427.289976)
				)
			)
		)
	)
	(zone
		(layers "B.Cu" "In11.Cu" "In13.Cu" "In15.Cu")
		(hatch none 0.5)
		(connect_pads
			(clearance 0)
		)
		(min_thickness 0.25)
		(keepout
			(tracks not_allowed)
			(vias allowed)
			(pads allowed)
			(copperpour not_allowed)
			(footprints allowed)
		)
		(placement
			(enabled no)
			(sheetname "")
		)
		(fill yes
			(thermal_gap 0.5)
			(thermal_bridge_width 0.5)
			(island_removal_mode 0)
		)
		(polygon
			(pts
				(arc
					(start 143.109696 -226.66452)
					(mid 142.479776 -226.66452)
					(end 143.109696 -226.66452)
				)
			)
		)
	)
	(zone
		(layers "B.Cu" "In11.Cu" "In13.Cu" "In15.Cu")
		(hatch none 0.5)
		(connect_pads
			(clearance 0)
		)
		(min_thickness 0.25)
		(keepout
			(tracks not_allowed)
			(vias allowed)
			(pads allowed)
			(copperpour not_allowed)
			(footprints allowed)
		)
		(placement
			(enabled no)
			(sheetname "")
		)
		(fill yes
			(thermal_gap 0.5)
			(thermal_bridge_width 0.5)
			(island_removal_mode 0)
		)
		(polygon
			(pts
				(arc
					(start 390.879838 -282.186126)
					(mid 390.249918 -282.186126)
					(end 390.879838 -282.186126)
				)
			)
		)
	)
	(zone
		(layers "B.Cu" "In11.Cu" "In13.Cu" "In15.Cu")
		(hatch none 0.5)
		(connect_pads
			(clearance 0)
		)
		(min_thickness 0.25)
		(keepout
			(tracks not_allowed)
			(vias allowed)
			(pads allowed)
			(copperpour not_allowed)
			(footprints allowed)
		)
		(placement
			(enabled no)
			(sheetname "")
		)
		(fill yes
			(thermal_gap 0.5)
			(thermal_bridge_width 0.5)
			(island_removal_mode 0)
		)
		(polygon
			(pts
				(arc
					(start 81.845912 -262.746236)
					(mid 81.215992 -262.746236)
					(end 81.845912 -262.746236)
				)
			)
		)
	)
	(zone
		(layers "B.Cu" "In11.Cu" "In13.Cu" "In15.Cu")
		(hatch none 0.5)
		(connect_pads
			(clearance 0)
		)
		(min_thickness 0.25)
		(keepout
			(tracks not_allowed)
			(vias allowed)
			(pads allowed)
			(copperpour not_allowed)
			(footprints allowed)
		)
		(placement
			(enabled no)
			(sheetname "")
		)
		(fill yes
			(thermal_gap 0.5)
			(thermal_bridge_width 0.5)
			(island_removal_mode 0)
		)
		(polygon
			(pts
				(arc
					(start 413.137096 -428.28972)
					(mid 412.362904 -428.28972)
					(end 413.137096 -428.28972)
				)
			)
		)
	)
	(zone
		(layers "B.Cu" "In11.Cu" "In13.Cu" "In15.Cu")
		(hatch none 0.5)
		(connect_pads
			(clearance 0)
		)
		(min_thickness 0.25)
		(keepout
			(tracks not_allowed)
			(vias allowed)
			(pads allowed)
			(copperpour not_allowed)
			(footprints allowed)
		)
		(placement
			(enabled no)
			(sheetname "")
		)
		(fill yes
			(thermal_gap 0.5)
			(thermal_bridge_width 0.5)
			(island_removal_mode 0)
		)
		(polygon
			(pts
				(arc
					(start 114.739674 -285.426404)
					(mid 114.109754 -285.426404)
					(end 114.739674 -285.426404)
				)
			)
		)
	)
	(zone
		(layers "B.Cu" "In11.Cu" "In13.Cu" "In15.Cu")
		(hatch none 0.5)
		(connect_pads
			(clearance 0)
		)
		(min_thickness 0.25)
		(keepout
			(tracks not_allowed)
			(vias allowed)
			(pads allowed)
			(copperpour not_allowed)
			(footprints allowed)
		)
		(placement
			(enabled no)
			(sheetname "")
		)
		(fill yes
			(thermal_gap 0.5)
			(thermal_bridge_width 0.5)
			(island_removal_mode 0)
		)
		(polygon
			(pts
				(arc
					(start 329.486006 -246.914162)
					(mid 328.856086 -246.914162)
					(end 329.486006 -246.914162)
				)
			)
		)
	)
	(zone
		(layers "B.Cu" "In11.Cu" "In13.Cu" "In15.Cu")
		(hatch none 0.5)
		(connect_pads
			(clearance 0)
		)
		(min_thickness 0.25)
		(keepout
			(tracks not_allowed)
			(vias allowed)
			(pads allowed)
			(copperpour not_allowed)
			(footprints allowed)
		)
		(placement
			(enabled no)
			(sheetname "")
		)
		(fill yes
			(thermal_gap 0.5)
			(thermal_bridge_width 0.5)
			(island_removal_mode 0)
		)
		(polygon
			(pts
				(arc
					(start 346.236036 -281.37612)
					(mid 345.606116 -281.37612)
					(end 346.236036 -281.37612)
				)
			)
		)
	)
	(zone
		(layers "B.Cu" "In11.Cu" "In13.Cu" "In15.Cu")
		(hatch none 0.5)
		(connect_pads
			(clearance 0)
		)
		(min_thickness 0.25)
		(keepout
			(tracks not_allowed)
			(vias allowed)
			(pads allowed)
			(copperpour not_allowed)
			(footprints allowed)
		)
		(placement
			(enabled no)
			(sheetname "")
		)
		(fill yes
			(thermal_gap 0.5)
			(thermal_bridge_width 0.5)
			(island_removal_mode 0)
		)
		(polygon
			(pts
				(arc
					(start 353.833684 -397.849344)
					(mid 353.203764 -397.849344)
					(end 353.833684 -397.849344)
				)
			)
		)
	)
	(zone
		(layers "B.Cu" "In11.Cu" "In13.Cu" "In15.Cu")
		(hatch none 0.5)
		(connect_pads
			(clearance 0)
		)
		(min_thickness 0.25)
		(keepout
			(tracks not_allowed)
			(vias allowed)
			(pads allowed)
			(copperpour not_allowed)
			(footprints allowed)
		)
		(placement
			(enabled no)
			(sheetname "")
		)
		(fill yes
			(thermal_gap 0.5)
			(thermal_bridge_width 0.5)
			(island_removal_mode 0)
		)
		(polygon
			(pts
				(arc
					(start 446.978278 -254.284988)
					(mid 446.310258 -254.284988)
					(end 446.978278 -254.284988)
				)
			)
		)
	)
	(zone
		(layers "B.Cu" "In11.Cu" "In13.Cu" "In15.Cu")
		(hatch none 0.5)
		(connect_pads
			(clearance 0)
		)
		(min_thickness 0.25)
		(keepout
			(tracks not_allowed)
			(vias allowed)
			(pads allowed)
			(copperpour not_allowed)
			(footprints allowed)
		)
		(placement
			(enabled no)
			(sheetname "")
		)
		(fill yes
			(thermal_gap 0.5)
			(thermal_bridge_width 0.5)
			(island_removal_mode 0)
		)
		(polygon
			(pts
				(arc
					(start 73.036938 -424.689778)
					(mid 72.262746 -424.689778)
					(end 73.036938 -424.689778)
				)
			)
		)
	)
	(zone
		(layers "B.Cu" "In11.Cu" "In13.Cu" "In15.Cu")
		(hatch none 0.5)
		(connect_pads
			(clearance 0)
		)
		(min_thickness 0.25)
		(keepout
			(tracks not_allowed)
			(vias allowed)
			(pads allowed)
			(copperpour not_allowed)
			(footprints allowed)
		)
		(placement
			(enabled no)
			(sheetname "")
		)
		(fill yes
			(thermal_gap 0.5)
			(thermal_bridge_width 0.5)
			(island_removal_mode 0)
		)
		(polygon
			(pts
				(arc
					(start 82.955892 -229.90429)
					(mid 82.325972 -229.90429)
					(end 82.955892 -229.90429)
				)
			)
		)
	)
	(zone
		(layers "B.Cu" "In11.Cu" "In13.Cu" "In15.Cu")
		(hatch none 0.5)
		(connect_pads
			(clearance 0)
		)
		(min_thickness 0.25)
		(keepout
			(tracks not_allowed)
			(vias allowed)
			(pads allowed)
			(copperpour not_allowed)
			(footprints allowed)
		)
		(placement
			(enabled no)
			(sheetname "")
		)
		(fill yes
			(thermal_gap 0.5)
			(thermal_bridge_width 0.5)
			(island_removal_mode 0)
		)
		(polygon
			(pts
				(arc
					(start 194.938142 -291.685218)
					(mid 194.270122 -291.685218)
					(end 194.938142 -291.685218)
				)
			)
		)
	)
	(zone
		(layers "B.Cu" "In11.Cu" "In13.Cu" "In15.Cu")
		(hatch none 0.5)
		(connect_pads
			(clearance 0)
		)
		(min_thickness 0.25)
		(keepout
			(tracks not_allowed)
			(vias allowed)
			(pads allowed)
			(copperpour not_allowed)
			(footprints allowed)
		)
		(placement
			(enabled no)
			(sheetname "")
		)
		(fill yes
			(thermal_gap 0.5)
			(thermal_bridge_width 0.5)
			(island_removal_mode 0)
		)
		(polygon
			(pts
				(arc
					(start 388.006336 -397.156432)
					(mid 387.376416 -397.156432)
					(end 388.006336 -397.156432)
				)
			)
		)
	)
	(zone
		(layers "B.Cu" "In11.Cu" "In13.Cu" "In15.Cu")
		(hatch none 0.5)
		(connect_pads
			(clearance 0)
		)
		(min_thickness 0.25)
		(keepout
			(tracks not_allowed)
			(vias allowed)
			(pads allowed)
			(copperpour not_allowed)
			(footprints allowed)
		)
		(placement
			(enabled no)
			(sheetname "")
		)
		(fill yes
			(thermal_gap 0.5)
			(thermal_bridge_width 0.5)
			(island_removal_mode 0)
		)
		(polygon
			(pts
				(arc
					(start 81.376012 -289.47618)
					(mid 80.746092 -289.47618)
					(end 81.376012 -289.47618)
				)
			)
		)
	)
	(zone
		(layers "B.Cu" "In11.Cu" "In13.Cu" "In15.Cu")
		(hatch none 0.5)
		(connect_pads
			(clearance 0)
		)
		(min_thickness 0.25)
		(keepout
			(tracks not_allowed)
			(vias allowed)
			(pads allowed)
			(copperpour not_allowed)
			(footprints allowed)
		)
		(placement
			(enabled no)
			(sheetname "")
		)
		(fill yes
			(thermal_gap 0.5)
			(thermal_bridge_width 0.5)
			(island_removal_mode 0)
		)
		(polygon
			(pts
				(arc
					(start 307.857906 -377.41733)
					(mid 307.189886 -377.41733)
					(end 307.857906 -377.41733)
				)
			)
		)
	)
	(zone
		(layers "B.Cu" "In11.Cu" "In13.Cu" "In15.Cu")
		(hatch none 0.5)
		(connect_pads
			(clearance 0)
		)
		(min_thickness 0.25)
		(keepout
			(tracks not_allowed)
			(vias allowed)
			(pads allowed)
			(copperpour not_allowed)
			(footprints allowed)
		)
		(placement
			(enabled no)
			(sheetname "")
		)
		(fill yes
			(thermal_gap 0.5)
			(thermal_bridge_width 0.5)
			(island_removal_mode 0)
		)
		(polygon
			(pts
				(arc
					(start 442.87821 -304.435002)
					(mid 442.21019 -304.435002)
					(end 442.87821 -304.435002)
				)
			)
		)
	)
	(zone
		(layers "B.Cu" "In11.Cu" "In13.Cu" "In15.Cu")
		(hatch none 0.5)
		(connect_pads
			(clearance 0)
		)
		(min_thickness 0.25)
		(keepout
			(tracks not_allowed)
			(vias allowed)
			(pads allowed)
			(copperpour not_allowed)
			(footprints allowed)
		)
		(placement
			(enabled no)
			(sheetname "")
		)
		(fill yes
			(thermal_gap 0.5)
			(thermal_bridge_width 0.5)
			(island_removal_mode 0)
		)
		(polygon
			(pts
				(arc
					(start 73.036938 -419.88994)
					(mid 72.262746 -419.88994)
					(end 73.036938 -419.88994)
				)
			)
		)
	)
	(zone
		(layers "B.Cu" "In11.Cu" "In13.Cu" "In15.Cu")
		(hatch none 0.5)
		(connect_pads
			(clearance 0)
		)
		(min_thickness 0.25)
		(keepout
			(tracks not_allowed)
			(vias allowed)
			(pads allowed)
			(copperpour not_allowed)
			(footprints allowed)
		)
		(placement
			(enabled no)
			(sheetname "")
		)
		(fill yes
			(thermal_gap 0.5)
			(thermal_bridge_width 0.5)
			(island_removal_mode 0)
		)
		(polygon
			(pts
				(arc
					(start 273.426174 -302.73498)
					(mid 272.758154 -302.73498)
					(end 273.426174 -302.73498)
				)
			)
		)
	)
	(zone
		(layers "B.Cu" "In11.Cu" "In13.Cu" "In15.Cu")
		(hatch none 0.5)
		(connect_pads
			(clearance 0)
		)
		(min_thickness 0.25)
		(keepout
			(tracks not_allowed)
			(vias allowed)
			(pads allowed)
			(copperpour not_allowed)
			(footprints allowed)
		)
		(placement
			(enabled no)
			(sheetname "")
		)
		(fill yes
			(thermal_gap 0.5)
			(thermal_bridge_width 0.5)
			(island_removal_mode 0)
		)
		(polygon
			(pts
				(arc
					(start 157.1371 -428.28972)
					(mid 156.362908 -428.28972)
					(end 157.1371 -428.28972)
				)
			)
		)
	)
	(zone
		(layers "B.Cu" "In11.Cu" "In13.Cu" "In15.Cu")
		(hatch none 0.5)
		(connect_pads
			(clearance 0)
		)
		(min_thickness 0.25)
		(keepout
			(tracks not_allowed)
			(vias allowed)
			(pads allowed)
			(copperpour not_allowed)
			(footprints allowed)
		)
		(placement
			(enabled no)
			(sheetname "")
		)
		(fill yes
			(thermal_gap 0.5)
			(thermal_bridge_width 0.5)
			(island_removal_mode 0)
		)
		(polygon
			(pts
				(arc
					(start 71.611744 -379.496828)
					(mid 70.943724 -379.496828)
					(end 71.611744 -379.496828)
				)
			)
		)
	)
	(zone
		(layers "B.Cu" "In11.Cu" "In13.Cu" "In15.Cu")
		(hatch none 0.5)
		(connect_pads
			(clearance 0)
		)
		(min_thickness 0.25)
		(keepout
			(tracks not_allowed)
			(vias allowed)
			(pads allowed)
			(copperpour not_allowed)
			(footprints allowed)
		)
		(placement
			(enabled no)
			(sheetname "")
		)
		(fill yes
			(thermal_gap 0.5)
			(thermal_bridge_width 0.5)
			(island_removal_mode 0)
		)
		(polygon
			(pts
				(arc
					(start 363.319822 -240.434114)
					(mid 362.689902 -240.434114)
					(end 363.319822 -240.434114)
				)
			)
		)
	)
	(zone
		(layers "B.Cu" "In11.Cu" "In13.Cu" "In15.Cu")
		(hatch none 0.5)
		(connect_pads
			(clearance 0)
		)
		(min_thickness 0.25)
		(keepout
			(tracks not_allowed)
			(vias allowed)
			(pads allowed)
			(copperpour not_allowed)
			(footprints allowed)
		)
		(placement
			(enabled no)
			(sheetname "")
		)
		(fill yes
			(thermal_gap 0.5)
			(thermal_bridge_width 0.5)
			(island_removal_mode 0)
		)
		(polygon
			(pts
				(arc
					(start 277.526242 -252.584966)
					(mid 276.858222 -252.584966)
					(end 277.526242 -252.584966)
				)
			)
		)
	)
	(zone
		(layers "B.Cu" "In11.Cu" "In13.Cu" "In15.Cu")
		(hatch none 0.5)
		(connect_pads
			(clearance 0)
		)
		(min_thickness 0.25)
		(keepout
			(tracks not_allowed)
			(vias allowed)
			(pads allowed)
			(copperpour not_allowed)
			(footprints allowed)
		)
		(placement
			(enabled no)
			(sheetname "")
		)
		(fill yes
			(thermal_gap 0.5)
			(thermal_bridge_width 0.5)
			(island_removal_mode 0)
		)
		(polygon
			(pts
				(arc
					(start 390.879838 -270.846042)
					(mid 390.249918 -270.846042)
					(end 390.879838 -270.846042)
				)
			)
		)
	)
	(zone
		(layers "B.Cu" "In11.Cu" "In13.Cu" "In15.Cu")
		(hatch none 0.5)
		(connect_pads
			(clearance 0)
		)
		(min_thickness 0.25)
		(keepout
			(tracks not_allowed)
			(vias allowed)
			(pads allowed)
			(copperpour not_allowed)
			(footprints allowed)
		)
		(placement
			(enabled no)
			(sheetname "")
		)
		(fill yes
			(thermal_gap 0.5)
			(thermal_bridge_width 0.5)
			(island_removal_mode 0)
		)
		(polygon
			(pts
				(arc
					(start 349.995998 -284.616144)
					(mid 349.366078 -284.616144)
					(end 349.995998 -284.616144)
				)
			)
		)
	)
	(zone
		(layers "B.Cu" "In11.Cu" "In13.Cu" "In15.Cu")
		(hatch none 0.5)
		(connect_pads
			(clearance 0)
		)
		(min_thickness 0.25)
		(keepout
			(tracks not_allowed)
			(vias allowed)
			(pads allowed)
			(copperpour not_allowed)
			(footprints allowed)
		)
		(placement
			(enabled no)
			(sheetname "")
		)
		(fill yes
			(thermal_gap 0.5)
			(thermal_bridge_width 0.5)
			(island_removal_mode 0)
		)
		(polygon
			(pts
				(arc
					(start 330.89596 -254.204216)
					(mid 330.26604 -254.204216)
					(end 330.89596 -254.204216)
				)
			)
		)
	)
	(zone
		(layers "B.Cu" "In11.Cu" "In13.Cu" "In15.Cu")
		(hatch none 0.5)
		(connect_pads
			(clearance 0)
		)
		(min_thickness 0.25)
		(keepout
			(tracks not_allowed)
			(vias allowed)
			(pads allowed)
			(copperpour not_allowed)
			(footprints allowed)
		)
		(placement
			(enabled no)
			(sheetname "")
		)
		(fill yes
			(thermal_gap 0.5)
			(thermal_bridge_width 0.5)
			(island_removal_mode 0)
		)
		(polygon
			(pts
				(arc
					(start 348.633796 -397.156432)
					(mid 348.003876 -397.156432)
					(end 348.633796 -397.156432)
				)
			)
		)
	)
	(zone
		(layers "B.Cu" "In11.Cu" "In13.Cu" "In15.Cu")
		(hatch none 0.5)
		(connect_pads
			(clearance 0)
		)
		(min_thickness 0.25)
		(keepout
			(tracks not_allowed)
			(vias allowed)
			(pads allowed)
			(copperpour not_allowed)
			(footprints allowed)
		)
		(placement
			(enabled no)
			(sheetname "")
		)
		(fill yes
			(thermal_gap 0.5)
			(thermal_bridge_width 0.5)
			(island_removal_mode 0)
		)
		(polygon
			(pts
				(arc
					(start 277.526242 -217.73515)
					(mid 276.858222 -217.73515)
					(end 277.526242 -217.73515)
				)
			)
		)
	)
	(zone
		(layers "B.Cu" "In11.Cu" "In13.Cu" "In15.Cu")
		(hatch none 0.5)
		(connect_pads
			(clearance 0)
		)
		(min_thickness 0.25)
		(keepout
			(tracks not_allowed)
			(vias allowed)
			(pads allowed)
			(copperpour not_allowed)
			(footprints allowed)
		)
		(placement
			(enabled no)
			(sheetname "")
		)
		(fill yes
			(thermal_gap 0.5)
			(thermal_bridge_width 0.5)
			(island_removal_mode 0)
		)
		(polygon
			(pts
				(arc
					(start 340.036912 -426.089826)
					(mid 339.26272 -426.089826)
					(end 340.036912 -426.089826)
				)
			)
		)
	)
	(zone
		(layers "B.Cu" "In11.Cu" "In13.Cu" "In15.Cu")
		(hatch none 0.5)
		(connect_pads
			(clearance 0)
		)
		(min_thickness 0.25)
		(keepout
			(tracks not_allowed)
			(vias allowed)
			(pads allowed)
			(copperpour not_allowed)
			(footprints allowed)
		)
		(placement
			(enabled no)
			(sheetname "")
		)
		(fill yes
			(thermal_gap 0.5)
			(thermal_bridge_width 0.5)
			(island_removal_mode 0)
		)
		(polygon
			(pts
				(arc
					(start 29.586174 -217.735404)
					(mid 28.918154 -217.735404)
					(end 29.586174 -217.735404)
				)
			)
		)
	)
	(zone
		(layers "B.Cu" "In11.Cu" "In13.Cu" "In15.Cu")
		(hatch none 0.5)
		(connect_pads
			(clearance 0)
		)
		(min_thickness 0.25)
		(keepout
			(tracks not_allowed)
			(vias allowed)
			(pads allowed)
			(copperpour not_allowed)
			(footprints allowed)
		)
		(placement
			(enabled no)
			(sheetname "")
		)
		(fill yes
			(thermal_gap 0.5)
			(thermal_bridge_width 0.5)
			(island_removal_mode 0)
		)
		(polygon
			(pts
				(arc
					(start 141.529816 -261.93623)
					(mid 140.899896 -261.93623)
					(end 141.529816 -261.93623)
				)
			)
		)
	)
	(zone
		(layers "B.Cu" "In11.Cu" "In13.Cu" "In15.Cu")
		(hatch none 0.5)
		(connect_pads
			(clearance 0)
		)
		(min_thickness 0.25)
		(keepout
			(tracks not_allowed)
			(vias allowed)
			(pads allowed)
			(copperpour not_allowed)
			(footprints allowed)
		)
		(placement
			(enabled no)
			(sheetname "")
		)
		(fill yes
			(thermal_gap 0.5)
			(thermal_bridge_width 0.5)
			(island_removal_mode 0)
		)
		(polygon
			(pts
				(arc
					(start 82.037174 -428.28972)
					(mid 81.262982 -428.28972)
					(end 82.037174 -428.28972)
				)
			)
		)
	)
	(zone
		(layers "B.Cu" "In11.Cu" "In13.Cu" "In15.Cu")
		(hatch none 0.5)
		(connect_pads
			(clearance 0)
		)
		(min_thickness 0.25)
		(keepout
			(tracks not_allowed)
			(vias allowed)
			(pads allowed)
			(copperpour not_allowed)
			(footprints allowed)
		)
		(placement
			(enabled no)
			(sheetname "")
		)
		(fill yes
			(thermal_gap 0.5)
			(thermal_bridge_width 0.5)
			(island_removal_mode 0)
		)
		(polygon
			(pts
				(arc
					(start 165.733984 -385.31038)
					(mid 165.104064 -385.31038)
					(end 165.733984 -385.31038)
				)
			)
		)
	)
	(zone
		(layers "B.Cu" "In11.Cu" "In13.Cu" "In15.Cu")
		(hatch none 0.5)
		(connect_pads
			(clearance 0)
		)
		(min_thickness 0.25)
		(keepout
			(tracks not_allowed)
			(vias allowed)
			(pads allowed)
			(copperpour not_allowed)
			(footprints allowed)
		)
		(placement
			(enabled no)
			(sheetname "")
		)
		(fill yes
			(thermal_gap 0.5)
			(thermal_bridge_width 0.5)
			(island_removal_mode 0)
		)
		(polygon
			(pts
				(arc
					(start 396.136876 -428.28972)
					(mid 395.362684 -428.28972)
					(end 396.136876 -428.28972)
				)
			)
		)
	)
	(zone
		(layers "B.Cu" "In11.Cu" "In13.Cu" "In15.Cu")
		(hatch none 0.5)
		(connect_pads
			(clearance 0)
		)
		(min_thickness 0.25)
		(keepout
			(tracks not_allowed)
			(vias allowed)
			(pads allowed)
			(copperpour not_allowed)
			(footprints allowed)
		)
		(placement
			(enabled no)
			(sheetname "")
		)
		(fill yes
			(thermal_gap 0.5)
			(thermal_bridge_width 0.5)
			(island_removal_mode 0)
		)
		(polygon
			(pts
				(arc
					(start 194.938142 -237.285276)
					(mid 194.270122 -237.285276)
					(end 194.938142 -237.285276)
				)
			)
		)
	)
	(zone
		(layers "B.Cu" "In11.Cu" "In13.Cu" "In15.Cu")
		(hatch none 0.5)
		(connect_pads
			(clearance 0)
		)
		(min_thickness 0.25)
		(keepout
			(tracks not_allowed)
			(vias allowed)
			(pads allowed)
			(copperpour not_allowed)
			(footprints allowed)
		)
		(placement
			(enabled no)
			(sheetname "")
		)
		(fill yes
			(thermal_gap 0.5)
			(thermal_bridge_width 0.5)
			(island_removal_mode 0)
		)
		(polygon
			(pts
				(arc
					(start 277.526242 -285.735014)
					(mid 276.858222 -285.735014)
					(end 277.526242 -285.735014)
				)
			)
		)
	)
	(zone
		(layers "B.Cu" "In11.Cu" "In13.Cu" "In15.Cu")
		(hatch none 0.5)
		(connect_pads
			(clearance 0)
		)
		(min_thickness 0.25)
		(keepout
			(tracks not_allowed)
			(vias allowed)
			(pads allowed)
			(copperpour not_allowed)
			(footprints allowed)
		)
		(placement
			(enabled no)
			(sheetname "")
		)
		(fill yes
			(thermal_gap 0.5)
			(thermal_bridge_width 0.5)
			(island_removal_mode 0)
		)
		(polygon
			(pts
				(arc
					(start 387.206236 -397.849344)
					(mid 386.576316 -397.849344)
					(end 387.206236 -397.849344)
				)
			)
		)
	)
	(zone
		(layers "B.Cu" "In11.Cu" "In13.Cu" "In15.Cu")
		(hatch none 0.5)
		(connect_pads
			(clearance 0)
		)
		(min_thickness 0.25)
		(keepout
			(tracks not_allowed)
			(vias allowed)
			(pads allowed)
			(copperpour not_allowed)
			(footprints allowed)
		)
		(placement
			(enabled no)
			(sheetname "")
		)
		(fill yes
			(thermal_gap 0.5)
			(thermal_bridge_width 0.5)
			(island_removal_mode 0)
		)
		(polygon
			(pts
				(arc
					(start 446.978278 -227.085144)
					(mid 446.310258 -227.085144)
					(end 446.978278 -227.085144)
				)
			)
		)
	)
	(zone
		(layers "B.Cu" "In11.Cu" "In13.Cu" "In15.Cu")
		(hatch none 0.5)
		(connect_pads
			(clearance 0)
		)
		(min_thickness 0.25)
		(keepout
			(tracks not_allowed)
			(vias allowed)
			(pads allowed)
			(copperpour not_allowed)
			(footprints allowed)
		)
		(placement
			(enabled no)
			(sheetname "")
		)
		(fill yes
			(thermal_gap 0.5)
			(thermal_bridge_width 0.5)
			(island_removal_mode 0)
		)
		(polygon
			(pts
				(arc
					(start 82.485992 -255.014476)
					(mid 81.856072 -255.014476)
					(end 82.485992 -255.014476)
				)
			)
		)
	)
	(zone
		(layers "B.Cu" "In11.Cu" "In13.Cu" "In15.Cu")
		(hatch none 0.5)
		(connect_pads
			(clearance 0)
		)
		(min_thickness 0.25)
		(keepout
			(tracks not_allowed)
			(vias allowed)
			(pads allowed)
			(copperpour not_allowed)
			(footprints allowed)
		)
		(placement
			(enabled no)
			(sheetname "")
		)
		(fill yes
			(thermal_gap 0.5)
			(thermal_bridge_width 0.5)
			(island_removal_mode 0)
		)
		(polygon
			(pts
				(arc
					(start 442.87821 -274.684998)
					(mid 442.21019 -274.684998)
					(end 442.87821 -274.684998)
				)
			)
		)
	)
	(zone
		(layers "B.Cu" "In11.Cu" "In13.Cu" "In15.Cu")
		(hatch none 0.5)
		(connect_pads
			(clearance 0)
		)
		(min_thickness 0.25)
		(keepout
			(tracks not_allowed)
			(vias allowed)
			(pads allowed)
			(copperpour not_allowed)
			(footprints allowed)
		)
		(placement
			(enabled no)
			(sheetname "")
		)
		(fill yes
			(thermal_gap 0.5)
			(thermal_bridge_width 0.5)
			(island_removal_mode 0)
		)
		(polygon
			(pts
				(arc
					(start 141.229842 -250.964446)
					(mid 140.599922 -250.964446)
					(end 141.229842 -250.964446)
				)
			)
		)
	)
	(zone
		(layers "B.Cu" "In11.Cu" "In13.Cu" "In15.Cu")
		(hatch none 0.5)
		(connect_pads
			(clearance 0)
		)
		(min_thickness 0.25)
		(keepout
			(tracks not_allowed)
			(vias allowed)
			(pads allowed)
			(copperpour not_allowed)
			(footprints allowed)
		)
		(placement
			(enabled no)
			(sheetname "")
		)
		(fill yes
			(thermal_gap 0.5)
			(thermal_bridge_width 0.5)
			(island_removal_mode 0)
		)
		(polygon
			(pts
				(arc
					(start 83.255866 -271.656302)
					(mid 82.625946 -271.656302)
					(end 83.255866 -271.656302)
				)
			)
		)
	)
	(zone
		(layers "B.Cu" "In11.Cu" "In13.Cu" "In15.Cu")
		(hatch none 0.5)
		(connect_pads
			(clearance 0)
		)
		(min_thickness 0.25)
		(keepout
			(tracks not_allowed)
			(vias allowed)
			(pads allowed)
			(copperpour not_allowed)
			(footprints allowed)
		)
		(placement
			(enabled no)
			(sheetname "")
		)
		(fill yes
			(thermal_gap 0.5)
			(thermal_bridge_width 0.5)
			(island_removal_mode 0)
		)
		(polygon
			(pts
				(arc
					(start 277.526242 -294.235124)
					(mid 276.858222 -294.235124)
					(end 277.526242 -294.235124)
				)
			)
		)
	)
	(zone
		(layers "B.Cu" "In11.Cu" "In13.Cu" "In15.Cu")
		(hatch none 0.5)
		(connect_pads
			(clearance 0)
		)
		(min_thickness 0.25)
		(keepout
			(tracks not_allowed)
			(vias allowed)
			(pads allowed)
			(copperpour not_allowed)
			(footprints allowed)
		)
		(placement
			(enabled no)
			(sheetname "")
		)
		(fill yes
			(thermal_gap 0.5)
			(thermal_bridge_width 0.5)
			(island_removal_mode 0)
		)
		(polygon
			(pts
				(arc
					(start 119.90959 -284.616398)
					(mid 119.27967 -284.616398)
					(end 119.90959 -284.616398)
				)
			)
		)
	)
	(zone
		(layers "B.Cu" "In11.Cu" "In13.Cu" "In15.Cu")
		(hatch none 0.5)
		(connect_pads
			(clearance 0)
		)
		(min_thickness 0.25)
		(keepout
			(tracks not_allowed)
			(vias allowed)
			(pads allowed)
			(copperpour not_allowed)
			(footprints allowed)
		)
		(placement
			(enabled no)
			(sheetname "")
		)
		(fill yes
			(thermal_gap 0.5)
			(thermal_bridge_width 0.5)
			(island_removal_mode 0)
		)
		(polygon
			(pts
				(arc
					(start 85.750654 -404.46452)
					(mid 85.082634 -404.46452)
					(end 85.750654 -404.46452)
				)
			)
		)
	)
	(zone
		(layers "B.Cu" "In11.Cu" "In13.Cu" "In15.Cu")
		(hatch none 0.5)
		(connect_pads
			(clearance 0)
		)
		(min_thickness 0.25)
		(keepout
			(tracks not_allowed)
			(vias allowed)
			(pads allowed)
			(copperpour not_allowed)
			(footprints allowed)
		)
		(placement
			(enabled no)
			(sheetname "")
		)
		(fill yes
			(thermal_gap 0.5)
			(thermal_bridge_width 0.5)
			(island_removal_mode 0)
		)
		(polygon
			(pts
				(arc
					(start 199.03821 -264.485374)
					(mid 198.37019 -264.485374)
					(end 199.03821 -264.485374)
				)
			)
		)
	)
	(zone
		(layers "B.Cu" "In11.Cu" "In13.Cu" "In15.Cu")
		(hatch none 0.5)
		(connect_pads
			(clearance 0)
		)
		(min_thickness 0.25)
		(keepout
			(tracks not_allowed)
			(vias allowed)
			(pads allowed)
			(copperpour not_allowed)
			(footprints allowed)
		)
		(placement
			(enabled no)
			(sheetname "")
		)
		(fill yes
			(thermal_gap 0.5)
			(thermal_bridge_width 0.5)
			(island_removal_mode 0)
		)
		(polygon
			(pts
				(arc
					(start 199.03821 -200.735438)
					(mid 198.37019 -200.735438)
					(end 199.03821 -200.735438)
				)
			)
		)
	)
	(zone
		(layers "B.Cu" "In11.Cu" "In13.Cu" "In15.Cu")
		(hatch none 0.5)
		(connect_pads
			(clearance 0)
		)
		(min_thickness 0.25)
		(keepout
			(tracks not_allowed)
			(vias allowed)
			(pads allowed)
			(copperpour not_allowed)
			(footprints allowed)
		)
		(placement
			(enabled no)
			(sheetname "")
		)
		(fill yes
			(thermal_gap 0.5)
			(thermal_bridge_width 0.5)
			(island_removal_mode 0)
		)
		(polygon
			(pts
				(arc
					(start 329.016106 -242.864132)
					(mid 328.386186 -242.864132)
					(end 329.016106 -242.864132)
				)
			)
		)
	)
	(zone
		(layers "B.Cu" "In11.Cu" "In13.Cu" "In15.Cu")
		(hatch none 0.5)
		(connect_pads
			(clearance 0)
		)
		(min_thickness 0.25)
		(keepout
			(tracks not_allowed)
			(vias allowed)
			(pads allowed)
			(copperpour not_allowed)
			(footprints allowed)
		)
		(placement
			(enabled no)
			(sheetname "")
		)
		(fill yes
			(thermal_gap 0.5)
			(thermal_bridge_width 0.5)
			(island_removal_mode 0)
		)
		(polygon
			(pts
				(arc
					(start 141.999716 -280.566368)
					(mid 141.369796 -280.566368)
					(end 141.999716 -280.566368)
				)
			)
		)
	)
	(zone
		(layers "B.Cu" "In11.Cu" "In13.Cu" "In15.Cu")
		(hatch none 0.5)
		(connect_pads
			(clearance 0)
		)
		(min_thickness 0.25)
		(keepout
			(tracks not_allowed)
			(vias allowed)
			(pads allowed)
			(copperpour not_allowed)
			(footprints allowed)
		)
		(placement
			(enabled no)
			(sheetname "")
		)
		(fill yes
			(thermal_gap 0.5)
			(thermal_bridge_width 0.5)
			(island_removal_mode 0)
		)
		(polygon
			(pts
				(arc
					(start 389.939784 -280.566114)
					(mid 389.309864 -280.566114)
					(end 389.939784 -280.566114)
				)
			)
		)
	)
	(zone
		(layers "B.Cu" "In11.Cu" "In13.Cu" "In15.Cu")
		(hatch none 0.5)
		(connect_pads
			(clearance 0)
		)
		(min_thickness 0.25)
		(keepout
			(tracks not_allowed)
			(vias allowed)
			(pads allowed)
			(copperpour not_allowed)
			(footprints allowed)
		)
		(placement
			(enabled no)
			(sheetname "")
		)
		(fill yes
			(thermal_gap 0.5)
			(thermal_bridge_width 0.5)
			(island_removal_mode 0)
		)
		(polygon
			(pts
				(arc
					(start 389.469884 -265.176)
					(mid 388.839964 -265.176)
					(end 389.469884 -265.176)
				)
			)
		)
	)
	(zone
		(layers "B.Cu" "In11.Cu" "In13.Cu" "In15.Cu")
		(hatch none 0.5)
		(connect_pads
			(clearance 0)
		)
		(min_thickness 0.25)
		(keepout
			(tracks not_allowed)
			(vias allowed)
			(pads allowed)
			(copperpour not_allowed)
			(footprints allowed)
		)
		(placement
			(enabled no)
			(sheetname "")
		)
		(fill yes
			(thermal_gap 0.5)
			(thermal_bridge_width 0.5)
			(island_removal_mode 0)
		)
		(polygon
			(pts
				(arc
					(start 329.03668 -428.28972)
					(mid 328.262488 -428.28972)
					(end 329.03668 -428.28972)
				)
			)
		)
	)
	(zone
		(layers "B.Cu" "In11.Cu" "In13.Cu" "In15.Cu")
		(hatch none 0.5)
		(connect_pads
			(clearance 0)
		)
		(min_thickness 0.25)
		(keepout
			(tracks not_allowed)
			(vias allowed)
			(pads allowed)
			(copperpour not_allowed)
			(footprints allowed)
		)
		(placement
			(enabled no)
			(sheetname "")
		)
		(fill yes
			(thermal_gap 0.5)
			(thermal_bridge_width 0.5)
			(island_removal_mode 0)
		)
		(polygon
			(pts
				(arc
					(start 199.03821 -254.285242)
					(mid 198.37019 -254.285242)
					(end 199.03821 -254.285242)
				)
			)
		)
	)
	(zone
		(layers "B.Cu" "In11.Cu" "In13.Cu" "In15.Cu")
		(hatch none 0.5)
		(connect_pads
			(clearance 0)
		)
		(min_thickness 0.25)
		(keepout
			(tracks not_allowed)
			(vias allowed)
			(pads allowed)
			(copperpour not_allowed)
			(footprints allowed)
		)
		(placement
			(enabled no)
			(sheetname "")
		)
		(fill yes
			(thermal_gap 0.5)
			(thermal_bridge_width 0.5)
			(island_removal_mode 0)
		)
		(polygon
			(pts
				(arc
					(start 378.806202 -397.849344)
					(mid 378.176282 -397.849344)
					(end 378.806202 -397.849344)
				)
			)
		)
	)
	(zone
		(layers "B.Cu" "In11.Cu" "In13.Cu" "In15.Cu")
		(hatch none 0.5)
		(connect_pads
			(clearance 0)
		)
		(min_thickness 0.25)
		(keepout
			(tracks not_allowed)
			(vias allowed)
			(pads allowed)
			(copperpour not_allowed)
			(footprints allowed)
		)
		(placement
			(enabled no)
			(sheetname "")
		)
		(fill yes
			(thermal_gap 0.5)
			(thermal_bridge_width 0.5)
			(island_removal_mode 0)
		)
		(polygon
			(pts
				(arc
					(start 446.978278 -275.535136)
					(mid 446.310258 -275.535136)
					(end 446.978278 -275.535136)
				)
			)
		)
	)
	(zone
		(layers "B.Cu" "In11.Cu" "In13.Cu" "In15.Cu")
		(hatch none 0.5)
		(connect_pads
			(clearance 0)
		)
		(min_thickness 0.25)
		(keepout
			(tracks not_allowed)
			(vias allowed)
			(pads allowed)
			(copperpour not_allowed)
			(footprints allowed)
		)
		(placement
			(enabled no)
			(sheetname "")
		)
		(fill yes
			(thermal_gap 0.5)
			(thermal_bridge_width 0.5)
			(island_removal_mode 0)
		)
		(polygon
			(pts
				(arc
					(start 83.255866 -263.556242)
					(mid 82.625946 -263.556242)
					(end 83.255866 -263.556242)
				)
			)
		)
	)
	(zone
		(layers "B.Cu" "In11.Cu" "In13.Cu" "In15.Cu")
		(hatch none 0.5)
		(connect_pads
			(clearance 0)
		)
		(min_thickness 0.25)
		(keepout
			(tracks not_allowed)
			(vias allowed)
			(pads allowed)
			(copperpour not_allowed)
			(footprints allowed)
		)
		(placement
			(enabled no)
			(sheetname "")
		)
		(fill yes
			(thermal_gap 0.5)
			(thermal_bridge_width 0.5)
			(island_removal_mode 0)
		)
		(polygon
			(pts
				(arc
					(start 143.40967 -279.756362)
					(mid 142.77975 -279.756362)
					(end 143.40967 -279.756362)
				)
			)
		)
	)
	(zone
		(layers "B.Cu" "In11.Cu" "In13.Cu" "In15.Cu")
		(hatch none 0.5)
		(connect_pads
			(clearance 0)
		)
		(min_thickness 0.25)
		(keepout
			(tracks not_allowed)
			(vias allowed)
			(pads allowed)
			(copperpour not_allowed)
			(footprints allowed)
		)
		(placement
			(enabled no)
			(sheetname "")
		)
		(fill yes
			(thermal_gap 0.5)
			(thermal_bridge_width 0.5)
			(island_removal_mode 0)
		)
		(polygon
			(pts
				(arc
					(start 329.486006 -232.334054)
					(mid 328.856086 -232.334054)
					(end 329.486006 -232.334054)
				)
			)
		)
	)
	(zone
		(layers "B.Cu" "In11.Cu" "In13.Cu" "In15.Cu")
		(hatch none 0.5)
		(connect_pads
			(clearance 0)
		)
		(min_thickness 0.25)
		(keepout
			(tracks not_allowed)
			(vias allowed)
			(pads allowed)
			(copperpour not_allowed)
			(footprints allowed)
		)
		(placement
			(enabled no)
			(sheetname "")
		)
		(fill yes
			(thermal_gap 0.5)
			(thermal_bridge_width 0.5)
			(island_removal_mode 0)
		)
		(polygon
			(pts
				(arc
					(start 330.89596 -226.664266)
					(mid 330.26604 -226.664266)
					(end 330.89596 -226.664266)
				)
			)
		)
	)
	(zone
		(layers "B.Cu" "In11.Cu" "In13.Cu" "In15.Cu")
		(hatch none 0.5)
		(connect_pads
			(clearance 0)
		)
		(min_thickness 0.25)
		(keepout
			(tracks not_allowed)
			(vias allowed)
			(pads allowed)
			(copperpour not_allowed)
			(footprints allowed)
		)
		(placement
			(enabled no)
			(sheetname "")
		)
		(fill yes
			(thermal_gap 0.5)
			(thermal_bridge_width 0.5)
			(island_removal_mode 0)
		)
		(polygon
			(pts
				(arc
					(start 327.611486 -388.742428)
					(mid 326.943466 -388.742428)
					(end 327.611486 -388.742428)
				)
			)
		)
	)
	(zone
		(layers "B.Cu" "In11.Cu" "In13.Cu" "In15.Cu")
		(hatch none 0.5)
		(connect_pads
			(clearance 0)
		)
		(min_thickness 0.25)
		(keepout
			(tracks not_allowed)
			(vias allowed)
			(pads allowed)
			(copperpour not_allowed)
			(footprints allowed)
		)
		(placement
			(enabled no)
			(sheetname "")
		)
		(fill yes
			(thermal_gap 0.5)
			(thermal_bridge_width 0.5)
			(island_removal_mode 0)
		)
		(polygon
			(pts
				(arc
					(start 82.485992 -240.434368)
					(mid 81.856072 -240.434368)
					(end 82.485992 -240.434368)
				)
			)
		)
	)
	(zone
		(layers "B.Cu" "In11.Cu" "In13.Cu" "In15.Cu")
		(hatch none 0.5)
		(connect_pads
			(clearance 0)
		)
		(min_thickness 0.25)
		(keepout
			(tracks not_allowed)
			(vias allowed)
			(pads allowed)
			(copperpour not_allowed)
			(footprints allowed)
		)
		(placement
			(enabled no)
			(sheetname "")
		)
		(fill yes
			(thermal_gap 0.5)
			(thermal_bridge_width 0.5)
			(island_removal_mode 0)
		)
		(polygon
			(pts
				(arc
					(start 29.586174 -261.08533)
					(mid 28.918154 -261.08533)
					(end 29.586174 -261.08533)
				)
			)
		)
	)
	(zone
		(layers "B.Cu" "In11.Cu" "In13.Cu" "In15.Cu")
		(hatch none 0.5)
		(connect_pads
			(clearance 0)
		)
		(min_thickness 0.25)
		(keepout
			(tracks not_allowed)
			(vias allowed)
			(pads allowed)
			(copperpour not_allowed)
			(footprints allowed)
		)
		(placement
			(enabled no)
			(sheetname "")
		)
		(fill yes
			(thermal_gap 0.5)
			(thermal_bridge_width 0.5)
			(island_removal_mode 0)
		)
		(polygon
			(pts
				(arc
					(start 141.699742 -255.014476)
					(mid 141.069822 -255.014476)
					(end 141.699742 -255.014476)
				)
			)
		)
	)
	(zone
		(layers "B.Cu" "In11.Cu" "In13.Cu" "In15.Cu")
		(hatch none 0.5)
		(connect_pads
			(clearance 0)
		)
		(min_thickness 0.25)
		(keepout
			(tracks not_allowed)
			(vias allowed)
			(pads allowed)
			(copperpour not_allowed)
			(footprints allowed)
		)
		(placement
			(enabled no)
			(sheetname "")
		)
		(fill yes
			(thermal_gap 0.5)
			(thermal_bridge_width 0.5)
			(island_removal_mode 0)
		)
		(polygon
			(pts
				(arc
					(start 64.906398 -388.774432)
					(mid 64.276478 -388.774432)
					(end 64.906398 -388.774432)
				)
			)
		)
	)
	(zone
		(layers "B.Cu" "In11.Cu" "In13.Cu" "In15.Cu")
		(hatch none 0.5)
		(connect_pads
			(clearance 0)
		)
		(min_thickness 0.25)
		(keepout
			(tracks not_allowed)
			(vias allowed)
			(pads allowed)
			(copperpour not_allowed)
			(footprints allowed)
		)
		(placement
			(enabled no)
			(sheetname "")
		)
		(fill yes
			(thermal_gap 0.5)
			(thermal_bridge_width 0.5)
			(island_removal_mode 0)
		)
		(polygon
			(pts
				(arc
					(start 277.526242 -229.63505)
					(mid 276.858222 -229.63505)
					(end 277.526242 -229.63505)
				)
			)
		)
	)
	(zone
		(layers "B.Cu" "In11.Cu" "In13.Cu" "In15.Cu")
		(hatch none 0.5)
		(connect_pads
			(clearance 0)
		)
		(min_thickness 0.25)
		(keepout
			(tracks not_allowed)
			(vias allowed)
			(pads allowed)
			(copperpour not_allowed)
			(footprints allowed)
		)
		(placement
			(enabled no)
			(sheetname "")
		)
		(fill yes
			(thermal_gap 0.5)
			(thermal_bridge_width 0.5)
			(island_removal_mode 0)
		)
		(polygon
			(pts
				(arc
					(start 277.526242 -275.535136)
					(mid 276.858222 -275.535136)
					(end 277.526242 -275.535136)
				)
			)
		)
	)
	(zone
		(layers "B.Cu" "In11.Cu" "In13.Cu" "In15.Cu")
		(hatch none 0.5)
		(connect_pads
			(clearance 0)
		)
		(min_thickness 0.25)
		(keepout
			(tracks not_allowed)
			(vias allowed)
			(pads allowed)
			(copperpour not_allowed)
			(footprints allowed)
		)
		(placement
			(enabled no)
			(sheetname "")
		)
		(fill yes
			(thermal_gap 0.5)
			(thermal_bridge_width 0.5)
			(island_removal_mode 0)
		)
		(polygon
			(pts
				(arc
					(start 199.03821 -289.135312)
					(mid 198.37019 -289.135312)
					(end 199.03821 -289.135312)
				)
			)
		)
	)
	(zone
		(layers "B.Cu" "In11.Cu" "In13.Cu" "In15.Cu")
		(hatch none 0.5)
		(connect_pads
			(clearance 0)
		)
		(min_thickness 0.25)
		(keepout
			(tracks not_allowed)
			(vias allowed)
			(pads allowed)
			(copperpour not_allowed)
			(footprints allowed)
		)
		(placement
			(enabled no)
			(sheetname "")
		)
		(fill yes
			(thermal_gap 0.5)
			(thermal_bridge_width 0.5)
			(island_removal_mode 0)
		)
		(polygon
			(pts
				(arc
					(start 126.489714 -282.996386)
					(mid 125.859794 -282.996386)
					(end 126.489714 -282.996386)
				)
			)
		)
	)
	(zone
		(layers "B.Cu" "In11.Cu" "In13.Cu" "In15.Cu")
		(hatch none 0.5)
		(connect_pads
			(clearance 0)
		)
		(min_thickness 0.25)
		(keepout
			(tracks not_allowed)
			(vias allowed)
			(pads allowed)
			(copperpour not_allowed)
			(footprints allowed)
		)
		(placement
			(enabled no)
			(sheetname "")
		)
		(fill yes
			(thermal_gap 0.5)
			(thermal_bridge_width 0.5)
			(island_removal_mode 0)
		)
		(polygon
			(pts
				(arc
					(start 351.876106 -286.236156)
					(mid 351.246186 -286.236156)
					(end 351.876106 -286.236156)
				)
			)
		)
	)
	(zone
		(layers "B.Cu" "In11.Cu" "In13.Cu" "In15.Cu")
		(hatch none 0.5)
		(connect_pads
			(clearance 0)
		)
		(min_thickness 0.25)
		(keepout
			(tracks not_allowed)
			(vias allowed)
			(pads allowed)
			(copperpour not_allowed)
			(footprints allowed)
		)
		(placement
			(enabled no)
			(sheetname "")
		)
		(fill yes
			(thermal_gap 0.5)
			(thermal_bridge_width 0.5)
			(island_removal_mode 0)
		)
		(polygon
			(pts
				(arc
					(start 277.526242 -206.685134)
					(mid 276.858222 -206.685134)
					(end 277.526242 -206.685134)
				)
			)
		)
	)
	(zone
		(layers "B.Cu" "In11.Cu" "In13.Cu" "In15.Cu")
		(hatch none 0.5)
		(connect_pads
			(clearance 0)
		)
		(min_thickness 0.25)
		(keepout
			(tracks not_allowed)
			(vias allowed)
			(pads allowed)
			(copperpour not_allowed)
			(footprints allowed)
		)
		(placement
			(enabled no)
			(sheetname "")
		)
		(fill yes
			(thermal_gap 0.5)
			(thermal_bridge_width 0.5)
			(island_removal_mode 0)
		)
		(polygon
			(pts
				(arc
					(start 389.469884 -284.616144)
					(mid 388.839964 -284.616144)
					(end 389.469884 -284.616144)
				)
			)
		)
	)
	(zone
		(layers "B.Cu" "In11.Cu" "In13.Cu" "In15.Cu")
		(hatch none 0.5)
		(connect_pads
			(clearance 0)
		)
		(min_thickness 0.25)
		(keepout
			(tracks not_allowed)
			(vias allowed)
			(pads allowed)
			(copperpour not_allowed)
			(footprints allowed)
		)
		(placement
			(enabled no)
			(sheetname "")
		)
		(fill yes
			(thermal_gap 0.5)
			(thermal_bridge_width 0.5)
			(island_removal_mode 0)
		)
		(polygon
			(pts
				(arc
					(start 99.236022 -284.616398)
					(mid 98.606102 -284.616398)
					(end 99.236022 -284.616398)
				)
			)
		)
	)
	(zone
		(layers "B.Cu" "In11.Cu" "In13.Cu" "In15.Cu")
		(hatch none 0.5)
		(connect_pads
			(clearance 0)
		)
		(min_thickness 0.25)
		(keepout
			(tracks not_allowed)
			(vias allowed)
			(pads allowed)
			(copperpour not_allowed)
			(footprints allowed)
		)
		(placement
			(enabled no)
			(sheetname "")
		)
		(fill yes
			(thermal_gap 0.5)
			(thermal_bridge_width 0.5)
			(island_removal_mode 0)
		)
		(polygon
			(pts
				(arc
					(start 142.93977 -262.746236)
					(mid 142.30985 -262.746236)
					(end 142.93977 -262.746236)
				)
			)
		)
	)
	(zone
		(layers "B.Cu" "In11.Cu" "In13.Cu" "In15.Cu")
		(hatch none 0.5)
		(connect_pads
			(clearance 0)
		)
		(min_thickness 0.25)
		(keepout
			(tracks not_allowed)
			(vias allowed)
			(pads allowed)
			(copperpour not_allowed)
			(footprints allowed)
		)
		(placement
			(enabled no)
			(sheetname "")
		)
		(fill yes
			(thermal_gap 0.5)
			(thermal_bridge_width 0.5)
			(island_removal_mode 0)
		)
		(polygon
			(pts
				(arc
					(start 367.849658 -282.996132)
					(mid 367.219738 -282.996132)
					(end 367.849658 -282.996132)
				)
			)
		)
	)
	(zone
		(layers "B.Cu" "In11.Cu" "In13.Cu" "In15.Cu")
		(hatch none 0.5)
		(connect_pads
			(clearance 0)
		)
		(min_thickness 0.25)
		(keepout
			(tracks not_allowed)
			(vias allowed)
			(pads allowed)
			(copperpour not_allowed)
			(footprints allowed)
		)
		(placement
			(enabled no)
			(sheetname "")
		)
		(fill yes
			(thermal_gap 0.5)
			(thermal_bridge_width 0.5)
			(island_removal_mode 0)
		)
		(polygon
			(pts
				(arc
					(start 389.939784 -277.32609)
					(mid 389.309864 -277.32609)
					(end 389.939784 -277.32609)
				)
			)
		)
	)
	(zone
		(layers "B.Cu" "In11.Cu" "In13.Cu" "In15.Cu")
		(hatch none 0.5)
		(connect_pads
			(clearance 0)
		)
		(min_thickness 0.25)
		(keepout
			(tracks not_allowed)
			(vias allowed)
			(pads allowed)
			(copperpour not_allowed)
			(footprints allowed)
		)
		(placement
			(enabled no)
			(sheetname "")
		)
		(fill yes
			(thermal_gap 0.5)
			(thermal_bridge_width 0.5)
			(island_removal_mode 0)
		)
		(polygon
			(pts
				(arc
					(start 194.938142 -229.635304)
					(mid 194.270122 -229.635304)
					(end 194.938142 -229.635304)
				)
			)
		)
	)
	(zone
		(layers "B.Cu" "In11.Cu" "In13.Cu" "In15.Cu")
		(hatch none 0.5)
		(connect_pads
			(clearance 0)
		)
		(min_thickness 0.25)
		(keepout
			(tracks not_allowed)
			(vias allowed)
			(pads allowed)
			(copperpour not_allowed)
			(footprints allowed)
		)
		(placement
			(enabled no)
			(sheetname "")
		)
		(fill yes
			(thermal_gap 0.5)
			(thermal_bridge_width 0.5)
			(island_removal_mode 0)
		)
		(polygon
			(pts
				(arc
					(start 107.396026 -239.624362)
					(mid 106.766106 -239.624362)
					(end 107.396026 -239.624362)
				)
			)
		)
	)
	(zone
		(layers "B.Cu" "In11.Cu" "In13.Cu" "In15.Cu")
		(hatch none 0.5)
		(connect_pads
			(clearance 0)
		)
		(min_thickness 0.25)
		(keepout
			(tracks not_allowed)
			(vias allowed)
			(pads allowed)
			(copperpour not_allowed)
			(footprints allowed)
		)
		(placement
			(enabled no)
			(sheetname "")
		)
		(fill yes
			(thermal_gap 0.5)
			(thermal_bridge_width 0.5)
			(island_removal_mode 0)
		)
		(polygon
			(pts
				(arc
					(start 273.426174 -316.335156)
					(mid 272.758154 -316.335156)
					(end 273.426174 -316.335156)
				)
			)
		)
	)
	(zone
		(layers "B.Cu" "In11.Cu" "In13.Cu" "In15.Cu")
		(hatch none 0.5)
		(connect_pads
			(clearance 0)
		)
		(min_thickness 0.25)
		(keepout
			(tracks not_allowed)
			(vias allowed)
			(pads allowed)
			(copperpour not_allowed)
			(footprints allowed)
		)
		(placement
			(enabled no)
			(sheetname "")
		)
		(fill yes
			(thermal_gap 0.5)
			(thermal_bridge_width 0.5)
			(island_removal_mode 0)
		)
		(polygon
			(pts
				(arc
					(start 106.455972 -239.624362)
					(mid 105.826052 -239.624362)
					(end 106.455972 -239.624362)
				)
			)
		)
	)
	(zone
		(layers "B.Cu" "In11.Cu" "In13.Cu" "In15.Cu")
		(hatch none 0.5)
		(connect_pads
			(clearance 0)
		)
		(min_thickness 0.25)
		(keepout
			(tracks not_allowed)
			(vias allowed)
			(pads allowed)
			(copperpour not_allowed)
			(footprints allowed)
		)
		(placement
			(enabled no)
			(sheetname "")
		)
		(fill yes
			(thermal_gap 0.5)
			(thermal_bridge_width 0.5)
			(island_removal_mode 0)
		)
		(polygon
			(pts
				(arc
					(start 142.93977 -267.606272)
					(mid 142.30985 -267.606272)
					(end 142.93977 -267.606272)
				)
			)
		)
	)
	(zone
		(layers "B.Cu" "In11.Cu" "In13.Cu" "In15.Cu")
		(hatch none 0.5)
		(connect_pads
			(clearance 0)
		)
		(min_thickness 0.25)
		(keepout
			(tracks not_allowed)
			(vias allowed)
			(pads allowed)
			(copperpour not_allowed)
			(footprints allowed)
		)
		(placement
			(enabled no)
			(sheetname "")
		)
		(fill yes
			(thermal_gap 0.5)
			(thermal_bridge_width 0.5)
			(island_removal_mode 0)
		)
		(polygon
			(pts
				(arc
					(start 374.129808 -242.864132)
					(mid 373.499888 -242.864132)
					(end 374.129808 -242.864132)
				)
			)
		)
	)
	(zone
		(layers "B.Cu" "In11.Cu" "In13.Cu" "In15.Cu")
		(hatch none 0.5)
		(connect_pads
			(clearance 0)
		)
		(min_thickness 0.25)
		(keepout
			(tracks not_allowed)
			(vias allowed)
			(pads allowed)
			(copperpour not_allowed)
			(footprints allowed)
		)
		(placement
			(enabled no)
			(sheetname "")
		)
		(fill yes
			(thermal_gap 0.5)
			(thermal_bridge_width 0.5)
			(island_removal_mode 0)
		)
		(polygon
			(pts
				(arc
					(start 277.526242 -212.635084)
					(mid 276.858222 -212.635084)
					(end 277.526242 -212.635084)
				)
			)
		)
	)
	(zone
		(layers "B.Cu" "In11.Cu" "In13.Cu" "In15.Cu")
		(hatch none 0.5)
		(connect_pads
			(clearance 0)
		)
		(min_thickness 0.25)
		(keepout
			(tracks not_allowed)
			(vias allowed)
			(pads allowed)
			(copperpour not_allowed)
			(footprints allowed)
		)
		(placement
			(enabled no)
			(sheetname "")
		)
		(fill yes
			(thermal_gap 0.5)
			(thermal_bridge_width 0.5)
			(island_removal_mode 0)
		)
		(polygon
			(pts
				(arc
					(start 81.376012 -274.896326)
					(mid 80.746092 -274.896326)
					(end 81.376012 -274.896326)
				)
			)
		)
	)
	(zone
		(layers "B.Cu" "In11.Cu" "In13.Cu" "In15.Cu")
		(hatch none 0.5)
		(connect_pads
			(clearance 0)
		)
		(min_thickness 0.25)
		(keepout
			(tracks not_allowed)
			(vias allowed)
			(pads allowed)
			(copperpour not_allowed)
			(footprints allowed)
		)
		(placement
			(enabled no)
			(sheetname "")
		)
		(fill yes
			(thermal_gap 0.5)
			(thermal_bridge_width 0.5)
			(island_removal_mode 0)
		)
		(polygon
			(pts
				(arc
					(start 29.586174 -304.435256)
					(mid 28.918154 -304.435256)
					(end 29.586174 -304.435256)
				)
			)
		)
	)
	(zone
		(layers "B.Cu" "In11.Cu" "In13.Cu" "In15.Cu")
		(hatch none 0.5)
		(connect_pads
			(clearance 0)
		)
		(min_thickness 0.25)
		(keepout
			(tracks not_allowed)
			(vias allowed)
			(pads allowed)
			(copperpour not_allowed)
			(footprints allowed)
		)
		(placement
			(enabled no)
			(sheetname "")
		)
		(fill yes
			(thermal_gap 0.5)
			(thermal_bridge_width 0.5)
			(island_removal_mode 0)
		)
		(polygon
			(pts
				(arc
					(start 109.746034 -238.814356)
					(mid 109.116114 -238.814356)
					(end 109.746034 -238.814356)
				)
			)
		)
	)
	(zone
		(layers "B.Cu" "In11.Cu" "In13.Cu" "In15.Cu")
		(hatch none 0.5)
		(connect_pads
			(clearance 0)
		)
		(min_thickness 0.25)
		(keepout
			(tracks not_allowed)
			(vias allowed)
			(pads allowed)
			(copperpour not_allowed)
			(footprints allowed)
		)
		(placement
			(enabled no)
			(sheetname "")
		)
		(fill yes
			(thermal_gap 0.5)
			(thermal_bridge_width 0.5)
			(island_removal_mode 0)
		)
		(polygon
			(pts
				(arc
					(start 330.726034 -285.42615)
					(mid 330.096114 -285.42615)
					(end 330.726034 -285.42615)
				)
			)
		)
	)
	(zone
		(layers "B.Cu" "In11.Cu" "In13.Cu" "In15.Cu")
		(hatch none 0.5)
		(connect_pads
			(clearance 0)
		)
		(min_thickness 0.25)
		(keepout
			(tracks not_allowed)
			(vias allowed)
			(pads allowed)
			(copperpour not_allowed)
			(footprints allowed)
		)
		(placement
			(enabled no)
			(sheetname "")
		)
		(fill yes
			(thermal_gap 0.5)
			(thermal_bridge_width 0.5)
			(island_removal_mode 0)
		)
		(polygon
			(pts
				(arc
					(start 446.978278 -270.43507)
					(mid 446.310258 -270.43507)
					(end 446.978278 -270.43507)
				)
			)
		)
	)
	(zone
		(layers "B.Cu" "In11.Cu" "In13.Cu" "In15.Cu")
		(hatch none 0.5)
		(connect_pads
			(clearance 0)
		)
		(min_thickness 0.25)
		(keepout
			(tracks not_allowed)
			(vias allowed)
			(pads allowed)
			(copperpour not_allowed)
			(footprints allowed)
		)
		(placement
			(enabled no)
			(sheetname "")
		)
		(fill yes
			(thermal_gap 0.5)
			(thermal_bridge_width 0.5)
			(island_removal_mode 0)
		)
		(polygon
			(pts
				(arc
					(start 141.229842 -234.764326)
					(mid 140.599922 -234.764326)
					(end 141.229842 -234.764326)
				)
			)
		)
	)
	(zone
		(layers "B.Cu" "In11.Cu" "In13.Cu" "In15.Cu")
		(hatch none 0.5)
		(connect_pads
			(clearance 0)
		)
		(min_thickness 0.25)
		(keepout
			(tracks not_allowed)
			(vias allowed)
			(pads allowed)
			(copperpour not_allowed)
			(footprints allowed)
		)
		(placement
			(enabled no)
			(sheetname "")
		)
		(fill yes
			(thermal_gap 0.5)
			(thermal_bridge_width 0.5)
			(island_removal_mode 0)
		)
		(polygon
			(pts
				(arc
					(start 277.526242 -262.785098)
					(mid 276.858222 -262.785098)
					(end 277.526242 -262.785098)
				)
			)
		)
	)
	(zone
		(layers "B.Cu" "In11.Cu" "In13.Cu" "In15.Cu")
		(hatch none 0.5)
		(connect_pads
			(clearance 0)
		)
		(min_thickness 0.25)
		(keepout
			(tracks not_allowed)
			(vias allowed)
			(pads allowed)
			(copperpour not_allowed)
			(footprints allowed)
		)
		(placement
			(enabled no)
			(sheetname "")
		)
		(fill yes
			(thermal_gap 0.5)
			(thermal_bridge_width 0.5)
			(island_removal_mode 0)
		)
		(polygon
			(pts
				(arc
					(start 384.80619 -397.849344)
					(mid 384.17627 -397.849344)
					(end 384.80619 -397.849344)
				)
			)
		)
	)
	(zone
		(layers "B.Cu" "In11.Cu" "In13.Cu" "In15.Cu")
		(hatch none 0.5)
		(connect_pads
			(clearance 0)
		)
		(min_thickness 0.25)
		(keepout
			(tracks not_allowed)
			(vias allowed)
			(pads allowed)
			(copperpour not_allowed)
			(footprints allowed)
		)
		(placement
			(enabled no)
			(sheetname "")
		)
		(fill yes
			(thermal_gap 0.5)
			(thermal_bridge_width 0.5)
			(island_removal_mode 0)
		)
		(polygon
			(pts
				(arc
					(start 82.955892 -233.144314)
					(mid 82.325972 -233.144314)
					(end 82.955892 -233.144314)
				)
			)
		)
	)
	(zone
		(layers "B.Cu" "In11.Cu" "In13.Cu" "In15.Cu")
		(hatch none 0.5)
		(connect_pads
			(clearance 0)
		)
		(min_thickness 0.25)
		(keepout
			(tracks not_allowed)
			(vias allowed)
			(pads allowed)
			(copperpour not_allowed)
			(footprints allowed)
		)
		(placement
			(enabled no)
			(sheetname "")
		)
		(fill yes
			(thermal_gap 0.5)
			(thermal_bridge_width 0.5)
			(island_removal_mode 0)
		)
		(polygon
			(pts
				(arc
					(start 442.87821 -233.884978)
					(mid 442.21019 -233.884978)
					(end 442.87821 -233.884978)
				)
			)
		)
	)
	(zone
		(layers "B.Cu" "In11.Cu" "In13.Cu" "In15.Cu")
		(hatch none 0.5)
		(connect_pads
			(clearance 0)
		)
		(min_thickness 0.25)
		(keepout
			(tracks not_allowed)
			(vias allowed)
			(pads allowed)
			(copperpour not_allowed)
			(footprints allowed)
		)
		(placement
			(enabled no)
			(sheetname "")
		)
		(fill yes
			(thermal_gap 0.5)
			(thermal_bridge_width 0.5)
			(island_removal_mode 0)
		)
		(polygon
			(pts
				(arc
					(start 370.66982 -286.236156)
					(mid 370.0399 -286.236156)
					(end 370.66982 -286.236156)
				)
			)
		)
	)
	(zone
		(layers "B.Cu" "In11.Cu" "In13.Cu" "In15.Cu")
		(hatch none 0.5)
		(connect_pads
			(clearance 0)
		)
		(min_thickness 0.25)
		(keepout
			(tracks not_allowed)
			(vias allowed)
			(pads allowed)
			(copperpour not_allowed)
			(footprints allowed)
		)
		(placement
			(enabled no)
			(sheetname "")
		)
		(fill yes
			(thermal_gap 0.5)
			(thermal_bridge_width 0.5)
			(island_removal_mode 0)
		)
		(polygon
			(pts
				(arc
					(start 82.955892 -255.824482)
					(mid 82.325972 -255.824482)
					(end 82.955892 -255.824482)
				)
			)
		)
	)
	(zone
		(layers "B.Cu" "In11.Cu" "In13.Cu" "In15.Cu")
		(hatch none 0.5)
		(connect_pads
			(clearance 0)
		)
		(min_thickness 0.25)
		(keepout
			(tracks not_allowed)
			(vias allowed)
			(pads allowed)
			(copperpour not_allowed)
			(footprints allowed)
		)
		(placement
			(enabled no)
			(sheetname "")
		)
		(fill yes
			(thermal_gap 0.5)
			(thermal_bridge_width 0.5)
			(island_removal_mode 0)
		)
		(polygon
			(pts
				(arc
					(start 29.586174 -298.485306)
					(mid 28.918154 -298.485306)
					(end 29.586174 -298.485306)
				)
			)
		)
	)
	(zone
		(layers "B.Cu" "In11.Cu" "In13.Cu" "In15.Cu")
		(hatch none 0.5)
		(connect_pads
			(clearance 0)
		)
		(min_thickness 0.25)
		(keepout
			(tracks not_allowed)
			(vias allowed)
			(pads allowed)
			(copperpour not_allowed)
			(footprints allowed)
		)
		(placement
			(enabled no)
			(sheetname "")
		)
		(fill yes
			(thermal_gap 0.5)
			(thermal_bridge_width 0.5)
			(island_removal_mode 0)
		)
		(polygon
			(pts
				(arc
					(start 123.669806 -282.996386)
					(mid 123.039886 -282.996386)
					(end 123.669806 -282.996386)
				)
			)
		)
	)
	(zone
		(layers "B.Cu" "In11.Cu" "In13.Cu" "In15.Cu")
		(hatch none 0.5)
		(connect_pads
			(clearance 0)
		)
		(min_thickness 0.25)
		(keepout
			(tracks not_allowed)
			(vias allowed)
			(pads allowed)
			(copperpour not_allowed)
			(footprints allowed)
		)
		(placement
			(enabled no)
			(sheetname "")
		)
		(fill yes
			(thermal_gap 0.5)
			(thermal_bridge_width 0.5)
			(island_removal_mode 0)
		)
		(polygon
			(pts
				(arc
					(start 159.733996 -385.31038)
					(mid 159.104076 -385.31038)
					(end 159.733996 -385.31038)
				)
			)
		)
	)
	(zone
		(layers "B.Cu" "In11.Cu" "In13.Cu" "In15.Cu")
		(hatch none 0.5)
		(connect_pads
			(clearance 0)
		)
		(min_thickness 0.25)
		(keepout
			(tracks not_allowed)
			(vias allowed)
			(pads allowed)
			(copperpour not_allowed)
			(footprints allowed)
		)
		(placement
			(enabled no)
			(sheetname "")
		)
		(fill yes
			(thermal_gap 0.5)
			(thermal_bridge_width 0.5)
			(island_removal_mode 0)
		)
		(polygon
			(pts
				(arc
					(start 142.639796 -253.394464)
					(mid 142.009876 -253.394464)
					(end 142.639796 -253.394464)
				)
			)
		)
	)
	(zone
		(layers "B.Cu" "In11.Cu" "In13.Cu" "In15.Cu")
		(hatch none 0.5)
		(connect_pads
			(clearance 0)
		)
		(min_thickness 0.25)
		(keepout
			(tracks not_allowed)
			(vias allowed)
			(pads allowed)
			(copperpour not_allowed)
			(footprints allowed)
		)
		(placement
			(enabled no)
			(sheetname "")
		)
		(fill yes
			(thermal_gap 0.5)
			(thermal_bridge_width 0.5)
			(island_removal_mode 0)
		)
		(polygon
			(pts
				(arc
					(start 446.978278 -212.635084)
					(mid 446.310258 -212.635084)
					(end 446.978278 -212.635084)
				)
			)
		)
	)
	(zone
		(layers "B.Cu" "In11.Cu" "In13.Cu" "In15.Cu")
		(hatch none 0.5)
		(connect_pads
			(clearance 0)
		)
		(min_thickness 0.25)
		(keepout
			(tracks not_allowed)
			(vias allowed)
			(pads allowed)
			(copperpour not_allowed)
			(footprints allowed)
		)
		(placement
			(enabled no)
			(sheetname "")
		)
		(fill yes
			(thermal_gap 0.5)
			(thermal_bridge_width 0.5)
			(island_removal_mode 0)
		)
		(polygon
			(pts
				(arc
					(start 25.486106 -293.38524)
					(mid 24.818086 -293.38524)
					(end 25.486106 -293.38524)
				)
			)
		)
	)
	(zone
		(layers "B.Cu" "In11.Cu" "In13.Cu" "In15.Cu")
		(hatch none 0.5)
		(connect_pads
			(clearance 0)
		)
		(min_thickness 0.25)
		(keepout
			(tracks not_allowed)
			(vias allowed)
			(pads allowed)
			(copperpour not_allowed)
			(footprints allowed)
		)
		(placement
			(enabled no)
			(sheetname "")
		)
		(fill yes
			(thermal_gap 0.5)
			(thermal_bridge_width 0.5)
			(island_removal_mode 0)
		)
		(polygon
			(pts
				(arc
					(start 389.939784 -262.745982)
					(mid 389.309864 -262.745982)
					(end 389.939784 -262.745982)
				)
			)
		)
	)
	(zone
		(layers "B.Cu" "In11.Cu" "In13.Cu" "In15.Cu")
		(hatch none 0.5)
		(connect_pads
			(clearance 0)
		)
		(min_thickness 0.25)
		(keepout
			(tracks not_allowed)
			(vias allowed)
			(pads allowed)
			(copperpour not_allowed)
			(footprints allowed)
		)
		(placement
			(enabled no)
			(sheetname "")
		)
		(fill yes
			(thermal_gap 0.5)
			(thermal_bridge_width 0.5)
			(island_removal_mode 0)
		)
		(polygon
			(pts
				(arc
					(start 389.939784 -291.905944)
					(mid 389.309864 -291.905944)
					(end 389.939784 -291.905944)
				)
			)
		)
	)
	(zone
		(layers "B.Cu" "In11.Cu" "In13.Cu" "In15.Cu")
		(hatch none 0.5)
		(connect_pads
			(clearance 0)
		)
		(min_thickness 0.25)
		(keepout
			(tracks not_allowed)
			(vias allowed)
			(pads allowed)
			(copperpour not_allowed)
			(footprints allowed)
		)
		(placement
			(enabled no)
			(sheetname "")
		)
		(fill yes
			(thermal_gap 0.5)
			(thermal_bridge_width 0.5)
			(island_removal_mode 0)
		)
		(polygon
			(pts
				(arc
					(start 194.938142 -210.935316)
					(mid 194.270122 -210.935316)
					(end 194.938142 -210.935316)
				)
			)
		)
	)
	(zone
		(layers "B.Cu" "In11.Cu" "In13.Cu" "In15.Cu")
		(hatch none 0.5)
		(connect_pads
			(clearance 0)
		)
		(min_thickness 0.25)
		(keepout
			(tracks not_allowed)
			(vias allowed)
			(pads allowed)
			(copperpour not_allowed)
			(footprints allowed)
		)
		(placement
			(enabled no)
			(sheetname "")
		)
		(fill yes
			(thermal_gap 0.5)
			(thermal_bridge_width 0.5)
			(island_removal_mode 0)
		)
		(polygon
			(pts
				(arc
					(start 142.639796 -248.534428)
					(mid 142.009876 -248.534428)
					(end 142.639796 -248.534428)
				)
			)
		)
	)
	(zone
		(layers "B.Cu" "In11.Cu" "In13.Cu" "In15.Cu")
		(hatch none 0.5)
		(connect_pads
			(clearance 0)
		)
		(min_thickness 0.25)
		(keepout
			(tracks not_allowed)
			(vias allowed)
			(pads allowed)
			(copperpour not_allowed)
			(footprints allowed)
		)
		(placement
			(enabled no)
			(sheetname "")
		)
		(fill yes
			(thermal_gap 0.5)
			(thermal_bridge_width 0.5)
			(island_removal_mode 0)
		)
		(polygon
			(pts
				(arc
					(start 51.858164 -369.03533)
					(mid 51.190144 -369.03533)
					(end 51.858164 -369.03533)
				)
			)
		)
	)
	(zone
		(layers "B.Cu" "In11.Cu" "In13.Cu" "In15.Cu")
		(hatch none 0.5)
		(connect_pads
			(clearance 0)
		)
		(min_thickness 0.25)
		(keepout
			(tracks not_allowed)
			(vias allowed)
			(pads allowed)
			(copperpour not_allowed)
			(footprints allowed)
		)
		(placement
			(enabled no)
			(sheetname "")
		)
		(fill yes
			(thermal_gap 0.5)
			(thermal_bridge_width 0.5)
			(island_removal_mode 0)
		)
		(polygon
			(pts
				(arc
					(start 442.87821 -297.635168)
					(mid 442.21019 -297.635168)
					(end 442.87821 -297.635168)
				)
			)
		)
	)
	(zone
		(layers "B.Cu" "In11.Cu" "In13.Cu" "In15.Cu")
		(hatch none 0.5)
		(connect_pads
			(clearance 0)
		)
		(min_thickness 0.25)
		(keepout
			(tracks not_allowed)
			(vias allowed)
			(pads allowed)
			(copperpour not_allowed)
			(footprints allowed)
		)
		(placement
			(enabled no)
			(sheetname "")
		)
		(fill yes
			(thermal_gap 0.5)
			(thermal_bridge_width 0.5)
			(island_removal_mode 0)
		)
		(polygon
			(pts
				(arc
					(start 340.633812 -397.849344)
					(mid 340.003892 -397.849344)
					(end 340.633812 -397.849344)
				)
			)
		)
	)
	(zone
		(layers "B.Cu" "In11.Cu" "In13.Cu" "In15.Cu")
		(hatch none 0.5)
		(connect_pads
			(clearance 0)
		)
		(min_thickness 0.25)
		(keepout
			(tracks not_allowed)
			(vias allowed)
			(pads allowed)
			(copperpour not_allowed)
			(footprints allowed)
		)
		(placement
			(enabled no)
			(sheetname "")
		)
		(fill yes
			(thermal_gap 0.5)
			(thermal_bridge_width 0.5)
			(island_removal_mode 0)
		)
		(polygon
			(pts
				(arc
					(start 142.639796 -242.05438)
					(mid 142.009876 -242.05438)
					(end 142.639796 -242.05438)
				)
			)
		)
	)
	(zone
		(layers "B.Cu" "In11.Cu" "In13.Cu" "In15.Cu")
		(hatch none 0.5)
		(connect_pads
			(clearance 0)
		)
		(min_thickness 0.25)
		(keepout
			(tracks not_allowed)
			(vias allowed)
			(pads allowed)
			(copperpour not_allowed)
			(footprints allowed)
		)
		(placement
			(enabled no)
			(sheetname "")
		)
		(fill yes
			(thermal_gap 0.5)
			(thermal_bridge_width 0.5)
			(island_removal_mode 0)
		)
		(polygon
			(pts
				(arc
					(start 82.785966 -270.846296)
					(mid 82.156046 -270.846296)
					(end 82.785966 -270.846296)
				)
			)
		)
	)
	(zone
		(layers "B.Cu" "In11.Cu" "In13.Cu" "In15.Cu")
		(hatch none 0.5)
		(connect_pads
			(clearance 0)
		)
		(min_thickness 0.25)
		(keepout
			(tracks not_allowed)
			(vias allowed)
			(pads allowed)
			(copperpour not_allowed)
			(footprints allowed)
		)
		(placement
			(enabled no)
			(sheetname "")
		)
		(fill yes
			(thermal_gap 0.5)
			(thermal_bridge_width 0.5)
			(island_removal_mode 0)
		)
		(polygon
			(pts
				(arc
					(start 71.611744 -380.360428)
					(mid 70.943724 -380.360428)
					(end 71.611744 -380.360428)
				)
			)
		)
	)
	(zone
		(layers "B.Cu" "In11.Cu" "In13.Cu" "In15.Cu")
		(hatch none 0.5)
		(connect_pads
			(clearance 0)
		)
		(min_thickness 0.25)
		(keepout
			(tracks not_allowed)
			(vias allowed)
			(pads allowed)
			(copperpour not_allowed)
			(footprints allowed)
		)
		(placement
			(enabled no)
			(sheetname "")
		)
		(fill yes
			(thermal_gap 0.5)
			(thermal_bridge_width 0.5)
			(island_removal_mode 0)
		)
		(polygon
			(pts
				(arc
					(start 98.295968 -284.616398)
					(mid 97.666048 -284.616398)
					(end 98.295968 -284.616398)
				)
			)
		)
	)
	(zone
		(layers "B.Cu" "In11.Cu" "In13.Cu" "In15.Cu")
		(hatch none 0.5)
		(connect_pads
			(clearance 0)
		)
		(min_thickness 0.25)
		(keepout
			(tracks not_allowed)
			(vias allowed)
			(pads allowed)
			(copperpour not_allowed)
			(footprints allowed)
		)
		(placement
			(enabled no)
			(sheetname "")
		)
		(fill yes
			(thermal_gap 0.5)
			(thermal_bridge_width 0.5)
			(island_removal_mode 0)
		)
		(polygon
			(pts
				(arc
					(start 390.879838 -269.22603)
					(mid 390.249918 -269.22603)
					(end 390.879838 -269.22603)
				)
			)
		)
	)
	(zone
		(layers "B.Cu" "In11.Cu" "In13.Cu" "In15.Cu")
		(hatch none 0.5)
		(connect_pads
			(clearance 0)
		)
		(min_thickness 0.25)
		(keepout
			(tracks not_allowed)
			(vias allowed)
			(pads allowed)
			(copperpour not_allowed)
			(footprints allowed)
		)
		(placement
			(enabled no)
			(sheetname "")
		)
		(fill yes
			(thermal_gap 0.5)
			(thermal_bridge_width 0.5)
			(island_removal_mode 0)
		)
		(polygon
			(pts
				(arc
					(start 446.978278 -238.985044)
					(mid 446.310258 -238.985044)
					(end 446.978278 -238.985044)
				)
			)
		)
	)
	(zone
		(layers "B.Cu" "In11.Cu" "In13.Cu" "In15.Cu")
		(hatch none 0.5)
		(connect_pads
			(clearance 0)
		)
		(min_thickness 0.25)
		(keepout
			(tracks not_allowed)
			(vias allowed)
			(pads allowed)
			(copperpour not_allowed)
			(footprints allowed)
		)
		(placement
			(enabled no)
			(sheetname "")
		)
		(fill yes
			(thermal_gap 0.5)
			(thermal_bridge_width 0.5)
			(island_removal_mode 0)
		)
		(polygon
			(pts
				(arc
					(start 365.969804 -282.996132)
					(mid 365.339884 -282.996132)
					(end 365.969804 -282.996132)
				)
			)
		)
	)
	(zone
		(layers "B.Cu" "In11.Cu" "In13.Cu" "In15.Cu")
		(hatch none 0.5)
		(connect_pads
			(clearance 0)
		)
		(min_thickness 0.25)
		(keepout
			(tracks not_allowed)
			(vias allowed)
			(pads allowed)
			(copperpour not_allowed)
			(footprints allowed)
		)
		(placement
			(enabled no)
			(sheetname "")
		)
		(fill yes
			(thermal_gap 0.5)
			(thermal_bridge_width 0.5)
			(island_removal_mode 0)
		)
		(polygon
			(pts
				(arc
					(start 409.137104 -427.089824)
					(mid 408.362912 -427.089824)
					(end 409.137104 -427.089824)
				)
			)
		)
	)
	(zone
		(layers "B.Cu" "In11.Cu" "In13.Cu" "In15.Cu")
		(hatch none 0.5)
		(connect_pads
			(clearance 0)
		)
		(min_thickness 0.25)
		(keepout
			(tracks not_allowed)
			(vias allowed)
			(pads allowed)
			(copperpour not_allowed)
			(footprints allowed)
		)
		(placement
			(enabled no)
			(sheetname "")
		)
		(fill yes
			(thermal_gap 0.5)
			(thermal_bridge_width 0.5)
			(island_removal_mode 0)
		)
		(polygon
			(pts
				(arc
					(start 330.726034 -277.32609)
					(mid 330.096114 -277.32609)
					(end 330.726034 -277.32609)
				)
			)
		)
	)
	(zone
		(layers "B.Cu" "In11.Cu" "In13.Cu" "In15.Cu")
		(hatch none 0.5)
		(connect_pads
			(clearance 0)
		)
		(min_thickness 0.25)
		(keepout
			(tracks not_allowed)
			(vias allowed)
			(pads allowed)
			(copperpour not_allowed)
			(footprints allowed)
		)
		(placement
			(enabled no)
			(sheetname "")
		)
		(fill yes
			(thermal_gap 0.5)
			(thermal_bridge_width 0.5)
			(island_removal_mode 0)
		)
		(polygon
			(pts
				(arc
					(start 141.699742 -232.334308)
					(mid 141.069822 -232.334308)
					(end 141.699742 -232.334308)
				)
			)
		)
	)
	(zone
		(layers "B.Cu" "In11.Cu" "In13.Cu" "In15.Cu")
		(hatch none 0.5)
		(connect_pads
			(clearance 0)
		)
		(min_thickness 0.25)
		(keepout
			(tracks not_allowed)
			(vias allowed)
			(pads allowed)
			(copperpour not_allowed)
			(footprints allowed)
		)
		(placement
			(enabled no)
			(sheetname "")
		)
		(fill yes
			(thermal_gap 0.5)
			(thermal_bridge_width 0.5)
			(island_removal_mode 0)
		)
		(polygon
			(pts
				(arc
					(start 25.486106 -295.9354)
					(mid 24.818086 -295.9354)
					(end 25.486106 -295.9354)
				)
			)
		)
	)
	(zone
		(layers "B.Cu" "In11.Cu" "In13.Cu" "In15.Cu")
		(hatch none 0.5)
		(connect_pads
			(clearance 0)
		)
		(min_thickness 0.25)
		(keepout
			(tracks not_allowed)
			(vias allowed)
			(pads allowed)
			(copperpour not_allowed)
			(footprints allowed)
		)
		(placement
			(enabled no)
			(sheetname "")
		)
		(fill yes
			(thermal_gap 0.5)
			(thermal_bridge_width 0.5)
			(island_removal_mode 0)
		)
		(polygon
			(pts
				(arc
					(start 156.134054 -385.31038)
					(mid 155.504134 -385.31038)
					(end 156.134054 -385.31038)
				)
			)
		)
	)
	(zone
		(layers "B.Cu" "In11.Cu" "In13.Cu" "In15.Cu")
		(hatch none 0.5)
		(connect_pads
			(clearance 0)
		)
		(min_thickness 0.25)
		(keepout
			(tracks not_allowed)
			(vias allowed)
			(pads allowed)
			(copperpour not_allowed)
			(footprints allowed)
		)
		(placement
			(enabled no)
			(sheetname "")
		)
		(fill yes
			(thermal_gap 0.5)
			(thermal_bridge_width 0.5)
			(island_removal_mode 0)
		)
		(polygon
			(pts
				(arc
					(start 194.938142 -282.335224)
					(mid 194.270122 -282.335224)
					(end 194.938142 -282.335224)
				)
			)
		)
	)
	(zone
		(layers "B.Cu" "In11.Cu" "In13.Cu" "In15.Cu")
		(hatch none 0.5)
		(connect_pads
			(clearance 0)
		)
		(min_thickness 0.25)
		(keepout
			(tracks not_allowed)
			(vias allowed)
			(pads allowed)
			(copperpour not_allowed)
			(footprints allowed)
		)
		(placement
			(enabled no)
			(sheetname "")
		)
		(fill yes
			(thermal_gap 0.5)
			(thermal_bridge_width 0.5)
			(island_removal_mode 0)
		)
		(polygon
			(pts
				(arc
					(start 29.586174 -201.585322)
					(mid 28.918154 -201.585322)
					(end 29.586174 -201.585322)
				)
			)
		)
	)
	(zone
		(layers "B.Cu" "In11.Cu" "In13.Cu" "In15.Cu")
		(hatch none 0.5)
		(connect_pads
			(clearance 0)
		)
		(min_thickness 0.25)
		(keepout
			(tracks not_allowed)
			(vias allowed)
			(pads allowed)
			(copperpour not_allowed)
			(footprints allowed)
		)
		(placement
			(enabled no)
			(sheetname "")
		)
		(fill yes
			(thermal_gap 0.5)
			(thermal_bridge_width 0.5)
			(island_removal_mode 0)
		)
		(polygon
			(pts
				(arc
					(start 273.426174 -272.984976)
					(mid 272.758154 -272.984976)
					(end 273.426174 -272.984976)
				)
			)
		)
	)
	(zone
		(layers "B.Cu" "In11.Cu" "In13.Cu" "In15.Cu")
		(hatch none 0.5)
		(connect_pads
			(clearance 0)
		)
		(min_thickness 0.25)
		(keepout
			(tracks not_allowed)
			(vias allowed)
			(pads allowed)
			(copperpour not_allowed)
			(footprints allowed)
		)
		(placement
			(enabled no)
			(sheetname "")
		)
		(fill yes
			(thermal_gap 0.5)
			(thermal_bridge_width 0.5)
			(island_removal_mode 0)
		)
		(polygon
			(pts
				(arc
					(start 155.137104 -426.089826)
					(mid 154.362912 -426.089826)
					(end 155.137104 -426.089826)
				)
			)
		)
	)
	(zone
		(layers "B.Cu" "In11.Cu" "In13.Cu" "In15.Cu")
		(hatch none 0.5)
		(connect_pads
			(clearance 0)
		)
		(min_thickness 0.25)
		(keepout
			(tracks not_allowed)
			(vias allowed)
			(pads allowed)
			(copperpour not_allowed)
			(footprints allowed)
		)
		(placement
			(enabled no)
			(sheetname "")
		)
		(fill yes
			(thermal_gap 0.5)
			(thermal_bridge_width 0.5)
			(island_removal_mode 0)
		)
		(polygon
			(pts
				(arc
					(start 330.726034 -291.905944)
					(mid 330.096114 -291.905944)
					(end 330.726034 -291.905944)
				)
			)
		)
	)
	(zone
		(layers "B.Cu" "In11.Cu" "In13.Cu" "In15.Cu")
		(hatch none 0.5)
		(connect_pads
			(clearance 0)
		)
		(min_thickness 0.25)
		(keepout
			(tracks not_allowed)
			(vias allowed)
			(pads allowed)
			(copperpour not_allowed)
			(footprints allowed)
		)
		(placement
			(enabled no)
			(sheetname "")
		)
		(fill yes
			(thermal_gap 0.5)
			(thermal_bridge_width 0.5)
			(island_removal_mode 0)
		)
		(polygon
			(pts
				(arc
					(start 25.486106 -288.285428)
					(mid 24.818086 -288.285428)
					(end 25.486106 -288.285428)
				)
			)
		)
	)
	(zone
		(layers "B.Cu" "In11.Cu" "In13.Cu" "In15.Cu")
		(hatch none 0.5)
		(connect_pads
			(clearance 0)
		)
		(min_thickness 0.25)
		(keepout
			(tracks not_allowed)
			(vias allowed)
			(pads allowed)
			(copperpour not_allowed)
			(footprints allowed)
		)
		(placement
			(enabled no)
			(sheetname "")
		)
		(fill yes
			(thermal_gap 0.5)
			(thermal_bridge_width 0.5)
			(island_removal_mode 0)
		)
		(polygon
			(pts
				(arc
					(start 390.579864 -238.814102)
					(mid 389.949944 -238.814102)
					(end 390.579864 -238.814102)
				)
			)
		)
	)
	(zone
		(layers "B.Cu" "In11.Cu" "In13.Cu" "In15.Cu")
		(hatch none 0.5)
		(connect_pads
			(clearance 0)
		)
		(min_thickness 0.25)
		(keepout
			(tracks not_allowed)
			(vias allowed)
			(pads allowed)
			(copperpour not_allowed)
			(footprints allowed)
		)
		(placement
			(enabled no)
			(sheetname "")
		)
		(fill yes
			(thermal_gap 0.5)
			(thermal_bridge_width 0.5)
			(island_removal_mode 0)
		)
		(polygon
			(pts
				(arc
					(start 273.426174 -274.684998)
					(mid 272.758154 -274.684998)
					(end 273.426174 -274.684998)
				)
			)
		)
	)
	(zone
		(layers "B.Cu" "In11.Cu" "In13.Cu" "In15.Cu")
		(hatch none 0.5)
		(connect_pads
			(clearance 0)
		)
		(min_thickness 0.25)
		(keepout
			(tracks not_allowed)
			(vias allowed)
			(pads allowed)
			(copperpour not_allowed)
			(footprints allowed)
		)
		(placement
			(enabled no)
			(sheetname "")
		)
		(fill yes
			(thermal_gap 0.5)
			(thermal_bridge_width 0.5)
			(island_removal_mode 0)
		)
		(polygon
			(pts
				(arc
					(start 389.63981 -237.19409)
					(mid 389.00989 -237.19409)
					(end 389.63981 -237.19409)
				)
			)
		)
	)
	(zone
		(layers "B.Cu" "In11.Cu" "In13.Cu" "In15.Cu")
		(hatch none 0.5)
		(connect_pads
			(clearance 0)
		)
		(min_thickness 0.25)
		(keepout
			(tracks not_allowed)
			(vias allowed)
			(pads allowed)
			(copperpour not_allowed)
			(footprints allowed)
		)
		(placement
			(enabled no)
			(sheetname "")
		)
		(fill yes
			(thermal_gap 0.5)
			(thermal_bridge_width 0.5)
			(island_removal_mode 0)
		)
		(polygon
			(pts
				(arc
					(start 25.486106 -209.235294)
					(mid 24.818086 -209.235294)
					(end 25.486106 -209.235294)
				)
			)
		)
	)
	(zone
		(layers "B.Cu" "In11.Cu" "In13.Cu" "In15.Cu")
		(hatch none 0.5)
		(connect_pads
			(clearance 0)
		)
		(min_thickness 0.25)
		(keepout
			(tracks not_allowed)
			(vias allowed)
			(pads allowed)
			(copperpour not_allowed)
			(footprints allowed)
		)
		(placement
			(enabled no)
			(sheetname "")
		)
		(fill yes
			(thermal_gap 0.5)
			(thermal_bridge_width 0.5)
			(island_removal_mode 0)
		)
		(polygon
			(pts
				(arc
					(start 81.845912 -277.326344)
					(mid 81.215992 -277.326344)
					(end 81.845912 -277.326344)
				)
			)
		)
	)
	(zone
		(layers "B.Cu" "In11.Cu" "In13.Cu" "In15.Cu")
		(hatch none 0.5)
		(connect_pads
			(clearance 0)
		)
		(min_thickness 0.25)
		(keepout
			(tracks not_allowed)
			(vias allowed)
			(pads allowed)
			(copperpour not_allowed)
			(footprints allowed)
		)
		(placement
			(enabled no)
			(sheetname "")
		)
		(fill yes
			(thermal_gap 0.5)
			(thermal_bridge_width 0.5)
			(island_removal_mode 0)
		)
		(polygon
			(pts
				(arc
					(start 106.755946 -286.23641)
					(mid 106.126026 -286.23641)
					(end 106.755946 -286.23641)
				)
			)
		)
	)
	(zone
		(layers "B.Cu" "In11.Cu" "In13.Cu" "In15.Cu")
		(hatch none 0.5)
		(connect_pads
			(clearance 0)
		)
		(min_thickness 0.25)
		(keepout
			(tracks not_allowed)
			(vias allowed)
			(pads allowed)
			(copperpour not_allowed)
			(footprints allowed)
		)
		(placement
			(enabled no)
			(sheetname "")
		)
		(fill yes
			(thermal_gap 0.5)
			(thermal_bridge_width 0.5)
			(island_removal_mode 0)
		)
		(polygon
			(pts
				(arc
					(start 330.89596 -247.724168)
					(mid 330.26604 -247.724168)
					(end 330.89596 -247.724168)
				)
			)
		)
	)
	(zone
		(layers "B.Cu" "In11.Cu" "In13.Cu" "In15.Cu")
		(hatch none 0.5)
		(connect_pads
			(clearance 0)
		)
		(min_thickness 0.25)
		(keepout
			(tracks not_allowed)
			(vias allowed)
			(pads allowed)
			(copperpour not_allowed)
			(footprints allowed)
		)
		(placement
			(enabled no)
			(sheetname "")
		)
		(fill yes
			(thermal_gap 0.5)
			(thermal_bridge_width 0.5)
			(island_removal_mode 0)
		)
		(polygon
			(pts
				(arc
					(start 329.78598 -283.806138)
					(mid 329.15606 -283.806138)
					(end 329.78598 -283.806138)
				)
			)
		)
	)
	(zone
		(layers "B.Cu" "In11.Cu" "In13.Cu" "In15.Cu")
		(hatch none 0.5)
		(connect_pads
			(clearance 0)
		)
		(min_thickness 0.25)
		(keepout
			(tracks not_allowed)
			(vias allowed)
			(pads allowed)
			(copperpour not_allowed)
			(footprints allowed)
		)
		(placement
			(enabled no)
			(sheetname "")
		)
		(fill yes
			(thermal_gap 0.5)
			(thermal_bridge_width 0.5)
			(island_removal_mode 0)
		)
		(polygon
			(pts
				(arc
					(start 94.821756 -209.023458)
					(mid 94.153736 -209.023458)
					(end 94.821756 -209.023458)
				)
			)
		)
	)
	(zone
		(layers "B.Cu" "In11.Cu" "In13.Cu" "In15.Cu")
		(hatch none 0.5)
		(connect_pads
			(clearance 0)
		)
		(min_thickness 0.25)
		(keepout
			(tracks not_allowed)
			(vias allowed)
			(pads allowed)
			(copperpour not_allowed)
			(footprints allowed)
		)
		(placement
			(enabled no)
			(sheetname "")
		)
		(fill yes
			(thermal_gap 0.5)
			(thermal_bridge_width 0.5)
			(island_removal_mode 0)
		)
		(polygon
			(pts
				(arc
					(start 320.634106 -379.88113)
					(mid 319.966086 -379.88113)
					(end 320.634106 -379.88113)
				)
			)
		)
	)
	(zone
		(layers "B.Cu" "In11.Cu" "In13.Cu" "In15.Cu")
		(hatch none 0.5)
		(connect_pads
			(clearance 0)
		)
		(min_thickness 0.25)
		(keepout
			(tracks not_allowed)
			(vias allowed)
			(pads allowed)
			(copperpour not_allowed)
			(footprints allowed)
		)
		(placement
			(enabled no)
			(sheetname "")
		)
		(fill yes
			(thermal_gap 0.5)
			(thermal_bridge_width 0.5)
			(island_removal_mode 0)
		)
		(polygon
			(pts
				(arc
					(start 330.89596 -238.004096)
					(mid 330.26604 -238.004096)
					(end 330.89596 -238.004096)
				)
			)
		)
	)
	(zone
		(layers "B.Cu" "In11.Cu" "In13.Cu" "In15.Cu")
		(hatch none 0.5)
		(connect_pads
			(clearance 0)
		)
		(min_thickness 0.25)
		(keepout
			(tracks not_allowed)
			(vias allowed)
			(pads allowed)
			(copperpour not_allowed)
			(footprints allowed)
		)
		(placement
			(enabled no)
			(sheetname "")
		)
		(fill yes
			(thermal_gap 0.5)
			(thermal_bridge_width 0.5)
			(island_removal_mode 0)
		)
		(polygon
			(pts
				(arc
					(start 277.526242 -234.735116)
					(mid 276.858222 -234.735116)
					(end 277.526242 -234.735116)
				)
			)
		)
	)
	(zone
		(layers "B.Cu" "In11.Cu" "In13.Cu" "In15.Cu")
		(hatch none 0.5)
		(connect_pads
			(clearance 0)
		)
		(min_thickness 0.25)
		(keepout
			(tracks not_allowed)
			(vias allowed)
			(pads allowed)
			(copperpour not_allowed)
			(footprints allowed)
		)
		(placement
			(enabled no)
			(sheetname "")
		)
		(fill yes
			(thermal_gap 0.5)
			(thermal_bridge_width 0.5)
			(island_removal_mode 0)
		)
		(polygon
			(pts
				(arc
					(start 118.029736 -282.996386)
					(mid 117.399816 -282.996386)
					(end 118.029736 -282.996386)
				)
			)
		)
	)
	(zone
		(layers "B.Cu" "In11.Cu" "In13.Cu" "In15.Cu")
		(hatch none 0.5)
		(connect_pads
			(clearance 0)
		)
		(min_thickness 0.25)
		(keepout
			(tracks not_allowed)
			(vias allowed)
			(pads allowed)
			(copperpour not_allowed)
			(footprints allowed)
		)
		(placement
			(enabled no)
			(sheetname "")
		)
		(fill yes
			(thermal_gap 0.5)
			(thermal_bridge_width 0.5)
			(island_removal_mode 0)
		)
		(polygon
			(pts
				(arc
					(start 273.426174 -216.885012)
					(mid 272.758154 -216.885012)
					(end 273.426174 -216.885012)
				)
			)
		)
	)
	(zone
		(layers "B.Cu" "In11.Cu" "In13.Cu" "In15.Cu")
		(hatch none 0.5)
		(connect_pads
			(clearance 0)
		)
		(min_thickness 0.25)
		(keepout
			(tracks not_allowed)
			(vias allowed)
			(pads allowed)
			(copperpour not_allowed)
			(footprints allowed)
		)
		(placement
			(enabled no)
			(sheetname "")
		)
		(fill yes
			(thermal_gap 0.5)
			(thermal_bridge_width 0.5)
			(island_removal_mode 0)
		)
		(polygon
			(pts
				(arc
					(start 128.406144 -388.774432)
					(mid 127.776224 -388.774432)
					(end 128.406144 -388.774432)
				)
			)
		)
	)
	(zone
		(layers "B.Cu" "In11.Cu" "In13.Cu" "In15.Cu")
		(hatch none 0.5)
		(connect_pads
			(clearance 0)
		)
		(min_thickness 0.25)
		(keepout
			(tracks not_allowed)
			(vias allowed)
			(pads allowed)
			(copperpour not_allowed)
			(footprints allowed)
		)
		(placement
			(enabled no)
			(sheetname "")
		)
		(fill yes
			(thermal_gap 0.5)
			(thermal_bridge_width 0.5)
			(island_removal_mode 0)
		)
		(polygon
			(pts
				(arc
					(start 142.93977 -274.08632)
					(mid 142.30985 -274.08632)
					(end 142.93977 -274.08632)
				)
			)
		)
	)
	(zone
		(layers "B.Cu" "In11.Cu" "In13.Cu" "In15.Cu")
		(hatch none 0.5)
		(connect_pads
			(clearance 0)
		)
		(min_thickness 0.25)
		(keepout
			(tracks not_allowed)
			(vias allowed)
			(pads allowed)
			(copperpour not_allowed)
			(footprints allowed)
		)
		(placement
			(enabled no)
			(sheetname "")
		)
		(fill yes
			(thermal_gap 0.5)
			(thermal_bridge_width 0.5)
			(island_removal_mode 0)
		)
		(polygon
			(pts
				(arc
					(start 81.076038 -231.524302)
					(mid 80.446118 -231.524302)
					(end 81.076038 -231.524302)
				)
			)
		)
	)
	(zone
		(layers "B.Cu" "In11.Cu" "In13.Cu" "In15.Cu")
		(hatch none 0.5)
		(connect_pads
			(clearance 0)
		)
		(min_thickness 0.25)
		(keepout
			(tracks not_allowed)
			(vias allowed)
			(pads allowed)
			(copperpour not_allowed)
			(footprints allowed)
		)
		(placement
			(enabled no)
			(sheetname "")
		)
		(fill yes
			(thermal_gap 0.5)
			(thermal_bridge_width 0.5)
			(island_removal_mode 0)
		)
		(polygon
			(pts
				(arc
					(start 29.586174 -221.985332)
					(mid 28.918154 -221.985332)
					(end 29.586174 -221.985332)
				)
			)
		)
	)
	(zone
		(layers "B.Cu" "In11.Cu" "In13.Cu" "In15.Cu")
		(hatch none 0.5)
		(connect_pads
			(clearance 0)
		)
		(min_thickness 0.25)
		(keepout
			(tracks not_allowed)
			(vias allowed)
			(pads allowed)
			(copperpour not_allowed)
			(footprints allowed)
		)
		(placement
			(enabled no)
			(sheetname "")
		)
		(fill yes
			(thermal_gap 0.5)
			(thermal_bridge_width 0.5)
			(island_removal_mode 0)
		)
		(polygon
			(pts
				(arc
					(start 330.42606 -242.054126)
					(mid 329.79614 -242.054126)
					(end 330.42606 -242.054126)
				)
			)
		)
	)
	(zone
		(layers "B.Cu" "In11.Cu" "In13.Cu" "In15.Cu")
		(hatch none 0.5)
		(connect_pads
			(clearance 0)
		)
		(min_thickness 0.25)
		(keepout
			(tracks not_allowed)
			(vias allowed)
			(pads allowed)
			(copperpour not_allowed)
			(footprints allowed)
		)
		(placement
			(enabled no)
			(sheetname "")
		)
		(fill yes
			(thermal_gap 0.5)
			(thermal_bridge_width 0.5)
			(island_removal_mode 0)
		)
		(polygon
			(pts
				(arc
					(start 446.978278 -307.835046)
					(mid 446.310258 -307.835046)
					(end 446.978278 -307.835046)
				)
			)
		)
	)
	(zone
		(layers "B.Cu" "In11.Cu" "In13.Cu" "In15.Cu")
		(hatch none 0.5)
		(connect_pads
			(clearance 0)
		)
		(min_thickness 0.25)
		(keepout
			(tracks not_allowed)
			(vias allowed)
			(pads allowed)
			(copperpour not_allowed)
			(footprints allowed)
		)
		(placement
			(enabled no)
			(sheetname "")
		)
		(fill yes
			(thermal_gap 0.5)
			(thermal_bridge_width 0.5)
			(island_removal_mode 0)
		)
		(polygon
			(pts
				(arc
					(start 413.137096 -427.089824)
					(mid 412.362904 -427.089824)
					(end 413.137096 -427.089824)
				)
			)
		)
	)
	(zone
		(layers "B.Cu" "In11.Cu" "In13.Cu" "In15.Cu")
		(hatch none 0.5)
		(connect_pads
			(clearance 0)
		)
		(min_thickness 0.25)
		(keepout
			(tracks not_allowed)
			(vias allowed)
			(pads allowed)
			(copperpour not_allowed)
			(footprints allowed)
		)
		(placement
			(enabled no)
			(sheetname "")
		)
		(fill yes
			(thermal_gap 0.5)
			(thermal_bridge_width 0.5)
			(island_removal_mode 0)
		)
		(polygon
			(pts
				(arc
					(start 142.639796 -240.434368)
					(mid 142.009876 -240.434368)
					(end 142.639796 -240.434368)
				)
			)
		)
	)
	(zone
		(layers "B.Cu" "In11.Cu" "In13.Cu" "In15.Cu")
		(hatch none 0.5)
		(connect_pads
			(clearance 0)
		)
		(min_thickness 0.25)
		(keepout
			(tracks not_allowed)
			(vias allowed)
			(pads allowed)
			(copperpour not_allowed)
			(footprints allowed)
		)
		(placement
			(enabled no)
			(sheetname "")
		)
		(fill yes
			(thermal_gap 0.5)
			(thermal_bridge_width 0.5)
			(island_removal_mode 0)
		)
		(polygon
			(pts
				(arc
					(start 115.206272 -388.774432)
					(mid 114.576352 -388.774432)
					(end 115.206272 -388.774432)
				)
			)
		)
	)
	(zone
		(layers "B.Cu" "In11.Cu" "In13.Cu" "In15.Cu")
		(hatch none 0.5)
		(connect_pads
			(clearance 0)
		)
		(min_thickness 0.25)
		(keepout
			(tracks not_allowed)
			(vias allowed)
			(pads allowed)
			(copperpour not_allowed)
			(footprints allowed)
		)
		(placement
			(enabled no)
			(sheetname "")
		)
		(fill yes
			(thermal_gap 0.5)
			(thermal_bridge_width 0.5)
			(island_removal_mode 0)
		)
		(polygon
			(pts
				(arc
					(start 199.03821 -245.785386)
					(mid 198.37019 -245.785386)
					(end 199.03821 -245.785386)
				)
			)
		)
	)
	(zone
		(layers "B.Cu" "In11.Cu" "In13.Cu" "In15.Cu")
		(hatch none 0.5)
		(connect_pads
			(clearance 0)
		)
		(min_thickness 0.25)
		(keepout
			(tracks not_allowed)
			(vias allowed)
			(pads allowed)
			(copperpour not_allowed)
			(footprints allowed)
		)
		(placement
			(enabled no)
			(sheetname "")
		)
		(fill yes
			(thermal_gap 0.5)
			(thermal_bridge_width 0.5)
			(island_removal_mode 0)
		)
		(polygon
			(pts
				(arc
					(start 344.036904 -426.089826)
					(mid 343.262712 -426.089826)
					(end 344.036904 -426.089826)
				)
			)
		)
	)
	(zone
		(layers "B.Cu" "In11.Cu" "In13.Cu" "In15.Cu")
		(hatch none 0.5)
		(connect_pads
			(clearance 0)
		)
		(min_thickness 0.25)
		(keepout
			(tracks not_allowed)
			(vias allowed)
			(pads allowed)
			(copperpour not_allowed)
			(footprints allowed)
		)
		(placement
			(enabled no)
			(sheetname "")
		)
		(fill yes
			(thermal_gap 0.5)
			(thermal_bridge_width 0.5)
			(island_removal_mode 0)
		)
		(polygon
			(pts
				(arc
					(start 194.938142 -198.185278)
					(mid 194.270122 -198.185278)
					(end 194.938142 -198.185278)
				)
			)
		)
	)
	(zone
		(layers "B.Cu" "In11.Cu" "In13.Cu" "In15.Cu")
		(hatch none 0.5)
		(connect_pads
			(clearance 0)
		)
		(min_thickness 0.25)
		(keepout
			(tracks not_allowed)
			(vias allowed)
			(pads allowed)
			(copperpour not_allowed)
			(footprints allowed)
		)
		(placement
			(enabled no)
			(sheetname "")
		)
		(fill yes
			(thermal_gap 0.5)
			(thermal_bridge_width 0.5)
			(island_removal_mode 0)
		)
		(polygon
			(pts
				(arc
					(start 69.036946 -419.88994)
					(mid 68.262754 -419.88994)
					(end 69.036946 -419.88994)
				)
			)
		)
	)
	(zone
		(layers "B.Cu" "In11.Cu" "In13.Cu" "In15.Cu")
		(hatch none 0.5)
		(connect_pads
			(clearance 0)
		)
		(min_thickness 0.25)
		(keepout
			(tracks not_allowed)
			(vias allowed)
			(pads allowed)
			(copperpour not_allowed)
			(footprints allowed)
		)
		(placement
			(enabled no)
			(sheetname "")
		)
		(fill yes
			(thermal_gap 0.5)
			(thermal_bridge_width 0.5)
			(island_removal_mode 0)
		)
		(polygon
			(pts
				(arc
					(start 147.13712 -426.089826)
					(mid 146.362928 -426.089826)
					(end 147.13712 -426.089826)
				)
			)
		)
	)
	(zone
		(layers "B.Cu" "In11.Cu" "In13.Cu" "In15.Cu")
		(hatch none 0.5)
		(connect_pads
			(clearance 0)
		)
		(min_thickness 0.25)
		(keepout
			(tracks not_allowed)
			(vias allowed)
			(pads allowed)
			(copperpour not_allowed)
			(footprints allowed)
		)
		(placement
			(enabled no)
			(sheetname "")
		)
		(fill yes
			(thermal_gap 0.5)
			(thermal_bridge_width 0.5)
			(island_removal_mode 0)
		)
		(polygon
			(pts
				(arc
					(start 29.586174 -287.43529)
					(mid 28.918154 -287.43529)
					(end 29.586174 -287.43529)
				)
			)
		)
	)
	(zone
		(layers "B.Cu" "In11.Cu" "In13.Cu" "In15.Cu")
		(hatch none 0.5)
		(connect_pads
			(clearance 0)
		)
		(min_thickness 0.25)
		(keepout
			(tracks not_allowed)
			(vias allowed)
			(pads allowed)
			(copperpour not_allowed)
			(footprints allowed)
		)
		(placement
			(enabled no)
			(sheetname "")
		)
		(fill yes
			(thermal_gap 0.5)
			(thermal_bridge_width 0.5)
			(island_removal_mode 0)
		)
		(polygon
			(pts
				(arc
					(start 389.16991 -241.24412)
					(mid 388.53999 -241.24412)
					(end 389.16991 -241.24412)
				)
			)
		)
	)
	(zone
		(layers "B.Cu" "In11.Cu" "In13.Cu" "In15.Cu")
		(hatch none 0.5)
		(connect_pads
			(clearance 0)
		)
		(min_thickness 0.25)
		(keepout
			(tracks not_allowed)
			(vias allowed)
			(pads allowed)
			(copperpour not_allowed)
			(footprints allowed)
		)
		(placement
			(enabled no)
			(sheetname "")
		)
		(fill yes
			(thermal_gap 0.5)
			(thermal_bridge_width 0.5)
			(island_removal_mode 0)
		)
		(polygon
			(pts
				(arc
					(start 389.939784 -265.986006)
					(mid 389.309864 -265.986006)
					(end 389.939784 -265.986006)
				)
			)
		)
	)
	(zone
		(layers "B.Cu" "In11.Cu" "In13.Cu" "In15.Cu")
		(hatch none 0.5)
		(connect_pads
			(clearance 0)
		)
		(min_thickness 0.25)
		(keepout
			(tracks not_allowed)
			(vias allowed)
			(pads allowed)
			(copperpour not_allowed)
			(footprints allowed)
		)
		(placement
			(enabled no)
			(sheetname "")
		)
		(fill yes
			(thermal_gap 0.5)
			(thermal_bridge_width 0.5)
			(island_removal_mode 0)
		)
		(polygon
			(pts
				(arc
					(start 277.526242 -250.884944)
					(mid 276.858222 -250.884944)
					(end 277.526242 -250.884944)
				)
			)
		)
	)
	(zone
		(layers "B.Cu" "In11.Cu" "In13.Cu" "In15.Cu")
		(hatch none 0.5)
		(connect_pads
			(clearance 0)
		)
		(min_thickness 0.25)
		(keepout
			(tracks not_allowed)
			(vias allowed)
			(pads allowed)
			(copperpour not_allowed)
			(footprints allowed)
		)
		(placement
			(enabled no)
			(sheetname "")
		)
		(fill yes
			(thermal_gap 0.5)
			(thermal_bridge_width 0.5)
			(island_removal_mode 0)
		)
		(polygon
			(pts
				(arc
					(start 389.469884 -276.516084)
					(mid 388.839964 -276.516084)
					(end 389.469884 -276.516084)
				)
			)
		)
	)
	(zone
		(layers "B.Cu" "In11.Cu" "In13.Cu" "In15.Cu")
		(hatch none 0.5)
		(connect_pads
			(clearance 0)
		)
		(min_thickness 0.25)
		(keepout
			(tracks not_allowed)
			(vias allowed)
			(pads allowed)
			(copperpour not_allowed)
			(footprints allowed)
		)
		(placement
			(enabled no)
			(sheetname "")
		)
		(fill yes
			(thermal_gap 0.5)
			(thermal_bridge_width 0.5)
			(island_removal_mode 0)
		)
		(polygon
			(pts
				(arc
					(start 390.879838 -262.745982)
					(mid 390.249918 -262.745982)
					(end 390.879838 -262.745982)
				)
			)
		)
	)
	(zone
		(layers "B.Cu" "In11.Cu" "In13.Cu" "In15.Cu")
		(hatch none 0.5)
		(connect_pads
			(clearance 0)
		)
		(min_thickness 0.25)
		(keepout
			(tracks not_allowed)
			(vias allowed)
			(pads allowed)
			(copperpour not_allowed)
			(footprints allowed)
		)
		(placement
			(enabled no)
			(sheetname "")
		)
		(fill yes
			(thermal_gap 0.5)
			(thermal_bridge_width 0.5)
			(island_removal_mode 0)
		)
		(polygon
			(pts
				(arc
					(start 84.887054 -404.46452)
					(mid 84.219034 -404.46452)
					(end 84.887054 -404.46452)
				)
			)
		)
	)
	(zone
		(layers "B.Cu" "In11.Cu" "In13.Cu" "In15.Cu")
		(hatch none 0.5)
		(connect_pads
			(clearance 0)
		)
		(min_thickness 0.25)
		(keepout
			(tracks not_allowed)
			(vias allowed)
			(pads allowed)
			(copperpour not_allowed)
			(footprints allowed)
		)
		(placement
			(enabled no)
			(sheetname "")
		)
		(fill yes
			(thermal_gap 0.5)
			(thermal_bridge_width 0.5)
			(island_removal_mode 0)
		)
		(polygon
			(pts
				(arc
					(start 194.938142 -254.285242)
					(mid 194.270122 -254.285242)
					(end 194.938142 -254.285242)
				)
			)
		)
	)
	(zone
		(layers "B.Cu" "In11.Cu" "In13.Cu" "In15.Cu")
		(hatch none 0.5)
		(connect_pads
			(clearance 0)
		)
		(min_thickness 0.25)
		(keepout
			(tracks not_allowed)
			(vias allowed)
			(pads allowed)
			(copperpour not_allowed)
			(footprints allowed)
		)
		(placement
			(enabled no)
			(sheetname "")
		)
		(fill yes
			(thermal_gap 0.5)
			(thermal_bridge_width 0.5)
			(island_removal_mode 0)
		)
		(polygon
			(pts
				(arc
					(start 391.349738 -281.37612)
					(mid 390.719818 -281.37612)
					(end 391.349738 -281.37612)
				)
			)
		)
	)
	(zone
		(layers "B.Cu" "In11.Cu" "In13.Cu" "In15.Cu")
		(hatch none 0.5)
		(connect_pads
			(clearance 0)
		)
		(min_thickness 0.25)
		(keepout
			(tracks not_allowed)
			(vias allowed)
			(pads allowed)
			(copperpour not_allowed)
			(footprints allowed)
		)
		(placement
			(enabled no)
			(sheetname "")
		)
		(fill yes
			(thermal_gap 0.5)
			(thermal_bridge_width 0.5)
			(island_removal_mode 0)
		)
		(polygon
			(pts
				(arc
					(start 194.938142 -295.085262)
					(mid 194.270122 -295.085262)
					(end 194.938142 -295.085262)
				)
			)
		)
	)
	(zone
		(layers "B.Cu" "In11.Cu" "In13.Cu" "In15.Cu")
		(hatch none 0.5)
		(connect_pads
			(clearance 0)
		)
		(min_thickness 0.25)
		(keepout
			(tracks not_allowed)
			(vias allowed)
			(pads allowed)
			(copperpour not_allowed)
			(footprints allowed)
		)
		(placement
			(enabled no)
			(sheetname "")
		)
		(fill yes
			(thermal_gap 0.5)
			(thermal_bridge_width 0.5)
			(island_removal_mode 0)
		)
		(polygon
			(pts
				(arc
					(start 342.036908 -427.089824)
					(mid 341.262716 -427.089824)
					(end 342.036908 -427.089824)
				)
			)
		)
	)
	(zone
		(layers "B.Cu" "In11.Cu" "In13.Cu" "In15.Cu")
		(hatch none 0.5)
		(connect_pads
			(clearance 0)
		)
		(min_thickness 0.25)
		(keepout
			(tracks not_allowed)
			(vias allowed)
			(pads allowed)
			(copperpour not_allowed)
			(footprints allowed)
		)
		(placement
			(enabled no)
			(sheetname "")
		)
		(fill yes
			(thermal_gap 0.5)
			(thermal_bridge_width 0.5)
			(island_removal_mode 0)
		)
		(polygon
			(pts
				(arc
					(start 329.78598 -269.22603)
					(mid 329.15606 -269.22603)
					(end 329.78598 -269.22603)
				)
			)
		)
	)
	(zone
		(layers "B.Cu" "In11.Cu" "In13.Cu" "In15.Cu")
		(hatch none 0.5)
		(connect_pads
			(clearance 0)
		)
		(min_thickness 0.25)
		(keepout
			(tracks not_allowed)
			(vias allowed)
			(pads allowed)
			(copperpour not_allowed)
			(footprints allowed)
		)
		(placement
			(enabled no)
			(sheetname "")
		)
		(fill yes
			(thermal_gap 0.5)
			(thermal_bridge_width 0.5)
			(island_removal_mode 0)
		)
		(polygon
			(pts
				(arc
					(start 81.545938 -230.71455)
					(mid 80.916018 -230.71455)
					(end 81.545938 -230.71455)
				)
			)
		)
	)
	(zone
		(layers "B.Cu" "In11.Cu" "In13.Cu" "In15.Cu")
		(hatch none 0.5)
		(connect_pads
			(clearance 0)
		)
		(min_thickness 0.25)
		(keepout
			(tracks not_allowed)
			(vias allowed)
			(pads allowed)
			(copperpour not_allowed)
			(footprints allowed)
		)
		(placement
			(enabled no)
			(sheetname "")
		)
		(fill yes
			(thermal_gap 0.5)
			(thermal_bridge_width 0.5)
			(island_removal_mode 0)
		)
		(polygon
			(pts
				(arc
					(start 377.606306 -397.849344)
					(mid 376.976386 -397.849344)
					(end 377.606306 -397.849344)
				)
			)
		)
	)
	(zone
		(layers "B.Cu" "In11.Cu" "In13.Cu" "In15.Cu")
		(hatch none 0.5)
		(connect_pads
			(clearance 0)
		)
		(min_thickness 0.25)
		(keepout
			(tracks not_allowed)
			(vias allowed)
			(pads allowed)
			(copperpour not_allowed)
			(footprints allowed)
		)
		(placement
			(enabled no)
			(sheetname "")
		)
		(fill yes
			(thermal_gap 0.5)
			(thermal_bridge_width 0.5)
			(island_removal_mode 0)
		)
		(polygon
			(pts
				(arc
					(start 25.486106 -199.8853)
					(mid 24.818086 -199.8853)
					(end 25.486106 -199.8853)
				)
			)
		)
	)
	(zone
		(layers "B.Cu" "In11.Cu" "In13.Cu" "In15.Cu")
		(hatch none 0.5)
		(connect_pads
			(clearance 0)
		)
		(min_thickness 0.25)
		(keepout
			(tracks not_allowed)
			(vias allowed)
			(pads allowed)
			(copperpour not_allowed)
			(footprints allowed)
		)
		(placement
			(enabled no)
			(sheetname "")
		)
		(fill yes
			(thermal_gap 0.5)
			(thermal_bridge_width 0.5)
			(island_removal_mode 0)
		)
		(polygon
			(pts
				(arc
					(start 391.049764 -241.24412)
					(mid 390.419844 -241.24412)
					(end 391.049764 -241.24412)
				)
			)
		)
	)
	(zone
		(layers "B.Cu" "In11.Cu" "In13.Cu" "In15.Cu")
		(hatch none 0.5)
		(connect_pads
			(clearance 0)
		)
		(min_thickness 0.25)
		(keepout
			(tracks not_allowed)
			(vias allowed)
			(pads allowed)
			(copperpour not_allowed)
			(footprints allowed)
		)
		(placement
			(enabled no)
			(sheetname "")
		)
		(fill yes
			(thermal_gap 0.5)
			(thermal_bridge_width 0.5)
			(island_removal_mode 0)
		)
		(polygon
			(pts
				(arc
					(start 273.426174 -312.084974)
					(mid 272.758154 -312.084974)
					(end 273.426174 -312.084974)
				)
			)
		)
	)
	(zone
		(layers "B.Cu" "In11.Cu" "In13.Cu" "In15.Cu")
		(hatch none 0.5)
		(connect_pads
			(clearance 0)
		)
		(min_thickness 0.25)
		(keepout
			(tracks not_allowed)
			(vias allowed)
			(pads allowed)
			(copperpour not_allowed)
			(footprints allowed)
		)
		(placement
			(enabled no)
			(sheetname "")
		)
		(fill yes
			(thermal_gap 0.5)
			(thermal_bridge_width 0.5)
			(island_removal_mode 0)
		)
		(polygon
			(pts
				(arc
					(start 68.876164 -369.03533)
					(mid 68.208144 -369.03533)
					(end 68.876164 -369.03533)
				)
			)
		)
	)
	(zone
		(layers "B.Cu" "In11.Cu" "In13.Cu" "In15.Cu")
		(hatch none 0.5)
		(connect_pads
			(clearance 0)
		)
		(min_thickness 0.25)
		(keepout
			(tracks not_allowed)
			(vias allowed)
			(pads allowed)
			(copperpour not_allowed)
			(footprints allowed)
		)
		(placement
			(enabled no)
			(sheetname "")
		)
		(fill yes
			(thermal_gap 0.5)
			(thermal_bridge_width 0.5)
			(island_removal_mode 0)
		)
		(polygon
			(pts
				(arc
					(start 25.486106 -297.635422)
					(mid 24.818086 -297.635422)
					(end 25.486106 -297.635422)
				)
			)
		)
	)
	(zone
		(layers "B.Cu" "In11.Cu" "In13.Cu" "In15.Cu")
		(hatch none 0.5)
		(connect_pads
			(clearance 0)
		)
		(min_thickness 0.25)
		(keepout
			(tracks not_allowed)
			(vias allowed)
			(pads allowed)
			(copperpour not_allowed)
			(footprints allowed)
		)
		(placement
			(enabled no)
			(sheetname "")
		)
		(fill yes
			(thermal_gap 0.5)
			(thermal_bridge_width 0.5)
			(island_removal_mode 0)
		)
		(polygon
			(pts
				(arc
					(start 389.939784 -275.706078)
					(mid 389.309864 -275.706078)
					(end 389.939784 -275.706078)
				)
			)
		)
	)
	(zone
		(layers "B.Cu" "In11.Cu" "In13.Cu" "In15.Cu")
		(hatch none 0.5)
		(connect_pads
			(clearance 0)
		)
		(min_thickness 0.25)
		(keepout
			(tracks not_allowed)
			(vias allowed)
			(pads allowed)
			(copperpour not_allowed)
			(footprints allowed)
		)
		(placement
			(enabled no)
			(sheetname "")
		)
		(fill yes
			(thermal_gap 0.5)
			(thermal_bridge_width 0.5)
			(island_removal_mode 0)
		)
		(polygon
			(pts
				(arc
					(start 142.93977 -282.18638)
					(mid 142.30985 -282.18638)
					(end 142.93977 -282.18638)
				)
			)
		)
	)
	(zone
		(layers "B.Cu" "In11.Cu" "In13.Cu" "In15.Cu")
		(hatch none 0.5)
		(connect_pads
			(clearance 0)
		)
		(min_thickness 0.25)
		(keepout
			(tracks not_allowed)
			(vias allowed)
			(pads allowed)
			(copperpour not_allowed)
			(footprints allowed)
		)
		(placement
			(enabled no)
			(sheetname "")
		)
		(fill yes
			(thermal_gap 0.5)
			(thermal_bridge_width 0.5)
			(island_removal_mode 0)
		)
		(polygon
			(pts
				(arc
					(start 321.036696 -428.28972)
					(mid 320.262504 -428.28972)
					(end 321.036696 -428.28972)
				)
			)
		)
	)
	(zone
		(layers "B.Cu" "In11.Cu" "In13.Cu" "In15.Cu")
		(hatch none 0.5)
		(connect_pads
			(clearance 0)
		)
		(min_thickness 0.25)
		(keepout
			(tracks not_allowed)
			(vias allowed)
			(pads allowed)
			(copperpour not_allowed)
			(footprints allowed)
		)
		(placement
			(enabled no)
			(sheetname "")
		)
		(fill yes
			(thermal_gap 0.5)
			(thermal_bridge_width 0.5)
			(island_removal_mode 0)
		)
		(polygon
			(pts
				(arc
					(start 29.586174 -269.58544)
					(mid 28.918154 -269.58544)
					(end 29.586174 -269.58544)
				)
			)
		)
	)
	(zone
		(layers "B.Cu" "In11.Cu" "In13.Cu" "In15.Cu")
		(hatch none 0.5)
		(connect_pads
			(clearance 0)
		)
		(min_thickness 0.25)
		(keepout
			(tracks not_allowed)
			(vias allowed)
			(pads allowed)
			(copperpour not_allowed)
			(footprints allowed)
		)
		(placement
			(enabled no)
			(sheetname "")
		)
		(fill yes
			(thermal_gap 0.5)
			(thermal_bridge_width 0.5)
			(island_removal_mode 0)
		)
		(polygon
			(pts
				(arc
					(start 29.586174 -295.085262)
					(mid 28.918154 -295.085262)
					(end 29.586174 -295.085262)
				)
			)
		)
	)
	(zone
		(layers "B.Cu" "In11.Cu" "In13.Cu" "In15.Cu")
		(hatch none 0.5)
		(connect_pads
			(clearance 0)
		)
		(min_thickness 0.25)
		(keepout
			(tracks not_allowed)
			(vias allowed)
			(pads allowed)
			(copperpour not_allowed)
			(footprints allowed)
		)
		(placement
			(enabled no)
			(sheetname "")
		)
		(fill yes
			(thermal_gap 0.5)
			(thermal_bridge_width 0.5)
			(island_removal_mode 0)
		)
		(polygon
			(pts
				(arc
					(start 277.526242 -245.785132)
					(mid 276.858222 -245.785132)
					(end 277.526242 -245.785132)
				)
			)
		)
	)
	(zone
		(layers "B.Cu" "In11.Cu" "In13.Cu" "In15.Cu")
		(hatch none 0.5)
		(connect_pads
			(clearance 0)
		)
		(min_thickness 0.25)
		(keepout
			(tracks not_allowed)
			(vias allowed)
			(pads allowed)
			(copperpour not_allowed)
			(footprints allowed)
		)
		(placement
			(enabled no)
			(sheetname "")
		)
		(fill yes
			(thermal_gap 0.5)
			(thermal_bridge_width 0.5)
			(island_removal_mode 0)
		)
		(polygon
			(pts
				(arc
					(start 273.426174 -248.335038)
					(mid 272.758154 -248.335038)
					(end 273.426174 -248.335038)
				)
			)
		)
	)
	(zone
		(layers "B.Cu" "In11.Cu" "In13.Cu" "In15.Cu")
		(hatch none 0.5)
		(connect_pads
			(clearance 0)
		)
		(min_thickness 0.25)
		(keepout
			(tracks not_allowed)
			(vias allowed)
			(pads allowed)
			(copperpour not_allowed)
			(footprints allowed)
		)
		(placement
			(enabled no)
			(sheetname "")
		)
		(fill yes
			(thermal_gap 0.5)
			(thermal_bridge_width 0.5)
			(island_removal_mode 0)
		)
		(polygon
			(pts
				(arc
					(start 373.189754 -242.864132)
					(mid 372.559834 -242.864132)
					(end 373.189754 -242.864132)
				)
			)
		)
	)
	(zone
		(layers "B.Cu" "In11.Cu" "In13.Cu" "In15.Cu")
		(hatch none 0.5)
		(connect_pads
			(clearance 0)
		)
		(min_thickness 0.25)
		(keepout
			(tracks not_allowed)
			(vias allowed)
			(pads allowed)
			(copperpour not_allowed)
			(footprints allowed)
		)
		(placement
			(enabled no)
			(sheetname "")
		)
		(fill yes
			(thermal_gap 0.5)
			(thermal_bridge_width 0.5)
			(island_removal_mode 0)
		)
		(polygon
			(pts
				(arc
					(start 346.0369 -427.089824)
					(mid 345.262708 -427.089824)
					(end 346.0369 -427.089824)
				)
			)
		)
	)
	(zone
		(layers "B.Cu" "In11.Cu" "In13.Cu" "In15.Cu")
		(hatch none 0.5)
		(connect_pads
			(clearance 0)
		)
		(min_thickness 0.25)
		(keepout
			(tracks not_allowed)
			(vias allowed)
			(pads allowed)
			(copperpour not_allowed)
			(footprints allowed)
		)
		(placement
			(enabled no)
			(sheetname "")
		)
		(fill yes
			(thermal_gap 0.5)
			(thermal_bridge_width 0.5)
			(island_removal_mode 0)
		)
		(polygon
			(pts
				(arc
					(start 409.137104 -428.28972)
					(mid 408.362912 -428.28972)
					(end 409.137104 -428.28972)
				)
			)
		)
	)
	(zone
		(layers "B.Cu" "In11.Cu" "In13.Cu" "In15.Cu")
		(hatch none 0.5)
		(connect_pads
			(clearance 0)
		)
		(min_thickness 0.25)
		(keepout
			(tracks not_allowed)
			(vias allowed)
			(pads allowed)
			(copperpour not_allowed)
			(footprints allowed)
		)
		(placement
			(enabled no)
			(sheetname "")
		)
		(fill yes
			(thermal_gap 0.5)
			(thermal_bridge_width 0.5)
			(island_removal_mode 0)
		)
		(polygon
			(pts
				(arc
					(start 354.633784 -397.156432)
					(mid 354.003864 -397.156432)
					(end 354.633784 -397.156432)
				)
			)
		)
	)
	(zone
		(layers "B.Cu" "In11.Cu" "In13.Cu" "In15.Cu")
		(hatch none 0.5)
		(connect_pads
			(clearance 0)
		)
		(min_thickness 0.25)
		(keepout
			(tracks not_allowed)
			(vias allowed)
			(pads allowed)
			(copperpour not_allowed)
			(footprints allowed)
		)
		(placement
			(enabled no)
			(sheetname "")
		)
		(fill yes
			(thermal_gap 0.5)
			(thermal_bridge_width 0.5)
			(island_removal_mode 0)
		)
		(polygon
			(pts
				(arc
					(start 442.87821 -224.534984)
					(mid 442.21019 -224.534984)
					(end 442.87821 -224.534984)
				)
			)
		)
	)
	(zone
		(layers "B.Cu" "In11.Cu" "In13.Cu" "In15.Cu")
		(hatch none 0.5)
		(connect_pads
			(clearance 0)
		)
		(min_thickness 0.25)
		(keepout
			(tracks not_allowed)
			(vias allowed)
			(pads allowed)
			(copperpour not_allowed)
			(footprints allowed)
		)
		(placement
			(enabled no)
			(sheetname "")
		)
		(fill yes
			(thermal_gap 0.5)
			(thermal_bridge_width 0.5)
			(island_removal_mode 0)
		)
		(polygon
			(pts
				(arc
					(start 341.833708 -397.849344)
					(mid 341.203788 -397.849344)
					(end 341.833708 -397.849344)
				)
			)
		)
	)
	(zone
		(layers "B.Cu" "In11.Cu" "In13.Cu" "In15.Cu")
		(hatch none 0.5)
		(connect_pads
			(clearance 0)
		)
		(min_thickness 0.25)
		(keepout
			(tracks not_allowed)
			(vias allowed)
			(pads allowed)
			(copperpour not_allowed)
			(footprints allowed)
		)
		(placement
			(enabled no)
			(sheetname "")
		)
		(fill yes
			(thermal_gap 0.5)
			(thermal_bridge_width 0.5)
			(island_removal_mode 0)
		)
		(polygon
			(pts
				(arc
					(start 273.426174 -207.535018)
					(mid 272.758154 -207.535018)
					(end 273.426174 -207.535018)
				)
			)
		)
	)
	(zone
		(layers "B.Cu" "In11.Cu" "In13.Cu" "In15.Cu")
		(hatch none 0.5)
		(connect_pads
			(clearance 0)
		)
		(min_thickness 0.25)
		(keepout
			(tracks not_allowed)
			(vias allowed)
			(pads allowed)
			(copperpour not_allowed)
			(footprints allowed)
		)
		(placement
			(enabled no)
			(sheetname "")
		)
		(fill yes
			(thermal_gap 0.5)
			(thermal_bridge_width 0.5)
			(island_removal_mode 0)
		)
		(polygon
			(pts
				(arc
					(start 277.526242 -269.585186)
					(mid 276.858222 -269.585186)
					(end 277.526242 -269.585186)
				)
			)
		)
	)
	(zone
		(layers "B.Cu" "In11.Cu" "In13.Cu" "In15.Cu")
		(hatch none 0.5)
		(connect_pads
			(clearance 0)
		)
		(min_thickness 0.25)
		(keepout
			(tracks not_allowed)
			(vias allowed)
			(pads allowed)
			(copperpour not_allowed)
			(footprints allowed)
		)
		(placement
			(enabled no)
			(sheetname "")
		)
		(fill yes
			(thermal_gap 0.5)
			(thermal_bridge_width 0.5)
			(island_removal_mode 0)
		)
		(polygon
			(pts
				(arc
					(start 329.31608 -271.656048)
					(mid 328.68616 -271.656048)
					(end 329.31608 -271.656048)
				)
			)
		)
	)
	(zone
		(layers "B.Cu" "In11.Cu" "In13.Cu" "In15.Cu")
		(hatch none 0.5)
		(connect_pads
			(clearance 0)
		)
		(min_thickness 0.25)
		(keepout
			(tracks not_allowed)
			(vias allowed)
			(pads allowed)
			(copperpour not_allowed)
			(footprints allowed)
		)
		(placement
			(enabled no)
			(sheetname "")
		)
		(fill yes
			(thermal_gap 0.5)
			(thermal_bridge_width 0.5)
			(island_removal_mode 0)
		)
		(polygon
			(pts
				(arc
					(start 102.042214 -29.51861)
					(mid 101.374194 -29.51861)
					(end 102.042214 -29.51861)
				)
			)
		)
	)
	(zone
		(layers "B.Cu" "In11.Cu" "In13.Cu" "In15.Cu")
		(hatch none 0.5)
		(connect_pads
			(clearance 0)
		)
		(min_thickness 0.25)
		(keepout
			(tracks not_allowed)
			(vias allowed)
			(pads allowed)
			(copperpour not_allowed)
			(footprints allowed)
		)
		(placement
			(enabled no)
			(sheetname "")
		)
		(fill yes
			(thermal_gap 0.5)
			(thermal_bridge_width 0.5)
			(island_removal_mode 0)
		)
		(polygon
			(pts
				(arc
					(start 182.375556 -50.949098)
					(mid 181.707536 -50.949098)
					(end 182.375556 -50.949098)
				)
			)
		)
	)
	(zone
		(layers "B.Cu" "In11.Cu" "In13.Cu" "In15.Cu")
		(hatch none 0.5)
		(connect_pads
			(clearance 0)
		)
		(min_thickness 0.25)
		(keepout
			(tracks not_allowed)
			(vias allowed)
			(pads allowed)
			(copperpour not_allowed)
			(footprints allowed)
		)
		(placement
			(enabled no)
			(sheetname "")
		)
		(fill yes
			(thermal_gap 0.5)
			(thermal_bridge_width 0.5)
			(island_removal_mode 0)
		)
		(polygon
			(pts
				(arc
					(start 141.699742 -246.914416)
					(mid 141.069822 -246.914416)
					(end 141.699742 -246.914416)
				)
			)
		)
	)
	(zone
		(layers "B.Cu" "In11.Cu" "In13.Cu" "In15.Cu")
		(hatch none 0.5)
		(connect_pads
			(clearance 0)
		)
		(min_thickness 0.25)
		(keepout
			(tracks not_allowed)
			(vias allowed)
			(pads allowed)
			(copperpour not_allowed)
			(footprints allowed)
		)
		(placement
			(enabled no)
			(sheetname "")
		)
		(fill yes
			(thermal_gap 0.5)
			(thermal_bridge_width 0.5)
			(island_removal_mode 0)
		)
		(polygon
			(pts
				(arc
					(start 390.579864 -232.334054)
					(mid 389.949944 -232.334054)
					(end 390.579864 -232.334054)
				)
			)
		)
	)
	(zone
		(layers "B.Cu" "In11.Cu" "In13.Cu" "In15.Cu")
		(hatch none 0.5)
		(connect_pads
			(clearance 0)
		)
		(min_thickness 0.25)
		(keepout
			(tracks not_allowed)
			(vias allowed)
			(pads allowed)
			(copperpour not_allowed)
			(footprints allowed)
		)
		(placement
			(enabled no)
			(sheetname "")
		)
		(fill yes
			(thermal_gap 0.5)
			(thermal_bridge_width 0.5)
			(island_removal_mode 0)
		)
		(polygon
			(pts
				(arc
					(start 273.426174 -229.63505)
					(mid 272.758154 -229.63505)
					(end 273.426174 -229.63505)
				)
			)
		)
	)
	(zone
		(layers "B.Cu" "In11.Cu" "In13.Cu" "In15.Cu")
		(hatch none 0.5)
		(connect_pads
			(clearance 0)
		)
		(min_thickness 0.25)
		(keepout
			(tracks not_allowed)
			(vias allowed)
			(pads allowed)
			(copperpour not_allowed)
			(footprints allowed)
		)
		(placement
			(enabled no)
			(sheetname "")
		)
		(fill yes
			(thermal_gap 0.5)
			(thermal_bridge_width 0.5)
			(island_removal_mode 0)
		)
		(polygon
			(pts
				(arc
					(start 329.31608 -289.475926)
					(mid 328.68616 -289.475926)
					(end 329.31608 -289.475926)
				)
			)
		)
	)
	(zone
		(layers "B.Cu" "In11.Cu" "In13.Cu" "In15.Cu")
		(hatch none 0.5)
		(connect_pads
			(clearance 0)
		)
		(min_thickness 0.25)
		(keepout
			(tracks not_allowed)
			(vias allowed)
			(pads allowed)
			(copperpour not_allowed)
			(footprints allowed)
		)
		(placement
			(enabled no)
			(sheetname "")
		)
		(fill yes
			(thermal_gap 0.5)
			(thermal_bridge_width 0.5)
			(island_removal_mode 0)
		)
		(polygon
			(pts
				(arc
					(start 376.406156 -397.849344)
					(mid 375.776236 -397.849344)
					(end 376.406156 -397.849344)
				)
			)
		)
	)
	(zone
		(layers "B.Cu" "In11.Cu" "In13.Cu" "In15.Cu")
		(hatch none 0.5)
		(connect_pads
			(clearance 0)
		)
		(min_thickness 0.25)
		(keepout
			(tracks not_allowed)
			(vias allowed)
			(pads allowed)
			(copperpour not_allowed)
			(footprints allowed)
		)
		(placement
			(enabled no)
			(sheetname "")
		)
		(fill yes
			(thermal_gap 0.5)
			(thermal_bridge_width 0.5)
			(island_removal_mode 0)
		)
		(polygon
			(pts
				(arc
					(start 82.785966 -272.466308)
					(mid 82.156046 -272.466308)
					(end 82.785966 -272.466308)
				)
			)
		)
	)
	(zone
		(layers "B.Cu" "In11.Cu" "In13.Cu" "In15.Cu")
		(hatch none 0.5)
		(connect_pads
			(clearance 0)
		)
		(min_thickness 0.25)
		(keepout
			(tracks not_allowed)
			(vias allowed)
			(pads allowed)
			(copperpour not_allowed)
			(footprints allowed)
		)
		(placement
			(enabled no)
			(sheetname "")
		)
		(fill yes
			(thermal_gap 0.5)
			(thermal_bridge_width 0.5)
			(island_removal_mode 0)
		)
		(polygon
			(pts
				(arc
					(start 273.426174 -297.635168)
					(mid 272.758154 -297.635168)
					(end 273.426174 -297.635168)
				)
			)
		)
	)
	(zone
		(layers "B.Cu" "In11.Cu" "In13.Cu" "In15.Cu")
		(hatch none 0.5)
		(connect_pads
			(clearance 0)
		)
		(min_thickness 0.25)
		(keepout
			(tracks not_allowed)
			(vias allowed)
			(pads allowed)
			(copperpour not_allowed)
			(footprints allowed)
		)
		(placement
			(enabled no)
			(sheetname "")
		)
		(fill yes
			(thermal_gap 0.5)
			(thermal_bridge_width 0.5)
			(island_removal_mode 0)
		)
		(polygon
			(pts
				(arc
					(start 442.87821 -316.335156)
					(mid 442.21019 -316.335156)
					(end 442.87821 -316.335156)
				)
			)
		)
	)
	(zone
		(layers "B.Cu" "In11.Cu" "In13.Cu" "In15.Cu")
		(hatch none 0.5)
		(connect_pads
			(clearance 0)
		)
		(min_thickness 0.25)
		(keepout
			(tracks not_allowed)
			(vias allowed)
			(pads allowed)
			(copperpour not_allowed)
			(footprints allowed)
		)
		(placement
			(enabled no)
			(sheetname "")
		)
		(fill yes
			(thermal_gap 0.5)
			(thermal_bridge_width 0.5)
			(island_removal_mode 0)
		)
		(polygon
			(pts
				(arc
					(start 25.486106 -302.735234)
					(mid 24.818086 -302.735234)
					(end 25.486106 -302.735234)
				)
			)
		)
	)
	(zone
		(layers "B.Cu" "In11.Cu" "In13.Cu" "In15.Cu")
		(hatch none 0.5)
		(connect_pads
			(clearance 0)
		)
		(min_thickness 0.25)
		(keepout
			(tracks not_allowed)
			(vias allowed)
			(pads allowed)
			(copperpour not_allowed)
			(footprints allowed)
		)
		(placement
			(enabled no)
			(sheetname "")
		)
		(fill yes
			(thermal_gap 0.5)
			(thermal_bridge_width 0.5)
			(island_removal_mode 0)
		)
		(polygon
			(pts
				(arc
					(start 82.485992 -229.094538)
					(mid 81.856072 -229.094538)
					(end 82.485992 -229.094538)
				)
			)
		)
	)
	(zone
		(layers "B.Cu" "In11.Cu" "In13.Cu" "In15.Cu")
		(hatch none 0.5)
		(connect_pads
			(clearance 0)
		)
		(min_thickness 0.25)
		(keepout
			(tracks not_allowed)
			(vias allowed)
			(pads allowed)
			(copperpour not_allowed)
			(footprints allowed)
		)
		(placement
			(enabled no)
			(sheetname "")
		)
		(fill yes
			(thermal_gap 0.5)
			(thermal_bridge_width 0.5)
			(island_removal_mode 0)
		)
		(polygon
			(pts
				(arc
					(start 81.076038 -255.824482)
					(mid 80.446118 -255.824482)
					(end 81.076038 -255.824482)
				)
			)
		)
	)
	(zone
		(layers "B.Cu" "In11.Cu" "In13.Cu" "In15.Cu")
		(hatch none 0.5)
		(connect_pads
			(clearance 0)
		)
		(min_thickness 0.25)
		(keepout
			(tracks not_allowed)
			(vias allowed)
			(pads allowed)
			(copperpour not_allowed)
			(footprints allowed)
		)
		(placement
			(enabled no)
			(sheetname "")
		)
		(fill yes
			(thermal_gap 0.5)
			(thermal_bridge_width 0.5)
			(island_removal_mode 0)
		)
		(polygon
			(pts
				(arc
					(start 391.049764 -228.284278)
					(mid 390.419844 -228.284278)
					(end 391.049764 -228.284278)
				)
			)
		)
	)
	(zone
		(layers "B.Cu" "In11.Cu" "In13.Cu" "In15.Cu")
		(hatch none 0.5)
		(connect_pads
			(clearance 0)
		)
		(min_thickness 0.25)
		(keepout
			(tracks not_allowed)
			(vias allowed)
			(pads allowed)
			(copperpour not_allowed)
			(footprints allowed)
		)
		(placement
			(enabled no)
			(sheetname "")
		)
		(fill yes
			(thermal_gap 0.5)
			(thermal_bridge_width 0.5)
			(island_removal_mode 0)
		)
		(polygon
			(pts
				(arc
					(start 380.806198 -397.156432)
					(mid 380.176278 -397.156432)
					(end 380.806198 -397.156432)
				)
			)
		)
	)
	(zone
		(layers "B.Cu" "In11.Cu" "In13.Cu" "In15.Cu")
		(hatch none 0.5)
		(connect_pads
			(clearance 0)
		)
		(min_thickness 0.25)
		(keepout
			(tracks not_allowed)
			(vias allowed)
			(pads allowed)
			(copperpour not_allowed)
			(footprints allowed)
		)
		(placement
			(enabled no)
			(sheetname "")
		)
		(fill yes
			(thermal_gap 0.5)
			(thermal_bridge_width 0.5)
			(island_removal_mode 0)
		)
		(polygon
			(pts
				(arc
					(start 69.036946 -423.489882)
					(mid 68.262754 -423.489882)
					(end 69.036946 -423.489882)
				)
			)
		)
	)
	(zone
		(layers "B.Cu" "In11.Cu" "In13.Cu" "In15.Cu")
		(hatch none 0.5)
		(connect_pads
			(clearance 0)
		)
		(min_thickness 0.25)
		(keepout
			(tracks not_allowed)
			(vias allowed)
			(pads allowed)
			(copperpour not_allowed)
			(footprints allowed)
		)
		(placement
			(enabled no)
			(sheetname "")
		)
		(fill yes
			(thermal_gap 0.5)
			(thermal_bridge_width 0.5)
			(island_removal_mode 0)
		)
		(polygon
			(pts
				(arc
					(start 367.849658 -286.236156)
					(mid 367.219738 -286.236156)
					(end 367.849658 -286.236156)
				)
			)
		)
	)
	(zone
		(layers "B.Cu" "In11.Cu" "In13.Cu" "In15.Cu")
		(hatch none 0.5)
		(connect_pads
			(clearance 0)
		)
		(min_thickness 0.25)
		(keepout
			(tracks not_allowed)
			(vias allowed)
			(pads allowed)
			(copperpour not_allowed)
			(footprints allowed)
		)
		(placement
			(enabled no)
			(sheetname "")
		)
		(fill yes
			(thermal_gap 0.5)
			(thermal_bridge_width 0.5)
			(island_removal_mode 0)
		)
		(polygon
			(pts
				(arc
					(start 141.229842 -236.384338)
					(mid 140.599922 -236.384338)
					(end 141.229842 -236.384338)
				)
			)
		)
	)
	(zone
		(layers "B.Cu" "In11.Cu" "In13.Cu" "In15.Cu")
		(hatch none 0.5)
		(connect_pads
			(clearance 0)
		)
		(min_thickness 0.25)
		(keepout
			(tracks not_allowed)
			(vias allowed)
			(pads allowed)
			(copperpour not_allowed)
			(footprints allowed)
		)
		(placement
			(enabled no)
			(sheetname "")
		)
		(fill yes
			(thermal_gap 0.5)
			(thermal_bridge_width 0.5)
			(island_removal_mode 0)
		)
		(polygon
			(pts
				(arc
					(start 41.764712 -381.50546)
					(mid 41.096692 -381.50546)
					(end 41.764712 -381.50546)
				)
			)
		)
	)
	(zone
		(layers "B.Cu" "In11.Cu" "In13.Cu" "In15.Cu")
		(hatch none 0.5)
		(connect_pads
			(clearance 0)
		)
		(min_thickness 0.25)
		(keepout
			(tracks not_allowed)
			(vias allowed)
			(pads allowed)
			(copperpour not_allowed)
			(footprints allowed)
		)
		(placement
			(enabled no)
			(sheetname "")
		)
		(fill yes
			(thermal_gap 0.5)
			(thermal_bridge_width 0.5)
			(island_removal_mode 0)
		)
		(polygon
			(pts
				(arc
					(start 390.879838 -285.42615)
					(mid 390.249918 -285.42615)
					(end 390.879838 -285.42615)
				)
			)
		)
	)
	(zone
		(layers "B.Cu" "In11.Cu" "In13.Cu" "In15.Cu")
		(hatch none 0.5)
		(connect_pads
			(clearance 0)
		)
		(min_thickness 0.25)
		(keepout
			(tracks not_allowed)
			(vias allowed)
			(pads allowed)
			(copperpour not_allowed)
			(footprints allowed)
		)
		(placement
			(enabled no)
			(sheetname "")
		)
		(fill yes
			(thermal_gap 0.5)
			(thermal_bridge_width 0.5)
			(island_removal_mode 0)
		)
		(polygon
			(pts
				(arc
					(start 389.469884 -270.036036)
					(mid 388.839964 -270.036036)
					(end 389.469884 -270.036036)
				)
			)
		)
	)
	(zone
		(layers "B.Cu" "In11.Cu" "In13.Cu" "In15.Cu")
		(hatch none 0.5)
		(connect_pads
			(clearance 0)
		)
		(min_thickness 0.25)
		(keepout
			(tracks not_allowed)
			(vias allowed)
			(pads allowed)
			(copperpour not_allowed)
			(footprints allowed)
		)
		(placement
			(enabled no)
			(sheetname "")
		)
		(fill yes
			(thermal_gap 0.5)
			(thermal_bridge_width 0.5)
			(island_removal_mode 0)
		)
		(polygon
			(pts
				(arc
					(start 329.016106 -254.204216)
					(mid 328.386186 -254.204216)
					(end 329.016106 -254.204216)
				)
			)
		)
	)
	(zone
		(layers "B.Cu" "In11.Cu" "In13.Cu" "In15.Cu")
		(hatch none 0.5)
		(connect_pads
			(clearance 0)
		)
		(min_thickness 0.25)
		(keepout
			(tracks not_allowed)
			(vias allowed)
			(pads allowed)
			(copperpour not_allowed)
			(footprints allowed)
		)
		(placement
			(enabled no)
			(sheetname "")
		)
		(fill yes
			(thermal_gap 0.5)
			(thermal_bridge_width 0.5)
			(island_removal_mode 0)
		)
		(polygon
			(pts
				(arc
					(start 141.699742 -251.774452)
					(mid 141.069822 -251.774452)
					(end 141.699742 -251.774452)
				)
			)
		)
	)
	(zone
		(layers "B.Cu" "In11.Cu" "In13.Cu" "In15.Cu")
		(hatch none 0.5)
		(connect_pads
			(clearance 0)
		)
		(min_thickness 0.25)
		(keepout
			(tracks not_allowed)
			(vias allowed)
			(pads allowed)
			(copperpour not_allowed)
			(footprints allowed)
		)
		(placement
			(enabled no)
			(sheetname "")
		)
		(fill yes
			(thermal_gap 0.5)
			(thermal_bridge_width 0.5)
			(island_removal_mode 0)
		)
		(polygon
			(pts
				(arc
					(start 446.978278 -301.885096)
					(mid 446.310258 -301.885096)
					(end 446.978278 -301.885096)
				)
			)
		)
	)
	(zone
		(layers "B.Cu" "In11.Cu" "In13.Cu" "In15.Cu")
		(hatch none 0.5)
		(connect_pads
			(clearance 0)
		)
		(min_thickness 0.25)
		(keepout
			(tracks not_allowed)
			(vias allowed)
			(pads allowed)
			(copperpour not_allowed)
			(footprints allowed)
		)
		(placement
			(enabled no)
			(sheetname "")
		)
		(fill yes
			(thermal_gap 0.5)
			(thermal_bridge_width 0.5)
			(island_removal_mode 0)
		)
		(polygon
			(pts
				(arc
					(start 386.806186 -397.156432)
					(mid 386.176266 -397.156432)
					(end 386.806186 -397.156432)
				)
			)
		)
	)
	(zone
		(layers "B.Cu" "In11.Cu" "In13.Cu" "In15.Cu")
		(hatch none 0.5)
		(connect_pads
			(clearance 0)
		)
		(min_thickness 0.25)
		(keepout
			(tracks not_allowed)
			(vias allowed)
			(pads allowed)
			(copperpour not_allowed)
			(footprints allowed)
		)
		(placement
			(enabled no)
			(sheetname "")
		)
		(fill yes
			(thermal_gap 0.5)
			(thermal_bridge_width 0.5)
			(island_removal_mode 0)
		)
		(polygon
			(pts
				(arc
					(start 81.076038 -234.764326)
					(mid 80.446118 -234.764326)
					(end 81.076038 -234.764326)
				)
			)
		)
	)
	(zone
		(layers "B.Cu" "In11.Cu" "In13.Cu" "In15.Cu")
		(hatch none 0.5)
		(connect_pads
			(clearance 0)
		)
		(min_thickness 0.25)
		(keepout
			(tracks not_allowed)
			(vias allowed)
			(pads allowed)
			(copperpour not_allowed)
			(footprints allowed)
		)
		(placement
			(enabled no)
			(sheetname "")
		)
		(fill yes
			(thermal_gap 0.5)
			(thermal_bridge_width 0.5)
			(island_removal_mode 0)
		)
		(polygon
			(pts
				(arc
					(start 420.93388 -394.385292)
					(mid 420.30396 -394.385292)
					(end 420.93388 -394.385292)
				)
			)
		)
	)
	(zone
		(layers "B.Cu" "In11.Cu" "In13.Cu" "In15.Cu")
		(hatch none 0.5)
		(connect_pads
			(clearance 0)
		)
		(min_thickness 0.25)
		(keepout
			(tracks not_allowed)
			(vias allowed)
			(pads allowed)
			(copperpour not_allowed)
			(footprints allowed)
		)
		(placement
			(enabled no)
			(sheetname "")
		)
		(fill yes
			(thermal_gap 0.5)
			(thermal_bridge_width 0.5)
			(island_removal_mode 0)
		)
		(polygon
			(pts
				(arc
					(start 81.376012 -291.096192)
					(mid 80.746092 -291.096192)
					(end 81.376012 -291.096192)
				)
			)
		)
	)
	(zone
		(layers "B.Cu" "In11.Cu" "In13.Cu" "In15.Cu")
		(hatch none 0.5)
		(connect_pads
			(clearance 0)
		)
		(min_thickness 0.25)
		(keepout
			(tracks not_allowed)
			(vias allowed)
			(pads allowed)
			(copperpour not_allowed)
			(footprints allowed)
		)
		(placement
			(enabled no)
			(sheetname "")
		)
		(fill yes
			(thermal_gap 0.5)
			(thermal_bridge_width 0.5)
			(island_removal_mode 0)
		)
		(polygon
			(pts
				(arc
					(start 329.486006 -235.574078)
					(mid 328.856086 -235.574078)
					(end 329.486006 -235.574078)
				)
			)
		)
	)
	(zone
		(layers "B.Cu" "In11.Cu" "In13.Cu" "In15.Cu")
		(hatch none 0.5)
		(connect_pads
			(clearance 0)
		)
		(min_thickness 0.25)
		(keepout
			(tracks not_allowed)
			(vias allowed)
			(pads allowed)
			(copperpour not_allowed)
			(footprints allowed)
		)
		(placement
			(enabled no)
			(sheetname "")
		)
		(fill yes
			(thermal_gap 0.5)
			(thermal_bridge_width 0.5)
			(island_removal_mode 0)
		)
		(polygon
			(pts
				(arc
					(start 330.89596 -229.904036)
					(mid 330.26604 -229.904036)
					(end 330.89596 -229.904036)
				)
			)
		)
	)
	(zone
		(layers "B.Cu" "In11.Cu" "In13.Cu" "In15.Cu")
		(hatch none 0.5)
		(connect_pads
			(clearance 0)
		)
		(min_thickness 0.25)
		(keepout
			(tracks not_allowed)
			(vias allowed)
			(pads allowed)
			(copperpour not_allowed)
			(footprints allowed)
		)
		(placement
			(enabled no)
			(sheetname "")
		)
		(fill yes
			(thermal_gap 0.5)
			(thermal_bridge_width 0.5)
			(island_removal_mode 0)
		)
		(polygon
			(pts
				(arc
					(start 336.03692 -426.089826)
					(mid 335.262728 -426.089826)
					(end 336.03692 -426.089826)
				)
			)
		)
	)
	(zone
		(layers "B.Cu" "In11.Cu" "In13.Cu" "In15.Cu")
		(hatch none 0.5)
		(connect_pads
			(clearance 0)
		)
		(min_thickness 0.25)
		(keepout
			(tracks not_allowed)
			(vias allowed)
			(pads allowed)
			(copperpour not_allowed)
			(footprints allowed)
		)
		(placement
			(enabled no)
			(sheetname "")
		)
		(fill yes
			(thermal_gap 0.5)
			(thermal_bridge_width 0.5)
			(island_removal_mode 0)
		)
		(polygon
			(pts
				(arc
					(start 117.089682 -286.23641)
					(mid 116.459762 -286.23641)
					(end 117.089682 -286.23641)
				)
			)
		)
	)
	(zone
		(layers "B.Cu" "In11.Cu" "In13.Cu" "In15.Cu")
		(hatch none 0.5)
		(connect_pads
			(clearance 0)
		)
		(min_thickness 0.25)
		(keepout
			(tracks not_allowed)
			(vias allowed)
			(pads allowed)
			(copperpour not_allowed)
			(footprints allowed)
		)
		(placement
			(enabled no)
			(sheetname "")
		)
		(fill yes
			(thermal_gap 0.5)
			(thermal_bridge_width 0.5)
			(island_removal_mode 0)
		)
		(polygon
			(pts
				(arc
					(start 25.486106 -312.085228)
					(mid 24.818086 -312.085228)
					(end 25.486106 -312.085228)
				)
			)
		)
	)
	(zone
		(layers "B.Cu" "In11.Cu" "In13.Cu" "In15.Cu")
		(hatch none 0.5)
		(connect_pads
			(clearance 0)
		)
		(min_thickness 0.25)
		(keepout
			(tracks not_allowed)
			(vias allowed)
			(pads allowed)
			(copperpour not_allowed)
			(footprints allowed)
		)
		(placement
			(enabled no)
			(sheetname "")
		)
		(fill yes
			(thermal_gap 0.5)
			(thermal_bridge_width 0.5)
			(island_removal_mode 0)
		)
		(polygon
			(pts
				(arc
					(start 415.733992 -393.69238)
					(mid 415.104072 -393.69238)
					(end 415.733992 -393.69238)
				)
			)
		)
	)
	(zone
		(layers "B.Cu" "In11.Cu" "In13.Cu" "In15.Cu")
		(hatch none 0.5)
		(connect_pads
			(clearance 0)
		)
		(min_thickness 0.25)
		(keepout
			(tracks not_allowed)
			(vias allowed)
			(pads allowed)
			(copperpour not_allowed)
			(footprints allowed)
		)
		(placement
			(enabled no)
			(sheetname "")
		)
		(fill yes
			(thermal_gap 0.5)
			(thermal_bridge_width 0.5)
			(island_removal_mode 0)
		)
		(polygon
			(pts
				(arc
					(start 142.93977 -290.286186)
					(mid 142.30985 -290.286186)
					(end 142.93977 -290.286186)
				)
			)
		)
	)
	(zone
		(layers "B.Cu" "In11.Cu" "In13.Cu" "In15.Cu")
		(hatch none 0.5)
		(connect_pads
			(clearance 0)
		)
		(min_thickness 0.25)
		(keepout
			(tracks not_allowed)
			(vias allowed)
			(pads allowed)
			(copperpour not_allowed)
			(footprints allowed)
		)
		(placement
			(enabled no)
			(sheetname "")
		)
		(fill yes
			(thermal_gap 0.5)
			(thermal_bridge_width 0.5)
			(island_removal_mode 0)
		)
		(polygon
			(pts
				(arc
					(start 83.255866 -281.376374)
					(mid 82.625946 -281.376374)
					(end 83.255866 -281.376374)
				)
			)
		)
	)
	(zone
		(layers "B.Cu" "In11.Cu" "In13.Cu" "In15.Cu")
		(hatch none 0.5)
		(connect_pads
			(clearance 0)
		)
		(min_thickness 0.25)
		(keepout
			(tracks not_allowed)
			(vias allowed)
			(pads allowed)
			(copperpour not_allowed)
			(footprints allowed)
		)
		(placement
			(enabled no)
			(sheetname "")
		)
		(fill yes
			(thermal_gap 0.5)
			(thermal_bridge_width 0.5)
			(island_removal_mode 0)
		)
		(polygon
			(pts
				(arc
					(start 118.806214 -388.774432)
					(mid 118.176294 -388.774432)
					(end 118.806214 -388.774432)
				)
			)
		)
	)
	(zone
		(layers "B.Cu" "In11.Cu" "In13.Cu" "In15.Cu")
		(hatch none 0.5)
		(connect_pads
			(clearance 0)
		)
		(min_thickness 0.25)
		(keepout
			(tracks not_allowed)
			(vias allowed)
			(pads allowed)
			(copperpour not_allowed)
			(footprints allowed)
		)
		(placement
			(enabled no)
			(sheetname "")
		)
		(fill yes
			(thermal_gap 0.5)
			(thermal_bridge_width 0.5)
			(island_removal_mode 0)
		)
		(polygon
			(pts
				(arc
					(start 331.195934 -278.136096)
					(mid 330.566014 -278.136096)
					(end 331.195934 -278.136096)
				)
			)
		)
	)
	(zone
		(layers "B.Cu" "In11.Cu" "In13.Cu" "In15.Cu")
		(hatch none 0.5)
		(connect_pads
			(clearance 0)
		)
		(min_thickness 0.25)
		(keepout
			(tracks not_allowed)
			(vias allowed)
			(pads allowed)
			(copperpour not_allowed)
			(footprints allowed)
		)
		(placement
			(enabled no)
			(sheetname "")
		)
		(fill yes
			(thermal_gap 0.5)
			(thermal_bridge_width 0.5)
			(island_removal_mode 0)
		)
		(polygon
			(pts
				(arc
					(start 354.696014 -282.996132)
					(mid 354.066094 -282.996132)
					(end 354.696014 -282.996132)
				)
			)
		)
	)
	(zone
		(layers "B.Cu" "In11.Cu" "In13.Cu" "In15.Cu")
		(hatch none 0.5)
		(connect_pads
			(clearance 0)
		)
		(min_thickness 0.25)
		(keepout
			(tracks not_allowed)
			(vias allowed)
			(pads allowed)
			(copperpour not_allowed)
			(footprints allowed)
		)
		(placement
			(enabled no)
			(sheetname "")
		)
		(fill yes
			(thermal_gap 0.5)
			(thermal_bridge_width 0.5)
			(island_removal_mode 0)
		)
		(polygon
			(pts
				(arc
					(start 330.726034 -275.706078)
					(mid 330.096114 -275.706078)
					(end 330.726034 -275.706078)
				)
			)
		)
	)
	(zone
		(layers "B.Cu" "In11.Cu" "In13.Cu" "In15.Cu")
		(hatch none 0.5)
		(connect_pads
			(clearance 0)
		)
		(min_thickness 0.25)
		(keepout
			(tracks not_allowed)
			(vias allowed)
			(pads allowed)
			(copperpour not_allowed)
			(footprints allowed)
		)
		(placement
			(enabled no)
			(sheetname "")
		)
		(fill yes
			(thermal_gap 0.5)
			(thermal_bridge_width 0.5)
			(island_removal_mode 0)
		)
		(polygon
			(pts
				(arc
					(start 330.726034 -264.365994)
					(mid 330.096114 -264.365994)
					(end 330.726034 -264.365994)
				)
			)
		)
	)
	(zone
		(layers "B.Cu" "In11.Cu" "In13.Cu" "In15.Cu")
		(hatch none 0.5)
		(connect_pads
			(clearance 0)
		)
		(min_thickness 0.25)
		(keepout
			(tracks not_allowed)
			(vias allowed)
			(pads allowed)
			(copperpour not_allowed)
			(footprints allowed)
		)
		(placement
			(enabled no)
			(sheetname "")
		)
		(fill yes
			(thermal_gap 0.5)
			(thermal_bridge_width 0.5)
			(island_removal_mode 0)
		)
		(polygon
			(pts
				(arc
					(start 299.348906 -379.88113)
					(mid 298.680886 -379.88113)
					(end 299.348906 -379.88113)
				)
			)
		)
	)
	(zone
		(layers "B.Cu" "In11.Cu" "In13.Cu" "In15.Cu")
		(hatch none 0.5)
		(connect_pads
			(clearance 0)
		)
		(min_thickness 0.25)
		(keepout
			(tracks not_allowed)
			(vias allowed)
			(pads allowed)
			(copperpour not_allowed)
			(footprints allowed)
		)
		(placement
			(enabled no)
			(sheetname "")
		)
		(fill yes
			(thermal_gap 0.5)
			(thermal_bridge_width 0.5)
			(island_removal_mode 0)
		)
		(polygon
			(pts
				(arc
					(start 65.036954 -423.489882)
					(mid 64.262762 -423.489882)
					(end 65.036954 -423.489882)
				)
			)
		)
	)
	(zone
		(layers "B.Cu" "In11.Cu" "In13.Cu" "In15.Cu")
		(hatch none 0.5)
		(connect_pads
			(clearance 0)
		)
		(min_thickness 0.25)
		(keepout
			(tracks not_allowed)
			(vias allowed)
			(pads allowed)
			(copperpour not_allowed)
			(footprints allowed)
		)
		(placement
			(enabled no)
			(sheetname "")
		)
		(fill yes
			(thermal_gap 0.5)
			(thermal_bridge_width 0.5)
			(island_removal_mode 0)
		)
		(polygon
			(pts
				(arc
					(start 365.66983 -241.24412)
					(mid 365.03991 -241.24412)
					(end 365.66983 -241.24412)
				)
			)
		)
	)
	(zone
		(layers "B.Cu" "In11.Cu" "In13.Cu" "In15.Cu")
		(hatch none 0.5)
		(connect_pads
			(clearance 0)
		)
		(min_thickness 0.25)
		(keepout
			(tracks not_allowed)
			(vias allowed)
			(pads allowed)
			(copperpour not_allowed)
			(footprints allowed)
		)
		(placement
			(enabled no)
			(sheetname "")
		)
		(fill yes
			(thermal_gap 0.5)
			(thermal_bridge_width 0.5)
			(island_removal_mode 0)
		)
		(polygon
			(pts
				(arc
					(start 330.42606 -238.814102)
					(mid 329.79614 -238.814102)
					(end 330.42606 -238.814102)
				)
			)
		)
	)
	(zone
		(layers "B.Cu" "In11.Cu" "In13.Cu" "In15.Cu")
		(hatch none 0.5)
		(connect_pads
			(clearance 0)
		)
		(min_thickness 0.25)
		(keepout
			(tracks not_allowed)
			(vias allowed)
			(pads allowed)
			(copperpour not_allowed)
			(footprints allowed)
		)
		(placement
			(enabled no)
			(sheetname "")
		)
		(fill yes
			(thermal_gap 0.5)
			(thermal_bridge_width 0.5)
			(island_removal_mode 0)
		)
		(polygon
			(pts
				(arc
					(start 389.16991 -231.524048)
					(mid 388.53999 -231.524048)
					(end 389.16991 -231.524048)
				)
			)
		)
	)
	(zone
		(layers "B.Cu" "In11.Cu" "In13.Cu" "In15.Cu")
		(hatch none 0.5)
		(connect_pads
			(clearance 0)
		)
		(min_thickness 0.25)
		(keepout
			(tracks not_allowed)
			(vias allowed)
			(pads allowed)
			(copperpour not_allowed)
			(footprints allowed)
		)
		(placement
			(enabled no)
			(sheetname "")
		)
		(fill yes
			(thermal_gap 0.5)
			(thermal_bridge_width 0.5)
			(island_removal_mode 0)
		)
		(polygon
			(pts
				(arc
					(start 133.206236 -388.774432)
					(mid 132.576316 -388.774432)
					(end 133.206236 -388.774432)
				)
			)
		)
	)
	(zone
		(layers "B.Cu" "In11.Cu" "In13.Cu" "In15.Cu")
		(hatch none 0.5)
		(connect_pads
			(clearance 0)
		)
		(min_thickness 0.25)
		(keepout
			(tracks not_allowed)
			(vias allowed)
			(pads allowed)
			(copperpour not_allowed)
			(footprints allowed)
		)
		(placement
			(enabled no)
			(sheetname "")
		)
		(fill yes
			(thermal_gap 0.5)
			(thermal_bridge_width 0.5)
			(island_removal_mode 0)
		)
		(polygon
			(pts
				(arc
					(start 391.049764 -233.14406)
					(mid 390.419844 -233.14406)
					(end 391.049764 -233.14406)
				)
			)
		)
	)
	(zone
		(layers "B.Cu" "In11.Cu" "In13.Cu" "In15.Cu")
		(hatch none 0.5)
		(connect_pads
			(clearance 0)
		)
		(min_thickness 0.25)
		(keepout
			(tracks not_allowed)
			(vias allowed)
			(pads allowed)
			(copperpour not_allowed)
			(footprints allowed)
		)
		(placement
			(enabled no)
			(sheetname "")
		)
		(fill yes
			(thermal_gap 0.5)
			(thermal_bridge_width 0.5)
			(island_removal_mode 0)
		)
		(polygon
			(pts
				(arc
					(start 374.429782 -282.996132)
					(mid 373.799862 -282.996132)
					(end 374.429782 -282.996132)
				)
			)
		)
	)
	(zone
		(layers "B.Cu" "In11.Cu" "In13.Cu" "In15.Cu")
		(hatch none 0.5)
		(connect_pads
			(clearance 0)
		)
		(min_thickness 0.25)
		(keepout
			(tracks not_allowed)
			(vias allowed)
			(pads allowed)
			(copperpour not_allowed)
			(footprints allowed)
		)
		(placement
			(enabled no)
			(sheetname "")
		)
		(fill yes
			(thermal_gap 0.5)
			(thermal_bridge_width 0.5)
			(island_removal_mode 0)
		)
		(polygon
			(pts
				(arc
					(start 194.938142 -280.635202)
					(mid 194.270122 -280.635202)
					(end 194.938142 -280.635202)
				)
			)
		)
	)
	(zone
		(layers "B.Cu" "In11.Cu" "In13.Cu" "In15.Cu")
		(hatch none 0.5)
		(connect_pads
			(clearance 0)
		)
		(min_thickness 0.25)
		(keepout
			(tracks not_allowed)
			(vias allowed)
			(pads allowed)
			(copperpour not_allowed)
			(footprints allowed)
		)
		(placement
			(enabled no)
			(sheetname "")
		)
		(fill yes
			(thermal_gap 0.5)
			(thermal_bridge_width 0.5)
			(island_removal_mode 0)
		)
		(polygon
			(pts
				(arc
					(start 142.93977 -287.046162)
					(mid 142.30985 -287.046162)
					(end 142.93977 -287.046162)
				)
			)
		)
	)
	(zone
		(layers "B.Cu" "In11.Cu" "In13.Cu" "In15.Cu")
		(hatch none 0.5)
		(connect_pads
			(clearance 0)
		)
		(min_thickness 0.25)
		(keepout
			(tracks not_allowed)
			(vias allowed)
			(pads allowed)
			(copperpour not_allowed)
			(footprints allowed)
		)
		(placement
			(enabled no)
			(sheetname "")
		)
		(fill yes
			(thermal_gap 0.5)
			(thermal_bridge_width 0.5)
			(island_removal_mode 0)
		)
		(polygon
			(pts
				(arc
					(start 194.938142 -216.885266)
					(mid 194.270122 -216.885266)
					(end 194.938142 -216.885266)
				)
			)
		)
	)
	(zone
		(layers "B.Cu" "In11.Cu" "In13.Cu" "In15.Cu")
		(hatch none 0.5)
		(connect_pads
			(clearance 0)
		)
		(min_thickness 0.25)
		(keepout
			(tracks not_allowed)
			(vias allowed)
			(pads allowed)
			(copperpour not_allowed)
			(footprints allowed)
		)
		(placement
			(enabled no)
			(sheetname "")
		)
		(fill yes
			(thermal_gap 0.5)
			(thermal_bridge_width 0.5)
			(island_removal_mode 0)
		)
		(polygon
			(pts
				(arc
					(start 61.036962 -419.88994)
					(mid 60.26277 -419.88994)
					(end 61.036962 -419.88994)
				)
			)
		)
	)
	(zone
		(layers "B.Cu" "In11.Cu" "In13.Cu" "In15.Cu")
		(hatch none 0.5)
		(connect_pads
			(clearance 0)
		)
		(min_thickness 0.25)
		(keepout
			(tracks not_allowed)
			(vias allowed)
			(pads allowed)
			(copperpour not_allowed)
			(footprints allowed)
		)
		(placement
			(enabled no)
			(sheetname "")
		)
		(fill yes
			(thermal_gap 0.5)
			(thermal_bridge_width 0.5)
			(island_removal_mode 0)
		)
		(polygon
			(pts
				(arc
					(start 377.206256 -397.156432)
					(mid 376.576336 -397.156432)
					(end 377.206256 -397.156432)
				)
			)
		)
	)
	(zone
		(layers "B.Cu" "In11.Cu" "In13.Cu" "In15.Cu")
		(hatch none 0.5)
		(connect_pads
			(clearance 0)
		)
		(min_thickness 0.25)
		(keepout
			(tracks not_allowed)
			(vias allowed)
			(pads allowed)
			(copperpour not_allowed)
			(footprints allowed)
		)
		(placement
			(enabled no)
			(sheetname "")
		)
		(fill yes
			(thermal_gap 0.5)
			(thermal_bridge_width 0.5)
			(island_removal_mode 0)
		)
		(polygon
			(pts
				(arc
					(start 194.938142 -306.985416)
					(mid 194.270122 -306.985416)
					(end 194.938142 -306.985416)
				)
			)
		)
	)
	(zone
		(layers "B.Cu" "In11.Cu" "In13.Cu" "In15.Cu")
		(hatch none 0.5)
		(connect_pads
			(clearance 0)
		)
		(min_thickness 0.25)
		(keepout
			(tracks not_allowed)
			(vias allowed)
			(pads allowed)
			(copperpour not_allowed)
			(footprints allowed)
		)
		(placement
			(enabled no)
			(sheetname "")
		)
		(fill yes
			(thermal_gap 0.5)
			(thermal_bridge_width 0.5)
			(island_removal_mode 0)
		)
		(polygon
			(pts
				(arc
					(start 29.586174 -301.88535)
					(mid 28.918154 -301.88535)
					(end 29.586174 -301.88535)
				)
			)
		)
	)
	(zone
		(layers "B.Cu" "In11.Cu" "In13.Cu" "In15.Cu")
		(hatch none 0.5)
		(connect_pads
			(clearance 0)
		)
		(min_thickness 0.25)
		(keepout
			(tracks not_allowed)
			(vias allowed)
			(pads allowed)
			(copperpour not_allowed)
			(footprints allowed)
		)
		(placement
			(enabled no)
			(sheetname "")
		)
		(fill yes
			(thermal_gap 0.5)
			(thermal_bridge_width 0.5)
			(island_removal_mode 0)
		)
		(polygon
			(pts
				(arc
					(start 329.31608 -287.856168)
					(mid 328.68616 -287.856168)
					(end 329.31608 -287.856168)
				)
			)
		)
	)
	(zone
		(layers "B.Cu" "In11.Cu" "In13.Cu" "In15.Cu")
		(hatch none 0.5)
		(connect_pads
			(clearance 0)
		)
		(min_thickness 0.25)
		(keepout
			(tracks not_allowed)
			(vias allowed)
			(pads allowed)
			(copperpour not_allowed)
			(footprints allowed)
		)
		(placement
			(enabled no)
			(sheetname "")
		)
		(fill yes
			(thermal_gap 0.5)
			(thermal_bridge_width 0.5)
			(island_removal_mode 0)
		)
		(polygon
			(pts
				(arc
					(start 82.785966 -293.52621)
					(mid 82.156046 -293.52621)
					(end 82.785966 -293.52621)
				)
			)
		)
	)
	(zone
		(layers "B.Cu" "In11.Cu" "In13.Cu" "In15.Cu")
		(hatch none 0.5)
		(connect_pads
			(clearance 0)
		)
		(min_thickness 0.25)
		(keepout
			(tracks not_allowed)
			(vias allowed)
			(pads allowed)
			(copperpour not_allowed)
			(footprints allowed)
		)
		(placement
			(enabled no)
			(sheetname "")
		)
		(fill yes
			(thermal_gap 0.5)
			(thermal_bridge_width 0.5)
			(island_removal_mode 0)
		)
		(polygon
			(pts
				(arc
					(start 330.726034 -293.525956)
					(mid 330.096114 -293.525956)
					(end 330.726034 -293.525956)
				)
			)
		)
	)
	(zone
		(layers "B.Cu" "In11.Cu" "In13.Cu" "In15.Cu")
		(hatch none 0.5)
		(connect_pads
			(clearance 0)
		)
		(min_thickness 0.25)
		(keepout
			(tracks not_allowed)
			(vias allowed)
			(pads allowed)
			(copperpour not_allowed)
			(footprints allowed)
		)
		(placement
			(enabled no)
			(sheetname "")
		)
		(fill yes
			(thermal_gap 0.5)
			(thermal_bridge_width 0.5)
			(island_removal_mode 0)
		)
		(polygon
			(pts
				(arc
					(start 25.486106 -207.535272)
					(mid 24.818086 -207.535272)
					(end 25.486106 -207.535272)
				)
			)
		)
	)
	(zone
		(layers "B.Cu" "In11.Cu" "In13.Cu" "In15.Cu")
		(hatch none 0.5)
		(connect_pads
			(clearance 0)
		)
		(min_thickness 0.25)
		(keepout
			(tracks not_allowed)
			(vias allowed)
			(pads allowed)
			(copperpour not_allowed)
			(footprints allowed)
		)
		(placement
			(enabled no)
			(sheetname "")
		)
		(fill yes
			(thermal_gap 0.5)
			(thermal_bridge_width 0.5)
			(island_removal_mode 0)
		)
		(polygon
			(pts
				(arc
					(start 405.137112 -427.089824)
					(mid 404.36292 -427.089824)
					(end 405.137112 -427.089824)
				)
			)
		)
	)
	(zone
		(layers "B.Cu" "In11.Cu" "In13.Cu" "In15.Cu")
		(hatch none 0.5)
		(connect_pads
			(clearance 0)
		)
		(min_thickness 0.25)
		(keepout
			(tracks not_allowed)
			(vias allowed)
			(pads allowed)
			(copperpour not_allowed)
			(footprints allowed)
		)
		(placement
			(enabled no)
			(sheetname "")
		)
		(fill yes
			(thermal_gap 0.5)
			(thermal_bridge_width 0.5)
			(island_removal_mode 0)
		)
		(polygon
			(pts
				(arc
					(start 412.13405 -393.69238)
					(mid 411.50413 -393.69238)
					(end 412.13405 -393.69238)
				)
			)
		)
	)
	(zone
		(layers "B.Cu" "In11.Cu" "In13.Cu" "In15.Cu")
		(hatch none 0.5)
		(connect_pads
			(clearance 0)
		)
		(min_thickness 0.25)
		(keepout
			(tracks not_allowed)
			(vias allowed)
			(pads allowed)
			(copperpour not_allowed)
			(footprints allowed)
		)
		(placement
			(enabled no)
			(sheetname "")
		)
		(fill yes
			(thermal_gap 0.5)
			(thermal_bridge_width 0.5)
			(island_removal_mode 0)
		)
		(polygon
			(pts
				(arc
					(start 336.03692 -427.289976)
					(mid 335.262728 -427.289976)
					(end 336.03692 -427.289976)
				)
			)
		)
	)
	(zone
		(layers "B.Cu" "In11.Cu" "In13.Cu" "In15.Cu")
		(hatch none 0.5)
		(connect_pads
			(clearance 0)
		)
		(min_thickness 0.25)
		(keepout
			(tracks not_allowed)
			(vias allowed)
			(pads allowed)
			(copperpour not_allowed)
			(footprints allowed)
		)
		(placement
			(enabled no)
			(sheetname "")
		)
		(fill yes
			(thermal_gap 0.5)
			(thermal_bridge_width 0.5)
			(island_removal_mode 0)
		)
		(polygon
			(pts
				(arc
					(start 391.049764 -242.864132)
					(mid 390.419844 -242.864132)
					(end 391.049764 -242.864132)
				)
			)
		)
	)
	(zone
		(layers "B.Cu" "In11.Cu" "In13.Cu" "In15.Cu")
		(hatch none 0.5)
		(connect_pads
			(clearance 0)
		)
		(min_thickness 0.25)
		(keepout
			(tracks not_allowed)
			(vias allowed)
			(pads allowed)
			(copperpour not_allowed)
			(footprints allowed)
		)
		(placement
			(enabled no)
			(sheetname "")
		)
		(fill yes
			(thermal_gap 0.5)
			(thermal_bridge_width 0.5)
			(island_removal_mode 0)
		)
		(polygon
			(pts
				(arc
					(start 389.606282 -397.849344)
					(mid 388.976362 -397.849344)
					(end 389.606282 -397.849344)
				)
			)
		)
	)
	(zone
		(layers "B.Cu" "In11.Cu" "In13.Cu" "In15.Cu")
		(hatch none 0.5)
		(connect_pads
			(clearance 0)
		)
		(min_thickness 0.25)
		(keepout
			(tracks not_allowed)
			(vias allowed)
			(pads allowed)
			(copperpour not_allowed)
			(footprints allowed)
		)
		(placement
			(enabled no)
			(sheetname "")
		)
		(fill yes
			(thermal_gap 0.5)
			(thermal_bridge_width 0.5)
			(island_removal_mode 0)
		)
		(polygon
			(pts
				(arc
					(start 29.586174 -247.485408)
					(mid 28.918154 -247.485408)
					(end 29.586174 -247.485408)
				)
			)
		)
	)
	(zone
		(layers "B.Cu" "In11.Cu" "In13.Cu" "In15.Cu")
		(hatch none 0.5)
		(connect_pads
			(clearance 0)
		)
		(min_thickness 0.25)
		(keepout
			(tracks not_allowed)
			(vias allowed)
			(pads allowed)
			(copperpour not_allowed)
			(footprints allowed)
		)
		(placement
			(enabled no)
			(sheetname "")
		)
		(fill yes
			(thermal_gap 0.5)
			(thermal_bridge_width 0.5)
			(island_removal_mode 0)
		)
		(polygon
			(pts
				(arc
					(start 194.938142 -263.635236)
					(mid 194.270122 -263.635236)
					(end 194.938142 -263.635236)
				)
			)
		)
	)
	(zone
		(layers "B.Cu" "In11.Cu" "In13.Cu" "In15.Cu")
		(hatch none 0.5)
		(connect_pads
			(clearance 0)
		)
		(min_thickness 0.25)
		(keepout
			(tracks not_allowed)
			(vias allowed)
			(pads allowed)
			(copperpour not_allowed)
			(footprints allowed)
		)
		(placement
			(enabled no)
			(sheetname "")
		)
		(fill yes
			(thermal_gap 0.5)
			(thermal_bridge_width 0.5)
			(island_removal_mode 0)
		)
		(polygon
			(pts
				(arc
					(start 110.046008 -285.426404)
					(mid 109.416088 -285.426404)
					(end 110.046008 -285.426404)
				)
			)
		)
	)
	(zone
		(layers "B.Cu" "In11.Cu" "In13.Cu" "In15.Cu")
		(hatch none 0.5)
		(connect_pads
			(clearance 0)
		)
		(min_thickness 0.25)
		(keepout
			(tracks not_allowed)
			(vias allowed)
			(pads allowed)
			(copperpour not_allowed)
			(footprints allowed)
		)
		(placement
			(enabled no)
			(sheetname "")
		)
		(fill yes
			(thermal_gap 0.5)
			(thermal_bridge_width 0.5)
			(island_removal_mode 0)
		)
		(polygon
			(pts
				(arc
					(start 277.526242 -300.185074)
					(mid 276.858222 -300.185074)
					(end 277.526242 -300.185074)
				)
			)
		)
	)
	(zone
		(layers "B.Cu" "In11.Cu" "In13.Cu" "In15.Cu")
		(hatch none 0.5)
		(connect_pads
			(clearance 0)
		)
		(min_thickness 0.25)
		(keepout
			(tracks not_allowed)
			(vias allowed)
			(pads allowed)
			(copperpour not_allowed)
			(footprints allowed)
		)
		(placement
			(enabled no)
			(sheetname "")
		)
		(fill yes
			(thermal_gap 0.5)
			(thermal_bridge_width 0.5)
			(island_removal_mode 0)
		)
		(polygon
			(pts
				(arc
					(start 29.586174 -307.8353)
					(mid 28.918154 -307.8353)
					(end 29.586174 -307.8353)
				)
			)
		)
	)
	(zone
		(layers "B.Cu" "In11.Cu" "In13.Cu" "In15.Cu")
		(hatch none 0.5)
		(connect_pads
			(clearance 0)
		)
		(min_thickness 0.25)
		(keepout
			(tracks not_allowed)
			(vias allowed)
			(pads allowed)
			(copperpour not_allowed)
			(footprints allowed)
		)
		(placement
			(enabled no)
			(sheetname "")
		)
		(fill yes
			(thermal_gap 0.5)
			(thermal_bridge_width 0.5)
			(island_removal_mode 0)
		)
		(polygon
			(pts
				(arc
					(start 141.529816 -273.276314)
					(mid 140.899896 -273.276314)
					(end 141.529816 -273.276314)
				)
			)
		)
	)
	(zone
		(layers "B.Cu" "In11.Cu" "In13.Cu" "In15.Cu")
		(hatch none 0.5)
		(connect_pads
			(clearance 0)
		)
		(min_thickness 0.25)
		(keepout
			(tracks not_allowed)
			(vias allowed)
			(pads allowed)
			(copperpour not_allowed)
			(footprints allowed)
		)
		(placement
			(enabled no)
			(sheetname "")
		)
		(fill yes
			(thermal_gap 0.5)
			(thermal_bridge_width 0.5)
			(island_removal_mode 0)
		)
		(polygon
			(pts
				(arc
					(start 389.939784 -272.466054)
					(mid 389.309864 -272.466054)
					(end 389.939784 -272.466054)
				)
			)
		)
	)
	(zone
		(layers "B.Cu" "In11.Cu" "In13.Cu" "In15.Cu")
		(hatch none 0.5)
		(connect_pads
			(clearance 0)
		)
		(min_thickness 0.25)
		(keepout
			(tracks not_allowed)
			(vias allowed)
			(pads allowed)
			(copperpour not_allowed)
			(footprints allowed)
		)
		(placement
			(enabled no)
			(sheetname "")
		)
		(fill yes
			(thermal_gap 0.5)
			(thermal_bridge_width 0.5)
			(island_removal_mode 0)
		)
		(polygon
			(pts
				(arc
					(start 297.764454 -384.35026)
					(mid 297.096434 -384.35026)
					(end 297.764454 -384.35026)
				)
			)
		)
	)
	(zone
		(layers "B.Cu" "In11.Cu" "In13.Cu" "In15.Cu")
		(hatch none 0.5)
		(connect_pads
			(clearance 0)
		)
		(min_thickness 0.25)
		(keepout
			(tracks not_allowed)
			(vias allowed)
			(pads allowed)
			(copperpour not_allowed)
			(footprints allowed)
		)
		(placement
			(enabled no)
			(sheetname "")
		)
		(fill yes
			(thermal_gap 0.5)
			(thermal_bridge_width 0.5)
			(island_removal_mode 0)
		)
		(polygon
			(pts
				(arc
					(start 63.036958 -427.289976)
					(mid 62.262766 -427.289976)
					(end 63.036958 -427.289976)
				)
			)
		)
	)
	(zone
		(layers "B.Cu" "In11.Cu" "In13.Cu" "In15.Cu")
		(hatch none 0.5)
		(connect_pads
			(clearance 0)
		)
		(min_thickness 0.25)
		(keepout
			(tracks not_allowed)
			(vias allowed)
			(pads allowed)
			(copperpour not_allowed)
			(footprints allowed)
		)
		(placement
			(enabled no)
			(sheetname "")
		)
		(fill yes
			(thermal_gap 0.5)
			(thermal_bridge_width 0.5)
			(island_removal_mode 0)
		)
		(polygon
			(pts
				(arc
					(start 81.376012 -263.556242)
					(mid 80.746092 -263.556242)
					(end 81.376012 -263.556242)
				)
			)
		)
	)
	(zone
		(layers "B.Cu" "In11.Cu" "In13.Cu" "In15.Cu")
		(hatch none 0.5)
		(connect_pads
			(clearance 0)
		)
		(min_thickness 0.25)
		(keepout
			(tracks not_allowed)
			(vias allowed)
			(pads allowed)
			(copperpour not_allowed)
			(footprints allowed)
		)
		(placement
			(enabled no)
			(sheetname "")
		)
		(fill yes
			(thermal_gap 0.5)
			(thermal_bridge_width 0.5)
			(island_removal_mode 0)
		)
		(polygon
			(pts
				(arc
					(start 123.669806 -286.23641)
					(mid 123.039886 -286.23641)
					(end 123.669806 -286.23641)
				)
			)
		)
	)
	(zone
		(layers "B.Cu" "In11.Cu" "In13.Cu" "In15.Cu")
		(hatch none 0.5)
		(connect_pads
			(clearance 0)
		)
		(min_thickness 0.25)
		(keepout
			(tracks not_allowed)
			(vias allowed)
			(pads allowed)
			(copperpour not_allowed)
			(footprints allowed)
		)
		(placement
			(enabled no)
			(sheetname "")
		)
		(fill yes
			(thermal_gap 0.5)
			(thermal_bridge_width 0.5)
			(island_removal_mode 0)
		)
		(polygon
			(pts
				(arc
					(start 413.333946 -393.69238)
					(mid 412.704026 -393.69238)
					(end 413.333946 -393.69238)
				)
			)
		)
	)
	(zone
		(layers "B.Cu" "In11.Cu" "In13.Cu" "In15.Cu")
		(hatch none 0.5)
		(connect_pads
			(clearance 0)
		)
		(min_thickness 0.25)
		(keepout
			(tracks not_allowed)
			(vias allowed)
			(pads allowed)
			(copperpour not_allowed)
			(footprints allowed)
		)
		(placement
			(enabled no)
			(sheetname "")
		)
		(fill yes
			(thermal_gap 0.5)
			(thermal_bridge_width 0.5)
			(island_removal_mode 0)
		)
		(polygon
			(pts
				(arc
					(start 199.03821 -273.835368)
					(mid 198.37019 -273.835368)
					(end 199.03821 -273.835368)
				)
			)
		)
	)
	(zone
		(layers "B.Cu" "In11.Cu" "In13.Cu" "In15.Cu")
		(hatch none 0.5)
		(connect_pads
			(clearance 0)
		)
		(min_thickness 0.25)
		(keepout
			(tracks not_allowed)
			(vias allowed)
			(pads allowed)
			(copperpour not_allowed)
			(footprints allowed)
		)
		(placement
			(enabled no)
			(sheetname "")
		)
		(fill yes
			(thermal_gap 0.5)
			(thermal_bridge_width 0.5)
			(island_removal_mode 0)
		)
		(polygon
			(pts
				(arc
					(start 82.485992 -225.854514)
					(mid 81.856072 -225.854514)
					(end 82.485992 -225.854514)
				)
			)
		)
	)
	(zone
		(layers "B.Cu" "In11.Cu" "In13.Cu" "In15.Cu")
		(hatch none 0.5)
		(connect_pads
			(clearance 0)
		)
		(min_thickness 0.25)
		(keepout
			(tracks not_allowed)
			(vias allowed)
			(pads allowed)
			(copperpour not_allowed)
			(footprints allowed)
		)
		(placement
			(enabled no)
			(sheetname "")
		)
		(fill yes
			(thermal_gap 0.5)
			(thermal_bridge_width 0.5)
			(island_removal_mode 0)
		)
		(polygon
			(pts
				(arc
					(start 329.31608 -291.095938)
					(mid 328.68616 -291.095938)
					(end 329.31608 -291.095938)
				)
			)
		)
	)
	(zone
		(layers "B.Cu" "In11.Cu" "In13.Cu" "In15.Cu")
		(hatch none 0.5)
		(connect_pads
			(clearance 0)
		)
		(min_thickness 0.25)
		(keepout
			(tracks not_allowed)
			(vias allowed)
			(pads allowed)
			(copperpour not_allowed)
			(footprints allowed)
		)
		(placement
			(enabled no)
			(sheetname "")
		)
		(fill yes
			(thermal_gap 0.5)
			(thermal_bridge_width 0.5)
			(island_removal_mode 0)
		)
		(polygon
			(pts
				(arc
					(start 142.93977 -264.366248)
					(mid 142.30985 -264.366248)
					(end 142.93977 -264.366248)
				)
			)
		)
	)
	(zone
		(layers "B.Cu" "In11.Cu" "In13.Cu" "In15.Cu")
		(hatch none 0.5)
		(connect_pads
			(clearance 0)
		)
		(min_thickness 0.25)
		(keepout
			(tracks not_allowed)
			(vias allowed)
			(pads allowed)
			(copperpour not_allowed)
			(footprints allowed)
		)
		(placement
			(enabled no)
			(sheetname "")
		)
		(fill yes
			(thermal_gap 0.5)
			(thermal_bridge_width 0.5)
			(island_removal_mode 0)
		)
		(polygon
			(pts
				(arc
					(start 389.63981 -225.85426)
					(mid 389.00989 -225.85426)
					(end 389.63981 -225.85426)
				)
			)
		)
	)
	(zone
		(layers "B.Cu" "In11.Cu" "In13.Cu" "In15.Cu")
		(hatch none 0.5)
		(connect_pads
			(clearance 0)
		)
		(min_thickness 0.25)
		(keepout
			(tracks not_allowed)
			(vias allowed)
			(pads allowed)
			(copperpour not_allowed)
			(footprints allowed)
		)
		(placement
			(enabled no)
			(sheetname "")
		)
		(fill yes
			(thermal_gap 0.5)
			(thermal_bridge_width 0.5)
			(island_removal_mode 0)
		)
		(polygon
			(pts
				(arc
					(start 117.089682 -282.996386)
					(mid 116.459762 -282.996386)
					(end 117.089682 -282.996386)
				)
			)
		)
	)
	(zone
		(layers "B.Cu" "In11.Cu" "In13.Cu" "In15.Cu")
		(hatch none 0.5)
		(connect_pads
			(clearance 0)
		)
		(min_thickness 0.25)
		(keepout
			(tracks not_allowed)
			(vias allowed)
			(pads allowed)
			(copperpour not_allowed)
			(footprints allowed)
		)
		(placement
			(enabled no)
			(sheetname "")
		)
		(fill yes
			(thermal_gap 0.5)
			(thermal_bridge_width 0.5)
			(island_removal_mode 0)
		)
		(polygon
			(pts
				(arc
					(start 141.999716 -278.946356)
					(mid 141.369796 -278.946356)
					(end 141.999716 -278.946356)
				)
			)
		)
	)
	(zone
		(layers "B.Cu" "In11.Cu" "In13.Cu" "In15.Cu")
		(hatch none 0.5)
		(connect_pads
			(clearance 0)
		)
		(min_thickness 0.25)
		(keepout
			(tracks not_allowed)
			(vias allowed)
			(pads allowed)
			(copperpour not_allowed)
			(footprints allowed)
		)
		(placement
			(enabled no)
			(sheetname "")
		)
		(fill yes
			(thermal_gap 0.5)
			(thermal_bridge_width 0.5)
			(island_removal_mode 0)
		)
		(polygon
			(pts
				(arc
					(start 416.933888 -393.69238)
					(mid 416.303968 -393.69238)
					(end 416.933888 -393.69238)
				)
			)
		)
	)
	(zone
		(layers "B.Cu" "In11.Cu" "In13.Cu" "In15.Cu")
		(hatch none 0.5)
		(connect_pads
			(clearance 0)
		)
		(min_thickness 0.25)
		(keepout
			(tracks not_allowed)
			(vias allowed)
			(pads allowed)
			(copperpour not_allowed)
			(footprints allowed)
		)
		(placement
			(enabled no)
			(sheetname "")
		)
		(fill yes
			(thermal_gap 0.5)
			(thermal_bridge_width 0.5)
			(island_removal_mode 0)
		)
		(polygon
			(pts
				(arc
					(start 319.770506 -379.88113)
					(mid 319.102486 -379.88113)
					(end 319.770506 -379.88113)
				)
			)
		)
	)
	(zone
		(layers "B.Cu" "In11.Cu" "In13.Cu" "In15.Cu")
		(hatch none 0.5)
		(connect_pads
			(clearance 0)
		)
		(min_thickness 0.25)
		(keepout
			(tracks not_allowed)
			(vias allowed)
			(pads allowed)
			(copperpour not_allowed)
			(footprints allowed)
		)
		(placement
			(enabled no)
			(sheetname "")
		)
		(fill yes
			(thermal_gap 0.5)
			(thermal_bridge_width 0.5)
			(island_removal_mode 0)
		)
		(polygon
			(pts
				(arc
					(start 194.938142 -288.285428)
					(mid 194.270122 -288.285428)
					(end 194.938142 -288.285428)
				)
			)
		)
	)
	(zone
		(layers "B.Cu" "In11.Cu" "In13.Cu" "In15.Cu")
		(hatch none 0.5)
		(connect_pads
			(clearance 0)
		)
		(min_thickness 0.25)
		(keepout
			(tracks not_allowed)
			(vias allowed)
			(pads allowed)
			(copperpour not_allowed)
			(footprints allowed)
		)
		(placement
			(enabled no)
			(sheetname "")
		)
		(fill yes
			(thermal_gap 0.5)
			(thermal_bridge_width 0.5)
			(island_removal_mode 0)
		)
		(polygon
			(pts
				(arc
					(start 329.31608 -265.176)
					(mid 328.68616 -265.176)
					(end 329.31608 -265.176)
				)
			)
		)
	)
	(zone
		(layers "B.Cu" "In11.Cu" "In13.Cu" "In15.Cu")
		(hatch none 0.5)
		(connect_pads
			(clearance 0)
		)
		(min_thickness 0.25)
		(keepout
			(tracks not_allowed)
			(vias allowed)
			(pads allowed)
			(copperpour not_allowed)
			(footprints allowed)
		)
		(placement
			(enabled no)
			(sheetname "")
		)
		(fill yes
			(thermal_gap 0.5)
			(thermal_bridge_width 0.5)
			(island_removal_mode 0)
		)
		(polygon
			(pts
				(arc
					(start 143.40967 -284.616398)
					(mid 142.77975 -284.616398)
					(end 143.40967 -284.616398)
				)
			)
		)
	)
	(zone
		(layers "B.Cu" "In11.Cu" "In13.Cu" "In15.Cu")
		(hatch none 0.5)
		(connect_pads
			(clearance 0)
		)
		(min_thickness 0.25)
		(keepout
			(tracks not_allowed)
			(vias allowed)
			(pads allowed)
			(copperpour not_allowed)
			(footprints allowed)
		)
		(placement
			(enabled no)
			(sheetname "")
		)
		(fill yes
			(thermal_gap 0.5)
			(thermal_bridge_width 0.5)
			(island_removal_mode 0)
		)
		(polygon
			(pts
				(arc
					(start 194.938142 -232.18521)
					(mid 194.270122 -232.18521)
					(end 194.938142 -232.18521)
				)
			)
		)
	)
	(zone
		(layers "B.Cu" "In11.Cu" "In13.Cu" "In15.Cu")
		(hatch none 0.5)
		(connect_pads
			(clearance 0)
		)
		(min_thickness 0.25)
		(keepout
			(tracks not_allowed)
			(vias allowed)
			(pads allowed)
			(copperpour not_allowed)
			(footprints allowed)
		)
		(placement
			(enabled no)
			(sheetname "")
		)
		(fill yes
			(thermal_gap 0.5)
			(thermal_bridge_width 0.5)
			(island_removal_mode 0)
		)
		(polygon
			(pts
				(arc
					(start 349.033846 -397.849344)
					(mid 348.403926 -397.849344)
					(end 349.033846 -397.849344)
				)
			)
		)
	)
	(zone
		(layers "B.Cu" "In11.Cu" "In13.Cu" "In15.Cu")
		(hatch none 0.5)
		(connect_pads
			(clearance 0)
		)
		(min_thickness 0.25)
		(keepout
			(tracks not_allowed)
			(vias allowed)
			(pads allowed)
			(copperpour not_allowed)
			(footprints allowed)
		)
		(placement
			(enabled no)
			(sheetname "")
		)
		(fill yes
			(thermal_gap 0.5)
			(thermal_bridge_width 0.5)
			(island_removal_mode 0)
		)
		(polygon
			(pts
				(arc
					(start 101.11613 -286.23641)
					(mid 100.48621 -286.23641)
					(end 101.11613 -286.23641)
				)
			)
		)
	)
	(zone
		(layers "B.Cu" "In11.Cu" "In13.Cu" "In15.Cu")
		(hatch none 0.5)
		(connect_pads
			(clearance 0)
		)
		(min_thickness 0.25)
		(keepout
			(tracks not_allowed)
			(vias allowed)
			(pads allowed)
			(copperpour not_allowed)
			(footprints allowed)
		)
		(placement
			(enabled no)
			(sheetname "")
		)
		(fill yes
			(thermal_gap 0.5)
			(thermal_bridge_width 0.5)
			(island_removal_mode 0)
		)
		(polygon
			(pts
				(arc
					(start 199.03821 -283.185362)
					(mid 198.37019 -283.185362)
					(end 199.03821 -283.185362)
				)
			)
		)
	)
	(zone
		(layers "B.Cu" "In11.Cu" "In13.Cu" "In15.Cu")
		(hatch none 0.5)
		(connect_pads
			(clearance 0)
		)
		(min_thickness 0.25)
		(keepout
			(tracks not_allowed)
			(vias allowed)
			(pads allowed)
			(copperpour not_allowed)
			(footprints allowed)
		)
		(placement
			(enabled no)
			(sheetname "")
		)
		(fill yes
			(thermal_gap 0.5)
			(thermal_bridge_width 0.5)
			(island_removal_mode 0)
		)
		(polygon
			(pts
				(arc
					(start 82.485992 -246.914416)
					(mid 81.856072 -246.914416)
					(end 82.485992 -246.914416)
				)
			)
		)
	)
	(zone
		(layers "B.Cu" "In11.Cu" "In13.Cu" "In15.Cu")
		(hatch none 0.5)
		(connect_pads
			(clearance 0)
		)
		(min_thickness 0.25)
		(keepout
			(tracks not_allowed)
			(vias allowed)
			(pads allowed)
			(copperpour not_allowed)
			(footprints allowed)
		)
		(placement
			(enabled no)
			(sheetname "")
		)
		(fill yes
			(thermal_gap 0.5)
			(thermal_bridge_width 0.5)
			(island_removal_mode 0)
		)
		(polygon
			(pts
				(arc
					(start 273.426174 -218.585034)
					(mid 272.758154 -218.585034)
					(end 273.426174 -218.585034)
				)
			)
		)
	)
	(zone
		(layers "B.Cu" "In11.Cu" "In13.Cu" "In15.Cu")
		(hatch none 0.5)
		(connect_pads
			(clearance 0)
		)
		(min_thickness 0.25)
		(keepout
			(tracks not_allowed)
			(vias allowed)
			(pads allowed)
			(copperpour not_allowed)
			(footprints allowed)
		)
		(placement
			(enabled no)
			(sheetname "")
		)
		(fill yes
			(thermal_gap 0.5)
			(thermal_bridge_width 0.5)
			(island_removal_mode 0)
		)
		(polygon
			(pts
				(arc
					(start 64.634364 -371.49913)
					(mid 63.966344 -371.49913)
					(end 64.634364 -371.49913)
				)
			)
		)
	)
	(zone
		(layers "B.Cu" "In11.Cu" "In13.Cu" "In15.Cu")
		(hatch none 0.5)
		(connect_pads
			(clearance 0)
		)
		(min_thickness 0.25)
		(keepout
			(tracks not_allowed)
			(vias allowed)
			(pads allowed)
			(copperpour not_allowed)
			(footprints allowed)
		)
		(placement
			(enabled no)
			(sheetname "")
		)
		(fill yes
			(thermal_gap 0.5)
			(thermal_bridge_width 0.5)
			(island_removal_mode 0)
		)
		(polygon
			(pts
				(arc
					(start 370.66982 -281.37612)
					(mid 370.0399 -281.37612)
					(end 370.66982 -281.37612)
				)
			)
		)
	)
	(zone
		(layers "B.Cu" "In11.Cu" "In13.Cu" "In15.Cu")
		(hatch none 0.5)
		(connect_pads
			(clearance 0)
		)
		(min_thickness 0.25)
		(keepout
			(tracks not_allowed)
			(vias allowed)
			(pads allowed)
			(copperpour not_allowed)
			(footprints allowed)
		)
		(placement
			(enabled no)
			(sheetname "")
		)
		(fill yes
			(thermal_gap 0.5)
			(thermal_bridge_width 0.5)
			(island_removal_mode 0)
		)
		(polygon
			(pts
				(arc
					(start 25.486106 -220.28531)
					(mid 24.818086 -220.28531)
					(end 25.486106 -220.28531)
				)
			)
		)
	)
	(zone
		(layers "B.Cu" "In11.Cu" "In13.Cu" "In15.Cu")
		(hatch none 0.5)
		(connect_pads
			(clearance 0)
		)
		(min_thickness 0.25)
		(keepout
			(tracks not_allowed)
			(vias allowed)
			(pads allowed)
			(copperpour not_allowed)
			(footprints allowed)
		)
		(placement
			(enabled no)
			(sheetname "")
		)
		(fill yes
			(thermal_gap 0.5)
			(thermal_bridge_width 0.5)
			(island_removal_mode 0)
		)
		(polygon
			(pts
				(arc
					(start 389.16991 -255.824228)
					(mid 388.53999 -255.824228)
					(end 389.16991 -255.824228)
				)
			)
		)
	)
	(zone
		(layers "B.Cu" "In11.Cu" "In13.Cu" "In15.Cu")
		(hatch none 0.5)
		(connect_pads
			(clearance 0)
		)
		(min_thickness 0.25)
		(keepout
			(tracks not_allowed)
			(vias allowed)
			(pads allowed)
			(copperpour not_allowed)
			(footprints allowed)
		)
		(placement
			(enabled no)
			(sheetname "")
		)
		(fill yes
			(thermal_gap 0.5)
			(thermal_bridge_width 0.5)
			(island_removal_mode 0)
		)
		(polygon
			(pts
				(arc
					(start 371.609874 -282.996132)
					(mid 370.979954 -282.996132)
					(end 371.609874 -282.996132)
				)
			)
		)
	)
	(zone
		(layers "B.Cu" "In11.Cu" "In13.Cu" "In15.Cu")
		(hatch none 0.5)
		(connect_pads
			(clearance 0)
		)
		(min_thickness 0.25)
		(keepout
			(tracks not_allowed)
			(vias allowed)
			(pads allowed)
			(copperpour not_allowed)
			(footprints allowed)
		)
		(placement
			(enabled no)
			(sheetname "")
		)
		(fill yes
			(thermal_gap 0.5)
			(thermal_bridge_width 0.5)
			(island_removal_mode 0)
		)
		(polygon
			(pts
				(arc
					(start 25.486106 -205.83525)
					(mid 24.818086 -205.83525)
					(end 25.486106 -205.83525)
				)
			)
		)
	)
	(zone
		(layers "B.Cu" "In11.Cu" "In13.Cu" "In15.Cu")
		(hatch none 0.5)
		(connect_pads
			(clearance 0)
		)
		(min_thickness 0.25)
		(keepout
			(tracks not_allowed)
			(vias allowed)
			(pads allowed)
			(copperpour not_allowed)
			(footprints allowed)
		)
		(placement
			(enabled no)
			(sheetname "")
		)
		(fill yes
			(thermal_gap 0.5)
			(thermal_bridge_width 0.5)
			(island_removal_mode 0)
		)
		(polygon
			(pts
				(arc
					(start 378.406152 -397.156432)
					(mid 377.776232 -397.156432)
					(end 378.406152 -397.156432)
				)
			)
		)
	)
	(zone
		(layers "B.Cu" "In11.Cu" "In13.Cu" "In15.Cu")
		(hatch none 0.5)
		(connect_pads
			(clearance 0)
		)
		(min_thickness 0.25)
		(keepout
			(tracks not_allowed)
			(vias allowed)
			(pads allowed)
			(copperpour not_allowed)
			(footprints allowed)
		)
		(placement
			(enabled no)
			(sheetname "")
		)
		(fill yes
			(thermal_gap 0.5)
			(thermal_bridge_width 0.5)
			(island_removal_mode 0)
		)
		(polygon
			(pts
				(arc
					(start 329.31608 -281.37612)
					(mid 328.68616 -281.37612)
					(end 329.31608 -281.37612)
				)
			)
		)
	)
	(zone
		(layers "B.Cu" "In11.Cu" "In13.Cu" "In15.Cu")
		(hatch none 0.5)
		(connect_pads
			(clearance 0)
		)
		(min_thickness 0.25)
		(keepout
			(tracks not_allowed)
			(vias allowed)
			(pads allowed)
			(copperpour not_allowed)
			(footprints allowed)
		)
		(placement
			(enabled no)
			(sheetname "")
		)
		(fill yes
			(thermal_gap 0.5)
			(thermal_bridge_width 0.5)
			(island_removal_mode 0)
		)
		(polygon
			(pts
				(arc
					(start 446.978278 -298.485052)
					(mid 446.310258 -298.485052)
					(end 446.978278 -298.485052)
				)
			)
		)
	)
	(zone
		(layers "B.Cu" "In11.Cu" "In13.Cu" "In15.Cu")
		(hatch none 0.5)
		(connect_pads
			(clearance 0)
		)
		(min_thickness 0.25)
		(keepout
			(tracks not_allowed)
			(vias allowed)
			(pads allowed)
			(copperpour not_allowed)
			(footprints allowed)
		)
		(placement
			(enabled no)
			(sheetname "")
		)
		(fill yes
			(thermal_gap 0.5)
			(thermal_bridge_width 0.5)
			(island_removal_mode 0)
		)
		(polygon
			(pts
				(arc
					(start 442.87821 -235.585)
					(mid 442.21019 -235.585)
					(end 442.87821 -235.585)
				)
			)
		)
	)
	(zone
		(layers "B.Cu" "In11.Cu" "In13.Cu" "In15.Cu")
		(hatch none 0.5)
		(connect_pads
			(clearance 0)
		)
		(min_thickness 0.25)
		(keepout
			(tracks not_allowed)
			(vias allowed)
			(pads allowed)
			(copperpour not_allowed)
			(footprints allowed)
		)
		(placement
			(enabled no)
			(sheetname "")
		)
		(fill yes
			(thermal_gap 0.5)
			(thermal_bridge_width 0.5)
			(island_removal_mode 0)
		)
		(polygon
			(pts
				(arc
					(start 405.137112 -428.28972)
					(mid 404.36292 -428.28972)
					(end 405.137112 -428.28972)
				)
			)
		)
	)
	(zone
		(layers "B.Cu" "In11.Cu" "In13.Cu" "In15.Cu")
		(hatch none 0.5)
		(connect_pads
			(clearance 0)
		)
		(min_thickness 0.25)
		(keepout
			(tracks not_allowed)
			(vias allowed)
			(pads allowed)
			(copperpour not_allowed)
			(footprints allowed)
		)
		(placement
			(enabled no)
			(sheetname "")
		)
		(fill yes
			(thermal_gap 0.5)
			(thermal_bridge_width 0.5)
			(island_removal_mode 0)
		)
		(polygon
			(pts
				(arc
					(start 330.89596 -249.34418)
					(mid 330.26604 -249.34418)
					(end 330.89596 -249.34418)
				)
			)
		)
	)
	(zone
		(layers "B.Cu" "In11.Cu" "In13.Cu" "In15.Cu")
		(hatch none 0.5)
		(connect_pads
			(clearance 0)
		)
		(min_thickness 0.25)
		(keepout
			(tracks not_allowed)
			(vias allowed)
			(pads allowed)
			(copperpour not_allowed)
			(footprints allowed)
		)
		(placement
			(enabled no)
			(sheetname "")
		)
		(fill yes
			(thermal_gap 0.5)
			(thermal_bridge_width 0.5)
			(island_removal_mode 0)
		)
		(polygon
			(pts
				(arc
					(start 52.906168 -388.774432)
					(mid 52.276248 -388.774432)
					(end 52.906168 -388.774432)
				)
			)
		)
	)
	(zone
		(layers "B.Cu" "In11.Cu" "In13.Cu" "In15.Cu")
		(hatch none 0.5)
		(connect_pads
			(clearance 0)
		)
		(min_thickness 0.25)
		(keepout
			(tracks not_allowed)
			(vias allowed)
			(pads allowed)
			(copperpour not_allowed)
			(footprints allowed)
		)
		(placement
			(enabled no)
			(sheetname "")
		)
		(fill yes
			(thermal_gap 0.5)
			(thermal_bridge_width 0.5)
			(island_removal_mode 0)
		)
		(polygon
			(pts
				(arc
					(start 81.545938 -229.094538)
					(mid 80.916018 -229.094538)
					(end 81.545938 -229.094538)
				)
			)
		)
	)
	(zone
		(layers "B.Cu" "In11.Cu" "In13.Cu" "In15.Cu")
		(hatch none 0.5)
		(connect_pads
			(clearance 0)
		)
		(min_thickness 0.25)
		(keepout
			(tracks not_allowed)
			(vias allowed)
			(pads allowed)
			(copperpour not_allowed)
			(footprints allowed)
		)
		(placement
			(enabled no)
			(sheetname "")
		)
		(fill yes
			(thermal_gap 0.5)
			(thermal_bridge_width 0.5)
			(island_removal_mode 0)
		)
		(polygon
			(pts
				(arc
					(start 391.049764 -255.824228)
					(mid 390.419844 -255.824228)
					(end 391.049764 -255.824228)
				)
			)
		)
	)
	(zone
		(layers "B.Cu" "In11.Cu" "In13.Cu" "In15.Cu")
		(hatch none 0.5)
		(connect_pads
			(clearance 0)
		)
		(min_thickness 0.25)
		(keepout
			(tracks not_allowed)
			(vias allowed)
			(pads allowed)
			(copperpour not_allowed)
			(footprints allowed)
		)
		(placement
			(enabled no)
			(sheetname "")
		)
		(fill yes
			(thermal_gap 0.5)
			(thermal_bridge_width 0.5)
			(island_removal_mode 0)
		)
		(polygon
			(pts
				(arc
					(start 94.82201 -211.276438)
					(mid 94.15399 -211.276438)
					(end 94.82201 -211.276438)
				)
			)
		)
	)
	(zone
		(layers "B.Cu" "In11.Cu" "In13.Cu" "In15.Cu")
		(hatch none 0.5)
		(connect_pads
			(clearance 0)
		)
		(min_thickness 0.25)
		(keepout
			(tracks not_allowed)
			(vias allowed)
			(pads allowed)
			(copperpour not_allowed)
			(footprints allowed)
		)
		(placement
			(enabled no)
			(sheetname "")
		)
		(fill yes
			(thermal_gap 0.5)
			(thermal_bridge_width 0.5)
			(island_removal_mode 0)
		)
		(polygon
			(pts
				(arc
					(start 442.87821 -313.784996)
					(mid 442.21019 -313.784996)
					(end 442.87821 -313.784996)
				)
			)
		)
	)
	(zone
		(layers "B.Cu" "In11.Cu" "In13.Cu" "In15.Cu")
		(hatch none 0.5)
		(connect_pads
			(clearance 0)
		)
		(min_thickness 0.25)
		(keepout
			(tracks not_allowed)
			(vias allowed)
			(pads allowed)
			(copperpour not_allowed)
			(footprints allowed)
		)
		(placement
			(enabled no)
			(sheetname "")
		)
		(fill yes
			(thermal_gap 0.5)
			(thermal_bridge_width 0.5)
			(island_removal_mode 0)
		)
		(polygon
			(pts
				(arc
					(start 331.195934 -282.996132)
					(mid 330.566014 -282.996132)
					(end 331.195934 -282.996132)
				)
			)
		)
	)
	(zone
		(layers "B.Cu" "In11.Cu" "In13.Cu" "In15.Cu")
		(hatch none 0.5)
		(connect_pads
			(clearance 0)
		)
		(min_thickness 0.25)
		(keepout
			(tracks not_allowed)
			(vias allowed)
			(pads allowed)
			(copperpour not_allowed)
			(footprints allowed)
		)
		(placement
			(enabled no)
			(sheetname "")
		)
		(fill yes
			(thermal_gap 0.5)
			(thermal_bridge_width 0.5)
			(island_removal_mode 0)
		)
		(polygon
			(pts
				(arc
					(start 29.586174 -200.735438)
					(mid 28.918154 -200.735438)
					(end 29.586174 -200.735438)
				)
			)
		)
	)
	(zone
		(layers "B.Cu" "In11.Cu" "In13.Cu" "In15.Cu")
		(hatch none 0.5)
		(connect_pads
			(clearance 0)
		)
		(min_thickness 0.25)
		(keepout
			(tracks not_allowed)
			(vias allowed)
			(pads allowed)
			(copperpour not_allowed)
			(footprints allowed)
		)
		(placement
			(enabled no)
			(sheetname "")
		)
		(fill yes
			(thermal_gap 0.5)
			(thermal_bridge_width 0.5)
			(island_removal_mode 0)
		)
		(polygon
			(pts
				(arc
					(start 329.31608 -273.27606)
					(mid 328.68616 -273.27606)
					(end 329.31608 -273.27606)
				)
			)
		)
	)
	(zone
		(layers "B.Cu" "In11.Cu" "In13.Cu" "In15.Cu")
		(hatch none 0.5)
		(connect_pads
			(clearance 0)
		)
		(min_thickness 0.25)
		(keepout
			(tracks not_allowed)
			(vias allowed)
			(pads allowed)
			(copperpour not_allowed)
			(footprints allowed)
		)
		(placement
			(enabled no)
			(sheetname "")
		)
		(fill yes
			(thermal_gap 0.5)
			(thermal_bridge_width 0.5)
			(island_removal_mode 0)
		)
		(polygon
			(pts
				(arc
					(start 29.586174 -197.335394)
					(mid 28.918154 -197.335394)
					(end 29.586174 -197.335394)
				)
			)
		)
	)
	(zone
		(layers "B.Cu" "In11.Cu" "In13.Cu" "In15.Cu")
		(hatch none 0.5)
		(connect_pads
			(clearance 0)
		)
		(min_thickness 0.25)
		(keepout
			(tracks not_allowed)
			(vias allowed)
			(pads allowed)
			(copperpour not_allowed)
			(footprints allowed)
		)
		(placement
			(enabled no)
			(sheetname "")
		)
		(fill yes
			(thermal_gap 0.5)
			(thermal_bridge_width 0.5)
			(island_removal_mode 0)
		)
		(polygon
			(pts
				(arc
					(start 25.486106 -306.985416)
					(mid 24.818086 -306.985416)
					(end 25.486106 -306.985416)
				)
			)
		)
	)
	(zone
		(layers "B.Cu" "In11.Cu" "In13.Cu" "In15.Cu")
		(hatch none 0.5)
		(connect_pads
			(clearance 0)
		)
		(min_thickness 0.25)
		(keepout
			(tracks not_allowed)
			(vias allowed)
			(pads allowed)
			(copperpour not_allowed)
			(footprints allowed)
		)
		(placement
			(enabled no)
			(sheetname "")
		)
		(fill yes
			(thermal_gap 0.5)
			(thermal_bridge_width 0.5)
			(island_removal_mode 0)
		)
		(polygon
			(pts
				(arc
					(start 153.734008 -385.31038)
					(mid 153.104088 -385.31038)
					(end 153.734008 -385.31038)
				)
			)
		)
	)
	(zone
		(layers "B.Cu" "In11.Cu" "In13.Cu" "In15.Cu")
		(hatch none 0.5)
		(connect_pads
			(clearance 0)
		)
		(min_thickness 0.25)
		(keepout
			(tracks not_allowed)
			(vias allowed)
			(pads allowed)
			(copperpour not_allowed)
			(footprints allowed)
		)
		(placement
			(enabled no)
			(sheetname "")
		)
		(fill yes
			(thermal_gap 0.5)
			(thermal_bridge_width 0.5)
			(island_removal_mode 0)
		)
		(polygon
			(pts
				(arc
					(start 121.20626 -388.774432)
					(mid 120.57634 -388.774432)
					(end 121.20626 -388.774432)
				)
			)
		)
	)
	(zone
		(layers "B.Cu" "In11.Cu" "In13.Cu" "In15.Cu")
		(hatch none 0.5)
		(connect_pads
			(clearance 0)
		)
		(min_thickness 0.25)
		(keepout
			(tracks not_allowed)
			(vias allowed)
			(pads allowed)
			(copperpour not_allowed)
			(footprints allowed)
		)
		(placement
			(enabled no)
			(sheetname "")
		)
		(fill yes
			(thermal_gap 0.5)
			(thermal_bridge_width 0.5)
			(island_removal_mode 0)
		)
		(polygon
			(pts
				(arc
					(start 330.89596 -241.24412)
					(mid 330.26604 -241.24412)
					(end 330.89596 -241.24412)
				)
			)
		)
	)
	(zone
		(layers "B.Cu" "In11.Cu" "In13.Cu" "In15.Cu")
		(hatch none 0.5)
		(connect_pads
			(clearance 0)
		)
		(min_thickness 0.25)
		(keepout
			(tracks not_allowed)
			(vias allowed)
			(pads allowed)
			(copperpour not_allowed)
			(footprints allowed)
		)
		(placement
			(enabled no)
			(sheetname "")
		)
		(fill yes
			(thermal_gap 0.5)
			(thermal_bridge_width 0.5)
			(island_removal_mode 0)
		)
		(polygon
			(pts
				(arc
					(start 143.109696 -238.00435)
					(mid 142.479776 -238.00435)
					(end 143.109696 -238.00435)
				)
			)
		)
	)
	(zone
		(layers "B.Cu" "In11.Cu" "In13.Cu" "In15.Cu")
		(hatch none 0.5)
		(connect_pads
			(clearance 0)
		)
		(min_thickness 0.25)
		(keepout
			(tracks not_allowed)
			(vias allowed)
			(pads allowed)
			(copperpour not_allowed)
			(footprints allowed)
		)
		(placement
			(enabled no)
			(sheetname "")
		)
		(fill yes
			(thermal_gap 0.5)
			(thermal_bridge_width 0.5)
			(island_removal_mode 0)
		)
		(polygon
			(pts
				(arc
					(start 82.955892 -244.484398)
					(mid 82.325972 -244.484398)
					(end 82.955892 -244.484398)
				)
			)
		)
	)
	(zone
		(layers "B.Cu" "In11.Cu" "In13.Cu" "In15.Cu")
		(hatch none 0.5)
		(connect_pads
			(clearance 0)
		)
		(min_thickness 0.25)
		(keepout
			(tracks not_allowed)
			(vias allowed)
			(pads allowed)
			(copperpour not_allowed)
			(footprints allowed)
		)
		(placement
			(enabled no)
			(sheetname "")
		)
		(fill yes
			(thermal_gap 0.5)
			(thermal_bridge_width 0.5)
			(island_removal_mode 0)
		)
		(polygon
			(pts
				(arc
					(start 109.105954 -285.426404)
					(mid 108.476034 -285.426404)
					(end 109.105954 -285.426404)
				)
			)
		)
	)
	(zone
		(layers "B.Cu" "In11.Cu" "In13.Cu" "In15.Cu")
		(hatch none 0.5)
		(connect_pads
			(clearance 0)
		)
		(min_thickness 0.25)
		(keepout
			(tracks not_allowed)
			(vias allowed)
			(pads allowed)
			(copperpour not_allowed)
			(footprints allowed)
		)
		(placement
			(enabled no)
			(sheetname "")
		)
		(fill yes
			(thermal_gap 0.5)
			(thermal_bridge_width 0.5)
			(island_removal_mode 0)
		)
		(polygon
			(pts
				(arc
					(start 81.845912 -272.466308)
					(mid 81.215992 -272.466308)
					(end 81.845912 -272.466308)
				)
			)
		)
	)
	(zone
		(layers "B.Cu" "In11.Cu" "In13.Cu" "In15.Cu")
		(hatch none 0.5)
		(connect_pads
			(clearance 0)
		)
		(min_thickness 0.25)
		(keepout
			(tracks not_allowed)
			(vias allowed)
			(pads allowed)
			(copperpour not_allowed)
			(footprints allowed)
		)
		(placement
			(enabled no)
			(sheetname "")
		)
		(fill yes
			(thermal_gap 0.5)
			(thermal_bridge_width 0.5)
			(island_removal_mode 0)
		)
		(polygon
			(pts
				(arc
					(start 25.486106 -253.435358)
					(mid 24.818086 -253.435358)
					(end 25.486106 -253.435358)
				)
			)
		)
	)
	(zone
		(layers "B.Cu" "In11.Cu" "In13.Cu" "In15.Cu")
		(hatch none 0.5)
		(connect_pads
			(clearance 0)
		)
		(min_thickness 0.25)
		(keepout
			(tracks not_allowed)
			(vias allowed)
			(pads allowed)
			(copperpour not_allowed)
			(footprints allowed)
		)
		(placement
			(enabled no)
			(sheetname "")
		)
		(fill yes
			(thermal_gap 0.5)
			(thermal_bridge_width 0.5)
			(island_removal_mode 0)
		)
		(polygon
			(pts
				(arc
					(start 81.376012 -292.716204)
					(mid 80.746092 -292.716204)
					(end 81.376012 -292.716204)
				)
			)
		)
	)
	(zone
		(layers "B.Cu" "In11.Cu" "In13.Cu" "In15.Cu")
		(hatch none 0.5)
		(connect_pads
			(clearance 0)
		)
		(min_thickness 0.25)
		(keepout
			(tracks not_allowed)
			(vias allowed)
			(pads allowed)
			(copperpour not_allowed)
			(footprints allowed)
		)
		(placement
			(enabled no)
			(sheetname "")
		)
		(fill yes
			(thermal_gap 0.5)
			(thermal_bridge_width 0.5)
			(island_removal_mode 0)
		)
		(polygon
			(pts
				(arc
					(start 80.037178 -426.089826)
					(mid 79.262986 -426.089826)
					(end 80.037178 -426.089826)
				)
			)
		)
	)
	(zone
		(layers "B.Cu" "In11.Cu" "In13.Cu" "In15.Cu")
		(hatch none 0.5)
		(connect_pads
			(clearance 0)
		)
		(min_thickness 0.25)
		(keepout
			(tracks not_allowed)
			(vias allowed)
			(pads allowed)
			(copperpour not_allowed)
			(footprints allowed)
		)
		(placement
			(enabled no)
			(sheetname "")
		)
		(fill yes
			(thermal_gap 0.5)
			(thermal_bridge_width 0.5)
			(island_removal_mode 0)
		)
		(polygon
			(pts
				(arc
					(start 401.13712 -428.28972)
					(mid 400.362928 -428.28972)
					(end 401.13712 -428.28972)
				)
			)
		)
	)
	(zone
		(layers "B.Cu" "In11.Cu" "In13.Cu" "In15.Cu")
		(hatch none 0.5)
		(connect_pads
			(clearance 0)
		)
		(min_thickness 0.25)
		(keepout
			(tracks not_allowed)
			(vias allowed)
			(pads allowed)
			(copperpour not_allowed)
			(footprints allowed)
		)
		(placement
			(enabled no)
			(sheetname "")
		)
		(fill yes
			(thermal_gap 0.5)
			(thermal_bridge_width 0.5)
			(island_removal_mode 0)
		)
		(polygon
			(pts
				(arc
					(start 50.506376 -388.774432)
					(mid 49.876456 -388.774432)
					(end 50.506376 -388.774432)
				)
			)
		)
	)
	(zone
		(layers "B.Cu" "In11.Cu" "In13.Cu" "In15.Cu")
		(hatch none 0.5)
		(connect_pads
			(clearance 0)
		)
		(min_thickness 0.25)
		(keepout
			(tracks not_allowed)
			(vias allowed)
			(pads allowed)
			(copperpour not_allowed)
			(footprints allowed)
		)
		(placement
			(enabled no)
			(sheetname "")
		)
		(fill yes
			(thermal_gap 0.5)
			(thermal_bridge_width 0.5)
			(island_removal_mode 0)
		)
		(polygon
			(pts
				(arc
					(start 157.33395 -385.31038)
					(mid 156.70403 -385.31038)
					(end 157.33395 -385.31038)
				)
			)
		)
	)
	(zone
		(layers "B.Cu" "In11.Cu" "In13.Cu" "In15.Cu")
		(hatch none 0.5)
		(connect_pads
			(clearance 0)
		)
		(min_thickness 0.25)
		(keepout
			(tracks not_allowed)
			(vias allowed)
			(pads allowed)
			(copperpour not_allowed)
			(footprints allowed)
		)
		(placement
			(enabled no)
			(sheetname "")
		)
		(fill yes
			(thermal_gap 0.5)
			(thermal_bridge_width 0.5)
			(island_removal_mode 0)
		)
		(polygon
			(pts
				(arc
					(start 273.426174 -211.784946)
					(mid 272.758154 -211.784946)
					(end 273.426174 -211.784946)
				)
			)
		)
	)
	(zone
		(layers "B.Cu" "In11.Cu" "In13.Cu" "In15.Cu")
		(hatch none 0.5)
		(connect_pads
			(clearance 0)
		)
		(min_thickness 0.25)
		(keepout
			(tracks not_allowed)
			(vias allowed)
			(pads allowed)
			(copperpour not_allowed)
			(footprints allowed)
		)
		(placement
			(enabled no)
			(sheetname "")
		)
		(fill yes
			(thermal_gap 0.5)
			(thermal_bridge_width 0.5)
			(island_removal_mode 0)
		)
		(polygon
			(pts
				(arc
					(start 98.295968 -282.996386)
					(mid 97.666048 -282.996386)
					(end 98.295968 -282.996386)
				)
			)
		)
	)
	(zone
		(layers "B.Cu" "In11.Cu" "In13.Cu" "In15.Cu")
		(hatch none 0.5)
		(connect_pads
			(clearance 0)
		)
		(min_thickness 0.25)
		(keepout
			(tracks not_allowed)
			(vias allowed)
			(pads allowed)
			(copperpour not_allowed)
			(footprints allowed)
		)
		(placement
			(enabled no)
			(sheetname "")
		)
		(fill yes
			(thermal_gap 0.5)
			(thermal_bridge_width 0.5)
			(island_removal_mode 0)
		)
		(polygon
			(pts
				(arc
					(start 82.955892 -226.66452)
					(mid 82.325972 -226.66452)
					(end 82.955892 -226.66452)
				)
			)
		)
	)
	(zone
		(layers "B.Cu" "In11.Cu" "In13.Cu" "In15.Cu")
		(hatch none 0.5)
		(connect_pads
			(clearance 0)
		)
		(min_thickness 0.25)
		(keepout
			(tracks not_allowed)
			(vias allowed)
			(pads allowed)
			(copperpour not_allowed)
			(footprints allowed)
		)
		(placement
			(enabled no)
			(sheetname "")
		)
		(fill yes
			(thermal_gap 0.5)
			(thermal_bridge_width 0.5)
			(island_removal_mode 0)
		)
		(polygon
			(pts
				(arc
					(start 329.016106 -252.584204)
					(mid 328.386186 -252.584204)
					(end 329.016106 -252.584204)
				)
			)
		)
	)
	(zone
		(layers "B.Cu" "In11.Cu" "In13.Cu" "In15.Cu")
		(hatch none 0.5)
		(connect_pads
			(clearance 0)
		)
		(min_thickness 0.25)
		(keepout
			(tracks not_allowed)
			(vias allowed)
			(pads allowed)
			(copperpour not_allowed)
			(footprints allowed)
		)
		(placement
			(enabled no)
			(sheetname "")
		)
		(fill yes
			(thermal_gap 0.5)
			(thermal_bridge_width 0.5)
			(island_removal_mode 0)
		)
		(polygon
			(pts
				(arc
					(start 408.533854 -393.69238)
					(mid 407.903934 -393.69238)
					(end 408.533854 -393.69238)
				)
			)
		)
	)
	(zone
		(layers "B.Cu" "In11.Cu" "In13.Cu" "In15.Cu")
		(hatch none 0.5)
		(connect_pads
			(clearance 0)
		)
		(min_thickness 0.25)
		(keepout
			(tracks not_allowed)
			(vias allowed)
			(pads allowed)
			(copperpour not_allowed)
			(footprints allowed)
		)
		(placement
			(enabled no)
			(sheetname "")
		)
		(fill yes
			(thermal_gap 0.5)
			(thermal_bridge_width 0.5)
			(island_removal_mode 0)
		)
		(polygon
			(pts
				(arc
					(start 194.938142 -272.98523)
					(mid 194.270122 -272.98523)
					(end 194.938142 -272.98523)
				)
			)
		)
	)
	(zone
		(layers "B.Cu" "In11.Cu" "In13.Cu" "In15.Cu")
		(hatch none 0.5)
		(connect_pads
			(clearance 0)
		)
		(min_thickness 0.25)
		(keepout
			(tracks not_allowed)
			(vias allowed)
			(pads allowed)
			(copperpour not_allowed)
			(footprints allowed)
		)
		(placement
			(enabled no)
			(sheetname "")
		)
		(fill yes
			(thermal_gap 0.5)
			(thermal_bridge_width 0.5)
			(island_removal_mode 0)
		)
		(polygon
			(pts
				(arc
					(start 389.939784 -274.086066)
					(mid 389.309864 -274.086066)
					(end 389.939784 -274.086066)
				)
			)
		)
	)
	(zone
		(layers "B.Cu" "In11.Cu" "In13.Cu" "In15.Cu")
		(hatch none 0.5)
		(connect_pads
			(clearance 0)
		)
		(min_thickness 0.25)
		(keepout
			(tracks not_allowed)
			(vias allowed)
			(pads allowed)
			(copperpour not_allowed)
			(footprints allowed)
		)
		(placement
			(enabled no)
			(sheetname "")
		)
		(fill yes
			(thermal_gap 0.5)
			(thermal_bridge_width 0.5)
			(island_removal_mode 0)
		)
		(polygon
			(pts
				(arc
					(start 346.6338 -397.849344)
					(mid 346.00388 -397.849344)
					(end 346.6338 -397.849344)
				)
			)
		)
	)
	(zone
		(layers "B.Cu" "In11.Cu" "In13.Cu" "In15.Cu")
		(hatch none 0.5)
		(connect_pads
			(clearance 0)
		)
		(min_thickness 0.25)
		(keepout
			(tracks not_allowed)
			(vias allowed)
			(pads allowed)
			(copperpour not_allowed)
			(footprints allowed)
		)
		(placement
			(enabled no)
			(sheetname "")
		)
		(fill yes
			(thermal_gap 0.5)
			(thermal_bridge_width 0.5)
			(island_removal_mode 0)
		)
		(polygon
			(pts
				(arc
					(start 411.33395 -394.385292)
					(mid 410.70403 -394.385292)
					(end 411.33395 -394.385292)
				)
			)
		)
	)
	(zone
		(layers "B.Cu" "In11.Cu" "In13.Cu" "In15.Cu")
		(hatch none 0.5)
		(connect_pads
			(clearance 0)
		)
		(min_thickness 0.25)
		(keepout
			(tracks not_allowed)
			(vias allowed)
			(pads allowed)
			(copperpour not_allowed)
			(footprints allowed)
		)
		(placement
			(enabled no)
			(sheetname "")
		)
		(fill yes
			(thermal_gap 0.5)
			(thermal_bridge_width 0.5)
			(island_removal_mode 0)
		)
		(polygon
			(pts
				(arc
					(start 391.049764 -236.384084)
					(mid 390.419844 -236.384084)
					(end 391.049764 -236.384084)
				)
			)
		)
	)
	(zone
		(layers "B.Cu" "In11.Cu" "In13.Cu" "In15.Cu")
		(hatch none 0.5)
		(connect_pads
			(clearance 0)
		)
		(min_thickness 0.25)
		(keepout
			(tracks not_allowed)
			(vias allowed)
			(pads allowed)
			(copperpour not_allowed)
			(footprints allowed)
		)
		(placement
			(enabled no)
			(sheetname "")
		)
		(fill yes
			(thermal_gap 0.5)
			(thermal_bridge_width 0.5)
			(island_removal_mode 0)
		)
		(polygon
			(pts
				(arc
					(start 422.13403 -394.385292)
					(mid 421.50411 -394.385292)
					(end 422.13403 -394.385292)
				)
			)
		)
	)
	(zone
		(layers "B.Cu" "In11.Cu" "In13.Cu" "In15.Cu")
		(hatch none 0.5)
		(connect_pads
			(clearance 0)
		)
		(min_thickness 0.25)
		(keepout
			(tracks not_allowed)
			(vias allowed)
			(pads allowed)
			(copperpour not_allowed)
			(footprints allowed)
		)
		(placement
			(enabled no)
			(sheetname "")
		)
		(fill yes
			(thermal_gap 0.5)
			(thermal_bridge_width 0.5)
			(island_removal_mode 0)
		)
		(polygon
			(pts
				(arc
					(start 345.43365 -397.849344)
					(mid 344.80373 -397.849344)
					(end 345.43365 -397.849344)
				)
			)
		)
	)
	(zone
		(layers "B.Cu" "In11.Cu" "In13.Cu" "In15.Cu")
		(hatch none 0.5)
		(connect_pads
			(clearance 0)
		)
		(min_thickness 0.25)
		(keepout
			(tracks not_allowed)
			(vias allowed)
			(pads allowed)
			(copperpour not_allowed)
			(footprints allowed)
		)
		(placement
			(enabled no)
			(sheetname "")
		)
		(fill yes
			(thermal_gap 0.5)
			(thermal_bridge_width 0.5)
			(island_removal_mode 0)
		)
		(polygon
			(pts
				(arc
					(start 277.526242 -247.485154)
					(mid 276.858222 -247.485154)
					(end 277.526242 -247.485154)
				)
			)
		)
	)
	(zone
		(layers "B.Cu" "In11.Cu" "In13.Cu" "In15.Cu")
		(hatch none 0.5)
		(connect_pads
			(clearance 0)
		)
		(min_thickness 0.25)
		(keepout
			(tracks not_allowed)
			(vias allowed)
			(pads allowed)
			(copperpour not_allowed)
			(footprints allowed)
		)
		(placement
			(enabled no)
			(sheetname "")
		)
		(fill yes
			(thermal_gap 0.5)
			(thermal_bridge_width 0.5)
			(island_removal_mode 0)
		)
		(polygon
			(pts
				(arc
					(start 82.785966 -265.98626)
					(mid 82.156046 -265.98626)
					(end 82.785966 -265.98626)
				)
			)
		)
	)
	(zone
		(layers "B.Cu" "In11.Cu" "In13.Cu" "In15.Cu")
		(hatch none 0.5)
		(connect_pads
			(clearance 0)
		)
		(min_thickness 0.25)
		(keepout
			(tracks not_allowed)
			(vias allowed)
			(pads allowed)
			(copperpour not_allowed)
			(footprints allowed)
		)
		(placement
			(enabled no)
			(sheetname "")
		)
		(fill yes
			(thermal_gap 0.5)
			(thermal_bridge_width 0.5)
			(island_removal_mode 0)
		)
		(polygon
			(pts
				(arc
					(start 103.936038 -286.23641)
					(mid 103.306118 -286.23641)
					(end 103.936038 -286.23641)
				)
			)
		)
	)
	(zone
		(layers "B.Cu" "In11.Cu" "In13.Cu" "In15.Cu")
		(hatch none 0.5)
		(connect_pads
			(clearance 0)
		)
		(min_thickness 0.25)
		(keepout
			(tracks not_allowed)
			(vias allowed)
			(pads allowed)
			(copperpour not_allowed)
			(footprints allowed)
		)
		(placement
			(enabled no)
			(sheetname "")
		)
		(fill yes
			(thermal_gap 0.5)
			(thermal_bridge_width 0.5)
			(island_removal_mode 0)
		)
		(polygon
			(pts
				(arc
					(start 122.406156 -388.774432)
					(mid 121.776236 -388.774432)
					(end 122.406156 -388.774432)
				)
			)
		)
	)
	(zone
		(layers "B.Cu" "In11.Cu" "In13.Cu" "In15.Cu")
		(hatch none 0.5)
		(connect_pads
			(clearance 0)
		)
		(min_thickness 0.25)
		(keepout
			(tracks not_allowed)
			(vias allowed)
			(pads allowed)
			(copperpour not_allowed)
			(footprints allowed)
		)
		(placement
			(enabled no)
			(sheetname "")
		)
		(fill yes
			(thermal_gap 0.5)
			(thermal_bridge_width 0.5)
			(island_removal_mode 0)
		)
		(polygon
			(pts
				(arc
					(start 194.938142 -293.38524)
					(mid 194.270122 -293.38524)
					(end 194.938142 -293.38524)
				)
			)
		)
	)
	(zone
		(layers "B.Cu" "In11.Cu" "In13.Cu" "In15.Cu")
		(hatch none 0.5)
		(connect_pads
			(clearance 0)
		)
		(min_thickness 0.25)
		(keepout
			(tracks not_allowed)
			(vias allowed)
			(pads allowed)
			(copperpour not_allowed)
			(footprints allowed)
		)
		(placement
			(enabled no)
			(sheetname "")
		)
		(fill yes
			(thermal_gap 0.5)
			(thermal_bridge_width 0.5)
			(island_removal_mode 0)
		)
		(polygon
			(pts
				(arc
					(start 331.195934 -261.935976)
					(mid 330.566014 -261.935976)
					(end 331.195934 -261.935976)
				)
			)
		)
	)
	(zone
		(layers "B.Cu" "In11.Cu" "In13.Cu" "In15.Cu")
		(hatch none 0.5)
		(connect_pads
			(clearance 0)
		)
		(min_thickness 0.25)
		(keepout
			(tracks not_allowed)
			(vias allowed)
			(pads allowed)
			(copperpour not_allowed)
			(footprints allowed)
		)
		(placement
			(enabled no)
			(sheetname "")
		)
		(fill yes
			(thermal_gap 0.5)
			(thermal_bridge_width 0.5)
			(island_removal_mode 0)
		)
		(polygon
			(pts
				(arc
					(start 25.486106 -198.185278)
					(mid 24.818086 -198.185278)
					(end 25.486106 -198.185278)
				)
			)
		)
	)
	(zone
		(layers "B.Cu" "In11.Cu" "In13.Cu" "In15.Cu")
		(hatch none 0.5)
		(connect_pads
			(clearance 0)
		)
		(min_thickness 0.25)
		(keepout
			(tracks not_allowed)
			(vias allowed)
			(pads allowed)
			(copperpour not_allowed)
			(footprints allowed)
		)
		(placement
			(enabled no)
			(sheetname "")
		)
		(fill yes
			(thermal_gap 0.5)
			(thermal_bridge_width 0.5)
			(island_removal_mode 0)
		)
		(polygon
			(pts
				(arc
					(start 442.87821 -198.185024)
					(mid 442.21019 -198.185024)
					(end 442.87821 -198.185024)
				)
			)
		)
	)
	(zone
		(layers "B.Cu" "In11.Cu" "In13.Cu" "In15.Cu")
		(hatch none 0.5)
		(connect_pads
			(clearance 0)
		)
		(min_thickness 0.25)
		(keepout
			(tracks not_allowed)
			(vias allowed)
			(pads allowed)
			(copperpour not_allowed)
			(footprints allowed)
		)
		(placement
			(enabled no)
			(sheetname "")
		)
		(fill yes
			(thermal_gap 0.5)
			(thermal_bridge_width 0.5)
			(island_removal_mode 0)
		)
		(polygon
			(pts
				(arc
					(start 389.939784 -270.846042)
					(mid 389.309864 -270.846042)
					(end 389.939784 -270.846042)
				)
			)
		)
	)
	(zone
		(layers "B.Cu" "In11.Cu" "In13.Cu" "In15.Cu")
		(hatch none 0.5)
		(connect_pads
			(clearance 0)
		)
		(min_thickness 0.25)
		(keepout
			(tracks not_allowed)
			(vias allowed)
			(pads allowed)
			(copperpour not_allowed)
			(footprints allowed)
		)
		(placement
			(enabled no)
			(sheetname "")
		)
		(fill yes
			(thermal_gap 0.5)
			(thermal_bridge_width 0.5)
			(island_removal_mode 0)
		)
		(polygon
			(pts
				(arc
					(start 141.529816 -289.47618)
					(mid 140.899896 -289.47618)
					(end 141.529816 -289.47618)
				)
			)
		)
	)
	(zone
		(layers "B.Cu" "In11.Cu" "In13.Cu" "In15.Cu")
		(hatch none 0.5)
		(connect_pads
			(clearance 0)
		)
		(min_thickness 0.25)
		(keepout
			(tracks not_allowed)
			(vias allowed)
			(pads allowed)
			(copperpour not_allowed)
			(footprints allowed)
		)
		(placement
			(enabled no)
			(sheetname "")
		)
		(fill yes
			(thermal_gap 0.5)
			(thermal_bridge_width 0.5)
			(island_removal_mode 0)
		)
		(polygon
			(pts
				(arc
					(start 81.545938 -225.854514)
					(mid 80.916018 -225.854514)
					(end 81.545938 -225.854514)
				)
			)
		)
	)
	(zone
		(layers "B.Cu" "In11.Cu" "In13.Cu" "In15.Cu")
		(hatch none 0.5)
		(connect_pads
			(clearance 0)
		)
		(min_thickness 0.25)
		(keepout
			(tracks not_allowed)
			(vias allowed)
			(pads allowed)
			(copperpour not_allowed)
			(footprints allowed)
		)
		(placement
			(enabled no)
			(sheetname "")
		)
		(fill yes
			(thermal_gap 0.5)
			(thermal_bridge_width 0.5)
			(island_removal_mode 0)
		)
		(polygon
			(pts
				(arc
					(start 277.526242 -276.38502)
					(mid 276.858222 -276.38502)
					(end 277.526242 -276.38502)
				)
			)
		)
	)
	(zone
		(layers "B.Cu" "In11.Cu" "In13.Cu" "In15.Cu")
		(hatch none 0.5)
		(connect_pads
			(clearance 0)
		)
		(min_thickness 0.25)
		(keepout
			(tracks not_allowed)
			(vias allowed)
			(pads allowed)
			(copperpour not_allowed)
			(footprints allowed)
		)
		(placement
			(enabled no)
			(sheetname "")
		)
		(fill yes
			(thermal_gap 0.5)
			(thermal_bridge_width 0.5)
			(island_removal_mode 0)
		)
		(polygon
			(pts
				(arc
					(start 91.013534 -404.46452)
					(mid 90.345514 -404.46452)
					(end 91.013534 -404.46452)
				)
			)
		)
	)
	(zone
		(layers "B.Cu" "In11.Cu" "In13.Cu" "In15.Cu")
		(hatch none 0.5)
		(connect_pads
			(clearance 0)
		)
		(min_thickness 0.25)
		(keepout
			(tracks not_allowed)
			(vias allowed)
			(pads allowed)
			(copperpour not_allowed)
			(footprints allowed)
		)
		(placement
			(enabled no)
			(sheetname "")
		)
		(fill yes
			(thermal_gap 0.5)
			(thermal_bridge_width 0.5)
			(island_removal_mode 0)
		)
		(polygon
			(pts
				(arc
					(start 321.036696 -427.089824)
					(mid 320.262504 -427.089824)
					(end 321.036696 -427.089824)
				)
			)
		)
	)
	(zone
		(layers "B.Cu" "In11.Cu" "In13.Cu" "In15.Cu")
		(hatch none 0.5)
		(connect_pads
			(clearance 0)
		)
		(min_thickness 0.25)
		(keepout
			(tracks not_allowed)
			(vias allowed)
			(pads allowed)
			(copperpour not_allowed)
			(footprints allowed)
		)
		(placement
			(enabled no)
			(sheetname "")
		)
		(fill yes
			(thermal_gap 0.5)
			(thermal_bridge_width 0.5)
			(island_removal_mode 0)
		)
		(polygon
			(pts
				(arc
					(start 141.999716 -285.426404)
					(mid 141.369796 -285.426404)
					(end 141.999716 -285.426404)
				)
			)
		)
	)
	(zone
		(layers "B.Cu" "In11.Cu" "In13.Cu" "In15.Cu")
		(hatch none 0.5)
		(connect_pads
			(clearance 0)
		)
		(min_thickness 0.25)
		(keepout
			(tracks not_allowed)
			(vias allowed)
			(pads allowed)
			(copperpour not_allowed)
			(footprints allowed)
		)
		(placement
			(enabled no)
			(sheetname "")
		)
		(fill yes
			(thermal_gap 0.5)
			(thermal_bridge_width 0.5)
			(island_removal_mode 0)
		)
		(polygon
			(pts
				(arc
					(start 297.764454 -390.75106)
					(mid 297.096434 -390.75106)
					(end 297.764454 -390.75106)
				)
			)
		)
	)
	(zone
		(layers "B.Cu" "In11.Cu" "In13.Cu" "In15.Cu")
		(hatch none 0.5)
		(connect_pads
			(clearance 0)
		)
		(min_thickness 0.25)
		(keepout
			(tracks not_allowed)
			(vias allowed)
			(pads allowed)
			(copperpour not_allowed)
			(footprints allowed)
		)
		(placement
			(enabled no)
			(sheetname "")
		)
		(fill yes
			(thermal_gap 0.5)
			(thermal_bridge_width 0.5)
			(island_removal_mode 0)
		)
		(polygon
			(pts
				(arc
					(start 134.05485 -24.76373)
					(mid 133.38683 -24.76373)
					(end 134.05485 -24.76373)
				)
			)
		)
	)
	(zone
		(layers "B.Cu" "In11.Cu" "In13.Cu" "In15.Cu")
		(hatch none 0.5)
		(connect_pads
			(clearance 0)
		)
		(min_thickness 0.25)
		(keepout
			(tracks not_allowed)
			(vias allowed)
			(pads allowed)
			(copperpour not_allowed)
			(footprints allowed)
		)
		(placement
			(enabled no)
			(sheetname "")
		)
		(fill yes
			(thermal_gap 0.5)
			(thermal_bridge_width 0.5)
			(island_removal_mode 0)
		)
		(polygon
			(pts
				(arc
					(start 25.486106 -280.635202)
					(mid 24.818086 -280.635202)
					(end 25.486106 -280.635202)
				)
			)
		)
	)
	(zone
		(layers "B.Cu" "In11.Cu" "In13.Cu" "In15.Cu")
		(hatch none 0.5)
		(connect_pads
			(clearance 0)
		)
		(min_thickness 0.25)
		(keepout
			(tracks not_allowed)
			(vias allowed)
			(pads allowed)
			(copperpour not_allowed)
			(footprints allowed)
		)
		(placement
			(enabled no)
			(sheetname "")
		)
		(fill yes
			(thermal_gap 0.5)
			(thermal_bridge_width 0.5)
			(island_removal_mode 0)
		)
		(polygon
			(pts
				(arc
					(start 330.726034 -262.745982)
					(mid 330.096114 -262.745982)
					(end 330.726034 -262.745982)
				)
			)
		)
	)
	(zone
		(layers "B.Cu" "In11.Cu" "In13.Cu" "In15.Cu")
		(hatch none 0.5)
		(connect_pads
			(clearance 0)
		)
		(min_thickness 0.25)
		(keepout
			(tracks not_allowed)
			(vias allowed)
			(pads allowed)
			(copperpour not_allowed)
			(footprints allowed)
		)
		(placement
			(enabled no)
			(sheetname "")
		)
		(fill yes
			(thermal_gap 0.5)
			(thermal_bridge_width 0.5)
			(island_removal_mode 0)
		)
		(polygon
			(pts
				(arc
					(start 442.87821 -288.285174)
					(mid 442.21019 -288.285174)
					(end 442.87821 -288.285174)
				)
			)
		)
	)
	(zone
		(layers "B.Cu" "In11.Cu" "In13.Cu" "In15.Cu")
		(hatch none 0.5)
		(connect_pads
			(clearance 0)
		)
		(min_thickness 0.25)
		(keepout
			(tracks not_allowed)
			(vias allowed)
			(pads allowed)
			(copperpour not_allowed)
			(footprints allowed)
		)
		(placement
			(enabled no)
			(sheetname "")
		)
		(fill yes
			(thermal_gap 0.5)
			(thermal_bridge_width 0.5)
			(island_removal_mode 0)
		)
		(polygon
			(pts
				(arc
					(start 273.426174 -224.534984)
					(mid 272.758154 -224.534984)
					(end 273.426174 -224.534984)
				)
			)
		)
	)
	(zone
		(layers "B.Cu" "In11.Cu" "In13.Cu" "In15.Cu")
		(hatch none 0.5)
		(connect_pads
			(clearance 0)
		)
		(min_thickness 0.25)
		(keepout
			(tracks not_allowed)
			(vias allowed)
			(pads allowed)
			(copperpour not_allowed)
			(footprints allowed)
		)
		(placement
			(enabled no)
			(sheetname "")
		)
		(fill yes
			(thermal_gap 0.5)
			(thermal_bridge_width 0.5)
			(island_removal_mode 0)
		)
		(polygon
			(pts
				(arc
					(start 29.586174 -208.38541)
					(mid 28.918154 -208.38541)
					(end 29.586174 -208.38541)
				)
			)
		)
	)
	(zone
		(layers "B.Cu" "In11.Cu" "In13.Cu" "In15.Cu")
		(hatch none 0.5)
		(connect_pads
			(clearance 0)
		)
		(min_thickness 0.25)
		(keepout
			(tracks not_allowed)
			(vias allowed)
			(pads allowed)
			(copperpour not_allowed)
			(footprints allowed)
		)
		(placement
			(enabled no)
			(sheetname "")
		)
		(fill yes
			(thermal_gap 0.5)
			(thermal_bridge_width 0.5)
			(island_removal_mode 0)
		)
		(polygon
			(pts
				(arc
					(start 277.526242 -272.135092)
					(mid 276.858222 -272.135092)
					(end 277.526242 -272.135092)
				)
			)
		)
	)
	(zone
		(layers "B.Cu" "In11.Cu" "In13.Cu" "In15.Cu")
		(hatch none 0.5)
		(connect_pads
			(clearance 0)
		)
		(min_thickness 0.25)
		(keepout
			(tracks not_allowed)
			(vias allowed)
			(pads allowed)
			(copperpour not_allowed)
			(footprints allowed)
		)
		(placement
			(enabled no)
			(sheetname "")
		)
		(fill yes
			(thermal_gap 0.5)
			(thermal_bridge_width 0.5)
			(island_removal_mode 0)
		)
		(polygon
			(pts
				(arc
					(start 385.60629 -397.156432)
					(mid 384.97637 -397.156432)
					(end 385.60629 -397.156432)
				)
			)
		)
	)
	(zone
		(layers "B.Cu" "In11.Cu" "In13.Cu" "In15.Cu")
		(hatch none 0.5)
		(connect_pads
			(clearance 0)
		)
		(min_thickness 0.25)
		(keepout
			(tracks not_allowed)
			(vias allowed)
			(pads allowed)
			(copperpour not_allowed)
			(footprints allowed)
		)
		(placement
			(enabled no)
			(sheetname "")
		)
		(fill yes
			(thermal_gap 0.5)
			(thermal_bridge_width 0.5)
			(island_removal_mode 0)
		)
		(polygon
			(pts
				(arc
					(start 82.955892 -239.624362)
					(mid 82.325972 -239.624362)
					(end 82.955892 -239.624362)
				)
			)
		)
	)
	(zone
		(layers "B.Cu" "In11.Cu" "In13.Cu" "In15.Cu")
		(hatch none 0.5)
		(connect_pads
			(clearance 0)
		)
		(min_thickness 0.25)
		(keepout
			(tracks not_allowed)
			(vias allowed)
			(pads allowed)
			(copperpour not_allowed)
			(footprints allowed)
		)
		(placement
			(enabled no)
			(sheetname "")
		)
		(fill yes
			(thermal_gap 0.5)
			(thermal_bridge_width 0.5)
			(island_removal_mode 0)
		)
		(polygon
			(pts
				(arc
					(start 442.87821 -265.335004)
					(mid 442.21019 -265.335004)
					(end 442.87821 -265.335004)
				)
			)
		)
	)
	(zone
		(layers "B.Cu" "In11.Cu" "In13.Cu" "In15.Cu")
		(hatch none 0.5)
		(connect_pads
			(clearance 0)
		)
		(min_thickness 0.25)
		(keepout
			(tracks not_allowed)
			(vias allowed)
			(pads allowed)
			(copperpour not_allowed)
			(footprints allowed)
		)
		(placement
			(enabled no)
			(sheetname "")
		)
		(fill yes
			(thermal_gap 0.5)
			(thermal_bridge_width 0.5)
			(island_removal_mode 0)
		)
		(polygon
			(pts
				(arc
					(start 126.136908 -427.289976)
					(mid 125.362716 -427.289976)
					(end 126.136908 -427.289976)
				)
			)
		)
	)
	(zone
		(layers "B.Cu" "In11.Cu" "In13.Cu" "In15.Cu")
		(hatch none 0.5)
		(connect_pads
			(clearance 0)
		)
		(min_thickness 0.25)
		(keepout
			(tracks not_allowed)
			(vias allowed)
			(pads allowed)
			(copperpour not_allowed)
			(footprints allowed)
		)
		(placement
			(enabled no)
			(sheetname "")
		)
		(fill yes
			(thermal_gap 0.5)
			(thermal_bridge_width 0.5)
			(island_removal_mode 0)
		)
		(polygon
			(pts
				(arc
					(start 352.81616 -286.236156)
					(mid 352.18624 -286.236156)
					(end 352.81616 -286.236156)
				)
			)
		)
	)
	(zone
		(layers "B.Cu" "In11.Cu" "In13.Cu" "In15.Cu")
		(hatch none 0.5)
		(connect_pads
			(clearance 0)
		)
		(min_thickness 0.25)
		(keepout
			(tracks not_allowed)
			(vias allowed)
			(pads allowed)
			(copperpour not_allowed)
			(footprints allowed)
		)
		(placement
			(enabled no)
			(sheetname "")
		)
		(fill yes
			(thermal_gap 0.5)
			(thermal_bridge_width 0.5)
			(island_removal_mode 0)
		)
		(polygon
			(pts
				(arc
					(start 277.526242 -221.985078)
					(mid 276.858222 -221.985078)
					(end 277.526242 -221.985078)
				)
			)
		)
	)
	(zone
		(layers "B.Cu" "In11.Cu" "In13.Cu" "In15.Cu")
		(hatch none 0.5)
		(connect_pads
			(clearance 0)
		)
		(min_thickness 0.25)
		(keepout
			(tracks not_allowed)
			(vias allowed)
			(pads allowed)
			(copperpour not_allowed)
			(footprints allowed)
		)
		(placement
			(enabled no)
			(sheetname "")
		)
		(fill yes
			(thermal_gap 0.5)
			(thermal_bridge_width 0.5)
			(island_removal_mode 0)
		)
		(polygon
			(pts
				(arc
					(start 273.426174 -318.035178)
					(mid 272.758154 -318.035178)
					(end 273.426174 -318.035178)
				)
			)
		)
	)
	(zone
		(layers "B.Cu" "In11.Cu" "In13.Cu" "In15.Cu")
		(hatch none 0.5)
		(connect_pads
			(clearance 0)
		)
		(min_thickness 0.25)
		(keepout
			(tracks not_allowed)
			(vias allowed)
			(pads allowed)
			(copperpour not_allowed)
			(footprints allowed)
		)
		(placement
			(enabled no)
			(sheetname "")
		)
		(fill yes
			(thermal_gap 0.5)
			(thermal_bridge_width 0.5)
			(island_removal_mode 0)
		)
		(polygon
			(pts
				(arc
					(start 373.606314 -397.156432)
					(mid 372.976394 -397.156432)
					(end 373.606314 -397.156432)
				)
			)
		)
	)
	(zone
		(layers "B.Cu" "In11.Cu" "In13.Cu" "In15.Cu")
		(hatch none 0.5)
		(connect_pads
			(clearance 0)
		)
		(min_thickness 0.25)
		(keepout
			(tracks not_allowed)
			(vias allowed)
			(pads allowed)
			(copperpour not_allowed)
			(footprints allowed)
		)
		(placement
			(enabled no)
			(sheetname "")
		)
		(fill yes
			(thermal_gap 0.5)
			(thermal_bridge_width 0.5)
			(island_removal_mode 0)
		)
		(polygon
			(pts
				(arc
					(start 199.03821 -216.035382)
					(mid 198.37019 -216.035382)
					(end 199.03821 -216.035382)
				)
			)
		)
	)
	(zone
		(layers "B.Cu" "In11.Cu" "In13.Cu" "In15.Cu")
		(hatch none 0.5)
		(connect_pads
			(clearance 0)
		)
		(min_thickness 0.25)
		(keepout
			(tracks not_allowed)
			(vias allowed)
			(pads allowed)
			(copperpour not_allowed)
			(footprints allowed)
		)
		(placement
			(enabled no)
			(sheetname "")
		)
		(fill yes
			(thermal_gap 0.5)
			(thermal_bridge_width 0.5)
			(island_removal_mode 0)
		)
		(polygon
			(pts
				(arc
					(start 25.486106 -213.485222)
					(mid 24.818086 -213.485222)
					(end 25.486106 -213.485222)
				)
			)
		)
	)
	(zone
		(layers "B.Cu" "In11.Cu" "In13.Cu" "In15.Cu")
		(hatch none 0.5)
		(connect_pads
			(clearance 0)
		)
		(min_thickness 0.25)
		(keepout
			(tracks not_allowed)
			(vias allowed)
			(pads allowed)
			(copperpour not_allowed)
			(footprints allowed)
		)
		(placement
			(enabled no)
			(sheetname "")
		)
		(fill yes
			(thermal_gap 0.5)
			(thermal_bridge_width 0.5)
			(island_removal_mode 0)
		)
		(polygon
			(pts
				(arc
					(start 365.144812 0.434594)
					(mid 364.476792 0.434594)
					(end 365.144812 0.434594)
				)
			)
		)
	)
	(zone
		(layers "B.Cu" "In11.Cu" "In13.Cu" "In15.Cu")
		(hatch none 0.5)
		(connect_pads
			(clearance 0)
		)
		(min_thickness 0.25)
		(keepout
			(tracks not_allowed)
			(vias allowed)
			(pads allowed)
			(copperpour not_allowed)
			(footprints allowed)
		)
		(placement
			(enabled no)
			(sheetname "")
		)
		(fill yes
			(thermal_gap 0.5)
			(thermal_bridge_width 0.5)
			(island_removal_mode 0)
		)
		(polygon
			(pts
				(arc
					(start 194.938142 -277.235412)
					(mid 194.270122 -277.235412)
					(end 194.938142 -277.235412)
				)
			)
		)
	)
	(zone
		(layers "B.Cu" "In11.Cu" "In13.Cu" "In15.Cu")
		(hatch none 0.5)
		(connect_pads
			(clearance 0)
		)
		(min_thickness 0.25)
		(keepout
			(tracks not_allowed)
			(vias allowed)
			(pads allowed)
			(copperpour not_allowed)
			(footprints allowed)
		)
		(placement
			(enabled no)
			(sheetname "")
		)
		(fill yes
			(thermal_gap 0.5)
			(thermal_bridge_width 0.5)
			(island_removal_mode 0)
		)
		(polygon
			(pts
				(arc
					(start 277.526242 -301.885096)
					(mid 276.858222 -301.885096)
					(end 277.526242 -301.885096)
				)
			)
		)
	)
	(zone
		(layers "B.Cu" "In11.Cu" "In13.Cu" "In15.Cu")
		(hatch none 0.5)
		(connect_pads
			(clearance 0)
		)
		(min_thickness 0.25)
		(keepout
			(tracks not_allowed)
			(vias allowed)
			(pads allowed)
			(copperpour not_allowed)
			(footprints allowed)
		)
		(placement
			(enabled no)
			(sheetname "")
		)
		(fill yes
			(thermal_gap 0.5)
			(thermal_bridge_width 0.5)
			(island_removal_mode 0)
		)
		(polygon
			(pts
				(arc
					(start 143.40967 -287.856422)
					(mid 142.77975 -287.856422)
					(end 143.40967 -287.856422)
				)
			)
		)
	)
	(zone
		(layers "B.Cu" "In11.Cu" "In13.Cu" "In15.Cu")
		(hatch none 0.5)
		(connect_pads
			(clearance 0)
		)
		(min_thickness 0.25)
		(keepout
			(tracks not_allowed)
			(vias allowed)
			(pads allowed)
			(copperpour not_allowed)
			(footprints allowed)
		)
		(placement
			(enabled no)
			(sheetname "")
		)
		(fill yes
			(thermal_gap 0.5)
			(thermal_bridge_width 0.5)
			(island_removal_mode 0)
		)
		(polygon
			(pts
				(arc
					(start 442.87821 -314.635134)
					(mid 442.21019 -314.635134)
					(end 442.87821 -314.635134)
				)
			)
		)
	)
	(zone
		(layers "B.Cu" "In11.Cu" "In13.Cu" "In15.Cu")
		(hatch none 0.5)
		(connect_pads
			(clearance 0)
		)
		(min_thickness 0.25)
		(keepout
			(tracks not_allowed)
			(vias allowed)
			(pads allowed)
			(copperpour not_allowed)
			(footprints allowed)
		)
		(placement
			(enabled no)
			(sheetname "")
		)
		(fill yes
			(thermal_gap 0.5)
			(thermal_bridge_width 0.5)
			(island_removal_mode 0)
		)
		(polygon
			(pts
				(arc
					(start 194.938142 -230.485442)
					(mid 194.270122 -230.485442)
					(end 194.938142 -230.485442)
				)
			)
		)
	)
	(zone
		(layers "B.Cu" "In11.Cu" "In13.Cu" "In15.Cu")
		(hatch none 0.5)
		(connect_pads
			(clearance 0)
		)
		(min_thickness 0.25)
		(keepout
			(tracks not_allowed)
			(vias allowed)
			(pads allowed)
			(copperpour not_allowed)
			(footprints allowed)
		)
		(placement
			(enabled no)
			(sheetname "")
		)
		(fill yes
			(thermal_gap 0.5)
			(thermal_bridge_width 0.5)
			(island_removal_mode 0)
		)
		(polygon
			(pts
				(arc
					(start 151.137112 -427.289976)
					(mid 150.36292 -427.289976)
					(end 151.137112 -427.289976)
				)
			)
		)
	)
	(zone
		(layers "B.Cu" "In11.Cu" "In13.Cu" "In15.Cu")
		(hatch none 0.5)
		(connect_pads
			(clearance 0)
		)
		(min_thickness 0.25)
		(keepout
			(tracks not_allowed)
			(vias allowed)
			(pads allowed)
			(copperpour not_allowed)
			(footprints allowed)
		)
		(placement
			(enabled no)
			(sheetname "")
		)
		(fill yes
			(thermal_gap 0.5)
			(thermal_bridge_width 0.5)
			(island_removal_mode 0)
		)
		(polygon
			(pts
				(arc
					(start 103.357934 -32.94761)
					(mid 102.689914 -32.94761)
					(end 103.357934 -32.94761)
				)
			)
		)
	)
	(zone
		(layers "B.Cu" "In11.Cu" "In13.Cu" "In15.Cu")
		(hatch none 0.5)
		(connect_pads
			(clearance 0)
		)
		(min_thickness 0.25)
		(keepout
			(tracks not_allowed)
			(vias allowed)
			(pads allowed)
			(copperpour not_allowed)
			(footprints allowed)
		)
		(placement
			(enabled no)
			(sheetname "")
		)
		(fill yes
			(thermal_gap 0.5)
			(thermal_bridge_width 0.5)
			(island_removal_mode 0)
		)
		(polygon
			(pts
				(arc
					(start 389.63981 -253.39421)
					(mid 389.00989 -253.39421)
					(end 389.63981 -253.39421)
				)
			)
		)
	)
	(zone
		(layers "B.Cu" "In11.Cu" "In13.Cu" "In15.Cu")
		(hatch none 0.5)
		(connect_pads
			(clearance 0)
		)
		(min_thickness 0.25)
		(keepout
			(tracks not_allowed)
			(vias allowed)
			(pads allowed)
			(copperpour not_allowed)
			(footprints allowed)
		)
		(placement
			(enabled no)
			(sheetname "")
		)
		(fill yes
			(thermal_gap 0.5)
			(thermal_bridge_width 0.5)
			(island_removal_mode 0)
		)
		(polygon
			(pts
				(arc
					(start 442.87821 -310.384952)
					(mid 442.21019 -310.384952)
					(end 442.87821 -310.384952)
				)
			)
		)
	)
	(zone
		(layers "B.Cu" "In11.Cu" "In13.Cu" "In15.Cu")
		(hatch none 0.5)
		(connect_pads
			(clearance 0)
		)
		(min_thickness 0.25)
		(keepout
			(tracks not_allowed)
			(vias allowed)
			(pads allowed)
			(copperpour not_allowed)
			(footprints allowed)
		)
		(placement
			(enabled no)
			(sheetname "")
		)
		(fill yes
			(thermal_gap 0.5)
			(thermal_bridge_width 0.5)
			(island_removal_mode 0)
		)
		(polygon
			(pts
				(arc
					(start 273.426174 -277.235158)
					(mid 272.758154 -277.235158)
					(end 273.426174 -277.235158)
				)
			)
		)
	)
	(zone
		(layers "B.Cu" "In11.Cu" "In13.Cu" "In15.Cu")
		(hatch none 0.5)
		(connect_pads
			(clearance 0)
		)
		(min_thickness 0.25)
		(keepout
			(tracks not_allowed)
			(vias allowed)
			(pads allowed)
			(copperpour not_allowed)
			(footprints allowed)
		)
		(placement
			(enabled no)
			(sheetname "")
		)
		(fill yes
			(thermal_gap 0.5)
			(thermal_bridge_width 0.5)
			(island_removal_mode 0)
		)
		(polygon
			(pts
				(arc
					(start 329.78598 -287.045908)
					(mid 329.15606 -287.045908)
					(end 329.78598 -287.045908)
				)
			)
		)
	)
	(zone
		(layers "B.Cu" "In11.Cu" "In13.Cu" "In15.Cu")
		(hatch none 0.5)
		(connect_pads
			(clearance 0)
		)
		(min_thickness 0.25)
		(keepout
			(tracks not_allowed)
			(vias allowed)
			(pads allowed)
			(copperpour not_allowed)
			(footprints allowed)
		)
		(placement
			(enabled no)
			(sheetname "")
		)
		(fill yes
			(thermal_gap 0.5)
			(thermal_bridge_width 0.5)
			(island_removal_mode 0)
		)
		(polygon
			(pts
				(arc
					(start 372.406164 -397.156432)
					(mid 371.776244 -397.156432)
					(end 372.406164 -397.156432)
				)
			)
		)
	)
	(zone
		(layers "B.Cu" "In11.Cu" "In13.Cu" "In15.Cu")
		(hatch none 0.5)
		(connect_pads
			(clearance 0)
		)
		(min_thickness 0.25)
		(keepout
			(tracks not_allowed)
			(vias allowed)
			(pads allowed)
			(copperpour not_allowed)
			(footprints allowed)
		)
		(placement
			(enabled no)
			(sheetname "")
		)
		(fill yes
			(thermal_gap 0.5)
			(thermal_bridge_width 0.5)
			(island_removal_mode 0)
		)
		(polygon
			(pts
				(arc
					(start 277.526242 -200.735184)
					(mid 276.858222 -200.735184)
					(end 277.526242 -200.735184)
				)
			)
		)
	)
	(zone
		(layers "B.Cu" "In11.Cu" "In13.Cu" "In15.Cu")
		(hatch none 0.5)
		(connect_pads
			(clearance 0)
		)
		(min_thickness 0.25)
		(keepout
			(tracks not_allowed)
			(vias allowed)
			(pads allowed)
			(copperpour not_allowed)
			(footprints allowed)
		)
		(placement
			(enabled no)
			(sheetname "")
		)
		(fill yes
			(thermal_gap 0.5)
			(thermal_bridge_width 0.5)
			(island_removal_mode 0)
		)
		(polygon
			(pts
				(arc
					(start 141.999716 -265.98626)
					(mid 141.369796 -265.98626)
					(end 141.999716 -265.98626)
				)
			)
		)
	)
	(zone
		(layers "B.Cu" "In11.Cu" "In13.Cu" "In15.Cu")
		(hatch none 0.5)
		(connect_pads
			(clearance 0)
		)
		(min_thickness 0.25)
		(keepout
			(tracks not_allowed)
			(vias allowed)
			(pads allowed)
			(copperpour not_allowed)
			(footprints allowed)
		)
		(placement
			(enabled no)
			(sheetname "")
		)
		(fill yes
			(thermal_gap 0.5)
			(thermal_bridge_width 0.5)
			(island_removal_mode 0)
		)
		(polygon
			(pts
				(arc
					(start 316.77737 0.434594)
					(mid 316.10935 0.434594)
					(end 316.77737 0.434594)
				)
			)
		)
	)
	(zone
		(layers "B.Cu" "In11.Cu" "In13.Cu" "In15.Cu")
		(hatch none 0.5)
		(connect_pads
			(clearance 0)
		)
		(min_thickness 0.25)
		(keepout
			(tracks not_allowed)
			(vias allowed)
			(pads allowed)
			(copperpour not_allowed)
			(footprints allowed)
		)
		(placement
			(enabled no)
			(sheetname "")
		)
		(fill yes
			(thermal_gap 0.5)
			(thermal_bridge_width 0.5)
			(island_removal_mode 0)
		)
		(polygon
			(pts
				(arc
					(start 82.485992 -242.05438)
					(mid 81.856072 -242.05438)
					(end 82.485992 -242.05438)
				)
			)
		)
	)
	(zone
		(layers "B.Cu" "In11.Cu" "In13.Cu" "In15.Cu")
		(hatch none 0.5)
		(connect_pads
			(clearance 0)
		)
		(min_thickness 0.25)
		(keepout
			(tracks not_allowed)
			(vias allowed)
			(pads allowed)
			(copperpour not_allowed)
			(footprints allowed)
		)
		(placement
			(enabled no)
			(sheetname "")
		)
		(fill yes
			(thermal_gap 0.5)
			(thermal_bridge_width 0.5)
			(island_removal_mode 0)
		)
		(polygon
			(pts
				(arc
					(start 61.036962 -428.28972)
					(mid 60.26277 -428.28972)
					(end 61.036962 -428.28972)
				)
			)
		)
	)
	(zone
		(layers "B.Cu" "In11.Cu" "In13.Cu" "In15.Cu")
		(hatch none 0.5)
		(connect_pads
			(clearance 0)
		)
		(min_thickness 0.25)
		(keepout
			(tracks not_allowed)
			(vias allowed)
			(pads allowed)
			(copperpour not_allowed)
			(footprints allowed)
		)
		(placement
			(enabled no)
			(sheetname "")
		)
		(fill yes
			(thermal_gap 0.5)
			(thermal_bridge_width 0.5)
			(island_removal_mode 0)
		)
		(polygon
			(pts
				(arc
					(start 370.369846 -239.624108)
					(mid 369.739926 -239.624108)
					(end 370.369846 -239.624108)
				)
			)
		)
	)
	(zone
		(layers "B.Cu" "In11.Cu" "In13.Cu" "In15.Cu")
		(hatch none 0.5)
		(connect_pads
			(clearance 0)
		)
		(min_thickness 0.25)
		(keepout
			(tracks not_allowed)
			(vias allowed)
			(pads allowed)
			(copperpour not_allowed)
			(footprints allowed)
		)
		(placement
			(enabled no)
			(sheetname "")
		)
		(fill yes
			(thermal_gap 0.5)
			(thermal_bridge_width 0.5)
			(island_removal_mode 0)
		)
		(polygon
			(pts
				(arc
					(start 389.63981 -235.574078)
					(mid 389.00989 -235.574078)
					(end 389.63981 -235.574078)
				)
			)
		)
	)
	(zone
		(layers "B.Cu" "In11.Cu" "In13.Cu" "In15.Cu")
		(hatch none 0.5)
		(connect_pads
			(clearance 0)
		)
		(min_thickness 0.25)
		(keepout
			(tracks not_allowed)
			(vias allowed)
			(pads allowed)
			(copperpour not_allowed)
			(footprints allowed)
		)
		(placement
			(enabled no)
			(sheetname "")
		)
		(fill yes
			(thermal_gap 0.5)
			(thermal_bridge_width 0.5)
			(island_removal_mode 0)
		)
		(polygon
			(pts
				(arc
					(start 194.938142 -213.485222)
					(mid 194.270122 -213.485222)
					(end 194.938142 -213.485222)
				)
			)
		)
	)
	(zone
		(layers "B.Cu" "In11.Cu" "In13.Cu" "In15.Cu")
		(hatch none 0.5)
		(connect_pads
			(clearance 0)
		)
		(min_thickness 0.25)
		(keepout
			(tracks not_allowed)
			(vias allowed)
			(pads allowed)
			(copperpour not_allowed)
			(footprints allowed)
		)
		(placement
			(enabled no)
			(sheetname "")
		)
		(fill yes
			(thermal_gap 0.5)
			(thermal_bridge_width 0.5)
			(island_removal_mode 0)
		)
		(polygon
			(pts
				(arc
					(start 389.63981 -229.094284)
					(mid 389.00989 -229.094284)
					(end 389.63981 -229.094284)
				)
			)
		)
	)
	(zone
		(layers "B.Cu" "In11.Cu" "In13.Cu" "In15.Cu")
		(hatch none 0.5)
		(connect_pads
			(clearance 0)
		)
		(min_thickness 0.25)
		(keepout
			(tracks not_allowed)
			(vias allowed)
			(pads allowed)
			(copperpour not_allowed)
			(footprints allowed)
		)
		(placement
			(enabled no)
			(sheetname "")
		)
		(fill yes
			(thermal_gap 0.5)
			(thermal_bridge_width 0.5)
			(island_removal_mode 0)
		)
		(polygon
			(pts
				(arc
					(start 363.619796 -282.186126)
					(mid 362.989876 -282.186126)
					(end 363.619796 -282.186126)
				)
			)
		)
	)
	(zone
		(layers "B.Cu" "In11.Cu" "In13.Cu" "In15.Cu")
		(hatch none 0.5)
		(connect_pads
			(clearance 0)
		)
		(min_thickness 0.25)
		(keepout
			(tracks not_allowed)
			(vias allowed)
			(pads allowed)
			(copperpour not_allowed)
			(footprints allowed)
		)
		(placement
			(enabled no)
			(sheetname "")
		)
		(fill yes
			(thermal_gap 0.5)
			(thermal_bridge_width 0.5)
			(island_removal_mode 0)
		)
		(polygon
			(pts
				(arc
					(start 82.955892 -234.764326)
					(mid 82.325972 -234.764326)
					(end 82.955892 -234.764326)
				)
			)
		)
	)
	(zone
		(layers "B.Cu" "In11.Cu" "In13.Cu" "In15.Cu")
		(hatch none 0.5)
		(connect_pads
			(clearance 0)
		)
		(min_thickness 0.25)
		(keepout
			(tracks not_allowed)
			(vias allowed)
			(pads allowed)
			(copperpour not_allowed)
			(footprints allowed)
		)
		(placement
			(enabled no)
			(sheetname "")
		)
		(fill yes
			(thermal_gap 0.5)
			(thermal_bridge_width 0.5)
			(island_removal_mode 0)
		)
		(polygon
			(pts
				(arc
					(start 78.760574 -404.46452)
					(mid 78.092554 -404.46452)
					(end 78.760574 -404.46452)
				)
			)
		)
	)
	(zone
		(layers "B.Cu" "In11.Cu" "In13.Cu" "In15.Cu")
		(hatch none 0.5)
		(connect_pads
			(clearance 0)
		)
		(min_thickness 0.25)
		(keepout
			(tracks not_allowed)
			(vias allowed)
			(pads allowed)
			(copperpour not_allowed)
			(footprints allowed)
		)
		(placement
			(enabled no)
			(sheetname "")
		)
		(fill yes
			(thermal_gap 0.5)
			(thermal_bridge_width 0.5)
			(island_removal_mode 0)
		)
		(polygon
			(pts
				(arc
					(start 442.87821 -221.13494)
					(mid 442.21019 -221.13494)
					(end 442.87821 -221.13494)
				)
			)
		)
	)
	(zone
		(layers "B.Cu" "In11.Cu" "In13.Cu" "In15.Cu")
		(hatch none 0.5)
		(connect_pads
			(clearance 0)
		)
		(min_thickness 0.25)
		(keepout
			(tracks not_allowed)
			(vias allowed)
			(pads allowed)
			(copperpour not_allowed)
			(footprints allowed)
		)
		(placement
			(enabled no)
			(sheetname "")
		)
		(fill yes
			(thermal_gap 0.5)
			(thermal_bridge_width 0.5)
			(island_removal_mode 0)
		)
		(polygon
			(pts
				(arc
					(start 107.696 -284.616398)
					(mid 107.06608 -284.616398)
					(end 107.696 -284.616398)
				)
			)
		)
	)
	(zone
		(layers "B.Cu" "In11.Cu" "In13.Cu" "In15.Cu")
		(hatch none 0.5)
		(connect_pads
			(clearance 0)
		)
		(min_thickness 0.25)
		(keepout
			(tracks not_allowed)
			(vias allowed)
			(pads allowed)
			(copperpour not_allowed)
			(footprints allowed)
		)
		(placement
			(enabled no)
			(sheetname "")
		)
		(fill yes
			(thermal_gap 0.5)
			(thermal_bridge_width 0.5)
			(island_removal_mode 0)
		)
		(polygon
			(pts
				(arc
					(start 365.969804 -284.616144)
					(mid 365.339884 -284.616144)
					(end 365.969804 -284.616144)
				)
			)
		)
	)
	(zone
		(layers "B.Cu" "In11.Cu" "In13.Cu" "In15.Cu")
		(hatch none 0.5)
		(connect_pads
			(clearance 0)
		)
		(min_thickness 0.25)
		(keepout
			(tracks not_allowed)
			(vias allowed)
			(pads allowed)
			(copperpour not_allowed)
			(footprints allowed)
		)
		(placement
			(enabled no)
			(sheetname "")
		)
		(fill yes
			(thermal_gap 0.5)
			(thermal_bridge_width 0.5)
			(island_removal_mode 0)
		)
		(polygon
			(pts
				(arc
					(start 323.036692 -427.289976)
					(mid 322.2625 -427.289976)
					(end 323.036692 -427.289976)
				)
			)
		)
	)
	(zone
		(layers "B.Cu" "In11.Cu" "In13.Cu" "In15.Cu")
		(hatch none 0.5)
		(connect_pads
			(clearance 0)
		)
		(min_thickness 0.25)
		(keepout
			(tracks not_allowed)
			(vias allowed)
			(pads allowed)
			(copperpour not_allowed)
			(footprints allowed)
		)
		(placement
			(enabled no)
			(sheetname "")
		)
		(fill yes
			(thermal_gap 0.5)
			(thermal_bridge_width 0.5)
			(island_removal_mode 0)
		)
		(polygon
			(pts
				(arc
					(start 442.87821 -216.885012)
					(mid 442.21019 -216.885012)
					(end 442.87821 -216.885012)
				)
			)
		)
	)
	(zone
		(layers "B.Cu" "In11.Cu" "In13.Cu" "In15.Cu")
		(hatch none 0.5)
		(connect_pads
			(clearance 0)
		)
		(min_thickness 0.25)
		(keepout
			(tracks not_allowed)
			(vias allowed)
			(pads allowed)
			(copperpour not_allowed)
			(footprints allowed)
		)
		(placement
			(enabled no)
			(sheetname "")
		)
		(fill yes
			(thermal_gap 0.5)
			(thermal_bridge_width 0.5)
			(island_removal_mode 0)
		)
		(polygon
			(pts
				(arc
					(start 25.486106 -314.635388)
					(mid 24.818086 -314.635388)
					(end 25.486106 -314.635388)
				)
			)
		)
	)
	(zone
		(layers "B.Cu" "In11.Cu" "In13.Cu" "In15.Cu")
		(hatch none 0.5)
		(connect_pads
			(clearance 0)
		)
		(min_thickness 0.25)
		(keepout
			(tracks not_allowed)
			(vias allowed)
			(pads allowed)
			(copperpour not_allowed)
			(footprints allowed)
		)
		(placement
			(enabled no)
			(sheetname "")
		)
		(fill yes
			(thermal_gap 0.5)
			(thermal_bridge_width 0.5)
			(island_removal_mode 0)
		)
		(polygon
			(pts
				(arc
					(start 29.586174 -267.885418)
					(mid 28.918154 -267.885418)
					(end 29.586174 -267.885418)
				)
			)
		)
	)
	(zone
		(layers "B.Cu" "In11.Cu" "In13.Cu" "In15.Cu")
		(hatch none 0.5)
		(connect_pads
			(clearance 0)
		)
		(min_thickness 0.25)
		(keepout
			(tracks not_allowed)
			(vias allowed)
			(pads allowed)
			(copperpour not_allowed)
			(footprints allowed)
		)
		(placement
			(enabled no)
			(sheetname "")
		)
		(fill yes
			(thermal_gap 0.5)
			(thermal_bridge_width 0.5)
			(island_removal_mode 0)
		)
		(polygon
			(pts
				(arc
					(start 88.813894 -404.46452)
					(mid 88.145874 -404.46452)
					(end 88.813894 -404.46452)
				)
			)
		)
	)
	(zone
		(layers "B.Cu" "In11.Cu" "In13.Cu" "In15.Cu")
		(hatch none 0.5)
		(connect_pads
			(clearance 0)
		)
		(min_thickness 0.25)
		(keepout
			(tracks not_allowed)
			(vias allowed)
			(pads allowed)
			(copperpour not_allowed)
			(footprints allowed)
		)
		(placement
			(enabled no)
			(sheetname "")
		)
		(fill yes
			(thermal_gap 0.5)
			(thermal_bridge_width 0.5)
			(island_removal_mode 0)
		)
		(polygon
			(pts
				(arc
					(start 143.40967 -291.096192)
					(mid 142.77975 -291.096192)
					(end 143.40967 -291.096192)
				)
			)
		)
	)
	(zone
		(layers "B.Cu" "In11.Cu" "In13.Cu" "In15.Cu")
		(hatch none 0.5)
		(connect_pads
			(clearance 0)
		)
		(min_thickness 0.25)
		(keepout
			(tracks not_allowed)
			(vias allowed)
			(pads allowed)
			(copperpour not_allowed)
			(footprints allowed)
		)
		(placement
			(enabled no)
			(sheetname "")
		)
		(fill yes
			(thermal_gap 0.5)
			(thermal_bridge_width 0.5)
			(island_removal_mode 0)
		)
		(polygon
			(pts
				(arc
					(start 116.406168 -388.774432)
					(mid 115.776248 -388.774432)
					(end 116.406168 -388.774432)
				)
			)
		)
	)
	(zone
		(layers "B.Cu" "In11.Cu" "In13.Cu" "In15.Cu")
		(hatch none 0.5)
		(connect_pads
			(clearance 0)
		)
		(min_thickness 0.25)
		(keepout
			(tracks not_allowed)
			(vias allowed)
			(pads allowed)
			(copperpour not_allowed)
			(footprints allowed)
		)
		(placement
			(enabled no)
			(sheetname "")
		)
		(fill yes
			(thermal_gap 0.5)
			(thermal_bridge_width 0.5)
			(island_removal_mode 0)
		)
		(polygon
			(pts
				(arc
					(start 143.40967 -276.516338)
					(mid 142.77975 -276.516338)
					(end 143.40967 -276.516338)
				)
			)
		)
	)
	(zone
		(layers "B.Cu" "In11.Cu" "In13.Cu" "In15.Cu")
		(hatch none 0.5)
		(connect_pads
			(clearance 0)
		)
		(min_thickness 0.25)
		(keepout
			(tracks not_allowed)
			(vias allowed)
			(pads allowed)
			(copperpour not_allowed)
			(footprints allowed)
		)
		(placement
			(enabled no)
			(sheetname "")
		)
		(fill yes
			(thermal_gap 0.5)
			(thermal_bridge_width 0.5)
			(island_removal_mode 0)
		)
		(polygon
			(pts
				(arc
					(start 396.136876 -427.089824)
					(mid 395.362684 -427.089824)
					(end 396.136876 -427.089824)
				)
			)
		)
	)
	(zone
		(layers "B.Cu" "In11.Cu" "In13.Cu" "In15.Cu")
		(hatch none 0.5)
		(connect_pads
			(clearance 0)
		)
		(min_thickness 0.25)
		(keepout
			(tracks not_allowed)
			(vias allowed)
			(pads allowed)
			(copperpour not_allowed)
			(footprints allowed)
		)
		(placement
			(enabled no)
			(sheetname "")
		)
		(fill yes
			(thermal_gap 0.5)
			(thermal_bridge_width 0.5)
			(island_removal_mode 0)
		)
		(polygon
			(pts
				(arc
					(start 389.469884 -289.475926)
					(mid 388.839964 -289.475926)
					(end 389.469884 -289.475926)
				)
			)
		)
	)
	(zone
		(layers "B.Cu" "In11.Cu" "In13.Cu" "In15.Cu")
		(hatch none 0.5)
		(connect_pads
			(clearance 0)
		)
		(min_thickness 0.25)
		(keepout
			(tracks not_allowed)
			(vias allowed)
			(pads allowed)
			(copperpour not_allowed)
			(footprints allowed)
		)
		(placement
			(enabled no)
			(sheetname "")
		)
		(fill yes
			(thermal_gap 0.5)
			(thermal_bridge_width 0.5)
			(island_removal_mode 0)
		)
		(polygon
			(pts
				(arc
					(start 370.66982 -282.996132)
					(mid 370.0399 -282.996132)
					(end 370.66982 -282.996132)
				)
			)
		)
	)
	(zone
		(layers "B.Cu" "In11.Cu" "In13.Cu" "In15.Cu")
		(hatch none 0.5)
		(connect_pads
			(clearance 0)
		)
		(min_thickness 0.25)
		(keepout
			(tracks not_allowed)
			(vias allowed)
			(pads allowed)
			(copperpour not_allowed)
			(footprints allowed)
		)
		(placement
			(enabled no)
			(sheetname "")
		)
		(fill yes
			(thermal_gap 0.5)
			(thermal_bridge_width 0.5)
			(island_removal_mode 0)
		)
		(polygon
			(pts
				(arc
					(start 199.03821 -227.085398)
					(mid 198.37019 -227.085398)
					(end 199.03821 -227.085398)
				)
			)
		)
	)
	(zone
		(layers "B.Cu" "In11.Cu" "In13.Cu" "In15.Cu")
		(hatch none 0.5)
		(connect_pads
			(clearance 0)
		)
		(min_thickness 0.25)
		(keepout
			(tracks not_allowed)
			(vias allowed)
			(pads allowed)
			(copperpour not_allowed)
			(footprints allowed)
		)
		(placement
			(enabled no)
			(sheetname "")
		)
		(fill yes
			(thermal_gap 0.5)
			(thermal_bridge_width 0.5)
			(island_removal_mode 0)
		)
		(polygon
			(pts
				(arc
					(start 194.938142 -224.535238)
					(mid 194.270122 -224.535238)
					(end 194.938142 -224.535238)
				)
			)
		)
	)
	(zone
		(layers "B.Cu" "In11.Cu" "In13.Cu" "In15.Cu")
		(hatch none 0.5)
		(connect_pads
			(clearance 0)
		)
		(min_thickness 0.25)
		(keepout
			(tracks not_allowed)
			(vias allowed)
			(pads allowed)
			(copperpour not_allowed)
			(footprints allowed)
		)
		(placement
			(enabled no)
			(sheetname "")
		)
		(fill yes
			(thermal_gap 0.5)
			(thermal_bridge_width 0.5)
			(island_removal_mode 0)
		)
		(polygon
			(pts
				(arc
					(start 308.721506 -377.41733)
					(mid 308.053486 -377.41733)
					(end 308.721506 -377.41733)
				)
			)
		)
	)
	(zone
		(layers "B.Cu" "In11.Cu" "In13.Cu" "In15.Cu")
		(hatch none 0.5)
		(connect_pads
			(clearance 0)
		)
		(min_thickness 0.25)
		(keepout
			(tracks not_allowed)
			(vias allowed)
			(pads allowed)
			(copperpour not_allowed)
			(footprints allowed)
		)
		(placement
			(enabled no)
			(sheetname "")
		)
		(fill yes
			(thermal_gap 0.5)
			(thermal_bridge_width 0.5)
			(island_removal_mode 0)
		)
		(polygon
			(pts
				(arc
					(start 142.639796 -237.194344)
					(mid 142.009876 -237.194344)
					(end 142.639796 -237.194344)
				)
			)
		)
	)
	(zone
		(layers "B.Cu" "In11.Cu" "In13.Cu" "In15.Cu")
		(hatch none 0.5)
		(connect_pads
			(clearance 0)
		)
		(min_thickness 0.25)
		(keepout
			(tracks not_allowed)
			(vias allowed)
			(pads allowed)
			(copperpour not_allowed)
			(footprints allowed)
		)
		(placement
			(enabled no)
			(sheetname "")
		)
		(fill yes
			(thermal_gap 0.5)
			(thermal_bridge_width 0.5)
			(island_removal_mode 0)
		)
		(polygon
			(pts
				(arc
					(start 98.936048 -241.244374)
					(mid 98.306128 -241.244374)
					(end 98.936048 -241.244374)
				)
			)
		)
	)
	(zone
		(layers "B.Cu" "In11.Cu" "In13.Cu" "In15.Cu")
		(hatch none 0.5)
		(connect_pads
			(clearance 0)
		)
		(min_thickness 0.25)
		(keepout
			(tracks not_allowed)
			(vias allowed)
			(pads allowed)
			(copperpour not_allowed)
			(footprints allowed)
		)
		(placement
			(enabled no)
			(sheetname "")
		)
		(fill yes
			(thermal_gap 0.5)
			(thermal_bridge_width 0.5)
			(island_removal_mode 0)
		)
		(polygon
			(pts
				(arc
					(start 273.426174 -227.935028)
					(mid 272.758154 -227.935028)
					(end 273.426174 -227.935028)
				)
			)
		)
	)
	(zone
		(layers "B.Cu" "In11.Cu" "In13.Cu" "In15.Cu")
		(hatch none 0.5)
		(connect_pads
			(clearance 0)
		)
		(min_thickness 0.25)
		(keepout
			(tracks not_allowed)
			(vias allowed)
			(pads allowed)
			(copperpour not_allowed)
			(footprints allowed)
		)
		(placement
			(enabled no)
			(sheetname "")
		)
		(fill yes
			(thermal_gap 0.5)
			(thermal_bridge_width 0.5)
			(island_removal_mode 0)
		)
		(polygon
			(pts
				(arc
					(start 273.426174 -305.28514)
					(mid 272.758154 -305.28514)
					(end 273.426174 -305.28514)
				)
			)
		)
	)
	(zone
		(layers "B.Cu" "In11.Cu" "In13.Cu" "In15.Cu")
		(hatch none 0.5)
		(connect_pads
			(clearance 0)
		)
		(min_thickness 0.25)
		(keepout
			(tracks not_allowed)
			(vias allowed)
			(pads allowed)
			(copperpour not_allowed)
			(footprints allowed)
		)
		(placement
			(enabled no)
			(sheetname "")
		)
		(fill yes
			(thermal_gap 0.5)
			(thermal_bridge_width 0.5)
			(island_removal_mode 0)
		)
		(polygon
			(pts
				(arc
					(start 25.486106 -237.285276)
					(mid 24.818086 -237.285276)
					(end 25.486106 -237.285276)
				)
			)
		)
	)
	(zone
		(layers "B.Cu" "In11.Cu" "In13.Cu" "In15.Cu")
		(hatch none 0.5)
		(connect_pads
			(clearance 0)
		)
		(min_thickness 0.25)
		(keepout
			(tracks not_allowed)
			(vias allowed)
			(pads allowed)
			(copperpour not_allowed)
			(footprints allowed)
		)
		(placement
			(enabled no)
			(sheetname "")
		)
		(fill yes
			(thermal_gap 0.5)
			(thermal_bridge_width 0.5)
			(island_removal_mode 0)
		)
		(polygon
			(pts
				(arc
					(start 442.87821 -204.134974)
					(mid 442.21019 -204.134974)
					(end 442.87821 -204.134974)
				)
			)
		)
	)
	(zone
		(layers "B.Cu" "In11.Cu" "In13.Cu" "In15.Cu")
		(hatch none 0.5)
		(connect_pads
			(clearance 0)
		)
		(min_thickness 0.25)
		(keepout
			(tracks not_allowed)
			(vias allowed)
			(pads allowed)
			(copperpour not_allowed)
			(footprints allowed)
		)
		(placement
			(enabled no)
			(sheetname "")
		)
		(fill yes
			(thermal_gap 0.5)
			(thermal_bridge_width 0.5)
			(island_removal_mode 0)
		)
		(polygon
			(pts
				(arc
					(start 143.137128 -426.089826)
					(mid 142.362936 -426.089826)
					(end 143.137128 -426.089826)
				)
			)
		)
	)
	(zone
		(layers "B.Cu" "In11.Cu" "In13.Cu" "In15.Cu")
		(hatch none 0.5)
		(connect_pads
			(clearance 0)
		)
		(min_thickness 0.25)
		(keepout
			(tracks not_allowed)
			(vias allowed)
			(pads allowed)
			(copperpour not_allowed)
			(footprints allowed)
		)
		(placement
			(enabled no)
			(sheetname "")
		)
		(fill yes
			(thermal_gap 0.5)
			(thermal_bridge_width 0.5)
			(island_removal_mode 0)
		)
		(polygon
			(pts
				(arc
					(start 446.978278 -311.23509)
					(mid 446.310258 -311.23509)
					(end 446.978278 -311.23509)
				)
			)
		)
	)
	(zone
		(layers "B.Cu" "In11.Cu" "In13.Cu" "In15.Cu")
		(hatch none 0.5)
		(connect_pads
			(clearance 0)
		)
		(min_thickness 0.25)
		(keepout
			(tracks not_allowed)
			(vias allowed)
			(pads allowed)
			(copperpour not_allowed)
			(footprints allowed)
		)
		(placement
			(enabled no)
			(sheetname "")
		)
		(fill yes
			(thermal_gap 0.5)
			(thermal_bridge_width 0.5)
			(island_removal_mode 0)
		)
		(polygon
			(pts
				(arc
					(start 446.978278 -220.285056)
					(mid 446.310258 -220.285056)
					(end 446.978278 -220.285056)
				)
			)
		)
	)
	(zone
		(layers "B.Cu" "In11.Cu" "In13.Cu" "In15.Cu")
		(hatch none 0.5)
		(connect_pads
			(clearance 0)
		)
		(min_thickness 0.25)
		(keepout
			(tracks not_allowed)
			(vias allowed)
			(pads allowed)
			(copperpour not_allowed)
			(footprints allowed)
		)
		(placement
			(enabled no)
			(sheetname "")
		)
		(fill yes
			(thermal_gap 0.5)
			(thermal_bridge_width 0.5)
			(island_removal_mode 0)
		)
		(polygon
			(pts
				(arc
					(start 273.426174 -265.335004)
					(mid 272.758154 -265.335004)
					(end 273.426174 -265.335004)
				)
			)
		)
	)
	(zone
		(layers "B.Cu" "In11.Cu" "In13.Cu" "In15.Cu")
		(hatch none 0.5)
		(connect_pads
			(clearance 0)
		)
		(min_thickness 0.25)
		(keepout
			(tracks not_allowed)
			(vias allowed)
			(pads allowed)
			(copperpour not_allowed)
			(footprints allowed)
		)
		(placement
			(enabled no)
			(sheetname "")
		)
		(fill yes
			(thermal_gap 0.5)
			(thermal_bridge_width 0.5)
			(island_removal_mode 0)
		)
		(polygon
			(pts
				(arc
					(start 29.586174 -223.685354)
					(mid 28.918154 -223.685354)
					(end 29.586174 -223.685354)
				)
			)
		)
	)
	(zone
		(layers "B.Cu" "In11.Cu" "In13.Cu" "In15.Cu")
		(hatch none 0.5)
		(connect_pads
			(clearance 0)
		)
		(min_thickness 0.25)
		(keepout
			(tracks not_allowed)
			(vias allowed)
			(pads allowed)
			(copperpour not_allowed)
			(footprints allowed)
		)
		(placement
			(enabled no)
			(sheetname "")
		)
		(fill yes
			(thermal_gap 0.5)
			(thermal_bridge_width 0.5)
			(island_removal_mode 0)
		)
		(polygon
			(pts
				(arc
					(start 71.036942 -418.889942)
					(mid 70.26275 -418.889942)
					(end 71.036942 -418.889942)
				)
			)
		)
	)
	(zone
		(layers "B.Cu" "In11.Cu" "In13.Cu" "In15.Cu")
		(hatch none 0.5)
		(connect_pads
			(clearance 0)
		)
		(min_thickness 0.25)
		(keepout
			(tracks not_allowed)
			(vias allowed)
			(pads allowed)
			(copperpour not_allowed)
			(footprints allowed)
		)
		(placement
			(enabled no)
			(sheetname "")
		)
		(fill yes
			(thermal_gap 0.5)
			(thermal_bridge_width 0.5)
			(island_removal_mode 0)
		)
		(polygon
			(pts
				(arc
					(start 199.03821 -298.485306)
					(mid 198.37019 -298.485306)
					(end 199.03821 -298.485306)
				)
			)
		)
	)
	(zone
		(layers "B.Cu" "In11.Cu" "In13.Cu" "In15.Cu")
		(hatch none 0.5)
		(connect_pads
			(clearance 0)
		)
		(min_thickness 0.25)
		(keepout
			(tracks not_allowed)
			(vias allowed)
			(pads allowed)
			(copperpour not_allowed)
			(footprints allowed)
		)
		(placement
			(enabled no)
			(sheetname "")
		)
		(fill yes
			(thermal_gap 0.5)
			(thermal_bridge_width 0.5)
			(island_removal_mode 0)
		)
		(polygon
			(pts
				(arc
					(start 71.611744 -376.093228)
					(mid 70.943724 -376.093228)
					(end 71.611744 -376.093228)
				)
			)
		)
	)
	(zone
		(layers "B.Cu" "In11.Cu" "In13.Cu" "In15.Cu")
		(hatch none 0.5)
		(connect_pads
			(clearance 0)
		)
		(min_thickness 0.25)
		(keepout
			(tracks not_allowed)
			(vias allowed)
			(pads allowed)
			(copperpour not_allowed)
			(footprints allowed)
		)
		(placement
			(enabled no)
			(sheetname "")
		)
		(fill yes
			(thermal_gap 0.5)
			(thermal_bridge_width 0.5)
			(island_removal_mode 0)
		)
		(polygon
			(pts
				(arc
					(start 126.006098 -388.774432)
					(mid 125.376178 -388.774432)
					(end 126.006098 -388.774432)
				)
			)
		)
	)
	(zone
		(layers "B.Cu" "In11.Cu" "In13.Cu" "In15.Cu")
		(hatch none 0.5)
		(connect_pads
			(clearance 0)
		)
		(min_thickness 0.25)
		(keepout
			(tracks not_allowed)
			(vias allowed)
			(pads allowed)
			(copperpour not_allowed)
			(footprints allowed)
		)
		(placement
			(enabled no)
			(sheetname "")
		)
		(fill yes
			(thermal_gap 0.5)
			(thermal_bridge_width 0.5)
			(island_removal_mode 0)
		)
		(polygon
			(pts
				(arc
					(start 82.485992 -245.294404)
					(mid 81.856072 -245.294404)
					(end 82.485992 -245.294404)
				)
			)
		)
	)
	(zone
		(layers "B.Cu" "In11.Cu" "In13.Cu" "In15.Cu")
		(hatch none 0.5)
		(connect_pads
			(clearance 0)
		)
		(min_thickness 0.25)
		(keepout
			(tracks not_allowed)
			(vias allowed)
			(pads allowed)
			(copperpour not_allowed)
			(footprints allowed)
		)
		(placement
			(enabled no)
			(sheetname "")
		)
		(fill yes
			(thermal_gap 0.5)
			(thermal_bridge_width 0.5)
			(island_removal_mode 0)
		)
		(polygon
			(pts
				(arc
					(start 182.375556 -47.164498)
					(mid 181.707536 -47.164498)
					(end 182.375556 -47.164498)
				)
			)
		)
	)
	(zone
		(layers "B.Cu" "In11.Cu" "In13.Cu" "In15.Cu")
		(hatch none 0.5)
		(connect_pads
			(clearance 0)
		)
		(min_thickness 0.25)
		(keepout
			(tracks not_allowed)
			(vias allowed)
			(pads allowed)
			(copperpour not_allowed)
			(footprints allowed)
		)
		(placement
			(enabled no)
			(sheetname "")
		)
		(fill yes
			(thermal_gap 0.5)
			(thermal_bridge_width 0.5)
			(island_removal_mode 0)
		)
		(polygon
			(pts
				(arc
					(start 390.879838 -275.706078)
					(mid 390.249918 -275.706078)
					(end 390.879838 -275.706078)
				)
			)
		)
	)
	(zone
		(layers "B.Cu" "In11.Cu" "In13.Cu" "In15.Cu")
		(hatch none 0.5)
		(connect_pads
			(clearance 0)
		)
		(min_thickness 0.25)
		(keepout
			(tracks not_allowed)
			(vias allowed)
			(pads allowed)
			(copperpour not_allowed)
			(footprints allowed)
		)
		(placement
			(enabled no)
			(sheetname "")
		)
		(fill yes
			(thermal_gap 0.5)
			(thermal_bridge_width 0.5)
			(island_removal_mode 0)
		)
		(polygon
			(pts
				(arc
					(start 142.93977 -277.326344)
					(mid 142.30985 -277.326344)
					(end 142.93977 -277.326344)
				)
			)
		)
	)
	(zone
		(layers "B.Cu" "In11.Cu" "In13.Cu" "In15.Cu")
		(hatch none 0.5)
		(connect_pads
			(clearance 0)
		)
		(min_thickness 0.25)
		(keepout
			(tracks not_allowed)
			(vias allowed)
			(pads allowed)
			(copperpour not_allowed)
			(footprints allowed)
		)
		(placement
			(enabled no)
			(sheetname "")
		)
		(fill yes
			(thermal_gap 0.5)
			(thermal_bridge_width 0.5)
			(island_removal_mode 0)
		)
		(polygon
			(pts
				(arc
					(start 25.486106 -226.23526)
					(mid 24.818086 -226.23526)
					(end 25.486106 -226.23526)
				)
			)
		)
	)
	(zone
		(layers "B.Cu" "In11.Cu" "In13.Cu" "In15.Cu")
		(hatch none 0.5)
		(connect_pads
			(clearance 0)
		)
		(min_thickness 0.25)
		(keepout
			(tracks not_allowed)
			(vias allowed)
			(pads allowed)
			(copperpour not_allowed)
			(footprints allowed)
		)
		(placement
			(enabled no)
			(sheetname "")
		)
		(fill yes
			(thermal_gap 0.5)
			(thermal_bridge_width 0.5)
			(island_removal_mode 0)
		)
		(polygon
			(pts
				(arc
					(start 442.87821 -308.685184)
					(mid 442.21019 -308.685184)
					(end 442.87821 -308.685184)
				)
			)
		)
	)
	(zone
		(layers "B.Cu" "In11.Cu" "In13.Cu" "In15.Cu")
		(hatch none 0.5)
		(connect_pads
			(clearance 0)
		)
		(min_thickness 0.25)
		(keepout
			(tracks not_allowed)
			(vias allowed)
			(pads allowed)
			(copperpour not_allowed)
			(footprints allowed)
		)
		(placement
			(enabled no)
			(sheetname "")
		)
		(fill yes
			(thermal_gap 0.5)
			(thermal_bridge_width 0.5)
			(island_removal_mode 0)
		)
		(polygon
			(pts
				(arc
					(start 82.485992 -230.71455)
					(mid 81.856072 -230.71455)
					(end 82.485992 -230.71455)
				)
			)
		)
	)
	(zone
		(layers "B.Cu" "In11.Cu" "In13.Cu" "In15.Cu")
		(hatch none 0.5)
		(connect_pads
			(clearance 0)
		)
		(min_thickness 0.25)
		(keepout
			(tracks not_allowed)
			(vias allowed)
			(pads allowed)
			(copperpour not_allowed)
			(footprints allowed)
		)
		(placement
			(enabled no)
			(sheetname "")
		)
		(fill yes
			(thermal_gap 0.5)
			(thermal_bridge_width 0.5)
			(island_removal_mode 0)
		)
		(polygon
			(pts
				(arc
					(start 330.89596 -239.624108)
					(mid 330.26604 -239.624108)
					(end 330.89596 -239.624108)
				)
			)
		)
	)
	(zone
		(layers "B.Cu" "In11.Cu" "In13.Cu" "In15.Cu")
		(hatch none 0.5)
		(connect_pads
			(clearance 0)
		)
		(min_thickness 0.25)
		(keepout
			(tracks not_allowed)
			(vias allowed)
			(pads allowed)
			(copperpour not_allowed)
			(footprints allowed)
		)
		(placement
			(enabled no)
			(sheetname "")
		)
		(fill yes
			(thermal_gap 0.5)
			(thermal_bridge_width 0.5)
			(island_removal_mode 0)
		)
		(polygon
			(pts
				(arc
					(start 88.037162 -426.089826)
					(mid 87.26297 -426.089826)
					(end 88.037162 -426.089826)
				)
			)
		)
	)
	(zone
		(layers "B.Cu" "In11.Cu" "In13.Cu" "In15.Cu")
		(hatch none 0.5)
		(connect_pads
			(clearance 0)
		)
		(min_thickness 0.25)
		(keepout
			(tracks not_allowed)
			(vias allowed)
			(pads allowed)
			(copperpour not_allowed)
			(footprints allowed)
		)
		(placement
			(enabled no)
			(sheetname "")
		)
		(fill yes
			(thermal_gap 0.5)
			(thermal_bridge_width 0.5)
			(island_removal_mode 0)
		)
		(polygon
			(pts
				(arc
					(start 141.999716 -288.666174)
					(mid 141.369796 -288.666174)
					(end 141.999716 -288.666174)
				)
			)
		)
	)
	(zone
		(layers "B.Cu" "In11.Cu" "In13.Cu" "In15.Cu")
		(hatch none 0.5)
		(connect_pads
			(clearance 0)
		)
		(min_thickness 0.25)
		(keepout
			(tracks not_allowed)
			(vias allowed)
			(pads allowed)
			(copperpour not_allowed)
			(footprints allowed)
		)
		(placement
			(enabled no)
			(sheetname "")
		)
		(fill yes
			(thermal_gap 0.5)
			(thermal_bridge_width 0.5)
			(island_removal_mode 0)
		)
		(polygon
			(pts
				(arc
					(start 194.938142 -261.935214)
					(mid 194.270122 -261.935214)
					(end 194.938142 -261.935214)
				)
			)
		)
	)
	(zone
		(layers "B.Cu" "In11.Cu" "In13.Cu" "In15.Cu")
		(hatch none 0.5)
		(connect_pads
			(clearance 0)
		)
		(min_thickness 0.25)
		(keepout
			(tracks not_allowed)
			(vias allowed)
			(pads allowed)
			(copperpour not_allowed)
			(footprints allowed)
		)
		(placement
			(enabled no)
			(sheetname "")
		)
		(fill yes
			(thermal_gap 0.5)
			(thermal_bridge_width 0.5)
			(island_removal_mode 0)
		)
		(polygon
			(pts
				(arc
					(start 329.31608 -263.555988)
					(mid 328.68616 -263.555988)
					(end 329.31608 -263.555988)
				)
			)
		)
	)
	(zone
		(layers "B.Cu" "In11.Cu" "In13.Cu" "In15.Cu")
		(hatch none 0.5)
		(connect_pads
			(clearance 0)
		)
		(min_thickness 0.25)
		(keepout
			(tracks not_allowed)
			(vias allowed)
			(pads allowed)
			(copperpour not_allowed)
			(footprints allowed)
		)
		(placement
			(enabled no)
			(sheetname "")
		)
		(fill yes
			(thermal_gap 0.5)
			(thermal_bridge_width 0.5)
			(island_removal_mode 0)
		)
		(polygon
			(pts
				(arc
					(start 157.1371 -427.089824)
					(mid 156.362908 -427.089824)
					(end 157.1371 -427.089824)
				)
			)
		)
	)
	(zone
		(layers "B.Cu" "In11.Cu" "In13.Cu" "In15.Cu")
		(hatch none 0.5)
		(connect_pads
			(clearance 0)
		)
		(min_thickness 0.25)
		(keepout
			(tracks not_allowed)
			(vias allowed)
			(pads allowed)
			(copperpour not_allowed)
			(footprints allowed)
		)
		(placement
			(enabled no)
			(sheetname "")
		)
		(fill yes
			(thermal_gap 0.5)
			(thermal_bridge_width 0.5)
			(island_removal_mode 0)
		)
		(polygon
			(pts
				(arc
					(start 330.89596 -246.104156)
					(mid 330.26604 -246.104156)
					(end 330.89596 -246.104156)
				)
			)
		)
	)
	(zone
		(layers "B.Cu" "In11.Cu" "In13.Cu" "In15.Cu")
		(hatch none 0.5)
		(connect_pads
			(clearance 0)
		)
		(min_thickness 0.25)
		(keepout
			(tracks not_allowed)
			(vias allowed)
			(pads allowed)
			(copperpour not_allowed)
			(footprints allowed)
		)
		(placement
			(enabled no)
			(sheetname "")
		)
		(fill yes
			(thermal_gap 0.5)
			(thermal_bridge_width 0.5)
			(island_removal_mode 0)
		)
		(polygon
			(pts
				(arc
					(start 141.999716 -270.846296)
					(mid 141.369796 -270.846296)
					(end 141.999716 -270.846296)
				)
			)
		)
	)
	(zone
		(layers "B.Cu" "In11.Cu" "In13.Cu" "In15.Cu")
		(hatch none 0.5)
		(connect_pads
			(clearance 0)
		)
		(min_thickness 0.25)
		(keepout
			(tracks not_allowed)
			(vias allowed)
			(pads allowed)
			(copperpour not_allowed)
			(footprints allowed)
		)
		(placement
			(enabled no)
			(sheetname "")
		)
		(fill yes
			(thermal_gap 0.5)
			(thermal_bridge_width 0.5)
			(island_removal_mode 0)
		)
		(polygon
			(pts
				(arc
					(start 120.849644 -282.996386)
					(mid 120.219724 -282.996386)
					(end 120.849644 -282.996386)
				)
			)
		)
	)
	(zone
		(layers "B.Cu" "In11.Cu" "In13.Cu" "In15.Cu")
		(hatch none 0.5)
		(connect_pads
			(clearance 0)
		)
		(min_thickness 0.25)
		(keepout
			(tracks not_allowed)
			(vias allowed)
			(pads allowed)
			(copperpour not_allowed)
			(footprints allowed)
		)
		(placement
			(enabled no)
			(sheetname "")
		)
		(fill yes
			(thermal_gap 0.5)
			(thermal_bridge_width 0.5)
			(island_removal_mode 0)
		)
		(polygon
			(pts
				(arc
					(start 107.696 -286.23641)
					(mid 107.06608 -286.23641)
					(end 107.696 -286.23641)
				)
			)
		)
	)
	(zone
		(layers "B.Cu" "In11.Cu" "In13.Cu" "In15.Cu")
		(hatch none 0.5)
		(connect_pads
			(clearance 0)
		)
		(min_thickness 0.25)
		(keepout
			(tracks not_allowed)
			(vias allowed)
			(pads allowed)
			(copperpour not_allowed)
			(footprints allowed)
		)
		(placement
			(enabled no)
			(sheetname "")
		)
		(fill yes
			(thermal_gap 0.5)
			(thermal_bridge_width 0.5)
			(island_removal_mode 0)
		)
		(polygon
			(pts
				(arc
					(start 25.486106 -244.935248)
					(mid 24.818086 -244.935248)
					(end 25.486106 -244.935248)
				)
			)
		)
	)
	(zone
		(layers "B.Cu" "In11.Cu" "In13.Cu" "In15.Cu")
		(hatch none 0.5)
		(connect_pads
			(clearance 0)
		)
		(min_thickness 0.25)
		(keepout
			(tracks not_allowed)
			(vias allowed)
			(pads allowed)
			(copperpour not_allowed)
			(footprints allowed)
		)
		(placement
			(enabled no)
			(sheetname "")
		)
		(fill yes
			(thermal_gap 0.5)
			(thermal_bridge_width 0.5)
			(island_removal_mode 0)
		)
		(polygon
			(pts
				(arc
					(start 128.136904 -427.089824)
					(mid 127.362712 -427.089824)
					(end 128.136904 -427.089824)
				)
			)
		)
	)
	(zone
		(layers "B.Cu" "In11.Cu" "In13.Cu" "In15.Cu")
		(hatch none 0.5)
		(connect_pads
			(clearance 0)
		)
		(min_thickness 0.25)
		(keepout
			(tracks not_allowed)
			(vias allowed)
			(pads allowed)
			(copperpour not_allowed)
			(footprints allowed)
		)
		(placement
			(enabled no)
			(sheetname "")
		)
		(fill yes
			(thermal_gap 0.5)
			(thermal_bridge_width 0.5)
			(island_removal_mode 0)
		)
		(polygon
			(pts
				(arc
					(start 81.845912 -269.226284)
					(mid 81.215992 -269.226284)
					(end 81.845912 -269.226284)
				)
			)
		)
	)
	(zone
		(layers "B.Cu" "In11.Cu" "In13.Cu" "In15.Cu")
		(hatch none 0.5)
		(connect_pads
			(clearance 0)
		)
		(min_thickness 0.25)
		(keepout
			(tracks not_allowed)
			(vias allowed)
			(pads allowed)
			(copperpour not_allowed)
			(footprints allowed)
		)
		(placement
			(enabled no)
			(sheetname "")
		)
		(fill yes
			(thermal_gap 0.5)
			(thermal_bridge_width 0.5)
			(island_removal_mode 0)
		)
		(polygon
			(pts
				(arc
					(start 102.05593 -284.616398)
					(mid 101.42601 -284.616398)
					(end 102.05593 -284.616398)
				)
			)
		)
	)
	(zone
		(layers "B.Cu" "In11.Cu" "In13.Cu" "In15.Cu")
		(hatch none 0.5)
		(connect_pads
			(clearance 0)
		)
		(min_thickness 0.25)
		(keepout
			(tracks not_allowed)
			(vias allowed)
			(pads allowed)
			(copperpour not_allowed)
			(footprints allowed)
		)
		(placement
			(enabled no)
			(sheetname "")
		)
		(fill yes
			(thermal_gap 0.5)
			(thermal_bridge_width 0.5)
			(island_removal_mode 0)
		)
		(polygon
			(pts
				(arc
					(start 446.978278 -317.18504)
					(mid 446.310258 -317.18504)
					(end 446.978278 -317.18504)
				)
			)
		)
	)
	(zone
		(layers "B.Cu" "In11.Cu" "In13.Cu" "In15.Cu")
		(hatch none 0.5)
		(connect_pads
			(clearance 0)
		)
		(min_thickness 0.25)
		(keepout
			(tracks not_allowed)
			(vias allowed)
			(pads allowed)
			(copperpour not_allowed)
			(footprints allowed)
		)
		(placement
			(enabled no)
			(sheetname "")
		)
		(fill yes
			(thermal_gap 0.5)
			(thermal_bridge_width 0.5)
			(island_removal_mode 0)
		)
		(polygon
			(pts
				(arc
					(start 389.63981 -242.054126)
					(mid 389.00989 -242.054126)
					(end 389.63981 -242.054126)
				)
			)
		)
	)
	(zone
		(layers "B.Cu" "In11.Cu" "In13.Cu" "In15.Cu")
		(hatch none 0.5)
		(connect_pads
			(clearance 0)
		)
		(min_thickness 0.25)
		(keepout
			(tracks not_allowed)
			(vias allowed)
			(pads allowed)
			(copperpour not_allowed)
			(footprints allowed)
		)
		(placement
			(enabled no)
			(sheetname "")
		)
		(fill yes
			(thermal_gap 0.5)
			(thermal_bridge_width 0.5)
			(island_removal_mode 0)
		)
		(polygon
			(pts
				(arc
					(start 82.037174 -427.089824)
					(mid 81.262982 -427.089824)
					(end 82.037174 -427.089824)
				)
			)
		)
	)
	(zone
		(layers "B.Cu" "In11.Cu" "In13.Cu" "In15.Cu")
		(hatch none 0.5)
		(connect_pads
			(clearance 0)
		)
		(min_thickness 0.25)
		(keepout
			(tracks not_allowed)
			(vias allowed)
			(pads allowed)
			(copperpour not_allowed)
			(footprints allowed)
		)
		(placement
			(enabled no)
			(sheetname "")
		)
		(fill yes
			(thermal_gap 0.5)
			(thermal_bridge_width 0.5)
			(island_removal_mode 0)
		)
		(polygon
			(pts
				(arc
					(start 214.28329 5.514594)
					(mid 213.61527 5.514594)
					(end 214.28329 5.514594)
				)
			)
		)
	)
	(zone
		(layers "B.Cu" "In11.Cu" "In13.Cu" "In15.Cu")
		(hatch none 0.5)
		(connect_pads
			(clearance 0)
		)
		(min_thickness 0.25)
		(keepout
			(tracks not_allowed)
			(vias allowed)
			(pads allowed)
			(copperpour not_allowed)
			(footprints allowed)
		)
		(placement
			(enabled no)
			(sheetname "")
		)
		(fill yes
			(thermal_gap 0.5)
			(thermal_bridge_width 0.5)
			(island_removal_mode 0)
		)
		(polygon
			(pts
				(arc
					(start 148.933916 -385.31038)
					(mid 148.303996 -385.31038)
					(end 148.933916 -385.31038)
				)
			)
		)
	)
	(zone
		(layers "B.Cu" "In11.Cu" "In13.Cu" "In15.Cu")
		(hatch none 0.5)
		(connect_pads
			(clearance 0)
		)
		(min_thickness 0.25)
		(keepout
			(tracks not_allowed)
			(vias allowed)
			(pads allowed)
			(copperpour not_allowed)
			(footprints allowed)
		)
		(placement
			(enabled no)
			(sheetname "")
		)
		(fill yes
			(thermal_gap 0.5)
			(thermal_bridge_width 0.5)
			(island_removal_mode 0)
		)
		(polygon
			(pts
				(arc
					(start 143.109696 -244.484398)
					(mid 142.479776 -244.484398)
					(end 143.109696 -244.484398)
				)
			)
		)
	)
	(zone
		(layers "B.Cu" "In11.Cu" "In13.Cu" "In15.Cu")
		(hatch none 0.5)
		(connect_pads
			(clearance 0)
		)
		(min_thickness 0.25)
		(keepout
			(tracks not_allowed)
			(vias allowed)
			(pads allowed)
			(copperpour not_allowed)
			(footprints allowed)
		)
		(placement
			(enabled no)
			(sheetname "")
		)
		(fill yes
			(thermal_gap 0.5)
			(thermal_bridge_width 0.5)
			(island_removal_mode 0)
		)
		(polygon
			(pts
				(arc
					(start 277.526242 -303.585118)
					(mid 276.858222 -303.585118)
					(end 277.526242 -303.585118)
				)
			)
		)
	)
	(zone
		(layers "B.Cu" "In11.Cu" "In13.Cu" "In15.Cu")
		(hatch none 0.5)
		(connect_pads
			(clearance 0)
		)
		(min_thickness 0.25)
		(keepout
			(tracks not_allowed)
			(vias allowed)
			(pads allowed)
			(copperpour not_allowed)
			(footprints allowed)
		)
		(placement
			(enabled no)
			(sheetname "")
		)
		(fill yes
			(thermal_gap 0.5)
			(thermal_bridge_width 0.5)
			(island_removal_mode 0)
		)
		(polygon
			(pts
				(arc
					(start 82.785966 -288.666174)
					(mid 82.156046 -288.666174)
					(end 82.785966 -288.666174)
				)
			)
		)
	)
	(zone
		(layers "B.Cu" "In11.Cu" "In13.Cu" "In15.Cu")
		(hatch none 0.5)
		(connect_pads
			(clearance 0)
		)
		(min_thickness 0.25)
		(keepout
			(tracks not_allowed)
			(vias allowed)
			(pads allowed)
			(copperpour not_allowed)
			(footprints allowed)
		)
		(placement
			(enabled no)
			(sheetname "")
		)
		(fill yes
			(thermal_gap 0.5)
			(thermal_bridge_width 0.5)
			(island_removal_mode 0)
		)
		(polygon
			(pts
				(arc
					(start 391.049764 -234.764072)
					(mid 390.419844 -234.764072)
					(end 391.049764 -234.764072)
				)
			)
		)
	)
	(zone
		(layers "B.Cu" "In11.Cu" "In13.Cu" "In15.Cu")
		(hatch none 0.5)
		(connect_pads
			(clearance 0)
		)
		(min_thickness 0.25)
		(keepout
			(tracks not_allowed)
			(vias allowed)
			(pads allowed)
			(copperpour not_allowed)
			(footprints allowed)
		)
		(placement
			(enabled no)
			(sheetname "")
		)
		(fill yes
			(thermal_gap 0.5)
			(thermal_bridge_width 0.5)
			(island_removal_mode 0)
		)
		(polygon
			(pts
				(arc
					(start 182.375556 -44.116498)
					(mid 181.707536 -44.116498)
					(end 182.375556 -44.116498)
				)
			)
		)
	)
	(zone
		(layers "B.Cu" "In11.Cu" "In13.Cu" "In15.Cu")
		(hatch none 0.5)
		(connect_pads
			(clearance 0)
		)
		(min_thickness 0.25)
		(keepout
			(tracks not_allowed)
			(vias allowed)
			(pads allowed)
			(copperpour not_allowed)
			(footprints allowed)
		)
		(placement
			(enabled no)
			(sheetname "")
		)
		(fill yes
			(thermal_gap 0.5)
			(thermal_bridge_width 0.5)
			(island_removal_mode 0)
		)
		(polygon
			(pts
				(arc
					(start 273.426174 -201.585068)
					(mid 272.758154 -201.585068)
					(end 273.426174 -201.585068)
				)
			)
		)
	)
	(zone
		(layers "B.Cu" "In11.Cu" "In13.Cu" "In15.Cu")
		(hatch none 0.5)
		(connect_pads
			(clearance 0)
		)
		(min_thickness 0.25)
		(keepout
			(tracks not_allowed)
			(vias allowed)
			(pads allowed)
			(copperpour not_allowed)
			(footprints allowed)
		)
		(placement
			(enabled no)
			(sheetname "")
		)
		(fill yes
			(thermal_gap 0.5)
			(thermal_bridge_width 0.5)
			(island_removal_mode 0)
		)
		(polygon
			(pts
				(arc
					(start 130.1369 -427.289976)
					(mid 129.362708 -427.289976)
					(end 130.1369 -427.289976)
				)
			)
		)
	)
	(zone
		(layers "B.Cu" "In11.Cu" "In13.Cu" "In15.Cu")
		(hatch none 0.5)
		(connect_pads
			(clearance 0)
		)
		(min_thickness 0.25)
		(keepout
			(tracks not_allowed)
			(vias allowed)
			(pads allowed)
			(copperpour not_allowed)
			(footprints allowed)
		)
		(placement
			(enabled no)
			(sheetname "")
		)
		(fill yes
			(thermal_gap 0.5)
			(thermal_bridge_width 0.5)
			(island_removal_mode 0)
		)
		(polygon
			(pts
				(arc
					(start 277.526242 -236.435138)
					(mid 276.858222 -236.435138)
					(end 277.526242 -236.435138)
				)
			)
		)
	)
	(zone
		(layers "B.Cu" "In11.Cu" "In13.Cu" "In15.Cu")
		(hatch none 0.5)
		(connect_pads
			(clearance 0)
		)
		(min_thickness 0.25)
		(keepout
			(tracks not_allowed)
			(vias allowed)
			(pads allowed)
			(copperpour not_allowed)
			(footprints allowed)
		)
		(placement
			(enabled no)
			(sheetname "")
		)
		(fill yes
			(thermal_gap 0.5)
			(thermal_bridge_width 0.5)
			(island_removal_mode 0)
		)
		(polygon
			(pts
				(arc
					(start 330.42606 -248.534174)
					(mid 329.79614 -248.534174)
					(end 330.42606 -248.534174)
				)
			)
		)
	)
	(zone
		(layers "B.Cu" "In11.Cu" "In13.Cu" "In15.Cu")
		(hatch none 0.5)
		(connect_pads
			(clearance 0)
		)
		(min_thickness 0.25)
		(keepout
			(tracks not_allowed)
			(vias allowed)
			(pads allowed)
			(copperpour not_allowed)
			(footprints allowed)
		)
		(placement
			(enabled no)
			(sheetname "")
		)
		(fill yes
			(thermal_gap 0.5)
			(thermal_bridge_width 0.5)
			(island_removal_mode 0)
		)
		(polygon
			(pts
				(arc
					(start 371.606318 -397.849344)
					(mid 370.976398 -397.849344)
					(end 371.606318 -397.849344)
				)
			)
		)
	)
	(zone
		(layers "B.Cu" "In11.Cu" "In13.Cu" "In15.Cu")
		(hatch none 0.5)
		(connect_pads
			(clearance 0)
		)
		(min_thickness 0.25)
		(keepout
			(tracks not_allowed)
			(vias allowed)
			(pads allowed)
			(copperpour not_allowed)
			(footprints allowed)
		)
		(placement
			(enabled no)
			(sheetname "")
		)
		(fill yes
			(thermal_gap 0.5)
			(thermal_bridge_width 0.5)
			(island_removal_mode 0)
		)
		(polygon
			(pts
				(arc
					(start 106.455972 -241.244374)
					(mid 105.826052 -241.244374)
					(end 106.455972 -241.244374)
				)
			)
		)
	)
	(zone
		(layers "B.Cu" "In11.Cu" "In13.Cu" "In15.Cu")
		(hatch none 0.5)
		(connect_pads
			(clearance 0)
		)
		(min_thickness 0.25)
		(keepout
			(tracks not_allowed)
			(vias allowed)
			(pads allowed)
			(copperpour not_allowed)
			(footprints allowed)
		)
		(placement
			(enabled no)
			(sheetname "")
		)
		(fill yes
			(thermal_gap 0.5)
			(thermal_bridge_width 0.5)
			(island_removal_mode 0)
		)
		(polygon
			(pts
				(arc
					(start 363.319822 -238.814102)
					(mid 362.689902 -238.814102)
					(end 363.319822 -238.814102)
				)
			)
		)
	)
	(zone
		(layers "B.Cu" "In11.Cu" "In13.Cu" "In15.Cu")
		(hatch none 0.5)
		(connect_pads
			(clearance 0)
		)
		(min_thickness 0.25)
		(keepout
			(tracks not_allowed)
			(vias allowed)
			(pads allowed)
			(copperpour not_allowed)
			(footprints allowed)
		)
		(placement
			(enabled no)
			(sheetname "")
		)
		(fill yes
			(thermal_gap 0.5)
			(thermal_bridge_width 0.5)
			(island_removal_mode 0)
		)
		(polygon
			(pts
				(arc
					(start 381.206248 -397.849344)
					(mid 380.576328 -397.849344)
					(end 381.206248 -397.849344)
				)
			)
		)
	)
	(zone
		(layers "B.Cu" "In11.Cu" "In13.Cu" "In15.Cu")
		(hatch none 0.5)
		(connect_pads
			(clearance 0)
		)
		(min_thickness 0.25)
		(keepout
			(tracks not_allowed)
			(vias allowed)
			(pads allowed)
			(copperpour not_allowed)
			(footprints allowed)
		)
		(placement
			(enabled no)
			(sheetname "")
		)
		(fill yes
			(thermal_gap 0.5)
			(thermal_bridge_width 0.5)
			(island_removal_mode 0)
		)
		(polygon
			(pts
				(arc
					(start 81.376012 -270.03629)
					(mid 80.746092 -270.03629)
					(end 81.376012 -270.03629)
				)
			)
		)
	)
	(zone
		(layers "B.Cu" "In11.Cu" "In13.Cu" "In15.Cu")
		(hatch none 0.5)
		(connect_pads
			(clearance 0)
		)
		(min_thickness 0.25)
		(keepout
			(tracks not_allowed)
			(vias allowed)
			(pads allowed)
			(copperpour not_allowed)
			(footprints allowed)
		)
		(placement
			(enabled no)
			(sheetname "")
		)
		(fill yes
			(thermal_gap 0.5)
			(thermal_bridge_width 0.5)
			(island_removal_mode 0)
		)
		(polygon
			(pts
				(arc
					(start 352.633788 -397.849344)
					(mid 352.003868 -397.849344)
					(end 352.633788 -397.849344)
				)
			)
		)
	)
	(zone
		(layers "B.Cu" "In11.Cu" "In13.Cu" "In15.Cu")
		(hatch none 0.5)
		(connect_pads
			(clearance 0)
		)
		(min_thickness 0.25)
		(keepout
			(tracks not_allowed)
			(vias allowed)
			(pads allowed)
			(copperpour not_allowed)
			(footprints allowed)
		)
		(placement
			(enabled no)
			(sheetname "")
		)
		(fill yes
			(thermal_gap 0.5)
			(thermal_bridge_width 0.5)
			(island_removal_mode 0)
		)
		(polygon
			(pts
				(arc
					(start 330.726034 -278.946102)
					(mid 330.096114 -278.946102)
					(end 330.726034 -278.946102)
				)
			)
		)
	)
	(zone
		(layers "B.Cu" "In11.Cu" "In13.Cu" "In15.Cu")
		(hatch none 0.5)
		(connect_pads
			(clearance 0)
		)
		(min_thickness 0.25)
		(keepout
			(tracks not_allowed)
			(vias allowed)
			(pads allowed)
			(copperpour not_allowed)
			(footprints allowed)
		)
		(placement
			(enabled no)
			(sheetname "")
		)
		(fill yes
			(thermal_gap 0.5)
			(thermal_bridge_width 0.5)
			(island_removal_mode 0)
		)
		(polygon
			(pts
				(arc
					(start 29.586174 -203.285344)
					(mid 28.918154 -203.285344)
					(end 29.586174 -203.285344)
				)
			)
		)
	)
	(zone
		(layers "B.Cu" "In11.Cu" "In13.Cu" "In15.Cu")
		(hatch none 0.5)
		(connect_pads
			(clearance 0)
		)
		(min_thickness 0.25)
		(keepout
			(tracks not_allowed)
			(vias allowed)
			(pads allowed)
			(copperpour not_allowed)
			(footprints allowed)
		)
		(placement
			(enabled no)
			(sheetname "")
		)
		(fill yes
			(thermal_gap 0.5)
			(thermal_bridge_width 0.5)
			(island_removal_mode 0)
		)
		(polygon
			(pts
				(arc
					(start 442.87821 -229.63505)
					(mid 442.21019 -229.63505)
					(end 442.87821 -229.63505)
				)
			)
		)
	)
	(zone
		(layers "B.Cu" "In11.Cu" "In13.Cu" "In15.Cu")
		(hatch none 0.5)
		(connect_pads
			(clearance 0)
		)
		(min_thickness 0.25)
		(keepout
			(tracks not_allowed)
			(vias allowed)
			(pads allowed)
			(copperpour not_allowed)
			(footprints allowed)
		)
		(placement
			(enabled no)
			(sheetname "")
		)
		(fill yes
			(thermal_gap 0.5)
			(thermal_bridge_width 0.5)
			(island_removal_mode 0)
		)
		(polygon
			(pts
				(arc
					(start 29.586174 -317.185294)
					(mid 28.918154 -317.185294)
					(end 29.586174 -317.185294)
				)
			)
		)
	)
	(zone
		(layers "B.Cu" "In11.Cu" "In13.Cu" "In15.Cu")
		(hatch none 0.5)
		(connect_pads
			(clearance 0)
		)
		(min_thickness 0.25)
		(keepout
			(tracks not_allowed)
			(vias allowed)
			(pads allowed)
			(copperpour not_allowed)
			(footprints allowed)
		)
		(placement
			(enabled no)
			(sheetname "")
		)
		(fill yes
			(thermal_gap 0.5)
			(thermal_bridge_width 0.5)
			(island_removal_mode 0)
		)
		(polygon
			(pts
				(arc
					(start 90.037158 -427.089824)
					(mid 89.262966 -427.089824)
					(end 90.037158 -427.089824)
				)
			)
		)
	)
	(zone
		(layers "B.Cu" "In11.Cu" "In13.Cu" "In15.Cu")
		(hatch none 0.5)
		(connect_pads
			(clearance 0)
		)
		(min_thickness 0.25)
		(keepout
			(tracks not_allowed)
			(vias allowed)
			(pads allowed)
			(copperpour not_allowed)
			(footprints allowed)
		)
		(placement
			(enabled no)
			(sheetname "")
		)
		(fill yes
			(thermal_gap 0.5)
			(thermal_bridge_width 0.5)
			(island_removal_mode 0)
		)
		(polygon
			(pts
				(arc
					(start 403.137116 -427.289976)
					(mid 402.362924 -427.289976)
					(end 403.137116 -427.289976)
				)
			)
		)
	)
	(zone
		(layers "B.Cu" "In11.Cu" "In13.Cu" "In15.Cu")
		(hatch none 0.5)
		(connect_pads
			(clearance 0)
		)
		(min_thickness 0.25)
		(keepout
			(tracks not_allowed)
			(vias allowed)
			(pads allowed)
			(copperpour not_allowed)
			(footprints allowed)
		)
		(placement
			(enabled no)
			(sheetname "")
		)
		(fill yes
			(thermal_gap 0.5)
			(thermal_bridge_width 0.5)
			(island_removal_mode 0)
		)
		(polygon
			(pts
				(arc
					(start 343.833704 -397.156432)
					(mid 343.203784 -397.156432)
					(end 343.833704 -397.156432)
				)
			)
		)
	)
	(zone
		(layers "B.Cu" "In11.Cu" "In13.Cu" "In15.Cu")
		(hatch none 0.5)
		(connect_pads
			(clearance 0)
		)
		(min_thickness 0.25)
		(keepout
			(tracks not_allowed)
			(vias allowed)
			(pads allowed)
			(copperpour not_allowed)
			(footprints allowed)
		)
		(placement
			(enabled no)
			(sheetname "")
		)
		(fill yes
			(thermal_gap 0.5)
			(thermal_bridge_width 0.5)
			(island_removal_mode 0)
		)
		(polygon
			(pts
				(arc
					(start 86.037166 -427.089824)
					(mid 85.262974 -427.089824)
					(end 86.037166 -427.089824)
				)
			)
		)
	)
	(zone
		(layers "B.Cu" "In11.Cu" "In13.Cu" "In15.Cu")
		(hatch none 0.5)
		(connect_pads
			(clearance 0)
		)
		(min_thickness 0.25)
		(keepout
			(tracks not_allowed)
			(vias allowed)
			(pads allowed)
			(copperpour not_allowed)
			(footprints allowed)
		)
		(placement
			(enabled no)
			(sheetname "")
		)
		(fill yes
			(thermal_gap 0.5)
			(thermal_bridge_width 0.5)
			(island_removal_mode 0)
		)
		(polygon
			(pts
				(arc
					(start 442.87821 -246.635016)
					(mid 442.21019 -246.635016)
					(end 442.87821 -246.635016)
				)
			)
		)
	)
	(zone
		(layers "B.Cu" "In11.Cu" "In13.Cu" "In15.Cu")
		(hatch none 0.5)
		(connect_pads
			(clearance 0)
		)
		(min_thickness 0.25)
		(keepout
			(tracks not_allowed)
			(vias allowed)
			(pads allowed)
			(copperpour not_allowed)
			(footprints allowed)
		)
		(placement
			(enabled no)
			(sheetname "")
		)
		(fill yes
			(thermal_gap 0.5)
			(thermal_bridge_width 0.5)
			(island_removal_mode 0)
		)
		(polygon
			(pts
				(arc
					(start 331.195934 -274.896072)
					(mid 330.566014 -274.896072)
					(end 331.195934 -274.896072)
				)
			)
		)
	)
	(zone
		(layers "B.Cu" "In11.Cu" "In13.Cu" "In15.Cu")
		(hatch none 0.5)
		(connect_pads
			(clearance 0)
		)
		(min_thickness 0.25)
		(keepout
			(tracks not_allowed)
			(vias allowed)
			(pads allowed)
			(copperpour not_allowed)
			(footprints allowed)
		)
		(placement
			(enabled no)
			(sheetname "")
		)
		(fill yes
			(thermal_gap 0.5)
			(thermal_bridge_width 0.5)
			(island_removal_mode 0)
		)
		(polygon
			(pts
				(arc
					(start 329.31608 -284.616144)
					(mid 328.68616 -284.616144)
					(end 329.31608 -284.616144)
				)
			)
		)
	)
	(zone
		(layers "B.Cu" "In11.Cu" "In13.Cu" "In15.Cu")
		(hatch none 0.5)
		(connect_pads
			(clearance 0)
		)
		(min_thickness 0.25)
		(keepout
			(tracks not_allowed)
			(vias allowed)
			(pads allowed)
			(copperpour not_allowed)
			(footprints allowed)
		)
		(placement
			(enabled no)
			(sheetname "")
		)
		(fill yes
			(thermal_gap 0.5)
			(thermal_bridge_width 0.5)
			(island_removal_mode 0)
		)
		(polygon
			(pts
				(arc
					(start 297.764454 -385.21386)
					(mid 297.096434 -385.21386)
					(end 297.764454 -385.21386)
				)
			)
		)
	)
	(zone
		(layers "B.Cu" "In11.Cu" "In13.Cu" "In15.Cu")
		(hatch none 0.5)
		(connect_pads
			(clearance 0)
		)
		(min_thickness 0.25)
		(keepout
			(tracks not_allowed)
			(vias allowed)
			(pads allowed)
			(copperpour not_allowed)
			(footprints allowed)
		)
		(placement
			(enabled no)
			(sheetname "")
		)
		(fill yes
			(thermal_gap 0.5)
			(thermal_bridge_width 0.5)
			(island_removal_mode 0)
		)
		(polygon
			(pts
				(arc
					(start 389.939784 -282.186126)
					(mid 389.309864 -282.186126)
					(end 389.939784 -282.186126)
				)
			)
		)
	)
	(zone
		(layers "B.Cu" "In11.Cu" "In13.Cu" "In15.Cu")
		(hatch none 0.5)
		(connect_pads
			(clearance 0)
		)
		(min_thickness 0.25)
		(keepout
			(tracks not_allowed)
			(vias allowed)
			(pads allowed)
			(copperpour not_allowed)
			(footprints allowed)
		)
		(placement
			(enabled no)
			(sheetname "")
		)
		(fill yes
			(thermal_gap 0.5)
			(thermal_bridge_width 0.5)
			(island_removal_mode 0)
		)
		(polygon
			(pts
				(arc
					(start 330.42606 -227.474272)
					(mid 329.79614 -227.474272)
					(end 330.42606 -227.474272)
				)
			)
		)
	)
	(zone
		(layers "B.Cu" "In11.Cu" "In13.Cu" "In15.Cu")
		(hatch none 0.5)
		(connect_pads
			(clearance 0)
		)
		(min_thickness 0.25)
		(keepout
			(tracks not_allowed)
			(vias allowed)
			(pads allowed)
			(copperpour not_allowed)
			(footprints allowed)
		)
		(placement
			(enabled no)
			(sheetname "")
		)
		(fill yes
			(thermal_gap 0.5)
			(thermal_bridge_width 0.5)
			(island_removal_mode 0)
		)
		(polygon
			(pts
				(arc
					(start 157.734 -386.003292)
					(mid 157.10408 -386.003292)
					(end 157.734 -386.003292)
				)
			)
		)
	)
	(zone
		(layers "B.Cu" "In11.Cu" "In13.Cu" "In15.Cu")
		(hatch none 0.5)
		(connect_pads
			(clearance 0)
		)
		(min_thickness 0.25)
		(keepout
			(tracks not_allowed)
			(vias allowed)
			(pads allowed)
			(copperpour not_allowed)
			(footprints allowed)
		)
		(placement
			(enabled no)
			(sheetname "")
		)
		(fill yes
			(thermal_gap 0.5)
			(thermal_bridge_width 0.5)
			(island_removal_mode 0)
		)
		(polygon
			(pts
				(arc
					(start 277.526242 -315.485018)
					(mid 276.858222 -315.485018)
					(end 277.526242 -315.485018)
				)
			)
		)
	)
	(zone
		(layers "B.Cu" "In11.Cu" "In13.Cu" "In15.Cu")
		(hatch none 0.5)
		(connect_pads
			(clearance 0)
		)
		(min_thickness 0.25)
		(keepout
			(tracks not_allowed)
			(vias allowed)
			(pads allowed)
			(copperpour not_allowed)
			(footprints allowed)
		)
		(placement
			(enabled no)
			(sheetname "")
		)
		(fill yes
			(thermal_gap 0.5)
			(thermal_bridge_width 0.5)
			(island_removal_mode 0)
		)
		(polygon
			(pts
				(arc
					(start 141.529816 -292.716204)
					(mid 140.899896 -292.716204)
					(end 141.529816 -292.716204)
				)
			)
		)
	)
	(zone
		(layers "B.Cu" "In11.Cu" "In13.Cu" "In15.Cu")
		(hatch none 0.5)
		(connect_pads
			(clearance 0)
		)
		(min_thickness 0.25)
		(keepout
			(tracks not_allowed)
			(vias allowed)
			(pads allowed)
			(copperpour not_allowed)
			(footprints allowed)
		)
		(placement
			(enabled no)
			(sheetname "")
		)
		(fill yes
			(thermal_gap 0.5)
			(thermal_bridge_width 0.5)
			(island_removal_mode 0)
		)
		(polygon
			(pts
				(arc
					(start 199.03821 -301.88535)
					(mid 198.37019 -301.88535)
					(end 199.03821 -301.88535)
				)
			)
		)
	)
	(zone
		(layers "B.Cu" "In11.Cu" "In13.Cu" "In15.Cu")
		(hatch none 0.5)
		(connect_pads
			(clearance 0)
		)
		(min_thickness 0.25)
		(keepout
			(tracks not_allowed)
			(vias allowed)
			(pads allowed)
			(copperpour not_allowed)
			(footprints allowed)
		)
		(placement
			(enabled no)
			(sheetname "")
		)
		(fill yes
			(thermal_gap 0.5)
			(thermal_bridge_width 0.5)
			(island_removal_mode 0)
		)
		(polygon
			(pts
				(arc
					(start 29.586174 -303.585372)
					(mid 28.918154 -303.585372)
					(end 29.586174 -303.585372)
				)
			)
		)
	)
	(zone
		(layers "B.Cu" "In11.Cu" "In13.Cu" "In15.Cu")
		(hatch none 0.5)
		(connect_pads
			(clearance 0)
		)
		(min_thickness 0.25)
		(keepout
			(tracks not_allowed)
			(vias allowed)
			(pads allowed)
			(copperpour not_allowed)
			(footprints allowed)
		)
		(placement
			(enabled no)
			(sheetname "")
		)
		(fill yes
			(thermal_gap 0.5)
			(thermal_bridge_width 0.5)
			(island_removal_mode 0)
		)
		(polygon
			(pts
				(arc
					(start 25.486106 -238.985298)
					(mid 24.818086 -238.985298)
					(end 25.486106 -238.985298)
				)
			)
		)
	)
	(zone
		(layers "B.Cu" "In11.Cu" "In13.Cu" "In15.Cu")
		(hatch none 0.5)
		(connect_pads
			(clearance 0)
		)
		(min_thickness 0.25)
		(keepout
			(tracks not_allowed)
			(vias allowed)
			(pads allowed)
			(copperpour not_allowed)
			(footprints allowed)
		)
		(placement
			(enabled no)
			(sheetname "")
		)
		(fill yes
			(thermal_gap 0.5)
			(thermal_bridge_width 0.5)
			(island_removal_mode 0)
		)
		(polygon
			(pts
				(arc
					(start 25.486106 -251.735336)
					(mid 24.818086 -251.735336)
					(end 25.486106 -251.735336)
				)
			)
		)
	)
	(zone
		(layers "B.Cu" "In11.Cu" "In13.Cu" "In15.Cu")
		(hatch none 0.5)
		(connect_pads
			(clearance 0)
		)
		(min_thickness 0.25)
		(keepout
			(tracks not_allowed)
			(vias allowed)
			(pads allowed)
			(copperpour not_allowed)
			(footprints allowed)
		)
		(placement
			(enabled no)
			(sheetname "")
		)
		(fill yes
			(thermal_gap 0.5)
			(thermal_bridge_width 0.5)
			(island_removal_mode 0)
		)
		(polygon
			(pts
				(arc
					(start 143.40967 -271.656302)
					(mid 142.77975 -271.656302)
					(end 143.40967 -271.656302)
				)
			)
		)
	)
	(zone
		(layers "B.Cu" "In11.Cu" "In13.Cu" "In15.Cu")
		(hatch none 0.5)
		(connect_pads
			(clearance 0)
		)
		(min_thickness 0.25)
		(keepout
			(tracks not_allowed)
			(vias allowed)
			(pads allowed)
			(copperpour not_allowed)
			(footprints allowed)
		)
		(placement
			(enabled no)
			(sheetname "")
		)
		(fill yes
			(thermal_gap 0.5)
			(thermal_bridge_width 0.5)
			(island_removal_mode 0)
		)
		(polygon
			(pts
				(arc
					(start 373.189754 -239.624108)
					(mid 372.559834 -239.624108)
					(end 373.189754 -239.624108)
				)
			)
		)
	)
	(zone
		(layers "B.Cu" "In11.Cu" "In13.Cu" "In15.Cu")
		(hatch none 0.5)
		(connect_pads
			(clearance 0)
		)
		(min_thickness 0.25)
		(keepout
			(tracks not_allowed)
			(vias allowed)
			(pads allowed)
			(copperpour not_allowed)
			(footprints allowed)
		)
		(placement
			(enabled no)
			(sheetname "")
		)
		(fill yes
			(thermal_gap 0.5)
			(thermal_bridge_width 0.5)
			(island_removal_mode 0)
		)
		(polygon
			(pts
				(arc
					(start 442.87821 -301.034958)
					(mid 442.21019 -301.034958)
					(end 442.87821 -301.034958)
				)
			)
		)
	)
	(zone
		(layers "B.Cu" "In11.Cu" "In13.Cu" "In15.Cu")
		(hatch none 0.5)
		(connect_pads
			(clearance 0)
		)
		(min_thickness 0.25)
		(keepout
			(tracks not_allowed)
			(vias allowed)
			(pads allowed)
			(copperpour not_allowed)
			(footprints allowed)
		)
		(placement
			(enabled no)
			(sheetname "")
		)
		(fill yes
			(thermal_gap 0.5)
			(thermal_bridge_width 0.5)
			(island_removal_mode 0)
		)
		(polygon
			(pts
				(arc
					(start 419.733984 -394.385292)
					(mid 419.104064 -394.385292)
					(end 419.733984 -394.385292)
				)
			)
		)
	)
	(zone
		(layers "B.Cu" "In11.Cu" "In13.Cu" "In15.Cu")
		(hatch none 0.5)
		(connect_pads
			(clearance 0)
		)
		(min_thickness 0.25)
		(keepout
			(tracks not_allowed)
			(vias allowed)
			(pads allowed)
			(copperpour not_allowed)
			(footprints allowed)
		)
		(placement
			(enabled no)
			(sheetname "")
		)
		(fill yes
			(thermal_gap 0.5)
			(thermal_bridge_width 0.5)
			(island_removal_mode 0)
		)
		(polygon
			(pts
				(arc
					(start 330.42606 -235.574078)
					(mid 329.79614 -235.574078)
					(end 330.42606 -235.574078)
				)
			)
		)
	)
	(zone
		(layers "B.Cu" "In11.Cu" "In13.Cu" "In15.Cu")
		(hatch none 0.5)
		(connect_pads
			(clearance 0)
		)
		(min_thickness 0.25)
		(keepout
			(tracks not_allowed)
			(vias allowed)
			(pads allowed)
			(copperpour not_allowed)
			(footprints allowed)
		)
		(placement
			(enabled no)
			(sheetname "")
		)
		(fill yes
			(thermal_gap 0.5)
			(thermal_bridge_width 0.5)
			(island_removal_mode 0)
		)
		(polygon
			(pts
				(arc
					(start 199.03821 -233.035348)
					(mid 198.37019 -233.035348)
					(end 199.03821 -233.035348)
				)
			)
		)
	)
	(zone
		(layers "B.Cu" "In11.Cu" "In13.Cu" "In15.Cu")
		(hatch none 0.5)
		(connect_pads
			(clearance 0)
		)
		(min_thickness 0.25)
		(keepout
			(tracks not_allowed)
			(vias allowed)
			(pads allowed)
			(copperpour not_allowed)
			(footprints allowed)
		)
		(placement
			(enabled no)
			(sheetname "")
		)
		(fill yes
			(thermal_gap 0.5)
			(thermal_bridge_width 0.5)
			(island_removal_mode 0)
		)
		(polygon
			(pts
				(arc
					(start 390.579864 -243.674138)
					(mid 389.949944 -243.674138)
					(end 390.579864 -243.674138)
				)
			)
		)
	)
	(zone
		(layers "B.Cu" "In11.Cu" "In13.Cu" "In15.Cu")
		(hatch none 0.5)
		(connect_pads
			(clearance 0)
		)
		(min_thickness 0.25)
		(keepout
			(tracks not_allowed)
			(vias allowed)
			(pads allowed)
			(copperpour not_allowed)
			(footprints allowed)
		)
		(placement
			(enabled no)
			(sheetname "")
		)
		(fill yes
			(thermal_gap 0.5)
			(thermal_bridge_width 0.5)
			(island_removal_mode 0)
		)
		(polygon
			(pts
				(arc
					(start 25.486106 -305.285394)
					(mid 24.818086 -305.285394)
					(end 25.486106 -305.285394)
				)
			)
		)
	)
	(zone
		(layers "B.Cu" "In11.Cu" "In13.Cu" "In15.Cu")
		(hatch none 0.5)
		(connect_pads
			(clearance 0)
		)
		(min_thickness 0.25)
		(keepout
			(tracks not_allowed)
			(vias allowed)
			(pads allowed)
			(copperpour not_allowed)
			(footprints allowed)
		)
		(placement
			(enabled no)
			(sheetname "")
		)
		(fill yes
			(thermal_gap 0.5)
			(thermal_bridge_width 0.5)
			(island_removal_mode 0)
		)
		(polygon
			(pts
				(arc
					(start 442.87821 -251.735082)
					(mid 442.21019 -251.735082)
					(end 442.87821 -251.735082)
				)
			)
		)
	)
	(zone
		(layers "B.Cu" "In11.Cu" "In13.Cu" "In15.Cu")
		(hatch none 0.5)
		(connect_pads
			(clearance 0)
		)
		(min_thickness 0.25)
		(keepout
			(tracks not_allowed)
			(vias allowed)
			(pads allowed)
			(copperpour not_allowed)
			(footprints allowed)
		)
		(placement
			(enabled no)
			(sheetname "")
		)
		(fill yes
			(thermal_gap 0.5)
			(thermal_bridge_width 0.5)
			(island_removal_mode 0)
		)
		(polygon
			(pts
				(arc
					(start 81.845912 -285.426404)
					(mid 81.215992 -285.426404)
					(end 81.845912 -285.426404)
				)
			)
		)
	)
	(zone
		(layers "B.Cu" "In11.Cu" "In13.Cu" "In15.Cu")
		(hatch none 0.5)
		(connect_pads
			(clearance 0)
		)
		(min_thickness 0.25)
		(keepout
			(tracks not_allowed)
			(vias allowed)
			(pads allowed)
			(copperpour not_allowed)
			(footprints allowed)
		)
		(placement
			(enabled no)
			(sheetname "")
		)
		(fill yes
			(thermal_gap 0.5)
			(thermal_bridge_width 0.5)
			(island_removal_mode 0)
		)
		(polygon
			(pts
				(arc
					(start 84.03717 -426.089826)
					(mid 83.262978 -426.089826)
					(end 84.03717 -426.089826)
				)
			)
		)
	)
	(zone
		(layers "B.Cu" "In11.Cu" "In13.Cu" "In15.Cu")
		(hatch none 0.5)
		(connect_pads
			(clearance 0)
		)
		(min_thickness 0.25)
		(keepout
			(tracks not_allowed)
			(vias allowed)
			(pads allowed)
			(copperpour not_allowed)
			(footprints allowed)
		)
		(placement
			(enabled no)
			(sheetname "")
		)
		(fill yes
			(thermal_gap 0.5)
			(thermal_bridge_width 0.5)
			(island_removal_mode 0)
		)
		(polygon
			(pts
				(arc
					(start 371.309646 -239.624108)
					(mid 370.679726 -239.624108)
					(end 371.309646 -239.624108)
				)
			)
		)
	)
	(zone
		(layers "B.Cu" "In11.Cu" "In13.Cu" "In15.Cu")
		(hatch none 0.5)
		(connect_pads
			(clearance 0)
		)
		(min_thickness 0.25)
		(keepout
			(tracks not_allowed)
			(vias allowed)
			(pads allowed)
			(copperpour not_allowed)
			(footprints allowed)
		)
		(placement
			(enabled no)
			(sheetname "")
		)
		(fill yes
			(thermal_gap 0.5)
			(thermal_bridge_width 0.5)
			(island_removal_mode 0)
		)
		(polygon
			(pts
				(arc
					(start 391.049764 -225.044254)
					(mid 390.419844 -225.044254)
					(end 391.049764 -225.044254)
				)
			)
		)
	)
	(zone
		(layers "B.Cu" "In11.Cu" "In13.Cu" "In15.Cu")
		(hatch none 0.5)
		(connect_pads
			(clearance 0)
		)
		(min_thickness 0.25)
		(keepout
			(tracks not_allowed)
			(vias allowed)
			(pads allowed)
			(copperpour not_allowed)
			(footprints allowed)
		)
		(placement
			(enabled no)
			(sheetname "")
		)
		(fill yes
			(thermal_gap 0.5)
			(thermal_bridge_width 0.5)
			(island_removal_mode 0)
		)
		(polygon
			(pts
				(arc
					(start 81.545938 -235.574332)
					(mid 80.916018 -235.574332)
					(end 81.545938 -235.574332)
				)
			)
		)
	)
	(zone
		(layers "B.Cu" "In11.Cu" "In13.Cu" "In15.Cu")
		(hatch none 0.5)
		(connect_pads
			(clearance 0)
		)
		(min_thickness 0.25)
		(keepout
			(tracks not_allowed)
			(vias allowed)
			(pads allowed)
			(copperpour not_allowed)
			(footprints allowed)
		)
		(placement
			(enabled no)
			(sheetname "")
		)
		(fill yes
			(thermal_gap 0.5)
			(thermal_bridge_width 0.5)
			(island_removal_mode 0)
		)
		(polygon
			(pts
				(arc
					(start 119.90959 -286.23641)
					(mid 119.27967 -286.23641)
					(end 119.90959 -286.23641)
				)
			)
		)
	)
	(zone
		(layers "B.Cu" "In11.Cu" "In13.Cu" "In15.Cu")
		(hatch none 0.5)
		(connect_pads
			(clearance 0)
		)
		(min_thickness 0.25)
		(keepout
			(tracks not_allowed)
			(vias allowed)
			(pads allowed)
			(copperpour not_allowed)
			(footprints allowed)
		)
		(placement
			(enabled no)
			(sheetname "")
		)
		(fill yes
			(thermal_gap 0.5)
			(thermal_bridge_width 0.5)
			(island_removal_mode 0)
		)
		(polygon
			(pts
				(arc
					(start 391.349738 -279.756108)
					(mid 390.719818 -279.756108)
					(end 391.349738 -279.756108)
				)
			)
		)
	)
	(zone
		(layers "B.Cu" "In11.Cu" "In13.Cu" "In15.Cu")
		(hatch none 0.5)
		(connect_pads
			(clearance 0)
		)
		(min_thickness 0.25)
		(keepout
			(tracks not_allowed)
			(vias allowed)
			(pads allowed)
			(copperpour not_allowed)
			(footprints allowed)
		)
		(placement
			(enabled no)
			(sheetname "")
		)
		(fill yes
			(thermal_gap 0.5)
			(thermal_bridge_width 0.5)
			(island_removal_mode 0)
		)
		(polygon
			(pts
				(arc
					(start 273.426174 -304.435002)
					(mid 272.758154 -304.435002)
					(end 273.426174 -304.435002)
				)
			)
		)
	)
	(zone
		(layers "B.Cu" "In11.Cu" "In13.Cu" "In15.Cu")
		(hatch none 0.5)
		(connect_pads
			(clearance 0)
		)
		(min_thickness 0.25)
		(keepout
			(tracks not_allowed)
			(vias allowed)
			(pads allowed)
			(copperpour not_allowed)
			(footprints allowed)
		)
		(placement
			(enabled no)
			(sheetname "")
		)
		(fill yes
			(thermal_gap 0.5)
			(thermal_bridge_width 0.5)
			(island_removal_mode 0)
		)
		(polygon
			(pts
				(arc
					(start 142.93977 -280.566368)
					(mid 142.30985 -280.566368)
					(end 142.93977 -280.566368)
				)
			)
		)
	)
	(zone
		(layers "B.Cu" "In11.Cu" "In13.Cu" "In15.Cu")
		(hatch none 0.5)
		(connect_pads
			(clearance 0)
		)
		(min_thickness 0.25)
		(keepout
			(tracks not_allowed)
			(vias allowed)
			(pads allowed)
			(copperpour not_allowed)
			(footprints allowed)
		)
		(placement
			(enabled no)
			(sheetname "")
		)
		(fill yes
			(thermal_gap 0.5)
			(thermal_bridge_width 0.5)
			(island_removal_mode 0)
		)
		(polygon
			(pts
				(arc
					(start 107.396026 -238.00435)
					(mid 106.766106 -238.00435)
					(end 107.396026 -238.00435)
				)
			)
		)
	)
	(zone
		(layers "B.Cu" "In11.Cu" "In13.Cu" "In15.Cu")
		(hatch none 0.5)
		(connect_pads
			(clearance 0)
		)
		(min_thickness 0.25)
		(keepout
			(tracks not_allowed)
			(vias allowed)
			(pads allowed)
			(copperpour not_allowed)
			(footprints allowed)
		)
		(placement
			(enabled no)
			(sheetname "")
		)
		(fill yes
			(thermal_gap 0.5)
			(thermal_bridge_width 0.5)
			(island_removal_mode 0)
		)
		(polygon
			(pts
				(arc
					(start 273.426174 -198.185024)
					(mid 272.758154 -198.185024)
					(end 273.426174 -198.185024)
				)
			)
		)
	)
	(zone
		(layers "B.Cu" "In11.Cu" "In13.Cu" "In15.Cu")
		(hatch none 0.5)
		(connect_pads
			(clearance 0)
		)
		(min_thickness 0.25)
		(keepout
			(tracks not_allowed)
			(vias allowed)
			(pads allowed)
			(copperpour not_allowed)
			(footprints allowed)
		)
		(placement
			(enabled no)
			(sheetname "")
		)
		(fill yes
			(thermal_gap 0.5)
			(thermal_bridge_width 0.5)
			(island_removal_mode 0)
		)
		(polygon
			(pts
				(arc
					(start 389.63981 -251.774198)
					(mid 389.00989 -251.774198)
					(end 389.63981 -251.774198)
				)
			)
		)
	)
	(zone
		(layers "B.Cu" "In11.Cu" "In13.Cu" "In15.Cu")
		(hatch none 0.5)
		(connect_pads
			(clearance 0)
		)
		(min_thickness 0.25)
		(keepout
			(tracks not_allowed)
			(vias allowed)
			(pads allowed)
			(copperpour not_allowed)
			(footprints allowed)
		)
		(placement
			(enabled no)
			(sheetname "")
		)
		(fill yes
			(thermal_gap 0.5)
			(thermal_bridge_width 0.5)
			(island_removal_mode 0)
		)
		(polygon
			(pts
				(arc
					(start 199.03821 -285.735268)
					(mid 198.37019 -285.735268)
					(end 199.03821 -285.735268)
				)
			)
		)
	)
	(zone
		(layers "B.Cu" "In11.Cu" "In13.Cu" "In15.Cu")
		(hatch none 0.5)
		(connect_pads
			(clearance 0)
		)
		(min_thickness 0.25)
		(keepout
			(tracks not_allowed)
			(vias allowed)
			(pads allowed)
			(copperpour not_allowed)
			(footprints allowed)
		)
		(placement
			(enabled no)
			(sheetname "")
		)
		(fill yes
			(thermal_gap 0.5)
			(thermal_bridge_width 0.5)
			(island_removal_mode 0)
		)
		(polygon
			(pts
				(arc
					(start 117.089682 -284.616398)
					(mid 116.459762 -284.616398)
					(end 117.089682 -284.616398)
				)
			)
		)
	)
	(zone
		(layers "B.Cu" "In11.Cu" "In13.Cu" "In15.Cu")
		(hatch none 0.5)
		(connect_pads
			(clearance 0)
		)
		(min_thickness 0.25)
		(keepout
			(tracks not_allowed)
			(vias allowed)
			(pads allowed)
			(copperpour not_allowed)
			(footprints allowed)
		)
		(placement
			(enabled no)
			(sheetname "")
		)
		(fill yes
			(thermal_gap 0.5)
			(thermal_bridge_width 0.5)
			(island_removal_mode 0)
		)
		(polygon
			(pts
				(arc
					(start 199.03821 -266.185396)
					(mid 198.37019 -266.185396)
					(end 199.03821 -266.185396)
				)
			)
		)
	)
	(zone
		(layers "B.Cu" "In11.Cu" "In13.Cu" "In15.Cu")
		(hatch none 0.5)
		(connect_pads
			(clearance 0)
		)
		(min_thickness 0.25)
		(keepout
			(tracks not_allowed)
			(vias allowed)
			(pads allowed)
			(copperpour not_allowed)
			(footprints allowed)
		)
		(placement
			(enabled no)
			(sheetname "")
		)
		(fill yes
			(thermal_gap 0.5)
			(thermal_bridge_width 0.5)
			(island_removal_mode 0)
		)
		(polygon
			(pts
				(arc
					(start 141.999716 -262.746236)
					(mid 141.369796 -262.746236)
					(end 141.999716 -262.746236)
				)
			)
		)
	)
	(zone
		(layers "B.Cu" "In11.Cu" "In13.Cu" "In15.Cu")
		(hatch none 0.5)
		(connect_pads
			(clearance 0)
		)
		(min_thickness 0.25)
		(keepout
			(tracks not_allowed)
			(vias allowed)
			(pads allowed)
			(copperpour not_allowed)
			(footprints allowed)
		)
		(placement
			(enabled no)
			(sheetname "")
		)
		(fill yes
			(thermal_gap 0.5)
			(thermal_bridge_width 0.5)
			(island_removal_mode 0)
		)
		(polygon
			(pts
				(arc
					(start 199.03821 -296.785284)
					(mid 198.37019 -296.785284)
					(end 199.03821 -296.785284)
				)
			)
		)
	)
	(zone
		(layers "B.Cu" "In11.Cu" "In13.Cu" "In15.Cu")
		(hatch none 0.5)
		(connect_pads
			(clearance 0)
		)
		(min_thickness 0.25)
		(keepout
			(tracks not_allowed)
			(vias allowed)
			(pads allowed)
			(copperpour not_allowed)
			(footprints allowed)
		)
		(placement
			(enabled no)
			(sheetname "")
		)
		(fill yes
			(thermal_gap 0.5)
			(thermal_bridge_width 0.5)
			(island_removal_mode 0)
		)
		(polygon
			(pts
				(arc
					(start 442.87821 -254.284988)
					(mid 442.21019 -254.284988)
					(end 442.87821 -254.284988)
				)
			)
		)
	)
	(zone
		(layers "B.Cu" "In11.Cu" "In13.Cu" "In15.Cu")
		(hatch none 0.5)
		(connect_pads
			(clearance 0)
		)
		(min_thickness 0.25)
		(keepout
			(tracks not_allowed)
			(vias allowed)
			(pads allowed)
			(copperpour not_allowed)
			(footprints allowed)
		)
		(placement
			(enabled no)
			(sheetname "")
		)
		(fill yes
			(thermal_gap 0.5)
			(thermal_bridge_width 0.5)
			(island_removal_mode 0)
		)
		(polygon
			(pts
				(arc
					(start 330.42606 -245.29415)
					(mid 329.79614 -245.29415)
					(end 330.42606 -245.29415)
				)
			)
		)
	)
	(zone
		(layers "B.Cu" "In11.Cu" "In13.Cu" "In15.Cu")
		(hatch none 0.5)
		(connect_pads
			(clearance 0)
		)
		(min_thickness 0.25)
		(keepout
			(tracks not_allowed)
			(vias allowed)
			(pads allowed)
			(copperpour not_allowed)
			(footprints allowed)
		)
		(placement
			(enabled no)
			(sheetname "")
		)
		(fill yes
			(thermal_gap 0.5)
			(thermal_bridge_width 0.5)
			(island_removal_mode 0)
		)
		(polygon
			(pts
				(arc
					(start 273.426174 -282.33497)
					(mid 272.758154 -282.33497)
					(end 273.426174 -282.33497)
				)
			)
		)
	)
	(zone
		(layers "B.Cu" "In11.Cu" "In13.Cu" "In15.Cu")
		(hatch none 0.5)
		(connect_pads
			(clearance 0)
		)
		(min_thickness 0.25)
		(keepout
			(tracks not_allowed)
			(vias allowed)
			(pads allowed)
			(copperpour not_allowed)
			(footprints allowed)
		)
		(placement
			(enabled no)
			(sheetname "")
		)
		(fill yes
			(thermal_gap 0.5)
			(thermal_bridge_width 0.5)
			(island_removal_mode 0)
		)
		(polygon
			(pts
				(arc
					(start 82.955892 -238.00435)
					(mid 82.325972 -238.00435)
					(end 82.955892 -238.00435)
				)
			)
		)
	)
	(zone
		(layers "B.Cu" "In11.Cu" "In13.Cu" "In15.Cu")
		(hatch none 0.5)
		(connect_pads
			(clearance 0)
		)
		(min_thickness 0.25)
		(keepout
			(tracks not_allowed)
			(vias allowed)
			(pads allowed)
			(copperpour not_allowed)
			(footprints allowed)
		)
		(placement
			(enabled no)
			(sheetname "")
		)
		(fill yes
			(thermal_gap 0.5)
			(thermal_bridge_width 0.5)
			(island_removal_mode 0)
		)
		(polygon
			(pts
				(arc
					(start 383.206244 -397.156432)
					(mid 382.576324 -397.156432)
					(end 383.206244 -397.156432)
				)
			)
		)
	)
	(zone
		(layers "B.Cu" "In11.Cu" "In13.Cu" "In15.Cu")
		(hatch none 0.5)
		(connect_pads
			(clearance 0)
		)
		(min_thickness 0.25)
		(keepout
			(tracks not_allowed)
			(vias allowed)
			(pads allowed)
			(copperpour not_allowed)
			(footprints allowed)
		)
		(placement
			(enabled no)
			(sheetname "")
		)
		(fill yes
			(thermal_gap 0.5)
			(thermal_bridge_width 0.5)
			(island_removal_mode 0)
		)
		(polygon
			(pts
				(arc
					(start 194.938142 -239.835436)
					(mid 194.270122 -239.835436)
					(end 194.938142 -239.835436)
				)
			)
		)
	)
	(zone
		(layers "B.Cu" "In11.Cu" "In13.Cu" "In15.Cu")
		(hatch none 0.5)
		(connect_pads
			(clearance 0)
		)
		(min_thickness 0.25)
		(keepout
			(tracks not_allowed)
			(vias allowed)
			(pads allowed)
			(copperpour not_allowed)
			(footprints allowed)
		)
		(placement
			(enabled no)
			(sheetname "")
		)
		(fill yes
			(thermal_gap 0.5)
			(thermal_bridge_width 0.5)
			(island_removal_mode 0)
		)
		(polygon
			(pts
				(arc
					(start 273.426174 -204.134974)
					(mid 272.758154 -204.134974)
					(end 273.426174 -204.134974)
				)
			)
		)
	)
	(zone
		(layers "B.Cu" "In11.Cu" "In13.Cu" "In15.Cu")
		(hatch none 0.5)
		(connect_pads
			(clearance 0)
		)
		(min_thickness 0.25)
		(keepout
			(tracks not_allowed)
			(vias allowed)
			(pads allowed)
			(copperpour not_allowed)
			(footprints allowed)
		)
		(placement
			(enabled no)
			(sheetname "")
		)
		(fill yes
			(thermal_gap 0.5)
			(thermal_bridge_width 0.5)
			(island_removal_mode 0)
		)
		(polygon
			(pts
				(arc
					(start 199.03821 -210.085432)
					(mid 198.37019 -210.085432)
					(end 199.03821 -210.085432)
				)
			)
		)
	)
	(zone
		(layers "B.Cu" "In11.Cu" "In13.Cu" "In15.Cu")
		(hatch none 0.5)
		(connect_pads
			(clearance 0)
		)
		(min_thickness 0.25)
		(keepout
			(tracks not_allowed)
			(vias allowed)
			(pads allowed)
			(copperpour not_allowed)
			(footprints allowed)
		)
		(placement
			(enabled no)
			(sheetname "")
		)
		(fill yes
			(thermal_gap 0.5)
			(thermal_bridge_width 0.5)
			(island_removal_mode 0)
		)
		(polygon
			(pts
				(arc
					(start 60.106306 -388.774432)
					(mid 59.476386 -388.774432)
					(end 60.106306 -388.774432)
				)
			)
		)
	)
	(zone
		(layers "B.Cu" "In11.Cu" "In13.Cu" "In15.Cu")
		(hatch none 0.5)
		(connect_pads
			(clearance 0)
		)
		(min_thickness 0.25)
		(keepout
			(tracks not_allowed)
			(vias allowed)
			(pads allowed)
			(copperpour not_allowed)
			(footprints allowed)
		)
		(placement
			(enabled no)
			(sheetname "")
		)
		(fill yes
			(thermal_gap 0.5)
			(thermal_bridge_width 0.5)
			(island_removal_mode 0)
		)
		(polygon
			(pts
				(arc
					(start 142.337536 -26.76779)
					(mid 141.669516 -26.76779)
					(end 142.337536 -26.76779)
				)
			)
		)
	)
	(zone
		(layers "B.Cu" "In11.Cu" "In13.Cu" "In15.Cu")
		(hatch none 0.5)
		(connect_pads
			(clearance 0)
		)
		(min_thickness 0.25)
		(keepout
			(tracks not_allowed)
			(vias allowed)
			(pads allowed)
			(copperpour not_allowed)
			(footprints allowed)
		)
		(placement
			(enabled no)
			(sheetname "")
		)
		(fill yes
			(thermal_gap 0.5)
			(thermal_bridge_width 0.5)
			(island_removal_mode 0)
		)
		(polygon
			(pts
				(arc
					(start 59.036966 -427.289976)
					(mid 58.262774 -427.289976)
					(end 59.036966 -427.289976)
				)
			)
		)
	)
	(zone
		(layers "B.Cu" "In11.Cu" "In13.Cu" "In15.Cu")
		(hatch none 0.5)
		(connect_pads
			(clearance 0)
		)
		(min_thickness 0.25)
		(keepout
			(tracks not_allowed)
			(vias allowed)
			(pads allowed)
			(copperpour not_allowed)
			(footprints allowed)
		)
		(placement
			(enabled no)
			(sheetname "")
		)
		(fill yes
			(thermal_gap 0.5)
			(thermal_bridge_width 0.5)
			(island_removal_mode 0)
		)
		(polygon
			(pts
				(arc
					(start 120.849644 -284.616398)
					(mid 120.219724 -284.616398)
					(end 120.849644 -284.616398)
				)
			)
		)
	)
	(zone
		(layers "B.Cu" "In11.Cu" "In13.Cu" "In15.Cu")
		(hatch none 0.5)
		(connect_pads
			(clearance 0)
		)
		(min_thickness 0.25)
		(keepout
			(tracks not_allowed)
			(vias allowed)
			(pads allowed)
			(copperpour not_allowed)
			(footprints allowed)
		)
		(placement
			(enabled no)
			(sheetname "")
		)
		(fill yes
			(thermal_gap 0.5)
			(thermal_bridge_width 0.5)
			(island_removal_mode 0)
		)
		(polygon
			(pts
				(arc
					(start 446.978278 -289.135058)
					(mid 446.310258 -289.135058)
					(end 446.978278 -289.135058)
				)
			)
		)
	)
	(zone
		(layers "B.Cu" "In11.Cu" "In13.Cu" "In15.Cu")
		(hatch none 0.5)
		(connect_pads
			(clearance 0)
		)
		(min_thickness 0.25)
		(keepout
			(tracks not_allowed)
			(vias allowed)
			(pads allowed)
			(copperpour not_allowed)
			(footprints allowed)
		)
		(placement
			(enabled no)
			(sheetname "")
		)
		(fill yes
			(thermal_gap 0.5)
			(thermal_bridge_width 0.5)
			(island_removal_mode 0)
		)
		(polygon
			(pts
				(arc
					(start 347.833696 -397.849344)
					(mid 347.203776 -397.849344)
					(end 347.833696 -397.849344)
				)
			)
		)
	)
	(zone
		(layers "B.Cu" "In11.Cu" "In13.Cu" "In15.Cu")
		(hatch none 0.5)
		(connect_pads
			(clearance 0)
		)
		(min_thickness 0.25)
		(keepout
			(tracks not_allowed)
			(vias allowed)
			(pads allowed)
			(copperpour not_allowed)
			(footprints allowed)
		)
		(placement
			(enabled no)
			(sheetname "")
		)
		(fill yes
			(thermal_gap 0.5)
			(thermal_bridge_width 0.5)
			(island_removal_mode 0)
		)
		(polygon
			(pts
				(arc
					(start 82.485992 -233.95432)
					(mid 81.856072 -233.95432)
					(end 82.485992 -233.95432)
				)
			)
		)
	)
	(zone
		(layers "B.Cu" "In11.Cu" "In13.Cu" "In15.Cu")
		(hatch none 0.5)
		(connect_pads
			(clearance 0)
		)
		(min_thickness 0.25)
		(keepout
			(tracks not_allowed)
			(vias allowed)
			(pads allowed)
			(copperpour not_allowed)
			(footprints allowed)
		)
		(placement
			(enabled no)
			(sheetname "")
		)
		(fill yes
			(thermal_gap 0.5)
			(thermal_bridge_width 0.5)
			(island_removal_mode 0)
		)
		(polygon
			(pts
				(arc
					(start 391.049764 -247.724168)
					(mid 390.419844 -247.724168)
					(end 391.049764 -247.724168)
				)
			)
		)
	)
	(zone
		(layers "B.Cu" "In11.Cu" "In13.Cu" "In15.Cu")
		(hatch none 0.5)
		(connect_pads
			(clearance 0)
		)
		(min_thickness 0.25)
		(keepout
			(tracks not_allowed)
			(vias allowed)
			(pads allowed)
			(copperpour not_allowed)
			(footprints allowed)
		)
		(placement
			(enabled no)
			(sheetname "")
		)
		(fill yes
			(thermal_gap 0.5)
			(thermal_bridge_width 0.5)
			(island_removal_mode 0)
		)
		(polygon
			(pts
				(arc
					(start 330.726034 -265.986006)
					(mid 330.096114 -265.986006)
					(end 330.726034 -265.986006)
				)
			)
		)
	)
	(zone
		(layers "B.Cu" "In11.Cu" "In13.Cu" "In15.Cu")
		(hatch none 0.5)
		(connect_pads
			(clearance 0)
		)
		(min_thickness 0.25)
		(keepout
			(tracks not_allowed)
			(vias allowed)
			(pads allowed)
			(copperpour not_allowed)
			(footprints allowed)
		)
		(placement
			(enabled no)
			(sheetname "")
		)
		(fill yes
			(thermal_gap 0.5)
			(thermal_bridge_width 0.5)
			(island_removal_mode 0)
		)
		(polygon
			(pts
				(arc
					(start 41.764712 -376.83186)
					(mid 41.096692 -376.83186)
					(end 41.764712 -376.83186)
				)
			)
		)
	)
	(zone
		(layers "B.Cu" "In11.Cu" "In13.Cu" "In15.Cu")
		(hatch none 0.5)
		(connect_pads
			(clearance 0)
		)
		(min_thickness 0.25)
		(keepout
			(tracks not_allowed)
			(vias allowed)
			(pads allowed)
			(copperpour not_allowed)
			(footprints allowed)
		)
		(placement
			(enabled no)
			(sheetname "")
		)
		(fill yes
			(thermal_gap 0.5)
			(thermal_bridge_width 0.5)
			(island_removal_mode 0)
		)
		(polygon
			(pts
				(arc
					(start 136.136888 -428.28972)
					(mid 135.362696 -428.28972)
					(end 136.136888 -428.28972)
				)
			)
		)
	)
	(zone
		(layers "B.Cu" "In11.Cu" "In13.Cu" "In15.Cu")
		(hatch none 0.5)
		(connect_pads
			(clearance 0)
		)
		(min_thickness 0.25)
		(keepout
			(tracks not_allowed)
			(vias allowed)
			(pads allowed)
			(copperpour not_allowed)
			(footprints allowed)
		)
		(placement
			(enabled no)
			(sheetname "")
		)
		(fill yes
			(thermal_gap 0.5)
			(thermal_bridge_width 0.5)
			(island_removal_mode 0)
		)
		(polygon
			(pts
				(arc
					(start 199.03821 -261.08533)
					(mid 198.37019 -261.08533)
					(end 199.03821 -261.08533)
				)
			)
		)
	)
	(zone
		(layers "B.Cu" "In11.Cu" "In13.Cu" "In15.Cu")
		(hatch none 0.5)
		(connect_pads
			(clearance 0)
		)
		(min_thickness 0.25)
		(keepout
			(tracks not_allowed)
			(vias allowed)
			(pads allowed)
			(copperpour not_allowed)
			(footprints allowed)
		)
		(placement
			(enabled no)
			(sheetname "")
		)
		(fill yes
			(thermal_gap 0.5)
			(thermal_bridge_width 0.5)
			(island_removal_mode 0)
		)
		(polygon
			(pts
				(arc
					(start 330.89596 -242.864132)
					(mid 330.26604 -242.864132)
					(end 330.89596 -242.864132)
				)
			)
		)
	)
	(zone
		(layers "B.Cu" "In11.Cu" "In13.Cu" "In15.Cu")
		(hatch none 0.5)
		(connect_pads
			(clearance 0)
		)
		(min_thickness 0.25)
		(keepout
			(tracks not_allowed)
			(vias allowed)
			(pads allowed)
			(copperpour not_allowed)
			(footprints allowed)
		)
		(placement
			(enabled no)
			(sheetname "")
		)
		(fill yes
			(thermal_gap 0.5)
			(thermal_bridge_width 0.5)
			(island_removal_mode 0)
		)
		(polygon
			(pts
				(arc
					(start 442.87821 -253.435104)
					(mid 442.21019 -253.435104)
					(end 442.87821 -253.435104)
				)
			)
		)
	)
	(zone
		(layers "B.Cu" "In11.Cu" "In13.Cu" "In15.Cu")
		(hatch none 0.5)
		(connect_pads
			(clearance 0)
		)
		(min_thickness 0.25)
		(keepout
			(tracks not_allowed)
			(vias allowed)
			(pads allowed)
			(copperpour not_allowed)
			(footprints allowed)
		)
		(placement
			(enabled no)
			(sheetname "")
		)
		(fill yes
			(thermal_gap 0.5)
			(thermal_bridge_width 0.5)
			(island_removal_mode 0)
		)
		(polygon
			(pts
				(arc
					(start 334.036924 -428.28972)
					(mid 333.262732 -428.28972)
					(end 334.036924 -428.28972)
				)
			)
		)
	)
	(zone
		(layers "B.Cu" "In11.Cu" "In13.Cu" "In15.Cu")
		(hatch none 0.5)
		(connect_pads
			(clearance 0)
		)
		(min_thickness 0.25)
		(keepout
			(tracks not_allowed)
			(vias allowed)
			(pads allowed)
			(copperpour not_allowed)
			(footprints allowed)
		)
		(placement
			(enabled no)
			(sheetname "")
		)
		(fill yes
			(thermal_gap 0.5)
			(thermal_bridge_width 0.5)
			(island_removal_mode 0)
		)
		(polygon
			(pts
				(arc
					(start 389.63981 -238.814102)
					(mid 389.00989 -238.814102)
					(end 389.63981 -238.814102)
				)
			)
		)
	)
	(zone
		(layers "B.Cu" "In11.Cu" "In13.Cu" "In15.Cu")
		(hatch none 0.5)
		(connect_pads
			(clearance 0)
		)
		(min_thickness 0.25)
		(keepout
			(tracks not_allowed)
			(vias allowed)
			(pads allowed)
			(copperpour not_allowed)
			(footprints allowed)
		)
		(placement
			(enabled no)
			(sheetname "")
		)
		(fill yes
			(thermal_gap 0.5)
			(thermal_bridge_width 0.5)
			(island_removal_mode 0)
		)
		(polygon
			(pts
				(arc
					(start 199.03821 -231.335326)
					(mid 198.37019 -231.335326)
					(end 199.03821 -231.335326)
				)
			)
		)
	)
	(zone
		(layers "B.Cu" "In11.Cu" "In13.Cu" "In15.Cu")
		(hatch none 0.5)
		(connect_pads
			(clearance 0)
		)
		(min_thickness 0.25)
		(keepout
			(tracks not_allowed)
			(vias allowed)
			(pads allowed)
			(copperpour not_allowed)
			(footprints allowed)
		)
		(placement
			(enabled no)
			(sheetname "")
		)
		(fill yes
			(thermal_gap 0.5)
			(thermal_bridge_width 0.5)
			(island_removal_mode 0)
		)
		(polygon
			(pts
				(arc
					(start 48.128174 -404.46452)
					(mid 47.460154 -404.46452)
					(end 48.128174 -404.46452)
				)
			)
		)
	)
	(zone
		(layers "B.Cu" "In11.Cu" "In13.Cu" "In15.Cu")
		(hatch none 0.5)
		(connect_pads
			(clearance 0)
		)
		(min_thickness 0.25)
		(keepout
			(tracks not_allowed)
			(vias allowed)
			(pads allowed)
			(copperpour not_allowed)
			(footprints allowed)
		)
		(placement
			(enabled no)
			(sheetname "")
		)
		(fill yes
			(thermal_gap 0.5)
			(thermal_bridge_width 0.5)
			(island_removal_mode 0)
		)
		(polygon
			(pts
				(arc
					(start 329.78598 -274.086066)
					(mid 329.15606 -274.086066)
					(end 329.78598 -274.086066)
				)
			)
		)
	)
	(zone
		(layers "B.Cu" "In11.Cu" "In13.Cu" "In15.Cu")
		(hatch none 0.5)
		(connect_pads
			(clearance 0)
		)
		(min_thickness 0.25)
		(keepout
			(tracks not_allowed)
			(vias allowed)
			(pads allowed)
			(copperpour not_allowed)
			(footprints allowed)
		)
		(placement
			(enabled no)
			(sheetname "")
		)
		(fill yes
			(thermal_gap 0.5)
			(thermal_bridge_width 0.5)
			(island_removal_mode 0)
		)
		(polygon
			(pts
				(arc
					(start 122.729752 -284.616398)
					(mid 122.099832 -284.616398)
					(end 122.729752 -284.616398)
				)
			)
		)
	)
	(zone
		(layers "B.Cu" "In11.Cu" "In13.Cu" "In15.Cu")
		(hatch none 0.5)
		(connect_pads
			(clearance 0)
		)
		(min_thickness 0.25)
		(keepout
			(tracks not_allowed)
			(vias allowed)
			(pads allowed)
			(copperpour not_allowed)
			(footprints allowed)
		)
		(placement
			(enabled no)
			(sheetname "")
		)
		(fill yes
			(thermal_gap 0.5)
			(thermal_bridge_width 0.5)
			(island_removal_mode 0)
		)
		(polygon
			(pts
				(arc
					(start 446.978278 -229.63505)
					(mid 446.310258 -229.63505)
					(end 446.978278 -229.63505)
				)
			)
		)
	)
	(zone
		(layers "B.Cu" "In11.Cu" "In13.Cu" "In15.Cu")
		(hatch none 0.5)
		(connect_pads
			(clearance 0)
		)
		(min_thickness 0.25)
		(keepout
			(tracks not_allowed)
			(vias allowed)
			(pads allowed)
			(copperpour not_allowed)
			(footprints allowed)
		)
		(placement
			(enabled no)
			(sheetname "")
		)
		(fill yes
			(thermal_gap 0.5)
			(thermal_bridge_width 0.5)
			(island_removal_mode 0)
		)
		(polygon
			(pts
				(arc
					(start 199.03821 -270.435324)
					(mid 198.37019 -270.435324)
					(end 199.03821 -270.435324)
				)
			)
		)
	)
	(zone
		(layers "B.Cu" "In11.Cu" "In13.Cu" "In15.Cu")
		(hatch none 0.5)
		(connect_pads
			(clearance 0)
		)
		(min_thickness 0.25)
		(keepout
			(tracks not_allowed)
			(vias allowed)
			(pads allowed)
			(copperpour not_allowed)
			(footprints allowed)
		)
		(placement
			(enabled no)
			(sheetname "")
		)
		(fill yes
			(thermal_gap 0.5)
			(thermal_bridge_width 0.5)
			(island_removal_mode 0)
		)
		(polygon
			(pts
				(arc
					(start 143.109696 -241.244374)
					(mid 142.479776 -241.244374)
					(end 143.109696 -241.244374)
				)
			)
		)
	)
	(zone
		(layers "B.Cu" "In11.Cu" "In13.Cu" "In15.Cu")
		(hatch none 0.5)
		(connect_pads
			(clearance 0)
		)
		(min_thickness 0.25)
		(keepout
			(tracks not_allowed)
			(vias allowed)
			(pads allowed)
			(copperpour not_allowed)
			(footprints allowed)
		)
		(placement
			(enabled no)
			(sheetname "")
		)
		(fill yes
			(thermal_gap 0.5)
			(thermal_bridge_width 0.5)
			(island_removal_mode 0)
		)
		(polygon
			(pts
				(arc
					(start 277.526242 -270.43507)
					(mid 276.858222 -270.43507)
					(end 277.526242 -270.43507)
				)
			)
		)
	)
	(zone
		(layers "B.Cu" "In11.Cu" "In13.Cu" "In15.Cu")
		(hatch none 0.5)
		(connect_pads
			(clearance 0)
		)
		(min_thickness 0.25)
		(keepout
			(tracks not_allowed)
			(vias allowed)
			(pads allowed)
			(copperpour not_allowed)
			(footprints allowed)
		)
		(placement
			(enabled no)
			(sheetname "")
		)
		(fill yes
			(thermal_gap 0.5)
			(thermal_bridge_width 0.5)
			(island_removal_mode 0)
		)
		(polygon
			(pts
				(arc
					(start 50.156364 -371.49913)
					(mid 49.488344 -371.49913)
					(end 50.156364 -371.49913)
				)
			)
		)
	)
	(zone
		(layers "B.Cu" "In11.Cu" "In13.Cu" "In15.Cu")
		(hatch none 0.5)
		(connect_pads
			(clearance 0)
		)
		(min_thickness 0.25)
		(keepout
			(tracks not_allowed)
			(vias allowed)
			(pads allowed)
			(copperpour not_allowed)
			(footprints allowed)
		)
		(placement
			(enabled no)
			(sheetname "")
		)
		(fill yes
			(thermal_gap 0.5)
			(thermal_bridge_width 0.5)
			(island_removal_mode 0)
		)
		(polygon
			(pts
				(arc
					(start 141.529816 -281.376374)
					(mid 140.899896 -281.376374)
					(end 141.529816 -281.376374)
				)
			)
		)
	)
	(zone
		(layers "B.Cu" "In11.Cu" "In13.Cu" "In15.Cu")
		(hatch none 0.5)
		(connect_pads
			(clearance 0)
		)
		(min_thickness 0.25)
		(keepout
			(tracks not_allowed)
			(vias allowed)
			(pads allowed)
			(copperpour not_allowed)
			(footprints allowed)
		)
		(placement
			(enabled no)
			(sheetname "")
		)
		(fill yes
			(thermal_gap 0.5)
			(thermal_bridge_width 0.5)
			(island_removal_mode 0)
		)
		(polygon
			(pts
				(arc
					(start 81.376012 -265.176254)
					(mid 80.746092 -265.176254)
					(end 81.376012 -265.176254)
				)
			)
		)
	)
	(zone
		(layers "B.Cu" "In11.Cu" "In13.Cu" "In15.Cu")
		(hatch none 0.5)
		(connect_pads
			(clearance 0)
		)
		(min_thickness 0.25)
		(keepout
			(tracks not_allowed)
			(vias allowed)
			(pads allowed)
			(copperpour not_allowed)
			(footprints allowed)
		)
		(placement
			(enabled no)
			(sheetname "")
		)
		(fill yes
			(thermal_gap 0.5)
			(thermal_bridge_width 0.5)
			(island_removal_mode 0)
		)
		(polygon
			(pts
				(arc
					(start 54.506368 -389.467344)
					(mid 53.876448 -389.467344)
					(end 54.506368 -389.467344)
				)
			)
		)
	)
	(zone
		(layers "B.Cu" "In11.Cu" "In13.Cu" "In15.Cu")
		(hatch none 0.5)
		(connect_pads
			(clearance 0)
		)
		(min_thickness 0.25)
		(keepout
			(tracks not_allowed)
			(vias allowed)
			(pads allowed)
			(copperpour not_allowed)
			(footprints allowed)
		)
		(placement
			(enabled no)
			(sheetname "")
		)
		(fill yes
			(thermal_gap 0.5)
			(thermal_bridge_width 0.5)
			(island_removal_mode 0)
		)
		(polygon
			(pts
				(arc
					(start 340.036912 -427.289976)
					(mid 339.26272 -427.289976)
					(end 340.036912 -427.289976)
				)
			)
		)
	)
	(zone
		(layers "B.Cu" "In11.Cu" "In13.Cu" "In15.Cu")
		(hatch none 0.5)
		(connect_pads
			(clearance 0)
		)
		(min_thickness 0.25)
		(keepout
			(tracks not_allowed)
			(vias allowed)
			(pads allowed)
			(copperpour not_allowed)
			(footprints allowed)
		)
		(placement
			(enabled no)
			(sheetname "")
		)
		(fill yes
			(thermal_gap 0.5)
			(thermal_bridge_width 0.5)
			(island_removal_mode 0)
		)
		(polygon
			(pts
				(arc
					(start 329.78598 -264.365994)
					(mid 329.15606 -264.365994)
					(end 329.78598 -264.365994)
				)
			)
		)
	)
	(zone
		(layers "B.Cu" "In11.Cu" "In13.Cu" "In15.Cu")
		(hatch none 0.5)
		(connect_pads
			(clearance 0)
		)
		(min_thickness 0.25)
		(keepout
			(tracks not_allowed)
			(vias allowed)
			(pads allowed)
			(copperpour not_allowed)
			(footprints allowed)
		)
		(placement
			(enabled no)
			(sheetname "")
		)
		(fill yes
			(thermal_gap 0.5)
			(thermal_bridge_width 0.5)
			(island_removal_mode 0)
		)
		(polygon
			(pts
				(arc
					(start 81.845912 -287.046162)
					(mid 81.215992 -287.046162)
					(end 81.845912 -287.046162)
				)
			)
		)
	)
	(zone
		(layers "B.Cu" "In11.Cu" "In13.Cu" "In15.Cu")
		(hatch none 0.5)
		(connect_pads
			(clearance 0)
		)
		(min_thickness 0.25)
		(keepout
			(tracks not_allowed)
			(vias allowed)
			(pads allowed)
			(copperpour not_allowed)
			(footprints allowed)
		)
		(placement
			(enabled no)
			(sheetname "")
		)
		(fill yes
			(thermal_gap 0.5)
			(thermal_bridge_width 0.5)
			(island_removal_mode 0)
		)
		(polygon
			(pts
				(arc
					(start 345.033854 -397.156432)
					(mid 344.403934 -397.156432)
					(end 345.033854 -397.156432)
				)
			)
		)
	)
	(zone
		(layers "B.Cu" "In11.Cu" "In13.Cu" "In15.Cu")
		(hatch none 0.5)
		(connect_pads
			(clearance 0)
		)
		(min_thickness 0.25)
		(keepout
			(tracks not_allowed)
			(vias allowed)
			(pads allowed)
			(copperpour not_allowed)
			(footprints allowed)
		)
		(placement
			(enabled no)
			(sheetname "")
		)
		(fill yes
			(thermal_gap 0.5)
			(thermal_bridge_width 0.5)
			(island_removal_mode 0)
		)
		(polygon
			(pts
				(arc
					(start 389.469884 -273.27606)
					(mid 388.839964 -273.27606)
					(end 389.469884 -273.27606)
				)
			)
		)
	)
	(zone
		(layers "B.Cu" "In11.Cu" "In13.Cu" "In15.Cu")
		(hatch none 0.5)
		(connect_pads
			(clearance 0)
		)
		(min_thickness 0.25)
		(keepout
			(tracks not_allowed)
			(vias allowed)
			(pads allowed)
			(copperpour not_allowed)
			(footprints allowed)
		)
		(placement
			(enabled no)
			(sheetname "")
		)
		(fill yes
			(thermal_gap 0.5)
			(thermal_bridge_width 0.5)
			(island_removal_mode 0)
		)
		(polygon
			(pts
				(arc
					(start 143.40967 -266.796266)
					(mid 142.77975 -266.796266)
					(end 143.40967 -266.796266)
				)
			)
		)
	)
	(zone
		(layers "B.Cu" "In11.Cu" "In13.Cu" "In15.Cu")
		(hatch none 0.5)
		(connect_pads
			(clearance 0)
		)
		(min_thickness 0.25)
		(keepout
			(tracks not_allowed)
			(vias allowed)
			(pads allowed)
			(copperpour not_allowed)
			(footprints allowed)
		)
		(placement
			(enabled no)
			(sheetname "")
		)
		(fill yes
			(thermal_gap 0.5)
			(thermal_bridge_width 0.5)
			(island_removal_mode 0)
		)
		(polygon
			(pts
				(arc
					(start 45.050964 -369.03533)
					(mid 44.382944 -369.03533)
					(end 45.050964 -369.03533)
				)
			)
		)
	)
	(zone
		(layers "B.Cu" "In11.Cu" "In13.Cu" "In15.Cu")
		(hatch none 0.5)
		(connect_pads
			(clearance 0)
		)
		(min_thickness 0.25)
		(keepout
			(tracks not_allowed)
			(vias allowed)
			(pads allowed)
			(copperpour not_allowed)
			(footprints allowed)
		)
		(placement
			(enabled no)
			(sheetname "")
		)
		(fill yes
			(thermal_gap 0.5)
			(thermal_bridge_width 0.5)
			(island_removal_mode 0)
		)
		(polygon
			(pts
				(arc
					(start 327.611486 -384.475228)
					(mid 326.943466 -384.475228)
					(end 327.611486 -384.475228)
				)
			)
		)
	)
	(zone
		(layers "B.Cu" "In11.Cu" "In13.Cu" "In15.Cu")
		(hatch none 0.5)
		(connect_pads
			(clearance 0)
		)
		(min_thickness 0.25)
		(keepout
			(tracks not_allowed)
			(vias allowed)
			(pads allowed)
			(copperpour not_allowed)
			(footprints allowed)
		)
		(placement
			(enabled no)
			(sheetname "")
		)
		(fill yes
			(thermal_gap 0.5)
			(thermal_bridge_width 0.5)
			(island_removal_mode 0)
		)
		(polygon
			(pts
				(arc
					(start 413.733996 -394.385292)
					(mid 413.104076 -394.385292)
					(end 413.733996 -394.385292)
				)
			)
		)
	)
	(zone
		(layers "B.Cu" "In11.Cu" "In13.Cu" "In15.Cu")
		(hatch none 0.5)
		(connect_pads
			(clearance 0)
		)
		(min_thickness 0.25)
		(keepout
			(tracks not_allowed)
			(vias allowed)
			(pads allowed)
			(copperpour not_allowed)
			(footprints allowed)
		)
		(placement
			(enabled no)
			(sheetname "")
		)
		(fill yes
			(thermal_gap 0.5)
			(thermal_bridge_width 0.5)
			(island_removal_mode 0)
		)
		(polygon
			(pts
				(arc
					(start 390.879838 -287.045908)
					(mid 390.249918 -287.045908)
					(end 390.879838 -287.045908)
				)
			)
		)
	)
	(zone
		(layers "B.Cu" "In11.Cu" "In13.Cu" "In15.Cu")
		(hatch none 0.5)
		(connect_pads
			(clearance 0)
		)
		(min_thickness 0.25)
		(keepout
			(tracks not_allowed)
			(vias allowed)
			(pads allowed)
			(copperpour not_allowed)
			(footprints allowed)
		)
		(placement
			(enabled no)
			(sheetname "")
		)
		(fill yes
			(thermal_gap 0.5)
			(thermal_bridge_width 0.5)
			(island_removal_mode 0)
		)
		(polygon
			(pts
				(arc
					(start 194.938142 -205.83525)
					(mid 194.270122 -205.83525)
					(end 194.938142 -205.83525)
				)
			)
		)
	)
	(zone
		(layers "B.Cu" "In11.Cu" "In13.Cu" "In15.Cu")
		(hatch none 0.5)
		(connect_pads
			(clearance 0)
		)
		(min_thickness 0.25)
		(keepout
			(tracks not_allowed)
			(vias allowed)
			(pads allowed)
			(copperpour not_allowed)
			(footprints allowed)
		)
		(placement
			(enabled no)
			(sheetname "")
		)
		(fill yes
			(thermal_gap 0.5)
			(thermal_bridge_width 0.5)
			(island_removal_mode 0)
		)
		(polygon
			(pts
				(arc
					(start 194.938142 -238.985298)
					(mid 194.270122 -238.985298)
					(end 194.938142 -238.985298)
				)
			)
		)
	)
	(zone
		(layers "B.Cu" "In11.Cu" "In13.Cu" "In15.Cu")
		(hatch none 0.5)
		(connect_pads
			(clearance 0)
		)
		(min_thickness 0.25)
		(keepout
			(tracks not_allowed)
			(vias allowed)
			(pads allowed)
			(copperpour not_allowed)
			(footprints allowed)
		)
		(placement
			(enabled no)
			(sheetname "")
		)
		(fill yes
			(thermal_gap 0.5)
			(thermal_bridge_width 0.5)
			(island_removal_mode 0)
		)
		(polygon
			(pts
				(arc
					(start 55.706264 -389.467344)
					(mid 55.076344 -389.467344)
					(end 55.706264 -389.467344)
				)
			)
		)
	)
	(zone
		(layers "B.Cu" "In11.Cu" "In13.Cu" "In15.Cu")
		(hatch none 0.5)
		(connect_pads
			(clearance 0)
		)
		(min_thickness 0.25)
		(keepout
			(tracks not_allowed)
			(vias allowed)
			(pads allowed)
			(copperpour not_allowed)
			(footprints allowed)
		)
		(placement
			(enabled no)
			(sheetname "")
		)
		(fill yes
			(thermal_gap 0.5)
			(thermal_bridge_width 0.5)
			(island_removal_mode 0)
		)
		(polygon
			(pts
				(arc
					(start 65.036954 -424.689778)
					(mid 64.262762 -424.689778)
					(end 65.036954 -424.689778)
				)
			)
		)
	)
	(zone
		(layers "B.Cu" "In11.Cu" "In13.Cu" "In15.Cu")
		(hatch none 0.5)
		(connect_pads
			(clearance 0)
		)
		(min_thickness 0.25)
		(keepout
			(tracks not_allowed)
			(vias allowed)
			(pads allowed)
			(copperpour not_allowed)
			(footprints allowed)
		)
		(placement
			(enabled no)
			(sheetname "")
		)
		(fill yes
			(thermal_gap 0.5)
			(thermal_bridge_width 0.5)
			(island_removal_mode 0)
		)
		(polygon
			(pts
				(arc
					(start 62.506352 -388.774432)
					(mid 61.876432 -388.774432)
					(end 62.506352 -388.774432)
				)
			)
		)
	)
	(zone
		(layers "B.Cu" "In11.Cu" "In13.Cu" "In15.Cu")
		(hatch none 0.5)
		(connect_pads
			(clearance 0)
		)
		(min_thickness 0.25)
		(keepout
			(tracks not_allowed)
			(vias allowed)
			(pads allowed)
			(copperpour not_allowed)
			(footprints allowed)
		)
		(placement
			(enabled no)
			(sheetname "")
		)
		(fill yes
			(thermal_gap 0.5)
			(thermal_bridge_width 0.5)
			(island_removal_mode 0)
		)
		(polygon
			(pts
				(arc
					(start 119.206264 -389.467344)
					(mid 118.576344 -389.467344)
					(end 119.206264 -389.467344)
				)
			)
		)
	)
	(zone
		(layers "B.Cu" "In11.Cu" "In13.Cu" "In15.Cu")
		(hatch none 0.5)
		(connect_pads
			(clearance 0)
		)
		(min_thickness 0.25)
		(keepout
			(tracks not_allowed)
			(vias allowed)
			(pads allowed)
			(copperpour not_allowed)
			(footprints allowed)
		)
		(placement
			(enabled no)
			(sheetname "")
		)
		(fill yes
			(thermal_gap 0.5)
			(thermal_bridge_width 0.5)
			(island_removal_mode 0)
		)
		(polygon
			(pts
				(arc
					(start 273.426174 -284.034992)
					(mid 272.758154 -284.034992)
					(end 273.426174 -284.034992)
				)
			)
		)
	)
	(zone
		(layers "B.Cu" "In11.Cu" "In13.Cu" "In15.Cu")
		(hatch none 0.5)
		(connect_pads
			(clearance 0)
		)
		(min_thickness 0.25)
		(keepout
			(tracks not_allowed)
			(vias allowed)
			(pads allowed)
			(copperpour not_allowed)
			(footprints allowed)
		)
		(placement
			(enabled no)
			(sheetname "")
		)
		(fill yes
			(thermal_gap 0.5)
			(thermal_bridge_width 0.5)
			(island_removal_mode 0)
		)
		(polygon
			(pts
				(arc
					(start 339.433662 -397.849344)
					(mid 338.803742 -397.849344)
					(end 339.433662 -397.849344)
				)
			)
		)
	)
	(zone
		(layers "B.Cu" "In11.Cu" "In13.Cu" "In15.Cu")
		(hatch none 0.5)
		(connect_pads
			(clearance 0)
		)
		(min_thickness 0.25)
		(keepout
			(tracks not_allowed)
			(vias allowed)
			(pads allowed)
			(copperpour not_allowed)
			(footprints allowed)
		)
		(placement
			(enabled no)
			(sheetname "")
		)
		(fill yes
			(thermal_gap 0.5)
			(thermal_bridge_width 0.5)
			(island_removal_mode 0)
		)
		(polygon
			(pts
				(arc
					(start 158.533846 -385.31038)
					(mid 157.903926 -385.31038)
					(end 158.533846 -385.31038)
				)
			)
		)
	)
	(zone
		(layers "B.Cu" "In11.Cu" "In13.Cu" "In15.Cu")
		(hatch none 0.5)
		(connect_pads
			(clearance 0)
		)
		(min_thickness 0.25)
		(keepout
			(tracks not_allowed)
			(vias allowed)
			(pads allowed)
			(copperpour not_allowed)
			(footprints allowed)
		)
		(placement
			(enabled no)
			(sheetname "")
		)
		(fill yes
			(thermal_gap 0.5)
			(thermal_bridge_width 0.5)
			(island_removal_mode 0)
		)
		(polygon
			(pts
				(arc
					(start 329.31608 -286.236156)
					(mid 328.68616 -286.236156)
					(end 329.31608 -286.236156)
				)
			)
		)
	)
	(zone
		(layers "B.Cu" "In11.Cu" "In13.Cu" "In15.Cu")
		(hatch none 0.5)
		(connect_pads
			(clearance 0)
		)
		(min_thickness 0.25)
		(keepout
			(tracks not_allowed)
			(vias allowed)
			(pads allowed)
			(copperpour not_allowed)
			(footprints allowed)
		)
		(placement
			(enabled no)
			(sheetname "")
		)
		(fill yes
			(thermal_gap 0.5)
			(thermal_bridge_width 0.5)
			(island_removal_mode 0)
		)
		(polygon
			(pts
				(arc
					(start 29.586174 -284.885384)
					(mid 28.918154 -284.885384)
					(end 29.586174 -284.885384)
				)
			)
		)
	)
	(zone
		(layers "B.Cu" "In11.Cu" "In13.Cu" "In15.Cu")
		(hatch none 0.5)
		(connect_pads
			(clearance 0)
		)
		(min_thickness 0.25)
		(keepout
			(tracks not_allowed)
			(vias allowed)
			(pads allowed)
			(copperpour not_allowed)
			(footprints allowed)
		)
		(placement
			(enabled no)
			(sheetname "")
		)
		(fill yes
			(thermal_gap 0.5)
			(thermal_bridge_width 0.5)
			(island_removal_mode 0)
		)
		(polygon
			(pts
				(arc
					(start 389.63981 -246.914162)
					(mid 389.00989 -246.914162)
					(end 389.63981 -246.914162)
				)
			)
		)
	)
	(zone
		(layers "B.Cu" "In11.Cu" "In13.Cu" "In15.Cu")
		(hatch none 0.5)
		(connect_pads
			(clearance 0)
		)
		(min_thickness 0.25)
		(keepout
			(tracks not_allowed)
			(vias allowed)
			(pads allowed)
			(copperpour not_allowed)
			(footprints allowed)
		)
		(placement
			(enabled no)
			(sheetname "")
		)
		(fill yes
			(thermal_gap 0.5)
			(thermal_bridge_width 0.5)
			(island_removal_mode 0)
		)
		(polygon
			(pts
				(arc
					(start 48.454564 -373.96293)
					(mid 47.786544 -373.96293)
					(end 48.454564 -373.96293)
				)
			)
		)
	)
	(zone
		(layers "B.Cu" "In11.Cu" "In13.Cu" "In15.Cu")
		(hatch none 0.5)
		(connect_pads
			(clearance 0)
		)
		(min_thickness 0.25)
		(keepout
			(tracks not_allowed)
			(vias allowed)
			(pads allowed)
			(copperpour not_allowed)
			(footprints allowed)
		)
		(placement
			(enabled no)
			(sheetname "")
		)
		(fill yes
			(thermal_gap 0.5)
			(thermal_bridge_width 0.5)
			(island_removal_mode 0)
		)
		(polygon
			(pts
				(arc
					(start 29.586174 -216.035382)
					(mid 28.918154 -216.035382)
					(end 29.586174 -216.035382)
				)
			)
		)
	)
	(zone
		(layers "B.Cu" "In11.Cu" "In13.Cu" "In15.Cu")
		(hatch none 0.5)
		(connect_pads
			(clearance 0)
		)
		(min_thickness 0.25)
		(keepout
			(tracks not_allowed)
			(vias allowed)
			(pads allowed)
			(copperpour not_allowed)
			(footprints allowed)
		)
		(placement
			(enabled no)
			(sheetname "")
		)
		(fill yes
			(thermal_gap 0.5)
			(thermal_bridge_width 0.5)
			(island_removal_mode 0)
		)
		(polygon
			(pts
				(arc
					(start 446.978278 -223.6851)
					(mid 446.310258 -223.6851)
					(end 446.978278 -223.6851)
				)
			)
		)
	)
	(zone
		(layers "B.Cu" "In11.Cu" "In13.Cu" "In15.Cu")
		(hatch none 0.5)
		(connect_pads
			(clearance 0)
		)
		(min_thickness 0.25)
		(keepout
			(tracks not_allowed)
			(vias allowed)
			(pads allowed)
			(copperpour not_allowed)
			(footprints allowed)
		)
		(placement
			(enabled no)
			(sheetname "")
		)
		(fill yes
			(thermal_gap 0.5)
			(thermal_bridge_width 0.5)
			(island_removal_mode 0)
		)
		(polygon
			(pts
				(arc
					(start 351.433638 -397.849344)
					(mid 350.803718 -397.849344)
					(end 351.433638 -397.849344)
				)
			)
		)
	)
	(zone
		(layers "B.Cu" "In11.Cu" "In13.Cu" "In15.Cu")
		(hatch none 0.5)
		(connect_pads
			(clearance 0)
		)
		(min_thickness 0.25)
		(keepout
			(tracks not_allowed)
			(vias allowed)
			(pads allowed)
			(copperpour not_allowed)
			(footprints allowed)
		)
		(placement
			(enabled no)
			(sheetname "")
		)
		(fill yes
			(thermal_gap 0.5)
			(thermal_bridge_width 0.5)
			(island_removal_mode 0)
		)
		(polygon
			(pts
				(arc
					(start 389.63981 -248.534174)
					(mid 389.00989 -248.534174)
					(end 389.63981 -248.534174)
				)
			)
		)
	)
	(zone
		(layers "B.Cu" "In11.Cu" "In13.Cu" "In15.Cu")
		(hatch none 0.5)
		(connect_pads
			(clearance 0)
		)
		(min_thickness 0.25)
		(keepout
			(tracks not_allowed)
			(vias allowed)
			(pads allowed)
			(copperpour not_allowed)
			(footprints allowed)
		)
		(placement
			(enabled no)
			(sheetname "")
		)
		(fill yes
			(thermal_gap 0.5)
			(thermal_bridge_width 0.5)
			(island_removal_mode 0)
		)
		(polygon
			(pts
				(arc
					(start 330.726034 -280.566114)
					(mid 330.096114 -280.566114)
					(end 330.726034 -280.566114)
				)
			)
		)
	)
	(zone
		(layers "B.Cu" "In11.Cu" "In13.Cu" "In15.Cu")
		(hatch none 0.5)
		(connect_pads
			(clearance 0)
		)
		(min_thickness 0.25)
		(keepout
			(tracks not_allowed)
			(vias allowed)
			(pads allowed)
			(copperpour not_allowed)
			(footprints allowed)
		)
		(placement
			(enabled no)
			(sheetname "")
		)
		(fill yes
			(thermal_gap 0.5)
			(thermal_bridge_width 0.5)
			(island_removal_mode 0)
		)
		(polygon
			(pts
				(arc
					(start 277.526242 -292.535102)
					(mid 276.858222 -292.535102)
					(end 277.526242 -292.535102)
				)
			)
		)
	)
	(zone
		(layers "B.Cu" "In11.Cu" "In13.Cu" "In15.Cu")
		(hatch none 0.5)
		(connect_pads
			(clearance 0)
		)
		(min_thickness 0.25)
		(keepout
			(tracks not_allowed)
			(vias allowed)
			(pads allowed)
			(copperpour not_allowed)
			(footprints allowed)
		)
		(placement
			(enabled no)
			(sheetname "")
		)
		(fill yes
			(thermal_gap 0.5)
			(thermal_bridge_width 0.5)
			(island_removal_mode 0)
		)
		(polygon
			(pts
				(arc
					(start 199.03821 -199.035416)
					(mid 198.37019 -199.035416)
					(end 199.03821 -199.035416)
				)
			)
		)
	)
	(zone
		(layers "B.Cu" "In11.Cu" "In13.Cu" "In15.Cu")
		(hatch none 0.5)
		(connect_pads
			(clearance 0)
		)
		(min_thickness 0.25)
		(keepout
			(tracks not_allowed)
			(vias allowed)
			(pads allowed)
			(copperpour not_allowed)
			(footprints allowed)
		)
		(placement
			(enabled no)
			(sheetname "")
		)
		(fill yes
			(thermal_gap 0.5)
			(thermal_bridge_width 0.5)
			(island_removal_mode 0)
		)
		(polygon
			(pts
				(arc
					(start 194.938142 -299.335444)
					(mid 194.270122 -299.335444)
					(end 194.938142 -299.335444)
				)
			)
		)
	)
	(zone
		(layers "B.Cu" "In11.Cu" "In13.Cu" "In15.Cu")
		(hatch none 0.5)
		(connect_pads
			(clearance 0)
		)
		(min_thickness 0.25)
		(keepout
			(tracks not_allowed)
			(vias allowed)
			(pads allowed)
			(copperpour not_allowed)
			(footprints allowed)
		)
		(placement
			(enabled no)
			(sheetname "")
		)
		(fill yes
			(thermal_gap 0.5)
			(thermal_bridge_width 0.5)
			(island_removal_mode 0)
		)
		(polygon
			(pts
				(arc
					(start 389.16991 -229.904036)
					(mid 388.53999 -229.904036)
					(end 389.16991 -229.904036)
				)
			)
		)
	)
	(zone
		(layers "B.Cu" "In11.Cu" "In13.Cu" "In15.Cu")
		(hatch none 0.5)
		(connect_pads
			(clearance 0)
		)
		(min_thickness 0.25)
		(keepout
			(tracks not_allowed)
			(vias allowed)
			(pads allowed)
			(copperpour not_allowed)
			(footprints allowed)
		)
		(placement
			(enabled no)
			(sheetname "")
		)
		(fill yes
			(thermal_gap 0.5)
			(thermal_bridge_width 0.5)
			(island_removal_mode 0)
		)
		(polygon
			(pts
				(arc
					(start 199.03821 -240.68532)
					(mid 198.37019 -240.68532)
					(end 199.03821 -240.68532)
				)
			)
		)
	)
	(zone
		(layers "B.Cu" "In11.Cu" "In13.Cu" "In15.Cu")
		(hatch none 0.5)
		(connect_pads
			(clearance 0)
		)
		(min_thickness 0.25)
		(keepout
			(tracks not_allowed)
			(vias allowed)
			(pads allowed)
			(copperpour not_allowed)
			(footprints allowed)
		)
		(placement
			(enabled no)
			(sheetname "")
		)
		(fill yes
			(thermal_gap 0.5)
			(thermal_bridge_width 0.5)
			(island_removal_mode 0)
		)
		(polygon
			(pts
				(arc
					(start 65.036954 -427.089824)
					(mid 64.262762 -427.089824)
					(end 65.036954 -427.089824)
				)
			)
		)
	)
	(zone
		(layers "B.Cu" "In11.Cu" "In13.Cu" "In15.Cu")
		(hatch none 0.5)
		(connect_pads
			(clearance 0)
		)
		(min_thickness 0.25)
		(keepout
			(tracks not_allowed)
			(vias allowed)
			(pads allowed)
			(copperpour not_allowed)
			(footprints allowed)
		)
		(placement
			(enabled no)
			(sheetname "")
		)
		(fill yes
			(thermal_gap 0.5)
			(thermal_bridge_width 0.5)
			(island_removal_mode 0)
		)
		(polygon
			(pts
				(arc
					(start 199.03821 -303.585372)
					(mid 198.37019 -303.585372)
					(end 199.03821 -303.585372)
				)
			)
		)
	)
	(zone
		(layers "B.Cu" "In11.Cu" "In13.Cu" "In15.Cu")
		(hatch none 0.5)
		(connect_pads
			(clearance 0)
		)
		(min_thickness 0.25)
		(keepout
			(tracks not_allowed)
			(vias allowed)
			(pads allowed)
			(copperpour not_allowed)
			(footprints allowed)
		)
		(placement
			(enabled no)
			(sheetname "")
		)
		(fill yes
			(thermal_gap 0.5)
			(thermal_bridge_width 0.5)
			(island_removal_mode 0)
		)
		(polygon
			(pts
				(arc
					(start 329.486006 -238.814102)
					(mid 328.856086 -238.814102)
					(end 329.486006 -238.814102)
				)
			)
		)
	)
	(zone
		(layers "B.Cu" "In11.Cu" "In13.Cu" "In15.Cu")
		(hatch none 0.5)
		(connect_pads
			(clearance 0)
		)
		(min_thickness 0.25)
		(keepout
			(tracks not_allowed)
			(vias allowed)
			(pads allowed)
			(copperpour not_allowed)
			(footprints allowed)
		)
		(placement
			(enabled no)
			(sheetname "")
		)
		(fill yes
			(thermal_gap 0.5)
			(thermal_bridge_width 0.5)
			(island_removal_mode 0)
		)
		(polygon
			(pts
				(arc
					(start 25.486106 -291.685218)
					(mid 24.818086 -291.685218)
					(end 25.486106 -291.685218)
				)
			)
		)
	)
	(zone
		(layers "B.Cu" "In11.Cu" "In13.Cu" "In15.Cu")
		(hatch none 0.5)
		(connect_pads
			(clearance 0)
		)
		(min_thickness 0.25)
		(keepout
			(tracks not_allowed)
			(vias allowed)
			(pads allowed)
			(copperpour not_allowed)
			(footprints allowed)
		)
		(placement
			(enabled no)
			(sheetname "")
		)
		(fill yes
			(thermal_gap 0.5)
			(thermal_bridge_width 0.5)
			(island_removal_mode 0)
		)
		(polygon
			(pts
				(arc
					(start 390.879838 -278.946102)
					(mid 390.249918 -278.946102)
					(end 390.879838 -278.946102)
				)
			)
		)
	)
	(zone
		(layers "B.Cu" "In11.Cu" "In13.Cu" "In15.Cu")
		(hatch none 0.5)
		(connect_pads
			(clearance 0)
		)
		(min_thickness 0.25)
		(keepout
			(tracks not_allowed)
			(vias allowed)
			(pads allowed)
			(copperpour not_allowed)
			(footprints allowed)
		)
		(placement
			(enabled no)
			(sheetname "")
		)
		(fill yes
			(thermal_gap 0.5)
			(thermal_bridge_width 0.5)
			(island_removal_mode 0)
		)
		(polygon
			(pts
				(arc
					(start 97.995994 -241.244374)
					(mid 97.366074 -241.244374)
					(end 97.995994 -241.244374)
				)
			)
		)
	)
	(zone
		(layers "B.Cu" "In11.Cu" "In13.Cu" "In15.Cu")
		(hatch none 0.5)
		(connect_pads
			(clearance 0)
		)
		(min_thickness 0.25)
		(keepout
			(tracks not_allowed)
			(vias allowed)
			(pads allowed)
			(copperpour not_allowed)
			(footprints allowed)
		)
		(placement
			(enabled no)
			(sheetname "")
		)
		(fill yes
			(thermal_gap 0.5)
			(thermal_bridge_width 0.5)
			(island_removal_mode 0)
		)
		(polygon
			(pts
				(arc
					(start 330.89596 -231.524048)
					(mid 330.26604 -231.524048)
					(end 330.89596 -231.524048)
				)
			)
		)
	)
	(zone
		(layers "B.Cu" "In11.Cu" "In13.Cu" "In15.Cu")
		(hatch none 0.5)
		(connect_pads
			(clearance 0)
		)
		(min_thickness 0.25)
		(keepout
			(tracks not_allowed)
			(vias allowed)
			(pads allowed)
			(copperpour not_allowed)
			(footprints allowed)
		)
		(placement
			(enabled no)
			(sheetname "")
		)
		(fill yes
			(thermal_gap 0.5)
			(thermal_bridge_width 0.5)
			(island_removal_mode 0)
		)
		(polygon
			(pts
				(arc
					(start 273.426174 -244.934994)
					(mid 272.758154 -244.934994)
					(end 273.426174 -244.934994)
				)
			)
		)
	)
	(zone
		(layers "B.Cu" "In11.Cu" "In13.Cu" "In15.Cu")
		(hatch none 0.5)
		(connect_pads
			(clearance 0)
		)
		(min_thickness 0.25)
		(keepout
			(tracks not_allowed)
			(vias allowed)
			(pads allowed)
			(copperpour not_allowed)
			(footprints allowed)
		)
		(placement
			(enabled no)
			(sheetname "")
		)
		(fill yes
			(thermal_gap 0.5)
			(thermal_bridge_width 0.5)
			(island_removal_mode 0)
		)
		(polygon
			(pts
				(arc
					(start 141.699742 -235.574332)
					(mid 141.069822 -235.574332)
					(end 141.699742 -235.574332)
				)
			)
		)
	)
	(zone
		(layers "B.Cu" "In11.Cu" "In13.Cu" "In15.Cu")
		(hatch none 0.5)
		(connect_pads
			(clearance 0)
		)
		(min_thickness 0.25)
		(keepout
			(tracks not_allowed)
			(vias allowed)
			(pads allowed)
			(copperpour not_allowed)
			(footprints allowed)
		)
		(placement
			(enabled no)
			(sheetname "")
		)
		(fill yes
			(thermal_gap 0.5)
			(thermal_bridge_width 0.5)
			(island_removal_mode 0)
		)
		(polygon
			(pts
				(arc
					(start 25.486106 -313.78525)
					(mid 24.818086 -313.78525)
					(end 25.486106 -313.78525)
				)
			)
		)
	)
	(zone
		(layers "B.Cu" "In11.Cu" "In13.Cu" "In15.Cu")
		(hatch none 0.5)
		(connect_pads
			(clearance 0)
		)
		(min_thickness 0.25)
		(keepout
			(tracks not_allowed)
			(vias allowed)
			(pads allowed)
			(copperpour not_allowed)
			(footprints allowed)
		)
		(placement
			(enabled no)
			(sheetname "")
		)
		(fill yes
			(thermal_gap 0.5)
			(thermal_bridge_width 0.5)
			(island_removal_mode 0)
		)
		(polygon
			(pts
				(arc
					(start 329.016106 -234.764072)
					(mid 328.386186 -234.764072)
					(end 329.016106 -234.764072)
				)
			)
		)
	)
	(zone
		(layers "B.Cu" "In11.Cu" "In13.Cu" "In15.Cu")
		(hatch none 0.5)
		(connect_pads
			(clearance 0)
		)
		(min_thickness 0.25)
		(keepout
			(tracks not_allowed)
			(vias allowed)
			(pads allowed)
			(copperpour not_allowed)
			(footprints allowed)
		)
		(placement
			(enabled no)
			(sheetname "")
		)
		(fill yes
			(thermal_gap 0.5)
			(thermal_bridge_width 0.5)
			(island_removal_mode 0)
		)
		(polygon
			(pts
				(arc
					(start 182.375556 -53.954934)
					(mid 181.707536 -53.954934)
					(end 182.375556 -53.954934)
				)
			)
		)
	)
	(zone
		(layers "B.Cu" "In11.Cu" "In13.Cu" "In15.Cu")
		(hatch none 0.5)
		(connect_pads
			(clearance 0)
		)
		(min_thickness 0.25)
		(keepout
			(tracks not_allowed)
			(vias allowed)
			(pads allowed)
			(copperpour not_allowed)
			(footprints allowed)
		)
		(placement
			(enabled no)
			(sheetname "")
		)
		(fill yes
			(thermal_gap 0.5)
			(thermal_bridge_width 0.5)
			(island_removal_mode 0)
		)
		(polygon
			(pts
				(arc
					(start 114.231166 -24.049736)
					(mid 113.563146 -24.049736)
					(end 114.231166 -24.049736)
				)
			)
		)
	)
	(zone
		(layers "B.Cu" "In11.Cu" "In13.Cu" "In15.Cu")
		(hatch none 0.5)
		(connect_pads
			(clearance 0)
		)
		(min_thickness 0.25)
		(keepout
			(tracks not_allowed)
			(vias allowed)
			(pads allowed)
			(copperpour not_allowed)
			(footprints allowed)
		)
		(placement
			(enabled no)
			(sheetname "")
		)
		(fill yes
			(thermal_gap 0.5)
			(thermal_bridge_width 0.5)
			(island_removal_mode 0)
		)
		(polygon
			(pts
				(arc
					(start 446.978278 -216.035128)
					(mid 446.310258 -216.035128)
					(end 446.978278 -216.035128)
				)
			)
		)
	)
	(zone
		(layers "B.Cu" "In11.Cu" "In13.Cu" "In15.Cu")
		(hatch none 0.5)
		(connect_pads
			(clearance 0)
		)
		(min_thickness 0.25)
		(keepout
			(tracks not_allowed)
			(vias allowed)
			(pads allowed)
			(copperpour not_allowed)
			(footprints allowed)
		)
		(placement
			(enabled no)
			(sheetname "")
		)
		(fill yes
			(thermal_gap 0.5)
			(thermal_bridge_width 0.5)
			(island_removal_mode 0)
		)
		(polygon
			(pts
				(arc
					(start 407.333958 -393.69238)
					(mid 406.704038 -393.69238)
					(end 407.333958 -393.69238)
				)
			)
		)
	)
	(zone
		(layers "B.Cu" "In11.Cu" "In13.Cu" "In15.Cu")
		(hatch none 0.5)
		(connect_pads
			(clearance 0)
		)
		(min_thickness 0.25)
		(keepout
			(tracks not_allowed)
			(vias allowed)
			(pads allowed)
			(copperpour not_allowed)
			(footprints allowed)
		)
		(placement
			(enabled no)
			(sheetname "")
		)
		(fill yes
			(thermal_gap 0.5)
			(thermal_bridge_width 0.5)
			(island_removal_mode 0)
		)
		(polygon
			(pts
				(arc
					(start 346.23375 -397.156432)
					(mid 345.60383 -397.156432)
					(end 346.23375 -397.156432)
				)
			)
		)
	)
	(zone
		(layers "B.Cu" "In11.Cu" "In13.Cu" "In15.Cu")
		(hatch none 0.5)
		(connect_pads
			(clearance 0)
		)
		(min_thickness 0.25)
		(keepout
			(tracks not_allowed)
			(vias allowed)
			(pads allowed)
			(copperpour not_allowed)
			(footprints allowed)
		)
		(placement
			(enabled no)
			(sheetname "")
		)
		(fill yes
			(thermal_gap 0.5)
			(thermal_bridge_width 0.5)
			(island_removal_mode 0)
		)
		(polygon
			(pts
				(arc
					(start 446.978278 -225.385122)
					(mid 446.310258 -225.385122)
					(end 446.978278 -225.385122)
				)
			)
		)
	)
	(zone
		(layers "B.Cu" "In11.Cu" "In13.Cu" "In15.Cu")
		(hatch none 0.5)
		(connect_pads
			(clearance 0)
		)
		(min_thickness 0.25)
		(keepout
			(tracks not_allowed)
			(vias allowed)
			(pads allowed)
			(copperpour not_allowed)
			(footprints allowed)
		)
		(placement
			(enabled no)
			(sheetname "")
		)
		(fill yes
			(thermal_gap 0.5)
			(thermal_bridge_width 0.5)
			(island_removal_mode 0)
		)
		(polygon
			(pts
				(arc
					(start 273.426174 -238.985044)
					(mid 272.758154 -238.985044)
					(end 273.426174 -238.985044)
				)
			)
		)
	)
	(zone
		(layers "B.Cu" "In11.Cu" "In13.Cu" "In15.Cu")
		(hatch none 0.5)
		(connect_pads
			(clearance 0)
		)
		(min_thickness 0.25)
		(keepout
			(tracks not_allowed)
			(vias allowed)
			(pads allowed)
			(copperpour not_allowed)
			(footprints allowed)
		)
		(placement
			(enabled no)
			(sheetname "")
		)
		(fill yes
			(thermal_gap 0.5)
			(thermal_bridge_width 0.5)
			(island_removal_mode 0)
		)
		(polygon
			(pts
				(arc
					(start 389.469884 -263.555988)
					(mid 388.839964 -263.555988)
					(end 389.469884 -263.555988)
				)
			)
		)
	)
	(zone
		(layers "B.Cu" "In11.Cu" "In13.Cu" "In15.Cu")
		(hatch none 0.5)
		(connect_pads
			(clearance 0)
		)
		(min_thickness 0.25)
		(keepout
			(tracks not_allowed)
			(vias allowed)
			(pads allowed)
			(copperpour not_allowed)
			(footprints allowed)
		)
		(placement
			(enabled no)
			(sheetname "")
		)
		(fill yes
			(thermal_gap 0.5)
			(thermal_bridge_width 0.5)
			(island_removal_mode 0)
		)
		(polygon
			(pts
				(arc
					(start 128.136904 -428.28972)
					(mid 127.362712 -428.28972)
					(end 128.136904 -428.28972)
				)
			)
		)
	)
	(zone
		(layers "B.Cu" "In11.Cu" "In13.Cu" "In15.Cu")
		(hatch none 0.5)
		(connect_pads
			(clearance 0)
		)
		(min_thickness 0.25)
		(keepout
			(tracks not_allowed)
			(vias allowed)
			(pads allowed)
			(copperpour not_allowed)
			(footprints allowed)
		)
		(placement
			(enabled no)
			(sheetname "")
		)
		(fill yes
			(thermal_gap 0.5)
			(thermal_bridge_width 0.5)
			(island_removal_mode 0)
		)
		(polygon
			(pts
				(arc
					(start 57.70626 -388.774432)
					(mid 57.07634 -388.774432)
					(end 57.70626 -388.774432)
				)
			)
		)
	)
	(zone
		(layers "B.Cu" "In11.Cu" "In13.Cu" "In15.Cu")
		(hatch none 0.5)
		(connect_pads
			(clearance 0)
		)
		(min_thickness 0.25)
		(keepout
			(tracks not_allowed)
			(vias allowed)
			(pads allowed)
			(copperpour not_allowed)
			(footprints allowed)
		)
		(placement
			(enabled no)
			(sheetname "")
		)
		(fill yes
			(thermal_gap 0.5)
			(thermal_bridge_width 0.5)
			(island_removal_mode 0)
		)
		(polygon
			(pts
				(arc
					(start 98.295968 -281.376374)
					(mid 97.666048 -281.376374)
					(end 98.295968 -281.376374)
				)
			)
		)
	)
	(zone
		(layers "B.Cu" "In11.Cu" "In13.Cu" "In15.Cu")
		(hatch none 0.5)
		(connect_pads
			(clearance 0)
		)
		(min_thickness 0.25)
		(keepout
			(tracks not_allowed)
			(vias allowed)
			(pads allowed)
			(copperpour not_allowed)
			(footprints allowed)
		)
		(placement
			(enabled no)
			(sheetname "")
		)
		(fill yes
			(thermal_gap 0.5)
			(thermal_bridge_width 0.5)
			(island_removal_mode 0)
		)
		(polygon
			(pts
				(arc
					(start 132.136896 -427.089824)
					(mid 131.362704 -427.089824)
					(end 132.136896 -427.089824)
				)
			)
		)
	)
	(zone
		(layers "B.Cu" "In11.Cu" "In13.Cu" "In15.Cu")
		(hatch none 0.5)
		(connect_pads
			(clearance 0)
		)
		(min_thickness 0.25)
		(keepout
			(tracks not_allowed)
			(vias allowed)
			(pads allowed)
			(copperpour not_allowed)
			(footprints allowed)
		)
		(placement
			(enabled no)
			(sheetname "")
		)
		(fill yes
			(thermal_gap 0.5)
			(thermal_bridge_width 0.5)
			(island_removal_mode 0)
		)
		(polygon
			(pts
				(arc
					(start 390.879838 -264.365994)
					(mid 390.249918 -264.365994)
					(end 390.879838 -264.365994)
				)
			)
		)
	)
	(zone
		(layers "B.Cu" "In11.Cu" "In13.Cu" "In15.Cu")
		(hatch none 0.5)
		(connect_pads
			(clearance 0)
		)
		(min_thickness 0.25)
		(keepout
			(tracks not_allowed)
			(vias allowed)
			(pads allowed)
			(copperpour not_allowed)
			(footprints allowed)
		)
		(placement
			(enabled no)
			(sheetname "")
		)
		(fill yes
			(thermal_gap 0.5)
			(thermal_bridge_width 0.5)
			(island_removal_mode 0)
		)
		(polygon
			(pts
				(arc
					(start 29.586174 -204.985366)
					(mid 28.918154 -204.985366)
					(end 29.586174 -204.985366)
				)
			)
		)
	)
	(zone
		(layers "B.Cu" "In11.Cu" "In13.Cu" "In15.Cu")
		(hatch none 0.5)
		(connect_pads
			(clearance 0)
		)
		(min_thickness 0.25)
		(keepout
			(tracks not_allowed)
			(vias allowed)
			(pads allowed)
			(copperpour not_allowed)
			(footprints allowed)
		)
		(placement
			(enabled no)
			(sheetname "")
		)
		(fill yes
			(thermal_gap 0.5)
			(thermal_bridge_width 0.5)
			(island_removal_mode 0)
		)
		(polygon
			(pts
				(arc
					(start 355.033834 -397.849344)
					(mid 354.403914 -397.849344)
					(end 355.033834 -397.849344)
				)
			)
		)
	)
	(zone
		(layers "B.Cu" "In11.Cu" "In13.Cu" "In15.Cu")
		(hatch none 0.5)
		(connect_pads
			(clearance 0)
		)
		(min_thickness 0.25)
		(keepout
			(tracks not_allowed)
			(vias allowed)
			(pads allowed)
			(copperpour not_allowed)
			(footprints allowed)
		)
		(placement
			(enabled no)
			(sheetname "")
		)
		(fill yes
			(thermal_gap 0.5)
			(thermal_bridge_width 0.5)
			(island_removal_mode 0)
		)
		(polygon
			(pts
				(arc
					(start 273.426174 -301.034958)
					(mid 272.758154 -301.034958)
					(end 273.426174 -301.034958)
				)
			)
		)
	)
	(zone
		(layers "B.Cu" "In11.Cu" "In13.Cu" "In15.Cu")
		(hatch none 0.5)
		(connect_pads
			(clearance 0)
		)
		(min_thickness 0.25)
		(keepout
			(tracks not_allowed)
			(vias allowed)
			(pads allowed)
			(copperpour not_allowed)
			(footprints allowed)
		)
		(placement
			(enabled no)
			(sheetname "")
		)
		(fill yes
			(thermal_gap 0.5)
			(thermal_bridge_width 0.5)
			(island_removal_mode 0)
		)
		(polygon
			(pts
				(arc
					(start 446.978278 -242.385088)
					(mid 446.310258 -242.385088)
					(end 446.978278 -242.385088)
				)
			)
		)
	)
	(zone
		(layers "B.Cu" "In11.Cu" "In13.Cu" "In15.Cu")
		(hatch none 0.5)
		(connect_pads
			(clearance 0)
		)
		(min_thickness 0.25)
		(keepout
			(tracks not_allowed)
			(vias allowed)
			(pads allowed)
			(copperpour not_allowed)
			(footprints allowed)
		)
		(placement
			(enabled no)
			(sheetname "")
		)
		(fill yes
			(thermal_gap 0.5)
			(thermal_bridge_width 0.5)
			(island_removal_mode 0)
		)
		(polygon
			(pts
				(arc
					(start 329.486006 -233.954066)
					(mid 328.856086 -233.954066)
					(end 329.486006 -233.954066)
				)
			)
		)
	)
	(zone
		(layers "B.Cu" "In11.Cu" "In13.Cu" "In15.Cu")
		(hatch none 0.5)
		(connect_pads
			(clearance 0)
		)
		(min_thickness 0.25)
		(keepout
			(tracks not_allowed)
			(vias allowed)
			(pads allowed)
			(copperpour not_allowed)
			(footprints allowed)
		)
		(placement
			(enabled no)
			(sheetname "")
		)
		(fill yes
			(thermal_gap 0.5)
			(thermal_bridge_width 0.5)
			(island_removal_mode 0)
		)
		(polygon
			(pts
				(arc
					(start 391.349738 -278.136096)
					(mid 390.719818 -278.136096)
					(end 391.349738 -278.136096)
				)
			)
		)
	)
	(zone
		(layers "B.Cu" "In11.Cu" "In13.Cu" "In15.Cu")
		(hatch none 0.5)
		(connect_pads
			(clearance 0)
		)
		(min_thickness 0.25)
		(keepout
			(tracks not_allowed)
			(vias allowed)
			(pads allowed)
			(copperpour not_allowed)
			(footprints allowed)
		)
		(placement
			(enabled no)
			(sheetname "")
		)
		(fill yes
			(thermal_gap 0.5)
			(thermal_bridge_width 0.5)
			(island_removal_mode 0)
		)
		(polygon
			(pts
				(arc
					(start 81.076038 -228.284532)
					(mid 80.446118 -228.284532)
					(end 81.076038 -228.284532)
				)
			)
		)
	)
	(zone
		(layers "B.Cu" "In11.Cu" "In13.Cu" "In15.Cu")
		(hatch none 0.5)
		(connect_pads
			(clearance 0)
		)
		(min_thickness 0.25)
		(keepout
			(tracks not_allowed)
			(vias allowed)
			(pads allowed)
			(copperpour not_allowed)
			(footprints allowed)
		)
		(placement
			(enabled no)
			(sheetname "")
		)
		(fill yes
			(thermal_gap 0.5)
			(thermal_bridge_width 0.5)
			(island_removal_mode 0)
		)
		(polygon
			(pts
				(arc
					(start 391.349738 -292.71595)
					(mid 390.719818 -292.71595)
					(end 391.349738 -292.71595)
				)
			)
		)
	)
	(zone
		(layers "B.Cu" "In11.Cu" "In13.Cu" "In15.Cu")
		(hatch none 0.5)
		(connect_pads
			(clearance 0)
		)
		(min_thickness 0.25)
		(keepout
			(tracks not_allowed)
			(vias allowed)
			(pads allowed)
			(copperpour not_allowed)
			(footprints allowed)
		)
		(placement
			(enabled no)
			(sheetname "")
		)
		(fill yes
			(thermal_gap 0.5)
			(thermal_bridge_width 0.5)
			(island_removal_mode 0)
		)
		(polygon
			(pts
				(arc
					(start 62.906148 -389.467344)
					(mid 62.276228 -389.467344)
					(end 62.906148 -389.467344)
				)
			)
		)
	)
	(zone
		(layers "B.Cu" "In11.Cu" "In13.Cu" "In15.Cu")
		(hatch none 0.5)
		(connect_pads
			(clearance 0)
		)
		(min_thickness 0.25)
		(keepout
			(tracks not_allowed)
			(vias allowed)
			(pads allowed)
			(copperpour not_allowed)
			(footprints allowed)
		)
		(placement
			(enabled no)
			(sheetname "")
		)
		(fill yes
			(thermal_gap 0.5)
			(thermal_bridge_width 0.5)
			(island_removal_mode 0)
		)
		(polygon
			(pts
				(arc
					(start 317.036704 -428.28972)
					(mid 316.262512 -428.28972)
					(end 317.036704 -428.28972)
				)
			)
		)
	)
	(zone
		(layers "B.Cu" "In11.Cu" "In13.Cu" "In15.Cu")
		(hatch none 0.5)
		(connect_pads
			(clearance 0)
		)
		(min_thickness 0.25)
		(keepout
			(tracks not_allowed)
			(vias allowed)
			(pads allowed)
			(copperpour not_allowed)
			(footprints allowed)
		)
		(placement
			(enabled no)
			(sheetname "")
		)
		(fill yes
			(thermal_gap 0.5)
			(thermal_bridge_width 0.5)
			(island_removal_mode 0)
		)
		(polygon
			(pts
				(arc
					(start 194.938142 -297.635422)
					(mid 194.270122 -297.635422)
					(end 194.938142 -297.635422)
				)
			)
		)
	)
	(zone
		(layers "B.Cu" "In11.Cu" "In13.Cu" "In15.Cu")
		(hatch none 0.5)
		(connect_pads
			(clearance 0)
		)
		(min_thickness 0.25)
		(keepout
			(tracks not_allowed)
			(vias allowed)
			(pads allowed)
			(copperpour not_allowed)
			(footprints allowed)
		)
		(placement
			(enabled no)
			(sheetname "")
		)
		(fill yes
			(thermal_gap 0.5)
			(thermal_bridge_width 0.5)
			(island_removal_mode 0)
		)
		(polygon
			(pts
				(arc
					(start 164.933884 -386.003292)
					(mid 164.303964 -386.003292)
					(end 164.933884 -386.003292)
				)
			)
		)
	)
	(zone
		(layers "B.Cu" "In11.Cu" "In13.Cu" "In15.Cu")
		(hatch none 0.5)
		(connect_pads
			(clearance 0)
		)
		(min_thickness 0.25)
		(keepout
			(tracks not_allowed)
			(vias allowed)
			(pads allowed)
			(copperpour not_allowed)
			(footprints allowed)
		)
		(placement
			(enabled no)
			(sheetname "")
		)
		(fill yes
			(thermal_gap 0.5)
			(thermal_bridge_width 0.5)
			(island_removal_mode 0)
		)
		(polygon
			(pts
				(arc
					(start 446.978278 -285.735014)
					(mid 446.310258 -285.735014)
					(end 446.978278 -285.735014)
				)
			)
		)
	)
	(zone
		(layers "B.Cu" "In11.Cu" "In13.Cu" "In15.Cu")
		(hatch none 0.5)
		(connect_pads
			(clearance 0)
		)
		(min_thickness 0.25)
		(keepout
			(tracks not_allowed)
			(vias allowed)
			(pads allowed)
			(copperpour not_allowed)
			(footprints allowed)
		)
		(placement
			(enabled no)
			(sheetname "")
		)
		(fill yes
			(thermal_gap 0.5)
			(thermal_bridge_width 0.5)
			(island_removal_mode 0)
		)
		(polygon
			(pts
				(arc
					(start 25.486106 -316.33541)
					(mid 24.818086 -316.33541)
					(end 25.486106 -316.33541)
				)
			)
		)
	)
	(zone
		(layers "B.Cu" "In11.Cu" "In13.Cu" "In15.Cu")
		(hatch none 0.5)
		(connect_pads
			(clearance 0)
		)
		(min_thickness 0.25)
		(keepout
			(tracks not_allowed)
			(vias allowed)
			(pads allowed)
			(copperpour not_allowed)
			(footprints allowed)
		)
		(placement
			(enabled no)
			(sheetname "")
		)
		(fill yes
			(thermal_gap 0.5)
			(thermal_bridge_width 0.5)
			(island_removal_mode 0)
		)
		(polygon
			(pts
				(arc
					(start 72.634094 -404.46452)
					(mid 71.966074 -404.46452)
					(end 72.634094 -404.46452)
				)
			)
		)
	)
	(zone
		(layers "B.Cu" "In11.Cu" "In13.Cu" "In15.Cu")
		(hatch none 0.5)
		(connect_pads
			(clearance 0)
		)
		(min_thickness 0.25)
		(keepout
			(tracks not_allowed)
			(vias allowed)
			(pads allowed)
			(copperpour not_allowed)
			(footprints allowed)
		)
		(placement
			(enabled no)
			(sheetname "")
		)
		(fill yes
			(thermal_gap 0.5)
			(thermal_bridge_width 0.5)
			(island_removal_mode 0)
		)
		(polygon
			(pts
				(arc
					(start 29.586174 -292.535356)
					(mid 28.918154 -292.535356)
					(end 29.586174 -292.535356)
				)
			)
		)
	)
	(zone
		(layers "B.Cu" "In11.Cu" "In13.Cu" "In15.Cu")
		(hatch none 0.5)
		(connect_pads
			(clearance 0)
		)
		(min_thickness 0.25)
		(keepout
			(tracks not_allowed)
			(vias allowed)
			(pads allowed)
			(copperpour not_allowed)
			(footprints allowed)
		)
		(placement
			(enabled no)
			(sheetname "")
		)
		(fill yes
			(thermal_gap 0.5)
			(thermal_bridge_width 0.5)
			(island_removal_mode 0)
		)
		(polygon
			(pts
				(arc
					(start 390.579864 -235.574078)
					(mid 389.949944 -235.574078)
					(end 390.579864 -235.574078)
				)
			)
		)
	)
	(zone
		(layers "B.Cu" "In11.Cu" "In13.Cu" "In15.Cu")
		(hatch none 0.5)
		(connect_pads
			(clearance 0)
		)
		(min_thickness 0.25)
		(keepout
			(tracks not_allowed)
			(vias allowed)
			(pads allowed)
			(copperpour not_allowed)
			(footprints allowed)
		)
		(placement
			(enabled no)
			(sheetname "")
		)
		(fill yes
			(thermal_gap 0.5)
			(thermal_bridge_width 0.5)
			(island_removal_mode 0)
		)
		(polygon
			(pts
				(arc
					(start 66.336164 -369.03533)
					(mid 65.668144 -369.03533)
					(end 66.336164 -369.03533)
				)
			)
		)
	)
	(zone
		(layers "B.Cu" "In11.Cu" "In13.Cu" "In15.Cu")
		(hatch none 0.5)
		(connect_pads
			(clearance 0)
		)
		(min_thickness 0.25)
		(keepout
			(tracks not_allowed)
			(vias allowed)
			(pads allowed)
			(copperpour not_allowed)
			(footprints allowed)
		)
		(placement
			(enabled no)
			(sheetname "")
		)
		(fill yes
			(thermal_gap 0.5)
			(thermal_bridge_width 0.5)
			(island_removal_mode 0)
		)
		(polygon
			(pts
				(arc
					(start 357.046022 -282.186126)
					(mid 356.416102 -282.186126)
					(end 357.046022 -282.186126)
				)
			)
		)
	)
	(zone
		(layers "B.Cu" "In11.Cu" "In13.Cu" "In15.Cu")
		(hatch none 0.5)
		(connect_pads
			(clearance 0)
		)
		(min_thickness 0.25)
		(keepout
			(tracks not_allowed)
			(vias allowed)
			(pads allowed)
			(copperpour not_allowed)
			(footprints allowed)
		)
		(placement
			(enabled no)
			(sheetname "")
		)
		(fill yes
			(thermal_gap 0.5)
			(thermal_bridge_width 0.5)
			(island_removal_mode 0)
		)
		(polygon
			(pts
				(arc
					(start 329.016106 -226.664266)
					(mid 328.386186 -226.664266)
					(end 329.016106 -226.664266)
				)
			)
		)
	)
	(zone
		(layers "B.Cu" "In11.Cu" "In13.Cu" "In15.Cu")
		(hatch none 0.5)
		(connect_pads
			(clearance 0)
		)
		(min_thickness 0.25)
		(keepout
			(tracks not_allowed)
			(vias allowed)
			(pads allowed)
			(copperpour not_allowed)
			(footprints allowed)
		)
		(placement
			(enabled no)
			(sheetname "")
		)
		(fill yes
			(thermal_gap 0.5)
			(thermal_bridge_width 0.5)
			(island_removal_mode 0)
		)
		(polygon
			(pts
				(arc
					(start 29.586174 -254.285242)
					(mid 28.918154 -254.285242)
					(end 29.586174 -254.285242)
				)
			)
		)
	)
	(zone
		(layers "B.Cu" "In11.Cu" "In13.Cu" "In15.Cu")
		(hatch none 0.5)
		(connect_pads
			(clearance 0)
		)
		(min_thickness 0.25)
		(keepout
			(tracks not_allowed)
			(vias allowed)
			(pads allowed)
			(copperpour not_allowed)
			(footprints allowed)
		)
		(placement
			(enabled no)
			(sheetname "")
		)
		(fill yes
			(thermal_gap 0.5)
			(thermal_bridge_width 0.5)
			(island_removal_mode 0)
		)
		(polygon
			(pts
				(arc
					(start 442.87821 -227.935028)
					(mid 442.21019 -227.935028)
					(end 442.87821 -227.935028)
				)
			)
		)
	)
	(zone
		(layers "B.Cu" "In11.Cu" "In13.Cu" "In15.Cu")
		(hatch none 0.5)
		(connect_pads
			(clearance 0)
		)
		(min_thickness 0.25)
		(keepout
			(tracks not_allowed)
			(vias allowed)
			(pads allowed)
			(copperpour not_allowed)
			(footprints allowed)
		)
		(placement
			(enabled no)
			(sheetname "")
		)
		(fill yes
			(thermal_gap 0.5)
			(thermal_bridge_width 0.5)
			(island_removal_mode 0)
		)
		(polygon
			(pts
				(arc
					(start 394.13688 -426.089826)
					(mid 393.362688 -426.089826)
					(end 394.13688 -426.089826)
				)
			)
		)
	)
	(zone
		(layers "B.Cu" "In11.Cu" "In13.Cu" "In15.Cu")
		(hatch none 0.5)
		(connect_pads
			(clearance 0)
		)
		(min_thickness 0.25)
		(keepout
			(tracks not_allowed)
			(vias allowed)
			(pads allowed)
			(copperpour not_allowed)
			(footprints allowed)
		)
		(placement
			(enabled no)
			(sheetname "")
		)
		(fill yes
			(thermal_gap 0.5)
			(thermal_bridge_width 0.5)
			(island_removal_mode 0)
		)
		(polygon
			(pts
				(arc
					(start 442.87821 -215.18499)
					(mid 442.21019 -215.18499)
					(end 442.87821 -215.18499)
				)
			)
		)
	)
	(zone
		(layers "B.Cu" "In11.Cu" "In13.Cu" "In15.Cu")
		(hatch none 0.5)
		(connect_pads
			(clearance 0)
		)
		(min_thickness 0.25)
		(keepout
			(tracks not_allowed)
			(vias allowed)
			(pads allowed)
			(copperpour not_allowed)
			(footprints allowed)
		)
		(placement
			(enabled no)
			(sheetname "")
		)
		(fill yes
			(thermal_gap 0.5)
			(thermal_bridge_width 0.5)
			(island_removal_mode 0)
		)
		(polygon
			(pts
				(arc
					(start 446.978278 -214.335106)
					(mid 446.310258 -214.335106)
					(end 446.978278 -214.335106)
				)
			)
		)
	)
	(zone
		(layers "B.Cu" "In11.Cu" "In13.Cu" "In15.Cu")
		(hatch none 0.5)
		(connect_pads
			(clearance 0)
		)
		(min_thickness 0.25)
		(keepout
			(tracks not_allowed)
			(vias allowed)
			(pads allowed)
			(copperpour not_allowed)
			(footprints allowed)
		)
		(placement
			(enabled no)
			(sheetname "")
		)
		(fill yes
			(thermal_gap 0.5)
			(thermal_bridge_width 0.5)
			(island_removal_mode 0)
		)
		(polygon
			(pts
				(arc
					(start 194.938142 -215.185244)
					(mid 194.270122 -215.185244)
					(end 194.938142 -215.185244)
				)
			)
		)
	)
	(zone
		(layers "B.Cu" "In11.Cu" "In13.Cu" "In15.Cu")
		(hatch none 0.5)
		(connect_pads
			(clearance 0)
		)
		(min_thickness 0.25)
		(keepout
			(tracks not_allowed)
			(vias allowed)
			(pads allowed)
			(copperpour not_allowed)
			(footprints allowed)
		)
		(placement
			(enabled no)
			(sheetname "")
		)
		(fill yes
			(thermal_gap 0.5)
			(thermal_bridge_width 0.5)
			(island_removal_mode 0)
		)
		(polygon
			(pts
				(arc
					(start 329.78598 -277.32609)
					(mid 329.15606 -277.32609)
					(end 329.78598 -277.32609)
				)
			)
		)
	)
	(zone
		(layers "B.Cu" "In11.Cu" "In13.Cu" "In15.Cu")
		(hatch none 0.5)
		(connect_pads
			(clearance 0)
		)
		(min_thickness 0.25)
		(keepout
			(tracks not_allowed)
			(vias allowed)
			(pads allowed)
			(copperpour not_allowed)
			(footprints allowed)
		)
		(placement
			(enabled no)
			(sheetname "")
		)
		(fill yes
			(thermal_gap 0.5)
			(thermal_bridge_width 0.5)
			(island_removal_mode 0)
		)
		(polygon
			(pts
				(arc
					(start 199.03821 -309.535322)
					(mid 198.37019 -309.535322)
					(end 199.03821 -309.535322)
				)
			)
		)
	)
	(zone
		(layers "B.Cu" "In11.Cu" "In13.Cu" "In15.Cu")
		(hatch none 0.5)
		(connect_pads
			(clearance 0)
		)
		(min_thickness 0.25)
		(keepout
			(tracks not_allowed)
			(vias allowed)
			(pads allowed)
			(copperpour not_allowed)
			(footprints allowed)
		)
		(placement
			(enabled no)
			(sheetname "")
		)
		(fill yes
			(thermal_gap 0.5)
			(thermal_bridge_width 0.5)
			(island_removal_mode 0)
		)
		(polygon
			(pts
				(arc
					(start 373.489728 -284.616144)
					(mid 372.859808 -284.616144)
					(end 373.489728 -284.616144)
				)
			)
		)
	)
	(zone
		(layers "B.Cu" "In11.Cu" "In13.Cu" "In15.Cu")
		(hatch none 0.5)
		(connect_pads
			(clearance 0)
		)
		(min_thickness 0.25)
		(keepout
			(tracks not_allowed)
			(vias allowed)
			(pads allowed)
			(copperpour not_allowed)
			(footprints allowed)
		)
		(placement
			(enabled no)
			(sheetname "")
		)
		(fill yes
			(thermal_gap 0.5)
			(thermal_bridge_width 0.5)
			(island_removal_mode 0)
		)
		(polygon
			(pts
				(arc
					(start 390.136888 -427.289976)
					(mid 389.362696 -427.289976)
					(end 390.136888 -427.289976)
				)
			)
		)
	)
	(zone
		(layers "B.Cu" "In11.Cu" "In13.Cu" "In15.Cu")
		(hatch none 0.5)
		(connect_pads
			(clearance 0)
		)
		(min_thickness 0.25)
		(keepout
			(tracks not_allowed)
			(vias allowed)
			(pads allowed)
			(copperpour not_allowed)
			(footprints allowed)
		)
		(placement
			(enabled no)
			(sheetname "")
		)
		(fill yes
			(thermal_gap 0.5)
			(thermal_bridge_width 0.5)
			(island_removal_mode 0)
		)
		(polygon
			(pts
				(arc
					(start 141.999716 -275.706332)
					(mid 141.369796 -275.706332)
					(end 141.999716 -275.706332)
				)
			)
		)
	)
	(zone
		(layers "B.Cu" "In11.Cu" "In13.Cu" "In15.Cu")
		(hatch none 0.5)
		(connect_pads
			(clearance 0)
		)
		(min_thickness 0.25)
		(keepout
			(tracks not_allowed)
			(vias allowed)
			(pads allowed)
			(copperpour not_allowed)
			(footprints allowed)
		)
		(placement
			(enabled no)
			(sheetname "")
		)
		(fill yes
			(thermal_gap 0.5)
			(thermal_bridge_width 0.5)
			(island_removal_mode 0)
		)
		(polygon
			(pts
				(arc
					(start 277.526242 -279.785064)
					(mid 276.858222 -279.785064)
					(end 277.526242 -279.785064)
				)
			)
		)
	)
	(zone
		(layers "B.Cu" "In11.Cu" "In13.Cu" "In15.Cu")
		(hatch none 0.5)
		(connect_pads
			(clearance 0)
		)
		(min_thickness 0.25)
		(keepout
			(tracks not_allowed)
			(vias allowed)
			(pads allowed)
			(copperpour not_allowed)
			(footprints allowed)
		)
		(placement
			(enabled no)
			(sheetname "")
		)
		(fill yes
			(thermal_gap 0.5)
			(thermal_bridge_width 0.5)
			(island_removal_mode 0)
		)
		(polygon
			(pts
				(arc
					(start 82.955892 -242.864386)
					(mid 82.325972 -242.864386)
					(end 82.955892 -242.864386)
				)
			)
		)
	)
	(zone
		(layers "B.Cu" "In11.Cu" "In13.Cu" "In15.Cu")
		(hatch none 0.5)
		(connect_pads
			(clearance 0)
		)
		(min_thickness 0.25)
		(keepout
			(tracks not_allowed)
			(vias allowed)
			(pads allowed)
			(copperpour not_allowed)
			(footprints allowed)
		)
		(placement
			(enabled no)
			(sheetname "")
		)
		(fill yes
			(thermal_gap 0.5)
			(thermal_bridge_width 0.5)
			(island_removal_mode 0)
		)
		(polygon
			(pts
				(arc
					(start 81.076038 -242.864386)
					(mid 80.446118 -242.864386)
					(end 81.076038 -242.864386)
				)
			)
		)
	)
	(zone
		(layers "B.Cu" "In11.Cu" "In13.Cu" "In15.Cu")
		(hatch none 0.5)
		(connect_pads
			(clearance 0)
		)
		(min_thickness 0.25)
		(keepout
			(tracks not_allowed)
			(vias allowed)
			(pads allowed)
			(copperpour not_allowed)
			(footprints allowed)
		)
		(placement
			(enabled no)
			(sheetname "")
		)
		(fill yes
			(thermal_gap 0.5)
			(thermal_bridge_width 0.5)
			(island_removal_mode 0)
		)
		(polygon
			(pts
				(arc
					(start 273.426174 -310.384952)
					(mid 272.758154 -310.384952)
					(end 273.426174 -310.384952)
				)
			)
		)
	)
	(zone
		(layers "B.Cu" "In11.Cu" "In13.Cu" "In15.Cu")
		(hatch none 0.5)
		(connect_pads
			(clearance 0)
		)
		(min_thickness 0.25)
		(keepout
			(tracks not_allowed)
			(vias allowed)
			(pads allowed)
			(copperpour not_allowed)
			(footprints allowed)
		)
		(placement
			(enabled no)
			(sheetname "")
		)
		(fill yes
			(thermal_gap 0.5)
			(thermal_bridge_width 0.5)
			(island_removal_mode 0)
		)
		(polygon
			(pts
				(arc
					(start 389.939784 -290.285932)
					(mid 389.309864 -290.285932)
					(end 389.939784 -290.285932)
				)
			)
		)
	)
	(zone
		(layers "B.Cu" "In11.Cu" "In13.Cu" "In15.Cu")
		(hatch none 0.5)
		(connect_pads
			(clearance 0)
		)
		(min_thickness 0.25)
		(keepout
			(tracks not_allowed)
			(vias allowed)
			(pads allowed)
			(copperpour not_allowed)
			(footprints allowed)
		)
		(placement
			(enabled no)
			(sheetname "")
		)
		(fill yes
			(thermal_gap 0.5)
			(thermal_bridge_width 0.5)
			(island_removal_mode 0)
		)
		(polygon
			(pts
				(arc
					(start 446.978278 -210.085178)
					(mid 446.310258 -210.085178)
					(end 446.978278 -210.085178)
				)
			)
		)
	)
	(zone
		(layers "B.Cu" "In11.Cu" "In13.Cu" "In15.Cu")
		(hatch none 0.5)
		(connect_pads
			(clearance 0)
		)
		(min_thickness 0.25)
		(keepout
			(tracks not_allowed)
			(vias allowed)
			(pads allowed)
			(copperpour not_allowed)
			(footprints allowed)
		)
		(placement
			(enabled no)
			(sheetname "")
		)
		(fill yes
			(thermal_gap 0.5)
			(thermal_bridge_width 0.5)
			(island_removal_mode 0)
		)
		(polygon
			(pts
				(arc
					(start 389.469884 -287.856168)
					(mid 388.839964 -287.856168)
					(end 389.469884 -287.856168)
				)
			)
		)
	)
	(zone
		(layers "B.Cu" "In11.Cu" "In13.Cu" "In15.Cu")
		(hatch none 0.5)
		(connect_pads
			(clearance 0)
		)
		(min_thickness 0.25)
		(keepout
			(tracks not_allowed)
			(vias allowed)
			(pads allowed)
			(copperpour not_allowed)
			(footprints allowed)
		)
		(placement
			(enabled no)
			(sheetname "")
		)
		(fill yes
			(thermal_gap 0.5)
			(thermal_bridge_width 0.5)
			(island_removal_mode 0)
		)
		(polygon
			(pts
				(arc
					(start 331.195934 -292.71595)
					(mid 330.566014 -292.71595)
					(end 331.195934 -292.71595)
				)
			)
		)
	)
	(zone
		(layers "B.Cu" "In11.Cu" "In13.Cu" "In15.Cu")
		(hatch none 0.5)
		(connect_pads
			(clearance 0)
		)
		(min_thickness 0.25)
		(keepout
			(tracks not_allowed)
			(vias allowed)
			(pads allowed)
			(copperpour not_allowed)
			(footprints allowed)
		)
		(placement
			(enabled no)
			(sheetname "")
		)
		(fill yes
			(thermal_gap 0.5)
			(thermal_bridge_width 0.5)
			(island_removal_mode 0)
		)
		(polygon
			(pts
				(arc
					(start 329.486006 -251.774198)
					(mid 328.856086 -251.774198)
					(end 329.486006 -251.774198)
				)
			)
		)
	)
	(zone
		(layers "B.Cu" "In11.Cu" "In13.Cu" "In15.Cu")
		(hatch none 0.5)
		(connect_pads
			(clearance 0)
		)
		(min_thickness 0.25)
		(keepout
			(tracks not_allowed)
			(vias allowed)
			(pads allowed)
			(copperpour not_allowed)
			(footprints allowed)
		)
		(placement
			(enabled no)
			(sheetname "")
		)
		(fill yes
			(thermal_gap 0.5)
			(thermal_bridge_width 0.5)
			(island_removal_mode 0)
		)
		(polygon
			(pts
				(arc
					(start 80.037178 -427.289976)
					(mid 79.262986 -427.289976)
					(end 80.037178 -427.289976)
				)
			)
		)
	)
	(zone
		(layers "B.Cu" "In11.Cu" "In13.Cu" "In15.Cu")
		(hatch none 0.5)
		(connect_pads
			(clearance 0)
		)
		(min_thickness 0.25)
		(keepout
			(tracks not_allowed)
			(vias allowed)
			(pads allowed)
			(copperpour not_allowed)
			(footprints allowed)
		)
		(placement
			(enabled no)
			(sheetname "")
		)
		(fill yes
			(thermal_gap 0.5)
			(thermal_bridge_width 0.5)
			(island_removal_mode 0)
		)
		(polygon
			(pts
				(arc
					(start 442.87821 -239.835182)
					(mid 442.21019 -239.835182)
					(end 442.87821 -239.835182)
				)
			)
		)
	)
	(zone
		(layers "B.Cu" "In11.Cu" "In13.Cu" "In15.Cu")
		(hatch none 0.5)
		(connect_pads
			(clearance 0)
		)
		(min_thickness 0.25)
		(keepout
			(tracks not_allowed)
			(vias allowed)
			(pads allowed)
			(copperpour not_allowed)
			(footprints allowed)
		)
		(placement
			(enabled no)
			(sheetname "")
		)
		(fill yes
			(thermal_gap 0.5)
			(thermal_bridge_width 0.5)
			(island_removal_mode 0)
		)
		(polygon
			(pts
				(arc
					(start 199.03821 -311.235344)
					(mid 198.37019 -311.235344)
					(end 199.03821 -311.235344)
				)
			)
		)
	)
	(zone
		(layers "B.Cu" "In11.Cu" "In13.Cu" "In15.Cu")
		(hatch none 0.5)
		(connect_pads
			(clearance 0)
		)
		(min_thickness 0.25)
		(keepout
			(tracks not_allowed)
			(vias allowed)
			(pads allowed)
			(copperpour not_allowed)
			(footprints allowed)
		)
		(placement
			(enabled no)
			(sheetname "")
		)
		(fill yes
			(thermal_gap 0.5)
			(thermal_bridge_width 0.5)
			(island_removal_mode 0)
		)
		(polygon
			(pts
				(arc
					(start 330.42606 -243.674138)
					(mid 329.79614 -243.674138)
					(end 330.42606 -243.674138)
				)
			)
		)
	)
	(zone
		(layers "B.Cu" "In11.Cu" "In13.Cu" "In15.Cu")
		(hatch none 0.5)
		(connect_pads
			(clearance 0)
		)
		(min_thickness 0.25)
		(keepout
			(tracks not_allowed)
			(vias allowed)
			(pads allowed)
			(copperpour not_allowed)
			(footprints allowed)
		)
		(placement
			(enabled no)
			(sheetname "")
		)
		(fill yes
			(thermal_gap 0.5)
			(thermal_bridge_width 0.5)
			(island_removal_mode 0)
		)
		(polygon
			(pts
				(arc
					(start 143.137128 -427.289976)
					(mid 142.362936 -427.289976)
					(end 143.137128 -427.289976)
				)
			)
		)
	)
	(zone
		(layers "B.Cu" "In11.Cu" "In13.Cu" "In15.Cu")
		(hatch none 0.5)
		(connect_pads
			(clearance 0)
		)
		(min_thickness 0.25)
		(keepout
			(tracks not_allowed)
			(vias allowed)
			(pads allowed)
			(copperpour not_allowed)
			(footprints allowed)
		)
		(placement
			(enabled no)
			(sheetname "")
		)
		(fill yes
			(thermal_gap 0.5)
			(thermal_bridge_width 0.5)
			(island_removal_mode 0)
		)
		(polygon
			(pts
				(arc
					(start 97.995994 -242.864386)
					(mid 97.366074 -242.864386)
					(end 97.995994 -242.864386)
				)
			)
		)
	)
	(zone
		(layers "B.Cu" "In11.Cu" "In13.Cu" "In15.Cu")
		(hatch none 0.5)
		(connect_pads
			(clearance 0)
		)
		(min_thickness 0.25)
		(keepout
			(tracks not_allowed)
			(vias allowed)
			(pads allowed)
			(copperpour not_allowed)
			(footprints allowed)
		)
		(placement
			(enabled no)
			(sheetname "")
		)
		(fill yes
			(thermal_gap 0.5)
			(thermal_bridge_width 0.5)
			(island_removal_mode 0)
		)
		(polygon
			(pts
				(arc
					(start 125.54966 -284.616398)
					(mid 124.91974 -284.616398)
					(end 125.54966 -284.616398)
				)
			)
		)
	)
	(zone
		(layers "B.Cu" "In11.Cu" "In13.Cu" "In15.Cu")
		(hatch none 0.5)
		(connect_pads
			(clearance 0)
		)
		(min_thickness 0.25)
		(keepout
			(tracks not_allowed)
			(vias allowed)
			(pads allowed)
			(copperpour not_allowed)
			(footprints allowed)
		)
		(placement
			(enabled no)
			(sheetname "")
		)
		(fill yes
			(thermal_gap 0.5)
			(thermal_bridge_width 0.5)
			(island_removal_mode 0)
		)
		(polygon
			(pts
				(arc
					(start 325.036688 -428.28972)
					(mid 324.262496 -428.28972)
					(end 325.036688 -428.28972)
				)
			)
		)
	)
	(zone
		(layers "B.Cu" "In11.Cu" "In13.Cu" "In15.Cu")
		(hatch none 0.5)
		(connect_pads
			(clearance 0)
		)
		(min_thickness 0.25)
		(keepout
			(tracks not_allowed)
			(vias allowed)
			(pads allowed)
			(copperpour not_allowed)
			(footprints allowed)
		)
		(placement
			(enabled no)
			(sheetname "")
		)
		(fill yes
			(thermal_gap 0.5)
			(thermal_bridge_width 0.5)
			(island_removal_mode 0)
		)
		(polygon
			(pts
				(arc
					(start 329.78598 -272.466054)
					(mid 329.15606 -272.466054)
					(end 329.78598 -272.466054)
				)
			)
		)
	)
	(zone
		(layers "B.Cu" "In11.Cu" "In13.Cu" "In15.Cu")
		(hatch none 0.5)
		(connect_pads
			(clearance 0)
		)
		(min_thickness 0.25)
		(keepout
			(tracks not_allowed)
			(vias allowed)
			(pads allowed)
			(copperpour not_allowed)
			(footprints allowed)
		)
		(placement
			(enabled no)
			(sheetname "")
		)
		(fill yes
			(thermal_gap 0.5)
			(thermal_bridge_width 0.5)
			(island_removal_mode 0)
		)
		(polygon
			(pts
				(arc
					(start 194.938142 -312.085228)
					(mid 194.270122 -312.085228)
					(end 194.938142 -312.085228)
				)
			)
		)
	)
	(zone
		(layers "B.Cu" "In11.Cu" "In13.Cu" "In15.Cu")
		(hatch none 0.5)
		(connect_pads
			(clearance 0)
		)
		(min_thickness 0.25)
		(keepout
			(tracks not_allowed)
			(vias allowed)
			(pads allowed)
			(copperpour not_allowed)
			(footprints allowed)
		)
		(placement
			(enabled no)
			(sheetname "")
		)
		(fill yes
			(thermal_gap 0.5)
			(thermal_bridge_width 0.5)
			(island_removal_mode 0)
		)
		(polygon
			(pts
				(arc
					(start 354.696014 -284.616144)
					(mid 354.066094 -284.616144)
					(end 354.696014 -284.616144)
				)
			)
		)
	)
	(zone
		(layers "B.Cu" "In11.Cu" "In13.Cu" "In15.Cu")
		(hatch none 0.5)
		(connect_pads
			(clearance 0)
		)
		(min_thickness 0.25)
		(keepout
			(tracks not_allowed)
			(vias allowed)
			(pads allowed)
			(copperpour not_allowed)
			(footprints allowed)
		)
		(placement
			(enabled no)
			(sheetname "")
		)
		(fill yes
			(thermal_gap 0.5)
			(thermal_bridge_width 0.5)
			(island_removal_mode 0)
		)
		(polygon
			(pts
				(arc
					(start 25.486106 -286.585406)
					(mid 24.818086 -286.585406)
					(end 25.486106 -286.585406)
				)
			)
		)
	)
	(zone
		(layers "B.Cu" "In11.Cu" "In13.Cu" "In15.Cu")
		(hatch none 0.5)
		(connect_pads
			(clearance 0)
		)
		(min_thickness 0.25)
		(keepout
			(tracks not_allowed)
			(vias allowed)
			(pads allowed)
			(copperpour not_allowed)
			(footprints allowed)
		)
		(placement
			(enabled no)
			(sheetname "")
		)
		(fill yes
			(thermal_gap 0.5)
			(thermal_bridge_width 0.5)
			(island_removal_mode 0)
		)
		(polygon
			(pts
				(arc
					(start 82.687414 -404.46452)
					(mid 82.019394 -404.46452)
					(end 82.687414 -404.46452)
				)
			)
		)
	)
	(zone
		(layers "B.Cu" "In11.Cu" "In13.Cu" "In15.Cu")
		(hatch none 0.5)
		(connect_pads
			(clearance 0)
		)
		(min_thickness 0.25)
		(keepout
			(tracks not_allowed)
			(vias allowed)
			(pads allowed)
			(copperpour not_allowed)
			(footprints allowed)
		)
		(placement
			(enabled no)
			(sheetname "")
		)
		(fill yes
			(thermal_gap 0.5)
			(thermal_bridge_width 0.5)
			(island_removal_mode 0)
		)
		(polygon
			(pts
				(arc
					(start 194.938142 -318.035432)
					(mid 194.270122 -318.035432)
					(end 194.938142 -318.035432)
				)
			)
		)
	)
	(zone
		(layers "B.Cu" "In11.Cu" "In13.Cu" "In15.Cu")
		(hatch none 0.5)
		(connect_pads
			(clearance 0)
		)
		(min_thickness 0.25)
		(keepout
			(tracks not_allowed)
			(vias allowed)
			(pads allowed)
			(copperpour not_allowed)
			(footprints allowed)
		)
		(placement
			(enabled no)
			(sheetname "")
		)
		(fill yes
			(thermal_gap 0.5)
			(thermal_bridge_width 0.5)
			(island_removal_mode 0)
		)
		(polygon
			(pts
				(arc
					(start 277.526242 -240.685066)
					(mid 276.858222 -240.685066)
					(end 277.526242 -240.685066)
				)
			)
		)
	)
	(zone
		(layers "B.Cu" "In11.Cu" "In13.Cu" "In15.Cu")
		(hatch none 0.5)
		(connect_pads
			(clearance 0)
		)
		(min_thickness 0.25)
		(keepout
			(tracks not_allowed)
			(vias allowed)
			(pads allowed)
			(copperpour not_allowed)
			(footprints allowed)
		)
		(placement
			(enabled no)
			(sheetname "")
		)
		(fill yes
			(thermal_gap 0.5)
			(thermal_bridge_width 0.5)
			(island_removal_mode 0)
		)
		(polygon
			(pts
				(arc
					(start 442.87821 -205.834996)
					(mid 442.21019 -205.834996)
					(end 442.87821 -205.834996)
				)
			)
		)
	)
	(zone
		(layers "B.Cu" "In11.Cu" "In13.Cu" "In15.Cu")
		(hatch none 0.5)
		(connect_pads
			(clearance 0)
		)
		(min_thickness 0.25)
		(keepout
			(tracks not_allowed)
			(vias allowed)
			(pads allowed)
			(copperpour not_allowed)
			(footprints allowed)
		)
		(placement
			(enabled no)
			(sheetname "")
		)
		(fill yes
			(thermal_gap 0.5)
			(thermal_bridge_width 0.5)
			(island_removal_mode 0)
		)
		(polygon
			(pts
				(arc
					(start 58.10631 -389.467344)
					(mid 57.47639 -389.467344)
					(end 58.10631 -389.467344)
				)
			)
		)
	)
	(zone
		(layers "B.Cu" "In11.Cu" "In13.Cu" "In15.Cu")
		(hatch none 0.5)
		(connect_pads
			(clearance 0)
		)
		(min_thickness 0.25)
		(keepout
			(tracks not_allowed)
			(vias allowed)
			(pads allowed)
			(copperpour not_allowed)
			(footprints allowed)
		)
		(placement
			(enabled no)
			(sheetname "")
		)
		(fill yes
			(thermal_gap 0.5)
			(thermal_bridge_width 0.5)
			(island_removal_mode 0)
		)
		(polygon
			(pts
				(arc
					(start 25.486106 -243.235226)
					(mid 24.818086 -243.235226)
					(end 25.486106 -243.235226)
				)
			)
		)
	)
	(zone
		(layers "B.Cu" "In11.Cu" "In13.Cu" "In15.Cu")
		(hatch none 0.5)
		(connect_pads
			(clearance 0)
		)
		(min_thickness 0.25)
		(keepout
			(tracks not_allowed)
			(vias allowed)
			(pads allowed)
			(copperpour not_allowed)
			(footprints allowed)
		)
		(placement
			(enabled no)
			(sheetname "")
		)
		(fill yes
			(thermal_gap 0.5)
			(thermal_bridge_width 0.5)
			(island_removal_mode 0)
		)
		(polygon
			(pts
				(arc
					(start 29.586174 -212.635338)
					(mid 28.918154 -212.635338)
					(end 29.586174 -212.635338)
				)
			)
		)
	)
	(zone
		(layers "B.Cu" "In11.Cu" "In13.Cu" "In15.Cu")
		(hatch none 0.5)
		(connect_pads
			(clearance 0)
		)
		(min_thickness 0.25)
		(keepout
			(tracks not_allowed)
			(vias allowed)
			(pads allowed)
			(copperpour not_allowed)
			(footprints allowed)
		)
		(placement
			(enabled no)
			(sheetname "")
		)
		(fill yes
			(thermal_gap 0.5)
			(thermal_bridge_width 0.5)
			(island_removal_mode 0)
		)
		(polygon
			(pts
				(arc
					(start 389.63981 -227.474272)
					(mid 389.00989 -227.474272)
					(end 389.63981 -227.474272)
				)
			)
		)
	)
	(zone
		(layers "B.Cu" "In11.Cu" "In13.Cu" "In15.Cu")
		(hatch none 0.5)
		(connect_pads
			(clearance 0)
		)
		(min_thickness 0.25)
		(keepout
			(tracks not_allowed)
			(vias allowed)
			(pads allowed)
			(copperpour not_allowed)
			(footprints allowed)
		)
		(placement
			(enabled no)
			(sheetname "")
		)
		(fill yes
			(thermal_gap 0.5)
			(thermal_bridge_width 0.5)
			(island_removal_mode 0)
		)
		(polygon
			(pts
				(arc
					(start 414.933892 -394.385292)
					(mid 414.303972 -394.385292)
					(end 414.933892 -394.385292)
				)
			)
		)
	)
	(zone
		(layers "B.Cu" "In11.Cu" "In13.Cu" "In15.Cu")
		(hatch none 0.5)
		(connect_pads
			(clearance 0)
		)
		(min_thickness 0.25)
		(keepout
			(tracks not_allowed)
			(vias allowed)
			(pads allowed)
			(copperpour not_allowed)
			(footprints allowed)
		)
		(placement
			(enabled no)
			(sheetname "")
		)
		(fill yes
			(thermal_gap 0.5)
			(thermal_bridge_width 0.5)
			(island_removal_mode 0)
		)
		(polygon
			(pts
				(arc
					(start 442.87821 -244.934994)
					(mid 442.21019 -244.934994)
					(end 442.87821 -244.934994)
				)
			)
		)
	)
	(zone
		(layers "B.Cu" "In11.Cu" "In13.Cu" "In15.Cu")
		(hatch none 0.5)
		(connect_pads
			(clearance 0)
		)
		(min_thickness 0.25)
		(keepout
			(tracks not_allowed)
			(vias allowed)
			(pads allowed)
			(copperpour not_allowed)
			(footprints allowed)
		)
		(placement
			(enabled no)
			(sheetname "")
		)
		(fill yes
			(thermal_gap 0.5)
			(thermal_bridge_width 0.5)
			(island_removal_mode 0)
		)
		(polygon
			(pts
				(arc
					(start 277.526242 -242.385088)
					(mid 276.858222 -242.385088)
					(end 277.526242 -242.385088)
				)
			)
		)
	)
	(zone
		(layers "B.Cu" "In11.Cu" "In13.Cu" "In15.Cu")
		(hatch none 0.5)
		(connect_pads
			(clearance 0)
		)
		(min_thickness 0.25)
		(keepout
			(tracks not_allowed)
			(vias allowed)
			(pads allowed)
			(copperpour not_allowed)
			(footprints allowed)
		)
		(placement
			(enabled no)
			(sheetname "")
		)
		(fill yes
			(thermal_gap 0.5)
			(thermal_bridge_width 0.5)
			(island_removal_mode 0)
		)
		(polygon
			(pts
				(arc
					(start 407.734008 -394.385292)
					(mid 407.104088 -394.385292)
					(end 407.734008 -394.385292)
				)
			)
		)
	)
	(zone
		(layers "B.Cu" "In11.Cu" "In13.Cu" "In15.Cu")
		(hatch none 0.5)
		(connect_pads
			(clearance 0)
		)
		(min_thickness 0.25)
		(keepout
			(tracks not_allowed)
			(vias allowed)
			(pads allowed)
			(copperpour not_allowed)
			(footprints allowed)
		)
		(placement
			(enabled no)
			(sheetname "")
		)
		(fill yes
			(thermal_gap 0.5)
			(thermal_bridge_width 0.5)
			(island_removal_mode 0)
		)
		(polygon
			(pts
				(arc
					(start 391.049764 -238.004096)
					(mid 390.419844 -238.004096)
					(end 391.049764 -238.004096)
				)
			)
		)
	)
	(zone
		(layers "B.Cu" "In11.Cu" "In13.Cu" "In15.Cu")
		(hatch none 0.5)
		(connect_pads
			(clearance 0)
		)
		(min_thickness 0.25)
		(keepout
			(tracks not_allowed)
			(vias allowed)
			(pads allowed)
			(copperpour not_allowed)
			(footprints allowed)
		)
		(placement
			(enabled no)
			(sheetname "")
		)
		(fill yes
			(thermal_gap 0.5)
			(thermal_bridge_width 0.5)
			(island_removal_mode 0)
		)
		(polygon
			(pts
				(arc
					(start 134.136892 -426.089826)
					(mid 133.3627 -426.089826)
					(end 134.136892 -426.089826)
				)
			)
		)
	)
	(zone
		(layers "B.Cu" "In11.Cu" "In13.Cu" "In15.Cu")
		(hatch none 0.5)
		(connect_pads
			(clearance 0)
		)
		(min_thickness 0.25)
		(keepout
			(tracks not_allowed)
			(vias allowed)
			(pads allowed)
			(copperpour not_allowed)
			(footprints allowed)
		)
		(placement
			(enabled no)
			(sheetname "")
		)
		(fill yes
			(thermal_gap 0.5)
			(thermal_bridge_width 0.5)
			(island_removal_mode 0)
		)
		(polygon
			(pts
				(arc
					(start 329.486006 -230.714296)
					(mid 328.856086 -230.714296)
					(end 329.486006 -230.714296)
				)
			)
		)
	)
	(zone
		(layers "B.Cu" "In11.Cu" "In13.Cu" "In15.Cu")
		(hatch none 0.5)
		(connect_pads
			(clearance 0)
		)
		(min_thickness 0.25)
		(keepout
			(tracks not_allowed)
			(vias allowed)
			(pads allowed)
			(copperpour not_allowed)
			(footprints allowed)
		)
		(placement
			(enabled no)
			(sheetname "")
		)
		(fill yes
			(thermal_gap 0.5)
			(thermal_bridge_width 0.5)
			(island_removal_mode 0)
		)
		(polygon
			(pts
				(arc
					(start 446.978278 -273.835114)
					(mid 446.310258 -273.835114)
					(end 446.978278 -273.835114)
				)
			)
		)
	)
	(zone
		(layers "B.Cu" "In11.Cu" "In13.Cu" "In15.Cu")
		(hatch none 0.5)
		(connect_pads
			(clearance 0)
		)
		(min_thickness 0.25)
		(keepout
			(tracks not_allowed)
			(vias allowed)
			(pads allowed)
			(copperpour not_allowed)
			(footprints allowed)
		)
		(placement
			(enabled no)
			(sheetname "")
		)
		(fill yes
			(thermal_gap 0.5)
			(thermal_bridge_width 0.5)
			(island_removal_mode 0)
		)
		(polygon
			(pts
				(arc
					(start 82.785966 -274.08632)
					(mid 82.156046 -274.08632)
					(end 82.785966 -274.08632)
				)
			)
		)
	)
	(zone
		(layers "B.Cu" "In11.Cu" "In13.Cu" "In15.Cu")
		(hatch none 0.5)
		(connect_pads
			(clearance 0)
		)
		(min_thickness 0.25)
		(keepout
			(tracks not_allowed)
			(vias allowed)
			(pads allowed)
			(copperpour not_allowed)
			(footprints allowed)
		)
		(placement
			(enabled no)
			(sheetname "")
		)
		(fill yes
			(thermal_gap 0.5)
			(thermal_bridge_width 0.5)
			(island_removal_mode 0)
		)
		(polygon
			(pts
				(arc
					(start 389.469884 -261.935976)
					(mid 388.839964 -261.935976)
					(end 389.469884 -261.935976)
				)
			)
		)
	)
	(zone
		(layers "B.Cu" "In11.Cu" "In13.Cu" "In15.Cu")
		(hatch none 0.5)
		(connect_pads
			(clearance 0)
		)
		(min_thickness 0.25)
		(keepout
			(tracks not_allowed)
			(vias allowed)
			(pads allowed)
			(copperpour not_allowed)
			(footprints allowed)
		)
		(placement
			(enabled no)
			(sheetname "")
		)
		(fill yes
			(thermal_gap 0.5)
			(thermal_bridge_width 0.5)
			(island_removal_mode 0)
		)
		(polygon
			(pts
				(arc
					(start 25.486106 -246.63527)
					(mid 24.818086 -246.63527)
					(end 25.486106 -246.63527)
				)
			)
		)
	)
	(zone
		(layers "B.Cu" "In11.Cu" "In13.Cu" "In15.Cu")
		(hatch none 0.5)
		(connect_pads
			(clearance 0)
		)
		(min_thickness 0.25)
		(keepout
			(tracks not_allowed)
			(vias allowed)
			(pads allowed)
			(copperpour not_allowed)
			(footprints allowed)
		)
		(placement
			(enabled no)
			(sheetname "")
		)
		(fill yes
			(thermal_gap 0.5)
			(thermal_bridge_width 0.5)
			(island_removal_mode 0)
		)
		(polygon
			(pts
				(arc
					(start 115.606322 -389.467344)
					(mid 114.976402 -389.467344)
					(end 115.606322 -389.467344)
				)
			)
		)
	)
	(zone
		(layers "B.Cu" "In11.Cu" "In13.Cu" "In15.Cu")
		(hatch none 0.5)
		(connect_pads
			(clearance 0)
		)
		(min_thickness 0.25)
		(keepout
			(tracks not_allowed)
			(vias allowed)
			(pads allowed)
			(copperpour not_allowed)
			(footprints allowed)
		)
		(placement
			(enabled no)
			(sheetname "")
		)
		(fill yes
			(thermal_gap 0.5)
			(thermal_bridge_width 0.5)
			(island_removal_mode 0)
		)
		(polygon
			(pts
				(arc
					(start 142.639796 -243.674392)
					(mid 142.009876 -243.674392)
					(end 142.639796 -243.674392)
				)
			)
		)
	)
	(zone
		(layers "B.Cu" "In11.Cu" "In13.Cu" "In15.Cu")
		(hatch none 0.5)
		(connect_pads
			(clearance 0)
		)
		(min_thickness 0.25)
		(keepout
			(tracks not_allowed)
			(vias allowed)
			(pads allowed)
			(copperpour not_allowed)
			(footprints allowed)
		)
		(placement
			(enabled no)
			(sheetname "")
		)
		(fill yes
			(thermal_gap 0.5)
			(thermal_bridge_width 0.5)
			(island_removal_mode 0)
		)
		(polygon
			(pts
				(arc
					(start 90.037158 -428.28972)
					(mid 89.262966 -428.28972)
					(end 90.037158 -428.28972)
				)
			)
		)
	)
	(zone
		(layers "B.Cu" "In11.Cu" "In13.Cu" "In15.Cu")
		(hatch none 0.5)
		(connect_pads
			(clearance 0)
		)
		(min_thickness 0.25)
		(keepout
			(tracks not_allowed)
			(vias allowed)
			(pads allowed)
			(copperpour not_allowed)
			(footprints allowed)
		)
		(placement
			(enabled no)
			(sheetname "")
		)
		(fill yes
			(thermal_gap 0.5)
			(thermal_bridge_width 0.5)
			(island_removal_mode 0)
		)
		(polygon
			(pts
				(arc
					(start 389.469884 -282.996132)
					(mid 388.839964 -282.996132)
					(end 389.469884 -282.996132)
				)
			)
		)
	)
	(zone
		(layers "B.Cu" "In11.Cu" "In13.Cu" "In15.Cu")
		(hatch none 0.5)
		(connect_pads
			(clearance 0)
		)
		(min_thickness 0.25)
		(keepout
			(tracks not_allowed)
			(vias allowed)
			(pads allowed)
			(copperpour not_allowed)
			(footprints allowed)
		)
		(placement
			(enabled no)
			(sheetname "")
		)
		(fill yes
			(thermal_gap 0.5)
			(thermal_bridge_width 0.5)
			(island_removal_mode 0)
		)
		(polygon
			(pts
				(arc
					(start 364.729776 -239.624108)
					(mid 364.099856 -239.624108)
					(end 364.729776 -239.624108)
				)
			)
		)
	)
	(zone
		(layers "B.Cu" "In11.Cu" "In13.Cu" "In15.Cu")
		(hatch none 0.5)
		(connect_pads
			(clearance 0)
		)
		(min_thickness 0.25)
		(keepout
			(tracks not_allowed)
			(vias allowed)
			(pads allowed)
			(copperpour not_allowed)
			(footprints allowed)
		)
		(placement
			(enabled no)
			(sheetname "")
		)
		(fill yes
			(thermal_gap 0.5)
			(thermal_bridge_width 0.5)
			(island_removal_mode 0)
		)
		(polygon
			(pts
				(arc
					(start 81.076038 -246.10441)
					(mid 80.446118 -246.10441)
					(end 81.076038 -246.10441)
				)
			)
		)
	)
	(zone
		(layers "B.Cu" "In11.Cu" "In13.Cu" "In15.Cu")
		(hatch none 0.5)
		(connect_pads
			(clearance 0)
		)
		(min_thickness 0.25)
		(keepout
			(tracks not_allowed)
			(vias allowed)
			(pads allowed)
			(copperpour not_allowed)
			(footprints allowed)
		)
		(placement
			(enabled no)
			(sheetname "")
		)
		(fill yes
			(thermal_gap 0.5)
			(thermal_bridge_width 0.5)
			(island_removal_mode 0)
		)
		(polygon
			(pts
				(arc
					(start 143.109696 -255.824482)
					(mid 142.479776 -255.824482)
					(end 143.109696 -255.824482)
				)
			)
		)
	)
	(zone
		(layers "B.Cu" "In11.Cu" "In13.Cu" "In15.Cu")
		(hatch none 0.5)
		(connect_pads
			(clearance 0)
		)
		(min_thickness 0.25)
		(keepout
			(tracks not_allowed)
			(vias allowed)
			(pads allowed)
			(copperpour not_allowed)
			(footprints allowed)
		)
		(placement
			(enabled no)
			(sheetname "")
		)
		(fill yes
			(thermal_gap 0.5)
			(thermal_bridge_width 0.5)
			(island_removal_mode 0)
		)
		(polygon
			(pts
				(arc
					(start 142.93977 -285.426404)
					(mid 142.30985 -285.426404)
					(end 142.93977 -285.426404)
				)
			)
		)
	)
	(zone
		(layers "B.Cu" "In11.Cu" "In13.Cu" "In15.Cu")
		(hatch none 0.5)
		(connect_pads
			(clearance 0)
		)
		(min_thickness 0.25)
		(keepout
			(tracks not_allowed)
			(vias allowed)
			(pads allowed)
			(copperpour not_allowed)
			(footprints allowed)
		)
		(placement
			(enabled no)
			(sheetname "")
		)
		(fill yes
			(thermal_gap 0.5)
			(thermal_bridge_width 0.5)
			(island_removal_mode 0)
		)
		(polygon
			(pts
				(arc
					(start 141.699742 -248.534428)
					(mid 141.069822 -248.534428)
					(end 141.699742 -248.534428)
				)
			)
		)
	)
	(zone
		(layers "B.Cu" "In11.Cu" "In13.Cu" "In15.Cu")
		(hatch none 0.5)
		(connect_pads
			(clearance 0)
		)
		(min_thickness 0.25)
		(keepout
			(tracks not_allowed)
			(vias allowed)
			(pads allowed)
			(copperpour not_allowed)
			(footprints allowed)
		)
		(placement
			(enabled no)
			(sheetname "")
		)
		(fill yes
			(thermal_gap 0.5)
			(thermal_bridge_width 0.5)
			(island_removal_mode 0)
		)
		(polygon
			(pts
				(arc
					(start 277.526242 -284.88513)
					(mid 276.858222 -284.88513)
					(end 277.526242 -284.88513)
				)
			)
		)
	)
	(zone
		(layers "B.Cu" "In11.Cu" "In13.Cu" "In15.Cu")
		(hatch none 0.5)
		(connect_pads
			(clearance 0)
		)
		(min_thickness 0.25)
		(keepout
			(tracks not_allowed)
			(vias allowed)
			(pads allowed)
			(copperpour not_allowed)
			(footprints allowed)
		)
		(placement
			(enabled no)
			(sheetname "")
		)
		(fill yes
			(thermal_gap 0.5)
			(thermal_bridge_width 0.5)
			(island_removal_mode 0)
		)
		(polygon
			(pts
				(arc
					(start 25.486106 -254.285242)
					(mid 24.818086 -254.285242)
					(end 25.486106 -254.285242)
				)
			)
		)
	)
	(zone
		(layers "B.Cu" "In11.Cu" "In13.Cu" "In15.Cu")
		(hatch none 0.5)
		(connect_pads
			(clearance 0)
		)
		(min_thickness 0.25)
		(keepout
			(tracks not_allowed)
			(vias allowed)
			(pads allowed)
			(copperpour not_allowed)
			(footprints allowed)
		)
		(placement
			(enabled no)
			(sheetname "")
		)
		(fill yes
			(thermal_gap 0.5)
			(thermal_bridge_width 0.5)
			(island_removal_mode 0)
		)
		(polygon
			(pts
				(arc
					(start 273.426174 -263.634982)
					(mid 272.758154 -263.634982)
					(end 273.426174 -263.634982)
				)
			)
		)
	)
	(zone
		(layers "B.Cu" "In11.Cu" "In13.Cu" "In15.Cu")
		(hatch none 0.5)
		(connect_pads
			(clearance 0)
		)
		(min_thickness 0.25)
		(keepout
			(tracks not_allowed)
			(vias allowed)
			(pads allowed)
			(copperpour not_allowed)
			(footprints allowed)
		)
		(placement
			(enabled no)
			(sheetname "")
		)
		(fill yes
			(thermal_gap 0.5)
			(thermal_bridge_width 0.5)
			(island_removal_mode 0)
		)
		(polygon
			(pts
				(arc
					(start 76.037186 -426.089826)
					(mid 75.262994 -426.089826)
					(end 76.037186 -426.089826)
				)
			)
		)
	)
	(zone
		(layers "B.Cu" "In11.Cu" "In13.Cu" "In15.Cu")
		(hatch none 0.5)
		(connect_pads
			(clearance 0)
		)
		(min_thickness 0.25)
		(keepout
			(tracks not_allowed)
			(vias allowed)
			(pads allowed)
			(copperpour not_allowed)
			(footprints allowed)
		)
		(placement
			(enabled no)
			(sheetname "")
		)
		(fill yes
			(thermal_gap 0.5)
			(thermal_bridge_width 0.5)
			(island_removal_mode 0)
		)
		(polygon
			(pts
				(arc
					(start 81.823814 -404.46452)
					(mid 81.155794 -404.46452)
					(end 81.823814 -404.46452)
				)
			)
		)
	)
	(zone
		(layers "B.Cu" "In11.Cu" "In13.Cu" "In15.Cu")
		(hatch none 0.5)
		(connect_pads
			(clearance 0)
		)
		(min_thickness 0.25)
		(keepout
			(tracks not_allowed)
			(vias allowed)
			(pads allowed)
			(copperpour not_allowed)
			(footprints allowed)
		)
		(placement
			(enabled no)
			(sheetname "")
		)
		(fill yes
			(thermal_gap 0.5)
			(thermal_bridge_width 0.5)
			(island_removal_mode 0)
		)
		(polygon
			(pts
				(arc
					(start 214.28329 4.650994)
					(mid 213.61527 4.650994)
					(end 214.28329 4.650994)
				)
			)
		)
	)
	(zone
		(layers "B.Cu" "In11.Cu" "In13.Cu" "In15.Cu")
		(hatch none 0.5)
		(connect_pads
			(clearance 0)
		)
		(min_thickness 0.25)
		(keepout
			(tracks not_allowed)
			(vias allowed)
			(pads allowed)
			(copperpour not_allowed)
			(footprints allowed)
		)
		(placement
			(enabled no)
			(sheetname "")
		)
		(fill yes
			(thermal_gap 0.5)
			(thermal_bridge_width 0.5)
			(island_removal_mode 0)
		)
		(polygon
			(pts
				(arc
					(start 106.755946 -284.616398)
					(mid 106.126026 -284.616398)
					(end 106.755946 -284.616398)
				)
			)
		)
	)
	(zone
		(layers "B.Cu" "In11.Cu" "In13.Cu" "In15.Cu")
		(hatch none 0.5)
		(connect_pads
			(clearance 0)
		)
		(min_thickness 0.25)
		(keepout
			(tracks not_allowed)
			(vias allowed)
			(pads allowed)
			(copperpour not_allowed)
			(footprints allowed)
		)
		(placement
			(enabled no)
			(sheetname "")
		)
		(fill yes
			(thermal_gap 0.5)
			(thermal_bridge_width 0.5)
			(island_removal_mode 0)
		)
		(polygon
			(pts
				(arc
					(start 61.036962 -427.089824)
					(mid 60.26277 -427.089824)
					(end 61.036962 -427.089824)
				)
			)
		)
	)
	(zone
		(layers "B.Cu" "In11.Cu" "In13.Cu" "In15.Cu")
		(hatch none 0.5)
		(connect_pads
			(clearance 0)
		)
		(min_thickness 0.25)
		(keepout
			(tracks not_allowed)
			(vias allowed)
			(pads allowed)
			(copperpour not_allowed)
			(footprints allowed)
		)
		(placement
			(enabled no)
			(sheetname "")
		)
		(fill yes
			(thermal_gap 0.5)
			(thermal_bridge_width 0.5)
			(island_removal_mode 0)
		)
		(polygon
			(pts
				(arc
					(start 29.586174 -250.885198)
					(mid 28.918154 -250.885198)
					(end 29.586174 -250.885198)
				)
			)
		)
	)
	(zone
		(layers "B.Cu" "In11.Cu" "In13.Cu" "In15.Cu")
		(hatch none 0.5)
		(connect_pads
			(clearance 0)
		)
		(min_thickness 0.25)
		(keepout
			(tracks not_allowed)
			(vias allowed)
			(pads allowed)
			(copperpour not_allowed)
			(footprints allowed)
		)
		(placement
			(enabled no)
			(sheetname "")
		)
		(fill yes
			(thermal_gap 0.5)
			(thermal_bridge_width 0.5)
			(island_removal_mode 0)
		)
		(polygon
			(pts
				(arc
					(start 142.93977 -272.466308)
					(mid 142.30985 -272.466308)
					(end 142.93977 -272.466308)
				)
			)
		)
	)
	(zone
		(layers "B.Cu" "In11.Cu" "In13.Cu" "In15.Cu")
		(hatch none 0.5)
		(connect_pads
			(clearance 0)
		)
		(min_thickness 0.25)
		(keepout
			(tracks not_allowed)
			(vias allowed)
			(pads allowed)
			(copperpour not_allowed)
			(footprints allowed)
		)
		(placement
			(enabled no)
			(sheetname "")
		)
		(fill yes
			(thermal_gap 0.5)
			(thermal_bridge_width 0.5)
			(island_removal_mode 0)
		)
		(polygon
			(pts
				(arc
					(start 446.978278 -204.985112)
					(mid 446.310258 -204.985112)
					(end 446.978278 -204.985112)
				)
			)
		)
	)
	(zone
		(layers "B.Cu" "In11.Cu" "In13.Cu" "In15.Cu")
		(hatch none 0.5)
		(connect_pads
			(clearance 0)
		)
		(min_thickness 0.25)
		(keepout
			(tracks not_allowed)
			(vias allowed)
			(pads allowed)
			(copperpour not_allowed)
			(footprints allowed)
		)
		(placement
			(enabled no)
			(sheetname "")
		)
		(fill yes
			(thermal_gap 0.5)
			(thermal_bridge_width 0.5)
			(island_removal_mode 0)
		)
		(polygon
			(pts
				(arc
					(start 81.845912 -270.846296)
					(mid 81.215992 -270.846296)
					(end 81.845912 -270.846296)
				)
			)
		)
	)
	(zone
		(layers "B.Cu" "In11.Cu" "In13.Cu" "In15.Cu")
		(hatch none 0.5)
		(connect_pads
			(clearance 0)
		)
		(min_thickness 0.25)
		(keepout
			(tracks not_allowed)
			(vias allowed)
			(pads allowed)
			(copperpour not_allowed)
			(footprints allowed)
		)
		(placement
			(enabled no)
			(sheetname "")
		)
		(fill yes
			(thermal_gap 0.5)
			(thermal_bridge_width 0.5)
			(island_removal_mode 0)
		)
		(polygon
			(pts
				(arc
					(start 329.486006 -242.054126)
					(mid 328.856086 -242.054126)
					(end 329.486006 -242.054126)
				)
			)
		)
	)
	(zone
		(layers "B.Cu" "In11.Cu" "In13.Cu" "In15.Cu")
		(hatch none 0.5)
		(connect_pads
			(clearance 0)
		)
		(min_thickness 0.25)
		(keepout
			(tracks not_allowed)
			(vias allowed)
			(pads allowed)
			(copperpour not_allowed)
			(footprints allowed)
		)
		(placement
			(enabled no)
			(sheetname "")
		)
		(fill yes
			(thermal_gap 0.5)
			(thermal_bridge_width 0.5)
			(island_removal_mode 0)
		)
		(polygon
			(pts
				(arc
					(start 446.978278 -269.585186)
					(mid 446.310258 -269.585186)
					(end 446.978278 -269.585186)
				)
			)
		)
	)
	(zone
		(layers "B.Cu" "In11.Cu" "In13.Cu" "In15.Cu")
		(hatch none 0.5)
		(connect_pads
			(clearance 0)
		)
		(min_thickness 0.25)
		(keepout
			(tracks not_allowed)
			(vias allowed)
			(pads allowed)
			(copperpour not_allowed)
			(footprints allowed)
		)
		(placement
			(enabled no)
			(sheetname "")
		)
		(fill yes
			(thermal_gap 0.5)
			(thermal_bridge_width 0.5)
			(island_removal_mode 0)
		)
		(polygon
			(pts
				(arc
					(start 442.87821 -241.53495)
					(mid 442.21019 -241.53495)
					(end 442.87821 -241.53495)
				)
			)
		)
	)
	(zone
		(layers "B.Cu" "In11.Cu" "In13.Cu" "In15.Cu")
		(hatch none 0.5)
		(connect_pads
			(clearance 0)
		)
		(min_thickness 0.25)
		(keepout
			(tracks not_allowed)
			(vias allowed)
			(pads allowed)
			(copperpour not_allowed)
			(footprints allowed)
		)
		(placement
			(enabled no)
			(sheetname "")
		)
		(fill yes
			(thermal_gap 0.5)
			(thermal_bridge_width 0.5)
			(island_removal_mode 0)
		)
		(polygon
			(pts
				(arc
					(start 412.533846 -394.385292)
					(mid 411.903926 -394.385292)
					(end 412.533846 -394.385292)
				)
			)
		)
	)
	(zone
		(layers "B.Cu" "In11.Cu" "In13.Cu" "In15.Cu")
		(hatch none 0.5)
		(connect_pads
			(clearance 0)
		)
		(min_thickness 0.25)
		(keepout
			(tracks not_allowed)
			(vias allowed)
			(pads allowed)
			(copperpour not_allowed)
			(footprints allowed)
		)
		(placement
			(enabled no)
			(sheetname "")
		)
		(fill yes
			(thermal_gap 0.5)
			(thermal_bridge_width 0.5)
			(island_removal_mode 0)
		)
		(polygon
			(pts
				(arc
					(start 194.938142 -276.385274)
					(mid 194.270122 -276.385274)
					(end 194.938142 -276.385274)
				)
			)
		)
	)
	(zone
		(layers "B.Cu" "In11.Cu" "In13.Cu" "In15.Cu")
		(hatch none 0.5)
		(connect_pads
			(clearance 0)
		)
		(min_thickness 0.25)
		(keepout
			(tracks not_allowed)
			(vias allowed)
			(pads allowed)
			(copperpour not_allowed)
			(footprints allowed)
		)
		(placement
			(enabled no)
			(sheetname "")
		)
		(fill yes
			(thermal_gap 0.5)
			(thermal_bridge_width 0.5)
			(island_removal_mode 0)
		)
		(polygon
			(pts
				(arc
					(start 277.526242 -210.935062)
					(mid 276.858222 -210.935062)
					(end 277.526242 -210.935062)
				)
			)
		)
	)
	(zone
		(layers "B.Cu" "In11.Cu" "In13.Cu" "In15.Cu")
		(hatch none 0.5)
		(connect_pads
			(clearance 0)
		)
		(min_thickness 0.25)
		(keepout
			(tracks not_allowed)
			(vias allowed)
			(pads allowed)
			(copperpour not_allowed)
			(footprints allowed)
		)
		(placement
			(enabled no)
			(sheetname "")
		)
		(fill yes
			(thermal_gap 0.5)
			(thermal_bridge_width 0.5)
			(island_removal_mode 0)
		)
		(polygon
			(pts
				(arc
					(start 442.87821 -207.535018)
					(mid 442.21019 -207.535018)
					(end 442.87821 -207.535018)
				)
			)
		)
	)
	(zone
		(layers "B.Cu" "In11.Cu" "In13.Cu" "In15.Cu")
		(hatch none 0.5)
		(connect_pads
			(clearance 0)
		)
		(min_thickness 0.25)
		(keepout
			(tracks not_allowed)
			(vias allowed)
			(pads allowed)
			(copperpour not_allowed)
			(footprints allowed)
		)
		(placement
			(enabled no)
			(sheetname "")
		)
		(fill yes
			(thermal_gap 0.5)
			(thermal_bridge_width 0.5)
			(island_removal_mode 0)
		)
		(polygon
			(pts
				(arc
					(start 277.526242 -204.985112)
					(mid 276.858222 -204.985112)
					(end 277.526242 -204.985112)
				)
			)
		)
	)
	(zone
		(layers "B.Cu" "In11.Cu" "In13.Cu" "In15.Cu")
		(hatch none 0.5)
		(connect_pads
			(clearance 0)
		)
		(min_thickness 0.25)
		(keepout
			(tracks not_allowed)
			(vias allowed)
			(pads allowed)
			(copperpour not_allowed)
			(footprints allowed)
		)
		(placement
			(enabled no)
			(sheetname "")
		)
		(fill yes
			(thermal_gap 0.5)
			(thermal_bridge_width 0.5)
			(island_removal_mode 0)
		)
		(polygon
			(pts
				(arc
					(start 277.526242 -254.284988)
					(mid 276.858222 -254.284988)
					(end 277.526242 -254.284988)
				)
			)
		)
	)
	(zone
		(layers "B.Cu" "In11.Cu" "In13.Cu" "In15.Cu")
		(hatch none 0.5)
		(connect_pads
			(clearance 0)
		)
		(min_thickness 0.25)
		(keepout
			(tracks not_allowed)
			(vias allowed)
			(pads allowed)
			(copperpour not_allowed)
			(footprints allowed)
		)
		(placement
			(enabled no)
			(sheetname "")
		)
		(fill yes
			(thermal_gap 0.5)
			(thermal_bridge_width 0.5)
			(island_removal_mode 0)
		)
		(polygon
			(pts
				(arc
					(start 331.195934 -281.37612)
					(mid 330.566014 -281.37612)
					(end 331.195934 -281.37612)
				)
			)
		)
	)
	(zone
		(layers "B.Cu" "In11.Cu" "In13.Cu" "In15.Cu")
		(hatch none 0.5)
		(connect_pads
			(clearance 0)
		)
		(min_thickness 0.25)
		(keepout
			(tracks not_allowed)
			(vias allowed)
			(pads allowed)
			(copperpour not_allowed)
			(footprints allowed)
		)
		(placement
			(enabled no)
			(sheetname "")
		)
		(fill yes
			(thermal_gap 0.5)
			(thermal_bridge_width 0.5)
			(island_removal_mode 0)
		)
		(polygon
			(pts
				(arc
					(start 141.229842 -241.244374)
					(mid 140.599922 -241.244374)
					(end 141.229842 -241.244374)
				)
			)
		)
	)
	(zone
		(layers "B.Cu" "In11.Cu" "In13.Cu" "In15.Cu")
		(hatch none 0.5)
		(connect_pads
			(clearance 0)
		)
		(min_thickness 0.25)
		(keepout
			(tracks not_allowed)
			(vias allowed)
			(pads allowed)
			(copperpour not_allowed)
			(footprints allowed)
		)
		(placement
			(enabled no)
			(sheetname "")
		)
		(fill yes
			(thermal_gap 0.5)
			(thermal_bridge_width 0.5)
			(island_removal_mode 0)
		)
		(polygon
			(pts
				(arc
					(start 141.529816 -286.23641)
					(mid 140.899896 -286.23641)
					(end 141.529816 -286.23641)
				)
			)
		)
	)
	(zone
		(layers "B.Cu" "In11.Cu" "In13.Cu" "In15.Cu")
		(hatch none 0.5)
		(connect_pads
			(clearance 0)
		)
		(min_thickness 0.25)
		(keepout
			(tracks not_allowed)
			(vias allowed)
			(pads allowed)
			(copperpour not_allowed)
			(footprints allowed)
		)
		(placement
			(enabled no)
			(sheetname "")
		)
		(fill yes
			(thermal_gap 0.5)
			(thermal_bridge_width 0.5)
			(island_removal_mode 0)
		)
		(polygon
			(pts
				(arc
					(start 374.129808 -241.24412)
					(mid 373.499888 -241.24412)
					(end 374.129808 -241.24412)
				)
			)
		)
	)
	(zone
		(layers "B.Cu" "In11.Cu" "In13.Cu" "In15.Cu")
		(hatch none 0.5)
		(connect_pads
			(clearance 0)
		)
		(min_thickness 0.25)
		(keepout
			(tracks not_allowed)
			(vias allowed)
			(pads allowed)
			(copperpour not_allowed)
			(footprints allowed)
		)
		(placement
			(enabled no)
			(sheetname "")
		)
		(fill yes
			(thermal_gap 0.5)
			(thermal_bridge_width 0.5)
			(island_removal_mode 0)
		)
		(polygon
			(pts
				(arc
					(start 349.995998 -281.37612)
					(mid 349.366078 -281.37612)
					(end 349.995998 -281.37612)
				)
			)
		)
	)
	(zone
		(layers "B.Cu" "In11.Cu" "In13.Cu" "In15.Cu")
		(hatch none 0.5)
		(connect_pads
			(clearance 0)
		)
		(min_thickness 0.25)
		(keepout
			(tracks not_allowed)
			(vias allowed)
			(pads allowed)
			(copperpour not_allowed)
			(footprints allowed)
		)
		(placement
			(enabled no)
			(sheetname "")
		)
		(fill yes
			(thermal_gap 0.5)
			(thermal_bridge_width 0.5)
			(island_removal_mode 0)
		)
		(polygon
			(pts
				(arc
					(start 81.376012 -279.756362)
					(mid 80.746092 -279.756362)
					(end 81.376012 -279.756362)
				)
			)
		)
	)
	(zone
		(layers "B.Cu" "In11.Cu" "In13.Cu" "In15.Cu")
		(hatch none 0.5)
		(connect_pads
			(clearance 0)
		)
		(min_thickness 0.25)
		(keepout
			(tracks not_allowed)
			(vias allowed)
			(pads allowed)
			(copperpour not_allowed)
			(footprints allowed)
		)
		(placement
			(enabled no)
			(sheetname "")
		)
		(fill yes
			(thermal_gap 0.5)
			(thermal_bridge_width 0.5)
			(island_removal_mode 0)
		)
		(polygon
			(pts
				(arc
					(start 331.195934 -273.27606)
					(mid 330.566014 -273.27606)
					(end 331.195934 -273.27606)
				)
			)
		)
	)
	(zone
		(layers "B.Cu" "In11.Cu" "In13.Cu" "In15.Cu")
		(hatch none 0.5)
		(connect_pads
			(clearance 0)
		)
		(min_thickness 0.25)
		(keepout
			(tracks not_allowed)
			(vias allowed)
			(pads allowed)
			(copperpour not_allowed)
			(footprints allowed)
		)
		(placement
			(enabled no)
			(sheetname "")
		)
		(fill yes
			(thermal_gap 0.5)
			(thermal_bridge_width 0.5)
			(island_removal_mode 0)
		)
		(polygon
			(pts
				(arc
					(start 156.53385 -386.003292)
					(mid 155.90393 -386.003292)
					(end 156.53385 -386.003292)
				)
			)
		)
	)
	(zone
		(layers "B.Cu" "In11.Cu" "In13.Cu" "In15.Cu")
		(hatch none 0.5)
		(connect_pads
			(clearance 0)
		)
		(min_thickness 0.25)
		(keepout
			(tracks not_allowed)
			(vias allowed)
			(pads allowed)
			(copperpour not_allowed)
			(footprints allowed)
		)
		(placement
			(enabled no)
			(sheetname "")
		)
		(fill yes
			(thermal_gap 0.5)
			(thermal_bridge_width 0.5)
			(island_removal_mode 0)
		)
		(polygon
			(pts
				(arc
					(start 418.533834 -394.385292)
					(mid 417.903914 -394.385292)
					(end 418.533834 -394.385292)
				)
			)
		)
	)
	(zone
		(layers "B.Cu" "In11.Cu" "In13.Cu" "In15.Cu")
		(hatch none 0.5)
		(connect_pads
			(clearance 0)
		)
		(min_thickness 0.25)
		(keepout
			(tracks not_allowed)
			(vias allowed)
			(pads allowed)
			(copperpour not_allowed)
			(footprints allowed)
		)
		(placement
			(enabled no)
			(sheetname "")
		)
		(fill yes
			(thermal_gap 0.5)
			(thermal_bridge_width 0.5)
			(island_removal_mode 0)
		)
		(polygon
			(pts
				(arc
					(start 133.606286 -389.467344)
					(mid 132.976366 -389.467344)
					(end 133.606286 -389.467344)
				)
			)
		)
	)
	(zone
		(layers "B.Cu" "In11.Cu" "In13.Cu" "In15.Cu")
		(hatch none 0.5)
		(connect_pads
			(clearance 0)
		)
		(min_thickness 0.25)
		(keepout
			(tracks not_allowed)
			(vias allowed)
			(pads allowed)
			(copperpour not_allowed)
			(footprints allowed)
		)
		(placement
			(enabled no)
			(sheetname "")
		)
		(fill yes
			(thermal_gap 0.5)
			(thermal_bridge_width 0.5)
			(island_removal_mode 0)
		)
		(polygon
			(pts
				(arc
					(start 113.367566 -24.049736)
					(mid 112.699546 -24.049736)
					(end 113.367566 -24.049736)
				)
			)
		)
	)
	(zone
		(layers "B.Cu" "In11.Cu" "In13.Cu" "In15.Cu")
		(hatch none 0.5)
		(connect_pads
			(clearance 0)
		)
		(min_thickness 0.25)
		(keepout
			(tracks not_allowed)
			(vias allowed)
			(pads allowed)
			(copperpour not_allowed)
			(footprints allowed)
		)
		(placement
			(enabled no)
			(sheetname "")
		)
		(fill yes
			(thermal_gap 0.5)
			(thermal_bridge_width 0.5)
			(island_removal_mode 0)
		)
		(polygon
			(pts
				(arc
					(start 442.87821 -261.93496)
					(mid 442.21019 -261.93496)
					(end 442.87821 -261.93496)
				)
			)
		)
	)
	(zone
		(layers "B.Cu" "In11.Cu" "In13.Cu" "In15.Cu")
		(hatch none 0.5)
		(connect_pads
			(clearance 0)
		)
		(min_thickness 0.25)
		(keepout
			(tracks not_allowed)
			(vias allowed)
			(pads allowed)
			(copperpour not_allowed)
			(footprints allowed)
		)
		(placement
			(enabled no)
			(sheetname "")
		)
		(fill yes
			(thermal_gap 0.5)
			(thermal_bridge_width 0.5)
			(island_removal_mode 0)
		)
		(polygon
			(pts
				(arc
					(start 362.379768 -240.434114)
					(mid 361.749848 -240.434114)
					(end 362.379768 -240.434114)
				)
			)
		)
	)
	(zone
		(layers "B.Cu" "In11.Cu" "In13.Cu" "In15.Cu")
		(hatch none 0.5)
		(connect_pads
			(clearance 0)
		)
		(min_thickness 0.25)
		(keepout
			(tracks not_allowed)
			(vias allowed)
			(pads allowed)
			(copperpour not_allowed)
			(footprints allowed)
		)
		(placement
			(enabled no)
			(sheetname "")
		)
		(fill yes
			(thermal_gap 0.5)
			(thermal_bridge_width 0.5)
			(island_removal_mode 0)
		)
		(polygon
			(pts
				(arc
					(start 389.469884 -291.095938)
					(mid 388.839964 -291.095938)
					(end 389.469884 -291.095938)
				)
			)
		)
	)
	(zone
		(layers "B.Cu" "In11.Cu" "In13.Cu" "In15.Cu")
		(hatch none 0.5)
		(connect_pads
			(clearance 0)
		)
		(min_thickness 0.25)
		(keepout
			(tracks not_allowed)
			(vias allowed)
			(pads allowed)
			(copperpour not_allowed)
			(footprints allowed)
		)
		(placement
			(enabled no)
			(sheetname "")
		)
		(fill yes
			(thermal_gap 0.5)
			(thermal_bridge_width 0.5)
			(island_removal_mode 0)
		)
		(polygon
			(pts
				(arc
					(start 82.785966 -277.326344)
					(mid 82.156046 -277.326344)
					(end 82.785966 -277.326344)
				)
			)
		)
	)
	(zone
		(layers "B.Cu" "In11.Cu" "In13.Cu" "In15.Cu")
		(hatch none 0.5)
		(connect_pads
			(clearance 0)
		)
		(min_thickness 0.25)
		(keepout
			(tracks not_allowed)
			(vias allowed)
			(pads allowed)
			(copperpour not_allowed)
			(footprints allowed)
		)
		(placement
			(enabled no)
			(sheetname "")
		)
		(fill yes
			(thermal_gap 0.5)
			(thermal_bridge_width 0.5)
			(island_removal_mode 0)
		)
		(polygon
			(pts
				(arc
					(start 78.037182 -427.089824)
					(mid 77.26299 -427.089824)
					(end 78.037182 -427.089824)
				)
			)
		)
	)
	(zone
		(layers "B.Cu" "In11.Cu" "In13.Cu" "In15.Cu")
		(hatch none 0.5)
		(connect_pads
			(clearance 0)
		)
		(min_thickness 0.25)
		(keepout
			(tracks not_allowed)
			(vias allowed)
			(pads allowed)
			(copperpour not_allowed)
			(footprints allowed)
		)
		(placement
			(enabled no)
			(sheetname "")
		)
		(fill yes
			(thermal_gap 0.5)
			(thermal_bridge_width 0.5)
			(island_removal_mode 0)
		)
		(polygon
			(pts
				(arc
					(start 142.639796 -235.574332)
					(mid 142.009876 -235.574332)
					(end 142.639796 -235.574332)
				)
			)
		)
	)
	(zone
		(layers "B.Cu" "In11.Cu" "In13.Cu" "In15.Cu")
		(hatch none 0.5)
		(connect_pads
			(clearance 0)
		)
		(min_thickness 0.25)
		(keepout
			(tracks not_allowed)
			(vias allowed)
			(pads allowed)
			(copperpour not_allowed)
			(footprints allowed)
		)
		(placement
			(enabled no)
			(sheetname "")
		)
		(fill yes
			(thermal_gap 0.5)
			(thermal_bridge_width 0.5)
			(island_removal_mode 0)
		)
		(polygon
			(pts
				(arc
					(start 81.076038 -229.90429)
					(mid 80.446118 -229.90429)
					(end 81.076038 -229.90429)
				)
			)
		)
	)
	(zone
		(layers "B.Cu" "In11.Cu" "In13.Cu" "In15.Cu")
		(hatch none 0.5)
		(connect_pads
			(clearance 0)
		)
		(min_thickness 0.25)
		(keepout
			(tracks not_allowed)
			(vias allowed)
			(pads allowed)
			(copperpour not_allowed)
			(footprints allowed)
		)
		(placement
			(enabled no)
			(sheetname "")
		)
		(fill yes
			(thermal_gap 0.5)
			(thermal_bridge_width 0.5)
			(island_removal_mode 0)
		)
		(polygon
			(pts
				(arc
					(start 56.506364 -388.774432)
					(mid 55.876444 -388.774432)
					(end 56.506364 -388.774432)
				)
			)
		)
	)
	(zone
		(layers "B.Cu" "In11.Cu" "In13.Cu" "In15.Cu")
		(hatch none 0.5)
		(connect_pads
			(clearance 0)
		)
		(min_thickness 0.25)
		(keepout
			(tracks not_allowed)
			(vias allowed)
			(pads allowed)
			(copperpour not_allowed)
			(footprints allowed)
		)
		(placement
			(enabled no)
			(sheetname "")
		)
		(fill yes
			(thermal_gap 0.5)
			(thermal_bridge_width 0.5)
			(island_removal_mode 0)
		)
		(polygon
			(pts
				(arc
					(start 122.729752 -281.376374)
					(mid 122.099832 -281.376374)
					(end 122.729752 -281.376374)
				)
			)
		)
	)
	(zone
		(layers "B.Cu" "In11.Cu" "In13.Cu" "In15.Cu")
		(hatch none 0.5)
		(connect_pads
			(clearance 0)
		)
		(min_thickness 0.25)
		(keepout
			(tracks not_allowed)
			(vias allowed)
			(pads allowed)
			(copperpour not_allowed)
			(footprints allowed)
		)
		(placement
			(enabled no)
			(sheetname "")
		)
		(fill yes
			(thermal_gap 0.5)
			(thermal_bridge_width 0.5)
			(island_removal_mode 0)
		)
		(polygon
			(pts
				(arc
					(start 391.349738 -274.896072)
					(mid 390.719818 -274.896072)
					(end 391.349738 -274.896072)
				)
			)
		)
	)
	(zone
		(layers "B.Cu" "In11.Cu" "In13.Cu" "In15.Cu")
		(hatch none 0.5)
		(connect_pads
			(clearance 0)
		)
		(min_thickness 0.25)
		(keepout
			(tracks not_allowed)
			(vias allowed)
			(pads allowed)
			(copperpour not_allowed)
			(footprints allowed)
		)
		(placement
			(enabled no)
			(sheetname "")
		)
		(fill yes
			(thermal_gap 0.5)
			(thermal_bridge_width 0.5)
			(island_removal_mode 0)
		)
		(polygon
			(pts
				(arc
					(start 199.03821 -249.18543)
					(mid 198.37019 -249.18543)
					(end 199.03821 -249.18543)
				)
			)
		)
	)
	(zone
		(layers "B.Cu" "In11.Cu" "In13.Cu" "In15.Cu")
		(hatch none 0.5)
		(connect_pads
			(clearance 0)
		)
		(min_thickness 0.25)
		(keepout
			(tracks not_allowed)
			(vias allowed)
			(pads allowed)
			(copperpour not_allowed)
			(footprints allowed)
		)
		(placement
			(enabled no)
			(sheetname "")
		)
		(fill yes
			(thermal_gap 0.5)
			(thermal_bridge_width 0.5)
			(island_removal_mode 0)
		)
		(polygon
			(pts
				(arc
					(start 149.137116 -427.089824)
					(mid 148.362924 -427.089824)
					(end 149.137116 -427.089824)
				)
			)
		)
	)
	(zone
		(layers "B.Cu" "In11.Cu" "In13.Cu" "In15.Cu")
		(hatch none 0.5)
		(connect_pads
			(clearance 0)
		)
		(min_thickness 0.25)
		(keepout
			(tracks not_allowed)
			(vias allowed)
			(pads allowed)
			(copperpour not_allowed)
			(footprints allowed)
		)
		(placement
			(enabled no)
			(sheetname "")
		)
		(fill yes
			(thermal_gap 0.5)
			(thermal_bridge_width 0.5)
			(island_removal_mode 0)
		)
		(polygon
			(pts
				(arc
					(start 29.586174 -273.835368)
					(mid 28.918154 -273.835368)
					(end 29.586174 -273.835368)
				)
			)
		)
	)
	(zone
		(layers "B.Cu" "In11.Cu" "In13.Cu" "In15.Cu")
		(hatch none 0.5)
		(connect_pads
			(clearance 0)
		)
		(min_thickness 0.25)
		(keepout
			(tracks not_allowed)
			(vias allowed)
			(pads allowed)
			(copperpour not_allowed)
			(footprints allowed)
		)
		(placement
			(enabled no)
			(sheetname "")
		)
		(fill yes
			(thermal_gap 0.5)
			(thermal_bridge_width 0.5)
			(island_removal_mode 0)
		)
		(polygon
			(pts
				(arc
					(start 329.486006 -227.474272)
					(mid 328.856086 -227.474272)
					(end 329.486006 -227.474272)
				)
			)
		)
	)
	(zone
		(layers "B.Cu" "In11.Cu" "In13.Cu" "In15.Cu")
		(hatch none 0.5)
		(connect_pads
			(clearance 0)
		)
		(min_thickness 0.25)
		(keepout
			(tracks not_allowed)
			(vias allowed)
			(pads allowed)
			(copperpour not_allowed)
			(footprints allowed)
		)
		(placement
			(enabled no)
			(sheetname "")
		)
		(fill yes
			(thermal_gap 0.5)
			(thermal_bridge_width 0.5)
			(island_removal_mode 0)
		)
		(polygon
			(pts
				(arc
					(start 199.03821 -204.985366)
					(mid 198.37019 -204.985366)
					(end 199.03821 -204.985366)
				)
			)
		)
	)
	(zone
		(layers "B.Cu" "In11.Cu" "In13.Cu" "In15.Cu")
		(hatch none 0.5)
		(connect_pads
			(clearance 0)
		)
		(min_thickness 0.25)
		(keepout
			(tracks not_allowed)
			(vias allowed)
			(pads allowed)
			(copperpour not_allowed)
			(footprints allowed)
		)
		(placement
			(enabled no)
			(sheetname "")
		)
		(fill yes
			(thermal_gap 0.5)
			(thermal_bridge_width 0.5)
			(island_removal_mode 0)
		)
		(polygon
			(pts
				(arc
					(start 194.938142 -286.585406)
					(mid 194.270122 -286.585406)
					(end 194.938142 -286.585406)
				)
			)
		)
	)
	(zone
		(layers "B.Cu" "In11.Cu" "In13.Cu" "In15.Cu")
		(hatch none 0.5)
		(connect_pads
			(clearance 0)
		)
		(min_thickness 0.25)
		(keepout
			(tracks not_allowed)
			(vias allowed)
			(pads allowed)
			(copperpour not_allowed)
			(footprints allowed)
		)
		(placement
			(enabled no)
			(sheetname "")
		)
		(fill yes
			(thermal_gap 0.5)
			(thermal_bridge_width 0.5)
			(island_removal_mode 0)
		)
		(polygon
			(pts
				(arc
					(start 442.87821 -202.434952)
					(mid 442.21019 -202.434952)
					(end 442.87821 -202.434952)
				)
			)
		)
	)
	(zone
		(layers "B.Cu" "In11.Cu" "In13.Cu" "In15.Cu")
		(hatch none 0.5)
		(connect_pads
			(clearance 0)
		)
		(min_thickness 0.25)
		(keepout
			(tracks not_allowed)
			(vias allowed)
			(pads allowed)
			(copperpour not_allowed)
			(footprints allowed)
		)
		(placement
			(enabled no)
			(sheetname "")
		)
		(fill yes
			(thermal_gap 0.5)
			(thermal_bridge_width 0.5)
			(island_removal_mode 0)
		)
		(polygon
			(pts
				(arc
					(start 312.125106 -382.34493)
					(mid 311.457086 -382.34493)
					(end 312.125106 -382.34493)
				)
			)
		)
	)
	(zone
		(layers "B.Cu" "In11.Cu" "In13.Cu" "In15.Cu")
		(hatch none 0.5)
		(connect_pads
			(clearance 0)
		)
		(min_thickness 0.25)
		(keepout
			(tracks not_allowed)
			(vias allowed)
			(pads allowed)
			(copperpour not_allowed)
			(footprints allowed)
		)
		(placement
			(enabled no)
			(sheetname "")
		)
		(fill yes
			(thermal_gap 0.5)
			(thermal_bridge_width 0.5)
			(island_removal_mode 0)
		)
		(polygon
			(pts
				(arc
					(start 391.349738 -271.656048)
					(mid 390.719818 -271.656048)
					(end 391.349738 -271.656048)
				)
			)
		)
	)
	(zone
		(layers "B.Cu" "In11.Cu" "In13.Cu" "In15.Cu")
		(hatch none 0.5)
		(connect_pads
			(clearance 0)
		)
		(min_thickness 0.25)
		(keepout
			(tracks not_allowed)
			(vias allowed)
			(pads allowed)
			(copperpour not_allowed)
			(footprints allowed)
		)
		(placement
			(enabled no)
			(sheetname "")
		)
		(fill yes
			(thermal_gap 0.5)
			(thermal_bridge_width 0.5)
			(island_removal_mode 0)
		)
		(polygon
			(pts
				(arc
					(start 141.999716 -274.08632)
					(mid 141.369796 -274.08632)
					(end 141.999716 -274.08632)
				)
			)
		)
	)
	(zone
		(layers "B.Cu" "In11.Cu" "In13.Cu" "In15.Cu")
		(hatch none 0.5)
		(connect_pads
			(clearance 0)
		)
		(min_thickness 0.25)
		(keepout
			(tracks not_allowed)
			(vias allowed)
			(pads allowed)
			(copperpour not_allowed)
			(footprints allowed)
		)
		(placement
			(enabled no)
			(sheetname "")
		)
		(fill yes
			(thermal_gap 0.5)
			(thermal_bridge_width 0.5)
			(island_removal_mode 0)
		)
		(polygon
			(pts
				(arc
					(start 199.03821 -221.985332)
					(mid 198.37019 -221.985332)
					(end 199.03821 -221.985332)
				)
			)
		)
	)
	(zone
		(layers "B.Cu" "In11.Cu" "In13.Cu" "In15.Cu")
		(hatch none 0.5)
		(connect_pads
			(clearance 0)
		)
		(min_thickness 0.25)
		(keepout
			(tracks not_allowed)
			(vias allowed)
			(pads allowed)
			(copperpour not_allowed)
			(footprints allowed)
		)
		(placement
			(enabled no)
			(sheetname "")
		)
		(fill yes
			(thermal_gap 0.5)
			(thermal_bridge_width 0.5)
			(island_removal_mode 0)
		)
		(polygon
			(pts
				(arc
					(start 273.426174 -308.685184)
					(mid 272.758154 -308.685184)
					(end 273.426174 -308.685184)
				)
			)
		)
	)
	(zone
		(layers "B.Cu" "In11.Cu" "In13.Cu" "In15.Cu")
		(hatch none 0.5)
		(connect_pads
			(clearance 0)
		)
		(min_thickness 0.25)
		(keepout
			(tracks not_allowed)
			(vias allowed)
			(pads allowed)
			(copperpour not_allowed)
			(footprints allowed)
		)
		(placement
			(enabled no)
			(sheetname "")
		)
		(fill yes
			(thermal_gap 0.5)
			(thermal_bridge_width 0.5)
			(island_removal_mode 0)
		)
		(polygon
			(pts
				(arc
					(start 442.87821 -277.235158)
					(mid 442.21019 -277.235158)
					(end 442.87821 -277.235158)
				)
			)
		)
	)
	(zone
		(layers "B.Cu" "In11.Cu" "In13.Cu" "In15.Cu")
		(hatch none 0.5)
		(connect_pads
			(clearance 0)
		)
		(min_thickness 0.25)
		(keepout
			(tracks not_allowed)
			(vias allowed)
			(pads allowed)
			(copperpour not_allowed)
			(footprints allowed)
		)
		(placement
			(enabled no)
			(sheetname "")
		)
		(fill yes
			(thermal_gap 0.5)
			(thermal_bridge_width 0.5)
			(island_removal_mode 0)
		)
		(polygon
			(pts
				(arc
					(start 59.528964 -369.03533)
					(mid 58.860944 -369.03533)
					(end 59.528964 -369.03533)
				)
			)
		)
	)
	(zone
		(layers "B.Cu" "In11.Cu" "In13.Cu" "In15.Cu")
		(hatch none 0.5)
		(connect_pads
			(clearance 0)
		)
		(min_thickness 0.25)
		(keepout
			(tracks not_allowed)
			(vias allowed)
			(pads allowed)
			(copperpour not_allowed)
			(footprints allowed)
		)
		(placement
			(enabled no)
			(sheetname "")
		)
		(fill yes
			(thermal_gap 0.5)
			(thermal_bridge_width 0.5)
			(island_removal_mode 0)
		)
		(polygon
			(pts
				(arc
					(start 81.545938 -237.194344)
					(mid 80.916018 -237.194344)
					(end 81.545938 -237.194344)
				)
			)
		)
	)
	(zone
		(layers "B.Cu" "In11.Cu" "In13.Cu" "In15.Cu")
		(hatch none 0.5)
		(connect_pads
			(clearance 0)
		)
		(min_thickness 0.25)
		(keepout
			(tracks not_allowed)
			(vias allowed)
			(pads allowed)
			(copperpour not_allowed)
			(footprints allowed)
		)
		(placement
			(enabled no)
			(sheetname "")
		)
		(fill yes
			(thermal_gap 0.5)
			(thermal_bridge_width 0.5)
			(island_removal_mode 0)
		)
		(polygon
			(pts
				(arc
					(start 329.016106 -228.284278)
					(mid 328.386186 -228.284278)
					(end 329.016106 -228.284278)
				)
			)
		)
	)
	(zone
		(layers "B.Cu" "In11.Cu" "In13.Cu" "In15.Cu")
		(hatch none 0.5)
		(connect_pads
			(clearance 0)
		)
		(min_thickness 0.25)
		(keepout
			(tracks not_allowed)
			(vias allowed)
			(pads allowed)
			(copperpour not_allowed)
			(footprints allowed)
		)
		(placement
			(enabled no)
			(sheetname "")
		)
		(fill yes
			(thermal_gap 0.5)
			(thermal_bridge_width 0.5)
			(island_removal_mode 0)
		)
		(polygon
			(pts
				(arc
					(start 25.486106 -274.685252)
					(mid 24.818086 -274.685252)
					(end 25.486106 -274.685252)
				)
			)
		)
	)
	(zone
		(layers "B.Cu" "In11.Cu" "In13.Cu" "In15.Cu")
		(hatch none 0.5)
		(connect_pads
			(clearance 0)
		)
		(min_thickness 0.25)
		(keepout
			(tracks not_allowed)
			(vias allowed)
			(pads allowed)
			(copperpour not_allowed)
			(footprints allowed)
		)
		(placement
			(enabled no)
			(sheetname "")
		)
		(fill yes
			(thermal_gap 0.5)
			(thermal_bridge_width 0.5)
			(island_removal_mode 0)
		)
		(polygon
			(pts
				(arc
					(start 386.006086 -397.849344)
					(mid 385.376166 -397.849344)
					(end 386.006086 -397.849344)
				)
			)
		)
	)
	(zone
		(layers "B.Cu" "In11.Cu" "In13.Cu" "In15.Cu")
		(hatch none 0.5)
		(connect_pads
			(clearance 0)
		)
		(min_thickness 0.25)
		(keepout
			(tracks not_allowed)
			(vias allowed)
			(pads allowed)
			(copperpour not_allowed)
			(footprints allowed)
		)
		(placement
			(enabled no)
			(sheetname "")
		)
		(fill yes
			(thermal_gap 0.5)
			(thermal_bridge_width 0.5)
			(island_removal_mode 0)
		)
		(polygon
			(pts
				(arc
					(start 277.526242 -304.435002)
					(mid 276.858222 -304.435002)
					(end 277.526242 -304.435002)
				)
			)
		)
	)
	(zone
		(layers "B.Cu" "In11.Cu" "In13.Cu" "In15.Cu")
		(hatch none 0.5)
		(connect_pads
			(clearance 0)
		)
		(min_thickness 0.25)
		(keepout
			(tracks not_allowed)
			(vias allowed)
			(pads allowed)
			(copperpour not_allowed)
			(footprints allowed)
		)
		(placement
			(enabled no)
			(sheetname "")
		)
		(fill yes
			(thermal_gap 0.5)
			(thermal_bridge_width 0.5)
			(island_removal_mode 0)
		)
		(polygon
			(pts
				(arc
					(start 41.764712 -375.96826)
					(mid 41.096692 -375.96826)
					(end 41.764712 -375.96826)
				)
			)
		)
	)
	(zone
		(layers "B.Cu" "In11.Cu" "In13.Cu" "In15.Cu")
		(hatch none 0.5)
		(connect_pads
			(clearance 0)
		)
		(min_thickness 0.25)
		(keepout
			(tracks not_allowed)
			(vias allowed)
			(pads allowed)
			(copperpour not_allowed)
			(footprints allowed)
		)
		(placement
			(enabled no)
			(sheetname "")
		)
		(fill yes
			(thermal_gap 0.5)
			(thermal_bridge_width 0.5)
			(island_removal_mode 0)
		)
		(polygon
			(pts
				(arc
					(start 318.932306 -382.34493)
					(mid 318.264286 -382.34493)
					(end 318.932306 -382.34493)
				)
			)
		)
	)
	(zone
		(layers "B.Cu" "In11.Cu" "In13.Cu" "In15.Cu")
		(hatch none 0.5)
		(connect_pads
			(clearance 0)
		)
		(min_thickness 0.25)
		(keepout
			(tracks not_allowed)
			(vias allowed)
			(pads allowed)
			(copperpour not_allowed)
			(footprints allowed)
		)
		(placement
			(enabled no)
			(sheetname "")
		)
		(fill yes
			(thermal_gap 0.5)
			(thermal_bridge_width 0.5)
			(island_removal_mode 0)
		)
		(polygon
			(pts
				(arc
					(start 330.726034 -290.285932)
					(mid 330.096114 -290.285932)
					(end 330.726034 -290.285932)
				)
			)
		)
	)
	(zone
		(layers "B.Cu" "In11.Cu" "In13.Cu" "In15.Cu")
		(hatch none 0.5)
		(connect_pads
			(clearance 0)
		)
		(min_thickness 0.25)
		(keepout
			(tracks not_allowed)
			(vias allowed)
			(pads allowed)
			(copperpour not_allowed)
			(footprints allowed)
		)
		(placement
			(enabled no)
			(sheetname "")
		)
		(fill yes
			(thermal_gap 0.5)
			(thermal_bridge_width 0.5)
			(island_removal_mode 0)
		)
		(polygon
			(pts
				(arc
					(start 126.406148 -389.467344)
					(mid 125.776228 -389.467344)
					(end 126.406148 -389.467344)
				)
			)
		)
	)
	(zone
		(layers "B.Cu" "In11.Cu" "In13.Cu" "In15.Cu")
		(hatch none 0.5)
		(connect_pads
			(clearance 0)
		)
		(min_thickness 0.25)
		(keepout
			(tracks not_allowed)
			(vias allowed)
			(pads allowed)
			(copperpour not_allowed)
			(footprints allowed)
		)
		(placement
			(enabled no)
			(sheetname "")
		)
		(fill yes
			(thermal_gap 0.5)
			(thermal_bridge_width 0.5)
			(island_removal_mode 0)
		)
		(polygon
			(pts
				(arc
					(start 143.40967 -282.996386)
					(mid 142.77975 -282.996386)
					(end 143.40967 -282.996386)
				)
			)
		)
	)
	(zone
		(layers "B.Cu" "In11.Cu" "In13.Cu" "In15.Cu")
		(hatch none 0.5)
		(connect_pads
			(clearance 0)
		)
		(min_thickness 0.25)
		(keepout
			(tracks not_allowed)
			(vias allowed)
			(pads allowed)
			(copperpour not_allowed)
			(footprints allowed)
		)
		(placement
			(enabled no)
			(sheetname "")
		)
		(fill yes
			(thermal_gap 0.5)
			(thermal_bridge_width 0.5)
			(island_removal_mode 0)
		)
		(polygon
			(pts
				(arc
					(start 199.03821 -306.135278)
					(mid 198.37019 -306.135278)
					(end 199.03821 -306.135278)
				)
			)
		)
	)
	(zone
		(layers "B.Cu" "In11.Cu" "In13.Cu" "In15.Cu")
		(hatch none 0.5)
		(connect_pads
			(clearance 0)
		)
		(min_thickness 0.25)
		(keepout
			(tracks not_allowed)
			(vias allowed)
			(pads allowed)
			(copperpour not_allowed)
			(footprints allowed)
		)
		(placement
			(enabled no)
			(sheetname "")
		)
		(fill yes
			(thermal_gap 0.5)
			(thermal_bridge_width 0.5)
			(island_removal_mode 0)
		)
		(polygon
			(pts
				(arc
					(start 329.486006 -225.85426)
					(mid 328.856086 -225.85426)
					(end 329.486006 -225.85426)
				)
			)
		)
	)
	(zone
		(layers "B.Cu" "In11.Cu" "In13.Cu" "In15.Cu")
		(hatch none 0.5)
		(connect_pads
			(clearance 0)
		)
		(min_thickness 0.25)
		(keepout
			(tracks not_allowed)
			(vias allowed)
			(pads allowed)
			(copperpour not_allowed)
			(footprints allowed)
		)
		(placement
			(enabled no)
			(sheetname "")
		)
		(fill yes
			(thermal_gap 0.5)
			(thermal_bridge_width 0.5)
			(island_removal_mode 0)
		)
		(polygon
			(pts
				(arc
					(start 122.806206 -389.467344)
					(mid 122.176286 -389.467344)
					(end 122.806206 -389.467344)
				)
			)
		)
	)
	(zone
		(layers "B.Cu" "In11.Cu" "In13.Cu" "In15.Cu")
		(hatch none 0.5)
		(connect_pads
			(clearance 0)
		)
		(min_thickness 0.25)
		(keepout
			(tracks not_allowed)
			(vias allowed)
			(pads allowed)
			(copperpour not_allowed)
			(footprints allowed)
		)
		(placement
			(enabled no)
			(sheetname "")
		)
		(fill yes
			(thermal_gap 0.5)
			(thermal_bridge_width 0.5)
			(island_removal_mode 0)
		)
		(polygon
			(pts
				(arc
					(start 110.046008 -283.806392)
					(mid 109.416088 -283.806392)
					(end 110.046008 -283.806392)
				)
			)
		)
	)
	(zone
		(layers "B.Cu" "In11.Cu" "In13.Cu" "In15.Cu")
		(hatch none 0.5)
		(connect_pads
			(clearance 0)
		)
		(min_thickness 0.25)
		(keepout
			(tracks not_allowed)
			(vias allowed)
			(pads allowed)
			(copperpour not_allowed)
			(footprints allowed)
		)
		(placement
			(enabled no)
			(sheetname "")
		)
		(fill yes
			(thermal_gap 0.5)
			(thermal_bridge_width 0.5)
			(island_removal_mode 0)
		)
		(polygon
			(pts
				(arc
					(start 194.938142 -285.735268)
					(mid 194.270122 -285.735268)
					(end 194.938142 -285.735268)
				)
			)
		)
	)
	(zone
		(layers "B.Cu" "In11.Cu" "In13.Cu" "In15.Cu")
		(hatch none 0.5)
		(connect_pads
			(clearance 0)
		)
		(min_thickness 0.25)
		(keepout
			(tracks not_allowed)
			(vias allowed)
			(pads allowed)
			(copperpour not_allowed)
			(footprints allowed)
		)
		(placement
			(enabled no)
			(sheetname "")
		)
		(fill yes
			(thermal_gap 0.5)
			(thermal_bridge_width 0.5)
			(island_removal_mode 0)
		)
		(polygon
			(pts
				(arc
					(start 389.16991 -228.284278)
					(mid 388.53999 -228.284278)
					(end 389.16991 -228.284278)
				)
			)
		)
	)
	(zone
		(layers "B.Cu" "In11.Cu" "In13.Cu" "In15.Cu")
		(hatch none 0.5)
		(connect_pads
			(clearance 0)
		)
		(min_thickness 0.25)
		(keepout
			(tracks not_allowed)
			(vias allowed)
			(pads allowed)
			(copperpour not_allowed)
			(footprints allowed)
		)
		(placement
			(enabled no)
			(sheetname "")
		)
		(fill yes
			(thermal_gap 0.5)
			(thermal_bridge_width 0.5)
			(island_removal_mode 0)
		)
		(polygon
			(pts
				(arc
					(start 81.376012 -276.516338)
					(mid 80.746092 -276.516338)
					(end 81.376012 -276.516338)
				)
			)
		)
	)
	(zone
		(layers "B.Cu" "In11.Cu" "In13.Cu" "In15.Cu")
		(hatch none 0.5)
		(connect_pads
			(clearance 0)
		)
		(min_thickness 0.25)
		(keepout
			(tracks not_allowed)
			(vias allowed)
			(pads allowed)
			(copperpour not_allowed)
			(footprints allowed)
		)
		(placement
			(enabled no)
			(sheetname "")
		)
		(fill yes
			(thermal_gap 0.5)
			(thermal_bridge_width 0.5)
			(island_removal_mode 0)
		)
		(polygon
			(pts
				(arc
					(start 327.611486 -385.338828)
					(mid 326.943466 -385.338828)
					(end 327.611486 -385.338828)
				)
			)
		)
	)
	(zone
		(layers "B.Cu" "In11.Cu" "In13.Cu" "In15.Cu")
		(hatch none 0.5)
		(connect_pads
			(clearance 0)
		)
		(min_thickness 0.25)
		(keepout
			(tracks not_allowed)
			(vias allowed)
			(pads allowed)
			(copperpour not_allowed)
			(footprints allowed)
		)
		(placement
			(enabled no)
			(sheetname "")
		)
		(fill yes
			(thermal_gap 0.5)
			(thermal_bridge_width 0.5)
			(island_removal_mode 0)
		)
		(polygon
			(pts
				(arc
					(start 143.109696 -242.864386)
					(mid 142.479776 -242.864386)
					(end 143.109696 -242.864386)
				)
			)
		)
	)
	(zone
		(layers "B.Cu" "In11.Cu" "In13.Cu" "In15.Cu")
		(hatch none 0.5)
		(connect_pads
			(clearance 0)
		)
		(min_thickness 0.25)
		(keepout
			(tracks not_allowed)
			(vias allowed)
			(pads allowed)
			(copperpour not_allowed)
			(footprints allowed)
		)
		(placement
			(enabled no)
			(sheetname "")
		)
		(fill yes
			(thermal_gap 0.5)
			(thermal_bridge_width 0.5)
			(island_removal_mode 0)
		)
		(polygon
			(pts
				(arc
					(start 141.699742 -233.95432)
					(mid 141.069822 -233.95432)
					(end 141.699742 -233.95432)
				)
			)
		)
	)
	(zone
		(layers "B.Cu" "In11.Cu" "In13.Cu" "In15.Cu")
		(hatch none 0.5)
		(connect_pads
			(clearance 0)
		)
		(min_thickness 0.25)
		(keepout
			(tracks not_allowed)
			(vias allowed)
			(pads allowed)
			(copperpour not_allowed)
			(footprints allowed)
		)
		(placement
			(enabled no)
			(sheetname "")
		)
		(fill yes
			(thermal_gap 0.5)
			(thermal_bridge_width 0.5)
			(island_removal_mode 0)
		)
		(polygon
			(pts
				(arc
					(start 82.785966 -262.746236)
					(mid 82.156046 -262.746236)
					(end 82.785966 -262.746236)
				)
			)
		)
	)
	(zone
		(layers "B.Cu" "In11.Cu" "In13.Cu" "In15.Cu")
		(hatch none 0.5)
		(connect_pads
			(clearance 0)
		)
		(min_thickness 0.25)
		(keepout
			(tracks not_allowed)
			(vias allowed)
			(pads allowed)
			(copperpour not_allowed)
			(footprints allowed)
		)
		(placement
			(enabled no)
			(sheetname "")
		)
		(fill yes
			(thermal_gap 0.5)
			(thermal_bridge_width 0.5)
			(island_removal_mode 0)
		)
		(polygon
			(pts
				(arc
					(start 442.87821 -226.235006)
					(mid 442.21019 -226.235006)
					(end 442.87821 -226.235006)
				)
			)
		)
	)
	(zone
		(layers "B.Cu" "In11.Cu" "In13.Cu" "In15.Cu")
		(hatch none 0.5)
		(connect_pads
			(clearance 0)
		)
		(min_thickness 0.25)
		(keepout
			(tracks not_allowed)
			(vias allowed)
			(pads allowed)
			(copperpour not_allowed)
			(footprints allowed)
		)
		(placement
			(enabled no)
			(sheetname "")
		)
		(fill yes
			(thermal_gap 0.5)
			(thermal_bridge_width 0.5)
			(island_removal_mode 0)
		)
		(polygon
			(pts
				(arc
					(start 277.526242 -295.085008)
					(mid 276.858222 -295.085008)
					(end 277.526242 -295.085008)
				)
			)
		)
	)
	(zone
		(layers "B.Cu" "In11.Cu" "In13.Cu" "In15.Cu")
		(hatch none 0.5)
		(connect_pads
			(clearance 0)
		)
		(min_thickness 0.25)
		(keepout
			(tracks not_allowed)
			(vias allowed)
			(pads allowed)
			(copperpour not_allowed)
			(footprints allowed)
		)
		(placement
			(enabled no)
			(sheetname "")
		)
		(fill yes
			(thermal_gap 0.5)
			(thermal_bridge_width 0.5)
			(island_removal_mode 0)
		)
		(polygon
			(pts
				(arc
					(start 82.485992 -227.474526)
					(mid 81.856072 -227.474526)
					(end 82.485992 -227.474526)
				)
			)
		)
	)
	(zone
		(layers "B.Cu" "In11.Cu" "In13.Cu" "In15.Cu")
		(hatch none 0.5)
		(connect_pads
			(clearance 0)
		)
		(min_thickness 0.25)
		(keepout
			(tracks not_allowed)
			(vias allowed)
			(pads allowed)
			(copperpour not_allowed)
			(footprints allowed)
		)
		(placement
			(enabled no)
			(sheetname "")
		)
		(fill yes
			(thermal_gap 0.5)
			(thermal_bridge_width 0.5)
			(island_removal_mode 0)
		)
		(polygon
			(pts
				(arc
					(start 141.529816 -276.516338)
					(mid 140.899896 -276.516338)
					(end 141.529816 -276.516338)
				)
			)
		)
	)
	(zone
		(layers "B.Cu" "In11.Cu" "In13.Cu" "In15.Cu")
		(hatch none 0.5)
		(connect_pads
			(clearance 0)
		)
		(min_thickness 0.25)
		(keepout
			(tracks not_allowed)
			(vias allowed)
			(pads allowed)
			(copperpour not_allowed)
			(footprints allowed)
		)
		(placement
			(enabled no)
			(sheetname "")
		)
		(fill yes
			(thermal_gap 0.5)
			(thermal_bridge_width 0.5)
			(island_removal_mode 0)
		)
		(polygon
			(pts
				(arc
					(start 373.489728 -282.996132)
					(mid 372.859808 -282.996132)
					(end 373.489728 -282.996132)
				)
			)
		)
	)
	(zone
		(layers "B.Cu" "In11.Cu" "In13.Cu" "In15.Cu")
		(hatch none 0.5)
		(connect_pads
			(clearance 0)
		)
		(min_thickness 0.25)
		(keepout
			(tracks not_allowed)
			(vias allowed)
			(pads allowed)
			(copperpour not_allowed)
			(footprints allowed)
		)
		(placement
			(enabled no)
			(sheetname "")
		)
		(fill yes
			(thermal_gap 0.5)
			(thermal_bridge_width 0.5)
			(island_removal_mode 0)
		)
		(polygon
			(pts
				(arc
					(start 81.545938 -233.95432)
					(mid 80.916018 -233.95432)
					(end 81.545938 -233.95432)
				)
			)
		)
	)
	(zone
		(layers "B.Cu" "In11.Cu" "In13.Cu" "In15.Cu")
		(hatch none 0.5)
		(connect_pads
			(clearance 0)
		)
		(min_thickness 0.25)
		(keepout
			(tracks not_allowed)
			(vias allowed)
			(pads allowed)
			(copperpour not_allowed)
			(footprints allowed)
		)
		(placement
			(enabled no)
			(sheetname "")
		)
		(fill yes
			(thermal_gap 0.5)
			(thermal_bridge_width 0.5)
			(island_removal_mode 0)
		)
		(polygon
			(pts
				(arc
					(start 114.739674 -283.806392)
					(mid 114.109754 -283.806392)
					(end 114.739674 -283.806392)
				)
			)
		)
	)
	(zone
		(layers "B.Cu" "In11.Cu" "In13.Cu" "In15.Cu")
		(hatch none 0.5)
		(connect_pads
			(clearance 0)
		)
		(min_thickness 0.25)
		(keepout
			(tracks not_allowed)
			(vias allowed)
			(pads allowed)
			(copperpour not_allowed)
			(footprints allowed)
		)
		(placement
			(enabled no)
			(sheetname "")
		)
		(fill yes
			(thermal_gap 0.5)
			(thermal_bridge_width 0.5)
			(island_removal_mode 0)
		)
		(polygon
			(pts
				(arc
					(start 84.03717 -427.289976)
					(mid 83.262978 -427.289976)
					(end 84.03717 -427.289976)
				)
			)
		)
	)
	(zone
		(layers "B.Cu" "In11.Cu" "In13.Cu" "In15.Cu")
		(hatch none 0.5)
		(connect_pads
			(clearance 0)
		)
		(min_thickness 0.25)
		(keepout
			(tracks not_allowed)
			(vias allowed)
			(pads allowed)
			(copperpour not_allowed)
			(footprints allowed)
		)
		(placement
			(enabled no)
			(sheetname "")
		)
		(fill yes
			(thermal_gap 0.5)
			(thermal_bridge_width 0.5)
			(island_removal_mode 0)
		)
		(polygon
			(pts
				(arc
					(start 125.54966 -281.376374)
					(mid 124.91974 -281.376374)
					(end 125.54966 -281.376374)
				)
			)
		)
	)
	(zone
		(layers "B.Cu" "In11.Cu" "In13.Cu" "In15.Cu")
		(hatch none 0.5)
		(connect_pads
			(clearance 0)
		)
		(min_thickness 0.25)
		(keepout
			(tracks not_allowed)
			(vias allowed)
			(pads allowed)
			(copperpour not_allowed)
			(footprints allowed)
		)
		(placement
			(enabled no)
			(sheetname "")
		)
		(fill yes
			(thermal_gap 0.5)
			(thermal_bridge_width 0.5)
			(island_removal_mode 0)
		)
		(polygon
			(pts
				(arc
					(start 382.136904 -426.089826)
					(mid 381.362712 -426.089826)
					(end 382.136904 -426.089826)
				)
			)
		)
	)
	(zone
		(layers "B.Cu" "In11.Cu" "In13.Cu" "In15.Cu")
		(hatch none 0.5)
		(connect_pads
			(clearance 0)
		)
		(min_thickness 0.25)
		(keepout
			(tracks not_allowed)
			(vias allowed)
			(pads allowed)
			(copperpour not_allowed)
			(footprints allowed)
		)
		(placement
			(enabled no)
			(sheetname "")
		)
		(fill yes
			(thermal_gap 0.5)
			(thermal_bridge_width 0.5)
			(island_removal_mode 0)
		)
		(polygon
			(pts
				(arc
					(start 199.03821 -276.385274)
					(mid 198.37019 -276.385274)
					(end 199.03821 -276.385274)
				)
			)
		)
	)
	(zone
		(layers "B.Cu" "In11.Cu" "In13.Cu" "In15.Cu")
		(hatch none 0.5)
		(connect_pads
			(clearance 0)
		)
		(min_thickness 0.25)
		(keepout
			(tracks not_allowed)
			(vias allowed)
			(pads allowed)
			(copperpour not_allowed)
			(footprints allowed)
		)
		(placement
			(enabled no)
			(sheetname "")
		)
		(fill yes
			(thermal_gap 0.5)
			(thermal_bridge_width 0.5)
			(island_removal_mode 0)
		)
		(polygon
			(pts
				(arc
					(start 442.87821 -284.034992)
					(mid 442.21019 -284.034992)
					(end 442.87821 -284.034992)
				)
			)
		)
	)
	(zone
		(layers "B.Cu" "In11.Cu" "In13.Cu" "In15.Cu")
		(hatch none 0.5)
		(connect_pads
			(clearance 0)
		)
		(min_thickness 0.25)
		(keepout
			(tracks not_allowed)
			(vias allowed)
			(pads allowed)
			(copperpour not_allowed)
			(footprints allowed)
		)
		(placement
			(enabled no)
			(sheetname "")
		)
		(fill yes
			(thermal_gap 0.5)
			(thermal_bridge_width 0.5)
			(island_removal_mode 0)
		)
		(polygon
			(pts
				(arc
					(start 41.764712 -382.36906)
					(mid 41.096692 -382.36906)
					(end 41.764712 -382.36906)
				)
			)
		)
	)
	(zone
		(layers "B.Cu" "In11.Cu" "In13.Cu" "In15.Cu")
		(hatch none 0.5)
		(connect_pads
			(clearance 0)
		)
		(min_thickness 0.25)
		(keepout
			(tracks not_allowed)
			(vias allowed)
			(pads allowed)
			(copperpour not_allowed)
			(footprints allowed)
		)
		(placement
			(enabled no)
			(sheetname "")
		)
		(fill yes
			(thermal_gap 0.5)
			(thermal_bridge_width 0.5)
			(island_removal_mode 0)
		)
		(polygon
			(pts
				(arc
					(start 329.016106 -255.824228)
					(mid 328.386186 -255.824228)
					(end 329.016106 -255.824228)
				)
			)
		)
	)
	(zone
		(layers "B.Cu" "In11.Cu" "In13.Cu" "In15.Cu")
		(hatch none 0.5)
		(connect_pads
			(clearance 0)
		)
		(min_thickness 0.25)
		(keepout
			(tracks not_allowed)
			(vias allowed)
			(pads allowed)
			(copperpour not_allowed)
			(footprints allowed)
		)
		(placement
			(enabled no)
			(sheetname "")
		)
		(fill yes
			(thermal_gap 0.5)
			(thermal_bridge_width 0.5)
			(island_removal_mode 0)
		)
		(polygon
			(pts
				(arc
					(start 329.31608 -292.71595)
					(mid 328.68616 -292.71595)
					(end 329.31608 -292.71595)
				)
			)
		)
	)
	(zone
		(layers "B.Cu" "In11.Cu" "In13.Cu" "In15.Cu")
		(hatch none 0.5)
		(connect_pads
			(clearance 0)
		)
		(min_thickness 0.25)
		(keepout
			(tracks not_allowed)
			(vias allowed)
			(pads allowed)
			(copperpour not_allowed)
			(footprints allowed)
		)
		(placement
			(enabled no)
			(sheetname "")
		)
		(fill yes
			(thermal_gap 0.5)
			(thermal_bridge_width 0.5)
			(island_removal_mode 0)
		)
		(polygon
			(pts
				(arc
					(start 346.0369 -428.28972)
					(mid 345.262708 -428.28972)
					(end 346.0369 -428.28972)
				)
			)
		)
	)
	(zone
		(layers "B.Cu" "In11.Cu" "In13.Cu" "In15.Cu")
		(hatch none 0.5)
		(connect_pads
			(clearance 0)
		)
		(min_thickness 0.25)
		(keepout
			(tracks not_allowed)
			(vias allowed)
			(pads allowed)
			(copperpour not_allowed)
			(footprints allowed)
		)
		(placement
			(enabled no)
			(sheetname "")
		)
		(fill yes
			(thermal_gap 0.5)
			(thermal_bridge_width 0.5)
			(island_removal_mode 0)
		)
		(polygon
			(pts
				(arc
					(start 446.978278 -267.885164)
					(mid 446.310258 -267.885164)
					(end 446.978278 -267.885164)
				)
			)
		)
	)
	(zone
		(layers "B.Cu" "In11.Cu" "In13.Cu" "In15.Cu")
		(hatch none 0.5)
		(connect_pads
			(clearance 0)
		)
		(min_thickness 0.25)
		(keepout
			(tracks not_allowed)
			(vias allowed)
			(pads allowed)
			(copperpour not_allowed)
			(footprints allowed)
		)
		(placement
			(enabled no)
			(sheetname "")
		)
		(fill yes
			(thermal_gap 0.5)
			(thermal_bridge_width 0.5)
			(island_removal_mode 0)
		)
		(polygon
			(pts
				(arc
					(start 329.78598 -275.706078)
					(mid 329.15606 -275.706078)
					(end 329.78598 -275.706078)
				)
			)
		)
	)
	(zone
		(layers "B.Cu" "In11.Cu" "In13.Cu" "In15.Cu")
		(hatch none 0.5)
		(connect_pads
			(clearance 0)
		)
		(min_thickness 0.25)
		(keepout
			(tracks not_allowed)
			(vias allowed)
			(pads allowed)
			(copperpour not_allowed)
			(footprints allowed)
		)
		(placement
			(enabled no)
			(sheetname "")
		)
		(fill yes
			(thermal_gap 0.5)
			(thermal_bridge_width 0.5)
			(island_removal_mode 0)
		)
		(polygon
			(pts
				(arc
					(start 273.426174 -230.485188)
					(mid 272.758154 -230.485188)
					(end 273.426174 -230.485188)
				)
			)
		)
	)
	(zone
		(layers "B.Cu" "In11.Cu" "In13.Cu" "In15.Cu")
		(hatch none 0.5)
		(connect_pads
			(clearance 0)
		)
		(min_thickness 0.25)
		(keepout
			(tracks not_allowed)
			(vias allowed)
			(pads allowed)
			(copperpour not_allowed)
			(footprints allowed)
		)
		(placement
			(enabled no)
			(sheetname "")
		)
		(fill yes
			(thermal_gap 0.5)
			(thermal_bridge_width 0.5)
			(island_removal_mode 0)
		)
		(polygon
			(pts
				(arc
					(start 124.806202 -388.774432)
					(mid 124.176282 -388.774432)
					(end 124.806202 -388.774432)
				)
			)
		)
	)
	(zone
		(layers "B.Cu" "In11.Cu" "In13.Cu" "In15.Cu")
		(hatch none 0.5)
		(connect_pads
			(clearance 0)
		)
		(min_thickness 0.25)
		(keepout
			(tracks not_allowed)
			(vias allowed)
			(pads allowed)
			(copperpour not_allowed)
			(footprints allowed)
		)
		(placement
			(enabled no)
			(sheetname "")
		)
		(fill yes
			(thermal_gap 0.5)
			(thermal_bridge_width 0.5)
			(island_removal_mode 0)
		)
		(polygon
			(pts
				(arc
					(start 330.89596 -236.384084)
					(mid 330.26604 -236.384084)
					(end 330.89596 -236.384084)
				)
			)
		)
	)
	(zone
		(layers "B.Cu" "In11.Cu" "In13.Cu" "In15.Cu")
		(hatch none 0.5)
		(connect_pads
			(clearance 0)
		)
		(min_thickness 0.25)
		(keepout
			(tracks not_allowed)
			(vias allowed)
			(pads allowed)
			(copperpour not_allowed)
			(footprints allowed)
		)
		(placement
			(enabled no)
			(sheetname "")
		)
		(fill yes
			(thermal_gap 0.5)
			(thermal_bridge_width 0.5)
			(island_removal_mode 0)
		)
		(polygon
			(pts
				(arc
					(start 82.955892 -250.964446)
					(mid 82.325972 -250.964446)
					(end 82.955892 -250.964446)
				)
			)
		)
	)
	(zone
		(layers "B.Cu" "In11.Cu" "In13.Cu" "In15.Cu")
		(hatch none 0.5)
		(connect_pads
			(clearance 0)
		)
		(min_thickness 0.25)
		(keepout
			(tracks not_allowed)
			(vias allowed)
			(pads allowed)
			(copperpour not_allowed)
			(footprints allowed)
		)
		(placement
			(enabled no)
			(sheetname "")
		)
		(fill yes
			(thermal_gap 0.5)
			(thermal_bridge_width 0.5)
			(island_removal_mode 0)
		)
		(polygon
			(pts
				(arc
					(start 329.016106 -247.724168)
					(mid 328.386186 -247.724168)
					(end 329.016106 -247.724168)
				)
			)
		)
	)
	(zone
		(layers "B.Cu" "In11.Cu" "In13.Cu" "In15.Cu")
		(hatch none 0.5)
		(connect_pads
			(clearance 0)
		)
		(min_thickness 0.25)
		(keepout
			(tracks not_allowed)
			(vias allowed)
			(pads allowed)
			(copperpour not_allowed)
			(footprints allowed)
		)
		(placement
			(enabled no)
			(sheetname "")
		)
		(fill yes
			(thermal_gap 0.5)
			(thermal_bridge_width 0.5)
			(island_removal_mode 0)
		)
		(polygon
			(pts
				(arc
					(start 61.036962 -421.089836)
					(mid 60.26277 -421.089836)
					(end 61.036962 -421.089836)
				)
			)
		)
	)
	(zone
		(layers "B.Cu" "In11.Cu" "In13.Cu" "In15.Cu")
		(hatch none 0.5)
		(connect_pads
			(clearance 0)
		)
		(min_thickness 0.25)
		(keepout
			(tracks not_allowed)
			(vias allowed)
			(pads allowed)
			(copperpour not_allowed)
			(footprints allowed)
		)
		(placement
			(enabled no)
			(sheetname "")
		)
		(fill yes
			(thermal_gap 0.5)
			(thermal_bridge_width 0.5)
			(island_removal_mode 0)
		)
		(polygon
			(pts
				(arc
					(start 29.586174 -300.185328)
					(mid 28.918154 -300.185328)
					(end 29.586174 -300.185328)
				)
			)
		)
	)
	(zone
		(layers "B.Cu" "In11.Cu" "In13.Cu" "In15.Cu")
		(hatch none 0.5)
		(connect_pads
			(clearance 0)
		)
		(min_thickness 0.25)
		(keepout
			(tracks not_allowed)
			(vias allowed)
			(pads allowed)
			(copperpour not_allowed)
			(footprints allowed)
		)
		(placement
			(enabled no)
			(sheetname "")
		)
		(fill yes
			(thermal_gap 0.5)
			(thermal_bridge_width 0.5)
			(island_removal_mode 0)
		)
		(polygon
			(pts
				(arc
					(start 82.485992 -248.534428)
					(mid 81.856072 -248.534428)
					(end 82.485992 -248.534428)
				)
			)
		)
	)
	(zone
		(layers "B.Cu" "In11.Cu" "In13.Cu" "In15.Cu")
		(hatch none 0.5)
		(connect_pads
			(clearance 0)
		)
		(min_thickness 0.25)
		(keepout
			(tracks not_allowed)
			(vias allowed)
			(pads allowed)
			(copperpour not_allowed)
			(footprints allowed)
		)
		(placement
			(enabled no)
			(sheetname "")
		)
		(fill yes
			(thermal_gap 0.5)
			(thermal_bridge_width 0.5)
			(island_removal_mode 0)
		)
		(polygon
			(pts
				(arc
					(start 71.036942 -427.289976)
					(mid 70.26275 -427.289976)
					(end 71.036942 -427.289976)
				)
			)
		)
	)
	(zone
		(layers "B.Cu" "In11.Cu" "In13.Cu" "In15.Cu")
		(hatch none 0.5)
		(connect_pads
			(clearance 0)
		)
		(min_thickness 0.25)
		(keepout
			(tracks not_allowed)
			(vias allowed)
			(pads allowed)
			(copperpour not_allowed)
			(footprints allowed)
		)
		(placement
			(enabled no)
			(sheetname "")
		)
		(fill yes
			(thermal_gap 0.5)
			(thermal_bridge_width 0.5)
			(island_removal_mode 0)
		)
		(polygon
			(pts
				(arc
					(start 29.586174 -294.235378)
					(mid 28.918154 -294.235378)
					(end 29.586174 -294.235378)
				)
			)
		)
	)
	(zone
		(layers "B.Cu" "In11.Cu" "In13.Cu" "In15.Cu")
		(hatch none 0.5)
		(connect_pads
			(clearance 0)
		)
		(min_thickness 0.25)
		(keepout
			(tracks not_allowed)
			(vias allowed)
			(pads allowed)
			(copperpour not_allowed)
			(footprints allowed)
		)
		(placement
			(enabled no)
			(sheetname "")
		)
		(fill yes
			(thermal_gap 0.5)
			(thermal_bridge_width 0.5)
			(island_removal_mode 0)
		)
		(polygon
			(pts
				(arc
					(start 25.486106 -222.835216)
					(mid 24.818086 -222.835216)
					(end 25.486106 -222.835216)
				)
			)
		)
	)
	(zone
		(layers "B.Cu" "In11.Cu" "In13.Cu" "In15.Cu")
		(hatch none 0.5)
		(connect_pads
			(clearance 0)
		)
		(min_thickness 0.25)
		(keepout
			(tracks not_allowed)
			(vias allowed)
			(pads allowed)
			(copperpour not_allowed)
			(footprints allowed)
		)
		(placement
			(enabled no)
			(sheetname "")
		)
		(fill yes
			(thermal_gap 0.5)
			(thermal_bridge_width 0.5)
			(island_removal_mode 0)
		)
		(polygon
			(pts
				(arc
					(start 141.699742 -237.194344)
					(mid 141.069822 -237.194344)
					(end 141.699742 -237.194344)
				)
			)
		)
	)
	(zone
		(layers "B.Cu" "In11.Cu" "In13.Cu" "In15.Cu")
		(hatch none 0.5)
		(connect_pads
			(clearance 0)
		)
		(min_thickness 0.25)
		(keepout
			(tracks not_allowed)
			(vias allowed)
			(pads allowed)
			(copperpour not_allowed)
			(footprints allowed)
		)
		(placement
			(enabled no)
			(sheetname "")
		)
		(fill yes
			(thermal_gap 0.5)
			(thermal_bridge_width 0.5)
			(island_removal_mode 0)
		)
		(polygon
			(pts
				(arc
					(start 25.486106 -215.185244)
					(mid 24.818086 -215.185244)
					(end 25.486106 -215.185244)
				)
			)
		)
	)
	(zone
		(layers "B.Cu" "In11.Cu" "In13.Cu" "In15.Cu")
		(hatch none 0.5)
		(connect_pads
			(clearance 0)
		)
		(min_thickness 0.25)
		(keepout
			(tracks not_allowed)
			(vias allowed)
			(pads allowed)
			(copperpour not_allowed)
			(footprints allowed)
		)
		(placement
			(enabled no)
			(sheetname "")
		)
		(fill yes
			(thermal_gap 0.5)
			(thermal_bridge_width 0.5)
			(island_removal_mode 0)
		)
		(polygon
			(pts
				(arc
					(start 273.426174 -202.434952)
					(mid 272.758154 -202.434952)
					(end 273.426174 -202.434952)
				)
			)
		)
	)
	(zone
		(layers "B.Cu" "In11.Cu" "In13.Cu" "In15.Cu")
		(hatch none 0.5)
		(connect_pads
			(clearance 0)
		)
		(min_thickness 0.25)
		(keepout
			(tracks not_allowed)
			(vias allowed)
			(pads allowed)
			(copperpour not_allowed)
			(footprints allowed)
		)
		(placement
			(enabled no)
			(sheetname "")
		)
		(fill yes
			(thermal_gap 0.5)
			(thermal_bridge_width 0.5)
			(island_removal_mode 0)
		)
		(polygon
			(pts
				(arc
					(start 389.16991 -226.664266)
					(mid 388.53999 -226.664266)
					(end 389.16991 -226.664266)
				)
			)
		)
	)
	(zone
		(layers "B.Cu" "In11.Cu" "In13.Cu" "In15.Cu")
		(hatch none 0.5)
		(connect_pads
			(clearance 0)
		)
		(min_thickness 0.25)
		(keepout
			(tracks not_allowed)
			(vias allowed)
			(pads allowed)
			(copperpour not_allowed)
			(footprints allowed)
		)
		(placement
			(enabled no)
			(sheetname "")
		)
		(fill yes
			(thermal_gap 0.5)
			(thermal_bridge_width 0.5)
			(island_removal_mode 0)
		)
		(polygon
			(pts
				(arc
					(start 57.317894 -404.46452)
					(mid 56.649874 -404.46452)
					(end 57.317894 -404.46452)
				)
			)
		)
	)
	(zone
		(layers "B.Cu" "In11.Cu" "In13.Cu" "In15.Cu")
		(hatch none 0.5)
		(connect_pads
			(clearance 0)
		)
		(min_thickness 0.25)
		(keepout
			(tracks not_allowed)
			(vias allowed)
			(pads allowed)
			(copperpour not_allowed)
			(footprints allowed)
		)
		(placement
			(enabled no)
			(sheetname "")
		)
		(fill yes
			(thermal_gap 0.5)
			(thermal_bridge_width 0.5)
			(island_removal_mode 0)
		)
		(polygon
			(pts
				(arc
					(start 446.978278 -296.78503)
					(mid 446.310258 -296.78503)
					(end 446.978278 -296.78503)
				)
			)
		)
	)
	(zone
		(layers "B.Cu" "In11.Cu" "In13.Cu" "In15.Cu")
		(hatch none 0.5)
		(connect_pads
			(clearance 0)
		)
		(min_thickness 0.25)
		(keepout
			(tracks not_allowed)
			(vias allowed)
			(pads allowed)
			(copperpour not_allowed)
			(footprints allowed)
		)
		(placement
			(enabled no)
			(sheetname "")
		)
		(fill yes
			(thermal_gap 0.5)
			(thermal_bridge_width 0.5)
			(island_removal_mode 0)
		)
		(polygon
			(pts
				(arc
					(start 446.978278 -201.585068)
					(mid 446.310258 -201.585068)
					(end 446.978278 -201.585068)
				)
			)
		)
	)
	(zone
		(layers "B.Cu" "In11.Cu" "In13.Cu" "In15.Cu")
		(hatch none 0.5)
		(connect_pads
			(clearance 0)
		)
		(min_thickness 0.25)
		(keepout
			(tracks not_allowed)
			(vias allowed)
			(pads allowed)
			(copperpour not_allowed)
			(footprints allowed)
		)
		(placement
			(enabled no)
			(sheetname "")
		)
		(fill yes
			(thermal_gap 0.5)
			(thermal_bridge_width 0.5)
			(island_removal_mode 0)
		)
		(polygon
			(pts
				(arc
					(start 194.938142 -246.63527)
					(mid 194.270122 -246.63527)
					(end 194.938142 -246.63527)
				)
			)
		)
	)
	(zone
		(layers "B.Cu" "In11.Cu" "In13.Cu" "In15.Cu")
		(hatch none 0.5)
		(connect_pads
			(clearance 0)
		)
		(min_thickness 0.25)
		(keepout
			(tracks not_allowed)
			(vias allowed)
			(pads allowed)
			(copperpour not_allowed)
			(footprints allowed)
		)
		(placement
			(enabled no)
			(sheetname "")
		)
		(fill yes
			(thermal_gap 0.5)
			(thermal_bridge_width 0.5)
			(island_removal_mode 0)
		)
		(polygon
			(pts
				(arc
					(start 25.486106 -310.385206)
					(mid 24.818086 -310.385206)
					(end 25.486106 -310.385206)
				)
			)
		)
	)
	(zone
		(layers "B.Cu" "In11.Cu" "In13.Cu" "In15.Cu")
		(hatch none 0.5)
		(connect_pads
			(clearance 0)
		)
		(min_thickness 0.25)
		(keepout
			(tracks not_allowed)
			(vias allowed)
			(pads allowed)
			(copperpour not_allowed)
			(footprints allowed)
		)
		(placement
			(enabled no)
			(sheetname "")
		)
		(fill yes
			(thermal_gap 0.5)
			(thermal_bridge_width 0.5)
			(island_removal_mode 0)
		)
		(polygon
			(pts
				(arc
					(start 389.16991 -234.764072)
					(mid 388.53999 -234.764072)
					(end 389.16991 -234.764072)
				)
			)
		)
	)
	(zone
		(layers "B.Cu" "In11.Cu" "In13.Cu" "In15.Cu")
		(hatch none 0.5)
		(connect_pads
			(clearance 0)
		)
		(min_thickness 0.25)
		(keepout
			(tracks not_allowed)
			(vias allowed)
			(pads allowed)
			(copperpour not_allowed)
			(footprints allowed)
		)
		(placement
			(enabled no)
			(sheetname "")
		)
		(fill yes
			(thermal_gap 0.5)
			(thermal_bridge_width 0.5)
			(island_removal_mode 0)
		)
		(polygon
			(pts
				(arc
					(start 389.469884 -271.656048)
					(mid 388.839964 -271.656048)
					(end 389.469884 -271.656048)
				)
			)
		)
	)
	(zone
		(layers "B.Cu" "In11.Cu" "In13.Cu" "In15.Cu")
		(hatch none 0.5)
		(connect_pads
			(clearance 0)
		)
		(min_thickness 0.25)
		(keepout
			(tracks not_allowed)
			(vias allowed)
			(pads allowed)
			(copperpour not_allowed)
			(footprints allowed)
		)
		(placement
			(enabled no)
			(sheetname "")
		)
		(fill yes
			(thermal_gap 0.5)
			(thermal_bridge_width 0.5)
			(island_removal_mode 0)
		)
		(polygon
			(pts
				(arc
					(start 141.699742 -250.15444)
					(mid 141.069822 -250.15444)
					(end 141.699742 -250.15444)
				)
			)
		)
	)
	(zone
		(layers "B.Cu" "In11.Cu" "In13.Cu" "In15.Cu")
		(hatch none 0.5)
		(connect_pads
			(clearance 0)
		)
		(min_thickness 0.25)
		(keepout
			(tracks not_allowed)
			(vias allowed)
			(pads allowed)
			(copperpour not_allowed)
			(footprints allowed)
		)
		(placement
			(enabled no)
			(sheetname "")
		)
		(fill yes
			(thermal_gap 0.5)
			(thermal_bridge_width 0.5)
			(island_removal_mode 0)
		)
		(polygon
			(pts
				(arc
					(start 102.05593 -281.376374)
					(mid 101.42601 -281.376374)
					(end 102.05593 -281.376374)
				)
			)
		)
	)
	(zone
		(layers "B.Cu" "In11.Cu" "In13.Cu" "In15.Cu")
		(hatch none 0.5)
		(connect_pads
			(clearance 0)
		)
		(min_thickness 0.25)
		(keepout
			(tracks not_allowed)
			(vias allowed)
			(pads allowed)
			(copperpour not_allowed)
			(footprints allowed)
		)
		(placement
			(enabled no)
			(sheetname "")
		)
		(fill yes
			(thermal_gap 0.5)
			(thermal_bridge_width 0.5)
			(island_removal_mode 0)
		)
		(polygon
			(pts
				(arc
					(start 364.729776 -241.24412)
					(mid 364.099856 -241.24412)
					(end 364.729776 -241.24412)
				)
			)
		)
	)
	(zone
		(layers "B.Cu" "In11.Cu" "In13.Cu" "In15.Cu")
		(hatch none 0.5)
		(connect_pads
			(clearance 0)
		)
		(min_thickness 0.25)
		(keepout
			(tracks not_allowed)
			(vias allowed)
			(pads allowed)
			(copperpour not_allowed)
			(footprints allowed)
		)
		(placement
			(enabled no)
			(sheetname "")
		)
		(fill yes
			(thermal_gap 0.5)
			(thermal_bridge_width 0.5)
			(island_removal_mode 0)
		)
		(polygon
			(pts
				(arc
					(start 65.306194 -389.467344)
					(mid 64.676274 -389.467344)
					(end 65.306194 -389.467344)
				)
			)
		)
	)
	(zone
		(layers "B.Cu" "In11.Cu" "In13.Cu" "In15.Cu")
		(hatch none 0.5)
		(connect_pads
			(clearance 0)
		)
		(min_thickness 0.25)
		(keepout
			(tracks not_allowed)
			(vias allowed)
			(pads allowed)
			(copperpour not_allowed)
			(footprints allowed)
		)
		(placement
			(enabled no)
			(sheetname "")
		)
		(fill yes
			(thermal_gap 0.5)
			(thermal_bridge_width 0.5)
			(island_removal_mode 0)
		)
		(polygon
			(pts
				(arc
					(start 83.255866 -286.23641)
					(mid 82.625946 -286.23641)
					(end 83.255866 -286.23641)
				)
			)
		)
	)
	(zone
		(layers "B.Cu" "In11.Cu" "In13.Cu" "In15.Cu")
		(hatch none 0.5)
		(connect_pads
			(clearance 0)
		)
		(min_thickness 0.25)
		(keepout
			(tracks not_allowed)
			(vias allowed)
			(pads allowed)
			(copperpour not_allowed)
			(footprints allowed)
		)
		(placement
			(enabled no)
			(sheetname "")
		)
		(fill yes
			(thermal_gap 0.5)
			(thermal_bridge_width 0.5)
			(island_removal_mode 0)
		)
		(polygon
			(pts
				(arc
					(start 25.486106 -267.03528)
					(mid 24.818086 -267.03528)
					(end 25.486106 -267.03528)
				)
			)
		)
	)
	(zone
		(layers "B.Cu" "In11.Cu" "In13.Cu" "In15.Cu")
		(hatch none 0.5)
		(connect_pads
			(clearance 0)
		)
		(min_thickness 0.25)
		(keepout
			(tracks not_allowed)
			(vias allowed)
			(pads allowed)
			(copperpour not_allowed)
			(footprints allowed)
		)
		(placement
			(enabled no)
			(sheetname "")
		)
		(fill yes
			(thermal_gap 0.5)
			(thermal_bridge_width 0.5)
			(island_removal_mode 0)
		)
		(polygon
			(pts
				(arc
					(start 141.699742 -229.094538)
					(mid 141.069822 -229.094538)
					(end 141.699742 -229.094538)
				)
			)
		)
	)
	(zone
		(layers "B.Cu" "In11.Cu" "In13.Cu" "In15.Cu")
		(hatch none 0.5)
		(connect_pads
			(clearance 0)
		)
		(min_thickness 0.25)
		(keepout
			(tracks not_allowed)
			(vias allowed)
			(pads allowed)
			(copperpour not_allowed)
			(footprints allowed)
		)
		(placement
			(enabled no)
			(sheetname "")
		)
		(fill yes
			(thermal_gap 0.5)
			(thermal_bridge_width 0.5)
			(island_removal_mode 0)
		)
		(polygon
			(pts
				(arc
					(start 194.938142 -274.685252)
					(mid 194.270122 -274.685252)
					(end 194.938142 -274.685252)
				)
			)
		)
	)
	(zone
		(layers "B.Cu" "In11.Cu" "In13.Cu" "In15.Cu")
		(hatch none 0.5)
		(connect_pads
			(clearance 0)
		)
		(min_thickness 0.25)
		(keepout
			(tracks not_allowed)
			(vias allowed)
			(pads allowed)
			(copperpour not_allowed)
			(footprints allowed)
		)
		(placement
			(enabled no)
			(sheetname "")
		)
		(fill yes
			(thermal_gap 0.5)
			(thermal_bridge_width 0.5)
			(island_removal_mode 0)
		)
		(polygon
			(pts
				(arc
					(start 194.938142 -289.98545)
					(mid 194.270122 -289.98545)
					(end 194.938142 -289.98545)
				)
			)
		)
	)
	(zone
		(layers "B.Cu" "In11.Cu" "In13.Cu" "In15.Cu")
		(hatch none 0.5)
		(connect_pads
			(clearance 0)
		)
		(min_thickness 0.25)
		(keepout
			(tracks not_allowed)
			(vias allowed)
			(pads allowed)
			(copperpour not_allowed)
			(footprints allowed)
		)
		(placement
			(enabled no)
			(sheetname "")
		)
		(fill yes
			(thermal_gap 0.5)
			(thermal_bridge_width 0.5)
			(island_removal_mode 0)
		)
		(polygon
			(pts
				(arc
					(start 368.489738 -239.624108)
					(mid 367.859818 -239.624108)
					(end 368.489738 -239.624108)
				)
			)
		)
	)
	(zone
		(layers "B.Cu" "In11.Cu" "In13.Cu" "In15.Cu")
		(hatch none 0.5)
		(connect_pads
			(clearance 0)
		)
		(min_thickness 0.25)
		(keepout
			(tracks not_allowed)
			(vias allowed)
			(pads allowed)
			(copperpour not_allowed)
			(footprints allowed)
		)
		(placement
			(enabled no)
			(sheetname "")
		)
		(fill yes
			(thermal_gap 0.5)
			(thermal_bridge_width 0.5)
			(island_removal_mode 0)
		)
		(polygon
			(pts
				(arc
					(start 334.036924 -427.089824)
					(mid 333.262732 -427.089824)
					(end 334.036924 -427.089824)
				)
			)
		)
	)
	(zone
		(layers "B.Cu" "In11.Cu" "In13.Cu" "In15.Cu")
		(hatch none 0.5)
		(connect_pads
			(clearance 0)
		)
		(min_thickness 0.25)
		(keepout
			(tracks not_allowed)
			(vias allowed)
			(pads allowed)
			(copperpour not_allowed)
			(footprints allowed)
		)
		(placement
			(enabled no)
			(sheetname "")
		)
		(fill yes
			(thermal_gap 0.5)
			(thermal_bridge_width 0.5)
			(island_removal_mode 0)
		)
		(polygon
			(pts
				(arc
					(start 25.486106 -261.935214)
					(mid 24.818086 -261.935214)
					(end 25.486106 -261.935214)
				)
			)
		)
	)
	(zone
		(layers "B.Cu" "In11.Cu" "In13.Cu" "In15.Cu")
		(hatch none 0.5)
		(connect_pads
			(clearance 0)
		)
		(min_thickness 0.25)
		(keepout
			(tracks not_allowed)
			(vias allowed)
			(pads allowed)
			(copperpour not_allowed)
			(footprints allowed)
		)
		(placement
			(enabled no)
			(sheetname "")
		)
		(fill yes
			(thermal_gap 0.5)
			(thermal_bridge_width 0.5)
			(island_removal_mode 0)
		)
		(polygon
			(pts
				(arc
					(start 59.036966 -422.489884)
					(mid 58.262774 -422.489884)
					(end 59.036966 -422.489884)
				)
			)
		)
	)
	(zone
		(layers "B.Cu" "In11.Cu" "In13.Cu" "In15.Cu")
		(hatch none 0.5)
		(connect_pads
			(clearance 0)
		)
		(min_thickness 0.25)
		(keepout
			(tracks not_allowed)
			(vias allowed)
			(pads allowed)
			(copperpour not_allowed)
			(footprints allowed)
		)
		(placement
			(enabled no)
			(sheetname "")
		)
		(fill yes
			(thermal_gap 0.5)
			(thermal_bridge_width 0.5)
			(island_removal_mode 0)
		)
		(polygon
			(pts
				(arc
					(start 330.89596 -233.14406)
					(mid 330.26604 -233.14406)
					(end 330.89596 -233.14406)
				)
			)
		)
	)
	(zone
		(layers "B.Cu" "In11.Cu" "In13.Cu" "In15.Cu")
		(hatch none 0.5)
		(connect_pads
			(clearance 0)
		)
		(min_thickness 0.25)
		(keepout
			(tracks not_allowed)
			(vias allowed)
			(pads allowed)
			(copperpour not_allowed)
			(footprints allowed)
		)
		(placement
			(enabled no)
			(sheetname "")
		)
		(fill yes
			(thermal_gap 0.5)
			(thermal_bridge_width 0.5)
			(island_removal_mode 0)
		)
		(polygon
			(pts
				(arc
					(start 273.426174 -306.985162)
					(mid 272.758154 -306.985162)
					(end 273.426174 -306.985162)
				)
			)
		)
	)
	(zone
		(layers "B.Cu" "In11.Cu" "In13.Cu" "In15.Cu")
		(hatch none 0.5)
		(connect_pads
			(clearance 0)
		)
		(min_thickness 0.25)
		(keepout
			(tracks not_allowed)
			(vias allowed)
			(pads allowed)
			(copperpour not_allowed)
			(footprints allowed)
		)
		(placement
			(enabled no)
			(sheetname "")
		)
		(fill yes
			(thermal_gap 0.5)
			(thermal_bridge_width 0.5)
			(island_removal_mode 0)
		)
		(polygon
			(pts
				(arc
					(start 336.63382 -397.156432)
					(mid 336.0039 -397.156432)
					(end 336.63382 -397.156432)
				)
			)
		)
	)
	(zone
		(layers "B.Cu" "In11.Cu" "In13.Cu" "In15.Cu")
		(hatch none 0.5)
		(connect_pads
			(clearance 0)
		)
		(min_thickness 0.25)
		(keepout
			(tracks not_allowed)
			(vias allowed)
			(pads allowed)
			(copperpour not_allowed)
			(footprints allowed)
		)
		(placement
			(enabled no)
			(sheetname "")
		)
		(fill yes
			(thermal_gap 0.5)
			(thermal_bridge_width 0.5)
			(island_removal_mode 0)
		)
		(polygon
			(pts
				(arc
					(start 297.764454 -389.88746)
					(mid 297.096434 -389.88746)
					(end 297.764454 -389.88746)
				)
			)
		)
	)
	(zone
		(layers "B.Cu" "In11.Cu" "In13.Cu" "In15.Cu")
		(hatch none 0.5)
		(connect_pads
			(clearance 0)
		)
		(min_thickness 0.25)
		(keepout
			(tracks not_allowed)
			(vias allowed)
			(pads allowed)
			(copperpour not_allowed)
			(footprints allowed)
		)
		(placement
			(enabled no)
			(sheetname "")
		)
		(fill yes
			(thermal_gap 0.5)
			(thermal_bridge_width 0.5)
			(island_removal_mode 0)
		)
		(polygon
			(pts
				(arc
					(start 91.877134 -404.46452)
					(mid 91.209114 -404.46452)
					(end 91.877134 -404.46452)
				)
			)
		)
	)
	(zone
		(layers "B.Cu" "In11.Cu" "In13.Cu" "In15.Cu")
		(hatch none 0.5)
		(connect_pads
			(clearance 0)
		)
		(min_thickness 0.25)
		(keepout
			(tracks not_allowed)
			(vias allowed)
			(pads allowed)
			(copperpour not_allowed)
			(footprints allowed)
		)
		(placement
			(enabled no)
			(sheetname "")
		)
		(fill yes
			(thermal_gap 0.5)
			(thermal_bridge_width 0.5)
			(island_removal_mode 0)
		)
		(polygon
			(pts
				(arc
					(start 273.426174 -253.435104)
					(mid 272.758154 -253.435104)
					(end 273.426174 -253.435104)
				)
			)
		)
	)
	(zone
		(layers "B.Cu" "In11.Cu" "In13.Cu" "In15.Cu")
		(hatch none 0.5)
		(connect_pads
			(clearance 0)
		)
		(min_thickness 0.25)
		(keepout
			(tracks not_allowed)
			(vias allowed)
			(pads allowed)
			(copperpour not_allowed)
			(footprints allowed)
		)
		(placement
			(enabled no)
			(sheetname "")
		)
		(fill yes
			(thermal_gap 0.5)
			(thermal_bridge_width 0.5)
			(island_removal_mode 0)
		)
		(polygon
			(pts
				(arc
					(start 391.349738 -266.796012)
					(mid 390.719818 -266.796012)
					(end 391.349738 -266.796012)
				)
			)
		)
	)
	(zone
		(layers "B.Cu" "In11.Cu" "In13.Cu" "In15.Cu")
		(hatch none 0.5)
		(connect_pads
			(clearance 0)
		)
		(min_thickness 0.25)
		(keepout
			(tracks not_allowed)
			(vias allowed)
			(pads allowed)
			(copperpour not_allowed)
			(footprints allowed)
		)
		(placement
			(enabled no)
			(sheetname "")
		)
		(fill yes
			(thermal_gap 0.5)
			(thermal_bridge_width 0.5)
			(island_removal_mode 0)
		)
		(polygon
			(pts
				(arc
					(start 73.036938 -427.089824)
					(mid 72.262746 -427.089824)
					(end 73.036938 -427.089824)
				)
			)
		)
	)
	(zone
		(layers "B.Cu" "In11.Cu" "In13.Cu" "In15.Cu")
		(hatch none 0.5)
		(connect_pads
			(clearance 0)
		)
		(min_thickness 0.25)
		(keepout
			(tracks not_allowed)
			(vias allowed)
			(pads allowed)
			(copperpour not_allowed)
			(footprints allowed)
		)
		(placement
			(enabled no)
			(sheetname "")
		)
		(fill yes
			(thermal_gap 0.5)
			(thermal_bridge_width 0.5)
			(island_removal_mode 0)
		)
		(polygon
			(pts
				(arc
					(start 29.586174 -252.58522)
					(mid 28.918154 -252.58522)
					(end 29.586174 -252.58522)
				)
			)
		)
	)
	(zone
		(layers "B.Cu" "In11.Cu" "In13.Cu" "In15.Cu")
		(hatch none 0.5)
		(connect_pads
			(clearance 0)
		)
		(min_thickness 0.25)
		(keepout
			(tracks not_allowed)
			(vias allowed)
			(pads allowed)
			(copperpour not_allowed)
			(footprints allowed)
		)
		(placement
			(enabled no)
			(sheetname "")
		)
		(fill yes
			(thermal_gap 0.5)
			(thermal_bridge_width 0.5)
			(island_removal_mode 0)
		)
		(polygon
			(pts
				(arc
					(start 194.938142 -284.035246)
					(mid 194.270122 -284.035246)
					(end 194.938142 -284.035246)
				)
			)
		)
	)
	(zone
		(layers "B.Cu" "In11.Cu" "In13.Cu" "In15.Cu")
		(hatch none 0.5)
		(connect_pads
			(clearance 0)
		)
		(min_thickness 0.25)
		(keepout
			(tracks not_allowed)
			(vias allowed)
			(pads allowed)
			(copperpour not_allowed)
			(footprints allowed)
		)
		(placement
			(enabled no)
			(sheetname "")
		)
		(fill yes
			(thermal_gap 0.5)
			(thermal_bridge_width 0.5)
			(island_removal_mode 0)
		)
		(polygon
			(pts
				(arc
					(start 81.376012 -266.796266)
					(mid 80.746092 -266.796266)
					(end 81.376012 -266.796266)
				)
			)
		)
	)
	(zone
		(layers "B.Cu" "In11.Cu" "In13.Cu" "In15.Cu")
		(hatch none 0.5)
		(connect_pads
			(clearance 0)
		)
		(min_thickness 0.25)
		(keepout
			(tracks not_allowed)
			(vias allowed)
			(pads allowed)
			(copperpour not_allowed)
			(footprints allowed)
		)
		(placement
			(enabled no)
			(sheetname "")
		)
		(fill yes
			(thermal_gap 0.5)
			(thermal_bridge_width 0.5)
			(island_removal_mode 0)
		)
		(polygon
			(pts
				(arc
					(start 314.665106 -377.41733)
					(mid 313.997086 -377.41733)
					(end 314.665106 -377.41733)
				)
			)
		)
	)
	(zone
		(layers "B.Cu" "In11.Cu" "In13.Cu" "In15.Cu")
		(hatch none 0.5)
		(connect_pads
			(clearance 0)
		)
		(min_thickness 0.25)
		(keepout
			(tracks not_allowed)
			(vias allowed)
			(pads allowed)
			(copperpour not_allowed)
			(footprints allowed)
		)
		(placement
			(enabled no)
			(sheetname "")
		)
		(fill yes
			(thermal_gap 0.5)
			(thermal_bridge_width 0.5)
			(island_removal_mode 0)
		)
		(polygon
			(pts
				(arc
					(start 99.236022 -282.996386)
					(mid 98.606102 -282.996386)
					(end 99.236022 -282.996386)
				)
			)
		)
	)
	(zone
		(layers "B.Cu" "In11.Cu" "In13.Cu" "In15.Cu")
		(hatch none 0.5)
		(connect_pads
			(clearance 0)
		)
		(min_thickness 0.25)
		(keepout
			(tracks not_allowed)
			(vias allowed)
			(pads allowed)
			(copperpour not_allowed)
			(footprints allowed)
		)
		(placement
			(enabled no)
			(sheetname "")
		)
		(fill yes
			(thermal_gap 0.5)
			(thermal_bridge_width 0.5)
			(island_removal_mode 0)
		)
		(polygon
			(pts
				(arc
					(start 273.426174 -268.735048)
					(mid 272.758154 -268.735048)
					(end 273.426174 -268.735048)
				)
			)
		)
	)
	(zone
		(layers "B.Cu" "In11.Cu" "In13.Cu" "In15.Cu")
		(hatch none 0.5)
		(connect_pads
			(clearance 0)
		)
		(min_thickness 0.25)
		(keepout
			(tracks not_allowed)
			(vias allowed)
			(pads allowed)
			(copperpour not_allowed)
			(footprints allowed)
		)
		(placement
			(enabled no)
			(sheetname "")
		)
		(fill yes
			(thermal_gap 0.5)
			(thermal_bridge_width 0.5)
			(island_removal_mode 0)
		)
		(polygon
			(pts
				(arc
					(start 127.206248 -388.774432)
					(mid 126.576328 -388.774432)
					(end 127.206248 -388.774432)
				)
			)
		)
	)
	(zone
		(layers "B.Cu" "In11.Cu" "In13.Cu" "In15.Cu")
		(hatch none 0.5)
		(connect_pads
			(clearance 0)
		)
		(min_thickness 0.25)
		(keepout
			(tracks not_allowed)
			(vias allowed)
			(pads allowed)
			(copperpour not_allowed)
			(footprints allowed)
		)
		(placement
			(enabled no)
			(sheetname "")
		)
		(fill yes
			(thermal_gap 0.5)
			(thermal_bridge_width 0.5)
			(island_removal_mode 0)
		)
		(polygon
			(pts
				(arc
					(start 389.16991 -246.104156)
					(mid 388.53999 -246.104156)
					(end 389.16991 -246.104156)
				)
			)
		)
	)
	(zone
		(layers "B.Cu" "In11.Cu" "In13.Cu" "In15.Cu")
		(hatch none 0.5)
		(connect_pads
			(clearance 0)
		)
		(min_thickness 0.25)
		(keepout
			(tracks not_allowed)
			(vias allowed)
			(pads allowed)
			(copperpour not_allowed)
			(footprints allowed)
		)
		(placement
			(enabled no)
			(sheetname "")
		)
		(fill yes
			(thermal_gap 0.5)
			(thermal_bridge_width 0.5)
			(island_removal_mode 0)
		)
		(polygon
			(pts
				(arc
					(start 194.938142 -310.385206)
					(mid 194.270122 -310.385206)
					(end 194.938142 -310.385206)
				)
			)
		)
	)
	(zone
		(layers "B.Cu" "In11.Cu" "In13.Cu" "In15.Cu")
		(hatch none 0.5)
		(connect_pads
			(clearance 0)
		)
		(min_thickness 0.25)
		(keepout
			(tracks not_allowed)
			(vias allowed)
			(pads allowed)
			(copperpour not_allowed)
			(footprints allowed)
		)
		(placement
			(enabled no)
			(sheetname "")
		)
		(fill yes
			(thermal_gap 0.5)
			(thermal_bridge_width 0.5)
			(island_removal_mode 0)
		)
		(polygon
			(pts
				(arc
					(start 273.426174 -209.23504)
					(mid 272.758154 -209.23504)
					(end 273.426174 -209.23504)
				)
			)
		)
	)
	(zone
		(layers "B.Cu" "In11.Cu" "In13.Cu" "In15.Cu")
		(hatch none 0.5)
		(connect_pads
			(clearance 0)
		)
		(min_thickness 0.25)
		(keepout
			(tracks not_allowed)
			(vias allowed)
			(pads allowed)
			(copperpour not_allowed)
			(footprints allowed)
		)
		(placement
			(enabled no)
			(sheetname "")
		)
		(fill yes
			(thermal_gap 0.5)
			(thermal_bridge_width 0.5)
			(island_removal_mode 0)
		)
		(polygon
			(pts
				(arc
					(start 391.349738 -273.27606)
					(mid 390.719818 -273.27606)
					(end 391.349738 -273.27606)
				)
			)
		)
	)
	(zone
		(layers "B.Cu" "In11.Cu" "In13.Cu" "In15.Cu")
		(hatch none 0.5)
		(connect_pads
			(clearance 0)
		)
		(min_thickness 0.25)
		(keepout
			(tracks not_allowed)
			(vias allowed)
			(pads allowed)
			(copperpour not_allowed)
			(footprints allowed)
		)
		(placement
			(enabled no)
			(sheetname "")
		)
		(fill yes
			(thermal_gap 0.5)
			(thermal_bridge_width 0.5)
			(island_removal_mode 0)
		)
		(polygon
			(pts
				(arc
					(start 141.529816 -278.13635)
					(mid 140.899896 -278.13635)
					(end 141.529816 -278.13635)
				)
			)
		)
	)
	(zone
		(layers "B.Cu" "In11.Cu" "In13.Cu" "In15.Cu")
		(hatch none 0.5)
		(connect_pads
			(clearance 0)
		)
		(min_thickness 0.25)
		(keepout
			(tracks not_allowed)
			(vias allowed)
			(pads allowed)
			(copperpour not_allowed)
			(footprints allowed)
		)
		(placement
			(enabled no)
			(sheetname "")
		)
		(fill yes
			(thermal_gap 0.5)
			(thermal_bridge_width 0.5)
			(island_removal_mode 0)
		)
		(polygon
			(pts
				(arc
					(start 389.16991 -249.34418)
					(mid 388.53999 -249.34418)
					(end 389.16991 -249.34418)
				)
			)
		)
	)
	(zone
		(layers "B.Cu" "In11.Cu" "In13.Cu" "In15.Cu")
		(hatch none 0.5)
		(connect_pads
			(clearance 0)
		)
		(min_thickness 0.25)
		(keepout
			(tracks not_allowed)
			(vias allowed)
			(pads allowed)
			(copperpour not_allowed)
			(footprints allowed)
		)
		(placement
			(enabled no)
			(sheetname "")
		)
		(fill yes
			(thermal_gap 0.5)
			(thermal_bridge_width 0.5)
			(island_removal_mode 0)
		)
		(polygon
			(pts
				(arc
					(start 141.699742 -242.05438)
					(mid 141.069822 -242.05438)
					(end 141.699742 -242.05438)
				)
			)
		)
	)
	(zone
		(layers "B.Cu" "In11.Cu" "In13.Cu" "In15.Cu")
		(hatch none 0.5)
		(connect_pads
			(clearance 0)
		)
		(min_thickness 0.25)
		(keepout
			(tracks not_allowed)
			(vias allowed)
			(pads allowed)
			(copperpour not_allowed)
			(footprints allowed)
		)
		(placement
			(enabled no)
			(sheetname "")
		)
		(fill yes
			(thermal_gap 0.5)
			(thermal_bridge_width 0.5)
			(island_removal_mode 0)
		)
		(polygon
			(pts
				(arc
					(start 368.789712 -282.996132)
					(mid 368.159792 -282.996132)
					(end 368.789712 -282.996132)
				)
			)
		)
	)
	(zone
		(layers "B.Cu" "In13.Cu" "In15.Cu")
		(hatch none 0.5)
		(connect_pads
			(clearance 0)
		)
		(min_thickness 0.25)
		(keepout
			(tracks not_allowed)
			(vias allowed)
			(pads allowed)
			(copperpour not_allowed)
			(footprints allowed)
		)
		(placement
			(enabled no)
			(sheetname "")
		)
		(fill yes
			(thermal_gap 0.5)
			(thermal_bridge_width 0.5)
			(island_removal_mode 0)
		)
		(polygon
			(pts
				(arc
					(start 206.58201 -229.635304)
					(mid 205.91399 -229.635304)
					(end 206.58201 -229.635304)
				)
			)
		)
	)
	(zone
		(layers "B.Cu" "In13.Cu" "In15.Cu")
		(hatch none 0.5)
		(connect_pads
			(clearance 0)
		)
		(min_thickness 0.25)
		(keepout
			(tracks not_allowed)
			(vias allowed)
			(pads allowed)
			(copperpour not_allowed)
			(footprints allowed)
		)
		(placement
			(enabled no)
			(sheetname "")
		)
		(fill yes
			(thermal_gap 0.5)
			(thermal_bridge_width 0.5)
			(island_removal_mode 0)
		)
		(polygon
			(pts
				(arc
					(start 138.136884 -430.889918)
					(mid 137.362692 -430.889918)
					(end 138.136884 -430.889918)
				)
			)
		)
	)
	(zone
		(layers "B.Cu" "In13.Cu" "In15.Cu")
		(hatch none 0.5)
		(connect_pads
			(clearance 0)
		)
		(min_thickness 0.25)
		(keepout
			(tracks not_allowed)
			(vias allowed)
			(pads allowed)
			(copperpour not_allowed)
			(footprints allowed)
		)
		(placement
			(enabled no)
			(sheetname "")
		)
		(fill yes
			(thermal_gap 0.5)
			(thermal_bridge_width 0.5)
			(island_removal_mode 0)
		)
		(polygon
			(pts
				(arc
					(start 388.136892 -431.889916)
					(mid 387.3627 -431.889916)
					(end 388.136892 -431.889916)
				)
			)
		)
	)
	(zone
		(layers "B.Cu" "In13.Cu" "In15.Cu")
		(hatch none 0.5)
		(connect_pads
			(clearance 0)
		)
		(min_thickness 0.25)
		(keepout
			(tracks not_allowed)
			(vias allowed)
			(pads allowed)
			(copperpour not_allowed)
			(footprints allowed)
		)
		(placement
			(enabled no)
			(sheetname "")
		)
		(fill yes
			(thermal_gap 0.5)
			(thermal_bridge_width 0.5)
			(island_removal_mode 0)
		)
		(polygon
			(pts
				(arc
					(start 349.995998 -278.136096)
					(mid 349.366078 -278.136096)
					(end 349.995998 -278.136096)
				)
			)
		)
	)
	(zone
		(layers "B.Cu" "In13.Cu" "In15.Cu")
		(hatch none 0.5)
		(connect_pads
			(clearance 0)
		)
		(min_thickness 0.25)
		(keepout
			(tracks not_allowed)
			(vias allowed)
			(pads allowed)
			(copperpour not_allowed)
			(footprints allowed)
		)
		(placement
			(enabled no)
			(sheetname "")
		)
		(fill yes
			(thermal_gap 0.5)
			(thermal_bridge_width 0.5)
			(island_removal_mode 0)
		)
		(polygon
			(pts
				(arc
					(start 141.43228 -28.499562)
					(mid 140.76426 -28.499562)
					(end 141.43228 -28.499562)
				)
			)
		)
	)
	(zone
		(layers "B.Cu" "In13.Cu" "In15.Cu")
		(hatch none 0.5)
		(connect_pads
			(clearance 0)
		)
		(min_thickness 0.25)
		(keepout
			(tracks not_allowed)
			(vias allowed)
			(pads allowed)
			(copperpour not_allowed)
			(footprints allowed)
		)
		(placement
			(enabled no)
			(sheetname "")
		)
		(fill yes
			(thermal_gap 0.5)
			(thermal_bridge_width 0.5)
			(island_removal_mode 0)
		)
		(polygon
			(pts
				(arc
					(start 354.696014 -276.516084)
					(mid 354.066094 -276.516084)
					(end 354.696014 -276.516084)
				)
			)
		)
	)
	(zone
		(layers "B.Cu" "In13.Cu" "In15.Cu")
		(hatch none 0.5)
		(connect_pads
			(clearance 0)
		)
		(min_thickness 0.25)
		(keepout
			(tracks not_allowed)
			(vias allowed)
			(pads allowed)
			(copperpour not_allowed)
			(footprints allowed)
		)
		(placement
			(enabled no)
			(sheetname "")
		)
		(fill yes
			(thermal_gap 0.5)
			(thermal_bridge_width 0.5)
			(island_removal_mode 0)
		)
		(polygon
			(pts
				(arc
					(start 17.942052 -224.535238)
					(mid 17.274032 -224.535238)
					(end 17.942052 -224.535238)
				)
			)
		)
	)
	(zone
		(layers "B.Cu" "In13.Cu" "In15.Cu")
		(hatch none 0.5)
		(connect_pads
			(clearance 0)
		)
		(min_thickness 0.25)
		(keepout
			(tracks not_allowed)
			(vias allowed)
			(pads allowed)
			(copperpour not_allowed)
			(footprints allowed)
		)
		(placement
			(enabled no)
			(sheetname "")
		)
		(fill yes
			(thermal_gap 0.5)
			(thermal_bridge_width 0.5)
			(island_removal_mode 0)
		)
		(polygon
			(pts
				(arc
					(start 48.128174 -412.570168)
					(mid 47.460154 -412.570168)
					(end 48.128174 -412.570168)
				)
			)
		)
	)
	(zone
		(layers "B.Cu" "In13.Cu" "In15.Cu")
		(hatch none 0.5)
		(connect_pads
			(clearance 0)
		)
		(min_thickness 0.25)
		(keepout
			(tracks not_allowed)
			(vias allowed)
			(pads allowed)
			(copperpour not_allowed)
			(footprints allowed)
		)
		(placement
			(enabled no)
			(sheetname "")
		)
		(fill yes
			(thermal_gap 0.5)
			(thermal_bridge_width 0.5)
			(island_removal_mode 0)
		)
		(polygon
			(pts
				(arc
					(start 387.289802 -238.004096)
					(mid 386.659882 -238.004096)
					(end 387.289802 -238.004096)
				)
			)
		)
	)
	(zone
		(layers "B.Cu" "In13.Cu" "In15.Cu")
		(hatch none 0.5)
		(connect_pads
			(clearance 0)
		)
		(min_thickness 0.25)
		(keepout
			(tracks not_allowed)
			(vias allowed)
			(pads allowed)
			(copperpour not_allowed)
			(footprints allowed)
		)
		(placement
			(enabled no)
			(sheetname "")
		)
		(fill yes
			(thermal_gap 0.5)
			(thermal_bridge_width 0.5)
			(island_removal_mode 0)
		)
		(polygon
			(pts
				(arc
					(start 109.105954 -275.706332)
					(mid 108.476034 -275.706332)
					(end 109.105954 -275.706332)
				)
			)
		)
	)
	(zone
		(layers "B.Cu" "In13.Cu" "In15.Cu")
		(hatch none 0.5)
		(connect_pads
			(clearance 0)
		)
		(min_thickness 0.25)
		(keepout
			(tracks not_allowed)
			(vias allowed)
			(pads allowed)
			(copperpour not_allowed)
			(footprints allowed)
		)
		(placement
			(enabled no)
			(sheetname "")
		)
		(fill yes
			(thermal_gap 0.5)
			(thermal_bridge_width 0.5)
			(island_removal_mode 0)
		)
		(polygon
			(pts
				(arc
					(start 84.63407 -389.467344)
					(mid 84.00415 -389.467344)
					(end 84.63407 -389.467344)
				)
			)
		)
	)
	(zone
		(layers "B.Cu" "In13.Cu" "In15.Cu")
		(hatch none 0.5)
		(connect_pads
			(clearance 0)
		)
		(min_thickness 0.25)
		(keepout
			(tracks not_allowed)
			(vias allowed)
			(pads allowed)
			(copperpour not_allowed)
			(footprints allowed)
		)
		(placement
			(enabled no)
			(sheetname "")
		)
		(fill yes
			(thermal_gap 0.5)
			(thermal_bridge_width 0.5)
			(island_removal_mode 0)
		)
		(polygon
			(pts
				(arc
					(start 139.349734 -246.10441)
					(mid 138.719814 -246.10441)
					(end 139.349734 -246.10441)
				)
			)
		)
	)
	(zone
		(layers "B.Cu" "In13.Cu" "In15.Cu")
		(hatch none 0.5)
		(connect_pads
			(clearance 0)
		)
		(min_thickness 0.25)
		(keepout
			(tracks not_allowed)
			(vias allowed)
			(pads allowed)
			(copperpour not_allowed)
			(footprints allowed)
		)
		(placement
			(enabled no)
			(sheetname "")
		)
		(fill yes
			(thermal_gap 0.5)
			(thermal_bridge_width 0.5)
			(island_removal_mode 0)
		)
		(polygon
			(pts
				(arc
					(start 346.6338 -394.385292)
					(mid 346.00388 -394.385292)
					(end 346.6338 -394.385292)
				)
			)
		)
	)
	(zone
		(layers "B.Cu" "In13.Cu" "In15.Cu")
		(hatch none 0.5)
		(connect_pads
			(clearance 0)
		)
		(min_thickness 0.25)
		(keepout
			(tracks not_allowed)
			(vias allowed)
			(pads allowed)
			(copperpour not_allowed)
			(footprints allowed)
		)
		(placement
			(enabled no)
			(sheetname "")
		)
		(fill yes
			(thermal_gap 0.5)
			(thermal_bridge_width 0.5)
			(island_removal_mode 0)
		)
		(polygon
			(pts
				(arc
					(start 84.836 -246.10441)
					(mid 84.20608 -246.10441)
					(end 84.836 -246.10441)
				)
			)
		)
	)
	(zone
		(layers "B.Cu" "In13.Cu" "In15.Cu")
		(hatch none 0.5)
		(connect_pads
			(clearance 0)
		)
		(min_thickness 0.25)
		(keepout
			(tracks not_allowed)
			(vias allowed)
			(pads allowed)
			(copperpour not_allowed)
			(footprints allowed)
		)
		(placement
			(enabled no)
			(sheetname "")
		)
		(fill yes
			(thermal_gap 0.5)
			(thermal_bridge_width 0.5)
			(island_removal_mode 0)
		)
		(polygon
			(pts
				(arc
					(start 365.66983 -246.104156)
					(mid 365.03991 -246.104156)
					(end 365.66983 -246.104156)
				)
			)
		)
	)
	(zone
		(layers "B.Cu" "In13.Cu" "In15.Cu")
		(hatch none 0.5)
		(connect_pads
			(clearance 0)
		)
		(min_thickness 0.25)
		(keepout
			(tracks not_allowed)
			(vias allowed)
			(pads allowed)
			(copperpour not_allowed)
			(footprints allowed)
		)
		(placement
			(enabled no)
			(sheetname "")
		)
		(fill yes
			(thermal_gap 0.5)
			(thermal_bridge_width 0.5)
			(island_removal_mode 0)
		)
		(polygon
			(pts
				(arc
					(start 123.669806 -274.896326)
					(mid 123.039886 -274.896326)
					(end 123.669806 -274.896326)
				)
			)
		)
	)
	(zone
		(layers "B.Cu" "In13.Cu" "In15.Cu")
		(hatch none 0.5)
		(connect_pads
			(clearance 0)
		)
		(min_thickness 0.25)
		(keepout
			(tracks not_allowed)
			(vias allowed)
			(pads allowed)
			(copperpour not_allowed)
			(footprints allowed)
		)
		(placement
			(enabled no)
			(sheetname "")
		)
		(fill yes
			(thermal_gap 0.5)
			(thermal_bridge_width 0.5)
			(island_removal_mode 0)
		)
		(polygon
			(pts
				(arc
					(start 206.58201 -290.835334)
					(mid 205.91399 -290.835334)
					(end 206.58201 -290.835334)
				)
			)
		)
	)
	(zone
		(layers "B.Cu" "In13.Cu" "In15.Cu")
		(hatch none 0.5)
		(connect_pads
			(clearance 0)
		)
		(min_thickness 0.25)
		(keepout
			(tracks not_allowed)
			(vias allowed)
			(pads allowed)
			(copperpour not_allowed)
			(footprints allowed)
		)
		(placement
			(enabled no)
			(sheetname "")
		)
		(fill yes
			(thermal_gap 0.5)
			(thermal_bridge_width 0.5)
			(island_removal_mode 0)
		)
		(polygon
			(pts
				(arc
					(start 152.850596 -412.570168)
					(mid 152.182576 -412.570168)
					(end 152.850596 -412.570168)
				)
			)
		)
	)
	(zone
		(layers "B.Cu" "In13.Cu" "In15.Cu")
		(hatch none 0.5)
		(connect_pads
			(clearance 0)
		)
		(min_thickness 0.25)
		(keepout
			(tracks not_allowed)
			(vias allowed)
			(pads allowed)
			(copperpour not_allowed)
			(footprints allowed)
		)
		(placement
			(enabled no)
			(sheetname "")
		)
		(fill yes
			(thermal_gap 0.5)
			(thermal_bridge_width 0.5)
			(island_removal_mode 0)
		)
		(polygon
			(pts
				(arc
					(start 17.942052 -318.035432)
					(mid 17.274032 -318.035432)
					(end 17.942052 -318.035432)
				)
			)
		)
	)
	(zone
		(layers "B.Cu" "In13.Cu" "In15.Cu")
		(hatch none 0.5)
		(connect_pads
			(clearance 0)
		)
		(min_thickness 0.25)
		(keepout
			(tracks not_allowed)
			(vias allowed)
			(pads allowed)
			(copperpour not_allowed)
			(footprints allowed)
		)
		(placement
			(enabled no)
			(sheetname "")
		)
		(fill yes
			(thermal_gap 0.5)
			(thermal_bridge_width 0.5)
			(island_removal_mode 0)
		)
		(polygon
			(pts
				(arc
					(start 138.40968 -242.864386)
					(mid 137.77976 -242.864386)
					(end 138.40968 -242.864386)
				)
			)
		)
	)
	(zone
		(layers "B.Cu" "In13.Cu" "In15.Cu")
		(hatch none 0.5)
		(connect_pads
			(clearance 0)
		)
		(min_thickness 0.25)
		(keepout
			(tracks not_allowed)
			(vias allowed)
			(pads allowed)
			(copperpour not_allowed)
			(footprints allowed)
		)
		(placement
			(enabled no)
			(sheetname "")
		)
		(fill yes
			(thermal_gap 0.5)
			(thermal_bridge_width 0.5)
			(island_removal_mode 0)
		)
		(polygon
			(pts
				(arc
					(start 84.836 -247.724422)
					(mid 84.20608 -247.724422)
					(end 84.836 -247.724422)
				)
			)
		)
	)
	(zone
		(layers "B.Cu" "In13.Cu" "In15.Cu")
		(hatch none 0.5)
		(connect_pads
			(clearance 0)
		)
		(min_thickness 0.25)
		(keepout
			(tracks not_allowed)
			(vias allowed)
			(pads allowed)
			(copperpour not_allowed)
			(footprints allowed)
		)
		(placement
			(enabled no)
			(sheetname "")
		)
		(fill yes
			(thermal_gap 0.5)
			(thermal_bridge_width 0.5)
			(island_removal_mode 0)
		)
		(polygon
			(pts
				(arc
					(start 392.136884 -430.689766)
					(mid 391.362692 -430.689766)
					(end 392.136884 -430.689766)
				)
			)
		)
	)
	(zone
		(layers "B.Cu" "In13.Cu" "In15.Cu")
		(hatch none 0.5)
		(connect_pads
			(clearance 0)
		)
		(min_thickness 0.25)
		(keepout
			(tracks not_allowed)
			(vias allowed)
			(pads allowed)
			(copperpour not_allowed)
			(footprints allowed)
		)
		(placement
			(enabled no)
			(sheetname "")
		)
		(fill yes
			(thermal_gap 0.5)
			(thermal_bridge_width 0.5)
			(island_removal_mode 0)
		)
		(polygon
			(pts
				(arc
					(start 81.833974 -385.31038)
					(mid 81.204054 -385.31038)
					(end 81.833974 -385.31038)
				)
			)
		)
	)
	(zone
		(layers "B.Cu" "In13.Cu" "In15.Cu")
		(hatch none 0.5)
		(connect_pads
			(clearance 0)
		)
		(min_thickness 0.25)
		(keepout
			(tracks not_allowed)
			(vias allowed)
			(pads allowed)
			(copperpour not_allowed)
			(footprints allowed)
		)
		(placement
			(enabled no)
			(sheetname "")
		)
		(fill yes
			(thermal_gap 0.5)
			(thermal_bridge_width 0.5)
			(island_removal_mode 0)
		)
		(polygon
			(pts
				(arc
					(start 22.04212 -292.535356)
					(mid 21.3741 -292.535356)
					(end 22.04212 -292.535356)
				)
			)
		)
	)
	(zone
		(layers "B.Cu" "In13.Cu" "In15.Cu")
		(hatch none 0.5)
		(connect_pads
			(clearance 0)
		)
		(min_thickness 0.25)
		(keepout
			(tracks not_allowed)
			(vias allowed)
			(pads allowed)
			(copperpour not_allowed)
			(footprints allowed)
		)
		(placement
			(enabled no)
			(sheetname "")
		)
		(fill yes
			(thermal_gap 0.5)
			(thermal_bridge_width 0.5)
			(island_removal_mode 0)
		)
		(polygon
			(pts
				(arc
					(start 374.429782 -278.136096)
					(mid 373.799862 -278.136096)
					(end 374.429782 -278.136096)
				)
			)
		)
	)
	(zone
		(layers "B.Cu" "In13.Cu" "In15.Cu")
		(hatch none 0.5)
		(connect_pads
			(clearance 0)
		)
		(min_thickness 0.25)
		(keepout
			(tracks not_allowed)
			(vias allowed)
			(pads allowed)
			(copperpour not_allowed)
			(footprints allowed)
		)
		(placement
			(enabled no)
			(sheetname "")
		)
		(fill yes
			(thermal_gap 0.5)
			(thermal_bridge_width 0.5)
			(island_removal_mode 0)
		)
		(polygon
			(pts
				(arc
					(start 120.54967 -231.524302)
					(mid 119.91975 -231.524302)
					(end 120.54967 -231.524302)
				)
			)
		)
	)
	(zone
		(layers "B.Cu" "In13.Cu" "In15.Cu")
		(hatch none 0.5)
		(connect_pads
			(clearance 0)
		)
		(min_thickness 0.25)
		(keepout
			(tracks not_allowed)
			(vias allowed)
			(pads allowed)
			(copperpour not_allowed)
			(footprints allowed)
		)
		(placement
			(enabled no)
			(sheetname "")
		)
		(fill yes
			(thermal_gap 0.5)
			(thermal_bridge_width 0.5)
			(island_removal_mode 0)
		)
		(polygon
			(pts
				(arc
					(start 407.986992 -420.952168)
					(mid 407.318972 -420.952168)
					(end 407.986992 -420.952168)
				)
			)
		)
	)
	(zone
		(layers "B.Cu" "In13.Cu" "In15.Cu")
		(hatch none 0.5)
		(connect_pads
			(clearance 0)
		)
		(min_thickness 0.25)
		(keepout
			(tracks not_allowed)
			(vias allowed)
			(pads allowed)
			(copperpour not_allowed)
			(footprints allowed)
		)
		(placement
			(enabled no)
			(sheetname "")
		)
		(fill yes
			(thermal_gap 0.5)
			(thermal_bridge_width 0.5)
			(island_removal_mode 0)
		)
		(polygon
			(pts
				(arc
					(start 84.3661 -238.814356)
					(mid 83.73618 -238.814356)
					(end 84.3661 -238.814356)
				)
			)
		)
	)
	(zone
		(layers "B.Cu" "In13.Cu" "In15.Cu")
		(hatch none 0.5)
		(connect_pads
			(clearance 0)
		)
		(min_thickness 0.25)
		(keepout
			(tracks not_allowed)
			(vias allowed)
			(pads allowed)
			(copperpour not_allowed)
			(footprints allowed)
		)
		(placement
			(enabled no)
			(sheetname "")
		)
		(fill yes
			(thermal_gap 0.5)
			(thermal_bridge_width 0.5)
			(island_removal_mode 0)
		)
		(polygon
			(pts
				(arc
					(start 202.481942 -278.935434)
					(mid 201.813922 -278.935434)
					(end 202.481942 -278.935434)
				)
			)
		)
	)
	(zone
		(layers "B.Cu" "In13.Cu" "In15.Cu")
		(hatch none 0.5)
		(connect_pads
			(clearance 0)
		)
		(min_thickness 0.25)
		(keepout
			(tracks not_allowed)
			(vias allowed)
			(pads allowed)
			(copperpour not_allowed)
			(footprints allowed)
		)
		(placement
			(enabled no)
			(sheetname "")
		)
		(fill yes
			(thermal_gap 0.5)
			(thermal_bridge_width 0.5)
			(island_removal_mode 0)
		)
		(polygon
			(pts
				(arc
					(start 386.649722 -265.176)
					(mid 386.019802 -265.176)
					(end 386.649722 -265.176)
				)
			)
		)
	)
	(zone
		(layers "B.Cu" "In13.Cu" "In15.Cu")
		(hatch none 0.5)
		(connect_pads
			(clearance 0)
		)
		(min_thickness 0.25)
		(keepout
			(tracks not_allowed)
			(vias allowed)
			(pads allowed)
			(copperpour not_allowed)
			(footprints allowed)
		)
		(placement
			(enabled no)
			(sheetname "")
		)
		(fill yes
			(thermal_gap 0.5)
			(thermal_bridge_width 0.5)
			(island_removal_mode 0)
		)
		(polygon
			(pts
				(arc
					(start 202.481942 -244.935248)
					(mid 201.813922 -244.935248)
					(end 202.481942 -244.935248)
				)
			)
		)
	)
	(zone
		(layers "B.Cu" "In13.Cu" "In15.Cu")
		(hatch none 0.5)
		(connect_pads
			(clearance 0)
		)
		(min_thickness 0.25)
		(keepout
			(tracks not_allowed)
			(vias allowed)
			(pads allowed)
			(copperpour not_allowed)
			(footprints allowed)
		)
		(placement
			(enabled no)
			(sheetname "")
		)
		(fill yes
			(thermal_gap 0.5)
			(thermal_bridge_width 0.5)
			(island_removal_mode 0)
		)
		(polygon
			(pts
				(arc
					(start 114.739674 -277.326344)
					(mid 114.109754 -277.326344)
					(end 114.739674 -277.326344)
				)
			)
		)
	)
	(zone
		(layers "B.Cu" "In13.Cu" "In15.Cu")
		(hatch none 0.5)
		(connect_pads
			(clearance 0)
		)
		(min_thickness 0.25)
		(keepout
			(tracks not_allowed)
			(vias allowed)
			(pads allowed)
			(copperpour not_allowed)
			(footprints allowed)
		)
		(placement
			(enabled no)
			(sheetname "")
		)
		(fill yes
			(thermal_gap 0.5)
			(thermal_bridge_width 0.5)
			(island_removal_mode 0)
		)
		(polygon
			(pts
				(arc
					(start 137.93978 -227.474526)
					(mid 137.30986 -227.474526)
					(end 137.93978 -227.474526)
				)
			)
		)
	)
	(zone
		(layers "B.Cu" "In13.Cu" "In15.Cu")
		(hatch none 0.5)
		(connect_pads
			(clearance 0)
		)
		(min_thickness 0.25)
		(keepout
			(tracks not_allowed)
			(vias allowed)
			(pads allowed)
			(copperpour not_allowed)
			(footprints allowed)
		)
		(placement
			(enabled no)
			(sheetname "")
		)
		(fill yes
			(thermal_gap 0.5)
			(thermal_bridge_width 0.5)
			(island_removal_mode 0)
		)
		(polygon
			(pts
				(arc
					(start 95.0341 -388.774432)
					(mid 94.40418 -388.774432)
					(end 95.0341 -388.774432)
				)
			)
		)
	)
	(zone
		(layers "B.Cu" "In13.Cu" "In15.Cu")
		(hatch none 0.5)
		(connect_pads
			(clearance 0)
		)
		(min_thickness 0.25)
		(keepout
			(tracks not_allowed)
			(vias allowed)
			(pads allowed)
			(copperpour not_allowed)
			(footprints allowed)
		)
		(placement
			(enabled no)
			(sheetname "")
		)
		(fill yes
			(thermal_gap 0.5)
			(thermal_bridge_width 0.5)
			(island_removal_mode 0)
		)
		(polygon
			(pts
				(arc
					(start 17.942052 -226.23526)
					(mid 17.274032 -226.23526)
					(end 17.942052 -226.23526)
				)
			)
		)
	)
	(zone
		(layers "B.Cu" "In13.Cu" "In15.Cu")
		(hatch none 0.5)
		(connect_pads
			(clearance 0)
		)
		(min_thickness 0.25)
		(keepout
			(tracks not_allowed)
			(vias allowed)
			(pads allowed)
			(copperpour not_allowed)
			(footprints allowed)
		)
		(placement
			(enabled no)
			(sheetname "")
		)
		(fill yes
			(thermal_gap 0.5)
			(thermal_bridge_width 0.5)
			(island_removal_mode 0)
		)
		(polygon
			(pts
				(arc
					(start 332.606142 -293.525956)
					(mid 331.976222 -293.525956)
					(end 332.606142 -293.525956)
				)
			)
		)
	)
	(zone
		(layers "B.Cu" "In13.Cu" "In15.Cu")
		(hatch none 0.5)
		(connect_pads
			(clearance 0)
		)
		(min_thickness 0.25)
		(keepout
			(tracks not_allowed)
			(vias allowed)
			(pads allowed)
			(copperpour not_allowed)
			(footprints allowed)
		)
		(placement
			(enabled no)
			(sheetname "")
		)
		(fill yes
			(thermal_gap 0.5)
			(thermal_bridge_width 0.5)
			(island_removal_mode 0)
		)
		(polygon
			(pts
				(arc
					(start 84.666074 -270.846296)
					(mid 84.036154 -270.846296)
					(end 84.666074 -270.846296)
				)
			)
		)
	)
	(zone
		(layers "B.Cu" "In13.Cu" "In15.Cu")
		(hatch none 0.5)
		(connect_pads
			(clearance 0)
		)
		(min_thickness 0.25)
		(keepout
			(tracks not_allowed)
			(vias allowed)
			(pads allowed)
			(copperpour not_allowed)
			(footprints allowed)
		)
		(placement
			(enabled no)
			(sheetname "")
		)
		(fill yes
			(thermal_gap 0.5)
			(thermal_bridge_width 0.5)
			(island_removal_mode 0)
		)
		(polygon
			(pts
				(arc
					(start 392.839702 -377.41733)
					(mid 392.171682 -377.41733)
					(end 392.839702 -377.41733)
				)
			)
		)
	)
	(zone
		(layers "B.Cu" "In13.Cu" "In15.Cu")
		(hatch none 0.5)
		(connect_pads
			(clearance 0)
		)
		(min_thickness 0.25)
		(keepout
			(tracks not_allowed)
			(vias allowed)
			(pads allowed)
			(copperpour not_allowed)
			(footprints allowed)
		)
		(placement
			(enabled no)
			(sheetname "")
		)
		(fill yes
			(thermal_gap 0.5)
			(thermal_bridge_width 0.5)
			(island_removal_mode 0)
		)
		(polygon
			(pts
				(arc
					(start 22.04212 -247.485408)
					(mid 21.3741 -247.485408)
					(end 22.04212 -247.485408)
				)
			)
		)
	)
	(zone
		(layers "B.Cu" "In13.Cu" "In15.Cu")
		(hatch none 0.5)
		(connect_pads
			(clearance 0)
		)
		(min_thickness 0.25)
		(keepout
			(tracks not_allowed)
			(vias allowed)
			(pads allowed)
			(copperpour not_allowed)
			(footprints allowed)
		)
		(placement
			(enabled no)
			(sheetname "")
		)
		(fill yes
			(thermal_gap 0.5)
			(thermal_bridge_width 0.5)
			(island_removal_mode 0)
		)
		(polygon
			(pts
				(arc
					(start 333.076042 -270.036036)
					(mid 332.446122 -270.036036)
					(end 333.076042 -270.036036)
				)
			)
		)
	)
	(zone
		(layers "B.Cu" "In13.Cu" "In15.Cu")
		(hatch none 0.5)
		(connect_pads
			(clearance 0)
		)
		(min_thickness 0.25)
		(keepout
			(tracks not_allowed)
			(vias allowed)
			(pads allowed)
			(copperpour not_allowed)
			(footprints allowed)
		)
		(placement
			(enabled no)
			(sheetname "")
		)
		(fill yes
			(thermal_gap 0.5)
			(thermal_bridge_width 0.5)
			(island_removal_mode 0)
		)
		(polygon
			(pts
				(arc
					(start 332.306168 -233.954066)
					(mid 331.676248 -233.954066)
					(end 332.306168 -233.954066)
				)
			)
		)
	)
	(zone
		(layers "B.Cu" "In13.Cu" "In15.Cu")
		(hatch none 0.5)
		(connect_pads
			(clearance 0)
		)
		(min_thickness 0.25)
		(keepout
			(tracks not_allowed)
			(vias allowed)
			(pads allowed)
			(copperpour not_allowed)
			(footprints allowed)
		)
		(placement
			(enabled no)
			(sheetname "")
		)
		(fill yes
			(thermal_gap 0.5)
			(thermal_bridge_width 0.5)
			(island_removal_mode 0)
		)
		(polygon
			(pts
				(arc
					(start 125.54966 -276.516338)
					(mid 124.91974 -276.516338)
					(end 125.54966 -276.516338)
				)
			)
		)
	)
	(zone
		(layers "B.Cu" "In13.Cu" "In15.Cu")
		(hatch none 0.5)
		(connect_pads
			(clearance 0)
		)
		(min_thickness 0.25)
		(keepout
			(tracks not_allowed)
			(vias allowed)
			(pads allowed)
			(copperpour not_allowed)
			(footprints allowed)
		)
		(placement
			(enabled no)
			(sheetname "")
		)
		(fill yes
			(thermal_gap 0.5)
			(thermal_bridge_width 0.5)
			(island_removal_mode 0)
		)
		(polygon
			(pts
				(arc
					(start 265.88212 -248.335038)
					(mid 265.2141 -248.335038)
					(end 265.88212 -248.335038)
				)
			)
		)
	)
	(zone
		(layers "B.Cu" "In13.Cu" "In15.Cu")
		(hatch none 0.5)
		(connect_pads
			(clearance 0)
		)
		(min_thickness 0.25)
		(keepout
			(tracks not_allowed)
			(vias allowed)
			(pads allowed)
			(copperpour not_allowed)
			(footprints allowed)
		)
		(placement
			(enabled no)
			(sheetname "")
		)
		(fill yes
			(thermal_gap 0.5)
			(thermal_bridge_width 0.5)
			(island_removal_mode 0)
		)
		(polygon
			(pts
				(arc
					(start 450.42201 -237.285022)
					(mid 449.75399 -237.285022)
					(end 450.42201 -237.285022)
				)
			)
		)
	)
	(zone
		(layers "B.Cu" "In13.Cu" "In15.Cu")
		(hatch none 0.5)
		(connect_pads
			(clearance 0)
		)
		(min_thickness 0.25)
		(keepout
			(tracks not_allowed)
			(vias allowed)
			(pads allowed)
			(copperpour not_allowed)
			(footprints allowed)
		)
		(placement
			(enabled no)
			(sheetname "")
		)
		(fill yes
			(thermal_gap 0.5)
			(thermal_bridge_width 0.5)
			(island_removal_mode 0)
		)
		(polygon
			(pts
				(arc
					(start 38.218872 -17.613122)
					(mid 37.550852 -17.613122)
					(end 38.218872 -17.613122)
				)
			)
		)
	)
	(zone
		(layers "B.Cu" "In13.Cu" "In15.Cu")
		(hatch none 0.5)
		(connect_pads
			(clearance 0)
		)
		(min_thickness 0.25)
		(keepout
			(tracks not_allowed)
			(vias allowed)
			(pads allowed)
			(copperpour not_allowed)
			(footprints allowed)
		)
		(placement
			(enabled no)
			(sheetname "")
		)
		(fill yes
			(thermal_gap 0.5)
			(thermal_bridge_width 0.5)
			(island_removal_mode 0)
		)
		(polygon
			(pts
				(arc
					(start 84.666074 -285.426404)
					(mid 84.036154 -285.426404)
					(end 84.666074 -285.426404)
				)
			)
		)
	)
	(zone
		(layers "B.Cu" "In13.Cu" "In15.Cu")
		(hatch none 0.5)
		(connect_pads
			(clearance 0)
		)
		(min_thickness 0.25)
		(keepout
			(tracks not_allowed)
			(vias allowed)
			(pads allowed)
			(copperpour not_allowed)
			(footprints allowed)
		)
		(placement
			(enabled no)
			(sheetname "")
		)
		(fill yes
			(thermal_gap 0.5)
			(thermal_bridge_width 0.5)
			(island_removal_mode 0)
		)
		(polygon
			(pts
				(arc
					(start 357.686102 -233.954066)
					(mid 357.056182 -233.954066)
					(end 357.686102 -233.954066)
				)
			)
		)
	)
	(zone
		(layers "B.Cu" "In13.Cu" "In15.Cu")
		(hatch none 0.5)
		(connect_pads
			(clearance 0)
		)
		(min_thickness 0.25)
		(keepout
			(tracks not_allowed)
			(vias allowed)
			(pads allowed)
			(copperpour not_allowed)
			(footprints allowed)
		)
		(placement
			(enabled no)
			(sheetname "")
		)
		(fill yes
			(thermal_gap 0.5)
			(thermal_bridge_width 0.5)
			(island_removal_mode 0)
		)
		(polygon
			(pts
				(arc
					(start 387.589776 -289.475926)
					(mid 386.959856 -289.475926)
					(end 387.589776 -289.475926)
				)
			)
		)
	)
	(zone
		(layers "B.Cu" "In13.Cu" "In15.Cu")
		(hatch none 0.5)
		(connect_pads
			(clearance 0)
		)
		(min_thickness 0.25)
		(keepout
			(tracks not_allowed)
			(vias allowed)
			(pads allowed)
			(copperpour not_allowed)
			(footprints allowed)
		)
		(placement
			(enabled no)
			(sheetname "")
		)
		(fill yes
			(thermal_gap 0.5)
			(thermal_bridge_width 0.5)
			(island_removal_mode 0)
		)
		(polygon
			(pts
				(arc
					(start 333.076042 -281.37612)
					(mid 332.446122 -281.37612)
					(end 333.076042 -281.37612)
				)
			)
		)
	)
	(zone
		(layers "B.Cu" "In13.Cu" "In15.Cu")
		(hatch none 0.5)
		(connect_pads
			(clearance 0)
		)
		(min_thickness 0.25)
		(keepout
			(tracks not_allowed)
			(vias allowed)
			(pads allowed)
			(copperpour not_allowed)
			(footprints allowed)
		)
		(placement
			(enabled no)
			(sheetname "")
		)
		(fill yes
			(thermal_gap 0.5)
			(thermal_bridge_width 0.5)
			(island_removal_mode 0)
		)
		(polygon
			(pts
				(arc
					(start 346.236036 -278.136096)
					(mid 345.606116 -278.136096)
					(end 346.236036 -278.136096)
				)
			)
		)
	)
	(zone
		(layers "B.Cu" "In13.Cu" "In15.Cu")
		(hatch none 0.5)
		(connect_pads
			(clearance 0)
		)
		(min_thickness 0.25)
		(keepout
			(tracks not_allowed)
			(vias allowed)
			(pads allowed)
			(copperpour not_allowed)
			(footprints allowed)
		)
		(placement
			(enabled no)
			(sheetname "")
		)
		(fill yes
			(thermal_gap 0.5)
			(thermal_bridge_width 0.5)
			(island_removal_mode 0)
		)
		(polygon
			(pts
				(arc
					(start 84.3661 -256.634488)
					(mid 83.73618 -256.634488)
					(end 84.3661 -256.634488)
				)
			)
		)
	)
	(zone
		(layers "B.Cu" "In13.Cu" "In15.Cu")
		(hatch none 0.5)
		(connect_pads
			(clearance 0)
		)
		(min_thickness 0.25)
		(keepout
			(tracks not_allowed)
			(vias allowed)
			(pads allowed)
			(copperpour not_allowed)
			(footprints allowed)
		)
		(placement
			(enabled no)
			(sheetname "")
		)
		(fill yes
			(thermal_gap 0.5)
			(thermal_bridge_width 0.5)
			(island_removal_mode 0)
		)
		(polygon
			(pts
				(arc
					(start 332.306168 -225.85426)
					(mid 331.676248 -225.85426)
					(end 332.306168 -225.85426)
				)
			)
		)
	)
	(zone
		(layers "B.Cu" "In13.Cu" "In15.Cu")
		(hatch none 0.5)
		(connect_pads
			(clearance 0)
		)
		(min_thickness 0.25)
		(keepout
			(tracks not_allowed)
			(vias allowed)
			(pads allowed)
			(copperpour not_allowed)
			(footprints allowed)
		)
		(placement
			(enabled no)
			(sheetname "")
		)
		(fill yes
			(thermal_gap 0.5)
			(thermal_bridge_width 0.5)
			(island_removal_mode 0)
		)
		(polygon
			(pts
				(arc
					(start 17.942052 -278.935434)
					(mid 17.274032 -278.935434)
					(end 17.942052 -278.935434)
				)
			)
		)
	)
	(zone
		(layers "B.Cu" "In13.Cu" "In15.Cu")
		(hatch none 0.5)
		(connect_pads
			(clearance 0)
		)
		(min_thickness 0.25)
		(keepout
			(tracks not_allowed)
			(vias allowed)
			(pads allowed)
			(copperpour not_allowed)
			(footprints allowed)
		)
		(placement
			(enabled no)
			(sheetname "")
		)
		(fill yes
			(thermal_gap 0.5)
			(thermal_bridge_width 0.5)
			(island_removal_mode 0)
		)
		(polygon
			(pts
				(arc
					(start 103.936038 -278.13635)
					(mid 103.306118 -278.13635)
					(end 103.936038 -278.13635)
				)
			)
		)
	)
	(zone
		(layers "B.Cu" "In13.Cu" "In15.Cu")
		(hatch none 0.5)
		(connect_pads
			(clearance 0)
		)
		(min_thickness 0.25)
		(keepout
			(tracks not_allowed)
			(vias allowed)
			(pads allowed)
			(copperpour not_allowed)
			(footprints allowed)
		)
		(placement
			(enabled no)
			(sheetname "")
		)
		(fill yes
			(thermal_gap 0.5)
			(thermal_bridge_width 0.5)
			(island_removal_mode 0)
		)
		(polygon
			(pts
				(arc
					(start 136.812782 -11.955018)
					(mid 136.144762 -11.955018)
					(end 136.812782 -11.955018)
				)
			)
		)
	)
	(zone
		(layers "B.Cu" "In13.Cu" "In15.Cu")
		(hatch none 0.5)
		(connect_pads
			(clearance 0)
		)
		(min_thickness 0.25)
		(keepout
			(tracks not_allowed)
			(vias allowed)
			(pads allowed)
			(copperpour not_allowed)
			(footprints allowed)
		)
		(placement
			(enabled no)
			(sheetname "")
		)
		(fill yes
			(thermal_gap 0.5)
			(thermal_bridge_width 0.5)
			(island_removal_mode 0)
		)
		(polygon
			(pts
				(arc
					(start 387.289802 -242.864132)
					(mid 386.659882 -242.864132)
					(end 387.289802 -242.864132)
				)
			)
		)
	)
	(zone
		(layers "B.Cu" "In13.Cu" "In15.Cu")
		(hatch none 0.5)
		(connect_pads
			(clearance 0)
		)
		(min_thickness 0.25)
		(keepout
			(tracks not_allowed)
			(vias allowed)
			(pads allowed)
			(copperpour not_allowed)
			(footprints allowed)
		)
		(placement
			(enabled no)
			(sheetname "")
		)
		(fill yes
			(thermal_gap 0.5)
			(thermal_bridge_width 0.5)
			(island_removal_mode 0)
		)
		(polygon
			(pts
				(arc
					(start 206.58201 -219.435426)
					(mid 205.91399 -219.435426)
					(end 206.58201 -219.435426)
				)
			)
		)
	)
	(zone
		(layers "B.Cu" "In13.Cu" "In15.Cu")
		(hatch none 0.5)
		(connect_pads
			(clearance 0)
		)
		(min_thickness 0.25)
		(keepout
			(tracks not_allowed)
			(vias allowed)
			(pads allowed)
			(copperpour not_allowed)
			(footprints allowed)
		)
		(placement
			(enabled no)
			(sheetname "")
		)
		(fill yes
			(thermal_gap 0.5)
			(thermal_bridge_width 0.5)
			(island_removal_mode 0)
		)
		(polygon
			(pts
				(arc
					(start 22.04212 -228.78542)
					(mid 21.3741 -228.78542)
					(end 22.04212 -228.78542)
				)
			)
		)
	)
	(zone
		(layers "B.Cu" "In13.Cu" "In15.Cu")
		(hatch none 0.5)
		(connect_pads
			(clearance 0)
		)
		(min_thickness 0.25)
		(keepout
			(tracks not_allowed)
			(vias allowed)
			(pads allowed)
			(copperpour not_allowed)
			(footprints allowed)
		)
		(placement
			(enabled no)
			(sheetname "")
		)
		(fill yes
			(thermal_gap 0.5)
			(thermal_bridge_width 0.5)
			(island_removal_mode 0)
		)
		(polygon
			(pts
				(arc
					(start 334.485996 -288.66592)
					(mid 333.856076 -288.66592)
					(end 334.485996 -288.66592)
				)
			)
		)
	)
	(zone
		(layers "B.Cu" "In13.Cu" "In15.Cu")
		(hatch none 0.5)
		(connect_pads
			(clearance 0)
		)
		(min_thickness 0.25)
		(keepout
			(tracks not_allowed)
			(vias allowed)
			(pads allowed)
			(copperpour not_allowed)
			(footprints allowed)
		)
		(placement
			(enabled no)
			(sheetname "")
		)
		(fill yes
			(thermal_gap 0.5)
			(thermal_bridge_width 0.5)
			(island_removal_mode 0)
		)
		(polygon
			(pts
				(arc
					(start 17.942052 -289.98545)
					(mid 17.274032 -289.98545)
					(end 17.942052 -289.98545)
				)
			)
		)
	)
	(zone
		(layers "B.Cu" "In13.Cu" "In15.Cu")
		(hatch none 0.5)
		(connect_pads
			(clearance 0)
		)
		(min_thickness 0.25)
		(keepout
			(tracks not_allowed)
			(vias allowed)
			(pads allowed)
			(copperpour not_allowed)
			(footprints allowed)
		)
		(placement
			(enabled no)
			(sheetname "")
		)
		(fill yes
			(thermal_gap 0.5)
			(thermal_bridge_width 0.5)
			(island_removal_mode 0)
		)
		(polygon
			(pts
				(arc
					(start 106.755946 -279.756362)
					(mid 106.126026 -279.756362)
					(end 106.755946 -279.756362)
				)
			)
		)
	)
	(zone
		(layers "B.Cu" "In13.Cu" "In15.Cu")
		(hatch none 0.5)
		(connect_pads
			(clearance 0)
		)
		(min_thickness 0.25)
		(keepout
			(tracks not_allowed)
			(vias allowed)
			(pads allowed)
			(copperpour not_allowed)
			(footprints allowed)
		)
		(placement
			(enabled no)
			(sheetname "")
		)
		(fill yes
			(thermal_gap 0.5)
			(thermal_bridge_width 0.5)
			(island_removal_mode 0)
		)
		(polygon
			(pts
				(arc
					(start 385.879848 -233.954066)
					(mid 385.249928 -233.954066)
					(end 385.879848 -233.954066)
				)
			)
		)
	)
	(zone
		(layers "B.Cu" "In13.Cu" "In15.Cu")
		(hatch none 0.5)
		(connect_pads
			(clearance 0)
		)
		(min_thickness 0.25)
		(keepout
			(tracks not_allowed)
			(vias allowed)
			(pads allowed)
			(copperpour not_allowed)
			(footprints allowed)
		)
		(placement
			(enabled no)
			(sheetname "")
		)
		(fill yes
			(thermal_gap 0.5)
			(thermal_bridge_width 0.5)
			(island_removal_mode 0)
		)
		(polygon
			(pts
				(arc
					(start 22.04212 -285.735268)
					(mid 21.3741 -285.735268)
					(end 22.04212 -285.735268)
				)
			)
		)
	)
	(zone
		(layers "B.Cu" "In13.Cu" "In15.Cu")
		(hatch none 0.5)
		(connect_pads
			(clearance 0)
		)
		(min_thickness 0.25)
		(keepout
			(tracks not_allowed)
			(vias allowed)
			(pads allowed)
			(copperpour not_allowed)
			(footprints allowed)
		)
		(placement
			(enabled no)
			(sheetname "")
		)
		(fill yes
			(thermal_gap 0.5)
			(thermal_bridge_width 0.5)
			(island_removal_mode 0)
		)
		(polygon
			(pts
				(arc
					(start 84.666074 -282.18638)
					(mid 84.036154 -282.18638)
					(end 84.666074 -282.18638)
				)
			)
		)
	)
	(zone
		(layers "B.Cu" "In13.Cu" "In15.Cu")
		(hatch none 0.5)
		(connect_pads
			(clearance 0)
		)
		(min_thickness 0.25)
		(keepout
			(tracks not_allowed)
			(vias allowed)
			(pads allowed)
			(copperpour not_allowed)
			(footprints allowed)
		)
		(placement
			(enabled no)
			(sheetname "")
		)
		(fill yes
			(thermal_gap 0.5)
			(thermal_bridge_width 0.5)
			(island_removal_mode 0)
		)
		(polygon
			(pts
				(arc
					(start 84.3661 -243.674392)
					(mid 83.73618 -243.674392)
					(end 84.3661 -243.674392)
				)
			)
		)
	)
	(zone
		(layers "B.Cu" "In13.Cu" "In15.Cu")
		(hatch none 0.5)
		(connect_pads
			(clearance 0)
		)
		(min_thickness 0.25)
		(keepout
			(tracks not_allowed)
			(vias allowed)
			(pads allowed)
			(copperpour not_allowed)
			(footprints allowed)
		)
		(placement
			(enabled no)
			(sheetname "")
		)
		(fill yes
			(thermal_gap 0.5)
			(thermal_bridge_width 0.5)
			(island_removal_mode 0)
		)
		(polygon
			(pts
				(arc
					(start 334.186022 -230.714296)
					(mid 333.556102 -230.714296)
					(end 334.186022 -230.714296)
				)
			)
		)
	)
	(zone
		(layers "B.Cu" "In13.Cu" "In15.Cu")
		(hatch none 0.5)
		(connect_pads
			(clearance 0)
		)
		(min_thickness 0.25)
		(keepout
			(tracks not_allowed)
			(vias allowed)
			(pads allowed)
			(copperpour not_allowed)
			(footprints allowed)
		)
		(placement
			(enabled no)
			(sheetname "")
		)
		(fill yes
			(thermal_gap 0.5)
			(thermal_bridge_width 0.5)
			(island_removal_mode 0)
		)
		(polygon
			(pts
				(arc
					(start 202.481942 -313.78525)
					(mid 201.813922 -313.78525)
					(end 202.481942 -313.78525)
				)
			)
		)
	)
	(zone
		(layers "B.Cu" "In13.Cu" "In15.Cu")
		(hatch none 0.5)
		(connect_pads
			(clearance 0)
		)
		(min_thickness 0.25)
		(keepout
			(tracks not_allowed)
			(vias allowed)
			(pads allowed)
			(copperpour not_allowed)
			(footprints allowed)
		)
		(placement
			(enabled no)
			(sheetname "")
		)
		(fill yes
			(thermal_gap 0.5)
			(thermal_bridge_width 0.5)
			(island_removal_mode 0)
		)
		(polygon
			(pts
				(arc
					(start 357.046022 -275.706078)
					(mid 356.416102 -275.706078)
					(end 357.046022 -275.706078)
				)
			)
		)
	)
	(zone
		(layers "B.Cu" "In13.Cu" "In15.Cu")
		(hatch none 0.5)
		(connect_pads
			(clearance 0)
		)
		(min_thickness 0.25)
		(keepout
			(tracks not_allowed)
			(vias allowed)
			(pads allowed)
			(copperpour not_allowed)
			(footprints allowed)
		)
		(placement
			(enabled no)
			(sheetname "")
		)
		(fill yes
			(thermal_gap 0.5)
			(thermal_bridge_width 0.5)
			(island_removal_mode 0)
		)
		(polygon
			(pts
				(arc
					(start 332.560676 -420.952168)
					(mid 331.892656 -420.952168)
					(end 332.560676 -420.952168)
				)
			)
		)
	)
	(zone
		(layers "B.Cu" "In13.Cu" "In15.Cu")
		(hatch none 0.5)
		(connect_pads
			(clearance 0)
		)
		(min_thickness 0.25)
		(keepout
			(tracks not_allowed)
			(vias allowed)
			(pads allowed)
			(copperpour not_allowed)
			(footprints allowed)
		)
		(placement
			(enabled no)
			(sheetname "")
		)
		(fill yes
			(thermal_gap 0.5)
			(thermal_bridge_width 0.5)
			(island_removal_mode 0)
		)
		(polygon
			(pts
				(arc
					(start 206.58201 -312.935366)
					(mid 205.91399 -312.935366)
					(end 206.58201 -312.935366)
				)
			)
		)
	)
	(zone
		(layers "B.Cu" "In13.Cu" "In15.Cu")
		(hatch none 0.5)
		(connect_pads
			(clearance 0)
		)
		(min_thickness 0.25)
		(keepout
			(tracks not_allowed)
			(vias allowed)
			(pads allowed)
			(copperpour not_allowed)
			(footprints allowed)
		)
		(placement
			(enabled no)
			(sheetname "")
		)
		(fill yes
			(thermal_gap 0.5)
			(thermal_bridge_width 0.5)
			(island_removal_mode 0)
		)
		(polygon
			(pts
				(arc
					(start 454.522078 -306.135024)
					(mid 453.854058 -306.135024)
					(end 454.522078 -306.135024)
				)
			)
		)
	)
	(zone
		(layers "B.Cu" "In13.Cu" "In15.Cu")
		(hatch none 0.5)
		(connect_pads
			(clearance 0)
		)
		(min_thickness 0.25)
		(keepout
			(tracks not_allowed)
			(vias allowed)
			(pads allowed)
			(copperpour not_allowed)
			(footprints allowed)
		)
		(placement
			(enabled no)
			(sheetname "")
		)
		(fill yes
			(thermal_gap 0.5)
			(thermal_bridge_width 0.5)
			(island_removal_mode 0)
		)
		(polygon
			(pts
				(arc
					(start 202.481942 -207.535272)
					(mid 201.813922 -207.535272)
					(end 202.481942 -207.535272)
				)
			)
		)
	)
	(zone
		(layers "B.Cu" "In13.Cu" "In15.Cu")
		(hatch none 0.5)
		(connect_pads
			(clearance 0)
		)
		(min_thickness 0.25)
		(keepout
			(tracks not_allowed)
			(vias allowed)
			(pads allowed)
			(copperpour not_allowed)
			(footprints allowed)
		)
		(placement
			(enabled no)
			(sheetname "")
		)
		(fill yes
			(thermal_gap 0.5)
			(thermal_bridge_width 0.5)
			(island_removal_mode 0)
		)
		(polygon
			(pts
				(arc
					(start 137.93978 -250.15444)
					(mid 137.30986 -250.15444)
					(end 137.93978 -250.15444)
				)
			)
		)
	)
	(zone
		(layers "B.Cu" "In13.Cu" "In15.Cu")
		(hatch none 0.5)
		(connect_pads
			(clearance 0)
		)
		(min_thickness 0.25)
		(keepout
			(tracks not_allowed)
			(vias allowed)
			(pads allowed)
			(copperpour not_allowed)
			(footprints allowed)
		)
		(placement
			(enabled no)
			(sheetname "")
		)
		(fill yes
			(thermal_gap 0.5)
			(thermal_bridge_width 0.5)
			(island_removal_mode 0)
		)
		(polygon
			(pts
				(arc
					(start 454.522078 -307.835046)
					(mid 453.854058 -307.835046)
					(end 454.522078 -307.835046)
				)
			)
		)
	)
	(zone
		(layers "B.Cu" "In13.Cu" "In15.Cu")
		(hatch none 0.5)
		(connect_pads
			(clearance 0)
		)
		(min_thickness 0.25)
		(keepout
			(tracks not_allowed)
			(vias allowed)
			(pads allowed)
			(copperpour not_allowed)
			(footprints allowed)
		)
		(placement
			(enabled no)
			(sheetname "")
		)
		(fill yes
			(thermal_gap 0.5)
			(thermal_bridge_width 0.5)
			(island_removal_mode 0)
		)
		(polygon
			(pts
				(arc
					(start 345.033854 -393.69238)
					(mid 344.403934 -393.69238)
					(end 345.033854 -393.69238)
				)
			)
		)
	)
	(zone
		(layers "B.Cu" "In13.Cu" "In15.Cu")
		(hatch none 0.5)
		(connect_pads
			(clearance 0)
		)
		(min_thickness 0.25)
		(keepout
			(tracks not_allowed)
			(vias allowed)
			(pads allowed)
			(copperpour not_allowed)
			(footprints allowed)
		)
		(placement
			(enabled no)
			(sheetname "")
		)
		(fill yes
			(thermal_gap 0.5)
			(thermal_bridge_width 0.5)
			(island_removal_mode 0)
		)
		(polygon
			(pts
				(arc
					(start 357.046022 -278.946102)
					(mid 356.416102 -278.946102)
					(end 357.046022 -278.946102)
				)
			)
		)
	)
	(zone
		(layers "B.Cu" "In13.Cu" "In15.Cu")
		(hatch none 0.5)
		(connect_pads
			(clearance 0)
		)
		(min_thickness 0.25)
		(keepout
			(tracks not_allowed)
			(vias allowed)
			(pads allowed)
			(copperpour not_allowed)
			(footprints allowed)
		)
		(placement
			(enabled no)
			(sheetname "")
		)
		(fill yes
			(thermal_gap 0.5)
			(thermal_bridge_width 0.5)
			(island_removal_mode 0)
		)
		(polygon
			(pts
				(arc
					(start 386.349748 -241.24412)
					(mid 385.719828 -241.24412)
					(end 386.349748 -241.24412)
				)
			)
		)
	)
	(zone
		(layers "B.Cu" "In13.Cu" "In15.Cu")
		(hatch none 0.5)
		(connect_pads
			(clearance 0)
		)
		(min_thickness 0.25)
		(keepout
			(tracks not_allowed)
			(vias allowed)
			(pads allowed)
			(copperpour not_allowed)
			(footprints allowed)
		)
		(placement
			(enabled no)
			(sheetname "")
		)
		(fill yes
			(thermal_gap 0.5)
			(thermal_bridge_width 0.5)
			(island_removal_mode 0)
		)
		(polygon
			(pts
				(arc
					(start 269.982188 -289.135058)
					(mid 269.314168 -289.135058)
					(end 269.982188 -289.135058)
				)
			)
		)
	)
	(zone
		(layers "B.Cu" "In13.Cu" "In15.Cu")
		(hatch none 0.5)
		(connect_pads
			(clearance 0)
		)
		(min_thickness 0.25)
		(keepout
			(tracks not_allowed)
			(vias allowed)
			(pads allowed)
			(copperpour not_allowed)
			(footprints allowed)
		)
		(placement
			(enabled no)
			(sheetname "")
		)
		(fill yes
			(thermal_gap 0.5)
			(thermal_bridge_width 0.5)
			(island_removal_mode 0)
		)
		(polygon
			(pts
				(arc
					(start 269.982188 -249.185176)
					(mid 269.314168 -249.185176)
					(end 269.982188 -249.185176)
				)
			)
		)
	)
	(zone
		(layers "B.Cu" "In13.Cu" "In15.Cu")
		(hatch none 0.5)
		(connect_pads
			(clearance 0)
		)
		(min_thickness 0.25)
		(keepout
			(tracks not_allowed)
			(vias allowed)
			(pads allowed)
			(copperpour not_allowed)
			(footprints allowed)
		)
		(placement
			(enabled no)
			(sheetname "")
		)
		(fill yes
			(thermal_gap 0.5)
			(thermal_bridge_width 0.5)
			(island_removal_mode 0)
		)
		(polygon
			(pts
				(arc
					(start 73.497694 -412.570168)
					(mid 72.829674 -412.570168)
					(end 73.497694 -412.570168)
				)
			)
		)
	)
	(zone
		(layers "B.Cu" "In13.Cu" "In15.Cu")
		(hatch none 0.5)
		(connect_pads
			(clearance 0)
		)
		(min_thickness 0.25)
		(keepout
			(tracks not_allowed)
			(vias allowed)
			(pads allowed)
			(copperpour not_allowed)
			(footprints allowed)
		)
		(placement
			(enabled no)
			(sheetname "")
		)
		(fill yes
			(thermal_gap 0.5)
			(thermal_bridge_width 0.5)
			(island_removal_mode 0)
		)
		(polygon
			(pts
				(arc
					(start 265.88212 -291.684964)
					(mid 265.2141 -291.684964)
					(end 265.88212 -291.684964)
				)
			)
		)
	)
	(zone
		(layers "B.Cu" "In13.Cu" "In15.Cu")
		(hatch none 0.5)
		(connect_pads
			(clearance 0)
		)
		(min_thickness 0.25)
		(keepout
			(tracks not_allowed)
			(vias allowed)
			(pads allowed)
			(copperpour not_allowed)
			(footprints allowed)
		)
		(placement
			(enabled no)
			(sheetname "")
		)
		(fill yes
			(thermal_gap 0.5)
			(thermal_bridge_width 0.5)
			(island_removal_mode 0)
		)
		(polygon
			(pts
				(arc
					(start 269.982188 -219.435172)
					(mid 269.314168 -219.435172)
					(end 269.982188 -219.435172)
				)
			)
		)
	)
	(zone
		(layers "B.Cu" "In13.Cu" "In15.Cu")
		(hatch none 0.5)
		(connect_pads
			(clearance 0)
		)
		(min_thickness 0.25)
		(keepout
			(tracks not_allowed)
			(vias allowed)
			(pads allowed)
			(copperpour not_allowed)
			(footprints allowed)
		)
		(placement
			(enabled no)
			(sheetname "")
		)
		(fill yes
			(thermal_gap 0.5)
			(thermal_bridge_width 0.5)
			(island_removal_mode 0)
		)
		(polygon
			(pts
				(arc
					(start 450.42201 -221.13494)
					(mid 449.75399 -221.13494)
					(end 450.42201 -221.13494)
				)
			)
		)
	)
	(zone
		(layers "B.Cu" "In13.Cu" "In15.Cu")
		(hatch none 0.5)
		(connect_pads
			(clearance 0)
		)
		(min_thickness 0.25)
		(keepout
			(tracks not_allowed)
			(vias allowed)
			(pads allowed)
			(copperpour not_allowed)
			(footprints allowed)
		)
		(placement
			(enabled no)
			(sheetname "")
		)
		(fill yes
			(thermal_gap 0.5)
			(thermal_bridge_width 0.5)
			(island_removal_mode 0)
		)
		(polygon
			(pts
				(arc
					(start 132.136896 -431.889916)
					(mid 131.362704 -431.889916)
					(end 132.136896 -431.889916)
				)
			)
		)
	)
	(zone
		(layers "B.Cu" "In13.Cu" "In15.Cu")
		(hatch none 0.5)
		(connect_pads
			(clearance 0)
		)
		(min_thickness 0.25)
		(keepout
			(tracks not_allowed)
			(vias allowed)
			(pads allowed)
			(copperpour not_allowed)
			(footprints allowed)
		)
		(placement
			(enabled no)
			(sheetname "")
		)
		(fill yes
			(thermal_gap 0.5)
			(thermal_bridge_width 0.5)
			(island_removal_mode 0)
		)
		(polygon
			(pts
				(arc
					(start 137.534396 -412.570168)
					(mid 136.866376 -412.570168)
					(end 137.534396 -412.570168)
				)
			)
		)
	)
	(zone
		(layers "B.Cu" "In13.Cu" "In15.Cu")
		(hatch none 0.5)
		(connect_pads
			(clearance 0)
		)
		(min_thickness 0.25)
		(keepout
			(tracks not_allowed)
			(vias allowed)
			(pads allowed)
			(copperpour not_allowed)
			(footprints allowed)
		)
		(placement
			(enabled no)
			(sheetname "")
		)
		(fill yes
			(thermal_gap 0.5)
			(thermal_bridge_width 0.5)
			(island_removal_mode 0)
		)
		(polygon
			(pts
				(arc
					(start 333.076042 -289.475926)
					(mid 332.446122 -289.475926)
					(end 333.076042 -289.475926)
				)
			)
		)
	)
	(zone
		(layers "B.Cu" "In13.Cu" "In15.Cu")
		(hatch none 0.5)
		(connect_pads
			(clearance 0)
		)
		(min_thickness 0.25)
		(keepout
			(tracks not_allowed)
			(vias allowed)
			(pads allowed)
			(copperpour not_allowed)
			(footprints allowed)
		)
		(placement
			(enabled no)
			(sheetname "")
		)
		(fill yes
			(thermal_gap 0.5)
			(thermal_bridge_width 0.5)
			(island_removal_mode 0)
		)
		(polygon
			(pts
				(arc
					(start 323.036692 -430.889918)
					(mid 322.2625 -430.889918)
					(end 323.036692 -430.889918)
				)
			)
		)
	)
	(zone
		(layers "B.Cu" "In13.Cu" "In15.Cu")
		(hatch none 0.5)
		(connect_pads
			(clearance 0)
		)
		(min_thickness 0.25)
		(keepout
			(tracks not_allowed)
			(vias allowed)
			(pads allowed)
			(copperpour not_allowed)
			(footprints allowed)
		)
		(placement
			(enabled no)
			(sheetname "")
		)
		(fill yes
			(thermal_gap 0.5)
			(thermal_bridge_width 0.5)
			(island_removal_mode 0)
		)
		(polygon
			(pts
				(arc
					(start 202.481942 -201.585322)
					(mid 201.813922 -201.585322)
					(end 202.481942 -201.585322)
				)
			)
		)
	)
	(zone
		(layers "B.Cu" "In13.Cu" "In15.Cu")
		(hatch none 0.5)
		(connect_pads
			(clearance 0)
		)
		(min_thickness 0.25)
		(keepout
			(tracks not_allowed)
			(vias allowed)
			(pads allowed)
			(copperpour not_allowed)
			(footprints allowed)
		)
		(placement
			(enabled no)
			(sheetname "")
		)
		(fill yes
			(thermal_gap 0.5)
			(thermal_bridge_width 0.5)
			(island_removal_mode 0)
		)
		(polygon
			(pts
				(arc
					(start 206.58201 -261.08533)
					(mid 205.91399 -261.08533)
					(end 206.58201 -261.08533)
				)
			)
		)
	)
	(zone
		(layers "B.Cu" "In13.Cu" "In15.Cu")
		(hatch none 0.5)
		(connect_pads
			(clearance 0)
		)
		(min_thickness 0.25)
		(keepout
			(tracks not_allowed)
			(vias allowed)
			(pads allowed)
			(copperpour not_allowed)
			(footprints allowed)
		)
		(placement
			(enabled no)
			(sheetname "")
		)
		(fill yes
			(thermal_gap 0.5)
			(thermal_bridge_width 0.5)
			(island_removal_mode 0)
		)
		(polygon
			(pts
				(arc
					(start 265.88212 -285.735014)
					(mid 265.2141 -285.735014)
					(end 265.88212 -285.735014)
				)
			)
		)
	)
	(zone
		(layers "B.Cu" "In13.Cu" "In15.Cu")
		(hatch none 0.5)
		(connect_pads
			(clearance 0)
		)
		(min_thickness 0.25)
		(keepout
			(tracks not_allowed)
			(vias allowed)
			(pads allowed)
			(copperpour not_allowed)
			(footprints allowed)
		)
		(placement
			(enabled no)
			(sheetname "")
		)
		(fill yes
			(thermal_gap 0.5)
			(thermal_bridge_width 0.5)
			(island_removal_mode 0)
		)
		(polygon
			(pts
				(arc
					(start 454.522078 -229.63505)
					(mid 453.854058 -229.63505)
					(end 454.522078 -229.63505)
				)
			)
		)
	)
	(zone
		(layers "B.Cu" "In13.Cu" "In15.Cu")
		(hatch none 0.5)
		(connect_pads
			(clearance 0)
		)
		(min_thickness 0.25)
		(keepout
			(tracks not_allowed)
			(vias allowed)
			(pads allowed)
			(copperpour not_allowed)
			(footprints allowed)
		)
		(placement
			(enabled no)
			(sheetname "")
		)
		(fill yes
			(thermal_gap 0.5)
			(thermal_bridge_width 0.5)
			(island_removal_mode 0)
		)
		(polygon
			(pts
				(arc
					(start 265.88212 -310.384952)
					(mid 265.2141 -310.384952)
					(end 265.88212 -310.384952)
				)
			)
		)
	)
	(zone
		(layers "B.Cu" "In13.Cu" "In15.Cu")
		(hatch none 0.5)
		(connect_pads
			(clearance 0)
		)
		(min_thickness 0.25)
		(keepout
			(tracks not_allowed)
			(vias allowed)
			(pads allowed)
			(copperpour not_allowed)
			(footprints allowed)
		)
		(placement
			(enabled no)
			(sheetname "")
		)
		(fill yes
			(thermal_gap 0.5)
			(thermal_bridge_width 0.5)
			(island_removal_mode 0)
		)
		(polygon
			(pts
				(arc
					(start 17.942052 -213.485222)
					(mid 17.274032 -213.485222)
					(end 17.942052 -213.485222)
				)
			)
		)
	)
	(zone
		(layers "B.Cu" "In13.Cu" "In15.Cu")
		(hatch none 0.5)
		(connect_pads
			(clearance 0)
		)
		(min_thickness 0.25)
		(keepout
			(tracks not_allowed)
			(vias allowed)
			(pads allowed)
			(copperpour not_allowed)
			(footprints allowed)
		)
		(placement
			(enabled no)
			(sheetname "")
		)
		(fill yes
			(thermal_gap 0.5)
			(thermal_bridge_width 0.5)
			(island_removal_mode 0)
		)
		(polygon
			(pts
				(arc
					(start 139.819634 -245.294404)
					(mid 139.189714 -245.294404)
					(end 139.819634 -245.294404)
				)
			)
		)
	)
	(zone
		(layers "B.Cu" "In13.Cu" "In15.Cu")
		(hatch none 0.5)
		(connect_pads
			(clearance 0)
		)
		(min_thickness 0.25)
		(keepout
			(tracks not_allowed)
			(vias allowed)
			(pads allowed)
			(copperpour not_allowed)
			(footprints allowed)
		)
		(placement
			(enabled no)
			(sheetname "")
		)
		(fill yes
			(thermal_gap 0.5)
			(thermal_bridge_width 0.5)
			(island_removal_mode 0)
		)
		(polygon
			(pts
				(arc
					(start 334.186022 -246.914162)
					(mid 333.556102 -246.914162)
					(end 334.186022 -246.914162)
				)
			)
		)
	)
	(zone
		(layers "B.Cu" "In13.Cu" "In15.Cu")
		(hatch none 0.5)
		(connect_pads
			(clearance 0)
		)
		(min_thickness 0.25)
		(keepout
			(tracks not_allowed)
			(vias allowed)
			(pads allowed)
			(copperpour not_allowed)
			(footprints allowed)
		)
		(placement
			(enabled no)
			(sheetname "")
		)
		(fill yes
			(thermal_gap 0.5)
			(thermal_bridge_width 0.5)
			(island_removal_mode 0)
		)
		(polygon
			(pts
				(arc
					(start 86.076028 -284.616398)
					(mid 85.446108 -284.616398)
					(end 86.076028 -284.616398)
				)
			)
		)
	)
	(zone
		(layers "B.Cu" "In13.Cu" "In15.Cu")
		(hatch none 0.5)
		(connect_pads
			(clearance 0)
		)
		(min_thickness 0.25)
		(keepout
			(tracks not_allowed)
			(vias allowed)
			(pads allowed)
			(copperpour not_allowed)
			(footprints allowed)
		)
		(placement
			(enabled no)
			(sheetname "")
		)
		(fill yes
			(thermal_gap 0.5)
			(thermal_bridge_width 0.5)
			(island_removal_mode 0)
		)
		(polygon
			(pts
				(arc
					(start 336.03692 -430.889918)
					(mid 335.262728 -430.889918)
					(end 336.03692 -430.889918)
				)
			)
		)
	)
	(zone
		(layers "B.Cu" "In13.Cu" "In15.Cu")
		(hatch none 0.5)
		(connect_pads
			(clearance 0)
		)
		(min_thickness 0.25)
		(keepout
			(tracks not_allowed)
			(vias allowed)
			(pads allowed)
			(copperpour not_allowed)
			(footprints allowed)
		)
		(placement
			(enabled no)
			(sheetname "")
		)
		(fill yes
			(thermal_gap 0.5)
			(thermal_bridge_width 0.5)
			(island_removal_mode 0)
		)
		(polygon
			(pts
				(arc
					(start 95.433896 -386.003292)
					(mid 94.803976 -386.003292)
					(end 95.433896 -386.003292)
				)
			)
		)
	)
	(zone
		(layers "B.Cu" "In13.Cu" "In15.Cu")
		(hatch none 0.5)
		(connect_pads
			(clearance 0)
		)
		(min_thickness 0.25)
		(keepout
			(tracks not_allowed)
			(vias allowed)
			(pads allowed)
			(copperpour not_allowed)
			(footprints allowed)
		)
		(placement
			(enabled no)
			(sheetname "")
		)
		(fill yes
			(thermal_gap 0.5)
			(thermal_bridge_width 0.5)
			(island_removal_mode 0)
		)
		(polygon
			(pts
				(arc
					(start 136.670796 -412.570168)
					(mid 136.002776 -412.570168)
					(end 136.670796 -412.570168)
				)
			)
		)
	)
	(zone
		(layers "B.Cu" "In13.Cu" "In15.Cu")
		(hatch none 0.5)
		(connect_pads
			(clearance 0)
		)
		(min_thickness 0.25)
		(keepout
			(tracks not_allowed)
			(vias allowed)
			(pads allowed)
			(copperpour not_allowed)
			(footprints allowed)
		)
		(placement
			(enabled no)
			(sheetname "")
		)
		(fill yes
			(thermal_gap 0.5)
			(thermal_bridge_width 0.5)
			(island_removal_mode 0)
		)
		(polygon
			(pts
				(arc
					(start 101.11613 -276.516338)
					(mid 100.48621 -276.516338)
					(end 101.11613 -276.516338)
				)
			)
		)
	)
	(zone
		(layers "B.Cu" "In13.Cu" "In15.Cu")
		(hatch none 0.5)
		(connect_pads
			(clearance 0)
		)
		(min_thickness 0.25)
		(keepout
			(tracks not_allowed)
			(vias allowed)
			(pads allowed)
			(copperpour not_allowed)
			(footprints allowed)
		)
		(placement
			(enabled no)
			(sheetname "")
		)
		(fill yes
			(thermal_gap 0.5)
			(thermal_bridge_width 0.5)
			(island_removal_mode 0)
		)
		(polygon
			(pts
				(arc
					(start 454.522078 -228.785166)
					(mid 453.854058 -228.785166)
					(end 454.522078 -228.785166)
				)
			)
		)
	)
	(zone
		(layers "B.Cu" "In13.Cu" "In15.Cu")
		(hatch none 0.5)
		(connect_pads
			(clearance 0)
		)
		(min_thickness 0.25)
		(keepout
			(tracks not_allowed)
			(vias allowed)
			(pads allowed)
			(copperpour not_allowed)
			(footprints allowed)
		)
		(placement
			(enabled no)
			(sheetname "")
		)
		(fill yes
			(thermal_gap 0.5)
			(thermal_bridge_width 0.5)
			(island_removal_mode 0)
		)
		(polygon
			(pts
				(arc
					(start 140.119608 -270.846296)
					(mid 139.489688 -270.846296)
					(end 140.119608 -270.846296)
				)
			)
		)
	)
	(zone
		(layers "B.Cu" "In13.Cu" "In15.Cu")
		(hatch none 0.5)
		(connect_pads
			(clearance 0)
		)
		(min_thickness 0.25)
		(keepout
			(tracks not_allowed)
			(vias allowed)
			(pads allowed)
			(copperpour not_allowed)
			(footprints allowed)
		)
		(placement
			(enabled no)
			(sheetname "")
		)
		(fill yes
			(thermal_gap 0.5)
			(thermal_bridge_width 0.5)
			(island_removal_mode 0)
		)
		(polygon
			(pts
				(arc
					(start 138.239754 -280.566368)
					(mid 137.609834 -280.566368)
					(end 138.239754 -280.566368)
				)
			)
		)
	)
	(zone
		(layers "B.Cu" "In13.Cu" "In15.Cu")
		(hatch none 0.5)
		(connect_pads
			(clearance 0)
		)
		(min_thickness 0.25)
		(keepout
			(tracks not_allowed)
			(vias allowed)
			(pads allowed)
			(copperpour not_allowed)
			(footprints allowed)
		)
		(placement
			(enabled no)
			(sheetname "")
		)
		(fill yes
			(thermal_gap 0.5)
			(thermal_bridge_width 0.5)
			(island_removal_mode 0)
		)
		(polygon
			(pts
				(arc
					(start 206.58201 -238.135414)
					(mid 205.91399 -238.135414)
					(end 206.58201 -238.135414)
				)
			)
		)
	)
	(zone
		(layers "B.Cu" "In13.Cu" "In15.Cu")
		(hatch none 0.5)
		(connect_pads
			(clearance 0)
		)
		(min_thickness 0.25)
		(keepout
			(tracks not_allowed)
			(vias allowed)
			(pads allowed)
			(copperpour not_allowed)
			(footprints allowed)
		)
		(placement
			(enabled no)
			(sheetname "")
		)
		(fill yes
			(thermal_gap 0.5)
			(thermal_bridge_width 0.5)
			(island_removal_mode 0)
		)
		(polygon
			(pts
				(arc
					(start 84.3661 -255.014476)
					(mid 83.73618 -255.014476)
					(end 84.3661 -255.014476)
				)
			)
		)
	)
	(zone
		(layers "B.Cu" "In13.Cu" "In15.Cu")
		(hatch none 0.5)
		(connect_pads
			(clearance 0)
		)
		(min_thickness 0.25)
		(keepout
			(tracks not_allowed)
			(vias allowed)
			(pads allowed)
			(copperpour not_allowed)
			(footprints allowed)
		)
		(placement
			(enabled no)
			(sheetname "")
		)
		(fill yes
			(thermal_gap 0.5)
			(thermal_bridge_width 0.5)
			(island_removal_mode 0)
		)
		(polygon
			(pts
				(arc
					(start 454.522078 -249.185176)
					(mid 453.854058 -249.185176)
					(end 454.522078 -249.185176)
				)
			)
		)
	)
	(zone
		(layers "B.Cu" "In13.Cu" "In15.Cu")
		(hatch none 0.5)
		(connect_pads
			(clearance 0)
		)
		(min_thickness 0.25)
		(keepout
			(tracks not_allowed)
			(vias allowed)
			(pads allowed)
			(copperpour not_allowed)
			(footprints allowed)
		)
		(placement
			(enabled no)
			(sheetname "")
		)
		(fill yes
			(thermal_gap 0.5)
			(thermal_bridge_width 0.5)
			(island_removal_mode 0)
		)
		(polygon
			(pts
				(arc
					(start 123.669806 -278.13635)
					(mid 123.039886 -278.13635)
					(end 123.669806 -278.13635)
				)
			)
		)
	)
	(zone
		(layers "B.Cu" "In13.Cu" "In15.Cu")
		(hatch none 0.5)
		(connect_pads
			(clearance 0)
		)
		(min_thickness 0.25)
		(keepout
			(tracks not_allowed)
			(vias allowed)
			(pads allowed)
			(copperpour not_allowed)
			(footprints allowed)
		)
		(placement
			(enabled no)
			(sheetname "")
		)
		(fill yes
			(thermal_gap 0.5)
			(thermal_bridge_width 0.5)
			(island_removal_mode 0)
		)
		(polygon
			(pts
				(arc
					(start 96.233996 -388.774432)
					(mid 95.604076 -388.774432)
					(end 96.233996 -388.774432)
				)
			)
		)
	)
	(zone
		(layers "B.Cu" "In13.Cu" "In15.Cu")
		(hatch none 0.5)
		(connect_pads
			(clearance 0)
		)
		(min_thickness 0.25)
		(keepout
			(tracks not_allowed)
			(vias allowed)
			(pads allowed)
			(copperpour not_allowed)
			(footprints allowed)
		)
		(placement
			(enabled no)
			(sheetname "")
		)
		(fill yes
			(thermal_gap 0.5)
			(thermal_bridge_width 0.5)
			(island_removal_mode 0)
		)
		(polygon
			(pts
				(arc
					(start 367.849658 -278.136096)
					(mid 367.219738 -278.136096)
					(end 367.849658 -278.136096)
				)
			)
		)
	)
	(zone
		(layers "B.Cu" "In13.Cu" "In15.Cu")
		(hatch none 0.5)
		(connect_pads
			(clearance 0)
		)
		(min_thickness 0.25)
		(keepout
			(tracks not_allowed)
			(vias allowed)
			(pads allowed)
			(copperpour not_allowed)
			(footprints allowed)
		)
		(placement
			(enabled no)
			(sheetname "")
		)
		(fill yes
			(thermal_gap 0.5)
			(thermal_bridge_width 0.5)
			(island_removal_mode 0)
		)
		(polygon
			(pts
				(arc
					(start 206.58201 -289.135312)
					(mid 205.91399 -289.135312)
					(end 206.58201 -289.135312)
				)
			)
		)
	)
	(zone
		(layers "B.Cu" "In13.Cu" "In15.Cu")
		(hatch none 0.5)
		(connect_pads
			(clearance 0)
		)
		(min_thickness 0.25)
		(keepout
			(tracks not_allowed)
			(vias allowed)
			(pads allowed)
			(copperpour not_allowed)
			(footprints allowed)
		)
		(placement
			(enabled no)
			(sheetname "")
		)
		(fill yes
			(thermal_gap 0.5)
			(thermal_bridge_width 0.5)
			(island_removal_mode 0)
		)
		(polygon
			(pts
				(arc
					(start 352.633788 -394.385292)
					(mid 352.003868 -394.385292)
					(end 352.633788 -394.385292)
				)
			)
		)
	)
	(zone
		(layers "B.Cu" "In13.Cu" "In15.Cu")
		(hatch none 0.5)
		(connect_pads
			(clearance 0)
		)
		(min_thickness 0.25)
		(keepout
			(tracks not_allowed)
			(vias allowed)
			(pads allowed)
			(copperpour not_allowed)
			(footprints allowed)
		)
		(placement
			(enabled no)
			(sheetname "")
		)
		(fill yes
			(thermal_gap 0.5)
			(thermal_bridge_width 0.5)
			(island_removal_mode 0)
		)
		(polygon
			(pts
				(arc
					(start 85.433916 -388.774432)
					(mid 84.803996 -388.774432)
					(end 85.433916 -388.774432)
				)
			)
		)
	)
	(zone
		(layers "B.Cu" "In13.Cu" "In15.Cu")
		(hatch none 0.5)
		(connect_pads
			(clearance 0)
		)
		(min_thickness 0.25)
		(keepout
			(tracks not_allowed)
			(vias allowed)
			(pads allowed)
			(copperpour not_allowed)
			(footprints allowed)
		)
		(placement
			(enabled no)
			(sheetname "")
		)
		(fill yes
			(thermal_gap 0.5)
			(thermal_bridge_width 0.5)
			(island_removal_mode 0)
		)
		(polygon
			(pts
				(arc
					(start 426.774356 -4.963414)
					(mid 426.106336 -4.963414)
					(end 426.774356 -4.963414)
				)
			)
		)
	)
	(zone
		(layers "B.Cu" "In13.Cu" "In15.Cu")
		(hatch none 0.5)
		(connect_pads
			(clearance 0)
		)
		(min_thickness 0.25)
		(keepout
			(tracks not_allowed)
			(vias allowed)
			(pads allowed)
			(copperpour not_allowed)
			(footprints allowed)
		)
		(placement
			(enabled no)
			(sheetname "")
		)
		(fill yes
			(thermal_gap 0.5)
			(thermal_bridge_width 0.5)
			(island_removal_mode 0)
		)
		(polygon
			(pts
				(arc
					(start 138.239754 -287.046162)
					(mid 137.609834 -287.046162)
					(end 138.239754 -287.046162)
				)
			)
		)
	)
	(zone
		(layers "B.Cu" "In13.Cu" "In15.Cu")
		(hatch none 0.5)
		(connect_pads
			(clearance 0)
		)
		(min_thickness 0.25)
		(keepout
			(tracks not_allowed)
			(vias allowed)
			(pads allowed)
			(copperpour not_allowed)
			(footprints allowed)
		)
		(placement
			(enabled no)
			(sheetname "")
		)
		(fill yes
			(thermal_gap 0.5)
			(thermal_bridge_width 0.5)
			(island_removal_mode 0)
		)
		(polygon
			(pts
				(arc
					(start 125.75413 -33.386268)
					(mid 125.08611 -33.386268)
					(end 125.75413 -33.386268)
				)
			)
		)
	)
	(zone
		(layers "B.Cu" "In13.Cu" "In15.Cu")
		(hatch none 0.5)
		(connect_pads
			(clearance 0)
		)
		(min_thickness 0.25)
		(keepout
			(tracks not_allowed)
			(vias allowed)
			(pads allowed)
			(copperpour not_allowed)
			(footprints allowed)
		)
		(placement
			(enabled no)
			(sheetname "")
		)
		(fill yes
			(thermal_gap 0.5)
			(thermal_bridge_width 0.5)
			(island_removal_mode 0)
		)
		(polygon
			(pts
				(arc
					(start 107.396026 -246.10441)
					(mid 106.766106 -246.10441)
					(end 107.396026 -246.10441)
				)
			)
		)
	)
	(zone
		(layers "B.Cu" "In13.Cu" "In15.Cu")
		(hatch none 0.5)
		(connect_pads
			(clearance 0)
		)
		(min_thickness 0.25)
		(keepout
			(tracks not_allowed)
			(vias allowed)
			(pads allowed)
			(copperpour not_allowed)
			(footprints allowed)
		)
		(placement
			(enabled no)
			(sheetname "")
		)
		(fill yes
			(thermal_gap 0.5)
			(thermal_bridge_width 0.5)
			(island_removal_mode 0)
		)
		(polygon
			(pts
				(arc
					(start 454.522078 -273.835114)
					(mid 453.854058 -273.835114)
					(end 454.522078 -273.835114)
				)
			)
		)
	)
	(zone
		(layers "B.Cu" "In13.Cu" "In15.Cu")
		(hatch none 0.5)
		(connect_pads
			(clearance 0)
		)
		(min_thickness 0.25)
		(keepout
			(tracks not_allowed)
			(vias allowed)
			(pads allowed)
			(copperpour not_allowed)
			(footprints allowed)
		)
		(placement
			(enabled no)
			(sheetname "")
		)
		(fill yes
			(thermal_gap 0.5)
			(thermal_bridge_width 0.5)
			(island_removal_mode 0)
		)
		(polygon
			(pts
				(arc
					(start 364.729776 -247.724168)
					(mid 364.099856 -247.724168)
					(end 364.729776 -247.724168)
				)
			)
		)
	)
	(zone
		(layers "B.Cu" "In13.Cu" "In15.Cu")
		(hatch none 0.5)
		(connect_pads
			(clearance 0)
		)
		(min_thickness 0.25)
		(keepout
			(tracks not_allowed)
			(vias allowed)
			(pads allowed)
			(copperpour not_allowed)
			(footprints allowed)
		)
		(placement
			(enabled no)
			(sheetname "")
		)
		(fill yes
			(thermal_gap 0.5)
			(thermal_bridge_width 0.5)
			(island_removal_mode 0)
		)
		(polygon
			(pts
				(arc
					(start 403.137116 -430.889918)
					(mid 402.362924 -430.889918)
					(end 403.137116 -430.889918)
				)
			)
		)
	)
	(zone
		(layers "B.Cu" "In13.Cu" "In15.Cu")
		(hatch none 0.5)
		(connect_pads
			(clearance 0)
		)
		(min_thickness 0.25)
		(keepout
			(tracks not_allowed)
			(vias allowed)
			(pads allowed)
			(copperpour not_allowed)
			(footprints allowed)
		)
		(placement
			(enabled no)
			(sheetname "")
		)
		(fill yes
			(thermal_gap 0.5)
			(thermal_bridge_width 0.5)
			(island_removal_mode 0)
		)
		(polygon
			(pts
				(arc
					(start 265.88212 -282.33497)
					(mid 265.2141 -282.33497)
					(end 265.88212 -282.33497)
				)
			)
		)
	)
	(zone
		(layers "B.Cu" "In13.Cu" "In15.Cu")
		(hatch none 0.5)
		(connect_pads
			(clearance 0)
		)
		(min_thickness 0.25)
		(keepout
			(tracks not_allowed)
			(vias allowed)
			(pads allowed)
			(copperpour not_allowed)
			(footprints allowed)
		)
		(placement
			(enabled no)
			(sheetname "")
		)
		(fill yes
			(thermal_gap 0.5)
			(thermal_bridge_width 0.5)
			(island_removal_mode 0)
		)
		(polygon
			(pts
				(arc
					(start 86.245954 -230.71455)
					(mid 85.616034 -230.71455)
					(end 86.245954 -230.71455)
				)
			)
		)
	)
	(zone
		(layers "B.Cu" "In13.Cu" "In15.Cu")
		(hatch none 0.5)
		(connect_pads
			(clearance 0)
		)
		(min_thickness 0.25)
		(keepout
			(tracks not_allowed)
			(vias allowed)
			(pads allowed)
			(copperpour not_allowed)
			(footprints allowed)
		)
		(placement
			(enabled no)
			(sheetname "")
		)
		(fill yes
			(thermal_gap 0.5)
			(thermal_bridge_width 0.5)
			(island_removal_mode 0)
		)
		(polygon
			(pts
				(arc
					(start 206.58201 -300.185328)
					(mid 205.91399 -300.185328)
					(end 206.58201 -300.185328)
				)
			)
		)
	)
	(zone
		(layers "B.Cu" "In13.Cu" "In15.Cu")
		(hatch none 0.5)
		(connect_pads
			(clearance 0)
		)
		(min_thickness 0.25)
		(keepout
			(tracks not_allowed)
			(vias allowed)
			(pads allowed)
			(copperpour not_allowed)
			(footprints allowed)
		)
		(placement
			(enabled no)
			(sheetname "")
		)
		(fill yes
			(thermal_gap 0.5)
			(thermal_bridge_width 0.5)
			(island_removal_mode 0)
		)
		(polygon
			(pts
				(arc
					(start 83.43392 -386.003292)
					(mid 82.804 -386.003292)
					(end 83.43392 -386.003292)
				)
			)
		)
	)
	(zone
		(layers "B.Cu" "In13.Cu" "In15.Cu")
		(hatch none 0.5)
		(connect_pads
			(clearance 0)
		)
		(min_thickness 0.25)
		(keepout
			(tracks not_allowed)
			(vias allowed)
			(pads allowed)
			(copperpour not_allowed)
			(footprints allowed)
		)
		(placement
			(enabled no)
			(sheetname "")
		)
		(fill yes
			(thermal_gap 0.5)
			(thermal_bridge_width 0.5)
			(island_removal_mode 0)
		)
		(polygon
			(pts
				(arc
					(start 206.58201 -217.735404)
					(mid 205.91399 -217.735404)
					(end 206.58201 -217.735404)
				)
			)
		)
	)
	(zone
		(layers "B.Cu" "In13.Cu" "In15.Cu")
		(hatch none 0.5)
		(connect_pads
			(clearance 0)
		)
		(min_thickness 0.25)
		(keepout
			(tracks not_allowed)
			(vias allowed)
			(pads allowed)
			(copperpour not_allowed)
			(footprints allowed)
		)
		(placement
			(enabled no)
			(sheetname "")
		)
		(fill yes
			(thermal_gap 0.5)
			(thermal_bridge_width 0.5)
			(island_removal_mode 0)
		)
		(polygon
			(pts
				(arc
					(start 108.80598 -243.674392)
					(mid 108.17606 -243.674392)
					(end 108.80598 -243.674392)
				)
			)
		)
	)
	(zone
		(layers "B.Cu" "In13.Cu" "In15.Cu")
		(hatch none 0.5)
		(connect_pads
			(clearance 0)
		)
		(min_thickness 0.25)
		(keepout
			(tracks not_allowed)
			(vias allowed)
			(pads allowed)
			(copperpour not_allowed)
			(footprints allowed)
		)
		(placement
			(enabled no)
			(sheetname "")
		)
		(fill yes
			(thermal_gap 0.5)
			(thermal_bridge_width 0.5)
			(island_removal_mode 0)
		)
		(polygon
			(pts
				(arc
					(start 265.88212 -297.635168)
					(mid 265.2141 -297.635168)
					(end 265.88212 -297.635168)
				)
			)
		)
	)
	(zone
		(layers "B.Cu" "In13.Cu" "In15.Cu")
		(hatch none 0.5)
		(connect_pads
			(clearance 0)
		)
		(min_thickness 0.25)
		(keepout
			(tracks not_allowed)
			(vias allowed)
			(pads allowed)
			(copperpour not_allowed)
			(footprints allowed)
		)
		(placement
			(enabled no)
			(sheetname "")
		)
		(fill yes
			(thermal_gap 0.5)
			(thermal_bridge_width 0.5)
			(island_removal_mode 0)
		)
		(polygon
			(pts
				(arc
					(start 386.349748 -226.664266)
					(mid 385.719828 -226.664266)
					(end 386.349748 -226.664266)
				)
			)
		)
	)
	(zone
		(layers "B.Cu" "In13.Cu" "In15.Cu")
		(hatch none 0.5)
		(connect_pads
			(clearance 0)
		)
		(min_thickness 0.25)
		(keepout
			(tracks not_allowed)
			(vias allowed)
			(pads allowed)
			(copperpour not_allowed)
			(footprints allowed)
		)
		(placement
			(enabled no)
			(sheetname "")
		)
		(fill yes
			(thermal_gap 0.5)
			(thermal_bridge_width 0.5)
			(island_removal_mode 0)
		)
		(polygon
			(pts
				(arc
					(start 454.522078 -210.085178)
					(mid 453.854058 -210.085178)
					(end 454.522078 -210.085178)
				)
			)
		)
	)
	(zone
		(layers "B.Cu" "In13.Cu" "In15.Cu")
		(hatch none 0.5)
		(connect_pads
			(clearance 0)
		)
		(min_thickness 0.25)
		(keepout
			(tracks not_allowed)
			(vias allowed)
			(pads allowed)
			(copperpour not_allowed)
			(footprints allowed)
		)
		(placement
			(enabled no)
			(sheetname "")
		)
		(fill yes
			(thermal_gap 0.5)
			(thermal_bridge_width 0.5)
			(island_removal_mode 0)
		)
		(polygon
			(pts
				(arc
					(start 124.063506 -371.49913)
					(mid 123.395486 -371.49913)
					(end 124.063506 -371.49913)
				)
			)
		)
	)
	(zone
		(layers "B.Cu" "In13.Cu" "In15.Cu")
		(hatch none 0.5)
		(connect_pads
			(clearance 0)
		)
		(min_thickness 0.25)
		(keepout
			(tracks not_allowed)
			(vias allowed)
			(pads allowed)
			(copperpour not_allowed)
			(footprints allowed)
		)
		(placement
			(enabled no)
			(sheetname "")
		)
		(fill yes
			(thermal_gap 0.5)
			(thermal_bridge_width 0.5)
			(island_removal_mode 0)
		)
		(polygon
			(pts
				(arc
					(start 347.17609 -274.896072)
					(mid 346.54617 -274.896072)
					(end 347.17609 -274.896072)
				)
			)
		)
	)
	(zone
		(layers "B.Cu" "In13.Cu" "In15.Cu")
		(hatch none 0.5)
		(connect_pads
			(clearance 0)
		)
		(min_thickness 0.25)
		(keepout
			(tracks not_allowed)
			(vias allowed)
			(pads allowed)
			(copperpour not_allowed)
			(footprints allowed)
		)
		(placement
			(enabled no)
			(sheetname "")
		)
		(fill yes
			(thermal_gap 0.5)
			(thermal_bridge_width 0.5)
			(island_removal_mode 0)
		)
		(polygon
			(pts
				(arc
					(start 454.522078 -220.285056)
					(mid 453.854058 -220.285056)
					(end 454.522078 -220.285056)
				)
			)
		)
	)
	(zone
		(layers "B.Cu" "In13.Cu" "In15.Cu")
		(hatch none 0.5)
		(connect_pads
			(clearance 0)
		)
		(min_thickness 0.25)
		(keepout
			(tracks not_allowed)
			(vias allowed)
			(pads allowed)
			(copperpour not_allowed)
			(footprints allowed)
		)
		(placement
			(enabled no)
			(sheetname "")
		)
		(fill yes
			(thermal_gap 0.5)
			(thermal_bridge_width 0.5)
			(island_removal_mode 0)
		)
		(polygon
			(pts
				(arc
					(start 115.679728 -278.946356)
					(mid 115.049808 -278.946356)
					(end 115.679728 -278.946356)
				)
			)
		)
	)
	(zone
		(layers "B.Cu" "In13.Cu" "In15.Cu")
		(hatch none 0.5)
		(connect_pads
			(clearance 0)
		)
		(min_thickness 0.25)
		(keepout
			(tracks not_allowed)
			(vias allowed)
			(pads allowed)
			(copperpour not_allowed)
			(footprints allowed)
		)
		(placement
			(enabled no)
			(sheetname "")
		)
		(fill yes
			(thermal_gap 0.5)
			(thermal_bridge_width 0.5)
			(island_removal_mode 0)
		)
		(polygon
			(pts
				(arc
					(start 202.481942 -272.98523)
					(mid 201.813922 -272.98523)
					(end 202.481942 -272.98523)
				)
			)
		)
	)
	(zone
		(layers "B.Cu" "In13.Cu" "In15.Cu")
		(hatch none 0.5)
		(connect_pads
			(clearance 0)
		)
		(min_thickness 0.25)
		(keepout
			(tracks not_allowed)
			(vias allowed)
			(pads allowed)
			(copperpour not_allowed)
			(footprints allowed)
		)
		(placement
			(enabled no)
			(sheetname "")
		)
		(fill yes
			(thermal_gap 0.5)
			(thermal_bridge_width 0.5)
			(island_removal_mode 0)
		)
		(polygon
			(pts
				(arc
					(start 87.833962 -388.774432)
					(mid 87.204042 -388.774432)
					(end 87.833962 -388.774432)
				)
			)
		)
	)
	(zone
		(layers "B.Cu" "In13.Cu" "In15.Cu")
		(hatch none 0.5)
		(connect_pads
			(clearance 0)
		)
		(min_thickness 0.25)
		(keepout
			(tracks not_allowed)
			(vias allowed)
			(pads allowed)
			(copperpour not_allowed)
			(footprints allowed)
		)
		(placement
			(enabled no)
			(sheetname "")
		)
		(fill yes
			(thermal_gap 0.5)
			(thermal_bridge_width 0.5)
			(island_removal_mode 0)
		)
		(polygon
			(pts
				(arc
					(start 83.43392 -389.467344)
					(mid 82.804 -389.467344)
					(end 83.43392 -389.467344)
				)
			)
		)
	)
	(zone
		(layers "B.Cu" "In13.Cu" "In15.Cu")
		(hatch none 0.5)
		(connect_pads
			(clearance 0)
		)
		(min_thickness 0.25)
		(keepout
			(tracks not_allowed)
			(vias allowed)
			(pads allowed)
			(copperpour not_allowed)
			(footprints allowed)
		)
		(placement
			(enabled no)
			(sheetname "")
		)
		(fill yes
			(thermal_gap 0.5)
			(thermal_bridge_width 0.5)
			(island_removal_mode 0)
		)
		(polygon
			(pts
				(arc
					(start 16.731488 -17.61236)
					(mid 16.063468 -17.61236)
					(end 16.731488 -17.61236)
				)
			)
		)
	)
	(zone
		(layers "B.Cu" "In13.Cu" "In15.Cu")
		(hatch none 0.5)
		(connect_pads
			(clearance 0)
		)
		(min_thickness 0.25)
		(keepout
			(tracks not_allowed)
			(vias allowed)
			(pads allowed)
			(copperpour not_allowed)
			(footprints allowed)
		)
		(placement
			(enabled no)
			(sheetname "")
		)
		(fill yes
			(thermal_gap 0.5)
			(thermal_bridge_width 0.5)
			(island_removal_mode 0)
		)
		(polygon
			(pts
				(arc
					(start 86.545928 -262.746236)
					(mid 85.916008 -262.746236)
					(end 86.545928 -262.746236)
				)
			)
		)
	)
	(zone
		(layers "B.Cu" "In13.Cu" "In15.Cu")
		(hatch none 0.5)
		(connect_pads
			(clearance 0)
		)
		(min_thickness 0.25)
		(keepout
			(tracks not_allowed)
			(vias allowed)
			(pads allowed)
			(copperpour not_allowed)
			(footprints allowed)
		)
		(placement
			(enabled no)
			(sheetname "")
		)
		(fill yes
			(thermal_gap 0.5)
			(thermal_bridge_width 0.5)
			(island_removal_mode 0)
		)
		(polygon
			(pts
				(arc
					(start 202.481942 -299.335444)
					(mid 201.813922 -299.335444)
					(end 202.481942 -299.335444)
				)
			)
		)
	)
	(zone
		(layers "B.Cu" "In13.Cu" "In15.Cu")
		(hatch none 0.5)
		(connect_pads
			(clearance 0)
		)
		(min_thickness 0.25)
		(keepout
			(tracks not_allowed)
			(vias allowed)
			(pads allowed)
			(copperpour not_allowed)
			(footprints allowed)
		)
		(placement
			(enabled no)
			(sheetname "")
		)
		(fill yes
			(thermal_gap 0.5)
			(thermal_bridge_width 0.5)
			(island_removal_mode 0)
		)
		(polygon
			(pts
				(arc
					(start 88.037162 -430.889918)
					(mid 87.26297 -430.889918)
					(end 88.037162 -430.889918)
				)
			)
		)
	)
	(zone
		(layers "B.Cu" "In13.Cu" "In15.Cu")
		(hatch none 0.5)
		(connect_pads
			(clearance 0)
		)
		(min_thickness 0.25)
		(keepout
			(tracks not_allowed)
			(vias allowed)
			(pads allowed)
			(copperpour not_allowed)
			(footprints allowed)
		)
		(placement
			(enabled no)
			(sheetname "")
		)
		(fill yes
			(thermal_gap 0.5)
			(thermal_bridge_width 0.5)
			(island_removal_mode 0)
		)
		(polygon
			(pts
				(arc
					(start 334.016096 -278.136096)
					(mid 333.386176 -278.136096)
					(end 334.016096 -278.136096)
				)
			)
		)
	)
	(zone
		(layers "B.Cu" "In13.Cu" "In15.Cu")
		(hatch none 0.5)
		(connect_pads
			(clearance 0)
		)
		(min_thickness 0.25)
		(keepout
			(tracks not_allowed)
			(vias allowed)
			(pads allowed)
			(copperpour not_allowed)
			(footprints allowed)
		)
		(placement
			(enabled no)
			(sheetname "")
		)
		(fill yes
			(thermal_gap 0.5)
			(thermal_bridge_width 0.5)
			(island_removal_mode 0)
		)
		(polygon
			(pts
				(arc
					(start 202.481942 -215.185244)
					(mid 201.813922 -215.185244)
					(end 202.481942 -215.185244)
				)
			)
		)
	)
	(zone
		(layers "B.Cu" "In13.Cu" "In15.Cu")
		(hatch none 0.5)
		(connect_pads
			(clearance 0)
		)
		(min_thickness 0.25)
		(keepout
			(tracks not_allowed)
			(vias allowed)
			(pads allowed)
			(copperpour not_allowed)
			(footprints allowed)
		)
		(placement
			(enabled no)
			(sheetname "")
		)
		(fill yes
			(thermal_gap 0.5)
			(thermal_bridge_width 0.5)
			(island_removal_mode 0)
		)
		(polygon
			(pts
				(arc
					(start 334.186022 -235.574078)
					(mid 333.556102 -235.574078)
					(end 334.186022 -235.574078)
				)
			)
		)
	)
	(zone
		(layers "B.Cu" "In13.Cu" "In15.Cu")
		(hatch none 0.5)
		(connect_pads
			(clearance 0)
		)
		(min_thickness 0.25)
		(keepout
			(tracks not_allowed)
			(vias allowed)
			(pads allowed)
			(copperpour not_allowed)
			(footprints allowed)
		)
		(placement
			(enabled no)
			(sheetname "")
		)
		(fill yes
			(thermal_gap 0.5)
			(thermal_bridge_width 0.5)
			(island_removal_mode 0)
		)
		(polygon
			(pts
				(arc
					(start 206.58201 -298.485306)
					(mid 205.91399 -298.485306)
					(end 206.58201 -298.485306)
				)
			)
		)
	)
	(zone
		(layers "B.Cu" "In13.Cu" "In15.Cu")
		(hatch none 0.5)
		(connect_pads
			(clearance 0)
		)
		(min_thickness 0.25)
		(keepout
			(tracks not_allowed)
			(vias allowed)
			(pads allowed)
			(copperpour not_allowed)
			(footprints allowed)
		)
		(placement
			(enabled no)
			(sheetname "")
		)
		(fill yes
			(thermal_gap 0.5)
			(thermal_bridge_width 0.5)
			(island_removal_mode 0)
		)
		(polygon
			(pts
				(arc
					(start 125.249686 -236.384338)
					(mid 124.619766 -236.384338)
					(end 125.249686 -236.384338)
				)
			)
		)
	)
	(zone
		(layers "B.Cu" "In13.Cu" "In15.Cu")
		(hatch none 0.5)
		(connect_pads
			(clearance 0)
		)
		(min_thickness 0.25)
		(keepout
			(tracks not_allowed)
			(vias allowed)
			(pads allowed)
			(copperpour not_allowed)
			(footprints allowed)
		)
		(placement
			(enabled no)
			(sheetname "")
		)
		(fill yes
			(thermal_gap 0.5)
			(thermal_bridge_width 0.5)
			(island_removal_mode 0)
		)
		(polygon
			(pts
				(arc
					(start 138.40968 -249.344434)
					(mid 137.77976 -249.344434)
					(end 138.40968 -249.344434)
				)
			)
		)
	)
	(zone
		(layers "B.Cu" "In13.Cu" "In15.Cu")
		(hatch none 0.5)
		(connect_pads
			(clearance 0)
		)
		(min_thickness 0.25)
		(keepout
			(tracks not_allowed)
			(vias allowed)
			(pads allowed)
			(copperpour not_allowed)
			(footprints allowed)
		)
		(placement
			(enabled no)
			(sheetname "")
		)
		(fill yes
			(thermal_gap 0.5)
			(thermal_bridge_width 0.5)
			(island_removal_mode 0)
		)
		(polygon
			(pts
				(arc
					(start 332.306168 -240.434114)
					(mid 331.676248 -240.434114)
					(end 332.306168 -240.434114)
				)
			)
		)
	)
	(zone
		(layers "B.Cu" "In13.Cu" "In15.Cu")
		(hatch none 0.5)
		(connect_pads
			(clearance 0)
		)
		(min_thickness 0.25)
		(keepout
			(tracks not_allowed)
			(vias allowed)
			(pads allowed)
			(copperpour not_allowed)
			(footprints allowed)
		)
		(placement
			(enabled no)
			(sheetname "")
		)
		(fill yes
			(thermal_gap 0.5)
			(thermal_bridge_width 0.5)
			(island_removal_mode 0)
		)
		(polygon
			(pts
				(arc
					(start 269.982188 -238.13516)
					(mid 269.314168 -238.13516)
					(end 269.982188 -238.13516)
				)
			)
		)
	)
	(zone
		(layers "B.Cu" "In13.Cu" "In15.Cu")
		(hatch none 0.5)
		(connect_pads
			(clearance 0)
		)
		(min_thickness 0.25)
		(keepout
			(tracks not_allowed)
			(vias allowed)
			(pads allowed)
			(copperpour not_allowed)
			(footprints allowed)
		)
		(placement
			(enabled no)
			(sheetname "")
		)
		(fill yes
			(thermal_gap 0.5)
			(thermal_bridge_width 0.5)
			(island_removal_mode 0)
		)
		(polygon
			(pts
				(arc
					(start 269.982188 -229.63505)
					(mid 269.314168 -229.63505)
					(end 269.982188 -229.63505)
				)
			)
		)
	)
	(zone
		(layers "B.Cu" "In13.Cu" "In15.Cu")
		(hatch none 0.5)
		(connect_pads
			(clearance 0)
		)
		(min_thickness 0.25)
		(keepout
			(tracks not_allowed)
			(vias allowed)
			(pads allowed)
			(copperpour not_allowed)
			(footprints allowed)
		)
		(placement
			(enabled no)
			(sheetname "")
		)
		(fill yes
			(thermal_gap 0.5)
			(thermal_bridge_width 0.5)
			(island_removal_mode 0)
		)
		(polygon
			(pts
				(arc
					(start 72.634094 -412.570168)
					(mid 71.966074 -412.570168)
					(end 72.634094 -412.570168)
				)
			)
		)
	)
	(zone
		(layers "B.Cu" "In13.Cu" "In15.Cu")
		(hatch none 0.5)
		(connect_pads
			(clearance 0)
		)
		(min_thickness 0.25)
		(keepout
			(tracks not_allowed)
			(vias allowed)
			(pads allowed)
			(copperpour not_allowed)
			(footprints allowed)
		)
		(placement
			(enabled no)
			(sheetname "")
		)
		(fill yes
			(thermal_gap 0.5)
			(thermal_bridge_width 0.5)
			(island_removal_mode 0)
		)
		(polygon
			(pts
				(arc
					(start 88.813894 -412.570168)
					(mid 88.145874 -412.570168)
					(end 88.813894 -412.570168)
				)
			)
		)
	)
	(zone
		(layers "B.Cu" "In13.Cu" "In15.Cu")
		(hatch none 0.5)
		(connect_pads
			(clearance 0)
		)
		(min_thickness 0.25)
		(keepout
			(tracks not_allowed)
			(vias allowed)
			(pads allowed)
			(copperpour not_allowed)
			(footprints allowed)
		)
		(placement
			(enabled no)
			(sheetname "")
		)
		(fill yes
			(thermal_gap 0.5)
			(thermal_bridge_width 0.5)
			(island_removal_mode 0)
		)
		(polygon
			(pts
				(arc
					(start 123.369578 -233.144314)
					(mid 122.739658 -233.144314)
					(end 123.369578 -233.144314)
				)
			)
		)
	)
	(zone
		(layers "B.Cu" "In13.Cu" "In15.Cu")
		(hatch none 0.5)
		(connect_pads
			(clearance 0)
		)
		(min_thickness 0.25)
		(keepout
			(tracks not_allowed)
			(vias allowed)
			(pads allowed)
			(copperpour not_allowed)
			(footprints allowed)
		)
		(placement
			(enabled no)
			(sheetname "")
		)
		(fill yes
			(thermal_gap 0.5)
			(thermal_bridge_width 0.5)
			(island_removal_mode 0)
		)
		(polygon
			(pts
				(arc
					(start 386.179822 -264.365994)
					(mid 385.549902 -264.365994)
					(end 386.179822 -264.365994)
				)
			)
		)
	)
	(zone
		(layers "B.Cu" "In13.Cu" "In15.Cu")
		(hatch none 0.5)
		(connect_pads
			(clearance 0)
		)
		(min_thickness 0.25)
		(keepout
			(tracks not_allowed)
			(vias allowed)
			(pads allowed)
			(copperpour not_allowed)
			(footprints allowed)
		)
		(placement
			(enabled no)
			(sheetname "")
		)
		(fill yes
			(thermal_gap 0.5)
			(thermal_bridge_width 0.5)
			(island_removal_mode 0)
		)
		(polygon
			(pts
				(arc
					(start 450.42201 -282.33497)
					(mid 449.75399 -282.33497)
					(end 450.42201 -282.33497)
				)
			)
		)
	)
	(zone
		(layers "B.Cu" "In13.Cu" "In15.Cu")
		(hatch none 0.5)
		(connect_pads
			(clearance 0)
		)
		(min_thickness 0.25)
		(keepout
			(tracks not_allowed)
			(vias allowed)
			(pads allowed)
			(copperpour not_allowed)
			(footprints allowed)
		)
		(placement
			(enabled no)
			(sheetname "")
		)
		(fill yes
			(thermal_gap 0.5)
			(thermal_bridge_width 0.5)
			(island_removal_mode 0)
		)
		(polygon
			(pts
				(arc
					(start 348.75597 -236.384084)
					(mid 348.12605 -236.384084)
					(end 348.75597 -236.384084)
				)
			)
		)
	)
	(zone
		(layers "B.Cu" "In13.Cu" "In15.Cu")
		(hatch none 0.5)
		(connect_pads
			(clearance 0)
		)
		(min_thickness 0.25)
		(keepout
			(tracks not_allowed)
			(vias allowed)
			(pads allowed)
			(copperpour not_allowed)
			(footprints allowed)
		)
		(placement
			(enabled no)
			(sheetname "")
		)
		(fill yes
			(thermal_gap 0.5)
			(thermal_bridge_width 0.5)
			(island_removal_mode 0)
		)
		(polygon
			(pts
				(arc
					(start 44.977304 -17.61236)
					(mid 44.309284 -17.61236)
					(end 44.977304 -17.61236)
				)
			)
		)
	)
	(zone
		(layers "B.Cu" "In13.Cu" "In15.Cu")
		(hatch none 0.5)
		(connect_pads
			(clearance 0)
		)
		(min_thickness 0.25)
		(keepout
			(tracks not_allowed)
			(vias allowed)
			(pads allowed)
			(copperpour not_allowed)
			(footprints allowed)
		)
		(placement
			(enabled no)
			(sheetname "")
		)
		(fill yes
			(thermal_gap 0.5)
			(thermal_bridge_width 0.5)
			(island_removal_mode 0)
		)
		(polygon
			(pts
				(arc
					(start 409.137104 -430.689766)
					(mid 408.362912 -430.689766)
					(end 409.137104 -430.689766)
				)
			)
		)
	)
	(zone
		(layers "B.Cu" "In13.Cu" "In15.Cu")
		(hatch none 0.5)
		(connect_pads
			(clearance 0)
		)
		(min_thickness 0.25)
		(keepout
			(tracks not_allowed)
			(vias allowed)
			(pads allowed)
			(copperpour not_allowed)
			(footprints allowed)
		)
		(placement
			(enabled no)
			(sheetname "")
		)
		(fill yes
			(thermal_gap 0.5)
			(thermal_bridge_width 0.5)
			(island_removal_mode 0)
		)
		(polygon
			(pts
				(arc
					(start 363.619796 -277.32609)
					(mid 362.989876 -277.32609)
					(end 363.619796 -277.32609)
				)
			)
		)
	)
	(zone
		(layers "B.Cu" "In13.Cu" "In15.Cu")
		(hatch none 0.5)
		(connect_pads
			(clearance 0)
		)
		(min_thickness 0.25)
		(keepout
			(tracks not_allowed)
			(vias allowed)
			(pads allowed)
			(copperpour not_allowed)
			(footprints allowed)
		)
		(placement
			(enabled no)
			(sheetname "")
		)
		(fill yes
			(thermal_gap 0.5)
			(thermal_bridge_width 0.5)
			(island_removal_mode 0)
		)
		(polygon
			(pts
				(arc
					(start 269.982188 -266.185142)
					(mid 269.314168 -266.185142)
					(end 269.982188 -266.185142)
				)
			)
		)
	)
	(zone
		(layers "B.Cu" "In13.Cu" "In15.Cu")
		(hatch none 0.5)
		(connect_pads
			(clearance 0)
		)
		(min_thickness 0.25)
		(keepout
			(tracks not_allowed)
			(vias allowed)
			(pads allowed)
			(copperpour not_allowed)
			(footprints allowed)
		)
		(placement
			(enabled no)
			(sheetname "")
		)
		(fill yes
			(thermal_gap 0.5)
			(thermal_bridge_width 0.5)
			(island_removal_mode 0)
		)
		(polygon
			(pts
				(arc
					(start 138.709654 -274.896326)
					(mid 138.079734 -274.896326)
					(end 138.709654 -274.896326)
				)
			)
		)
	)
	(zone
		(layers "B.Cu" "In13.Cu" "In15.Cu")
		(hatch none 0.5)
		(connect_pads
			(clearance 0)
		)
		(min_thickness 0.25)
		(keepout
			(tracks not_allowed)
			(vias allowed)
			(pads allowed)
			(copperpour not_allowed)
			(footprints allowed)
		)
		(placement
			(enabled no)
			(sheetname "")
		)
		(fill yes
			(thermal_gap 0.5)
			(thermal_bridge_width 0.5)
			(island_removal_mode 0)
		)
		(polygon
			(pts
				(arc
					(start 22.04212 -208.38541)
					(mid 21.3741 -208.38541)
					(end 22.04212 -208.38541)
				)
			)
		)
	)
	(zone
		(layers "B.Cu" "In13.Cu" "In15.Cu")
		(hatch none 0.5)
		(connect_pads
			(clearance 0)
		)
		(min_thickness 0.25)
		(keepout
			(tracks not_allowed)
			(vias allowed)
			(pads allowed)
			(copperpour not_allowed)
			(footprints allowed)
		)
		(placement
			(enabled no)
			(sheetname "")
		)
		(fill yes
			(thermal_gap 0.5)
			(thermal_bridge_width 0.5)
			(island_removal_mode 0)
		)
		(polygon
			(pts
				(arc
					(start 388.059676 -287.045908)
					(mid 387.429756 -287.045908)
					(end 388.059676 -287.045908)
				)
			)
		)
	)
	(zone
		(layers "B.Cu" "In13.Cu" "In15.Cu")
		(hatch none 0.5)
		(connect_pads
			(clearance 0)
		)
		(min_thickness 0.25)
		(keepout
			(tracks not_allowed)
			(vias allowed)
			(pads allowed)
			(copperpour not_allowed)
			(footprints allowed)
		)
		(placement
			(enabled no)
			(sheetname "")
		)
		(fill yes
			(thermal_gap 0.5)
			(thermal_bridge_width 0.5)
			(island_removal_mode 0)
		)
		(polygon
			(pts
				(arc
					(start 202.481942 -220.28531)
					(mid 201.813922 -220.28531)
					(end 202.481942 -220.28531)
				)
			)
		)
	)
	(zone
		(layers "B.Cu" "In13.Cu" "In15.Cu")
		(hatch none 0.5)
		(connect_pads
			(clearance 0)
		)
		(min_thickness 0.25)
		(keepout
			(tracks not_allowed)
			(vias allowed)
			(pads allowed)
			(copperpour not_allowed)
			(footprints allowed)
		)
		(placement
			(enabled no)
			(sheetname "")
		)
		(fill yes
			(thermal_gap 0.5)
			(thermal_bridge_width 0.5)
			(island_removal_mode 0)
		)
		(polygon
			(pts
				(arc
					(start 106.755946 -276.516338)
					(mid 106.126026 -276.516338)
					(end 106.755946 -276.516338)
				)
			)
		)
	)
	(zone
		(layers "B.Cu" "In13.Cu" "In15.Cu")
		(hatch none 0.5)
		(connect_pads
			(clearance 0)
		)
		(min_thickness 0.25)
		(keepout
			(tracks not_allowed)
			(vias allowed)
			(pads allowed)
			(copperpour not_allowed)
			(footprints allowed)
		)
		(placement
			(enabled no)
			(sheetname "")
		)
		(fill yes
			(thermal_gap 0.5)
			(thermal_bridge_width 0.5)
			(island_removal_mode 0)
		)
		(polygon
			(pts
				(arc
					(start 394.711682 -384.475228)
					(mid 394.043662 -384.475228)
					(end 394.711682 -384.475228)
				)
			)
		)
	)
	(zone
		(layers "B.Cu" "In13.Cu" "In15.Cu")
		(hatch none 0.5)
		(connect_pads
			(clearance 0)
		)
		(min_thickness 0.25)
		(keepout
			(tracks not_allowed)
			(vias allowed)
			(pads allowed)
			(copperpour not_allowed)
			(footprints allowed)
		)
		(placement
			(enabled no)
			(sheetname "")
		)
		(fill yes
			(thermal_gap 0.5)
			(thermal_bridge_width 0.5)
			(island_removal_mode 0)
		)
		(polygon
			(pts
				(arc
					(start 22.04212 -236.435392)
					(mid 21.3741 -236.435392)
					(end 22.04212 -236.435392)
				)
			)
		)
	)
	(zone
		(layers "B.Cu" "In13.Cu" "In15.Cu")
		(hatch none 0.5)
		(connect_pads
			(clearance 0)
		)
		(min_thickness 0.25)
		(keepout
			(tracks not_allowed)
			(vias allowed)
			(pads allowed)
			(copperpour not_allowed)
			(footprints allowed)
		)
		(placement
			(enabled no)
			(sheetname "")
		)
		(fill yes
			(thermal_gap 0.5)
			(thermal_bridge_width 0.5)
			(island_removal_mode 0)
		)
		(polygon
			(pts
				(arc
					(start 145.860516 -412.570168)
					(mid 145.192496 -412.570168)
					(end 145.860516 -412.570168)
				)
			)
		)
	)
	(zone
		(layers "B.Cu" "In13.Cu" "In15.Cu")
		(hatch none 0.5)
		(connect_pads
			(clearance 0)
		)
		(min_thickness 0.25)
		(keepout
			(tracks not_allowed)
			(vias allowed)
			(pads allowed)
			(copperpour not_allowed)
			(footprints allowed)
		)
		(placement
			(enabled no)
			(sheetname "")
		)
		(fill yes
			(thermal_gap 0.5)
			(thermal_bridge_width 0.5)
			(island_removal_mode 0)
		)
		(polygon
			(pts
				(arc
					(start 450.42201 -213.484968)
					(mid 449.75399 -213.484968)
					(end 450.42201 -213.484968)
				)
			)
		)
	)
	(zone
		(layers "B.Cu" "In13.Cu" "In15.Cu")
		(hatch none 0.5)
		(connect_pads
			(clearance 0)
		)
		(min_thickness 0.25)
		(keepout
			(tracks not_allowed)
			(vias allowed)
			(pads allowed)
			(copperpour not_allowed)
			(footprints allowed)
		)
		(placement
			(enabled no)
			(sheetname "")
		)
		(fill yes
			(thermal_gap 0.5)
			(thermal_bridge_width 0.5)
			(island_removal_mode 0)
		)
		(polygon
			(pts
				(arc
					(start 390.136888 -429.689768)
					(mid 389.362696 -429.689768)
					(end 390.136888 -429.689768)
				)
			)
		)
	)
	(zone
		(layers "B.Cu" "In13.Cu" "In15.Cu")
		(hatch none 0.5)
		(connect_pads
			(clearance 0)
		)
		(min_thickness 0.25)
		(keepout
			(tracks not_allowed)
			(vias allowed)
			(pads allowed)
			(copperpour not_allowed)
			(footprints allowed)
		)
		(placement
			(enabled no)
			(sheetname "")
		)
		(fill yes
			(thermal_gap 0.5)
			(thermal_bridge_width 0.5)
			(island_removal_mode 0)
		)
		(polygon
			(pts
				(arc
					(start 269.982188 -301.885096)
					(mid 269.314168 -301.885096)
					(end 269.982188 -301.885096)
				)
			)
		)
	)
	(zone
		(layers "B.Cu" "In13.Cu" "In15.Cu")
		(hatch none 0.5)
		(connect_pads
			(clearance 0)
		)
		(min_thickness 0.25)
		(keepout
			(tracks not_allowed)
			(vias allowed)
			(pads allowed)
			(copperpour not_allowed)
			(footprints allowed)
		)
		(placement
			(enabled no)
			(sheetname "")
		)
		(fill yes
			(thermal_gap 0.5)
			(thermal_bridge_width 0.5)
			(island_removal_mode 0)
		)
		(polygon
			(pts
				(arc
					(start 97.833942 -386.003292)
					(mid 97.204022 -386.003292)
					(end 97.833942 -386.003292)
				)
			)
		)
	)
	(zone
		(layers "B.Cu" "In13.Cu" "In15.Cu")
		(hatch none 0.5)
		(connect_pads
			(clearance 0)
		)
		(min_thickness 0.25)
		(keepout
			(tracks not_allowed)
			(vias allowed)
			(pads allowed)
			(copperpour not_allowed)
			(footprints allowed)
		)
		(placement
			(enabled no)
			(sheetname "")
		)
		(fill yes
			(thermal_gap 0.5)
			(thermal_bridge_width 0.5)
			(island_removal_mode 0)
		)
		(polygon
			(pts
				(arc
					(start 269.982188 -303.585118)
					(mid 269.314168 -303.585118)
					(end 269.982188 -303.585118)
				)
			)
		)
	)
	(zone
		(layers "B.Cu" "In13.Cu" "In15.Cu")
		(hatch none 0.5)
		(connect_pads
			(clearance 0)
		)
		(min_thickness 0.25)
		(keepout
			(tracks not_allowed)
			(vias allowed)
			(pads allowed)
			(copperpour not_allowed)
			(footprints allowed)
		)
		(placement
			(enabled no)
			(sheetname "")
		)
		(fill yes
			(thermal_gap 0.5)
			(thermal_bridge_width 0.5)
			(island_removal_mode 0)
		)
		(polygon
			(pts
				(arc
					(start 355.336094 -234.764072)
					(mid 354.706174 -234.764072)
					(end 355.336094 -234.764072)
				)
			)
		)
	)
	(zone
		(layers "B.Cu" "In13.Cu" "In15.Cu")
		(hatch none 0.5)
		(connect_pads
			(clearance 0)
		)
		(min_thickness 0.25)
		(keepout
			(tracks not_allowed)
			(vias allowed)
			(pads allowed)
			(copperpour not_allowed)
			(footprints allowed)
		)
		(placement
			(enabled no)
			(sheetname "")
		)
		(fill yes
			(thermal_gap 0.5)
			(thermal_bridge_width 0.5)
			(island_removal_mode 0)
		)
		(polygon
			(pts
				(arc
					(start 202.481942 -276.385274)
					(mid 201.813922 -276.385274)
					(end 202.481942 -276.385274)
				)
			)
		)
	)
	(zone
		(layers "B.Cu" "In13.Cu" "In15.Cu")
		(hatch none 0.5)
		(connect_pads
			(clearance 0)
		)
		(min_thickness 0.25)
		(keepout
			(tracks not_allowed)
			(vias allowed)
			(pads allowed)
			(copperpour not_allowed)
			(footprints allowed)
		)
		(placement
			(enabled no)
			(sheetname "")
		)
		(fill yes
			(thermal_gap 0.5)
			(thermal_bridge_width 0.5)
			(island_removal_mode 0)
		)
		(polygon
			(pts
				(arc
					(start 386.179822 -291.905944)
					(mid 385.549902 -291.905944)
					(end 386.179822 -291.905944)
				)
			)
		)
	)
	(zone
		(layers "B.Cu" "In13.Cu" "In15.Cu")
		(hatch none 0.5)
		(connect_pads
			(clearance 0)
		)
		(min_thickness 0.25)
		(keepout
			(tracks not_allowed)
			(vias allowed)
			(pads allowed)
			(copperpour not_allowed)
			(footprints allowed)
		)
		(placement
			(enabled no)
			(sheetname "")
		)
		(fill yes
			(thermal_gap 0.5)
			(thermal_bridge_width 0.5)
			(island_removal_mode 0)
		)
		(polygon
			(pts
				(arc
					(start 136.136888 -430.689766)
					(mid 135.362696 -430.689766)
					(end 136.136888 -430.689766)
				)
			)
		)
	)
	(zone
		(layers "B.Cu" "In13.Cu" "In15.Cu")
		(hatch none 0.5)
		(connect_pads
			(clearance 0)
		)
		(min_thickness 0.25)
		(keepout
			(tracks not_allowed)
			(vias allowed)
			(pads allowed)
			(copperpour not_allowed)
			(footprints allowed)
		)
		(placement
			(enabled no)
			(sheetname "")
		)
		(fill yes
			(thermal_gap 0.5)
			(thermal_bridge_width 0.5)
			(island_removal_mode 0)
		)
		(polygon
			(pts
				(arc
					(start 117.256306 -371.49913)
					(mid 116.588286 -371.49913)
					(end 117.256306 -371.49913)
				)
			)
		)
	)
	(zone
		(layers "B.Cu" "In13.Cu" "In15.Cu")
		(hatch none 0.5)
		(connect_pads
			(clearance 0)
		)
		(min_thickness 0.25)
		(keepout
			(tracks not_allowed)
			(vias allowed)
			(pads allowed)
			(copperpour not_allowed)
			(footprints allowed)
		)
		(placement
			(enabled no)
			(sheetname "")
		)
		(fill yes
			(thermal_gap 0.5)
			(thermal_bridge_width 0.5)
			(island_removal_mode 0)
		)
		(polygon
			(pts
				(arc
					(start 85.135974 -265.176254)
					(mid 84.506054 -265.176254)
					(end 85.135974 -265.176254)
				)
			)
		)
	)
	(zone
		(layers "B.Cu" "In13.Cu" "In15.Cu")
		(hatch none 0.5)
		(connect_pads
			(clearance 0)
		)
		(min_thickness 0.25)
		(keepout
			(tracks not_allowed)
			(vias allowed)
			(pads allowed)
			(copperpour not_allowed)
			(footprints allowed)
		)
		(placement
			(enabled no)
			(sheetname "")
		)
		(fill yes
			(thermal_gap 0.5)
			(thermal_bridge_width 0.5)
			(island_removal_mode 0)
		)
		(polygon
			(pts
				(arc
					(start 365.02975 -276.516084)
					(mid 364.39983 -276.516084)
					(end 365.02975 -276.516084)
				)
			)
		)
	)
	(zone
		(layers "B.Cu" "In13.Cu" "In15.Cu")
		(hatch none 0.5)
		(connect_pads
			(clearance 0)
		)
		(min_thickness 0.25)
		(keepout
			(tracks not_allowed)
			(vias allowed)
			(pads allowed)
			(copperpour not_allowed)
			(footprints allowed)
		)
		(placement
			(enabled no)
			(sheetname "")
		)
		(fill yes
			(thermal_gap 0.5)
			(thermal_bridge_width 0.5)
			(island_removal_mode 0)
		)
		(polygon
			(pts
				(arc
					(start 347.876876 -420.952168)
					(mid 347.208856 -420.952168)
					(end 347.876876 -420.952168)
				)
			)
		)
	)
	(zone
		(layers "B.Cu" "In13.Cu" "In15.Cu")
		(hatch none 0.5)
		(connect_pads
			(clearance 0)
		)
		(min_thickness 0.25)
		(keepout
			(tracks not_allowed)
			(vias allowed)
			(pads allowed)
			(copperpour not_allowed)
			(footprints allowed)
		)
		(placement
			(enabled no)
			(sheetname "")
		)
		(fill yes
			(thermal_gap 0.5)
			(thermal_bridge_width 0.5)
			(island_removal_mode 0)
		)
		(polygon
			(pts
				(arc
					(start 17.942052 -272.98523)
					(mid 17.274032 -272.98523)
					(end 17.942052 -272.98523)
				)
			)
		)
	)
	(zone
		(layers "B.Cu" "In13.Cu" "In15.Cu")
		(hatch none 0.5)
		(connect_pads
			(clearance 0)
		)
		(min_thickness 0.25)
		(keepout
			(tracks not_allowed)
			(vias allowed)
			(pads allowed)
			(copperpour not_allowed)
			(footprints allowed)
		)
		(placement
			(enabled no)
			(sheetname "")
		)
		(fill yes
			(thermal_gap 0.5)
			(thermal_bridge_width 0.5)
			(island_removal_mode 0)
		)
		(polygon
			(pts
				(arc
					(start 388.059676 -272.466054)
					(mid 387.429756 -272.466054)
					(end 388.059676 -272.466054)
				)
			)
		)
	)
	(zone
		(layers "B.Cu" "In13.Cu" "In15.Cu")
		(hatch none 0.5)
		(connect_pads
			(clearance 0)
		)
		(min_thickness 0.25)
		(keepout
			(tracks not_allowed)
			(vias allowed)
			(pads allowed)
			(copperpour not_allowed)
			(footprints allowed)
		)
		(placement
			(enabled no)
			(sheetname "")
		)
		(fill yes
			(thermal_gap 0.5)
			(thermal_bridge_width 0.5)
			(island_removal_mode 0)
		)
		(polygon
			(pts
				(arc
					(start 332.606142 -264.365994)
					(mid 331.976222 -264.365994)
					(end 332.606142 -264.365994)
				)
			)
		)
	)
	(zone
		(layers "B.Cu" "In13.Cu" "In15.Cu")
		(hatch none 0.5)
		(connect_pads
			(clearance 0)
		)
		(min_thickness 0.25)
		(keepout
			(tracks not_allowed)
			(vias allowed)
			(pads allowed)
			(copperpour not_allowed)
			(footprints allowed)
		)
		(placement
			(enabled no)
			(sheetname "")
		)
		(fill yes
			(thermal_gap 0.5)
			(thermal_bridge_width 0.5)
			(island_removal_mode 0)
		)
		(polygon
			(pts
				(arc
					(start 110.046008 -278.946356)
					(mid 109.416088 -278.946356)
					(end 110.046008 -278.946356)
				)
			)
		)
	)
	(zone
		(layers "B.Cu" "In13.Cu" "In15.Cu")
		(hatch none 0.5)
		(connect_pads
			(clearance 0)
		)
		(min_thickness 0.25)
		(keepout
			(tracks not_allowed)
			(vias allowed)
			(pads allowed)
			(copperpour not_allowed)
			(footprints allowed)
		)
		(placement
			(enabled no)
			(sheetname "")
		)
		(fill yes
			(thermal_gap 0.5)
			(thermal_bridge_width 0.5)
			(island_removal_mode 0)
		)
		(polygon
			(pts
				(arc
					(start 374.129808 -244.484144)
					(mid 373.499888 -244.484144)
					(end 374.129808 -244.484144)
				)
			)
		)
	)
	(zone
		(layers "B.Cu" "In13.Cu" "In15.Cu")
		(hatch none 0.5)
		(connect_pads
			(clearance 0)
		)
		(min_thickness 0.25)
		(keepout
			(tracks not_allowed)
			(vias allowed)
			(pads allowed)
			(copperpour not_allowed)
			(footprints allowed)
		)
		(placement
			(enabled no)
			(sheetname "")
		)
		(fill yes
			(thermal_gap 0.5)
			(thermal_bridge_width 0.5)
			(island_removal_mode 0)
		)
		(polygon
			(pts
				(arc
					(start 454.522078 -292.535102)
					(mid 453.854058 -292.535102)
					(end 454.522078 -292.535102)
				)
			)
		)
	)
	(zone
		(layers "B.Cu" "In13.Cu" "In15.Cu")
		(hatch none 0.5)
		(connect_pads
			(clearance 0)
		)
		(min_thickness 0.25)
		(keepout
			(tracks not_allowed)
			(vias allowed)
			(pads allowed)
			(copperpour not_allowed)
			(footprints allowed)
		)
		(placement
			(enabled no)
			(sheetname "")
		)
		(fill yes
			(thermal_gap 0.5)
			(thermal_bridge_width 0.5)
			(island_removal_mode 0)
		)
		(polygon
			(pts
				(arc
					(start 404.649686 -6.725158)
					(mid 403.981666 -6.725158)
					(end 404.649686 -6.725158)
				)
			)
		)
	)
	(zone
		(layers "B.Cu" "In13.Cu" "In15.Cu")
		(hatch none 0.5)
		(connect_pads
			(clearance 0)
		)
		(min_thickness 0.25)
		(keepout
			(tracks not_allowed)
			(vias allowed)
			(pads allowed)
			(copperpour not_allowed)
			(footprints allowed)
		)
		(placement
			(enabled no)
			(sheetname "")
		)
		(fill yes
			(thermal_gap 0.5)
			(thermal_bridge_width 0.5)
			(island_removal_mode 0)
		)
		(polygon
			(pts
				(arc
					(start 340.886796 -420.952168)
					(mid 340.218776 -420.952168)
					(end 340.886796 -420.952168)
				)
			)
		)
	)
	(zone
		(layers "B.Cu" "In13.Cu" "In15.Cu")
		(hatch none 0.5)
		(connect_pads
			(clearance 0)
		)
		(min_thickness 0.25)
		(keepout
			(tracks not_allowed)
			(vias allowed)
			(pads allowed)
			(copperpour not_allowed)
			(footprints allowed)
		)
		(placement
			(enabled no)
			(sheetname "")
		)
		(fill yes
			(thermal_gap 0.5)
			(thermal_bridge_width 0.5)
			(island_removal_mode 0)
		)
		(polygon
			(pts
				(arc
					(start 22.04212 -197.335394)
					(mid 21.3741 -197.335394)
					(end 22.04212 -197.335394)
				)
			)
		)
	)
	(zone
		(layers "B.Cu" "In13.Cu" "In15.Cu")
		(hatch none 0.5)
		(connect_pads
			(clearance 0)
		)
		(min_thickness 0.25)
		(keepout
			(tracks not_allowed)
			(vias allowed)
			(pads allowed)
			(copperpour not_allowed)
			(footprints allowed)
		)
		(placement
			(enabled no)
			(sheetname "")
		)
		(fill yes
			(thermal_gap 0.5)
			(thermal_bridge_width 0.5)
			(island_removal_mode 0)
		)
		(polygon
			(pts
				(arc
					(start 85.135974 -281.376374)
					(mid 84.506054 -281.376374)
					(end 85.135974 -281.376374)
				)
			)
		)
	)
	(zone
		(layers "B.Cu" "In13.Cu" "In15.Cu")
		(hatch none 0.5)
		(connect_pads
			(clearance 0)
		)
		(min_thickness 0.25)
		(keepout
			(tracks not_allowed)
			(vias allowed)
			(pads allowed)
			(copperpour not_allowed)
			(footprints allowed)
		)
		(placement
			(enabled no)
			(sheetname "")
		)
		(fill yes
			(thermal_gap 0.5)
			(thermal_bridge_width 0.5)
			(island_removal_mode 0)
		)
		(polygon
			(pts
				(arc
					(start 85.135974 -263.556242)
					(mid 84.506054 -263.556242)
					(end 85.135974 -263.556242)
				)
			)
		)
	)
	(zone
		(layers "B.Cu" "In13.Cu" "In15.Cu")
		(hatch none 0.5)
		(connect_pads
			(clearance 0)
		)
		(min_thickness 0.25)
		(keepout
			(tracks not_allowed)
			(vias allowed)
			(pads allowed)
			(copperpour not_allowed)
			(footprints allowed)
		)
		(placement
			(enabled no)
			(sheetname "")
		)
		(fill yes
			(thermal_gap 0.5)
			(thermal_bridge_width 0.5)
			(island_removal_mode 0)
		)
		(polygon
			(pts
				(arc
					(start 84.3661 -248.534428)
					(mid 83.73618 -248.534428)
					(end 84.3661 -248.534428)
				)
			)
		)
	)
	(zone
		(layers "B.Cu" "In13.Cu" "In15.Cu")
		(hatch none 0.5)
		(connect_pads
			(clearance 0)
		)
		(min_thickness 0.25)
		(keepout
			(tracks not_allowed)
			(vias allowed)
			(pads allowed)
			(copperpour not_allowed)
			(footprints allowed)
		)
		(placement
			(enabled no)
			(sheetname "")
		)
		(fill yes
			(thermal_gap 0.5)
			(thermal_bridge_width 0.5)
			(island_removal_mode 0)
		)
		(polygon
			(pts
				(arc
					(start 202.481942 -216.885266)
					(mid 201.813922 -216.885266)
					(end 202.481942 -216.885266)
				)
			)
		)
	)
	(zone
		(layers "B.Cu" "In13.Cu" "In15.Cu")
		(hatch none 0.5)
		(connect_pads
			(clearance 0)
		)
		(min_thickness 0.25)
		(keepout
			(tracks not_allowed)
			(vias allowed)
			(pads allowed)
			(copperpour not_allowed)
			(footprints allowed)
		)
		(placement
			(enabled no)
			(sheetname "")
		)
		(fill yes
			(thermal_gap 0.5)
			(thermal_bridge_width 0.5)
			(island_removal_mode 0)
		)
		(polygon
			(pts
				(arc
					(start 202.481942 -286.585406)
					(mid 201.813922 -286.585406)
					(end 202.481942 -286.585406)
				)
			)
		)
	)
	(zone
		(layers "B.Cu" "In13.Cu" "In15.Cu")
		(hatch none 0.5)
		(connect_pads
			(clearance 0)
		)
		(min_thickness 0.25)
		(keepout
			(tracks not_allowed)
			(vias allowed)
			(pads allowed)
			(copperpour not_allowed)
			(footprints allowed)
		)
		(placement
			(enabled no)
			(sheetname "")
		)
		(fill yes
			(thermal_gap 0.5)
			(thermal_bridge_width 0.5)
			(island_removal_mode 0)
		)
		(polygon
			(pts
				(arc
					(start 388.059676 -274.086066)
					(mid 387.429756 -274.086066)
					(end 388.059676 -274.086066)
				)
			)
		)
	)
	(zone
		(layers "B.Cu" "In13.Cu" "In15.Cu")
		(hatch none 0.5)
		(connect_pads
			(clearance 0)
		)
		(min_thickness 0.25)
		(keepout
			(tracks not_allowed)
			(vias allowed)
			(pads allowed)
			(copperpour not_allowed)
			(footprints allowed)
		)
		(placement
			(enabled no)
			(sheetname "")
		)
		(fill yes
			(thermal_gap 0.5)
			(thermal_bridge_width 0.5)
			(island_removal_mode 0)
		)
		(polygon
			(pts
				(arc
					(start 454.522078 -298.485052)
					(mid 453.854058 -298.485052)
					(end 454.522078 -298.485052)
				)
			)
		)
	)
	(zone
		(layers "B.Cu" "In13.Cu" "In15.Cu")
		(hatch none 0.5)
		(connect_pads
			(clearance 0)
		)
		(min_thickness 0.25)
		(keepout
			(tracks not_allowed)
			(vias allowed)
			(pads allowed)
			(copperpour not_allowed)
			(footprints allowed)
		)
		(placement
			(enabled no)
			(sheetname "")
		)
		(fill yes
			(thermal_gap 0.5)
			(thermal_bridge_width 0.5)
			(island_removal_mode 0)
		)
		(polygon
			(pts
				(arc
					(start 340.036912 -430.889918)
					(mid 339.26272 -430.889918)
					(end 340.036912 -430.889918)
				)
			)
		)
	)
	(zone
		(layers "B.Cu" "In13.Cu" "In15.Cu")
		(hatch none 0.5)
		(connect_pads
			(clearance 0)
		)
		(min_thickness 0.25)
		(keepout
			(tracks not_allowed)
			(vias allowed)
			(pads allowed)
			(copperpour not_allowed)
			(footprints allowed)
		)
		(placement
			(enabled no)
			(sheetname "")
		)
		(fill yes
			(thermal_gap 0.5)
			(thermal_bridge_width 0.5)
			(island_removal_mode 0)
		)
		(polygon
			(pts
				(arc
					(start 450.42201 -198.185024)
					(mid 449.75399 -198.185024)
					(end 450.42201 -198.185024)
				)
			)
		)
	)
	(zone
		(layers "B.Cu" "In13.Cu" "In15.Cu")
		(hatch none 0.5)
		(connect_pads
			(clearance 0)
		)
		(min_thickness 0.25)
		(keepout
			(tracks not_allowed)
			(vias allowed)
			(pads allowed)
			(copperpour not_allowed)
			(footprints allowed)
		)
		(placement
			(enabled no)
			(sheetname "")
		)
		(fill yes
			(thermal_gap 0.5)
			(thermal_bridge_width 0.5)
			(island_removal_mode 0)
		)
		(polygon
			(pts
				(arc
					(start 80.634078 -388.774432)
					(mid 80.004158 -388.774432)
					(end 80.634078 -388.774432)
				)
			)
		)
	)
	(zone
		(layers "B.Cu" "In13.Cu" "In15.Cu")
		(hatch none 0.5)
		(connect_pads
			(clearance 0)
		)
		(min_thickness 0.25)
		(keepout
			(tracks not_allowed)
			(vias allowed)
			(pads allowed)
			(copperpour not_allowed)
			(footprints allowed)
		)
		(placement
			(enabled no)
			(sheetname "")
		)
		(fill yes
			(thermal_gap 0.5)
			(thermal_bridge_width 0.5)
			(island_removal_mode 0)
		)
		(polygon
			(pts
				(arc
					(start 387.289802 -236.384084)
					(mid 386.659882 -236.384084)
					(end 387.289802 -236.384084)
				)
			)
		)
	)
	(zone
		(layers "B.Cu" "In13.Cu" "In15.Cu")
		(hatch none 0.5)
		(connect_pads
			(clearance 0)
		)
		(min_thickness 0.25)
		(keepout
			(tracks not_allowed)
			(vias allowed)
			(pads allowed)
			(copperpour not_allowed)
			(footprints allowed)
		)
		(placement
			(enabled no)
			(sheetname "")
		)
		(fill yes
			(thermal_gap 0.5)
			(thermal_bridge_width 0.5)
			(island_removal_mode 0)
		)
		(polygon
			(pts
				(arc
					(start 137.93978 -245.294404)
					(mid 137.30986 -245.294404)
					(end 137.93978 -245.294404)
				)
			)
		)
	)
	(zone
		(layers "B.Cu" "In13.Cu" "In15.Cu")
		(hatch none 0.5)
		(connect_pads
			(clearance 0)
		)
		(min_thickness 0.25)
		(keepout
			(tracks not_allowed)
			(vias allowed)
			(pads allowed)
			(copperpour not_allowed)
			(footprints allowed)
		)
		(placement
			(enabled no)
			(sheetname "")
		)
		(fill yes
			(thermal_gap 0.5)
			(thermal_bridge_width 0.5)
			(island_removal_mode 0)
		)
		(polygon
			(pts
				(arc
					(start 269.982188 -208.385156)
					(mid 269.314168 -208.385156)
					(end 269.982188 -208.385156)
				)
			)
		)
	)
	(zone
		(layers "B.Cu" "In13.Cu" "In15.Cu")
		(hatch none 0.5)
		(connect_pads
			(clearance 0)
		)
		(min_thickness 0.25)
		(keepout
			(tracks not_allowed)
			(vias allowed)
			(pads allowed)
			(copperpour not_allowed)
			(footprints allowed)
		)
		(placement
			(enabled no)
			(sheetname "")
		)
		(fill yes
			(thermal_gap 0.5)
			(thermal_bridge_width 0.5)
			(island_removal_mode 0)
		)
		(polygon
			(pts
				(arc
					(start 84.666074 -288.666174)
					(mid 84.036154 -288.666174)
					(end 84.666074 -288.666174)
				)
			)
		)
	)
	(zone
		(layers "B.Cu" "In13.Cu" "In15.Cu")
		(hatch none 0.5)
		(connect_pads
			(clearance 0)
		)
		(min_thickness 0.25)
		(keepout
			(tracks not_allowed)
			(vias allowed)
			(pads allowed)
			(copperpour not_allowed)
			(footprints allowed)
		)
		(placement
			(enabled no)
			(sheetname "")
		)
		(fill yes
			(thermal_gap 0.5)
			(thermal_bridge_width 0.5)
			(island_removal_mode 0)
		)
		(polygon
			(pts
				(arc
					(start 84.666074 -262.746236)
					(mid 84.036154 -262.746236)
					(end 84.666074 -262.746236)
				)
			)
		)
	)
	(zone
		(layers "B.Cu" "In13.Cu" "In15.Cu")
		(hatch none 0.5)
		(connect_pads
			(clearance 0)
		)
		(min_thickness 0.25)
		(keepout
			(tracks not_allowed)
			(vias allowed)
			(pads allowed)
			(copperpour not_allowed)
			(footprints allowed)
		)
		(placement
			(enabled no)
			(sheetname "")
		)
		(fill yes
			(thermal_gap 0.5)
			(thermal_bridge_width 0.5)
			(island_removal_mode 0)
		)
		(polygon
			(pts
				(arc
					(start 353.433888 -393.69238)
					(mid 352.803968 -393.69238)
					(end 353.433888 -393.69238)
				)
			)
		)
	)
	(zone
		(layers "B.Cu" "In13.Cu" "In15.Cu")
		(hatch none 0.5)
		(connect_pads
			(clearance 0)
		)
		(min_thickness 0.25)
		(keepout
			(tracks not_allowed)
			(vias allowed)
			(pads allowed)
			(copperpour not_allowed)
			(footprints allowed)
		)
		(placement
			(enabled no)
			(sheetname "")
		)
		(fill yes
			(thermal_gap 0.5)
			(thermal_bridge_width 0.5)
			(island_removal_mode 0)
		)
		(polygon
			(pts
				(arc
					(start 42.183304 -19.13636)
					(mid 41.515284 -19.13636)
					(end 42.183304 -19.13636)
				)
			)
		)
	)
	(zone
		(layers "B.Cu" "In13.Cu" "In15.Cu")
		(hatch none 0.5)
		(connect_pads
			(clearance 0)
		)
		(min_thickness 0.25)
		(keepout
			(tracks not_allowed)
			(vias allowed)
			(pads allowed)
			(copperpour not_allowed)
			(footprints allowed)
		)
		(placement
			(enabled no)
			(sheetname "")
		)
		(fill yes
			(thermal_gap 0.5)
			(thermal_bridge_width 0.5)
			(island_removal_mode 0)
		)
		(polygon
			(pts
				(arc
					(start 450.42201 -205.834996)
					(mid 449.75399 -205.834996)
					(end 450.42201 -205.834996)
				)
			)
		)
	)
	(zone
		(layers "B.Cu" "In13.Cu" "In15.Cu")
		(hatch none 0.5)
		(connect_pads
			(clearance 0)
		)
		(min_thickness 0.25)
		(keepout
			(tracks not_allowed)
			(vias allowed)
			(pads allowed)
			(copperpour not_allowed)
			(footprints allowed)
		)
		(placement
			(enabled no)
			(sheetname "")
		)
		(fill yes
			(thermal_gap 0.5)
			(thermal_bridge_width 0.5)
			(island_removal_mode 0)
		)
		(polygon
			(pts
				(arc
					(start 17.942052 -288.285428)
					(mid 17.274032 -288.285428)
					(end 17.942052 -288.285428)
				)
			)
		)
	)
	(zone
		(layers "B.Cu" "In13.Cu" "In15.Cu")
		(hatch none 0.5)
		(connect_pads
			(clearance 0)
		)
		(min_thickness 0.25)
		(keepout
			(tracks not_allowed)
			(vias allowed)
			(pads allowed)
			(copperpour not_allowed)
			(footprints allowed)
		)
		(placement
			(enabled no)
			(sheetname "")
		)
		(fill yes
			(thermal_gap 0.5)
			(thermal_bridge_width 0.5)
			(island_removal_mode 0)
		)
		(polygon
			(pts
				(arc
					(start 269.982188 -204.985112)
					(mid 269.314168 -204.985112)
					(end 269.982188 -204.985112)
				)
			)
		)
	)
	(zone
		(layers "B.Cu" "In13.Cu" "In15.Cu")
		(hatch none 0.5)
		(connect_pads
			(clearance 0)
		)
		(min_thickness 0.25)
		(keepout
			(tracks not_allowed)
			(vias allowed)
			(pads allowed)
			(copperpour not_allowed)
			(footprints allowed)
		)
		(placement
			(enabled no)
			(sheetname "")
		)
		(fill yes
			(thermal_gap 0.5)
			(thermal_bridge_width 0.5)
			(island_removal_mode 0)
		)
		(polygon
			(pts
				(arc
					(start 76.560934 -412.570168)
					(mid 75.892914 -412.570168)
					(end 76.560934 -412.570168)
				)
			)
		)
	)
	(zone
		(layers "B.Cu" "In13.Cu" "In15.Cu")
		(hatch none 0.5)
		(connect_pads
			(clearance 0)
		)
		(min_thickness 0.25)
		(keepout
			(tracks not_allowed)
			(vias allowed)
			(pads allowed)
			(copperpour not_allowed)
			(footprints allowed)
		)
		(placement
			(enabled no)
			(sheetname "")
		)
		(fill yes
			(thermal_gap 0.5)
			(thermal_bridge_width 0.5)
			(island_removal_mode 0)
		)
		(polygon
			(pts
				(arc
					(start 17.942052 -277.235412)
					(mid 17.274032 -277.235412)
					(end 17.942052 -277.235412)
				)
			)
		)
	)
	(zone
		(layers "B.Cu" "In13.Cu" "In15.Cu")
		(hatch none 0.5)
		(connect_pads
			(clearance 0)
		)
		(min_thickness 0.25)
		(keepout
			(tracks not_allowed)
			(vias allowed)
			(pads allowed)
			(copperpour not_allowed)
			(footprints allowed)
		)
		(placement
			(enabled no)
			(sheetname "")
		)
		(fill yes
			(thermal_gap 0.5)
			(thermal_bridge_width 0.5)
			(island_removal_mode 0)
		)
		(polygon
			(pts
				(arc
					(start 22.04212 -278.085296)
					(mid 21.3741 -278.085296)
					(end 22.04212 -278.085296)
				)
			)
		)
	)
	(zone
		(layers "B.Cu" "In13.Cu" "In15.Cu")
		(hatch none 0.5)
		(connect_pads
			(clearance 0)
		)
		(min_thickness 0.25)
		(keepout
			(tracks not_allowed)
			(vias allowed)
			(pads allowed)
			(copperpour not_allowed)
			(footprints allowed)
		)
		(placement
			(enabled no)
			(sheetname "")
		)
		(fill yes
			(thermal_gap 0.5)
			(thermal_bridge_width 0.5)
			(island_removal_mode 0)
		)
		(polygon
			(pts
				(arc
					(start 450.42201 -235.585)
					(mid 449.75399 -235.585)
					(end 450.42201 -235.585)
				)
			)
		)
	)
	(zone
		(layers "B.Cu" "In13.Cu" "In15.Cu")
		(hatch none 0.5)
		(connect_pads
			(clearance 0)
		)
		(min_thickness 0.25)
		(keepout
			(tracks not_allowed)
			(vias allowed)
			(pads allowed)
			(copperpour not_allowed)
			(footprints allowed)
		)
		(placement
			(enabled no)
			(sheetname "")
		)
		(fill yes
			(thermal_gap 0.5)
			(thermal_bridge_width 0.5)
			(island_removal_mode 0)
		)
		(polygon
			(pts
				(arc
					(start 411.1371 -429.689768)
					(mid 410.362908 -429.689768)
					(end 411.1371 -429.689768)
				)
			)
		)
	)
	(zone
		(layers "B.Cu" "In13.Cu" "In15.Cu")
		(hatch none 0.5)
		(connect_pads
			(clearance 0)
		)
		(min_thickness 0.25)
		(keepout
			(tracks not_allowed)
			(vias allowed)
			(pads allowed)
			(copperpour not_allowed)
			(footprints allowed)
		)
		(placement
			(enabled no)
			(sheetname "")
		)
		(fill yes
			(thermal_gap 0.5)
			(thermal_bridge_width 0.5)
			(island_removal_mode 0)
		)
		(polygon
			(pts
				(arc
					(start 130.544316 -412.570168)
					(mid 129.876296 -412.570168)
					(end 130.544316 -412.570168)
				)
			)
		)
	)
	(zone
		(layers "B.Cu" "In13.Cu" "In15.Cu")
		(hatch none 0.5)
		(connect_pads
			(clearance 0)
		)
		(min_thickness 0.25)
		(keepout
			(tracks not_allowed)
			(vias allowed)
			(pads allowed)
			(copperpour not_allowed)
			(footprints allowed)
		)
		(placement
			(enabled no)
			(sheetname "")
		)
		(fill yes
			(thermal_gap 0.5)
			(thermal_bridge_width 0.5)
			(island_removal_mode 0)
		)
		(polygon
			(pts
				(arc
					(start 387.589776 -274.896072)
					(mid 386.959856 -274.896072)
					(end 387.589776 -274.896072)
				)
			)
		)
	)
	(zone
		(layers "B.Cu" "In13.Cu" "In15.Cu")
		(hatch none 0.5)
		(connect_pads
			(clearance 0)
		)
		(min_thickness 0.25)
		(keepout
			(tracks not_allowed)
			(vias allowed)
			(pads allowed)
			(copperpour not_allowed)
			(footprints allowed)
		)
		(placement
			(enabled no)
			(sheetname "")
		)
		(fill yes
			(thermal_gap 0.5)
			(thermal_bridge_width 0.5)
			(island_removal_mode 0)
		)
		(polygon
			(pts
				(arc
					(start 349.696024 -236.384084)
					(mid 349.066104 -236.384084)
					(end 349.696024 -236.384084)
				)
			)
		)
	)
	(zone
		(layers "B.Cu" "In13.Cu" "In15.Cu")
		(hatch none 0.5)
		(connect_pads
			(clearance 0)
		)
		(min_thickness 0.25)
		(keepout
			(tracks not_allowed)
			(vias allowed)
			(pads allowed)
			(copperpour not_allowed)
			(footprints allowed)
		)
		(placement
			(enabled no)
			(sheetname "")
		)
		(fill yes
			(thermal_gap 0.5)
			(thermal_bridge_width 0.5)
			(island_removal_mode 0)
		)
		(polygon
			(pts
				(arc
					(start 114.4397 -232.334308)
					(mid 113.80978 -232.334308)
					(end 114.4397 -232.334308)
				)
			)
		)
	)
	(zone
		(layers "B.Cu" "In13.Cu" "In15.Cu")
		(hatch none 0.5)
		(connect_pads
			(clearance 0)
		)
		(min_thickness 0.25)
		(keepout
			(tracks not_allowed)
			(vias allowed)
			(pads allowed)
			(copperpour not_allowed)
			(footprints allowed)
		)
		(placement
			(enabled no)
			(sheetname "")
		)
		(fill yes
			(thermal_gap 0.5)
			(thermal_bridge_width 0.5)
			(island_removal_mode 0)
		)
		(polygon
			(pts
				(arc
					(start 206.58201 -223.685354)
					(mid 205.91399 -223.685354)
					(end 206.58201 -223.685354)
				)
			)
		)
	)
	(zone
		(layers "B.Cu" "In13.Cu" "In15.Cu")
		(hatch none 0.5)
		(connect_pads
			(clearance 0)
		)
		(min_thickness 0.25)
		(keepout
			(tracks not_allowed)
			(vias allowed)
			(pads allowed)
			(copperpour not_allowed)
			(footprints allowed)
		)
		(placement
			(enabled no)
			(sheetname "")
		)
		(fill yes
			(thermal_gap 0.5)
			(thermal_bridge_width 0.5)
			(island_removal_mode 0)
		)
		(polygon
			(pts
				(arc
					(start 345.936062 -234.764072)
					(mid 345.306142 -234.764072)
					(end 345.936062 -234.764072)
				)
			)
		)
	)
	(zone
		(layers "B.Cu" "In13.Cu" "In15.Cu")
		(hatch none 0.5)
		(connect_pads
			(clearance 0)
		)
		(min_thickness 0.25)
		(keepout
			(tracks not_allowed)
			(vias allowed)
			(pads allowed)
			(copperpour not_allowed)
			(footprints allowed)
		)
		(placement
			(enabled no)
			(sheetname "")
		)
		(fill yes
			(thermal_gap 0.5)
			(thermal_bridge_width 0.5)
			(island_removal_mode 0)
		)
		(polygon
			(pts
				(arc
					(start 450.42201 -207.535018)
					(mid 449.75399 -207.535018)
					(end 450.42201 -207.535018)
				)
			)
		)
	)
	(zone
		(layers "B.Cu" "In13.Cu" "In15.Cu")
		(hatch none 0.5)
		(connect_pads
			(clearance 0)
		)
		(min_thickness 0.25)
		(keepout
			(tracks not_allowed)
			(vias allowed)
			(pads allowed)
			(copperpour not_allowed)
			(footprints allowed)
		)
		(placement
			(enabled no)
			(sheetname "")
		)
		(fill yes
			(thermal_gap 0.5)
			(thermal_bridge_width 0.5)
			(island_removal_mode 0)
		)
		(polygon
			(pts
				(arc
					(start 269.982188 -225.385122)
					(mid 269.314168 -225.385122)
					(end 269.982188 -225.385122)
				)
			)
		)
	)
	(zone
		(layers "B.Cu" "In13.Cu" "In15.Cu")
		(hatch none 0.5)
		(connect_pads
			(clearance 0)
		)
		(min_thickness 0.25)
		(keepout
			(tracks not_allowed)
			(vias allowed)
			(pads allowed)
			(copperpour not_allowed)
			(footprints allowed)
		)
		(placement
			(enabled no)
			(sheetname "")
		)
		(fill yes
			(thermal_gap 0.5)
			(thermal_bridge_width 0.5)
			(island_removal_mode 0)
		)
		(polygon
			(pts
				(arc
					(start 202.481942 -291.685218)
					(mid 201.813922 -291.685218)
					(end 202.481942 -291.685218)
				)
			)
		)
	)
	(zone
		(layers "B.Cu" "In13.Cu" "In15.Cu")
		(hatch none 0.5)
		(connect_pads
			(clearance 0)
		)
		(min_thickness 0.25)
		(keepout
			(tracks not_allowed)
			(vias allowed)
			(pads allowed)
			(copperpour not_allowed)
			(footprints allowed)
		)
		(placement
			(enabled no)
			(sheetname "")
		)
		(fill yes
			(thermal_gap 0.5)
			(thermal_bridge_width 0.5)
			(island_removal_mode 0)
		)
		(polygon
			(pts
				(arc
					(start 22.04212 -269.58544)
					(mid 21.3741 -269.58544)
					(end 22.04212 -269.58544)
				)
			)
		)
	)
	(zone
		(layers "B.Cu" "In13.Cu" "In15.Cu")
		(hatch none 0.5)
		(connect_pads
			(clearance 0)
		)
		(min_thickness 0.25)
		(keepout
			(tracks not_allowed)
			(vias allowed)
			(pads allowed)
			(copperpour not_allowed)
			(footprints allowed)
		)
		(placement
			(enabled no)
			(sheetname "")
		)
		(fill yes
			(thermal_gap 0.5)
			(thermal_bridge_width 0.5)
			(island_removal_mode 0)
		)
		(polygon
			(pts
				(arc
					(start 138.239754 -291.906198)
					(mid 137.609834 -291.906198)
					(end 138.239754 -291.906198)
				)
			)
		)
	)
	(zone
		(layers "B.Cu" "In13.Cu" "In15.Cu")
		(hatch none 0.5)
		(connect_pads
			(clearance 0)
		)
		(min_thickness 0.25)
		(keepout
			(tracks not_allowed)
			(vias allowed)
			(pads allowed)
			(copperpour not_allowed)
			(footprints allowed)
		)
		(placement
			(enabled no)
			(sheetname "")
		)
		(fill yes
			(thermal_gap 0.5)
			(thermal_bridge_width 0.5)
			(island_removal_mode 0)
		)
		(polygon
			(pts
				(arc
					(start 86.245954 -233.95432)
					(mid 85.616034 -233.95432)
					(end 86.245954 -233.95432)
				)
			)
		)
	)
	(zone
		(layers "B.Cu" "In13.Cu" "In15.Cu")
		(hatch none 0.5)
		(connect_pads
			(clearance 0)
		)
		(min_thickness 0.25)
		(keepout
			(tracks not_allowed)
			(vias allowed)
			(pads allowed)
			(copperpour not_allowed)
			(footprints allowed)
		)
		(placement
			(enabled no)
			(sheetname "")
		)
		(fill yes
			(thermal_gap 0.5)
			(thermal_bridge_width 0.5)
			(island_removal_mode 0)
		)
		(polygon
			(pts
				(arc
					(start 374.129808 -246.104156)
					(mid 373.499888 -246.104156)
					(end 374.129808 -246.104156)
				)
			)
		)
	)
	(zone
		(layers "B.Cu" "In13.Cu" "In15.Cu")
		(hatch none 0.5)
		(connect_pads
			(clearance 0)
		)
		(min_thickness 0.25)
		(keepout
			(tracks not_allowed)
			(vias allowed)
			(pads allowed)
			(copperpour not_allowed)
			(footprints allowed)
		)
		(placement
			(enabled no)
			(sheetname "")
		)
		(fill yes
			(thermal_gap 0.5)
			(thermal_bridge_width 0.5)
			(island_removal_mode 0)
		)
		(polygon
			(pts
				(arc
					(start 454.522078 -204.985112)
					(mid 453.854058 -204.985112)
					(end 454.522078 -204.985112)
				)
			)
		)
	)
	(zone
		(layers "B.Cu" "In13.Cu" "In15.Cu")
		(hatch none 0.5)
		(connect_pads
			(clearance 0)
		)
		(min_thickness 0.25)
		(keepout
			(tracks not_allowed)
			(vias allowed)
			(pads allowed)
			(copperpour not_allowed)
			(footprints allowed)
		)
		(placement
			(enabled no)
			(sheetname "")
		)
		(fill yes
			(thermal_gap 0.5)
			(thermal_bridge_width 0.5)
			(island_removal_mode 0)
		)
		(polygon
			(pts
				(arc
					(start 96.634046 -386.003292)
					(mid 96.004126 -386.003292)
					(end 96.634046 -386.003292)
				)
			)
		)
	)
	(zone
		(layers "B.Cu" "In13.Cu" "In15.Cu")
		(hatch none 0.5)
		(connect_pads
			(clearance 0)
		)
		(min_thickness 0.25)
		(keepout
			(tracks not_allowed)
			(vias allowed)
			(pads allowed)
			(copperpour not_allowed)
			(footprints allowed)
		)
		(placement
			(enabled no)
			(sheetname "")
		)
		(fill yes
			(thermal_gap 0.5)
			(thermal_bridge_width 0.5)
			(island_removal_mode 0)
		)
		(polygon
			(pts
				(arc
					(start 206.58201 -231.335326)
					(mid 205.91399 -231.335326)
					(end 206.58201 -231.335326)
				)
			)
		)
	)
	(zone
		(layers "B.Cu" "In13.Cu" "In15.Cu")
		(hatch none 0.5)
		(connect_pads
			(clearance 0)
		)
		(min_thickness 0.25)
		(keepout
			(tracks not_allowed)
			(vias allowed)
			(pads allowed)
			(copperpour not_allowed)
			(footprints allowed)
		)
		(placement
			(enabled no)
			(sheetname "")
		)
		(fill yes
			(thermal_gap 0.5)
			(thermal_bridge_width 0.5)
			(island_removal_mode 0)
		)
		(polygon
			(pts
				(arc
					(start 138.709654 -278.13635)
					(mid 138.079734 -278.13635)
					(end 138.709654 -278.13635)
				)
			)
		)
	)
	(zone
		(layers "B.Cu" "In13.Cu" "In15.Cu")
		(hatch none 0.5)
		(connect_pads
			(clearance 0)
		)
		(min_thickness 0.25)
		(keepout
			(tracks not_allowed)
			(vias allowed)
			(pads allowed)
			(copperpour not_allowed)
			(footprints allowed)
		)
		(placement
			(enabled no)
			(sheetname "")
		)
		(fill yes
			(thermal_gap 0.5)
			(thermal_bridge_width 0.5)
			(island_removal_mode 0)
		)
		(polygon
			(pts
				(arc
					(start 265.88212 -293.384986)
					(mid 265.2141 -293.384986)
					(end 265.88212 -293.384986)
				)
			)
		)
	)
	(zone
		(layers "B.Cu" "In13.Cu" "In15.Cu")
		(hatch none 0.5)
		(connect_pads
			(clearance 0)
		)
		(min_thickness 0.25)
		(keepout
			(tracks not_allowed)
			(vias allowed)
			(pads allowed)
			(copperpour not_allowed)
			(footprints allowed)
		)
		(placement
			(enabled no)
			(sheetname "")
		)
		(fill yes
			(thermal_gap 0.5)
			(thermal_bridge_width 0.5)
			(island_removal_mode 0)
		)
		(polygon
			(pts
				(arc
					(start 22.04212 -220.28531)
					(mid 21.3741 -220.28531)
					(end 22.04212 -220.28531)
				)
			)
		)
	)
	(zone
		(layers "B.Cu" "In13.Cu" "In15.Cu")
		(hatch none 0.5)
		(connect_pads
			(clearance 0)
		)
		(min_thickness 0.25)
		(keepout
			(tracks not_allowed)
			(vias allowed)
			(pads allowed)
			(copperpour not_allowed)
			(footprints allowed)
		)
		(placement
			(enabled no)
			(sheetname "")
		)
		(fill yes
			(thermal_gap 0.5)
			(thermal_bridge_width 0.5)
			(island_removal_mode 0)
		)
		(polygon
			(pts
				(arc
					(start 206.58201 -206.685388)
					(mid 205.91399 -206.685388)
					(end 206.58201 -206.685388)
				)
			)
		)
	)
	(zone
		(layers "B.Cu" "In13.Cu" "In15.Cu")
		(hatch none 0.5)
		(connect_pads
			(clearance 0)
		)
		(min_thickness 0.25)
		(keepout
			(tracks not_allowed)
			(vias allowed)
			(pads allowed)
			(copperpour not_allowed)
			(footprints allowed)
		)
		(placement
			(enabled no)
			(sheetname "")
		)
		(fill yes
			(thermal_gap 0.5)
			(thermal_bridge_width 0.5)
			(island_removal_mode 0)
		)
		(polygon
			(pts
				(arc
					(start 92.634054 -385.31038)
					(mid 92.004134 -385.31038)
					(end 92.634054 -385.31038)
				)
			)
		)
	)
	(zone
		(layers "B.Cu" "In13.Cu" "In15.Cu")
		(hatch none 0.5)
		(connect_pads
			(clearance 0)
		)
		(min_thickness 0.25)
		(keepout
			(tracks not_allowed)
			(vias allowed)
			(pads allowed)
			(copperpour not_allowed)
			(footprints allowed)
		)
		(placement
			(enabled no)
			(sheetname "")
		)
		(fill yes
			(thermal_gap 0.5)
			(thermal_bridge_width 0.5)
			(island_removal_mode 0)
		)
		(polygon
			(pts
				(arc
					(start 17.942052 -295.9354)
					(mid 17.274032 -295.9354)
					(end 17.942052 -295.9354)
				)
			)
		)
	)
	(zone
		(layers "B.Cu" "In13.Cu" "In15.Cu")
		(hatch none 0.5)
		(connect_pads
			(clearance 0)
		)
		(min_thickness 0.25)
		(keepout
			(tracks not_allowed)
			(vias allowed)
			(pads allowed)
			(copperpour not_allowed)
			(footprints allowed)
		)
		(placement
			(enabled no)
			(sheetname "")
		)
		(fill yes
			(thermal_gap 0.5)
			(thermal_bridge_width 0.5)
			(island_removal_mode 0)
		)
		(polygon
			(pts
				(arc
					(start 334.016096 -273.27606)
					(mid 333.386176 -273.27606)
					(end 334.016096 -273.27606)
				)
			)
		)
	)
	(zone
		(layers "B.Cu" "In13.Cu" "In15.Cu")
		(hatch none 0.5)
		(connect_pads
			(clearance 0)
		)
		(min_thickness 0.25)
		(keepout
			(tracks not_allowed)
			(vias allowed)
			(pads allowed)
			(copperpour not_allowed)
			(footprints allowed)
		)
		(placement
			(enabled no)
			(sheetname "")
		)
		(fill yes
			(thermal_gap 0.5)
			(thermal_bridge_width 0.5)
			(island_removal_mode 0)
		)
		(polygon
			(pts
				(arc
					(start 120.54967 -233.144314)
					(mid 119.91975 -233.144314)
					(end 120.54967 -233.144314)
				)
			)
		)
	)
	(zone
		(layers "B.Cu" "In13.Cu" "In15.Cu")
		(hatch none 0.5)
		(connect_pads
			(clearance 0)
		)
		(min_thickness 0.25)
		(keepout
			(tracks not_allowed)
			(vias allowed)
			(pads allowed)
			(copperpour not_allowed)
			(footprints allowed)
		)
		(placement
			(enabled no)
			(sheetname "")
		)
		(fill yes
			(thermal_gap 0.5)
			(thermal_bridge_width 0.5)
			(island_removal_mode 0)
		)
		(polygon
			(pts
				(arc
					(start 138.239754 -277.326344)
					(mid 137.609834 -277.326344)
					(end 138.239754 -277.326344)
				)
			)
		)
	)
	(zone
		(layers "B.Cu" "In13.Cu" "In15.Cu")
		(hatch none 0.5)
		(connect_pads
			(clearance 0)
		)
		(min_thickness 0.25)
		(keepout
			(tracks not_allowed)
			(vias allowed)
			(pads allowed)
			(copperpour not_allowed)
			(footprints allowed)
		)
		(placement
			(enabled no)
			(sheetname "")
		)
		(fill yes
			(thermal_gap 0.5)
			(thermal_bridge_width 0.5)
			(island_removal_mode 0)
		)
		(polygon
			(pts
				(arc
					(start 84.666074 -277.326344)
					(mid 84.036154 -277.326344)
					(end 84.666074 -277.326344)
				)
			)
		)
	)
	(zone
		(layers "B.Cu" "In13.Cu" "In15.Cu")
		(hatch none 0.5)
		(connect_pads
			(clearance 0)
		)
		(min_thickness 0.25)
		(keepout
			(tracks not_allowed)
			(vias allowed)
			(pads allowed)
			(copperpour not_allowed)
			(footprints allowed)
		)
		(placement
			(enabled no)
			(sheetname "")
		)
		(fill yes
			(thermal_gap 0.5)
			(thermal_bridge_width 0.5)
			(island_removal_mode 0)
		)
		(polygon
			(pts
				(arc
					(start 332.036928 -430.889918)
					(mid 331.262736 -430.889918)
					(end 332.036928 -430.889918)
				)
			)
		)
	)
	(zone
		(layers "B.Cu" "In13.Cu" "In15.Cu")
		(hatch none 0.5)
		(connect_pads
			(clearance 0)
		)
		(min_thickness 0.25)
		(keepout
			(tracks not_allowed)
			(vias allowed)
			(pads allowed)
			(copperpour not_allowed)
			(footprints allowed)
		)
		(placement
			(enabled no)
			(sheetname "")
		)
		(fill yes
			(thermal_gap 0.5)
			(thermal_bridge_width 0.5)
			(island_removal_mode 0)
		)
		(polygon
			(pts
				(arc
					(start 206.58201 -266.185396)
					(mid 205.91399 -266.185396)
					(end 206.58201 -266.185396)
				)
			)
		)
	)
	(zone
		(layers "B.Cu" "In13.Cu" "In15.Cu")
		(hatch none 0.5)
		(connect_pads
			(clearance 0)
		)
		(min_thickness 0.25)
		(keepout
			(tracks not_allowed)
			(vias allowed)
			(pads allowed)
			(copperpour not_allowed)
			(footprints allowed)
		)
		(placement
			(enabled no)
			(sheetname "")
		)
		(fill yes
			(thermal_gap 0.5)
			(thermal_bridge_width 0.5)
			(island_removal_mode 0)
		)
		(polygon
			(pts
				(arc
					(start 388.572502 -377.41733)
					(mid 387.904482 -377.41733)
					(end 388.572502 -377.41733)
				)
			)
		)
	)
	(zone
		(layers "B.Cu" "In13.Cu" "In15.Cu")
		(hatch none 0.5)
		(connect_pads
			(clearance 0)
		)
		(min_thickness 0.25)
		(keepout
			(tracks not_allowed)
			(vias allowed)
			(pads allowed)
			(copperpour not_allowed)
			(footprints allowed)
		)
		(placement
			(enabled no)
			(sheetname "")
		)
		(fill yes
			(thermal_gap 0.5)
			(thermal_bridge_width 0.5)
			(island_removal_mode 0)
		)
		(polygon
			(pts
				(arc
					(start 332.306168 -232.334054)
					(mid 331.676248 -232.334054)
					(end 332.306168 -232.334054)
				)
			)
		)
	)
	(zone
		(layers "B.Cu" "In13.Cu" "In15.Cu")
		(hatch none 0.5)
		(connect_pads
			(clearance 0)
		)
		(min_thickness 0.25)
		(keepout
			(tracks not_allowed)
			(vias allowed)
			(pads allowed)
			(copperpour not_allowed)
			(footprints allowed)
		)
		(placement
			(enabled no)
			(sheetname "")
		)
		(fill yes
			(thermal_gap 0.5)
			(thermal_bridge_width 0.5)
			(island_removal_mode 0)
		)
		(polygon
			(pts
				(arc
					(start 265.88212 -302.73498)
					(mid 265.2141 -302.73498)
					(end 265.88212 -302.73498)
				)
			)
		)
	)
	(zone
		(layers "B.Cu" "In13.Cu" "In15.Cu")
		(hatch none 0.5)
		(connect_pads
			(clearance 0)
		)
		(min_thickness 0.25)
		(keepout
			(tracks not_allowed)
			(vias allowed)
			(pads allowed)
			(copperpour not_allowed)
			(footprints allowed)
		)
		(placement
			(enabled no)
			(sheetname "")
		)
		(fill yes
			(thermal_gap 0.5)
			(thermal_bridge_width 0.5)
			(island_removal_mode 0)
		)
		(polygon
			(pts
				(arc
					(start 86.545928 -283.806392)
					(mid 85.916008 -283.806392)
					(end 86.545928 -283.806392)
				)
			)
		)
	)
	(zone
		(layers "B.Cu" "In13.Cu" "In15.Cu")
		(hatch none 0.5)
		(connect_pads
			(clearance 0)
		)
		(min_thickness 0.25)
		(keepout
			(tracks not_allowed)
			(vias allowed)
			(pads allowed)
			(copperpour not_allowed)
			(footprints allowed)
		)
		(placement
			(enabled no)
			(sheetname "")
		)
		(fill yes
			(thermal_gap 0.5)
			(thermal_bridge_width 0.5)
			(island_removal_mode 0)
		)
		(polygon
			(pts
				(arc
					(start 138.40968 -241.244374)
					(mid 137.77976 -241.244374)
					(end 138.40968 -241.244374)
				)
			)
		)
	)
	(zone
		(layers "B.Cu" "In13.Cu" "In15.Cu")
		(hatch none 0.5)
		(connect_pads
			(clearance 0)
		)
		(min_thickness 0.25)
		(keepout
			(tracks not_allowed)
			(vias allowed)
			(pads allowed)
			(copperpour not_allowed)
			(footprints allowed)
		)
		(placement
			(enabled no)
			(sheetname "")
		)
		(fill yes
			(thermal_gap 0.5)
			(thermal_bridge_width 0.5)
			(island_removal_mode 0)
		)
		(polygon
			(pts
				(arc
					(start 334.485996 -291.905944)
					(mid 333.856076 -291.905944)
					(end 334.485996 -291.905944)
				)
			)
		)
	)
	(zone
		(layers "B.Cu" "In13.Cu" "In15.Cu")
		(hatch none 0.5)
		(connect_pads
			(clearance 0)
		)
		(min_thickness 0.25)
		(keepout
			(tracks not_allowed)
			(vias allowed)
			(pads allowed)
			(copperpour not_allowed)
			(footprints allowed)
		)
		(placement
			(enabled no)
			(sheetname "")
		)
		(fill yes
			(thermal_gap 0.5)
			(thermal_bridge_width 0.5)
			(island_removal_mode 0)
		)
		(polygon
			(pts
				(arc
					(start 387.589776 -263.555988)
					(mid 386.959856 -263.555988)
					(end 387.589776 -263.555988)
				)
			)
		)
	)
	(zone
		(layers "B.Cu" "In13.Cu" "In15.Cu")
		(hatch none 0.5)
		(connect_pads
			(clearance 0)
		)
		(min_thickness 0.25)
		(keepout
			(tracks not_allowed)
			(vias allowed)
			(pads allowed)
			(copperpour not_allowed)
			(footprints allowed)
		)
		(placement
			(enabled no)
			(sheetname "")
		)
		(fill yes
			(thermal_gap 0.5)
			(thermal_bridge_width 0.5)
			(island_removal_mode 0)
		)
		(polygon
			(pts
				(arc
					(start 371.309646 -244.484144)
					(mid 370.679726 -244.484144)
					(end 371.309646 -244.484144)
				)
			)
		)
	)
	(zone
		(layers "B.Cu" "In13.Cu" "In15.Cu")
		(hatch none 0.5)
		(connect_pads
			(clearance 0)
		)
		(min_thickness 0.25)
		(keepout
			(tracks not_allowed)
			(vias allowed)
			(pads allowed)
			(copperpour not_allowed)
			(footprints allowed)
		)
		(placement
			(enabled no)
			(sheetname "")
		)
		(fill yes
			(thermal_gap 0.5)
			(thermal_bridge_width 0.5)
			(island_removal_mode 0)
		)
		(polygon
			(pts
				(arc
					(start 140.119608 -288.666174)
					(mid 139.489688 -288.666174)
					(end 140.119608 -288.666174)
				)
			)
		)
	)
	(zone
		(layers "B.Cu" "In13.Cu" "In15.Cu")
		(hatch none 0.5)
		(connect_pads
			(clearance 0)
		)
		(min_thickness 0.25)
		(keepout
			(tracks not_allowed)
			(vias allowed)
			(pads allowed)
			(copperpour not_allowed)
			(footprints allowed)
		)
		(placement
			(enabled no)
			(sheetname "")
		)
		(fill yes
			(thermal_gap 0.5)
			(thermal_bridge_width 0.5)
			(island_removal_mode 0)
		)
		(polygon
			(pts
				(arc
					(start 334.485996 -264.365994)
					(mid 333.856076 -264.365994)
					(end 334.485996 -264.365994)
				)
			)
		)
	)
	(zone
		(layers "B.Cu" "In13.Cu" "In15.Cu")
		(hatch none 0.5)
		(connect_pads
			(clearance 0)
		)
		(min_thickness 0.25)
		(keepout
			(tracks not_allowed)
			(vias allowed)
			(pads allowed)
			(copperpour not_allowed)
			(footprints allowed)
		)
		(placement
			(enabled no)
			(sheetname "")
		)
		(fill yes
			(thermal_gap 0.5)
			(thermal_bridge_width 0.5)
			(island_removal_mode 0)
		)
		(polygon
			(pts
				(arc
					(start 265.88212 -213.484968)
					(mid 265.2141 -213.484968)
					(end 265.88212 -213.484968)
				)
			)
		)
	)
	(zone
		(layers "B.Cu" "In13.Cu" "In15.Cu")
		(hatch none 0.5)
		(connect_pads
			(clearance 0)
		)
		(min_thickness 0.25)
		(keepout
			(tracks not_allowed)
			(vias allowed)
			(pads allowed)
			(copperpour not_allowed)
			(footprints allowed)
		)
		(placement
			(enabled no)
			(sheetname "")
		)
		(fill yes
			(thermal_gap 0.5)
			(thermal_bridge_width 0.5)
			(island_removal_mode 0)
		)
		(polygon
			(pts
				(arc
					(start 84.666074 -275.706332)
					(mid 84.036154 -275.706332)
					(end 84.666074 -275.706332)
				)
			)
		)
	)
	(zone
		(layers "B.Cu" "In13.Cu" "In15.Cu")
		(hatch none 0.5)
		(connect_pads
			(clearance 0)
		)
		(min_thickness 0.25)
		(keepout
			(tracks not_allowed)
			(vias allowed)
			(pads allowed)
			(copperpour not_allowed)
			(footprints allowed)
		)
		(placement
			(enabled no)
			(sheetname "")
		)
		(fill yes
			(thermal_gap 0.5)
			(thermal_bridge_width 0.5)
			(island_removal_mode 0)
		)
		(polygon
			(pts
				(arc
					(start 17.942052 -308.685438)
					(mid 17.274032 -308.685438)
					(end 17.942052 -308.685438)
				)
			)
		)
	)
	(zone
		(layers "B.Cu" "In13.Cu" "In15.Cu")
		(hatch none 0.5)
		(connect_pads
			(clearance 0)
		)
		(min_thickness 0.25)
		(keepout
			(tracks not_allowed)
			(vias allowed)
			(pads allowed)
			(copperpour not_allowed)
			(footprints allowed)
		)
		(placement
			(enabled no)
			(sheetname "")
		)
		(fill yes
			(thermal_gap 0.5)
			(thermal_bridge_width 0.5)
			(island_removal_mode 0)
		)
		(polygon
			(pts
				(arc
					(start 151.137112 -429.689768)
					(mid 150.36292 -429.689768)
					(end 151.137112 -429.689768)
				)
			)
		)
	)
	(zone
		(layers "B.Cu" "In13.Cu" "In15.Cu")
		(hatch none 0.5)
		(connect_pads
			(clearance 0)
		)
		(min_thickness 0.25)
		(keepout
			(tracks not_allowed)
			(vias allowed)
			(pads allowed)
			(copperpour not_allowed)
			(footprints allowed)
		)
		(placement
			(enabled no)
			(sheetname "")
		)
		(fill yes
			(thermal_gap 0.5)
			(thermal_bridge_width 0.5)
			(island_removal_mode 0)
		)
		(polygon
			(pts
				(arc
					(start 334.186022 -243.674138)
					(mid 333.556102 -243.674138)
					(end 334.186022 -243.674138)
				)
			)
		)
	)
	(zone
		(layers "B.Cu" "In13.Cu" "In15.Cu")
		(hatch none 0.5)
		(connect_pads
			(clearance 0)
		)
		(min_thickness 0.25)
		(keepout
			(tracks not_allowed)
			(vias allowed)
			(pads allowed)
			(copperpour not_allowed)
			(footprints allowed)
		)
		(placement
			(enabled no)
			(sheetname "")
		)
		(fill yes
			(thermal_gap 0.5)
			(thermal_bridge_width 0.5)
			(island_removal_mode 0)
		)
		(polygon
			(pts
				(arc
					(start 17.942052 -302.735234)
					(mid 17.274032 -302.735234)
					(end 17.942052 -302.735234)
				)
			)
		)
	)
	(zone
		(layers "B.Cu" "In13.Cu" "In15.Cu")
		(hatch none 0.5)
		(connect_pads
			(clearance 0)
		)
		(min_thickness 0.25)
		(keepout
			(tracks not_allowed)
			(vias allowed)
			(pads allowed)
			(copperpour not_allowed)
			(footprints allowed)
		)
		(placement
			(enabled no)
			(sheetname "")
		)
		(fill yes
			(thermal_gap 0.5)
			(thermal_bridge_width 0.5)
			(island_removal_mode 0)
		)
		(polygon
			(pts
				(arc
					(start 269.982188 -231.335072)
					(mid 269.314168 -231.335072)
					(end 269.982188 -231.335072)
				)
			)
		)
	)
	(zone
		(layers "B.Cu" "In13.Cu" "In15.Cu")
		(hatch none 0.5)
		(connect_pads
			(clearance 0)
		)
		(min_thickness 0.25)
		(keepout
			(tracks not_allowed)
			(vias allowed)
			(pads allowed)
			(copperpour not_allowed)
			(footprints allowed)
		)
		(placement
			(enabled no)
			(sheetname "")
		)
		(fill yes
			(thermal_gap 0.5)
			(thermal_bridge_width 0.5)
			(island_removal_mode 0)
		)
		(polygon
			(pts
				(arc
					(start 347.833696 -394.385292)
					(mid 347.203776 -394.385292)
					(end 347.833696 -394.385292)
				)
			)
		)
	)
	(zone
		(layers "B.Cu" "In13.Cu" "In15.Cu")
		(hatch none 0.5)
		(connect_pads
			(clearance 0)
		)
		(min_thickness 0.25)
		(keepout
			(tracks not_allowed)
			(vias allowed)
			(pads allowed)
			(copperpour not_allowed)
			(footprints allowed)
		)
		(placement
			(enabled no)
			(sheetname "")
		)
		(fill yes
			(thermal_gap 0.5)
			(thermal_bridge_width 0.5)
			(island_removal_mode 0)
		)
		(polygon
			(pts
				(arc
					(start 450.42201 -250.03506)
					(mid 449.75399 -250.03506)
					(end 450.42201 -250.03506)
				)
			)
		)
	)
	(zone
		(layers "B.Cu" "In13.Cu" "In15.Cu")
		(hatch none 0.5)
		(connect_pads
			(clearance 0)
		)
		(min_thickness 0.25)
		(keepout
			(tracks not_allowed)
			(vias allowed)
			(pads allowed)
			(copperpour not_allowed)
			(footprints allowed)
		)
		(placement
			(enabled no)
			(sheetname "")
		)
		(fill yes
			(thermal_gap 0.5)
			(thermal_bridge_width 0.5)
			(island_removal_mode 0)
		)
		(polygon
			(pts
				(arc
					(start 334.036924 -430.689766)
					(mid 333.262732 -430.689766)
					(end 334.036924 -430.689766)
				)
			)
		)
	)
	(zone
		(layers "B.Cu" "In13.Cu" "In15.Cu")
		(hatch none 0.5)
		(connect_pads
			(clearance 0)
		)
		(min_thickness 0.25)
		(keepout
			(tracks not_allowed)
			(vias allowed)
			(pads allowed)
			(copperpour not_allowed)
			(footprints allowed)
		)
		(placement
			(enabled no)
			(sheetname "")
		)
		(fill yes
			(thermal_gap 0.5)
			(thermal_bridge_width 0.5)
			(island_removal_mode 0)
		)
		(polygon
			(pts
				(arc
					(start 17.942052 -211.7852)
					(mid 17.274032 -211.7852)
					(end 17.942052 -211.7852)
				)
			)
		)
	)
	(zone
		(layers "B.Cu" "In13.Cu" "In15.Cu")
		(hatch none 0.5)
		(connect_pads
			(clearance 0)
		)
		(min_thickness 0.25)
		(keepout
			(tracks not_allowed)
			(vias allowed)
			(pads allowed)
			(copperpour not_allowed)
			(footprints allowed)
		)
		(placement
			(enabled no)
			(sheetname "")
		)
		(fill yes
			(thermal_gap 0.5)
			(thermal_bridge_width 0.5)
			(island_removal_mode 0)
		)
		(polygon
			(pts
				(arc
					(start 122.218196 -412.570168)
					(mid 121.550176 -412.570168)
					(end 122.218196 -412.570168)
				)
			)
		)
	)
	(zone
		(layers "B.Cu" "In13.Cu" "In15.Cu")
		(hatch none 0.5)
		(connect_pads
			(clearance 0)
		)
		(min_thickness 0.25)
		(keepout
			(tracks not_allowed)
			(vias allowed)
			(pads allowed)
			(copperpour not_allowed)
			(footprints allowed)
		)
		(placement
			(enabled no)
			(sheetname "")
		)
		(fill yes
			(thermal_gap 0.5)
			(thermal_bridge_width 0.5)
			(island_removal_mode 0)
		)
		(polygon
			(pts
				(arc
					(start 332.306168 -243.674138)
					(mid 331.676248 -243.674138)
					(end 332.306168 -243.674138)
				)
			)
		)
	)
	(zone
		(layers "B.Cu" "In13.Cu" "In15.Cu")
		(hatch none 0.5)
		(connect_pads
			(clearance 0)
		)
		(min_thickness 0.25)
		(keepout
			(tracks not_allowed)
			(vias allowed)
			(pads allowed)
			(copperpour not_allowed)
			(footprints allowed)
		)
		(placement
			(enabled no)
			(sheetname "")
		)
		(fill yes
			(thermal_gap 0.5)
			(thermal_bridge_width 0.5)
			(island_removal_mode 0)
		)
		(polygon
			(pts
				(arc
					(start 450.42201 -218.585034)
					(mid 449.75399 -218.585034)
					(end 450.42201 -218.585034)
				)
			)
		)
	)
	(zone
		(layers "B.Cu" "In13.Cu" "In15.Cu")
		(hatch none 0.5)
		(connect_pads
			(clearance 0)
		)
		(min_thickness 0.25)
		(keepout
			(tracks not_allowed)
			(vias allowed)
			(pads allowed)
			(copperpour not_allowed)
			(footprints allowed)
		)
		(placement
			(enabled no)
			(sheetname "")
		)
		(fill yes
			(thermal_gap 0.5)
			(thermal_bridge_width 0.5)
			(island_removal_mode 0)
		)
		(polygon
			(pts
				(arc
					(start 351.433638 -394.385292)
					(mid 350.803718 -394.385292)
					(end 351.433638 -394.385292)
				)
			)
		)
	)
	(zone
		(layers "B.Cu" "In13.Cu" "In15.Cu")
		(hatch none 0.5)
		(connect_pads
			(clearance 0)
		)
		(min_thickness 0.25)
		(keepout
			(tracks not_allowed)
			(vias allowed)
			(pads allowed)
			(copperpour not_allowed)
			(footprints allowed)
		)
		(placement
			(enabled no)
			(sheetname "")
		)
		(fill yes
			(thermal_gap 0.5)
			(thermal_bridge_width 0.5)
			(island_removal_mode 0)
		)
		(polygon
			(pts
				(arc
					(start 363.319822 -246.914162)
					(mid 362.689902 -246.914162)
					(end 363.319822 -246.914162)
				)
			)
		)
	)
	(zone
		(layers "B.Cu" "In13.Cu" "In15.Cu")
		(hatch none 0.5)
		(connect_pads
			(clearance 0)
		)
		(min_thickness 0.25)
		(keepout
			(tracks not_allowed)
			(vias allowed)
			(pads allowed)
			(copperpour not_allowed)
			(footprints allowed)
		)
		(placement
			(enabled no)
			(sheetname "")
		)
		(fill yes
			(thermal_gap 0.5)
			(thermal_bridge_width 0.5)
			(island_removal_mode 0)
		)
		(polygon
			(pts
				(arc
					(start 346.876116 -233.14406)
					(mid 346.246196 -233.14406)
					(end 346.876116 -233.14406)
				)
			)
		)
	)
	(zone
		(layers "B.Cu" "In13.Cu" "In15.Cu")
		(hatch none 0.5)
		(connect_pads
			(clearance 0)
		)
		(min_thickness 0.25)
		(keepout
			(tracks not_allowed)
			(vias allowed)
			(pads allowed)
			(copperpour not_allowed)
			(footprints allowed)
		)
		(placement
			(enabled no)
			(sheetname "")
		)
		(fill yes
			(thermal_gap 0.5)
			(thermal_bridge_width 0.5)
			(island_removal_mode 0)
		)
		(polygon
			(pts
				(arc
					(start 370.66982 -274.896072)
					(mid 370.0399 -274.896072)
					(end 370.66982 -274.896072)
				)
			)
		)
	)
	(zone
		(layers "B.Cu" "In13.Cu" "In15.Cu")
		(hatch none 0.5)
		(connect_pads
			(clearance 0)
		)
		(min_thickness 0.25)
		(keepout
			(tracks not_allowed)
			(vias allowed)
			(pads allowed)
			(copperpour not_allowed)
			(footprints allowed)
		)
		(placement
			(enabled no)
			(sheetname "")
		)
		(fill yes
			(thermal_gap 0.5)
			(thermal_bridge_width 0.5)
			(island_removal_mode 0)
		)
		(polygon
			(pts
				(arc
					(start 450.42201 -310.384952)
					(mid 449.75399 -310.384952)
					(end 450.42201 -310.384952)
				)
			)
		)
	)
	(zone
		(layers "B.Cu" "In13.Cu" "In15.Cu")
		(hatch none 0.5)
		(connect_pads
			(clearance 0)
		)
		(min_thickness 0.25)
		(keepout
			(tracks not_allowed)
			(vias allowed)
			(pads allowed)
			(copperpour not_allowed)
			(footprints allowed)
		)
		(placement
			(enabled no)
			(sheetname "")
		)
		(fill yes
			(thermal_gap 0.5)
			(thermal_bridge_width 0.5)
			(island_removal_mode 0)
		)
		(polygon
			(pts
				(arc
					(start 387.289802 -233.14406)
					(mid 386.659882 -233.14406)
					(end 387.289802 -233.14406)
				)
			)
		)
	)
	(zone
		(layers "B.Cu" "In13.Cu" "In15.Cu")
		(hatch none 0.5)
		(connect_pads
			(clearance 0)
		)
		(min_thickness 0.25)
		(keepout
			(tracks not_allowed)
			(vias allowed)
			(pads allowed)
			(copperpour not_allowed)
			(footprints allowed)
		)
		(placement
			(enabled no)
			(sheetname "")
		)
		(fill yes
			(thermal_gap 0.5)
			(thermal_bridge_width 0.5)
			(island_removal_mode 0)
		)
		(polygon
			(pts
				(arc
					(start 350.076516 -420.952168)
					(mid 349.408496 -420.952168)
					(end 350.076516 -420.952168)
				)
			)
		)
	)
	(zone
		(layers "B.Cu" "In13.Cu" "In15.Cu")
		(hatch none 0.5)
		(connect_pads
			(clearance 0)
		)
		(min_thickness 0.25)
		(keepout
			(tracks not_allowed)
			(vias allowed)
			(pads allowed)
			(copperpour not_allowed)
			(footprints allowed)
		)
		(placement
			(enabled no)
			(sheetname "")
		)
		(fill yes
			(thermal_gap 0.5)
			(thermal_bridge_width 0.5)
			(island_removal_mode 0)
		)
		(polygon
			(pts
				(arc
					(start 125.765306 -369.03533)
					(mid 125.097286 -369.03533)
					(end 125.765306 -369.03533)
				)
			)
		)
	)
	(zone
		(layers "B.Cu" "In13.Cu" "In15.Cu")
		(hatch none 0.5)
		(connect_pads
			(clearance 0)
		)
		(min_thickness 0.25)
		(keepout
			(tracks not_allowed)
			(vias allowed)
			(pads allowed)
			(copperpour not_allowed)
			(footprints allowed)
		)
		(placement
			(enabled no)
			(sheetname "")
		)
		(fill yes
			(thermal_gap 0.5)
			(thermal_bridge_width 0.5)
			(island_removal_mode 0)
		)
		(polygon
			(pts
				(arc
					(start 265.88212 -251.735082)
					(mid 265.2141 -251.735082)
					(end 265.88212 -251.735082)
				)
			)
		)
	)
	(zone
		(layers "B.Cu" "In13.Cu" "In15.Cu")
		(hatch none 0.5)
		(connect_pads
			(clearance 0)
		)
		(min_thickness 0.25)
		(keepout
			(tracks not_allowed)
			(vias allowed)
			(pads allowed)
			(copperpour not_allowed)
			(footprints allowed)
		)
		(placement
			(enabled no)
			(sheetname "")
		)
		(fill yes
			(thermal_gap 0.5)
			(thermal_bridge_width 0.5)
			(island_removal_mode 0)
		)
		(polygon
			(pts
				(arc
					(start 206.58201 -317.185294)
					(mid 205.91399 -317.185294)
					(end 206.58201 -317.185294)
				)
			)
		)
	)
	(zone
		(layers "B.Cu" "In13.Cu" "In15.Cu")
		(hatch none 0.5)
		(connect_pads
			(clearance 0)
		)
		(min_thickness 0.25)
		(keepout
			(tracks not_allowed)
			(vias allowed)
			(pads allowed)
			(copperpour not_allowed)
			(footprints allowed)
		)
		(placement
			(enabled no)
			(sheetname "")
		)
		(fill yes
			(thermal_gap 0.5)
			(thermal_bridge_width 0.5)
			(island_removal_mode 0)
		)
		(polygon
			(pts
				(arc
					(start 86.245954 -237.194344)
					(mid 85.616034 -237.194344)
					(end 86.245954 -237.194344)
				)
			)
		)
	)
	(zone
		(layers "B.Cu" "In13.Cu" "In15.Cu")
		(hatch none 0.5)
		(connect_pads
			(clearance 0)
		)
		(min_thickness 0.25)
		(keepout
			(tracks not_allowed)
			(vias allowed)
			(pads allowed)
			(copperpour not_allowed)
			(footprints allowed)
		)
		(placement
			(enabled no)
			(sheetname "")
		)
		(fill yes
			(thermal_gap 0.5)
			(thermal_bridge_width 0.5)
			(island_removal_mode 0)
		)
		(polygon
			(pts
				(arc
					(start 98.936048 -247.724422)
					(mid 98.306128 -247.724422)
					(end 98.936048 -247.724422)
				)
			)
		)
	)
	(zone
		(layers "B.Cu" "In13.Cu" "In15.Cu")
		(hatch none 0.5)
		(connect_pads
			(clearance 0)
		)
		(min_thickness 0.25)
		(keepout
			(tracks not_allowed)
			(vias allowed)
			(pads allowed)
			(copperpour not_allowed)
			(footprints allowed)
		)
		(placement
			(enabled no)
			(sheetname "")
		)
		(fill yes
			(thermal_gap 0.5)
			(thermal_bridge_width 0.5)
			(island_removal_mode 0)
		)
		(polygon
			(pts
				(arc
					(start 85.135974 -291.096192)
					(mid 84.506054 -291.096192)
					(end 85.135974 -291.096192)
				)
			)
		)
	)
	(zone
		(layers "B.Cu" "In13.Cu" "In15.Cu")
		(hatch none 0.5)
		(connect_pads
			(clearance 0)
		)
		(min_thickness 0.25)
		(keepout
			(tracks not_allowed)
			(vias allowed)
			(pads allowed)
			(copperpour not_allowed)
			(footprints allowed)
		)
		(placement
			(enabled no)
			(sheetname "")
		)
		(fill yes
			(thermal_gap 0.5)
			(thermal_bridge_width 0.5)
			(island_removal_mode 0)
		)
		(polygon
			(pts
				(arc
					(start 81.034128 -389.467344)
					(mid 80.404208 -389.467344)
					(end 81.034128 -389.467344)
				)
			)
		)
	)
	(zone
		(layers "B.Cu" "In13.Cu" "In15.Cu")
		(hatch none 0.5)
		(connect_pads
			(clearance 0)
		)
		(min_thickness 0.25)
		(keepout
			(tracks not_allowed)
			(vias allowed)
			(pads allowed)
			(copperpour not_allowed)
			(footprints allowed)
		)
		(placement
			(enabled no)
			(sheetname "")
		)
		(fill yes
			(thermal_gap 0.5)
			(thermal_bridge_width 0.5)
			(island_removal_mode 0)
		)
		(polygon
			(pts
				(arc
					(start 206.58201 -203.285344)
					(mid 205.91399 -203.285344)
					(end 206.58201 -203.285344)
				)
			)
		)
	)
	(zone
		(layers "B.Cu" "In13.Cu" "In15.Cu")
		(hatch none 0.5)
		(connect_pads
			(clearance 0)
		)
		(min_thickness 0.25)
		(keepout
			(tracks not_allowed)
			(vias allowed)
			(pads allowed)
			(copperpour not_allowed)
			(footprints allowed)
		)
		(placement
			(enabled no)
			(sheetname "")
		)
		(fill yes
			(thermal_gap 0.5)
			(thermal_bridge_width 0.5)
			(island_removal_mode 0)
		)
		(polygon
			(pts
				(arc
					(start 63.444374 -412.570168)
					(mid 62.776354 -412.570168)
					(end 63.444374 -412.570168)
				)
			)
		)
	)
	(zone
		(layers "B.Cu" "In13.Cu" "In15.Cu")
		(hatch none 0.5)
		(connect_pads
			(clearance 0)
		)
		(min_thickness 0.25)
		(keepout
			(tracks not_allowed)
			(vias allowed)
			(pads allowed)
			(copperpour not_allowed)
			(footprints allowed)
		)
		(placement
			(enabled no)
			(sheetname "")
		)
		(fill yes
			(thermal_gap 0.5)
			(thermal_bridge_width 0.5)
			(island_removal_mode 0)
		)
		(polygon
			(pts
				(arc
					(start 386.649722 -266.796012)
					(mid 386.019802 -266.796012)
					(end 386.649722 -266.796012)
				)
			)
		)
	)
	(zone
		(layers "B.Cu" "In13.Cu" "In15.Cu")
		(hatch none 0.5)
		(connect_pads
			(clearance 0)
		)
		(min_thickness 0.25)
		(keepout
			(tracks not_allowed)
			(vias allowed)
			(pads allowed)
			(copperpour not_allowed)
			(footprints allowed)
		)
		(placement
			(enabled no)
			(sheetname "")
		)
		(fill yes
			(thermal_gap 0.5)
			(thermal_bridge_width 0.5)
			(island_removal_mode 0)
		)
		(polygon
			(pts
				(arc
					(start 84.23402 -385.31038)
					(mid 83.6041 -385.31038)
					(end 84.23402 -385.31038)
				)
			)
		)
	)
	(zone
		(layers "B.Cu" "In13.Cu" "In15.Cu")
		(hatch none 0.5)
		(connect_pads
			(clearance 0)
		)
		(min_thickness 0.25)
		(keepout
			(tracks not_allowed)
			(vias allowed)
			(pads allowed)
			(copperpour not_allowed)
			(footprints allowed)
		)
		(placement
			(enabled no)
			(sheetname "")
		)
		(fill yes
			(thermal_gap 0.5)
			(thermal_bridge_width 0.5)
			(island_removal_mode 0)
		)
		(polygon
			(pts
				(arc
					(start 84.836 -236.384338)
					(mid 84.20608 -236.384338)
					(end 84.836 -236.384338)
				)
			)
		)
	)
	(zone
		(layers "B.Cu" "In13.Cu" "In15.Cu")
		(hatch none 0.5)
		(connect_pads
			(clearance 0)
		)
		(min_thickness 0.25)
		(keepout
			(tracks not_allowed)
			(vias allowed)
			(pads allowed)
			(copperpour not_allowed)
			(footprints allowed)
		)
		(placement
			(enabled no)
			(sheetname "")
		)
		(fill yes
			(thermal_gap 0.5)
			(thermal_bridge_width 0.5)
			(island_removal_mode 0)
		)
		(polygon
			(pts
				(arc
					(start 202.481942 -227.935282)
					(mid 201.813922 -227.935282)
					(end 202.481942 -227.935282)
				)
			)
		)
	)
	(zone
		(layers "B.Cu" "In13.Cu" "In15.Cu")
		(hatch none 0.5)
		(connect_pads
			(clearance 0)
		)
		(min_thickness 0.25)
		(keepout
			(tracks not_allowed)
			(vias allowed)
			(pads allowed)
			(copperpour not_allowed)
			(footprints allowed)
		)
		(placement
			(enabled no)
			(sheetname "")
		)
		(fill yes
			(thermal_gap 0.5)
			(thermal_bridge_width 0.5)
			(island_removal_mode 0)
		)
		(polygon
			(pts
				(arc
					(start 202.481942 -268.735302)
					(mid 201.813922 -268.735302)
					(end 202.481942 -268.735302)
				)
			)
		)
	)
	(zone
		(layers "B.Cu" "In13.Cu" "In15.Cu")
		(hatch none 0.5)
		(connect_pads
			(clearance 0)
		)
		(min_thickness 0.25)
		(keepout
			(tracks not_allowed)
			(vias allowed)
			(pads allowed)
			(copperpour not_allowed)
			(footprints allowed)
		)
		(placement
			(enabled no)
			(sheetname "")
		)
		(fill yes
			(thermal_gap 0.5)
			(thermal_bridge_width 0.5)
			(island_removal_mode 0)
		)
		(polygon
			(pts
				(arc
					(start 265.88212 -226.235006)
					(mid 265.2141 -226.235006)
					(end 265.88212 -226.235006)
				)
			)
		)
	)
	(zone
		(layers "B.Cu" "In13.Cu" "In15.Cu")
		(hatch none 0.5)
		(connect_pads
			(clearance 0)
		)
		(min_thickness 0.25)
		(keepout
			(tracks not_allowed)
			(vias allowed)
			(pads allowed)
			(copperpour not_allowed)
			(footprints allowed)
		)
		(placement
			(enabled no)
			(sheetname "")
		)
		(fill yes
			(thermal_gap 0.5)
			(thermal_bridge_width 0.5)
			(island_removal_mode 0)
		)
		(polygon
			(pts
				(arc
					(start 343.033858 -394.385292)
					(mid 342.403938 -394.385292)
					(end 343.033858 -394.385292)
				)
			)
		)
	)
	(zone
		(layers "B.Cu" "In13.Cu" "In15.Cu")
		(hatch none 0.5)
		(connect_pads
			(clearance 0)
		)
		(min_thickness 0.25)
		(keepout
			(tracks not_allowed)
			(vias allowed)
			(pads allowed)
			(copperpour not_allowed)
			(footprints allowed)
		)
		(placement
			(enabled no)
			(sheetname "")
		)
		(fill yes
			(thermal_gap 0.5)
			(thermal_bridge_width 0.5)
			(island_removal_mode 0)
		)
		(polygon
			(pts
				(arc
					(start 332.606142 -285.42615)
					(mid 331.976222 -285.42615)
					(end 332.606142 -285.42615)
				)
			)
		)
	)
	(zone
		(layers "B.Cu" "In13.Cu" "In15.Cu")
		(hatch none 0.5)
		(connect_pads
			(clearance 0)
		)
		(min_thickness 0.25)
		(keepout
			(tracks not_allowed)
			(vias allowed)
			(pads allowed)
			(copperpour not_allowed)
			(footprints allowed)
		)
		(placement
			(enabled no)
			(sheetname "")
		)
		(fill yes
			(thermal_gap 0.5)
			(thermal_bridge_width 0.5)
			(island_removal_mode 0)
		)
		(polygon
			(pts
				(arc
					(start 202.481942 -209.235294)
					(mid 201.813922 -209.235294)
					(end 202.481942 -209.235294)
				)
			)
		)
	)
	(zone
		(layers "B.Cu" "In13.Cu" "In15.Cu")
		(hatch none 0.5)
		(connect_pads
			(clearance 0)
		)
		(min_thickness 0.25)
		(keepout
			(tracks not_allowed)
			(vias allowed)
			(pads allowed)
			(copperpour not_allowed)
			(footprints allowed)
		)
		(placement
			(enabled no)
			(sheetname "")
		)
		(fill yes
			(thermal_gap 0.5)
			(thermal_bridge_width 0.5)
			(island_removal_mode 0)
		)
		(polygon
			(pts
				(arc
					(start 332.606142 -278.946102)
					(mid 331.976222 -278.946102)
					(end 332.606142 -278.946102)
				)
			)
		)
	)
	(zone
		(layers "B.Cu" "In13.Cu" "In15.Cu")
		(hatch none 0.5)
		(connect_pads
			(clearance 0)
		)
		(min_thickness 0.25)
		(keepout
			(tracks not_allowed)
			(vias allowed)
			(pads allowed)
			(copperpour not_allowed)
			(footprints allowed)
		)
		(placement
			(enabled no)
			(sheetname "")
		)
		(fill yes
			(thermal_gap 0.5)
			(thermal_bridge_width 0.5)
			(island_removal_mode 0)
		)
		(polygon
			(pts
				(arc
					(start 333.716122 -238.004096)
					(mid 333.086202 -238.004096)
					(end 333.716122 -238.004096)
				)
			)
		)
	)
	(zone
		(layers "B.Cu" "In13.Cu" "In15.Cu")
		(hatch none 0.5)
		(connect_pads
			(clearance 0)
		)
		(min_thickness 0.25)
		(keepout
			(tracks not_allowed)
			(vias allowed)
			(pads allowed)
			(copperpour not_allowed)
			(footprints allowed)
		)
		(placement
			(enabled no)
			(sheetname "")
		)
		(fill yes
			(thermal_gap 0.5)
			(thermal_bridge_width 0.5)
			(island_removal_mode 0)
		)
		(polygon
			(pts
				(arc
					(start 115.379754 -233.95432)
					(mid 114.749834 -233.95432)
					(end 115.379754 -233.95432)
				)
			)
		)
	)
	(zone
		(layers "B.Cu" "In13.Cu" "In15.Cu")
		(hatch none 0.5)
		(connect_pads
			(clearance 0)
		)
		(min_thickness 0.25)
		(keepout
			(tracks not_allowed)
			(vias allowed)
			(pads allowed)
			(copperpour not_allowed)
			(footprints allowed)
		)
		(placement
			(enabled no)
			(sheetname "")
		)
		(fill yes
			(thermal_gap 0.5)
			(thermal_bridge_width 0.5)
			(island_removal_mode 0)
		)
		(polygon
			(pts
				(arc
					(start 17.942052 -268.735302)
					(mid 17.274032 -268.735302)
					(end 17.942052 -268.735302)
				)
			)
		)
	)
	(zone
		(layers "B.Cu" "In13.Cu" "In15.Cu")
		(hatch none 0.5)
		(connect_pads
			(clearance 0)
		)
		(min_thickness 0.25)
		(keepout
			(tracks not_allowed)
			(vias allowed)
			(pads allowed)
			(copperpour not_allowed)
			(footprints allowed)
		)
		(placement
			(enabled no)
			(sheetname "")
		)
		(fill yes
			(thermal_gap 0.5)
			(thermal_bridge_width 0.5)
			(island_removal_mode 0)
		)
		(polygon
			(pts
				(arc
					(start 334.186022 -227.474272)
					(mid 333.556102 -227.474272)
					(end 334.186022 -227.474272)
				)
			)
		)
	)
	(zone
		(layers "B.Cu" "In13.Cu" "In15.Cu")
		(hatch none 0.5)
		(connect_pads
			(clearance 0)
		)
		(min_thickness 0.25)
		(keepout
			(tracks not_allowed)
			(vias allowed)
			(pads allowed)
			(copperpour not_allowed)
			(footprints allowed)
		)
		(placement
			(enabled no)
			(sheetname "")
		)
		(fill yes
			(thermal_gap 0.5)
			(thermal_bridge_width 0.5)
			(island_removal_mode 0)
		)
		(polygon
			(pts
				(arc
					(start 126.136908 -429.689768)
					(mid 125.362716 -429.689768)
					(end 126.136908 -429.689768)
				)
			)
		)
	)
	(zone
		(layers "B.Cu" "In13.Cu" "In15.Cu")
		(hatch none 0.5)
		(connect_pads
			(clearance 0)
		)
		(min_thickness 0.25)
		(keepout
			(tracks not_allowed)
			(vias allowed)
			(pads allowed)
			(copperpour not_allowed)
			(footprints allowed)
		)
		(placement
			(enabled no)
			(sheetname "")
		)
		(fill yes
			(thermal_gap 0.5)
			(thermal_bridge_width 0.5)
			(island_removal_mode 0)
		)
		(polygon
			(pts
				(arc
					(start 138.40968 -247.724422)
					(mid 137.77976 -247.724422)
					(end 138.40968 -247.724422)
				)
			)
		)
	)
	(zone
		(layers "B.Cu" "In13.Cu" "In15.Cu")
		(hatch none 0.5)
		(connect_pads
			(clearance 0)
		)
		(min_thickness 0.25)
		(keepout
			(tracks not_allowed)
			(vias allowed)
			(pads allowed)
			(copperpour not_allowed)
			(footprints allowed)
		)
		(placement
			(enabled no)
			(sheetname "")
		)
		(fill yes
			(thermal_gap 0.5)
			(thermal_bridge_width 0.5)
			(island_removal_mode 0)
		)
		(polygon
			(pts
				(arc
					(start 107.396026 -247.724422)
					(mid 106.766106 -247.724422)
					(end 107.396026 -247.724422)
				)
			)
		)
	)
	(zone
		(layers "B.Cu" "In13.Cu" "In15.Cu")
		(hatch none 0.5)
		(connect_pads
			(clearance 0)
		)
		(min_thickness 0.25)
		(keepout
			(tracks not_allowed)
			(vias allowed)
			(pads allowed)
			(copperpour not_allowed)
			(footprints allowed)
		)
		(placement
			(enabled no)
			(sheetname "")
		)
		(fill yes
			(thermal_gap 0.5)
			(thermal_bridge_width 0.5)
			(island_removal_mode 0)
		)
		(polygon
			(pts
				(arc
					(start 84.3661 -229.094538)
					(mid 83.73618 -229.094538)
					(end 84.3661 -229.094538)
				)
			)
		)
	)
	(zone
		(layers "B.Cu" "In13.Cu" "In15.Cu")
		(hatch none 0.5)
		(connect_pads
			(clearance 0)
		)
		(min_thickness 0.25)
		(keepout
			(tracks not_allowed)
			(vias allowed)
			(pads allowed)
			(copperpour not_allowed)
			(footprints allowed)
		)
		(placement
			(enabled no)
			(sheetname "")
		)
		(fill yes
			(thermal_gap 0.5)
			(thermal_bridge_width 0.5)
			(island_removal_mode 0)
		)
		(polygon
			(pts
				(arc
					(start 143.660876 -412.570168)
					(mid 142.992856 -412.570168)
					(end 143.660876 -412.570168)
				)
			)
		)
	)
	(zone
		(layers "B.Cu" "In13.Cu" "In15.Cu")
		(hatch none 0.5)
		(connect_pads
			(clearance 0)
		)
		(min_thickness 0.25)
		(keepout
			(tracks not_allowed)
			(vias allowed)
			(pads allowed)
			(copperpour not_allowed)
			(footprints allowed)
		)
		(placement
			(enabled no)
			(sheetname "")
		)
		(fill yes
			(thermal_gap 0.5)
			(thermal_bridge_width 0.5)
			(island_removal_mode 0)
		)
		(polygon
			(pts
				(arc
					(start 107.696 -278.13635)
					(mid 107.06608 -278.13635)
					(end 107.696 -278.13635)
				)
			)
		)
	)
	(zone
		(layers "B.Cu" "In13.Cu" "In15.Cu")
		(hatch none 0.5)
		(connect_pads
			(clearance 0)
		)
		(min_thickness 0.25)
		(keepout
			(tracks not_allowed)
			(vias allowed)
			(pads allowed)
			(copperpour not_allowed)
			(footprints allowed)
		)
		(placement
			(enabled no)
			(sheetname "")
		)
		(fill yes
			(thermal_gap 0.5)
			(thermal_bridge_width 0.5)
			(island_removal_mode 0)
		)
		(polygon
			(pts
				(arc
					(start 94.940374 -412.570168)
					(mid 94.272354 -412.570168)
					(end 94.940374 -412.570168)
				)
			)
		)
	)
	(zone
		(layers "B.Cu" "In13.Cu" "In15.Cu")
		(hatch none 0.5)
		(connect_pads
			(clearance 0)
		)
		(min_thickness 0.25)
		(keepout
			(tracks not_allowed)
			(vias allowed)
			(pads allowed)
			(copperpour not_allowed)
			(footprints allowed)
		)
		(placement
			(enabled no)
			(sheetname "")
		)
		(fill yes
			(thermal_gap 0.5)
			(thermal_bridge_width 0.5)
			(island_removal_mode 0)
		)
		(polygon
			(pts
				(arc
					(start 388.059676 -290.285932)
					(mid 387.429756 -290.285932)
					(end 388.059676 -290.285932)
				)
			)
		)
	)
	(zone
		(layers "B.Cu" "In13.Cu" "In15.Cu")
		(hatch none 0.5)
		(connect_pads
			(clearance 0)
		)
		(min_thickness 0.25)
		(keepout
			(tracks not_allowed)
			(vias allowed)
			(pads allowed)
			(copperpour not_allowed)
			(footprints allowed)
		)
		(placement
			(enabled no)
			(sheetname "")
		)
		(fill yes
			(thermal_gap 0.5)
			(thermal_bridge_width 0.5)
			(island_removal_mode 0)
		)
		(polygon
			(pts
				(arc
					(start 338.233766 -394.385292)
					(mid 337.603846 -394.385292)
					(end 338.233766 -394.385292)
				)
			)
		)
	)
	(zone
		(layers "B.Cu" "In13.Cu" "In15.Cu")
		(hatch none 0.5)
		(connect_pads
			(clearance 0)
		)
		(min_thickness 0.25)
		(keepout
			(tracks not_allowed)
			(vias allowed)
			(pads allowed)
			(copperpour not_allowed)
			(footprints allowed)
		)
		(placement
			(enabled no)
			(sheetname "")
		)
		(fill yes
			(thermal_gap 0.5)
			(thermal_bridge_width 0.5)
			(island_removal_mode 0)
		)
		(polygon
			(pts
				(arc
					(start 393.849606 -6.725158)
					(mid 393.181586 -6.725158)
					(end 393.849606 -6.725158)
				)
			)
		)
	)
	(zone
		(layers "B.Cu" "In13.Cu" "In15.Cu")
		(hatch none 0.5)
		(connect_pads
			(clearance 0)
		)
		(min_thickness 0.25)
		(keepout
			(tracks not_allowed)
			(vias allowed)
			(pads allowed)
			(copperpour not_allowed)
			(footprints allowed)
		)
		(placement
			(enabled no)
			(sheetname "")
		)
		(fill yes
			(thermal_gap 0.5)
			(thermal_bridge_width 0.5)
			(island_removal_mode 0)
		)
		(polygon
			(pts
				(arc
					(start 353.833684 -394.385292)
					(mid 353.203764 -394.385292)
					(end 353.833684 -394.385292)
				)
			)
		)
	)
	(zone
		(layers "B.Cu" "In13.Cu" "In15.Cu")
		(hatch none 0.5)
		(connect_pads
			(clearance 0)
		)
		(min_thickness 0.25)
		(keepout
			(tracks not_allowed)
			(vias allowed)
			(pads allowed)
			(copperpour not_allowed)
			(footprints allowed)
		)
		(placement
			(enabled no)
			(sheetname "")
		)
		(fill yes
			(thermal_gap 0.5)
			(thermal_bridge_width 0.5)
			(island_removal_mode 0)
		)
		(polygon
			(pts
				(arc
					(start 101.11613 -274.896326)
					(mid 100.48621 -274.896326)
					(end 101.11613 -274.896326)
				)
			)
		)
	)
	(zone
		(layers "B.Cu" "In13.Cu" "In15.Cu")
		(hatch none 0.5)
		(connect_pads
			(clearance 0)
		)
		(min_thickness 0.25)
		(keepout
			(tracks not_allowed)
			(vias allowed)
			(pads allowed)
			(copperpour not_allowed)
			(footprints allowed)
		)
		(placement
			(enabled no)
			(sheetname "")
		)
		(fill yes
			(thermal_gap 0.5)
			(thermal_bridge_width 0.5)
			(island_removal_mode 0)
		)
		(polygon
			(pts
				(arc
					(start 98.634042 -388.774432)
					(mid 98.004122 -388.774432)
					(end 98.634042 -388.774432)
				)
			)
		)
	)
	(zone
		(layers "B.Cu" "In13.Cu" "In15.Cu")
		(hatch none 0.5)
		(connect_pads
			(clearance 0)
		)
		(min_thickness 0.25)
		(keepout
			(tracks not_allowed)
			(vias allowed)
			(pads allowed)
			(copperpour not_allowed)
			(footprints allowed)
		)
		(placement
			(enabled no)
			(sheetname "")
		)
		(fill yes
			(thermal_gap 0.5)
			(thermal_bridge_width 0.5)
			(island_removal_mode 0)
		)
		(polygon
			(pts
				(arc
					(start 161.176716 -412.570168)
					(mid 160.508696 -412.570168)
					(end 161.176716 -412.570168)
				)
			)
		)
	)
	(zone
		(layers "B.Cu" "In13.Cu" "In15.Cu")
		(hatch none 0.5)
		(connect_pads
			(clearance 0)
		)
		(min_thickness 0.25)
		(keepout
			(tracks not_allowed)
			(vias allowed)
			(pads allowed)
			(copperpour not_allowed)
			(footprints allowed)
		)
		(placement
			(enabled no)
			(sheetname "")
		)
		(fill yes
			(thermal_gap 0.5)
			(thermal_bridge_width 0.5)
			(island_removal_mode 0)
		)
		(polygon
			(pts
				(arc
					(start 265.88212 -272.984976)
					(mid 265.2141 -272.984976)
					(end 265.88212 -272.984976)
				)
			)
		)
	)
	(zone
		(layers "B.Cu" "In13.Cu" "In15.Cu")
		(hatch none 0.5)
		(connect_pads
			(clearance 0)
		)
		(min_thickness 0.25)
		(keepout
			(tracks not_allowed)
			(vias allowed)
			(pads allowed)
			(copperpour not_allowed)
			(footprints allowed)
		)
		(placement
			(enabled no)
			(sheetname "")
		)
		(fill yes
			(thermal_gap 0.5)
			(thermal_bridge_width 0.5)
			(island_removal_mode 0)
		)
		(polygon
			(pts
				(arc
					(start 85.776054 -242.864386)
					(mid 85.146134 -242.864386)
					(end 85.776054 -242.864386)
				)
			)
		)
	)
	(zone
		(layers "B.Cu" "In13.Cu" "In15.Cu")
		(hatch none 0.5)
		(connect_pads
			(clearance 0)
		)
		(min_thickness 0.25)
		(keepout
			(tracks not_allowed)
			(vias allowed)
			(pads allowed)
			(copperpour not_allowed)
			(footprints allowed)
		)
		(placement
			(enabled no)
			(sheetname "")
		)
		(fill yes
			(thermal_gap 0.5)
			(thermal_bridge_width 0.5)
			(island_removal_mode 0)
		)
		(polygon
			(pts
				(arc
					(start 70.434454 -412.570168)
					(mid 69.766434 -412.570168)
					(end 70.434454 -412.570168)
				)
			)
		)
	)
	(zone
		(layers "B.Cu" "In13.Cu" "In15.Cu")
		(hatch none 0.5)
		(connect_pads
			(clearance 0)
		)
		(min_thickness 0.25)
		(keepout
			(tracks not_allowed)
			(vias allowed)
			(pads allowed)
			(copperpour not_allowed)
			(footprints allowed)
		)
		(placement
			(enabled no)
			(sheetname "")
		)
		(fill yes
			(thermal_gap 0.5)
			(thermal_bridge_width 0.5)
			(island_removal_mode 0)
		)
		(polygon
			(pts
				(arc
					(start 363.619796 -275.706078)
					(mid 362.989876 -275.706078)
					(end 363.619796 -275.706078)
				)
			)
		)
	)
	(zone
		(layers "B.Cu" "In13.Cu" "In15.Cu")
		(hatch none 0.5)
		(connect_pads
			(clearance 0)
		)
		(min_thickness 0.25)
		(keepout
			(tracks not_allowed)
			(vias allowed)
			(pads allowed)
			(copperpour not_allowed)
			(footprints allowed)
		)
		(placement
			(enabled no)
			(sheetname "")
		)
		(fill yes
			(thermal_gap 0.5)
			(thermal_bridge_width 0.5)
			(island_removal_mode 0)
		)
		(polygon
			(pts
				(arc
					(start 401.04949 -6.725158)
					(mid 400.38147 -6.725158)
					(end 401.04949 -6.725158)
				)
			)
		)
	)
	(zone
		(layers "B.Cu" "In13.Cu" "In15.Cu")
		(hatch none 0.5)
		(connect_pads
			(clearance 0)
		)
		(min_thickness 0.25)
		(keepout
			(tracks not_allowed)
			(vias allowed)
			(pads allowed)
			(copperpour not_allowed)
			(footprints allowed)
		)
		(placement
			(enabled no)
			(sheetname "")
		)
		(fill yes
			(thermal_gap 0.5)
			(thermal_bridge_width 0.5)
			(island_removal_mode 0)
		)
		(polygon
			(pts
				(arc
					(start 76.037186 -429.689768)
					(mid 75.262994 -429.689768)
					(end 76.037186 -429.689768)
				)
			)
		)
	)
	(zone
		(layers "B.Cu" "In13.Cu" "In15.Cu")
		(hatch none 0.5)
		(connect_pads
			(clearance 0)
		)
		(min_thickness 0.25)
		(keepout
			(tracks not_allowed)
			(vias allowed)
			(pads allowed)
			(copperpour not_allowed)
			(footprints allowed)
		)
		(placement
			(enabled no)
			(sheetname "")
		)
		(fill yes
			(thermal_gap 0.5)
			(thermal_bridge_width 0.5)
			(island_removal_mode 0)
		)
		(polygon
			(pts
				(arc
					(start 386.649722 -291.095938)
					(mid 386.019802 -291.095938)
					(end 386.649722 -291.095938)
				)
			)
		)
	)
	(zone
		(layers "B.Cu" "In13.Cu" "In15.Cu")
		(hatch none 0.5)
		(connect_pads
			(clearance 0)
		)
		(min_thickness 0.25)
		(keepout
			(tracks not_allowed)
			(vias allowed)
			(pads allowed)
			(copperpour not_allowed)
			(footprints allowed)
		)
		(placement
			(enabled no)
			(sheetname "")
		)
		(fill yes
			(thermal_gap 0.5)
			(thermal_bridge_width 0.5)
			(island_removal_mode 0)
		)
		(polygon
			(pts
				(arc
					(start 343.833704 -393.69238)
					(mid 343.203784 -393.69238)
					(end 343.833704 -393.69238)
				)
			)
		)
	)
	(zone
		(layers "B.Cu" "In13.Cu" "In15.Cu")
		(hatch none 0.5)
		(connect_pads
			(clearance 0)
		)
		(min_thickness 0.25)
		(keepout
			(tracks not_allowed)
			(vias allowed)
			(pads allowed)
			(copperpour not_allowed)
			(footprints allowed)
		)
		(placement
			(enabled no)
			(sheetname "")
		)
		(fill yes
			(thermal_gap 0.5)
			(thermal_bridge_width 0.5)
			(island_removal_mode 0)
		)
		(polygon
			(pts
				(arc
					(start 85.776054 -254.20447)
					(mid 85.146134 -254.20447)
					(end 85.776054 -254.20447)
				)
			)
		)
	)
	(zone
		(layers "B.Cu" "In13.Cu" "In15.Cu")
		(hatch none 0.5)
		(connect_pads
			(clearance 0)
		)
		(min_thickness 0.25)
		(keepout
			(tracks not_allowed)
			(vias allowed)
			(pads allowed)
			(copperpour not_allowed)
			(footprints allowed)
		)
		(placement
			(enabled no)
			(sheetname "")
		)
		(fill yes
			(thermal_gap 0.5)
			(thermal_bridge_width 0.5)
			(island_removal_mode 0)
		)
		(polygon
			(pts
				(arc
					(start 269.982188 -214.335106)
					(mid 269.314168 -214.335106)
					(end 269.982188 -214.335106)
				)
			)
		)
	)
	(zone
		(layers "B.Cu" "In13.Cu" "In15.Cu")
		(hatch none 0.5)
		(connect_pads
			(clearance 0)
		)
		(min_thickness 0.25)
		(keepout
			(tracks not_allowed)
			(vias allowed)
			(pads allowed)
			(copperpour not_allowed)
			(footprints allowed)
		)
		(placement
			(enabled no)
			(sheetname "")
		)
		(fill yes
			(thermal_gap 0.5)
			(thermal_bridge_width 0.5)
			(island_removal_mode 0)
		)
		(polygon
			(pts
				(arc
					(start 91.833954 -389.467344)
					(mid 91.204034 -389.467344)
					(end 91.833954 -389.467344)
				)
			)
		)
	)
	(zone
		(layers "B.Cu" "In13.Cu" "In15.Cu")
		(hatch none 0.5)
		(connect_pads
			(clearance 0)
		)
		(min_thickness 0.25)
		(keepout
			(tracks not_allowed)
			(vias allowed)
			(pads allowed)
			(copperpour not_allowed)
			(footprints allowed)
		)
		(placement
			(enabled no)
			(sheetname "")
		)
		(fill yes
			(thermal_gap 0.5)
			(thermal_bridge_width 0.5)
			(island_removal_mode 0)
		)
		(polygon
			(pts
				(arc
					(start 269.982188 -262.785098)
					(mid 269.314168 -262.785098)
					(end 269.982188 -262.785098)
				)
			)
		)
	)
	(zone
		(layers "B.Cu" "In13.Cu" "In15.Cu")
		(hatch none 0.5)
		(connect_pads
			(clearance 0)
		)
		(min_thickness 0.25)
		(keepout
			(tracks not_allowed)
			(vias allowed)
			(pads allowed)
			(copperpour not_allowed)
			(footprints allowed)
		)
		(placement
			(enabled no)
			(sheetname "")
		)
		(fill yes
			(thermal_gap 0.5)
			(thermal_bridge_width 0.5)
			(island_removal_mode 0)
		)
		(polygon
			(pts
				(arc
					(start 140.13688 -430.689766)
					(mid 139.362688 -430.689766)
					(end 140.13688 -430.689766)
				)
			)
		)
	)
	(zone
		(layers "B.Cu" "In13.Cu" "In15.Cu")
		(hatch none 0.5)
		(connect_pads
			(clearance 0)
		)
		(min_thickness 0.25)
		(keepout
			(tracks not_allowed)
			(vias allowed)
			(pads allowed)
			(copperpour not_allowed)
			(footprints allowed)
		)
		(placement
			(enabled no)
			(sheetname "")
		)
		(fill yes
			(thermal_gap 0.5)
			(thermal_bridge_width 0.5)
			(island_removal_mode 0)
		)
		(polygon
			(pts
				(arc
					(start 450.42201 -268.735048)
					(mid 449.75399 -268.735048)
					(end 450.42201 -268.735048)
				)
			)
		)
	)
	(zone
		(layers "B.Cu" "In13.Cu" "In15.Cu")
		(hatch none 0.5)
		(connect_pads
			(clearance 0)
		)
		(min_thickness 0.25)
		(keepout
			(tracks not_allowed)
			(vias allowed)
			(pads allowed)
			(copperpour not_allowed)
			(footprints allowed)
		)
		(placement
			(enabled no)
			(sheetname "")
		)
		(fill yes
			(thermal_gap 0.5)
			(thermal_bridge_width 0.5)
			(island_removal_mode 0)
		)
		(polygon
			(pts
				(arc
					(start 85.135974 -289.47618)
					(mid 84.506054 -289.47618)
					(end 85.135974 -289.47618)
				)
			)
		)
	)
	(zone
		(layers "B.Cu" "In13.Cu" "In15.Cu")
		(hatch none 0.5)
		(connect_pads
			(clearance 0)
		)
		(min_thickness 0.25)
		(keepout
			(tracks not_allowed)
			(vias allowed)
			(pads allowed)
			(copperpour not_allowed)
			(footprints allowed)
		)
		(placement
			(enabled no)
			(sheetname "")
		)
		(fill yes
			(thermal_gap 0.5)
			(thermal_bridge_width 0.5)
			(island_removal_mode 0)
		)
		(polygon
			(pts
				(arc
					(start 206.58201 -284.885384)
					(mid 205.91399 -284.885384)
					(end 206.58201 -284.885384)
				)
			)
		)
	)
	(zone
		(layers "B.Cu" "In13.Cu" "In15.Cu")
		(hatch none 0.5)
		(connect_pads
			(clearance 0)
		)
		(min_thickness 0.25)
		(keepout
			(tracks not_allowed)
			(vias allowed)
			(pads allowed)
			(copperpour not_allowed)
			(footprints allowed)
		)
		(placement
			(enabled no)
			(sheetname "")
		)
		(fill yes
			(thermal_gap 0.5)
			(thermal_bridge_width 0.5)
			(island_removal_mode 0)
		)
		(polygon
			(pts
				(arc
					(start 113.014506 -369.03533)
					(mid 112.346486 -369.03533)
					(end 113.014506 -369.03533)
				)
			)
		)
	)
	(zone
		(layers "B.Cu" "In13.Cu" "In15.Cu")
		(hatch none 0.5)
		(connect_pads
			(clearance 0)
		)
		(min_thickness 0.25)
		(keepout
			(tracks not_allowed)
			(vias allowed)
			(pads allowed)
			(copperpour not_allowed)
			(footprints allowed)
		)
		(placement
			(enabled no)
			(sheetname "")
		)
		(fill yes
			(thermal_gap 0.5)
			(thermal_bridge_width 0.5)
			(island_removal_mode 0)
		)
		(polygon
			(pts
				(arc
					(start 365.969804 -276.516084)
					(mid 365.339884 -276.516084)
					(end 365.969804 -276.516084)
				)
			)
		)
	)
	(zone
		(layers "B.Cu" "In13.Cu" "In15.Cu")
		(hatch none 0.5)
		(connect_pads
			(clearance 0)
		)
		(min_thickness 0.25)
		(keepout
			(tracks not_allowed)
			(vias allowed)
			(pads allowed)
			(copperpour not_allowed)
			(footprints allowed)
		)
		(placement
			(enabled no)
			(sheetname "")
		)
		(fill yes
			(thermal_gap 0.5)
			(thermal_bridge_width 0.5)
			(island_removal_mode 0)
		)
		(polygon
			(pts
				(arc
					(start 17.942052 -220.28531)
					(mid 17.274032 -220.28531)
					(end 17.942052 -220.28531)
				)
			)
		)
	)
	(zone
		(layers "B.Cu" "In13.Cu" "In15.Cu")
		(hatch none 0.5)
		(connect_pads
			(clearance 0)
		)
		(min_thickness 0.25)
		(keepout
			(tracks not_allowed)
			(vias allowed)
			(pads allowed)
			(copperpour not_allowed)
			(footprints allowed)
		)
		(placement
			(enabled no)
			(sheetname "")
		)
		(fill yes
			(thermal_gap 0.5)
			(thermal_bridge_width 0.5)
			(island_removal_mode 0)
		)
		(polygon
			(pts
				(arc
					(start 17.942052 -235.585254)
					(mid 17.274032 -235.585254)
					(end 17.942052 -235.585254)
				)
			)
		)
	)
	(zone
		(layers "B.Cu" "In13.Cu" "In15.Cu")
		(hatch none 0.5)
		(connect_pads
			(clearance 0)
		)
		(min_thickness 0.25)
		(keepout
			(tracks not_allowed)
			(vias allowed)
			(pads allowed)
			(copperpour not_allowed)
			(footprints allowed)
		)
		(placement
			(enabled no)
			(sheetname "")
		)
		(fill yes
			(thermal_gap 0.5)
			(thermal_bridge_width 0.5)
			(island_removal_mode 0)
		)
		(polygon
			(pts
				(arc
					(start 139.349734 -244.484398)
					(mid 138.719814 -244.484398)
					(end 139.349734 -244.484398)
				)
			)
		)
	)
	(zone
		(layers "B.Cu" "In13.Cu" "In15.Cu")
		(hatch none 0.5)
		(connect_pads
			(clearance 0)
		)
		(min_thickness 0.25)
		(keepout
			(tracks not_allowed)
			(vias allowed)
			(pads allowed)
			(copperpour not_allowed)
			(footprints allowed)
		)
		(placement
			(enabled no)
			(sheetname "")
		)
		(fill yes
			(thermal_gap 0.5)
			(thermal_bridge_width 0.5)
			(island_removal_mode 0)
		)
		(polygon
			(pts
				(arc
					(start 337.833716 -393.69238)
					(mid 337.203796 -393.69238)
					(end 337.833716 -393.69238)
				)
			)
		)
	)
	(zone
		(layers "B.Cu" "In13.Cu" "In15.Cu")
		(hatch none 0.5)
		(connect_pads
			(clearance 0)
		)
		(min_thickness 0.25)
		(keepout
			(tracks not_allowed)
			(vias allowed)
			(pads allowed)
			(copperpour not_allowed)
			(footprints allowed)
		)
		(placement
			(enabled no)
			(sheetname "")
		)
		(fill yes
			(thermal_gap 0.5)
			(thermal_bridge_width 0.5)
			(island_removal_mode 0)
		)
		(polygon
			(pts
				(arc
					(start 123.369578 -236.384338)
					(mid 122.739658 -236.384338)
					(end 123.369578 -236.384338)
				)
			)
		)
	)
	(zone
		(layers "B.Cu" "In13.Cu" "In15.Cu")
		(hatch none 0.5)
		(connect_pads
			(clearance 0)
		)
		(min_thickness 0.25)
		(keepout
			(tracks not_allowed)
			(vias allowed)
			(pads allowed)
			(copperpour not_allowed)
			(footprints allowed)
		)
		(placement
			(enabled no)
			(sheetname "")
		)
		(fill yes
			(thermal_gap 0.5)
			(thermal_bridge_width 0.5)
			(island_removal_mode 0)
		)
		(polygon
			(pts
				(arc
					(start 332.306168 -251.774198)
					(mid 331.676248 -251.774198)
					(end 332.306168 -251.774198)
				)
			)
		)
	)
	(zone
		(layers "B.Cu" "In13.Cu" "In15.Cu")
		(hatch none 0.5)
		(connect_pads
			(clearance 0)
		)
		(min_thickness 0.25)
		(keepout
			(tracks not_allowed)
			(vias allowed)
			(pads allowed)
			(copperpour not_allowed)
			(footprints allowed)
		)
		(placement
			(enabled no)
			(sheetname "")
		)
		(fill yes
			(thermal_gap 0.5)
			(thermal_bridge_width 0.5)
			(island_removal_mode 0)
		)
		(polygon
			(pts
				(arc
					(start 80.037178 -430.889918)
					(mid 79.262986 -430.889918)
					(end 80.037178 -430.889918)
				)
			)
		)
	)
	(zone
		(layers "B.Cu" "In13.Cu" "In15.Cu")
		(hatch none 0.5)
		(connect_pads
			(clearance 0)
		)
		(min_thickness 0.25)
		(keepout
			(tracks not_allowed)
			(vias allowed)
			(pads allowed)
			(copperpour not_allowed)
			(footprints allowed)
		)
		(placement
			(enabled no)
			(sheetname "")
		)
		(fill yes
			(thermal_gap 0.5)
			(thermal_bridge_width 0.5)
			(island_removal_mode 0)
		)
		(polygon
			(pts
				(arc
					(start 86.545928 -272.466308)
					(mid 85.916008 -272.466308)
					(end 86.545928 -272.466308)
				)
			)
		)
	)
	(zone
		(layers "B.Cu" "In13.Cu" "In15.Cu")
		(hatch none 0.5)
		(connect_pads
			(clearance 0)
		)
		(min_thickness 0.25)
		(keepout
			(tracks not_allowed)
			(vias allowed)
			(pads allowed)
			(copperpour not_allowed)
			(footprints allowed)
		)
		(placement
			(enabled no)
			(sheetname "")
		)
		(fill yes
			(thermal_gap 0.5)
			(thermal_bridge_width 0.5)
			(island_removal_mode 0)
		)
		(polygon
			(pts
				(arc
					(start 22.04212 -311.235344)
					(mid 21.3741 -311.235344)
					(end 22.04212 -311.235344)
				)
			)
		)
	)
	(zone
		(layers "B.Cu" "In13.Cu" "In15.Cu")
		(hatch none 0.5)
		(connect_pads
			(clearance 0)
		)
		(min_thickness 0.25)
		(keepout
			(tracks not_allowed)
			(vias allowed)
			(pads allowed)
			(copperpour not_allowed)
			(footprints allowed)
		)
		(placement
			(enabled no)
			(sheetname "")
		)
		(fill yes
			(thermal_gap 0.5)
			(thermal_bridge_width 0.5)
			(island_removal_mode 0)
		)
		(polygon
			(pts
				(arc
					(start 333.076042 -265.176)
					(mid 332.446122 -265.176)
					(end 333.076042 -265.176)
				)
			)
		)
	)
	(zone
		(layers "B.Cu" "In13.Cu" "In15.Cu")
		(hatch none 0.5)
		(connect_pads
			(clearance 0)
		)
		(min_thickness 0.25)
		(keepout
			(tracks not_allowed)
			(vias allowed)
			(pads allowed)
			(copperpour not_allowed)
			(footprints allowed)
		)
		(placement
			(enabled no)
			(sheetname "")
		)
		(fill yes
			(thermal_gap 0.5)
			(thermal_bridge_width 0.5)
			(island_removal_mode 0)
		)
		(polygon
			(pts
				(arc
					(start 86.545928 -277.326344)
					(mid 85.916008 -277.326344)
					(end 86.545928 -277.326344)
				)
			)
		)
	)
	(zone
		(layers "B.Cu" "In13.Cu" "In15.Cu")
		(hatch none 0.5)
		(connect_pads
			(clearance 0)
		)
		(min_thickness 0.25)
		(keepout
			(tracks not_allowed)
			(vias allowed)
			(pads allowed)
			(copperpour not_allowed)
			(footprints allowed)
		)
		(placement
			(enabled no)
			(sheetname "")
		)
		(fill yes
			(thermal_gap 0.5)
			(thermal_bridge_width 0.5)
			(island_removal_mode 0)
		)
		(polygon
			(pts
				(arc
					(start 373.489728 -276.516084)
					(mid 372.859808 -276.516084)
					(end 373.489728 -276.516084)
				)
			)
		)
	)
	(zone
		(layers "B.Cu" "In13.Cu" "In15.Cu")
		(hatch none 0.5)
		(connect_pads
			(clearance 0)
		)
		(min_thickness 0.25)
		(keepout
			(tracks not_allowed)
			(vias allowed)
			(pads allowed)
			(copperpour not_allowed)
			(footprints allowed)
		)
		(placement
			(enabled no)
			(sheetname "")
		)
		(fill yes
			(thermal_gap 0.5)
			(thermal_bridge_width 0.5)
			(island_removal_mode 0)
		)
		(polygon
			(pts
				(arc
					(start 454.522078 -238.985044)
					(mid 453.854058 -238.985044)
					(end 454.522078 -238.985044)
				)
			)
		)
	)
	(zone
		(layers "B.Cu" "In13.Cu" "In15.Cu")
		(hatch none 0.5)
		(connect_pads
			(clearance 0)
		)
		(min_thickness 0.25)
		(keepout
			(tracks not_allowed)
			(vias allowed)
			(pads allowed)
			(copperpour not_allowed)
			(footprints allowed)
		)
		(placement
			(enabled no)
			(sheetname "")
		)
		(fill yes
			(thermal_gap 0.5)
			(thermal_bridge_width 0.5)
			(island_removal_mode 0)
		)
		(polygon
			(pts
				(arc
					(start 118.029736 -278.13635)
					(mid 117.399816 -278.13635)
					(end 118.029736 -278.13635)
				)
			)
		)
	)
	(zone
		(layers "B.Cu" "In13.Cu" "In15.Cu")
		(hatch none 0.5)
		(connect_pads
			(clearance 0)
		)
		(min_thickness 0.25)
		(keepout
			(tracks not_allowed)
			(vias allowed)
			(pads allowed)
			(copperpour not_allowed)
			(footprints allowed)
		)
		(placement
			(enabled no)
			(sheetname "")
		)
		(fill yes
			(thermal_gap 0.5)
			(thermal_bridge_width 0.5)
			(island_removal_mode 0)
		)
		(polygon
			(pts
				(arc
					(start 139.349734 -228.284532)
					(mid 138.719814 -228.284532)
					(end 139.349734 -228.284532)
				)
			)
		)
	)
	(zone
		(layers "B.Cu" "In13.Cu" "In15.Cu")
		(hatch none 0.5)
		(connect_pads
			(clearance 0)
		)
		(min_thickness 0.25)
		(keepout
			(tracks not_allowed)
			(vias allowed)
			(pads allowed)
			(copperpour not_allowed)
			(footprints allowed)
		)
		(placement
			(enabled no)
			(sheetname "")
		)
		(fill yes
			(thermal_gap 0.5)
			(thermal_bridge_width 0.5)
			(island_removal_mode 0)
		)
		(polygon
			(pts
				(arc
					(start 117.729762 -234.764326)
					(mid 117.099842 -234.764326)
					(end 117.729762 -234.764326)
				)
			)
		)
	)
	(zone
		(layers "B.Cu" "In13.Cu" "In15.Cu")
		(hatch none 0.5)
		(connect_pads
			(clearance 0)
		)
		(min_thickness 0.25)
		(keepout
			(tracks not_allowed)
			(vias allowed)
			(pads allowed)
			(copperpour not_allowed)
			(footprints allowed)
		)
		(placement
			(enabled no)
			(sheetname "")
		)
		(fill yes
			(thermal_gap 0.5)
			(thermal_bridge_width 0.5)
			(island_removal_mode 0)
		)
		(polygon
			(pts
				(arc
					(start 206.58201 -249.18543)
					(mid 205.91399 -249.18543)
					(end 206.58201 -249.18543)
				)
			)
		)
	)
	(zone
		(layers "B.Cu" "In13.Cu" "In15.Cu")
		(hatch none 0.5)
		(connect_pads
			(clearance 0)
		)
		(min_thickness 0.25)
		(keepout
			(tracks not_allowed)
			(vias allowed)
			(pads allowed)
			(copperpour not_allowed)
			(footprints allowed)
		)
		(placement
			(enabled no)
			(sheetname "")
		)
		(fill yes
			(thermal_gap 0.5)
			(thermal_bridge_width 0.5)
			(island_removal_mode 0)
		)
		(polygon
			(pts
				(arc
					(start 120.54967 -234.764326)
					(mid 119.91975 -234.764326)
					(end 120.54967 -234.764326)
				)
			)
		)
	)
	(zone
		(layers "B.Cu" "In13.Cu" "In15.Cu")
		(hatch none 0.5)
		(connect_pads
			(clearance 0)
		)
		(min_thickness 0.25)
		(keepout
			(tracks not_allowed)
			(vias allowed)
			(pads allowed)
			(copperpour not_allowed)
			(footprints allowed)
		)
		(placement
			(enabled no)
			(sheetname "")
		)
		(fill yes
			(thermal_gap 0.5)
			(thermal_bridge_width 0.5)
			(island_removal_mode 0)
		)
		(polygon
			(pts
				(arc
					(start 265.88212 -222.834962)
					(mid 265.2141 -222.834962)
					(end 265.88212 -222.834962)
				)
			)
		)
	)
	(zone
		(layers "B.Cu" "In13.Cu" "In15.Cu")
		(hatch none 0.5)
		(connect_pads
			(clearance 0)
		)
		(min_thickness 0.25)
		(keepout
			(tracks not_allowed)
			(vias allowed)
			(pads allowed)
			(copperpour not_allowed)
			(footprints allowed)
		)
		(placement
			(enabled no)
			(sheetname "")
		)
		(fill yes
			(thermal_gap 0.5)
			(thermal_bridge_width 0.5)
			(island_removal_mode 0)
		)
		(polygon
			(pts
				(arc
					(start 335.623916 -420.952168)
					(mid 334.955896 -420.952168)
					(end 335.623916 -420.952168)
				)
			)
		)
	)
	(zone
		(layers "B.Cu" "In13.Cu" "In15.Cu")
		(hatch none 0.5)
		(connect_pads
			(clearance 0)
		)
		(min_thickness 0.25)
		(keepout
			(tracks not_allowed)
			(vias allowed)
			(pads allowed)
			(copperpour not_allowed)
			(footprints allowed)
		)
		(placement
			(enabled no)
			(sheetname "")
		)
		(fill yes
			(thermal_gap 0.5)
			(thermal_bridge_width 0.5)
			(island_removal_mode 0)
		)
		(polygon
			(pts
				(arc
					(start 138.709654 -291.096192)
					(mid 138.079734 -291.096192)
					(end 138.709654 -291.096192)
				)
			)
		)
	)
	(zone
		(layers "B.Cu" "In13.Cu" "In15.Cu")
		(hatch none 0.5)
		(connect_pads
			(clearance 0)
		)
		(min_thickness 0.25)
		(keepout
			(tracks not_allowed)
			(vias allowed)
			(pads allowed)
			(copperpour not_allowed)
			(footprints allowed)
		)
		(placement
			(enabled no)
			(sheetname "")
		)
		(fill yes
			(thermal_gap 0.5)
			(thermal_bridge_width 0.5)
			(island_removal_mode 0)
		)
		(polygon
			(pts
				(arc
					(start 22.04212 -261.08533)
					(mid 21.3741 -261.08533)
					(end 22.04212 -261.08533)
				)
			)
		)
	)
	(zone
		(layers "B.Cu" "In13.Cu" "In15.Cu")
		(hatch none 0.5)
		(connect_pads
			(clearance 0)
		)
		(min_thickness 0.25)
		(keepout
			(tracks not_allowed)
			(vias allowed)
			(pads allowed)
			(copperpour not_allowed)
			(footprints allowed)
		)
		(placement
			(enabled no)
			(sheetname "")
		)
		(fill yes
			(thermal_gap 0.5)
			(thermal_bridge_width 0.5)
			(island_removal_mode 0)
		)
		(polygon
			(pts
				(arc
					(start 450.42201 -276.38502)
					(mid 449.75399 -276.38502)
					(end 450.42201 -276.38502)
				)
			)
		)
	)
	(zone
		(layers "B.Cu" "In13.Cu" "In15.Cu")
		(hatch none 0.5)
		(connect_pads
			(clearance 0)
		)
		(min_thickness 0.25)
		(keepout
			(tracks not_allowed)
			(vias allowed)
			(pads allowed)
			(copperpour not_allowed)
			(footprints allowed)
		)
		(placement
			(enabled no)
			(sheetname "")
		)
		(fill yes
			(thermal_gap 0.5)
			(thermal_bridge_width 0.5)
			(island_removal_mode 0)
		)
		(polygon
			(pts
				(arc
					(start 17.942052 -313.78525)
					(mid 17.274032 -313.78525)
					(end 17.942052 -313.78525)
				)
			)
		)
	)
	(zone
		(layers "B.Cu" "In13.Cu" "In15.Cu")
		(hatch none 0.5)
		(connect_pads
			(clearance 0)
		)
		(min_thickness 0.25)
		(keepout
			(tracks not_allowed)
			(vias allowed)
			(pads allowed)
			(copperpour not_allowed)
			(footprints allowed)
		)
		(placement
			(enabled no)
			(sheetname "")
		)
		(fill yes
			(thermal_gap 0.5)
			(thermal_bridge_width 0.5)
			(island_removal_mode 0)
		)
		(polygon
			(pts
				(arc
					(start 385.879848 -225.85426)
					(mid 385.249928 -225.85426)
					(end 385.879848 -225.85426)
				)
			)
		)
	)
	(zone
		(layers "B.Cu" "In13.Cu" "In15.Cu")
		(hatch none 0.5)
		(connect_pads
			(clearance 0)
		)
		(min_thickness 0.25)
		(keepout
			(tracks not_allowed)
			(vias allowed)
			(pads allowed)
			(copperpour not_allowed)
			(footprints allowed)
		)
		(placement
			(enabled no)
			(sheetname "")
		)
		(fill yes
			(thermal_gap 0.5)
			(thermal_bridge_width 0.5)
			(island_removal_mode 0)
		)
		(polygon
			(pts
				(arc
					(start 103.636064 -244.484398)
					(mid 103.006144 -244.484398)
					(end 103.636064 -244.484398)
				)
			)
		)
	)
	(zone
		(layers "B.Cu" "In13.Cu" "In15.Cu")
		(hatch none 0.5)
		(connect_pads
			(clearance 0)
		)
		(min_thickness 0.25)
		(keepout
			(tracks not_allowed)
			(vias allowed)
			(pads allowed)
			(copperpour not_allowed)
			(footprints allowed)
		)
		(placement
			(enabled no)
			(sheetname "")
		)
		(fill yes
			(thermal_gap 0.5)
			(thermal_bridge_width 0.5)
			(island_removal_mode 0)
		)
		(polygon
			(pts
				(arc
					(start 399.137124 -429.689768)
					(mid 398.362932 -429.689768)
					(end 399.137124 -429.689768)
				)
			)
		)
	)
	(zone
		(layers "B.Cu" "In13.Cu" "In15.Cu")
		(hatch none 0.5)
		(connect_pads
			(clearance 0)
		)
		(min_thickness 0.25)
		(keepout
			(tracks not_allowed)
			(vias allowed)
			(pads allowed)
			(copperpour not_allowed)
			(footprints allowed)
		)
		(placement
			(enabled no)
			(sheetname "")
		)
		(fill yes
			(thermal_gap 0.5)
			(thermal_bridge_width 0.5)
			(island_removal_mode 0)
		)
		(polygon
			(pts
				(arc
					(start 454.522078 -296.78503)
					(mid 453.854058 -296.78503)
					(end 454.522078 -296.78503)
				)
			)
		)
	)
	(zone
		(layers "B.Cu" "In13.Cu" "In15.Cu")
		(hatch none 0.5)
		(connect_pads
			(clearance 0)
		)
		(min_thickness 0.25)
		(keepout
			(tracks not_allowed)
			(vias allowed)
			(pads allowed)
			(copperpour not_allowed)
			(footprints allowed)
		)
		(placement
			(enabled no)
			(sheetname "")
		)
		(fill yes
			(thermal_gap 0.5)
			(thermal_bridge_width 0.5)
			(island_removal_mode 0)
		)
		(polygon
			(pts
				(arc
					(start 386.179822 -285.42615)
					(mid 385.549902 -285.42615)
					(end 386.179822 -285.42615)
				)
			)
		)
	)
	(zone
		(layers "B.Cu" "In13.Cu" "In15.Cu")
		(hatch none 0.5)
		(connect_pads
			(clearance 0)
		)
		(min_thickness 0.25)
		(keepout
			(tracks not_allowed)
			(vias allowed)
			(pads allowed)
			(copperpour not_allowed)
			(footprints allowed)
		)
		(placement
			(enabled no)
			(sheetname "")
		)
		(fill yes
			(thermal_gap 0.5)
			(thermal_bridge_width 0.5)
			(island_removal_mode 0)
		)
		(polygon
			(pts
				(arc
					(start 265.88212 -229.63505)
					(mid 265.2141 -229.63505)
					(end 265.88212 -229.63505)
				)
			)
		)
	)
	(zone
		(layers "B.Cu" "In13.Cu" "In15.Cu")
		(hatch none 0.5)
		(connect_pads
			(clearance 0)
		)
		(min_thickness 0.25)
		(keepout
			(tracks not_allowed)
			(vias allowed)
			(pads allowed)
			(copperpour not_allowed)
			(footprints allowed)
		)
		(placement
			(enabled no)
			(sheetname "")
		)
		(fill yes
			(thermal_gap 0.5)
			(thermal_bridge_width 0.5)
			(island_removal_mode 0)
		)
		(polygon
			(pts
				(arc
					(start 202.481942 -295.9354)
					(mid 201.813922 -295.9354)
					(end 202.481942 -295.9354)
				)
			)
		)
	)
	(zone
		(layers "B.Cu" "In13.Cu" "In15.Cu")
		(hatch none 0.5)
		(connect_pads
			(clearance 0)
		)
		(min_thickness 0.25)
		(keepout
			(tracks not_allowed)
			(vias allowed)
			(pads allowed)
			(copperpour not_allowed)
			(footprints allowed)
		)
		(placement
			(enabled no)
			(sheetname "")
		)
		(fill yes
			(thermal_gap 0.5)
			(thermal_bridge_width 0.5)
			(island_removal_mode 0)
		)
		(polygon
			(pts
				(arc
					(start 139.819634 -253.394464)
					(mid 139.189714 -253.394464)
					(end 139.819634 -253.394464)
				)
			)
		)
	)
	(zone
		(layers "B.Cu" "In13.Cu" "In15.Cu")
		(hatch none 0.5)
		(connect_pads
			(clearance 0)
		)
		(min_thickness 0.25)
		(keepout
			(tracks not_allowed)
			(vias allowed)
			(pads allowed)
			(copperpour not_allowed)
			(footprints allowed)
		)
		(placement
			(enabled no)
			(sheetname "")
		)
		(fill yes
			(thermal_gap 0.5)
			(thermal_bridge_width 0.5)
			(island_removal_mode 0)
		)
		(polygon
			(pts
				(arc
					(start 407.317956 -4.963414)
					(mid 406.649936 -4.963414)
					(end 407.317956 -4.963414)
				)
			)
		)
	)
	(zone
		(layers "B.Cu" "In13.Cu" "In15.Cu")
		(hatch none 0.5)
		(connect_pads
			(clearance 0)
		)
		(min_thickness 0.25)
		(keepout
			(tracks not_allowed)
			(vias allowed)
			(pads allowed)
			(copperpour not_allowed)
			(footprints allowed)
		)
		(placement
			(enabled no)
			(sheetname "")
		)
		(fill yes
			(thermal_gap 0.5)
			(thermal_bridge_width 0.5)
			(island_removal_mode 0)
		)
		(polygon
			(pts
				(arc
					(start 351.576132 -234.764072)
					(mid 350.946212 -234.764072)
					(end 351.576132 -234.764072)
				)
			)
		)
	)
	(zone
		(layers "B.Cu" "In13.Cu" "In15.Cu")
		(hatch none 0.5)
		(connect_pads
			(clearance 0)
		)
		(min_thickness 0.25)
		(keepout
			(tracks not_allowed)
			(vias allowed)
			(pads allowed)
			(copperpour not_allowed)
			(footprints allowed)
		)
		(placement
			(enabled no)
			(sheetname "")
		)
		(fill yes
			(thermal_gap 0.5)
			(thermal_bridge_width 0.5)
			(island_removal_mode 0)
		)
		(polygon
			(pts
				(arc
					(start 54.254654 -412.570168)
					(mid 53.586634 -412.570168)
					(end 54.254654 -412.570168)
				)
			)
		)
	)
	(zone
		(layers "B.Cu" "In13.Cu" "In15.Cu")
		(hatch none 0.5)
		(connect_pads
			(clearance 0)
		)
		(min_thickness 0.25)
		(keepout
			(tracks not_allowed)
			(vias allowed)
			(pads allowed)
			(copperpour not_allowed)
			(footprints allowed)
		)
		(placement
			(enabled no)
			(sheetname "")
		)
		(fill yes
			(thermal_gap 0.5)
			(thermal_bridge_width 0.5)
			(island_removal_mode 0)
		)
		(polygon
			(pts
				(arc
					(start 206.58201 -304.435256)
					(mid 205.91399 -304.435256)
					(end 206.58201 -304.435256)
				)
			)
		)
	)
	(zone
		(layers "B.Cu" "In13.Cu" "In15.Cu")
		(hatch none 0.5)
		(connect_pads
			(clearance 0)
		)
		(min_thickness 0.25)
		(keepout
			(tracks not_allowed)
			(vias allowed)
			(pads allowed)
			(copperpour not_allowed)
			(footprints allowed)
		)
		(placement
			(enabled no)
			(sheetname "")
		)
		(fill yes
			(thermal_gap 0.5)
			(thermal_bridge_width 0.5)
			(island_removal_mode 0)
		)
		(polygon
			(pts
				(arc
					(start 396.517876 -4.963414)
					(mid 395.849856 -4.963414)
					(end 396.517876 -4.963414)
				)
			)
		)
	)
	(zone
		(layers "B.Cu" "In13.Cu" "In15.Cu")
		(hatch none 0.5)
		(connect_pads
			(clearance 0)
		)
		(min_thickness 0.25)
		(keepout
			(tracks not_allowed)
			(vias allowed)
			(pads allowed)
			(copperpour not_allowed)
			(footprints allowed)
		)
		(placement
			(enabled no)
			(sheetname "")
		)
		(fill yes
			(thermal_gap 0.5)
			(thermal_bridge_width 0.5)
			(island_removal_mode 0)
		)
		(polygon
			(pts
				(arc
					(start 91.833954 -386.003292)
					(mid 91.204034 -386.003292)
					(end 91.833954 -386.003292)
				)
			)
		)
	)
	(zone
		(layers "B.Cu" "In13.Cu" "In15.Cu")
		(hatch none 0.5)
		(connect_pads
			(clearance 0)
		)
		(min_thickness 0.25)
		(keepout
			(tracks not_allowed)
			(vias allowed)
			(pads allowed)
			(copperpour not_allowed)
			(footprints allowed)
		)
		(placement
			(enabled no)
			(sheetname "")
		)
		(fill yes
			(thermal_gap 0.5)
			(thermal_bridge_width 0.5)
			(island_removal_mode 0)
		)
		(polygon
			(pts
				(arc
					(start 202.481942 -204.135228)
					(mid 201.813922 -204.135228)
					(end 202.481942 -204.135228)
				)
			)
		)
	)
	(zone
		(layers "B.Cu" "In13.Cu" "In15.Cu")
		(hatch none 0.5)
		(connect_pads
			(clearance 0)
		)
		(min_thickness 0.25)
		(keepout
			(tracks not_allowed)
			(vias allowed)
			(pads allowed)
			(copperpour not_allowed)
			(footprints allowed)
		)
		(placement
			(enabled no)
			(sheetname "")
		)
		(fill yes
			(thermal_gap 0.5)
			(thermal_bridge_width 0.5)
			(island_removal_mode 0)
		)
		(polygon
			(pts
				(arc
					(start 334.485996 -282.186126)
					(mid 333.856076 -282.186126)
					(end 334.485996 -282.186126)
				)
			)
		)
	)
	(zone
		(layers "B.Cu" "In13.Cu" "In15.Cu")
		(hatch none 0.5)
		(connect_pads
			(clearance 0)
		)
		(min_thickness 0.25)
		(keepout
			(tracks not_allowed)
			(vias allowed)
			(pads allowed)
			(copperpour not_allowed)
			(footprints allowed)
		)
		(placement
			(enabled no)
			(sheetname "")
		)
		(fill yes
			(thermal_gap 0.5)
			(thermal_bridge_width 0.5)
			(island_removal_mode 0)
		)
		(polygon
			(pts
				(arc
					(start 206.58201 -292.535356)
					(mid 205.91399 -292.535356)
					(end 206.58201 -292.535356)
				)
			)
		)
	)
	(zone
		(layers "B.Cu" "In13.Cu" "In15.Cu")
		(hatch none 0.5)
		(connect_pads
			(clearance 0)
		)
		(min_thickness 0.25)
		(keepout
			(tracks not_allowed)
			(vias allowed)
			(pads allowed)
			(copperpour not_allowed)
			(footprints allowed)
		)
		(placement
			(enabled no)
			(sheetname "")
		)
		(fill yes
			(thermal_gap 0.5)
			(thermal_bridge_width 0.5)
			(island_removal_mode 0)
		)
		(polygon
			(pts
				(arc
					(start 352.81616 -276.516084)
					(mid 352.18624 -276.516084)
					(end 352.81616 -276.516084)
				)
			)
		)
	)
	(zone
		(layers "B.Cu" "In13.Cu" "In15.Cu")
		(hatch none 0.5)
		(connect_pads
			(clearance 0)
		)
		(min_thickness 0.25)
		(keepout
			(tracks not_allowed)
			(vias allowed)
			(pads allowed)
			(copperpour not_allowed)
			(footprints allowed)
		)
		(placement
			(enabled no)
			(sheetname "")
		)
		(fill yes
			(thermal_gap 0.5)
			(thermal_bridge_width 0.5)
			(island_removal_mode 0)
		)
		(polygon
			(pts
				(arc
					(start 334.186022 -245.29415)
					(mid 333.556102 -245.29415)
					(end 334.186022 -245.29415)
				)
			)
		)
	)
	(zone
		(layers "B.Cu" "In13.Cu" "In15.Cu")
		(hatch none 0.5)
		(connect_pads
			(clearance 0)
		)
		(min_thickness 0.25)
		(keepout
			(tracks not_allowed)
			(vias allowed)
			(pads allowed)
			(copperpour not_allowed)
			(footprints allowed)
		)
		(placement
			(enabled no)
			(sheetname "")
		)
		(fill yes
			(thermal_gap 0.5)
			(thermal_bridge_width 0.5)
			(island_removal_mode 0)
		)
		(polygon
			(pts
				(arc
					(start 314.181236 -420.952168)
					(mid 313.513216 -420.952168)
					(end 314.181236 -420.952168)
				)
			)
		)
	)
	(zone
		(layers "B.Cu" "In13.Cu" "In15.Cu")
		(hatch none 0.5)
		(connect_pads
			(clearance 0)
		)
		(min_thickness 0.25)
		(keepout
			(tracks not_allowed)
			(vias allowed)
			(pads allowed)
			(copperpour not_allowed)
			(footprints allowed)
		)
		(placement
			(enabled no)
			(sheetname "")
		)
		(fill yes
			(thermal_gap 0.5)
			(thermal_bridge_width 0.5)
			(island_removal_mode 0)
		)
		(polygon
			(pts
				(arc
					(start 265.88212 -237.285022)
					(mid 265.2141 -237.285022)
					(end 265.88212 -237.285022)
				)
			)
		)
	)
	(zone
		(layers "B.Cu" "In13.Cu" "In15.Cu")
		(hatch none 0.5)
		(connect_pads
			(clearance 0)
		)
		(min_thickness 0.25)
		(keepout
			(tracks not_allowed)
			(vias allowed)
			(pads allowed)
			(copperpour not_allowed)
			(footprints allowed)
		)
		(placement
			(enabled no)
			(sheetname "")
		)
		(fill yes
			(thermal_gap 0.5)
			(thermal_bridge_width 0.5)
			(island_removal_mode 0)
		)
		(polygon
			(pts
				(arc
					(start 334.485996 -280.566114)
					(mid 333.856076 -280.566114)
					(end 334.485996 -280.566114)
				)
			)
		)
	)
	(zone
		(layers "B.Cu" "In13.Cu" "In15.Cu")
		(hatch none 0.5)
		(connect_pads
			(clearance 0)
		)
		(min_thickness 0.25)
		(keepout
			(tracks not_allowed)
			(vias allowed)
			(pads allowed)
			(copperpour not_allowed)
			(footprints allowed)
		)
		(placement
			(enabled no)
			(sheetname "")
		)
		(fill yes
			(thermal_gap 0.5)
			(thermal_bridge_width 0.5)
			(island_removal_mode 0)
		)
		(polygon
			(pts
				(arc
					(start 403.71776 -4.963414)
					(mid 403.04974 -4.963414)
					(end 403.71776 -4.963414)
				)
			)
		)
	)
	(zone
		(layers "B.Cu" "In13.Cu" "In15.Cu")
		(hatch none 0.5)
		(connect_pads
			(clearance 0)
		)
		(min_thickness 0.25)
		(keepout
			(tracks not_allowed)
			(vias allowed)
			(pads allowed)
			(copperpour not_allowed)
			(footprints allowed)
		)
		(placement
			(enabled no)
			(sheetname "")
		)
		(fill yes
			(thermal_gap 0.5)
			(thermal_bridge_width 0.5)
			(island_removal_mode 0)
		)
		(polygon
			(pts
				(arc
					(start 265.88212 -199.885046)
					(mid 265.2141 -199.885046)
					(end 265.88212 -199.885046)
				)
			)
		)
	)
	(zone
		(layers "B.Cu" "In13.Cu" "In15.Cu")
		(hatch none 0.5)
		(connect_pads
			(clearance 0)
		)
		(min_thickness 0.25)
		(keepout
			(tracks not_allowed)
			(vias allowed)
			(pads allowed)
			(copperpour not_allowed)
			(footprints allowed)
		)
		(placement
			(enabled no)
			(sheetname "")
		)
		(fill yes
			(thermal_gap 0.5)
			(thermal_bridge_width 0.5)
			(island_removal_mode 0)
		)
		(polygon
			(pts
				(arc
					(start 386.179822 -282.186126)
					(mid 385.549902 -282.186126)
					(end 386.179822 -282.186126)
				)
			)
		)
	)
	(zone
		(layers "B.Cu" "In13.Cu" "In15.Cu")
		(hatch none 0.5)
		(connect_pads
			(clearance 0)
		)
		(min_thickness 0.25)
		(keepout
			(tracks not_allowed)
			(vias allowed)
			(pads allowed)
			(copperpour not_allowed)
			(footprints allowed)
		)
		(placement
			(enabled no)
			(sheetname "")
		)
		(fill yes
			(thermal_gap 0.5)
			(thermal_bridge_width 0.5)
			(island_removal_mode 0)
		)
		(polygon
			(pts
				(arc
					(start 450.42201 -265.335004)
					(mid 449.75399 -265.335004)
					(end 450.42201 -265.335004)
				)
			)
		)
	)
	(zone
		(layers "B.Cu" "In13.Cu" "In15.Cu")
		(hatch none 0.5)
		(connect_pads
			(clearance 0)
		)
		(min_thickness 0.25)
		(keepout
			(tracks not_allowed)
			(vias allowed)
			(pads allowed)
			(copperpour not_allowed)
			(footprints allowed)
		)
		(placement
			(enabled no)
			(sheetname "")
		)
		(fill yes
			(thermal_gap 0.5)
			(thermal_bridge_width 0.5)
			(island_removal_mode 0)
		)
		(polygon
			(pts
				(arc
					(start 454.522078 -208.385156)
					(mid 453.854058 -208.385156)
					(end 454.522078 -208.385156)
				)
			)
		)
	)
	(zone
		(layers "B.Cu" "In13.Cu" "In15.Cu")
		(hatch none 0.5)
		(connect_pads
			(clearance 0)
		)
		(min_thickness 0.25)
		(keepout
			(tracks not_allowed)
			(vias allowed)
			(pads allowed)
			(copperpour not_allowed)
			(footprints allowed)
		)
		(placement
			(enabled no)
			(sheetname "")
		)
		(fill yes
			(thermal_gap 0.5)
			(thermal_bridge_width 0.5)
			(island_removal_mode 0)
		)
		(polygon
			(pts
				(arc
					(start 265.88212 -276.38502)
					(mid 265.2141 -276.38502)
					(end 265.88212 -276.38502)
				)
			)
		)
	)
	(zone
		(layers "B.Cu" "In13.Cu" "In15.Cu")
		(hatch none 0.5)
		(connect_pads
			(clearance 0)
		)
		(min_thickness 0.25)
		(keepout
			(tracks not_allowed)
			(vias allowed)
			(pads allowed)
			(copperpour not_allowed)
			(footprints allowed)
		)
		(placement
			(enabled no)
			(sheetname "")
		)
		(fill yes
			(thermal_gap 0.5)
			(thermal_bridge_width 0.5)
			(island_removal_mode 0)
		)
		(polygon
			(pts
				(arc
					(start 17.942052 -312.085228)
					(mid 17.274032 -312.085228)
					(end 17.942052 -312.085228)
				)
			)
		)
	)
	(zone
		(layers "B.Cu" "In13.Cu" "In15.Cu")
		(hatch none 0.5)
		(connect_pads
			(clearance 0)
		)
		(min_thickness 0.25)
		(keepout
			(tracks not_allowed)
			(vias allowed)
			(pads allowed)
			(copperpour not_allowed)
			(footprints allowed)
		)
		(placement
			(enabled no)
			(sheetname "")
		)
		(fill yes
			(thermal_gap 0.5)
			(thermal_bridge_width 0.5)
			(island_removal_mode 0)
		)
		(polygon
			(pts
				(arc
					(start 22.04212 -242.385342)
					(mid 21.3741 -242.385342)
					(end 22.04212 -242.385342)
				)
			)
		)
	)
	(zone
		(layers "B.Cu" "In13.Cu" "In15.Cu")
		(hatch none 0.5)
		(connect_pads
			(clearance 0)
		)
		(min_thickness 0.25)
		(keepout
			(tracks not_allowed)
			(vias allowed)
			(pads allowed)
			(copperpour not_allowed)
			(footprints allowed)
		)
		(placement
			(enabled no)
			(sheetname "")
		)
		(fill yes
			(thermal_gap 0.5)
			(thermal_bridge_width 0.5)
			(island_removal_mode 0)
		)
		(polygon
			(pts
				(arc
					(start 85.135974 -287.856422)
					(mid 84.506054 -287.856422)
					(end 85.135974 -287.856422)
				)
			)
		)
	)
	(zone
		(layers "B.Cu" "In13.Cu" "In15.Cu")
		(hatch none 0.5)
		(connect_pads
			(clearance 0)
		)
		(min_thickness 0.25)
		(keepout
			(tracks not_allowed)
			(vias allowed)
			(pads allowed)
			(copperpour not_allowed)
			(footprints allowed)
		)
		(placement
			(enabled no)
			(sheetname "")
		)
		(fill yes
			(thermal_gap 0.5)
			(thermal_bridge_width 0.5)
			(island_removal_mode 0)
		)
		(polygon
			(pts
				(arc
					(start 454.522078 -287.435036)
					(mid 453.854058 -287.435036)
					(end 454.522078 -287.435036)
				)
			)
		)
	)
	(zone
		(layers "B.Cu" "In13.Cu" "In15.Cu")
		(hatch none 0.5)
		(connect_pads
			(clearance 0)
		)
		(min_thickness 0.25)
		(keepout
			(tracks not_allowed)
			(vias allowed)
			(pads allowed)
			(copperpour not_allowed)
			(footprints allowed)
		)
		(placement
			(enabled no)
			(sheetname "")
		)
		(fill yes
			(thermal_gap 0.5)
			(thermal_bridge_width 0.5)
			(island_removal_mode 0)
		)
		(polygon
			(pts
				(arc
					(start 22.04212 -262.785352)
					(mid 21.3741 -262.785352)
					(end 22.04212 -262.785352)
				)
			)
		)
	)
	(zone
		(layers "B.Cu" "In13.Cu" "In15.Cu")
		(hatch none 0.5)
		(connect_pads
			(clearance 0)
		)
		(min_thickness 0.25)
		(keepout
			(tracks not_allowed)
			(vias allowed)
			(pads allowed)
			(copperpour not_allowed)
			(footprints allowed)
		)
		(placement
			(enabled no)
			(sheetname "")
		)
		(fill yes
			(thermal_gap 0.5)
			(thermal_bridge_width 0.5)
			(island_removal_mode 0)
		)
		(polygon
			(pts
				(arc
					(start 336.63382 -393.69238)
					(mid 336.0039 -393.69238)
					(end 336.63382 -393.69238)
				)
			)
		)
	)
	(zone
		(layers "B.Cu" "In13.Cu" "In15.Cu")
		(hatch none 0.5)
		(connect_pads
			(clearance 0)
		)
		(min_thickness 0.25)
		(keepout
			(tracks not_allowed)
			(vias allowed)
			(pads allowed)
			(copperpour not_allowed)
			(footprints allowed)
		)
		(placement
			(enabled no)
			(sheetname "")
		)
		(fill yes
			(thermal_gap 0.5)
			(thermal_bridge_width 0.5)
			(island_removal_mode 0)
		)
		(polygon
			(pts
				(arc
					(start 269.982188 -234.735116)
					(mid 269.314168 -234.735116)
					(end 269.982188 -234.735116)
				)
			)
		)
	)
	(zone
		(layers "B.Cu" "In13.Cu" "In15.Cu")
		(hatch none 0.5)
		(connect_pads
			(clearance 0)
		)
		(min_thickness 0.25)
		(keepout
			(tracks not_allowed)
			(vias allowed)
			(pads allowed)
			(copperpour not_allowed)
			(footprints allowed)
		)
		(placement
			(enabled no)
			(sheetname "")
		)
		(fill yes
			(thermal_gap 0.5)
			(thermal_bridge_width 0.5)
			(island_removal_mode 0)
		)
		(polygon
			(pts
				(arc
					(start 139.819634 -238.814356)
					(mid 139.189714 -238.814356)
					(end 139.819634 -238.814356)
				)
			)
		)
	)
	(zone
		(layers "B.Cu" "In13.Cu" "In15.Cu")
		(hatch none 0.5)
		(connect_pads
			(clearance 0)
		)
		(min_thickness 0.25)
		(keepout
			(tracks not_allowed)
			(vias allowed)
			(pads allowed)
			(copperpour not_allowed)
			(footprints allowed)
		)
		(placement
			(enabled no)
			(sheetname "")
		)
		(fill yes
			(thermal_gap 0.5)
			(thermal_bridge_width 0.5)
			(island_removal_mode 0)
		)
		(polygon
			(pts
				(arc
					(start 115.679728 -275.706332)
					(mid 115.049808 -275.706332)
					(end 115.679728 -275.706332)
				)
			)
		)
	)
	(zone
		(layers "B.Cu" "In13.Cu" "In15.Cu")
		(hatch none 0.5)
		(connect_pads
			(clearance 0)
		)
		(min_thickness 0.25)
		(keepout
			(tracks not_allowed)
			(vias allowed)
			(pads allowed)
			(copperpour not_allowed)
			(footprints allowed)
		)
		(placement
			(enabled no)
			(sheetname "")
		)
		(fill yes
			(thermal_gap 0.5)
			(thermal_bridge_width 0.5)
			(island_removal_mode 0)
		)
		(polygon
			(pts
				(arc
					(start 310.254396 -420.952168)
					(mid 309.586376 -420.952168)
					(end 310.254396 -420.952168)
				)
			)
		)
	)
	(zone
		(layers "B.Cu" "In13.Cu" "In15.Cu")
		(hatch none 0.5)
		(connect_pads
			(clearance 0)
		)
		(min_thickness 0.25)
		(keepout
			(tracks not_allowed)
			(vias allowed)
			(pads allowed)
			(copperpour not_allowed)
			(footprints allowed)
		)
		(placement
			(enabled no)
			(sheetname "")
		)
		(fill yes
			(thermal_gap 0.5)
			(thermal_bridge_width 0.5)
			(island_removal_mode 0)
		)
		(polygon
			(pts
				(arc
					(start 454.522078 -262.785098)
					(mid 453.854058 -262.785098)
					(end 454.522078 -262.785098)
				)
			)
		)
	)
	(zone
		(layers "B.Cu" "In13.Cu" "In15.Cu")
		(hatch none 0.5)
		(connect_pads
			(clearance 0)
		)
		(min_thickness 0.25)
		(keepout
			(tracks not_allowed)
			(vias allowed)
			(pads allowed)
			(copperpour not_allowed)
			(footprints allowed)
		)
		(placement
			(enabled no)
			(sheetname "")
		)
		(fill yes
			(thermal_gap 0.5)
			(thermal_bridge_width 0.5)
			(island_removal_mode 0)
		)
		(polygon
			(pts
				(arc
					(start 55.322724 -17.613122)
					(mid 54.654704 -17.613122)
					(end 55.322724 -17.613122)
				)
			)
		)
	)
	(zone
		(layers "B.Cu" "In13.Cu" "In15.Cu")
		(hatch none 0.5)
		(connect_pads
			(clearance 0)
		)
		(min_thickness 0.25)
		(keepout
			(tracks not_allowed)
			(vias allowed)
			(pads allowed)
			(copperpour not_allowed)
			(footprints allowed)
		)
		(placement
			(enabled no)
			(sheetname "")
		)
		(fill yes
			(thermal_gap 0.5)
			(thermal_bridge_width 0.5)
			(island_removal_mode 0)
		)
		(polygon
			(pts
				(arc
					(start 327.036684 -430.889918)
					(mid 326.262492 -430.889918)
					(end 327.036684 -430.889918)
				)
			)
		)
	)
	(zone
		(layers "B.Cu" "In13.Cu" "In15.Cu")
		(hatch none 0.5)
		(connect_pads
			(clearance 0)
		)
		(min_thickness 0.25)
		(keepout
			(tracks not_allowed)
			(vias allowed)
			(pads allowed)
			(copperpour not_allowed)
			(footprints allowed)
		)
		(placement
			(enabled no)
			(sheetname "")
		)
		(fill yes
			(thermal_gap 0.5)
			(thermal_bridge_width 0.5)
			(island_removal_mode 0)
		)
		(polygon
			(pts
				(arc
					(start 454.522078 -269.585186)
					(mid 453.854058 -269.585186)
					(end 454.522078 -269.585186)
				)
			)
		)
	)
	(zone
		(layers "B.Cu" "In13.Cu" "In15.Cu")
		(hatch none 0.5)
		(connect_pads
			(clearance 0)
		)
		(min_thickness 0.25)
		(keepout
			(tracks not_allowed)
			(vias allowed)
			(pads allowed)
			(copperpour not_allowed)
			(footprints allowed)
		)
		(placement
			(enabled no)
			(sheetname "")
		)
		(fill yes
			(thermal_gap 0.5)
			(thermal_bridge_width 0.5)
			(island_removal_mode 0)
		)
		(polygon
			(pts
				(arc
					(start 84.666074 -264.366248)
					(mid 84.036154 -264.366248)
					(end 84.666074 -264.366248)
				)
			)
		)
	)
	(zone
		(layers "B.Cu" "In13.Cu" "In15.Cu")
		(hatch none 0.5)
		(connect_pads
			(clearance 0)
		)
		(min_thickness 0.25)
		(keepout
			(tracks not_allowed)
			(vias allowed)
			(pads allowed)
			(copperpour not_allowed)
			(footprints allowed)
		)
		(placement
			(enabled no)
			(sheetname "")
		)
		(fill yes
			(thermal_gap 0.5)
			(thermal_bridge_width 0.5)
			(island_removal_mode 0)
		)
		(polygon
			(pts
				(arc
					(start 341.433658 -393.69238)
					(mid 340.803738 -393.69238)
					(end 341.433658 -393.69238)
				)
			)
		)
	)
	(zone
		(layers "B.Cu" "In13.Cu" "In15.Cu")
		(hatch none 0.5)
		(connect_pads
			(clearance 0)
		)
		(min_thickness 0.25)
		(keepout
			(tracks not_allowed)
			(vias allowed)
			(pads allowed)
			(copperpour not_allowed)
			(footprints allowed)
		)
		(placement
			(enabled no)
			(sheetname "")
		)
		(fill yes
			(thermal_gap 0.5)
			(thermal_bridge_width 0.5)
			(island_removal_mode 0)
		)
		(polygon
			(pts
				(arc
					(start 265.88212 -289.985196)
					(mid 265.2141 -289.985196)
					(end 265.88212 -289.985196)
				)
			)
		)
	)
	(zone
		(layers "B.Cu" "In13.Cu" "In15.Cu")
		(hatch none 0.5)
		(connect_pads
			(clearance 0)
		)
		(min_thickness 0.25)
		(keepout
			(tracks not_allowed)
			(vias allowed)
			(pads allowed)
			(copperpour not_allowed)
			(footprints allowed)
		)
		(placement
			(enabled no)
			(sheetname "")
		)
		(fill yes
			(thermal_gap 0.5)
			(thermal_bridge_width 0.5)
			(island_removal_mode 0)
		)
		(polygon
			(pts
				(arc
					(start 104.876092 -276.516338)
					(mid 104.246172 -276.516338)
					(end 104.876092 -276.516338)
				)
			)
		)
	)
	(zone
		(layers "B.Cu" "In13.Cu" "In15.Cu")
		(hatch none 0.5)
		(connect_pads
			(clearance 0)
		)
		(min_thickness 0.25)
		(keepout
			(tracks not_allowed)
			(vias allowed)
			(pads allowed)
			(copperpour not_allowed)
			(footprints allowed)
		)
		(placement
			(enabled no)
			(sheetname "")
		)
		(fill yes
			(thermal_gap 0.5)
			(thermal_bridge_width 0.5)
			(island_removal_mode 0)
		)
		(polygon
			(pts
				(arc
					(start 122.429778 -234.764326)
					(mid 121.799858 -234.764326)
					(end 122.429778 -234.764326)
				)
			)
		)
	)
	(zone
		(layers "B.Cu" "In13.Cu" "In15.Cu")
		(hatch none 0.5)
		(connect_pads
			(clearance 0)
		)
		(min_thickness 0.25)
		(keepout
			(tracks not_allowed)
			(vias allowed)
			(pads allowed)
			(copperpour not_allowed)
			(footprints allowed)
		)
		(placement
			(enabled no)
			(sheetname "")
		)
		(fill yes
			(thermal_gap 0.5)
			(thermal_bridge_width 0.5)
			(island_removal_mode 0)
		)
		(polygon
			(pts
				(arc
					(start 84.666074 -291.906198)
					(mid 84.036154 -291.906198)
					(end 84.666074 -291.906198)
				)
			)
		)
	)
	(zone
		(layers "B.Cu" "In13.Cu" "In15.Cu")
		(hatch none 0.5)
		(connect_pads
			(clearance 0)
		)
		(min_thickness 0.25)
		(keepout
			(tracks not_allowed)
			(vias allowed)
			(pads allowed)
			(copperpour not_allowed)
			(footprints allowed)
		)
		(placement
			(enabled no)
			(sheetname "")
		)
		(fill yes
			(thermal_gap 0.5)
			(thermal_bridge_width 0.5)
			(island_removal_mode 0)
		)
		(polygon
			(pts
				(arc
					(start 85.433916 -385.31038)
					(mid 84.803996 -385.31038)
					(end 85.433916 -385.31038)
				)
			)
		)
	)
	(zone
		(layers "B.Cu" "In13.Cu" "In15.Cu")
		(hatch none 0.5)
		(connect_pads
			(clearance 0)
		)
		(min_thickness 0.25)
		(keepout
			(tracks not_allowed)
			(vias allowed)
			(pads allowed)
			(copperpour not_allowed)
			(footprints allowed)
		)
		(placement
			(enabled no)
			(sheetname "")
		)
		(fill yes
			(thermal_gap 0.5)
			(thermal_bridge_width 0.5)
			(island_removal_mode 0)
		)
		(polygon
			(pts
				(arc
					(start 73.036938 -431.889916)
					(mid 72.262746 -431.889916)
					(end 73.036938 -431.889916)
				)
			)
		)
	)
	(zone
		(layers "B.Cu" "In13.Cu" "In15.Cu")
		(hatch none 0.5)
		(connect_pads
			(clearance 0)
		)
		(min_thickness 0.25)
		(keepout
			(tracks not_allowed)
			(vias allowed)
			(pads allowed)
			(copperpour not_allowed)
			(footprints allowed)
		)
		(placement
			(enabled no)
			(sheetname "")
		)
		(fill yes
			(thermal_gap 0.5)
			(thermal_bridge_width 0.5)
			(island_removal_mode 0)
		)
		(polygon
			(pts
				(arc
					(start 153.137108 -430.689766)
					(mid 152.362916 -430.689766)
					(end 153.137108 -430.689766)
				)
			)
		)
	)
	(zone
		(layers "B.Cu" "In13.Cu" "In15.Cu")
		(hatch none 0.5)
		(connect_pads
			(clearance 0)
		)
		(min_thickness 0.25)
		(keepout
			(tracks not_allowed)
			(vias allowed)
			(pads allowed)
			(copperpour not_allowed)
			(footprints allowed)
		)
		(placement
			(enabled no)
			(sheetname "")
		)
		(fill yes
			(thermal_gap 0.5)
			(thermal_bridge_width 0.5)
			(island_removal_mode 0)
		)
		(polygon
			(pts
				(arc
					(start 334.485996 -275.706078)
					(mid 333.856076 -275.706078)
					(end 334.485996 -275.706078)
				)
			)
		)
	)
	(zone
		(layers "B.Cu" "In13.Cu" "In15.Cu")
		(hatch none 0.5)
		(connect_pads
			(clearance 0)
		)
		(min_thickness 0.25)
		(keepout
			(tracks not_allowed)
			(vias allowed)
			(pads allowed)
			(copperpour not_allowed)
			(footprints allowed)
		)
		(placement
			(enabled no)
			(sheetname "")
		)
		(fill yes
			(thermal_gap 0.5)
			(thermal_bridge_width 0.5)
			(island_removal_mode 0)
		)
		(polygon
			(pts
				(arc
					(start 334.485996 -287.045908)
					(mid 333.856076 -287.045908)
					(end 334.485996 -287.045908)
				)
			)
		)
	)
	(zone
		(layers "B.Cu" "In13.Cu" "In15.Cu")
		(hatch none 0.5)
		(connect_pads
			(clearance 0)
		)
		(min_thickness 0.25)
		(keepout
			(tracks not_allowed)
			(vias allowed)
			(pads allowed)
			(copperpour not_allowed)
			(footprints allowed)
		)
		(placement
			(enabled no)
			(sheetname "")
		)
		(fill yes
			(thermal_gap 0.5)
			(thermal_bridge_width 0.5)
			(island_removal_mode 0)
		)
		(polygon
			(pts
				(arc
					(start 349.995998 -276.516084)
					(mid 349.366078 -276.516084)
					(end 349.995998 -276.516084)
				)
			)
		)
	)
	(zone
		(layers "B.Cu" "In13.Cu" "In15.Cu")
		(hatch none 0.5)
		(connect_pads
			(clearance 0)
		)
		(min_thickness 0.25)
		(keepout
			(tracks not_allowed)
			(vias allowed)
			(pads allowed)
			(copperpour not_allowed)
			(footprints allowed)
		)
		(placement
			(enabled no)
			(sheetname "")
		)
		(fill yes
			(thermal_gap 0.5)
			(thermal_bridge_width 0.5)
			(island_removal_mode 0)
		)
		(polygon
			(pts
				(arc
					(start 386.649722 -281.37612)
					(mid 386.019802 -281.37612)
					(end 386.649722 -281.37612)
				)
			)
		)
	)
	(zone
		(layers "B.Cu" "In13.Cu" "In15.Cu")
		(hatch none 0.5)
		(connect_pads
			(clearance 0)
		)
		(min_thickness 0.25)
		(keepout
			(tracks not_allowed)
			(vias allowed)
			(pads allowed)
			(copperpour not_allowed)
			(footprints allowed)
		)
		(placement
			(enabled no)
			(sheetname "")
		)
		(fill yes
			(thermal_gap 0.5)
			(thermal_bridge_width 0.5)
			(island_removal_mode 0)
		)
		(polygon
			(pts
				(arc
					(start 265.88212 -277.235158)
					(mid 265.2141 -277.235158)
					(end 265.88212 -277.235158)
				)
			)
		)
	)
	(zone
		(layers "B.Cu" "In13.Cu" "In15.Cu")
		(hatch none 0.5)
		(connect_pads
			(clearance 0)
		)
		(min_thickness 0.25)
		(keepout
			(tracks not_allowed)
			(vias allowed)
			(pads allowed)
			(copperpour not_allowed)
			(footprints allowed)
		)
		(placement
			(enabled no)
			(sheetname "")
		)
		(fill yes
			(thermal_gap 0.5)
			(thermal_bridge_width 0.5)
			(island_removal_mode 0)
		)
		(polygon
			(pts
				(arc
					(start 206.58201 -247.485408)
					(mid 205.91399 -247.485408)
					(end 206.58201 -247.485408)
				)
			)
		)
	)
	(zone
		(layers "B.Cu" "In13.Cu" "In15.Cu")
		(hatch none 0.5)
		(connect_pads
			(clearance 0)
		)
		(min_thickness 0.25)
		(keepout
			(tracks not_allowed)
			(vias allowed)
			(pads allowed)
			(copperpour not_allowed)
			(footprints allowed)
		)
		(placement
			(enabled no)
			(sheetname "")
		)
		(fill yes
			(thermal_gap 0.5)
			(thermal_bridge_width 0.5)
			(island_removal_mode 0)
		)
		(polygon
			(pts
				(arc
					(start 137.93978 -248.534428)
					(mid 137.30986 -248.534428)
					(end 137.93978 -248.534428)
				)
			)
		)
	)
	(zone
		(layers "B.Cu" "In13.Cu" "In15.Cu")
		(hatch none 0.5)
		(connect_pads
			(clearance 0)
		)
		(min_thickness 0.25)
		(keepout
			(tracks not_allowed)
			(vias allowed)
			(pads allowed)
			(copperpour not_allowed)
			(footprints allowed)
		)
		(placement
			(enabled no)
			(sheetname "")
		)
		(fill yes
			(thermal_gap 0.5)
			(thermal_bridge_width 0.5)
			(island_removal_mode 0)
		)
		(polygon
			(pts
				(arc
					(start 17.942052 -209.235294)
					(mid 17.274032 -209.235294)
					(end 17.942052 -209.235294)
				)
			)
		)
	)
	(zone
		(layers "B.Cu" "In13.Cu" "In15.Cu")
		(hatch none 0.5)
		(connect_pads
			(clearance 0)
		)
		(min_thickness 0.25)
		(keepout
			(tracks not_allowed)
			(vias allowed)
			(pads allowed)
			(copperpour not_allowed)
			(footprints allowed)
		)
		(placement
			(enabled no)
			(sheetname "")
		)
		(fill yes
			(thermal_gap 0.5)
			(thermal_bridge_width 0.5)
			(island_removal_mode 0)
		)
		(polygon
			(pts
				(arc
					(start 139.649708 -287.856422)
					(mid 139.019788 -287.856422)
					(end 139.649708 -287.856422)
				)
			)
		)
	)
	(zone
		(layers "B.Cu" "In13.Cu" "In15.Cu")
		(hatch none 0.5)
		(connect_pads
			(clearance 0)
		)
		(min_thickness 0.25)
		(keepout
			(tracks not_allowed)
			(vias allowed)
			(pads allowed)
			(copperpour not_allowed)
			(footprints allowed)
		)
		(placement
			(enabled no)
			(sheetname "")
		)
		(fill yes
			(thermal_gap 0.5)
			(thermal_bridge_width 0.5)
			(island_removal_mode 0)
		)
		(polygon
			(pts
				(arc
					(start 61.036962 -431.889916)
					(mid 60.26277 -431.889916)
					(end 61.036962 -431.889916)
				)
			)
		)
	)
	(zone
		(layers "B.Cu" "In13.Cu" "In15.Cu")
		(hatch none 0.5)
		(connect_pads
			(clearance 0)
		)
		(min_thickness 0.25)
		(keepout
			(tracks not_allowed)
			(vias allowed)
			(pads allowed)
			(copperpour not_allowed)
			(footprints allowed)
		)
		(placement
			(enabled no)
			(sheetname "")
		)
		(fill yes
			(thermal_gap 0.5)
			(thermal_bridge_width 0.5)
			(island_removal_mode 0)
		)
		(polygon
			(pts
				(arc
					(start 22.04212 -309.535322)
					(mid 21.3741 -309.535322)
					(end 22.04212 -309.535322)
				)
			)
		)
	)
	(zone
		(layers "B.Cu" "In13.Cu" "In15.Cu")
		(hatch none 0.5)
		(connect_pads
			(clearance 0)
		)
		(min_thickness 0.25)
		(keepout
			(tracks not_allowed)
			(vias allowed)
			(pads allowed)
			(copperpour not_allowed)
			(footprints allowed)
		)
		(placement
			(enabled no)
			(sheetname "")
		)
		(fill yes
			(thermal_gap 0.5)
			(thermal_bridge_width 0.5)
			(island_removal_mode 0)
		)
		(polygon
			(pts
				(arc
					(start 22.04212 -204.985366)
					(mid 21.3741 -204.985366)
					(end 22.04212 -204.985366)
				)
			)
		)
	)
	(zone
		(layers "B.Cu" "In13.Cu" "In15.Cu")
		(hatch none 0.5)
		(connect_pads
			(clearance 0)
		)
		(min_thickness 0.25)
		(keepout
			(tracks not_allowed)
			(vias allowed)
			(pads allowed)
			(copperpour not_allowed)
			(footprints allowed)
		)
		(placement
			(enabled no)
			(sheetname "")
		)
		(fill yes
			(thermal_gap 0.5)
			(thermal_bridge_width 0.5)
			(island_removal_mode 0)
		)
		(polygon
			(pts
				(arc
					(start 21.455888 -17.61236)
					(mid 20.787868 -17.61236)
					(end 21.455888 -17.61236)
				)
			)
		)
	)
	(zone
		(layers "B.Cu" "In13.Cu" "In15.Cu")
		(hatch none 0.5)
		(connect_pads
			(clearance 0)
		)
		(min_thickness 0.25)
		(keepout
			(tracks not_allowed)
			(vias allowed)
			(pads allowed)
			(copperpour not_allowed)
			(footprints allowed)
		)
		(placement
			(enabled no)
			(sheetname "")
		)
		(fill yes
			(thermal_gap 0.5)
			(thermal_bridge_width 0.5)
			(island_removal_mode 0)
		)
		(polygon
			(pts
				(arc
					(start 17.942052 -233.885232)
					(mid 17.274032 -233.885232)
					(end 17.942052 -233.885232)
				)
			)
		)
	)
	(zone
		(layers "B.Cu" "In13.Cu" "In15.Cu")
		(hatch none 0.5)
		(connect_pads
			(clearance 0)
		)
		(min_thickness 0.25)
		(keepout
			(tracks not_allowed)
			(vias allowed)
			(pads allowed)
			(copperpour not_allowed)
			(footprints allowed)
		)
		(placement
			(enabled no)
			(sheetname "")
		)
		(fill yes
			(thermal_gap 0.5)
			(thermal_bridge_width 0.5)
			(island_removal_mode 0)
		)
		(polygon
			(pts
				(arc
					(start 364.86465 -390.75106)
					(mid 364.19663 -390.75106)
					(end 364.86465 -390.75106)
				)
			)
		)
	)
	(zone
		(layers "B.Cu" "In13.Cu" "In15.Cu")
		(hatch none 0.5)
		(connect_pads
			(clearance 0)
		)
		(min_thickness 0.25)
		(keepout
			(tracks not_allowed)
			(vias allowed)
			(pads allowed)
			(copperpour not_allowed)
			(footprints allowed)
		)
		(placement
			(enabled no)
			(sheetname "")
		)
		(fill yes
			(thermal_gap 0.5)
			(thermal_bridge_width 0.5)
			(island_removal_mode 0)
		)
		(polygon
			(pts
				(arc
					(start 323.370956 -420.952168)
					(mid 322.702936 -420.952168)
					(end 323.370956 -420.952168)
				)
			)
		)
	)
	(zone
		(layers "B.Cu" "In13.Cu" "In15.Cu")
		(hatch none 0.5)
		(connect_pads
			(clearance 0)
		)
		(min_thickness 0.25)
		(keepout
			(tracks not_allowed)
			(vias allowed)
			(pads allowed)
			(copperpour not_allowed)
			(footprints allowed)
		)
		(placement
			(enabled no)
			(sheetname "")
		)
		(fill yes
			(thermal_gap 0.5)
			(thermal_bridge_width 0.5)
			(island_removal_mode 0)
		)
		(polygon
			(pts
				(arc
					(start 137.93978 -230.71455)
					(mid 137.30986 -230.71455)
					(end 137.93978 -230.71455)
				)
			)
		)
	)
	(zone
		(layers "B.Cu" "In13.Cu" "In15.Cu")
		(hatch none 0.5)
		(connect_pads
			(clearance 0)
		)
		(min_thickness 0.25)
		(keepout
			(tracks not_allowed)
			(vias allowed)
			(pads allowed)
			(copperpour not_allowed)
			(footprints allowed)
		)
		(placement
			(enabled no)
			(sheetname "")
		)
		(fill yes
			(thermal_gap 0.5)
			(thermal_bridge_width 0.5)
			(island_removal_mode 0)
		)
		(polygon
			(pts
				(arc
					(start 85.776054 -241.244374)
					(mid 85.146134 -241.244374)
					(end 85.776054 -241.244374)
				)
			)
		)
	)
	(zone
		(layers "B.Cu" "In13.Cu" "In15.Cu")
		(hatch none 0.5)
		(connect_pads
			(clearance 0)
		)
		(min_thickness 0.25)
		(keepout
			(tracks not_allowed)
			(vias allowed)
			(pads allowed)
			(copperpour not_allowed)
			(footprints allowed)
		)
		(placement
			(enabled no)
			(sheetname "")
		)
		(fill yes
			(thermal_gap 0.5)
			(thermal_bridge_width 0.5)
			(island_removal_mode 0)
		)
		(polygon
			(pts
				(arc
					(start 59.036966 -429.689768)
					(mid 58.262774 -429.689768)
					(end 59.036966 -429.689768)
				)
			)
		)
	)
	(zone
		(layers "B.Cu" "In13.Cu" "In15.Cu")
		(hatch none 0.5)
		(connect_pads
			(clearance 0)
		)
		(min_thickness 0.25)
		(keepout
			(tracks not_allowed)
			(vias allowed)
			(pads allowed)
			(copperpour not_allowed)
			(footprints allowed)
		)
		(placement
			(enabled no)
			(sheetname "")
		)
		(fill yes
			(thermal_gap 0.5)
			(thermal_bridge_width 0.5)
			(island_removal_mode 0)
		)
		(polygon
			(pts
				(arc
					(start 347.433646 -393.69238)
					(mid 346.803726 -393.69238)
					(end 347.433646 -393.69238)
				)
			)
		)
	)
	(zone
		(layers "B.Cu" "In13.Cu" "In15.Cu")
		(hatch none 0.5)
		(connect_pads
			(clearance 0)
		)
		(min_thickness 0.25)
		(keepout
			(tracks not_allowed)
			(vias allowed)
			(pads allowed)
			(copperpour not_allowed)
			(footprints allowed)
		)
		(placement
			(enabled no)
			(sheetname "")
		)
		(fill yes
			(thermal_gap 0.5)
			(thermal_bridge_width 0.5)
			(island_removal_mode 0)
		)
		(polygon
			(pts
				(arc
					(start 362.379768 -245.29415)
					(mid 361.749848 -245.29415)
					(end 362.379768 -245.29415)
				)
			)
		)
	)
	(zone
		(layers "B.Cu" "In13.Cu" "In15.Cu")
		(hatch none 0.5)
		(connect_pads
			(clearance 0)
		)
		(min_thickness 0.25)
		(keepout
			(tracks not_allowed)
			(vias allowed)
			(pads allowed)
			(copperpour not_allowed)
			(footprints allowed)
		)
		(placement
			(enabled no)
			(sheetname "")
		)
		(fill yes
			(thermal_gap 0.5)
			(thermal_bridge_width 0.5)
			(island_removal_mode 0)
		)
		(polygon
			(pts
				(arc
					(start 386.870702 -379.88113)
					(mid 386.202682 -379.88113)
					(end 386.870702 -379.88113)
				)
			)
		)
	)
	(zone
		(layers "B.Cu" "In13.Cu" "In15.Cu")
		(hatch none 0.5)
		(connect_pads
			(clearance 0)
		)
		(min_thickness 0.25)
		(keepout
			(tracks not_allowed)
			(vias allowed)
			(pads allowed)
			(copperpour not_allowed)
			(footprints allowed)
		)
		(placement
			(enabled no)
			(sheetname "")
		)
		(fill yes
			(thermal_gap 0.5)
			(thermal_bridge_width 0.5)
			(island_removal_mode 0)
		)
		(polygon
			(pts
				(arc
					(start 450.42201 -230.485188)
					(mid 449.75399 -230.485188)
					(end 450.42201 -230.485188)
				)
			)
		)
	)
	(zone
		(layers "B.Cu" "In13.Cu" "In15.Cu")
		(hatch none 0.5)
		(connect_pads
			(clearance 0)
		)
		(min_thickness 0.25)
		(keepout
			(tracks not_allowed)
			(vias allowed)
			(pads allowed)
			(copperpour not_allowed)
			(footprints allowed)
		)
		(placement
			(enabled no)
			(sheetname "")
		)
		(fill yes
			(thermal_gap 0.5)
			(thermal_bridge_width 0.5)
			(island_removal_mode 0)
		)
		(polygon
			(pts
				(arc
					(start 138.711686 -380.360428)
					(mid 138.043666 -380.360428)
					(end 138.711686 -380.360428)
				)
			)
		)
	)
	(zone
		(layers "B.Cu" "In13.Cu" "In15.Cu")
		(hatch none 0.5)
		(connect_pads
			(clearance 0)
		)
		(min_thickness 0.25)
		(keepout
			(tracks not_allowed)
			(vias allowed)
			(pads allowed)
			(copperpour not_allowed)
			(footprints allowed)
		)
		(placement
			(enabled no)
			(sheetname "")
		)
		(fill yes
			(thermal_gap 0.5)
			(thermal_bridge_width 0.5)
			(island_removal_mode 0)
		)
		(polygon
			(pts
				(arc
					(start 206.58201 -301.88535)
					(mid 205.91399 -301.88535)
					(end 206.58201 -301.88535)
				)
			)
		)
	)
	(zone
		(layers "B.Cu" "In13.Cu" "In15.Cu")
		(hatch none 0.5)
		(connect_pads
			(clearance 0)
		)
		(min_thickness 0.25)
		(keepout
			(tracks not_allowed)
			(vias allowed)
			(pads allowed)
			(copperpour not_allowed)
			(footprints allowed)
		)
		(placement
			(enabled no)
			(sheetname "")
		)
		(fill yes
			(thermal_gap 0.5)
			(thermal_bridge_width 0.5)
			(island_removal_mode 0)
		)
		(polygon
			(pts
				(arc
					(start 124.417836 -412.570168)
					(mid 123.749816 -412.570168)
					(end 124.417836 -412.570168)
				)
			)
		)
	)
	(zone
		(layers "B.Cu" "In13.Cu" "In15.Cu")
		(hatch none 0.5)
		(connect_pads
			(clearance 0)
		)
		(min_thickness 0.25)
		(keepout
			(tracks not_allowed)
			(vias allowed)
			(pads allowed)
			(copperpour not_allowed)
			(footprints allowed)
		)
		(placement
			(enabled no)
			(sheetname "")
		)
		(fill yes
			(thermal_gap 0.5)
			(thermal_bridge_width 0.5)
			(island_removal_mode 0)
		)
		(polygon
			(pts
				(arc
					(start 155.137104 -429.689768)
					(mid 154.362912 -429.689768)
					(end 155.137104 -429.689768)
				)
			)
		)
	)
	(zone
		(layers "B.Cu" "In13.Cu" "In15.Cu")
		(hatch none 0.5)
		(connect_pads
			(clearance 0)
		)
		(min_thickness 0.25)
		(keepout
			(tracks not_allowed)
			(vias allowed)
			(pads allowed)
			(copperpour not_allowed)
			(footprints allowed)
		)
		(placement
			(enabled no)
			(sheetname "")
		)
		(fill yes
			(thermal_gap 0.5)
			(thermal_bridge_width 0.5)
			(island_removal_mode 0)
		)
		(polygon
			(pts
				(arc
					(start 57.317894 -412.570168)
					(mid 56.649874 -412.570168)
					(end 57.317894 -412.570168)
				)
			)
		)
	)
	(zone
		(layers "B.Cu" "In13.Cu" "In15.Cu")
		(hatch none 0.5)
		(connect_pads
			(clearance 0)
		)
		(min_thickness 0.25)
		(keepout
			(tracks not_allowed)
			(vias allowed)
			(pads allowed)
			(copperpour not_allowed)
			(footprints allowed)
		)
		(placement
			(enabled no)
			(sheetname "")
		)
		(fill yes
			(thermal_gap 0.5)
			(thermal_bridge_width 0.5)
			(island_removal_mode 0)
		)
		(polygon
			(pts
				(arc
					(start 17.942052 -261.935214)
					(mid 17.274032 -261.935214)
					(end 17.942052 -261.935214)
				)
			)
		)
	)
	(zone
		(layers "B.Cu" "In13.Cu" "In15.Cu")
		(hatch none 0.5)
		(connect_pads
			(clearance 0)
		)
		(min_thickness 0.25)
		(keepout
			(tracks not_allowed)
			(vias allowed)
			(pads allowed)
			(copperpour not_allowed)
			(footprints allowed)
		)
		(placement
			(enabled no)
			(sheetname "")
		)
		(fill yes
			(thermal_gap 0.5)
			(thermal_bridge_width 0.5)
			(island_removal_mode 0)
		)
		(polygon
			(pts
				(arc
					(start 206.58201 -295.085262)
					(mid 205.91399 -295.085262)
					(end 206.58201 -295.085262)
				)
			)
		)
	)
	(zone
		(layers "B.Cu" "In13.Cu" "In15.Cu")
		(hatch none 0.5)
		(connect_pads
			(clearance 0)
		)
		(min_thickness 0.25)
		(keepout
			(tracks not_allowed)
			(vias allowed)
			(pads allowed)
			(copperpour not_allowed)
			(footprints allowed)
		)
		(placement
			(enabled no)
			(sheetname "")
		)
		(fill yes
			(thermal_gap 0.5)
			(thermal_bridge_width 0.5)
			(island_removal_mode 0)
		)
		(polygon
			(pts
				(arc
					(start 27.043888 -17.61236)
					(mid 26.375868 -17.61236)
					(end 27.043888 -17.61236)
				)
			)
		)
	)
	(zone
		(layers "B.Cu" "In13.Cu" "In15.Cu")
		(hatch none 0.5)
		(connect_pads
			(clearance 0)
		)
		(min_thickness 0.25)
		(keepout
			(tracks not_allowed)
			(vias allowed)
			(pads allowed)
			(copperpour not_allowed)
			(footprints allowed)
		)
		(placement
			(enabled no)
			(sheetname "")
		)
		(fill yes
			(thermal_gap 0.5)
			(thermal_bridge_width 0.5)
			(island_removal_mode 0)
		)
		(polygon
			(pts
				(arc
					(start 206.58201 -221.985332)
					(mid 205.91399 -221.985332)
					(end 206.58201 -221.985332)
				)
			)
		)
	)
	(zone
		(layers "B.Cu" "In13.Cu" "In15.Cu")
		(hatch none 0.5)
		(connect_pads
			(clearance 0)
		)
		(min_thickness 0.25)
		(keepout
			(tracks not_allowed)
			(vias allowed)
			(pads allowed)
			(copperpour not_allowed)
			(footprints allowed)
		)
		(placement
			(enabled no)
			(sheetname "")
		)
		(fill yes
			(thermal_gap 0.5)
			(thermal_bridge_width 0.5)
			(island_removal_mode 0)
		)
		(polygon
			(pts
				(arc
					(start 450.42201 -251.735082)
					(mid 449.75399 -251.735082)
					(end 450.42201 -251.735082)
				)
			)
		)
	)
	(zone
		(layers "B.Cu" "In13.Cu" "In15.Cu")
		(hatch none 0.5)
		(connect_pads
			(clearance 0)
		)
		(min_thickness 0.25)
		(keepout
			(tracks not_allowed)
			(vias allowed)
			(pads allowed)
			(copperpour not_allowed)
			(footprints allowed)
		)
		(placement
			(enabled no)
			(sheetname "")
		)
		(fill yes
			(thermal_gap 0.5)
			(thermal_bridge_width 0.5)
			(island_removal_mode 0)
		)
		(polygon
			(pts
				(arc
					(start 454.522078 -304.435002)
					(mid 453.854058 -304.435002)
					(end 454.522078 -304.435002)
				)
			)
		)
	)
	(zone
		(layers "B.Cu" "In13.Cu" "In15.Cu")
		(hatch none 0.5)
		(connect_pads
			(clearance 0)
		)
		(min_thickness 0.25)
		(keepout
			(tracks not_allowed)
			(vias allowed)
			(pads allowed)
			(copperpour not_allowed)
			(footprints allowed)
		)
		(placement
			(enabled no)
			(sheetname "")
		)
		(fill yes
			(thermal_gap 0.5)
			(thermal_bridge_width 0.5)
			(island_removal_mode 0)
		)
		(polygon
			(pts
				(arc
					(start 86.245954 -246.914416)
					(mid 85.616034 -246.914416)
					(end 86.245954 -246.914416)
				)
			)
		)
	)
	(zone
		(layers "B.Cu" "In13.Cu" "In15.Cu")
		(hatch none 0.5)
		(connect_pads
			(clearance 0)
		)
		(min_thickness 0.25)
		(keepout
			(tracks not_allowed)
			(vias allowed)
			(pads allowed)
			(copperpour not_allowed)
			(footprints allowed)
		)
		(placement
			(enabled no)
			(sheetname "")
		)
		(fill yes
			(thermal_gap 0.5)
			(thermal_bridge_width 0.5)
			(island_removal_mode 0)
		)
		(polygon
			(pts
				(arc
					(start 386.179822 -277.32609)
					(mid 385.549902 -277.32609)
					(end 386.179822 -277.32609)
				)
			)
		)
	)
	(zone
		(layers "B.Cu" "In13.Cu" "In15.Cu")
		(hatch none 0.5)
		(connect_pads
			(clearance 0)
		)
		(min_thickness 0.25)
		(keepout
			(tracks not_allowed)
			(vias allowed)
			(pads allowed)
			(copperpour not_allowed)
			(footprints allowed)
		)
		(placement
			(enabled no)
			(sheetname "")
		)
		(fill yes
			(thermal_gap 0.5)
			(thermal_bridge_width 0.5)
			(island_removal_mode 0)
		)
		(polygon
			(pts
				(arc
					(start 85.776054 -250.964446)
					(mid 85.146134 -250.964446)
					(end 85.776054 -250.964446)
				)
			)
		)
	)
	(zone
		(layers "B.Cu" "In13.Cu" "In15.Cu")
		(hatch none 0.5)
		(connect_pads
			(clearance 0)
		)
		(min_thickness 0.25)
		(keepout
			(tracks not_allowed)
			(vias allowed)
			(pads allowed)
			(copperpour not_allowed)
			(footprints allowed)
		)
		(placement
			(enabled no)
			(sheetname "")
		)
		(fill yes
			(thermal_gap 0.5)
			(thermal_bridge_width 0.5)
			(island_removal_mode 0)
		)
		(polygon
			(pts
				(arc
					(start 386.649722 -274.896072)
					(mid 386.019802 -274.896072)
					(end 386.649722 -274.896072)
				)
			)
		)
	)
	(zone
		(layers "B.Cu" "In13.Cu" "In15.Cu")
		(hatch none 0.5)
		(connect_pads
			(clearance 0)
		)
		(min_thickness 0.25)
		(keepout
			(tracks not_allowed)
			(vias allowed)
			(pads allowed)
			(copperpour not_allowed)
			(footprints allowed)
		)
		(placement
			(enabled no)
			(sheetname "")
		)
		(fill yes
			(thermal_gap 0.5)
			(thermal_bridge_width 0.5)
			(island_removal_mode 0)
		)
		(polygon
			(pts
				(arc
					(start 139.349734 -247.724422)
					(mid 138.719814 -247.724422)
					(end 139.349734 -247.724422)
				)
			)
		)
	)
	(zone
		(layers "B.Cu" "In13.Cu" "In15.Cu")
		(hatch none 0.5)
		(connect_pads
			(clearance 0)
		)
		(min_thickness 0.25)
		(keepout
			(tracks not_allowed)
			(vias allowed)
			(pads allowed)
			(copperpour not_allowed)
			(footprints allowed)
		)
		(placement
			(enabled no)
			(sheetname "")
		)
		(fill yes
			(thermal_gap 0.5)
			(thermal_bridge_width 0.5)
			(island_removal_mode 0)
		)
		(polygon
			(pts
				(arc
					(start 89.433908 -389.467344)
					(mid 88.803988 -389.467344)
					(end 89.433908 -389.467344)
				)
			)
		)
	)
	(zone
		(layers "B.Cu" "In13.Cu" "In15.Cu")
		(hatch none 0.5)
		(connect_pads
			(clearance 0)
		)
		(min_thickness 0.25)
		(keepout
			(tracks not_allowed)
			(vias allowed)
			(pads allowed)
			(copperpour not_allowed)
			(footprints allowed)
		)
		(placement
			(enabled no)
			(sheetname "")
		)
		(fill yes
			(thermal_gap 0.5)
			(thermal_bridge_width 0.5)
			(island_removal_mode 0)
		)
		(polygon
			(pts
				(arc
					(start 333.076042 -271.656048)
					(mid 332.446122 -271.656048)
					(end 333.076042 -271.656048)
				)
			)
		)
	)
	(zone
		(layers "B.Cu" "In13.Cu" "In15.Cu")
		(hatch none 0.5)
		(connect_pads
			(clearance 0)
		)
		(min_thickness 0.25)
		(keepout
			(tracks not_allowed)
			(vias allowed)
			(pads allowed)
			(copperpour not_allowed)
			(footprints allowed)
		)
		(placement
			(enabled no)
			(sheetname "")
		)
		(fill yes
			(thermal_gap 0.5)
			(thermal_bridge_width 0.5)
			(island_removal_mode 0)
		)
		(polygon
			(pts
				(arc
					(start 17.942052 -282.335224)
					(mid 17.274032 -282.335224)
					(end 17.942052 -282.335224)
				)
			)
		)
	)
	(zone
		(layers "B.Cu" "In13.Cu" "In15.Cu")
		(hatch none 0.5)
		(connect_pads
			(clearance 0)
		)
		(min_thickness 0.25)
		(keepout
			(tracks not_allowed)
			(vias allowed)
			(pads allowed)
			(copperpour not_allowed)
			(footprints allowed)
		)
		(placement
			(enabled no)
			(sheetname "")
		)
		(fill yes
			(thermal_gap 0.5)
			(thermal_bridge_width 0.5)
			(island_removal_mode 0)
		)
		(polygon
			(pts
				(arc
					(start 333.716122 -254.204216)
					(mid 333.086202 -254.204216)
					(end 333.716122 -254.204216)
				)
			)
		)
	)
	(zone
		(layers "B.Cu" "In13.Cu" "In15.Cu")
		(hatch none 0.5)
		(connect_pads
			(clearance 0)
		)
		(min_thickness 0.25)
		(keepout
			(tracks not_allowed)
			(vias allowed)
			(pads allowed)
			(copperpour not_allowed)
			(footprints allowed)
		)
		(placement
			(enabled no)
			(sheetname "")
		)
		(fill yes
			(thermal_gap 0.5)
			(thermal_bridge_width 0.5)
			(island_removal_mode 0)
		)
		(polygon
			(pts
				(arc
					(start 334.485996 -262.745982)
					(mid 333.856076 -262.745982)
					(end 334.485996 -262.745982)
				)
			)
		)
	)
	(zone
		(layers "B.Cu" "In13.Cu" "In15.Cu")
		(hatch none 0.5)
		(connect_pads
			(clearance 0)
		)
		(min_thickness 0.25)
		(keepout
			(tracks not_allowed)
			(vias allowed)
			(pads allowed)
			(copperpour not_allowed)
			(footprints allowed)
		)
		(placement
			(enabled no)
			(sheetname "")
		)
		(fill yes
			(thermal_gap 0.5)
			(thermal_bridge_width 0.5)
			(island_removal_mode 0)
		)
		(polygon
			(pts
				(arc
					(start 206.58201 -233.035348)
					(mid 205.91399 -233.035348)
					(end 206.58201 -233.035348)
				)
			)
		)
	)
	(zone
		(layers "B.Cu" "In13.Cu" "In15.Cu")
		(hatch none 0.5)
		(connect_pads
			(clearance 0)
		)
		(min_thickness 0.25)
		(keepout
			(tracks not_allowed)
			(vias allowed)
			(pads allowed)
			(copperpour not_allowed)
			(footprints allowed)
		)
		(placement
			(enabled no)
			(sheetname "")
		)
		(fill yes
			(thermal_gap 0.5)
			(thermal_bridge_width 0.5)
			(island_removal_mode 0)
		)
		(polygon
			(pts
				(arc
					(start 367.849658 -274.896072)
					(mid 367.219738 -274.896072)
					(end 367.849658 -274.896072)
				)
			)
		)
	)
	(zone
		(layers "B.Cu" "In13.Cu" "In15.Cu")
		(hatch none 0.5)
		(connect_pads
			(clearance 0)
		)
		(min_thickness 0.25)
		(keepout
			(tracks not_allowed)
			(vias allowed)
			(pads allowed)
			(copperpour not_allowed)
			(footprints allowed)
		)
		(placement
			(enabled no)
			(sheetname "")
		)
		(fill yes
			(thermal_gap 0.5)
			(thermal_bridge_width 0.5)
			(island_removal_mode 0)
		)
		(polygon
			(pts
				(arc
					(start 332.606142 -272.466054)
					(mid 331.976222 -272.466054)
					(end 332.606142 -272.466054)
				)
			)
		)
	)
	(zone
		(layers "B.Cu" "In13.Cu" "In15.Cu")
		(hatch none 0.5)
		(connect_pads
			(clearance 0)
		)
		(min_thickness 0.25)
		(keepout
			(tracks not_allowed)
			(vias allowed)
			(pads allowed)
			(copperpour not_allowed)
			(footprints allowed)
		)
		(placement
			(enabled no)
			(sheetname "")
		)
		(fill yes
			(thermal_gap 0.5)
			(thermal_bridge_width 0.5)
			(island_removal_mode 0)
		)
		(polygon
			(pts
				(arc
					(start 138.40968 -239.624362)
					(mid 137.77976 -239.624362)
					(end 138.40968 -239.624362)
				)
			)
		)
	)
	(zone
		(layers "B.Cu" "In13.Cu" "In15.Cu")
		(hatch none 0.5)
		(connect_pads
			(clearance 0)
		)
		(min_thickness 0.25)
		(keepout
			(tracks not_allowed)
			(vias allowed)
			(pads allowed)
			(copperpour not_allowed)
			(footprints allowed)
		)
		(placement
			(enabled no)
			(sheetname "")
		)
		(fill yes
			(thermal_gap 0.5)
			(thermal_bridge_width 0.5)
			(island_removal_mode 0)
		)
		(polygon
			(pts
				(arc
					(start 387.759702 -225.85426)
					(mid 387.129782 -225.85426)
					(end 387.759702 -225.85426)
				)
			)
		)
	)
	(zone
		(layers "B.Cu" "In13.Cu" "In15.Cu")
		(hatch none 0.5)
		(connect_pads
			(clearance 0)
		)
		(min_thickness 0.25)
		(keepout
			(tracks not_allowed)
			(vias allowed)
			(pads allowed)
			(copperpour not_allowed)
			(footprints allowed)
		)
		(placement
			(enabled no)
			(sheetname "")
		)
		(fill yes
			(thermal_gap 0.5)
			(thermal_bridge_width 0.5)
			(island_removal_mode 0)
		)
		(polygon
			(pts
				(arc
					(start 265.88212 -202.434952)
					(mid 265.2141 -202.434952)
					(end 265.88212 -202.434952)
				)
			)
		)
	)
	(zone
		(layers "B.Cu" "In13.Cu" "In15.Cu")
		(hatch none 0.5)
		(connect_pads
			(clearance 0)
		)
		(min_thickness 0.25)
		(keepout
			(tracks not_allowed)
			(vias allowed)
			(pads allowed)
			(copperpour not_allowed)
			(footprints allowed)
		)
		(placement
			(enabled no)
			(sheetname "")
		)
		(fill yes
			(thermal_gap 0.5)
			(thermal_bridge_width 0.5)
			(island_removal_mode 0)
		)
		(polygon
			(pts
				(arc
					(start 86.545928 -270.846296)
					(mid 85.916008 -270.846296)
					(end 86.545928 -270.846296)
				)
			)
		)
	)
	(zone
		(layers "B.Cu" "In13.Cu" "In15.Cu")
		(hatch none 0.5)
		(connect_pads
			(clearance 0)
		)
		(min_thickness 0.25)
		(keepout
			(tracks not_allowed)
			(vias allowed)
			(pads allowed)
			(copperpour not_allowed)
			(footprints allowed)
		)
		(placement
			(enabled no)
			(sheetname "")
		)
		(fill yes
			(thermal_gap 0.5)
			(thermal_bridge_width 0.5)
			(island_removal_mode 0)
		)
		(polygon
			(pts
				(arc
					(start 378.361702 -382.34493)
					(mid 377.693682 -382.34493)
					(end 378.361702 -382.34493)
				)
			)
		)
	)
	(zone
		(layers "B.Cu" "In13.Cu" "In15.Cu")
		(hatch none 0.5)
		(connect_pads
			(clearance 0)
		)
		(min_thickness 0.25)
		(keepout
			(tracks not_allowed)
			(vias allowed)
			(pads allowed)
			(copperpour not_allowed)
			(footprints allowed)
		)
		(placement
			(enabled no)
			(sheetname "")
		)
		(fill yes
			(thermal_gap 0.5)
			(thermal_bridge_width 0.5)
			(island_removal_mode 0)
		)
		(polygon
			(pts
				(arc
					(start 17.942052 -218.585288)
					(mid 17.274032 -218.585288)
					(end 17.942052 -218.585288)
				)
			)
		)
	)
	(zone
		(layers "B.Cu" "In13.Cu" "In15.Cu")
		(hatch none 0.5)
		(connect_pads
			(clearance 0)
		)
		(min_thickness 0.25)
		(keepout
			(tracks not_allowed)
			(vias allowed)
			(pads allowed)
			(copperpour not_allowed)
			(footprints allowed)
		)
		(placement
			(enabled no)
			(sheetname "")
		)
		(fill yes
			(thermal_gap 0.5)
			(thermal_bridge_width 0.5)
			(island_removal_mode 0)
		)
		(polygon
			(pts
				(arc
					(start 206.58201 -204.985366)
					(mid 205.91399 -204.985366)
					(end 206.58201 -204.985366)
				)
			)
		)
	)
	(zone
		(layers "B.Cu" "In13.Cu" "In15.Cu")
		(hatch none 0.5)
		(connect_pads
			(clearance 0)
		)
		(min_thickness 0.25)
		(keepout
			(tracks not_allowed)
			(vias allowed)
			(pads allowed)
			(copperpour not_allowed)
			(footprints allowed)
		)
		(placement
			(enabled no)
			(sheetname "")
		)
		(fill yes
			(thermal_gap 0.5)
			(thermal_bridge_width 0.5)
			(island_removal_mode 0)
		)
		(polygon
			(pts
				(arc
					(start 93.83395 -385.31038)
					(mid 93.20403 -385.31038)
					(end 93.83395 -385.31038)
				)
			)
		)
	)
	(zone
		(layers "B.Cu" "In13.Cu" "In15.Cu")
		(hatch none 0.5)
		(connect_pads
			(clearance 0)
		)
		(min_thickness 0.25)
		(keepout
			(tracks not_allowed)
			(vias allowed)
			(pads allowed)
			(copperpour not_allowed)
			(footprints allowed)
		)
		(placement
			(enabled no)
			(sheetname "")
		)
		(fill yes
			(thermal_gap 0.5)
			(thermal_bridge_width 0.5)
			(island_removal_mode 0)
		)
		(polygon
			(pts
				(arc
					(start 429.433228 -6.725158)
					(mid 428.765208 -6.725158)
					(end 429.433228 -6.725158)
				)
			)
		)
	)
	(zone
		(layers "B.Cu" "In13.Cu" "In15.Cu")
		(hatch none 0.5)
		(connect_pads
			(clearance 0)
		)
		(min_thickness 0.25)
		(keepout
			(tracks not_allowed)
			(vias allowed)
			(pads allowed)
			(copperpour not_allowed)
			(footprints allowed)
		)
		(placement
			(enabled no)
			(sheetname "")
		)
		(fill yes
			(thermal_gap 0.5)
			(thermal_bridge_width 0.5)
			(island_removal_mode 0)
		)
		(polygon
			(pts
				(arc
					(start 22.04212 -276.385274)
					(mid 21.3741 -276.385274)
					(end 22.04212 -276.385274)
				)
			)
		)
	)
	(zone
		(layers "B.Cu" "In13.Cu" "In15.Cu")
		(hatch none 0.5)
		(connect_pads
			(clearance 0)
		)
		(min_thickness 0.25)
		(keepout
			(tracks not_allowed)
			(vias allowed)
			(pads allowed)
			(copperpour not_allowed)
			(footprints allowed)
		)
		(placement
			(enabled no)
			(sheetname "")
		)
		(fill yes
			(thermal_gap 0.5)
			(thermal_bridge_width 0.5)
			(island_removal_mode 0)
		)
		(polygon
			(pts
				(arc
					(start 265.88212 -284.034992)
					(mid 265.2141 -284.034992)
					(end 265.88212 -284.034992)
				)
			)
		)
	)
	(zone
		(layers "B.Cu" "In13.Cu" "In15.Cu")
		(hatch none 0.5)
		(connect_pads
			(clearance 0)
		)
		(min_thickness 0.25)
		(keepout
			(tracks not_allowed)
			(vias allowed)
			(pads allowed)
			(copperpour not_allowed)
			(footprints allowed)
		)
		(placement
			(enabled no)
			(sheetname "")
		)
		(fill yes
			(thermal_gap 0.5)
			(thermal_bridge_width 0.5)
			(island_removal_mode 0)
		)
		(polygon
			(pts
				(arc
					(start 202.481942 -310.385206)
					(mid 201.813922 -310.385206)
					(end 202.481942 -310.385206)
				)
			)
		)
	)
	(zone
		(layers "B.Cu" "In13.Cu" "In15.Cu")
		(hatch none 0.5)
		(connect_pads
			(clearance 0)
		)
		(min_thickness 0.25)
		(keepout
			(tracks not_allowed)
			(vias allowed)
			(pads allowed)
			(copperpour not_allowed)
			(footprints allowed)
		)
		(placement
			(enabled no)
			(sheetname "")
		)
		(fill yes
			(thermal_gap 0.5)
			(thermal_bridge_width 0.5)
			(island_removal_mode 0)
		)
		(polygon
			(pts
				(arc
					(start 386.544312 -420.952168)
					(mid 385.876292 -420.952168)
					(end 386.544312 -420.952168)
				)
			)
		)
	)
	(zone
		(layers "B.Cu" "In13.Cu" "In15.Cu")
		(hatch none 0.5)
		(connect_pads
			(clearance 0)
		)
		(min_thickness 0.25)
		(keepout
			(tracks not_allowed)
			(vias allowed)
			(pads allowed)
			(copperpour not_allowed)
			(footprints allowed)
		)
		(placement
			(enabled no)
			(sheetname "")
		)
		(fill yes
			(thermal_gap 0.5)
			(thermal_bridge_width 0.5)
			(island_removal_mode 0)
		)
		(polygon
			(pts
				(arc
					(start 17.942052 -232.18521)
					(mid 17.274032 -232.18521)
					(end 17.942052 -232.18521)
				)
			)
		)
	)
	(zone
		(layers "B.Cu" "In13.Cu" "In15.Cu")
		(hatch none 0.5)
		(connect_pads
			(clearance 0)
		)
		(min_thickness 0.25)
		(keepout
			(tracks not_allowed)
			(vias allowed)
			(pads allowed)
			(copperpour not_allowed)
			(footprints allowed)
		)
		(placement
			(enabled no)
			(sheetname "")
		)
		(fill yes
			(thermal_gap 0.5)
			(thermal_bridge_width 0.5)
			(island_removal_mode 0)
		)
		(polygon
			(pts
				(arc
					(start 355.336094 -231.524048)
					(mid 354.706174 -231.524048)
					(end 355.336094 -231.524048)
				)
			)
		)
	)
	(zone
		(layers "B.Cu" "In13.Cu" "In15.Cu")
		(hatch none 0.5)
		(connect_pads
			(clearance 0)
		)
		(min_thickness 0.25)
		(keepout
			(tracks not_allowed)
			(vias allowed)
			(pads allowed)
			(copperpour not_allowed)
			(footprints allowed)
		)
		(placement
			(enabled no)
			(sheetname "")
		)
		(fill yes
			(thermal_gap 0.5)
			(thermal_bridge_width 0.5)
			(island_removal_mode 0)
		)
		(polygon
			(pts
				(arc
					(start 387.589776 -266.796012)
					(mid 386.959856 -266.796012)
					(end 387.589776 -266.796012)
				)
			)
		)
	)
	(zone
		(layers "B.Cu" "In13.Cu" "In15.Cu")
		(hatch none 0.5)
		(connect_pads
			(clearance 0)
		)
		(min_thickness 0.25)
		(keepout
			(tracks not_allowed)
			(vias allowed)
			(pads allowed)
			(copperpour not_allowed)
			(footprints allowed)
		)
		(placement
			(enabled no)
			(sheetname "")
		)
		(fill yes
			(thermal_gap 0.5)
			(thermal_bridge_width 0.5)
			(island_removal_mode 0)
		)
		(polygon
			(pts
				(arc
					(start 385.879848 -251.774198)
					(mid 385.249928 -251.774198)
					(end 385.879848 -251.774198)
				)
			)
		)
	)
	(zone
		(layers "B.Cu" "In13.Cu" "In15.Cu")
		(hatch none 0.5)
		(connect_pads
			(clearance 0)
		)
		(min_thickness 0.25)
		(keepout
			(tracks not_allowed)
			(vias allowed)
			(pads allowed)
			(copperpour not_allowed)
			(footprints allowed)
		)
		(placement
			(enabled no)
			(sheetname "")
		)
		(fill yes
			(thermal_gap 0.5)
			(thermal_bridge_width 0.5)
			(island_removal_mode 0)
		)
		(polygon
			(pts
				(arc
					(start 378.218192 -420.952168)
					(mid 377.550172 -420.952168)
					(end 378.218192 -420.952168)
				)
			)
		)
	)
	(zone
		(layers "B.Cu" "In13.Cu" "In15.Cu")
		(hatch none 0.5)
		(connect_pads
			(clearance 0)
		)
		(min_thickness 0.25)
		(keepout
			(tracks not_allowed)
			(vias allowed)
			(pads allowed)
			(copperpour not_allowed)
			(footprints allowed)
		)
		(placement
			(enabled no)
			(sheetname "")
		)
		(fill yes
			(thermal_gap 0.5)
			(thermal_bridge_width 0.5)
			(island_removal_mode 0)
		)
		(polygon
			(pts
				(arc
					(start 326.434196 -420.952168)
					(mid 325.766176 -420.952168)
					(end 326.434196 -420.952168)
				)
			)
		)
	)
	(zone
		(layers "B.Cu" "In13.Cu" "In15.Cu")
		(hatch none 0.5)
		(connect_pads
			(clearance 0)
		)
		(min_thickness 0.25)
		(keepout
			(tracks not_allowed)
			(vias allowed)
			(pads allowed)
			(copperpour not_allowed)
			(footprints allowed)
		)
		(placement
			(enabled no)
			(sheetname "")
		)
		(fill yes
			(thermal_gap 0.5)
			(thermal_bridge_width 0.5)
			(island_removal_mode 0)
		)
		(polygon
			(pts
				(arc
					(start 333.716122 -249.34418)
					(mid 333.086202 -249.34418)
					(end 333.716122 -249.34418)
				)
			)
		)
	)
	(zone
		(layers "B.Cu" "In13.Cu" "In15.Cu")
		(hatch none 0.5)
		(connect_pads
			(clearance 0)
		)
		(min_thickness 0.25)
		(keepout
			(tracks not_allowed)
			(vias allowed)
			(pads allowed)
			(copperpour not_allowed)
			(footprints allowed)
		)
		(placement
			(enabled no)
			(sheetname "")
		)
		(fill yes
			(thermal_gap 0.5)
			(thermal_bridge_width 0.5)
			(island_removal_mode 0)
		)
		(polygon
			(pts
				(arc
					(start 139.349734 -239.624362)
					(mid 138.719814 -239.624362)
					(end 139.349734 -239.624362)
				)
			)
		)
	)
	(zone
		(layers "B.Cu" "In13.Cu" "In15.Cu")
		(hatch none 0.5)
		(connect_pads
			(clearance 0)
		)
		(min_thickness 0.25)
		(keepout
			(tracks not_allowed)
			(vias allowed)
			(pads allowed)
			(copperpour not_allowed)
			(footprints allowed)
		)
		(placement
			(enabled no)
			(sheetname "")
		)
		(fill yes
			(thermal_gap 0.5)
			(thermal_bridge_width 0.5)
			(island_removal_mode 0)
		)
		(polygon
			(pts
				(arc
					(start 90.037158 -431.889916)
					(mid 89.262966 -431.889916)
					(end 90.037158 -431.889916)
				)
			)
		)
	)
	(zone
		(layers "B.Cu" "In13.Cu" "In15.Cu")
		(hatch none 0.5)
		(connect_pads
			(clearance 0)
		)
		(min_thickness 0.25)
		(keepout
			(tracks not_allowed)
			(vias allowed)
			(pads allowed)
			(copperpour not_allowed)
			(footprints allowed)
		)
		(placement
			(enabled no)
			(sheetname "")
		)
		(fill yes
			(thermal_gap 0.5)
			(thermal_bridge_width 0.5)
			(island_removal_mode 0)
		)
		(polygon
			(pts
				(arc
					(start 319.444116 -420.952168)
					(mid 318.776096 -420.952168)
					(end 319.444116 -420.952168)
				)
			)
		)
	)
	(zone
		(layers "B.Cu" "In13.Cu" "In15.Cu")
		(hatch none 0.5)
		(connect_pads
			(clearance 0)
		)
		(min_thickness 0.25)
		(keepout
			(tracks not_allowed)
			(vias allowed)
			(pads allowed)
			(copperpour not_allowed)
			(footprints allowed)
		)
		(placement
			(enabled no)
			(sheetname "")
		)
		(fill yes
			(thermal_gap 0.5)
			(thermal_bridge_width 0.5)
			(island_removal_mode 0)
		)
		(polygon
			(pts
				(arc
					(start 387.289802 -246.104156)
					(mid 386.659882 -246.104156)
					(end 387.289802 -246.104156)
				)
			)
		)
	)
	(zone
		(layers "B.Cu" "In13.Cu" "In15.Cu")
		(hatch none 0.5)
		(connect_pads
			(clearance 0)
		)
		(min_thickness 0.25)
		(keepout
			(tracks not_allowed)
			(vias allowed)
			(pads allowed)
			(copperpour not_allowed)
			(footprints allowed)
		)
		(placement
			(enabled no)
			(sheetname "")
		)
		(fill yes
			(thermal_gap 0.5)
			(thermal_bridge_width 0.5)
			(island_removal_mode 0)
		)
		(polygon
			(pts
				(arc
					(start 115.228116 -412.570168)
					(mid 114.560096 -412.570168)
					(end 115.228116 -412.570168)
				)
			)
		)
	)
	(zone
		(layers "B.Cu" "In13.Cu" "In15.Cu")
		(hatch none 0.5)
		(connect_pads
			(clearance 0)
		)
		(min_thickness 0.25)
		(keepout
			(tracks not_allowed)
			(vias allowed)
			(pads allowed)
			(copperpour not_allowed)
			(footprints allowed)
		)
		(placement
			(enabled no)
			(sheetname "")
		)
		(fill yes
			(thermal_gap 0.5)
			(thermal_bridge_width 0.5)
			(island_removal_mode 0)
		)
		(polygon
			(pts
				(arc
					(start 80.634078 -385.31038)
					(mid 80.004158 -385.31038)
					(end 80.634078 -385.31038)
				)
			)
		)
	)
	(zone
		(layers "B.Cu" "In13.Cu" "In15.Cu")
		(hatch none 0.5)
		(connect_pads
			(clearance 0)
		)
		(min_thickness 0.25)
		(keepout
			(tracks not_allowed)
			(vias allowed)
			(pads allowed)
			(copperpour not_allowed)
			(footprints allowed)
		)
		(placement
			(enabled no)
			(sheetname "")
		)
		(fill yes
			(thermal_gap 0.5)
			(thermal_bridge_width 0.5)
			(island_removal_mode 0)
		)
		(polygon
			(pts
				(arc
					(start 85.776054 -249.344434)
					(mid 85.146134 -249.344434)
					(end 85.776054 -249.344434)
				)
			)
		)
	)
	(zone
		(layers "B.Cu" "In13.Cu" "In15.Cu")
		(hatch none 0.5)
		(connect_pads
			(clearance 0)
		)
		(min_thickness 0.25)
		(keepout
			(tracks not_allowed)
			(vias allowed)
			(pads allowed)
			(copperpour not_allowed)
			(footprints allowed)
		)
		(placement
			(enabled no)
			(sheetname "")
		)
		(fill yes
			(thermal_gap 0.5)
			(thermal_bridge_width 0.5)
			(island_removal_mode 0)
		)
		(polygon
			(pts
				(arc
					(start 365.969804 -274.896072)
					(mid 365.339884 -274.896072)
					(end 365.969804 -274.896072)
				)
			)
		)
	)
	(zone
		(layers "B.Cu" "In13.Cu" "In15.Cu")
		(hatch none 0.5)
		(connect_pads
			(clearance 0)
		)
		(min_thickness 0.25)
		(keepout
			(tracks not_allowed)
			(vias allowed)
			(pads allowed)
			(copperpour not_allowed)
			(footprints allowed)
		)
		(placement
			(enabled no)
			(sheetname "")
		)
		(fill yes
			(thermal_gap 0.5)
			(thermal_bridge_width 0.5)
			(island_removal_mode 0)
		)
		(polygon
			(pts
				(arc
					(start 332.306168 -235.574078)
					(mid 331.676248 -235.574078)
					(end 332.306168 -235.574078)
				)
			)
		)
	)
	(zone
		(layers "B.Cu" "In13.Cu" "In15.Cu")
		(hatch none 0.5)
		(connect_pads
			(clearance 0)
		)
		(min_thickness 0.25)
		(keepout
			(tracks not_allowed)
			(vias allowed)
			(pads allowed)
			(copperpour not_allowed)
			(footprints allowed)
		)
		(placement
			(enabled no)
			(sheetname "")
		)
		(fill yes
			(thermal_gap 0.5)
			(thermal_bridge_width 0.5)
			(island_removal_mode 0)
		)
		(polygon
			(pts
				(arc
					(start 136.839706 -369.03533)
					(mid 136.171686 -369.03533)
					(end 136.839706 -369.03533)
				)
			)
		)
	)
	(zone
		(layers "B.Cu" "In13.Cu" "In15.Cu")
		(hatch none 0.5)
		(connect_pads
			(clearance 0)
		)
		(min_thickness 0.25)
		(keepout
			(tracks not_allowed)
			(vias allowed)
			(pads allowed)
			(copperpour not_allowed)
			(footprints allowed)
		)
		(placement
			(enabled no)
			(sheetname "")
		)
		(fill yes
			(thermal_gap 0.5)
			(thermal_bridge_width 0.5)
			(island_removal_mode 0)
		)
		(polygon
			(pts
				(arc
					(start 103.936038 -276.516338)
					(mid 103.306118 -276.516338)
					(end 103.936038 -276.516338)
				)
			)
		)
	)
	(zone
		(layers "B.Cu" "In13.Cu" "In15.Cu")
		(hatch none 0.5)
		(connect_pads
			(clearance 0)
		)
		(min_thickness 0.25)
		(keepout
			(tracks not_allowed)
			(vias allowed)
			(pads allowed)
			(copperpour not_allowed)
			(footprints allowed)
		)
		(placement
			(enabled no)
			(sheetname "")
		)
		(fill yes
			(thermal_gap 0.5)
			(thermal_bridge_width 0.5)
			(island_removal_mode 0)
		)
		(polygon
			(pts
				(arc
					(start 22.04212 -296.785284)
					(mid 21.3741 -296.785284)
					(end 22.04212 -296.785284)
				)
			)
		)
	)
	(zone
		(layers "B.Cu" "In13.Cu" "In15.Cu")
		(hatch none 0.5)
		(connect_pads
			(clearance 0)
		)
		(min_thickness 0.25)
		(keepout
			(tracks not_allowed)
			(vias allowed)
			(pads allowed)
			(copperpour not_allowed)
			(footprints allowed)
		)
		(placement
			(enabled no)
			(sheetname "")
		)
		(fill yes
			(thermal_gap 0.5)
			(thermal_bridge_width 0.5)
			(island_removal_mode 0)
		)
		(polygon
			(pts
				(arc
					(start 315.036708 -430.889918)
					(mid 314.262516 -430.889918)
					(end 315.036708 -430.889918)
				)
			)
		)
	)
	(zone
		(layers "B.Cu" "In13.Cu" "In15.Cu")
		(hatch none 0.5)
		(connect_pads
			(clearance 0)
		)
		(min_thickness 0.25)
		(keepout
			(tracks not_allowed)
			(vias allowed)
			(pads allowed)
			(copperpour not_allowed)
			(footprints allowed)
		)
		(placement
			(enabled no)
			(sheetname "")
		)
		(fill yes
			(thermal_gap 0.5)
			(thermal_bridge_width 0.5)
			(island_removal_mode 0)
		)
		(polygon
			(pts
				(arc
					(start 22.04212 -300.185328)
					(mid 21.3741 -300.185328)
					(end 22.04212 -300.185328)
				)
			)
		)
	)
	(zone
		(layers "B.Cu" "In13.Cu" "In15.Cu")
		(hatch none 0.5)
		(connect_pads
			(clearance 0)
		)
		(min_thickness 0.25)
		(keepout
			(tracks not_allowed)
			(vias allowed)
			(pads allowed)
			(copperpour not_allowed)
			(footprints allowed)
		)
		(placement
			(enabled no)
			(sheetname "")
		)
		(fill yes
			(thermal_gap 0.5)
			(thermal_bridge_width 0.5)
			(island_removal_mode 0)
		)
		(polygon
			(pts
				(arc
					(start 139.819634 -256.634488)
					(mid 139.189714 -256.634488)
					(end 139.819634 -256.634488)
				)
			)
		)
	)
	(zone
		(layers "B.Cu" "In13.Cu" "In15.Cu")
		(hatch none 0.5)
		(connect_pads
			(clearance 0)
		)
		(min_thickness 0.25)
		(keepout
			(tracks not_allowed)
			(vias allowed)
			(pads allowed)
			(copperpour not_allowed)
			(footprints allowed)
		)
		(placement
			(enabled no)
			(sheetname "")
		)
		(fill yes
			(thermal_gap 0.5)
			(thermal_bridge_width 0.5)
			(island_removal_mode 0)
		)
		(polygon
			(pts
				(arc
					(start 116.789708 -231.524302)
					(mid 116.159788 -231.524302)
					(end 116.789708 -231.524302)
				)
			)
		)
	)
	(zone
		(layers "B.Cu" "In13.Cu" "In15.Cu")
		(hatch none 0.5)
		(connect_pads
			(clearance 0)
		)
		(min_thickness 0.25)
		(keepout
			(tracks not_allowed)
			(vias allowed)
			(pads allowed)
			(copperpour not_allowed)
			(footprints allowed)
		)
		(placement
			(enabled no)
			(sheetname "")
		)
		(fill yes
			(thermal_gap 0.5)
			(thermal_bridge_width 0.5)
			(island_removal_mode 0)
		)
		(polygon
			(pts
				(arc
					(start 206.58201 -276.385274)
					(mid 205.91399 -276.385274)
					(end 206.58201 -276.385274)
				)
			)
		)
	)
	(zone
		(layers "B.Cu" "In13.Cu" "In15.Cu")
		(hatch none 0.5)
		(connect_pads
			(clearance 0)
		)
		(min_thickness 0.25)
		(keepout
			(tracks not_allowed)
			(vias allowed)
			(pads allowed)
			(copperpour not_allowed)
			(footprints allowed)
		)
		(placement
			(enabled no)
			(sheetname "")
		)
		(fill yes
			(thermal_gap 0.5)
			(thermal_bridge_width 0.5)
			(island_removal_mode 0)
		)
		(polygon
			(pts
				(arc
					(start 138.239754 -285.426404)
					(mid 137.609834 -285.426404)
					(end 138.239754 -285.426404)
				)
			)
		)
	)
	(zone
		(layers "B.Cu" "In13.Cu" "In15.Cu")
		(hatch none 0.5)
		(connect_pads
			(clearance 0)
		)
		(min_thickness 0.25)
		(keepout
			(tracks not_allowed)
			(vias allowed)
			(pads allowed)
			(copperpour not_allowed)
			(footprints allowed)
		)
		(placement
			(enabled no)
			(sheetname "")
		)
		(fill yes
			(thermal_gap 0.5)
			(thermal_bridge_width 0.5)
			(island_removal_mode 0)
		)
		(polygon
			(pts
				(arc
					(start 85.776054 -252.584458)
					(mid 85.146134 -252.584458)
					(end 85.776054 -252.584458)
				)
			)
		)
	)
	(zone
		(layers "B.Cu" "In13.Cu" "In15.Cu")
		(hatch none 0.5)
		(connect_pads
			(clearance 0)
		)
		(min_thickness 0.25)
		(keepout
			(tracks not_allowed)
			(vias allowed)
			(pads allowed)
			(copperpour not_allowed)
			(footprints allowed)
		)
		(placement
			(enabled no)
			(sheetname "")
		)
		(fill yes
			(thermal_gap 0.5)
			(thermal_bridge_width 0.5)
			(island_removal_mode 0)
		)
		(polygon
			(pts
				(arc
					(start 139.819634 -230.71455)
					(mid 139.189714 -230.71455)
					(end 139.819634 -230.71455)
				)
			)
		)
	)
	(zone
		(layers "B.Cu" "In13.Cu" "In15.Cu")
		(hatch none 0.5)
		(connect_pads
			(clearance 0)
		)
		(min_thickness 0.25)
		(keepout
			(tracks not_allowed)
			(vias allowed)
			(pads allowed)
			(copperpour not_allowed)
			(footprints allowed)
		)
		(placement
			(enabled no)
			(sheetname "")
		)
		(fill yes
			(thermal_gap 0.5)
			(thermal_bridge_width 0.5)
			(island_removal_mode 0)
		)
		(polygon
			(pts
				(arc
					(start 371.609874 -276.516084)
					(mid 370.979954 -276.516084)
					(end 371.609874 -276.516084)
				)
			)
		)
	)
	(zone
		(layers "B.Cu" "In13.Cu" "In15.Cu")
		(hatch none 0.5)
		(connect_pads
			(clearance 0)
		)
		(min_thickness 0.25)
		(keepout
			(tracks not_allowed)
			(vias allowed)
			(pads allowed)
			(copperpour not_allowed)
			(footprints allowed)
		)
		(placement
			(enabled no)
			(sheetname "")
		)
		(fill yes
			(thermal_gap 0.5)
			(thermal_bridge_width 0.5)
			(island_removal_mode 0)
		)
		(polygon
			(pts
				(arc
					(start 104.876092 -278.13635)
					(mid 104.246172 -278.13635)
					(end 104.876092 -278.13635)
				)
			)
		)
	)
	(zone
		(layers "B.Cu" "In13.Cu" "In15.Cu")
		(hatch none 0.5)
		(connect_pads
			(clearance 0)
		)
		(min_thickness 0.25)
		(keepout
			(tracks not_allowed)
			(vias allowed)
			(pads allowed)
			(copperpour not_allowed)
			(footprints allowed)
		)
		(placement
			(enabled no)
			(sheetname "")
		)
		(fill yes
			(thermal_gap 0.5)
			(thermal_bridge_width 0.5)
			(island_removal_mode 0)
		)
		(polygon
			(pts
				(arc
					(start 22.04212 -250.885198)
					(mid 21.3741 -250.885198)
					(end 22.04212 -250.885198)
				)
			)
		)
	)
	(zone
		(layers "B.Cu" "In13.Cu" "In15.Cu")
		(hatch none 0.5)
		(connect_pads
			(clearance 0)
		)
		(min_thickness 0.25)
		(keepout
			(tracks not_allowed)
			(vias allowed)
			(pads allowed)
			(copperpour not_allowed)
			(footprints allowed)
		)
		(placement
			(enabled no)
			(sheetname "")
		)
		(fill yes
			(thermal_gap 0.5)
			(thermal_bridge_width 0.5)
			(island_removal_mode 0)
		)
		(polygon
			(pts
				(arc
					(start 138.40968 -255.824482)
					(mid 137.77976 -255.824482)
					(end 138.40968 -255.824482)
				)
			)
		)
	)
	(zone
		(layers "B.Cu" "In13.Cu" "In15.Cu")
		(hatch none 0.5)
		(connect_pads
			(clearance 0)
		)
		(min_thickness 0.25)
		(keepout
			(tracks not_allowed)
			(vias allowed)
			(pads allowed)
			(copperpour not_allowed)
			(footprints allowed)
		)
		(placement
			(enabled no)
			(sheetname "")
		)
		(fill yes
			(thermal_gap 0.5)
			(thermal_bridge_width 0.5)
			(island_removal_mode 0)
		)
		(polygon
			(pts
				(arc
					(start 334.016096 -279.756108)
					(mid 333.386176 -279.756108)
					(end 334.016096 -279.756108)
				)
			)
		)
	)
	(zone
		(layers "B.Cu" "In13.Cu" "In15.Cu")
		(hatch none 0.5)
		(connect_pads
			(clearance 0)
		)
		(min_thickness 0.25)
		(keepout
			(tracks not_allowed)
			(vias allowed)
			(pads allowed)
			(copperpour not_allowed)
			(footprints allowed)
		)
		(placement
			(enabled no)
			(sheetname "")
		)
		(fill yes
			(thermal_gap 0.5)
			(thermal_bridge_width 0.5)
			(island_removal_mode 0)
		)
		(polygon
			(pts
				(arc
					(start 332.606142 -267.606018)
					(mid 331.976222 -267.606018)
					(end 332.606142 -267.606018)
				)
			)
		)
	)
	(zone
		(layers "B.Cu" "In13.Cu" "In15.Cu")
		(hatch none 0.5)
		(connect_pads
			(clearance 0)
		)
		(min_thickness 0.25)
		(keepout
			(tracks not_allowed)
			(vias allowed)
			(pads allowed)
			(copperpour not_allowed)
			(footprints allowed)
		)
		(placement
			(enabled no)
			(sheetname "")
		)
		(fill yes
			(thermal_gap 0.5)
			(thermal_bridge_width 0.5)
			(island_removal_mode 0)
		)
		(polygon
			(pts
				(arc
					(start 450.42201 -263.634982)
					(mid 449.75399 -263.634982)
					(end 450.42201 -263.634982)
				)
			)
		)
	)
	(zone
		(layers "B.Cu" "In13.Cu" "In15.Cu")
		(hatch none 0.5)
		(connect_pads
			(clearance 0)
		)
		(min_thickness 0.25)
		(keepout
			(tracks not_allowed)
			(vias allowed)
			(pads allowed)
			(copperpour not_allowed)
			(footprints allowed)
		)
		(placement
			(enabled no)
			(sheetname "")
		)
		(fill yes
			(thermal_gap 0.5)
			(thermal_bridge_width 0.5)
			(island_removal_mode 0)
		)
		(polygon
			(pts
				(arc
					(start 450.42201 -253.435104)
					(mid 449.75399 -253.435104)
					(end 450.42201 -253.435104)
				)
			)
		)
	)
	(zone
		(layers "B.Cu" "In13.Cu" "In15.Cu")
		(hatch none 0.5)
		(connect_pads
			(clearance 0)
		)
		(min_thickness 0.25)
		(keepout
			(tracks not_allowed)
			(vias allowed)
			(pads allowed)
			(copperpour not_allowed)
			(footprints allowed)
		)
		(placement
			(enabled no)
			(sheetname "")
		)
		(fill yes
			(thermal_gap 0.5)
			(thermal_bridge_width 0.5)
			(island_removal_mode 0)
		)
		(polygon
			(pts
				(arc
					(start 202.481942 -243.235226)
					(mid 201.813922 -243.235226)
					(end 202.481942 -243.235226)
				)
			)
		)
	)
	(zone
		(layers "B.Cu" "In13.Cu" "In15.Cu")
		(hatch none 0.5)
		(connect_pads
			(clearance 0)
		)
		(min_thickness 0.25)
		(keepout
			(tracks not_allowed)
			(vias allowed)
			(pads allowed)
			(copperpour not_allowed)
			(footprints allowed)
		)
		(placement
			(enabled no)
			(sheetname "")
		)
		(fill yes
			(thermal_gap 0.5)
			(thermal_bridge_width 0.5)
			(island_removal_mode 0)
		)
		(polygon
			(pts
				(arc
					(start 354.39604 -231.524048)
					(mid 353.76612 -231.524048)
					(end 354.39604 -231.524048)
				)
			)
		)
	)
	(zone
		(layers "B.Cu" "In13.Cu" "In15.Cu")
		(hatch none 0.5)
		(connect_pads
			(clearance 0)
		)
		(min_thickness 0.25)
		(keepout
			(tracks not_allowed)
			(vias allowed)
			(pads allowed)
			(copperpour not_allowed)
			(footprints allowed)
		)
		(placement
			(enabled no)
			(sheetname "")
		)
		(fill yes
			(thermal_gap 0.5)
			(thermal_bridge_width 0.5)
			(island_removal_mode 0)
		)
		(polygon
			(pts
				(arc
					(start 269.982188 -245.785132)
					(mid 269.314168 -245.785132)
					(end 269.982188 -245.785132)
				)
			)
		)
	)
	(zone
		(layers "B.Cu" "In13.Cu" "In15.Cu")
		(hatch none 0.5)
		(connect_pads
			(clearance 0)
		)
		(min_thickness 0.25)
		(keepout
			(tracks not_allowed)
			(vias allowed)
			(pads allowed)
			(copperpour not_allowed)
			(footprints allowed)
		)
		(placement
			(enabled no)
			(sheetname "")
		)
		(fill yes
			(thermal_gap 0.5)
			(thermal_bridge_width 0.5)
			(island_removal_mode 0)
		)
		(polygon
			(pts
				(arc
					(start 139.649708 -276.516338)
					(mid 139.019788 -276.516338)
					(end 139.649708 -276.516338)
				)
			)
		)
	)
	(zone
		(layers "B.Cu" "In13.Cu" "In15.Cu")
		(hatch none 0.5)
		(connect_pads
			(clearance 0)
		)
		(min_thickness 0.25)
		(keepout
			(tracks not_allowed)
			(vias allowed)
			(pads allowed)
			(copperpour not_allowed)
			(footprints allowed)
		)
		(placement
			(enabled no)
			(sheetname "")
		)
		(fill yes
			(thermal_gap 0.5)
			(thermal_bridge_width 0.5)
			(island_removal_mode 0)
		)
		(polygon
			(pts
				(arc
					(start 332.776068 -233.14406)
					(mid 332.146148 -233.14406)
					(end 332.776068 -233.14406)
				)
			)
		)
	)
	(zone
		(layers "B.Cu" "In13.Cu" "In15.Cu")
		(hatch none 0.5)
		(connect_pads
			(clearance 0)
		)
		(min_thickness 0.25)
		(keepout
			(tracks not_allowed)
			(vias allowed)
			(pads allowed)
			(copperpour not_allowed)
			(footprints allowed)
		)
		(placement
			(enabled no)
			(sheetname "")
		)
		(fill yes
			(thermal_gap 0.5)
			(thermal_bridge_width 0.5)
			(island_removal_mode 0)
		)
		(polygon
			(pts
				(arc
					(start 101.11613 -278.13635)
					(mid 100.48621 -278.13635)
					(end 101.11613 -278.13635)
				)
			)
		)
	)
	(zone
		(layers "B.Cu" "In13.Cu" "In15.Cu")
		(hatch none 0.5)
		(connect_pads
			(clearance 0)
		)
		(min_thickness 0.25)
		(keepout
			(tracks not_allowed)
			(vias allowed)
			(pads allowed)
			(copperpour not_allowed)
			(footprints allowed)
		)
		(placement
			(enabled no)
			(sheetname "")
		)
		(fill yes
			(thermal_gap 0.5)
			(thermal_bridge_width 0.5)
			(island_removal_mode 0)
		)
		(polygon
			(pts
				(arc
					(start 454.522078 -227.085144)
					(mid 453.854058 -227.085144)
					(end 454.522078 -227.085144)
				)
			)
		)
	)
	(zone
		(layers "B.Cu" "In13.Cu" "In15.Cu")
		(hatch none 0.5)
		(connect_pads
			(clearance 0)
		)
		(min_thickness 0.25)
		(keepout
			(tracks not_allowed)
			(vias allowed)
			(pads allowed)
			(copperpour not_allowed)
			(footprints allowed)
		)
		(placement
			(enabled no)
			(sheetname "")
		)
		(fill yes
			(thermal_gap 0.5)
			(thermal_bridge_width 0.5)
			(island_removal_mode 0)
		)
		(polygon
			(pts
				(arc
					(start 454.522078 -247.485154)
					(mid 453.854058 -247.485154)
					(end 454.522078 -247.485154)
				)
			)
		)
	)
	(zone
		(layers "B.Cu" "In13.Cu" "In15.Cu")
		(hatch none 0.5)
		(connect_pads
			(clearance 0)
		)
		(min_thickness 0.25)
		(keepout
			(tracks not_allowed)
			(vias allowed)
			(pads allowed)
			(copperpour not_allowed)
			(footprints allowed)
		)
		(placement
			(enabled no)
			(sheetname "")
		)
		(fill yes
			(thermal_gap 0.5)
			(thermal_bridge_width 0.5)
			(island_removal_mode 0)
		)
		(polygon
			(pts
				(arc
					(start 122.429778 -236.384338)
					(mid 121.799858 -236.384338)
					(end 122.429778 -236.384338)
				)
			)
		)
	)
	(zone
		(layers "B.Cu" "In13.Cu" "In15.Cu")
		(hatch none 0.5)
		(connect_pads
			(clearance 0)
		)
		(min_thickness 0.25)
		(keepout
			(tracks not_allowed)
			(vias allowed)
			(pads allowed)
			(copperpour not_allowed)
			(footprints allowed)
		)
		(placement
			(enabled no)
			(sheetname "")
		)
		(fill yes
			(thermal_gap 0.5)
			(thermal_bridge_width 0.5)
			(island_removal_mode 0)
		)
		(polygon
			(pts
				(arc
					(start 265.88212 -295.085008)
					(mid 265.2141 -295.085008)
					(end 265.88212 -295.085008)
				)
			)
		)
	)
	(zone
		(layers "B.Cu" "In13.Cu" "In15.Cu")
		(hatch none 0.5)
		(connect_pads
			(clearance 0)
		)
		(min_thickness 0.25)
		(keepout
			(tracks not_allowed)
			(vias allowed)
			(pads allowed)
			(copperpour not_allowed)
			(footprints allowed)
		)
		(placement
			(enabled no)
			(sheetname "")
		)
		(fill yes
			(thermal_gap 0.5)
			(thermal_bridge_width 0.5)
			(island_removal_mode 0)
		)
		(polygon
			(pts
				(arc
					(start 371.609874 -274.896072)
					(mid 370.979954 -274.896072)
					(end 371.609874 -274.896072)
				)
			)
		)
	)
	(zone
		(layers "B.Cu" "In13.Cu" "In15.Cu")
		(hatch none 0.5)
		(connect_pads
			(clearance 0)
		)
		(min_thickness 0.25)
		(keepout
			(tracks not_allowed)
			(vias allowed)
			(pads allowed)
			(copperpour not_allowed)
			(footprints allowed)
		)
		(placement
			(enabled no)
			(sheetname "")
		)
		(fill yes
			(thermal_gap 0.5)
			(thermal_bridge_width 0.5)
			(island_removal_mode 0)
		)
		(polygon
			(pts
				(arc
					(start 22.04212 -267.885418)
					(mid 21.3741 -267.885418)
					(end 22.04212 -267.885418)
				)
			)
		)
	)
	(zone
		(layers "B.Cu" "In13.Cu" "In15.Cu")
		(hatch none 0.5)
		(connect_pads
			(clearance 0)
		)
		(min_thickness 0.25)
		(keepout
			(tracks not_allowed)
			(vias allowed)
			(pads allowed)
			(copperpour not_allowed)
			(footprints allowed)
		)
		(placement
			(enabled no)
			(sheetname "")
		)
		(fill yes
			(thermal_gap 0.5)
			(thermal_bridge_width 0.5)
			(island_removal_mode 0)
		)
		(polygon
			(pts
				(arc
					(start 427.637956 -4.963414)
					(mid 426.969936 -4.963414)
					(end 427.637956 -4.963414)
				)
			)
		)
	)
	(zone
		(layers "B.Cu" "In13.Cu" "In15.Cu")
		(hatch none 0.5)
		(connect_pads
			(clearance 0)
		)
		(min_thickness 0.25)
		(keepout
			(tracks not_allowed)
			(vias allowed)
			(pads allowed)
			(copperpour not_allowed)
			(footprints allowed)
		)
		(placement
			(enabled no)
			(sheetname "")
		)
		(fill yes
			(thermal_gap 0.5)
			(thermal_bridge_width 0.5)
			(island_removal_mode 0)
		)
		(polygon
			(pts
				(arc
					(start 394.711682 -388.742428)
					(mid 394.043662 -388.742428)
					(end 394.711682 -388.742428)
				)
			)
		)
	)
	(zone
		(layers "B.Cu" "In13.Cu" "In15.Cu")
		(hatch none 0.5)
		(connect_pads
			(clearance 0)
		)
		(min_thickness 0.25)
		(keepout
			(tracks not_allowed)
			(vias allowed)
			(pads allowed)
			(copperpour not_allowed)
			(footprints allowed)
		)
		(placement
			(enabled no)
			(sheetname "")
		)
		(fill yes
			(thermal_gap 0.5)
			(thermal_bridge_width 0.5)
			(island_removal_mode 0)
		)
		(polygon
			(pts
				(arc
					(start 396.136876 -430.689766)
					(mid 395.362684 -430.689766)
					(end 396.136876 -430.689766)
				)
			)
		)
	)
	(zone
		(layers "B.Cu" "In13.Cu" "In15.Cu")
		(hatch none 0.5)
		(connect_pads
			(clearance 0)
		)
		(min_thickness 0.25)
		(keepout
			(tracks not_allowed)
			(vias allowed)
			(pads allowed)
			(copperpour not_allowed)
			(footprints allowed)
		)
		(placement
			(enabled no)
			(sheetname "")
		)
		(fill yes
			(thermal_gap 0.5)
			(thermal_bridge_width 0.5)
			(island_removal_mode 0)
		)
		(polygon
			(pts
				(arc
					(start 84.3661 -227.474526)
					(mid 83.73618 -227.474526)
					(end 84.3661 -227.474526)
				)
			)
		)
	)
	(zone
		(layers "B.Cu" "In13.Cu" "In15.Cu")
		(hatch none 0.5)
		(connect_pads
			(clearance 0)
		)
		(min_thickness 0.25)
		(keepout
			(tracks not_allowed)
			(vias allowed)
			(pads allowed)
			(copperpour not_allowed)
			(footprints allowed)
		)
		(placement
			(enabled no)
			(sheetname "")
		)
		(fill yes
			(thermal_gap 0.5)
			(thermal_bridge_width 0.5)
			(island_removal_mode 0)
		)
		(polygon
			(pts
				(arc
					(start 86.076028 -292.716204)
					(mid 85.446108 -292.716204)
					(end 86.076028 -292.716204)
				)
			)
		)
	)
	(zone
		(layers "B.Cu" "In13.Cu" "In15.Cu")
		(hatch none 0.5)
		(connect_pads
			(clearance 0)
		)
		(min_thickness 0.25)
		(keepout
			(tracks not_allowed)
			(vias allowed)
			(pads allowed)
			(copperpour not_allowed)
			(footprints allowed)
		)
		(placement
			(enabled no)
			(sheetname "")
		)
		(fill yes
			(thermal_gap 0.5)
			(thermal_bridge_width 0.5)
			(island_removal_mode 0)
		)
		(polygon
			(pts
				(arc
					(start 84.836 -239.624362)
					(mid 84.20608 -239.624362)
					(end 84.836 -239.624362)
				)
			)
		)
	)
	(zone
		(layers "B.Cu" "In13.Cu" "In15.Cu")
		(hatch none 0.5)
		(connect_pads
			(clearance 0)
		)
		(min_thickness 0.25)
		(keepout
			(tracks not_allowed)
			(vias allowed)
			(pads allowed)
			(copperpour not_allowed)
			(footprints allowed)
		)
		(placement
			(enabled no)
			(sheetname "")
		)
		(fill yes
			(thermal_gap 0.5)
			(thermal_bridge_width 0.5)
			(island_removal_mode 0)
		)
		(polygon
			(pts
				(arc
					(start 450.42201 -199.885046)
					(mid 449.75399 -199.885046)
					(end 450.42201 -199.885046)
				)
			)
		)
	)
	(zone
		(layers "B.Cu" "In13.Cu" "In15.Cu")
		(hatch none 0.5)
		(connect_pads
			(clearance 0)
		)
		(min_thickness 0.25)
		(keepout
			(tracks not_allowed)
			(vias allowed)
			(pads allowed)
			(copperpour not_allowed)
			(footprints allowed)
		)
		(placement
			(enabled no)
			(sheetname "")
		)
		(fill yes
			(thermal_gap 0.5)
			(thermal_bridge_width 0.5)
			(island_removal_mode 0)
		)
		(polygon
			(pts
				(arc
					(start 139.649708 -282.996386)
					(mid 139.019788 -282.996386)
					(end 139.649708 -282.996386)
				)
			)
		)
	)
	(zone
		(layers "B.Cu" "In13.Cu" "In15.Cu")
		(hatch none 0.5)
		(connect_pads
			(clearance 0)
		)
		(min_thickness 0.25)
		(keepout
			(tracks not_allowed)
			(vias allowed)
			(pads allowed)
			(copperpour not_allowed)
			(footprints allowed)
		)
		(placement
			(enabled no)
			(sheetname "")
		)
		(fill yes
			(thermal_gap 0.5)
			(thermal_bridge_width 0.5)
			(island_removal_mode 0)
		)
		(polygon
			(pts
				(arc
					(start 269.982188 -252.584966)
					(mid 269.314168 -252.584966)
					(end 269.982188 -252.584966)
				)
			)
		)
	)
	(zone
		(layers "B.Cu" "In13.Cu" "In15.Cu")
		(hatch none 0.5)
		(connect_pads
			(clearance 0)
		)
		(min_thickness 0.25)
		(keepout
			(tracks not_allowed)
			(vias allowed)
			(pads allowed)
			(copperpour not_allowed)
			(footprints allowed)
		)
		(placement
			(enabled no)
			(sheetname "")
		)
		(fill yes
			(thermal_gap 0.5)
			(thermal_bridge_width 0.5)
			(island_removal_mode 0)
		)
		(polygon
			(pts
				(arc
					(start 269.982188 -313.784996)
					(mid 269.314168 -313.784996)
					(end 269.982188 -313.784996)
				)
			)
		)
	)
	(zone
		(layers "B.Cu" "In13.Cu" "In15.Cu")
		(hatch none 0.5)
		(connect_pads
			(clearance 0)
		)
		(min_thickness 0.25)
		(keepout
			(tracks not_allowed)
			(vias allowed)
			(pads allowed)
			(copperpour not_allowed)
			(footprints allowed)
		)
		(placement
			(enabled no)
			(sheetname "")
		)
		(fill yes
			(thermal_gap 0.5)
			(thermal_bridge_width 0.5)
			(island_removal_mode 0)
		)
		(polygon
			(pts
				(arc
					(start 386.349748 -246.104156)
					(mid 385.719828 -246.104156)
					(end 386.349748 -246.104156)
				)
			)
		)
	)
	(zone
		(layers "B.Cu" "In13.Cu" "In15.Cu")
		(hatch none 0.5)
		(connect_pads
			(clearance 0)
		)
		(min_thickness 0.25)
		(keepout
			(tracks not_allowed)
			(vias allowed)
			(pads allowed)
			(copperpour not_allowed)
			(footprints allowed)
		)
		(placement
			(enabled no)
			(sheetname "")
		)
		(fill yes
			(thermal_gap 0.5)
			(thermal_bridge_width 0.5)
			(island_removal_mode 0)
		)
		(polygon
			(pts
				(arc
					(start 332.776068 -239.624108)
					(mid 332.146148 -239.624108)
					(end 332.776068 -239.624108)
				)
			)
		)
	)
	(zone
		(layers "B.Cu" "In13.Cu" "In15.Cu")
		(hatch none 0.5)
		(connect_pads
			(clearance 0)
		)
		(min_thickness 0.25)
		(keepout
			(tracks not_allowed)
			(vias allowed)
			(pads allowed)
			(copperpour not_allowed)
			(footprints allowed)
		)
		(placement
			(enabled no)
			(sheetname "")
		)
		(fill yes
			(thermal_gap 0.5)
			(thermal_bridge_width 0.5)
			(island_removal_mode 0)
		)
		(polygon
			(pts
				(arc
					(start 139.349734 -254.20447)
					(mid 138.719814 -254.20447)
					(end 139.349734 -254.20447)
				)
			)
		)
	)
	(zone
		(layers "B.Cu" "In13.Cu" "In15.Cu")
		(hatch none 0.5)
		(connect_pads
			(clearance 0)
		)
		(min_thickness 0.25)
		(keepout
			(tracks not_allowed)
			(vias allowed)
			(pads allowed)
			(copperpour not_allowed)
			(footprints allowed)
		)
		(placement
			(enabled no)
			(sheetname "")
		)
		(fill yes
			(thermal_gap 0.5)
			(thermal_bridge_width 0.5)
			(island_removal_mode 0)
		)
		(polygon
			(pts
				(arc
					(start 206.58201 -234.73537)
					(mid 205.91399 -234.73537)
					(end 206.58201 -234.73537)
				)
			)
		)
	)
	(zone
		(layers "B.Cu" "In13.Cu" "In15.Cu")
		(hatch none 0.5)
		(connect_pads
			(clearance 0)
		)
		(min_thickness 0.25)
		(keepout
			(tracks not_allowed)
			(vias allowed)
			(pads allowed)
			(copperpour not_allowed)
			(footprints allowed)
		)
		(placement
			(enabled no)
			(sheetname "")
		)
		(fill yes
			(thermal_gap 0.5)
			(thermal_bridge_width 0.5)
			(island_removal_mode 0)
		)
		(polygon
			(pts
				(arc
					(start 206.58201 -227.085398)
					(mid 205.91399 -227.085398)
					(end 206.58201 -227.085398)
				)
			)
		)
	)
	(zone
		(layers "B.Cu" "In13.Cu" "In15.Cu")
		(hatch none 0.5)
		(connect_pads
			(clearance 0)
		)
		(min_thickness 0.25)
		(keepout
			(tracks not_allowed)
			(vias allowed)
			(pads allowed)
			(copperpour not_allowed)
			(footprints allowed)
		)
		(placement
			(enabled no)
			(sheetname "")
		)
		(fill yes
			(thermal_gap 0.5)
			(thermal_bridge_width 0.5)
			(island_removal_mode 0)
		)
		(polygon
			(pts
				(arc
					(start 123.225306 -373.96293)
					(mid 122.557286 -373.96293)
					(end 123.225306 -373.96293)
				)
			)
		)
	)
	(zone
		(layers "B.Cu" "In13.Cu" "In15.Cu")
		(hatch none 0.5)
		(connect_pads
			(clearance 0)
		)
		(min_thickness 0.25)
		(keepout
			(tracks not_allowed)
			(vias allowed)
			(pads allowed)
			(copperpour not_allowed)
			(footprints allowed)
		)
		(placement
			(enabled no)
			(sheetname "")
		)
		(fill yes
			(thermal_gap 0.5)
			(thermal_bridge_width 0.5)
			(island_removal_mode 0)
		)
		(polygon
			(pts
				(arc
					(start 385.879848 -238.814102)
					(mid 385.249928 -238.814102)
					(end 385.879848 -238.814102)
				)
			)
		)
	)
	(zone
		(layers "B.Cu" "In13.Cu" "In15.Cu")
		(hatch none 0.5)
		(connect_pads
			(clearance 0)
		)
		(min_thickness 0.25)
		(keepout
			(tracks not_allowed)
			(vias allowed)
			(pads allowed)
			(copperpour not_allowed)
			(footprints allowed)
		)
		(placement
			(enabled no)
			(sheetname "")
		)
		(fill yes
			(thermal_gap 0.5)
			(thermal_bridge_width 0.5)
			(island_removal_mode 0)
		)
		(polygon
			(pts
				(arc
					(start 86.245954 -235.574332)
					(mid 85.616034 -235.574332)
					(end 86.245954 -235.574332)
				)
			)
		)
	)
	(zone
		(layers "B.Cu" "In13.Cu" "In15.Cu")
		(hatch none 0.5)
		(connect_pads
			(clearance 0)
		)
		(min_thickness 0.25)
		(keepout
			(tracks not_allowed)
			(vias allowed)
			(pads allowed)
			(copperpour not_allowed)
			(footprints allowed)
		)
		(placement
			(enabled no)
			(sheetname "")
		)
		(fill yes
			(thermal_gap 0.5)
			(thermal_bridge_width 0.5)
			(island_removal_mode 0)
		)
		(polygon
			(pts
				(arc
					(start 341.750396 -420.952168)
					(mid 341.082376 -420.952168)
					(end 341.750396 -420.952168)
				)
			)
		)
	)
	(zone
		(layers "B.Cu" "In13.Cu" "In15.Cu")
		(hatch none 0.5)
		(connect_pads
			(clearance 0)
		)
		(min_thickness 0.25)
		(keepout
			(tracks not_allowed)
			(vias allowed)
			(pads allowed)
			(copperpour not_allowed)
			(footprints allowed)
		)
		(placement
			(enabled no)
			(sheetname "")
		)
		(fill yes
			(thermal_gap 0.5)
			(thermal_bridge_width 0.5)
			(island_removal_mode 0)
		)
		(polygon
			(pts
				(arc
					(start 388.059676 -283.806138)
					(mid 387.429756 -283.806138)
					(end 388.059676 -283.806138)
				)
			)
		)
	)
	(zone
		(layers "B.Cu" "In13.Cu" "In15.Cu")
		(hatch none 0.5)
		(connect_pads
			(clearance 0)
		)
		(min_thickness 0.25)
		(keepout
			(tracks not_allowed)
			(vias allowed)
			(pads allowed)
			(copperpour not_allowed)
			(footprints allowed)
		)
		(placement
			(enabled no)
			(sheetname "")
		)
		(fill yes
			(thermal_gap 0.5)
			(thermal_bridge_width 0.5)
			(island_removal_mode 0)
		)
		(polygon
			(pts
				(arc
					(start 265.88212 -244.934994)
					(mid 265.2141 -244.934994)
					(end 265.88212 -244.934994)
				)
			)
		)
	)
	(zone
		(layers "B.Cu" "In13.Cu" "In15.Cu")
		(hatch none 0.5)
		(connect_pads
			(clearance 0)
		)
		(min_thickness 0.25)
		(keepout
			(tracks not_allowed)
			(vias allowed)
			(pads allowed)
			(copperpour not_allowed)
			(footprints allowed)
		)
		(placement
			(enabled no)
			(sheetname "")
		)
		(fill yes
			(thermal_gap 0.5)
			(thermal_bridge_width 0.5)
			(island_removal_mode 0)
		)
		(polygon
			(pts
				(arc
					(start 202.481942 -213.485222)
					(mid 201.813922 -213.485222)
					(end 202.481942 -213.485222)
				)
			)
		)
	)
	(zone
		(layers "B.Cu" "In13.Cu" "In15.Cu")
		(hatch none 0.5)
		(connect_pads
			(clearance 0)
		)
		(min_thickness 0.25)
		(keepout
			(tracks not_allowed)
			(vias allowed)
			(pads allowed)
			(copperpour not_allowed)
			(footprints allowed)
		)
		(placement
			(enabled no)
			(sheetname "")
		)
		(fill yes
			(thermal_gap 0.5)
			(thermal_bridge_width 0.5)
			(island_removal_mode 0)
		)
		(polygon
			(pts
				(arc
					(start 388.059676 -275.706078)
					(mid 387.429756 -275.706078)
					(end 388.059676 -275.706078)
				)
			)
		)
	)
	(zone
		(layers "B.Cu" "In13.Cu" "In15.Cu")
		(hatch none 0.5)
		(connect_pads
			(clearance 0)
		)
		(min_thickness 0.25)
		(keepout
			(tracks not_allowed)
			(vias allowed)
			(pads allowed)
			(copperpour not_allowed)
			(footprints allowed)
		)
		(placement
			(enabled no)
			(sheetname "")
		)
		(fill yes
			(thermal_gap 0.5)
			(thermal_bridge_width 0.5)
			(island_removal_mode 0)
		)
		(polygon
			(pts
				(arc
					(start 269.982188 -304.435002)
					(mid 269.314168 -304.435002)
					(end 269.982188 -304.435002)
				)
			)
		)
	)
	(zone
		(layers "B.Cu" "In13.Cu" "In15.Cu")
		(hatch none 0.5)
		(connect_pads
			(clearance 0)
		)
		(min_thickness 0.25)
		(keepout
			(tracks not_allowed)
			(vias allowed)
			(pads allowed)
			(copperpour not_allowed)
			(footprints allowed)
		)
		(placement
			(enabled no)
			(sheetname "")
		)
		(fill yes
			(thermal_gap 0.5)
			(thermal_bridge_width 0.5)
			(island_removal_mode 0)
		)
		(polygon
			(pts
				(arc
					(start 139.349734 -225.044508)
					(mid 138.719814 -225.044508)
					(end 139.349734 -225.044508)
				)
			)
		)
	)
	(zone
		(layers "B.Cu" "In13.Cu" "In15.Cu")
		(hatch none 0.5)
		(connect_pads
			(clearance 0)
		)
		(min_thickness 0.25)
		(keepout
			(tracks not_allowed)
			(vias allowed)
			(pads allowed)
			(copperpour not_allowed)
			(footprints allowed)
		)
		(placement
			(enabled no)
			(sheetname "")
		)
		(fill yes
			(thermal_gap 0.5)
			(thermal_bridge_width 0.5)
			(island_removal_mode 0)
		)
		(polygon
			(pts
				(arc
					(start 321.036696 -430.689766)
					(mid 320.262504 -430.689766)
					(end 321.036696 -430.689766)
				)
			)
		)
	)
	(zone
		(layers "B.Cu" "In13.Cu" "In15.Cu")
		(hatch none 0.5)
		(connect_pads
			(clearance 0)
		)
		(min_thickness 0.25)
		(keepout
			(tracks not_allowed)
			(vias allowed)
			(pads allowed)
			(copperpour not_allowed)
			(footprints allowed)
		)
		(placement
			(enabled no)
			(sheetname "")
		)
		(fill yes
			(thermal_gap 0.5)
			(thermal_bridge_width 0.5)
			(island_removal_mode 0)
		)
		(polygon
			(pts
				(arc
					(start 202.481942 -241.535204)
					(mid 201.813922 -241.535204)
					(end 202.481942 -241.535204)
				)
			)
		)
	)
	(zone
		(layers "B.Cu" "In13.Cu" "In15.Cu")
		(hatch none 0.5)
		(connect_pads
			(clearance 0)
		)
		(min_thickness 0.25)
		(keepout
			(tracks not_allowed)
			(vias allowed)
			(pads allowed)
			(copperpour not_allowed)
			(footprints allowed)
		)
		(placement
			(enabled no)
			(sheetname "")
		)
		(fill yes
			(thermal_gap 0.5)
			(thermal_bridge_width 0.5)
			(island_removal_mode 0)
		)
		(polygon
			(pts
				(arc
					(start 85.776054 -244.484398)
					(mid 85.146134 -244.484398)
					(end 85.776054 -244.484398)
				)
			)
		)
	)
	(zone
		(layers "B.Cu" "In13.Cu" "In15.Cu")
		(hatch none 0.5)
		(connect_pads
			(clearance 0)
		)
		(min_thickness 0.25)
		(keepout
			(tracks not_allowed)
			(vias allowed)
			(pads allowed)
			(copperpour not_allowed)
			(footprints allowed)
		)
		(placement
			(enabled no)
			(sheetname "")
		)
		(fill yes
			(thermal_gap 0.5)
			(thermal_bridge_width 0.5)
			(island_removal_mode 0)
		)
		(polygon
			(pts
				(arc
					(start 334.485996 -278.946102)
					(mid 333.856076 -278.946102)
					(end 334.485996 -278.946102)
				)
			)
		)
	)
	(zone
		(layers "B.Cu" "In13.Cu" "In15.Cu")
		(hatch none 0.5)
		(connect_pads
			(clearance 0)
		)
		(min_thickness 0.25)
		(keepout
			(tracks not_allowed)
			(vias allowed)
			(pads allowed)
			(copperpour not_allowed)
			(footprints allowed)
		)
		(placement
			(enabled no)
			(sheetname "")
		)
		(fill yes
			(thermal_gap 0.5)
			(thermal_bridge_width 0.5)
			(island_removal_mode 0)
		)
		(polygon
			(pts
				(arc
					(start 332.306168 -238.814102)
					(mid 331.676248 -238.814102)
					(end 332.306168 -238.814102)
				)
			)
		)
	)
	(zone
		(layers "B.Cu" "In13.Cu" "In15.Cu")
		(hatch none 0.5)
		(connect_pads
			(clearance 0)
		)
		(min_thickness 0.25)
		(keepout
			(tracks not_allowed)
			(vias allowed)
			(pads allowed)
			(copperpour not_allowed)
			(footprints allowed)
		)
		(placement
			(enabled no)
			(sheetname "")
		)
		(fill yes
			(thermal_gap 0.5)
			(thermal_bridge_width 0.5)
			(island_removal_mode 0)
		)
		(polygon
			(pts
				(arc
					(start 351.876106 -276.516084)
					(mid 351.246186 -276.516084)
					(end 351.876106 -276.516084)
				)
			)
		)
	)
	(zone
		(layers "B.Cu" "In13.Cu" "In15.Cu")
		(hatch none 0.5)
		(connect_pads
			(clearance 0)
		)
		(min_thickness 0.25)
		(keepout
			(tracks not_allowed)
			(vias allowed)
			(pads allowed)
			(copperpour not_allowed)
			(footprints allowed)
		)
		(placement
			(enabled no)
			(sheetname "")
		)
		(fill yes
			(thermal_gap 0.5)
			(thermal_bridge_width 0.5)
			(island_removal_mode 0)
		)
		(polygon
			(pts
				(arc
					(start 86.076028 -261.93623)
					(mid 85.446108 -261.93623)
					(end 86.076028 -261.93623)
				)
			)
		)
	)
	(zone
		(layers "B.Cu" "In13.Cu" "In15.Cu")
		(hatch none 0.5)
		(connect_pads
			(clearance 0)
		)
		(min_thickness 0.25)
		(keepout
			(tracks not_allowed)
			(vias allowed)
			(pads allowed)
			(copperpour not_allowed)
			(footprints allowed)
		)
		(placement
			(enabled no)
			(sheetname "")
		)
		(fill yes
			(thermal_gap 0.5)
			(thermal_bridge_width 0.5)
			(island_removal_mode 0)
		)
		(polygon
			(pts
				(arc
					(start 130.1369 -429.689768)
					(mid 129.362708 -429.689768)
					(end 130.1369 -429.689768)
				)
			)
		)
	)
	(zone
		(layers "B.Cu" "In13.Cu" "In15.Cu")
		(hatch none 0.5)
		(connect_pads
			(clearance 0)
		)
		(min_thickness 0.25)
		(keepout
			(tracks not_allowed)
			(vias allowed)
			(pads allowed)
			(copperpour not_allowed)
			(footprints allowed)
		)
		(placement
			(enabled no)
			(sheetname "")
		)
		(fill yes
			(thermal_gap 0.5)
			(thermal_bridge_width 0.5)
			(island_removal_mode 0)
		)
		(polygon
			(pts
				(arc
					(start 132.572506 -369.03533)
					(mid 131.904486 -369.03533)
					(end 132.572506 -369.03533)
				)
			)
		)
	)
	(zone
		(layers "B.Cu" "In13.Cu" "In15.Cu")
		(hatch none 0.5)
		(connect_pads
			(clearance 0)
		)
		(min_thickness 0.25)
		(keepout
			(tracks not_allowed)
			(vias allowed)
			(pads allowed)
			(copperpour not_allowed)
			(footprints allowed)
		)
		(placement
			(enabled no)
			(sheetname "")
		)
		(fill yes
			(thermal_gap 0.5)
			(thermal_bridge_width 0.5)
			(island_removal_mode 0)
		)
		(polygon
			(pts
				(arc
					(start 265.88212 -209.23504)
					(mid 265.2141 -209.23504)
					(end 265.88212 -209.23504)
				)
			)
		)
	)
	(zone
		(layers "B.Cu" "In13.Cu" "In15.Cu")
		(hatch none 0.5)
		(connect_pads
			(clearance 0)
		)
		(min_thickness 0.25)
		(keepout
			(tracks not_allowed)
			(vias allowed)
			(pads allowed)
			(copperpour not_allowed)
			(footprints allowed)
		)
		(placement
			(enabled no)
			(sheetname "")
		)
		(fill yes
			(thermal_gap 0.5)
			(thermal_bridge_width 0.5)
			(island_removal_mode 0)
		)
		(polygon
			(pts
				(arc
					(start 138.239754 -275.706332)
					(mid 137.609834 -275.706332)
					(end 138.239754 -275.706332)
				)
			)
		)
	)
	(zone
		(layers "B.Cu" "In13.Cu" "In15.Cu")
		(hatch none 0.5)
		(connect_pads
			(clearance 0)
		)
		(min_thickness 0.25)
		(keepout
			(tracks not_allowed)
			(vias allowed)
			(pads allowed)
			(copperpour not_allowed)
			(footprints allowed)
		)
		(placement
			(enabled no)
			(sheetname "")
		)
		(fill yes
			(thermal_gap 0.5)
			(thermal_bridge_width 0.5)
			(island_removal_mode 0)
		)
		(polygon
			(pts
				(arc
					(start 80.037178 -429.689768)
					(mid 79.262986 -429.689768)
					(end 80.037178 -429.689768)
				)
			)
		)
	)
	(zone
		(layers "B.Cu" "In13.Cu" "In15.Cu")
		(hatch none 0.5)
		(connect_pads
			(clearance 0)
		)
		(min_thickness 0.25)
		(keepout
			(tracks not_allowed)
			(vias allowed)
			(pads allowed)
			(copperpour not_allowed)
			(footprints allowed)
		)
		(placement
			(enabled no)
			(sheetname "")
		)
		(fill yes
			(thermal_gap 0.5)
			(thermal_bridge_width 0.5)
			(island_removal_mode 0)
		)
		(polygon
			(pts
				(arc
					(start 119.90959 -276.516338)
					(mid 119.27967 -276.516338)
					(end 119.90959 -276.516338)
				)
			)
		)
	)
	(zone
		(layers "B.Cu" "In13.Cu" "In15.Cu")
		(hatch none 0.5)
		(connect_pads
			(clearance 0)
		)
		(min_thickness 0.25)
		(keepout
			(tracks not_allowed)
			(vias allowed)
			(pads allowed)
			(copperpour not_allowed)
			(footprints allowed)
		)
		(placement
			(enabled no)
			(sheetname "")
		)
		(fill yes
			(thermal_gap 0.5)
			(thermal_bridge_width 0.5)
			(island_removal_mode 0)
		)
		(polygon
			(pts
				(arc
					(start 334.485996 -290.285932)
					(mid 333.856076 -290.285932)
					(end 334.485996 -290.285932)
				)
			)
		)
	)
	(zone
		(layers "B.Cu" "In13.Cu" "In15.Cu")
		(hatch none 0.5)
		(connect_pads
			(clearance 0)
		)
		(min_thickness 0.25)
		(keepout
			(tracks not_allowed)
			(vias allowed)
			(pads allowed)
			(copperpour not_allowed)
			(footprints allowed)
		)
		(placement
			(enabled no)
			(sheetname "")
		)
		(fill yes
			(thermal_gap 0.5)
			(thermal_bridge_width 0.5)
			(island_removal_mode 0)
		)
		(polygon
			(pts
				(arc
					(start 84.3661 -232.334308)
					(mid 83.73618 -232.334308)
					(end 84.3661 -232.334308)
				)
			)
		)
	)
	(zone
		(layers "B.Cu" "In13.Cu" "In15.Cu")
		(hatch none 0.5)
		(connect_pads
			(clearance 0)
		)
		(min_thickness 0.25)
		(keepout
			(tracks not_allowed)
			(vias allowed)
			(pads allowed)
			(copperpour not_allowed)
			(footprints allowed)
		)
		(placement
			(enabled no)
			(sheetname "")
		)
		(fill yes
			(thermal_gap 0.5)
			(thermal_bridge_width 0.5)
			(island_removal_mode 0)
		)
		(polygon
			(pts
				(arc
					(start 450.42201 -277.235158)
					(mid 449.75399 -277.235158)
					(end 450.42201 -277.235158)
				)
			)
		)
	)
	(zone
		(layers "B.Cu" "In13.Cu" "In15.Cu")
		(hatch none 0.5)
		(connect_pads
			(clearance 0)
		)
		(min_thickness 0.25)
		(keepout
			(tracks not_allowed)
			(vias allowed)
			(pads allowed)
			(copperpour not_allowed)
			(footprints allowed)
		)
		(placement
			(enabled no)
			(sheetname "")
		)
		(fill yes
			(thermal_gap 0.5)
			(thermal_bridge_width 0.5)
			(island_removal_mode 0)
		)
		(polygon
			(pts
				(arc
					(start 352.233738 -393.69238)
					(mid 351.603818 -393.69238)
					(end 352.233738 -393.69238)
				)
			)
		)
	)
	(zone
		(layers "B.Cu" "In13.Cu" "In15.Cu")
		(hatch none 0.5)
		(connect_pads
			(clearance 0)
		)
		(min_thickness 0.25)
		(keepout
			(tracks not_allowed)
			(vias allowed)
			(pads allowed)
			(copperpour not_allowed)
			(footprints allowed)
		)
		(placement
			(enabled no)
			(sheetname "")
		)
		(fill yes
			(thermal_gap 0.5)
			(thermal_bridge_width 0.5)
			(island_removal_mode 0)
		)
		(polygon
			(pts
				(arc
					(start 139.649708 -266.796266)
					(mid 139.019788 -266.796266)
					(end 139.649708 -266.796266)
				)
			)
		)
	)
	(zone
		(layers "B.Cu" "In13.Cu" "In15.Cu")
		(hatch none 0.5)
		(connect_pads
			(clearance 0)
		)
		(min_thickness 0.25)
		(keepout
			(tracks not_allowed)
			(vias allowed)
			(pads allowed)
			(copperpour not_allowed)
			(footprints allowed)
		)
		(placement
			(enabled no)
			(sheetname "")
		)
		(fill yes
			(thermal_gap 0.5)
			(thermal_bridge_width 0.5)
			(island_removal_mode 0)
		)
		(polygon
			(pts
				(arc
					(start 86.245954 -238.814356)
					(mid 85.616034 -238.814356)
					(end 86.245954 -238.814356)
				)
			)
		)
	)
	(zone
		(layers "B.Cu" "In13.Cu" "In15.Cu")
		(hatch none 0.5)
		(connect_pads
			(clearance 0)
		)
		(min_thickness 0.25)
		(keepout
			(tracks not_allowed)
			(vias allowed)
			(pads allowed)
			(copperpour not_allowed)
			(footprints allowed)
		)
		(placement
			(enabled no)
			(sheetname "")
		)
		(fill yes
			(thermal_gap 0.5)
			(thermal_bridge_width 0.5)
			(island_removal_mode 0)
		)
		(polygon
			(pts
				(arc
					(start 17.942052 -241.535204)
					(mid 17.274032 -241.535204)
					(end 17.942052 -241.535204)
				)
			)
		)
	)
	(zone
		(layers "B.Cu" "In13.Cu" "In15.Cu")
		(hatch none 0.5)
		(connect_pads
			(clearance 0)
		)
		(min_thickness 0.25)
		(keepout
			(tracks not_allowed)
			(vias allowed)
			(pads allowed)
			(copperpour not_allowed)
			(footprints allowed)
		)
		(placement
			(enabled no)
			(sheetname "")
		)
		(fill yes
			(thermal_gap 0.5)
			(thermal_bridge_width 0.5)
			(island_removal_mode 0)
		)
		(polygon
			(pts
				(arc
					(start 202.481942 -318.035432)
					(mid 201.813922 -318.035432)
					(end 202.481942 -318.035432)
				)
			)
		)
	)
	(zone
		(layers "B.Cu" "In13.Cu" "In15.Cu")
		(hatch none 0.5)
		(connect_pads
			(clearance 0)
		)
		(min_thickness 0.25)
		(keepout
			(tracks not_allowed)
			(vias allowed)
			(pads allowed)
			(copperpour not_allowed)
			(footprints allowed)
		)
		(placement
			(enabled no)
			(sheetname "")
		)
		(fill yes
			(thermal_gap 0.5)
			(thermal_bridge_width 0.5)
			(island_removal_mode 0)
		)
		(polygon
			(pts
				(arc
					(start 334.186022 -250.154186)
					(mid 333.556102 -250.154186)
					(end 334.186022 -250.154186)
				)
			)
		)
	)
	(zone
		(layers "B.Cu" "In13.Cu" "In15.Cu")
		(hatch none 0.5)
		(connect_pads
			(clearance 0)
		)
		(min_thickness 0.25)
		(keepout
			(tracks not_allowed)
			(vias allowed)
			(pads allowed)
			(copperpour not_allowed)
			(footprints allowed)
		)
		(placement
			(enabled no)
			(sheetname "")
		)
		(fill yes
			(thermal_gap 0.5)
			(thermal_bridge_width 0.5)
			(island_removal_mode 0)
		)
		(polygon
			(pts
				(arc
					(start 22.04212 -264.485374)
					(mid 21.3741 -264.485374)
					(end 22.04212 -264.485374)
				)
			)
		)
	)
	(zone
		(layers "B.Cu" "In13.Cu" "In15.Cu")
		(hatch none 0.5)
		(connect_pads
			(clearance 0)
		)
		(min_thickness 0.25)
		(keepout
			(tracks not_allowed)
			(vias allowed)
			(pads allowed)
			(copperpour not_allowed)
			(footprints allowed)
		)
		(placement
			(enabled no)
			(sheetname "")
		)
		(fill yes
			(thermal_gap 0.5)
			(thermal_bridge_width 0.5)
			(island_removal_mode 0)
		)
		(polygon
			(pts
				(arc
					(start 143.137128 -429.689768)
					(mid 142.362936 -429.689768)
					(end 143.137128 -429.689768)
				)
			)
		)
	)
	(zone
		(layers "B.Cu" "In13.Cu" "In15.Cu")
		(hatch none 0.5)
		(connect_pads
			(clearance 0)
		)
		(min_thickness 0.25)
		(keepout
			(tracks not_allowed)
			(vias allowed)
			(pads allowed)
			(copperpour not_allowed)
			(footprints allowed)
		)
		(placement
			(enabled no)
			(sheetname "")
		)
		(fill yes
			(thermal_gap 0.5)
			(thermal_bridge_width 0.5)
			(island_removal_mode 0)
		)
		(polygon
			(pts
				(arc
					(start 269.982188 -294.235124)
					(mid 269.314168 -294.235124)
					(end 269.982188 -294.235124)
				)
			)
		)
	)
	(zone
		(layers "B.Cu" "In13.Cu" "In15.Cu")
		(hatch none 0.5)
		(connect_pads
			(clearance 0)
		)
		(min_thickness 0.25)
		(keepout
			(tracks not_allowed)
			(vias allowed)
			(pads allowed)
			(copperpour not_allowed)
			(footprints allowed)
		)
		(placement
			(enabled no)
			(sheetname "")
		)
		(fill yes
			(thermal_gap 0.5)
			(thermal_bridge_width 0.5)
			(island_removal_mode 0)
		)
		(polygon
			(pts
				(arc
					(start 22.04212 -275.53539)
					(mid 21.3741 -275.53539)
					(end 22.04212 -275.53539)
				)
			)
		)
	)
	(zone
		(layers "B.Cu" "In13.Cu" "In15.Cu")
		(hatch none 0.5)
		(connect_pads
			(clearance 0)
		)
		(min_thickness 0.25)
		(keepout
			(tracks not_allowed)
			(vias allowed)
			(pads allowed)
			(copperpour not_allowed)
			(footprints allowed)
		)
		(placement
			(enabled no)
			(sheetname "")
		)
		(fill yes
			(thermal_gap 0.5)
			(thermal_bridge_width 0.5)
			(island_removal_mode 0)
		)
		(polygon
			(pts
				(arc
					(start 85.135974 -278.13635)
					(mid 84.506054 -278.13635)
					(end 85.135974 -278.13635)
				)
			)
		)
	)
	(zone
		(layers "B.Cu" "In13.Cu" "In15.Cu")
		(hatch none 0.5)
		(connect_pads
			(clearance 0)
		)
		(min_thickness 0.25)
		(keepout
			(tracks not_allowed)
			(vias allowed)
			(pads allowed)
			(copperpour not_allowed)
			(footprints allowed)
		)
		(placement
			(enabled no)
			(sheetname "")
		)
		(fill yes
			(thermal_gap 0.5)
			(thermal_bridge_width 0.5)
			(island_removal_mode 0)
		)
		(polygon
			(pts
				(arc
					(start 138.709654 -279.756362)
					(mid 138.079734 -279.756362)
					(end 138.709654 -279.756362)
				)
			)
		)
	)
	(zone
		(layers "B.Cu" "In13.Cu" "In15.Cu")
		(hatch none 0.5)
		(connect_pads
			(clearance 0)
		)
		(min_thickness 0.25)
		(keepout
			(tracks not_allowed)
			(vias allowed)
			(pads allowed)
			(copperpour not_allowed)
			(footprints allowed)
		)
		(placement
			(enabled no)
			(sheetname "")
		)
		(fill yes
			(thermal_gap 0.5)
			(thermal_bridge_width 0.5)
			(island_removal_mode 0)
		)
		(polygon
			(pts
				(arc
					(start 151.986996 -412.570168)
					(mid 151.318976 -412.570168)
					(end 151.986996 -412.570168)
				)
			)
		)
	)
	(zone
		(layers "B.Cu" "In13.Cu" "In15.Cu")
		(hatch none 0.5)
		(connect_pads
			(clearance 0)
		)
		(min_thickness 0.25)
		(keepout
			(tracks not_allowed)
			(vias allowed)
			(pads allowed)
			(copperpour not_allowed)
			(footprints allowed)
		)
		(placement
			(enabled no)
			(sheetname "")
		)
		(fill yes
			(thermal_gap 0.5)
			(thermal_bridge_width 0.5)
			(island_removal_mode 0)
		)
		(polygon
			(pts
				(arc
					(start 265.88212 -299.33519)
					(mid 265.2141 -299.33519)
					(end 265.88212 -299.33519)
				)
			)
		)
	)
	(zone
		(layers "B.Cu" "In13.Cu" "In15.Cu")
		(hatch none 0.5)
		(connect_pads
			(clearance 0)
		)
		(min_thickness 0.25)
		(keepout
			(tracks not_allowed)
			(vias allowed)
			(pads allowed)
			(copperpour not_allowed)
			(footprints allowed)
		)
		(placement
			(enabled no)
			(sheetname "")
		)
		(fill yes
			(thermal_gap 0.5)
			(thermal_bridge_width 0.5)
			(island_removal_mode 0)
		)
		(polygon
			(pts
				(arc
					(start 334.485996 -277.32609)
					(mid 333.856076 -277.32609)
					(end 334.485996 -277.32609)
				)
			)
		)
	)
	(zone
		(layers "B.Cu" "In13.Cu" "In15.Cu")
		(hatch none 0.5)
		(connect_pads
			(clearance 0)
		)
		(min_thickness 0.25)
		(keepout
			(tracks not_allowed)
			(vias allowed)
			(pads allowed)
			(copperpour not_allowed)
			(footprints allowed)
		)
		(placement
			(enabled no)
			(sheetname "")
		)
		(fill yes
			(thermal_gap 0.5)
			(thermal_bridge_width 0.5)
			(island_removal_mode 0)
		)
		(polygon
			(pts
				(arc
					(start 61.036962 -430.689766)
					(mid 60.26277 -430.689766)
					(end 61.036962 -430.689766)
				)
			)
		)
	)
	(zone
		(layers "B.Cu" "In13.Cu" "In15.Cu")
		(hatch none 0.5)
		(connect_pads
			(clearance 0)
		)
		(min_thickness 0.25)
		(keepout
			(tracks not_allowed)
			(vias allowed)
			(pads allowed)
			(copperpour not_allowed)
			(footprints allowed)
		)
		(placement
			(enabled no)
			(sheetname "")
		)
		(fill yes
			(thermal_gap 0.5)
			(thermal_bridge_width 0.5)
			(island_removal_mode 0)
		)
		(polygon
			(pts
				(arc
					(start 349.056198 -278.136096)
					(mid 348.426278 -278.136096)
					(end 349.056198 -278.136096)
				)
			)
		)
	)
	(zone
		(layers "B.Cu" "In13.Cu" "In15.Cu")
		(hatch none 0.5)
		(connect_pads
			(clearance 0)
		)
		(min_thickness 0.25)
		(keepout
			(tracks not_allowed)
			(vias allowed)
			(pads allowed)
			(copperpour not_allowed)
			(footprints allowed)
		)
		(placement
			(enabled no)
			(sheetname "")
		)
		(fill yes
			(thermal_gap 0.5)
			(thermal_bridge_width 0.5)
			(island_removal_mode 0)
		)
		(polygon
			(pts
				(arc
					(start 123.369578 -231.524302)
					(mid 122.739658 -231.524302)
					(end 123.369578 -231.524302)
				)
			)
		)
	)
	(zone
		(layers "B.Cu" "In13.Cu" "In15.Cu")
		(hatch none 0.5)
		(connect_pads
			(clearance 0)
		)
		(min_thickness 0.25)
		(keepout
			(tracks not_allowed)
			(vias allowed)
			(pads allowed)
			(copperpour not_allowed)
			(footprints allowed)
		)
		(placement
			(enabled no)
			(sheetname "")
		)
		(fill yes
			(thermal_gap 0.5)
			(thermal_bridge_width 0.5)
			(island_removal_mode 0)
		)
		(polygon
			(pts
				(arc
					(start 346.0369 -431.889916)
					(mid 345.262708 -431.889916)
					(end 346.0369 -431.889916)
				)
			)
		)
	)
	(zone
		(layers "B.Cu" "In13.Cu" "In15.Cu")
		(hatch none 0.5)
		(connect_pads
			(clearance 0)
		)
		(min_thickness 0.25)
		(keepout
			(tracks not_allowed)
			(vias allowed)
			(pads allowed)
			(copperpour not_allowed)
			(footprints allowed)
		)
		(placement
			(enabled no)
			(sheetname "")
		)
		(fill yes
			(thermal_gap 0.5)
			(thermal_bridge_width 0.5)
			(island_removal_mode 0)
		)
		(polygon
			(pts
				(arc
					(start 373.189754 -244.484144)
					(mid 372.559834 -244.484144)
					(end 373.189754 -244.484144)
				)
			)
		)
	)
	(zone
		(layers "B.Cu" "In13.Cu" "In15.Cu")
		(hatch none 0.5)
		(connect_pads
			(clearance 0)
		)
		(min_thickness 0.25)
		(keepout
			(tracks not_allowed)
			(vias allowed)
			(pads allowed)
			(copperpour not_allowed)
			(footprints allowed)
		)
		(placement
			(enabled no)
			(sheetname "")
		)
		(fill yes
			(thermal_gap 0.5)
			(thermal_bridge_width 0.5)
			(island_removal_mode 0)
		)
		(polygon
			(pts
				(arc
					(start 22.04212 -225.385376)
					(mid 21.3741 -225.385376)
					(end 22.04212 -225.385376)
				)
			)
		)
	)
	(zone
		(layers "B.Cu" "In13.Cu" "In15.Cu")
		(hatch none 0.5)
		(connect_pads
			(clearance 0)
		)
		(min_thickness 0.25)
		(keepout
			(tracks not_allowed)
			(vias allowed)
			(pads allowed)
			(copperpour not_allowed)
			(footprints allowed)
		)
		(placement
			(enabled no)
			(sheetname "")
		)
		(fill yes
			(thermal_gap 0.5)
			(thermal_bridge_width 0.5)
			(island_removal_mode 0)
		)
		(polygon
			(pts
				(arc
					(start 157.1371 -430.689766)
					(mid 156.362908 -430.689766)
					(end 157.1371 -430.689766)
				)
			)
		)
	)
	(zone
		(layers "B.Cu" "In13.Cu" "In15.Cu")
		(hatch none 0.5)
		(connect_pads
			(clearance 0)
		)
		(min_thickness 0.25)
		(keepout
			(tracks not_allowed)
			(vias allowed)
			(pads allowed)
			(copperpour not_allowed)
			(footprints allowed)
		)
		(placement
			(enabled no)
			(sheetname "")
		)
		(fill yes
			(thermal_gap 0.5)
			(thermal_bridge_width 0.5)
			(island_removal_mode 0)
		)
		(polygon
			(pts
				(arc
					(start 155.137104 -430.889918)
					(mid 154.362912 -430.889918)
					(end 155.137104 -430.889918)
				)
			)
		)
	)
	(zone
		(layers "B.Cu" "In13.Cu" "In15.Cu")
		(hatch none 0.5)
		(connect_pads
			(clearance 0)
		)
		(min_thickness 0.25)
		(keepout
			(tracks not_allowed)
			(vias allowed)
			(pads allowed)
			(copperpour not_allowed)
			(footprints allowed)
		)
		(placement
			(enabled no)
			(sheetname "")
		)
		(fill yes
			(thermal_gap 0.5)
			(thermal_bridge_width 0.5)
			(island_removal_mode 0)
		)
		(polygon
			(pts
				(arc
					(start 265.88212 -210.935062)
					(mid 265.2141 -210.935062)
					(end 265.88212 -210.935062)
				)
			)
		)
	)
	(zone
		(layers "B.Cu" "In13.Cu" "In15.Cu")
		(hatch none 0.5)
		(connect_pads
			(clearance 0)
		)
		(min_thickness 0.25)
		(keepout
			(tracks not_allowed)
			(vias allowed)
			(pads allowed)
			(copperpour not_allowed)
			(footprints allowed)
		)
		(placement
			(enabled no)
			(sheetname "")
		)
		(fill yes
			(thermal_gap 0.5)
			(thermal_bridge_width 0.5)
			(island_removal_mode 0)
		)
		(polygon
			(pts
				(arc
					(start 327.036684 -429.689768)
					(mid 326.262492 -429.689768)
					(end 327.036684 -429.689768)
				)
			)
		)
	)
	(zone
		(layers "B.Cu" "In13.Cu" "In15.Cu")
		(hatch none 0.5)
		(connect_pads
			(clearance 0)
		)
		(min_thickness 0.25)
		(keepout
			(tracks not_allowed)
			(vias allowed)
			(pads allowed)
			(copperpour not_allowed)
			(footprints allowed)
		)
		(placement
			(enabled no)
			(sheetname "")
		)
		(fill yes
			(thermal_gap 0.5)
			(thermal_bridge_width 0.5)
			(island_removal_mode 0)
		)
		(polygon
			(pts
				(arc
					(start 334.186022 -253.39421)
					(mid 333.556102 -253.39421)
					(end 334.186022 -253.39421)
				)
			)
		)
	)
	(zone
		(layers "B.Cu" "In13.Cu" "In15.Cu")
		(hatch none 0.5)
		(connect_pads
			(clearance 0)
		)
		(min_thickness 0.25)
		(keepout
			(tracks not_allowed)
			(vias allowed)
			(pads allowed)
			(copperpour not_allowed)
			(footprints allowed)
		)
		(placement
			(enabled no)
			(sheetname "")
		)
		(fill yes
			(thermal_gap 0.5)
			(thermal_bridge_width 0.5)
			(island_removal_mode 0)
		)
		(polygon
			(pts
				(arc
					(start 127.481076 -412.570168)
					(mid 126.813056 -412.570168)
					(end 127.481076 -412.570168)
				)
			)
		)
	)
	(zone
		(layers "B.Cu" "In13.Cu" "In15.Cu")
		(hatch none 0.5)
		(connect_pads
			(clearance 0)
		)
		(min_thickness 0.25)
		(keepout
			(tracks not_allowed)
			(vias allowed)
			(pads allowed)
			(copperpour not_allowed)
			(footprints allowed)
		)
		(placement
			(enabled no)
			(sheetname "")
		)
		(fill yes
			(thermal_gap 0.5)
			(thermal_bridge_width 0.5)
			(island_removal_mode 0)
		)
		(polygon
			(pts
				(arc
					(start 269.982188 -287.435036)
					(mid 269.314168 -287.435036)
					(end 269.982188 -287.435036)
				)
			)
		)
	)
	(zone
		(layers "B.Cu" "In13.Cu" "In15.Cu")
		(hatch none 0.5)
		(connect_pads
			(clearance 0)
		)
		(min_thickness 0.25)
		(keepout
			(tracks not_allowed)
			(vias allowed)
			(pads allowed)
			(copperpour not_allowed)
			(footprints allowed)
		)
		(placement
			(enabled no)
			(sheetname "")
		)
		(fill yes
			(thermal_gap 0.5)
			(thermal_bridge_width 0.5)
			(island_removal_mode 0)
		)
		(polygon
			(pts
				(arc
					(start 365.02975 -279.756108)
					(mid 364.39983 -279.756108)
					(end 365.02975 -279.756108)
				)
			)
		)
	)
	(zone
		(layers "B.Cu" "In13.Cu" "In15.Cu")
		(hatch none 0.5)
		(connect_pads
			(clearance 0)
		)
		(min_thickness 0.25)
		(keepout
			(tracks not_allowed)
			(vias allowed)
			(pads allowed)
			(copperpour not_allowed)
			(footprints allowed)
		)
		(placement
			(enabled no)
			(sheetname "")
		)
		(fill yes
			(thermal_gap 0.5)
			(thermal_bridge_width 0.5)
			(island_removal_mode 0)
		)
		(polygon
			(pts
				(arc
					(start 388.059676 -264.365994)
					(mid 387.429756 -264.365994)
					(end 388.059676 -264.365994)
				)
			)
		)
	)
	(zone
		(layers "B.Cu" "In13.Cu" "In15.Cu")
		(hatch none 0.5)
		(connect_pads
			(clearance 0)
		)
		(min_thickness 0.25)
		(keepout
			(tracks not_allowed)
			(vias allowed)
			(pads allowed)
			(copperpour not_allowed)
			(footprints allowed)
		)
		(placement
			(enabled no)
			(sheetname "")
		)
		(fill yes
			(thermal_gap 0.5)
			(thermal_bridge_width 0.5)
			(island_removal_mode 0)
		)
		(polygon
			(pts
				(arc
					(start 202.481942 -246.63527)
					(mid 201.813922 -246.63527)
					(end 202.481942 -246.63527)
				)
			)
		)
	)
	(zone
		(layers "B.Cu" "In13.Cu" "In15.Cu")
		(hatch none 0.5)
		(connect_pads
			(clearance 0)
		)
		(min_thickness 0.25)
		(keepout
			(tracks not_allowed)
			(vias allowed)
			(pads allowed)
			(copperpour not_allowed)
			(footprints allowed)
		)
		(placement
			(enabled no)
			(sheetname "")
		)
		(fill yes
			(thermal_gap 0.5)
			(thermal_bridge_width 0.5)
			(island_removal_mode 0)
		)
		(polygon
			(pts
				(arc
					(start 354.633784 -393.69238)
					(mid 354.003864 -393.69238)
					(end 354.633784 -393.69238)
				)
			)
		)
	)
	(zone
		(layers "B.Cu" "In13.Cu" "In15.Cu")
		(hatch none 0.5)
		(connect_pads
			(clearance 0)
		)
		(min_thickness 0.25)
		(keepout
			(tracks not_allowed)
			(vias allowed)
			(pads allowed)
			(copperpour not_allowed)
			(footprints allowed)
		)
		(placement
			(enabled no)
			(sheetname "")
		)
		(fill yes
			(thermal_gap 0.5)
			(thermal_bridge_width 0.5)
			(island_removal_mode 0)
		)
		(polygon
			(pts
				(arc
					(start 138.40968 -231.524302)
					(mid 137.77976 -231.524302)
					(end 138.40968 -231.524302)
				)
			)
		)
	)
	(zone
		(layers "B.Cu" "In13.Cu" "In15.Cu")
		(hatch none 0.5)
		(connect_pads
			(clearance 0)
		)
		(min_thickness 0.25)
		(keepout
			(tracks not_allowed)
			(vias allowed)
			(pads allowed)
			(copperpour not_allowed)
			(footprints allowed)
		)
		(placement
			(enabled no)
			(sheetname "")
		)
		(fill yes
			(thermal_gap 0.5)
			(thermal_bridge_width 0.5)
			(island_removal_mode 0)
		)
		(polygon
			(pts
				(arc
					(start 137.93978 -240.434368)
					(mid 137.30986 -240.434368)
					(end 137.93978 -240.434368)
				)
			)
		)
	)
	(zone
		(layers "B.Cu" "In13.Cu" "In15.Cu")
		(hatch none 0.5)
		(connect_pads
			(clearance 0)
		)
		(min_thickness 0.25)
		(keepout
			(tracks not_allowed)
			(vias allowed)
			(pads allowed)
			(copperpour not_allowed)
			(footprints allowed)
		)
		(placement
			(enabled no)
			(sheetname "")
		)
		(fill yes
			(thermal_gap 0.5)
			(thermal_bridge_width 0.5)
			(island_removal_mode 0)
		)
		(polygon
			(pts
				(arc
					(start 202.481942 -232.18521)
					(mid 201.813922 -232.18521)
					(end 202.481942 -232.18521)
				)
			)
		)
	)
	(zone
		(layers "B.Cu" "In13.Cu" "In15.Cu")
		(hatch none 0.5)
		(connect_pads
			(clearance 0)
		)
		(min_thickness 0.25)
		(keepout
			(tracks not_allowed)
			(vias allowed)
			(pads allowed)
			(copperpour not_allowed)
			(footprints allowed)
		)
		(placement
			(enabled no)
			(sheetname "")
		)
		(fill yes
			(thermal_gap 0.5)
			(thermal_bridge_width 0.5)
			(island_removal_mode 0)
		)
		(polygon
			(pts
				(arc
					(start 86.076028 -276.516338)
					(mid 85.446108 -276.516338)
					(end 86.076028 -276.516338)
				)
			)
		)
	)
	(zone
		(layers "B.Cu" "In13.Cu" "In15.Cu")
		(hatch none 0.5)
		(connect_pads
			(clearance 0)
		)
		(min_thickness 0.25)
		(keepout
			(tracks not_allowed)
			(vias allowed)
			(pads allowed)
			(copperpour not_allowed)
			(footprints allowed)
		)
		(placement
			(enabled no)
			(sheetname "")
		)
		(fill yes
			(thermal_gap 0.5)
			(thermal_bridge_width 0.5)
			(island_removal_mode 0)
		)
		(polygon
			(pts
				(arc
					(start 85.776054 -233.144314)
					(mid 85.146134 -233.144314)
					(end 85.776054 -233.144314)
				)
			)
		)
	)
	(zone
		(layers "B.Cu" "In13.Cu" "In15.Cu")
		(hatch none 0.5)
		(connect_pads
			(clearance 0)
		)
		(min_thickness 0.25)
		(keepout
			(tracks not_allowed)
			(vias allowed)
			(pads allowed)
			(copperpour not_allowed)
			(footprints allowed)
		)
		(placement
			(enabled no)
			(sheetname "")
		)
		(fill yes
			(thermal_gap 0.5)
			(thermal_bridge_width 0.5)
			(island_removal_mode 0)
		)
		(polygon
			(pts
				(arc
					(start 430.374298 -4.963414)
					(mid 429.706278 -4.963414)
					(end 430.374298 -4.963414)
				)
			)
		)
	)
	(zone
		(layers "B.Cu" "In13.Cu" "In15.Cu")
		(hatch none 0.5)
		(connect_pads
			(clearance 0)
		)
		(min_thickness 0.25)
		(keepout
			(tracks not_allowed)
			(vias allowed)
			(pads allowed)
			(copperpour not_allowed)
			(footprints allowed)
		)
		(placement
			(enabled no)
			(sheetname "")
		)
		(fill yes
			(thermal_gap 0.5)
			(thermal_bridge_width 0.5)
			(island_removal_mode 0)
		)
		(polygon
			(pts
				(arc
					(start 22.04212 -317.185294)
					(mid 21.3741 -317.185294)
					(end 22.04212 -317.185294)
				)
			)
		)
	)
	(zone
		(layers "B.Cu" "In13.Cu" "In15.Cu")
		(hatch none 0.5)
		(connect_pads
			(clearance 0)
		)
		(min_thickness 0.25)
		(keepout
			(tracks not_allowed)
			(vias allowed)
			(pads allowed)
			(copperpour not_allowed)
			(footprints allowed)
		)
		(placement
			(enabled no)
			(sheetname "")
		)
		(fill yes
			(thermal_gap 0.5)
			(thermal_bridge_width 0.5)
			(island_removal_mode 0)
		)
		(polygon
			(pts
				(arc
					(start 98.295968 -278.13635)
					(mid 97.666048 -278.13635)
					(end 98.295968 -278.13635)
				)
			)
		)
	)
	(zone
		(layers "B.Cu" "In13.Cu" "In15.Cu")
		(hatch none 0.5)
		(connect_pads
			(clearance 0)
		)
		(min_thickness 0.25)
		(keepout
			(tracks not_allowed)
			(vias allowed)
			(pads allowed)
			(copperpour not_allowed)
			(footprints allowed)
		)
		(placement
			(enabled no)
			(sheetname "")
		)
		(fill yes
			(thermal_gap 0.5)
			(thermal_bridge_width 0.5)
			(island_removal_mode 0)
		)
		(polygon
			(pts
				(arc
					(start 202.481942 -253.435358)
					(mid 201.813922 -253.435358)
					(end 202.481942 -253.435358)
				)
			)
		)
	)
	(zone
		(layers "B.Cu" "In13.Cu" "In15.Cu")
		(hatch none 0.5)
		(connect_pads
			(clearance 0)
		)
		(min_thickness 0.25)
		(keepout
			(tracks not_allowed)
			(vias allowed)
			(pads allowed)
			(copperpour not_allowed)
			(footprints allowed)
		)
		(placement
			(enabled no)
			(sheetname "")
		)
		(fill yes
			(thermal_gap 0.5)
			(thermal_bridge_width 0.5)
			(island_removal_mode 0)
		)
		(polygon
			(pts
				(arc
					(start 86.076028 -282.996386)
					(mid 85.446108 -282.996386)
					(end 86.076028 -282.996386)
				)
			)
		)
	)
	(zone
		(layers "B.Cu" "In13.Cu" "In15.Cu")
		(hatch none 0.5)
		(connect_pads
			(clearance 0)
		)
		(min_thickness 0.25)
		(keepout
			(tracks not_allowed)
			(vias allowed)
			(pads allowed)
			(copperpour not_allowed)
			(footprints allowed)
		)
		(placement
			(enabled no)
			(sheetname "")
		)
		(fill yes
			(thermal_gap 0.5)
			(thermal_bridge_width 0.5)
			(island_removal_mode 0)
		)
		(polygon
			(pts
				(arc
					(start 431.237898 -4.963414)
					(mid 430.569878 -4.963414)
					(end 431.237898 -4.963414)
				)
			)
		)
	)
	(zone
		(layers "B.Cu" "In13.Cu" "In15.Cu")
		(hatch none 0.5)
		(connect_pads
			(clearance 0)
		)
		(min_thickness 0.25)
		(keepout
			(tracks not_allowed)
			(vias allowed)
			(pads allowed)
			(copperpour not_allowed)
			(footprints allowed)
		)
		(placement
			(enabled no)
			(sheetname "")
		)
		(fill yes
			(thermal_gap 0.5)
			(thermal_bridge_width 0.5)
			(island_removal_mode 0)
		)
		(polygon
			(pts
				(arc
					(start 22.04212 -301.88535)
					(mid 21.3741 -301.88535)
					(end 22.04212 -301.88535)
				)
			)
		)
	)
	(zone
		(layers "B.Cu" "In13.Cu" "In15.Cu")
		(hatch none 0.5)
		(connect_pads
			(clearance 0)
		)
		(min_thickness 0.25)
		(keepout
			(tracks not_allowed)
			(vias allowed)
			(pads allowed)
			(copperpour not_allowed)
			(footprints allowed)
		)
		(placement
			(enabled no)
			(sheetname "")
		)
		(fill yes
			(thermal_gap 0.5)
			(thermal_bridge_width 0.5)
			(island_removal_mode 0)
		)
		(polygon
			(pts
				(arc
					(start 382.628902 -377.41733)
					(mid 381.960882 -377.41733)
					(end 382.628902 -377.41733)
				)
			)
		)
	)
	(zone
		(layers "B.Cu" "In13.Cu" "In15.Cu")
		(hatch none 0.5)
		(connect_pads
			(clearance 0)
		)
		(min_thickness 0.25)
		(keepout
			(tracks not_allowed)
			(vias allowed)
			(pads allowed)
			(copperpour not_allowed)
			(footprints allowed)
		)
		(placement
			(enabled no)
			(sheetname "")
		)
		(fill yes
			(thermal_gap 0.5)
			(thermal_bridge_width 0.5)
			(island_removal_mode 0)
		)
		(polygon
			(pts
				(arc
					(start 86.245954 -242.05438)
					(mid 85.616034 -242.05438)
					(end 86.245954 -242.05438)
				)
			)
		)
	)
	(zone
		(layers "B.Cu" "In13.Cu" "In15.Cu")
		(hatch none 0.5)
		(connect_pads
			(clearance 0)
		)
		(min_thickness 0.25)
		(keepout
			(tracks not_allowed)
			(vias allowed)
			(pads allowed)
			(copperpour not_allowed)
			(footprints allowed)
		)
		(placement
			(enabled no)
			(sheetname "")
		)
		(fill yes
			(thermal_gap 0.5)
			(thermal_bridge_width 0.5)
			(island_removal_mode 0)
		)
		(polygon
			(pts
				(arc
					(start 61.244734 -412.570168)
					(mid 60.576714 -412.570168)
					(end 61.244734 -412.570168)
				)
			)
		)
	)
	(zone
		(layers "B.Cu" "In13.Cu" "In15.Cu")
		(hatch none 0.5)
		(connect_pads
			(clearance 0)
		)
		(min_thickness 0.25)
		(keepout
			(tracks not_allowed)
			(vias allowed)
			(pads allowed)
			(copperpour not_allowed)
			(footprints allowed)
		)
		(placement
			(enabled no)
			(sheetname "")
		)
		(fill yes
			(thermal_gap 0.5)
			(thermal_bridge_width 0.5)
			(island_removal_mode 0)
		)
		(polygon
			(pts
				(arc
					(start 364.729776 -244.484144)
					(mid 364.099856 -244.484144)
					(end 364.729776 -244.484144)
				)
			)
		)
	)
	(zone
		(layers "B.Cu" "In13.Cu" "In15.Cu")
		(hatch none 0.5)
		(connect_pads
			(clearance 0)
		)
		(min_thickness 0.25)
		(keepout
			(tracks not_allowed)
			(vias allowed)
			(pads allowed)
			(copperpour not_allowed)
			(footprints allowed)
		)
		(placement
			(enabled no)
			(sheetname "")
		)
		(fill yes
			(thermal_gap 0.5)
			(thermal_bridge_width 0.5)
			(island_removal_mode 0)
		)
		(polygon
			(pts
				(arc
					(start 120.849644 -276.516338)
					(mid 120.219724 -276.516338)
					(end 120.849644 -276.516338)
				)
			)
		)
	)
	(zone
		(layers "B.Cu" "In13.Cu" "In15.Cu")
		(hatch none 0.5)
		(connect_pads
			(clearance 0)
		)
		(min_thickness 0.25)
		(keepout
			(tracks not_allowed)
			(vias allowed)
			(pads allowed)
			(copperpour not_allowed)
			(footprints allowed)
		)
		(placement
			(enabled no)
			(sheetname "")
		)
		(fill yes
			(thermal_gap 0.5)
			(thermal_bridge_width 0.5)
			(island_removal_mode 0)
		)
		(polygon
			(pts
				(arc
					(start 139.649708 -279.756362)
					(mid 139.019788 -279.756362)
					(end 139.649708 -279.756362)
				)
			)
		)
	)
	(zone
		(layers "B.Cu" "In13.Cu" "In15.Cu")
		(hatch none 0.5)
		(connect_pads
			(clearance 0)
		)
		(min_thickness 0.25)
		(keepout
			(tracks not_allowed)
			(vias allowed)
			(pads allowed)
			(copperpour not_allowed)
			(footprints allowed)
		)
		(placement
			(enabled no)
			(sheetname "")
		)
		(fill yes
			(thermal_gap 0.5)
			(thermal_bridge_width 0.5)
			(island_removal_mode 0)
		)
		(polygon
			(pts
				(arc
					(start 450.42201 -308.685184)
					(mid 449.75399 -308.685184)
					(end 450.42201 -308.685184)
				)
			)
		)
	)
	(zone
		(layers "B.Cu" "In13.Cu" "In15.Cu")
		(hatch none 0.5)
		(connect_pads
			(clearance 0)
		)
		(min_thickness 0.25)
		(keepout
			(tracks not_allowed)
			(vias allowed)
			(pads allowed)
			(copperpour not_allowed)
			(footprints allowed)
		)
		(placement
			(enabled no)
			(sheetname "")
		)
		(fill yes
			(thermal_gap 0.5)
			(thermal_bridge_width 0.5)
			(island_removal_mode 0)
		)
		(polygon
			(pts
				(arc
					(start 334.036924 -431.889916)
					(mid 333.262732 -431.889916)
					(end 334.036924 -431.889916)
				)
			)
		)
	)
	(zone
		(layers "B.Cu" "In13.Cu" "In15.Cu")
		(hatch none 0.5)
		(connect_pads
			(clearance 0)
		)
		(min_thickness 0.25)
		(keepout
			(tracks not_allowed)
			(vias allowed)
			(pads allowed)
			(copperpour not_allowed)
			(footprints allowed)
		)
		(placement
			(enabled no)
			(sheetname "")
		)
		(fill yes
			(thermal_gap 0.5)
			(thermal_bridge_width 0.5)
			(island_removal_mode 0)
		)
		(polygon
			(pts
				(arc
					(start 86.245954 -243.674392)
					(mid 85.616034 -243.674392)
					(end 86.245954 -243.674392)
				)
			)
		)
	)
	(zone
		(layers "B.Cu" "In13.Cu" "In15.Cu")
		(hatch none 0.5)
		(connect_pads
			(clearance 0)
		)
		(min_thickness 0.25)
		(keepout
			(tracks not_allowed)
			(vias allowed)
			(pads allowed)
			(copperpour not_allowed)
			(footprints allowed)
		)
		(placement
			(enabled no)
			(sheetname "")
		)
		(fill yes
			(thermal_gap 0.5)
			(thermal_bridge_width 0.5)
			(island_removal_mode 0)
		)
		(polygon
			(pts
				(arc
					(start 122.82678 -33.838388)
					(mid 122.15876 -33.838388)
					(end 122.82678 -33.838388)
				)
			)
		)
	)
	(zone
		(layers "B.Cu" "In13.Cu" "In15.Cu")
		(hatch none 0.5)
		(connect_pads
			(clearance 0)
		)
		(min_thickness 0.25)
		(keepout
			(tracks not_allowed)
			(vias allowed)
			(pads allowed)
			(copperpour not_allowed)
			(footprints allowed)
		)
		(placement
			(enabled no)
			(sheetname "")
		)
		(fill yes
			(thermal_gap 0.5)
			(thermal_bridge_width 0.5)
			(island_removal_mode 0)
		)
		(polygon
			(pts
				(arc
					(start 202.481942 -235.585254)
					(mid 201.813922 -235.585254)
					(end 202.481942 -235.585254)
				)
			)
		)
	)
	(zone
		(layers "B.Cu" "In13.Cu" "In15.Cu")
		(hatch none 0.5)
		(connect_pads
			(clearance 0)
		)
		(min_thickness 0.25)
		(keepout
			(tracks not_allowed)
			(vias allowed)
			(pads allowed)
			(copperpour not_allowed)
			(footprints allowed)
		)
		(placement
			(enabled no)
			(sheetname "")
		)
		(fill yes
			(thermal_gap 0.5)
			(thermal_bridge_width 0.5)
			(island_removal_mode 0)
		)
		(polygon
			(pts
				(arc
					(start 340.036912 -429.689768)
					(mid 339.26272 -429.689768)
					(end 340.036912 -429.689768)
				)
			)
		)
	)
	(zone
		(layers "B.Cu" "In13.Cu" "In15.Cu")
		(hatch none 0.5)
		(connect_pads
			(clearance 0)
		)
		(min_thickness 0.25)
		(keepout
			(tracks not_allowed)
			(vias allowed)
			(pads allowed)
			(copperpour not_allowed)
			(footprints allowed)
		)
		(placement
			(enabled no)
			(sheetname "")
		)
		(fill yes
			(thermal_gap 0.5)
			(thermal_bridge_width 0.5)
			(island_removal_mode 0)
		)
		(polygon
			(pts
				(arc
					(start 86.076028 -289.47618)
					(mid 85.446108 -289.47618)
					(end 86.076028 -289.47618)
				)
			)
		)
	)
	(zone
		(layers "B.Cu" "In13.Cu" "In15.Cu")
		(hatch none 0.5)
		(connect_pads
			(clearance 0)
		)
		(min_thickness 0.25)
		(keepout
			(tracks not_allowed)
			(vias allowed)
			(pads allowed)
			(copperpour not_allowed)
			(footprints allowed)
		)
		(placement
			(enabled no)
			(sheetname "")
		)
		(fill yes
			(thermal_gap 0.5)
			(thermal_bridge_width 0.5)
			(island_removal_mode 0)
		)
		(polygon
			(pts
				(arc
					(start 336.03692 -429.689768)
					(mid 335.262728 -429.689768)
					(end 336.03692 -429.689768)
				)
			)
		)
	)
	(zone
		(layers "B.Cu" "In13.Cu" "In15.Cu")
		(hatch none 0.5)
		(connect_pads
			(clearance 0)
		)
		(min_thickness 0.25)
		(keepout
			(tracks not_allowed)
			(vias allowed)
			(pads allowed)
			(copperpour not_allowed)
			(footprints allowed)
		)
		(placement
			(enabled no)
			(sheetname "")
		)
		(fill yes
			(thermal_gap 0.5)
			(thermal_bridge_width 0.5)
			(island_removal_mode 0)
		)
		(polygon
			(pts
				(arc
					(start 17.942052 -314.635388)
					(mid 17.274032 -314.635388)
					(end 17.942052 -314.635388)
				)
			)
		)
	)
	(zone
		(layers "B.Cu" "In13.Cu" "In15.Cu")
		(hatch none 0.5)
		(connect_pads
			(clearance 0)
		)
		(min_thickness 0.25)
		(keepout
			(tracks not_allowed)
			(vias allowed)
			(pads allowed)
			(copperpour not_allowed)
			(footprints allowed)
		)
		(placement
			(enabled no)
			(sheetname "")
		)
		(fill yes
			(thermal_gap 0.5)
			(thermal_bridge_width 0.5)
			(island_removal_mode 0)
		)
		(polygon
			(pts
				(arc
					(start 139.349734 -229.90429)
					(mid 138.719814 -229.90429)
					(end 139.349734 -229.90429)
				)
			)
		)
	)
	(zone
		(layers "B.Cu" "In13.Cu" "In15.Cu")
		(hatch none 0.5)
		(connect_pads
			(clearance 0)
		)
		(min_thickness 0.25)
		(keepout
			(tracks not_allowed)
			(vias allowed)
			(pads allowed)
			(copperpour not_allowed)
			(footprints allowed)
		)
		(placement
			(enabled no)
			(sheetname "")
		)
		(fill yes
			(thermal_gap 0.5)
			(thermal_bridge_width 0.5)
			(island_removal_mode 0)
		)
		(polygon
			(pts
				(arc
					(start 138.711686 -379.496828)
					(mid 138.043666 -379.496828)
					(end 138.711686 -379.496828)
				)
			)
		)
	)
	(zone
		(layers "B.Cu" "In13.Cu" "In15.Cu")
		(hatch none 0.5)
		(connect_pads
			(clearance 0)
		)
		(min_thickness 0.25)
		(keepout
			(tracks not_allowed)
			(vias allowed)
			(pads allowed)
			(copperpour not_allowed)
			(footprints allowed)
		)
		(placement
			(enabled no)
			(sheetname "")
		)
		(fill yes
			(thermal_gap 0.5)
			(thermal_bridge_width 0.5)
			(island_removal_mode 0)
		)
		(polygon
			(pts
				(arc
					(start 91.433904 -385.31038)
					(mid 90.803984 -385.31038)
					(end 91.433904 -385.31038)
				)
			)
		)
	)
	(zone
		(layers "B.Cu" "In13.Cu" "In15.Cu")
		(hatch none 0.5)
		(connect_pads
			(clearance 0)
		)
		(min_thickness 0.25)
		(keepout
			(tracks not_allowed)
			(vias allowed)
			(pads allowed)
			(copperpour not_allowed)
			(footprints allowed)
		)
		(placement
			(enabled no)
			(sheetname "")
		)
		(fill yes
			(thermal_gap 0.5)
			(thermal_bridge_width 0.5)
			(island_removal_mode 0)
		)
		(polygon
			(pts
				(arc
					(start 84.836 -244.484398)
					(mid 84.20608 -244.484398)
					(end 84.836 -244.484398)
				)
			)
		)
	)
	(zone
		(layers "B.Cu" "In13.Cu" "In15.Cu")
		(hatch none 0.5)
		(connect_pads
			(clearance 0)
		)
		(min_thickness 0.25)
		(keepout
			(tracks not_allowed)
			(vias allowed)
			(pads allowed)
			(copperpour not_allowed)
			(footprints allowed)
		)
		(placement
			(enabled no)
			(sheetname "")
		)
		(fill yes
			(thermal_gap 0.5)
			(thermal_bridge_width 0.5)
			(island_removal_mode 0)
		)
		(polygon
			(pts
				(arc
					(start 64.307974 -412.570168)
					(mid 63.639954 -412.570168)
					(end 64.307974 -412.570168)
				)
			)
		)
	)
	(zone
		(layers "B.Cu" "In13.Cu" "In15.Cu")
		(hatch none 0.5)
		(connect_pads
			(clearance 0)
		)
		(min_thickness 0.25)
		(keepout
			(tracks not_allowed)
			(vias allowed)
			(pads allowed)
			(copperpour not_allowed)
			(footprints allowed)
		)
		(placement
			(enabled no)
			(sheetname "")
		)
		(fill yes
			(thermal_gap 0.5)
			(thermal_bridge_width 0.5)
			(island_removal_mode 0)
		)
		(polygon
			(pts
				(arc
					(start 137.93978 -242.05438)
					(mid 137.30986 -242.05438)
					(end 137.93978 -242.05438)
				)
			)
		)
	)
	(zone
		(layers "B.Cu" "In13.Cu" "In15.Cu")
		(hatch none 0.5)
		(connect_pads
			(clearance 0)
		)
		(min_thickness 0.25)
		(keepout
			(tracks not_allowed)
			(vias allowed)
			(pads allowed)
			(copperpour not_allowed)
			(footprints allowed)
		)
		(placement
			(enabled no)
			(sheetname "")
		)
		(fill yes
			(thermal_gap 0.5)
			(thermal_bridge_width 0.5)
			(island_removal_mode 0)
		)
		(polygon
			(pts
				(arc
					(start 71.036942 -430.889918)
					(mid 70.26275 -430.889918)
					(end 71.036942 -430.889918)
				)
			)
		)
	)
	(zone
		(layers "B.Cu" "In13.Cu" "In15.Cu")
		(hatch none 0.5)
		(connect_pads
			(clearance 0)
		)
		(min_thickness 0.25)
		(keepout
			(tracks not_allowed)
			(vias allowed)
			(pads allowed)
			(copperpour not_allowed)
			(footprints allowed)
		)
		(placement
			(enabled no)
			(sheetname "")
		)
		(fill yes
			(thermal_gap 0.5)
			(thermal_bridge_width 0.5)
			(island_removal_mode 0)
		)
		(polygon
			(pts
				(arc
					(start 269.982188 -254.284988)
					(mid 269.314168 -254.284988)
					(end 269.982188 -254.284988)
				)
			)
		)
	)
	(zone
		(layers "B.Cu" "In13.Cu" "In15.Cu")
		(hatch none 0.5)
		(connect_pads
			(clearance 0)
		)
		(min_thickness 0.25)
		(keepout
			(tracks not_allowed)
			(vias allowed)
			(pads allowed)
			(copperpour not_allowed)
			(footprints allowed)
		)
		(placement
			(enabled no)
			(sheetname "")
		)
		(fill yes
			(thermal_gap 0.5)
			(thermal_bridge_width 0.5)
			(island_removal_mode 0)
		)
		(polygon
			(pts
				(arc
					(start 22.04212 -283.185362)
					(mid 21.3741 -283.185362)
					(end 22.04212 -283.185362)
				)
			)
		)
	)
	(zone
		(layers "B.Cu" "In13.Cu" "In15.Cu")
		(hatch none 0.5)
		(connect_pads
			(clearance 0)
		)
		(min_thickness 0.25)
		(keepout
			(tracks not_allowed)
			(vias allowed)
			(pads allowed)
			(copperpour not_allowed)
			(footprints allowed)
		)
		(placement
			(enabled no)
			(sheetname "")
		)
		(fill yes
			(thermal_gap 0.5)
			(thermal_bridge_width 0.5)
			(island_removal_mode 0)
		)
		(polygon
			(pts
				(arc
					(start 122.729752 -274.896326)
					(mid 122.099832 -274.896326)
					(end 122.729752 -274.896326)
				)
			)
		)
	)
	(zone
		(layers "B.Cu" "In13.Cu" "In15.Cu")
		(hatch none 0.5)
		(connect_pads
			(clearance 0)
		)
		(min_thickness 0.25)
		(keepout
			(tracks not_allowed)
			(vias allowed)
			(pads allowed)
			(copperpour not_allowed)
			(footprints allowed)
		)
		(placement
			(enabled no)
			(sheetname "")
		)
		(fill yes
			(thermal_gap 0.5)
			(thermal_bridge_width 0.5)
			(island_removal_mode 0)
		)
		(polygon
			(pts
				(arc
					(start 414.62325 -6.725158)
					(mid 413.95523 -6.725158)
					(end 414.62325 -6.725158)
				)
			)
		)
	)
	(zone
		(layers "B.Cu" "In13.Cu" "In15.Cu")
		(hatch none 0.5)
		(connect_pads
			(clearance 0)
		)
		(min_thickness 0.25)
		(keepout
			(tracks not_allowed)
			(vias allowed)
			(pads allowed)
			(copperpour not_allowed)
			(footprints allowed)
		)
		(placement
			(enabled no)
			(sheetname "")
		)
		(fill yes
			(thermal_gap 0.5)
			(thermal_bridge_width 0.5)
			(island_removal_mode 0)
		)
		(polygon
			(pts
				(arc
					(start 367.849658 -276.516084)
					(mid 367.219738 -276.516084)
					(end 367.849658 -276.516084)
				)
			)
		)
	)
	(zone
		(layers "B.Cu" "In13.Cu" "In15.Cu")
		(hatch none 0.5)
		(connect_pads
			(clearance 0)
		)
		(min_thickness 0.25)
		(keepout
			(tracks not_allowed)
			(vias allowed)
			(pads allowed)
			(copperpour not_allowed)
			(footprints allowed)
		)
		(placement
			(enabled no)
			(sheetname "")
		)
		(fill yes
			(thermal_gap 0.5)
			(thermal_bridge_width 0.5)
			(island_removal_mode 0)
		)
		(polygon
			(pts
				(arc
					(start 206.58201 -240.68532)
					(mid 205.91399 -240.68532)
					(end 206.58201 -240.68532)
				)
			)
		)
	)
	(zone
		(layers "B.Cu" "In13.Cu" "In15.Cu")
		(hatch none 0.5)
		(connect_pads
			(clearance 0)
		)
		(min_thickness 0.25)
		(keepout
			(tracks not_allowed)
			(vias allowed)
			(pads allowed)
			(copperpour not_allowed)
			(footprints allowed)
		)
		(placement
			(enabled no)
			(sheetname "")
		)
		(fill yes
			(thermal_gap 0.5)
			(thermal_bridge_width 0.5)
			(island_removal_mode 0)
		)
		(polygon
			(pts
				(arc
					(start 365.969804 -279.756108)
					(mid 365.339884 -279.756108)
					(end 365.969804 -279.756108)
				)
			)
		)
	)
	(zone
		(layers "B.Cu" "In13.Cu" "In15.Cu")
		(hatch none 0.5)
		(connect_pads
			(clearance 0)
		)
		(min_thickness 0.25)
		(keepout
			(tracks not_allowed)
			(vias allowed)
			(pads allowed)
			(copperpour not_allowed)
			(footprints allowed)
		)
		(placement
			(enabled no)
			(sheetname "")
		)
		(fill yes
			(thermal_gap 0.5)
			(thermal_bridge_width 0.5)
			(island_removal_mode 0)
		)
		(polygon
			(pts
				(arc
					(start 411.1371 -430.889918)
					(mid 410.362908 -430.889918)
					(end 411.1371 -430.889918)
				)
			)
		)
	)
	(zone
		(layers "B.Cu" "In13.Cu" "In15.Cu")
		(hatch none 0.5)
		(connect_pads
			(clearance 0)
		)
		(min_thickness 0.25)
		(keepout
			(tracks not_allowed)
			(vias allowed)
			(pads allowed)
			(copperpour not_allowed)
			(footprints allowed)
		)
		(placement
			(enabled no)
			(sheetname "")
		)
		(fill yes
			(thermal_gap 0.5)
			(thermal_bridge_width 0.5)
			(island_removal_mode 0)
		)
		(polygon
			(pts
				(arc
					(start 454.522078 -212.635084)
					(mid 453.854058 -212.635084)
					(end 454.522078 -212.635084)
				)
			)
		)
	)
	(zone
		(layers "B.Cu" "In13.Cu" "In15.Cu")
		(hatch none 0.5)
		(connect_pads
			(clearance 0)
		)
		(min_thickness 0.25)
		(keepout
			(tracks not_allowed)
			(vias allowed)
			(pads allowed)
			(copperpour not_allowed)
			(footprints allowed)
		)
		(placement
			(enabled no)
			(sheetname "")
		)
		(fill yes
			(thermal_gap 0.5)
			(thermal_bridge_width 0.5)
			(island_removal_mode 0)
		)
		(polygon
			(pts
				(arc
					(start 89.034112 -388.774432)
					(mid 88.404192 -388.774432)
					(end 89.034112 -388.774432)
				)
			)
		)
	)
	(zone
		(layers "B.Cu" "In13.Cu" "In15.Cu")
		(hatch none 0.5)
		(connect_pads
			(clearance 0)
		)
		(min_thickness 0.25)
		(keepout
			(tracks not_allowed)
			(vias allowed)
			(pads allowed)
			(copperpour not_allowed)
			(footprints allowed)
		)
		(placement
			(enabled no)
			(sheetname "")
		)
		(fill yes
			(thermal_gap 0.5)
			(thermal_bridge_width 0.5)
			(island_removal_mode 0)
		)
		(polygon
			(pts
				(arc
					(start 265.88212 -201.585068)
					(mid 265.2141 -201.585068)
					(end 265.88212 -201.585068)
				)
			)
		)
	)
	(zone
		(layers "B.Cu" "In13.Cu" "In15.Cu")
		(hatch none 0.5)
		(connect_pads
			(clearance 0)
		)
		(min_thickness 0.25)
		(keepout
			(tracks not_allowed)
			(vias allowed)
			(pads allowed)
			(copperpour not_allowed)
			(footprints allowed)
		)
		(placement
			(enabled no)
			(sheetname "")
		)
		(fill yes
			(thermal_gap 0.5)
			(thermal_bridge_width 0.5)
			(island_removal_mode 0)
		)
		(polygon
			(pts
				(arc
					(start 139.819634 -240.434368)
					(mid 139.189714 -240.434368)
					(end 139.819634 -240.434368)
				)
			)
		)
	)
	(zone
		(layers "B.Cu" "In13.Cu" "In15.Cu")
		(hatch none 0.5)
		(connect_pads
			(clearance 0)
		)
		(min_thickness 0.25)
		(keepout
			(tracks not_allowed)
			(vias allowed)
			(pads allowed)
			(copperpour not_allowed)
			(footprints allowed)
		)
		(placement
			(enabled no)
			(sheetname "")
		)
		(fill yes
			(thermal_gap 0.5)
			(thermal_bridge_width 0.5)
			(island_removal_mode 0)
		)
		(polygon
			(pts
				(arc
					(start 387.759702 -233.954066)
					(mid 387.129782 -233.954066)
					(end 387.759702 -233.954066)
				)
			)
		)
	)
	(zone
		(layers "B.Cu" "In13.Cu" "In15.Cu")
		(hatch none 0.5)
		(connect_pads
			(clearance 0)
		)
		(min_thickness 0.25)
		(keepout
			(tracks not_allowed)
			(vias allowed)
			(pads allowed)
			(copperpour not_allowed)
			(footprints allowed)
		)
		(placement
			(enabled no)
			(sheetname "")
		)
		(fill yes
			(thermal_gap 0.5)
			(thermal_bridge_width 0.5)
			(island_removal_mode 0)
		)
		(polygon
			(pts
				(arc
					(start 334.016096 -266.796012)
					(mid 333.386176 -266.796012)
					(end 334.016096 -266.796012)
				)
			)
		)
	)
	(zone
		(layers "B.Cu" "In13.Cu" "In15.Cu")
		(hatch none 0.5)
		(connect_pads
			(clearance 0)
		)
		(min_thickness 0.25)
		(keepout
			(tracks not_allowed)
			(vias allowed)
			(pads allowed)
			(copperpour not_allowed)
			(footprints allowed)
		)
		(placement
			(enabled no)
			(sheetname "")
		)
		(fill yes
			(thermal_gap 0.5)
			(thermal_bridge_width 0.5)
			(island_removal_mode 0)
		)
		(polygon
			(pts
				(arc
					(start 332.606142 -270.846042)
					(mid 331.976222 -270.846042)
					(end 332.606142 -270.846042)
				)
			)
		)
	)
	(zone
		(layers "B.Cu" "In13.Cu" "In15.Cu")
		(hatch none 0.5)
		(connect_pads
			(clearance 0)
		)
		(min_thickness 0.25)
		(keepout
			(tracks not_allowed)
			(vias allowed)
			(pads allowed)
			(copperpour not_allowed)
			(footprints allowed)
		)
		(placement
			(enabled no)
			(sheetname "")
		)
		(fill yes
			(thermal_gap 0.5)
			(thermal_bridge_width 0.5)
			(island_removal_mode 0)
		)
		(polygon
			(pts
				(arc
					(start 265.88212 -204.134974)
					(mid 265.2141 -204.134974)
					(end 265.88212 -204.134974)
				)
			)
		)
	)
	(zone
		(layers "B.Cu" "In13.Cu" "In15.Cu")
		(hatch none 0.5)
		(connect_pads
			(clearance 0)
		)
		(min_thickness 0.25)
		(keepout
			(tracks not_allowed)
			(vias allowed)
			(pads allowed)
			(copperpour not_allowed)
			(footprints allowed)
		)
		(placement
			(enabled no)
			(sheetname "")
		)
		(fill yes
			(thermal_gap 0.5)
			(thermal_bridge_width 0.5)
			(island_removal_mode 0)
		)
		(polygon
			(pts
				(arc
					(start 17.942052 -263.635236)
					(mid 17.274032 -263.635236)
					(end 17.942052 -263.635236)
				)
			)
		)
	)
	(zone
		(layers "B.Cu" "In13.Cu" "In15.Cu")
		(hatch none 0.5)
		(connect_pads
			(clearance 0)
		)
		(min_thickness 0.25)
		(keepout
			(tracks not_allowed)
			(vias allowed)
			(pads allowed)
			(copperpour not_allowed)
			(footprints allowed)
		)
		(placement
			(enabled no)
			(sheetname "")
		)
		(fill yes
			(thermal_gap 0.5)
			(thermal_bridge_width 0.5)
			(island_removal_mode 0)
		)
		(polygon
			(pts
				(arc
					(start 88.234012 -386.003292)
					(mid 87.604092 -386.003292)
					(end 88.234012 -386.003292)
				)
			)
		)
	)
	(zone
		(layers "B.Cu" "In13.Cu" "In15.Cu")
		(hatch none 0.5)
		(connect_pads
			(clearance 0)
		)
		(min_thickness 0.25)
		(keepout
			(tracks not_allowed)
			(vias allowed)
			(pads allowed)
			(copperpour not_allowed)
			(footprints allowed)
		)
		(placement
			(enabled no)
			(sheetname "")
		)
		(fill yes
			(thermal_gap 0.5)
			(thermal_bridge_width 0.5)
			(island_removal_mode 0)
		)
		(polygon
			(pts
				(arc
					(start 332.306168 -242.054126)
					(mid 331.676248 -242.054126)
					(end 332.306168 -242.054126)
				)
			)
		)
	)
	(zone
		(layers "B.Cu" "In13.Cu" "In15.Cu")
		(hatch none 0.5)
		(connect_pads
			(clearance 0)
		)
		(min_thickness 0.25)
		(keepout
			(tracks not_allowed)
			(vias allowed)
			(pads allowed)
			(copperpour not_allowed)
			(footprints allowed)
		)
		(placement
			(enabled no)
			(sheetname "")
		)
		(fill yes
			(thermal_gap 0.5)
			(thermal_bridge_width 0.5)
			(island_removal_mode 0)
		)
		(polygon
			(pts
				(arc
					(start 84.887054 -412.570168)
					(mid 84.219034 -412.570168)
					(end 84.887054 -412.570168)
				)
			)
		)
	)
	(zone
		(layers "B.Cu" "In13.Cu" "In15.Cu")
		(hatch none 0.5)
		(connect_pads
			(clearance 0)
		)
		(min_thickness 0.25)
		(keepout
			(tracks not_allowed)
			(vias allowed)
			(pads allowed)
			(copperpour not_allowed)
			(footprints allowed)
		)
		(placement
			(enabled no)
			(sheetname "")
		)
		(fill yes
			(thermal_gap 0.5)
			(thermal_bridge_width 0.5)
			(island_removal_mode 0)
		)
		(polygon
			(pts
				(arc
					(start 334.186022 -248.534174)
					(mid 333.556102 -248.534174)
					(end 334.186022 -248.534174)
				)
			)
		)
	)
	(zone
		(layers "B.Cu" "In13.Cu" "In15.Cu")
		(hatch none 0.5)
		(connect_pads
			(clearance 0)
		)
		(min_thickness 0.25)
		(keepout
			(tracks not_allowed)
			(vias allowed)
			(pads allowed)
			(copperpour not_allowed)
			(footprints allowed)
		)
		(placement
			(enabled no)
			(sheetname "")
		)
		(fill yes
			(thermal_gap 0.5)
			(thermal_bridge_width 0.5)
			(island_removal_mode 0)
		)
		(polygon
			(pts
				(arc
					(start 333.076042 -286.236156)
					(mid 332.446122 -286.236156)
					(end 333.076042 -286.236156)
				)
			)
		)
	)
	(zone
		(layers "B.Cu" "In13.Cu" "In15.Cu")
		(hatch none 0.5)
		(connect_pads
			(clearance 0)
		)
		(min_thickness 0.25)
		(keepout
			(tracks not_allowed)
			(vias allowed)
			(pads allowed)
			(copperpour not_allowed)
			(footprints allowed)
		)
		(placement
			(enabled no)
			(sheetname "")
		)
		(fill yes
			(thermal_gap 0.5)
			(thermal_bridge_width 0.5)
			(island_removal_mode 0)
		)
		(polygon
			(pts
				(arc
					(start 108.864654 -381.50546)
					(mid 108.196634 -381.50546)
					(end 108.864654 -381.50546)
				)
			)
		)
	)
	(zone
		(layers "B.Cu" "In13.Cu" "In15.Cu")
		(hatch none 0.5)
		(connect_pads
			(clearance 0)
		)
		(min_thickness 0.25)
		(keepout
			(tracks not_allowed)
			(vias allowed)
			(pads allowed)
			(copperpour not_allowed)
			(footprints allowed)
		)
		(placement
			(enabled no)
			(sheetname "")
		)
		(fill yes
			(thermal_gap 0.5)
			(thermal_bridge_width 0.5)
			(island_removal_mode 0)
		)
		(polygon
			(pts
				(arc
					(start 386.349748 -250.964192)
					(mid 385.719828 -250.964192)
					(end 386.349748 -250.964192)
				)
			)
		)
	)
	(zone
		(layers "B.Cu" "In13.Cu" "In15.Cu")
		(hatch none 0.5)
		(connect_pads
			(clearance 0)
		)
		(min_thickness 0.25)
		(keepout
			(tracks not_allowed)
			(vias allowed)
			(pads allowed)
			(copperpour not_allowed)
			(footprints allowed)
		)
		(placement
			(enabled no)
			(sheetname "")
		)
		(fill yes
			(thermal_gap 0.5)
			(thermal_bridge_width 0.5)
			(island_removal_mode 0)
		)
		(polygon
			(pts
				(arc
					(start 202.481942 -198.185278)
					(mid 201.813922 -198.185278)
					(end 202.481942 -198.185278)
				)
			)
		)
	)
	(zone
		(layers "B.Cu" "In13.Cu" "In15.Cu")
		(hatch none 0.5)
		(connect_pads
			(clearance 0)
		)
		(min_thickness 0.25)
		(keepout
			(tracks not_allowed)
			(vias allowed)
			(pads allowed)
			(copperpour not_allowed)
			(footprints allowed)
		)
		(placement
			(enabled no)
			(sheetname "")
		)
		(fill yes
			(thermal_gap 0.5)
			(thermal_bridge_width 0.5)
			(island_removal_mode 0)
		)
		(polygon
			(pts
				(arc
					(start 149.787356 -412.570168)
					(mid 149.119336 -412.570168)
					(end 149.787356 -412.570168)
				)
			)
		)
	)
	(zone
		(layers "B.Cu" "In13.Cu" "In15.Cu")
		(hatch none 0.5)
		(connect_pads
			(clearance 0)
		)
		(min_thickness 0.25)
		(keepout
			(tracks not_allowed)
			(vias allowed)
			(pads allowed)
			(copperpour not_allowed)
			(footprints allowed)
		)
		(placement
			(enabled no)
			(sheetname "")
		)
		(fill yes
			(thermal_gap 0.5)
			(thermal_bridge_width 0.5)
			(island_removal_mode 0)
		)
		(polygon
			(pts
				(arc
					(start 84.836 -252.584458)
					(mid 84.20608 -252.584458)
					(end 84.836 -252.584458)
				)
			)
		)
	)
	(zone
		(layers "B.Cu" "In13.Cu" "In15.Cu")
		(hatch none 0.5)
		(connect_pads
			(clearance 0)
		)
		(min_thickness 0.25)
		(keepout
			(tracks not_allowed)
			(vias allowed)
			(pads allowed)
			(copperpour not_allowed)
			(footprints allowed)
		)
		(placement
			(enabled no)
			(sheetname "")
		)
		(fill yes
			(thermal_gap 0.5)
			(thermal_bridge_width 0.5)
			(island_removal_mode 0)
		)
		(polygon
			(pts
				(arc
					(start 102.05593 -274.896326)
					(mid 101.42601 -274.896326)
					(end 102.05593 -274.896326)
				)
			)
		)
	)
	(zone
		(layers "B.Cu" "In13.Cu" "In15.Cu")
		(hatch none 0.5)
		(connect_pads
			(clearance 0)
		)
		(min_thickness 0.25)
		(keepout
			(tracks not_allowed)
			(vias allowed)
			(pads allowed)
			(copperpour not_allowed)
			(footprints allowed)
		)
		(placement
			(enabled no)
			(sheetname "")
		)
		(fill yes
			(thermal_gap 0.5)
			(thermal_bridge_width 0.5)
			(island_removal_mode 0)
		)
		(polygon
			(pts
				(arc
					(start 387.289802 -250.964192)
					(mid 386.659882 -250.964192)
					(end 387.289802 -250.964192)
				)
			)
		)
	)
	(zone
		(layers "B.Cu" "In13.Cu" "In15.Cu")
		(hatch none 0.5)
		(connect_pads
			(clearance 0)
		)
		(min_thickness 0.25)
		(keepout
			(tracks not_allowed)
			(vias allowed)
			(pads allowed)
			(copperpour not_allowed)
			(footprints allowed)
		)
		(placement
			(enabled no)
			(sheetname "")
		)
		(fill yes
			(thermal_gap 0.5)
			(thermal_bridge_width 0.5)
			(island_removal_mode 0)
		)
		(polygon
			(pts
				(arc
					(start 29.837888 -19.13636)
					(mid 29.169868 -19.13636)
					(end 29.837888 -19.13636)
				)
			)
		)
	)
	(zone
		(layers "B.Cu" "In13.Cu" "In15.Cu")
		(hatch none 0.5)
		(connect_pads
			(clearance 0)
		)
		(min_thickness 0.25)
		(keepout
			(tracks not_allowed)
			(vias allowed)
			(pads allowed)
			(copperpour not_allowed)
			(footprints allowed)
		)
		(placement
			(enabled no)
			(sheetname "")
		)
		(fill yes
			(thermal_gap 0.5)
			(thermal_bridge_width 0.5)
			(island_removal_mode 0)
		)
		(polygon
			(pts
				(arc
					(start 450.42201 -239.835182)
					(mid 449.75399 -239.835182)
					(end 450.42201 -239.835182)
				)
			)
		)
	)
	(zone
		(layers "B.Cu" "In13.Cu" "In15.Cu")
		(hatch none 0.5)
		(connect_pads
			(clearance 0)
		)
		(min_thickness 0.25)
		(keepout
			(tracks not_allowed)
			(vias allowed)
			(pads allowed)
			(copperpour not_allowed)
			(footprints allowed)
		)
		(placement
			(enabled no)
			(sheetname "")
		)
		(fill yes
			(thermal_gap 0.5)
			(thermal_bridge_width 0.5)
			(island_removal_mode 0)
		)
		(polygon
			(pts
				(arc
					(start 334.186022 -255.014222)
					(mid 333.556102 -255.014222)
					(end 334.186022 -255.014222)
				)
			)
		)
	)
	(zone
		(layers "B.Cu" "In13.Cu" "In15.Cu")
		(hatch none 0.5)
		(connect_pads
			(clearance 0)
		)
		(min_thickness 0.25)
		(keepout
			(tracks not_allowed)
			(vias allowed)
			(pads allowed)
			(copperpour not_allowed)
			(footprints allowed)
		)
		(placement
			(enabled no)
			(sheetname "")
		)
		(fill yes
			(thermal_gap 0.5)
			(thermal_bridge_width 0.5)
			(island_removal_mode 0)
		)
		(polygon
			(pts
				(arc
					(start 399.660872 -420.952168)
					(mid 398.992852 -420.952168)
					(end 399.660872 -420.952168)
				)
			)
		)
	)
	(zone
		(layers "B.Cu" "In13.Cu" "In15.Cu")
		(hatch none 0.5)
		(connect_pads
			(clearance 0)
		)
		(min_thickness 0.25)
		(keepout
			(tracks not_allowed)
			(vias allowed)
			(pads allowed)
			(copperpour not_allowed)
			(footprints allowed)
		)
		(placement
			(enabled no)
			(sheetname "")
		)
		(fill yes
			(thermal_gap 0.5)
			(thermal_bridge_width 0.5)
			(island_removal_mode 0)
		)
		(polygon
			(pts
				(arc
					(start 407.137108 -429.689768)
					(mid 406.362916 -429.689768)
					(end 407.137108 -429.689768)
				)
			)
		)
	)
	(zone
		(layers "B.Cu" "In13.Cu" "In15.Cu")
		(hatch none 0.5)
		(connect_pads
			(clearance 0)
		)
		(min_thickness 0.25)
		(keepout
			(tracks not_allowed)
			(vias allowed)
			(pads allowed)
			(copperpour not_allowed)
			(footprints allowed)
		)
		(placement
			(enabled no)
			(sheetname "")
		)
		(fill yes
			(thermal_gap 0.5)
			(thermal_bridge_width 0.5)
			(island_removal_mode 0)
		)
		(polygon
			(pts
				(arc
					(start 372.418102 -382.34493)
					(mid 371.750082 -382.34493)
					(end 372.418102 -382.34493)
				)
			)
		)
	)
	(zone
		(layers "B.Cu" "In13.Cu" "In15.Cu")
		(hatch none 0.5)
		(connect_pads
			(clearance 0)
		)
		(min_thickness 0.25)
		(keepout
			(tracks not_allowed)
			(vias allowed)
			(pads allowed)
			(copperpour not_allowed)
			(footprints allowed)
		)
		(placement
			(enabled no)
			(sheetname "")
		)
		(fill yes
			(thermal_gap 0.5)
			(thermal_bridge_width 0.5)
			(island_removal_mode 0)
		)
		(polygon
			(pts
				(arc
					(start 33.494472 -17.613122)
					(mid 32.826452 -17.613122)
					(end 33.494472 -17.613122)
				)
			)
		)
	)
	(zone
		(layers "B.Cu" "In13.Cu" "In15.Cu")
		(hatch none 0.5)
		(connect_pads
			(clearance 0)
		)
		(min_thickness 0.25)
		(keepout
			(tracks not_allowed)
			(vias allowed)
			(pads allowed)
			(copperpour not_allowed)
			(footprints allowed)
		)
		(placement
			(enabled no)
			(sheetname "")
		)
		(fill yes
			(thermal_gap 0.5)
			(thermal_bridge_width 0.5)
			(island_removal_mode 0)
		)
		(polygon
			(pts
				(arc
					(start 85.776054 -226.66452)
					(mid 85.146134 -226.66452)
					(end 85.776054 -226.66452)
				)
			)
		)
	)
	(zone
		(layers "B.Cu" "In13.Cu" "In15.Cu")
		(hatch none 0.5)
		(connect_pads
			(clearance 0)
		)
		(min_thickness 0.25)
		(keepout
			(tracks not_allowed)
			(vias allowed)
			(pads allowed)
			(copperpour not_allowed)
			(footprints allowed)
		)
		(placement
			(enabled no)
			(sheetname "")
		)
		(fill yes
			(thermal_gap 0.5)
			(thermal_bridge_width 0.5)
			(island_removal_mode 0)
		)
		(polygon
			(pts
				(arc
					(start 333.716122 -247.724168)
					(mid 333.086202 -247.724168)
					(end 333.716122 -247.724168)
				)
			)
		)
	)
	(zone
		(layers "B.Cu" "In13.Cu" "In15.Cu")
		(hatch none 0.5)
		(connect_pads
			(clearance 0)
		)
		(min_thickness 0.25)
		(keepout
			(tracks not_allowed)
			(vias allowed)
			(pads allowed)
			(copperpour not_allowed)
			(footprints allowed)
		)
		(placement
			(enabled no)
			(sheetname "")
		)
		(fill yes
			(thermal_gap 0.5)
			(thermal_bridge_width 0.5)
			(island_removal_mode 0)
		)
		(polygon
			(pts
				(arc
					(start 17.942052 -202.435206)
					(mid 17.274032 -202.435206)
					(end 17.942052 -202.435206)
				)
			)
		)
	)
	(zone
		(layers "B.Cu" "In13.Cu" "In15.Cu")
		(hatch none 0.5)
		(connect_pads
			(clearance 0)
		)
		(min_thickness 0.25)
		(keepout
			(tracks not_allowed)
			(vias allowed)
			(pads allowed)
			(copperpour not_allowed)
			(footprints allowed)
		)
		(placement
			(enabled no)
			(sheetname "")
		)
		(fill yes
			(thermal_gap 0.5)
			(thermal_bridge_width 0.5)
			(island_removal_mode 0)
		)
		(polygon
			(pts
				(arc
					(start 454.522078 -217.73515)
					(mid 453.854058 -217.73515)
					(end 454.522078 -217.73515)
				)
			)
		)
	)
	(zone
		(layers "B.Cu" "In13.Cu" "In15.Cu")
		(hatch none 0.5)
		(connect_pads
			(clearance 0)
		)
		(min_thickness 0.25)
		(keepout
			(tracks not_allowed)
			(vias allowed)
			(pads allowed)
			(copperpour not_allowed)
			(footprints allowed)
		)
		(placement
			(enabled no)
			(sheetname "")
		)
		(fill yes
			(thermal_gap 0.5)
			(thermal_bridge_width 0.5)
			(island_removal_mode 0)
		)
		(polygon
			(pts
				(arc
					(start 450.42201 -220.285056)
					(mid 449.75399 -220.285056)
					(end 450.42201 -220.285056)
				)
			)
		)
	)
	(zone
		(layers "B.Cu" "In13.Cu" "In15.Cu")
		(hatch none 0.5)
		(connect_pads
			(clearance 0)
		)
		(min_thickness 0.25)
		(keepout
			(tracks not_allowed)
			(vias allowed)
			(pads allowed)
			(copperpour not_allowed)
			(footprints allowed)
		)
		(placement
			(enabled no)
			(sheetname "")
		)
		(fill yes
			(thermal_gap 0.5)
			(thermal_bridge_width 0.5)
			(island_removal_mode 0)
		)
		(polygon
			(pts
				(arc
					(start 332.606142 -280.566114)
					(mid 331.976222 -280.566114)
					(end 332.606142 -280.566114)
				)
			)
		)
	)
	(zone
		(layers "B.Cu" "In13.Cu" "In15.Cu")
		(hatch none 0.5)
		(connect_pads
			(clearance 0)
		)
		(min_thickness 0.25)
		(keepout
			(tracks not_allowed)
			(vias allowed)
			(pads allowed)
			(copperpour not_allowed)
			(footprints allowed)
		)
		(placement
			(enabled no)
			(sheetname "")
		)
		(fill yes
			(thermal_gap 0.5)
			(thermal_bridge_width 0.5)
			(island_removal_mode 0)
		)
		(polygon
			(pts
				(arc
					(start 116.091716 -412.570168)
					(mid 115.423696 -412.570168)
					(end 116.091716 -412.570168)
				)
			)
		)
	)
	(zone
		(layers "B.Cu" "In13.Cu" "In15.Cu")
		(hatch none 0.5)
		(connect_pads
			(clearance 0)
		)
		(min_thickness 0.25)
		(keepout
			(tracks not_allowed)
			(vias allowed)
			(pads allowed)
			(copperpour not_allowed)
			(footprints allowed)
		)
		(placement
			(enabled no)
			(sheetname "")
		)
		(fill yes
			(thermal_gap 0.5)
			(thermal_bridge_width 0.5)
			(island_removal_mode 0)
		)
		(polygon
			(pts
				(arc
					(start 115.554506 -373.96293)
					(mid 114.886486 -373.96293)
					(end 115.554506 -373.96293)
				)
			)
		)
	)
	(zone
		(layers "B.Cu" "In13.Cu" "In15.Cu")
		(hatch none 0.5)
		(connect_pads
			(clearance 0)
		)
		(min_thickness 0.25)
		(keepout
			(tracks not_allowed)
			(vias allowed)
			(pads allowed)
			(copperpour not_allowed)
			(footprints allowed)
		)
		(placement
			(enabled no)
			(sheetname "")
		)
		(fill yes
			(thermal_gap 0.5)
			(thermal_bridge_width 0.5)
			(island_removal_mode 0)
		)
		(polygon
			(pts
				(arc
					(start 450.42201 -306.985162)
					(mid 449.75399 -306.985162)
					(end 450.42201 -306.985162)
				)
			)
		)
	)
	(zone
		(layers "B.Cu" "In13.Cu" "In15.Cu")
		(hatch none 0.5)
		(connect_pads
			(clearance 0)
		)
		(min_thickness 0.25)
		(keepout
			(tracks not_allowed)
			(vias allowed)
			(pads allowed)
			(copperpour not_allowed)
			(footprints allowed)
		)
		(placement
			(enabled no)
			(sheetname "")
		)
		(fill yes
			(thermal_gap 0.5)
			(thermal_bridge_width 0.5)
			(island_removal_mode 0)
		)
		(polygon
			(pts
				(arc
					(start 98.936048 -246.10441)
					(mid 98.306128 -246.10441)
					(end 98.936048 -246.10441)
				)
			)
		)
	)
	(zone
		(layers "B.Cu" "In13.Cu" "In15.Cu")
		(hatch none 0.5)
		(connect_pads
			(clearance 0)
		)
		(min_thickness 0.25)
		(keepout
			(tracks not_allowed)
			(vias allowed)
			(pads allowed)
			(copperpour not_allowed)
			(footprints allowed)
		)
		(placement
			(enabled no)
			(sheetname "")
		)
		(fill yes
			(thermal_gap 0.5)
			(thermal_bridge_width 0.5)
			(island_removal_mode 0)
		)
		(polygon
			(pts
				(arc
					(start 58.181494 -412.570168)
					(mid 57.513474 -412.570168)
					(end 58.181494 -412.570168)
				)
			)
		)
	)
	(zone
		(layers "B.Cu" "In13.Cu" "In15.Cu")
		(hatch none 0.5)
		(connect_pads
			(clearance 0)
		)
		(min_thickness 0.25)
		(keepout
			(tracks not_allowed)
			(vias allowed)
			(pads allowed)
			(copperpour not_allowed)
			(footprints allowed)
		)
		(placement
			(enabled no)
			(sheetname "")
		)
		(fill yes
			(thermal_gap 0.5)
			(thermal_bridge_width 0.5)
			(island_removal_mode 0)
		)
		(polygon
			(pts
				(arc
					(start 454.522078 -242.385088)
					(mid 453.854058 -242.385088)
					(end 454.522078 -242.385088)
				)
			)
		)
	)
	(zone
		(layers "B.Cu" "In13.Cu" "In15.Cu")
		(hatch none 0.5)
		(connect_pads
			(clearance 0)
		)
		(min_thickness 0.25)
		(keepout
			(tracks not_allowed)
			(vias allowed)
			(pads allowed)
			(copperpour not_allowed)
			(footprints allowed)
		)
		(placement
			(enabled no)
			(sheetname "")
		)
		(fill yes
			(thermal_gap 0.5)
			(thermal_bridge_width 0.5)
			(island_removal_mode 0)
		)
		(polygon
			(pts
				(arc
					(start 86.245954 -227.474526)
					(mid 85.616034 -227.474526)
					(end 86.245954 -227.474526)
				)
			)
		)
	)
	(zone
		(layers "B.Cu" "In13.Cu" "In15.Cu")
		(hatch none 0.5)
		(connect_pads
			(clearance 0)
		)
		(min_thickness 0.25)
		(keepout
			(tracks not_allowed)
			(vias allowed)
			(pads allowed)
			(copperpour not_allowed)
			(footprints allowed)
		)
		(placement
			(enabled no)
			(sheetname "")
		)
		(fill yes
			(thermal_gap 0.5)
			(thermal_bridge_width 0.5)
			(island_removal_mode 0)
		)
		(polygon
			(pts
				(arc
					(start 365.66983 -247.724168)
					(mid 365.03991 -247.724168)
					(end 365.66983 -247.724168)
				)
			)
		)
	)
	(zone
		(layers "B.Cu" "In13.Cu" "In15.Cu")
		(hatch none 0.5)
		(connect_pads
			(clearance 0)
		)
		(min_thickness 0.25)
		(keepout
			(tracks not_allowed)
			(vias allowed)
			(pads allowed)
			(copperpour not_allowed)
			(footprints allowed)
		)
		(placement
			(enabled no)
			(sheetname "")
		)
		(fill yes
			(thermal_gap 0.5)
			(thermal_bridge_width 0.5)
			(island_removal_mode 0)
		)
		(polygon
			(pts
				(arc
					(start 339.433662 -394.385292)
					(mid 338.803742 -394.385292)
					(end 339.433662 -394.385292)
				)
			)
		)
	)
	(zone
		(layers "B.Cu" "In13.Cu" "In15.Cu")
		(hatch none 0.5)
		(connect_pads
			(clearance 0)
		)
		(min_thickness 0.25)
		(keepout
			(tracks not_allowed)
			(vias allowed)
			(pads allowed)
			(copperpour not_allowed)
			(footprints allowed)
		)
		(placement
			(enabled no)
			(sheetname "")
		)
		(fill yes
			(thermal_gap 0.5)
			(thermal_bridge_width 0.5)
			(island_removal_mode 0)
		)
		(polygon
			(pts
				(arc
					(start 370.66982 -276.516084)
					(mid 370.0399 -276.516084)
					(end 370.66982 -276.516084)
				)
			)
		)
	)
	(zone
		(layers "B.Cu" "In13.Cu" "In15.Cu")
		(hatch none 0.5)
		(connect_pads
			(clearance 0)
		)
		(min_thickness 0.25)
		(keepout
			(tracks not_allowed)
			(vias allowed)
			(pads allowed)
			(copperpour not_allowed)
			(footprints allowed)
		)
		(placement
			(enabled no)
			(sheetname "")
		)
		(fill yes
			(thermal_gap 0.5)
			(thermal_bridge_width 0.5)
			(island_removal_mode 0)
		)
		(polygon
			(pts
				(arc
					(start 85.776054 -238.00435)
					(mid 85.146134 -238.00435)
					(end 85.776054 -238.00435)
				)
			)
		)
	)
	(zone
		(layers "B.Cu" "In13.Cu" "In15.Cu")
		(hatch none 0.5)
		(connect_pads
			(clearance 0)
		)
		(min_thickness 0.25)
		(keepout
			(tracks not_allowed)
			(vias allowed)
			(pads allowed)
			(copperpour not_allowed)
			(footprints allowed)
		)
		(placement
			(enabled no)
			(sheetname "")
		)
		(fill yes
			(thermal_gap 0.5)
			(thermal_bridge_width 0.5)
			(island_removal_mode 0)
		)
		(polygon
			(pts
				(arc
					(start 123.369578 -234.764326)
					(mid 122.739658 -234.764326)
					(end 123.369578 -234.764326)
				)
			)
		)
	)
	(zone
		(layers "B.Cu" "In13.Cu" "In15.Cu")
		(hatch none 0.5)
		(connect_pads
			(clearance 0)
		)
		(min_thickness 0.25)
		(keepout
			(tracks not_allowed)
			(vias allowed)
			(pads allowed)
			(copperpour not_allowed)
			(footprints allowed)
		)
		(placement
			(enabled no)
			(sheetname "")
		)
		(fill yes
			(thermal_gap 0.5)
			(thermal_bridge_width 0.5)
			(island_removal_mode 0)
		)
		(polygon
			(pts
				(arc
					(start 390.471152 -420.952168)
					(mid 389.803132 -420.952168)
					(end 390.471152 -420.952168)
				)
			)
		)
	)
	(zone
		(layers "B.Cu" "In13.Cu" "In15.Cu")
		(hatch none 0.5)
		(connect_pads
			(clearance 0)
		)
		(min_thickness 0.25)
		(keepout
			(tracks not_allowed)
			(vias allowed)
			(pads allowed)
			(copperpour not_allowed)
			(footprints allowed)
		)
		(placement
			(enabled no)
			(sheetname "")
		)
		(fill yes
			(thermal_gap 0.5)
			(thermal_bridge_width 0.5)
			(island_removal_mode 0)
		)
		(polygon
			(pts
				(arc
					(start 308.054756 -420.952168)
					(mid 307.386736 -420.952168)
					(end 308.054756 -420.952168)
				)
			)
		)
	)
	(zone
		(layers "B.Cu" "In13.Cu" "In15.Cu")
		(hatch none 0.5)
		(connect_pads
			(clearance 0)
		)
		(min_thickness 0.25)
		(keepout
			(tracks not_allowed)
			(vias allowed)
			(pads allowed)
			(copperpour not_allowed)
			(footprints allowed)
		)
		(placement
			(enabled no)
			(sheetname "")
		)
		(fill yes
			(thermal_gap 0.5)
			(thermal_bridge_width 0.5)
			(island_removal_mode 0)
		)
		(polygon
			(pts
				(arc
					(start 269.982188 -236.435138)
					(mid 269.314168 -236.435138)
					(end 269.982188 -236.435138)
				)
			)
		)
	)
	(zone
		(layers "B.Cu" "In13.Cu" "In15.Cu")
		(hatch none 0.5)
		(connect_pads
			(clearance 0)
		)
		(min_thickness 0.25)
		(keepout
			(tracks not_allowed)
			(vias allowed)
			(pads allowed)
			(copperpour not_allowed)
			(footprints allowed)
		)
		(placement
			(enabled no)
			(sheetname "")
		)
		(fill yes
			(thermal_gap 0.5)
			(thermal_bridge_width 0.5)
			(island_removal_mode 0)
		)
		(polygon
			(pts
				(arc
					(start 454.522078 -264.48512)
					(mid 453.854058 -264.48512)
					(end 454.522078 -264.48512)
				)
			)
		)
	)
	(zone
		(layers "B.Cu" "In13.Cu" "In15.Cu")
		(hatch none 0.5)
		(connect_pads
			(clearance 0)
		)
		(min_thickness 0.25)
		(keepout
			(tracks not_allowed)
			(vias allowed)
			(pads allowed)
			(copperpour not_allowed)
			(footprints allowed)
		)
		(placement
			(enabled no)
			(sheetname "")
		)
		(fill yes
			(thermal_gap 0.5)
			(thermal_bridge_width 0.5)
			(island_removal_mode 0)
		)
		(polygon
			(pts
				(arc
					(start 86.245954 -253.394464)
					(mid 85.616034 -253.394464)
					(end 86.245954 -253.394464)
				)
			)
		)
	)
	(zone
		(layers "B.Cu" "In13.Cu" "In15.Cu")
		(hatch none 0.5)
		(connect_pads
			(clearance 0)
		)
		(min_thickness 0.25)
		(keepout
			(tracks not_allowed)
			(vias allowed)
			(pads allowed)
			(copperpour not_allowed)
			(footprints allowed)
		)
		(placement
			(enabled no)
			(sheetname "")
		)
		(fill yes
			(thermal_gap 0.5)
			(thermal_bridge_width 0.5)
			(island_removal_mode 0)
		)
		(polygon
			(pts
				(arc
					(start 317.036704 -431.889916)
					(mid 316.262512 -431.889916)
					(end 317.036704 -431.889916)
				)
			)
		)
	)
	(zone
		(layers "B.Cu" "In13.Cu" "In15.Cu")
		(hatch none 0.5)
		(connect_pads
			(clearance 0)
		)
		(min_thickness 0.25)
		(keepout
			(tracks not_allowed)
			(vias allowed)
			(pads allowed)
			(copperpour not_allowed)
			(footprints allowed)
		)
		(placement
			(enabled no)
			(sheetname "")
		)
		(fill yes
			(thermal_gap 0.5)
			(thermal_bridge_width 0.5)
			(island_removal_mode 0)
		)
		(polygon
			(pts
				(arc
					(start 265.88212 -243.234972)
					(mid 265.2141 -243.234972)
					(end 265.88212 -243.234972)
				)
			)
		)
	)
	(zone
		(layers "B.Cu" "In13.Cu" "In15.Cu")
		(hatch none 0.5)
		(connect_pads
			(clearance 0)
		)
		(min_thickness 0.25)
		(keepout
			(tracks not_allowed)
			(vias allowed)
			(pads allowed)
			(copperpour not_allowed)
			(footprints allowed)
		)
		(placement
			(enabled no)
			(sheetname "")
		)
		(fill yes
			(thermal_gap 0.5)
			(thermal_bridge_width 0.5)
			(island_removal_mode 0)
		)
		(polygon
			(pts
				(arc
					(start 332.036928 -429.689768)
					(mid 331.262736 -429.689768)
					(end 332.036928 -429.689768)
				)
			)
		)
	)
	(zone
		(layers "B.Cu" "In13.Cu" "In15.Cu")
		(hatch none 0.5)
		(connect_pads
			(clearance 0)
		)
		(min_thickness 0.25)
		(keepout
			(tracks not_allowed)
			(vias allowed)
			(pads allowed)
			(copperpour not_allowed)
			(footprints allowed)
		)
		(placement
			(enabled no)
			(sheetname "")
		)
		(fill yes
			(thermal_gap 0.5)
			(thermal_bridge_width 0.5)
			(island_removal_mode 0)
		)
		(polygon
			(pts
				(arc
					(start 387.289802 -226.664266)
					(mid 386.659882 -226.664266)
					(end 387.289802 -226.664266)
				)
			)
		)
	)
	(zone
		(layers "B.Cu" "In13.Cu" "In15.Cu")
		(hatch none 0.5)
		(connect_pads
			(clearance 0)
		)
		(min_thickness 0.25)
		(keepout
			(tracks not_allowed)
			(vias allowed)
			(pads allowed)
			(copperpour not_allowed)
			(footprints allowed)
		)
		(placement
			(enabled no)
			(sheetname "")
		)
		(fill yes
			(thermal_gap 0.5)
			(thermal_bridge_width 0.5)
			(island_removal_mode 0)
		)
		(polygon
			(pts
				(arc
					(start 450.42201 -305.28514)
					(mid 449.75399 -305.28514)
					(end 450.42201 -305.28514)
				)
			)
		)
	)
	(zone
		(layers "B.Cu" "In13.Cu" "In15.Cu")
		(hatch none 0.5)
		(connect_pads
			(clearance 0)
		)
		(min_thickness 0.25)
		(keepout
			(tracks not_allowed)
			(vias allowed)
			(pads allowed)
			(copperpour not_allowed)
			(footprints allowed)
		)
		(placement
			(enabled no)
			(sheetname "")
		)
		(fill yes
			(thermal_gap 0.5)
			(thermal_bridge_width 0.5)
			(island_removal_mode 0)
		)
		(polygon
			(pts
				(arc
					(start 103.636064 -246.10441)
					(mid 103.006144 -246.10441)
					(end 103.636064 -246.10441)
				)
			)
		)
	)
	(zone
		(layers "B.Cu" "In13.Cu" "In15.Cu")
		(hatch none 0.5)
		(connect_pads
			(clearance 0)
		)
		(min_thickness 0.25)
		(keepout
			(tracks not_allowed)
			(vias allowed)
			(pads allowed)
			(copperpour not_allowed)
			(footprints allowed)
		)
		(placement
			(enabled no)
			(sheetname "")
		)
		(fill yes
			(thermal_gap 0.5)
			(thermal_bridge_width 0.5)
			(island_removal_mode 0)
		)
		(polygon
			(pts
				(arc
					(start 86.545928 -280.566368)
					(mid 85.916008 -280.566368)
					(end 86.545928 -280.566368)
				)
			)
		)
	)
	(zone
		(layers "B.Cu" "In13.Cu" "In15.Cu")
		(hatch none 0.5)
		(connect_pads
			(clearance 0)
		)
		(min_thickness 0.25)
		(keepout
			(tracks not_allowed)
			(vias allowed)
			(pads allowed)
			(copperpour not_allowed)
			(footprints allowed)
		)
		(placement
			(enabled no)
			(sheetname "")
		)
		(fill yes
			(thermal_gap 0.5)
			(thermal_bridge_width 0.5)
			(island_removal_mode 0)
		)
		(polygon
			(pts
				(arc
					(start 333.076042 -291.095938)
					(mid 332.446122 -291.095938)
					(end 333.076042 -291.095938)
				)
			)
		)
	)
	(zone
		(layers "B.Cu" "In13.Cu" "In15.Cu")
		(hatch none 0.5)
		(connect_pads
			(clearance 0)
		)
		(min_thickness 0.25)
		(keepout
			(tracks not_allowed)
			(vias allowed)
			(pads allowed)
			(copperpour not_allowed)
			(footprints allowed)
		)
		(placement
			(enabled no)
			(sheetname "")
		)
		(fill yes
			(thermal_gap 0.5)
			(thermal_bridge_width 0.5)
			(island_removal_mode 0)
		)
		(polygon
			(pts
				(arc
					(start 138.709654 -273.276314)
					(mid 138.079734 -273.276314)
					(end 138.709654 -273.276314)
				)
			)
		)
	)
	(zone
		(layers "B.Cu" "In13.Cu" "In15.Cu")
		(hatch none 0.5)
		(connect_pads
			(clearance 0)
		)
		(min_thickness 0.25)
		(keepout
			(tracks not_allowed)
			(vias allowed)
			(pads allowed)
			(copperpour not_allowed)
			(footprints allowed)
		)
		(placement
			(enabled no)
			(sheetname "")
		)
		(fill yes
			(thermal_gap 0.5)
			(thermal_bridge_width 0.5)
			(island_removal_mode 0)
		)
		(polygon
			(pts
				(arc
					(start 17.942052 -250.035314)
					(mid 17.274032 -250.035314)
					(end 17.942052 -250.035314)
				)
			)
		)
	)
	(zone
		(layers "B.Cu" "In13.Cu" "In15.Cu")
		(hatch none 0.5)
		(connect_pads
			(clearance 0)
		)
		(min_thickness 0.25)
		(keepout
			(tracks not_allowed)
			(vias allowed)
			(pads allowed)
			(copperpour not_allowed)
			(footprints allowed)
		)
		(placement
			(enabled no)
			(sheetname "")
		)
		(fill yes
			(thermal_gap 0.5)
			(thermal_bridge_width 0.5)
			(island_removal_mode 0)
		)
		(polygon
			(pts
				(arc
					(start 82.234024 -389.467344)
					(mid 81.604104 -389.467344)
					(end 82.234024 -389.467344)
				)
			)
		)
	)
	(zone
		(layers "B.Cu" "In13.Cu" "In15.Cu")
		(hatch none 0.5)
		(connect_pads
			(clearance 0)
		)
		(min_thickness 0.25)
		(keepout
			(tracks not_allowed)
			(vias allowed)
			(pads allowed)
			(copperpour not_allowed)
			(footprints allowed)
		)
		(placement
			(enabled no)
			(sheetname "")
		)
		(fill yes
			(thermal_gap 0.5)
			(thermal_bridge_width 0.5)
			(island_removal_mode 0)
		)
		(polygon
			(pts
				(arc
					(start 48.991774 -412.570168)
					(mid 48.323754 -412.570168)
					(end 48.991774 -412.570168)
				)
			)
		)
	)
	(zone
		(layers "B.Cu" "In13.Cu" "In15.Cu")
		(hatch none 0.5)
		(connect_pads
			(clearance 0)
		)
		(min_thickness 0.25)
		(keepout
			(tracks not_allowed)
			(vias allowed)
			(pads allowed)
			(copperpour not_allowed)
			(footprints allowed)
		)
		(placement
			(enabled no)
			(sheetname "")
		)
		(fill yes
			(thermal_gap 0.5)
			(thermal_bridge_width 0.5)
			(island_removal_mode 0)
		)
		(polygon
			(pts
				(arc
					(start 387.759702 -255.014222)
					(mid 387.129782 -255.014222)
					(end 387.759702 -255.014222)
				)
			)
		)
	)
	(zone
		(layers "B.Cu" "In13.Cu" "In15.Cu")
		(hatch none 0.5)
		(connect_pads
			(clearance 0)
		)
		(min_thickness 0.25)
		(keepout
			(tracks not_allowed)
			(vias allowed)
			(pads allowed)
			(copperpour not_allowed)
			(footprints allowed)
		)
		(placement
			(enabled no)
			(sheetname "")
		)
		(fill yes
			(thermal_gap 0.5)
			(thermal_bridge_width 0.5)
			(island_removal_mode 0)
		)
		(polygon
			(pts
				(arc
					(start 22.04212 -233.035348)
					(mid 21.3741 -233.035348)
					(end 22.04212 -233.035348)
				)
			)
		)
	)
	(zone
		(layers "B.Cu" "In13.Cu" "In15.Cu")
		(hatch none 0.5)
		(connect_pads
			(clearance 0)
		)
		(min_thickness 0.25)
		(keepout
			(tracks not_allowed)
			(vias allowed)
			(pads allowed)
			(copperpour not_allowed)
			(footprints allowed)
		)
		(placement
			(enabled no)
			(sheetname "")
		)
		(fill yes
			(thermal_gap 0.5)
			(thermal_bridge_width 0.5)
			(island_removal_mode 0)
		)
		(polygon
			(pts
				(arc
					(start 386.179822 -283.806138)
					(mid 385.549902 -283.806138)
					(end 386.179822 -283.806138)
				)
			)
		)
	)
	(zone
		(layers "B.Cu" "In13.Cu" "In15.Cu")
		(hatch none 0.5)
		(connect_pads
			(clearance 0)
		)
		(min_thickness 0.25)
		(keepout
			(tracks not_allowed)
			(vias allowed)
			(pads allowed)
			(copperpour not_allowed)
			(footprints allowed)
		)
		(placement
			(enabled no)
			(sheetname "")
		)
		(fill yes
			(thermal_gap 0.5)
			(thermal_bridge_width 0.5)
			(island_removal_mode 0)
		)
		(polygon
			(pts
				(arc
					(start 91.433904 -388.774432)
					(mid 90.803984 -388.774432)
					(end 91.433904 -388.774432)
				)
			)
		)
	)
	(zone
		(layers "B.Cu" "In13.Cu" "In15.Cu")
		(hatch none 0.5)
		(connect_pads
			(clearance 0)
		)
		(min_thickness 0.25)
		(keepout
			(tracks not_allowed)
			(vias allowed)
			(pads allowed)
			(copperpour not_allowed)
			(footprints allowed)
		)
		(placement
			(enabled no)
			(sheetname "")
		)
		(fill yes
			(thermal_gap 0.5)
			(thermal_bridge_width 0.5)
			(island_removal_mode 0)
		)
		(polygon
			(pts
				(arc
					(start 387.589776 -273.27606)
					(mid 386.959856 -273.27606)
					(end 387.589776 -273.27606)
				)
			)
		)
	)
	(zone
		(layers "B.Cu" "In13.Cu" "In15.Cu")
		(hatch none 0.5)
		(connect_pads
			(clearance 0)
		)
		(min_thickness 0.25)
		(keepout
			(tracks not_allowed)
			(vias allowed)
			(pads allowed)
			(copperpour not_allowed)
			(footprints allowed)
		)
		(placement
			(enabled no)
			(sheetname "")
		)
		(fill yes
			(thermal_gap 0.5)
			(thermal_bridge_width 0.5)
			(island_removal_mode 0)
		)
		(polygon
			(pts
				(arc
					(start 269.982188 -267.885164)
					(mid 269.314168 -267.885164)
					(end 269.982188 -267.885164)
				)
			)
		)
	)
	(zone
		(layers "B.Cu" "In13.Cu" "In15.Cu")
		(hatch none 0.5)
		(connect_pads
			(clearance 0)
		)
		(min_thickness 0.25)
		(keepout
			(tracks not_allowed)
			(vias allowed)
			(pads allowed)
			(copperpour not_allowed)
			(footprints allowed)
		)
		(placement
			(enabled no)
			(sheetname "")
		)
		(fill yes
			(thermal_gap 0.5)
			(thermal_bridge_width 0.5)
			(island_removal_mode 0)
		)
		(polygon
			(pts
				(arc
					(start 158.113476 -412.570168)
					(mid 157.445456 -412.570168)
					(end 158.113476 -412.570168)
				)
			)
		)
	)
	(zone
		(layers "B.Cu" "In13.Cu" "In15.Cu")
		(hatch none 0.5)
		(connect_pads
			(clearance 0)
		)
		(min_thickness 0.25)
		(keepout
			(tracks not_allowed)
			(vias allowed)
			(pads allowed)
			(copperpour not_allowed)
			(footprints allowed)
		)
		(placement
			(enabled no)
			(sheetname "")
		)
		(fill yes
			(thermal_gap 0.5)
			(thermal_bridge_width 0.5)
			(island_removal_mode 0)
		)
		(polygon
			(pts
				(arc
					(start 84.63407 -386.003292)
					(mid 84.00415 -386.003292)
					(end 84.63407 -386.003292)
				)
			)
		)
	)
	(zone
		(layers "B.Cu" "In13.Cu" "In15.Cu")
		(hatch none 0.5)
		(connect_pads
			(clearance 0)
		)
		(min_thickness 0.25)
		(keepout
			(tracks not_allowed)
			(vias allowed)
			(pads allowed)
			(copperpour not_allowed)
			(footprints allowed)
		)
		(placement
			(enabled no)
			(sheetname "")
		)
		(fill yes
			(thermal_gap 0.5)
			(thermal_bridge_width 0.5)
			(island_removal_mode 0)
		)
		(polygon
			(pts
				(arc
					(start 90.634058 -386.003292)
					(mid 90.004138 -386.003292)
					(end 90.634058 -386.003292)
				)
			)
		)
	)
	(zone
		(layers "B.Cu" "In13.Cu" "In15.Cu")
		(hatch none 0.5)
		(connect_pads
			(clearance 0)
		)
		(min_thickness 0.25)
		(keepout
			(tracks not_allowed)
			(vias allowed)
			(pads allowed)
			(copperpour not_allowed)
			(footprints allowed)
		)
		(placement
			(enabled no)
			(sheetname "")
		)
		(fill yes
			(thermal_gap 0.5)
			(thermal_bridge_width 0.5)
			(island_removal_mode 0)
		)
		(polygon
			(pts
				(arc
					(start 332.306168 -256.634234)
					(mid 331.676248 -256.634234)
					(end 332.306168 -256.634234)
				)
			)
		)
	)
	(zone
		(layers "B.Cu" "In13.Cu" "In15.Cu")
		(hatch none 0.5)
		(connect_pads
			(clearance 0)
		)
		(min_thickness 0.25)
		(keepout
			(tracks not_allowed)
			(vias allowed)
			(pads allowed)
			(copperpour not_allowed)
			(footprints allowed)
		)
		(placement
			(enabled no)
			(sheetname "")
		)
		(fill yes
			(thermal_gap 0.5)
			(thermal_bridge_width 0.5)
			(island_removal_mode 0)
		)
		(polygon
			(pts
				(arc
					(start 52.52974 -19.13636)
					(mid 51.86172 -19.13636)
					(end 52.52974 -19.13636)
				)
			)
		)
	)
	(zone
		(layers "B.Cu" "In13.Cu" "In15.Cu")
		(hatch none 0.5)
		(connect_pads
			(clearance 0)
		)
		(min_thickness 0.25)
		(keepout
			(tracks not_allowed)
			(vias allowed)
			(pads allowed)
			(copperpour not_allowed)
			(footprints allowed)
		)
		(placement
			(enabled no)
			(sheetname "")
		)
		(fill yes
			(thermal_gap 0.5)
			(thermal_bridge_width 0.5)
			(island_removal_mode 0)
		)
		(polygon
			(pts
				(arc
					(start 387.589776 -270.036036)
					(mid 386.959856 -270.036036)
					(end 387.589776 -270.036036)
				)
			)
		)
	)
	(zone
		(layers "B.Cu" "In13.Cu" "In15.Cu")
		(hatch none 0.5)
		(connect_pads
			(clearance 0)
		)
		(min_thickness 0.25)
		(keepout
			(tracks not_allowed)
			(vias allowed)
			(pads allowed)
			(copperpour not_allowed)
			(footprints allowed)
		)
		(placement
			(enabled no)
			(sheetname "")
		)
		(fill yes
			(thermal_gap 0.5)
			(thermal_bridge_width 0.5)
			(island_removal_mode 0)
		)
		(polygon
			(pts
				(arc
					(start 334.186022 -242.054126)
					(mid 333.556102 -242.054126)
					(end 334.186022 -242.054126)
				)
			)
		)
	)
	(zone
		(layers "B.Cu" "In13.Cu" "In15.Cu")
		(hatch none 0.5)
		(connect_pads
			(clearance 0)
		)
		(min_thickness 0.25)
		(keepout
			(tracks not_allowed)
			(vias allowed)
			(pads allowed)
			(copperpour not_allowed)
			(footprints allowed)
		)
		(placement
			(enabled no)
			(sheetname "")
		)
		(fill yes
			(thermal_gap 0.5)
			(thermal_bridge_width 0.5)
			(island_removal_mode 0)
		)
		(polygon
			(pts
				(arc
					(start 85.776054 -231.524302)
					(mid 85.146134 -231.524302)
					(end 85.776054 -231.524302)
				)
			)
		)
	)
	(zone
		(layers "B.Cu" "In13.Cu" "In15.Cu")
		(hatch none 0.5)
		(connect_pads
			(clearance 0)
		)
		(min_thickness 0.25)
		(keepout
			(tracks not_allowed)
			(vias allowed)
			(pads allowed)
			(copperpour not_allowed)
			(footprints allowed)
		)
		(placement
			(enabled no)
			(sheetname "")
		)
		(fill yes
			(thermal_gap 0.5)
			(thermal_bridge_width 0.5)
			(island_removal_mode 0)
		)
		(polygon
			(pts
				(arc
					(start 146.724116 -412.570168)
					(mid 146.056096 -412.570168)
					(end 146.724116 -412.570168)
				)
			)
		)
	)
	(zone
		(layers "B.Cu" "In13.Cu" "In15.Cu")
		(hatch none 0.5)
		(connect_pads
			(clearance 0)
		)
		(min_thickness 0.25)
		(keepout
			(tracks not_allowed)
			(vias allowed)
			(pads allowed)
			(copperpour not_allowed)
			(footprints allowed)
		)
		(placement
			(enabled no)
			(sheetname "")
		)
		(fill yes
			(thermal_gap 0.5)
			(thermal_bridge_width 0.5)
			(island_removal_mode 0)
		)
		(polygon
			(pts
				(arc
					(start 332.776068 -229.904036)
					(mid 332.146148 -229.904036)
					(end 332.776068 -229.904036)
				)
			)
		)
	)
	(zone
		(layers "B.Cu" "In13.Cu" "In15.Cu")
		(hatch none 0.5)
		(connect_pads
			(clearance 0)
		)
		(min_thickness 0.25)
		(keepout
			(tracks not_allowed)
			(vias allowed)
			(pads allowed)
			(copperpour not_allowed)
			(footprints allowed)
		)
		(placement
			(enabled no)
			(sheetname "")
		)
		(fill yes
			(thermal_gap 0.5)
			(thermal_bridge_width 0.5)
			(island_removal_mode 0)
		)
		(polygon
			(pts
				(arc
					(start 58.98134 -19.13636)
					(mid 58.31332 -19.13636)
					(end 58.98134 -19.13636)
				)
			)
		)
	)
	(zone
		(layers "B.Cu" "In13.Cu" "In15.Cu")
		(hatch none 0.5)
		(connect_pads
			(clearance 0)
		)
		(min_thickness 0.25)
		(keepout
			(tracks not_allowed)
			(vias allowed)
			(pads allowed)
			(copperpour not_allowed)
			(footprints allowed)
		)
		(placement
			(enabled no)
			(sheetname "")
		)
		(fill yes
			(thermal_gap 0.5)
			(thermal_bridge_width 0.5)
			(island_removal_mode 0)
		)
		(polygon
			(pts
				(arc
					(start 386.032502 -382.34493)
					(mid 385.364482 -382.34493)
					(end 386.032502 -382.34493)
				)
			)
		)
	)
	(zone
		(layers "B.Cu" "In13.Cu" "In15.Cu")
		(hatch none 0.5)
		(connect_pads
			(clearance 0)
		)
		(min_thickness 0.25)
		(keepout
			(tracks not_allowed)
			(vias allowed)
			(pads allowed)
			(copperpour not_allowed)
			(footprints allowed)
		)
		(placement
			(enabled no)
			(sheetname "")
		)
		(fill yes
			(thermal_gap 0.5)
			(thermal_bridge_width 0.5)
			(island_removal_mode 0)
		)
		(polygon
			(pts
				(arc
					(start 86.545928 -275.706332)
					(mid 85.916008 -275.706332)
					(end 86.545928 -275.706332)
				)
			)
		)
	)
	(zone
		(layers "B.Cu" "In13.Cu" "In15.Cu")
		(hatch none 0.5)
		(connect_pads
			(clearance 0)
		)
		(min_thickness 0.25)
		(keepout
			(tracks not_allowed)
			(vias allowed)
			(pads allowed)
			(copperpour not_allowed)
			(footprints allowed)
		)
		(placement
			(enabled no)
			(sheetname "")
		)
		(fill yes
			(thermal_gap 0.5)
			(thermal_bridge_width 0.5)
			(island_removal_mode 0)
		)
		(polygon
			(pts
				(arc
					(start 319.0367 -430.889918)
					(mid 318.262508 -430.889918)
					(end 319.0367 -430.889918)
				)
			)
		)
	)
	(zone
		(layers "B.Cu" "In13.Cu" "In15.Cu")
		(hatch none 0.5)
		(connect_pads
			(clearance 0)
		)
		(min_thickness 0.25)
		(keepout
			(tracks not_allowed)
			(vias allowed)
			(pads allowed)
			(copperpour not_allowed)
			(footprints allowed)
		)
		(placement
			(enabled no)
			(sheetname "")
		)
		(fill yes
			(thermal_gap 0.5)
			(thermal_bridge_width 0.5)
			(island_removal_mode 0)
		)
		(polygon
			(pts
				(arc
					(start 454.522078 -312.935112)
					(mid 453.854058 -312.935112)
					(end 454.522078 -312.935112)
				)
			)
		)
	)
	(zone
		(layers "B.Cu" "In13.Cu" "In15.Cu")
		(hatch none 0.5)
		(connect_pads
			(clearance 0)
		)
		(min_thickness 0.25)
		(keepout
			(tracks not_allowed)
			(vias allowed)
			(pads allowed)
			(copperpour not_allowed)
			(footprints allowed)
		)
		(placement
			(enabled no)
			(sheetname "")
		)
		(fill yes
			(thermal_gap 0.5)
			(thermal_bridge_width 0.5)
			(island_removal_mode 0)
		)
		(polygon
			(pts
				(arc
					(start 138.239754 -282.18638)
					(mid 137.609834 -282.18638)
					(end 138.239754 -282.18638)
				)
			)
		)
	)
	(zone
		(layers "B.Cu" "In13.Cu" "In15.Cu")
		(hatch none 0.5)
		(connect_pads
			(clearance 0)
		)
		(min_thickness 0.25)
		(keepout
			(tracks not_allowed)
			(vias allowed)
			(pads allowed)
			(copperpour not_allowed)
			(footprints allowed)
		)
		(placement
			(enabled no)
			(sheetname "")
		)
		(fill yes
			(thermal_gap 0.5)
			(thermal_bridge_width 0.5)
			(island_removal_mode 0)
		)
		(polygon
			(pts
				(arc
					(start 85.135974 -284.616398)
					(mid 84.506054 -284.616398)
					(end 85.135974 -284.616398)
				)
			)
		)
	)
	(zone
		(layers "B.Cu" "In13.Cu" "In15.Cu")
		(hatch none 0.5)
		(connect_pads
			(clearance 0)
		)
		(min_thickness 0.25)
		(keepout
			(tracks not_allowed)
			(vias allowed)
			(pads allowed)
			(copperpour not_allowed)
			(footprints allowed)
		)
		(placement
			(enabled no)
			(sheetname "")
		)
		(fill yes
			(thermal_gap 0.5)
			(thermal_bridge_width 0.5)
			(island_removal_mode 0)
		)
		(polygon
			(pts
				(arc
					(start 396.136876 -431.889916)
					(mid 395.362684 -431.889916)
					(end 396.136876 -431.889916)
				)
			)
		)
	)
	(zone
		(layers "B.Cu" "In13.Cu" "In15.Cu")
		(hatch none 0.5)
		(connect_pads
			(clearance 0)
		)
		(min_thickness 0.25)
		(keepout
			(tracks not_allowed)
			(vias allowed)
			(pads allowed)
			(copperpour not_allowed)
			(footprints allowed)
		)
		(placement
			(enabled no)
			(sheetname "")
		)
		(fill yes
			(thermal_gap 0.5)
			(thermal_bridge_width 0.5)
			(island_removal_mode 0)
		)
		(polygon
			(pts
				(arc
					(start 386.179822 -280.566114)
					(mid 385.549902 -280.566114)
					(end 386.179822 -280.566114)
				)
			)
		)
	)
	(zone
		(layers "B.Cu" "In13.Cu" "In15.Cu")
		(hatch none 0.5)
		(connect_pads
			(clearance 0)
		)
		(min_thickness 0.25)
		(keepout
			(tracks not_allowed)
			(vias allowed)
			(pads allowed)
			(copperpour not_allowed)
			(footprints allowed)
		)
		(placement
			(enabled no)
			(sheetname "")
		)
		(fill yes
			(thermal_gap 0.5)
			(thermal_bridge_width 0.5)
			(island_removal_mode 0)
		)
		(polygon
			(pts
				(arc
					(start 454.522078 -214.335106)
					(mid 453.854058 -214.335106)
					(end 454.522078 -214.335106)
				)
			)
		)
	)
	(zone
		(layers "B.Cu" "In13.Cu" "In15.Cu")
		(hatch none 0.5)
		(connect_pads
			(clearance 0)
		)
		(min_thickness 0.25)
		(keepout
			(tracks not_allowed)
			(vias allowed)
			(pads allowed)
			(copperpour not_allowed)
			(footprints allowed)
		)
		(placement
			(enabled no)
			(sheetname "")
		)
		(fill yes
			(thermal_gap 0.5)
			(thermal_bridge_width 0.5)
			(island_removal_mode 0)
		)
		(polygon
			(pts
				(arc
					(start 139.649708 -286.23641)
					(mid 139.019788 -286.23641)
					(end 139.649708 -286.23641)
				)
			)
		)
	)
	(zone
		(layers "B.Cu" "In13.Cu" "In15.Cu")
		(hatch none 0.5)
		(connect_pads
			(clearance 0)
		)
		(min_thickness 0.25)
		(keepout
			(tracks not_allowed)
			(vias allowed)
			(pads allowed)
			(copperpour not_allowed)
			(footprints allowed)
		)
		(placement
			(enabled no)
			(sheetname "")
		)
		(fill yes
			(thermal_gap 0.5)
			(thermal_bridge_width 0.5)
			(island_removal_mode 0)
		)
		(polygon
			(pts
				(arc
					(start 109.746034 -246.914416)
					(mid 109.116114 -246.914416)
					(end 109.746034 -246.914416)
				)
			)
		)
	)
	(zone
		(layers "B.Cu" "In13.Cu" "In15.Cu")
		(hatch none 0.5)
		(connect_pads
			(clearance 0)
		)
		(min_thickness 0.25)
		(keepout
			(tracks not_allowed)
			(vias allowed)
			(pads allowed)
			(copperpour not_allowed)
			(footprints allowed)
		)
		(placement
			(enabled no)
			(sheetname "")
		)
		(fill yes
			(thermal_gap 0.5)
			(thermal_bridge_width 0.5)
			(island_removal_mode 0)
		)
		(polygon
			(pts
				(arc
					(start 84.3661 -235.574332)
					(mid 83.73618 -235.574332)
					(end 84.3661 -235.574332)
				)
			)
		)
	)
	(zone
		(layers "B.Cu" "In13.Cu" "In15.Cu")
		(hatch none 0.5)
		(connect_pads
			(clearance 0)
		)
		(min_thickness 0.25)
		(keepout
			(tracks not_allowed)
			(vias allowed)
			(pads allowed)
			(copperpour not_allowed)
			(footprints allowed)
		)
		(placement
			(enabled no)
			(sheetname "")
		)
		(fill yes
			(thermal_gap 0.5)
			(thermal_bridge_width 0.5)
			(island_removal_mode 0)
		)
		(polygon
			(pts
				(arc
					(start 265.88212 -227.935028)
					(mid 265.2141 -227.935028)
					(end 265.88212 -227.935028)
				)
			)
		)
	)
	(zone
		(layers "B.Cu" "In13.Cu" "In15.Cu")
		(hatch none 0.5)
		(connect_pads
			(clearance 0)
		)
		(min_thickness 0.25)
		(keepout
			(tracks not_allowed)
			(vias allowed)
			(pads allowed)
			(copperpour not_allowed)
			(footprints allowed)
		)
		(placement
			(enabled no)
			(sheetname "")
		)
		(fill yes
			(thermal_gap 0.5)
			(thermal_bridge_width 0.5)
			(island_removal_mode 0)
		)
		(polygon
			(pts
				(arc
					(start 155.050236 -412.570168)
					(mid 154.382216 -412.570168)
					(end 155.050236 -412.570168)
				)
			)
		)
	)
	(zone
		(layers "B.Cu" "In13.Cu" "In15.Cu")
		(hatch none 0.5)
		(connect_pads
			(clearance 0)
		)
		(min_thickness 0.25)
		(keepout
			(tracks not_allowed)
			(vias allowed)
			(pads allowed)
			(copperpour not_allowed)
			(footprints allowed)
		)
		(placement
			(enabled no)
			(sheetname "")
		)
		(fill yes
			(thermal_gap 0.5)
			(thermal_bridge_width 0.5)
			(island_removal_mode 0)
		)
		(polygon
			(pts
				(arc
					(start 206.58201 -283.185362)
					(mid 205.91399 -283.185362)
					(end 206.58201 -283.185362)
				)
			)
		)
	)
	(zone
		(layers "B.Cu" "In13.Cu" "In15.Cu")
		(hatch none 0.5)
		(connect_pads
			(clearance 0)
		)
		(min_thickness 0.25)
		(keepout
			(tracks not_allowed)
			(vias allowed)
			(pads allowed)
			(copperpour not_allowed)
			(footprints allowed)
		)
		(placement
			(enabled no)
			(sheetname "")
		)
		(fill yes
			(thermal_gap 0.5)
			(thermal_bridge_width 0.5)
			(island_removal_mode 0)
		)
		(polygon
			(pts
				(arc
					(start 385.879848 -245.29415)
					(mid 385.249928 -245.29415)
					(end 385.879848 -245.29415)
				)
			)
		)
	)
	(zone
		(layers "B.Cu" "In13.Cu" "In15.Cu")
		(hatch none 0.5)
		(connect_pads
			(clearance 0)
		)
		(min_thickness 0.25)
		(keepout
			(tracks not_allowed)
			(vias allowed)
			(pads allowed)
			(copperpour not_allowed)
			(footprints allowed)
		)
		(placement
			(enabled no)
			(sheetname "")
		)
		(fill yes
			(thermal_gap 0.5)
			(thermal_bridge_width 0.5)
			(island_removal_mode 0)
		)
		(polygon
			(pts
				(arc
					(start 387.759702 -240.434114)
					(mid 387.129782 -240.434114)
					(end 387.759702 -240.434114)
				)
			)
		)
	)
	(zone
		(layers "B.Cu" "In13.Cu" "In15.Cu")
		(hatch none 0.5)
		(connect_pads
			(clearance 0)
		)
		(min_thickness 0.25)
		(keepout
			(tracks not_allowed)
			(vias allowed)
			(pads allowed)
			(copperpour not_allowed)
			(footprints allowed)
		)
		(placement
			(enabled no)
			(sheetname "")
		)
		(fill yes
			(thermal_gap 0.5)
			(thermal_bridge_width 0.5)
			(island_removal_mode 0)
		)
		(polygon
			(pts
				(arc
					(start 78.760574 -412.570168)
					(mid 78.092554 -412.570168)
					(end 78.760574 -412.570168)
				)
			)
		)
	)
	(zone
		(layers "B.Cu" "In13.Cu" "In15.Cu")
		(hatch none 0.5)
		(connect_pads
			(clearance 0)
		)
		(min_thickness 0.25)
		(keepout
			(tracks not_allowed)
			(vias allowed)
			(pads allowed)
			(copperpour not_allowed)
			(footprints allowed)
		)
		(placement
			(enabled no)
			(sheetname "")
		)
		(fill yes
			(thermal_gap 0.5)
			(thermal_bridge_width 0.5)
			(island_removal_mode 0)
		)
		(polygon
			(pts
				(arc
					(start 206.58201 -279.785318)
					(mid 205.91399 -279.785318)
					(end 206.58201 -279.785318)
				)
			)
		)
	)
	(zone
		(layers "B.Cu" "In13.Cu" "In15.Cu")
		(hatch none 0.5)
		(connect_pads
			(clearance 0)
		)
		(min_thickness 0.25)
		(keepout
			(tracks not_allowed)
			(vias allowed)
			(pads allowed)
			(copperpour not_allowed)
			(footprints allowed)
		)
		(placement
			(enabled no)
			(sheetname "")
		)
		(fill yes
			(thermal_gap 0.5)
			(thermal_bridge_width 0.5)
			(island_removal_mode 0)
		)
		(polygon
			(pts
				(arc
					(start 22.04212 -221.985332)
					(mid 21.3741 -221.985332)
					(end 22.04212 -221.985332)
				)
			)
		)
	)
	(zone
		(layers "B.Cu" "In13.Cu" "In15.Cu")
		(hatch none 0.5)
		(connect_pads
			(clearance 0)
		)
		(min_thickness 0.25)
		(keepout
			(tracks not_allowed)
			(vias allowed)
			(pads allowed)
			(copperpour not_allowed)
			(footprints allowed)
		)
		(placement
			(enabled no)
			(sheetname "")
		)
		(fill yes
			(thermal_gap 0.5)
			(thermal_bridge_width 0.5)
			(island_removal_mode 0)
		)
		(polygon
			(pts
				(arc
					(start 17.942052 -239.835436)
					(mid 17.274032 -239.835436)
					(end 17.942052 -239.835436)
				)
			)
		)
	)
	(zone
		(layers "B.Cu" "In13.Cu" "In15.Cu")
		(hatch none 0.5)
		(connect_pads
			(clearance 0)
		)
		(min_thickness 0.25)
		(keepout
			(tracks not_allowed)
			(vias allowed)
			(pads allowed)
			(copperpour not_allowed)
			(footprints allowed)
		)
		(placement
			(enabled no)
			(sheetname "")
		)
		(fill yes
			(thermal_gap 0.5)
			(thermal_bridge_width 0.5)
			(island_removal_mode 0)
		)
		(polygon
			(pts
				(arc
					(start 32.630872 -17.613122)
					(mid 31.962852 -17.613122)
					(end 32.630872 -17.613122)
				)
			)
		)
	)
	(zone
		(layers "B.Cu" "In13.Cu" "In15.Cu")
		(hatch none 0.5)
		(connect_pads
			(clearance 0)
		)
		(min_thickness 0.25)
		(keepout
			(tracks not_allowed)
			(vias allowed)
			(pads allowed)
			(copperpour not_allowed)
			(footprints allowed)
		)
		(placement
			(enabled no)
			(sheetname "")
		)
		(fill yes
			(thermal_gap 0.5)
			(thermal_bridge_width 0.5)
			(island_removal_mode 0)
		)
		(polygon
			(pts
				(arc
					(start 147.13712 -430.889918)
					(mid 146.362928 -430.889918)
					(end 147.13712 -430.889918)
				)
			)
		)
	)
	(zone
		(layers "B.Cu" "In13.Cu" "In15.Cu")
		(hatch none 0.5)
		(connect_pads
			(clearance 0)
		)
		(min_thickness 0.25)
		(keepout
			(tracks not_allowed)
			(vias allowed)
			(pads allowed)
			(copperpour not_allowed)
			(footprints allowed)
		)
		(placement
			(enabled no)
			(sheetname "")
		)
		(fill yes
			(thermal_gap 0.5)
			(thermal_bridge_width 0.5)
			(island_removal_mode 0)
		)
		(polygon
			(pts
				(arc
					(start 342.036908 -430.689766)
					(mid 341.262716 -430.689766)
					(end 342.036908 -430.689766)
				)
			)
		)
	)
	(zone
		(layers "B.Cu" "In13.Cu" "In15.Cu")
		(hatch none 0.5)
		(connect_pads
			(clearance 0)
		)
		(min_thickness 0.25)
		(keepout
			(tracks not_allowed)
			(vias allowed)
			(pads allowed)
			(copperpour not_allowed)
			(footprints allowed)
		)
		(placement
			(enabled no)
			(sheetname "")
		)
		(fill yes
			(thermal_gap 0.5)
			(thermal_bridge_width 0.5)
			(island_removal_mode 0)
		)
		(polygon
			(pts
				(arc
					(start 269.982188 -199.035162)
					(mid 269.314168 -199.035162)
					(end 269.982188 -199.035162)
				)
			)
		)
	)
	(zone
		(layers "B.Cu" "In13.Cu" "In15.Cu")
		(hatch none 0.5)
		(connect_pads
			(clearance 0)
		)
		(min_thickness 0.25)
		(keepout
			(tracks not_allowed)
			(vias allowed)
			(pads allowed)
			(copperpour not_allowed)
			(footprints allowed)
		)
		(placement
			(enabled no)
			(sheetname "")
		)
		(fill yes
			(thermal_gap 0.5)
			(thermal_bridge_width 0.5)
			(island_removal_mode 0)
		)
		(polygon
			(pts
				(arc
					(start 202.481942 -289.98545)
					(mid 201.813922 -289.98545)
					(end 202.481942 -289.98545)
				)
			)
		)
	)
	(zone
		(layers "B.Cu" "In13.Cu" "In15.Cu")
		(hatch none 0.5)
		(connect_pads
			(clearance 0)
		)
		(min_thickness 0.25)
		(keepout
			(tracks not_allowed)
			(vias allowed)
			(pads allowed)
			(copperpour not_allowed)
			(footprints allowed)
		)
		(placement
			(enabled no)
			(sheetname "")
		)
		(fill yes
			(thermal_gap 0.5)
			(thermal_bridge_width 0.5)
			(island_removal_mode 0)
		)
		(polygon
			(pts
				(arc
					(start 454.522078 -206.685134)
					(mid 453.854058 -206.685134)
					(end 454.522078 -206.685134)
				)
			)
		)
	)
	(zone
		(layers "B.Cu" "In13.Cu" "In15.Cu")
		(hatch none 0.5)
		(connect_pads
			(clearance 0)
		)
		(min_thickness 0.25)
		(keepout
			(tracks not_allowed)
			(vias allowed)
			(pads allowed)
			(copperpour not_allowed)
			(footprints allowed)
		)
		(placement
			(enabled no)
			(sheetname "")
		)
		(fill yes
			(thermal_gap 0.5)
			(thermal_bridge_width 0.5)
			(island_removal_mode 0)
		)
		(polygon
			(pts
				(arc
					(start 386.649722 -261.935976)
					(mid 386.019802 -261.935976)
					(end 386.649722 -261.935976)
				)
			)
		)
	)
	(zone
		(layers "B.Cu" "In13.Cu" "In15.Cu")
		(hatch none 0.5)
		(connect_pads
			(clearance 0)
		)
		(min_thickness 0.25)
		(keepout
			(tracks not_allowed)
			(vias allowed)
			(pads allowed)
			(copperpour not_allowed)
			(footprints allowed)
		)
		(placement
			(enabled no)
			(sheetname "")
		)
		(fill yes
			(thermal_gap 0.5)
			(thermal_bridge_width 0.5)
			(island_removal_mode 0)
		)
		(polygon
			(pts
				(arc
					(start 114.4397 -235.574332)
					(mid 113.80978 -235.574332)
					(end 114.4397 -235.574332)
				)
			)
		)
	)
	(zone
		(layers "B.Cu" "In13.Cu" "In15.Cu")
		(hatch none 0.5)
		(connect_pads
			(clearance 0)
		)
		(min_thickness 0.25)
		(keepout
			(tracks not_allowed)
			(vias allowed)
			(pads allowed)
			(copperpour not_allowed)
			(footprints allowed)
		)
		(placement
			(enabled no)
			(sheetname "")
		)
		(fill yes
			(thermal_gap 0.5)
			(thermal_bridge_width 0.5)
			(island_removal_mode 0)
		)
		(polygon
			(pts
				(arc
					(start 206.58201 -262.785352)
					(mid 205.91399 -262.785352)
					(end 206.58201 -262.785352)
				)
			)
		)
	)
	(zone
		(layers "B.Cu" "In13.Cu" "In15.Cu")
		(hatch none 0.5)
		(connect_pads
			(clearance 0)
		)
		(min_thickness 0.25)
		(keepout
			(tracks not_allowed)
			(vias allowed)
			(pads allowed)
			(copperpour not_allowed)
			(footprints allowed)
		)
		(placement
			(enabled no)
			(sheetname "")
		)
		(fill yes
			(thermal_gap 0.5)
			(thermal_bridge_width 0.5)
			(island_removal_mode 0)
		)
		(polygon
			(pts
				(arc
					(start 384.344672 -420.952168)
					(mid 383.676652 -420.952168)
					(end 384.344672 -420.952168)
				)
			)
		)
	)
	(zone
		(layers "B.Cu" "In13.Cu" "In15.Cu")
		(hatch none 0.5)
		(connect_pads
			(clearance 0)
		)
		(min_thickness 0.25)
		(keepout
			(tracks not_allowed)
			(vias allowed)
			(pads allowed)
			(copperpour not_allowed)
			(footprints allowed)
		)
		(placement
			(enabled no)
			(sheetname "")
		)
		(fill yes
			(thermal_gap 0.5)
			(thermal_bridge_width 0.5)
			(island_removal_mode 0)
		)
		(polygon
			(pts
				(arc
					(start 202.481942 -293.38524)
					(mid 201.813922 -293.38524)
					(end 202.481942 -293.38524)
				)
			)
		)
	)
	(zone
		(layers "B.Cu" "In13.Cu" "In15.Cu")
		(hatch none 0.5)
		(connect_pads
			(clearance 0)
		)
		(min_thickness 0.25)
		(keepout
			(tracks not_allowed)
			(vias allowed)
			(pads allowed)
			(copperpour not_allowed)
			(footprints allowed)
		)
		(placement
			(enabled no)
			(sheetname "")
		)
		(fill yes
			(thermal_gap 0.5)
			(thermal_bridge_width 0.5)
			(island_removal_mode 0)
		)
		(polygon
			(pts
				(arc
					(start 405.513286 -6.725158)
					(mid 404.845266 -6.725158)
					(end 405.513286 -6.725158)
				)
			)
		)
	)
	(zone
		(layers "B.Cu" "In13.Cu" "In15.Cu")
		(hatch none 0.5)
		(connect_pads
			(clearance 0)
		)
		(min_thickness 0.25)
		(keepout
			(tracks not_allowed)
			(vias allowed)
			(pads allowed)
			(copperpour not_allowed)
			(footprints allowed)
		)
		(placement
			(enabled no)
			(sheetname "")
		)
		(fill yes
			(thermal_gap 0.5)
			(thermal_bridge_width 0.5)
			(island_removal_mode 0)
		)
		(polygon
			(pts
				(arc
					(start 385.879848 -240.434114)
					(mid 385.249928 -240.434114)
					(end 385.879848 -240.434114)
				)
			)
		)
	)
	(zone
		(layers "B.Cu" "In13.Cu" "In15.Cu")
		(hatch none 0.5)
		(connect_pads
			(clearance 0)
		)
		(min_thickness 0.25)
		(keepout
			(tracks not_allowed)
			(vias allowed)
			(pads allowed)
			(copperpour not_allowed)
			(footprints allowed)
		)
		(placement
			(enabled no)
			(sheetname "")
		)
		(fill yes
			(thermal_gap 0.5)
			(thermal_bridge_width 0.5)
			(island_removal_mode 0)
		)
		(polygon
			(pts
				(arc
					(start 88.234012 -389.467344)
					(mid 87.604092 -389.467344)
					(end 88.234012 -389.467344)
				)
			)
		)
	)
	(zone
		(layers "B.Cu" "In13.Cu" "In15.Cu")
		(hatch none 0.5)
		(connect_pads
			(clearance 0)
		)
		(min_thickness 0.25)
		(keepout
			(tracks not_allowed)
			(vias allowed)
			(pads allowed)
			(copperpour not_allowed)
			(footprints allowed)
		)
		(placement
			(enabled no)
			(sheetname "")
		)
		(fill yes
			(thermal_gap 0.5)
			(thermal_bridge_width 0.5)
			(island_removal_mode 0)
		)
		(polygon
			(pts
				(arc
					(start 450.42201 -288.285174)
					(mid 449.75399 -288.285174)
					(end 450.42201 -288.285174)
				)
			)
		)
	)
	(zone
		(layers "B.Cu" "In13.Cu" "In15.Cu")
		(hatch none 0.5)
		(connect_pads
			(clearance 0)
		)
		(min_thickness 0.25)
		(keepout
			(tracks not_allowed)
			(vias allowed)
			(pads allowed)
			(copperpour not_allowed)
			(footprints allowed)
		)
		(placement
			(enabled no)
			(sheetname "")
		)
		(fill yes
			(thermal_gap 0.5)
			(thermal_bridge_width 0.5)
			(island_removal_mode 0)
		)
		(polygon
			(pts
				(arc
					(start 125.54966 -278.13635)
					(mid 124.91974 -278.13635)
					(end 125.54966 -278.13635)
				)
			)
		)
	)
	(zone
		(layers "B.Cu" "In13.Cu" "In15.Cu")
		(hatch none 0.5)
		(connect_pads
			(clearance 0)
		)
		(min_thickness 0.25)
		(keepout
			(tracks not_allowed)
			(vias allowed)
			(pads allowed)
			(copperpour not_allowed)
			(footprints allowed)
		)
		(placement
			(enabled no)
			(sheetname "")
		)
		(fill yes
			(thermal_gap 0.5)
			(thermal_bridge_width 0.5)
			(island_removal_mode 0)
		)
		(polygon
			(pts
				(arc
					(start 343.950036 -420.952168)
					(mid 343.282016 -420.952168)
					(end 343.950036 -420.952168)
				)
			)
		)
	)
	(zone
		(layers "B.Cu" "In13.Cu" "In15.Cu")
		(hatch none 0.5)
		(connect_pads
			(clearance 0)
		)
		(min_thickness 0.25)
		(keepout
			(tracks not_allowed)
			(vias allowed)
			(pads allowed)
			(copperpour not_allowed)
			(footprints allowed)
		)
		(placement
			(enabled no)
			(sheetname "")
		)
		(fill yes
			(thermal_gap 0.5)
			(thermal_bridge_width 0.5)
			(island_removal_mode 0)
		)
		(polygon
			(pts
				(arc
					(start 119.609616 -234.764326)
					(mid 118.979696 -234.764326)
					(end 119.609616 -234.764326)
				)
			)
		)
	)
	(zone
		(layers "B.Cu" "In13.Cu" "In15.Cu")
		(hatch none 0.5)
		(connect_pads
			(clearance 0)
		)
		(min_thickness 0.25)
		(keepout
			(tracks not_allowed)
			(vias allowed)
			(pads allowed)
			(copperpour not_allowed)
			(footprints allowed)
		)
		(placement
			(enabled no)
			(sheetname "")
		)
		(fill yes
			(thermal_gap 0.5)
			(thermal_bridge_width 0.5)
			(island_removal_mode 0)
		)
		(polygon
			(pts
				(arc
					(start 22.04212 -227.085398)
					(mid 21.3741 -227.085398)
					(end 22.04212 -227.085398)
				)
			)
		)
	)
	(zone
		(layers "B.Cu" "In13.Cu" "In15.Cu")
		(hatch none 0.5)
		(connect_pads
			(clearance 0)
		)
		(min_thickness 0.25)
		(keepout
			(tracks not_allowed)
			(vias allowed)
			(pads allowed)
			(copperpour not_allowed)
			(footprints allowed)
		)
		(placement
			(enabled no)
			(sheetname "")
		)
		(fill yes
			(thermal_gap 0.5)
			(thermal_bridge_width 0.5)
			(island_removal_mode 0)
		)
		(polygon
			(pts
				(arc
					(start 454.522078 -313.784996)
					(mid 453.854058 -313.784996)
					(end 454.522078 -313.784996)
				)
			)
		)
	)
	(zone
		(layers "B.Cu" "In13.Cu" "In15.Cu")
		(hatch none 0.5)
		(connect_pads
			(clearance 0)
		)
		(min_thickness 0.25)
		(keepout
			(tracks not_allowed)
			(vias allowed)
			(pads allowed)
			(copperpour not_allowed)
			(footprints allowed)
		)
		(placement
			(enabled no)
			(sheetname "")
		)
		(fill yes
			(thermal_gap 0.5)
			(thermal_bridge_width 0.5)
			(island_removal_mode 0)
		)
		(polygon
			(pts
				(arc
					(start 118.119906 -371.49913)
					(mid 117.451886 -371.49913)
					(end 118.119906 -371.49913)
				)
			)
		)
	)
	(zone
		(layers "B.Cu" "In13.Cu" "In15.Cu")
		(hatch none 0.5)
		(connect_pads
			(clearance 0)
		)
		(min_thickness 0.25)
		(keepout
			(tracks not_allowed)
			(vias allowed)
			(pads allowed)
			(copperpour not_allowed)
			(footprints allowed)
		)
		(placement
			(enabled no)
			(sheetname "")
		)
		(fill yes
			(thermal_gap 0.5)
			(thermal_bridge_width 0.5)
			(island_removal_mode 0)
		)
		(polygon
			(pts
				(arc
					(start 334.016096 -286.236156)
					(mid 333.386176 -286.236156)
					(end 334.016096 -286.236156)
				)
			)
		)
	)
	(zone
		(layers "B.Cu" "In13.Cu" "In15.Cu")
		(hatch none 0.5)
		(connect_pads
			(clearance 0)
		)
		(min_thickness 0.25)
		(keepout
			(tracks not_allowed)
			(vias allowed)
			(pads allowed)
			(copperpour not_allowed)
			(footprints allowed)
		)
		(placement
			(enabled no)
			(sheetname "")
		)
		(fill yes
			(thermal_gap 0.5)
			(thermal_bridge_width 0.5)
			(island_removal_mode 0)
		)
		(polygon
			(pts
				(arc
					(start 425.833286 -6.725158)
					(mid 425.165266 -6.725158)
					(end 425.833286 -6.725158)
				)
			)
		)
	)
	(zone
		(layers "B.Cu" "In13.Cu" "In15.Cu")
		(hatch none 0.5)
		(connect_pads
			(clearance 0)
		)
		(min_thickness 0.25)
		(keepout
			(tracks not_allowed)
			(vias allowed)
			(pads allowed)
			(copperpour not_allowed)
			(footprints allowed)
		)
		(placement
			(enabled no)
			(sheetname "")
		)
		(fill yes
			(thermal_gap 0.5)
			(thermal_bridge_width 0.5)
			(island_removal_mode 0)
		)
		(polygon
			(pts
				(arc
					(start 50.565304 -17.61236)
					(mid 49.897284 -17.61236)
					(end 50.565304 -17.61236)
				)
			)
		)
	)
	(zone
		(layers "B.Cu" "In13.Cu" "In15.Cu")
		(hatch none 0.5)
		(connect_pads
			(clearance 0)
		)
		(min_thickness 0.25)
		(keepout
			(tracks not_allowed)
			(vias allowed)
			(pads allowed)
			(copperpour not_allowed)
			(footprints allowed)
		)
		(placement
			(enabled no)
			(sheetname "")
		)
		(fill yes
			(thermal_gap 0.5)
			(thermal_bridge_width 0.5)
			(island_removal_mode 0)
		)
		(polygon
			(pts
				(arc
					(start 365.969804 -278.136096)
					(mid 365.339884 -278.136096)
					(end 365.969804 -278.136096)
				)
			)
		)
	)
	(zone
		(layers "B.Cu" "In13.Cu" "In15.Cu")
		(hatch none 0.5)
		(connect_pads
			(clearance 0)
		)
		(min_thickness 0.25)
		(keepout
			(tracks not_allowed)
			(vias allowed)
			(pads allowed)
			(copperpour not_allowed)
			(footprints allowed)
		)
		(placement
			(enabled no)
			(sheetname "")
		)
		(fill yes
			(thermal_gap 0.5)
			(thermal_bridge_width 0.5)
			(island_removal_mode 0)
		)
		(polygon
			(pts
				(arc
					(start 269.982188 -206.685134)
					(mid 269.314168 -206.685134)
					(end 269.982188 -206.685134)
				)
			)
		)
	)
	(zone
		(layers "B.Cu" "In13.Cu" "In15.Cu")
		(hatch none 0.5)
		(connect_pads
			(clearance 0)
		)
		(min_thickness 0.25)
		(keepout
			(tracks not_allowed)
			(vias allowed)
			(pads allowed)
			(copperpour not_allowed)
			(footprints allowed)
		)
		(placement
			(enabled no)
			(sheetname "")
		)
		(fill yes
			(thermal_gap 0.5)
			(thermal_bridge_width 0.5)
			(island_removal_mode 0)
		)
		(polygon
			(pts
				(arc
					(start 140.119608 -293.52621)
					(mid 139.489688 -293.52621)
					(end 140.119608 -293.52621)
				)
			)
		)
	)
	(zone
		(layers "B.Cu" "In13.Cu" "In15.Cu")
		(hatch none 0.5)
		(connect_pads
			(clearance 0)
		)
		(min_thickness 0.25)
		(keepout
			(tracks not_allowed)
			(vias allowed)
			(pads allowed)
			(copperpour not_allowed)
			(footprints allowed)
		)
		(placement
			(enabled no)
			(sheetname "")
		)
		(fill yes
			(thermal_gap 0.5)
			(thermal_bridge_width 0.5)
			(island_removal_mode 0)
		)
		(polygon
			(pts
				(arc
					(start 454.522078 -203.28509)
					(mid 453.854058 -203.28509)
					(end 454.522078 -203.28509)
				)
			)
		)
	)
	(zone
		(layers "B.Cu" "In13.Cu" "In15.Cu")
		(hatch none 0.5)
		(connect_pads
			(clearance 0)
		)
		(min_thickness 0.25)
		(keepout
			(tracks not_allowed)
			(vias allowed)
			(pads allowed)
			(copperpour not_allowed)
			(footprints allowed)
		)
		(placement
			(enabled no)
			(sheetname "")
		)
		(fill yes
			(thermal_gap 0.5)
			(thermal_bridge_width 0.5)
			(island_removal_mode 0)
		)
		(polygon
			(pts
				(arc
					(start 97.995994 -244.484398)
					(mid 97.366074 -244.484398)
					(end 97.995994 -244.484398)
				)
			)
		)
	)
	(zone
		(layers "B.Cu" "In13.Cu" "In15.Cu")
		(hatch none 0.5)
		(connect_pads
			(clearance 0)
		)
		(min_thickness 0.25)
		(keepout
			(tracks not_allowed)
			(vias allowed)
			(pads allowed)
			(copperpour not_allowed)
			(footprints allowed)
		)
		(placement
			(enabled no)
			(sheetname "")
		)
		(fill yes
			(thermal_gap 0.5)
			(thermal_bridge_width 0.5)
			(island_removal_mode 0)
		)
		(polygon
			(pts
				(arc
					(start 383.481072 -420.952168)
					(mid 382.813052 -420.952168)
					(end 383.481072 -420.952168)
				)
			)
		)
	)
	(zone
		(layers "B.Cu" "In13.Cu" "In15.Cu")
		(hatch none 0.5)
		(connect_pads
			(clearance 0)
		)
		(min_thickness 0.25)
		(keepout
			(tracks not_allowed)
			(vias allowed)
			(pads allowed)
			(copperpour not_allowed)
			(footprints allowed)
		)
		(placement
			(enabled no)
			(sheetname "")
		)
		(fill yes
			(thermal_gap 0.5)
			(thermal_bridge_width 0.5)
			(island_removal_mode 0)
		)
		(polygon
			(pts
				(arc
					(start 85.776054 -246.10441)
					(mid 85.146134 -246.10441)
					(end 85.776054 -246.10441)
				)
			)
		)
	)
	(zone
		(layers "B.Cu" "In13.Cu" "In15.Cu")
		(hatch none 0.5)
		(connect_pads
			(clearance 0)
		)
		(min_thickness 0.25)
		(keepout
			(tracks not_allowed)
			(vias allowed)
			(pads allowed)
			(copperpour not_allowed)
			(footprints allowed)
		)
		(placement
			(enabled no)
			(sheetname "")
		)
		(fill yes
			(thermal_gap 0.5)
			(thermal_bridge_width 0.5)
			(island_removal_mode 0)
		)
		(polygon
			(pts
				(arc
					(start 133.607556 -412.570168)
					(mid 132.939536 -412.570168)
					(end 133.607556 -412.570168)
				)
			)
		)
	)
	(zone
		(layers "B.Cu" "In13.Cu" "In15.Cu")
		(hatch none 0.5)
		(connect_pads
			(clearance 0)
		)
		(min_thickness 0.25)
		(keepout
			(tracks not_allowed)
			(vias allowed)
			(pads allowed)
			(copperpour not_allowed)
			(footprints allowed)
		)
		(placement
			(enabled no)
			(sheetname "")
		)
		(fill yes
			(thermal_gap 0.5)
			(thermal_bridge_width 0.5)
			(island_removal_mode 0)
		)
		(polygon
			(pts
				(arc
					(start 85.135974 -271.656302)
					(mid 84.506054 -271.656302)
					(end 85.135974 -271.656302)
				)
			)
		)
	)
	(zone
		(layers "B.Cu" "In13.Cu" "In15.Cu")
		(hatch none 0.5)
		(connect_pads
			(clearance 0)
		)
		(min_thickness 0.25)
		(keepout
			(tracks not_allowed)
			(vias allowed)
			(pads allowed)
			(copperpour not_allowed)
			(footprints allowed)
		)
		(placement
			(enabled no)
			(sheetname "")
		)
		(fill yes
			(thermal_gap 0.5)
			(thermal_bridge_width 0.5)
			(island_removal_mode 0)
		)
		(polygon
			(pts
				(arc
					(start 138.40968 -236.384338)
					(mid 137.77976 -236.384338)
					(end 138.40968 -236.384338)
				)
			)
		)
	)
	(zone
		(layers "B.Cu" "In13.Cu" "In15.Cu")
		(hatch none 0.5)
		(connect_pads
			(clearance 0)
		)
		(min_thickness 0.25)
		(keepout
			(tracks not_allowed)
			(vias allowed)
			(pads allowed)
			(copperpour not_allowed)
			(footprints allowed)
		)
		(placement
			(enabled no)
			(sheetname "")
		)
		(fill yes
			(thermal_gap 0.5)
			(thermal_bridge_width 0.5)
			(island_removal_mode 0)
		)
		(polygon
			(pts
				(arc
					(start 454.522078 -270.43507)
					(mid 453.854058 -270.43507)
					(end 454.522078 -270.43507)
				)
			)
		)
	)
	(zone
		(layers "B.Cu" "In13.Cu" "In15.Cu")
		(hatch none 0.5)
		(connect_pads
			(clearance 0)
		)
		(min_thickness 0.25)
		(keepout
			(tracks not_allowed)
			(vias allowed)
			(pads allowed)
			(copperpour not_allowed)
			(footprints allowed)
		)
		(placement
			(enabled no)
			(sheetname "")
		)
		(fill yes
			(thermal_gap 0.5)
			(thermal_bridge_width 0.5)
			(island_removal_mode 0)
		)
		(polygon
			(pts
				(arc
					(start 202.481942 -250.035314)
					(mid 201.813922 -250.035314)
					(end 202.481942 -250.035314)
				)
			)
		)
	)
	(zone
		(layers "B.Cu" "In13.Cu" "In15.Cu")
		(hatch none 0.5)
		(connect_pads
			(clearance 0)
		)
		(min_thickness 0.25)
		(keepout
			(tracks not_allowed)
			(vias allowed)
			(pads allowed)
			(copperpour not_allowed)
			(footprints allowed)
		)
		(placement
			(enabled no)
			(sheetname "")
		)
		(fill yes
			(thermal_gap 0.5)
			(thermal_bridge_width 0.5)
			(island_removal_mode 0)
		)
		(polygon
			(pts
				(arc
					(start 134.136892 -429.689768)
					(mid 133.3627 -429.689768)
					(end 134.136892 -429.689768)
				)
			)
		)
	)
	(zone
		(layers "B.Cu" "In13.Cu" "In15.Cu")
		(hatch none 0.5)
		(connect_pads
			(clearance 0)
		)
		(min_thickness 0.25)
		(keepout
			(tracks not_allowed)
			(vias allowed)
			(pads allowed)
			(copperpour not_allowed)
			(footprints allowed)
		)
		(placement
			(enabled no)
			(sheetname "")
		)
		(fill yes
			(thermal_gap 0.5)
			(thermal_bridge_width 0.5)
			(island_removal_mode 0)
		)
		(polygon
			(pts
				(arc
					(start 450.42201 -297.635168)
					(mid 449.75399 -297.635168)
					(end 450.42201 -297.635168)
				)
			)
		)
	)
	(zone
		(layers "B.Cu" "In13.Cu" "In15.Cu")
		(hatch none 0.5)
		(connect_pads
			(clearance 0)
		)
		(min_thickness 0.25)
		(keepout
			(tracks not_allowed)
			(vias allowed)
			(pads allowed)
			(copperpour not_allowed)
			(footprints allowed)
		)
		(placement
			(enabled no)
			(sheetname "")
		)
		(fill yes
			(thermal_gap 0.5)
			(thermal_bridge_width 0.5)
			(island_removal_mode 0)
		)
		(polygon
			(pts
				(arc
					(start 17.942052 -251.735336)
					(mid 17.274032 -251.735336)
					(end 17.942052 -251.735336)
				)
			)
		)
	)
	(zone
		(layers "B.Cu" "In13.Cu" "In15.Cu")
		(hatch none 0.5)
		(connect_pads
			(clearance 0)
		)
		(min_thickness 0.25)
		(keepout
			(tracks not_allowed)
			(vias allowed)
			(pads allowed)
			(copperpour not_allowed)
			(footprints allowed)
		)
		(placement
			(enabled no)
			(sheetname "")
		)
		(fill yes
			(thermal_gap 0.5)
			(thermal_bridge_width 0.5)
			(island_removal_mode 0)
		)
		(polygon
			(pts
				(arc
					(start 206.58201 -225.385376)
					(mid 205.91399 -225.385376)
					(end 206.58201 -225.385376)
				)
			)
		)
	)
	(zone
		(layers "B.Cu" "In13.Cu" "In15.Cu")
		(hatch none 0.5)
		(connect_pads
			(clearance 0)
		)
		(min_thickness 0.25)
		(keepout
			(tracks not_allowed)
			(vias allowed)
			(pads allowed)
			(copperpour not_allowed)
			(footprints allowed)
		)
		(placement
			(enabled no)
			(sheetname "")
		)
		(fill yes
			(thermal_gap 0.5)
			(thermal_bridge_width 0.5)
			(island_removal_mode 0)
		)
		(polygon
			(pts
				(arc
					(start 450.42201 -216.885012)
					(mid 449.75399 -216.885012)
					(end 450.42201 -216.885012)
				)
			)
		)
	)
	(zone
		(layers "B.Cu" "In13.Cu" "In15.Cu")
		(hatch none 0.5)
		(connect_pads
			(clearance 0)
		)
		(min_thickness 0.25)
		(keepout
			(tracks not_allowed)
			(vias allowed)
			(pads allowed)
			(copperpour not_allowed)
			(footprints allowed)
		)
		(placement
			(enabled no)
			(sheetname "")
		)
		(fill yes
			(thermal_gap 0.5)
			(thermal_bridge_width 0.5)
			(island_removal_mode 0)
		)
		(polygon
			(pts
				(arc
					(start 269.982188 -220.285056)
					(mid 269.314168 -220.285056)
					(end 269.982188 -220.285056)
				)
			)
		)
	)
	(zone
		(layers "B.Cu" "In13.Cu" "In15.Cu")
		(hatch none 0.5)
		(connect_pads
			(clearance 0)
		)
		(min_thickness 0.25)
		(keepout
			(tracks not_allowed)
			(vias allowed)
			(pads allowed)
			(copperpour not_allowed)
			(footprints allowed)
		)
		(placement
			(enabled no)
			(sheetname "")
		)
		(fill yes
			(thermal_gap 0.5)
			(thermal_bridge_width 0.5)
			(island_removal_mode 0)
		)
		(polygon
			(pts
				(arc
					(start 85.135974 -282.996386)
					(mid 84.506054 -282.996386)
					(end 85.135974 -282.996386)
				)
			)
		)
	)
	(zone
		(layers "B.Cu" "In13.Cu" "In15.Cu")
		(hatch none 0.5)
		(connect_pads
			(clearance 0)
		)
		(min_thickness 0.25)
		(keepout
			(tracks not_allowed)
			(vias allowed)
			(pads allowed)
			(copperpour not_allowed)
			(footprints allowed)
		)
		(placement
			(enabled no)
			(sheetname "")
		)
		(fill yes
			(thermal_gap 0.5)
			(thermal_bridge_width 0.5)
			(island_removal_mode 0)
		)
		(polygon
			(pts
				(arc
					(start 333.716122 -236.384084)
					(mid 333.086202 -236.384084)
					(end 333.716122 -236.384084)
				)
			)
		)
	)
	(zone
		(layers "B.Cu" "In13.Cu" "In15.Cu")
		(hatch none 0.5)
		(connect_pads
			(clearance 0)
		)
		(min_thickness 0.25)
		(keepout
			(tracks not_allowed)
			(vias allowed)
			(pads allowed)
			(copperpour not_allowed)
			(footprints allowed)
		)
		(placement
			(enabled no)
			(sheetname "")
		)
		(fill yes
			(thermal_gap 0.5)
			(thermal_bridge_width 0.5)
			(island_removal_mode 0)
		)
		(polygon
			(pts
				(arc
					(start 17.942052 -237.285276)
					(mid 17.274032 -237.285276)
					(end 17.942052 -237.285276)
				)
			)
		)
	)
	(zone
		(layers "B.Cu" "In13.Cu" "In15.Cu")
		(hatch none 0.5)
		(connect_pads
			(clearance 0)
		)
		(min_thickness 0.25)
		(keepout
			(tracks not_allowed)
			(vias allowed)
			(pads allowed)
			(copperpour not_allowed)
			(footprints allowed)
		)
		(placement
			(enabled no)
			(sheetname "")
		)
		(fill yes
			(thermal_gap 0.5)
			(thermal_bridge_width 0.5)
			(island_removal_mode 0)
		)
		(polygon
			(pts
				(arc
					(start 149.137116 -431.889916)
					(mid 148.362924 -431.889916)
					(end 149.137116 -431.889916)
				)
			)
		)
	)
	(zone
		(layers "B.Cu" "In13.Cu" "In15.Cu")
		(hatch none 0.5)
		(connect_pads
			(clearance 0)
		)
		(min_thickness 0.25)
		(keepout
			(tracks not_allowed)
			(vias allowed)
			(pads allowed)
			(copperpour not_allowed)
			(footprints allowed)
		)
		(placement
			(enabled no)
			(sheetname "")
		)
		(fill yes
			(thermal_gap 0.5)
			(thermal_bridge_width 0.5)
			(island_removal_mode 0)
		)
		(polygon
			(pts
				(arc
					(start 454.522078 -252.584966)
					(mid 453.854058 -252.584966)
					(end 454.522078 -252.584966)
				)
			)
		)
	)
	(zone
		(layers "B.Cu" "In13.Cu" "In15.Cu")
		(hatch none 0.5)
		(connect_pads
			(clearance 0)
		)
		(min_thickness 0.25)
		(keepout
			(tracks not_allowed)
			(vias allowed)
			(pads allowed)
			(copperpour not_allowed)
			(footprints allowed)
		)
		(placement
			(enabled no)
			(sheetname "")
		)
		(fill yes
			(thermal_gap 0.5)
			(thermal_bridge_width 0.5)
			(island_removal_mode 0)
		)
		(polygon
			(pts
				(arc
					(start 139.649708 -291.096192)
					(mid 139.019788 -291.096192)
					(end 139.649708 -291.096192)
				)
			)
		)
	)
	(zone
		(layers "B.Cu" "In13.Cu" "In15.Cu")
		(hatch none 0.5)
		(connect_pads
			(clearance 0)
		)
		(min_thickness 0.25)
		(keepout
			(tracks not_allowed)
			(vias allowed)
			(pads allowed)
			(copperpour not_allowed)
			(footprints allowed)
		)
		(placement
			(enabled no)
			(sheetname "")
		)
		(fill yes
			(thermal_gap 0.5)
			(thermal_bridge_width 0.5)
			(island_removal_mode 0)
		)
		(polygon
			(pts
				(arc
					(start 138.709654 -292.716204)
					(mid 138.079734 -292.716204)
					(end 138.709654 -292.716204)
				)
			)
		)
	)
	(zone
		(layers "B.Cu" "In13.Cu" "In15.Cu")
		(hatch none 0.5)
		(connect_pads
			(clearance 0)
		)
		(min_thickness 0.25)
		(keepout
			(tracks not_allowed)
			(vias allowed)
			(pads allowed)
			(copperpour not_allowed)
			(footprints allowed)
		)
		(placement
			(enabled no)
			(sheetname "")
		)
		(fill yes
			(thermal_gap 0.5)
			(thermal_bridge_width 0.5)
			(island_removal_mode 0)
		)
		(polygon
			(pts
				(arc
					(start 202.481942 -302.735234)
					(mid 201.813922 -302.735234)
					(end 202.481942 -302.735234)
				)
			)
		)
	)
	(zone
		(layers "B.Cu" "In13.Cu" "In15.Cu")
		(hatch none 0.5)
		(connect_pads
			(clearance 0)
		)
		(min_thickness 0.25)
		(keepout
			(tracks not_allowed)
			(vias allowed)
			(pads allowed)
			(copperpour not_allowed)
			(footprints allowed)
		)
		(placement
			(enabled no)
			(sheetname "")
		)
		(fill yes
			(thermal_gap 0.5)
			(thermal_bridge_width 0.5)
			(island_removal_mode 0)
		)
		(polygon
			(pts
				(arc
					(start 355.636068 -274.896072)
					(mid 355.006148 -274.896072)
					(end 355.636068 -274.896072)
				)
			)
		)
	)
	(zone
		(layers "B.Cu" "In13.Cu" "In15.Cu")
		(hatch none 0.5)
		(connect_pads
			(clearance 0)
		)
		(min_thickness 0.25)
		(keepout
			(tracks not_allowed)
			(vias allowed)
			(pads allowed)
			(copperpour not_allowed)
			(footprints allowed)
		)
		(placement
			(enabled no)
			(sheetname "")
		)
		(fill yes
			(thermal_gap 0.5)
			(thermal_bridge_width 0.5)
			(island_removal_mode 0)
		)
		(polygon
			(pts
				(arc
					(start 85.135974 -273.276314)
					(mid 84.506054 -273.276314)
					(end 85.135974 -273.276314)
				)
			)
		)
	)
	(zone
		(layers "B.Cu" "In13.Cu" "In15.Cu")
		(hatch none 0.5)
		(connect_pads
			(clearance 0)
		)
		(min_thickness 0.25)
		(keepout
			(tracks not_allowed)
			(vias allowed)
			(pads allowed)
			(copperpour not_allowed)
			(footprints allowed)
		)
		(placement
			(enabled no)
			(sheetname "")
		)
		(fill yes
			(thermal_gap 0.5)
			(thermal_bridge_width 0.5)
			(island_removal_mode 0)
		)
		(polygon
			(pts
				(arc
					(start 388.059676 -277.32609)
					(mid 387.429756 -277.32609)
					(end 388.059676 -277.32609)
				)
			)
		)
	)
	(zone
		(layers "B.Cu" "In13.Cu" "In15.Cu")
		(hatch none 0.5)
		(connect_pads
			(clearance 0)
		)
		(min_thickness 0.25)
		(keepout
			(tracks not_allowed)
			(vias allowed)
			(pads allowed)
			(copperpour not_allowed)
			(footprints allowed)
		)
		(placement
			(enabled no)
			(sheetname "")
		)
		(fill yes
			(thermal_gap 0.5)
			(thermal_bridge_width 0.5)
			(island_removal_mode 0)
		)
		(polygon
			(pts
				(arc
					(start 202.481942 -218.585288)
					(mid 201.813922 -218.585288)
					(end 202.481942 -218.585288)
				)
			)
		)
	)
	(zone
		(layers "B.Cu" "In13.Cu" "In15.Cu")
		(hatch none 0.5)
		(connect_pads
			(clearance 0)
		)
		(min_thickness 0.25)
		(keepout
			(tracks not_allowed)
			(vias allowed)
			(pads allowed)
			(copperpour not_allowed)
			(footprints allowed)
		)
		(placement
			(enabled no)
			(sheetname "")
		)
		(fill yes
			(thermal_gap 0.5)
			(thermal_bridge_width 0.5)
			(island_removal_mode 0)
		)
		(polygon
			(pts
				(arc
					(start 363.619796 -278.946102)
					(mid 362.989876 -278.946102)
					(end 363.619796 -278.946102)
				)
			)
		)
	)
	(zone
		(layers "B.Cu" "In13.Cu" "In15.Cu")
		(hatch none 0.5)
		(connect_pads
			(clearance 0)
		)
		(min_thickness 0.25)
		(keepout
			(tracks not_allowed)
			(vias allowed)
			(pads allowed)
			(copperpour not_allowed)
			(footprints allowed)
		)
		(placement
			(enabled no)
			(sheetname "")
		)
		(fill yes
			(thermal_gap 0.5)
			(thermal_bridge_width 0.5)
			(island_removal_mode 0)
		)
		(polygon
			(pts
				(arc
					(start 86.245954 -232.334308)
					(mid 85.616034 -232.334308)
					(end 86.245954 -232.334308)
				)
			)
		)
	)
	(zone
		(layers "B.Cu" "In13.Cu" "In15.Cu")
		(hatch none 0.5)
		(connect_pads
			(clearance 0)
		)
		(min_thickness 0.25)
		(keepout
			(tracks not_allowed)
			(vias allowed)
			(pads allowed)
			(copperpour not_allowed)
			(footprints allowed)
		)
		(placement
			(enabled no)
			(sheetname "")
		)
		(fill yes
			(thermal_gap 0.5)
			(thermal_bridge_width 0.5)
			(island_removal_mode 0)
		)
		(polygon
			(pts
				(arc
					(start 269.982188 -217.73515)
					(mid 269.314168 -217.73515)
					(end 269.982188 -217.73515)
				)
			)
		)
	)
	(zone
		(layers "B.Cu" "In13.Cu" "In15.Cu")
		(hatch none 0.5)
		(connect_pads
			(clearance 0)
		)
		(min_thickness 0.25)
		(keepout
			(tracks not_allowed)
			(vias allowed)
			(pads allowed)
			(copperpour not_allowed)
			(footprints allowed)
		)
		(placement
			(enabled no)
			(sheetname "")
		)
		(fill yes
			(thermal_gap 0.5)
			(thermal_bridge_width 0.5)
			(island_removal_mode 0)
		)
		(polygon
			(pts
				(arc
					(start 333.076042 -278.136096)
					(mid 332.446122 -278.136096)
					(end 333.076042 -278.136096)
				)
			)
		)
	)
	(zone
		(layers "B.Cu" "In13.Cu" "In15.Cu")
		(hatch none 0.5)
		(connect_pads
			(clearance 0)
		)
		(min_thickness 0.25)
		(keepout
			(tracks not_allowed)
			(vias allowed)
			(pads allowed)
			(copperpour not_allowed)
			(footprints allowed)
		)
		(placement
			(enabled no)
			(sheetname "")
		)
		(fill yes
			(thermal_gap 0.5)
			(thermal_bridge_width 0.5)
			(island_removal_mode 0)
		)
		(polygon
			(pts
				(arc
					(start 333.076042 -284.616144)
					(mid 332.446122 -284.616144)
					(end 333.076042 -284.616144)
				)
			)
		)
	)
	(zone
		(layers "B.Cu" "In13.Cu" "In15.Cu")
		(hatch none 0.5)
		(connect_pads
			(clearance 0)
		)
		(min_thickness 0.25)
		(keepout
			(tracks not_allowed)
			(vias allowed)
			(pads allowed)
			(copperpour not_allowed)
			(footprints allowed)
		)
		(placement
			(enabled no)
			(sheetname "")
		)
		(fill yes
			(thermal_gap 0.5)
			(thermal_bridge_width 0.5)
			(island_removal_mode 0)
		)
		(polygon
			(pts
				(arc
					(start 22.04212 -266.185396)
					(mid 21.3741 -266.185396)
					(end 22.04212 -266.185396)
				)
			)
		)
	)
	(zone
		(layers "B.Cu" "In13.Cu" "In15.Cu")
		(hatch none 0.5)
		(connect_pads
			(clearance 0)
		)
		(min_thickness 0.25)
		(keepout
			(tracks not_allowed)
			(vias allowed)
			(pads allowed)
			(copperpour not_allowed)
			(footprints allowed)
		)
		(placement
			(enabled no)
			(sheetname "")
		)
		(fill yes
			(thermal_gap 0.5)
			(thermal_bridge_width 0.5)
			(island_removal_mode 0)
		)
		(polygon
			(pts
				(arc
					(start 86.076028 -274.896326)
					(mid 85.446108 -274.896326)
					(end 86.076028 -274.896326)
				)
			)
		)
	)
	(zone
		(layers "B.Cu" "In13.Cu" "In15.Cu")
		(hatch none 0.5)
		(connect_pads
			(clearance 0)
		)
		(min_thickness 0.25)
		(keepout
			(tracks not_allowed)
			(vias allowed)
			(pads allowed)
			(copperpour not_allowed)
			(footprints allowed)
		)
		(placement
			(enabled no)
			(sheetname "")
		)
		(fill yes
			(thermal_gap 0.5)
			(thermal_bridge_width 0.5)
			(island_removal_mode 0)
		)
		(polygon
			(pts
				(arc
					(start 387.734302 -379.88113)
					(mid 387.066282 -379.88113)
					(end 387.734302 -379.88113)
				)
			)
		)
	)
	(zone
		(layers "B.Cu" "In13.Cu" "In15.Cu")
		(hatch none 0.5)
		(connect_pads
			(clearance 0)
		)
		(min_thickness 0.25)
		(keepout
			(tracks not_allowed)
			(vias allowed)
			(pads allowed)
			(copperpour not_allowed)
			(footprints allowed)
		)
		(placement
			(enabled no)
			(sheetname "")
		)
		(fill yes
			(thermal_gap 0.5)
			(thermal_bridge_width 0.5)
			(island_removal_mode 0)
		)
		(polygon
			(pts
				(arc
					(start 269.982188 -315.485018)
					(mid 269.314168 -315.485018)
					(end 269.982188 -315.485018)
				)
			)
		)
	)
	(zone
		(layers "B.Cu" "In13.Cu" "In15.Cu")
		(hatch none 0.5)
		(connect_pads
			(clearance 0)
		)
		(min_thickness 0.25)
		(keepout
			(tracks not_allowed)
			(vias allowed)
			(pads allowed)
			(copperpour not_allowed)
			(footprints allowed)
		)
		(placement
			(enabled no)
			(sheetname "")
		)
		(fill yes
			(thermal_gap 0.5)
			(thermal_bridge_width 0.5)
			(island_removal_mode 0)
		)
		(polygon
			(pts
				(arc
					(start 118.029736 -274.896326)
					(mid 117.399816 -274.896326)
					(end 118.029736 -274.896326)
				)
			)
		)
	)
	(zone
		(layers "B.Cu" "In13.Cu" "In15.Cu")
		(hatch none 0.5)
		(connect_pads
			(clearance 0)
		)
		(min_thickness 0.25)
		(keepout
			(tracks not_allowed)
			(vias allowed)
			(pads allowed)
			(copperpour not_allowed)
			(footprints allowed)
		)
		(placement
			(enabled no)
			(sheetname "")
		)
		(fill yes
			(thermal_gap 0.5)
			(thermal_bridge_width 0.5)
			(island_removal_mode 0)
		)
		(polygon
			(pts
				(arc
					(start 265.88212 -221.13494)
					(mid 265.2141 -221.13494)
					(end 265.88212 -221.13494)
				)
			)
		)
	)
	(zone
		(layers "B.Cu" "In13.Cu" "In15.Cu")
		(hatch none 0.5)
		(connect_pads
			(clearance 0)
		)
		(min_thickness 0.25)
		(keepout
			(tracks not_allowed)
			(vias allowed)
			(pads allowed)
			(copperpour not_allowed)
			(footprints allowed)
		)
		(placement
			(enabled no)
			(sheetname "")
		)
		(fill yes
			(thermal_gap 0.5)
			(thermal_bridge_width 0.5)
			(island_removal_mode 0)
		)
		(polygon
			(pts
				(arc
					(start 368.789712 -274.896072)
					(mid 368.159792 -274.896072)
					(end 368.789712 -274.896072)
				)
			)
		)
	)
	(zone
		(layers "B.Cu" "In13.Cu" "In15.Cu")
		(hatch none 0.5)
		(connect_pads
			(clearance 0)
		)
		(min_thickness 0.25)
		(keepout
			(tracks not_allowed)
			(vias allowed)
			(pads allowed)
			(copperpour not_allowed)
			(footprints allowed)
		)
		(placement
			(enabled no)
			(sheetname "")
		)
		(fill yes
			(thermal_gap 0.5)
			(thermal_bridge_width 0.5)
			(island_removal_mode 0)
		)
		(polygon
			(pts
				(arc
					(start 351.576132 -233.14406)
					(mid 350.946212 -233.14406)
					(end 351.576132 -233.14406)
				)
			)
		)
	)
	(zone
		(layers "B.Cu" "In13.Cu" "In15.Cu")
		(hatch none 0.5)
		(connect_pads
			(clearance 0)
		)
		(min_thickness 0.25)
		(keepout
			(tracks not_allowed)
			(vias allowed)
			(pads allowed)
			(copperpour not_allowed)
			(footprints allowed)
		)
		(placement
			(enabled no)
			(sheetname "")
		)
		(fill yes
			(thermal_gap 0.5)
			(thermal_bridge_width 0.5)
			(island_removal_mode 0)
		)
		(polygon
			(pts
				(arc
					(start 126.18974 -234.764326)
					(mid 125.55982 -234.764326)
					(end 126.18974 -234.764326)
				)
			)
		)
	)
	(zone
		(layers "B.Cu" "In13.Cu" "In15.Cu")
		(hatch none 0.5)
		(connect_pads
			(clearance 0)
		)
		(min_thickness 0.25)
		(keepout
			(tracks not_allowed)
			(vias allowed)
			(pads allowed)
			(copperpour not_allowed)
			(footprints allowed)
		)
		(placement
			(enabled no)
			(sheetname "")
		)
		(fill yes
			(thermal_gap 0.5)
			(thermal_bridge_width 0.5)
			(island_removal_mode 0)
		)
		(polygon
			(pts
				(arc
					(start 202.481942 -282.335224)
					(mid 201.813922 -282.335224)
					(end 202.481942 -282.335224)
				)
			)
		)
	)
	(zone
		(layers "B.Cu" "In13.Cu" "In15.Cu")
		(hatch none 0.5)
		(connect_pads
			(clearance 0)
		)
		(min_thickness 0.25)
		(keepout
			(tracks not_allowed)
			(vias allowed)
			(pads allowed)
			(copperpour not_allowed)
			(footprints allowed)
		)
		(placement
			(enabled no)
			(sheetname "")
		)
		(fill yes
			(thermal_gap 0.5)
			(thermal_bridge_width 0.5)
			(island_removal_mode 0)
		)
		(polygon
			(pts
				(arc
					(start 265.88212 -274.684998)
					(mid 265.2141 -274.684998)
					(end 265.88212 -274.684998)
				)
			)
		)
	)
	(zone
		(layers "B.Cu" "In13.Cu" "In15.Cu")
		(hatch none 0.5)
		(connect_pads
			(clearance 0)
		)
		(min_thickness 0.25)
		(keepout
			(tracks not_allowed)
			(vias allowed)
			(pads allowed)
			(copperpour not_allowed)
			(footprints allowed)
		)
		(placement
			(enabled no)
			(sheetname "")
		)
		(fill yes
			(thermal_gap 0.5)
			(thermal_bridge_width 0.5)
			(island_removal_mode 0)
		)
		(polygon
			(pts
				(arc
					(start 332.606142 -287.045908)
					(mid 331.976222 -287.045908)
					(end 332.606142 -287.045908)
				)
			)
		)
	)
	(zone
		(layers "B.Cu" "In13.Cu" "In15.Cu")
		(hatch none 0.5)
		(connect_pads
			(clearance 0)
		)
		(min_thickness 0.25)
		(keepout
			(tracks not_allowed)
			(vias allowed)
			(pads allowed)
			(copperpour not_allowed)
			(footprints allowed)
		)
		(placement
			(enabled no)
			(sheetname "")
		)
		(fill yes
			(thermal_gap 0.5)
			(thermal_bridge_width 0.5)
			(island_removal_mode 0)
		)
		(polygon
			(pts
				(arc
					(start 265.88212 -280.634948)
					(mid 265.2141 -280.634948)
					(end 265.88212 -280.634948)
				)
			)
		)
	)
	(zone
		(layers "B.Cu" "In13.Cu" "In15.Cu")
		(hatch none 0.5)
		(connect_pads
			(clearance 0)
		)
		(min_thickness 0.25)
		(keepout
			(tracks not_allowed)
			(vias allowed)
			(pads allowed)
			(copperpour not_allowed)
			(footprints allowed)
		)
		(placement
			(enabled no)
			(sheetname "")
		)
		(fill yes
			(thermal_gap 0.5)
			(thermal_bridge_width 0.5)
			(island_removal_mode 0)
		)
		(polygon
			(pts
				(arc
					(start 389.436102 -377.41733)
					(mid 388.768082 -377.41733)
					(end 389.436102 -377.41733)
				)
			)
		)
	)
	(zone
		(layers "B.Cu" "In13.Cu" "In15.Cu")
		(hatch none 0.5)
		(connect_pads
			(clearance 0)
		)
		(min_thickness 0.25)
		(keepout
			(tracks not_allowed)
			(vias allowed)
			(pads allowed)
			(copperpour not_allowed)
			(footprints allowed)
		)
		(placement
			(enabled no)
			(sheetname "")
		)
		(fill yes
			(thermal_gap 0.5)
			(thermal_bridge_width 0.5)
			(island_removal_mode 0)
		)
		(polygon
			(pts
				(arc
					(start 265.88212 -305.28514)
					(mid 265.2141 -305.28514)
					(end 265.88212 -305.28514)
				)
			)
		)
	)
	(zone
		(layers "B.Cu" "In13.Cu" "In15.Cu")
		(hatch none 0.5)
		(connect_pads
			(clearance 0)
		)
		(min_thickness 0.25)
		(keepout
			(tracks not_allowed)
			(vias allowed)
			(pads allowed)
			(copperpour not_allowed)
			(footprints allowed)
		)
		(placement
			(enabled no)
			(sheetname "")
		)
		(fill yes
			(thermal_gap 0.5)
			(thermal_bridge_width 0.5)
			(island_removal_mode 0)
		)
		(polygon
			(pts
				(arc
					(start 304.127916 -420.952168)
					(mid 303.459896 -420.952168)
					(end 304.127916 -420.952168)
				)
			)
		)
	)
	(zone
		(layers "B.Cu" "In13.Cu" "In15.Cu")
		(hatch none 0.5)
		(connect_pads
			(clearance 0)
		)
		(min_thickness 0.25)
		(keepout
			(tracks not_allowed)
			(vias allowed)
			(pads allowed)
			(copperpour not_allowed)
			(footprints allowed)
		)
		(placement
			(enabled no)
			(sheetname "")
		)
		(fill yes
			(thermal_gap 0.5)
			(thermal_bridge_width 0.5)
			(island_removal_mode 0)
		)
		(polygon
			(pts
				(arc
					(start 206.58201 -200.735438)
					(mid 205.91399 -200.735438)
					(end 206.58201 -200.735438)
				)
			)
		)
	)
	(zone
		(layers "B.Cu" "In13.Cu" "In15.Cu")
		(hatch none 0.5)
		(connect_pads
			(clearance 0)
		)
		(min_thickness 0.25)
		(keepout
			(tracks not_allowed)
			(vias allowed)
			(pads allowed)
			(copperpour not_allowed)
			(footprints allowed)
		)
		(placement
			(enabled no)
			(sheetname "")
		)
		(fill yes
			(thermal_gap 0.5)
			(thermal_bridge_width 0.5)
			(island_removal_mode 0)
		)
		(polygon
			(pts
				(arc
					(start 320.307716 -420.952168)
					(mid 319.639696 -420.952168)
					(end 320.307716 -420.952168)
				)
			)
		)
	)
	(zone
		(layers "B.Cu" "In13.Cu" "In15.Cu")
		(hatch none 0.5)
		(connect_pads
			(clearance 0)
		)
		(min_thickness 0.25)
		(keepout
			(tracks not_allowed)
			(vias allowed)
			(pads allowed)
			(copperpour not_allowed)
			(footprints allowed)
		)
		(placement
			(enabled no)
			(sheetname "")
		)
		(fill yes
			(thermal_gap 0.5)
			(thermal_bridge_width 0.5)
			(island_removal_mode 0)
		)
		(polygon
			(pts
				(arc
					(start 386.179822 -290.285932)
					(mid 385.549902 -290.285932)
					(end 386.179822 -290.285932)
				)
			)
		)
	)
	(zone
		(layers "B.Cu" "In13.Cu" "In15.Cu")
		(hatch none 0.5)
		(connect_pads
			(clearance 0)
		)
		(min_thickness 0.25)
		(keepout
			(tracks not_allowed)
			(vias allowed)
			(pads allowed)
			(copperpour not_allowed)
			(footprints allowed)
		)
		(placement
			(enabled no)
			(sheetname "")
		)
		(fill yes
			(thermal_gap 0.5)
			(thermal_bridge_width 0.5)
			(island_removal_mode 0)
		)
		(polygon
			(pts
				(arc
					(start 17.942052 -244.935248)
					(mid 17.274032 -244.935248)
					(end 17.942052 -244.935248)
				)
			)
		)
	)
	(zone
		(layers "B.Cu" "In13.Cu" "In15.Cu")
		(hatch none 0.5)
		(connect_pads
			(clearance 0)
		)
		(min_thickness 0.25)
		(keepout
			(tracks not_allowed)
			(vias allowed)
			(pads allowed)
			(copperpour not_allowed)
			(footprints allowed)
		)
		(placement
			(enabled no)
			(sheetname "")
		)
		(fill yes
			(thermal_gap 0.5)
			(thermal_bridge_width 0.5)
			(island_removal_mode 0)
		)
		(polygon
			(pts
				(arc
					(start 450.42201 -293.384986)
					(mid 449.75399 -293.384986)
					(end 450.42201 -293.384986)
				)
			)
		)
	)
	(zone
		(layers "B.Cu" "In13.Cu" "In15.Cu")
		(hatch none 0.5)
		(connect_pads
			(clearance 0)
		)
		(min_thickness 0.25)
		(keepout
			(tracks not_allowed)
			(vias allowed)
			(pads allowed)
			(copperpour not_allowed)
			(footprints allowed)
		)
		(placement
			(enabled no)
			(sheetname "")
		)
		(fill yes
			(thermal_gap 0.5)
			(thermal_bridge_width 0.5)
			(island_removal_mode 0)
		)
		(polygon
			(pts
				(arc
					(start 265.88212 -265.335004)
					(mid 265.2141 -265.335004)
					(end 265.88212 -265.335004)
				)
			)
		)
	)
	(zone
		(layers "B.Cu" "In13.Cu" "In15.Cu")
		(hatch none 0.5)
		(connect_pads
			(clearance 0)
		)
		(min_thickness 0.25)
		(keepout
			(tracks not_allowed)
			(vias allowed)
			(pads allowed)
			(copperpour not_allowed)
			(footprints allowed)
		)
		(placement
			(enabled no)
			(sheetname "")
		)
		(fill yes
			(thermal_gap 0.5)
			(thermal_bridge_width 0.5)
			(island_removal_mode 0)
		)
		(polygon
			(pts
				(arc
					(start 367.549684 -246.104156)
					(mid 366.919764 -246.104156)
					(end 367.549684 -246.104156)
				)
			)
		)
	)
	(zone
		(layers "B.Cu" "In13.Cu" "In15.Cu")
		(hatch none 0.5)
		(connect_pads
			(clearance 0)
		)
		(min_thickness 0.25)
		(keepout
			(tracks not_allowed)
			(vias allowed)
			(pads allowed)
			(copperpour not_allowed)
			(footprints allowed)
		)
		(placement
			(enabled no)
			(sheetname "")
		)
		(fill yes
			(thermal_gap 0.5)
			(thermal_bridge_width 0.5)
			(island_removal_mode 0)
		)
		(polygon
			(pts
				(arc
					(start 386.349748 -229.904036)
					(mid 385.719828 -229.904036)
					(end 386.349748 -229.904036)
				)
			)
		)
	)
	(zone
		(layers "B.Cu" "In13.Cu" "In15.Cu")
		(hatch none 0.5)
		(connect_pads
			(clearance 0)
		)
		(min_thickness 0.25)
		(keepout
			(tracks not_allowed)
			(vias allowed)
			(pads allowed)
			(copperpour not_allowed)
			(footprints allowed)
		)
		(placement
			(enabled no)
			(sheetname "")
		)
		(fill yes
			(thermal_gap 0.5)
			(thermal_bridge_width 0.5)
			(island_removal_mode 0)
		)
		(polygon
			(pts
				(arc
					(start 265.88212 -232.184956)
					(mid 265.2141 -232.184956)
					(end 265.88212 -232.184956)
				)
			)
		)
	)
	(zone
		(layers "B.Cu" "In13.Cu" "In15.Cu")
		(hatch none 0.5)
		(connect_pads
			(clearance 0)
		)
		(min_thickness 0.25)
		(keepout
			(tracks not_allowed)
			(vias allowed)
			(pads allowed)
			(copperpour not_allowed)
			(footprints allowed)
		)
		(placement
			(enabled no)
			(sheetname "")
		)
		(fill yes
			(thermal_gap 0.5)
			(thermal_bridge_width 0.5)
			(island_removal_mode 0)
		)
		(polygon
			(pts
				(arc
					(start 332.776068 -241.24412)
					(mid 332.146148 -241.24412)
					(end 332.776068 -241.24412)
				)
			)
		)
	)
	(zone
		(layers "B.Cu" "In13.Cu" "In15.Cu")
		(hatch none 0.5)
		(connect_pads
			(clearance 0)
		)
		(min_thickness 0.25)
		(keepout
			(tracks not_allowed)
			(vias allowed)
			(pads allowed)
			(copperpour not_allowed)
			(footprints allowed)
		)
		(placement
			(enabled no)
			(sheetname "")
		)
		(fill yes
			(thermal_gap 0.5)
			(thermal_bridge_width 0.5)
			(island_removal_mode 0)
		)
		(polygon
			(pts
				(arc
					(start 78.037182 -431.889916)
					(mid 77.26299 -431.889916)
					(end 78.037182 -431.889916)
				)
			)
		)
	)
	(zone
		(layers "B.Cu" "In13.Cu" "In15.Cu")
		(hatch none 0.5)
		(connect_pads
			(clearance 0)
		)
		(min_thickness 0.25)
		(keepout
			(tracks not_allowed)
			(vias allowed)
			(pads allowed)
			(copperpour not_allowed)
			(footprints allowed)
		)
		(placement
			(enabled no)
			(sheetname "")
		)
		(fill yes
			(thermal_gap 0.5)
			(thermal_bridge_width 0.5)
			(island_removal_mode 0)
		)
		(polygon
			(pts
				(arc
					(start 352.81616 -274.896072)
					(mid 352.18624 -274.896072)
					(end 352.81616 -274.896072)
				)
			)
		)
	)
	(zone
		(layers "B.Cu" "In13.Cu" "In15.Cu")
		(hatch none 0.5)
		(connect_pads
			(clearance 0)
		)
		(min_thickness 0.25)
		(keepout
			(tracks not_allowed)
			(vias allowed)
			(pads allowed)
			(copperpour not_allowed)
			(footprints allowed)
		)
		(placement
			(enabled no)
			(sheetname "")
		)
		(fill yes
			(thermal_gap 0.5)
			(thermal_bridge_width 0.5)
			(island_removal_mode 0)
		)
		(polygon
			(pts
				(arc
					(start 388.059676 -285.42615)
					(mid 387.429756 -285.42615)
					(end 388.059676 -285.42615)
				)
			)
		)
	)
	(zone
		(layers "B.Cu" "In13.Cu" "In15.Cu")
		(hatch none 0.5)
		(connect_pads
			(clearance 0)
		)
		(min_thickness 0.25)
		(keepout
			(tracks not_allowed)
			(vias allowed)
			(pads allowed)
			(copperpour not_allowed)
			(footprints allowed)
		)
		(placement
			(enabled no)
			(sheetname "")
		)
		(fill yes
			(thermal_gap 0.5)
			(thermal_bridge_width 0.5)
			(island_removal_mode 0)
		)
		(polygon
			(pts
				(arc
					(start 94.076774 -412.570168)
					(mid 93.408754 -412.570168)
					(end 94.076774 -412.570168)
				)
			)
		)
	)
	(zone
		(layers "B.Cu" "In13.Cu" "In15.Cu")
		(hatch none 0.5)
		(connect_pads
			(clearance 0)
		)
		(min_thickness 0.25)
		(keepout
			(tracks not_allowed)
			(vias allowed)
			(pads allowed)
			(copperpour not_allowed)
			(footprints allowed)
		)
		(placement
			(enabled no)
			(sheetname "")
		)
		(fill yes
			(thermal_gap 0.5)
			(thermal_bridge_width 0.5)
			(island_removal_mode 0)
		)
		(polygon
			(pts
				(arc
					(start 82.687414 -412.570168)
					(mid 82.019394 -412.570168)
					(end 82.687414 -412.570168)
				)
			)
		)
	)
	(zone
		(layers "B.Cu" "In13.Cu" "In15.Cu")
		(hatch none 0.5)
		(connect_pads
			(clearance 0)
		)
		(min_thickness 0.25)
		(keepout
			(tracks not_allowed)
			(vias allowed)
			(pads allowed)
			(copperpour not_allowed)
			(footprints allowed)
		)
		(placement
			(enabled no)
			(sheetname "")
		)
		(fill yes
			(thermal_gap 0.5)
			(thermal_bridge_width 0.5)
			(island_removal_mode 0)
		)
		(polygon
			(pts
				(arc
					(start 373.489728 -278.136096)
					(mid 372.859808 -278.136096)
					(end 373.489728 -278.136096)
				)
			)
		)
	)
	(zone
		(layers "B.Cu" "In13.Cu" "In15.Cu")
		(hatch none 0.5)
		(connect_pads
			(clearance 0)
		)
		(min_thickness 0.25)
		(keepout
			(tracks not_allowed)
			(vias allowed)
			(pads allowed)
			(copperpour not_allowed)
			(footprints allowed)
		)
		(placement
			(enabled no)
			(sheetname "")
		)
		(fill yes
			(thermal_gap 0.5)
			(thermal_bridge_width 0.5)
			(island_removal_mode 0)
		)
		(polygon
			(pts
				(arc
					(start 128.136904 -431.889916)
					(mid 127.362712 -431.889916)
					(end 128.136904 -431.889916)
				)
			)
		)
	)
	(zone
		(layers "B.Cu" "In13.Cu" "In15.Cu")
		(hatch none 0.5)
		(connect_pads
			(clearance 0)
		)
		(min_thickness 0.25)
		(keepout
			(tracks not_allowed)
			(vias allowed)
			(pads allowed)
			(copperpour not_allowed)
			(footprints allowed)
		)
		(placement
			(enabled no)
			(sheetname "")
		)
		(fill yes
			(thermal_gap 0.5)
			(thermal_bridge_width 0.5)
			(island_removal_mode 0)
		)
		(polygon
			(pts
				(arc
					(start 349.056198 -274.896072)
					(mid 348.426278 -274.896072)
					(end 349.056198 -274.896072)
				)
			)
		)
	)
	(zone
		(layers "B.Cu" "In13.Cu" "In15.Cu")
		(hatch none 0.5)
		(connect_pads
			(clearance 0)
		)
		(min_thickness 0.25)
		(keepout
			(tracks not_allowed)
			(vias allowed)
			(pads allowed)
			(copperpour not_allowed)
			(footprints allowed)
		)
		(placement
			(enabled no)
			(sheetname "")
		)
		(fill yes
			(thermal_gap 0.5)
			(thermal_bridge_width 0.5)
			(island_removal_mode 0)
		)
		(polygon
			(pts
				(arc
					(start 22.04212 -223.685354)
					(mid 21.3741 -223.685354)
					(end 22.04212 -223.685354)
				)
			)
		)
	)
	(zone
		(layers "B.Cu" "In13.Cu" "In15.Cu")
		(hatch none 0.5)
		(connect_pads
			(clearance 0)
		)
		(min_thickness 0.25)
		(keepout
			(tracks not_allowed)
			(vias allowed)
			(pads allowed)
			(copperpour not_allowed)
			(footprints allowed)
		)
		(placement
			(enabled no)
			(sheetname "")
		)
		(fill yes
			(thermal_gap 0.5)
			(thermal_bridge_width 0.5)
			(island_removal_mode 0)
		)
		(polygon
			(pts
				(arc
					(start 387.289802 -229.904036)
					(mid 386.659882 -229.904036)
					(end 387.289802 -229.904036)
				)
			)
		)
	)
	(zone
		(layers "B.Cu" "In13.Cu" "In15.Cu")
		(hatch none 0.5)
		(connect_pads
			(clearance 0)
		)
		(min_thickness 0.25)
		(keepout
			(tracks not_allowed)
			(vias allowed)
			(pads allowed)
			(copperpour not_allowed)
			(footprints allowed)
		)
		(placement
			(enabled no)
			(sheetname "")
		)
		(fill yes
			(thermal_gap 0.5)
			(thermal_bridge_width 0.5)
			(island_removal_mode 0)
		)
		(polygon
			(pts
				(arc
					(start 51.191414 -412.570168)
					(mid 50.523394 -412.570168)
					(end 51.191414 -412.570168)
				)
			)
		)
	)
	(zone
		(layers "B.Cu" "In13.Cu" "In15.Cu")
		(hatch none 0.5)
		(connect_pads
			(clearance 0)
		)
		(min_thickness 0.25)
		(keepout
			(tracks not_allowed)
			(vias allowed)
			(pads allowed)
			(copperpour not_allowed)
			(footprints allowed)
		)
		(placement
			(enabled no)
			(sheetname "")
		)
		(fill yes
			(thermal_gap 0.5)
			(thermal_bridge_width 0.5)
			(island_removal_mode 0)
		)
		(polygon
			(pts
				(arc
					(start 65.036954 -430.689766)
					(mid 64.262762 -430.689766)
					(end 65.036954 -430.689766)
				)
			)
		)
	)
	(zone
		(layers "B.Cu" "In13.Cu" "In15.Cu")
		(hatch none 0.5)
		(connect_pads
			(clearance 0)
		)
		(min_thickness 0.25)
		(keepout
			(tracks not_allowed)
			(vias allowed)
			(pads allowed)
			(copperpour not_allowed)
			(footprints allowed)
		)
		(placement
			(enabled no)
			(sheetname "")
		)
		(fill yes
			(thermal_gap 0.5)
			(thermal_bridge_width 0.5)
			(island_removal_mode 0)
		)
		(polygon
			(pts
				(arc
					(start 148.923756 -412.570168)
					(mid 148.255736 -412.570168)
					(end 148.923756 -412.570168)
				)
			)
		)
	)
	(zone
		(layers "B.Cu" "In13.Cu" "In15.Cu")
		(hatch none 0.5)
		(connect_pads
			(clearance 0)
		)
		(min_thickness 0.25)
		(keepout
			(tracks not_allowed)
			(vias allowed)
			(pads allowed)
			(copperpour not_allowed)
			(footprints allowed)
		)
		(placement
			(enabled no)
			(sheetname "")
		)
		(fill yes
			(thermal_gap 0.5)
			(thermal_bridge_width 0.5)
			(island_removal_mode 0)
		)
		(polygon
			(pts
				(arc
					(start 454.522078 -281.485086)
					(mid 453.854058 -281.485086)
					(end 454.522078 -281.485086)
				)
			)
		)
	)
	(zone
		(layers "B.Cu" "In13.Cu" "In15.Cu")
		(hatch none 0.5)
		(connect_pads
			(clearance 0)
		)
		(min_thickness 0.25)
		(keepout
			(tracks not_allowed)
			(vias allowed)
			(pads allowed)
			(copperpour not_allowed)
			(footprints allowed)
		)
		(placement
			(enabled no)
			(sheetname "")
		)
		(fill yes
			(thermal_gap 0.5)
			(thermal_bridge_width 0.5)
			(island_removal_mode 0)
		)
		(polygon
			(pts
				(arc
					(start 388.059676 -291.905944)
					(mid 387.429756 -291.905944)
					(end 388.059676 -291.905944)
				)
			)
		)
	)
	(zone
		(layers "B.Cu" "In13.Cu" "In15.Cu")
		(hatch none 0.5)
		(connect_pads
			(clearance 0)
		)
		(min_thickness 0.25)
		(keepout
			(tracks not_allowed)
			(vias allowed)
			(pads allowed)
			(copperpour not_allowed)
			(footprints allowed)
		)
		(placement
			(enabled no)
			(sheetname "")
		)
		(fill yes
			(thermal_gap 0.5)
			(thermal_bridge_width 0.5)
			(island_removal_mode 0)
		)
		(polygon
			(pts
				(arc
					(start 86.076028 -271.656302)
					(mid 85.446108 -271.656302)
					(end 86.076028 -271.656302)
				)
			)
		)
	)
	(zone
		(layers "B.Cu" "In13.Cu" "In15.Cu")
		(hatch none 0.5)
		(connect_pads
			(clearance 0)
		)
		(min_thickness 0.25)
		(keepout
			(tracks not_allowed)
			(vias allowed)
			(pads allowed)
			(copperpour not_allowed)
			(footprints allowed)
		)
		(placement
			(enabled no)
			(sheetname "")
		)
		(fill yes
			(thermal_gap 0.5)
			(thermal_bridge_width 0.5)
			(island_removal_mode 0)
		)
		(polygon
			(pts
				(arc
					(start 84.03717 -429.689768)
					(mid 83.262978 -429.689768)
					(end 84.03717 -429.689768)
				)
			)
		)
	)
	(zone
		(layers "B.Cu" "In13.Cu" "In15.Cu")
		(hatch none 0.5)
		(connect_pads
			(clearance 0)
		)
		(min_thickness 0.25)
		(keepout
			(tracks not_allowed)
			(vias allowed)
			(pads allowed)
			(copperpour not_allowed)
			(footprints allowed)
		)
		(placement
			(enabled no)
			(sheetname "")
		)
		(fill yes
			(thermal_gap 0.5)
			(thermal_bridge_width 0.5)
			(island_removal_mode 0)
		)
		(polygon
			(pts
				(arc
					(start 138.239754 -290.286186)
					(mid 137.609834 -290.286186)
					(end 138.239754 -290.286186)
				)
			)
		)
	)
	(zone
		(layers "B.Cu" "In13.Cu" "In15.Cu")
		(hatch none 0.5)
		(connect_pads
			(clearance 0)
		)
		(min_thickness 0.25)
		(keepout
			(tracks not_allowed)
			(vias allowed)
			(pads allowed)
			(copperpour not_allowed)
			(footprints allowed)
		)
		(placement
			(enabled no)
			(sheetname "")
		)
		(fill yes
			(thermal_gap 0.5)
			(thermal_bridge_width 0.5)
			(island_removal_mode 0)
		)
		(polygon
			(pts
				(arc
					(start 363.319822 -245.29415)
					(mid 362.689902 -245.29415)
					(end 363.319822 -245.29415)
				)
			)
		)
	)
	(zone
		(layers "B.Cu" "In13.Cu" "In15.Cu")
		(hatch none 0.5)
		(connect_pads
			(clearance 0)
		)
		(min_thickness 0.25)
		(keepout
			(tracks not_allowed)
			(vias allowed)
			(pads allowed)
			(copperpour not_allowed)
			(footprints allowed)
		)
		(placement
			(enabled no)
			(sheetname "")
		)
		(fill yes
			(thermal_gap 0.5)
			(thermal_bridge_width 0.5)
			(island_removal_mode 0)
		)
		(polygon
			(pts
				(arc
					(start 75.697334 -412.570168)
					(mid 75.029314 -412.570168)
					(end 75.697334 -412.570168)
				)
			)
		)
	)
	(zone
		(layers "B.Cu" "In13.Cu" "In15.Cu")
		(hatch none 0.5)
		(connect_pads
			(clearance 0)
		)
		(min_thickness 0.25)
		(keepout
			(tracks not_allowed)
			(vias allowed)
			(pads allowed)
			(copperpour not_allowed)
			(footprints allowed)
		)
		(placement
			(enabled no)
			(sheetname "")
		)
		(fill yes
			(thermal_gap 0.5)
			(thermal_bridge_width 0.5)
			(island_removal_mode 0)
		)
		(polygon
			(pts
				(arc
					(start 22.04212 -252.58522)
					(mid 21.3741 -252.58522)
					(end 22.04212 -252.58522)
				)
			)
		)
	)
	(zone
		(layers "B.Cu" "In13.Cu" "In15.Cu")
		(hatch none 0.5)
		(connect_pads
			(clearance 0)
		)
		(min_thickness 0.25)
		(keepout
			(tracks not_allowed)
			(vias allowed)
			(pads allowed)
			(copperpour not_allowed)
			(footprints allowed)
		)
		(placement
			(enabled no)
			(sheetname "")
		)
		(fill yes
			(thermal_gap 0.5)
			(thermal_bridge_width 0.5)
			(island_removal_mode 0)
		)
		(polygon
			(pts
				(arc
					(start 332.306168 -227.474272)
					(mid 331.676248 -227.474272)
					(end 332.306168 -227.474272)
				)
			)
		)
	)
	(zone
		(layers "B.Cu" "In13.Cu" "In15.Cu")
		(hatch none 0.5)
		(connect_pads
			(clearance 0)
		)
		(min_thickness 0.25)
		(keepout
			(tracks not_allowed)
			(vias allowed)
			(pads allowed)
			(copperpour not_allowed)
			(footprints allowed)
		)
		(placement
			(enabled no)
			(sheetname "")
		)
		(fill yes
			(thermal_gap 0.5)
			(thermal_bridge_width 0.5)
			(island_removal_mode 0)
		)
		(polygon
			(pts
				(arc
					(start 338.036916 -431.889916)
					(mid 337.262724 -431.889916)
					(end 338.036916 -431.889916)
				)
			)
		)
	)
	(zone
		(layers "B.Cu" "In13.Cu" "In15.Cu")
		(hatch none 0.5)
		(connect_pads
			(clearance 0)
		)
		(min_thickness 0.25)
		(keepout
			(tracks not_allowed)
			(vias allowed)
			(pads allowed)
			(copperpour not_allowed)
			(footprints allowed)
		)
		(placement
			(enabled no)
			(sheetname "")
		)
		(fill yes
			(thermal_gap 0.5)
			(thermal_bridge_width 0.5)
			(island_removal_mode 0)
		)
		(polygon
			(pts
				(arc
					(start 139.819634 -235.574332)
					(mid 139.189714 -235.574332)
					(end 139.819634 -235.574332)
				)
			)
		)
	)
	(zone
		(layers "B.Cu" "In13.Cu" "In15.Cu")
		(hatch none 0.5)
		(connect_pads
			(clearance 0)
		)
		(min_thickness 0.25)
		(keepout
			(tracks not_allowed)
			(vias allowed)
			(pads allowed)
			(copperpour not_allowed)
			(footprints allowed)
		)
		(placement
			(enabled no)
			(sheetname "")
		)
		(fill yes
			(thermal_gap 0.5)
			(thermal_bridge_width 0.5)
			(island_removal_mode 0)
		)
		(polygon
			(pts
				(arc
					(start 398.797272 -420.952168)
					(mid 398.129252 -420.952168)
					(end 398.797272 -420.952168)
				)
			)
		)
	)
	(zone
		(layers "B.Cu" "In13.Cu" "In15.Cu")
		(hatch none 0.5)
		(connect_pads
			(clearance 0)
		)
		(min_thickness 0.25)
		(keepout
			(tracks not_allowed)
			(vias allowed)
			(pads allowed)
			(copperpour not_allowed)
			(footprints allowed)
		)
		(placement
			(enabled no)
			(sheetname "")
		)
		(fill yes
			(thermal_gap 0.5)
			(thermal_bridge_width 0.5)
			(island_removal_mode 0)
		)
		(polygon
			(pts
				(arc
					(start 95.0341 -385.31038)
					(mid 94.40418 -385.31038)
					(end 95.0341 -385.31038)
				)
			)
		)
	)
	(zone
		(layers "B.Cu" "In13.Cu" "In15.Cu")
		(hatch none 0.5)
		(connect_pads
			(clearance 0)
		)
		(min_thickness 0.25)
		(keepout
			(tracks not_allowed)
			(vias allowed)
			(pads allowed)
			(copperpour not_allowed)
			(footprints allowed)
		)
		(placement
			(enabled no)
			(sheetname "")
		)
		(fill yes
			(thermal_gap 0.5)
			(thermal_bridge_width 0.5)
			(island_removal_mode 0)
		)
		(polygon
			(pts
				(arc
					(start 322.507356 -420.952168)
					(mid 321.839336 -420.952168)
					(end 322.507356 -420.952168)
				)
			)
		)
	)
	(zone
		(layers "B.Cu" "In13.Cu" "In15.Cu")
		(hatch none 0.5)
		(connect_pads
			(clearance 0)
		)
		(min_thickness 0.25)
		(keepout
			(tracks not_allowed)
			(vias allowed)
			(pads allowed)
			(copperpour not_allowed)
			(footprints allowed)
		)
		(placement
			(enabled no)
			(sheetname "")
		)
		(fill yes
			(thermal_gap 0.5)
			(thermal_bridge_width 0.5)
			(island_removal_mode 0)
		)
		(polygon
			(pts
				(arc
					(start 202.481942 -261.935214)
					(mid 201.813922 -261.935214)
					(end 202.481942 -261.935214)
				)
			)
		)
	)
	(zone
		(layers "B.Cu" "In13.Cu" "In15.Cu")
		(hatch none 0.5)
		(connect_pads
			(clearance 0)
		)
		(min_thickness 0.25)
		(keepout
			(tracks not_allowed)
			(vias allowed)
			(pads allowed)
			(copperpour not_allowed)
			(footprints allowed)
		)
		(placement
			(enabled no)
			(sheetname "")
		)
		(fill yes
			(thermal_gap 0.5)
			(thermal_bridge_width 0.5)
			(island_removal_mode 0)
		)
		(polygon
			(pts
				(arc
					(start 140.119608 -280.566368)
					(mid 139.489688 -280.566368)
					(end 140.119608 -280.566368)
				)
			)
		)
	)
	(zone
		(layers "B.Cu" "In13.Cu" "In15.Cu")
		(hatch none 0.5)
		(connect_pads
			(clearance 0)
		)
		(min_thickness 0.25)
		(keepout
			(tracks not_allowed)
			(vias allowed)
			(pads allowed)
			(copperpour not_allowed)
			(footprints allowed)
		)
		(placement
			(enabled no)
			(sheetname "")
		)
		(fill yes
			(thermal_gap 0.5)
			(thermal_bridge_width 0.5)
			(island_removal_mode 0)
		)
		(polygon
			(pts
				(arc
					(start 454.522078 -279.785064)
					(mid 453.854058 -279.785064)
					(end 454.522078 -279.785064)
				)
			)
		)
	)
	(zone
		(layers "B.Cu" "In13.Cu" "In15.Cu")
		(hatch none 0.5)
		(connect_pads
			(clearance 0)
		)
		(min_thickness 0.25)
		(keepout
			(tracks not_allowed)
			(vias allowed)
			(pads allowed)
			(copperpour not_allowed)
			(footprints allowed)
		)
		(placement
			(enabled no)
			(sheetname "")
		)
		(fill yes
			(thermal_gap 0.5)
			(thermal_bridge_width 0.5)
			(island_removal_mode 0)
		)
		(polygon
			(pts
				(arc
					(start 17.942052 -285.735268)
					(mid 17.274032 -285.735268)
					(end 17.942052 -285.735268)
				)
			)
		)
	)
	(zone
		(layers "B.Cu" "In13.Cu" "In15.Cu")
		(hatch none 0.5)
		(connect_pads
			(clearance 0)
		)
		(min_thickness 0.25)
		(keepout
			(tracks not_allowed)
			(vias allowed)
			(pads allowed)
			(copperpour not_allowed)
			(footprints allowed)
		)
		(placement
			(enabled no)
			(sheetname "")
		)
		(fill yes
			(thermal_gap 0.5)
			(thermal_bridge_width 0.5)
			(island_removal_mode 0)
		)
		(polygon
			(pts
				(arc
					(start 202.481942 -222.835216)
					(mid 201.813922 -222.835216)
					(end 202.481942 -222.835216)
				)
			)
		)
	)
	(zone
		(layers "B.Cu" "In13.Cu" "In15.Cu")
		(hatch none 0.5)
		(connect_pads
			(clearance 0)
		)
		(min_thickness 0.25)
		(keepout
			(tracks not_allowed)
			(vias allowed)
			(pads allowed)
			(copperpour not_allowed)
			(footprints allowed)
		)
		(placement
			(enabled no)
			(sheetname "")
		)
		(fill yes
			(thermal_gap 0.5)
			(thermal_bridge_width 0.5)
			(island_removal_mode 0)
		)
		(polygon
			(pts
				(arc
					(start 123.669806 -276.516338)
					(mid 123.039886 -276.516338)
					(end 123.669806 -276.516338)
				)
			)
		)
	)
	(zone
		(layers "B.Cu" "In13.Cu" "In15.Cu")
		(hatch none 0.5)
		(connect_pads
			(clearance 0)
		)
		(min_thickness 0.25)
		(keepout
			(tracks not_allowed)
			(vias allowed)
			(pads allowed)
			(copperpour not_allowed)
			(footprints allowed)
		)
		(placement
			(enabled no)
			(sheetname "")
		)
		(fill yes
			(thermal_gap 0.5)
			(thermal_bridge_width 0.5)
			(island_removal_mode 0)
		)
		(polygon
			(pts
				(arc
					(start 450.42201 -272.984976)
					(mid 449.75399 -272.984976)
					(end 450.42201 -272.984976)
				)
			)
		)
	)
	(zone
		(layers "B.Cu" "In13.Cu" "In15.Cu")
		(hatch none 0.5)
		(connect_pads
			(clearance 0)
		)
		(min_thickness 0.25)
		(keepout
			(tracks not_allowed)
			(vias allowed)
			(pads allowed)
			(copperpour not_allowed)
			(footprints allowed)
		)
		(placement
			(enabled no)
			(sheetname "")
		)
		(fill yes
			(thermal_gap 0.5)
			(thermal_bridge_width 0.5)
			(island_removal_mode 0)
		)
		(polygon
			(pts
				(arc
					(start 84.666074 -269.226284)
					(mid 84.036154 -269.226284)
					(end 84.666074 -269.226284)
				)
			)
		)
	)
	(zone
		(layers "B.Cu" "In13.Cu" "In15.Cu")
		(hatch none 0.5)
		(connect_pads
			(clearance 0)
		)
		(min_thickness 0.25)
		(keepout
			(tracks not_allowed)
			(vias allowed)
			(pads allowed)
			(copperpour not_allowed)
			(footprints allowed)
		)
		(placement
			(enabled no)
			(sheetname "")
		)
		(fill yes
			(thermal_gap 0.5)
			(thermal_bridge_width 0.5)
			(island_removal_mode 0)
		)
		(polygon
			(pts
				(arc
					(start 269.982188 -285.735014)
					(mid 269.314168 -285.735014)
					(end 269.982188 -285.735014)
				)
			)
		)
	)
	(zone
		(layers "B.Cu" "In13.Cu" "In15.Cu")
		(hatch none 0.5)
		(connect_pads
			(clearance 0)
		)
		(min_thickness 0.25)
		(keepout
			(tracks not_allowed)
			(vias allowed)
			(pads allowed)
			(copperpour not_allowed)
			(footprints allowed)
		)
		(placement
			(enabled no)
			(sheetname "")
		)
		(fill yes
			(thermal_gap 0.5)
			(thermal_bridge_width 0.5)
			(island_removal_mode 0)
		)
		(polygon
			(pts
				(arc
					(start 333.076042 -282.996132)
					(mid 332.446122 -282.996132)
					(end 333.076042 -282.996132)
				)
			)
		)
	)
	(zone
		(layers "B.Cu" "In13.Cu" "In15.Cu")
		(hatch none 0.5)
		(connect_pads
			(clearance 0)
		)
		(min_thickness 0.25)
		(keepout
			(tracks not_allowed)
			(vias allowed)
			(pads allowed)
			(copperpour not_allowed)
			(footprints allowed)
		)
		(placement
			(enabled no)
			(sheetname "")
		)
		(fill yes
			(thermal_gap 0.5)
			(thermal_bridge_width 0.5)
			(island_removal_mode 0)
		)
		(polygon
			(pts
				(arc
					(start 269.982188 -261.085076)
					(mid 269.314168 -261.085076)
					(end 269.982188 -261.085076)
				)
			)
		)
	)
	(zone
		(layers "B.Cu" "In13.Cu" "In15.Cu")
		(hatch none 0.5)
		(connect_pads
			(clearance 0)
		)
		(min_thickness 0.25)
		(keepout
			(tracks not_allowed)
			(vias allowed)
			(pads allowed)
			(copperpour not_allowed)
			(footprints allowed)
		)
		(placement
			(enabled no)
			(sheetname "")
		)
		(fill yes
			(thermal_gap 0.5)
			(thermal_bridge_width 0.5)
			(island_removal_mode 0)
		)
		(polygon
			(pts
				(arc
					(start 206.58201 -214.33536)
					(mid 205.91399 -214.33536)
					(end 206.58201 -214.33536)
				)
			)
		)
	)
	(zone
		(layers "B.Cu" "In13.Cu" "In15.Cu")
		(hatch none 0.5)
		(connect_pads
			(clearance 0)
		)
		(min_thickness 0.25)
		(keepout
			(tracks not_allowed)
			(vias allowed)
			(pads allowed)
			(copperpour not_allowed)
			(footprints allowed)
		)
		(placement
			(enabled no)
			(sheetname "")
		)
		(fill yes
			(thermal_gap 0.5)
			(thermal_bridge_width 0.5)
			(island_removal_mode 0)
		)
		(polygon
			(pts
				(arc
					(start 202.481942 -251.735336)
					(mid 201.813922 -251.735336)
					(end 202.481942 -251.735336)
				)
			)
		)
	)
	(zone
		(layers "B.Cu" "In13.Cu" "In15.Cu")
		(hatch none 0.5)
		(connect_pads
			(clearance 0)
		)
		(min_thickness 0.25)
		(keepout
			(tracks not_allowed)
			(vias allowed)
			(pads allowed)
			(copperpour not_allowed)
			(footprints allowed)
		)
		(placement
			(enabled no)
			(sheetname "")
		)
		(fill yes
			(thermal_gap 0.5)
			(thermal_bridge_width 0.5)
			(island_removal_mode 0)
		)
		(polygon
			(pts
				(arc
					(start 315.036708 -429.689768)
					(mid 314.262516 -429.689768)
					(end 315.036708 -429.689768)
				)
			)
		)
	)
	(zone
		(layers "B.Cu" "In13.Cu" "In15.Cu")
		(hatch none 0.5)
		(connect_pads
			(clearance 0)
		)
		(min_thickness 0.25)
		(keepout
			(tracks not_allowed)
			(vias allowed)
			(pads allowed)
			(copperpour not_allowed)
			(footprints allowed)
		)
		(placement
			(enabled no)
			(sheetname "")
		)
		(fill yes
			(thermal_gap 0.5)
			(thermal_bridge_width 0.5)
			(island_removal_mode 0)
		)
		(polygon
			(pts
				(arc
					(start 333.716122 -242.864132)
					(mid 333.086202 -242.864132)
					(end 333.716122 -242.864132)
				)
			)
		)
	)
	(zone
		(layers "B.Cu" "In13.Cu" "In15.Cu")
		(hatch none 0.5)
		(connect_pads
			(clearance 0)
		)
		(min_thickness 0.25)
		(keepout
			(tracks not_allowed)
			(vias allowed)
			(pads allowed)
			(copperpour not_allowed)
			(footprints allowed)
		)
		(placement
			(enabled no)
			(sheetname "")
		)
		(fill yes
			(thermal_gap 0.5)
			(thermal_bridge_width 0.5)
			(island_removal_mode 0)
		)
		(polygon
			(pts
				(arc
					(start 109.746034 -248.534428)
					(mid 109.116114 -248.534428)
					(end 109.746034 -248.534428)
				)
			)
		)
	)
	(zone
		(layers "B.Cu" "In13.Cu" "In15.Cu")
		(hatch none 0.5)
		(connect_pads
			(clearance 0)
		)
		(min_thickness 0.25)
		(keepout
			(tracks not_allowed)
			(vias allowed)
			(pads allowed)
			(copperpour not_allowed)
			(footprints allowed)
		)
		(placement
			(enabled no)
			(sheetname "")
		)
		(fill yes
			(thermal_gap 0.5)
			(thermal_bridge_width 0.5)
			(island_removal_mode 0)
		)
		(polygon
			(pts
				(arc
					(start 386.349748 -239.624108)
					(mid 385.719828 -239.624108)
					(end 386.349748 -239.624108)
				)
			)
		)
	)
	(zone
		(layers "B.Cu" "In13.Cu" "In15.Cu")
		(hatch none 0.5)
		(connect_pads
			(clearance 0)
		)
		(min_thickness 0.25)
		(keepout
			(tracks not_allowed)
			(vias allowed)
			(pads allowed)
			(copperpour not_allowed)
			(footprints allowed)
		)
		(placement
			(enabled no)
			(sheetname "")
		)
		(fill yes
			(thermal_gap 0.5)
			(thermal_bridge_width 0.5)
			(island_removal_mode 0)
		)
		(polygon
			(pts
				(arc
					(start 106.455972 -247.724422)
					(mid 105.826052 -247.724422)
					(end 106.455972 -247.724422)
				)
			)
		)
	)
	(zone
		(layers "B.Cu" "In13.Cu" "In15.Cu")
		(hatch none 0.5)
		(connect_pads
			(clearance 0)
		)
		(min_thickness 0.25)
		(keepout
			(tracks not_allowed)
			(vias allowed)
			(pads allowed)
			(copperpour not_allowed)
			(footprints allowed)
		)
		(placement
			(enabled no)
			(sheetname "")
		)
		(fill yes
			(thermal_gap 0.5)
			(thermal_bridge_width 0.5)
			(island_removal_mode 0)
		)
		(polygon
			(pts
				(arc
					(start 85.776054 -255.824482)
					(mid 85.146134 -255.824482)
					(end 85.776054 -255.824482)
				)
			)
		)
	)
	(zone
		(layers "B.Cu" "In13.Cu" "In15.Cu")
		(hatch none 0.5)
		(connect_pads
			(clearance 0)
		)
		(min_thickness 0.25)
		(keepout
			(tracks not_allowed)
			(vias allowed)
			(pads allowed)
			(copperpour not_allowed)
			(footprints allowed)
		)
		(placement
			(enabled no)
			(sheetname "")
		)
		(fill yes
			(thermal_gap 0.5)
			(thermal_bridge_width 0.5)
			(island_removal_mode 0)
		)
		(polygon
			(pts
				(arc
					(start 386.179822 -287.045908)
					(mid 385.549902 -287.045908)
					(end 386.179822 -287.045908)
				)
			)
		)
	)
	(zone
		(layers "B.Cu" "In13.Cu" "In15.Cu")
		(hatch none 0.5)
		(connect_pads
			(clearance 0)
		)
		(min_thickness 0.25)
		(keepout
			(tracks not_allowed)
			(vias allowed)
			(pads allowed)
			(copperpour not_allowed)
			(footprints allowed)
		)
		(placement
			(enabled no)
			(sheetname "")
		)
		(fill yes
			(thermal_gap 0.5)
			(thermal_bridge_width 0.5)
			(island_removal_mode 0)
		)
		(polygon
			(pts
				(arc
					(start 86.076028 -270.03629)
					(mid 85.446108 -270.03629)
					(end 86.076028 -270.03629)
				)
			)
		)
	)
	(zone
		(layers "B.Cu" "In13.Cu" "In15.Cu")
		(hatch none 0.5)
		(connect_pads
			(clearance 0)
		)
		(min_thickness 0.25)
		(keepout
			(tracks not_allowed)
			(vias allowed)
			(pads allowed)
			(copperpour not_allowed)
			(footprints allowed)
		)
		(placement
			(enabled no)
			(sheetname "")
		)
		(fill yes
			(thermal_gap 0.5)
			(thermal_bridge_width 0.5)
			(island_removal_mode 0)
		)
		(polygon
			(pts
				(arc
					(start 332.776068 -225.044254)
					(mid 332.146148 -225.044254)
					(end 332.776068 -225.044254)
				)
			)
		)
	)
	(zone
		(layers "B.Cu" "In13.Cu" "In15.Cu")
		(hatch none 0.5)
		(connect_pads
			(clearance 0)
		)
		(min_thickness 0.25)
		(keepout
			(tracks not_allowed)
			(vias allowed)
			(pads allowed)
			(copperpour not_allowed)
			(footprints allowed)
		)
		(placement
			(enabled no)
			(sheetname "")
		)
		(fill yes
			(thermal_gap 0.5)
			(thermal_bridge_width 0.5)
			(island_removal_mode 0)
		)
		(polygon
			(pts
				(arc
					(start 333.716122 -250.964192)
					(mid 333.086202 -250.964192)
					(end 333.716122 -250.964192)
				)
			)
		)
	)
	(zone
		(layers "B.Cu" "In13.Cu" "In15.Cu")
		(hatch none 0.5)
		(connect_pads
			(clearance 0)
		)
		(min_thickness 0.25)
		(keepout
			(tracks not_allowed)
			(vias allowed)
			(pads allowed)
			(copperpour not_allowed)
			(footprints allowed)
		)
		(placement
			(enabled no)
			(sheetname "")
		)
		(fill yes
			(thermal_gap 0.5)
			(thermal_bridge_width 0.5)
			(island_removal_mode 0)
		)
		(polygon
			(pts
				(arc
					(start 98.295968 -274.896326)
					(mid 97.666048 -274.896326)
					(end 98.295968 -274.896326)
				)
			)
		)
	)
	(zone
		(layers "B.Cu" "In13.Cu" "In15.Cu")
		(hatch none 0.5)
		(connect_pads
			(clearance 0)
		)
		(min_thickness 0.25)
		(keepout
			(tracks not_allowed)
			(vias allowed)
			(pads allowed)
			(copperpour not_allowed)
			(footprints allowed)
		)
		(placement
			(enabled no)
			(sheetname "")
		)
		(fill yes
			(thermal_gap 0.5)
			(thermal_bridge_width 0.5)
			(island_removal_mode 0)
		)
		(polygon
			(pts
				(arc
					(start 206.58201 -201.585322)
					(mid 205.91399 -201.585322)
					(end 206.58201 -201.585322)
				)
			)
		)
	)
	(zone
		(layers "B.Cu" "In13.Cu" "In15.Cu")
		(hatch none 0.5)
		(connect_pads
			(clearance 0)
		)
		(min_thickness 0.25)
		(keepout
			(tracks not_allowed)
			(vias allowed)
			(pads allowed)
			(copperpour not_allowed)
			(footprints allowed)
		)
		(placement
			(enabled no)
			(sheetname "")
		)
		(fill yes
			(thermal_gap 0.5)
			(thermal_bridge_width 0.5)
			(island_removal_mode 0)
		)
		(polygon
			(pts
				(arc
					(start 139.349734 -242.864386)
					(mid 138.719814 -242.864386)
					(end 139.349734 -242.864386)
				)
			)
		)
	)
	(zone
		(layers "B.Cu" "In13.Cu" "In15.Cu")
		(hatch none 0.5)
		(connect_pads
			(clearance 0)
		)
		(min_thickness 0.25)
		(keepout
			(tracks not_allowed)
			(vias allowed)
			(pads allowed)
			(copperpour not_allowed)
			(footprints allowed)
		)
		(placement
			(enabled no)
			(sheetname "")
		)
		(fill yes
			(thermal_gap 0.5)
			(thermal_bridge_width 0.5)
			(island_removal_mode 0)
		)
		(polygon
			(pts
				(arc
					(start 84.836 -233.144314)
					(mid 84.20608 -233.144314)
					(end 84.836 -233.144314)
				)
			)
		)
	)
	(zone
		(layers "B.Cu" "In13.Cu" "In15.Cu")
		(hatch none 0.5)
		(connect_pads
			(clearance 0)
		)
		(min_thickness 0.25)
		(keepout
			(tracks not_allowed)
			(vias allowed)
			(pads allowed)
			(copperpour not_allowed)
			(footprints allowed)
		)
		(placement
			(enabled no)
			(sheetname "")
		)
		(fill yes
			(thermal_gap 0.5)
			(thermal_bridge_width 0.5)
			(island_removal_mode 0)
		)
		(polygon
			(pts
				(arc
					(start 106.455972 -244.484398)
					(mid 105.826052 -244.484398)
					(end 106.455972 -244.484398)
				)
			)
		)
	)
	(zone
		(layers "B.Cu" "In13.Cu" "In15.Cu")
		(hatch none 0.5)
		(connect_pads
			(clearance 0)
		)
		(min_thickness 0.25)
		(keepout
			(tracks not_allowed)
			(vias allowed)
			(pads allowed)
			(copperpour not_allowed)
			(footprints allowed)
		)
		(placement
			(enabled no)
			(sheetname "")
		)
		(fill yes
			(thermal_gap 0.5)
			(thermal_bridge_width 0.5)
			(island_removal_mode 0)
		)
		(polygon
			(pts
				(arc
					(start 450.42201 -232.184956)
					(mid 449.75399 -232.184956)
					(end 450.42201 -232.184956)
				)
			)
		)
	)
	(zone
		(layers "B.Cu" "In13.Cu" "In15.Cu")
		(hatch none 0.5)
		(connect_pads
			(clearance 0)
		)
		(min_thickness 0.25)
		(keepout
			(tracks not_allowed)
			(vias allowed)
			(pads allowed)
			(copperpour not_allowed)
			(footprints allowed)
		)
		(placement
			(enabled no)
			(sheetname "")
		)
		(fill yes
			(thermal_gap 0.5)
			(thermal_bridge_width 0.5)
			(island_removal_mode 0)
		)
		(polygon
			(pts
				(arc
					(start 86.245954 -255.014476)
					(mid 85.616034 -255.014476)
					(end 86.245954 -255.014476)
				)
			)
		)
	)
	(zone
		(layers "B.Cu" "In13.Cu" "In15.Cu")
		(hatch none 0.5)
		(connect_pads
			(clearance 0)
		)
		(min_thickness 0.25)
		(keepout
			(tracks not_allowed)
			(vias allowed)
			(pads allowed)
			(copperpour not_allowed)
			(footprints allowed)
		)
		(placement
			(enabled no)
			(sheetname "")
		)
		(fill yes
			(thermal_gap 0.5)
			(thermal_bridge_width 0.5)
			(island_removal_mode 0)
		)
		(polygon
			(pts
				(arc
					(start 202.481942 -237.285276)
					(mid 201.813922 -237.285276)
					(end 202.481942 -237.285276)
				)
			)
		)
	)
	(zone
		(layers "B.Cu" "In13.Cu" "In15.Cu")
		(hatch none 0.5)
		(connect_pads
			(clearance 0)
		)
		(min_thickness 0.25)
		(keepout
			(tracks not_allowed)
			(vias allowed)
			(pads allowed)
			(copperpour not_allowed)
			(footprints allowed)
		)
		(placement
			(enabled no)
			(sheetname "")
		)
		(fill yes
			(thermal_gap 0.5)
			(thermal_bridge_width 0.5)
			(island_removal_mode 0)
		)
		(polygon
			(pts
				(arc
					(start 117.089682 -278.13635)
					(mid 116.459762 -278.13635)
					(end 117.089682 -278.13635)
				)
			)
		)
	)
	(zone
		(layers "B.Cu" "In13.Cu" "In15.Cu")
		(hatch none 0.5)
		(connect_pads
			(clearance 0)
		)
		(min_thickness 0.25)
		(keepout
			(tracks not_allowed)
			(vias allowed)
			(pads allowed)
			(copperpour not_allowed)
			(footprints allowed)
		)
		(placement
			(enabled no)
			(sheetname "")
		)
		(fill yes
			(thermal_gap 0.5)
			(thermal_bridge_width 0.5)
			(island_removal_mode 0)
		)
		(polygon
			(pts
				(arc
					(start 380.417832 -420.952168)
					(mid 379.749812 -420.952168)
					(end 380.417832 -420.952168)
				)
			)
		)
	)
	(zone
		(layers "B.Cu" "In13.Cu" "In15.Cu")
		(hatch none 0.5)
		(connect_pads
			(clearance 0)
		)
		(min_thickness 0.25)
		(keepout
			(tracks not_allowed)
			(vias allowed)
			(pads allowed)
			(copperpour not_allowed)
			(footprints allowed)
		)
		(placement
			(enabled no)
			(sheetname "")
		)
		(fill yes
			(thermal_gap 0.5)
			(thermal_bridge_width 0.5)
			(island_removal_mode 0)
		)
		(polygon
			(pts
				(arc
					(start 350.233742 -394.385292)
					(mid 349.603822 -394.385292)
					(end 350.233742 -394.385292)
				)
			)
		)
	)
	(zone
		(layers "B.Cu" "In13.Cu" "In15.Cu")
		(hatch none 0.5)
		(connect_pads
			(clearance 0)
		)
		(min_thickness 0.25)
		(keepout
			(tracks not_allowed)
			(vias allowed)
			(pads allowed)
			(copperpour not_allowed)
			(footprints allowed)
		)
		(placement
			(enabled no)
			(sheetname "")
		)
		(fill yes
			(thermal_gap 0.5)
			(thermal_bridge_width 0.5)
			(island_removal_mode 0)
		)
		(polygon
			(pts
				(arc
					(start 269.982188 -264.48512)
					(mid 269.314168 -264.48512)
					(end 269.982188 -264.48512)
				)
			)
		)
	)
	(zone
		(layers "B.Cu" "In13.Cu" "In15.Cu")
		(hatch none 0.5)
		(connect_pads
			(clearance 0)
		)
		(min_thickness 0.25)
		(keepout
			(tracks not_allowed)
			(vias allowed)
			(pads allowed)
			(copperpour not_allowed)
			(footprints allowed)
		)
		(placement
			(enabled no)
			(sheetname "")
		)
		(fill yes
			(thermal_gap 0.5)
			(thermal_bridge_width 0.5)
			(island_removal_mode 0)
		)
		(polygon
			(pts
				(arc
					(start 83.034124 -388.774432)
					(mid 82.404204 -388.774432)
					(end 83.034124 -388.774432)
				)
			)
		)
	)
	(zone
		(layers "B.Cu" "In13.Cu" "In15.Cu")
		(hatch none 0.5)
		(connect_pads
			(clearance 0)
		)
		(min_thickness 0.25)
		(keepout
			(tracks not_allowed)
			(vias allowed)
			(pads allowed)
			(copperpour not_allowed)
			(footprints allowed)
		)
		(placement
			(enabled no)
			(sheetname "")
		)
		(fill yes
			(thermal_gap 0.5)
			(thermal_bridge_width 0.5)
			(island_removal_mode 0)
		)
		(polygon
			(pts
				(arc
					(start 387.759702 -237.19409)
					(mid 387.129782 -237.19409)
					(end 387.759702 -237.19409)
				)
			)
		)
	)
	(zone
		(layers "B.Cu" "In13.Cu" "In15.Cu")
		(hatch none 0.5)
		(connect_pads
			(clearance 0)
		)
		(min_thickness 0.25)
		(keepout
			(tracks not_allowed)
			(vias allowed)
			(pads allowed)
			(copperpour not_allowed)
			(footprints allowed)
		)
		(placement
			(enabled no)
			(sheetname "")
		)
		(fill yes
			(thermal_gap 0.5)
			(thermal_bridge_width 0.5)
			(island_removal_mode 0)
		)
		(polygon
			(pts
				(arc
					(start 357.046022 -277.32609)
					(mid 356.416102 -277.32609)
					(end 357.046022 -277.32609)
				)
			)
		)
	)
	(zone
		(layers "B.Cu" "In13.Cu" "In15.Cu")
		(hatch none 0.5)
		(connect_pads
			(clearance 0)
		)
		(min_thickness 0.25)
		(keepout
			(tracks not_allowed)
			(vias allowed)
			(pads allowed)
			(copperpour not_allowed)
			(footprints allowed)
		)
		(placement
			(enabled no)
			(sheetname "")
		)
		(fill yes
			(thermal_gap 0.5)
			(thermal_bridge_width 0.5)
			(island_removal_mode 0)
		)
		(polygon
			(pts
				(arc
					(start 454.522078 -231.335072)
					(mid 453.854058 -231.335072)
					(end 454.522078 -231.335072)
				)
			)
		)
	)
	(zone
		(layers "B.Cu" "In13.Cu" "In15.Cu")
		(hatch none 0.5)
		(connect_pads
			(clearance 0)
		)
		(min_thickness 0.25)
		(keepout
			(tracks not_allowed)
			(vias allowed)
			(pads allowed)
			(copperpour not_allowed)
			(footprints allowed)
		)
		(placement
			(enabled no)
			(sheetname "")
		)
		(fill yes
			(thermal_gap 0.5)
			(thermal_bridge_width 0.5)
			(island_removal_mode 0)
		)
		(polygon
			(pts
				(arc
					(start 387.589776 -287.856168)
					(mid 386.959856 -287.856168)
					(end 387.589776 -287.856168)
				)
			)
		)
	)
	(zone
		(layers "B.Cu" "In13.Cu" "In15.Cu")
		(hatch none 0.5)
		(connect_pads
			(clearance 0)
		)
		(min_thickness 0.25)
		(keepout
			(tracks not_allowed)
			(vias allowed)
			(pads allowed)
			(copperpour not_allowed)
			(footprints allowed)
		)
		(placement
			(enabled no)
			(sheetname "")
		)
		(fill yes
			(thermal_gap 0.5)
			(thermal_bridge_width 0.5)
			(island_removal_mode 0)
		)
		(polygon
			(pts
				(arc
					(start 339.033866 -393.69238)
					(mid 338.403946 -393.69238)
					(end 339.033866 -393.69238)
				)
			)
		)
	)
	(zone
		(layers "B.Cu" "In13.Cu" "In15.Cu")
		(hatch none 0.5)
		(connect_pads
			(clearance 0)
		)
		(min_thickness 0.25)
		(keepout
			(tracks not_allowed)
			(vias allowed)
			(pads allowed)
			(copperpour not_allowed)
			(footprints allowed)
		)
		(placement
			(enabled no)
			(sheetname "")
		)
		(fill yes
			(thermal_gap 0.5)
			(thermal_bridge_width 0.5)
			(island_removal_mode 0)
		)
		(polygon
			(pts
				(arc
					(start 135.949182 -11.955018)
					(mid 135.281162 -11.955018)
					(end 135.949182 -11.955018)
				)
			)
		)
	)
	(zone
		(layers "B.Cu" "In13.Cu" "In15.Cu")
		(hatch none 0.5)
		(connect_pads
			(clearance 0)
		)
		(min_thickness 0.25)
		(keepout
			(tracks not_allowed)
			(vias allowed)
			(pads allowed)
			(copperpour not_allowed)
			(footprints allowed)
		)
		(placement
			(enabled no)
			(sheetname "")
		)
		(fill yes
			(thermal_gap 0.5)
			(thermal_bridge_width 0.5)
			(island_removal_mode 0)
		)
		(polygon
			(pts
				(arc
					(start 345.936062 -236.384084)
					(mid 345.306142 -236.384084)
					(end 345.936062 -236.384084)
				)
			)
		)
	)
	(zone
		(layers "B.Cu" "In13.Cu" "In15.Cu")
		(hatch none 0.5)
		(connect_pads
			(clearance 0)
		)
		(min_thickness 0.25)
		(keepout
			(tracks not_allowed)
			(vias allowed)
			(pads allowed)
			(copperpour not_allowed)
			(footprints allowed)
		)
		(placement
			(enabled no)
			(sheetname "")
		)
		(fill yes
			(thermal_gap 0.5)
			(thermal_bridge_width 0.5)
			(island_removal_mode 0)
		)
		(polygon
			(pts
				(arc
					(start 387.289802 -241.24412)
					(mid 386.659882 -241.24412)
					(end 387.289802 -241.24412)
				)
			)
		)
	)
	(zone
		(layers "B.Cu" "In13.Cu" "In15.Cu")
		(hatch none 0.5)
		(connect_pads
			(clearance 0)
		)
		(min_thickness 0.25)
		(keepout
			(tracks not_allowed)
			(vias allowed)
			(pads allowed)
			(copperpour not_allowed)
			(footprints allowed)
		)
		(placement
			(enabled no)
			(sheetname "")
		)
		(fill yes
			(thermal_gap 0.5)
			(thermal_bridge_width 0.5)
			(island_removal_mode 0)
		)
		(polygon
			(pts
				(arc
					(start 139.349734 -250.964446)
					(mid 138.719814 -250.964446)
					(end 139.349734 -250.964446)
				)
			)
		)
	)
	(zone
		(layers "B.Cu" "In13.Cu" "In15.Cu")
		(hatch none 0.5)
		(connect_pads
			(clearance 0)
		)
		(min_thickness 0.25)
		(keepout
			(tracks not_allowed)
			(vias allowed)
			(pads allowed)
			(copperpour not_allowed)
			(footprints allowed)
		)
		(placement
			(enabled no)
			(sheetname "")
		)
		(fill yes
			(thermal_gap 0.5)
			(thermal_bridge_width 0.5)
			(island_removal_mode 0)
		)
		(polygon
			(pts
				(arc
					(start 349.033846 -394.385292)
					(mid 348.403926 -394.385292)
					(end 349.033846 -394.385292)
				)
			)
		)
	)
	(zone
		(layers "B.Cu" "In13.Cu" "In15.Cu")
		(hatch none 0.5)
		(connect_pads
			(clearance 0)
		)
		(min_thickness 0.25)
		(keepout
			(tracks not_allowed)
			(vias allowed)
			(pads allowed)
			(copperpour not_allowed)
			(footprints allowed)
		)
		(placement
			(enabled no)
			(sheetname "")
		)
		(fill yes
			(thermal_gap 0.5)
			(thermal_bridge_width 0.5)
			(island_removal_mode 0)
		)
		(polygon
			(pts
				(arc
					(start 86.076028 -281.376374)
					(mid 85.446108 -281.376374)
					(end 86.076028 -281.376374)
				)
			)
		)
	)
	(zone
		(layers "B.Cu" "In13.Cu" "In15.Cu")
		(hatch none 0.5)
		(connect_pads
			(clearance 0)
		)
		(min_thickness 0.25)
		(keepout
			(tracks not_allowed)
			(vias allowed)
			(pads allowed)
			(copperpour not_allowed)
			(footprints allowed)
		)
		(placement
			(enabled no)
			(sheetname "")
		)
		(fill yes
			(thermal_gap 0.5)
			(thermal_bridge_width 0.5)
			(island_removal_mode 0)
		)
		(polygon
			(pts
				(arc
					(start 22.04212 -289.135312)
					(mid 21.3741 -289.135312)
					(end 22.04212 -289.135312)
				)
			)
		)
	)
	(zone
		(layers "B.Cu" "In13.Cu" "In15.Cu")
		(hatch none 0.5)
		(connect_pads
			(clearance 0)
		)
		(min_thickness 0.25)
		(keepout
			(tracks not_allowed)
			(vias allowed)
			(pads allowed)
			(copperpour not_allowed)
			(footprints allowed)
		)
		(placement
			(enabled no)
			(sheetname "")
		)
		(fill yes
			(thermal_gap 0.5)
			(thermal_bridge_width 0.5)
			(island_removal_mode 0)
		)
		(polygon
			(pts
				(arc
					(start 84.23402 -388.774432)
					(mid 83.6041 -388.774432)
					(end 84.23402 -388.774432)
				)
			)
		)
	)
	(zone
		(layers "B.Cu" "In13.Cu" "In15.Cu")
		(hatch none 0.5)
		(connect_pads
			(clearance 0)
		)
		(min_thickness 0.25)
		(keepout
			(tracks not_allowed)
			(vias allowed)
			(pads allowed)
			(copperpour not_allowed)
			(footprints allowed)
		)
		(placement
			(enabled no)
			(sheetname "")
		)
		(fill yes
			(thermal_gap 0.5)
			(thermal_bridge_width 0.5)
			(island_removal_mode 0)
		)
		(polygon
			(pts
				(arc
					(start 140.119608 -287.046162)
					(mid 139.489688 -287.046162)
					(end 140.119608 -287.046162)
				)
			)
		)
	)
	(zone
		(layers "B.Cu" "In13.Cu" "In15.Cu")
		(hatch none 0.5)
		(connect_pads
			(clearance 0)
		)
		(min_thickness 0.25)
		(keepout
			(tracks not_allowed)
			(vias allowed)
			(pads allowed)
			(copperpour not_allowed)
			(footprints allowed)
		)
		(placement
			(enabled no)
			(sheetname "")
		)
		(fill yes
			(thermal_gap 0.5)
			(thermal_bridge_width 0.5)
			(island_removal_mode 0)
		)
		(polygon
			(pts
				(arc
					(start 265.88212 -301.034958)
					(mid 265.2141 -301.034958)
					(end 265.88212 -301.034958)
				)
			)
		)
	)
	(zone
		(layers "B.Cu" "In13.Cu" "In15.Cu")
		(hatch none 0.5)
		(connect_pads
			(clearance 0)
		)
		(min_thickness 0.25)
		(keepout
			(tracks not_allowed)
			(vias allowed)
			(pads allowed)
			(copperpour not_allowed)
			(footprints allowed)
		)
		(placement
			(enabled no)
			(sheetname "")
		)
		(fill yes
			(thermal_gap 0.5)
			(thermal_bridge_width 0.5)
			(island_removal_mode 0)
		)
		(polygon
			(pts
				(arc
					(start 332.776068 -238.004096)
					(mid 332.146148 -238.004096)
					(end 332.776068 -238.004096)
				)
			)
		)
	)
	(zone
		(layers "B.Cu" "In13.Cu" "In15.Cu")
		(hatch none 0.5)
		(connect_pads
			(clearance 0)
		)
		(min_thickness 0.25)
		(keepout
			(tracks not_allowed)
			(vias allowed)
			(pads allowed)
			(copperpour not_allowed)
			(footprints allowed)
		)
		(placement
			(enabled no)
			(sheetname "")
		)
		(fill yes
			(thermal_gap 0.5)
			(thermal_bridge_width 0.5)
			(island_removal_mode 0)
		)
		(polygon
			(pts
				(arc
					(start 85.776054 -236.384338)
					(mid 85.146134 -236.384338)
					(end 85.776054 -236.384338)
				)
			)
		)
	)
	(zone
		(layers "B.Cu" "In13.Cu" "In15.Cu")
		(hatch none 0.5)
		(connect_pads
			(clearance 0)
		)
		(min_thickness 0.25)
		(keepout
			(tracks not_allowed)
			(vias allowed)
			(pads allowed)
			(copperpour not_allowed)
			(footprints allowed)
		)
		(placement
			(enabled no)
			(sheetname "")
		)
		(fill yes
			(thermal_gap 0.5)
			(thermal_bridge_width 0.5)
			(island_removal_mode 0)
		)
		(polygon
			(pts
				(arc
					(start 140.13688 -431.889916)
					(mid 139.362688 -431.889916)
					(end 140.13688 -431.889916)
				)
			)
		)
	)
	(zone
		(layers "B.Cu" "In13.Cu" "In15.Cu")
		(hatch none 0.5)
		(connect_pads
			(clearance 0)
		)
		(min_thickness 0.25)
		(keepout
			(tracks not_allowed)
			(vias allowed)
			(pads allowed)
			(copperpour not_allowed)
			(footprints allowed)
		)
		(placement
			(enabled no)
			(sheetname "")
		)
		(fill yes
			(thermal_gap 0.5)
			(thermal_bridge_width 0.5)
			(island_removal_mode 0)
		)
		(polygon
			(pts
				(arc
					(start 269.982188 -292.535102)
					(mid 269.314168 -292.535102)
					(end 269.982188 -292.535102)
				)
			)
		)
	)
	(zone
		(layers "B.Cu" "In13.Cu" "In15.Cu")
		(hatch none 0.5)
		(connect_pads
			(clearance 0)
		)
		(min_thickness 0.25)
		(keepout
			(tracks not_allowed)
			(vias allowed)
			(pads allowed)
			(copperpour not_allowed)
			(footprints allowed)
		)
		(placement
			(enabled no)
			(sheetname "")
		)
		(fill yes
			(thermal_gap 0.5)
			(thermal_bridge_width 0.5)
			(island_removal_mode 0)
		)
		(polygon
			(pts
				(arc
					(start 115.379754 -235.574332)
					(mid 114.749834 -235.574332)
					(end 115.379754 -235.574332)
				)
			)
		)
	)
	(zone
		(layers "B.Cu" "In13.Cu" "In15.Cu")
		(hatch none 0.5)
		(connect_pads
			(clearance 0)
		)
		(min_thickness 0.25)
		(keepout
			(tracks not_allowed)
			(vias allowed)
			(pads allowed)
			(copperpour not_allowed)
			(footprints allowed)
		)
		(placement
			(enabled no)
			(sheetname "")
		)
		(fill yes
			(thermal_gap 0.5)
			(thermal_bridge_width 0.5)
			(island_removal_mode 0)
		)
		(polygon
			(pts
				(arc
					(start 143.137128 -430.889918)
					(mid 142.362936 -430.889918)
					(end 143.137128 -430.889918)
				)
			)
		)
	)
	(zone
		(layers "B.Cu" "In13.Cu" "In15.Cu")
		(hatch none 0.5)
		(connect_pads
			(clearance 0)
		)
		(min_thickness 0.25)
		(keepout
			(tracks not_allowed)
			(vias allowed)
			(pads allowed)
			(copperpour not_allowed)
			(footprints allowed)
		)
		(placement
			(enabled no)
			(sheetname "")
		)
		(fill yes
			(thermal_gap 0.5)
			(thermal_bridge_width 0.5)
			(island_removal_mode 0)
		)
		(polygon
			(pts
				(arc
					(start 384.1369 -431.889916)
					(mid 383.362708 -431.889916)
					(end 384.1369 -431.889916)
				)
			)
		)
	)
	(zone
		(layers "B.Cu" "In13.Cu" "In15.Cu")
		(hatch none 0.5)
		(connect_pads
			(clearance 0)
		)
		(min_thickness 0.25)
		(keepout
			(tracks not_allowed)
			(vias allowed)
			(pads allowed)
			(copperpour not_allowed)
			(footprints allowed)
		)
		(placement
			(enabled no)
			(sheetname "")
		)
		(fill yes
			(thermal_gap 0.5)
			(thermal_bridge_width 0.5)
			(island_removal_mode 0)
		)
		(polygon
			(pts
				(arc
					(start 386.349748 -234.764072)
					(mid 385.719828 -234.764072)
					(end 386.349748 -234.764072)
				)
			)
		)
	)
	(zone
		(layers "B.Cu" "In13.Cu" "In15.Cu")
		(hatch none 0.5)
		(connect_pads
			(clearance 0)
		)
		(min_thickness 0.25)
		(keepout
			(tracks not_allowed)
			(vias allowed)
			(pads allowed)
			(copperpour not_allowed)
			(footprints allowed)
		)
		(placement
			(enabled no)
			(sheetname "")
		)
		(fill yes
			(thermal_gap 0.5)
			(thermal_bridge_width 0.5)
			(island_removal_mode 0)
		)
		(polygon
			(pts
				(arc
					(start 265.88212 -295.935146)
					(mid 265.2141 -295.935146)
					(end 265.88212 -295.935146)
				)
			)
		)
	)
	(zone
		(layers "B.Cu" "In13.Cu" "In15.Cu")
		(hatch none 0.5)
		(connect_pads
			(clearance 0)
		)
		(min_thickness 0.25)
		(keepout
			(tracks not_allowed)
			(vias allowed)
			(pads allowed)
			(copperpour not_allowed)
			(footprints allowed)
		)
		(placement
			(enabled no)
			(sheetname "")
		)
		(fill yes
			(thermal_gap 0.5)
			(thermal_bridge_width 0.5)
			(island_removal_mode 0)
		)
		(polygon
			(pts
				(arc
					(start 402.724112 -420.952168)
					(mid 402.056092 -420.952168)
					(end 402.724112 -420.952168)
				)
			)
		)
	)
	(zone
		(layers "B.Cu" "In13.Cu" "In15.Cu")
		(hatch none 0.5)
		(connect_pads
			(clearance 0)
		)
		(min_thickness 0.25)
		(keepout
			(tracks not_allowed)
			(vias allowed)
			(pads allowed)
			(copperpour not_allowed)
			(footprints allowed)
		)
		(placement
			(enabled no)
			(sheetname "")
		)
		(fill yes
			(thermal_gap 0.5)
			(thermal_bridge_width 0.5)
			(island_removal_mode 0)
		)
		(polygon
			(pts
				(arc
					(start 86.545928 -282.18638)
					(mid 85.916008 -282.18638)
					(end 86.545928 -282.18638)
				)
			)
		)
	)
	(zone
		(layers "B.Cu" "In13.Cu" "In15.Cu")
		(hatch none 0.5)
		(connect_pads
			(clearance 0)
		)
		(min_thickness 0.25)
		(keepout
			(tracks not_allowed)
			(vias allowed)
			(pads allowed)
			(copperpour not_allowed)
			(footprints allowed)
		)
		(placement
			(enabled no)
			(sheetname "")
		)
		(fill yes
			(thermal_gap 0.5)
			(thermal_bridge_width 0.5)
			(island_removal_mode 0)
		)
		(polygon
			(pts
				(arc
					(start 311.117996 -420.952168)
					(mid 310.449976 -420.952168)
					(end 311.117996 -420.952168)
				)
			)
		)
	)
	(zone
		(layers "B.Cu" "In13.Cu" "In15.Cu")
		(hatch none 0.5)
		(connect_pads
			(clearance 0)
		)
		(min_thickness 0.25)
		(keepout
			(tracks not_allowed)
			(vias allowed)
			(pads allowed)
			(copperpour not_allowed)
			(footprints allowed)
		)
		(placement
			(enabled no)
			(sheetname "")
		)
		(fill yes
			(thermal_gap 0.5)
			(thermal_bridge_width 0.5)
			(island_removal_mode 0)
		)
		(polygon
			(pts
				(arc
					(start 99.236022 -278.13635)
					(mid 98.606102 -278.13635)
					(end 99.236022 -278.13635)
				)
			)
		)
	)
	(zone
		(layers "B.Cu" "In13.Cu" "In15.Cu")
		(hatch none 0.5)
		(connect_pads
			(clearance 0)
		)
		(min_thickness 0.25)
		(keepout
			(tracks not_allowed)
			(vias allowed)
			(pads allowed)
			(copperpour not_allowed)
			(footprints allowed)
		)
		(placement
			(enabled no)
			(sheetname "")
		)
		(fill yes
			(thermal_gap 0.5)
			(thermal_bridge_width 0.5)
			(island_removal_mode 0)
		)
		(polygon
			(pts
				(arc
					(start 332.776068 -231.524048)
					(mid 332.146148 -231.524048)
					(end 332.776068 -231.524048)
				)
			)
		)
	)
	(zone
		(layers "B.Cu" "In13.Cu" "In15.Cu")
		(hatch none 0.5)
		(connect_pads
			(clearance 0)
		)
		(min_thickness 0.25)
		(keepout
			(tracks not_allowed)
			(vias allowed)
			(pads allowed)
			(copperpour not_allowed)
			(footprints allowed)
		)
		(placement
			(enabled no)
			(sheetname "")
		)
		(fill yes
			(thermal_gap 0.5)
			(thermal_bridge_width 0.5)
			(island_removal_mode 0)
		)
		(polygon
			(pts
				(arc
					(start 84.3661 -225.854514)
					(mid 83.73618 -225.854514)
					(end 84.3661 -225.854514)
				)
			)
		)
	)
	(zone
		(layers "B.Cu" "In13.Cu" "In15.Cu")
		(hatch none 0.5)
		(connect_pads
			(clearance 0)
		)
		(min_thickness 0.25)
		(keepout
			(tracks not_allowed)
			(vias allowed)
			(pads allowed)
			(copperpour not_allowed)
			(footprints allowed)
		)
		(placement
			(enabled no)
			(sheetname "")
		)
		(fill yes
			(thermal_gap 0.5)
			(thermal_bridge_width 0.5)
			(island_removal_mode 0)
		)
		(polygon
			(pts
				(arc
					(start 22.04212 -199.035416)
					(mid 21.3741 -199.035416)
					(end 22.04212 -199.035416)
				)
			)
		)
	)
	(zone
		(layers "B.Cu" "In13.Cu" "In15.Cu")
		(hatch none 0.5)
		(connect_pads
			(clearance 0)
		)
		(min_thickness 0.25)
		(keepout
			(tracks not_allowed)
			(vias allowed)
			(pads allowed)
			(copperpour not_allowed)
			(footprints allowed)
		)
		(placement
			(enabled no)
			(sheetname "")
		)
		(fill yes
			(thermal_gap 0.5)
			(thermal_bridge_width 0.5)
			(island_removal_mode 0)
		)
		(polygon
			(pts
				(arc
					(start 206.58201 -311.235344)
					(mid 205.91399 -311.235344)
					(end 206.58201 -311.235344)
				)
			)
		)
	)
	(zone
		(layers "B.Cu" "In13.Cu" "In15.Cu")
		(hatch none 0.5)
		(connect_pads
			(clearance 0)
		)
		(min_thickness 0.25)
		(keepout
			(tracks not_allowed)
			(vias allowed)
			(pads allowed)
			(copperpour not_allowed)
			(footprints allowed)
		)
		(placement
			(enabled no)
			(sheetname "")
		)
		(fill yes
			(thermal_gap 0.5)
			(thermal_bridge_width 0.5)
			(island_removal_mode 0)
		)
		(polygon
			(pts
				(arc
					(start 379.225302 -382.34493)
					(mid 378.557282 -382.34493)
					(end 379.225302 -382.34493)
				)
			)
		)
	)
	(zone
		(layers "B.Cu" "In13.Cu" "In15.Cu")
		(hatch none 0.5)
		(connect_pads
			(clearance 0)
		)
		(min_thickness 0.25)
		(keepout
			(tracks not_allowed)
			(vias allowed)
			(pads allowed)
			(copperpour not_allowed)
			(footprints allowed)
		)
		(placement
			(enabled no)
			(sheetname "")
		)
		(fill yes
			(thermal_gap 0.5)
			(thermal_bridge_width 0.5)
			(island_removal_mode 0)
		)
		(polygon
			(pts
				(arc
					(start 104.576118 -246.10441)
					(mid 103.946198 -246.10441)
					(end 104.576118 -246.10441)
				)
			)
		)
	)
	(zone
		(layers "B.Cu" "In13.Cu" "In15.Cu")
		(hatch none 0.5)
		(connect_pads
			(clearance 0)
		)
		(min_thickness 0.25)
		(keepout
			(tracks not_allowed)
			(vias allowed)
			(pads allowed)
			(copperpour not_allowed)
			(footprints allowed)
		)
		(placement
			(enabled no)
			(sheetname "")
		)
		(fill yes
			(thermal_gap 0.5)
			(thermal_bridge_width 0.5)
			(island_removal_mode 0)
		)
		(polygon
			(pts
				(arc
					(start 387.289802 -247.724168)
					(mid 386.659882 -247.724168)
					(end 387.289802 -247.724168)
				)
			)
		)
	)
	(zone
		(layers "B.Cu" "In13.Cu" "In15.Cu")
		(hatch none 0.5)
		(connect_pads
			(clearance 0)
		)
		(min_thickness 0.25)
		(keepout
			(tracks not_allowed)
			(vias allowed)
			(pads allowed)
			(copperpour not_allowed)
			(footprints allowed)
		)
		(placement
			(enabled no)
			(sheetname "")
		)
		(fill yes
			(thermal_gap 0.5)
			(thermal_bridge_width 0.5)
			(island_removal_mode 0)
		)
		(polygon
			(pts
				(arc
					(start 90.634058 -389.467344)
					(mid 90.004138 -389.467344)
					(end 90.634058 -389.467344)
				)
			)
		)
	)
	(zone
		(layers "B.Cu" "In13.Cu" "In15.Cu")
		(hatch none 0.5)
		(connect_pads
			(clearance 0)
		)
		(min_thickness 0.25)
		(keepout
			(tracks not_allowed)
			(vias allowed)
			(pads allowed)
			(copperpour not_allowed)
			(footprints allowed)
		)
		(placement
			(enabled no)
			(sheetname "")
		)
		(fill yes
			(thermal_gap 0.5)
			(thermal_bridge_width 0.5)
			(island_removal_mode 0)
		)
		(polygon
			(pts
				(arc
					(start 17.942052 -310.385206)
					(mid 17.274032 -310.385206)
					(end 17.942052 -310.385206)
				)
			)
		)
	)
	(zone
		(layers "B.Cu" "In13.Cu" "In15.Cu")
		(hatch none 0.5)
		(connect_pads
			(clearance 0)
		)
		(min_thickness 0.25)
		(keepout
			(tracks not_allowed)
			(vias allowed)
			(pads allowed)
			(copperpour not_allowed)
			(footprints allowed)
		)
		(placement
			(enabled no)
			(sheetname "")
		)
		(fill yes
			(thermal_gap 0.5)
			(thermal_bridge_width 0.5)
			(island_removal_mode 0)
		)
		(polygon
			(pts
				(arc
					(start 371.609874 -278.136096)
					(mid 370.979954 -278.136096)
					(end 371.609874 -278.136096)
				)
			)
		)
	)
	(zone
		(layers "B.Cu" "In13.Cu" "In15.Cu")
		(hatch none 0.5)
		(connect_pads
			(clearance 0)
		)
		(min_thickness 0.25)
		(keepout
			(tracks not_allowed)
			(vias allowed)
			(pads allowed)
			(copperpour not_allowed)
			(footprints allowed)
		)
		(placement
			(enabled no)
			(sheetname "")
		)
		(fill yes
			(thermal_gap 0.5)
			(thermal_bridge_width 0.5)
			(island_removal_mode 0)
		)
		(polygon
			(pts
				(arc
					(start 22.04212 -273.835368)
					(mid 21.3741 -273.835368)
					(end 22.04212 -273.835368)
				)
			)
		)
	)
	(zone
		(layers "B.Cu" "In13.Cu" "In15.Cu")
		(hatch none 0.5)
		(connect_pads
			(clearance 0)
		)
		(min_thickness 0.25)
		(keepout
			(tracks not_allowed)
			(vias allowed)
			(pads allowed)
			(copperpour not_allowed)
			(footprints allowed)
		)
		(placement
			(enabled no)
			(sheetname "")
		)
		(fill yes
			(thermal_gap 0.5)
			(thermal_bridge_width 0.5)
			(island_removal_mode 0)
		)
		(polygon
			(pts
				(arc
					(start 269.982188 -300.185074)
					(mid 269.314168 -300.185074)
					(end 269.982188 -300.185074)
				)
			)
		)
	)
	(zone
		(layers "B.Cu" "In13.Cu" "In15.Cu")
		(hatch none 0.5)
		(connect_pads
			(clearance 0)
		)
		(min_thickness 0.25)
		(keepout
			(tracks not_allowed)
			(vias allowed)
			(pads allowed)
			(copperpour not_allowed)
			(footprints allowed)
		)
		(placement
			(enabled no)
			(sheetname "")
		)
		(fill yes
			(thermal_gap 0.5)
			(thermal_bridge_width 0.5)
			(island_removal_mode 0)
		)
		(polygon
			(pts
				(arc
					(start 17.942052 -274.685252)
					(mid 17.274032 -274.685252)
					(end 17.942052 -274.685252)
				)
			)
		)
	)
	(zone
		(layers "B.Cu" "In13.Cu" "In15.Cu")
		(hatch none 0.5)
		(connect_pads
			(clearance 0)
		)
		(min_thickness 0.25)
		(keepout
			(tracks not_allowed)
			(vias allowed)
			(pads allowed)
			(copperpour not_allowed)
			(footprints allowed)
		)
		(placement
			(enabled no)
			(sheetname "")
		)
		(fill yes
			(thermal_gap 0.5)
			(thermal_bridge_width 0.5)
			(island_removal_mode 0)
		)
		(polygon
			(pts
				(arc
					(start 131.407916 -412.570168)
					(mid 130.739896 -412.570168)
					(end 131.407916 -412.570168)
				)
			)
		)
	)
	(zone
		(layers "B.Cu" "In13.Cu" "In15.Cu")
		(hatch none 0.5)
		(connect_pads
			(clearance 0)
		)
		(min_thickness 0.25)
		(keepout
			(tracks not_allowed)
			(vias allowed)
			(pads allowed)
			(copperpour not_allowed)
			(footprints allowed)
		)
		(placement
			(enabled no)
			(sheetname "")
		)
		(fill yes
			(thermal_gap 0.5)
			(thermal_bridge_width 0.5)
			(island_removal_mode 0)
		)
		(polygon
			(pts
				(arc
					(start 162.040316 -412.570168)
					(mid 161.372296 -412.570168)
					(end 162.040316 -412.570168)
				)
			)
		)
	)
	(zone
		(layers "B.Cu" "In13.Cu" "In15.Cu")
		(hatch none 0.5)
		(connect_pads
			(clearance 0)
		)
		(min_thickness 0.25)
		(keepout
			(tracks not_allowed)
			(vias allowed)
			(pads allowed)
			(copperpour not_allowed)
			(footprints allowed)
		)
		(placement
			(enabled no)
			(sheetname "")
		)
		(fill yes
			(thermal_gap 0.5)
			(thermal_bridge_width 0.5)
			(island_removal_mode 0)
		)
		(polygon
			(pts
				(arc
					(start 90.234008 -385.31038)
					(mid 89.604088 -385.31038)
					(end 90.234008 -385.31038)
				)
			)
		)
	)
	(zone
		(layers "B.Cu" "In13.Cu" "In15.Cu")
		(hatch none 0.5)
		(connect_pads
			(clearance 0)
		)
		(min_thickness 0.25)
		(keepout
			(tracks not_allowed)
			(vias allowed)
			(pads allowed)
			(copperpour not_allowed)
			(footprints allowed)
		)
		(placement
			(enabled no)
			(sheetname "")
		)
		(fill yes
			(thermal_gap 0.5)
			(thermal_bridge_width 0.5)
			(island_removal_mode 0)
		)
		(polygon
			(pts
				(arc
					(start 386.179822 -265.986006)
					(mid 385.549902 -265.986006)
					(end 386.179822 -265.986006)
				)
			)
		)
	)
	(zone
		(layers "B.Cu" "In13.Cu" "In15.Cu")
		(hatch none 0.5)
		(connect_pads
			(clearance 0)
		)
		(min_thickness 0.25)
		(keepout
			(tracks not_allowed)
			(vias allowed)
			(pads allowed)
			(copperpour not_allowed)
			(footprints allowed)
		)
		(placement
			(enabled no)
			(sheetname "")
		)
		(fill yes
			(thermal_gap 0.5)
			(thermal_bridge_width 0.5)
			(island_removal_mode 0)
		)
		(polygon
			(pts
				(arc
					(start 85.776054 -247.724422)
					(mid 85.146134 -247.724422)
					(end 85.776054 -247.724422)
				)
			)
		)
	)
	(zone
		(layers "B.Cu" "In13.Cu" "In15.Cu")
		(hatch none 0.5)
		(connect_pads
			(clearance 0)
		)
		(min_thickness 0.25)
		(keepout
			(tracks not_allowed)
			(vias allowed)
			(pads allowed)
			(copperpour not_allowed)
			(footprints allowed)
		)
		(placement
			(enabled no)
			(sheetname "")
		)
		(fill yes
			(thermal_gap 0.5)
			(thermal_bridge_width 0.5)
			(island_removal_mode 0)
		)
		(polygon
			(pts
				(arc
					(start 450.42201 -209.23504)
					(mid 449.75399 -209.23504)
					(end 450.42201 -209.23504)
				)
			)
		)
	)
	(zone
		(layers "B.Cu" "In13.Cu" "In15.Cu")
		(hatch none 0.5)
		(connect_pads
			(clearance 0)
		)
		(min_thickness 0.25)
		(keepout
			(tracks not_allowed)
			(vias allowed)
			(pads allowed)
			(copperpour not_allowed)
			(footprints allowed)
		)
		(placement
			(enabled no)
			(sheetname "")
		)
		(fill yes
			(thermal_gap 0.5)
			(thermal_bridge_width 0.5)
			(island_removal_mode 0)
		)
		(polygon
			(pts
				(arc
					(start 124.89053 -33.386268)
					(mid 124.22251 -33.386268)
					(end 124.89053 -33.386268)
				)
			)
		)
	)
	(zone
		(layers "B.Cu" "In13.Cu" "In15.Cu")
		(hatch none 0.5)
		(connect_pads
			(clearance 0)
		)
		(min_thickness 0.25)
		(keepout
			(tracks not_allowed)
			(vias allowed)
			(pads allowed)
			(copperpour not_allowed)
			(footprints allowed)
		)
		(placement
			(enabled no)
			(sheetname "")
		)
		(fill yes
			(thermal_gap 0.5)
			(thermal_bridge_width 0.5)
			(island_removal_mode 0)
		)
		(polygon
			(pts
				(arc
					(start 269.982188 -281.485086)
					(mid 269.314168 -281.485086)
					(end 269.982188 -281.485086)
				)
			)
		)
	)
	(zone
		(layers "B.Cu" "In13.Cu" "In15.Cu")
		(hatch none 0.5)
		(connect_pads
			(clearance 0)
		)
		(min_thickness 0.25)
		(keepout
			(tracks not_allowed)
			(vias allowed)
			(pads allowed)
			(copperpour not_allowed)
			(footprints allowed)
		)
		(placement
			(enabled no)
			(sheetname "")
		)
		(fill yes
			(thermal_gap 0.5)
			(thermal_bridge_width 0.5)
			(island_removal_mode 0)
		)
		(polygon
			(pts
				(arc
					(start 269.982188 -210.085178)
					(mid 269.314168 -210.085178)
					(end 269.982188 -210.085178)
				)
			)
		)
	)
	(zone
		(layers "B.Cu" "In13.Cu" "In15.Cu")
		(hatch none 0.5)
		(connect_pads
			(clearance 0)
		)
		(min_thickness 0.25)
		(keepout
			(tracks not_allowed)
			(vias allowed)
			(pads allowed)
			(copperpour not_allowed)
			(footprints allowed)
		)
		(placement
			(enabled no)
			(sheetname "")
		)
		(fill yes
			(thermal_gap 0.5)
			(thermal_bridge_width 0.5)
			(island_removal_mode 0)
		)
		(polygon
			(pts
				(arc
					(start 338.687156 -420.952168)
					(mid 338.019136 -420.952168)
					(end 338.687156 -420.952168)
				)
			)
		)
	)
	(zone
		(layers "B.Cu" "In13.Cu" "In15.Cu")
		(hatch none 0.5)
		(connect_pads
			(clearance 0)
		)
		(min_thickness 0.25)
		(keepout
			(tracks not_allowed)
			(vias allowed)
			(pads allowed)
			(copperpour not_allowed)
			(footprints allowed)
		)
		(placement
			(enabled no)
			(sheetname "")
		)
		(fill yes
			(thermal_gap 0.5)
			(thermal_bridge_width 0.5)
			(island_removal_mode 0)
		)
		(polygon
			(pts
				(arc
					(start 202.481942 -305.285394)
					(mid 201.813922 -305.285394)
					(end 202.481942 -305.285394)
				)
			)
		)
	)
	(zone
		(layers "B.Cu" "In13.Cu" "In15.Cu")
		(hatch none 0.5)
		(connect_pads
			(clearance 0)
		)
		(min_thickness 0.25)
		(keepout
			(tracks not_allowed)
			(vias allowed)
			(pads allowed)
			(copperpour not_allowed)
			(footprints allowed)
		)
		(placement
			(enabled no)
			(sheetname "")
		)
		(fill yes
			(thermal_gap 0.5)
			(thermal_bridge_width 0.5)
			(island_removal_mode 0)
		)
		(polygon
			(pts
				(arc
					(start 400.117818 -4.963414)
					(mid 399.449798 -4.963414)
					(end 400.117818 -4.963414)
				)
			)
		)
	)
	(zone
		(layers "B.Cu" "In13.Cu" "In15.Cu")
		(hatch none 0.5)
		(connect_pads
			(clearance 0)
		)
		(min_thickness 0.25)
		(keepout
			(tracks not_allowed)
			(vias allowed)
			(pads allowed)
			(copperpour not_allowed)
			(footprints allowed)
		)
		(placement
			(enabled no)
			(sheetname "")
		)
		(fill yes
			(thermal_gap 0.5)
			(thermal_bridge_width 0.5)
			(island_removal_mode 0)
		)
		(polygon
			(pts
				(arc
					(start 22.04212 -245.785386)
					(mid 21.3741 -245.785386)
					(end 22.04212 -245.785386)
				)
			)
		)
	)
	(zone
		(layers "B.Cu" "In13.Cu" "In15.Cu")
		(hatch none 0.5)
		(connect_pads
			(clearance 0)
		)
		(min_thickness 0.25)
		(keepout
			(tracks not_allowed)
			(vias allowed)
			(pads allowed)
			(copperpour not_allowed)
			(footprints allowed)
		)
		(placement
			(enabled no)
			(sheetname "")
		)
		(fill yes
			(thermal_gap 0.5)
			(thermal_bridge_width 0.5)
			(island_removal_mode 0)
		)
		(polygon
			(pts
				(arc
					(start 122.82678 -32.974788)
					(mid 122.15876 -32.974788)
					(end 122.82678 -32.974788)
				)
			)
		)
	)
	(zone
		(layers "B.Cu" "In13.Cu" "In15.Cu")
		(hatch none 0.5)
		(connect_pads
			(clearance 0)
		)
		(min_thickness 0.25)
		(keepout
			(tracks not_allowed)
			(vias allowed)
			(pads allowed)
			(copperpour not_allowed)
			(footprints allowed)
		)
		(placement
			(enabled no)
			(sheetname "")
		)
		(fill yes
			(thermal_gap 0.5)
			(thermal_bridge_width 0.5)
			(island_removal_mode 0)
		)
		(polygon
			(pts
				(arc
					(start 63.036958 -430.889918)
					(mid 62.262766 -430.889918)
					(end 63.036958 -430.889918)
				)
			)
		)
	)
	(zone
		(layers "B.Cu" "In13.Cu" "In15.Cu")
		(hatch none 0.5)
		(connect_pads
			(clearance 0)
		)
		(min_thickness 0.25)
		(keepout
			(tracks not_allowed)
			(vias allowed)
			(pads allowed)
			(copperpour not_allowed)
			(footprints allowed)
		)
		(placement
			(enabled no)
			(sheetname "")
		)
		(fill yes
			(thermal_gap 0.5)
			(thermal_bridge_width 0.5)
			(island_removal_mode 0)
		)
		(polygon
			(pts
				(arc
					(start 334.186022 -237.19409)
					(mid 333.556102 -237.19409)
					(end 334.186022 -237.19409)
				)
			)
		)
	)
	(zone
		(layers "B.Cu" "In13.Cu" "In15.Cu")
		(hatch none 0.5)
		(connect_pads
			(clearance 0)
		)
		(min_thickness 0.25)
		(keepout
			(tracks not_allowed)
			(vias allowed)
			(pads allowed)
			(copperpour not_allowed)
			(footprints allowed)
		)
		(placement
			(enabled no)
			(sheetname "")
		)
		(fill yes
			(thermal_gap 0.5)
			(thermal_bridge_width 0.5)
			(island_removal_mode 0)
		)
		(polygon
			(pts
				(arc
					(start 341.833708 -394.385292)
					(mid 341.203788 -394.385292)
					(end 341.833708 -394.385292)
				)
			)
		)
	)
	(zone
		(layers "B.Cu" "In13.Cu" "In15.Cu")
		(hatch none 0.5)
		(connect_pads
			(clearance 0)
		)
		(min_thickness 0.25)
		(keepout
			(tracks not_allowed)
			(vias allowed)
			(pads allowed)
			(copperpour not_allowed)
			(footprints allowed)
		)
		(placement
			(enabled no)
			(sheetname "")
		)
		(fill yes
			(thermal_gap 0.5)
			(thermal_bridge_width 0.5)
			(island_removal_mode 0)
		)
		(polygon
			(pts
				(arc
					(start 97.833942 -389.467344)
					(mid 97.204022 -389.467344)
					(end 97.833942 -389.467344)
				)
			)
		)
	)
	(zone
		(layers "B.Cu" "In13.Cu" "In15.Cu")
		(hatch none 0.5)
		(connect_pads
			(clearance 0)
		)
		(min_thickness 0.25)
		(keepout
			(tracks not_allowed)
			(vias allowed)
			(pads allowed)
			(copperpour not_allowed)
			(footprints allowed)
		)
		(placement
			(enabled no)
			(sheetname "")
		)
		(fill yes
			(thermal_gap 0.5)
			(thermal_bridge_width 0.5)
			(island_removal_mode 0)
		)
		(polygon
			(pts
				(arc
					(start 108.864654 -375.96826)
					(mid 108.196634 -375.96826)
					(end 108.864654 -375.96826)
				)
			)
		)
	)
	(zone
		(layers "B.Cu" "In13.Cu" "In15.Cu")
		(hatch none 0.5)
		(connect_pads
			(clearance 0)
		)
		(min_thickness 0.25)
		(keepout
			(tracks not_allowed)
			(vias allowed)
			(pads allowed)
			(copperpour not_allowed)
			(footprints allowed)
		)
		(placement
			(enabled no)
			(sheetname "")
		)
		(fill yes
			(thermal_gap 0.5)
			(thermal_bridge_width 0.5)
			(island_removal_mode 0)
		)
		(polygon
			(pts
				(arc
					(start 140.119608 -274.08632)
					(mid 139.489688 -274.08632)
					(end 140.119608 -274.08632)
				)
			)
		)
	)
	(zone
		(layers "B.Cu" "In13.Cu" "In15.Cu")
		(hatch none 0.5)
		(connect_pads
			(clearance 0)
		)
		(min_thickness 0.25)
		(keepout
			(tracks not_allowed)
			(vias allowed)
			(pads allowed)
			(copperpour not_allowed)
			(footprints allowed)
		)
		(placement
			(enabled no)
			(sheetname "")
		)
		(fill yes
			(thermal_gap 0.5)
			(thermal_bridge_width 0.5)
			(island_removal_mode 0)
		)
		(polygon
			(pts
				(arc
					(start 206.58201 -270.435324)
					(mid 205.91399 -270.435324)
					(end 206.58201 -270.435324)
				)
			)
		)
	)
	(zone
		(layers "B.Cu" "In13.Cu" "In15.Cu")
		(hatch none 0.5)
		(connect_pads
			(clearance 0)
		)
		(min_thickness 0.25)
		(keepout
			(tracks not_allowed)
			(vias allowed)
			(pads allowed)
			(copperpour not_allowed)
			(footprints allowed)
		)
		(placement
			(enabled no)
			(sheetname "")
		)
		(fill yes
			(thermal_gap 0.5)
			(thermal_bridge_width 0.5)
			(island_removal_mode 0)
		)
		(polygon
			(pts
				(arc
					(start 385.168902 -382.34493)
					(mid 384.500882 -382.34493)
					(end 385.168902 -382.34493)
				)
			)
		)
	)
	(zone
		(layers "B.Cu" "In13.Cu" "In15.Cu")
		(hatch none 0.5)
		(connect_pads
			(clearance 0)
		)
		(min_thickness 0.25)
		(keepout
			(tracks not_allowed)
			(vias allowed)
			(pads allowed)
			(copperpour not_allowed)
			(footprints allowed)
		)
		(placement
			(enabled no)
			(sheetname "")
		)
		(fill yes
			(thermal_gap 0.5)
			(thermal_bridge_width 0.5)
			(island_removal_mode 0)
		)
		(polygon
			(pts
				(arc
					(start 52.055014 -412.570168)
					(mid 51.386994 -412.570168)
					(end 52.055014 -412.570168)
				)
			)
		)
	)
	(zone
		(layers "B.Cu" "In13.Cu" "In15.Cu")
		(hatch none 0.5)
		(connect_pads
			(clearance 0)
		)
		(min_thickness 0.25)
		(keepout
			(tracks not_allowed)
			(vias allowed)
			(pads allowed)
			(copperpour not_allowed)
			(footprints allowed)
		)
		(placement
			(enabled no)
			(sheetname "")
		)
		(fill yes
			(thermal_gap 0.5)
			(thermal_bridge_width 0.5)
			(island_removal_mode 0)
		)
		(polygon
			(pts
				(arc
					(start 84.3661 -246.914416)
					(mid 83.73618 -246.914416)
					(end 84.3661 -246.914416)
				)
			)
		)
	)
	(zone
		(layers "B.Cu" "In13.Cu" "In15.Cu")
		(hatch none 0.5)
		(connect_pads
			(clearance 0)
		)
		(min_thickness 0.25)
		(keepout
			(tracks not_allowed)
			(vias allowed)
			(pads allowed)
			(copperpour not_allowed)
			(footprints allowed)
		)
		(placement
			(enabled no)
			(sheetname "")
		)
		(fill yes
			(thermal_gap 0.5)
			(thermal_bridge_width 0.5)
			(island_removal_mode 0)
		)
		(polygon
			(pts
				(arc
					(start 450.42201 -318.035178)
					(mid 449.75399 -318.035178)
					(end 450.42201 -318.035178)
				)
			)
		)
	)
	(zone
		(layers "B.Cu" "In13.Cu" "In15.Cu")
		(hatch none 0.5)
		(connect_pads
			(clearance 0)
		)
		(min_thickness 0.25)
		(keepout
			(tracks not_allowed)
			(vias allowed)
			(pads allowed)
			(copperpour not_allowed)
			(footprints allowed)
		)
		(placement
			(enabled no)
			(sheetname "")
		)
		(fill yes
			(thermal_gap 0.5)
			(thermal_bridge_width 0.5)
			(island_removal_mode 0)
		)
		(polygon
			(pts
				(arc
					(start 386.349748 -236.384084)
					(mid 385.719828 -236.384084)
					(end 386.349748 -236.384084)
				)
			)
		)
	)
	(zone
		(layers "B.Cu" "In13.Cu" "In15.Cu")
		(hatch none 0.5)
		(connect_pads
			(clearance 0)
		)
		(min_thickness 0.25)
		(keepout
			(tracks not_allowed)
			(vias allowed)
			(pads allowed)
			(copperpour not_allowed)
			(footprints allowed)
		)
		(placement
			(enabled no)
			(sheetname "")
		)
		(fill yes
			(thermal_gap 0.5)
			(thermal_bridge_width 0.5)
			(island_removal_mode 0)
		)
		(polygon
			(pts
				(arc
					(start 362.679742 -278.946102)
					(mid 362.049822 -278.946102)
					(end 362.679742 -278.946102)
				)
			)
		)
	)
	(zone
		(layers "B.Cu" "In13.Cu" "In15.Cu")
		(hatch none 0.5)
		(connect_pads
			(clearance 0)
		)
		(min_thickness 0.25)
		(keepout
			(tracks not_allowed)
			(vias allowed)
			(pads allowed)
			(copperpour not_allowed)
			(footprints allowed)
		)
		(placement
			(enabled no)
			(sheetname "")
		)
		(fill yes
			(thermal_gap 0.5)
			(thermal_bridge_width 0.5)
			(island_removal_mode 0)
		)
		(polygon
			(pts
				(arc
					(start 85.776054 -239.624362)
					(mid 85.146134 -239.624362)
					(end 85.776054 -239.624362)
				)
			)
		)
	)
	(zone
		(layers "B.Cu" "In13.Cu" "In15.Cu")
		(hatch none 0.5)
		(connect_pads
			(clearance 0)
		)
		(min_thickness 0.25)
		(keepout
			(tracks not_allowed)
			(vias allowed)
			(pads allowed)
			(copperpour not_allowed)
			(footprints allowed)
		)
		(placement
			(enabled no)
			(sheetname "")
		)
		(fill yes
			(thermal_gap 0.5)
			(thermal_bridge_width 0.5)
			(island_removal_mode 0)
		)
		(polygon
			(pts
				(arc
					(start 387.759702 -235.574078)
					(mid 387.129782 -235.574078)
					(end 387.759702 -235.574078)
				)
			)
		)
	)
	(zone
		(layers "B.Cu" "In13.Cu" "In15.Cu")
		(hatch none 0.5)
		(connect_pads
			(clearance 0)
		)
		(min_thickness 0.25)
		(keepout
			(tracks not_allowed)
			(vias allowed)
			(pads allowed)
			(copperpour not_allowed)
			(footprints allowed)
		)
		(placement
			(enabled no)
			(sheetname "")
		)
		(fill yes
			(thermal_gap 0.5)
			(thermal_bridge_width 0.5)
			(island_removal_mode 0)
		)
		(polygon
			(pts
				(arc
					(start 387.289802 -234.764072)
					(mid 386.659882 -234.764072)
					(end 387.289802 -234.764072)
				)
			)
		)
	)
	(zone
		(layers "B.Cu" "In13.Cu" "In15.Cu")
		(hatch none 0.5)
		(connect_pads
			(clearance 0)
		)
		(min_thickness 0.25)
		(keepout
			(tracks not_allowed)
			(vias allowed)
			(pads allowed)
			(copperpour not_allowed)
			(footprints allowed)
		)
		(placement
			(enabled no)
			(sheetname "")
		)
		(fill yes
			(thermal_gap 0.5)
			(thermal_bridge_width 0.5)
			(island_removal_mode 0)
		)
		(polygon
			(pts
				(arc
					(start 334.016096 -271.656048)
					(mid 333.386176 -271.656048)
					(end 334.016096 -271.656048)
				)
			)
		)
	)
	(zone
		(layers "B.Cu" "In13.Cu" "In15.Cu")
		(hatch none 0.5)
		(connect_pads
			(clearance 0)
		)
		(min_thickness 0.25)
		(keepout
			(tracks not_allowed)
			(vias allowed)
			(pads allowed)
			(copperpour not_allowed)
			(footprints allowed)
		)
		(placement
			(enabled no)
			(sheetname "")
		)
		(fill yes
			(thermal_gap 0.5)
			(thermal_bridge_width 0.5)
			(island_removal_mode 0)
		)
		(polygon
			(pts
				(arc
					(start 344.233754 -394.385292)
					(mid 343.603834 -394.385292)
					(end 344.233754 -394.385292)
				)
			)
		)
	)
	(zone
		(layers "B.Cu" "In13.Cu" "In15.Cu")
		(hatch none 0.5)
		(connect_pads
			(clearance 0)
		)
		(min_thickness 0.25)
		(keepout
			(tracks not_allowed)
			(vias allowed)
			(pads allowed)
			(copperpour not_allowed)
			(footprints allowed)
		)
		(placement
			(enabled no)
			(sheetname "")
		)
		(fill yes
			(thermal_gap 0.5)
			(thermal_bridge_width 0.5)
			(island_removal_mode 0)
		)
		(polygon
			(pts
				(arc
					(start 22.04212 -294.235378)
					(mid 21.3741 -294.235378)
					(end 22.04212 -294.235378)
				)
			)
		)
	)
	(zone
		(layers "B.Cu" "In13.Cu" "In15.Cu")
		(hatch none 0.5)
		(connect_pads
			(clearance 0)
		)
		(min_thickness 0.25)
		(keepout
			(tracks not_allowed)
			(vias allowed)
			(pads allowed)
			(copperpour not_allowed)
			(footprints allowed)
		)
		(placement
			(enabled no)
			(sheetname "")
		)
		(fill yes
			(thermal_gap 0.5)
			(thermal_bridge_width 0.5)
			(island_removal_mode 0)
		)
		(polygon
			(pts
				(arc
					(start 138.239754 -265.98626)
					(mid 137.609834 -265.98626)
					(end 138.239754 -265.98626)
				)
			)
		)
	)
	(zone
		(layers "B.Cu" "In13.Cu" "In15.Cu")
		(hatch none 0.5)
		(connect_pads
			(clearance 0)
		)
		(min_thickness 0.25)
		(keepout
			(tracks not_allowed)
			(vias allowed)
			(pads allowed)
			(copperpour not_allowed)
			(footprints allowed)
		)
		(placement
			(enabled no)
			(sheetname "")
		)
		(fill yes
			(thermal_gap 0.5)
			(thermal_bridge_width 0.5)
			(island_removal_mode 0)
		)
		(polygon
			(pts
				(arc
					(start 386.649722 -276.516084)
					(mid 386.019802 -276.516084)
					(end 386.649722 -276.516084)
				)
			)
		)
	)
	(zone
		(layers "B.Cu" "In13.Cu" "In15.Cu")
		(hatch none 0.5)
		(connect_pads
			(clearance 0)
		)
		(min_thickness 0.25)
		(keepout
			(tracks not_allowed)
			(vias allowed)
			(pads allowed)
			(copperpour not_allowed)
			(footprints allowed)
		)
		(placement
			(enabled no)
			(sheetname "")
		)
		(fill yes
			(thermal_gap 0.5)
			(thermal_bridge_width 0.5)
			(island_removal_mode 0)
		)
		(polygon
			(pts
				(arc
					(start 130.032506 -373.96293)
					(mid 129.364486 -373.96293)
					(end 130.032506 -373.96293)
				)
			)
		)
	)
	(zone
		(layers "B.Cu" "In13.Cu" "In15.Cu")
		(hatch none 0.5)
		(connect_pads
			(clearance 0)
		)
		(min_thickness 0.25)
		(keepout
			(tracks not_allowed)
			(vias allowed)
			(pads allowed)
			(copperpour not_allowed)
			(footprints allowed)
		)
		(placement
			(enabled no)
			(sheetname "")
		)
		(fill yes
			(thermal_gap 0.5)
			(thermal_bridge_width 0.5)
			(island_removal_mode 0)
		)
		(polygon
			(pts
				(arc
					(start 265.88212 -306.985162)
					(mid 265.2141 -306.985162)
					(end 265.88212 -306.985162)
				)
			)
		)
	)
	(zone
		(layers "B.Cu" "In13.Cu" "In15.Cu")
		(hatch none 0.5)
		(connect_pads
			(clearance 0)
		)
		(min_thickness 0.25)
		(keepout
			(tracks not_allowed)
			(vias allowed)
			(pads allowed)
			(copperpour not_allowed)
			(footprints allowed)
		)
		(placement
			(enabled no)
			(sheetname "")
		)
		(fill yes
			(thermal_gap 0.5)
			(thermal_bridge_width 0.5)
			(island_removal_mode 0)
		)
		(polygon
			(pts
				(arc
					(start 329.03668 -430.689766)
					(mid 328.262488 -430.689766)
					(end 329.03668 -430.689766)
				)
			)
		)
	)
	(zone
		(layers "B.Cu" "In13.Cu" "In15.Cu")
		(hatch none 0.5)
		(connect_pads
			(clearance 0)
		)
		(min_thickness 0.25)
		(keepout
			(tracks not_allowed)
			(vias allowed)
			(pads allowed)
			(copperpour not_allowed)
			(footprints allowed)
		)
		(placement
			(enabled no)
			(sheetname "")
		)
		(fill yes
			(thermal_gap 0.5)
			(thermal_bridge_width 0.5)
			(island_removal_mode 0)
		)
		(polygon
			(pts
				(arc
					(start 84.666074 -267.606272)
					(mid 84.036154 -267.606272)
					(end 84.666074 -267.606272)
				)
			)
		)
	)
	(zone
		(layers "B.Cu" "In13.Cu" "In15.Cu")
		(hatch none 0.5)
		(connect_pads
			(clearance 0)
		)
		(min_thickness 0.25)
		(keepout
			(tracks not_allowed)
			(vias allowed)
			(pads allowed)
			(copperpour not_allowed)
			(footprints allowed)
		)
		(placement
			(enabled no)
			(sheetname "")
		)
		(fill yes
			(thermal_gap 0.5)
			(thermal_bridge_width 0.5)
			(island_removal_mode 0)
		)
		(polygon
			(pts
				(arc
					(start 334.485996 -285.42615)
					(mid 333.856076 -285.42615)
					(end 334.485996 -285.42615)
				)
			)
		)
	)
	(zone
		(layers "B.Cu" "In13.Cu" "In15.Cu")
		(hatch none 0.5)
		(connect_pads
			(clearance 0)
		)
		(min_thickness 0.25)
		(keepout
			(tracks not_allowed)
			(vias allowed)
			(pads allowed)
			(copperpour not_allowed)
			(footprints allowed)
		)
		(placement
			(enabled no)
			(sheetname "")
		)
		(fill yes
			(thermal_gap 0.5)
			(thermal_bridge_width 0.5)
			(island_removal_mode 0)
		)
		(polygon
			(pts
				(arc
					(start 206.58201 -197.335394)
					(mid 205.91399 -197.335394)
					(end 206.58201 -197.335394)
				)
			)
		)
	)
	(zone
		(layers "B.Cu" "In13.Cu" "In15.Cu")
		(hatch none 0.5)
		(connect_pads
			(clearance 0)
		)
		(min_thickness 0.25)
		(keepout
			(tracks not_allowed)
			(vias allowed)
			(pads allowed)
			(copperpour not_allowed)
			(footprints allowed)
		)
		(placement
			(enabled no)
			(sheetname "")
		)
		(fill yes
			(thermal_gap 0.5)
			(thermal_bridge_width 0.5)
			(island_removal_mode 0)
		)
		(polygon
			(pts
				(arc
					(start 454.522078 -295.085008)
					(mid 453.854058 -295.085008)
					(end 454.522078 -295.085008)
				)
			)
		)
	)
	(zone
		(layers "B.Cu" "In13.Cu" "In15.Cu")
		(hatch none 0.5)
		(connect_pads
			(clearance 0)
		)
		(min_thickness 0.25)
		(keepout
			(tracks not_allowed)
			(vias allowed)
			(pads allowed)
			(copperpour not_allowed)
			(footprints allowed)
		)
		(placement
			(enabled no)
			(sheetname "")
		)
		(fill yes
			(thermal_gap 0.5)
			(thermal_bridge_width 0.5)
			(island_removal_mode 0)
		)
		(polygon
			(pts
				(arc
					(start 86.037166 -431.889916)
					(mid 85.262974 -431.889916)
					(end 86.037166 -431.889916)
				)
			)
		)
	)
	(zone
		(layers "B.Cu" "In13.Cu" "In15.Cu")
		(hatch none 0.5)
		(connect_pads
			(clearance 0)
		)
		(min_thickness 0.25)
		(keepout
			(tracks not_allowed)
			(vias allowed)
			(pads allowed)
			(copperpour not_allowed)
			(footprints allowed)
		)
		(placement
			(enabled no)
			(sheetname "")
		)
		(fill yes
			(thermal_gap 0.5)
			(thermal_bridge_width 0.5)
			(island_removal_mode 0)
		)
		(polygon
			(pts
				(arc
					(start 388.136892 -430.689766)
					(mid 387.3627 -430.689766)
					(end 388.136892 -430.689766)
				)
			)
		)
	)
	(zone
		(layers "B.Cu" "In13.Cu" "In15.Cu")
		(hatch none 0.5)
		(connect_pads
			(clearance 0)
		)
		(min_thickness 0.25)
		(keepout
			(tracks not_allowed)
			(vias allowed)
			(pads allowed)
			(copperpour not_allowed)
			(footprints allowed)
		)
		(placement
			(enabled no)
			(sheetname "")
		)
		(fill yes
			(thermal_gap 0.5)
			(thermal_bridge_width 0.5)
			(island_removal_mode 0)
		)
		(polygon
			(pts
				(arc
					(start 206.58201 -216.035382)
					(mid 205.91399 -216.035382)
					(end 206.58201 -216.035382)
				)
			)
		)
	)
	(zone
		(layers "B.Cu" "In13.Cu" "In15.Cu")
		(hatch none 0.5)
		(connect_pads
			(clearance 0)
		)
		(min_thickness 0.25)
		(keepout
			(tracks not_allowed)
			(vias allowed)
			(pads allowed)
			(copperpour not_allowed)
			(footprints allowed)
		)
		(placement
			(enabled no)
			(sheetname "")
		)
		(fill yes
			(thermal_gap 0.5)
			(thermal_bridge_width 0.5)
			(island_removal_mode 0)
		)
		(polygon
			(pts
				(arc
					(start 333.716122 -228.284278)
					(mid 333.086202 -228.284278)
					(end 333.716122 -228.284278)
				)
			)
		)
	)
	(zone
		(layers "B.Cu" "In13.Cu" "In15.Cu")
		(hatch none 0.5)
		(connect_pads
			(clearance 0)
		)
		(min_thickness 0.25)
		(keepout
			(tracks not_allowed)
			(vias allowed)
			(pads allowed)
			(copperpour not_allowed)
			(footprints allowed)
		)
		(placement
			(enabled no)
			(sheetname "")
		)
		(fill yes
			(thermal_gap 0.5)
			(thermal_bridge_width 0.5)
			(island_removal_mode 0)
		)
		(polygon
			(pts
				(arc
					(start 385.879848 -248.534174)
					(mid 385.249928 -248.534174)
					(end 385.879848 -248.534174)
				)
			)
		)
	)
	(zone
		(layers "B.Cu" "In13.Cu" "In15.Cu")
		(hatch none 0.5)
		(connect_pads
			(clearance 0)
		)
		(min_thickness 0.25)
		(keepout
			(tracks not_allowed)
			(vias allowed)
			(pads allowed)
			(copperpour not_allowed)
			(footprints allowed)
		)
		(placement
			(enabled no)
			(sheetname "")
		)
		(fill yes
			(thermal_gap 0.5)
			(thermal_bridge_width 0.5)
			(island_removal_mode 0)
		)
		(polygon
			(pts
				(arc
					(start 138.709654 -266.796266)
					(mid 138.079734 -266.796266)
					(end 138.709654 -266.796266)
				)
			)
		)
	)
	(zone
		(layers "B.Cu" "In13.Cu" "In15.Cu")
		(hatch none 0.5)
		(connect_pads
			(clearance 0)
		)
		(min_thickness 0.25)
		(keepout
			(tracks not_allowed)
			(vias allowed)
			(pads allowed)
			(copperpour not_allowed)
			(footprints allowed)
		)
		(placement
			(enabled no)
			(sheetname "")
		)
		(fill yes
			(thermal_gap 0.5)
			(thermal_bridge_width 0.5)
			(island_removal_mode 0)
		)
		(polygon
			(pts
				(arc
					(start 202.481942 -205.83525)
					(mid 201.813922 -205.83525)
					(end 202.481942 -205.83525)
				)
			)
		)
	)
	(zone
		(layers "B.Cu" "In13.Cu" "In15.Cu")
		(hatch none 0.5)
		(connect_pads
			(clearance 0)
		)
		(min_thickness 0.25)
		(keepout
			(tracks not_allowed)
			(vias allowed)
			(pads allowed)
			(copperpour not_allowed)
			(footprints allowed)
		)
		(placement
			(enabled no)
			(sheetname "")
		)
		(fill yes
			(thermal_gap 0.5)
			(thermal_bridge_width 0.5)
			(island_removal_mode 0)
		)
		(polygon
			(pts
				(arc
					(start 346.236036 -276.516084)
					(mid 345.606116 -276.516084)
					(end 346.236036 -276.516084)
				)
			)
		)
	)
	(zone
		(layers "B.Cu" "In13.Cu" "In15.Cu")
		(hatch none 0.5)
		(connect_pads
			(clearance 0)
		)
		(min_thickness 0.25)
		(keepout
			(tracks not_allowed)
			(vias allowed)
			(pads allowed)
			(copperpour not_allowed)
			(footprints allowed)
		)
		(placement
			(enabled no)
			(sheetname "")
		)
		(fill yes
			(thermal_gap 0.5)
			(thermal_bridge_width 0.5)
			(island_removal_mode 0)
		)
		(polygon
			(pts
				(arc
					(start 69.570854 -412.570168)
					(mid 68.902834 -412.570168)
					(end 69.570854 -412.570168)
				)
			)
		)
	)
	(zone
		(layers "B.Cu" "In13.Cu" "In15.Cu")
		(hatch none 0.5)
		(connect_pads
			(clearance 0)
		)
		(min_thickness 0.25)
		(keepout
			(tracks not_allowed)
			(vias allowed)
			(pads allowed)
			(copperpour not_allowed)
			(footprints allowed)
		)
		(placement
			(enabled no)
			(sheetname "")
		)
		(fill yes
			(thermal_gap 0.5)
			(thermal_bridge_width 0.5)
			(island_removal_mode 0)
		)
		(polygon
			(pts
				(arc
					(start 122.729752 -278.13635)
					(mid 122.099832 -278.13635)
					(end 122.729752 -278.13635)
				)
			)
		)
	)
	(zone
		(layers "B.Cu" "In13.Cu" "In15.Cu")
		(hatch none 0.5)
		(connect_pads
			(clearance 0)
		)
		(min_thickness 0.25)
		(keepout
			(tracks not_allowed)
			(vias allowed)
			(pads allowed)
			(copperpour not_allowed)
			(footprints allowed)
		)
		(placement
			(enabled no)
			(sheetname "")
		)
		(fill yes
			(thermal_gap 0.5)
			(thermal_bridge_width 0.5)
			(island_removal_mode 0)
		)
		(polygon
			(pts
				(arc
					(start 334.016096 -287.856168)
					(mid 333.386176 -287.856168)
					(end 334.016096 -287.856168)
				)
			)
		)
	)
	(zone
		(layers "B.Cu" "In13.Cu" "In15.Cu")
		(hatch none 0.5)
		(connect_pads
			(clearance 0)
		)
		(min_thickness 0.25)
		(keepout
			(tracks not_allowed)
			(vias allowed)
			(pads allowed)
			(copperpour not_allowed)
			(footprints allowed)
		)
		(placement
			(enabled no)
			(sheetname "")
		)
		(fill yes
			(thermal_gap 0.5)
			(thermal_bridge_width 0.5)
			(island_removal_mode 0)
		)
		(polygon
			(pts
				(arc
					(start 138.40968 -233.144314)
					(mid 137.77976 -233.144314)
					(end 138.40968 -233.144314)
				)
			)
		)
	)
	(zone
		(layers "B.Cu" "In13.Cu" "In15.Cu")
		(hatch none 0.5)
		(connect_pads
			(clearance 0)
		)
		(min_thickness 0.25)
		(keepout
			(tracks not_allowed)
			(vias allowed)
			(pads allowed)
			(copperpour not_allowed)
			(footprints allowed)
		)
		(placement
			(enabled no)
			(sheetname "")
		)
		(fill yes
			(thermal_gap 0.5)
			(thermal_bridge_width 0.5)
			(island_removal_mode 0)
		)
		(polygon
			(pts
				(arc
					(start 142.797276 -412.570168)
					(mid 142.129256 -412.570168)
					(end 142.797276 -412.570168)
				)
			)
		)
	)
	(zone
		(layers "B.Cu" "In13.Cu" "In15.Cu")
		(hatch none 0.5)
		(connect_pads
			(clearance 0)
		)
		(min_thickness 0.25)
		(keepout
			(tracks not_allowed)
			(vias allowed)
			(pads allowed)
			(copperpour not_allowed)
			(footprints allowed)
		)
		(placement
			(enabled no)
			(sheetname "")
		)
		(fill yes
			(thermal_gap 0.5)
			(thermal_bridge_width 0.5)
			(island_removal_mode 0)
		)
		(polygon
			(pts
				(arc
					(start 126.489714 -274.896326)
					(mid 125.859794 -274.896326)
					(end 126.489714 -274.896326)
				)
			)
		)
	)
	(zone
		(layers "B.Cu" "In13.Cu" "In15.Cu")
		(hatch none 0.5)
		(connect_pads
			(clearance 0)
		)
		(min_thickness 0.25)
		(keepout
			(tracks not_allowed)
			(vias allowed)
			(pads allowed)
			(copperpour not_allowed)
			(footprints allowed)
		)
		(placement
			(enabled no)
			(sheetname "")
		)
		(fill yes
			(thermal_gap 0.5)
			(thermal_bridge_width 0.5)
			(island_removal_mode 0)
		)
		(polygon
			(pts
				(arc
					(start 82.037174 -430.689766)
					(mid 81.262982 -430.689766)
					(end 82.037174 -430.689766)
				)
			)
		)
	)
	(zone
		(layers "B.Cu" "In13.Cu" "In15.Cu")
		(hatch none 0.5)
		(connect_pads
			(clearance 0)
		)
		(min_thickness 0.25)
		(keepout
			(tracks not_allowed)
			(vias allowed)
			(pads allowed)
			(copperpour not_allowed)
			(footprints allowed)
		)
		(placement
			(enabled no)
			(sheetname "")
		)
		(fill yes
			(thermal_gap 0.5)
			(thermal_bridge_width 0.5)
			(island_removal_mode 0)
		)
		(polygon
			(pts
				(arc
					(start 386.349748 -242.864132)
					(mid 385.719828 -242.864132)
					(end 386.349748 -242.864132)
				)
			)
		)
	)
	(zone
		(layers "B.Cu" "In13.Cu" "In15.Cu")
		(hatch none 0.5)
		(connect_pads
			(clearance 0)
		)
		(min_thickness 0.25)
		(keepout
			(tracks not_allowed)
			(vias allowed)
			(pads allowed)
			(copperpour not_allowed)
			(footprints allowed)
		)
		(placement
			(enabled no)
			(sheetname "")
		)
		(fill yes
			(thermal_gap 0.5)
			(thermal_bridge_width 0.5)
			(island_removal_mode 0)
		)
		(polygon
			(pts
				(arc
					(start 138.40968 -226.66452)
					(mid 137.77976 -226.66452)
					(end 138.40968 -226.66452)
				)
			)
		)
	)
	(zone
		(layers "B.Cu" "In13.Cu" "In15.Cu")
		(hatch none 0.5)
		(connect_pads
			(clearance 0)
		)
		(min_thickness 0.25)
		(keepout
			(tracks not_allowed)
			(vias allowed)
			(pads allowed)
			(copperpour not_allowed)
			(footprints allowed)
		)
		(placement
			(enabled no)
			(sheetname "")
		)
		(fill yes
			(thermal_gap 0.5)
			(thermal_bridge_width 0.5)
			(island_removal_mode 0)
		)
		(polygon
			(pts
				(arc
					(start 265.88212 -253.435104)
					(mid 265.2141 -253.435104)
					(end 265.88212 -253.435104)
				)
			)
		)
	)
	(zone
		(layers "B.Cu" "In13.Cu" "In15.Cu")
		(hatch none 0.5)
		(connect_pads
			(clearance 0)
		)
		(min_thickness 0.25)
		(keepout
			(tracks not_allowed)
			(vias allowed)
			(pads allowed)
			(copperpour not_allowed)
			(footprints allowed)
		)
		(placement
			(enabled no)
			(sheetname "")
		)
		(fill yes
			(thermal_gap 0.5)
			(thermal_bridge_width 0.5)
			(island_removal_mode 0)
		)
		(polygon
			(pts
				(arc
					(start 386.349748 -244.484144)
					(mid 385.719828 -244.484144)
					(end 386.349748 -244.484144)
				)
			)
		)
	)
	(zone
		(layers "B.Cu" "In13.Cu" "In15.Cu")
		(hatch none 0.5)
		(connect_pads
			(clearance 0)
		)
		(min_thickness 0.25)
		(keepout
			(tracks not_allowed)
			(vias allowed)
			(pads allowed)
			(copperpour not_allowed)
			(footprints allowed)
		)
		(placement
			(enabled no)
			(sheetname "")
		)
		(fill yes
			(thermal_gap 0.5)
			(thermal_bridge_width 0.5)
			(island_removal_mode 0)
		)
		(polygon
			(pts
				(arc
					(start 450.42201 -244.934994)
					(mid 449.75399 -244.934994)
					(end 450.42201 -244.934994)
				)
			)
		)
	)
	(zone
		(layers "B.Cu" "In13.Cu" "In15.Cu")
		(hatch none 0.5)
		(connect_pads
			(clearance 0)
		)
		(min_thickness 0.25)
		(keepout
			(tracks not_allowed)
			(vias allowed)
			(pads allowed)
			(copperpour not_allowed)
			(footprints allowed)
		)
		(placement
			(enabled no)
			(sheetname "")
		)
		(fill yes
			(thermal_gap 0.5)
			(thermal_bridge_width 0.5)
			(island_removal_mode 0)
		)
		(polygon
			(pts
				(arc
					(start 384.1369 -430.689766)
					(mid 383.362708 -430.689766)
					(end 384.1369 -430.689766)
				)
			)
		)
	)
	(zone
		(layers "B.Cu" "In13.Cu" "In15.Cu")
		(hatch none 0.5)
		(connect_pads
			(clearance 0)
		)
		(min_thickness 0.25)
		(keepout
			(tracks not_allowed)
			(vias allowed)
			(pads allowed)
			(copperpour not_allowed)
			(footprints allowed)
		)
		(placement
			(enabled no)
			(sheetname "")
		)
		(fill yes
			(thermal_gap 0.5)
			(thermal_bridge_width 0.5)
			(island_removal_mode 0)
		)
		(polygon
			(pts
				(arc
					(start 96.233996 -385.31038)
					(mid 95.604076 -385.31038)
					(end 96.233996 -385.31038)
				)
			)
		)
	)
	(zone
		(layers "B.Cu" "In13.Cu" "In15.Cu")
		(hatch none 0.5)
		(connect_pads
			(clearance 0)
		)
		(min_thickness 0.25)
		(keepout
			(tracks not_allowed)
			(vias allowed)
			(pads allowed)
			(copperpour not_allowed)
			(footprints allowed)
		)
		(placement
			(enabled no)
			(sheetname "")
		)
		(fill yes
			(thermal_gap 0.5)
			(thermal_bridge_width 0.5)
			(island_removal_mode 0)
		)
		(polygon
			(pts
				(arc
					(start 265.88212 -263.634982)
					(mid 265.2141 -263.634982)
					(end 265.88212 -263.634982)
				)
			)
		)
	)
	(zone
		(layers "B.Cu" "In13.Cu" "In15.Cu")
		(hatch none 0.5)
		(connect_pads
			(clearance 0)
		)
		(min_thickness 0.25)
		(keepout
			(tracks not_allowed)
			(vias allowed)
			(pads allowed)
			(copperpour not_allowed)
			(footprints allowed)
		)
		(placement
			(enabled no)
			(sheetname "")
		)
		(fill yes
			(thermal_gap 0.5)
			(thermal_bridge_width 0.5)
			(island_removal_mode 0)
		)
		(polygon
			(pts
				(arc
					(start 95.433896 -389.467344)
					(mid 94.803976 -389.467344)
					(end 95.433896 -389.467344)
				)
			)
		)
	)
	(zone
		(layers "B.Cu" "In13.Cu" "In15.Cu")
		(hatch none 0.5)
		(connect_pads
			(clearance 0)
		)
		(min_thickness 0.25)
		(keepout
			(tracks not_allowed)
			(vias allowed)
			(pads allowed)
			(copperpour not_allowed)
			(footprints allowed)
		)
		(placement
			(enabled no)
			(sheetname "")
		)
		(fill yes
			(thermal_gap 0.5)
			(thermal_bridge_width 0.5)
			(island_removal_mode 0)
		)
		(polygon
			(pts
				(arc
					(start 454.522078 -275.535136)
					(mid 453.854058 -275.535136)
					(end 454.522078 -275.535136)
				)
			)
		)
	)
	(zone
		(layers "B.Cu" "In13.Cu" "In15.Cu")
		(hatch none 0.5)
		(connect_pads
			(clearance 0)
		)
		(min_thickness 0.25)
		(keepout
			(tracks not_allowed)
			(vias allowed)
			(pads allowed)
			(copperpour not_allowed)
			(footprints allowed)
		)
		(placement
			(enabled no)
			(sheetname "")
		)
		(fill yes
			(thermal_gap 0.5)
			(thermal_bridge_width 0.5)
			(island_removal_mode 0)
		)
		(polygon
			(pts
				(arc
					(start 454.522078 -250.884944)
					(mid 453.854058 -250.884944)
					(end 454.522078 -250.884944)
				)
			)
		)
	)
	(zone
		(layers "B.Cu" "In13.Cu" "In15.Cu")
		(hatch none 0.5)
		(connect_pads
			(clearance 0)
		)
		(min_thickness 0.25)
		(keepout
			(tracks not_allowed)
			(vias allowed)
			(pads allowed)
			(copperpour not_allowed)
			(footprints allowed)
		)
		(placement
			(enabled no)
			(sheetname "")
		)
		(fill yes
			(thermal_gap 0.5)
			(thermal_bridge_width 0.5)
			(island_removal_mode 0)
		)
		(polygon
			(pts
				(arc
					(start 386.649722 -279.756108)
					(mid 386.019802 -279.756108)
					(end 386.649722 -279.756108)
				)
			)
		)
	)
	(zone
		(layers "B.Cu" "In13.Cu" "In15.Cu")
		(hatch none 0.5)
		(connect_pads
			(clearance 0)
		)
		(min_thickness 0.25)
		(keepout
			(tracks not_allowed)
			(vias allowed)
			(pads allowed)
			(copperpour not_allowed)
			(footprints allowed)
		)
		(placement
			(enabled no)
			(sheetname "")
		)
		(fill yes
			(thermal_gap 0.5)
			(thermal_bridge_width 0.5)
			(island_removal_mode 0)
		)
		(polygon
			(pts
				(arc
					(start 386.136896 -429.689768)
					(mid 385.362704 -429.689768)
					(end 386.136896 -429.689768)
				)
			)
		)
	)
	(zone
		(layers "B.Cu" "In13.Cu" "In15.Cu")
		(hatch none 0.5)
		(connect_pads
			(clearance 0)
		)
		(min_thickness 0.25)
		(keepout
			(tracks not_allowed)
			(vias allowed)
			(pads allowed)
			(copperpour not_allowed)
			(footprints allowed)
		)
		(placement
			(enabled no)
			(sheetname "")
		)
		(fill yes
			(thermal_gap 0.5)
			(thermal_bridge_width 0.5)
			(island_removal_mode 0)
		)
		(polygon
			(pts
				(arc
					(start 450.42201 -204.134974)
					(mid 449.75399 -204.134974)
					(end 450.42201 -204.134974)
				)
			)
		)
	)
	(zone
		(layers "B.Cu" "In13.Cu" "In15.Cu")
		(hatch none 0.5)
		(connect_pads
			(clearance 0)
		)
		(min_thickness 0.25)
		(keepout
			(tracks not_allowed)
			(vias allowed)
			(pads allowed)
			(copperpour not_allowed)
			(footprints allowed)
		)
		(placement
			(enabled no)
			(sheetname "")
		)
		(fill yes
			(thermal_gap 0.5)
			(thermal_bridge_width 0.5)
			(island_removal_mode 0)
		)
		(polygon
			(pts
				(arc
					(start 139.649708 -270.03629)
					(mid 139.019788 -270.03629)
					(end 139.649708 -270.03629)
				)
			)
		)
	)
	(zone
		(layers "B.Cu" "In13.Cu" "In15.Cu")
		(hatch none 0.5)
		(connect_pads
			(clearance 0)
		)
		(min_thickness 0.25)
		(keepout
			(tracks not_allowed)
			(vias allowed)
			(pads allowed)
			(copperpour not_allowed)
			(footprints allowed)
		)
		(placement
			(enabled no)
			(sheetname "")
		)
		(fill yes
			(thermal_gap 0.5)
			(thermal_bridge_width 0.5)
			(island_removal_mode 0)
		)
		(polygon
			(pts
				(arc
					(start 206.58201 -212.635338)
					(mid 205.91399 -212.635338)
					(end 206.58201 -212.635338)
				)
			)
		)
	)
	(zone
		(layers "B.Cu" "In13.Cu" "In15.Cu")
		(hatch none 0.5)
		(connect_pads
			(clearance 0)
		)
		(min_thickness 0.25)
		(keepout
			(tracks not_allowed)
			(vias allowed)
			(pads allowed)
			(copperpour not_allowed)
			(footprints allowed)
		)
		(placement
			(enabled no)
			(sheetname "")
		)
		(fill yes
			(thermal_gap 0.5)
			(thermal_bridge_width 0.5)
			(island_removal_mode 0)
		)
		(polygon
			(pts
				(arc
					(start 265.88212 -267.035026)
					(mid 265.2141 -267.035026)
					(end 265.88212 -267.035026)
				)
			)
		)
	)
	(zone
		(layers "B.Cu" "In13.Cu" "In15.Cu")
		(hatch none 0.5)
		(connect_pads
			(clearance 0)
		)
		(min_thickness 0.25)
		(keepout
			(tracks not_allowed)
			(vias allowed)
			(pads allowed)
			(copperpour not_allowed)
			(footprints allowed)
		)
		(placement
			(enabled no)
			(sheetname "")
		)
		(fill yes
			(thermal_gap 0.5)
			(thermal_bridge_width 0.5)
			(island_removal_mode 0)
		)
		(polygon
			(pts
				(arc
					(start 71.036942 -429.689768)
					(mid 70.26275 -429.689768)
					(end 71.036942 -429.689768)
				)
			)
		)
	)
	(zone
		(layers "B.Cu" "In13.Cu" "In15.Cu")
		(hatch none 0.5)
		(connect_pads
			(clearance 0)
		)
		(min_thickness 0.25)
		(keepout
			(tracks not_allowed)
			(vias allowed)
			(pads allowed)
			(copperpour not_allowed)
			(footprints allowed)
		)
		(placement
			(enabled no)
			(sheetname "")
		)
		(fill yes
			(thermal_gap 0.5)
			(thermal_bridge_width 0.5)
			(island_removal_mode 0)
		)
		(polygon
			(pts
				(arc
					(start 454.522078 -225.385122)
					(mid 453.854058 -225.385122)
					(end 454.522078 -225.385122)
				)
			)
		)
	)
	(zone
		(layers "B.Cu" "In13.Cu" "In15.Cu")
		(hatch none 0.5)
		(connect_pads
			(clearance 0)
		)
		(min_thickness 0.25)
		(keepout
			(tracks not_allowed)
			(vias allowed)
			(pads allowed)
			(copperpour not_allowed)
			(footprints allowed)
		)
		(placement
			(enabled no)
			(sheetname "")
		)
		(fill yes
			(thermal_gap 0.5)
			(thermal_bridge_width 0.5)
			(island_removal_mode 0)
		)
		(polygon
			(pts
				(arc
					(start 333.716122 -241.24412)
					(mid 333.086202 -241.24412)
					(end 333.716122 -241.24412)
				)
			)
		)
	)
	(zone
		(layers "B.Cu" "In13.Cu" "In15.Cu")
		(hatch none 0.5)
		(connect_pads
			(clearance 0)
		)
		(min_thickness 0.25)
		(keepout
			(tracks not_allowed)
			(vias allowed)
			(pads allowed)
			(copperpour not_allowed)
			(footprints allowed)
		)
		(placement
			(enabled no)
			(sheetname "")
		)
		(fill yes
			(thermal_gap 0.5)
			(thermal_bridge_width 0.5)
			(island_removal_mode 0)
		)
		(polygon
			(pts
				(arc
					(start 454.522078 -315.485018)
					(mid 453.854058 -315.485018)
					(end 454.522078 -315.485018)
				)
			)
		)
	)
	(zone
		(layers "B.Cu" "In13.Cu" "In15.Cu")
		(hatch none 0.5)
		(connect_pads
			(clearance 0)
		)
		(min_thickness 0.25)
		(keepout
			(tracks not_allowed)
			(vias allowed)
			(pads allowed)
			(copperpour not_allowed)
			(footprints allowed)
		)
		(placement
			(enabled no)
			(sheetname "")
		)
		(fill yes
			(thermal_gap 0.5)
			(thermal_bridge_width 0.5)
			(island_removal_mode 0)
		)
		(polygon
			(pts
				(arc
					(start 334.760316 -420.952168)
					(mid 334.092296 -420.952168)
					(end 334.760316 -420.952168)
				)
			)
		)
	)
	(zone
		(layers "B.Cu" "In13.Cu" "In15.Cu")
		(hatch none 0.5)
		(connect_pads
			(clearance 0)
		)
		(min_thickness 0.25)
		(keepout
			(tracks not_allowed)
			(vias allowed)
			(pads allowed)
			(copperpour not_allowed)
			(footprints allowed)
		)
		(placement
			(enabled no)
			(sheetname "")
		)
		(fill yes
			(thermal_gap 0.5)
			(thermal_bridge_width 0.5)
			(island_removal_mode 0)
		)
		(polygon
			(pts
				(arc
					(start 202.481942 -312.085228)
					(mid 201.813922 -312.085228)
					(end 202.481942 -312.085228)
				)
			)
		)
	)
	(zone
		(layers "B.Cu" "In13.Cu" "In15.Cu")
		(hatch none 0.5)
		(connect_pads
			(clearance 0)
		)
		(min_thickness 0.25)
		(keepout
			(tracks not_allowed)
			(vias allowed)
			(pads allowed)
			(copperpour not_allowed)
			(footprints allowed)
		)
		(placement
			(enabled no)
			(sheetname "")
		)
		(fill yes
			(thermal_gap 0.5)
			(thermal_bridge_width 0.5)
			(island_removal_mode 0)
		)
		(polygon
			(pts
				(arc
					(start 206.58201 -303.585372)
					(mid 205.91399 -303.585372)
					(end 206.58201 -303.585372)
				)
			)
		)
	)
	(zone
		(layers "B.Cu" "In13.Cu" "In15.Cu")
		(hatch none 0.5)
		(connect_pads
			(clearance 0)
		)
		(min_thickness 0.25)
		(keepout
			(tracks not_allowed)
			(vias allowed)
			(pads allowed)
			(copperpour not_allowed)
			(footprints allowed)
		)
		(placement
			(enabled no)
			(sheetname "")
		)
		(fill yes
			(thermal_gap 0.5)
			(thermal_bridge_width 0.5)
			(island_removal_mode 0)
		)
		(polygon
			(pts
				(arc
					(start 84.3661 -251.774452)
					(mid 83.73618 -251.774452)
					(end 84.3661 -251.774452)
				)
			)
		)
	)
	(zone
		(layers "B.Cu" "In13.Cu" "In15.Cu")
		(hatch none 0.5)
		(connect_pads
			(clearance 0)
		)
		(min_thickness 0.25)
		(keepout
			(tracks not_allowed)
			(vias allowed)
			(pads allowed)
			(copperpour not_allowed)
			(footprints allowed)
		)
		(placement
			(enabled no)
			(sheetname "")
		)
		(fill yes
			(thermal_gap 0.5)
			(thermal_bridge_width 0.5)
			(island_removal_mode 0)
		)
		(polygon
			(pts
				(arc
					(start 86.545928 -265.98626)
					(mid 85.916008 -265.98626)
					(end 86.545928 -265.98626)
				)
			)
		)
	)
	(zone
		(layers "B.Cu" "In13.Cu" "In15.Cu")
		(hatch none 0.5)
		(connect_pads
			(clearance 0)
		)
		(min_thickness 0.25)
		(keepout
			(tracks not_allowed)
			(vias allowed)
			(pads allowed)
			(copperpour not_allowed)
			(footprints allowed)
		)
		(placement
			(enabled no)
			(sheetname "")
		)
		(fill yes
			(thermal_gap 0.5)
			(thermal_bridge_width 0.5)
			(island_removal_mode 0)
		)
		(polygon
			(pts
				(arc
					(start 84.836 -226.66452)
					(mid 84.20608 -226.66452)
					(end 84.836 -226.66452)
				)
			)
		)
	)
	(zone
		(layers "B.Cu" "In13.Cu" "In15.Cu")
		(hatch none 0.5)
		(connect_pads
			(clearance 0)
		)
		(min_thickness 0.25)
		(keepout
			(tracks not_allowed)
			(vias allowed)
			(pads allowed)
			(copperpour not_allowed)
			(footprints allowed)
		)
		(placement
			(enabled no)
			(sheetname "")
		)
		(fill yes
			(thermal_gap 0.5)
			(thermal_bridge_width 0.5)
			(island_removal_mode 0)
		)
		(polygon
			(pts
				(arc
					(start 202.481942 -226.23526)
					(mid 201.813922 -226.23526)
					(end 202.481942 -226.23526)
				)
			)
		)
	)
	(zone
		(layers "B.Cu" "In13.Cu" "In15.Cu")
		(hatch none 0.5)
		(connect_pads
			(clearance 0)
		)
		(min_thickness 0.25)
		(keepout
			(tracks not_allowed)
			(vias allowed)
			(pads allowed)
			(copperpour not_allowed)
			(footprints allowed)
		)
		(placement
			(enabled no)
			(sheetname "")
		)
		(fill yes
			(thermal_gap 0.5)
			(thermal_bridge_width 0.5)
			(island_removal_mode 0)
		)
		(polygon
			(pts
				(arc
					(start 73.036938 -430.689766)
					(mid 72.262746 -430.689766)
					(end 73.036938 -430.689766)
				)
			)
		)
	)
	(zone
		(layers "B.Cu" "In13.Cu" "In15.Cu")
		(hatch none 0.5)
		(connect_pads
			(clearance 0)
		)
		(min_thickness 0.25)
		(keepout
			(tracks not_allowed)
			(vias allowed)
			(pads allowed)
			(copperpour not_allowed)
			(footprints allowed)
		)
		(placement
			(enabled no)
			(sheetname "")
		)
		(fill yes
			(thermal_gap 0.5)
			(thermal_bridge_width 0.5)
			(island_removal_mode 0)
		)
		(polygon
			(pts
				(arc
					(start 86.076028 -278.13635)
					(mid 85.446108 -278.13635)
					(end 86.076028 -278.13635)
				)
			)
		)
	)
	(zone
		(layers "B.Cu" "In13.Cu" "In15.Cu")
		(hatch none 0.5)
		(connect_pads
			(clearance 0)
		)
		(min_thickness 0.25)
		(keepout
			(tracks not_allowed)
			(vias allowed)
			(pads allowed)
			(copperpour not_allowed)
			(footprints allowed)
		)
		(placement
			(enabled no)
			(sheetname "")
		)
		(fill yes
			(thermal_gap 0.5)
			(thermal_bridge_width 0.5)
			(island_removal_mode 0)
		)
		(polygon
			(pts
				(arc
					(start 269.982188 -307.835046)
					(mid 269.314168 -307.835046)
					(end 269.982188 -307.835046)
				)
			)
		)
	)
	(zone
		(layers "B.Cu" "In13.Cu" "In15.Cu")
		(hatch none 0.5)
		(connect_pads
			(clearance 0)
		)
		(min_thickness 0.25)
		(keepout
			(tracks not_allowed)
			(vias allowed)
			(pads allowed)
			(copperpour not_allowed)
			(footprints allowed)
		)
		(placement
			(enabled no)
			(sheetname "")
		)
		(fill yes
			(thermal_gap 0.5)
			(thermal_bridge_width 0.5)
			(island_removal_mode 0)
		)
		(polygon
			(pts
				(arc
					(start 265.88212 -250.03506)
					(mid 265.2141 -250.03506)
					(end 265.88212 -250.03506)
				)
			)
		)
	)
	(zone
		(layers "B.Cu" "In13.Cu" "In15.Cu")
		(hatch none 0.5)
		(connect_pads
			(clearance 0)
		)
		(min_thickness 0.25)
		(keepout
			(tracks not_allowed)
			(vias allowed)
			(pads allowed)
			(copperpour not_allowed)
			(footprints allowed)
		)
		(placement
			(enabled no)
			(sheetname "")
		)
		(fill yes
			(thermal_gap 0.5)
			(thermal_bridge_width 0.5)
			(island_removal_mode 0)
		)
		(polygon
			(pts
				(arc
					(start 140.119608 -285.426404)
					(mid 139.489688 -285.426404)
					(end 140.119608 -285.426404)
				)
			)
		)
	)
	(zone
		(layers "B.Cu" "In13.Cu" "In15.Cu")
		(hatch none 0.5)
		(connect_pads
			(clearance 0)
		)
		(min_thickness 0.25)
		(keepout
			(tracks not_allowed)
			(vias allowed)
			(pads allowed)
			(copperpour not_allowed)
			(footprints allowed)
		)
		(placement
			(enabled no)
			(sheetname "")
		)
		(fill yes
			(thermal_gap 0.5)
			(thermal_bridge_width 0.5)
			(island_removal_mode 0)
		)
		(polygon
			(pts
				(arc
					(start 89.433908 -386.003292)
					(mid 88.803988 -386.003292)
					(end 89.433908 -386.003292)
				)
			)
		)
	)
	(zone
		(layers "B.Cu" "In13.Cu" "In15.Cu")
		(hatch none 0.5)
		(connect_pads
			(clearance 0)
		)
		(min_thickness 0.25)
		(keepout
			(tracks not_allowed)
			(vias allowed)
			(pads allowed)
			(copperpour not_allowed)
			(footprints allowed)
		)
		(placement
			(enabled no)
			(sheetname "")
		)
		(fill yes
			(thermal_gap 0.5)
			(thermal_bridge_width 0.5)
			(island_removal_mode 0)
		)
		(polygon
			(pts
				(arc
					(start 390.136888 -430.889918)
					(mid 389.362696 -430.889918)
					(end 390.136888 -430.889918)
				)
			)
		)
	)
	(zone
		(layers "B.Cu" "In13.Cu" "In15.Cu")
		(hatch none 0.5)
		(connect_pads
			(clearance 0)
		)
		(min_thickness 0.25)
		(keepout
			(tracks not_allowed)
			(vias allowed)
			(pads allowed)
			(copperpour not_allowed)
			(footprints allowed)
		)
		(placement
			(enabled no)
			(sheetname "")
		)
		(fill yes
			(thermal_gap 0.5)
			(thermal_bridge_width 0.5)
			(island_removal_mode 0)
		)
		(polygon
			(pts
				(arc
					(start 138.709654 -271.656302)
					(mid 138.079734 -271.656302)
					(end 138.709654 -271.656302)
				)
			)
		)
	)
	(zone
		(layers "B.Cu" "In13.Cu" "In15.Cu")
		(hatch none 0.5)
		(connect_pads
			(clearance 0)
		)
		(min_thickness 0.25)
		(keepout
			(tracks not_allowed)
			(vias allowed)
			(pads allowed)
			(copperpour not_allowed)
			(footprints allowed)
		)
		(placement
			(enabled no)
			(sheetname "")
		)
		(fill yes
			(thermal_gap 0.5)
			(thermal_bridge_width 0.5)
			(island_removal_mode 0)
		)
		(polygon
			(pts
				(arc
					(start 86.076028 -266.796266)
					(mid 85.446108 -266.796266)
					(end 86.076028 -266.796266)
				)
			)
		)
	)
	(zone
		(layers "B.Cu" "In13.Cu" "In15.Cu")
		(hatch none 0.5)
		(connect_pads
			(clearance 0)
		)
		(min_thickness 0.25)
		(keepout
			(tracks not_allowed)
			(vias allowed)
			(pads allowed)
			(copperpour not_allowed)
			(footprints allowed)
		)
		(placement
			(enabled no)
			(sheetname "")
		)
		(fill yes
			(thermal_gap 0.5)
			(thermal_bridge_width 0.5)
			(island_removal_mode 0)
		)
		(polygon
			(pts
				(arc
					(start 388.059676 -262.745982)
					(mid 387.429756 -262.745982)
					(end 388.059676 -262.745982)
				)
			)
		)
	)
	(zone
		(layers "B.Cu" "In13.Cu" "In15.Cu")
		(hatch none 0.5)
		(connect_pads
			(clearance 0)
		)
		(min_thickness 0.25)
		(keepout
			(tracks not_allowed)
			(vias allowed)
			(pads allowed)
			(copperpour not_allowed)
			(footprints allowed)
		)
		(placement
			(enabled no)
			(sheetname "")
		)
		(fill yes
			(thermal_gap 0.5)
			(thermal_bridge_width 0.5)
			(island_removal_mode 0)
		)
		(polygon
			(pts
				(arc
					(start 450.42201 -224.534984)
					(mid 449.75399 -224.534984)
					(end 450.42201 -224.534984)
				)
			)
		)
	)
	(zone
		(layers "B.Cu" "In13.Cu" "In15.Cu")
		(hatch none 0.5)
		(connect_pads
			(clearance 0)
		)
		(min_thickness 0.25)
		(keepout
			(tracks not_allowed)
			(vias allowed)
			(pads allowed)
			(copperpour not_allowed)
			(footprints allowed)
		)
		(placement
			(enabled no)
			(sheetname "")
		)
		(fill yes
			(thermal_gap 0.5)
			(thermal_bridge_width 0.5)
			(island_removal_mode 0)
		)
		(polygon
			(pts
				(arc
					(start 269.982188 -197.33514)
					(mid 269.314168 -197.33514)
					(end 269.982188 -197.33514)
				)
			)
		)
	)
	(zone
		(layers "B.Cu" "In13.Cu" "In15.Cu")
		(hatch none 0.5)
		(connect_pads
			(clearance 0)
		)
		(min_thickness 0.25)
		(keepout
			(tracks not_allowed)
			(vias allowed)
			(pads allowed)
			(copperpour not_allowed)
			(footprints allowed)
		)
		(placement
			(enabled no)
			(sheetname "")
		)
		(fill yes
			(thermal_gap 0.5)
			(thermal_bridge_width 0.5)
			(island_removal_mode 0)
		)
		(polygon
			(pts
				(arc
					(start 334.016096 -291.095938)
					(mid 333.386176 -291.095938)
					(end 334.016096 -291.095938)
				)
			)
		)
	)
	(zone
		(layers "B.Cu" "In13.Cu" "In15.Cu")
		(hatch none 0.5)
		(connect_pads
			(clearance 0)
		)
		(min_thickness 0.25)
		(keepout
			(tracks not_allowed)
			(vias allowed)
			(pads allowed)
			(copperpour not_allowed)
			(footprints allowed)
		)
		(placement
			(enabled no)
			(sheetname "")
		)
		(fill yes
			(thermal_gap 0.5)
			(thermal_bridge_width 0.5)
			(island_removal_mode 0)
		)
		(polygon
			(pts
				(arc
					(start 206.58201 -228.78542)
					(mid 205.91399 -228.78542)
					(end 206.58201 -228.78542)
				)
			)
		)
	)
	(zone
		(layers "B.Cu" "In13.Cu" "In15.Cu")
		(hatch none 0.5)
		(connect_pads
			(clearance 0)
		)
		(min_thickness 0.25)
		(keepout
			(tracks not_allowed)
			(vias allowed)
			(pads allowed)
			(copperpour not_allowed)
			(footprints allowed)
		)
		(placement
			(enabled no)
			(sheetname "")
		)
		(fill yes
			(thermal_gap 0.5)
			(thermal_bridge_width 0.5)
			(island_removal_mode 0)
		)
		(polygon
			(pts
				(arc
					(start 265.88212 -246.635016)
					(mid 265.2141 -246.635016)
					(end 265.88212 -246.635016)
				)
			)
		)
	)
	(zone
		(layers "B.Cu" "In13.Cu" "In15.Cu")
		(hatch none 0.5)
		(connect_pads
			(clearance 0)
		)
		(min_thickness 0.25)
		(keepout
			(tracks not_allowed)
			(vias allowed)
			(pads allowed)
			(copperpour not_allowed)
			(footprints allowed)
		)
		(placement
			(enabled no)
			(sheetname "")
		)
		(fill yes
			(thermal_gap 0.5)
			(thermal_bridge_width 0.5)
			(island_removal_mode 0)
		)
		(polygon
			(pts
				(arc
					(start 334.016096 -292.71595)
					(mid 333.386176 -292.71595)
					(end 334.016096 -292.71595)
				)
			)
		)
	)
	(zone
		(layers "B.Cu" "In13.Cu" "In15.Cu")
		(hatch none 0.5)
		(connect_pads
			(clearance 0)
		)
		(min_thickness 0.25)
		(keepout
			(tracks not_allowed)
			(vias allowed)
			(pads allowed)
			(copperpour not_allowed)
			(footprints allowed)
		)
		(placement
			(enabled no)
			(sheetname "")
		)
		(fill yes
			(thermal_gap 0.5)
			(thermal_bridge_width 0.5)
			(island_removal_mode 0)
		)
		(polygon
			(pts
				(arc
					(start 348.633796 -393.69238)
					(mid 348.003876 -393.69238)
					(end 348.633796 -393.69238)
				)
			)
		)
	)
	(zone
		(layers "B.Cu" "In13.Cu" "In15.Cu")
		(hatch none 0.5)
		(connect_pads
			(clearance 0)
		)
		(min_thickness 0.25)
		(keepout
			(tracks not_allowed)
			(vias allowed)
			(pads allowed)
			(copperpour not_allowed)
			(footprints allowed)
		)
		(placement
			(enabled no)
			(sheetname "")
		)
		(fill yes
			(thermal_gap 0.5)
			(thermal_bridge_width 0.5)
			(island_removal_mode 0)
		)
		(polygon
			(pts
				(arc
					(start 100.815902 -246.10441)
					(mid 100.185982 -246.10441)
					(end 100.815902 -246.10441)
				)
			)
		)
	)
	(zone
		(layers "B.Cu" "In13.Cu" "In15.Cu")
		(hatch none 0.5)
		(connect_pads
			(clearance 0)
		)
		(min_thickness 0.25)
		(keepout
			(tracks not_allowed)
			(vias allowed)
			(pads allowed)
			(copperpour not_allowed)
			(footprints allowed)
		)
		(placement
			(enabled no)
			(sheetname "")
		)
		(fill yes
			(thermal_gap 0.5)
			(thermal_bridge_width 0.5)
			(island_removal_mode 0)
		)
		(polygon
			(pts
				(arc
					(start 317.036704 -430.689766)
					(mid 316.262512 -430.689766)
					(end 317.036704 -430.689766)
				)
			)
		)
	)
	(zone
		(layers "B.Cu" "In13.Cu" "In15.Cu")
		(hatch none 0.5)
		(connect_pads
			(clearance 0)
		)
		(min_thickness 0.25)
		(keepout
			(tracks not_allowed)
			(vias allowed)
			(pads allowed)
			(copperpour not_allowed)
			(footprints allowed)
		)
		(placement
			(enabled no)
			(sheetname "")
		)
		(fill yes
			(thermal_gap 0.5)
			(thermal_bridge_width 0.5)
			(island_removal_mode 0)
		)
		(polygon
			(pts
				(arc
					(start 27.907488 -17.61236)
					(mid 27.239468 -17.61236)
					(end 27.907488 -17.61236)
				)
			)
		)
	)
	(zone
		(layers "B.Cu" "In13.Cu" "In15.Cu")
		(hatch none 0.5)
		(connect_pads
			(clearance 0)
		)
		(min_thickness 0.25)
		(keepout
			(tracks not_allowed)
			(vias allowed)
			(pads allowed)
			(copperpour not_allowed)
			(footprints allowed)
		)
		(placement
			(enabled no)
			(sheetname "")
		)
		(fill yes
			(thermal_gap 0.5)
			(thermal_bridge_width 0.5)
			(island_removal_mode 0)
		)
		(polygon
			(pts
				(arc
					(start 22.04212 -240.68532)
					(mid 21.3741 -240.68532)
					(end 22.04212 -240.68532)
				)
			)
		)
	)
	(zone
		(layers "B.Cu" "In13.Cu" "In15.Cu")
		(hatch none 0.5)
		(connect_pads
			(clearance 0)
		)
		(min_thickness 0.25)
		(keepout
			(tracks not_allowed)
			(vias allowed)
			(pads allowed)
			(copperpour not_allowed)
			(footprints allowed)
		)
		(placement
			(enabled no)
			(sheetname "")
		)
		(fill yes
			(thermal_gap 0.5)
			(thermal_bridge_width 0.5)
			(island_removal_mode 0)
		)
		(polygon
			(pts
				(arc
					(start 206.58201 -287.43529)
					(mid 205.91399 -287.43529)
					(end 206.58201 -287.43529)
				)
			)
		)
	)
	(zone
		(layers "B.Cu" "In13.Cu" "In15.Cu")
		(hatch none 0.5)
		(connect_pads
			(clearance 0)
		)
		(min_thickness 0.25)
		(keepout
			(tracks not_allowed)
			(vias allowed)
			(pads allowed)
			(copperpour not_allowed)
			(footprints allowed)
		)
		(placement
			(enabled no)
			(sheetname "")
		)
		(fill yes
			(thermal_gap 0.5)
			(thermal_bridge_width 0.5)
			(island_removal_mode 0)
		)
		(polygon
			(pts
				(arc
					(start 139.349734 -238.00435)
					(mid 138.719814 -238.00435)
					(end 139.349734 -238.00435)
				)
			)
		)
	)
	(zone
		(layers "B.Cu" "In13.Cu" "In15.Cu")
		(hatch none 0.5)
		(connect_pads
			(clearance 0)
		)
		(min_thickness 0.25)
		(keepout
			(tracks not_allowed)
			(vias allowed)
			(pads allowed)
			(copperpour not_allowed)
			(footprints allowed)
		)
		(placement
			(enabled no)
			(sheetname "")
		)
		(fill yes
			(thermal_gap 0.5)
			(thermal_bridge_width 0.5)
			(island_removal_mode 0)
		)
		(polygon
			(pts
				(arc
					(start 17.942052 -306.985416)
					(mid 17.274032 -306.985416)
					(end 17.942052 -306.985416)
				)
			)
		)
	)
	(zone
		(layers "B.Cu" "In13.Cu" "In15.Cu")
		(hatch none 0.5)
		(connect_pads
			(clearance 0)
		)
		(min_thickness 0.25)
		(keepout
			(tracks not_allowed)
			(vias allowed)
			(pads allowed)
			(copperpour not_allowed)
			(footprints allowed)
		)
		(placement
			(enabled no)
			(sheetname "")
		)
		(fill yes
			(thermal_gap 0.5)
			(thermal_bridge_width 0.5)
			(island_removal_mode 0)
		)
		(polygon
			(pts
				(arc
					(start 415.56432 -4.963414)
					(mid 414.8963 -4.963414)
					(end 415.56432 -4.963414)
				)
			)
		)
	)
	(zone
		(layers "B.Cu" "In13.Cu" "In15.Cu")
		(hatch none 0.5)
		(connect_pads
			(clearance 0)
		)
		(min_thickness 0.25)
		(keepout
			(tracks not_allowed)
			(vias allowed)
			(pads allowed)
			(copperpour not_allowed)
			(footprints allowed)
		)
		(placement
			(enabled no)
			(sheetname "")
		)
		(fill yes
			(thermal_gap 0.5)
			(thermal_bridge_width 0.5)
			(island_removal_mode 0)
		)
		(polygon
			(pts
				(arc
					(start 157.1371 -431.889916)
					(mid 156.362908 -431.889916)
					(end 157.1371 -431.889916)
				)
			)
		)
	)
	(zone
		(layers "B.Cu" "In13.Cu" "In15.Cu")
		(hatch none 0.5)
		(connect_pads
			(clearance 0)
		)
		(min_thickness 0.25)
		(keepout
			(tracks not_allowed)
			(vias allowed)
			(pads allowed)
			(copperpour not_allowed)
			(footprints allowed)
		)
		(placement
			(enabled no)
			(sheetname "")
		)
		(fill yes
			(thermal_gap 0.5)
			(thermal_bridge_width 0.5)
			(island_removal_mode 0)
		)
		(polygon
			(pts
				(arc
					(start 137.93978 -238.814356)
					(mid 137.30986 -238.814356)
					(end 137.93978 -238.814356)
				)
			)
		)
	)
	(zone
		(layers "B.Cu" "In13.Cu" "In15.Cu")
		(hatch none 0.5)
		(connect_pads
			(clearance 0)
		)
		(min_thickness 0.25)
		(keepout
			(tracks not_allowed)
			(vias allowed)
			(pads allowed)
			(copperpour not_allowed)
			(footprints allowed)
		)
		(placement
			(enabled no)
			(sheetname "")
		)
		(fill yes
			(thermal_gap 0.5)
			(thermal_bridge_width 0.5)
			(island_removal_mode 0)
		)
		(polygon
			(pts
				(arc
					(start 265.88212 -261.93496)
					(mid 265.2141 -261.93496)
					(end 265.88212 -261.93496)
				)
			)
		)
	)
	(zone
		(layers "B.Cu" "In13.Cu" "In15.Cu")
		(hatch none 0.5)
		(connect_pads
			(clearance 0)
		)
		(min_thickness 0.25)
		(keepout
			(tracks not_allowed)
			(vias allowed)
			(pads allowed)
			(copperpour not_allowed)
			(footprints allowed)
		)
		(placement
			(enabled no)
			(sheetname "")
		)
		(fill yes
			(thermal_gap 0.5)
			(thermal_bridge_width 0.5)
			(island_removal_mode 0)
		)
		(polygon
			(pts
				(arc
					(start 22.04212 -210.935316)
					(mid 21.3741 -210.935316)
					(end 22.04212 -210.935316)
				)
			)
		)
	)
	(zone
		(layers "B.Cu" "In13.Cu" "In15.Cu")
		(hatch none 0.5)
		(connect_pads
			(clearance 0)
		)
		(min_thickness 0.25)
		(keepout
			(tracks not_allowed)
			(vias allowed)
			(pads allowed)
			(copperpour not_allowed)
			(footprints allowed)
		)
		(placement
			(enabled no)
			(sheetname "")
		)
		(fill yes
			(thermal_gap 0.5)
			(thermal_bridge_width 0.5)
			(island_removal_mode 0)
		)
		(polygon
			(pts
				(arc
					(start 108.80598 -245.294404)
					(mid 108.17606 -245.294404)
					(end 108.80598 -245.294404)
				)
			)
		)
	)
	(zone
		(layers "B.Cu" "In13.Cu" "In15.Cu")
		(hatch none 0.5)
		(connect_pads
			(clearance 0)
		)
		(min_thickness 0.25)
		(keepout
			(tracks not_allowed)
			(vias allowed)
			(pads allowed)
			(copperpour not_allowed)
			(footprints allowed)
		)
		(placement
			(enabled no)
			(sheetname "")
		)
		(fill yes
			(thermal_gap 0.5)
			(thermal_bridge_width 0.5)
			(island_removal_mode 0)
		)
		(polygon
			(pts
				(arc
					(start 22.04212 -254.285242)
					(mid 21.3741 -254.285242)
					(end 22.04212 -254.285242)
				)
			)
		)
	)
	(zone
		(layers "B.Cu" "In13.Cu" "In15.Cu")
		(hatch none 0.5)
		(connect_pads
			(clearance 0)
		)
		(min_thickness 0.25)
		(keepout
			(tracks not_allowed)
			(vias allowed)
			(pads allowed)
			(copperpour not_allowed)
			(footprints allowed)
		)
		(placement
			(enabled no)
			(sheetname "")
		)
		(fill yes
			(thermal_gap 0.5)
			(thermal_bridge_width 0.5)
			(island_removal_mode 0)
		)
		(polygon
			(pts
				(arc
					(start 355.636068 -278.136096)
					(mid 355.006148 -278.136096)
					(end 355.636068 -278.136096)
				)
			)
		)
	)
	(zone
		(layers "B.Cu" "In13.Cu" "In15.Cu")
		(hatch none 0.5)
		(connect_pads
			(clearance 0)
		)
		(min_thickness 0.25)
		(keepout
			(tracks not_allowed)
			(vias allowed)
			(pads allowed)
			(copperpour not_allowed)
			(footprints allowed)
		)
		(placement
			(enabled no)
			(sheetname "")
		)
		(fill yes
			(thermal_gap 0.5)
			(thermal_bridge_width 0.5)
			(island_removal_mode 0)
		)
		(polygon
			(pts
				(arc
					(start 17.942052 -229.635304)
					(mid 17.274032 -229.635304)
					(end 17.942052 -229.635304)
				)
			)
		)
	)
	(zone
		(layers "B.Cu" "In13.Cu" "In15.Cu")
		(hatch none 0.5)
		(connect_pads
			(clearance 0)
		)
		(min_thickness 0.25)
		(keepout
			(tracks not_allowed)
			(vias allowed)
			(pads allowed)
			(copperpour not_allowed)
			(footprints allowed)
		)
		(placement
			(enabled no)
			(sheetname "")
		)
		(fill yes
			(thermal_gap 0.5)
			(thermal_bridge_width 0.5)
			(island_removal_mode 0)
		)
		(polygon
			(pts
				(arc
					(start 17.942052 -291.685218)
					(mid 17.274032 -291.685218)
					(end 17.942052 -291.685218)
				)
			)
		)
	)
	(zone
		(layers "B.Cu" "In13.Cu" "In15.Cu")
		(hatch none 0.5)
		(connect_pads
			(clearance 0)
		)
		(min_thickness 0.25)
		(keepout
			(tracks not_allowed)
			(vias allowed)
			(pads allowed)
			(copperpour not_allowed)
			(footprints allowed)
		)
		(placement
			(enabled no)
			(sheetname "")
		)
		(fill yes
			(thermal_gap 0.5)
			(thermal_bridge_width 0.5)
			(island_removal_mode 0)
		)
		(polygon
			(pts
				(arc
					(start 454.522078 -221.985078)
					(mid 453.854058 -221.985078)
					(end 454.522078 -221.985078)
				)
			)
		)
	)
	(zone
		(layers "B.Cu" "In13.Cu" "In15.Cu")
		(hatch none 0.5)
		(connect_pads
			(clearance 0)
		)
		(min_thickness 0.25)
		(keepout
			(tracks not_allowed)
			(vias allowed)
			(pads allowed)
			(copperpour not_allowed)
			(footprints allowed)
		)
		(placement
			(enabled no)
			(sheetname "")
		)
		(fill yes
			(thermal_gap 0.5)
			(thermal_bridge_width 0.5)
			(island_removal_mode 0)
		)
		(polygon
			(pts
				(arc
					(start 84.666074 -278.946356)
					(mid 84.036154 -278.946356)
					(end 84.666074 -278.946356)
				)
			)
		)
	)
	(zone
		(layers "B.Cu" "In13.Cu" "In15.Cu")
		(hatch none 0.5)
		(connect_pads
			(clearance 0)
		)
		(min_thickness 0.25)
		(keepout
			(tracks not_allowed)
			(vias allowed)
			(pads allowed)
			(copperpour not_allowed)
			(footprints allowed)
		)
		(placement
			(enabled no)
			(sheetname "")
		)
		(fill yes
			(thermal_gap 0.5)
			(thermal_bridge_width 0.5)
			(island_removal_mode 0)
		)
		(polygon
			(pts
				(arc
					(start 388.059676 -282.186126)
					(mid 387.429756 -282.186126)
					(end 388.059676 -282.186126)
				)
			)
		)
	)
	(zone
		(layers "B.Cu" "In13.Cu" "In15.Cu")
		(hatch none 0.5)
		(connect_pads
			(clearance 0)
		)
		(min_thickness 0.25)
		(keepout
			(tracks not_allowed)
			(vias allowed)
			(pads allowed)
			(copperpour not_allowed)
			(footprints allowed)
		)
		(placement
			(enabled no)
			(sheetname "")
		)
		(fill yes
			(thermal_gap 0.5)
			(thermal_bridge_width 0.5)
			(island_removal_mode 0)
		)
		(polygon
			(pts
				(arc
					(start 86.076028 -273.276314)
					(mid 85.446108 -273.276314)
					(end 86.076028 -273.276314)
				)
			)
		)
	)
	(zone
		(layers "B.Cu" "In13.Cu" "In15.Cu")
		(hatch none 0.5)
		(connect_pads
			(clearance 0)
		)
		(min_thickness 0.25)
		(keepout
			(tracks not_allowed)
			(vias allowed)
			(pads allowed)
			(copperpour not_allowed)
			(footprints allowed)
		)
		(placement
			(enabled no)
			(sheetname "")
		)
		(fill yes
			(thermal_gap 0.5)
			(thermal_bridge_width 0.5)
			(island_removal_mode 0)
		)
		(polygon
			(pts
				(arc
					(start 140.597636 -412.570168)
					(mid 139.929616 -412.570168)
					(end 140.597636 -412.570168)
				)
			)
		)
	)
	(zone
		(layers "B.Cu" "In13.Cu" "In15.Cu")
		(hatch none 0.5)
		(connect_pads
			(clearance 0)
		)
		(min_thickness 0.25)
		(keepout
			(tracks not_allowed)
			(vias allowed)
			(pads allowed)
			(copperpour not_allowed)
			(footprints allowed)
		)
		(placement
			(enabled no)
			(sheetname "")
		)
		(fill yes
			(thermal_gap 0.5)
			(thermal_bridge_width 0.5)
			(island_removal_mode 0)
		)
		(polygon
			(pts
				(arc
					(start 334.485996 -270.846042)
					(mid 333.856076 -270.846042)
					(end 334.485996 -270.846042)
				)
			)
		)
	)
	(zone
		(layers "B.Cu" "In13.Cu" "In15.Cu")
		(hatch none 0.5)
		(connect_pads
			(clearance 0)
		)
		(min_thickness 0.25)
		(keepout
			(tracks not_allowed)
			(vias allowed)
			(pads allowed)
			(copperpour not_allowed)
			(footprints allowed)
		)
		(placement
			(enabled no)
			(sheetname "")
		)
		(fill yes
			(thermal_gap 0.5)
			(thermal_bridge_width 0.5)
			(island_removal_mode 0)
		)
		(polygon
			(pts
				(arc
					(start 387.759702 -227.474272)
					(mid 387.129782 -227.474272)
					(end 387.759702 -227.474272)
				)
			)
		)
	)
	(zone
		(layers "B.Cu" "In13.Cu" "In15.Cu")
		(hatch none 0.5)
		(connect_pads
			(clearance 0)
		)
		(min_thickness 0.25)
		(keepout
			(tracks not_allowed)
			(vias allowed)
			(pads allowed)
			(copperpour not_allowed)
			(footprints allowed)
		)
		(placement
			(enabled no)
			(sheetname "")
		)
		(fill yes
			(thermal_gap 0.5)
			(thermal_bridge_width 0.5)
			(island_removal_mode 0)
		)
		(polygon
			(pts
				(arc
					(start 139.649708 -271.656302)
					(mid 139.019788 -271.656302)
					(end 139.649708 -271.656302)
				)
			)
		)
	)
	(zone
		(layers "B.Cu" "In13.Cu" "In15.Cu")
		(hatch none 0.5)
		(connect_pads
			(clearance 0)
		)
		(min_thickness 0.25)
		(keepout
			(tracks not_allowed)
			(vias allowed)
			(pads allowed)
			(copperpour not_allowed)
			(footprints allowed)
		)
		(placement
			(enabled no)
			(sheetname "")
		)
		(fill yes
			(thermal_gap 0.5)
			(thermal_bridge_width 0.5)
			(island_removal_mode 0)
		)
		(polygon
			(pts
				(arc
					(start 334.016096 -274.896072)
					(mid 333.386176 -274.896072)
					(end 334.016096 -274.896072)
				)
			)
		)
	)
	(zone
		(layers "B.Cu" "In13.Cu" "In15.Cu")
		(hatch none 0.5)
		(connect_pads
			(clearance 0)
		)
		(min_thickness 0.25)
		(keepout
			(tracks not_allowed)
			(vias allowed)
			(pads allowed)
			(copperpour not_allowed)
			(footprints allowed)
		)
		(placement
			(enabled no)
			(sheetname "")
		)
		(fill yes
			(thermal_gap 0.5)
			(thermal_bridge_width 0.5)
			(island_removal_mode 0)
		)
		(polygon
			(pts
				(arc
					(start 386.649722 -270.036036)
					(mid 386.019802 -270.036036)
					(end 386.649722 -270.036036)
				)
			)
		)
	)
	(zone
		(layers "B.Cu" "In13.Cu" "In15.Cu")
		(hatch none 0.5)
		(connect_pads
			(clearance 0)
		)
		(min_thickness 0.25)
		(keepout
			(tracks not_allowed)
			(vias allowed)
			(pads allowed)
			(copperpour not_allowed)
			(footprints allowed)
		)
		(placement
			(enabled no)
			(sheetname "")
		)
		(fill yes
			(thermal_gap 0.5)
			(thermal_bridge_width 0.5)
			(island_removal_mode 0)
		)
		(polygon
			(pts
				(arc
					(start 402.85416 -4.963414)
					(mid 402.18614 -4.963414)
					(end 402.85416 -4.963414)
				)
			)
		)
	)
	(zone
		(layers "B.Cu" "In13.Cu" "In15.Cu")
		(hatch none 0.5)
		(connect_pads
			(clearance 0)
		)
		(min_thickness 0.25)
		(keepout
			(tracks not_allowed)
			(vias allowed)
			(pads allowed)
			(copperpour not_allowed)
			(footprints allowed)
		)
		(placement
			(enabled no)
			(sheetname "")
		)
		(fill yes
			(thermal_gap 0.5)
			(thermal_bridge_width 0.5)
			(island_removal_mode 0)
		)
		(polygon
			(pts
				(arc
					(start 386.349748 -247.724168)
					(mid 385.719828 -247.724168)
					(end 386.349748 -247.724168)
				)
			)
		)
	)
	(zone
		(layers "B.Cu" "In13.Cu" "In15.Cu")
		(hatch none 0.5)
		(connect_pads
			(clearance 0)
		)
		(min_thickness 0.25)
		(keepout
			(tracks not_allowed)
			(vias allowed)
			(pads allowed)
			(copperpour not_allowed)
			(footprints allowed)
		)
		(placement
			(enabled no)
			(sheetname "")
		)
		(fill yes
			(thermal_gap 0.5)
			(thermal_bridge_width 0.5)
			(island_removal_mode 0)
		)
		(polygon
			(pts
				(arc
					(start 134.471156 -412.570168)
					(mid 133.803136 -412.570168)
					(end 134.471156 -412.570168)
				)
			)
		)
	)
	(zone
		(layers "B.Cu" "In13.Cu" "In15.Cu")
		(hatch none 0.5)
		(connect_pads
			(clearance 0)
		)
		(min_thickness 0.25)
		(keepout
			(tracks not_allowed)
			(vias allowed)
			(pads allowed)
			(copperpour not_allowed)
			(footprints allowed)
		)
		(placement
			(enabled no)
			(sheetname "")
		)
		(fill yes
			(thermal_gap 0.5)
			(thermal_bridge_width 0.5)
			(island_removal_mode 0)
		)
		(polygon
			(pts
				(arc
					(start 137.93978 -233.95432)
					(mid 137.30986 -233.95432)
					(end 137.93978 -233.95432)
				)
			)
		)
	)
	(zone
		(layers "B.Cu" "In13.Cu" "In15.Cu")
		(hatch none 0.5)
		(connect_pads
			(clearance 0)
		)
		(min_thickness 0.25)
		(keepout
			(tracks not_allowed)
			(vias allowed)
			(pads allowed)
			(copperpour not_allowed)
			(footprints allowed)
		)
		(placement
			(enabled no)
			(sheetname "")
		)
		(fill yes
			(thermal_gap 0.5)
			(thermal_bridge_width 0.5)
			(island_removal_mode 0)
		)
		(polygon
			(pts
				(arc
					(start 374.291352 -420.952168)
					(mid 373.623332 -420.952168)
					(end 374.291352 -420.952168)
				)
			)
		)
	)
	(zone
		(layers "B.Cu" "In13.Cu" "In15.Cu")
		(hatch none 0.5)
		(connect_pads
			(clearance 0)
		)
		(min_thickness 0.25)
		(keepout
			(tracks not_allowed)
			(vias allowed)
			(pads allowed)
			(copperpour not_allowed)
			(footprints allowed)
		)
		(placement
			(enabled no)
			(sheetname "")
		)
		(fill yes
			(thermal_gap 0.5)
			(thermal_bridge_width 0.5)
			(island_removal_mode 0)
		)
		(polygon
			(pts
				(arc
					(start 454.522078 -199.035162)
					(mid 453.854058 -199.035162)
					(end 454.522078 -199.035162)
				)
			)
		)
	)
	(zone
		(layers "B.Cu" "In13.Cu" "In15.Cu")
		(hatch none 0.5)
		(connect_pads
			(clearance 0)
		)
		(min_thickness 0.25)
		(keepout
			(tracks not_allowed)
			(vias allowed)
			(pads allowed)
			(copperpour not_allowed)
			(footprints allowed)
		)
		(placement
			(enabled no)
			(sheetname "")
		)
		(fill yes
			(thermal_gap 0.5)
			(thermal_bridge_width 0.5)
			(island_removal_mode 0)
		)
		(polygon
			(pts
				(arc
					(start 265.88212 -312.084974)
					(mid 265.2141 -312.084974)
					(end 265.88212 -312.084974)
				)
			)
		)
	)
	(zone
		(layers "B.Cu" "In13.Cu" "In15.Cu")
		(hatch none 0.5)
		(connect_pads
			(clearance 0)
		)
		(min_thickness 0.25)
		(keepout
			(tracks not_allowed)
			(vias allowed)
			(pads allowed)
			(copperpour not_allowed)
			(footprints allowed)
		)
		(placement
			(enabled no)
			(sheetname "")
		)
		(fill yes
			(thermal_gap 0.5)
			(thermal_bridge_width 0.5)
			(island_removal_mode 0)
		)
		(polygon
			(pts
				(arc
					(start 139.819634 -246.914416)
					(mid 139.189714 -246.914416)
					(end 139.819634 -246.914416)
				)
			)
		)
	)
	(zone
		(layers "B.Cu" "In13.Cu" "In15.Cu")
		(hatch none 0.5)
		(connect_pads
			(clearance 0)
		)
		(min_thickness 0.25)
		(keepout
			(tracks not_allowed)
			(vias allowed)
			(pads allowed)
			(copperpour not_allowed)
			(footprints allowed)
		)
		(placement
			(enabled no)
			(sheetname "")
		)
		(fill yes
			(thermal_gap 0.5)
			(thermal_bridge_width 0.5)
			(island_removal_mode 0)
		)
		(polygon
			(pts
				(arc
					(start 206.58201 -306.135278)
					(mid 205.91399 -306.135278)
					(end 206.58201 -306.135278)
				)
			)
		)
	)
	(zone
		(layers "B.Cu" "In13.Cu" "In15.Cu")
		(hatch none 0.5)
		(connect_pads
			(clearance 0)
		)
		(min_thickness 0.25)
		(keepout
			(tracks not_allowed)
			(vias allowed)
			(pads allowed)
			(copperpour not_allowed)
			(footprints allowed)
		)
		(placement
			(enabled no)
			(sheetname "")
		)
		(fill yes
			(thermal_gap 0.5)
			(thermal_bridge_width 0.5)
			(island_removal_mode 0)
		)
		(polygon
			(pts
				(arc
					(start 454.522078 -284.88513)
					(mid 453.854058 -284.88513)
					(end 454.522078 -284.88513)
				)
			)
		)
	)
	(zone
		(layers "B.Cu" "In13.Cu" "In15.Cu")
		(hatch none 0.5)
		(connect_pads
			(clearance 0)
		)
		(min_thickness 0.25)
		(keepout
			(tracks not_allowed)
			(vias allowed)
			(pads allowed)
			(copperpour not_allowed)
			(footprints allowed)
		)
		(placement
			(enabled no)
			(sheetname "")
		)
		(fill yes
			(thermal_gap 0.5)
			(thermal_bridge_width 0.5)
			(island_removal_mode 0)
		)
		(polygon
			(pts
				(arc
					(start 413.137096 -431.889916)
					(mid 412.362904 -431.889916)
					(end 413.137096 -431.889916)
				)
			)
		)
	)
	(zone
		(layers "B.Cu" "In13.Cu" "In15.Cu")
		(hatch none 0.5)
		(connect_pads
			(clearance 0)
		)
		(min_thickness 0.25)
		(keepout
			(tracks not_allowed)
			(vias allowed)
			(pads allowed)
			(copperpour not_allowed)
			(footprints allowed)
		)
		(placement
			(enabled no)
			(sheetname "")
		)
		(fill yes
			(thermal_gap 0.5)
			(thermal_bridge_width 0.5)
			(island_removal_mode 0)
		)
		(polygon
			(pts
				(arc
					(start 124.927106 -371.49913)
					(mid 124.259086 -371.49913)
					(end 124.927106 -371.49913)
				)
			)
		)
	)
	(zone
		(layers "B.Cu" "In13.Cu" "In15.Cu")
		(hatch none 0.5)
		(connect_pads
			(clearance 0)
		)
		(min_thickness 0.25)
		(keepout
			(tracks not_allowed)
			(vias allowed)
			(pads allowed)
			(copperpour not_allowed)
			(footprints allowed)
		)
		(placement
			(enabled no)
			(sheetname "")
		)
		(fill yes
			(thermal_gap 0.5)
			(thermal_bridge_width 0.5)
			(island_removal_mode 0)
		)
		(polygon
			(pts
				(arc
					(start 138.40968 -244.484398)
					(mid 137.77976 -244.484398)
					(end 138.40968 -244.484398)
				)
			)
		)
	)
	(zone
		(layers "B.Cu" "In13.Cu" "In15.Cu")
		(hatch none 0.5)
		(connect_pads
			(clearance 0)
		)
		(min_thickness 0.25)
		(keepout
			(tracks not_allowed)
			(vias allowed)
			(pads allowed)
			(copperpour not_allowed)
			(footprints allowed)
		)
		(placement
			(enabled no)
			(sheetname "")
		)
		(fill yes
			(thermal_gap 0.5)
			(thermal_bridge_width 0.5)
			(island_removal_mode 0)
		)
		(polygon
			(pts
				(arc
					(start 22.04212 -229.635304)
					(mid 21.3741 -229.635304)
					(end 22.04212 -229.635304)
				)
			)
		)
	)
	(zone
		(layers "B.Cu" "In13.Cu" "In15.Cu")
		(hatch none 0.5)
		(connect_pads
			(clearance 0)
		)
		(min_thickness 0.25)
		(keepout
			(tracks not_allowed)
			(vias allowed)
			(pads allowed)
			(copperpour not_allowed)
			(footprints allowed)
		)
		(placement
			(enabled no)
			(sheetname "")
		)
		(fill yes
			(thermal_gap 0.5)
			(thermal_bridge_width 0.5)
			(island_removal_mode 0)
		)
		(polygon
			(pts
				(arc
					(start 139.649708 -292.716204)
					(mid 139.019788 -292.716204)
					(end 139.649708 -292.716204)
				)
			)
		)
	)
	(zone
		(layers "B.Cu" "In13.Cu" "In15.Cu")
		(hatch none 0.5)
		(connect_pads
			(clearance 0)
		)
		(min_thickness 0.25)
		(keepout
			(tracks not_allowed)
			(vias allowed)
			(pads allowed)
			(copperpour not_allowed)
			(footprints allowed)
		)
		(placement
			(enabled no)
			(sheetname "")
		)
		(fill yes
			(thermal_gap 0.5)
			(thermal_bridge_width 0.5)
			(island_removal_mode 0)
		)
		(polygon
			(pts
				(arc
					(start 116.789708 -233.144314)
					(mid 116.159788 -233.144314)
					(end 116.789708 -233.144314)
				)
			)
		)
	)
	(zone
		(layers "B.Cu" "In13.Cu" "In15.Cu")
		(hatch none 0.5)
		(connect_pads
			(clearance 0)
		)
		(min_thickness 0.25)
		(keepout
			(tracks not_allowed)
			(vias allowed)
			(pads allowed)
			(copperpour not_allowed)
			(footprints allowed)
		)
		(placement
			(enabled no)
			(sheetname "")
		)
		(fill yes
			(thermal_gap 0.5)
			(thermal_bridge_width 0.5)
			(island_removal_mode 0)
		)
		(polygon
			(pts
				(arc
					(start 385.879848 -229.094284)
					(mid 385.249928 -229.094284)
					(end 385.879848 -229.094284)
				)
			)
		)
	)
	(zone
		(layers "B.Cu" "In13.Cu" "In15.Cu")
		(hatch none 0.5)
		(connect_pads
			(clearance 0)
		)
		(min_thickness 0.25)
		(keepout
			(tracks not_allowed)
			(vias allowed)
			(pads allowed)
			(copperpour not_allowed)
			(footprints allowed)
		)
		(placement
			(enabled no)
			(sheetname "")
		)
		(fill yes
			(thermal_gap 0.5)
			(thermal_bridge_width 0.5)
			(island_removal_mode 0)
		)
		(polygon
			(pts
				(arc
					(start 265.88212 -241.53495)
					(mid 265.2141 -241.53495)
					(end 265.88212 -241.53495)
				)
			)
		)
	)
	(zone
		(layers "B.Cu" "In13.Cu" "In15.Cu")
		(hatch none 0.5)
		(connect_pads
			(clearance 0)
		)
		(min_thickness 0.25)
		(keepout
			(tracks not_allowed)
			(vias allowed)
			(pads allowed)
			(copperpour not_allowed)
			(footprints allowed)
		)
		(placement
			(enabled no)
			(sheetname "")
		)
		(fill yes
			(thermal_gap 0.5)
			(thermal_bridge_width 0.5)
			(island_removal_mode 0)
		)
		(polygon
			(pts
				(arc
					(start 450.42201 -246.635016)
					(mid 449.75399 -246.635016)
					(end 450.42201 -246.635016)
				)
			)
		)
	)
	(zone
		(layers "B.Cu" "In13.Cu" "In15.Cu")
		(hatch none 0.5)
		(connect_pads
			(clearance 0)
		)
		(min_thickness 0.25)
		(keepout
			(tracks not_allowed)
			(vias allowed)
			(pads allowed)
			(copperpour not_allowed)
			(footprints allowed)
		)
		(placement
			(enabled no)
			(sheetname "")
		)
		(fill yes
			(thermal_gap 0.5)
			(thermal_bridge_width 0.5)
			(island_removal_mode 0)
		)
		(polygon
			(pts
				(arc
					(start 117.729762 -233.144314)
					(mid 117.099842 -233.144314)
					(end 117.729762 -233.144314)
				)
			)
		)
	)
	(zone
		(layers "B.Cu" "In13.Cu" "In15.Cu")
		(hatch none 0.5)
		(connect_pads
			(clearance 0)
		)
		(min_thickness 0.25)
		(keepout
			(tracks not_allowed)
			(vias allowed)
			(pads allowed)
			(copperpour not_allowed)
			(footprints allowed)
		)
		(placement
			(enabled no)
			(sheetname "")
		)
		(fill yes
			(thermal_gap 0.5)
			(thermal_bridge_width 0.5)
			(island_removal_mode 0)
		)
		(polygon
			(pts
				(arc
					(start 334.016096 -289.475926)
					(mid 333.386176 -289.475926)
					(end 334.016096 -289.475926)
				)
			)
		)
	)
	(zone
		(layers "B.Cu" "In13.Cu" "In15.Cu")
		(hatch none 0.5)
		(connect_pads
			(clearance 0)
		)
		(min_thickness 0.25)
		(keepout
			(tracks not_allowed)
			(vias allowed)
			(pads allowed)
			(copperpour not_allowed)
			(footprints allowed)
		)
		(placement
			(enabled no)
			(sheetname "")
		)
		(fill yes
			(thermal_gap 0.5)
			(thermal_bridge_width 0.5)
			(island_removal_mode 0)
		)
		(polygon
			(pts
				(arc
					(start 206.58201 -220.28531)
					(mid 205.91399 -220.28531)
					(end 206.58201 -220.28531)
				)
			)
		)
	)
	(zone
		(layers "B.Cu" "In13.Cu" "In15.Cu")
		(hatch none 0.5)
		(connect_pads
			(clearance 0)
		)
		(min_thickness 0.25)
		(keepout
			(tracks not_allowed)
			(vias allowed)
			(pads allowed)
			(copperpour not_allowed)
			(footprints allowed)
		)
		(placement
			(enabled no)
			(sheetname "")
		)
		(fill yes
			(thermal_gap 0.5)
			(thermal_bridge_width 0.5)
			(island_removal_mode 0)
		)
		(polygon
			(pts
				(arc
					(start 355.636068 -276.516084)
					(mid 355.006148 -276.516084)
					(end 355.636068 -276.516084)
				)
			)
		)
	)
	(zone
		(layers "B.Cu" "In13.Cu" "In15.Cu")
		(hatch none 0.5)
		(connect_pads
			(clearance 0)
		)
		(min_thickness 0.25)
		(keepout
			(tracks not_allowed)
			(vias allowed)
			(pads allowed)
			(copperpour not_allowed)
			(footprints allowed)
		)
		(placement
			(enabled no)
			(sheetname "")
		)
		(fill yes
			(thermal_gap 0.5)
			(thermal_bridge_width 0.5)
			(island_removal_mode 0)
		)
		(polygon
			(pts
				(arc
					(start 138.239754 -283.806392)
					(mid 137.609834 -283.806392)
					(end 138.239754 -283.806392)
				)
			)
		)
	)
	(zone
		(layers "B.Cu" "In13.Cu" "In15.Cu")
		(hatch none 0.5)
		(connect_pads
			(clearance 0)
		)
		(min_thickness 0.25)
		(keepout
			(tracks not_allowed)
			(vias allowed)
			(pads allowed)
			(copperpour not_allowed)
			(footprints allowed)
		)
		(placement
			(enabled no)
			(sheetname "")
		)
		(fill yes
			(thermal_gap 0.5)
			(thermal_bridge_width 0.5)
			(island_removal_mode 0)
		)
		(polygon
			(pts
				(arc
					(start 22.04212 -216.035382)
					(mid 21.3741 -216.035382)
					(end 22.04212 -216.035382)
				)
			)
		)
	)
	(zone
		(layers "B.Cu" "In13.Cu" "In15.Cu")
		(hatch none 0.5)
		(connect_pads
			(clearance 0)
		)
		(min_thickness 0.25)
		(keepout
			(tracks not_allowed)
			(vias allowed)
			(pads allowed)
			(copperpour not_allowed)
			(footprints allowed)
		)
		(placement
			(enabled no)
			(sheetname "")
		)
		(fill yes
			(thermal_gap 0.5)
			(thermal_bridge_width 0.5)
			(island_removal_mode 0)
		)
		(polygon
			(pts
				(arc
					(start 84.3661 -237.194344)
					(mid 83.73618 -237.194344)
					(end 84.3661 -237.194344)
				)
			)
		)
	)
	(zone
		(layers "B.Cu" "In13.Cu" "In15.Cu")
		(hatch none 0.5)
		(connect_pads
			(clearance 0)
		)
		(min_thickness 0.25)
		(keepout
			(tracks not_allowed)
			(vias allowed)
			(pads allowed)
			(copperpour not_allowed)
			(footprints allowed)
		)
		(placement
			(enabled no)
			(sheetname "")
		)
		(fill yes
			(thermal_gap 0.5)
			(thermal_bridge_width 0.5)
			(island_removal_mode 0)
		)
		(polygon
			(pts
				(arc
					(start 206.58201 -242.385342)
					(mid 205.91399 -242.385342)
					(end 206.58201 -242.385342)
				)
			)
		)
	)
	(zone
		(layers "B.Cu" "In13.Cu" "In15.Cu")
		(hatch none 0.5)
		(connect_pads
			(clearance 0)
		)
		(min_thickness 0.25)
		(keepout
			(tracks not_allowed)
			(vias allowed)
			(pads allowed)
			(copperpour not_allowed)
			(footprints allowed)
		)
		(placement
			(enabled no)
			(sheetname "")
		)
		(fill yes
			(thermal_gap 0.5)
			(thermal_bridge_width 0.5)
			(island_removal_mode 0)
		)
		(polygon
			(pts
				(arc
					(start 140.119608 -278.946356)
					(mid 139.489688 -278.946356)
					(end 140.119608 -278.946356)
				)
			)
		)
	)
	(zone
		(layers "B.Cu" "In13.Cu" "In15.Cu")
		(hatch none 0.5)
		(connect_pads
			(clearance 0)
		)
		(min_thickness 0.25)
		(keepout
			(tracks not_allowed)
			(vias allowed)
			(pads allowed)
			(copperpour not_allowed)
			(footprints allowed)
		)
		(placement
			(enabled no)
			(sheetname "")
		)
		(fill yes
			(thermal_gap 0.5)
			(thermal_bridge_width 0.5)
			(island_removal_mode 0)
		)
		(polygon
			(pts
				(arc
					(start 332.606142 -277.32609)
					(mid 331.976222 -277.32609)
					(end 332.606142 -277.32609)
				)
			)
		)
	)
	(zone
		(layers "B.Cu" "In13.Cu" "In15.Cu")
		(hatch none 0.5)
		(connect_pads
			(clearance 0)
		)
		(min_thickness 0.25)
		(keepout
			(tracks not_allowed)
			(vias allowed)
			(pads allowed)
			(copperpour not_allowed)
			(footprints allowed)
		)
		(placement
			(enabled no)
			(sheetname "")
		)
		(fill yes
			(thermal_gap 0.5)
			(thermal_bridge_width 0.5)
			(island_removal_mode 0)
		)
		(polygon
			(pts
				(arc
					(start 372.091712 -420.952168)
					(mid 371.423692 -420.952168)
					(end 372.091712 -420.952168)
				)
			)
		)
	)
	(zone
		(layers "B.Cu" "In13.Cu" "In15.Cu")
		(hatch none 0.5)
		(connect_pads
			(clearance 0)
		)
		(min_thickness 0.25)
		(keepout
			(tracks not_allowed)
			(vias allowed)
			(pads allowed)
			(copperpour not_allowed)
			(footprints allowed)
		)
		(placement
			(enabled no)
			(sheetname "")
		)
		(fill yes
			(thermal_gap 0.5)
			(thermal_bridge_width 0.5)
			(island_removal_mode 0)
		)
		(polygon
			(pts
				(arc
					(start 206.58201 -254.285242)
					(mid 205.91399 -254.285242)
					(end 206.58201 -254.285242)
				)
			)
		)
	)
	(zone
		(layers "B.Cu" "In13.Cu" "In15.Cu")
		(hatch none 0.5)
		(connect_pads
			(clearance 0)
		)
		(min_thickness 0.25)
		(keepout
			(tracks not_allowed)
			(vias allowed)
			(pads allowed)
			(copperpour not_allowed)
			(footprints allowed)
		)
		(placement
			(enabled no)
			(sheetname "")
		)
		(fill yes
			(thermal_gap 0.5)
			(thermal_bridge_width 0.5)
			(island_removal_mode 0)
		)
		(polygon
			(pts
				(arc
					(start 405.787352 -420.952168)
					(mid 405.119332 -420.952168)
					(end 405.787352 -420.952168)
				)
			)
		)
	)
	(zone
		(layers "B.Cu" "In13.Cu" "In15.Cu")
		(hatch none 0.5)
		(connect_pads
			(clearance 0)
		)
		(min_thickness 0.25)
		(keepout
			(tracks not_allowed)
			(vias allowed)
			(pads allowed)
			(copperpour not_allowed)
			(footprints allowed)
		)
		(placement
			(enabled no)
			(sheetname "")
		)
		(fill yes
			(thermal_gap 0.5)
			(thermal_bridge_width 0.5)
			(island_removal_mode 0)
		)
		(polygon
			(pts
				(arc
					(start 206.58201 -264.485374)
					(mid 205.91399 -264.485374)
					(end 206.58201 -264.485374)
				)
			)
		)
	)
	(zone
		(layers "B.Cu" "In13.Cu" "In15.Cu")
		(hatch none 0.5)
		(connect_pads
			(clearance 0)
		)
		(min_thickness 0.25)
		(keepout
			(tracks not_allowed)
			(vias allowed)
			(pads allowed)
			(copperpour not_allowed)
			(footprints allowed)
		)
		(placement
			(enabled no)
			(sheetname "")
		)
		(fill yes
			(thermal_gap 0.5)
			(thermal_bridge_width 0.5)
			(island_removal_mode 0)
		)
		(polygon
			(pts
				(arc
					(start 269.982188 -269.585186)
					(mid 269.314168 -269.585186)
					(end 269.982188 -269.585186)
				)
			)
		)
	)
	(zone
		(layers "B.Cu" "In13.Cu" "In15.Cu")
		(hatch none 0.5)
		(connect_pads
			(clearance 0)
		)
		(min_thickness 0.25)
		(keepout
			(tracks not_allowed)
			(vias allowed)
			(pads allowed)
			(copperpour not_allowed)
			(footprints allowed)
		)
		(placement
			(enabled no)
			(sheetname "")
		)
		(fill yes
			(thermal_gap 0.5)
			(thermal_bridge_width 0.5)
			(island_removal_mode 0)
		)
		(polygon
			(pts
				(arc
					(start 140.119608 -275.706332)
					(mid 139.489688 -275.706332)
					(end 140.119608 -275.706332)
				)
			)
		)
	)
	(zone
		(layers "B.Cu" "In13.Cu" "In15.Cu")
		(hatch none 0.5)
		(connect_pads
			(clearance 0)
		)
		(min_thickness 0.25)
		(keepout
			(tracks not_allowed)
			(vias allowed)
			(pads allowed)
			(copperpour not_allowed)
			(footprints allowed)
		)
		(placement
			(enabled no)
			(sheetname "")
		)
		(fill yes
			(thermal_gap 0.5)
			(thermal_bridge_width 0.5)
			(island_removal_mode 0)
		)
		(polygon
			(pts
				(arc
					(start 333.076042 -279.756108)
					(mid 332.446122 -279.756108)
					(end 333.076042 -279.756108)
				)
			)
		)
	)
	(zone
		(layers "B.Cu" "In13.Cu" "In15.Cu")
		(hatch none 0.5)
		(connect_pads
			(clearance 0)
		)
		(min_thickness 0.25)
		(keepout
			(tracks not_allowed)
			(vias allowed)
			(pads allowed)
			(copperpour not_allowed)
			(footprints allowed)
		)
		(placement
			(enabled no)
			(sheetname "")
		)
		(fill yes
			(thermal_gap 0.5)
			(thermal_bridge_width 0.5)
			(island_removal_mode 0)
		)
		(polygon
			(pts
				(arc
					(start 387.289802 -231.524048)
					(mid 386.659882 -231.524048)
					(end 387.289802 -231.524048)
				)
			)
		)
	)
	(zone
		(layers "B.Cu" "In13.Cu" "In15.Cu")
		(hatch none 0.5)
		(connect_pads
			(clearance 0)
		)
		(min_thickness 0.25)
		(keepout
			(tracks not_allowed)
			(vias allowed)
			(pads allowed)
			(copperpour not_allowed)
			(footprints allowed)
		)
		(placement
			(enabled no)
			(sheetname "")
		)
		(fill yes
			(thermal_gap 0.5)
			(thermal_bridge_width 0.5)
			(island_removal_mode 0)
		)
		(polygon
			(pts
				(arc
					(start 139.819634 -227.474526)
					(mid 139.189714 -227.474526)
					(end 139.819634 -227.474526)
				)
			)
		)
	)
	(zone
		(layers "B.Cu" "In13.Cu" "In15.Cu")
		(hatch none 0.5)
		(connect_pads
			(clearance 0)
		)
		(min_thickness 0.25)
		(keepout
			(tracks not_allowed)
			(vias allowed)
			(pads allowed)
			(copperpour not_allowed)
			(footprints allowed)
		)
		(placement
			(enabled no)
			(sheetname "")
		)
		(fill yes
			(thermal_gap 0.5)
			(thermal_bridge_width 0.5)
			(island_removal_mode 0)
		)
		(polygon
			(pts
				(arc
					(start 269.982188 -272.135092)
					(mid 269.314168 -272.135092)
					(end 269.982188 -272.135092)
				)
			)
		)
	)
	(zone
		(layers "B.Cu" "In13.Cu" "In15.Cu")
		(hatch none 0.5)
		(connect_pads
			(clearance 0)
		)
		(min_thickness 0.25)
		(keepout
			(tracks not_allowed)
			(vias allowed)
			(pads allowed)
			(copperpour not_allowed)
			(footprints allowed)
		)
		(placement
			(enabled no)
			(sheetname "")
		)
		(fill yes
			(thermal_gap 0.5)
			(thermal_bridge_width 0.5)
			(island_removal_mode 0)
		)
		(polygon
			(pts
				(arc
					(start 118.029736 -279.756362)
					(mid 117.399816 -279.756362)
					(end 118.029736 -279.756362)
				)
			)
		)
	)
	(zone
		(layers "B.Cu" "In13.Cu" "In15.Cu")
		(hatch none 0.5)
		(connect_pads
			(clearance 0)
		)
		(min_thickness 0.25)
		(keepout
			(tracks not_allowed)
			(vias allowed)
			(pads allowed)
			(copperpour not_allowed)
			(footprints allowed)
		)
		(placement
			(enabled no)
			(sheetname "")
		)
		(fill yes
			(thermal_gap 0.5)
			(thermal_bridge_width 0.5)
			(island_removal_mode 0)
		)
		(polygon
			(pts
				(arc
					(start 138.709654 -265.176254)
					(mid 138.079734 -265.176254)
					(end 138.709654 -265.176254)
				)
			)
		)
	)
	(zone
		(layers "B.Cu" "In13.Cu" "In15.Cu")
		(hatch none 0.5)
		(connect_pads
			(clearance 0)
		)
		(min_thickness 0.25)
		(keepout
			(tracks not_allowed)
			(vias allowed)
			(pads allowed)
			(copperpour not_allowed)
			(footprints allowed)
		)
		(placement
			(enabled no)
			(sheetname "")
		)
		(fill yes
			(thermal_gap 0.5)
			(thermal_bridge_width 0.5)
			(island_removal_mode 0)
		)
		(polygon
			(pts
				(arc
					(start 86.245954 -229.094538)
					(mid 85.616034 -229.094538)
					(end 86.245954 -229.094538)
				)
			)
		)
	)
	(zone
		(layers "B.Cu" "In13.Cu" "In15.Cu")
		(hatch none 0.5)
		(connect_pads
			(clearance 0)
		)
		(min_thickness 0.25)
		(keepout
			(tracks not_allowed)
			(vias allowed)
			(pads allowed)
			(copperpour not_allowed)
			(footprints allowed)
		)
		(placement
			(enabled no)
			(sheetname "")
		)
		(fill yes
			(thermal_gap 0.5)
			(thermal_bridge_width 0.5)
			(island_removal_mode 0)
		)
		(polygon
			(pts
				(arc
					(start 138.709654 -263.556242)
					(mid 138.079734 -263.556242)
					(end 138.709654 -263.556242)
				)
			)
		)
	)
	(zone
		(layers "B.Cu" "In13.Cu" "In15.Cu")
		(hatch none 0.5)
		(connect_pads
			(clearance 0)
		)
		(min_thickness 0.25)
		(keepout
			(tracks not_allowed)
			(vias allowed)
			(pads allowed)
			(copperpour not_allowed)
			(footprints allowed)
		)
		(placement
			(enabled no)
			(sheetname "")
		)
		(fill yes
			(thermal_gap 0.5)
			(thermal_bridge_width 0.5)
			(island_removal_mode 0)
		)
		(polygon
			(pts
				(arc
					(start 202.481942 -308.685438)
					(mid 201.813922 -308.685438)
					(end 202.481942 -308.685438)
				)
			)
		)
	)
	(zone
		(layers "B.Cu" "In13.Cu" "In15.Cu")
		(hatch none 0.5)
		(connect_pads
			(clearance 0)
		)
		(min_thickness 0.25)
		(keepout
			(tracks not_allowed)
			(vias allowed)
			(pads allowed)
			(copperpour not_allowed)
			(footprints allowed)
		)
		(placement
			(enabled no)
			(sheetname "")
		)
		(fill yes
			(thermal_gap 0.5)
			(thermal_bridge_width 0.5)
			(island_removal_mode 0)
		)
		(polygon
			(pts
				(arc
					(start 17.942052 -227.935282)
					(mid 17.274032 -227.935282)
					(end 17.942052 -227.935282)
				)
			)
		)
	)
	(zone
		(layers "B.Cu" "In13.Cu" "In15.Cu")
		(hatch none 0.5)
		(connect_pads
			(clearance 0)
		)
		(min_thickness 0.25)
		(keepout
			(tracks not_allowed)
			(vias allowed)
			(pads allowed)
			(copperpour not_allowed)
			(footprints allowed)
		)
		(placement
			(enabled no)
			(sheetname "")
		)
		(fill yes
			(thermal_gap 0.5)
			(thermal_bridge_width 0.5)
			(island_removal_mode 0)
		)
		(polygon
			(pts
				(arc
					(start 399.254218 -4.963414)
					(mid 398.586198 -4.963414)
					(end 399.254218 -4.963414)
				)
			)
		)
	)
	(zone
		(layers "B.Cu" "In13.Cu" "In15.Cu")
		(hatch none 0.5)
		(connect_pads
			(clearance 0)
		)
		(min_thickness 0.25)
		(keepout
			(tracks not_allowed)
			(vias allowed)
			(pads allowed)
			(copperpour not_allowed)
			(footprints allowed)
		)
		(placement
			(enabled no)
			(sheetname "")
		)
		(fill yes
			(thermal_gap 0.5)
			(thermal_bridge_width 0.5)
			(island_removal_mode 0)
		)
		(polygon
			(pts
				(arc
					(start 140.119608 -290.286186)
					(mid 139.489688 -290.286186)
					(end 140.119608 -290.286186)
				)
			)
		)
	)
	(zone
		(layers "B.Cu" "In13.Cu" "In15.Cu")
		(hatch none 0.5)
		(connect_pads
			(clearance 0)
		)
		(min_thickness 0.25)
		(keepout
			(tracks not_allowed)
			(vias allowed)
			(pads allowed)
			(copperpour not_allowed)
			(footprints allowed)
		)
		(placement
			(enabled no)
			(sheetname "")
		)
		(fill yes
			(thermal_gap 0.5)
			(thermal_bridge_width 0.5)
			(island_removal_mode 0)
		)
		(polygon
			(pts
				(arc
					(start 265.88212 -288.285174)
					(mid 265.2141 -288.285174)
					(end 265.88212 -288.285174)
				)
			)
		)
	)
	(zone
		(layers "B.Cu" "In13.Cu" "In15.Cu")
		(hatch none 0.5)
		(connect_pads
			(clearance 0)
		)
		(min_thickness 0.25)
		(keepout
			(tracks not_allowed)
			(vias allowed)
			(pads allowed)
			(copperpour not_allowed)
			(footprints allowed)
		)
		(placement
			(enabled no)
			(sheetname "")
		)
		(fill yes
			(thermal_gap 0.5)
			(thermal_bridge_width 0.5)
			(island_removal_mode 0)
		)
		(polygon
			(pts
				(arc
					(start 334.016096 -270.036036)
					(mid 333.386176 -270.036036)
					(end 334.016096 -270.036036)
				)
			)
		)
	)
	(zone
		(layers "B.Cu" "In13.Cu" "In15.Cu")
		(hatch none 0.5)
		(connect_pads
			(clearance 0)
		)
		(min_thickness 0.25)
		(keepout
			(tracks not_allowed)
			(vias allowed)
			(pads allowed)
			(copperpour not_allowed)
			(footprints allowed)
		)
		(placement
			(enabled no)
			(sheetname "")
		)
		(fill yes
			(thermal_gap 0.5)
			(thermal_bridge_width 0.5)
			(island_removal_mode 0)
		)
		(polygon
			(pts
				(arc
					(start 206.58201 -272.135346)
					(mid 205.91399 -272.135346)
					(end 206.58201 -272.135346)
				)
			)
		)
	)
	(zone
		(layers "B.Cu" "In13.Cu" "In15.Cu")
		(hatch none 0.5)
		(connect_pads
			(clearance 0)
		)
		(min_thickness 0.25)
		(keepout
			(tracks not_allowed)
			(vias allowed)
			(pads allowed)
			(copperpour not_allowed)
			(footprints allowed)
		)
		(placement
			(enabled no)
			(sheetname "")
		)
		(fill yes
			(thermal_gap 0.5)
			(thermal_bridge_width 0.5)
			(island_removal_mode 0)
		)
		(polygon
			(pts
				(arc
					(start 454.522078 -254.284988)
					(mid 453.854058 -254.284988)
					(end 454.522078 -254.284988)
				)
			)
		)
	)
	(zone
		(layers "B.Cu" "In13.Cu" "In15.Cu")
		(hatch none 0.5)
		(connect_pads
			(clearance 0)
		)
		(min_thickness 0.25)
		(keepout
			(tracks not_allowed)
			(vias allowed)
			(pads allowed)
			(copperpour not_allowed)
			(footprints allowed)
		)
		(placement
			(enabled no)
			(sheetname "")
		)
		(fill yes
			(thermal_gap 0.5)
			(thermal_bridge_width 0.5)
			(island_removal_mode 0)
		)
		(polygon
			(pts
				(arc
					(start 364.86465 -385.21386)
					(mid 364.19663 -385.21386)
					(end 364.86465 -385.21386)
				)
			)
		)
	)
	(zone
		(layers "B.Cu" "In13.Cu" "In15.Cu")
		(hatch none 0.5)
		(connect_pads
			(clearance 0)
		)
		(min_thickness 0.25)
		(keepout
			(tracks not_allowed)
			(vias allowed)
			(pads allowed)
			(copperpour not_allowed)
			(footprints allowed)
		)
		(placement
			(enabled no)
			(sheetname "")
		)
		(fill yes
			(thermal_gap 0.5)
			(thermal_bridge_width 0.5)
			(island_removal_mode 0)
		)
		(polygon
			(pts
				(arc
					(start 334.016096 -281.37612)
					(mid 333.386176 -281.37612)
					(end 334.016096 -281.37612)
				)
			)
		)
	)
	(zone
		(layers "B.Cu" "In13.Cu" "In15.Cu")
		(hatch none 0.5)
		(connect_pads
			(clearance 0)
		)
		(min_thickness 0.25)
		(keepout
			(tracks not_allowed)
			(vias allowed)
			(pads allowed)
			(copperpour not_allowed)
			(footprints allowed)
		)
		(placement
			(enabled no)
			(sheetname "")
		)
		(fill yes
			(thermal_gap 0.5)
			(thermal_bridge_width 0.5)
			(island_removal_mode 0)
		)
		(polygon
			(pts
				(arc
					(start 126.18974 -236.384338)
					(mid 125.55982 -236.384338)
					(end 126.18974 -236.384338)
				)
			)
		)
	)
	(zone
		(layers "B.Cu" "In13.Cu" "In15.Cu")
		(hatch none 0.5)
		(connect_pads
			(clearance 0)
		)
		(min_thickness 0.25)
		(keepout
			(tracks not_allowed)
			(vias allowed)
			(pads allowed)
			(copperpour not_allowed)
			(footprints allowed)
		)
		(placement
			(enabled no)
			(sheetname "")
		)
		(fill yes
			(thermal_gap 0.5)
			(thermal_bridge_width 0.5)
			(island_removal_mode 0)
		)
		(polygon
			(pts
				(arc
					(start 401.860512 -420.952168)
					(mid 401.192492 -420.952168)
					(end 401.860512 -420.952168)
				)
			)
		)
	)
	(zone
		(layers "B.Cu" "In13.Cu" "In15.Cu")
		(hatch none 0.5)
		(connect_pads
			(clearance 0)
		)
		(min_thickness 0.25)
		(keepout
			(tracks not_allowed)
			(vias allowed)
			(pads allowed)
			(copperpour not_allowed)
			(footprints allowed)
		)
		(placement
			(enabled no)
			(sheetname "")
		)
		(fill yes
			(thermal_gap 0.5)
			(thermal_bridge_width 0.5)
			(island_removal_mode 0)
		)
		(polygon
			(pts
				(arc
					(start 206.58201 -281.48534)
					(mid 205.91399 -281.48534)
					(end 206.58201 -281.48534)
				)
			)
		)
	)
	(zone
		(layers "B.Cu" "In13.Cu" "In15.Cu")
		(hatch none 0.5)
		(connect_pads
			(clearance 0)
		)
		(min_thickness 0.25)
		(keepout
			(tracks not_allowed)
			(vias allowed)
			(pads allowed)
			(copperpour not_allowed)
			(footprints allowed)
		)
		(placement
			(enabled no)
			(sheetname "")
		)
		(fill yes
			(thermal_gap 0.5)
			(thermal_bridge_width 0.5)
			(island_removal_mode 0)
		)
		(polygon
			(pts
				(arc
					(start 117.089682 -274.896326)
					(mid 116.459762 -274.896326)
					(end 117.089682 -274.896326)
				)
			)
		)
	)
	(zone
		(layers "B.Cu" "In13.Cu" "In15.Cu")
		(hatch none 0.5)
		(connect_pads
			(clearance 0)
		)
		(min_thickness 0.25)
		(keepout
			(tracks not_allowed)
			(vias allowed)
			(pads allowed)
			(copperpour not_allowed)
			(footprints allowed)
		)
		(placement
			(enabled no)
			(sheetname "")
		)
		(fill yes
			(thermal_gap 0.5)
			(thermal_bridge_width 0.5)
			(island_removal_mode 0)
		)
		(polygon
			(pts
				(arc
					(start 367.549684 -244.484144)
					(mid 366.919764 -244.484144)
					(end 367.549684 -244.484144)
				)
			)
		)
	)
	(zone
		(layers "B.Cu" "In13.Cu" "In15.Cu")
		(hatch none 0.5)
		(connect_pads
			(clearance 0)
		)
		(min_thickness 0.25)
		(keepout
			(tracks not_allowed)
			(vias allowed)
			(pads allowed)
			(copperpour not_allowed)
			(footprints allowed)
		)
		(placement
			(enabled no)
			(sheetname "")
		)
		(fill yes
			(thermal_gap 0.5)
			(thermal_bridge_width 0.5)
			(island_removal_mode 0)
		)
		(polygon
			(pts
				(arc
					(start 114.739674 -275.706332)
					(mid 114.109754 -275.706332)
					(end 114.739674 -275.706332)
				)
			)
		)
	)
	(zone
		(layers "B.Cu" "In13.Cu" "In15.Cu")
		(hatch none 0.5)
		(connect_pads
			(clearance 0)
		)
		(min_thickness 0.25)
		(keepout
			(tracks not_allowed)
			(vias allowed)
			(pads allowed)
			(copperpour not_allowed)
			(footprints allowed)
		)
		(placement
			(enabled no)
			(sheetname "")
		)
		(fill yes
			(thermal_gap 0.5)
			(thermal_bridge_width 0.5)
			(island_removal_mode 0)
		)
		(polygon
			(pts
				(arc
					(start 450.42201 -267.035026)
					(mid 449.75399 -267.035026)
					(end 450.42201 -267.035026)
				)
			)
		)
	)
	(zone
		(layers "B.Cu" "In13.Cu" "In15.Cu")
		(hatch none 0.5)
		(connect_pads
			(clearance 0)
		)
		(min_thickness 0.25)
		(keepout
			(tracks not_allowed)
			(vias allowed)
			(pads allowed)
			(copperpour not_allowed)
			(footprints allowed)
		)
		(placement
			(enabled no)
			(sheetname "")
		)
		(fill yes
			(thermal_gap 0.5)
			(thermal_bridge_width 0.5)
			(island_removal_mode 0)
		)
		(polygon
			(pts
				(arc
					(start 332.776068 -244.484144)
					(mid 332.146148 -244.484144)
					(end 332.776068 -244.484144)
				)
			)
		)
	)
	(zone
		(layers "B.Cu" "In13.Cu" "In15.Cu")
		(hatch none 0.5)
		(connect_pads
			(clearance 0)
		)
		(min_thickness 0.25)
		(keepout
			(tracks not_allowed)
			(vias allowed)
			(pads allowed)
			(copperpour not_allowed)
			(footprints allowed)
		)
		(placement
			(enabled no)
			(sheetname "")
		)
		(fill yes
			(thermal_gap 0.5)
			(thermal_bridge_width 0.5)
			(island_removal_mode 0)
		)
		(polygon
			(pts
				(arc
					(start 109.105954 -278.946356)
					(mid 108.476034 -278.946356)
					(end 109.105954 -278.946356)
				)
			)
		)
	)
	(zone
		(layers "B.Cu" "In13.Cu" "In15.Cu")
		(hatch none 0.5)
		(connect_pads
			(clearance 0)
		)
		(min_thickness 0.25)
		(keepout
			(tracks not_allowed)
			(vias allowed)
			(pads allowed)
			(copperpour not_allowed)
			(footprints allowed)
		)
		(placement
			(enabled no)
			(sheetname "")
		)
		(fill yes
			(thermal_gap 0.5)
			(thermal_bridge_width 0.5)
			(island_removal_mode 0)
		)
		(polygon
			(pts
				(arc
					(start 373.489728 -274.896072)
					(mid 372.859808 -274.896072)
					(end 373.489728 -274.896072)
				)
			)
		)
	)
	(zone
		(layers "B.Cu" "In13.Cu" "In15.Cu")
		(hatch none 0.5)
		(connect_pads
			(clearance 0)
		)
		(min_thickness 0.25)
		(keepout
			(tracks not_allowed)
			(vias allowed)
			(pads allowed)
			(copperpour not_allowed)
			(footprints allowed)
		)
		(placement
			(enabled no)
			(sheetname "")
		)
		(fill yes
			(thermal_gap 0.5)
			(thermal_bridge_width 0.5)
			(island_removal_mode 0)
		)
		(polygon
			(pts
				(arc
					(start 344.036904 -429.689768)
					(mid 343.262712 -429.689768)
					(end 344.036904 -429.689768)
				)
			)
		)
	)
	(zone
		(layers "B.Cu" "In13.Cu" "In15.Cu")
		(hatch none 0.5)
		(connect_pads
			(clearance 0)
		)
		(min_thickness 0.25)
		(keepout
			(tracks not_allowed)
			(vias allowed)
			(pads allowed)
			(copperpour not_allowed)
			(footprints allowed)
		)
		(placement
			(enabled no)
			(sheetname "")
		)
		(fill yes
			(thermal_gap 0.5)
			(thermal_bridge_width 0.5)
			(island_removal_mode 0)
		)
		(polygon
			(pts
				(arc
					(start 346.0369 -430.689766)
					(mid 345.262708 -430.689766)
					(end 346.0369 -430.689766)
				)
			)
		)
	)
	(zone
		(layers "B.Cu" "In13.Cu" "In15.Cu")
		(hatch none 0.5)
		(connect_pads
			(clearance 0)
		)
		(min_thickness 0.25)
		(keepout
			(tracks not_allowed)
			(vias allowed)
			(pads allowed)
			(copperpour not_allowed)
			(footprints allowed)
		)
		(placement
			(enabled no)
			(sheetname "")
		)
		(fill yes
			(thermal_gap 0.5)
			(thermal_bridge_width 0.5)
			(island_removal_mode 0)
		)
		(polygon
			(pts
				(arc
					(start 119.154956 -412.570168)
					(mid 118.486936 -412.570168)
					(end 119.154956 -412.570168)
				)
			)
		)
	)
	(zone
		(layers "B.Cu" "In13.Cu" "In15.Cu")
		(hatch none 0.5)
		(connect_pads
			(clearance 0)
		)
		(min_thickness 0.25)
		(keepout
			(tracks not_allowed)
			(vias allowed)
			(pads allowed)
			(copperpour not_allowed)
			(footprints allowed)
		)
		(placement
			(enabled no)
			(sheetname "")
		)
		(fill yes
			(thermal_gap 0.5)
			(thermal_bridge_width 0.5)
			(island_removal_mode 0)
		)
		(polygon
			(pts
				(arc
					(start 354.696014 -274.896072)
					(mid 354.066094 -274.896072)
					(end 354.696014 -274.896072)
				)
			)
		)
	)
	(zone
		(layers "B.Cu" "In13.Cu" "In15.Cu")
		(hatch none 0.5)
		(connect_pads
			(clearance 0)
		)
		(min_thickness 0.25)
		(keepout
			(tracks not_allowed)
			(vias allowed)
			(pads allowed)
			(copperpour not_allowed)
			(footprints allowed)
		)
		(placement
			(enabled no)
			(sheetname "")
		)
		(fill yes
			(thermal_gap 0.5)
			(thermal_bridge_width 0.5)
			(island_removal_mode 0)
		)
		(polygon
			(pts
				(arc
					(start 85.135974 -276.516338)
					(mid 84.506054 -276.516338)
					(end 85.135974 -276.516338)
				)
			)
		)
	)
	(zone
		(layers "B.Cu" "In13.Cu" "In15.Cu")
		(hatch none 0.5)
		(connect_pads
			(clearance 0)
		)
		(min_thickness 0.25)
		(keepout
			(tracks not_allowed)
			(vias allowed)
			(pads allowed)
			(copperpour not_allowed)
			(footprints allowed)
		)
		(placement
			(enabled no)
			(sheetname "")
		)
		(fill yes
			(thermal_gap 0.5)
			(thermal_bridge_width 0.5)
			(island_removal_mode 0)
		)
		(polygon
			(pts
				(arc
					(start 332.776068 -236.384084)
					(mid 332.146148 -236.384084)
					(end 332.776068 -236.384084)
				)
			)
		)
	)
	(zone
		(layers "B.Cu" "In13.Cu" "In15.Cu")
		(hatch none 0.5)
		(connect_pads
			(clearance 0)
		)
		(min_thickness 0.25)
		(keepout
			(tracks not_allowed)
			(vias allowed)
			(pads allowed)
			(copperpour not_allowed)
			(footprints allowed)
		)
		(placement
			(enabled no)
			(sheetname "")
		)
		(fill yes
			(thermal_gap 0.5)
			(thermal_bridge_width 0.5)
			(island_removal_mode 0)
		)
		(polygon
			(pts
				(arc
					(start 58.11774 -19.13636)
					(mid 57.44972 -19.13636)
					(end 58.11774 -19.13636)
				)
			)
		)
	)
	(zone
		(layers "B.Cu" "In13.Cu" "In15.Cu")
		(hatch none 0.5)
		(connect_pads
			(clearance 0)
		)
		(min_thickness 0.25)
		(keepout
			(tracks not_allowed)
			(vias allowed)
			(pads allowed)
			(copperpour not_allowed)
			(footprints allowed)
		)
		(placement
			(enabled no)
			(sheetname "")
		)
		(fill yes
			(thermal_gap 0.5)
			(thermal_bridge_width 0.5)
			(island_removal_mode 0)
		)
		(polygon
			(pts
				(arc
					(start 387.759702 -229.094284)
					(mid 387.129782 -229.094284)
					(end 387.759702 -229.094284)
				)
			)
		)
	)
	(zone
		(layers "B.Cu" "In13.Cu" "In15.Cu")
		(hatch none 0.5)
		(connect_pads
			(clearance 0)
		)
		(min_thickness 0.25)
		(keepout
			(tracks not_allowed)
			(vias allowed)
			(pads allowed)
			(copperpour not_allowed)
			(footprints allowed)
		)
		(placement
			(enabled no)
			(sheetname "")
		)
		(fill yes
			(thermal_gap 0.5)
			(thermal_bridge_width 0.5)
			(island_removal_mode 0)
		)
		(polygon
			(pts
				(arc
					(start 450.42201 -215.18499)
					(mid 449.75399 -215.18499)
					(end 450.42201 -215.18499)
				)
			)
		)
	)
	(zone
		(layers "B.Cu" "In13.Cu" "In15.Cu")
		(hatch none 0.5)
		(connect_pads
			(clearance 0)
		)
		(min_thickness 0.25)
		(keepout
			(tracks not_allowed)
			(vias allowed)
			(pads allowed)
			(copperpour not_allowed)
			(footprints allowed)
		)
		(placement
			(enabled no)
			(sheetname "")
		)
		(fill yes
			(thermal_gap 0.5)
			(thermal_bridge_width 0.5)
			(island_removal_mode 0)
		)
		(polygon
			(pts
				(arc
					(start 110.046008 -275.706332)
					(mid 109.416088 -275.706332)
					(end 110.046008 -275.706332)
				)
			)
		)
	)
	(zone
		(layers "B.Cu" "In13.Cu" "In15.Cu")
		(hatch none 0.5)
		(connect_pads
			(clearance 0)
		)
		(min_thickness 0.25)
		(keepout
			(tracks not_allowed)
			(vias allowed)
			(pads allowed)
			(copperpour not_allowed)
			(footprints allowed)
		)
		(placement
			(enabled no)
			(sheetname "")
		)
		(fill yes
			(thermal_gap 0.5)
			(thermal_bridge_width 0.5)
			(island_removal_mode 0)
		)
		(polygon
			(pts
				(arc
					(start 206.58201 -238.985298)
					(mid 205.91399 -238.985298)
					(end 206.58201 -238.985298)
				)
			)
		)
	)
	(zone
		(layers "B.Cu" "In13.Cu" "In15.Cu")
		(hatch none 0.5)
		(connect_pads
			(clearance 0)
		)
		(min_thickness 0.25)
		(keepout
			(tracks not_allowed)
			(vias allowed)
			(pads allowed)
			(copperpour not_allowed)
			(footprints allowed)
		)
		(placement
			(enabled no)
			(sheetname "")
		)
		(fill yes
			(thermal_gap 0.5)
			(thermal_bridge_width 0.5)
			(island_removal_mode 0)
		)
		(polygon
			(pts
				(arc
					(start 17.942052 -280.635202)
					(mid 17.274032 -280.635202)
					(end 17.942052 -280.635202)
				)
			)
		)
	)
	(zone
		(layers "B.Cu" "In13.Cu" "In15.Cu")
		(hatch none 0.5)
		(connect_pads
			(clearance 0)
		)
		(min_thickness 0.25)
		(keepout
			(tracks not_allowed)
			(vias allowed)
			(pads allowed)
			(copperpour not_allowed)
			(footprints allowed)
		)
		(placement
			(enabled no)
			(sheetname "")
		)
		(fill yes
			(thermal_gap 0.5)
			(thermal_bridge_width 0.5)
			(island_removal_mode 0)
		)
		(polygon
			(pts
				(arc
					(start 102.05593 -278.13635)
					(mid 101.42601 -278.13635)
					(end 102.05593 -278.13635)
				)
			)
		)
	)
	(zone
		(layers "B.Cu" "In13.Cu" "In15.Cu")
		(hatch none 0.5)
		(connect_pads
			(clearance 0)
		)
		(min_thickness 0.25)
		(keepout
			(tracks not_allowed)
			(vias allowed)
			(pads allowed)
			(copperpour not_allowed)
			(footprints allowed)
		)
		(placement
			(enabled no)
			(sheetname "")
		)
		(fill yes
			(thermal_gap 0.5)
			(thermal_bridge_width 0.5)
			(island_removal_mode 0)
		)
		(polygon
			(pts
				(arc
					(start 139.819634 -229.094538)
					(mid 139.189714 -229.094538)
					(end 139.819634 -229.094538)
				)
			)
		)
	)
	(zone
		(layers "B.Cu" "In13.Cu" "In15.Cu")
		(hatch none 0.5)
		(connect_pads
			(clearance 0)
		)
		(min_thickness 0.25)
		(keepout
			(tracks not_allowed)
			(vias allowed)
			(pads allowed)
			(copperpour not_allowed)
			(footprints allowed)
		)
		(placement
			(enabled no)
			(sheetname "")
		)
		(fill yes
			(thermal_gap 0.5)
			(thermal_bridge_width 0.5)
			(island_removal_mode 0)
		)
		(polygon
			(pts
				(arc
					(start 387.759702 -230.714296)
					(mid 387.129782 -230.714296)
					(end 387.759702 -230.714296)
				)
			)
		)
	)
	(zone
		(layers "B.Cu" "In13.Cu" "In15.Cu")
		(hatch none 0.5)
		(connect_pads
			(clearance 0)
		)
		(min_thickness 0.25)
		(keepout
			(tracks not_allowed)
			(vias allowed)
			(pads allowed)
			(copperpour not_allowed)
			(footprints allowed)
		)
		(placement
			(enabled no)
			(sheetname "")
		)
		(fill yes
			(thermal_gap 0.5)
			(thermal_bridge_width 0.5)
			(island_removal_mode 0)
		)
		(polygon
			(pts
				(arc
					(start 139.819634 -248.534428)
					(mid 139.189714 -248.534428)
					(end 139.819634 -248.534428)
				)
			)
		)
	)
	(zone
		(layers "B.Cu" "In13.Cu" "In15.Cu")
		(hatch none 0.5)
		(connect_pads
			(clearance 0)
		)
		(min_thickness 0.25)
		(keepout
			(tracks not_allowed)
			(vias allowed)
			(pads allowed)
			(copperpour not_allowed)
			(footprints allowed)
		)
		(placement
			(enabled no)
			(sheetname "")
		)
		(fill yes
			(thermal_gap 0.5)
			(thermal_bridge_width 0.5)
			(island_removal_mode 0)
		)
		(polygon
			(pts
				(arc
					(start 265.88212 -216.885012)
					(mid 265.2141 -216.885012)
					(end 265.88212 -216.885012)
				)
			)
		)
	)
	(zone
		(layers "B.Cu" "In13.Cu" "In15.Cu")
		(hatch none 0.5)
		(connect_pads
			(clearance 0)
		)
		(min_thickness 0.25)
		(keepout
			(tracks not_allowed)
			(vias allowed)
			(pads allowed)
			(copperpour not_allowed)
			(footprints allowed)
		)
		(placement
			(enabled no)
			(sheetname "")
		)
		(fill yes
			(thermal_gap 0.5)
			(thermal_bridge_width 0.5)
			(island_removal_mode 0)
		)
		(polygon
			(pts
				(arc
					(start 269.982188 -250.884944)
					(mid 269.314168 -250.884944)
					(end 269.982188 -250.884944)
				)
			)
		)
	)
	(zone
		(layers "B.Cu" "In13.Cu" "In15.Cu")
		(hatch none 0.5)
		(connect_pads
			(clearance 0)
		)
		(min_thickness 0.25)
		(keepout
			(tracks not_allowed)
			(vias allowed)
			(pads allowed)
			(copperpour not_allowed)
			(footprints allowed)
		)
		(placement
			(enabled no)
			(sheetname "")
		)
		(fill yes
			(thermal_gap 0.5)
			(thermal_bridge_width 0.5)
			(island_removal_mode 0)
		)
		(polygon
			(pts
				(arc
					(start 121.354596 -412.570168)
					(mid 120.686576 -412.570168)
					(end 121.354596 -412.570168)
				)
			)
		)
	)
	(zone
		(layers "B.Cu" "In13.Cu" "In15.Cu")
		(hatch none 0.5)
		(connect_pads
			(clearance 0)
		)
		(min_thickness 0.25)
		(keepout
			(tracks not_allowed)
			(vias allowed)
			(pads allowed)
			(copperpour not_allowed)
			(footprints allowed)
		)
		(placement
			(enabled no)
			(sheetname "")
		)
		(fill yes
			(thermal_gap 0.5)
			(thermal_bridge_width 0.5)
			(island_removal_mode 0)
		)
		(polygon
			(pts
				(arc
					(start 374.129808 -247.724168)
					(mid 373.499888 -247.724168)
					(end 374.129808 -247.724168)
				)
			)
		)
	)
	(zone
		(layers "B.Cu" "In13.Cu" "In15.Cu")
		(hatch none 0.5)
		(connect_pads
			(clearance 0)
		)
		(min_thickness 0.25)
		(keepout
			(tracks not_allowed)
			(vias allowed)
			(pads allowed)
			(copperpour not_allowed)
			(footprints allowed)
		)
		(placement
			(enabled no)
			(sheetname "")
		)
		(fill yes
			(thermal_gap 0.5)
			(thermal_bridge_width 0.5)
			(island_removal_mode 0)
		)
		(polygon
			(pts
				(arc
					(start 405.137112 -430.689766)
					(mid 404.36292 -430.689766)
					(end 405.137112 -430.689766)
				)
			)
		)
	)
	(zone
		(layers "B.Cu" "In13.Cu" "In15.Cu")
		(hatch none 0.5)
		(connect_pads
			(clearance 0)
		)
		(min_thickness 0.25)
		(keepout
			(tracks not_allowed)
			(vias allowed)
			(pads allowed)
			(copperpour not_allowed)
			(footprints allowed)
		)
		(placement
			(enabled no)
			(sheetname "")
		)
		(fill yes
			(thermal_gap 0.5)
			(thermal_bridge_width 0.5)
			(island_removal_mode 0)
		)
		(polygon
			(pts
				(arc
					(start 17.942052 -221.135194)
					(mid 17.274032 -221.135194)
					(end 17.942052 -221.135194)
				)
			)
		)
	)
	(zone
		(layers "B.Cu" "In13.Cu" "In15.Cu")
		(hatch none 0.5)
		(connect_pads
			(clearance 0)
		)
		(min_thickness 0.25)
		(keepout
			(tracks not_allowed)
			(vias allowed)
			(pads allowed)
			(copperpour not_allowed)
			(footprints allowed)
		)
		(placement
			(enabled no)
			(sheetname "")
		)
		(fill yes
			(thermal_gap 0.5)
			(thermal_bridge_width 0.5)
			(island_removal_mode 0)
		)
		(polygon
			(pts
				(arc
					(start 86.545928 -285.426404)
					(mid 85.916008 -285.426404)
					(end 86.545928 -285.426404)
				)
			)
		)
	)
	(zone
		(layers "B.Cu" "In13.Cu" "In15.Cu")
		(hatch none 0.5)
		(connect_pads
			(clearance 0)
		)
		(min_thickness 0.25)
		(keepout
			(tracks not_allowed)
			(vias allowed)
			(pads allowed)
			(copperpour not_allowed)
			(footprints allowed)
		)
		(placement
			(enabled no)
			(sheetname "")
		)
		(fill yes
			(thermal_gap 0.5)
			(thermal_bridge_width 0.5)
			(island_removal_mode 0)
		)
		(polygon
			(pts
				(arc
					(start 348.75597 -233.14406)
					(mid 348.12605 -233.14406)
					(end 348.75597 -233.14406)
				)
			)
		)
	)
	(zone
		(layers "B.Cu" "In13.Cu" "In15.Cu")
		(hatch none 0.5)
		(connect_pads
			(clearance 0)
		)
		(min_thickness 0.25)
		(keepout
			(tracks not_allowed)
			(vias allowed)
			(pads allowed)
			(copperpour not_allowed)
			(footprints allowed)
		)
		(placement
			(enabled no)
			(sheetname "")
		)
		(fill yes
			(thermal_gap 0.5)
			(thermal_bridge_width 0.5)
			(island_removal_mode 0)
		)
		(polygon
			(pts
				(arc
					(start 139.349734 -252.584458)
					(mid 138.719814 -252.584458)
					(end 139.349734 -252.584458)
				)
			)
		)
	)
	(zone
		(layers "B.Cu" "In13.Cu" "In15.Cu")
		(hatch none 0.5)
		(connect_pads
			(clearance 0)
		)
		(min_thickness 0.25)
		(keepout
			(tracks not_allowed)
			(vias allowed)
			(pads allowed)
			(copperpour not_allowed)
			(footprints allowed)
		)
		(placement
			(enabled no)
			(sheetname "")
		)
		(fill yes
			(thermal_gap 0.5)
			(thermal_bridge_width 0.5)
			(island_removal_mode 0)
		)
		(polygon
			(pts
				(arc
					(start 202.481942 -301.035212)
					(mid 201.813922 -301.035212)
					(end 202.481942 -301.035212)
				)
			)
		)
	)
	(zone
		(layers "B.Cu" "In13.Cu" "In15.Cu")
		(hatch none 0.5)
		(connect_pads
			(clearance 0)
		)
		(min_thickness 0.25)
		(keepout
			(tracks not_allowed)
			(vias allowed)
			(pads allowed)
			(copperpour not_allowed)
			(footprints allowed)
		)
		(placement
			(enabled no)
			(sheetname "")
		)
		(fill yes
			(thermal_gap 0.5)
			(thermal_bridge_width 0.5)
			(island_removal_mode 0)
		)
		(polygon
			(pts
				(arc
					(start 265.88212 -235.585)
					(mid 265.2141 -235.585)
					(end 265.88212 -235.585)
				)
			)
		)
	)
	(zone
		(layers "B.Cu" "In13.Cu" "In15.Cu")
		(hatch none 0.5)
		(connect_pads
			(clearance 0)
		)
		(min_thickness 0.25)
		(keepout
			(tracks not_allowed)
			(vias allowed)
			(pads allowed)
			(copperpour not_allowed)
			(footprints allowed)
		)
		(placement
			(enabled no)
			(sheetname "")
		)
		(fill yes
			(thermal_gap 0.5)
			(thermal_bridge_width 0.5)
			(island_removal_mode 0)
		)
		(polygon
			(pts
				(arc
					(start 86.634066 -388.774432)
					(mid 86.004146 -388.774432)
					(end 86.634066 -388.774432)
				)
			)
		)
	)
	(zone
		(layers "B.Cu" "In13.Cu" "In15.Cu")
		(hatch none 0.5)
		(connect_pads
			(clearance 0)
		)
		(min_thickness 0.25)
		(keepout
			(tracks not_allowed)
			(vias allowed)
			(pads allowed)
			(copperpour not_allowed)
			(footprints allowed)
		)
		(placement
			(enabled no)
			(sheetname "")
		)
		(fill yes
			(thermal_gap 0.5)
			(thermal_bridge_width 0.5)
			(island_removal_mode 0)
		)
		(polygon
			(pts
				(arc
					(start 145.137124 -431.889916)
					(mid 144.362932 -431.889916)
					(end 145.137124 -431.889916)
				)
			)
		)
	)
	(zone
		(layers "B.Cu" "In13.Cu" "In15.Cu")
		(hatch none 0.5)
		(connect_pads
			(clearance 0)
		)
		(min_thickness 0.25)
		(keepout
			(tracks not_allowed)
			(vias allowed)
			(pads allowed)
			(copperpour not_allowed)
			(footprints allowed)
		)
		(placement
			(enabled no)
			(sheetname "")
		)
		(fill yes
			(thermal_gap 0.5)
			(thermal_bridge_width 0.5)
			(island_removal_mode 0)
		)
		(polygon
			(pts
				(arc
					(start 387.759702 -256.634234)
					(mid 387.129782 -256.634234)
					(end 387.759702 -256.634234)
				)
			)
		)
	)
	(zone
		(layers "B.Cu" "In13.Cu" "In15.Cu")
		(hatch none 0.5)
		(connect_pads
			(clearance 0)
		)
		(min_thickness 0.25)
		(keepout
			(tracks not_allowed)
			(vias allowed)
			(pads allowed)
			(copperpour not_allowed)
			(footprints allowed)
		)
		(placement
			(enabled no)
			(sheetname "")
		)
		(fill yes
			(thermal_gap 0.5)
			(thermal_bridge_width 0.5)
			(island_removal_mode 0)
		)
		(polygon
			(pts
				(arc
					(start 385.879848 -230.714296)
					(mid 385.249928 -230.714296)
					(end 385.879848 -230.714296)
				)
			)
		)
	)
	(zone
		(layers "B.Cu" "In13.Cu" "In15.Cu")
		(hatch none 0.5)
		(connect_pads
			(clearance 0)
		)
		(min_thickness 0.25)
		(keepout
			(tracks not_allowed)
			(vias allowed)
			(pads allowed)
			(copperpour not_allowed)
			(footprints allowed)
		)
		(placement
			(enabled no)
			(sheetname "")
		)
		(fill yes
			(thermal_gap 0.5)
			(thermal_bridge_width 0.5)
			(island_removal_mode 0)
		)
		(polygon
			(pts
				(arc
					(start 366.449102 -379.88113)
					(mid 365.781082 -379.88113)
					(end 366.449102 -379.88113)
				)
			)
		)
	)
	(zone
		(layers "B.Cu" "In13.Cu" "In15.Cu")
		(hatch none 0.5)
		(connect_pads
			(clearance 0)
		)
		(min_thickness 0.25)
		(keepout
			(tracks not_allowed)
			(vias allowed)
			(pads allowed)
			(copperpour not_allowed)
			(footprints allowed)
		)
		(placement
			(enabled no)
			(sheetname "")
		)
		(fill yes
			(thermal_gap 0.5)
			(thermal_bridge_width 0.5)
			(island_removal_mode 0)
		)
		(polygon
			(pts
				(arc
					(start 385.879848 -232.334054)
					(mid 385.249928 -232.334054)
					(end 385.879848 -232.334054)
				)
			)
		)
	)
	(zone
		(layers "B.Cu" "In13.Cu" "In15.Cu")
		(hatch none 0.5)
		(connect_pads
			(clearance 0)
		)
		(min_thickness 0.25)
		(keepout
			(tracks not_allowed)
			(vias allowed)
			(pads allowed)
			(copperpour not_allowed)
			(footprints allowed)
		)
		(placement
			(enabled no)
			(sheetname "")
		)
		(fill yes
			(thermal_gap 0.5)
			(thermal_bridge_width 0.5)
			(island_removal_mode 0)
		)
		(polygon
			(pts
				(arc
					(start 137.93978 -235.574332)
					(mid 137.30986 -235.574332)
					(end 137.93978 -235.574332)
				)
			)
		)
	)
	(zone
		(layers "B.Cu" "In13.Cu" "In15.Cu")
		(hatch none 0.5)
		(connect_pads
			(clearance 0)
		)
		(min_thickness 0.25)
		(keepout
			(tracks not_allowed)
			(vias allowed)
			(pads allowed)
			(copperpour not_allowed)
			(footprints allowed)
		)
		(placement
			(enabled no)
			(sheetname "")
		)
		(fill yes
			(thermal_gap 0.5)
			(thermal_bridge_width 0.5)
			(island_removal_mode 0)
		)
		(polygon
			(pts
				(arc
					(start 202.481942 -229.635304)
					(mid 201.813922 -229.635304)
					(end 202.481942 -229.635304)
				)
			)
		)
	)
	(zone
		(layers "B.Cu" "In13.Cu" "In15.Cu")
		(hatch none 0.5)
		(connect_pads
			(clearance 0)
		)
		(min_thickness 0.25)
		(keepout
			(tracks not_allowed)
			(vias allowed)
			(pads allowed)
			(copperpour not_allowed)
			(footprints allowed)
		)
		(placement
			(enabled no)
			(sheetname "")
		)
		(fill yes
			(thermal_gap 0.5)
			(thermal_bridge_width 0.5)
			(island_removal_mode 0)
		)
		(polygon
			(pts
				(arc
					(start 265.88212 -205.834996)
					(mid 265.2141 -205.834996)
					(end 265.88212 -205.834996)
				)
			)
		)
	)
	(zone
		(layers "B.Cu" "In13.Cu" "In15.Cu")
		(hatch none 0.5)
		(connect_pads
			(clearance 0)
		)
		(min_thickness 0.25)
		(keepout
			(tracks not_allowed)
			(vias allowed)
			(pads allowed)
			(copperpour not_allowed)
			(footprints allowed)
		)
		(placement
			(enabled no)
			(sheetname "")
		)
		(fill yes
			(thermal_gap 0.5)
			(thermal_bridge_width 0.5)
			(island_removal_mode 0)
		)
		(polygon
			(pts
				(arc
					(start 139.349734 -234.764326)
					(mid 138.719814 -234.764326)
					(end 139.349734 -234.764326)
				)
			)
		)
	)
	(zone
		(layers "B.Cu" "In13.Cu" "In15.Cu")
		(hatch none 0.5)
		(connect_pads
			(clearance 0)
		)
		(min_thickness 0.25)
		(keepout
			(tracks not_allowed)
			(vias allowed)
			(pads allowed)
			(copperpour not_allowed)
			(footprints allowed)
		)
		(placement
			(enabled no)
			(sheetname "")
		)
		(fill yes
			(thermal_gap 0.5)
			(thermal_bridge_width 0.5)
			(island_removal_mode 0)
		)
		(polygon
			(pts
				(arc
					(start 420.027862 -4.963414)
					(mid 419.359842 -4.963414)
					(end 420.027862 -4.963414)
				)
			)
		)
	)
	(zone
		(layers "B.Cu" "In13.Cu" "In15.Cu")
		(hatch none 0.5)
		(connect_pads
			(clearance 0)
		)
		(min_thickness 0.25)
		(keepout
			(tracks not_allowed)
			(vias allowed)
			(pads allowed)
			(copperpour not_allowed)
			(footprints allowed)
		)
		(placement
			(enabled no)
			(sheetname "")
		)
		(fill yes
			(thermal_gap 0.5)
			(thermal_bridge_width 0.5)
			(island_removal_mode 0)
		)
		(polygon
			(pts
				(arc
					(start 86.076028 -263.556242)
					(mid 85.446108 -263.556242)
					(end 86.076028 -263.556242)
				)
			)
		)
	)
	(zone
		(layers "B.Cu" "In13.Cu" "In15.Cu")
		(hatch none 0.5)
		(connect_pads
			(clearance 0)
		)
		(min_thickness 0.25)
		(keepout
			(tracks not_allowed)
			(vias allowed)
			(pads allowed)
			(copperpour not_allowed)
			(footprints allowed)
		)
		(placement
			(enabled no)
			(sheetname "")
		)
		(fill yes
			(thermal_gap 0.5)
			(thermal_bridge_width 0.5)
			(island_removal_mode 0)
		)
		(polygon
			(pts
				(arc
					(start 206.58201 -269.58544)
					(mid 205.91399 -269.58544)
					(end 206.58201 -269.58544)
				)
			)
		)
	)
	(zone
		(layers "B.Cu" "In13.Cu" "In15.Cu")
		(hatch none 0.5)
		(connect_pads
			(clearance 0)
		)
		(min_thickness 0.25)
		(keepout
			(tracks not_allowed)
			(vias allowed)
			(pads allowed)
			(copperpour not_allowed)
			(footprints allowed)
		)
		(placement
			(enabled no)
			(sheetname "")
		)
		(fill yes
			(thermal_gap 0.5)
			(thermal_bridge_width 0.5)
			(island_removal_mode 0)
		)
		(polygon
			(pts
				(arc
					(start 374.958102 -377.41733)
					(mid 374.290082 -377.41733)
					(end 374.958102 -377.41733)
				)
			)
		)
	)
	(zone
		(layers "B.Cu" "In13.Cu" "In15.Cu")
		(hatch none 0.5)
		(connect_pads
			(clearance 0)
		)
		(min_thickness 0.25)
		(keepout
			(tracks not_allowed)
			(vias allowed)
			(pads allowed)
			(copperpour not_allowed)
			(footprints allowed)
		)
		(placement
			(enabled no)
			(sheetname "")
		)
		(fill yes
			(thermal_gap 0.5)
			(thermal_bridge_width 0.5)
			(island_removal_mode 0)
		)
		(polygon
			(pts
				(arc
					(start 332.306168 -246.914162)
					(mid 331.676248 -246.914162)
					(end 332.306168 -246.914162)
				)
			)
		)
	)
	(zone
		(layers "B.Cu" "In13.Cu" "In15.Cu")
		(hatch none 0.5)
		(connect_pads
			(clearance 0)
		)
		(min_thickness 0.25)
		(keepout
			(tracks not_allowed)
			(vias allowed)
			(pads allowed)
			(copperpour not_allowed)
			(footprints allowed)
		)
		(placement
			(enabled no)
			(sheetname "")
		)
		(fill yes
			(thermal_gap 0.5)
			(thermal_bridge_width 0.5)
			(island_removal_mode 0)
		)
		(polygon
			(pts
				(arc
					(start 138.709654 -276.516338)
					(mid 138.079734 -276.516338)
					(end 138.709654 -276.516338)
				)
			)
		)
	)
	(zone
		(layers "B.Cu" "In13.Cu" "In15.Cu")
		(hatch none 0.5)
		(connect_pads
			(clearance 0)
		)
		(min_thickness 0.25)
		(keepout
			(tracks not_allowed)
			(vias allowed)
			(pads allowed)
			(copperpour not_allowed)
			(footprints allowed)
		)
		(placement
			(enabled no)
			(sheetname "")
		)
		(fill yes
			(thermal_gap 0.5)
			(thermal_bridge_width 0.5)
			(island_removal_mode 0)
		)
		(polygon
			(pts
				(arc
					(start 269.982188 -212.635084)
					(mid 269.314168 -212.635084)
					(end 269.982188 -212.635084)
				)
			)
		)
	)
	(zone
		(layers "B.Cu" "In13.Cu" "In15.Cu")
		(hatch none 0.5)
		(connect_pads
			(clearance 0)
		)
		(min_thickness 0.25)
		(keepout
			(tracks not_allowed)
			(vias allowed)
			(pads allowed)
			(copperpour not_allowed)
			(footprints allowed)
		)
		(placement
			(enabled no)
			(sheetname "")
		)
		(fill yes
			(thermal_gap 0.5)
			(thermal_bridge_width 0.5)
			(island_removal_mode 0)
		)
		(polygon
			(pts
				(arc
					(start 107.696 -274.896326)
					(mid 107.06608 -274.896326)
					(end 107.696 -274.896326)
				)
			)
		)
	)
	(zone
		(layers "B.Cu" "In13.Cu" "In15.Cu")
		(hatch none 0.5)
		(connect_pads
			(clearance 0)
		)
		(min_thickness 0.25)
		(keepout
			(tracks not_allowed)
			(vias allowed)
			(pads allowed)
			(copperpour not_allowed)
			(footprints allowed)
		)
		(placement
			(enabled no)
			(sheetname "")
		)
		(fill yes
			(thermal_gap 0.5)
			(thermal_bridge_width 0.5)
			(island_removal_mode 0)
		)
		(polygon
			(pts
				(arc
					(start 137.93978 -253.394464)
					(mid 137.30986 -253.394464)
					(end 137.93978 -253.394464)
				)
			)
		)
	)
	(zone
		(layers "B.Cu" "In13.Cu" "In15.Cu")
		(hatch none 0.5)
		(connect_pads
			(clearance 0)
		)
		(min_thickness 0.25)
		(keepout
			(tracks not_allowed)
			(vias allowed)
			(pads allowed)
			(copperpour not_allowed)
			(footprints allowed)
		)
		(placement
			(enabled no)
			(sheetname "")
		)
		(fill yes
			(thermal_gap 0.5)
			(thermal_bridge_width 0.5)
			(island_removal_mode 0)
		)
		(polygon
			(pts
				(arc
					(start 385.879848 -253.39421)
					(mid 385.249928 -253.39421)
					(end 385.879848 -253.39421)
				)
			)
		)
	)
	(zone
		(layers "B.Cu" "In13.Cu" "In15.Cu")
		(hatch none 0.5)
		(connect_pads
			(clearance 0)
		)
		(min_thickness 0.25)
		(keepout
			(tracks not_allowed)
			(vias allowed)
			(pads allowed)
			(copperpour not_allowed)
			(footprints allowed)
		)
		(placement
			(enabled no)
			(sheetname "")
		)
		(fill yes
			(thermal_gap 0.5)
			(thermal_bridge_width 0.5)
			(island_removal_mode 0)
		)
		(polygon
			(pts
				(arc
					(start 406.454356 -4.963414)
					(mid 405.786336 -4.963414)
					(end 406.454356 -4.963414)
				)
			)
		)
	)
	(zone
		(layers "B.Cu" "In13.Cu" "In15.Cu")
		(hatch none 0.5)
		(connect_pads
			(clearance 0)
		)
		(min_thickness 0.25)
		(keepout
			(tracks not_allowed)
			(vias allowed)
			(pads allowed)
			(copperpour not_allowed)
			(footprints allowed)
		)
		(placement
			(enabled no)
			(sheetname "")
		)
		(fill yes
			(thermal_gap 0.5)
			(thermal_bridge_width 0.5)
			(island_removal_mode 0)
		)
		(polygon
			(pts
				(arc
					(start 60.381134 -412.570168)
					(mid 59.713114 -412.570168)
					(end 60.381134 -412.570168)
				)
			)
		)
	)
	(zone
		(layers "B.Cu" "In13.Cu" "In15.Cu")
		(hatch none 0.5)
		(connect_pads
			(clearance 0)
		)
		(min_thickness 0.25)
		(keepout
			(tracks not_allowed)
			(vias allowed)
			(pads allowed)
			(copperpour not_allowed)
			(footprints allowed)
		)
		(placement
			(enabled no)
			(sheetname "")
		)
		(fill yes
			(thermal_gap 0.5)
			(thermal_bridge_width 0.5)
			(island_removal_mode 0)
		)
		(polygon
			(pts
				(arc
					(start 394.13688 -429.689768)
					(mid 393.362688 -429.689768)
					(end 394.13688 -429.689768)
				)
			)
		)
	)
	(zone
		(layers "B.Cu" "In13.Cu" "In15.Cu")
		(hatch none 0.5)
		(connect_pads
			(clearance 0)
		)
		(min_thickness 0.25)
		(keepout
			(tracks not_allowed)
			(vias allowed)
			(pads allowed)
			(copperpour not_allowed)
			(footprints allowed)
		)
		(placement
			(enabled no)
			(sheetname "")
		)
		(fill yes
			(thermal_gap 0.5)
			(thermal_bridge_width 0.5)
			(island_removal_mode 0)
		)
		(polygon
			(pts
				(arc
					(start 17.942052 -301.035212)
					(mid 17.274032 -301.035212)
					(end 17.942052 -301.035212)
				)
			)
		)
	)
	(zone
		(layers "B.Cu" "In13.Cu" "In15.Cu")
		(hatch none 0.5)
		(connect_pads
			(clearance 0)
		)
		(min_thickness 0.25)
		(keepout
			(tracks not_allowed)
			(vias allowed)
			(pads allowed)
			(copperpour not_allowed)
			(footprints allowed)
		)
		(placement
			(enabled no)
			(sheetname "")
		)
		(fill yes
			(thermal_gap 0.5)
			(thermal_bridge_width 0.5)
			(island_removal_mode 0)
		)
		(polygon
			(pts
				(arc
					(start 347.013276 -420.952168)
					(mid 346.345256 -420.952168)
					(end 347.013276 -420.952168)
				)
			)
		)
	)
	(zone
		(layers "B.Cu" "In13.Cu" "In15.Cu")
		(hatch none 0.5)
		(connect_pads
			(clearance 0)
		)
		(min_thickness 0.25)
		(keepout
			(tracks not_allowed)
			(vias allowed)
			(pads allowed)
			(copperpour not_allowed)
			(footprints allowed)
		)
		(placement
			(enabled no)
			(sheetname "")
		)
		(fill yes
			(thermal_gap 0.5)
			(thermal_bridge_width 0.5)
			(island_removal_mode 0)
		)
		(polygon
			(pts
				(arc
					(start 98.936048 -244.484398)
					(mid 98.306128 -244.484398)
					(end 98.936048 -244.484398)
				)
			)
		)
	)
	(zone
		(layers "B.Cu" "In13.Cu" "In15.Cu")
		(hatch none 0.5)
		(connect_pads
			(clearance 0)
		)
		(min_thickness 0.25)
		(keepout
			(tracks not_allowed)
			(vias allowed)
			(pads allowed)
			(copperpour not_allowed)
			(footprints allowed)
		)
		(placement
			(enabled no)
			(sheetname "")
		)
		(fill yes
			(thermal_gap 0.5)
			(thermal_bridge_width 0.5)
			(island_removal_mode 0)
		)
		(polygon
			(pts
				(arc
					(start 334.186022 -238.814102)
					(mid 333.556102 -238.814102)
					(end 334.186022 -238.814102)
				)
			)
		)
	)
	(zone
		(layers "B.Cu" "In13.Cu" "In15.Cu")
		(hatch none 0.5)
		(connect_pads
			(clearance 0)
		)
		(min_thickness 0.25)
		(keepout
			(tracks not_allowed)
			(vias allowed)
			(pads allowed)
			(copperpour not_allowed)
			(footprints allowed)
		)
		(placement
			(enabled no)
			(sheetname "")
		)
		(fill yes
			(thermal_gap 0.5)
			(thermal_bridge_width 0.5)
			(island_removal_mode 0)
		)
		(polygon
			(pts
				(arc
					(start 22.04212 -234.73537)
					(mid 21.3741 -234.73537)
					(end 22.04212 -234.73537)
				)
			)
		)
	)
	(zone
		(layers "B.Cu" "In13.Cu" "In15.Cu")
		(hatch none 0.5)
		(connect_pads
			(clearance 0)
		)
		(min_thickness 0.25)
		(keepout
			(tracks not_allowed)
			(vias allowed)
			(pads allowed)
			(copperpour not_allowed)
			(footprints allowed)
		)
		(placement
			(enabled no)
			(sheetname "")
		)
		(fill yes
			(thermal_gap 0.5)
			(thermal_bridge_width 0.5)
			(island_removal_mode 0)
		)
		(polygon
			(pts
				(arc
					(start 374.429782 -276.516084)
					(mid 373.799862 -276.516084)
					(end 374.429782 -276.516084)
				)
			)
		)
	)
	(zone
		(layers "B.Cu" "In13.Cu" "In15.Cu")
		(hatch none 0.5)
		(connect_pads
			(clearance 0)
		)
		(min_thickness 0.25)
		(keepout
			(tracks not_allowed)
			(vias allowed)
			(pads allowed)
			(copperpour not_allowed)
			(footprints allowed)
		)
		(placement
			(enabled no)
			(sheetname "")
		)
		(fill yes
			(thermal_gap 0.5)
			(thermal_bridge_width 0.5)
			(island_removal_mode 0)
		)
		(polygon
			(pts
				(arc
					(start 269.982188 -279.785064)
					(mid 269.314168 -279.785064)
					(end 269.982188 -279.785064)
				)
			)
		)
	)
	(zone
		(layers "B.Cu" "In13.Cu" "In15.Cu")
		(hatch none 0.5)
		(connect_pads
			(clearance 0)
		)
		(min_thickness 0.25)
		(keepout
			(tracks not_allowed)
			(vias allowed)
			(pads allowed)
			(copperpour not_allowed)
			(footprints allowed)
		)
		(placement
			(enabled no)
			(sheetname "")
		)
		(fill yes
			(thermal_gap 0.5)
			(thermal_bridge_width 0.5)
			(island_removal_mode 0)
		)
		(polygon
			(pts
				(arc
					(start 307.191156 -420.952168)
					(mid 306.523136 -420.952168)
					(end 307.191156 -420.952168)
				)
			)
		)
	)
	(zone
		(layers "B.Cu" "In13.Cu" "In15.Cu")
		(hatch none 0.5)
		(connect_pads
			(clearance 0)
		)
		(min_thickness 0.25)
		(keepout
			(tracks not_allowed)
			(vias allowed)
			(pads allowed)
			(copperpour not_allowed)
			(footprints allowed)
		)
		(placement
			(enabled no)
			(sheetname "")
		)
		(fill yes
			(thermal_gap 0.5)
			(thermal_bridge_width 0.5)
			(island_removal_mode 0)
		)
		(polygon
			(pts
				(arc
					(start 265.88212 -268.735048)
					(mid 265.2141 -268.735048)
					(end 265.88212 -268.735048)
				)
			)
		)
	)
	(zone
		(layers "B.Cu" "In13.Cu" "In15.Cu")
		(hatch none 0.5)
		(connect_pads
			(clearance 0)
		)
		(min_thickness 0.25)
		(keepout
			(tracks not_allowed)
			(vias allowed)
			(pads allowed)
			(copperpour not_allowed)
			(footprints allowed)
		)
		(placement
			(enabled no)
			(sheetname "")
		)
		(fill yes
			(thermal_gap 0.5)
			(thermal_bridge_width 0.5)
			(island_removal_mode 0)
		)
		(polygon
			(pts
				(arc
					(start 269.982188 -238.985044)
					(mid 269.314168 -238.985044)
					(end 269.982188 -238.985044)
				)
			)
		)
	)
	(zone
		(layers "B.Cu" "In13.Cu" "In15.Cu")
		(hatch none 0.5)
		(connect_pads
			(clearance 0)
		)
		(min_thickness 0.25)
		(keepout
			(tracks not_allowed)
			(vias allowed)
			(pads allowed)
			(copperpour not_allowed)
			(footprints allowed)
		)
		(placement
			(enabled no)
			(sheetname "")
		)
		(fill yes
			(thermal_gap 0.5)
			(thermal_bridge_width 0.5)
			(island_removal_mode 0)
		)
		(polygon
			(pts
				(arc
					(start 17.942052 -305.285394)
					(mid 17.274032 -305.285394)
					(end 17.942052 -305.285394)
				)
			)
		)
	)
	(zone
		(layers "B.Cu" "In13.Cu" "In15.Cu")
		(hatch none 0.5)
		(connect_pads
			(clearance 0)
		)
		(min_thickness 0.25)
		(keepout
			(tracks not_allowed)
			(vias allowed)
			(pads allowed)
			(copperpour not_allowed)
			(footprints allowed)
		)
		(placement
			(enabled no)
			(sheetname "")
		)
		(fill yes
			(thermal_gap 0.5)
			(thermal_bridge_width 0.5)
			(island_removal_mode 0)
		)
		(polygon
			(pts
				(arc
					(start 387.589776 -282.996132)
					(mid 386.959856 -282.996132)
					(end 387.589776 -282.996132)
				)
			)
		)
	)
	(zone
		(layers "B.Cu" "In13.Cu" "In15.Cu")
		(hatch none 0.5)
		(connect_pads
			(clearance 0)
		)
		(min_thickness 0.25)
		(keepout
			(tracks not_allowed)
			(vias allowed)
			(pads allowed)
			(copperpour not_allowed)
			(footprints allowed)
		)
		(placement
			(enabled no)
			(sheetname "")
		)
		(fill yes
			(thermal_gap 0.5)
			(thermal_bridge_width 0.5)
			(island_removal_mode 0)
		)
		(polygon
			(pts
				(arc
					(start 85.833966 -389.467344)
					(mid 85.204046 -389.467344)
					(end 85.833966 -389.467344)
				)
			)
		)
	)
	(zone
		(layers "B.Cu" "In13.Cu" "In15.Cu")
		(hatch none 0.5)
		(connect_pads
			(clearance 0)
		)
		(min_thickness 0.25)
		(keepout
			(tracks not_allowed)
			(vias allowed)
			(pads allowed)
			(copperpour not_allowed)
			(footprints allowed)
		)
		(placement
			(enabled no)
			(sheetname "")
		)
		(fill yes
			(thermal_gap 0.5)
			(thermal_bridge_width 0.5)
			(island_removal_mode 0)
		)
		(polygon
			(pts
				(arc
					(start 398.313148 -6.725158)
					(mid 397.645128 -6.725158)
					(end 398.313148 -6.725158)
				)
			)
		)
	)
	(zone
		(layers "B.Cu" "In13.Cu" "In15.Cu")
		(hatch none 0.5)
		(connect_pads
			(clearance 0)
		)
		(min_thickness 0.25)
		(keepout
			(tracks not_allowed)
			(vias allowed)
			(pads allowed)
			(copperpour not_allowed)
			(footprints allowed)
		)
		(placement
			(enabled no)
			(sheetname "")
		)
		(fill yes
			(thermal_gap 0.5)
			(thermal_bridge_width 0.5)
			(island_removal_mode 0)
		)
		(polygon
			(pts
				(arc
					(start 138.709654 -286.23641)
					(mid 138.079734 -286.23641)
					(end 138.709654 -286.23641)
				)
			)
		)
	)
	(zone
		(layers "B.Cu" "In13.Cu" "In15.Cu")
		(hatch none 0.5)
		(connect_pads
			(clearance 0)
		)
		(min_thickness 0.25)
		(keepout
			(tracks not_allowed)
			(vias allowed)
			(pads allowed)
			(copperpour not_allowed)
			(footprints allowed)
		)
		(placement
			(enabled no)
			(sheetname "")
		)
		(fill yes
			(thermal_gap 0.5)
			(thermal_bridge_width 0.5)
			(island_removal_mode 0)
		)
		(polygon
			(pts
				(arc
					(start 119.609616 -233.144314)
					(mid 118.979696 -233.144314)
					(end 119.609616 -233.144314)
				)
			)
		)
	)
	(zone
		(layers "B.Cu" "In13.Cu" "In15.Cu")
		(hatch none 0.5)
		(connect_pads
			(clearance 0)
		)
		(min_thickness 0.25)
		(keepout
			(tracks not_allowed)
			(vias allowed)
			(pads allowed)
			(copperpour not_allowed)
			(footprints allowed)
		)
		(placement
			(enabled no)
			(sheetname "")
		)
		(fill yes
			(thermal_gap 0.5)
			(thermal_bridge_width 0.5)
			(island_removal_mode 0)
		)
		(polygon
			(pts
				(arc
					(start 450.42201 -202.434952)
					(mid 449.75399 -202.434952)
					(end 450.42201 -202.434952)
				)
			)
		)
	)
	(zone
		(layers "B.Cu" "In13.Cu" "In15.Cu")
		(hatch none 0.5)
		(connect_pads
			(clearance 0)
		)
		(min_thickness 0.25)
		(keepout
			(tracks not_allowed)
			(vias allowed)
			(pads allowed)
			(copperpour not_allowed)
			(footprints allowed)
		)
		(placement
			(enabled no)
			(sheetname "")
		)
		(fill yes
			(thermal_gap 0.5)
			(thermal_bridge_width 0.5)
			(island_removal_mode 0)
		)
		(polygon
			(pts
				(arc
					(start 269.982188 -317.18504)
					(mid 269.314168 -317.18504)
					(end 269.982188 -317.18504)
				)
			)
		)
	)
	(zone
		(layers "B.Cu" "In13.Cu" "In15.Cu")
		(hatch none 0.5)
		(connect_pads
			(clearance 0)
		)
		(min_thickness 0.25)
		(keepout
			(tracks not_allowed)
			(vias allowed)
			(pads allowed)
			(copperpour not_allowed)
			(footprints allowed)
		)
		(placement
			(enabled no)
			(sheetname "")
		)
		(fill yes
			(thermal_gap 0.5)
			(thermal_bridge_width 0.5)
			(island_removal_mode 0)
		)
		(polygon
			(pts
				(arc
					(start 265.88212 -278.93518)
					(mid 265.2141 -278.93518)
					(end 265.88212 -278.93518)
				)
			)
		)
	)
	(zone
		(layers "B.Cu" "In13.Cu" "In15.Cu")
		(hatch none 0.5)
		(connect_pads
			(clearance 0)
		)
		(min_thickness 0.25)
		(keepout
			(tracks not_allowed)
			(vias allowed)
			(pads allowed)
			(copperpour not_allowed)
			(footprints allowed)
		)
		(placement
			(enabled no)
			(sheetname "")
		)
		(fill yes
			(thermal_gap 0.5)
			(thermal_bridge_width 0.5)
			(island_removal_mode 0)
		)
		(polygon
			(pts
				(arc
					(start 22.04212 -217.735404)
					(mid 21.3741 -217.735404)
					(end 22.04212 -217.735404)
				)
			)
		)
	)
	(zone
		(layers "B.Cu" "In13.Cu" "In15.Cu")
		(hatch none 0.5)
		(connect_pads
			(clearance 0)
		)
		(min_thickness 0.25)
		(keepout
			(tracks not_allowed)
			(vias allowed)
			(pads allowed)
			(copperpour not_allowed)
			(footprints allowed)
		)
		(placement
			(enabled no)
			(sheetname "")
		)
		(fill yes
			(thermal_gap 0.5)
			(thermal_bridge_width 0.5)
			(island_removal_mode 0)
		)
		(polygon
			(pts
				(arc
					(start 86.245954 -240.434368)
					(mid 85.616034 -240.434368)
					(end 86.245954 -240.434368)
				)
			)
		)
	)
	(zone
		(layers "B.Cu" "In13.Cu" "In15.Cu")
		(hatch none 0.5)
		(connect_pads
			(clearance 0)
		)
		(min_thickness 0.25)
		(keepout
			(tracks not_allowed)
			(vias allowed)
			(pads allowed)
			(copperpour not_allowed)
			(footprints allowed)
		)
		(placement
			(enabled no)
			(sheetname "")
		)
		(fill yes
			(thermal_gap 0.5)
			(thermal_bridge_width 0.5)
			(island_removal_mode 0)
		)
		(polygon
			(pts
				(arc
					(start 125.249686 -234.764326)
					(mid 124.619766 -234.764326)
					(end 125.249686 -234.764326)
				)
			)
		)
	)
	(zone
		(layers "B.Cu" "In13.Cu" "In15.Cu")
		(hatch none 0.5)
		(connect_pads
			(clearance 0)
		)
		(min_thickness 0.25)
		(keepout
			(tracks not_allowed)
			(vias allowed)
			(pads allowed)
			(copperpour not_allowed)
			(footprints allowed)
		)
		(placement
			(enabled no)
			(sheetname "")
		)
		(fill yes
			(thermal_gap 0.5)
			(thermal_bridge_width 0.5)
			(island_removal_mode 0)
		)
		(polygon
			(pts
				(arc
					(start 395.734032 -420.952168)
					(mid 395.066012 -420.952168)
					(end 395.734032 -420.952168)
				)
			)
		)
	)
	(zone
		(layers "B.Cu" "In13.Cu" "In15.Cu")
		(hatch none 0.5)
		(connect_pads
			(clearance 0)
		)
		(min_thickness 0.25)
		(keepout
			(tracks not_allowed)
			(vias allowed)
			(pads allowed)
			(copperpour not_allowed)
			(footprints allowed)
		)
		(placement
			(enabled no)
			(sheetname "")
		)
		(fill yes
			(thermal_gap 0.5)
			(thermal_bridge_width 0.5)
			(island_removal_mode 0)
		)
		(polygon
			(pts
				(arc
					(start 454.522078 -216.035128)
					(mid 453.854058 -216.035128)
					(end 454.522078 -216.035128)
				)
			)
		)
	)
	(zone
		(layers "B.Cu" "In13.Cu" "In15.Cu")
		(hatch none 0.5)
		(connect_pads
			(clearance 0)
		)
		(min_thickness 0.25)
		(keepout
			(tracks not_allowed)
			(vias allowed)
			(pads allowed)
			(copperpour not_allowed)
			(footprints allowed)
		)
		(placement
			(enabled no)
			(sheetname "")
		)
		(fill yes
			(thermal_gap 0.5)
			(thermal_bridge_width 0.5)
			(island_removal_mode 0)
		)
		(polygon
			(pts
				(arc
					(start 101.755956 -246.10441)
					(mid 101.126036 -246.10441)
					(end 101.755956 -246.10441)
				)
			)
		)
	)
	(zone
		(layers "B.Cu" "In13.Cu" "In15.Cu")
		(hatch none 0.5)
		(connect_pads
			(clearance 0)
		)
		(min_thickness 0.25)
		(keepout
			(tracks not_allowed)
			(vias allowed)
			(pads allowed)
			(copperpour not_allowed)
			(footprints allowed)
		)
		(placement
			(enabled no)
			(sheetname "")
		)
		(fill yes
			(thermal_gap 0.5)
			(thermal_bridge_width 0.5)
			(island_removal_mode 0)
		)
		(polygon
			(pts
				(arc
					(start 450.42201 -201.585068)
					(mid 449.75399 -201.585068)
					(end 450.42201 -201.585068)
				)
			)
		)
	)
	(zone
		(layers "B.Cu" "In13.Cu" "In15.Cu")
		(hatch none 0.5)
		(connect_pads
			(clearance 0)
		)
		(min_thickness 0.25)
		(keepout
			(tracks not_allowed)
			(vias allowed)
			(pads allowed)
			(copperpour not_allowed)
			(footprints allowed)
		)
		(placement
			(enabled no)
			(sheetname "")
		)
		(fill yes
			(thermal_gap 0.5)
			(thermal_bridge_width 0.5)
			(island_removal_mode 0)
		)
		(polygon
			(pts
				(arc
					(start 394.711682 -387.878828)
					(mid 394.043662 -387.878828)
					(end 394.711682 -387.878828)
				)
			)
		)
	)
	(zone
		(layers "B.Cu" "In13.Cu" "In15.Cu")
		(hatch none 0.5)
		(connect_pads
			(clearance 0)
		)
		(min_thickness 0.25)
		(keepout
			(tracks not_allowed)
			(vias allowed)
			(pads allowed)
			(copperpour not_allowed)
			(footprints allowed)
		)
		(placement
			(enabled no)
			(sheetname "")
		)
		(fill yes
			(thermal_gap 0.5)
			(thermal_bridge_width 0.5)
			(island_removal_mode 0)
		)
		(polygon
			(pts
				(arc
					(start 418.223192 -6.725158)
					(mid 417.555172 -6.725158)
					(end 418.223192 -6.725158)
				)
			)
		)
	)
	(zone
		(layers "B.Cu" "In13.Cu" "In15.Cu")
		(hatch none 0.5)
		(connect_pads
			(clearance 0)
		)
		(min_thickness 0.25)
		(keepout
			(tracks not_allowed)
			(vias allowed)
			(pads allowed)
			(copperpour not_allowed)
			(footprints allowed)
		)
		(placement
			(enabled no)
			(sheetname "")
		)
		(fill yes
			(thermal_gap 0.5)
			(thermal_bridge_width 0.5)
			(island_removal_mode 0)
		)
		(polygon
			(pts
				(arc
					(start 332.606142 -275.706078)
					(mid 331.976222 -275.706078)
					(end 332.606142 -275.706078)
				)
			)
		)
	)
	(zone
		(layers "B.Cu" "In13.Cu" "In15.Cu")
		(hatch none 0.5)
		(connect_pads
			(clearance 0)
		)
		(min_thickness 0.25)
		(keepout
			(tracks not_allowed)
			(vias allowed)
			(pads allowed)
			(copperpour not_allowed)
			(footprints allowed)
		)
		(placement
			(enabled no)
			(sheetname "")
		)
		(fill yes
			(thermal_gap 0.5)
			(thermal_bridge_width 0.5)
			(island_removal_mode 0)
		)
		(polygon
			(pts
				(arc
					(start 22.04212 -270.435324)
					(mid 21.3741 -270.435324)
					(end 22.04212 -270.435324)
				)
			)
		)
	)
	(zone
		(layers "B.Cu" "In13.Cu" "In15.Cu")
		(hatch none 0.5)
		(connect_pads
			(clearance 0)
		)
		(min_thickness 0.25)
		(keepout
			(tracks not_allowed)
			(vias allowed)
			(pads allowed)
			(copperpour not_allowed)
			(footprints allowed)
		)
		(placement
			(enabled no)
			(sheetname "")
		)
		(fill yes
			(thermal_gap 0.5)
			(thermal_bridge_width 0.5)
			(island_removal_mode 0)
		)
		(polygon
			(pts
				(arc
					(start 85.776054 -229.90429)
					(mid 85.146134 -229.90429)
					(end 85.776054 -229.90429)
				)
			)
		)
	)
	(zone
		(layers "B.Cu" "In13.Cu" "In15.Cu")
		(hatch none 0.5)
		(connect_pads
			(clearance 0)
		)
		(min_thickness 0.25)
		(keepout
			(tracks not_allowed)
			(vias allowed)
			(pads allowed)
			(copperpour not_allowed)
			(footprints allowed)
		)
		(placement
			(enabled no)
			(sheetname "")
		)
		(fill yes
			(thermal_gap 0.5)
			(thermal_bridge_width 0.5)
			(island_removal_mode 0)
		)
		(polygon
			(pts
				(arc
					(start 351.576132 -231.524048)
					(mid 350.946212 -231.524048)
					(end 351.576132 -231.524048)
				)
			)
		)
	)
	(zone
		(layers "B.Cu" "In13.Cu" "In15.Cu")
		(hatch none 0.5)
		(connect_pads
			(clearance 0)
		)
		(min_thickness 0.25)
		(keepout
			(tracks not_allowed)
			(vias allowed)
			(pads allowed)
			(copperpour not_allowed)
			(footprints allowed)
		)
		(placement
			(enabled no)
			(sheetname "")
		)
		(fill yes
			(thermal_gap 0.5)
			(thermal_bridge_width 0.5)
			(island_removal_mode 0)
		)
		(polygon
			(pts
				(arc
					(start 88.037162 -429.689768)
					(mid 87.26297 -429.689768)
					(end 88.037162 -429.689768)
				)
			)
		)
	)
	(zone
		(layers "B.Cu" "In13.Cu" "In15.Cu")
		(hatch none 0.5)
		(connect_pads
			(clearance 0)
		)
		(min_thickness 0.25)
		(keepout
			(tracks not_allowed)
			(vias allowed)
			(pads allowed)
			(copperpour not_allowed)
			(footprints allowed)
		)
		(placement
			(enabled no)
			(sheetname "")
		)
		(fill yes
			(thermal_gap 0.5)
			(thermal_bridge_width 0.5)
			(island_removal_mode 0)
		)
		(polygon
			(pts
				(arc
					(start 138.709654 -281.376374)
					(mid 138.079734 -281.376374)
					(end 138.709654 -281.376374)
				)
			)
		)
	)
	(zone
		(layers "B.Cu" "In13.Cu" "In15.Cu")
		(hatch none 0.5)
		(connect_pads
			(clearance 0)
		)
		(min_thickness 0.25)
		(keepout
			(tracks not_allowed)
			(vias allowed)
			(pads allowed)
			(copperpour not_allowed)
			(footprints allowed)
		)
		(placement
			(enabled no)
			(sheetname "")
		)
		(fill yes
			(thermal_gap 0.5)
			(thermal_bridge_width 0.5)
			(island_removal_mode 0)
		)
		(polygon
			(pts
				(arc
					(start 135.976106 -369.03533)
					(mid 135.308086 -369.03533)
					(end 135.976106 -369.03533)
				)
			)
		)
	)
	(zone
		(layers "B.Cu" "In13.Cu" "In15.Cu")
		(hatch none 0.5)
		(connect_pads
			(clearance 0)
		)
		(min_thickness 0.25)
		(keepout
			(tracks not_allowed)
			(vias allowed)
			(pads allowed)
			(copperpour not_allowed)
			(footprints allowed)
		)
		(placement
			(enabled no)
			(sheetname "")
		)
		(fill yes
			(thermal_gap 0.5)
			(thermal_bridge_width 0.5)
			(island_removal_mode 0)
		)
		(polygon
			(pts
				(arc
					(start 387.759702 -242.054126)
					(mid 387.129782 -242.054126)
					(end 387.759702 -242.054126)
				)
			)
		)
	)
	(zone
		(layers "B.Cu" "In13.Cu" "In15.Cu")
		(hatch none 0.5)
		(connect_pads
			(clearance 0)
		)
		(min_thickness 0.25)
		(keepout
			(tracks not_allowed)
			(vias allowed)
			(pads allowed)
			(copperpour not_allowed)
			(footprints allowed)
		)
		(placement
			(enabled no)
			(sheetname "")
		)
		(fill yes
			(thermal_gap 0.5)
			(thermal_bridge_width 0.5)
			(island_removal_mode 0)
		)
		(polygon
			(pts
				(arc
					(start 17.942052 -276.385274)
					(mid 17.274032 -276.385274)
					(end 17.942052 -276.385274)
				)
			)
		)
	)
	(zone
		(layers "B.Cu" "In13.Cu" "In15.Cu")
		(hatch none 0.5)
		(connect_pads
			(clearance 0)
		)
		(min_thickness 0.25)
		(keepout
			(tracks not_allowed)
			(vias allowed)
			(pads allowed)
			(copperpour not_allowed)
			(footprints allowed)
		)
		(placement
			(enabled no)
			(sheetname "")
		)
		(fill yes
			(thermal_gap 0.5)
			(thermal_bridge_width 0.5)
			(island_removal_mode 0)
		)
		(polygon
			(pts
				(arc
					(start 202.481942 -224.535238)
					(mid 201.813922 -224.535238)
					(end 202.481942 -224.535238)
				)
			)
		)
	)
	(zone
		(layers "B.Cu" "In13.Cu" "In15.Cu")
		(hatch none 0.5)
		(connect_pads
			(clearance 0)
		)
		(min_thickness 0.25)
		(keepout
			(tracks not_allowed)
			(vias allowed)
			(pads allowed)
			(copperpour not_allowed)
			(footprints allowed)
		)
		(placement
			(enabled no)
			(sheetname "")
		)
		(fill yes
			(thermal_gap 0.5)
			(thermal_bridge_width 0.5)
			(island_removal_mode 0)
		)
		(polygon
			(pts
				(arc
					(start 22.04212 -306.135278)
					(mid 21.3741 -306.135278)
					(end 22.04212 -306.135278)
				)
			)
		)
	)
	(zone
		(layers "B.Cu" "In13.Cu" "In15.Cu")
		(hatch none 0.5)
		(connect_pads
			(clearance 0)
		)
		(min_thickness 0.25)
		(keepout
			(tracks not_allowed)
			(vias allowed)
			(pads allowed)
			(copperpour not_allowed)
			(footprints allowed)
		)
		(placement
			(enabled no)
			(sheetname "")
		)
		(fill yes
			(thermal_gap 0.5)
			(thermal_bridge_width 0.5)
			(island_removal_mode 0)
		)
		(polygon
			(pts
				(arc
					(start 97.434146 -385.31038)
					(mid 96.804226 -385.31038)
					(end 97.434146 -385.31038)
				)
			)
		)
	)
	(zone
		(layers "B.Cu" "In13.Cu" "In15.Cu")
		(hatch none 0.5)
		(connect_pads
			(clearance 0)
		)
		(min_thickness 0.25)
		(keepout
			(tracks not_allowed)
			(vias allowed)
			(pads allowed)
			(copperpour not_allowed)
			(footprints allowed)
		)
		(placement
			(enabled no)
			(sheetname "")
		)
		(fill yes
			(thermal_gap 0.5)
			(thermal_bridge_width 0.5)
			(island_removal_mode 0)
		)
		(polygon
			(pts
				(arc
					(start 332.606142 -291.905944)
					(mid 331.976222 -291.905944)
					(end 332.606142 -291.905944)
				)
			)
		)
	)
	(zone
		(layers "B.Cu" "In13.Cu" "In15.Cu")
		(hatch none 0.5)
		(connect_pads
			(clearance 0)
		)
		(min_thickness 0.25)
		(keepout
			(tracks not_allowed)
			(vias allowed)
			(pads allowed)
			(copperpour not_allowed)
			(footprints allowed)
		)
		(placement
			(enabled no)
			(sheetname "")
		)
		(fill yes
			(thermal_gap 0.5)
			(thermal_bridge_width 0.5)
			(island_removal_mode 0)
		)
		(polygon
			(pts
				(arc
					(start 138.239754 -272.466308)
					(mid 137.609834 -272.466308)
					(end 138.239754 -272.466308)
				)
			)
		)
	)
	(zone
		(layers "B.Cu" "In13.Cu" "In15.Cu")
		(hatch none 0.5)
		(connect_pads
			(clearance 0)
		)
		(min_thickness 0.25)
		(keepout
			(tracks not_allowed)
			(vias allowed)
			(pads allowed)
			(copperpour not_allowed)
			(footprints allowed)
		)
		(placement
			(enabled no)
			(sheetname "")
		)
		(fill yes
			(thermal_gap 0.5)
			(thermal_bridge_width 0.5)
			(island_removal_mode 0)
		)
		(polygon
			(pts
				(arc
					(start 22.04212 -284.885384)
					(mid 21.3741 -284.885384)
					(end 22.04212 -284.885384)
				)
			)
		)
	)
	(zone
		(layers "B.Cu" "In13.Cu" "In15.Cu")
		(hatch none 0.5)
		(connect_pads
			(clearance 0)
		)
		(min_thickness 0.25)
		(keepout
			(tracks not_allowed)
			(vias allowed)
			(pads allowed)
			(copperpour not_allowed)
			(footprints allowed)
		)
		(placement
			(enabled no)
			(sheetname "")
		)
		(fill yes
			(thermal_gap 0.5)
			(thermal_bridge_width 0.5)
			(island_removal_mode 0)
		)
		(polygon
			(pts
				(arc
					(start 334.485996 -283.806138)
					(mid 333.856076 -283.806138)
					(end 334.485996 -283.806138)
				)
			)
		)
	)
	(zone
		(layers "B.Cu" "In13.Cu" "In15.Cu")
		(hatch none 0.5)
		(connect_pads
			(clearance 0)
		)
		(min_thickness 0.25)
		(keepout
			(tracks not_allowed)
			(vias allowed)
			(pads allowed)
			(copperpour not_allowed)
			(footprints allowed)
		)
		(placement
			(enabled no)
			(sheetname "")
		)
		(fill yes
			(thermal_gap 0.5)
			(thermal_bridge_width 0.5)
			(island_removal_mode 0)
		)
		(polygon
			(pts
				(arc
					(start 392.670792 -420.952168)
					(mid 392.002772 -420.952168)
					(end 392.670792 -420.952168)
				)
			)
		)
	)
	(zone
		(layers "B.Cu" "In13.Cu" "In15.Cu")
		(hatch none 0.5)
		(connect_pads
			(clearance 0)
		)
		(min_thickness 0.25)
		(keepout
			(tracks not_allowed)
			(vias allowed)
			(pads allowed)
			(copperpour not_allowed)
			(footprints allowed)
		)
		(placement
			(enabled no)
			(sheetname "")
		)
		(fill yes
			(thermal_gap 0.5)
			(thermal_bridge_width 0.5)
			(island_removal_mode 0)
		)
		(polygon
			(pts
				(arc
					(start 401.13712 -431.889916)
					(mid 400.362928 -431.889916)
					(end 401.13712 -431.889916)
				)
			)
		)
	)
	(zone
		(layers "B.Cu" "In13.Cu" "In15.Cu")
		(hatch none 0.5)
		(connect_pads
			(clearance 0)
		)
		(min_thickness 0.25)
		(keepout
			(tracks not_allowed)
			(vias allowed)
			(pads allowed)
			(copperpour not_allowed)
			(footprints allowed)
		)
		(placement
			(enabled no)
			(sheetname "")
		)
		(fill yes
			(thermal_gap 0.5)
			(thermal_bridge_width 0.5)
			(island_removal_mode 0)
		)
		(polygon
			(pts
				(arc
					(start 206.58201 -236.435392)
					(mid 205.91399 -236.435392)
					(end 206.58201 -236.435392)
				)
			)
		)
	)
	(zone
		(layers "B.Cu" "In13.Cu" "In15.Cu")
		(hatch none 0.5)
		(connect_pads
			(clearance 0)
		)
		(min_thickness 0.25)
		(keepout
			(tracks not_allowed)
			(vias allowed)
			(pads allowed)
			(copperpour not_allowed)
			(footprints allowed)
		)
		(placement
			(enabled no)
			(sheetname "")
		)
		(fill yes
			(thermal_gap 0.5)
			(thermal_bridge_width 0.5)
			(island_removal_mode 0)
		)
		(polygon
			(pts
				(arc
					(start 103.936038 -274.896326)
					(mid 103.306118 -274.896326)
					(end 103.936038 -274.896326)
				)
			)
		)
	)
	(zone
		(layers "B.Cu" "In13.Cu" "In15.Cu")
		(hatch none 0.5)
		(connect_pads
			(clearance 0)
		)
		(min_thickness 0.25)
		(keepout
			(tracks not_allowed)
			(vias allowed)
			(pads allowed)
			(copperpour not_allowed)
			(footprints allowed)
		)
		(placement
			(enabled no)
			(sheetname "")
		)
		(fill yes
			(thermal_gap 0.5)
			(thermal_bridge_width 0.5)
			(island_removal_mode 0)
		)
		(polygon
			(pts
				(arc
					(start 386.349748 -249.34418)
					(mid 385.719828 -249.34418)
					(end 386.349748 -249.34418)
				)
			)
		)
	)
	(zone
		(layers "B.Cu" "In13.Cu" "In15.Cu")
		(hatch none 0.5)
		(connect_pads
			(clearance 0)
		)
		(min_thickness 0.25)
		(keepout
			(tracks not_allowed)
			(vias allowed)
			(pads allowed)
			(copperpour not_allowed)
			(footprints allowed)
		)
		(placement
			(enabled no)
			(sheetname "")
		)
		(fill yes
			(thermal_gap 0.5)
			(thermal_bridge_width 0.5)
			(island_removal_mode 0)
		)
		(polygon
			(pts
				(arc
					(start 22.04212 -298.485306)
					(mid 21.3741 -298.485306)
					(end 22.04212 -298.485306)
				)
			)
		)
	)
	(zone
		(layers "B.Cu" "In13.Cu" "In15.Cu")
		(hatch none 0.5)
		(connect_pads
			(clearance 0)
		)
		(min_thickness 0.25)
		(keepout
			(tracks not_allowed)
			(vias allowed)
			(pads allowed)
			(copperpour not_allowed)
			(footprints allowed)
		)
		(placement
			(enabled no)
			(sheetname "")
		)
		(fill yes
			(thermal_gap 0.5)
			(thermal_bridge_width 0.5)
			(island_removal_mode 0)
		)
		(polygon
			(pts
				(arc
					(start 22.04212 -212.635338)
					(mid 21.3741 -212.635338)
					(end 22.04212 -212.635338)
				)
			)
		)
	)
	(zone
		(layers "B.Cu" "In13.Cu" "In15.Cu")
		(hatch none 0.5)
		(connect_pads
			(clearance 0)
		)
		(min_thickness 0.25)
		(keepout
			(tracks not_allowed)
			(vias allowed)
			(pads allowed)
			(copperpour not_allowed)
			(footprints allowed)
		)
		(placement
			(enabled no)
			(sheetname "")
		)
		(fill yes
			(thermal_gap 0.5)
			(thermal_bridge_width 0.5)
			(island_removal_mode 0)
		)
		(polygon
			(pts
				(arc
					(start 332.306168 -245.29415)
					(mid 331.676248 -245.29415)
					(end 332.306168 -245.29415)
				)
			)
		)
	)
	(zone
		(layers "B.Cu" "In13.Cu" "In15.Cu")
		(hatch none 0.5)
		(connect_pads
			(clearance 0)
		)
		(min_thickness 0.25)
		(keepout
			(tracks not_allowed)
			(vias allowed)
			(pads allowed)
			(copperpour not_allowed)
			(footprints allowed)
		)
		(placement
			(enabled no)
			(sheetname "")
		)
		(fill yes
			(thermal_gap 0.5)
			(thermal_bridge_width 0.5)
			(island_removal_mode 0)
		)
		(polygon
			(pts
				(arc
					(start 265.88212 -198.185024)
					(mid 265.2141 -198.185024)
					(end 265.88212 -198.185024)
				)
			)
		)
	)
	(zone
		(layers "B.Cu" "In13.Cu" "In15.Cu")
		(hatch none 0.5)
		(connect_pads
			(clearance 0)
		)
		(min_thickness 0.25)
		(keepout
			(tracks not_allowed)
			(vias allowed)
			(pads allowed)
			(copperpour not_allowed)
			(footprints allowed)
		)
		(placement
			(enabled no)
			(sheetname "")
		)
		(fill yes
			(thermal_gap 0.5)
			(thermal_bridge_width 0.5)
			(island_removal_mode 0)
		)
		(polygon
			(pts
				(arc
					(start 388.059676 -280.566114)
					(mid 387.429756 -280.566114)
					(end 388.059676 -280.566114)
				)
			)
		)
	)
	(zone
		(layers "B.Cu" "In13.Cu" "In15.Cu")
		(hatch none 0.5)
		(connect_pads
			(clearance 0)
		)
		(min_thickness 0.25)
		(keepout
			(tracks not_allowed)
			(vias allowed)
			(pads allowed)
			(copperpour not_allowed)
			(footprints allowed)
		)
		(placement
			(enabled no)
			(sheetname "")
		)
		(fill yes
			(thermal_gap 0.5)
			(thermal_bridge_width 0.5)
			(island_removal_mode 0)
		)
		(polygon
			(pts
				(arc
					(start 351.033842 -393.69238)
					(mid 350.403922 -393.69238)
					(end 351.033842 -393.69238)
				)
			)
		)
	)
	(zone
		(layers "B.Cu" "In13.Cu" "In15.Cu")
		(hatch none 0.5)
		(connect_pads
			(clearance 0)
		)
		(min_thickness 0.25)
		(keepout
			(tracks not_allowed)
			(vias allowed)
			(pads allowed)
			(copperpour not_allowed)
			(footprints allowed)
		)
		(placement
			(enabled no)
			(sheetname "")
		)
		(fill yes
			(thermal_gap 0.5)
			(thermal_bridge_width 0.5)
			(island_removal_mode 0)
		)
		(polygon
			(pts
				(arc
					(start 84.666074 -290.286186)
					(mid 84.036154 -290.286186)
					(end 84.666074 -290.286186)
				)
			)
		)
	)
	(zone
		(layers "B.Cu" "In13.Cu" "In15.Cu")
		(hatch none 0.5)
		(connect_pads
			(clearance 0)
		)
		(min_thickness 0.25)
		(keepout
			(tracks not_allowed)
			(vias allowed)
			(pads allowed)
			(copperpour not_allowed)
			(footprints allowed)
		)
		(placement
			(enabled no)
			(sheetname "")
		)
		(fill yes
			(thermal_gap 0.5)
			(thermal_bridge_width 0.5)
			(island_removal_mode 0)
		)
		(polygon
			(pts
				(arc
					(start 56.186324 -17.613122)
					(mid 55.518304 -17.613122)
					(end 56.186324 -17.613122)
				)
			)
		)
	)
	(zone
		(layers "B.Cu" "In13.Cu" "In15.Cu")
		(hatch none 0.5)
		(connect_pads
			(clearance 0)
		)
		(min_thickness 0.25)
		(keepout
			(tracks not_allowed)
			(vias allowed)
			(pads allowed)
			(copperpour not_allowed)
			(footprints allowed)
		)
		(placement
			(enabled no)
			(sheetname "")
		)
		(fill yes
			(thermal_gap 0.5)
			(thermal_bridge_width 0.5)
			(island_removal_mode 0)
		)
		(polygon
			(pts
				(arc
					(start 407.137108 -430.889918)
					(mid 406.362916 -430.889918)
					(end 407.137108 -430.889918)
				)
			)
		)
	)
	(zone
		(layers "B.Cu" "In13.Cu" "In15.Cu")
		(hatch none 0.5)
		(connect_pads
			(clearance 0)
		)
		(min_thickness 0.25)
		(keepout
			(tracks not_allowed)
			(vias allowed)
			(pads allowed)
			(copperpour not_allowed)
			(footprints allowed)
		)
		(placement
			(enabled no)
			(sheetname "")
		)
		(fill yes
			(thermal_gap 0.5)
			(thermal_bridge_width 0.5)
			(island_removal_mode 0)
		)
		(polygon
			(pts
				(arc
					(start 100.815902 -244.484398)
					(mid 100.185982 -244.484398)
					(end 100.815902 -244.484398)
				)
			)
		)
	)
	(zone
		(layers "B.Cu" "In13.Cu" "In15.Cu")
		(hatch none 0.5)
		(connect_pads
			(clearance 0)
		)
		(min_thickness 0.25)
		(keepout
			(tracks not_allowed)
			(vias allowed)
			(pads allowed)
			(copperpour not_allowed)
			(footprints allowed)
		)
		(placement
			(enabled no)
			(sheetname "")
		)
		(fill yes
			(thermal_gap 0.5)
			(thermal_bridge_width 0.5)
			(island_removal_mode 0)
		)
		(polygon
			(pts
				(arc
					(start 368.150902 -377.41733)
					(mid 367.482882 -377.41733)
					(end 368.150902 -377.41733)
				)
			)
		)
	)
	(zone
		(layers "B.Cu" "In13.Cu" "In15.Cu")
		(hatch none 0.5)
		(connect_pads
			(clearance 0)
		)
		(min_thickness 0.25)
		(keepout
			(tracks not_allowed)
			(vias allowed)
			(pads allowed)
			(copperpour not_allowed)
			(footprints allowed)
		)
		(placement
			(enabled no)
			(sheetname "")
		)
		(fill yes
			(thermal_gap 0.5)
			(thermal_bridge_width 0.5)
			(island_removal_mode 0)
		)
		(polygon
			(pts
				(arc
					(start 22.04212 -290.835334)
					(mid 21.3741 -290.835334)
					(end 22.04212 -290.835334)
				)
			)
		)
	)
	(zone
		(layers "B.Cu" "In13.Cu" "In15.Cu")
		(hatch none 0.5)
		(connect_pads
			(clearance 0)
		)
		(min_thickness 0.25)
		(keepout
			(tracks not_allowed)
			(vias allowed)
			(pads allowed)
			(copperpour not_allowed)
			(footprints allowed)
		)
		(placement
			(enabled no)
			(sheetname "")
		)
		(fill yes
			(thermal_gap 0.5)
			(thermal_bridge_width 0.5)
			(island_removal_mode 0)
		)
		(polygon
			(pts
				(arc
					(start 202.481942 -267.03528)
					(mid 201.813922 -267.03528)
					(end 202.481942 -267.03528)
				)
			)
		)
	)
	(zone
		(layers "B.Cu" "In13.Cu" "In15.Cu")
		(hatch none 0.5)
		(connect_pads
			(clearance 0)
		)
		(min_thickness 0.25)
		(keepout
			(tracks not_allowed)
			(vias allowed)
			(pads allowed)
			(copperpour not_allowed)
			(footprints allowed)
		)
		(placement
			(enabled no)
			(sheetname "")
		)
		(fill yes
			(thermal_gap 0.5)
			(thermal_bridge_width 0.5)
			(island_removal_mode 0)
		)
		(polygon
			(pts
				(arc
					(start 450.42201 -226.235006)
					(mid 449.75399 -226.235006)
					(end 450.42201 -226.235006)
				)
			)
		)
	)
	(zone
		(layers "B.Cu" "In13.Cu" "In15.Cu")
		(hatch none 0.5)
		(connect_pads
			(clearance 0)
		)
		(min_thickness 0.25)
		(keepout
			(tracks not_allowed)
			(vias allowed)
			(pads allowed)
			(copperpour not_allowed)
			(footprints allowed)
		)
		(placement
			(enabled no)
			(sheetname "")
		)
		(fill yes
			(thermal_gap 0.5)
			(thermal_bridge_width 0.5)
			(island_removal_mode 0)
		)
		(polygon
			(pts
				(arc
					(start 206.58201 -210.085432)
					(mid 205.91399 -210.085432)
					(end 206.58201 -210.085432)
				)
			)
		)
	)
	(zone
		(layers "B.Cu" "In13.Cu" "In15.Cu")
		(hatch none 0.5)
		(connect_pads
			(clearance 0)
		)
		(min_thickness 0.25)
		(keepout
			(tracks not_allowed)
			(vias allowed)
			(pads allowed)
			(copperpour not_allowed)
			(footprints allowed)
		)
		(placement
			(enabled no)
			(sheetname "")
		)
		(fill yes
			(thermal_gap 0.5)
			(thermal_bridge_width 0.5)
			(island_removal_mode 0)
		)
		(polygon
			(pts
				(arc
					(start 82.037174 -431.889916)
					(mid 81.262982 -431.889916)
					(end 82.037174 -431.889916)
				)
			)
		)
	)
	(zone
		(layers "B.Cu" "In13.Cu" "In15.Cu")
		(hatch none 0.5)
		(connect_pads
			(clearance 0)
		)
		(min_thickness 0.25)
		(keepout
			(tracks not_allowed)
			(vias allowed)
			(pads allowed)
			(copperpour not_allowed)
			(footprints allowed)
		)
		(placement
			(enabled no)
			(sheetname "")
		)
		(fill yes
			(thermal_gap 0.5)
			(thermal_bridge_width 0.5)
			(island_removal_mode 0)
		)
		(polygon
			(pts
				(arc
					(start 86.545928 -274.08632)
					(mid 85.916008 -274.08632)
					(end 86.545928 -274.08632)
				)
			)
		)
	)
	(zone
		(layers "B.Cu" "In13.Cu" "In15.Cu")
		(hatch none 0.5)
		(connect_pads
			(clearance 0)
		)
		(min_thickness 0.25)
		(keepout
			(tracks not_allowed)
			(vias allowed)
			(pads allowed)
			(copperpour not_allowed)
			(footprints allowed)
		)
		(placement
			(enabled no)
			(sheetname "")
		)
		(fill yes
			(thermal_gap 0.5)
			(thermal_bridge_width 0.5)
			(island_removal_mode 0)
		)
		(polygon
			(pts
				(arc
					(start 104.576118 -244.484398)
					(mid 103.946198 -244.484398)
					(end 104.576118 -244.484398)
				)
			)
		)
	)
	(zone
		(layers "B.Cu" "In13.Cu" "In15.Cu")
		(hatch none 0.5)
		(connect_pads
			(clearance 0)
		)
		(min_thickness 0.25)
		(keepout
			(tracks not_allowed)
			(vias allowed)
			(pads allowed)
			(copperpour not_allowed)
			(footprints allowed)
		)
		(placement
			(enabled no)
			(sheetname "")
		)
		(fill yes
			(thermal_gap 0.5)
			(thermal_bridge_width 0.5)
			(island_removal_mode 0)
		)
		(polygon
			(pts
				(arc
					(start 49.701704 -17.61236)
					(mid 49.033684 -17.61236)
					(end 49.701704 -17.61236)
				)
			)
		)
	)
	(zone
		(layers "B.Cu" "In13.Cu" "In15.Cu")
		(hatch none 0.5)
		(connect_pads
			(clearance 0)
		)
		(min_thickness 0.25)
		(keepout
			(tracks not_allowed)
			(vias allowed)
			(pads allowed)
			(copperpour not_allowed)
			(footprints allowed)
		)
		(placement
			(enabled no)
			(sheetname "")
		)
		(fill yes
			(thermal_gap 0.5)
			(thermal_bridge_width 0.5)
			(island_removal_mode 0)
		)
		(polygon
			(pts
				(arc
					(start 269.982188 -242.385088)
					(mid 269.314168 -242.385088)
					(end 269.982188 -242.385088)
				)
			)
		)
	)
	(zone
		(layers "B.Cu" "In13.Cu" "In15.Cu")
		(hatch none 0.5)
		(connect_pads
			(clearance 0)
		)
		(min_thickness 0.25)
		(keepout
			(tracks not_allowed)
			(vias allowed)
			(pads allowed)
			(copperpour not_allowed)
			(footprints allowed)
		)
		(placement
			(enabled no)
			(sheetname "")
		)
		(fill yes
			(thermal_gap 0.5)
			(thermal_bridge_width 0.5)
			(island_removal_mode 0)
		)
		(polygon
			(pts
				(arc
					(start 387.589776 -292.71595)
					(mid 386.959856 -292.71595)
					(end 387.589776 -292.71595)
				)
			)
		)
	)
	(zone
		(layers "B.Cu" "In13.Cu" "In15.Cu")
		(hatch none 0.5)
		(connect_pads
			(clearance 0)
		)
		(min_thickness 0.25)
		(keepout
			(tracks not_allowed)
			(vias allowed)
			(pads allowed)
			(copperpour not_allowed)
			(footprints allowed)
		)
		(placement
			(enabled no)
			(sheetname "")
		)
		(fill yes
			(thermal_gap 0.5)
			(thermal_bridge_width 0.5)
			(island_removal_mode 0)
		)
		(polygon
			(pts
				(arc
					(start 110.449106 -371.49913)
					(mid 109.781086 -371.49913)
					(end 110.449106 -371.49913)
				)
			)
		)
	)
	(zone
		(layers "B.Cu" "In13.Cu" "In15.Cu")
		(hatch none 0.5)
		(connect_pads
			(clearance 0)
		)
		(min_thickness 0.25)
		(keepout
			(tracks not_allowed)
			(vias allowed)
			(pads allowed)
			(copperpour not_allowed)
			(footprints allowed)
		)
		(placement
			(enabled no)
			(sheetname "")
		)
		(fill yes
			(thermal_gap 0.5)
			(thermal_bridge_width 0.5)
			(island_removal_mode 0)
		)
		(polygon
			(pts
				(arc
					(start 93.034104 -389.467344)
					(mid 92.404184 -389.467344)
					(end 93.034104 -389.467344)
				)
			)
		)
	)
	(zone
		(layers "B.Cu" "In13.Cu" "In15.Cu")
		(hatch none 0.5)
		(connect_pads
			(clearance 0)
		)
		(min_thickness 0.25)
		(keepout
			(tracks not_allowed)
			(vias allowed)
			(pads allowed)
			(copperpour not_allowed)
			(footprints allowed)
		)
		(placement
			(enabled no)
			(sheetname "")
		)
		(fill yes
			(thermal_gap 0.5)
			(thermal_bridge_width 0.5)
			(island_removal_mode 0)
		)
		(polygon
			(pts
				(arc
					(start 138.40968 -246.10441)
					(mid 137.77976 -246.10441)
					(end 138.40968 -246.10441)
				)
			)
		)
	)
	(zone
		(layers "B.Cu" "In13.Cu" "In15.Cu")
		(hatch none 0.5)
		(connect_pads
			(clearance 0)
		)
		(min_thickness 0.25)
		(keepout
			(tracks not_allowed)
			(vias allowed)
			(pads allowed)
			(copperpour not_allowed)
			(footprints allowed)
		)
		(placement
			(enabled no)
			(sheetname "")
		)
		(fill yes
			(thermal_gap 0.5)
			(thermal_bridge_width 0.5)
			(island_removal_mode 0)
		)
		(polygon
			(pts
				(arc
					(start 387.289802 -228.284278)
					(mid 386.659882 -228.284278)
					(end 387.289802 -228.284278)
				)
			)
		)
	)
	(zone
		(layers "B.Cu" "In13.Cu" "In15.Cu")
		(hatch none 0.5)
		(connect_pads
			(clearance 0)
		)
		(min_thickness 0.25)
		(keepout
			(tracks not_allowed)
			(vias allowed)
			(pads allowed)
			(copperpour not_allowed)
			(footprints allowed)
		)
		(placement
			(enabled no)
			(sheetname "")
		)
		(fill yes
			(thermal_gap 0.5)
			(thermal_bridge_width 0.5)
			(island_removal_mode 0)
		)
		(polygon
			(pts
				(arc
					(start 265.88212 -239.835182)
					(mid 265.2141 -239.835182)
					(end 265.88212 -239.835182)
				)
			)
		)
	)
	(zone
		(layers "B.Cu" "In13.Cu" "In15.Cu")
		(hatch none 0.5)
		(connect_pads
			(clearance 0)
		)
		(min_thickness 0.25)
		(keepout
			(tracks not_allowed)
			(vias allowed)
			(pads allowed)
			(copperpour not_allowed)
			(footprints allowed)
		)
		(placement
			(enabled no)
			(sheetname "")
		)
		(fill yes
			(thermal_gap 0.5)
			(thermal_bridge_width 0.5)
			(island_removal_mode 0)
		)
		(polygon
			(pts
				(arc
					(start 269.982188 -298.485052)
					(mid 269.314168 -298.485052)
					(end 269.982188 -298.485052)
				)
			)
		)
	)
	(zone
		(layers "B.Cu" "In13.Cu" "In15.Cu")
		(hatch none 0.5)
		(connect_pads
			(clearance 0)
		)
		(min_thickness 0.25)
		(keepout
			(tracks not_allowed)
			(vias allowed)
			(pads allowed)
			(copperpour not_allowed)
			(footprints allowed)
		)
		(placement
			(enabled no)
			(sheetname "")
		)
		(fill yes
			(thermal_gap 0.5)
			(thermal_bridge_width 0.5)
			(island_removal_mode 0)
		)
		(polygon
			(pts
				(arc
					(start 151.137112 -430.889918)
					(mid 150.36292 -430.889918)
					(end 151.137112 -430.889918)
				)
			)
		)
	)
	(zone
		(layers "B.Cu" "In13.Cu" "In15.Cu")
		(hatch none 0.5)
		(connect_pads
			(clearance 0)
		)
		(min_thickness 0.25)
		(keepout
			(tracks not_allowed)
			(vias allowed)
			(pads allowed)
			(copperpour not_allowed)
			(footprints allowed)
		)
		(placement
			(enabled no)
			(sheetname "")
		)
		(fill yes
			(thermal_gap 0.5)
			(thermal_bridge_width 0.5)
			(island_removal_mode 0)
		)
		(polygon
			(pts
				(arc
					(start 109.746034 -243.674392)
					(mid 109.116114 -243.674392)
					(end 109.746034 -243.674392)
				)
			)
		)
	)
	(zone
		(layers "B.Cu" "In13.Cu" "In15.Cu")
		(hatch none 0.5)
		(connect_pads
			(clearance 0)
		)
		(min_thickness 0.25)
		(keepout
			(tracks not_allowed)
			(vias allowed)
			(pads allowed)
			(copperpour not_allowed)
			(footprints allowed)
		)
		(placement
			(enabled no)
			(sheetname "")
		)
		(fill yes
			(thermal_gap 0.5)
			(thermal_bridge_width 0.5)
			(island_removal_mode 0)
		)
		(polygon
			(pts
				(arc
					(start 139.649708 -273.276314)
					(mid 139.019788 -273.276314)
					(end 139.649708 -273.276314)
				)
			)
		)
	)
	(zone
		(layers "B.Cu" "In13.Cu" "In15.Cu")
		(hatch none 0.5)
		(connect_pads
			(clearance 0)
		)
		(min_thickness 0.25)
		(keepout
			(tracks not_allowed)
			(vias allowed)
			(pads allowed)
			(copperpour not_allowed)
			(footprints allowed)
		)
		(placement
			(enabled no)
			(sheetname "")
		)
		(fill yes
			(thermal_gap 0.5)
			(thermal_bridge_width 0.5)
			(island_removal_mode 0)
		)
		(polygon
			(pts
				(arc
					(start 418.040312 -420.952168)
					(mid 417.372292 -420.952168)
					(end 418.040312 -420.952168)
				)
			)
		)
	)
	(zone
		(layers "B.Cu" "In13.Cu" "In15.Cu")
		(hatch none 0.5)
		(connect_pads
			(clearance 0)
		)
		(min_thickness 0.25)
		(keepout
			(tracks not_allowed)
			(vias allowed)
			(pads allowed)
			(copperpour not_allowed)
			(footprints allowed)
		)
		(placement
			(enabled no)
			(sheetname "")
		)
		(fill yes
			(thermal_gap 0.5)
			(thermal_bridge_width 0.5)
			(island_removal_mode 0)
		)
		(polygon
			(pts
				(arc
					(start 265.88212 -220.285056)
					(mid 265.2141 -220.285056)
					(end 265.88212 -220.285056)
				)
			)
		)
	)
	(zone
		(layers "B.Cu" "In13.Cu" "In15.Cu")
		(hatch none 0.5)
		(connect_pads
			(clearance 0)
		)
		(min_thickness 0.25)
		(keepout
			(tracks not_allowed)
			(vias allowed)
			(pads allowed)
			(copperpour not_allowed)
			(footprints allowed)
		)
		(placement
			(enabled no)
			(sheetname "")
		)
		(fill yes
			(thermal_gap 0.5)
			(thermal_bridge_width 0.5)
			(island_removal_mode 0)
		)
		(polygon
			(pts
				(arc
					(start 332.306168 -253.39421)
					(mid 331.676248 -253.39421)
					(end 332.306168 -253.39421)
				)
			)
		)
	)
	(zone
		(layers "B.Cu" "In13.Cu" "In15.Cu")
		(hatch none 0.5)
		(connect_pads
			(clearance 0)
		)
		(min_thickness 0.25)
		(keepout
			(tracks not_allowed)
			(vias allowed)
			(pads allowed)
			(copperpour not_allowed)
			(footprints allowed)
		)
		(placement
			(enabled no)
			(sheetname "")
		)
		(fill yes
			(thermal_gap 0.5)
			(thermal_bridge_width 0.5)
			(island_removal_mode 0)
		)
		(polygon
			(pts
				(arc
					(start 126.489714 -276.516338)
					(mid 125.859794 -276.516338)
					(end 126.489714 -276.516338)
				)
			)
		)
	)
	(zone
		(layers "B.Cu" "In13.Cu" "In15.Cu")
		(hatch none 0.5)
		(connect_pads
			(clearance 0)
		)
		(min_thickness 0.25)
		(keepout
			(tracks not_allowed)
			(vias allowed)
			(pads allowed)
			(copperpour not_allowed)
			(footprints allowed)
		)
		(placement
			(enabled no)
			(sheetname "")
		)
		(fill yes
			(thermal_gap 0.5)
			(thermal_bridge_width 0.5)
			(island_removal_mode 0)
		)
		(polygon
			(pts
				(arc
					(start 202.481942 -265.335258)
					(mid 201.813922 -265.335258)
					(end 202.481942 -265.335258)
				)
			)
		)
	)
	(zone
		(layers "B.Cu" "In13.Cu" "In15.Cu")
		(hatch none 0.5)
		(connect_pads
			(clearance 0)
		)
		(min_thickness 0.25)
		(keepout
			(tracks not_allowed)
			(vias allowed)
			(pads allowed)
			(copperpour not_allowed)
			(footprints allowed)
		)
		(placement
			(enabled no)
			(sheetname "")
		)
		(fill yes
			(thermal_gap 0.5)
			(thermal_bridge_width 0.5)
			(island_removal_mode 0)
		)
		(polygon
			(pts
				(arc
					(start 112.150906 -369.03533)
					(mid 111.482886 -369.03533)
					(end 112.150906 -369.03533)
				)
			)
		)
	)
	(zone
		(layers "B.Cu" "In13.Cu" "In15.Cu")
		(hatch none 0.5)
		(connect_pads
			(clearance 0)
		)
		(min_thickness 0.25)
		(keepout
			(tracks not_allowed)
			(vias allowed)
			(pads allowed)
			(copperpour not_allowed)
			(footprints allowed)
		)
		(placement
			(enabled no)
			(sheetname "")
		)
		(fill yes
			(thermal_gap 0.5)
			(thermal_bridge_width 0.5)
			(island_removal_mode 0)
		)
		(polygon
			(pts
				(arc
					(start 138.40968 -228.284532)
					(mid 137.77976 -228.284532)
					(end 138.40968 -228.284532)
				)
			)
		)
	)
	(zone
		(layers "B.Cu" "In13.Cu" "In15.Cu")
		(hatch none 0.5)
		(connect_pads
			(clearance 0)
		)
		(min_thickness 0.25)
		(keepout
			(tracks not_allowed)
			(vias allowed)
			(pads allowed)
			(copperpour not_allowed)
			(footprints allowed)
		)
		(placement
			(enabled no)
			(sheetname "")
		)
		(fill yes
			(thermal_gap 0.5)
			(thermal_bridge_width 0.5)
			(island_removal_mode 0)
		)
		(polygon
			(pts
				(arc
					(start 139.349734 -241.244374)
					(mid 138.719814 -241.244374)
					(end 139.349734 -241.244374)
				)
			)
		)
	)
	(zone
		(layers "B.Cu" "In13.Cu" "In15.Cu")
		(hatch none 0.5)
		(connect_pads
			(clearance 0)
		)
		(min_thickness 0.25)
		(keepout
			(tracks not_allowed)
			(vias allowed)
			(pads allowed)
			(copperpour not_allowed)
			(footprints allowed)
		)
		(placement
			(enabled no)
			(sheetname "")
		)
		(fill yes
			(thermal_gap 0.5)
			(thermal_bridge_width 0.5)
			(island_removal_mode 0)
		)
		(polygon
			(pts
				(arc
					(start 401.91309 -6.725158)
					(mid 401.24507 -6.725158)
					(end 401.91309 -6.725158)
				)
			)
		)
	)
	(zone
		(layers "B.Cu" "In13.Cu" "In15.Cu")
		(hatch none 0.5)
		(connect_pads
			(clearance 0)
		)
		(min_thickness 0.25)
		(keepout
			(tracks not_allowed)
			(vias allowed)
			(pads allowed)
			(copperpour not_allowed)
			(footprints allowed)
		)
		(placement
			(enabled no)
			(sheetname "")
		)
		(fill yes
			(thermal_gap 0.5)
			(thermal_bridge_width 0.5)
			(island_removal_mode 0)
		)
		(polygon
			(pts
				(arc
					(start 138.40968 -229.90429)
					(mid 137.77976 -229.90429)
					(end 138.40968 -229.90429)
				)
			)
		)
	)
	(zone
		(layers "B.Cu" "In13.Cu" "In15.Cu")
		(hatch none 0.5)
		(connect_pads
			(clearance 0)
		)
		(min_thickness 0.25)
		(keepout
			(tracks not_allowed)
			(vias allowed)
			(pads allowed)
			(copperpour not_allowed)
			(footprints allowed)
		)
		(placement
			(enabled no)
			(sheetname "")
		)
		(fill yes
			(thermal_gap 0.5)
			(thermal_bridge_width 0.5)
			(island_removal_mode 0)
		)
		(polygon
			(pts
				(arc
					(start 22.04212 -238.135414)
					(mid 21.3741 -238.135414)
					(end 22.04212 -238.135414)
				)
			)
		)
	)
	(zone
		(layers "B.Cu" "In13.Cu" "In15.Cu")
		(hatch none 0.5)
		(connect_pads
			(clearance 0)
		)
		(min_thickness 0.25)
		(keepout
			(tracks not_allowed)
			(vias allowed)
			(pads allowed)
			(copperpour not_allowed)
			(footprints allowed)
		)
		(placement
			(enabled no)
			(sheetname "")
		)
		(fill yes
			(thermal_gap 0.5)
			(thermal_bridge_width 0.5)
			(island_removal_mode 0)
		)
		(polygon
			(pts
				(arc
					(start 128.344676 -412.570168)
					(mid 127.676656 -412.570168)
					(end 128.344676 -412.570168)
				)
			)
		)
	)
	(zone
		(layers "B.Cu" "In13.Cu" "In15.Cu")
		(hatch none 0.5)
		(connect_pads
			(clearance 0)
		)
		(min_thickness 0.25)
		(keepout
			(tracks not_allowed)
			(vias allowed)
			(pads allowed)
			(copperpour not_allowed)
			(footprints allowed)
		)
		(placement
			(enabled no)
			(sheetname "")
		)
		(fill yes
			(thermal_gap 0.5)
			(thermal_bridge_width 0.5)
			(island_removal_mode 0)
		)
		(polygon
			(pts
				(arc
					(start 85.135974 -292.716204)
					(mid 84.506054 -292.716204)
					(end 85.135974 -292.716204)
				)
			)
		)
	)
	(zone
		(layers "B.Cu" "In13.Cu" "In15.Cu")
		(hatch none 0.5)
		(connect_pads
			(clearance 0)
		)
		(min_thickness 0.25)
		(keepout
			(tracks not_allowed)
			(vias allowed)
			(pads allowed)
			(copperpour not_allowed)
			(footprints allowed)
		)
		(placement
			(enabled no)
			(sheetname "")
		)
		(fill yes
			(thermal_gap 0.5)
			(thermal_bridge_width 0.5)
			(island_removal_mode 0)
		)
		(polygon
			(pts
				(arc
					(start 22.04212 -307.8353)
					(mid 21.3741 -307.8353)
					(end 22.04212 -307.8353)
				)
			)
		)
	)
	(zone
		(layers "B.Cu" "In13.Cu" "In15.Cu")
		(hatch none 0.5)
		(connect_pads
			(clearance 0)
		)
		(min_thickness 0.25)
		(keepout
			(tracks not_allowed)
			(vias allowed)
			(pads allowed)
			(copperpour not_allowed)
			(footprints allowed)
		)
		(placement
			(enabled no)
			(sheetname "")
		)
		(fill yes
			(thermal_gap 0.5)
			(thermal_bridge_width 0.5)
			(island_removal_mode 0)
		)
		(polygon
			(pts
				(arc
					(start 373.189754 -247.724168)
					(mid 372.559834 -247.724168)
					(end 373.189754 -247.724168)
				)
			)
		)
	)
	(zone
		(layers "B.Cu" "In13.Cu" "In15.Cu")
		(hatch none 0.5)
		(connect_pads
			(clearance 0)
		)
		(min_thickness 0.25)
		(keepout
			(tracks not_allowed)
			(vias allowed)
			(pads allowed)
			(copperpour not_allowed)
			(footprints allowed)
		)
		(placement
			(enabled no)
			(sheetname "")
		)
		(fill yes
			(thermal_gap 0.5)
			(thermal_bridge_width 0.5)
			(island_removal_mode 0)
		)
		(polygon
			(pts
				(arc
					(start 101.755956 -247.724422)
					(mid 101.126036 -247.724422)
					(end 101.755956 -247.724422)
				)
			)
		)
	)
	(zone
		(layers "B.Cu" "In13.Cu" "In15.Cu")
		(hatch none 0.5)
		(connect_pads
			(clearance 0)
		)
		(min_thickness 0.25)
		(keepout
			(tracks not_allowed)
			(vias allowed)
			(pads allowed)
			(copperpour not_allowed)
			(footprints allowed)
		)
		(placement
			(enabled no)
			(sheetname "")
		)
		(fill yes
			(thermal_gap 0.5)
			(thermal_bridge_width 0.5)
			(island_removal_mode 0)
		)
		(polygon
			(pts
				(arc
					(start 454.522078 -289.135058)
					(mid 453.854058 -289.135058)
					(end 454.522078 -289.135058)
				)
			)
		)
	)
	(zone
		(layers "B.Cu" "In13.Cu" "In15.Cu")
		(hatch none 0.5)
		(connect_pads
			(clearance 0)
		)
		(min_thickness 0.25)
		(keepout
			(tracks not_allowed)
			(vias allowed)
			(pads allowed)
			(copperpour not_allowed)
			(footprints allowed)
		)
		(placement
			(enabled no)
			(sheetname "")
		)
		(fill yes
			(thermal_gap 0.5)
			(thermal_bridge_width 0.5)
			(island_removal_mode 0)
		)
		(polygon
			(pts
				(arc
					(start 450.42201 -222.834962)
					(mid 449.75399 -222.834962)
					(end 450.42201 -222.834962)
				)
			)
		)
	)
	(zone
		(layers "B.Cu" "In13.Cu" "In15.Cu")
		(hatch none 0.5)
		(connect_pads
			(clearance 0)
		)
		(min_thickness 0.25)
		(keepout
			(tracks not_allowed)
			(vias allowed)
			(pads allowed)
			(copperpour not_allowed)
			(footprints allowed)
		)
		(placement
			(enabled no)
			(sheetname "")
		)
		(fill yes
			(thermal_gap 0.5)
			(thermal_bridge_width 0.5)
			(island_removal_mode 0)
		)
		(polygon
			(pts
				(arc
					(start 356.746048 -235.574078)
					(mid 356.116128 -235.574078)
					(end 356.746048 -235.574078)
				)
			)
		)
	)
	(zone
		(layers "B.Cu" "In13.Cu" "In15.Cu")
		(hatch none 0.5)
		(connect_pads
			(clearance 0)
		)
		(min_thickness 0.25)
		(keepout
			(tracks not_allowed)
			(vias allowed)
			(pads allowed)
			(copperpour not_allowed)
			(footprints allowed)
		)
		(placement
			(enabled no)
			(sheetname "")
		)
		(fill yes
			(thermal_gap 0.5)
			(thermal_bridge_width 0.5)
			(island_removal_mode 0)
		)
		(polygon
			(pts
				(arc
					(start 202.481942 -254.285242)
					(mid 201.813922 -254.285242)
					(end 202.481942 -254.285242)
				)
			)
		)
	)
	(zone
		(layers "B.Cu" "In13.Cu" "In15.Cu")
		(hatch none 0.5)
		(connect_pads
			(clearance 0)
		)
		(min_thickness 0.25)
		(keepout
			(tracks not_allowed)
			(vias allowed)
			(pads allowed)
			(copperpour not_allowed)
			(footprints allowed)
		)
		(placement
			(enabled no)
			(sheetname "")
		)
		(fill yes
			(thermal_gap 0.5)
			(thermal_bridge_width 0.5)
			(island_removal_mode 0)
		)
		(polygon
			(pts
				(arc
					(start 385.879848 -242.054126)
					(mid 385.249928 -242.054126)
					(end 385.879848 -242.054126)
				)
			)
		)
	)
	(zone
		(layers "B.Cu" "In13.Cu" "In15.Cu")
		(hatch none 0.5)
		(connect_pads
			(clearance 0)
		)
		(min_thickness 0.25)
		(keepout
			(tracks not_allowed)
			(vias allowed)
			(pads allowed)
			(copperpour not_allowed)
			(footprints allowed)
		)
		(placement
			(enabled no)
			(sheetname "")
		)
		(fill yes
			(thermal_gap 0.5)
			(thermal_bridge_width 0.5)
			(island_removal_mode 0)
		)
		(polygon
			(pts
				(arc
					(start 450.42201 -243.234972)
					(mid 449.75399 -243.234972)
					(end 450.42201 -243.234972)
				)
			)
		)
	)
	(zone
		(layers "B.Cu" "In13.Cu" "In15.Cu")
		(hatch none 0.5)
		(connect_pads
			(clearance 0)
		)
		(min_thickness 0.25)
		(keepout
			(tracks not_allowed)
			(vias allowed)
			(pads allowed)
			(copperpour not_allowed)
			(footprints allowed)
		)
		(placement
			(enabled no)
			(sheetname "")
		)
		(fill yes
			(thermal_gap 0.5)
			(thermal_bridge_width 0.5)
			(island_removal_mode 0)
		)
		(polygon
			(pts
				(arc
					(start 139.649708 -289.47618)
					(mid 139.019788 -289.47618)
					(end 139.649708 -289.47618)
				)
			)
		)
	)
	(zone
		(layers "B.Cu" "In13.Cu" "In15.Cu")
		(hatch none 0.5)
		(connect_pads
			(clearance 0)
		)
		(min_thickness 0.25)
		(keepout
			(tracks not_allowed)
			(vias allowed)
			(pads allowed)
			(copperpour not_allowed)
			(footprints allowed)
		)
		(placement
			(enabled no)
			(sheetname "")
		)
		(fill yes
			(thermal_gap 0.5)
			(thermal_bridge_width 0.5)
			(island_removal_mode 0)
		)
		(polygon
			(pts
				(arc
					(start 387.759702 -238.814102)
					(mid 387.129782 -238.814102)
					(end 387.759702 -238.814102)
				)
			)
		)
	)
	(zone
		(layers "B.Cu" "In13.Cu" "In15.Cu")
		(hatch none 0.5)
		(connect_pads
			(clearance 0)
		)
		(min_thickness 0.25)
		(keepout
			(tracks not_allowed)
			(vias allowed)
			(pads allowed)
			(copperpour not_allowed)
			(footprints allowed)
		)
		(placement
			(enabled no)
			(sheetname "")
		)
		(fill yes
			(thermal_gap 0.5)
			(thermal_bridge_width 0.5)
			(island_removal_mode 0)
		)
		(polygon
			(pts
				(arc
					(start 22.04212 -312.935366)
					(mid 21.3741 -312.935366)
					(end 22.04212 -312.935366)
				)
			)
		)
	)
	(zone
		(layers "B.Cu" "In13.Cu" "In15.Cu")
		(hatch none 0.5)
		(connect_pads
			(clearance 0)
		)
		(min_thickness 0.25)
		(keepout
			(tracks not_allowed)
			(vias allowed)
			(pads allowed)
			(copperpour not_allowed)
			(footprints allowed)
		)
		(placement
			(enabled no)
			(sheetname "")
		)
		(fill yes
			(thermal_gap 0.5)
			(thermal_bridge_width 0.5)
			(island_removal_mode 0)
		)
		(polygon
			(pts
				(arc
					(start 81.833974 -388.774432)
					(mid 81.204054 -388.774432)
					(end 81.833974 -388.774432)
				)
			)
		)
	)
	(zone
		(layers "B.Cu" "In13.Cu" "In15.Cu")
		(hatch none 0.5)
		(connect_pads
			(clearance 0)
		)
		(min_thickness 0.25)
		(keepout
			(tracks not_allowed)
			(vias allowed)
			(pads allowed)
			(copperpour not_allowed)
			(footprints allowed)
		)
		(placement
			(enabled no)
			(sheetname "")
		)
		(fill yes
			(thermal_gap 0.5)
			(thermal_bridge_width 0.5)
			(island_removal_mode 0)
		)
		(polygon
			(pts
				(arc
					(start 138.239754 -288.666174)
					(mid 137.609834 -288.666174)
					(end 138.239754 -288.666174)
				)
			)
		)
	)
	(zone
		(layers "B.Cu" "In13.Cu" "In15.Cu")
		(hatch none 0.5)
		(connect_pads
			(clearance 0)
		)
		(min_thickness 0.25)
		(keepout
			(tracks not_allowed)
			(vias allowed)
			(pads allowed)
			(copperpour not_allowed)
			(footprints allowed)
		)
		(placement
			(enabled no)
			(sheetname "")
		)
		(fill yes
			(thermal_gap 0.5)
			(thermal_bridge_width 0.5)
			(island_removal_mode 0)
		)
		(polygon
			(pts
				(arc
					(start 352.516186 -234.764072)
					(mid 351.886266 -234.764072)
					(end 352.516186 -234.764072)
				)
			)
		)
	)
	(zone
		(layers "B.Cu" "In13.Cu" "In15.Cu")
		(hatch none 0.5)
		(connect_pads
			(clearance 0)
		)
		(min_thickness 0.25)
		(keepout
			(tracks not_allowed)
			(vias allowed)
			(pads allowed)
			(copperpour not_allowed)
			(footprints allowed)
		)
		(placement
			(enabled no)
			(sheetname "")
		)
		(fill yes
			(thermal_gap 0.5)
			(thermal_bridge_width 0.5)
			(island_removal_mode 0)
		)
		(polygon
			(pts
				(arc
					(start 22.04212 -272.135346)
					(mid 21.3741 -272.135346)
					(end 22.04212 -272.135346)
				)
			)
		)
	)
	(zone
		(layers "B.Cu" "In13.Cu" "In15.Cu")
		(hatch none 0.5)
		(connect_pads
			(clearance 0)
		)
		(min_thickness 0.25)
		(keepout
			(tracks not_allowed)
			(vias allowed)
			(pads allowed)
			(copperpour not_allowed)
			(footprints allowed)
		)
		(placement
			(enabled no)
			(sheetname "")
		)
		(fill yes
			(thermal_gap 0.5)
			(thermal_bridge_width 0.5)
			(island_removal_mode 0)
		)
		(polygon
			(pts
				(arc
					(start 158.977076 -412.570168)
					(mid 158.309056 -412.570168)
					(end 158.977076 -412.570168)
				)
			)
		)
	)
	(zone
		(layers "B.Cu" "In13.Cu" "In15.Cu")
		(hatch none 0.5)
		(connect_pads
			(clearance 0)
		)
		(min_thickness 0.25)
		(keepout
			(tracks not_allowed)
			(vias allowed)
			(pads allowed)
			(copperpour not_allowed)
			(footprints allowed)
		)
		(placement
			(enabled no)
			(sheetname "")
		)
		(fill yes
			(thermal_gap 0.5)
			(thermal_bridge_width 0.5)
			(island_removal_mode 0)
		)
		(polygon
			(pts
				(arc
					(start 454.522078 -223.6851)
					(mid 453.854058 -223.6851)
					(end 454.522078 -223.6851)
				)
			)
		)
	)
	(zone
		(layers "B.Cu" "In13.Cu" "In15.Cu")
		(hatch none 0.5)
		(connect_pads
			(clearance 0)
		)
		(min_thickness 0.25)
		(keepout
			(tracks not_allowed)
			(vias allowed)
			(pads allowed)
			(copperpour not_allowed)
			(footprints allowed)
		)
		(placement
			(enabled no)
			(sheetname "")
		)
		(fill yes
			(thermal_gap 0.5)
			(thermal_bridge_width 0.5)
			(island_removal_mode 0)
		)
		(polygon
			(pts
				(arc
					(start 78.037182 -430.689766)
					(mid 77.26299 -430.689766)
					(end 78.037182 -430.689766)
				)
			)
		)
	)
	(zone
		(layers "B.Cu" "In13.Cu" "In15.Cu")
		(hatch none 0.5)
		(connect_pads
			(clearance 0)
		)
		(min_thickness 0.25)
		(keepout
			(tracks not_allowed)
			(vias allowed)
			(pads allowed)
			(copperpour not_allowed)
			(footprints allowed)
		)
		(placement
			(enabled no)
			(sheetname "")
		)
		(fill yes
			(thermal_gap 0.5)
			(thermal_bridge_width 0.5)
			(island_removal_mode 0)
		)
		(polygon
			(pts
				(arc
					(start 108.864654 -382.36906)
					(mid 108.196634 -382.36906)
					(end 108.864654 -382.36906)
				)
			)
		)
	)
	(zone
		(layers "B.Cu" "In13.Cu" "In15.Cu")
		(hatch none 0.5)
		(connect_pads
			(clearance 0)
		)
		(min_thickness 0.25)
		(keepout
			(tracks not_allowed)
			(vias allowed)
			(pads allowed)
			(copperpour not_allowed)
			(footprints allowed)
		)
		(placement
			(enabled no)
			(sheetname "")
		)
		(fill yes
			(thermal_gap 0.5)
			(thermal_bridge_width 0.5)
			(island_removal_mode 0)
		)
		(polygon
			(pts
				(arc
					(start 103.636064 -247.724422)
					(mid 103.006144 -247.724422)
					(end 103.636064 -247.724422)
				)
			)
		)
	)
	(zone
		(layers "B.Cu" "In13.Cu" "In15.Cu")
		(hatch none 0.5)
		(connect_pads
			(clearance 0)
		)
		(min_thickness 0.25)
		(keepout
			(tracks not_allowed)
			(vias allowed)
			(pads allowed)
			(copperpour not_allowed)
			(footprints allowed)
		)
		(placement
			(enabled no)
			(sheetname "")
		)
		(fill yes
			(thermal_gap 0.5)
			(thermal_bridge_width 0.5)
			(island_removal_mode 0)
		)
		(polygon
			(pts
				(arc
					(start 126.18974 -233.144314)
					(mid 125.55982 -233.144314)
					(end 126.18974 -233.144314)
				)
			)
		)
	)
	(zone
		(layers "B.Cu" "In13.Cu" "In15.Cu")
		(hatch none 0.5)
		(connect_pads
			(clearance 0)
		)
		(min_thickness 0.25)
		(keepout
			(tracks not_allowed)
			(vias allowed)
			(pads allowed)
			(copperpour not_allowed)
			(footprints allowed)
		)
		(placement
			(enabled no)
			(sheetname "")
		)
		(fill yes
			(thermal_gap 0.5)
			(thermal_bridge_width 0.5)
			(island_removal_mode 0)
		)
		(polygon
			(pts
				(arc
					(start 106.375454 -32.405066)
					(mid 105.707434 -32.405066)
					(end 106.375454 -32.405066)
				)
			)
		)
	)
	(zone
		(layers "B.Cu" "In13.Cu" "In15.Cu")
		(hatch none 0.5)
		(connect_pads
			(clearance 0)
		)
		(min_thickness 0.25)
		(keepout
			(tracks not_allowed)
			(vias allowed)
			(pads allowed)
			(copperpour not_allowed)
			(footprints allowed)
		)
		(placement
			(enabled no)
			(sheetname "")
		)
		(fill yes
			(thermal_gap 0.5)
			(thermal_bridge_width 0.5)
			(island_removal_mode 0)
		)
		(polygon
			(pts
				(arc
					(start 386.649722 -292.71595)
					(mid 386.019802 -292.71595)
					(end 386.649722 -292.71595)
				)
			)
		)
	)
	(zone
		(layers "B.Cu" "In13.Cu" "In15.Cu")
		(hatch none 0.5)
		(connect_pads
			(clearance 0)
		)
		(min_thickness 0.25)
		(keepout
			(tracks not_allowed)
			(vias allowed)
			(pads allowed)
			(copperpour not_allowed)
			(footprints allowed)
		)
		(placement
			(enabled no)
			(sheetname "")
		)
		(fill yes
			(thermal_gap 0.5)
			(thermal_bridge_width 0.5)
			(island_removal_mode 0)
		)
		(polygon
			(pts
				(arc
					(start 387.589776 -286.236156)
					(mid 386.959856 -286.236156)
					(end 387.589776 -286.236156)
				)
			)
		)
	)
	(zone
		(layers "B.Cu" "In13.Cu" "In15.Cu")
		(hatch none 0.5)
		(connect_pads
			(clearance 0)
		)
		(min_thickness 0.25)
		(keepout
			(tracks not_allowed)
			(vias allowed)
			(pads allowed)
			(copperpour not_allowed)
			(footprints allowed)
		)
		(placement
			(enabled no)
			(sheetname "")
		)
		(fill yes
			(thermal_gap 0.5)
			(thermal_bridge_width 0.5)
			(island_removal_mode 0)
		)
		(polygon
			(pts
				(arc
					(start 17.942052 -198.185278)
					(mid 17.274032 -198.185278)
					(end 17.942052 -198.185278)
				)
			)
		)
	)
	(zone
		(layers "B.Cu" "In13.Cu" "In15.Cu")
		(hatch none 0.5)
		(connect_pads
			(clearance 0)
		)
		(min_thickness 0.25)
		(keepout
			(tracks not_allowed)
			(vias allowed)
			(pads allowed)
			(copperpour not_allowed)
			(footprints allowed)
		)
		(placement
			(enabled no)
			(sheetname "")
		)
		(fill yes
			(thermal_gap 0.5)
			(thermal_bridge_width 0.5)
			(island_removal_mode 0)
		)
		(polygon
			(pts
				(arc
					(start 329.03668 -431.889916)
					(mid 328.262488 -431.889916)
					(end 329.03668 -431.889916)
				)
			)
		)
	)
	(zone
		(layers "B.Cu" "In13.Cu" "In15.Cu")
		(hatch none 0.5)
		(connect_pads
			(clearance 0)
		)
		(min_thickness 0.25)
		(keepout
			(tracks not_allowed)
			(vias allowed)
			(pads allowed)
			(copperpour not_allowed)
			(footprints allowed)
		)
		(placement
			(enabled no)
			(sheetname "")
		)
		(fill yes
			(thermal_gap 0.5)
			(thermal_bridge_width 0.5)
			(island_removal_mode 0)
		)
		(polygon
			(pts
				(arc
					(start 139.819634 -242.05438)
					(mid 139.189714 -242.05438)
					(end 139.819634 -242.05438)
				)
			)
		)
	)
	(zone
		(layers "B.Cu" "In13.Cu" "In15.Cu")
		(hatch none 0.5)
		(connect_pads
			(clearance 0)
		)
		(min_thickness 0.25)
		(keepout
			(tracks not_allowed)
			(vias allowed)
			(pads allowed)
			(copperpour not_allowed)
			(footprints allowed)
		)
		(placement
			(enabled no)
			(sheetname "")
		)
		(fill yes
			(thermal_gap 0.5)
			(thermal_bridge_width 0.5)
			(island_removal_mode 0)
		)
		(polygon
			(pts
				(arc
					(start 334.016096 -282.996132)
					(mid 333.386176 -282.996132)
					(end 334.016096 -282.996132)
				)
			)
		)
	)
	(zone
		(layers "B.Cu" "In13.Cu" "In15.Cu")
		(hatch none 0.5)
		(connect_pads
			(clearance 0)
		)
		(min_thickness 0.25)
		(keepout
			(tracks not_allowed)
			(vias allowed)
			(pads allowed)
			(copperpour not_allowed)
			(footprints allowed)
		)
		(placement
			(enabled no)
			(sheetname "")
		)
		(fill yes
			(thermal_gap 0.5)
			(thermal_bridge_width 0.5)
			(island_removal_mode 0)
		)
		(polygon
			(pts
				(arc
					(start 386.649722 -284.616144)
					(mid 386.019802 -284.616144)
					(end 386.649722 -284.616144)
				)
			)
		)
	)
	(zone
		(layers "B.Cu" "In13.Cu" "In15.Cu")
		(hatch none 0.5)
		(connect_pads
			(clearance 0)
		)
		(min_thickness 0.25)
		(keepout
			(tracks not_allowed)
			(vias allowed)
			(pads allowed)
			(copperpour not_allowed)
			(footprints allowed)
		)
		(placement
			(enabled no)
			(sheetname "")
		)
		(fill yes
			(thermal_gap 0.5)
			(thermal_bridge_width 0.5)
			(island_removal_mode 0)
		)
		(polygon
			(pts
				(arc
					(start 119.609616 -231.524302)
					(mid 118.979696 -231.524302)
					(end 119.609616 -231.524302)
				)
			)
		)
	)
	(zone
		(layers "B.Cu" "In13.Cu" "In15.Cu")
		(hatch none 0.5)
		(connect_pads
			(clearance 0)
		)
		(min_thickness 0.25)
		(keepout
			(tracks not_allowed)
			(vias allowed)
			(pads allowed)
			(copperpour not_allowed)
			(footprints allowed)
		)
		(placement
			(enabled no)
			(sheetname "")
		)
		(fill yes
			(thermal_gap 0.5)
			(thermal_bridge_width 0.5)
			(island_removal_mode 0)
		)
		(polygon
			(pts
				(arc
					(start 385.879848 -246.914162)
					(mid 385.249928 -246.914162)
					(end 385.879848 -246.914162)
				)
			)
		)
	)
	(zone
		(layers "B.Cu" "In13.Cu" "In15.Cu")
		(hatch none 0.5)
		(connect_pads
			(clearance 0)
		)
		(min_thickness 0.25)
		(keepout
			(tracks not_allowed)
			(vias allowed)
			(pads allowed)
			(copperpour not_allowed)
			(footprints allowed)
		)
		(placement
			(enabled no)
			(sheetname "")
		)
		(fill yes
			(thermal_gap 0.5)
			(thermal_bridge_width 0.5)
			(island_removal_mode 0)
		)
		(polygon
			(pts
				(arc
					(start 87.034116 -386.003292)
					(mid 86.404196 -386.003292)
					(end 87.034116 -386.003292)
				)
			)
		)
	)
	(zone
		(layers "B.Cu" "In13.Cu" "In15.Cu")
		(hatch none 0.5)
		(connect_pads
			(clearance 0)
		)
		(min_thickness 0.25)
		(keepout
			(tracks not_allowed)
			(vias allowed)
			(pads allowed)
			(copperpour not_allowed)
			(footprints allowed)
		)
		(placement
			(enabled no)
			(sheetname "")
		)
		(fill yes
			(thermal_gap 0.5)
			(thermal_bridge_width 0.5)
			(island_removal_mode 0)
		)
		(polygon
			(pts
				(arc
					(start 332.306168 -255.014222)
					(mid 331.676248 -255.014222)
					(end 332.306168 -255.014222)
				)
			)
		)
	)
	(zone
		(layers "B.Cu" "In13.Cu" "In15.Cu")
		(hatch none 0.5)
		(connect_pads
			(clearance 0)
		)
		(min_thickness 0.25)
		(keepout
			(tracks not_allowed)
			(vias allowed)
			(pads allowed)
			(copperpour not_allowed)
			(footprints allowed)
		)
		(placement
			(enabled no)
			(sheetname "")
		)
		(fill yes
			(thermal_gap 0.5)
			(thermal_bridge_width 0.5)
			(island_removal_mode 0)
		)
		(polygon
			(pts
				(arc
					(start 138.709654 -284.616398)
					(mid 138.079734 -284.616398)
					(end 138.709654 -284.616398)
				)
			)
		)
	)
	(zone
		(layers "B.Cu" "In13.Cu" "In15.Cu")
		(hatch none 0.5)
		(connect_pads
			(clearance 0)
		)
		(min_thickness 0.25)
		(keepout
			(tracks not_allowed)
			(vias allowed)
			(pads allowed)
			(copperpour not_allowed)
			(footprints allowed)
		)
		(placement
			(enabled no)
			(sheetname "")
		)
		(fill yes
			(thermal_gap 0.5)
			(thermal_bridge_width 0.5)
			(island_removal_mode 0)
		)
		(polygon
			(pts
				(arc
					(start 405.137112 -431.889916)
					(mid 404.36292 -431.889916)
					(end 405.137112 -431.889916)
				)
			)
		)
	)
	(zone
		(layers "B.Cu" "In13.Cu" "In15.Cu")
		(hatch none 0.5)
		(connect_pads
			(clearance 0)
		)
		(min_thickness 0.25)
		(keepout
			(tracks not_allowed)
			(vias allowed)
			(pads allowed)
			(copperpour not_allowed)
			(footprints allowed)
		)
		(placement
			(enabled no)
			(sheetname "")
		)
		(fill yes
			(thermal_gap 0.5)
			(thermal_bridge_width 0.5)
			(island_removal_mode 0)
		)
		(polygon
			(pts
				(arc
					(start 139.349734 -231.524302)
					(mid 138.719814 -231.524302)
					(end 139.349734 -231.524302)
				)
			)
		)
	)
	(zone
		(layers "B.Cu" "In13.Cu" "In15.Cu")
		(hatch none 0.5)
		(connect_pads
			(clearance 0)
		)
		(min_thickness 0.25)
		(keepout
			(tracks not_allowed)
			(vias allowed)
			(pads allowed)
			(copperpour not_allowed)
			(footprints allowed)
		)
		(placement
			(enabled no)
			(sheetname "")
		)
		(fill yes
			(thermal_gap 0.5)
			(thermal_bridge_width 0.5)
			(island_removal_mode 0)
		)
		(polygon
			(pts
				(arc
					(start 333.716122 -231.524048)
					(mid 333.086202 -231.524048)
					(end 333.716122 -231.524048)
				)
			)
		)
	)
	(zone
		(layers "B.Cu" "In13.Cu" "In15.Cu")
		(hatch none 0.5)
		(connect_pads
			(clearance 0)
		)
		(min_thickness 0.25)
		(keepout
			(tracks not_allowed)
			(vias allowed)
			(pads allowed)
			(copperpour not_allowed)
			(footprints allowed)
		)
		(placement
			(enabled no)
			(sheetname "")
		)
		(fill yes
			(thermal_gap 0.5)
			(thermal_bridge_width 0.5)
			(island_removal_mode 0)
		)
		(polygon
			(pts
				(arc
					(start 122.729752 -276.516338)
					(mid 122.099832 -276.516338)
					(end 122.729752 -276.516338)
				)
			)
		)
	)
	(zone
		(layers "B.Cu" "In13.Cu" "In15.Cu")
		(hatch none 0.5)
		(connect_pads
			(clearance 0)
		)
		(min_thickness 0.25)
		(keepout
			(tracks not_allowed)
			(vias allowed)
			(pads allowed)
			(copperpour not_allowed)
			(footprints allowed)
		)
		(placement
			(enabled no)
			(sheetname "")
		)
		(fill yes
			(thermal_gap 0.5)
			(thermal_bridge_width 0.5)
			(island_removal_mode 0)
		)
		(polygon
			(pts
				(arc
					(start 428.569628 -6.725158)
					(mid 427.901608 -6.725158)
					(end 428.569628 -6.725158)
				)
			)
		)
	)
	(zone
		(layers "B.Cu" "In13.Cu" "In15.Cu")
		(hatch none 0.5)
		(connect_pads
			(clearance 0)
		)
		(min_thickness 0.25)
		(keepout
			(tracks not_allowed)
			(vias allowed)
			(pads allowed)
			(copperpour not_allowed)
			(footprints allowed)
		)
		(placement
			(enabled no)
			(sheetname "")
		)
		(fill yes
			(thermal_gap 0.5)
			(thermal_bridge_width 0.5)
			(island_removal_mode 0)
		)
		(polygon
			(pts
				(arc
					(start 202.481942 -288.285428)
					(mid 201.813922 -288.285428)
					(end 202.481942 -288.285428)
				)
			)
		)
	)
	(zone
		(layers "B.Cu" "In13.Cu" "In15.Cu")
		(hatch none 0.5)
		(connect_pads
			(clearance 0)
		)
		(min_thickness 0.25)
		(keepout
			(tracks not_allowed)
			(vias allowed)
			(pads allowed)
			(copperpour not_allowed)
			(footprints allowed)
		)
		(placement
			(enabled no)
			(sheetname "")
		)
		(fill yes
			(thermal_gap 0.5)
			(thermal_bridge_width 0.5)
			(island_removal_mode 0)
		)
		(polygon
			(pts
				(arc
					(start 18.660872 -19.137122)
					(mid 17.992852 -19.137122)
					(end 18.660872 -19.137122)
				)
			)
		)
	)
	(zone
		(layers "B.Cu" "In13.Cu" "In15.Cu")
		(hatch none 0.5)
		(connect_pads
			(clearance 0)
		)
		(min_thickness 0.25)
		(keepout
			(tracks not_allowed)
			(vias allowed)
			(pads allowed)
			(copperpour not_allowed)
			(footprints allowed)
		)
		(placement
			(enabled no)
			(sheetname "")
		)
		(fill yes
			(thermal_gap 0.5)
			(thermal_bridge_width 0.5)
			(island_removal_mode 0)
		)
		(polygon
			(pts
				(arc
					(start 334.016096 -263.555988)
					(mid 333.386176 -263.555988)
					(end 334.016096 -263.555988)
				)
			)
		)
	)
	(zone
		(layers "B.Cu" "In13.Cu" "In15.Cu")
		(hatch none 0.5)
		(connect_pads
			(clearance 0)
		)
		(min_thickness 0.25)
		(keepout
			(tracks not_allowed)
			(vias allowed)
			(pads allowed)
			(copperpour not_allowed)
			(footprints allowed)
		)
		(placement
			(enabled no)
			(sheetname "")
		)
		(fill yes
			(thermal_gap 0.5)
			(thermal_bridge_width 0.5)
			(island_removal_mode 0)
		)
		(polygon
			(pts
				(arc
					(start 137.93978 -251.774452)
					(mid 137.30986 -251.774452)
					(end 137.93978 -251.774452)
				)
			)
		)
	)
	(zone
		(layers "B.Cu" "In13.Cu" "In15.Cu")
		(hatch none 0.5)
		(connect_pads
			(clearance 0)
		)
		(min_thickness 0.25)
		(keepout
			(tracks not_allowed)
			(vias allowed)
			(pads allowed)
			(copperpour not_allowed)
			(footprints allowed)
		)
		(placement
			(enabled no)
			(sheetname "")
		)
		(fill yes
			(thermal_gap 0.5)
			(thermal_bridge_width 0.5)
			(island_removal_mode 0)
		)
		(polygon
			(pts
				(arc
					(start 387.759702 -243.674138)
					(mid 387.129782 -243.674138)
					(end 387.759702 -243.674138)
				)
			)
		)
	)
	(zone
		(layers "B.Cu" "In13.Cu" "In15.Cu")
		(hatch none 0.5)
		(connect_pads
			(clearance 0)
		)
		(min_thickness 0.25)
		(keepout
			(tracks not_allowed)
			(vias allowed)
			(pads allowed)
			(copperpour not_allowed)
			(footprints allowed)
		)
		(placement
			(enabled no)
			(sheetname "")
		)
		(fill yes
			(thermal_gap 0.5)
			(thermal_bridge_width 0.5)
			(island_removal_mode 0)
		)
		(polygon
			(pts
				(arc
					(start 386.649722 -273.27606)
					(mid 386.019802 -273.27606)
					(end 386.649722 -273.27606)
				)
			)
		)
	)
	(zone
		(layers "B.Cu" "In13.Cu" "In15.Cu")
		(hatch none 0.5)
		(connect_pads
			(clearance 0)
		)
		(min_thickness 0.25)
		(keepout
			(tracks not_allowed)
			(vias allowed)
			(pads allowed)
			(copperpour not_allowed)
			(footprints allowed)
		)
		(placement
			(enabled no)
			(sheetname "")
		)
		(fill yes
			(thermal_gap 0.5)
			(thermal_bridge_width 0.5)
			(island_removal_mode 0)
		)
		(polygon
			(pts
				(arc
					(start 450.42201 -274.684998)
					(mid 449.75399 -274.684998)
					(end 450.42201 -274.684998)
				)
			)
		)
	)
	(zone
		(layers "B.Cu" "In13.Cu" "In15.Cu")
		(hatch none 0.5)
		(connect_pads
			(clearance 0)
		)
		(min_thickness 0.25)
		(keepout
			(tracks not_allowed)
			(vias allowed)
			(pads allowed)
			(copperpour not_allowed)
			(footprints allowed)
		)
		(placement
			(enabled no)
			(sheetname "")
		)
		(fill yes
			(thermal_gap 0.5)
			(thermal_bridge_width 0.5)
			(island_removal_mode 0)
		)
		(polygon
			(pts
				(arc
					(start 139.819634 -237.194344)
					(mid 139.189714 -237.194344)
					(end 139.819634 -237.194344)
				)
			)
		)
	)
	(zone
		(layers "B.Cu" "In13.Cu" "In15.Cu")
		(hatch none 0.5)
		(connect_pads
			(clearance 0)
		)
		(min_thickness 0.25)
		(keepout
			(tracks not_allowed)
			(vias allowed)
			(pads allowed)
			(copperpour not_allowed)
			(footprints allowed)
		)
		(placement
			(enabled no)
			(sheetname "")
		)
		(fill yes
			(thermal_gap 0.5)
			(thermal_bridge_width 0.5)
			(island_removal_mode 0)
		)
		(polygon
			(pts
				(arc
					(start 140.119608 -291.906198)
					(mid 139.489688 -291.906198)
					(end 140.119608 -291.906198)
				)
			)
		)
	)
	(zone
		(layers "B.Cu" "In13.Cu" "In15.Cu")
		(hatch none 0.5)
		(connect_pads
			(clearance 0)
		)
		(min_thickness 0.25)
		(keepout
			(tracks not_allowed)
			(vias allowed)
			(pads allowed)
			(copperpour not_allowed)
			(footprints allowed)
		)
		(placement
			(enabled no)
			(sheetname "")
		)
		(fill yes
			(thermal_gap 0.5)
			(thermal_bridge_width 0.5)
			(island_removal_mode 0)
		)
		(polygon
			(pts
				(arc
					(start 206.58201 -309.535322)
					(mid 205.91399 -309.535322)
					(end 206.58201 -309.535322)
				)
			)
		)
	)
	(zone
		(layers "B.Cu" "In13.Cu" "In15.Cu")
		(hatch none 0.5)
		(connect_pads
			(clearance 0)
		)
		(min_thickness 0.25)
		(keepout
			(tracks not_allowed)
			(vias allowed)
			(pads allowed)
			(copperpour not_allowed)
			(footprints allowed)
		)
		(placement
			(enabled no)
			(sheetname "")
		)
		(fill yes
			(thermal_gap 0.5)
			(thermal_bridge_width 0.5)
			(island_removal_mode 0)
		)
		(polygon
			(pts
				(arc
					(start 84.836 -229.90429)
					(mid 84.20608 -229.90429)
					(end 84.836 -229.90429)
				)
			)
		)
	)
	(zone
		(layers "B.Cu" "In13.Cu" "In15.Cu")
		(hatch none 0.5)
		(connect_pads
			(clearance 0)
		)
		(min_thickness 0.25)
		(keepout
			(tracks not_allowed)
			(vias allowed)
			(pads allowed)
			(copperpour not_allowed)
			(footprints allowed)
		)
		(placement
			(enabled no)
			(sheetname "")
		)
		(fill yes
			(thermal_gap 0.5)
			(thermal_bridge_width 0.5)
			(island_removal_mode 0)
		)
		(polygon
			(pts
				(arc
					(start 118.029736 -276.516338)
					(mid 117.399816 -276.516338)
					(end 118.029736 -276.516338)
				)
			)
		)
	)
	(zone
		(layers "B.Cu" "In13.Cu" "In15.Cu")
		(hatch none 0.5)
		(connect_pads
			(clearance 0)
		)
		(min_thickness 0.25)
		(keepout
			(tracks not_allowed)
			(vias allowed)
			(pads allowed)
			(copperpour not_allowed)
			(footprints allowed)
		)
		(placement
			(enabled no)
			(sheetname "")
		)
		(fill yes
			(thermal_gap 0.5)
			(thermal_bridge_width 0.5)
			(island_removal_mode 0)
		)
		(polygon
			(pts
				(arc
					(start 454.522078 -266.185142)
					(mid 453.854058 -266.185142)
					(end 454.522078 -266.185142)
				)
			)
		)
	)
	(zone
		(layers "B.Cu" "In13.Cu" "In15.Cu")
		(hatch none 0.5)
		(connect_pads
			(clearance 0)
		)
		(min_thickness 0.25)
		(keepout
			(tracks not_allowed)
			(vias allowed)
			(pads allowed)
			(copperpour not_allowed)
			(footprints allowed)
		)
		(placement
			(enabled no)
			(sheetname "")
		)
		(fill yes
			(thermal_gap 0.5)
			(thermal_bridge_width 0.5)
			(island_removal_mode 0)
		)
		(polygon
			(pts
				(arc
					(start 84.3661 -245.294404)
					(mid 83.73618 -245.294404)
					(end 84.3661 -245.294404)
				)
			)
		)
	)
	(zone
		(layers "B.Cu" "In13.Cu" "In15.Cu")
		(hatch none 0.5)
		(connect_pads
			(clearance 0)
		)
		(min_thickness 0.25)
		(keepout
			(tracks not_allowed)
			(vias allowed)
			(pads allowed)
			(copperpour not_allowed)
			(footprints allowed)
		)
		(placement
			(enabled no)
			(sheetname "")
		)
		(fill yes
			(thermal_gap 0.5)
			(thermal_bridge_width 0.5)
			(island_removal_mode 0)
		)
		(polygon
			(pts
				(arc
					(start 84.836 -238.00435)
					(mid 84.20608 -238.00435)
					(end 84.836 -238.00435)
				)
			)
		)
	)
	(zone
		(layers "B.Cu" "In13.Cu" "In15.Cu")
		(hatch none 0.5)
		(connect_pads
			(clearance 0)
		)
		(min_thickness 0.25)
		(keepout
			(tracks not_allowed)
			(vias allowed)
			(pads allowed)
			(copperpour not_allowed)
			(footprints allowed)
		)
		(placement
			(enabled no)
			(sheetname "")
		)
		(fill yes
			(thermal_gap 0.5)
			(thermal_bridge_width 0.5)
			(island_removal_mode 0)
		)
		(polygon
			(pts
				(arc
					(start 145.137124 -430.689766)
					(mid 144.362932 -430.689766)
					(end 145.137124 -430.689766)
				)
			)
		)
	)
	(zone
		(layers "B.Cu" "In13.Cu" "In15.Cu")
		(hatch none 0.5)
		(connect_pads
			(clearance 0)
		)
		(min_thickness 0.25)
		(keepout
			(tracks not_allowed)
			(vias allowed)
			(pads allowed)
			(copperpour not_allowed)
			(footprints allowed)
		)
		(placement
			(enabled no)
			(sheetname "")
		)
		(fill yes
			(thermal_gap 0.5)
			(thermal_bridge_width 0.5)
			(island_removal_mode 0)
		)
		(polygon
			(pts
				(arc
					(start 417.176712 -420.952168)
					(mid 416.508692 -420.952168)
					(end 417.176712 -420.952168)
				)
			)
		)
	)
	(zone
		(layers "B.Cu" "In13.Cu" "In15.Cu")
		(hatch none 0.5)
		(connect_pads
			(clearance 0)
		)
		(min_thickness 0.25)
		(keepout
			(tracks not_allowed)
			(vias allowed)
			(pads allowed)
			(copperpour not_allowed)
			(footprints allowed)
		)
		(placement
			(enabled no)
			(sheetname "")
		)
		(fill yes
			(thermal_gap 0.5)
			(thermal_bridge_width 0.5)
			(island_removal_mode 0)
		)
		(polygon
			(pts
				(arc
					(start 126.489714 -278.13635)
					(mid 125.859794 -278.13635)
					(end 126.489714 -278.13635)
				)
			)
		)
	)
	(zone
		(layers "B.Cu" "In13.Cu" "In15.Cu")
		(hatch none 0.5)
		(connect_pads
			(clearance 0)
		)
		(min_thickness 0.25)
		(keepout
			(tracks not_allowed)
			(vias allowed)
			(pads allowed)
			(copperpour not_allowed)
			(footprints allowed)
		)
		(placement
			(enabled no)
			(sheetname "")
		)
		(fill yes
			(thermal_gap 0.5)
			(thermal_bridge_width 0.5)
			(island_removal_mode 0)
		)
		(polygon
			(pts
				(arc
					(start 380.927102 -379.88113)
					(mid 380.259082 -379.88113)
					(end 380.927102 -379.88113)
				)
			)
		)
	)
	(zone
		(layers "B.Cu" "In13.Cu" "In15.Cu")
		(hatch none 0.5)
		(connect_pads
			(clearance 0)
		)
		(min_thickness 0.25)
		(keepout
			(tracks not_allowed)
			(vias allowed)
			(pads allowed)
			(copperpour not_allowed)
			(footprints allowed)
		)
		(placement
			(enabled no)
			(sheetname "")
		)
		(fill yes
			(thermal_gap 0.5)
			(thermal_bridge_width 0.5)
			(island_removal_mode 0)
		)
		(polygon
			(pts
				(arc
					(start 269.982188 -233.035094)
					(mid 269.314168 -233.035094)
					(end 269.982188 -233.035094)
				)
			)
		)
	)
	(zone
		(layers "B.Cu" "In13.Cu" "In15.Cu")
		(hatch none 0.5)
		(connect_pads
			(clearance 0)
		)
		(min_thickness 0.25)
		(keepout
			(tracks not_allowed)
			(vias allowed)
			(pads allowed)
			(copperpour not_allowed)
			(footprints allowed)
		)
		(placement
			(enabled no)
			(sheetname "")
		)
		(fill yes
			(thermal_gap 0.5)
			(thermal_bridge_width 0.5)
			(island_removal_mode 0)
		)
		(polygon
			(pts
				(arc
					(start 334.485996 -265.986006)
					(mid 333.856076 -265.986006)
					(end 334.485996 -265.986006)
				)
			)
		)
	)
	(zone
		(layers "B.Cu" "In13.Cu" "In15.Cu")
		(hatch none 0.5)
		(connect_pads
			(clearance 0)
		)
		(min_thickness 0.25)
		(keepout
			(tracks not_allowed)
			(vias allowed)
			(pads allowed)
			(copperpour not_allowed)
			(footprints allowed)
		)
		(placement
			(enabled no)
			(sheetname "")
		)
		(fill yes
			(thermal_gap 0.5)
			(thermal_bridge_width 0.5)
			(island_removal_mode 0)
		)
		(polygon
			(pts
				(arc
					(start 345.936062 -233.14406)
					(mid 345.306142 -233.14406)
					(end 345.936062 -233.14406)
				)
			)
		)
	)
	(zone
		(layers "B.Cu" "In13.Cu" "In15.Cu")
		(hatch none 0.5)
		(connect_pads
			(clearance 0)
		)
		(min_thickness 0.25)
		(keepout
			(tracks not_allowed)
			(vias allowed)
			(pads allowed)
			(copperpour not_allowed)
			(footprints allowed)
		)
		(placement
			(enabled no)
			(sheetname "")
		)
		(fill yes
			(thermal_gap 0.5)
			(thermal_bridge_width 0.5)
			(island_removal_mode 0)
		)
		(polygon
			(pts
				(arc
					(start 333.716122 -229.904036)
					(mid 333.086202 -229.904036)
					(end 333.716122 -229.904036)
				)
			)
		)
	)
	(zone
		(layers "B.Cu" "In13.Cu" "In15.Cu")
		(hatch none 0.5)
		(connect_pads
			(clearance 0)
		)
		(min_thickness 0.25)
		(keepout
			(tracks not_allowed)
			(vias allowed)
			(pads allowed)
			(copperpour not_allowed)
			(footprints allowed)
		)
		(placement
			(enabled no)
			(sheetname "")
		)
		(fill yes
			(thermal_gap 0.5)
			(thermal_bridge_width 0.5)
			(island_removal_mode 0)
		)
		(polygon
			(pts
				(arc
					(start 385.879848 -255.014222)
					(mid 385.249928 -255.014222)
					(end 385.879848 -255.014222)
				)
			)
		)
	)
	(zone
		(layers "B.Cu" "In13.Cu" "In15.Cu")
		(hatch none 0.5)
		(connect_pads
			(clearance 0)
		)
		(min_thickness 0.25)
		(keepout
			(tracks not_allowed)
			(vias allowed)
			(pads allowed)
			(copperpour not_allowed)
			(footprints allowed)
		)
		(placement
			(enabled no)
			(sheetname "")
		)
		(fill yes
			(thermal_gap 0.5)
			(thermal_bridge_width 0.5)
			(island_removal_mode 0)
		)
		(polygon
			(pts
				(arc
					(start 331.697076 -420.952168)
					(mid 331.029056 -420.952168)
					(end 331.697076 -420.952168)
				)
			)
		)
	)
	(zone
		(layers "B.Cu" "In13.Cu" "In15.Cu")
		(hatch none 0.5)
		(connect_pads
			(clearance 0)
		)
		(min_thickness 0.25)
		(keepout
			(tracks not_allowed)
			(vias allowed)
			(pads allowed)
			(copperpour not_allowed)
			(footprints allowed)
		)
		(placement
			(enabled no)
			(sheetname "")
		)
		(fill yes
			(thermal_gap 0.5)
			(thermal_bridge_width 0.5)
			(island_removal_mode 0)
		)
		(polygon
			(pts
				(arc
					(start 93.83395 -388.774432)
					(mid 93.20403 -388.774432)
					(end 93.83395 -388.774432)
				)
			)
		)
	)
	(zone
		(layers "B.Cu" "In13.Cu" "In15.Cu")
		(hatch none 0.5)
		(connect_pads
			(clearance 0)
		)
		(min_thickness 0.25)
		(keepout
			(tracks not_allowed)
			(vias allowed)
			(pads allowed)
			(copperpour not_allowed)
			(footprints allowed)
		)
		(placement
			(enabled no)
			(sheetname "")
		)
		(fill yes
			(thermal_gap 0.5)
			(thermal_bridge_width 0.5)
			(island_removal_mode 0)
		)
		(polygon
			(pts
				(arc
					(start 67.371214 -412.570168)
					(mid 66.703194 -412.570168)
					(end 67.371214 -412.570168)
				)
			)
		)
	)
	(zone
		(layers "B.Cu" "In13.Cu" "In15.Cu")
		(hatch none 0.5)
		(connect_pads
			(clearance 0)
		)
		(min_thickness 0.25)
		(keepout
			(tracks not_allowed)
			(vias allowed)
			(pads allowed)
			(copperpour not_allowed)
			(footprints allowed)
		)
		(placement
			(enabled no)
			(sheetname "")
		)
		(fill yes
			(thermal_gap 0.5)
			(thermal_bridge_width 0.5)
			(island_removal_mode 0)
		)
		(polygon
			(pts
				(arc
					(start 265.88212 -215.18499)
					(mid 265.2141 -215.18499)
					(end 265.88212 -215.18499)
				)
			)
		)
	)
	(zone
		(layers "B.Cu" "In13.Cu" "In15.Cu")
		(hatch none 0.5)
		(connect_pads
			(clearance 0)
		)
		(min_thickness 0.25)
		(keepout
			(tracks not_allowed)
			(vias allowed)
			(pads allowed)
			(copperpour not_allowed)
			(footprints allowed)
		)
		(placement
			(enabled no)
			(sheetname "")
		)
		(fill yes
			(thermal_gap 0.5)
			(thermal_bridge_width 0.5)
			(island_removal_mode 0)
		)
		(polygon
			(pts
				(arc
					(start 386.349748 -233.14406)
					(mid 385.719828 -233.14406)
					(end 386.349748 -233.14406)
				)
			)
		)
	)
	(zone
		(layers "B.Cu" "In13.Cu" "In15.Cu")
		(hatch none 0.5)
		(connect_pads
			(clearance 0)
		)
		(min_thickness 0.25)
		(keepout
			(tracks not_allowed)
			(vias allowed)
			(pads allowed)
			(copperpour not_allowed)
			(footprints allowed)
		)
		(placement
			(enabled no)
			(sheetname "")
		)
		(fill yes
			(thermal_gap 0.5)
			(thermal_bridge_width 0.5)
			(island_removal_mode 0)
		)
		(polygon
			(pts
				(arc
					(start 137.93978 -232.334308)
					(mid 137.30986 -232.334308)
					(end 137.93978 -232.334308)
				)
			)
		)
	)
	(zone
		(layers "B.Cu" "In13.Cu" "In15.Cu")
		(hatch none 0.5)
		(connect_pads
			(clearance 0)
		)
		(min_thickness 0.25)
		(keepout
			(tracks not_allowed)
			(vias allowed)
			(pads allowed)
			(copperpour not_allowed)
			(footprints allowed)
		)
		(placement
			(enabled no)
			(sheetname "")
		)
		(fill yes
			(thermal_gap 0.5)
			(thermal_bridge_width 0.5)
			(island_removal_mode 0)
		)
		(polygon
			(pts
				(arc
					(start 83.034124 -385.31038)
					(mid 82.404204 -385.31038)
					(end 83.034124 -385.31038)
				)
			)
		)
	)
	(zone
		(layers "B.Cu" "In13.Cu" "In15.Cu")
		(hatch none 0.5)
		(connect_pads
			(clearance 0)
		)
		(min_thickness 0.25)
		(keepout
			(tracks not_allowed)
			(vias allowed)
			(pads allowed)
			(copperpour not_allowed)
			(footprints allowed)
		)
		(placement
			(enabled no)
			(sheetname "")
		)
		(fill yes
			(thermal_gap 0.5)
			(thermal_bridge_width 0.5)
			(island_removal_mode 0)
		)
		(polygon
			(pts
				(arc
					(start 206.58201 -313.78525)
					(mid 205.91399 -313.78525)
					(end 206.58201 -313.78525)
				)
			)
		)
	)
	(zone
		(layers "B.Cu" "In13.Cu" "In15.Cu")
		(hatch none 0.5)
		(connect_pads
			(clearance 0)
		)
		(min_thickness 0.25)
		(keepout
			(tracks not_allowed)
			(vias allowed)
			(pads allowed)
			(copperpour not_allowed)
			(footprints allowed)
		)
		(placement
			(enabled no)
			(sheetname "")
		)
		(fill yes
			(thermal_gap 0.5)
			(thermal_bridge_width 0.5)
			(island_removal_mode 0)
		)
		(polygon
			(pts
				(arc
					(start 17.942052 -243.235226)
					(mid 17.274032 -243.235226)
					(end 17.942052 -243.235226)
				)
			)
		)
	)
	(zone
		(layers "B.Cu" "In13.Cu" "In15.Cu")
		(hatch none 0.5)
		(connect_pads
			(clearance 0)
		)
		(min_thickness 0.25)
		(keepout
			(tracks not_allowed)
			(vias allowed)
			(pads allowed)
			(copperpour not_allowed)
			(footprints allowed)
		)
		(placement
			(enabled no)
			(sheetname "")
		)
		(fill yes
			(thermal_gap 0.5)
			(thermal_bridge_width 0.5)
			(island_removal_mode 0)
		)
		(polygon
			(pts
				(arc
					(start 17.942052 -238.985298)
					(mid 17.274032 -238.985298)
					(end 17.942052 -238.985298)
				)
			)
		)
	)
	(zone
		(layers "B.Cu" "In13.Cu" "In15.Cu")
		(hatch none 0.5)
		(connect_pads
			(clearance 0)
		)
		(min_thickness 0.25)
		(keepout
			(tracks not_allowed)
			(vias allowed)
			(pads allowed)
			(copperpour not_allowed)
			(footprints allowed)
		)
		(placement
			(enabled no)
			(sheetname "")
		)
		(fill yes
			(thermal_gap 0.5)
			(thermal_bridge_width 0.5)
			(island_removal_mode 0)
		)
		(polygon
			(pts
				(arc
					(start 333.076042 -273.27606)
					(mid 332.446122 -273.27606)
					(end 333.076042 -273.27606)
				)
			)
		)
	)
	(zone
		(layers "B.Cu" "In13.Cu" "In15.Cu")
		(hatch none 0.5)
		(connect_pads
			(clearance 0)
		)
		(min_thickness 0.25)
		(keepout
			(tracks not_allowed)
			(vias allowed)
			(pads allowed)
			(copperpour not_allowed)
			(footprints allowed)
		)
		(placement
			(enabled no)
			(sheetname "")
		)
		(fill yes
			(thermal_gap 0.5)
			(thermal_bridge_width 0.5)
			(island_removal_mode 0)
		)
		(polygon
			(pts
				(arc
					(start 81.823814 -412.570168)
					(mid 81.155794 -412.570168)
					(end 81.823814 -412.570168)
				)
			)
		)
	)
	(zone
		(layers "B.Cu" "In13.Cu" "In15.Cu")
		(hatch none 0.5)
		(connect_pads
			(clearance 0)
		)
		(min_thickness 0.25)
		(keepout
			(tracks not_allowed)
			(vias allowed)
			(pads allowed)
			(copperpour not_allowed)
			(footprints allowed)
		)
		(placement
			(enabled no)
			(sheetname "")
		)
		(fill yes
			(thermal_gap 0.5)
			(thermal_bridge_width 0.5)
			(island_removal_mode 0)
		)
		(polygon
			(pts
				(arc
					(start 344.813636 -420.952168)
					(mid 344.145616 -420.952168)
					(end 344.813636 -420.952168)
				)
			)
		)
	)
	(zone
		(layers "B.Cu" "In13.Cu" "In15.Cu")
		(hatch none 0.5)
		(connect_pads
			(clearance 0)
		)
		(min_thickness 0.25)
		(keepout
			(tracks not_allowed)
			(vias allowed)
			(pads allowed)
			(copperpour not_allowed)
			(footprints allowed)
		)
		(placement
			(enabled no)
			(sheetname "")
		)
		(fill yes
			(thermal_gap 0.5)
			(thermal_bridge_width 0.5)
			(island_removal_mode 0)
		)
		(polygon
			(pts
				(arc
					(start 386.349748 -254.204216)
					(mid 385.719828 -254.204216)
					(end 386.349748 -254.204216)
				)
			)
		)
	)
	(zone
		(layers "B.Cu" "In13.Cu" "In15.Cu")
		(hatch none 0.5)
		(connect_pads
			(clearance 0)
		)
		(min_thickness 0.25)
		(keepout
			(tracks not_allowed)
			(vias allowed)
			(pads allowed)
			(copperpour not_allowed)
			(footprints allowed)
		)
		(placement
			(enabled no)
			(sheetname "")
		)
		(fill yes
			(thermal_gap 0.5)
			(thermal_bridge_width 0.5)
			(island_removal_mode 0)
		)
		(polygon
			(pts
				(arc
					(start 333.716122 -239.624108)
					(mid 333.086202 -239.624108)
					(end 333.716122 -239.624108)
				)
			)
		)
	)
	(zone
		(layers "B.Cu" "In13.Cu" "In15.Cu")
		(hatch none 0.5)
		(connect_pads
			(clearance 0)
		)
		(min_thickness 0.25)
		(keepout
			(tracks not_allowed)
			(vias allowed)
			(pads allowed)
			(copperpour not_allowed)
			(footprints allowed)
		)
		(placement
			(enabled no)
			(sheetname "")
		)
		(fill yes
			(thermal_gap 0.5)
			(thermal_bridge_width 0.5)
			(island_removal_mode 0)
		)
		(polygon
			(pts
				(arc
					(start 147.13712 -429.689768)
					(mid 146.362928 -429.689768)
					(end 147.13712 -429.689768)
				)
			)
		)
	)
	(zone
		(layers "B.Cu" "In13.Cu" "In15.Cu")
		(hatch none 0.5)
		(connect_pads
			(clearance 0)
		)
		(min_thickness 0.25)
		(keepout
			(tracks not_allowed)
			(vias allowed)
			(pads allowed)
			(copperpour not_allowed)
			(footprints allowed)
		)
		(placement
			(enabled no)
			(sheetname "")
		)
		(fill yes
			(thermal_gap 0.5)
			(thermal_bridge_width 0.5)
			(island_removal_mode 0)
		)
		(polygon
			(pts
				(arc
					(start 313.317636 -420.952168)
					(mid 312.649616 -420.952168)
					(end 313.317636 -420.952168)
				)
			)
		)
	)
	(zone
		(layers "B.Cu" "In13.Cu" "In15.Cu")
		(hatch none 0.5)
		(connect_pads
			(clearance 0)
		)
		(min_thickness 0.25)
		(keepout
			(tracks not_allowed)
			(vias allowed)
			(pads allowed)
			(copperpour not_allowed)
			(footprints allowed)
		)
		(placement
			(enabled no)
			(sheetname "")
		)
		(fill yes
			(thermal_gap 0.5)
			(thermal_bridge_width 0.5)
			(island_removal_mode 0)
		)
		(polygon
			(pts
				(arc
					(start 450.42201 -278.93518)
					(mid 449.75399 -278.93518)
					(end 450.42201 -278.93518)
				)
			)
		)
	)
	(zone
		(layers "B.Cu" "In13.Cu" "In15.Cu")
		(hatch none 0.5)
		(connect_pads
			(clearance 0)
		)
		(min_thickness 0.25)
		(keepout
			(tracks not_allowed)
			(vias allowed)
			(pads allowed)
			(copperpour not_allowed)
			(footprints allowed)
		)
		(placement
			(enabled no)
			(sheetname "")
		)
		(fill yes
			(thermal_gap 0.5)
			(thermal_bridge_width 0.5)
			(island_removal_mode 0)
		)
		(polygon
			(pts
				(arc
					(start 111.312706 -371.49913)
					(mid 110.644686 -371.49913)
					(end 111.312706 -371.49913)
				)
			)
		)
	)
	(zone
		(layers "B.Cu" "In13.Cu" "In15.Cu")
		(hatch none 0.5)
		(connect_pads
			(clearance 0)
		)
		(min_thickness 0.25)
		(keepout
			(tracks not_allowed)
			(vias allowed)
			(pads allowed)
			(copperpour not_allowed)
			(footprints allowed)
		)
		(placement
			(enabled no)
			(sheetname "")
		)
		(fill yes
			(thermal_gap 0.5)
			(thermal_bridge_width 0.5)
			(island_removal_mode 0)
		)
		(polygon
			(pts
				(arc
					(start 374.119902 -379.88113)
					(mid 373.451882 -379.88113)
					(end 374.119902 -379.88113)
				)
			)
		)
	)
	(zone
		(layers "B.Cu" "In13.Cu" "In15.Cu")
		(hatch none 0.5)
		(connect_pads
			(clearance 0)
		)
		(min_thickness 0.25)
		(keepout
			(tracks not_allowed)
			(vias allowed)
			(pads allowed)
			(copperpour not_allowed)
			(footprints allowed)
		)
		(placement
			(enabled no)
			(sheetname "")
		)
		(fill yes
			(thermal_gap 0.5)
			(thermal_bridge_width 0.5)
			(island_removal_mode 0)
		)
		(polygon
			(pts
				(arc
					(start 22.04212 -295.085262)
					(mid 21.3741 -295.085262)
					(end 22.04212 -295.085262)
				)
			)
		)
	)
	(zone
		(layers "B.Cu" "In13.Cu" "In15.Cu")
		(hatch none 0.5)
		(connect_pads
			(clearance 0)
		)
		(min_thickness 0.25)
		(keepout
			(tracks not_allowed)
			(vias allowed)
			(pads allowed)
			(copperpour not_allowed)
			(footprints allowed)
		)
		(placement
			(enabled no)
			(sheetname "")
		)
		(fill yes
			(thermal_gap 0.5)
			(thermal_bridge_width 0.5)
			(island_removal_mode 0)
		)
		(polygon
			(pts
				(arc
					(start 454.522078 -240.685066)
					(mid 453.854058 -240.685066)
					(end 454.522078 -240.685066)
				)
			)
		)
	)
	(zone
		(layers "B.Cu" "In13.Cu" "In15.Cu")
		(hatch none 0.5)
		(connect_pads
			(clearance 0)
		)
		(min_thickness 0.25)
		(keepout
			(tracks not_allowed)
			(vias allowed)
			(pads allowed)
			(copperpour not_allowed)
			(footprints allowed)
		)
		(placement
			(enabled no)
			(sheetname "")
		)
		(fill yes
			(thermal_gap 0.5)
			(thermal_bridge_width 0.5)
			(island_removal_mode 0)
		)
		(polygon
			(pts
				(arc
					(start 139.819634 -255.014476)
					(mid 139.189714 -255.014476)
					(end 139.819634 -255.014476)
				)
			)
		)
	)
	(zone
		(layers "B.Cu" "In13.Cu" "In15.Cu")
		(hatch none 0.5)
		(connect_pads
			(clearance 0)
		)
		(min_thickness 0.25)
		(keepout
			(tracks not_allowed)
			(vias allowed)
			(pads allowed)
			(copperpour not_allowed)
			(footprints allowed)
		)
		(placement
			(enabled no)
			(sheetname "")
		)
		(fill yes
			(thermal_gap 0.5)
			(thermal_bridge_width 0.5)
			(island_removal_mode 0)
		)
		(polygon
			(pts
				(arc
					(start 364.86465 -389.88746)
					(mid 364.19663 -389.88746)
					(end 364.86465 -389.88746)
				)
			)
		)
	)
	(zone
		(layers "B.Cu" "In13.Cu" "In15.Cu")
		(hatch none 0.5)
		(connect_pads
			(clearance 0)
		)
		(min_thickness 0.25)
		(keepout
			(tracks not_allowed)
			(vias allowed)
			(pads allowed)
			(copperpour not_allowed)
			(footprints allowed)
		)
		(placement
			(enabled no)
			(sheetname "")
		)
		(fill yes
			(thermal_gap 0.5)
			(thermal_bridge_width 0.5)
			(island_removal_mode 0)
		)
		(polygon
			(pts
				(arc
					(start 374.429782 -274.896072)
					(mid 373.799862 -274.896072)
					(end 374.429782 -274.896072)
				)
			)
		)
	)
	(zone
		(layers "B.Cu" "In13.Cu" "In15.Cu")
		(hatch none 0.5)
		(connect_pads
			(clearance 0)
		)
		(min_thickness 0.25)
		(keepout
			(tracks not_allowed)
			(vias allowed)
			(pads allowed)
			(copperpour not_allowed)
			(footprints allowed)
		)
		(placement
			(enabled no)
			(sheetname "")
		)
		(fill yes
			(thermal_gap 0.5)
			(thermal_bridge_width 0.5)
			(island_removal_mode 0)
		)
		(polygon
			(pts
				(arc
					(start 120.849644 -274.896326)
					(mid 120.219724 -274.896326)
					(end 120.849644 -274.896326)
				)
			)
		)
	)
	(zone
		(layers "B.Cu" "In13.Cu" "In15.Cu")
		(hatch none 0.5)
		(connect_pads
			(clearance 0)
		)
		(min_thickness 0.25)
		(keepout
			(tracks not_allowed)
			(vias allowed)
			(pads allowed)
			(copperpour not_allowed)
			(footprints allowed)
		)
		(placement
			(enabled no)
			(sheetname "")
		)
		(fill yes
			(thermal_gap 0.5)
			(thermal_bridge_width 0.5)
			(island_removal_mode 0)
		)
		(polygon
			(pts
				(arc
					(start 22.04212 -203.285344)
					(mid 21.3741 -203.285344)
					(end 22.04212 -203.285344)
				)
			)
		)
	)
	(zone
		(layers "B.Cu" "In13.Cu" "In15.Cu")
		(hatch none 0.5)
		(connect_pads
			(clearance 0)
		)
		(min_thickness 0.25)
		(keepout
			(tracks not_allowed)
			(vias allowed)
			(pads allowed)
			(copperpour not_allowed)
			(footprints allowed)
		)
		(placement
			(enabled no)
			(sheetname "")
		)
		(fill yes
			(thermal_gap 0.5)
			(thermal_bridge_width 0.5)
			(island_removal_mode 0)
		)
		(polygon
			(pts
				(arc
					(start 137.93978 -237.194344)
					(mid 137.30986 -237.194344)
					(end 137.93978 -237.194344)
				)
			)
		)
	)
	(zone
		(layers "B.Cu" "In13.Cu" "In15.Cu")
		(hatch none 0.5)
		(connect_pads
			(clearance 0)
		)
		(min_thickness 0.25)
		(keepout
			(tracks not_allowed)
			(vias allowed)
			(pads allowed)
			(copperpour not_allowed)
			(footprints allowed)
		)
		(placement
			(enabled no)
			(sheetname "")
		)
		(fill yes
			(thermal_gap 0.5)
			(thermal_bridge_width 0.5)
			(island_removal_mode 0)
		)
		(polygon
			(pts
				(arc
					(start 139.819634 -225.854514)
					(mid 139.189714 -225.854514)
					(end 139.819634 -225.854514)
				)
			)
		)
	)
	(zone
		(layers "B.Cu" "In13.Cu" "In15.Cu")
		(hatch none 0.5)
		(connect_pads
			(clearance 0)
		)
		(min_thickness 0.25)
		(keepout
			(tracks not_allowed)
			(vias allowed)
			(pads allowed)
			(copperpour not_allowed)
			(footprints allowed)
		)
		(placement
			(enabled no)
			(sheetname "")
		)
		(fill yes
			(thermal_gap 0.5)
			(thermal_bridge_width 0.5)
			(island_removal_mode 0)
		)
		(polygon
			(pts
				(arc
					(start 84.3661 -233.95432)
					(mid 83.73618 -233.95432)
					(end 84.3661 -233.95432)
				)
			)
		)
	)
	(zone
		(layers "B.Cu" "In13.Cu" "In15.Cu")
		(hatch none 0.5)
		(connect_pads
			(clearance 0)
		)
		(min_thickness 0.25)
		(keepout
			(tracks not_allowed)
			(vias allowed)
			(pads allowed)
			(copperpour not_allowed)
			(footprints allowed)
		)
		(placement
			(enabled no)
			(sheetname "")
		)
		(fill yes
			(thermal_gap 0.5)
			(thermal_bridge_width 0.5)
			(island_removal_mode 0)
		)
		(polygon
			(pts
				(arc
					(start 334.186022 -232.334054)
					(mid 333.556102 -232.334054)
					(end 334.186022 -232.334054)
				)
			)
		)
	)
	(zone
		(layers "B.Cu" "In13.Cu" "In15.Cu")
		(hatch none 0.5)
		(connect_pads
			(clearance 0)
		)
		(min_thickness 0.25)
		(keepout
			(tracks not_allowed)
			(vias allowed)
			(pads allowed)
			(copperpour not_allowed)
			(footprints allowed)
		)
		(placement
			(enabled no)
			(sheetname "")
		)
		(fill yes
			(thermal_gap 0.5)
			(thermal_bridge_width 0.5)
			(island_removal_mode 0)
		)
		(polygon
			(pts
				(arc
					(start 125.249686 -233.144314)
					(mid 124.619766 -233.144314)
					(end 125.249686 -233.144314)
				)
			)
		)
	)
	(zone
		(layers "B.Cu" "In13.Cu" "In15.Cu")
		(hatch none 0.5)
		(connect_pads
			(clearance 0)
		)
		(min_thickness 0.25)
		(keepout
			(tracks not_allowed)
			(vias allowed)
			(pads allowed)
			(copperpour not_allowed)
			(footprints allowed)
		)
		(placement
			(enabled no)
			(sheetname "")
		)
		(fill yes
			(thermal_gap 0.5)
			(thermal_bridge_width 0.5)
			(island_removal_mode 0)
		)
		(polygon
			(pts
				(arc
					(start 351.876106 -274.896072)
					(mid 351.246186 -274.896072)
					(end 351.876106 -274.896072)
				)
			)
		)
	)
	(zone
		(layers "B.Cu" "In13.Cu" "In15.Cu")
		(hatch none 0.5)
		(connect_pads
			(clearance 0)
		)
		(min_thickness 0.25)
		(keepout
			(tracks not_allowed)
			(vias allowed)
			(pads allowed)
			(copperpour not_allowed)
			(footprints allowed)
		)
		(placement
			(enabled no)
			(sheetname "")
		)
		(fill yes
			(thermal_gap 0.5)
			(thermal_bridge_width 0.5)
			(island_removal_mode 0)
		)
		(polygon
			(pts
				(arc
					(start 206.58201 -275.53539)
					(mid 205.91399 -275.53539)
					(end 206.58201 -275.53539)
				)
			)
		)
	)
	(zone
		(layers "B.Cu" "In13.Cu" "In15.Cu")
		(hatch none 0.5)
		(connect_pads
			(clearance 0)
		)
		(min_thickness 0.25)
		(keepout
			(tracks not_allowed)
			(vias allowed)
			(pads allowed)
			(copperpour not_allowed)
			(footprints allowed)
		)
		(placement
			(enabled no)
			(sheetname "")
		)
		(fill yes
			(thermal_gap 0.5)
			(thermal_bridge_width 0.5)
			(island_removal_mode 0)
		)
		(polygon
			(pts
				(arc
					(start 22.04212 -214.33536)
					(mid 21.3741 -214.33536)
					(end 22.04212 -214.33536)
				)
			)
		)
	)
	(zone
		(layers "B.Cu" "In13.Cu" "In15.Cu")
		(hatch none 0.5)
		(connect_pads
			(clearance 0)
		)
		(min_thickness 0.25)
		(keepout
			(tracks not_allowed)
			(vias allowed)
			(pads allowed)
			(copperpour not_allowed)
			(footprints allowed)
		)
		(placement
			(enabled no)
			(sheetname "")
		)
		(fill yes
			(thermal_gap 0.5)
			(thermal_bridge_width 0.5)
			(island_removal_mode 0)
		)
		(polygon
			(pts
				(arc
					(start 269.982188 -210.935062)
					(mid 269.314168 -210.935062)
					(end 269.982188 -210.935062)
				)
			)
		)
	)
	(zone
		(layers "B.Cu" "In13.Cu" "In15.Cu")
		(hatch none 0.5)
		(connect_pads
			(clearance 0)
		)
		(min_thickness 0.25)
		(keepout
			(tracks not_allowed)
			(vias allowed)
			(pads allowed)
			(copperpour not_allowed)
			(footprints allowed)
		)
		(placement
			(enabled no)
			(sheetname "")
		)
		(fill yes
			(thermal_gap 0.5)
			(thermal_bridge_width 0.5)
			(island_removal_mode 0)
		)
		(polygon
			(pts
				(arc
					(start 110.046008 -277.326344)
					(mid 109.416088 -277.326344)
					(end 110.046008 -277.326344)
				)
			)
		)
	)
	(zone
		(layers "B.Cu" "In13.Cu" "In15.Cu")
		(hatch none 0.5)
		(connect_pads
			(clearance 0)
		)
		(min_thickness 0.25)
		(keepout
			(tracks not_allowed)
			(vias allowed)
			(pads allowed)
			(copperpour not_allowed)
			(footprints allowed)
		)
		(placement
			(enabled no)
			(sheetname "")
		)
		(fill yes
			(thermal_gap 0.5)
			(thermal_bridge_width 0.5)
			(island_removal_mode 0)
		)
		(polygon
			(pts
				(arc
					(start 99.034092 -386.003292)
					(mid 98.404172 -386.003292)
					(end 99.034092 -386.003292)
				)
			)
		)
	)
	(zone
		(layers "B.Cu" "In13.Cu" "In15.Cu")
		(hatch none 0.5)
		(connect_pads
			(clearance 0)
		)
		(min_thickness 0.25)
		(keepout
			(tracks not_allowed)
			(vias allowed)
			(pads allowed)
			(copperpour not_allowed)
			(footprints allowed)
		)
		(placement
			(enabled no)
			(sheetname "")
		)
		(fill yes
			(thermal_gap 0.5)
			(thermal_bridge_width 0.5)
			(island_removal_mode 0)
		)
		(polygon
			(pts
				(arc
					(start 86.245954 -245.294404)
					(mid 85.616034 -245.294404)
					(end 86.245954 -245.294404)
				)
			)
		)
	)
	(zone
		(layers "B.Cu" "In13.Cu" "In15.Cu")
		(hatch none 0.5)
		(connect_pads
			(clearance 0)
		)
		(min_thickness 0.25)
		(keepout
			(tracks not_allowed)
			(vias allowed)
			(pads allowed)
			(copperpour not_allowed)
			(footprints allowed)
		)
		(placement
			(enabled no)
			(sheetname "")
		)
		(fill yes
			(thermal_gap 0.5)
			(thermal_bridge_width 0.5)
			(island_removal_mode 0)
		)
		(polygon
			(pts
				(arc
					(start 134.136892 -430.889918)
					(mid 133.3627 -430.889918)
					(end 134.136892 -430.889918)
				)
			)
		)
	)
	(zone
		(layers "B.Cu" "In13.Cu" "In15.Cu")
		(hatch none 0.5)
		(connect_pads
			(clearance 0)
		)
		(min_thickness 0.25)
		(keepout
			(tracks not_allowed)
			(vias allowed)
			(pads allowed)
			(copperpour not_allowed)
			(footprints allowed)
		)
		(placement
			(enabled no)
			(sheetname "")
		)
		(fill yes
			(thermal_gap 0.5)
			(thermal_bridge_width 0.5)
			(island_removal_mode 0)
		)
		(polygon
			(pts
				(arc
					(start 342.036908 -431.889916)
					(mid 341.262716 -431.889916)
					(end 342.036908 -431.889916)
				)
			)
		)
	)
	(zone
		(layers "B.Cu" "In13.Cu" "In15.Cu")
		(hatch none 0.5)
		(connect_pads
			(clearance 0)
		)
		(min_thickness 0.25)
		(keepout
			(tracks not_allowed)
			(vias allowed)
			(pads allowed)
			(copperpour not_allowed)
			(footprints allowed)
		)
		(placement
			(enabled no)
			(sheetname "")
		)
		(fill yes
			(thermal_gap 0.5)
			(thermal_bridge_width 0.5)
			(island_removal_mode 0)
		)
		(polygon
			(pts
				(arc
					(start 122.429778 -231.524302)
					(mid 121.799858 -231.524302)
					(end 122.429778 -231.524302)
				)
			)
		)
	)
	(zone
		(layers "B.Cu" "In13.Cu" "In15.Cu")
		(hatch none 0.5)
		(connect_pads
			(clearance 0)
		)
		(min_thickness 0.25)
		(keepout
			(tracks not_allowed)
			(vias allowed)
			(pads allowed)
			(copperpour not_allowed)
			(footprints allowed)
		)
		(placement
			(enabled no)
			(sheetname "")
		)
		(fill yes
			(thermal_gap 0.5)
			(thermal_bridge_width 0.5)
			(island_removal_mode 0)
		)
		(polygon
			(pts
				(arc
					(start 333.076042 -276.516084)
					(mid 332.446122 -276.516084)
					(end 333.076042 -276.516084)
				)
			)
		)
	)
	(zone
		(layers "B.Cu" "In13.Cu" "In15.Cu")
		(hatch none 0.5)
		(connect_pads
			(clearance 0)
		)
		(min_thickness 0.25)
		(keepout
			(tracks not_allowed)
			(vias allowed)
			(pads allowed)
			(copperpour not_allowed)
			(footprints allowed)
		)
		(placement
			(enabled no)
			(sheetname "")
		)
		(fill yes
			(thermal_gap 0.5)
			(thermal_bridge_width 0.5)
			(island_removal_mode 0)
		)
		(polygon
			(pts
				(arc
					(start 346.876116 -234.764072)
					(mid 346.246196 -234.764072)
					(end 346.876116 -234.764072)
				)
			)
		)
	)
	(zone
		(layers "B.Cu" "In13.Cu" "In15.Cu")
		(hatch none 0.5)
		(connect_pads
			(clearance 0)
		)
		(min_thickness 0.25)
		(keepout
			(tracks not_allowed)
			(vias allowed)
			(pads allowed)
			(copperpour not_allowed)
			(footprints allowed)
		)
		(placement
			(enabled no)
			(sheetname "")
		)
		(fill yes
			(thermal_gap 0.5)
			(thermal_bridge_width 0.5)
			(island_removal_mode 0)
		)
		(polygon
			(pts
				(arc
					(start 114.4397 -233.95432)
					(mid 113.80978 -233.95432)
					(end 114.4397 -233.95432)
				)
			)
		)
	)
	(zone
		(layers "B.Cu" "In13.Cu" "In15.Cu")
		(hatch none 0.5)
		(connect_pads
			(clearance 0)
		)
		(min_thickness 0.25)
		(keepout
			(tracks not_allowed)
			(vias allowed)
			(pads allowed)
			(copperpour not_allowed)
			(footprints allowed)
		)
		(placement
			(enabled no)
			(sheetname "")
		)
		(fill yes
			(thermal_gap 0.5)
			(thermal_bridge_width 0.5)
			(island_removal_mode 0)
		)
		(polygon
			(pts
				(arc
					(start 349.833692 -393.69238)
					(mid 349.203772 -393.69238)
					(end 349.833692 -393.69238)
				)
			)
		)
	)
	(zone
		(layers "B.Cu" "In13.Cu" "In15.Cu")
		(hatch none 0.5)
		(connect_pads
			(clearance 0)
		)
		(min_thickness 0.25)
		(keepout
			(tracks not_allowed)
			(vias allowed)
			(pads allowed)
			(copperpour not_allowed)
			(footprints allowed)
		)
		(placement
			(enabled no)
			(sheetname "")
		)
		(fill yes
			(thermal_gap 0.5)
			(thermal_bridge_width 0.5)
			(island_removal_mode 0)
		)
		(polygon
			(pts
				(arc
					(start 86.245954 -248.534428)
					(mid 85.616034 -248.534428)
					(end 86.245954 -248.534428)
				)
			)
		)
	)
	(zone
		(layers "B.Cu" "In13.Cu" "In15.Cu")
		(hatch none 0.5)
		(connect_pads
			(clearance 0)
		)
		(min_thickness 0.25)
		(keepout
			(tracks not_allowed)
			(vias allowed)
			(pads allowed)
			(copperpour not_allowed)
			(footprints allowed)
		)
		(placement
			(enabled no)
			(sheetname "")
		)
		(fill yes
			(thermal_gap 0.5)
			(thermal_bridge_width 0.5)
			(island_removal_mode 0)
		)
		(polygon
			(pts
				(arc
					(start 357.986076 -275.706078)
					(mid 357.356156 -275.706078)
					(end 357.986076 -275.706078)
				)
			)
		)
	)
	(zone
		(layers "B.Cu" "In13.Cu" "In15.Cu")
		(hatch none 0.5)
		(connect_pads
			(clearance 0)
		)
		(min_thickness 0.25)
		(keepout
			(tracks not_allowed)
			(vias allowed)
			(pads allowed)
			(copperpour not_allowed)
			(footprints allowed)
		)
		(placement
			(enabled no)
			(sheetname "")
		)
		(fill yes
			(thermal_gap 0.5)
			(thermal_bridge_width 0.5)
			(island_removal_mode 0)
		)
		(polygon
			(pts
				(arc
					(start 22.319488 -17.61236)
					(mid 21.651468 -17.61236)
					(end 22.319488 -17.61236)
				)
			)
		)
	)
	(zone
		(layers "B.Cu" "In13.Cu" "In15.Cu")
		(hatch none 0.5)
		(connect_pads
			(clearance 0)
		)
		(min_thickness 0.25)
		(keepout
			(tracks not_allowed)
			(vias allowed)
			(pads allowed)
			(copperpour not_allowed)
			(footprints allowed)
		)
		(placement
			(enabled no)
			(sheetname "")
		)
		(fill yes
			(thermal_gap 0.5)
			(thermal_bridge_width 0.5)
			(island_removal_mode 0)
		)
		(polygon
			(pts
				(arc
					(start 202.481942 -248.335292)
					(mid 201.813922 -248.335292)
					(end 202.481942 -248.335292)
				)
			)
		)
	)
	(zone
		(layers "B.Cu" "In13.Cu" "In15.Cu")
		(hatch none 0.5)
		(connect_pads
			(clearance 0)
		)
		(min_thickness 0.25)
		(keepout
			(tracks not_allowed)
			(vias allowed)
			(pads allowed)
			(copperpour not_allowed)
			(footprints allowed)
		)
		(placement
			(enabled no)
			(sheetname "")
		)
		(fill yes
			(thermal_gap 0.5)
			(thermal_bridge_width 0.5)
			(island_removal_mode 0)
		)
		(polygon
			(pts
				(arc
					(start 381.281432 -420.952168)
					(mid 380.613412 -420.952168)
					(end 381.281432 -420.952168)
				)
			)
		)
	)
	(zone
		(layers "B.Cu" "In13.Cu" "In15.Cu")
		(hatch none 0.5)
		(connect_pads
			(clearance 0)
		)
		(min_thickness 0.25)
		(keepout
			(tracks not_allowed)
			(vias allowed)
			(pads allowed)
			(copperpour not_allowed)
			(footprints allowed)
		)
		(placement
			(enabled no)
			(sheetname "")
		)
		(fill yes
			(thermal_gap 0.5)
			(thermal_bridge_width 0.5)
			(island_removal_mode 0)
		)
		(polygon
			(pts
				(arc
					(start 138.136884 -429.689768)
					(mid 137.362692 -429.689768)
					(end 138.136884 -429.689768)
				)
			)
		)
	)
	(zone
		(layers "B.Cu" "In13.Cu" "In15.Cu")
		(hatch none 0.5)
		(connect_pads
			(clearance 0)
		)
		(min_thickness 0.25)
		(keepout
			(tracks not_allowed)
			(vias allowed)
			(pads allowed)
			(copperpour not_allowed)
			(footprints allowed)
		)
		(placement
			(enabled no)
			(sheetname "")
		)
		(fill yes
			(thermal_gap 0.5)
			(thermal_bridge_width 0.5)
			(island_removal_mode 0)
		)
		(polygon
			(pts
				(arc
					(start 99.236022 -276.516338)
					(mid 98.606102 -276.516338)
					(end 99.236022 -276.516338)
				)
			)
		)
	)
	(zone
		(layers "B.Cu" "In13.Cu" "In15.Cu")
		(hatch none 0.5)
		(connect_pads
			(clearance 0)
		)
		(min_thickness 0.25)
		(keepout
			(tracks not_allowed)
			(vias allowed)
			(pads allowed)
			(copperpour not_allowed)
			(footprints allowed)
		)
		(placement
			(enabled no)
			(sheetname "")
		)
		(fill yes
			(thermal_gap 0.5)
			(thermal_bridge_width 0.5)
			(island_removal_mode 0)
		)
		(polygon
			(pts
				(arc
					(start 86.076028 -279.756362)
					(mid 85.446108 -279.756362)
					(end 86.076028 -279.756362)
				)
			)
		)
	)
	(zone
		(layers "B.Cu" "In13.Cu" "In15.Cu")
		(hatch none 0.5)
		(connect_pads
			(clearance 0)
		)
		(min_thickness 0.25)
		(keepout
			(tracks not_allowed)
			(vias allowed)
			(pads allowed)
			(copperpour not_allowed)
			(footprints allowed)
		)
		(placement
			(enabled no)
			(sheetname "")
		)
		(fill yes
			(thermal_gap 0.5)
			(thermal_bridge_width 0.5)
			(island_removal_mode 0)
		)
		(polygon
			(pts
				(arc
					(start 334.016096 -261.935976)
					(mid 333.386176 -261.935976)
					(end 334.016096 -261.935976)
				)
			)
		)
	)
	(zone
		(layers "B.Cu" "In13.Cu" "In15.Cu")
		(hatch none 0.5)
		(connect_pads
			(clearance 0)
		)
		(min_thickness 0.25)
		(keepout
			(tracks not_allowed)
			(vias allowed)
			(pads allowed)
			(copperpour not_allowed)
			(footprints allowed)
		)
		(placement
			(enabled no)
			(sheetname "")
		)
		(fill yes
			(thermal_gap 0.5)
			(thermal_bridge_width 0.5)
			(island_removal_mode 0)
		)
		(polygon
			(pts
				(arc
					(start 325.036688 -430.689766)
					(mid 324.262496 -430.689766)
					(end 325.036688 -430.689766)
				)
			)
		)
	)
	(zone
		(layers "B.Cu" "In13.Cu" "In15.Cu")
		(hatch none 0.5)
		(connect_pads
			(clearance 0)
		)
		(min_thickness 0.25)
		(keepout
			(tracks not_allowed)
			(vias allowed)
			(pads allowed)
			(copperpour not_allowed)
			(footprints allowed)
		)
		(placement
			(enabled no)
			(sheetname "")
		)
		(fill yes
			(thermal_gap 0.5)
			(thermal_bridge_width 0.5)
			(island_removal_mode 0)
		)
		(polygon
			(pts
				(arc
					(start 47.770288 -19.137122)
					(mid 47.102268 -19.137122)
					(end 47.770288 -19.137122)
				)
			)
		)
	)
	(zone
		(layers "B.Cu" "In13.Cu" "In15.Cu")
		(hatch none 0.5)
		(connect_pads
			(clearance 0)
		)
		(min_thickness 0.25)
		(keepout
			(tracks not_allowed)
			(vias allowed)
			(pads allowed)
			(copperpour not_allowed)
			(footprints allowed)
		)
		(placement
			(enabled no)
			(sheetname "")
		)
		(fill yes
			(thermal_gap 0.5)
			(thermal_bridge_width 0.5)
			(island_removal_mode 0)
		)
		(polygon
			(pts
				(arc
					(start 139.649708 -281.376374)
					(mid 139.019788 -281.376374)
					(end 139.649708 -281.376374)
				)
			)
		)
	)
	(zone
		(layers "B.Cu" "In13.Cu" "In15.Cu")
		(hatch none 0.5)
		(connect_pads
			(clearance 0)
		)
		(min_thickness 0.25)
		(keepout
			(tracks not_allowed)
			(vias allowed)
			(pads allowed)
			(copperpour not_allowed)
			(footprints allowed)
		)
		(placement
			(enabled no)
			(sheetname "")
		)
		(fill yes
			(thermal_gap 0.5)
			(thermal_bridge_width 0.5)
			(island_removal_mode 0)
		)
		(polygon
			(pts
				(arc
					(start 106.755946 -278.13635)
					(mid 106.126026 -278.13635)
					(end 106.755946 -278.13635)
				)
			)
		)
	)
	(zone
		(layers "B.Cu" "In13.Cu" "In15.Cu")
		(hatch none 0.5)
		(connect_pads
			(clearance 0)
		)
		(min_thickness 0.25)
		(keepout
			(tracks not_allowed)
			(vias allowed)
			(pads allowed)
			(copperpour not_allowed)
			(footprints allowed)
		)
		(placement
			(enabled no)
			(sheetname "")
		)
		(fill yes
			(thermal_gap 0.5)
			(thermal_bridge_width 0.5)
			(island_removal_mode 0)
		)
		(polygon
			(pts
				(arc
					(start 138.709654 -270.03629)
					(mid 138.079734 -270.03629)
					(end 138.709654 -270.03629)
				)
			)
		)
	)
	(zone
		(layers "B.Cu" "In13.Cu" "In15.Cu")
		(hatch none 0.5)
		(connect_pads
			(clearance 0)
		)
		(min_thickness 0.25)
		(keepout
			(tracks not_allowed)
			(vias allowed)
			(pads allowed)
			(copperpour not_allowed)
			(footprints allowed)
		)
		(placement
			(enabled no)
			(sheetname "")
		)
		(fill yes
			(thermal_gap 0.5)
			(thermal_bridge_width 0.5)
			(island_removal_mode 0)
		)
		(polygon
			(pts
				(arc
					(start 450.42201 -211.784946)
					(mid 449.75399 -211.784946)
					(end 450.42201 -211.784946)
				)
			)
		)
	)
	(zone
		(layers "B.Cu" "In13.Cu" "In15.Cu")
		(hatch none 0.5)
		(connect_pads
			(clearance 0)
		)
		(min_thickness 0.25)
		(keepout
			(tracks not_allowed)
			(vias allowed)
			(pads allowed)
			(copperpour not_allowed)
			(footprints allowed)
		)
		(placement
			(enabled no)
			(sheetname "")
		)
		(fill yes
			(thermal_gap 0.5)
			(thermal_bridge_width 0.5)
			(island_removal_mode 0)
		)
		(polygon
			(pts
				(arc
					(start 387.589776 -278.136096)
					(mid 386.959856 -278.136096)
					(end 387.589776 -278.136096)
				)
			)
		)
	)
	(zone
		(layers "B.Cu" "In13.Cu" "In15.Cu")
		(hatch none 0.5)
		(connect_pads
			(clearance 0)
		)
		(min_thickness 0.25)
		(keepout
			(tracks not_allowed)
			(vias allowed)
			(pads allowed)
			(copperpour not_allowed)
			(footprints allowed)
		)
		(placement
			(enabled no)
			(sheetname "")
		)
		(fill yes
			(thermal_gap 0.5)
			(thermal_bridge_width 0.5)
			(island_removal_mode 0)
		)
		(polygon
			(pts
				(arc
					(start 86.037166 -430.689766)
					(mid 85.262974 -430.689766)
					(end 86.037166 -430.689766)
				)
			)
		)
	)
	(zone
		(layers "B.Cu" "In13.Cu" "In15.Cu")
		(hatch none 0.5)
		(connect_pads
			(clearance 0)
		)
		(min_thickness 0.25)
		(keepout
			(tracks not_allowed)
			(vias allowed)
			(pads allowed)
			(copperpour not_allowed)
			(footprints allowed)
		)
		(placement
			(enabled no)
			(sheetname "")
		)
		(fill yes
			(thermal_gap 0.5)
			(thermal_bridge_width 0.5)
			(island_removal_mode 0)
		)
		(polygon
			(pts
				(arc
					(start 397.449548 -6.725158)
					(mid 396.781528 -6.725158)
					(end 397.449548 -6.725158)
				)
			)
		)
	)
	(zone
		(layers "B.Cu" "In13.Cu" "In15.Cu")
		(hatch none 0.5)
		(connect_pads
			(clearance 0)
		)
		(min_thickness 0.25)
		(keepout
			(tracks not_allowed)
			(vias allowed)
			(pads allowed)
			(copperpour not_allowed)
			(footprints allowed)
		)
		(placement
			(enabled no)
			(sheetname "")
		)
		(fill yes
			(thermal_gap 0.5)
			(thermal_bridge_width 0.5)
			(island_removal_mode 0)
		)
		(polygon
			(pts
				(arc
					(start 22.04212 -231.335326)
					(mid 21.3741 -231.335326)
					(end 22.04212 -231.335326)
				)
			)
		)
	)
	(zone
		(layers "B.Cu" "In13.Cu" "In15.Cu")
		(hatch none 0.5)
		(connect_pads
			(clearance 0)
		)
		(min_thickness 0.25)
		(keepout
			(tracks not_allowed)
			(vias allowed)
			(pads allowed)
			(copperpour not_allowed)
			(footprints allowed)
		)
		(placement
			(enabled no)
			(sheetname "")
		)
		(fill yes
			(thermal_gap 0.5)
			(thermal_bridge_width 0.5)
			(island_removal_mode 0)
		)
		(polygon
			(pts
				(arc
					(start 450.42201 -291.684964)
					(mid 449.75399 -291.684964)
					(end 450.42201 -291.684964)
				)
			)
		)
	)
	(zone
		(layers "B.Cu" "In13.Cu" "In15.Cu")
		(hatch none 0.5)
		(connect_pads
			(clearance 0)
		)
		(min_thickness 0.25)
		(keepout
			(tracks not_allowed)
			(vias allowed)
			(pads allowed)
			(copperpour not_allowed)
			(footprints allowed)
		)
		(placement
			(enabled no)
			(sheetname "")
		)
		(fill yes
			(thermal_gap 0.5)
			(thermal_bridge_width 0.5)
			(island_removal_mode 0)
		)
		(polygon
			(pts
				(arc
					(start 206.58201 -278.085296)
					(mid 205.91399 -278.085296)
					(end 206.58201 -278.085296)
				)
			)
		)
	)
	(zone
		(layers "B.Cu" "In13.Cu" "In15.Cu")
		(hatch none 0.5)
		(connect_pads
			(clearance 0)
		)
		(min_thickness 0.25)
		(keepout
			(tracks not_allowed)
			(vias allowed)
			(pads allowed)
			(copperpour not_allowed)
			(footprints allowed)
		)
		(placement
			(enabled no)
			(sheetname "")
		)
		(fill yes
			(thermal_gap 0.5)
			(thermal_bridge_width 0.5)
			(island_removal_mode 0)
		)
		(polygon
			(pts
				(arc
					(start 139.649708 -263.556242)
					(mid 139.019788 -263.556242)
					(end 139.649708 -263.556242)
				)
			)
		)
	)
	(zone
		(layers "B.Cu" "In13.Cu" "In15.Cu")
		(hatch none 0.5)
		(connect_pads
			(clearance 0)
		)
		(min_thickness 0.25)
		(keepout
			(tracks not_allowed)
			(vias allowed)
			(pads allowed)
			(copperpour not_allowed)
			(footprints allowed)
		)
		(placement
			(enabled no)
			(sheetname "")
		)
		(fill yes
			(thermal_gap 0.5)
			(thermal_bridge_width 0.5)
			(island_removal_mode 0)
		)
		(polygon
			(pts
				(arc
					(start 36.289488 -19.13636)
					(mid 35.621468 -19.13636)
					(end 36.289488 -19.13636)
				)
			)
		)
	)
	(zone
		(layers "B.Cu" "In13.Cu" "In15.Cu")
		(hatch none 0.5)
		(connect_pads
			(clearance 0)
		)
		(min_thickness 0.25)
		(keepout
			(tracks not_allowed)
			(vias allowed)
			(pads allowed)
			(copperpour not_allowed)
			(footprints allowed)
		)
		(placement
			(enabled no)
			(sheetname "")
		)
		(fill yes
			(thermal_gap 0.5)
			(thermal_bridge_width 0.5)
			(island_removal_mode 0)
		)
		(polygon
			(pts
				(arc
					(start 419.164262 -4.963414)
					(mid 418.496242 -4.963414)
					(end 419.164262 -4.963414)
				)
			)
		)
	)
	(zone
		(layers "B.Cu" "In13.Cu" "In15.Cu")
		(hatch none 0.5)
		(connect_pads
			(clearance 0)
		)
		(min_thickness 0.25)
		(keepout
			(tracks not_allowed)
			(vias allowed)
			(pads allowed)
			(copperpour not_allowed)
			(footprints allowed)
		)
		(placement
			(enabled no)
			(sheetname "")
		)
		(fill yes
			(thermal_gap 0.5)
			(thermal_bridge_width 0.5)
			(island_removal_mode 0)
		)
		(polygon
			(pts
				(arc
					(start 450.42201 -284.034992)
					(mid 449.75399 -284.034992)
					(end 450.42201 -284.034992)
				)
			)
		)
	)
	(zone
		(layers "B.Cu" "In13.Cu" "In15.Cu")
		(hatch none 0.5)
		(connect_pads
			(clearance 0)
		)
		(min_thickness 0.25)
		(keepout
			(tracks not_allowed)
			(vias allowed)
			(pads allowed)
			(copperpour not_allowed)
			(footprints allowed)
		)
		(placement
			(enabled no)
			(sheetname "")
		)
		(fill yes
			(thermal_gap 0.5)
			(thermal_bridge_width 0.5)
			(island_removal_mode 0)
		)
		(polygon
			(pts
				(arc
					(start 454.522078 -278.085042)
					(mid 453.854058 -278.085042)
					(end 454.522078 -278.085042)
				)
			)
		)
	)
	(zone
		(layers "B.Cu" "In13.Cu" "In15.Cu")
		(hatch none 0.5)
		(connect_pads
			(clearance 0)
		)
		(min_thickness 0.25)
		(keepout
			(tracks not_allowed)
			(vias allowed)
			(pads allowed)
			(copperpour not_allowed)
			(footprints allowed)
		)
		(placement
			(enabled no)
			(sheetname "")
		)
		(fill yes
			(thermal_gap 0.5)
			(thermal_bridge_width 0.5)
			(island_removal_mode 0)
		)
		(polygon
			(pts
				(arc
					(start 206.58201 -267.885418)
					(mid 205.91399 -267.885418)
					(end 206.58201 -267.885418)
				)
			)
		)
	)
	(zone
		(layers "B.Cu" "In13.Cu" "In15.Cu")
		(hatch none 0.5)
		(connect_pads
			(clearance 0)
		)
		(min_thickness 0.25)
		(keepout
			(tracks not_allowed)
			(vias allowed)
			(pads allowed)
			(copperpour not_allowed)
			(footprints allowed)
		)
		(placement
			(enabled no)
			(sheetname "")
		)
		(fill yes
			(thermal_gap 0.5)
			(thermal_bridge_width 0.5)
			(island_removal_mode 0)
		)
		(polygon
			(pts
				(arc
					(start 388.059676 -278.946102)
					(mid 387.429756 -278.946102)
					(end 388.059676 -278.946102)
				)
			)
		)
	)
	(zone
		(layers "B.Cu" "In13.Cu" "In15.Cu")
		(hatch none 0.5)
		(connect_pads
			(clearance 0)
		)
		(min_thickness 0.25)
		(keepout
			(tracks not_allowed)
			(vias allowed)
			(pads allowed)
			(copperpour not_allowed)
			(footprints allowed)
		)
		(placement
			(enabled no)
			(sheetname "")
		)
		(fill yes
			(thermal_gap 0.5)
			(thermal_bridge_width 0.5)
			(island_removal_mode 0)
		)
		(polygon
			(pts
				(arc
					(start 386.649722 -271.656048)
					(mid 386.019802 -271.656048)
					(end 386.649722 -271.656048)
				)
			)
		)
	)
	(zone
		(layers "B.Cu" "In13.Cu" "In15.Cu")
		(hatch none 0.5)
		(connect_pads
			(clearance 0)
		)
		(min_thickness 0.25)
		(keepout
			(tracks not_allowed)
			(vias allowed)
			(pads allowed)
			(copperpour not_allowed)
			(footprints allowed)
		)
		(placement
			(enabled no)
			(sheetname "")
		)
		(fill yes
			(thermal_gap 0.5)
			(thermal_bridge_width 0.5)
			(island_removal_mode 0)
		)
		(polygon
			(pts
				(arc
					(start 265.88212 -314.635134)
					(mid 265.2141 -314.635134)
					(end 265.88212 -314.635134)
				)
			)
		)
	)
	(zone
		(layers "B.Cu" "In13.Cu" "In15.Cu")
		(hatch none 0.5)
		(connect_pads
			(clearance 0)
		)
		(min_thickness 0.25)
		(keepout
			(tracks not_allowed)
			(vias allowed)
			(pads allowed)
			(copperpour not_allowed)
			(footprints allowed)
		)
		(placement
			(enabled no)
			(sheetname "")
		)
		(fill yes
			(thermal_gap 0.5)
			(thermal_bridge_width 0.5)
			(island_removal_mode 0)
		)
		(polygon
			(pts
				(arc
					(start 371.228112 -420.952168)
					(mid 370.560092 -420.952168)
					(end 371.228112 -420.952168)
				)
			)
		)
	)
	(zone
		(layers "B.Cu" "In13.Cu" "In15.Cu")
		(hatch none 0.5)
		(connect_pads
			(clearance 0)
		)
		(min_thickness 0.25)
		(keepout
			(tracks not_allowed)
			(vias allowed)
			(pads allowed)
			(copperpour not_allowed)
			(footprints allowed)
		)
		(placement
			(enabled no)
			(sheetname "")
		)
		(fill yes
			(thermal_gap 0.5)
			(thermal_bridge_width 0.5)
			(island_removal_mode 0)
		)
		(polygon
			(pts
				(arc
					(start 316.380876 -420.952168)
					(mid 315.712856 -420.952168)
					(end 316.380876 -420.952168)
				)
			)
		)
	)
	(zone
		(layers "B.Cu" "In13.Cu" "In15.Cu")
		(hatch none 0.5)
		(connect_pads
			(clearance 0)
		)
		(min_thickness 0.25)
		(keepout
			(tracks not_allowed)
			(vias allowed)
			(pads allowed)
			(copperpour not_allowed)
			(footprints allowed)
		)
		(placement
			(enabled no)
			(sheetname "")
		)
		(fill yes
			(thermal_gap 0.5)
			(thermal_bridge_width 0.5)
			(island_removal_mode 0)
		)
		(polygon
			(pts
				(arc
					(start 387.759702 -232.334054)
					(mid 387.129782 -232.334054)
					(end 387.759702 -232.334054)
				)
			)
		)
	)
	(zone
		(layers "B.Cu" "In13.Cu" "In15.Cu")
		(hatch none 0.5)
		(connect_pads
			(clearance 0)
		)
		(min_thickness 0.25)
		(keepout
			(tracks not_allowed)
			(vias allowed)
			(pads allowed)
			(copperpour not_allowed)
			(footprints allowed)
		)
		(placement
			(enabled no)
			(sheetname "")
		)
		(fill yes
			(thermal_gap 0.5)
			(thermal_bridge_width 0.5)
			(island_removal_mode 0)
		)
		(polygon
			(pts
				(arc
					(start 17.942052 -222.835216)
					(mid 17.274032 -222.835216)
					(end 17.942052 -222.835216)
				)
			)
		)
	)
	(zone
		(layers "B.Cu" "In13.Cu" "In15.Cu")
		(hatch none 0.5)
		(connect_pads
			(clearance 0)
		)
		(min_thickness 0.25)
		(keepout
			(tracks not_allowed)
			(vias allowed)
			(pads allowed)
			(copperpour not_allowed)
			(footprints allowed)
		)
		(placement
			(enabled no)
			(sheetname "")
		)
		(fill yes
			(thermal_gap 0.5)
			(thermal_bridge_width 0.5)
			(island_removal_mode 0)
		)
		(polygon
			(pts
				(arc
					(start 363.319822 -248.534174)
					(mid 362.689902 -248.534174)
					(end 363.319822 -248.534174)
				)
			)
		)
	)
	(zone
		(layers "B.Cu" "In13.Cu" "In15.Cu")
		(hatch none 0.5)
		(connect_pads
			(clearance 0)
		)
		(min_thickness 0.25)
		(keepout
			(tracks not_allowed)
			(vias allowed)
			(pads allowed)
			(copperpour not_allowed)
			(footprints allowed)
		)
		(placement
			(enabled no)
			(sheetname "")
		)
		(fill yes
			(thermal_gap 0.5)
			(thermal_bridge_width 0.5)
			(island_removal_mode 0)
		)
		(polygon
			(pts
				(arc
					(start 352.516186 -231.524048)
					(mid 351.886266 -231.524048)
					(end 352.516186 -231.524048)
				)
			)
		)
	)
	(zone
		(layers "B.Cu" "In13.Cu" "In15.Cu")
		(hatch none 0.5)
		(connect_pads
			(clearance 0)
		)
		(min_thickness 0.25)
		(keepout
			(tracks not_allowed)
			(vias allowed)
			(pads allowed)
			(copperpour not_allowed)
			(footprints allowed)
		)
		(placement
			(enabled no)
			(sheetname "")
		)
		(fill yes
			(thermal_gap 0.5)
			(thermal_bridge_width 0.5)
			(island_removal_mode 0)
		)
		(polygon
			(pts
				(arc
					(start 206.58201 -210.935316)
					(mid 205.91399 -210.935316)
					(end 206.58201 -210.935316)
				)
			)
		)
	)
	(zone
		(layers "B.Cu" "In13.Cu" "In15.Cu")
		(hatch none 0.5)
		(connect_pads
			(clearance 0)
		)
		(min_thickness 0.25)
		(keepout
			(tracks not_allowed)
			(vias allowed)
			(pads allowed)
			(copperpour not_allowed)
			(footprints allowed)
		)
		(placement
			(enabled no)
			(sheetname "")
		)
		(fill yes
			(thermal_gap 0.5)
			(thermal_bridge_width 0.5)
			(island_removal_mode 0)
		)
		(polygon
			(pts
				(arc
					(start 66.507614 -412.570168)
					(mid 65.839594 -412.570168)
					(end 66.507614 -412.570168)
				)
			)
		)
	)
	(zone
		(layers "B.Cu" "In13.Cu" "In15.Cu")
		(hatch none 0.5)
		(connect_pads
			(clearance 0)
		)
		(min_thickness 0.25)
		(keepout
			(tracks not_allowed)
			(vias allowed)
			(pads allowed)
			(copperpour not_allowed)
			(footprints allowed)
		)
		(placement
			(enabled no)
			(sheetname "")
		)
		(fill yes
			(thermal_gap 0.5)
			(thermal_bridge_width 0.5)
			(island_removal_mode 0)
		)
		(polygon
			(pts
				(arc
					(start 450.42201 -302.73498)
					(mid 449.75399 -302.73498)
					(end 450.42201 -302.73498)
				)
			)
		)
	)
	(zone
		(layers "B.Cu" "In13.Cu" "In15.Cu")
		(hatch none 0.5)
		(connect_pads
			(clearance 0)
		)
		(min_thickness 0.25)
		(keepout
			(tracks not_allowed)
			(vias allowed)
			(pads allowed)
			(copperpour not_allowed)
			(footprints allowed)
		)
		(placement
			(enabled no)
			(sheetname "")
		)
		(fill yes
			(thermal_gap 0.5)
			(thermal_bridge_width 0.5)
			(island_removal_mode 0)
		)
		(polygon
			(pts
				(arc
					(start 202.481942 -297.635422)
					(mid 201.813922 -297.635422)
					(end 202.481942 -297.635422)
				)
			)
		)
	)
	(zone
		(layers "B.Cu" "In13.Cu" "In15.Cu")
		(hatch none 0.5)
		(connect_pads
			(clearance 0)
		)
		(min_thickness 0.25)
		(keepout
			(tracks not_allowed)
			(vias allowed)
			(pads allowed)
			(copperpour not_allowed)
			(footprints allowed)
		)
		(placement
			(enabled no)
			(sheetname "")
		)
		(fill yes
			(thermal_gap 0.5)
			(thermal_bridge_width 0.5)
			(island_removal_mode 0)
		)
		(polygon
			(pts
				(arc
					(start 332.776068 -234.764072)
					(mid 332.146148 -234.764072)
					(end 332.776068 -234.764072)
				)
			)
		)
	)
	(zone
		(layers "B.Cu" "In13.Cu" "In15.Cu")
		(hatch none 0.5)
		(connect_pads
			(clearance 0)
		)
		(min_thickness 0.25)
		(keepout
			(tracks not_allowed)
			(vias allowed)
			(pads allowed)
			(copperpour not_allowed)
			(footprints allowed)
		)
		(placement
			(enabled no)
			(sheetname "")
		)
		(fill yes
			(thermal_gap 0.5)
			(thermal_bridge_width 0.5)
			(island_removal_mode 0)
		)
		(polygon
			(pts
				(arc
					(start 269.982188 -311.23509)
					(mid 269.314168 -311.23509)
					(end 269.982188 -311.23509)
				)
			)
		)
	)
	(zone
		(layers "B.Cu" "In13.Cu" "In15.Cu")
		(hatch none 0.5)
		(connect_pads
			(clearance 0)
		)
		(min_thickness 0.25)
		(keepout
			(tracks not_allowed)
			(vias allowed)
			(pads allowed)
			(copperpour not_allowed)
			(footprints allowed)
		)
		(placement
			(enabled no)
			(sheetname "")
		)
		(fill yes
			(thermal_gap 0.5)
			(thermal_bridge_width 0.5)
			(island_removal_mode 0)
		)
		(polygon
			(pts
				(arc
					(start 155.913836 -412.570168)
					(mid 155.245816 -412.570168)
					(end 155.913836 -412.570168)
				)
			)
		)
	)
	(zone
		(layers "B.Cu" "In13.Cu" "In15.Cu")
		(hatch none 0.5)
		(connect_pads
			(clearance 0)
		)
		(min_thickness 0.25)
		(keepout
			(tracks not_allowed)
			(vias allowed)
			(pads allowed)
			(copperpour not_allowed)
			(footprints allowed)
		)
		(placement
			(enabled no)
			(sheetname "")
		)
		(fill yes
			(thermal_gap 0.5)
			(thermal_bridge_width 0.5)
			(island_removal_mode 0)
		)
		(polygon
			(pts
				(arc
					(start 332.306168 -248.534174)
					(mid 331.676248 -248.534174)
					(end 332.306168 -248.534174)
				)
			)
		)
	)
	(zone
		(layers "B.Cu" "In13.Cu" "In15.Cu")
		(hatch none 0.5)
		(connect_pads
			(clearance 0)
		)
		(min_thickness 0.25)
		(keepout
			(tracks not_allowed)
			(vias allowed)
			(pads allowed)
			(copperpour not_allowed)
			(footprints allowed)
		)
		(placement
			(enabled no)
			(sheetname "")
		)
		(fill yes
			(thermal_gap 0.5)
			(thermal_bridge_width 0.5)
			(island_removal_mode 0)
		)
		(polygon
			(pts
				(arc
					(start 450.42201 -301.034958)
					(mid 449.75399 -301.034958)
					(end 450.42201 -301.034958)
				)
			)
		)
	)
	(zone
		(layers "B.Cu" "In13.Cu" "In15.Cu")
		(hatch none 0.5)
		(connect_pads
			(clearance 0)
		)
		(min_thickness 0.25)
		(keepout
			(tracks not_allowed)
			(vias allowed)
			(pads allowed)
			(copperpour not_allowed)
			(footprints allowed)
		)
		(placement
			(enabled no)
			(sheetname "")
		)
		(fill yes
			(thermal_gap 0.5)
			(thermal_bridge_width 0.5)
			(island_removal_mode 0)
		)
		(polygon
			(pts
				(arc
					(start 91.013534 -412.570168)
					(mid 90.345514 -412.570168)
					(end 91.013534 -412.570168)
				)
			)
		)
	)
	(zone
		(layers "B.Cu" "In13.Cu" "In15.Cu")
		(hatch none 0.5)
		(connect_pads
			(clearance 0)
		)
		(min_thickness 0.25)
		(keepout
			(tracks not_allowed)
			(vias allowed)
			(pads allowed)
			(copperpour not_allowed)
			(footprints allowed)
		)
		(placement
			(enabled no)
			(sheetname "")
		)
		(fill yes
			(thermal_gap 0.5)
			(thermal_bridge_width 0.5)
			(island_removal_mode 0)
		)
		(polygon
			(pts
				(arc
					(start 101.755956 -244.484398)
					(mid 101.126036 -244.484398)
					(end 101.755956 -244.484398)
				)
			)
		)
	)
	(zone
		(layers "B.Cu" "In13.Cu" "In15.Cu")
		(hatch none 0.5)
		(connect_pads
			(clearance 0)
		)
		(min_thickness 0.25)
		(keepout
			(tracks not_allowed)
			(vias allowed)
			(pads allowed)
			(copperpour not_allowed)
			(footprints allowed)
		)
		(placement
			(enabled no)
			(sheetname "")
		)
		(fill yes
			(thermal_gap 0.5)
			(thermal_bridge_width 0.5)
			(island_removal_mode 0)
		)
		(polygon
			(pts
				(arc
					(start 454.522078 -276.38502)
					(mid 453.854058 -276.38502)
					(end 454.522078 -276.38502)
				)
			)
		)
	)
	(zone
		(layers "B.Cu" "In13.Cu" "In15.Cu")
		(hatch none 0.5)
		(connect_pads
			(clearance 0)
		)
		(min_thickness 0.25)
		(keepout
			(tracks not_allowed)
			(vias allowed)
			(pads allowed)
			(copperpour not_allowed)
			(footprints allowed)
		)
		(placement
			(enabled no)
			(sheetname "")
		)
		(fill yes
			(thermal_gap 0.5)
			(thermal_bridge_width 0.5)
			(island_removal_mode 0)
		)
		(polygon
			(pts
				(arc
					(start 202.481942 -284.035246)
					(mid 201.813922 -284.035246)
					(end 202.481942 -284.035246)
				)
			)
		)
	)
	(zone
		(layers "B.Cu" "In13.Cu" "In15.Cu")
		(hatch none 0.5)
		(connect_pads
			(clearance 0)
		)
		(min_thickness 0.25)
		(keepout
			(tracks not_allowed)
			(vias allowed)
			(pads allowed)
			(copperpour not_allowed)
			(footprints allowed)
		)
		(placement
			(enabled no)
			(sheetname "")
		)
		(fill yes
			(thermal_gap 0.5)
			(thermal_bridge_width 0.5)
			(island_removal_mode 0)
		)
		(polygon
			(pts
				(arc
					(start 118.291356 -412.570168)
					(mid 117.623336 -412.570168)
					(end 118.291356 -412.570168)
				)
			)
		)
	)
	(zone
		(layers "B.Cu" "In13.Cu" "In15.Cu")
		(hatch none 0.5)
		(connect_pads
			(clearance 0)
		)
		(min_thickness 0.25)
		(keepout
			(tracks not_allowed)
			(vias allowed)
			(pads allowed)
			(copperpour not_allowed)
			(footprints allowed)
		)
		(placement
			(enabled no)
			(sheetname "")
		)
		(fill yes
			(thermal_gap 0.5)
			(thermal_bridge_width 0.5)
			(island_removal_mode 0)
		)
		(polygon
			(pts
				(arc
					(start 368.489738 -244.484144)
					(mid 367.859818 -244.484144)
					(end 368.489738 -244.484144)
				)
			)
		)
	)
	(zone
		(layers "B.Cu" "In13.Cu" "In15.Cu")
		(hatch none 0.5)
		(connect_pads
			(clearance 0)
		)
		(min_thickness 0.25)
		(keepout
			(tracks not_allowed)
			(vias allowed)
			(pads allowed)
			(copperpour not_allowed)
			(footprints allowed)
		)
		(placement
			(enabled no)
			(sheetname "")
		)
		(fill yes
			(thermal_gap 0.5)
			(thermal_bridge_width 0.5)
			(island_removal_mode 0)
		)
		(polygon
			(pts
				(arc
					(start 450.42201 -233.884978)
					(mid 449.75399 -233.884978)
					(end 450.42201 -233.884978)
				)
			)
		)
	)
	(zone
		(layers "B.Cu" "In13.Cu" "In15.Cu")
		(hatch none 0.5)
		(connect_pads
			(clearance 0)
		)
		(min_thickness 0.25)
		(keepout
			(tracks not_allowed)
			(vias allowed)
			(pads allowed)
			(copperpour not_allowed)
			(footprints allowed)
		)
		(placement
			(enabled no)
			(sheetname "")
		)
		(fill yes
			(thermal_gap 0.5)
			(thermal_bridge_width 0.5)
			(island_removal_mode 0)
		)
		(polygon
			(pts
				(arc
					(start 17.942052 -304.435256)
					(mid 17.274032 -304.435256)
					(end 17.942052 -304.435256)
				)
			)
		)
	)
	(zone
		(layers "B.Cu" "In13.Cu" "In15.Cu")
		(hatch none 0.5)
		(connect_pads
			(clearance 0)
		)
		(min_thickness 0.25)
		(keepout
			(tracks not_allowed)
			(vias allowed)
			(pads allowed)
			(copperpour not_allowed)
			(footprints allowed)
		)
		(placement
			(enabled no)
			(sheetname "")
		)
		(fill yes
			(thermal_gap 0.5)
			(thermal_bridge_width 0.5)
			(island_removal_mode 0)
		)
		(polygon
			(pts
				(arc
					(start 139.349734 -226.66452)
					(mid 138.719814 -226.66452)
					(end 139.349734 -226.66452)
				)
			)
		)
	)
	(zone
		(layers "B.Cu" "In13.Cu" "In15.Cu")
		(hatch none 0.5)
		(connect_pads
			(clearance 0)
		)
		(min_thickness 0.25)
		(keepout
			(tracks not_allowed)
			(vias allowed)
			(pads allowed)
			(copperpour not_allowed)
			(footprints allowed)
		)
		(placement
			(enabled no)
			(sheetname "")
		)
		(fill yes
			(thermal_gap 0.5)
			(thermal_bridge_width 0.5)
			(island_removal_mode 0)
		)
		(polygon
			(pts
				(arc
					(start 454.522078 -311.23509)
					(mid 453.854058 -311.23509)
					(end 454.522078 -311.23509)
				)
			)
		)
	)
	(zone
		(layers "B.Cu" "In13.Cu" "In15.Cu")
		(hatch none 0.5)
		(connect_pads
			(clearance 0)
		)
		(min_thickness 0.25)
		(keepout
			(tracks not_allowed)
			(vias allowed)
			(pads allowed)
			(copperpour not_allowed)
			(footprints allowed)
		)
		(placement
			(enabled no)
			(sheetname "")
		)
		(fill yes
			(thermal_gap 0.5)
			(thermal_bridge_width 0.5)
			(island_removal_mode 0)
		)
		(polygon
			(pts
				(arc
					(start 332.606142 -290.285932)
					(mid 331.976222 -290.285932)
					(end 332.606142 -290.285932)
				)
			)
		)
	)
	(zone
		(layers "B.Cu" "In13.Cu" "In15.Cu")
		(hatch none 0.5)
		(connect_pads
			(clearance 0)
		)
		(min_thickness 0.25)
		(keepout
			(tracks not_allowed)
			(vias allowed)
			(pads allowed)
			(copperpour not_allowed)
			(footprints allowed)
		)
		(placement
			(enabled no)
			(sheetname "")
		)
		(fill yes
			(thermal_gap 0.5)
			(thermal_bridge_width 0.5)
			(island_removal_mode 0)
		)
		(polygon
			(pts
				(arc
					(start 139.349734 -233.144314)
					(mid 138.719814 -233.144314)
					(end 139.349734 -233.144314)
				)
			)
		)
	)
	(zone
		(layers "B.Cu" "In13.Cu" "In15.Cu")
		(hatch none 0.5)
		(connect_pads
			(clearance 0)
		)
		(min_thickness 0.25)
		(keepout
			(tracks not_allowed)
			(vias allowed)
			(pads allowed)
			(copperpour not_allowed)
			(footprints allowed)
		)
		(placement
			(enabled no)
			(sheetname "")
		)
		(fill yes
			(thermal_gap 0.5)
			(thermal_bridge_width 0.5)
			(island_removal_mode 0)
		)
		(polygon
			(pts
				(arc
					(start 450.42201 -313.784996)
					(mid 449.75399 -313.784996)
					(end 450.42201 -313.784996)
				)
			)
		)
	)
	(zone
		(layers "B.Cu" "In13.Cu" "In15.Cu")
		(hatch none 0.5)
		(connect_pads
			(clearance 0)
		)
		(min_thickness 0.25)
		(keepout
			(tracks not_allowed)
			(vias allowed)
			(pads allowed)
			(copperpour not_allowed)
			(footprints allowed)
		)
		(placement
			(enabled no)
			(sheetname "")
		)
		(fill yes
			(thermal_gap 0.5)
			(thermal_bridge_width 0.5)
			(island_removal_mode 0)
		)
		(polygon
			(pts
				(arc
					(start 84.836 -254.20447)
					(mid 84.20608 -254.20447)
					(end 84.836 -254.20447)
				)
			)
		)
	)
	(zone
		(layers "B.Cu" "In13.Cu" "In15.Cu")
		(hatch none 0.5)
		(connect_pads
			(clearance 0)
		)
		(min_thickness 0.25)
		(keepout
			(tracks not_allowed)
			(vias allowed)
			(pads allowed)
			(copperpour not_allowed)
			(footprints allowed)
		)
		(placement
			(enabled no)
			(sheetname "")
		)
		(fill yes
			(thermal_gap 0.5)
			(thermal_bridge_width 0.5)
			(island_removal_mode 0)
		)
		(polygon
			(pts
				(arc
					(start 102.05593 -276.516338)
					(mid 101.42601 -276.516338)
					(end 102.05593 -276.516338)
				)
			)
		)
	)
	(zone
		(layers "B.Cu" "In13.Cu" "In15.Cu")
		(hatch none 0.5)
		(connect_pads
			(clearance 0)
		)
		(min_thickness 0.25)
		(keepout
			(tracks not_allowed)
			(vias allowed)
			(pads allowed)
			(copperpour not_allowed)
			(footprints allowed)
		)
		(placement
			(enabled no)
			(sheetname "")
		)
		(fill yes
			(thermal_gap 0.5)
			(thermal_bridge_width 0.5)
			(island_removal_mode 0)
		)
		(polygon
			(pts
				(arc
					(start 206.58201 -199.035416)
					(mid 205.91399 -199.035416)
					(end 206.58201 -199.035416)
				)
			)
		)
	)
	(zone
		(layers "B.Cu" "In13.Cu" "In15.Cu")
		(hatch none 0.5)
		(connect_pads
			(clearance 0)
		)
		(min_thickness 0.25)
		(keepout
			(tracks not_allowed)
			(vias allowed)
			(pads allowed)
			(copperpour not_allowed)
			(footprints allowed)
		)
		(placement
			(enabled no)
			(sheetname "")
		)
		(fill yes
			(thermal_gap 0.5)
			(thermal_bridge_width 0.5)
			(island_removal_mode 0)
		)
		(polygon
			(pts
				(arc
					(start 84.3661 -240.434368)
					(mid 83.73618 -240.434368)
					(end 84.3661 -240.434368)
				)
			)
		)
	)
	(zone
		(layers "B.Cu" "In13.Cu" "In15.Cu")
		(hatch none 0.5)
		(connect_pads
			(clearance 0)
		)
		(min_thickness 0.25)
		(keepout
			(tracks not_allowed)
			(vias allowed)
			(pads allowed)
			(copperpour not_allowed)
			(footprints allowed)
		)
		(placement
			(enabled no)
			(sheetname "")
		)
		(fill yes
			(thermal_gap 0.5)
			(thermal_bridge_width 0.5)
			(island_removal_mode 0)
		)
		(polygon
			(pts
				(arc
					(start 108.80598 -246.914416)
					(mid 108.17606 -246.914416)
					(end 108.80598 -246.914416)
				)
			)
		)
	)
	(zone
		(layers "B.Cu" "In13.Cu" "In15.Cu")
		(hatch none 0.5)
		(connect_pads
			(clearance 0)
		)
		(min_thickness 0.25)
		(keepout
			(tracks not_allowed)
			(vias allowed)
			(pads allowed)
			(copperpour not_allowed)
			(footprints allowed)
		)
		(placement
			(enabled no)
			(sheetname "")
		)
		(fill yes
			(thermal_gap 0.5)
			(thermal_bridge_width 0.5)
			(island_removal_mode 0)
		)
		(polygon
			(pts
				(arc
					(start 454.522078 -245.785132)
					(mid 453.854058 -245.785132)
					(end 454.522078 -245.785132)
				)
			)
		)
	)
	(zone
		(layers "B.Cu" "In13.Cu" "In15.Cu")
		(hatch none 0.5)
		(connect_pads
			(clearance 0)
		)
		(min_thickness 0.25)
		(keepout
			(tracks not_allowed)
			(vias allowed)
			(pads allowed)
			(copperpour not_allowed)
			(footprints allowed)
		)
		(placement
			(enabled no)
			(sheetname "")
		)
		(fill yes
			(thermal_gap 0.5)
			(thermal_bridge_width 0.5)
			(island_removal_mode 0)
		)
		(polygon
			(pts
				(arc
					(start 333.716122 -234.764072)
					(mid 333.086202 -234.764072)
					(end 333.716122 -234.764072)
				)
			)
		)
	)
	(zone
		(layers "B.Cu" "In13.Cu" "In15.Cu")
		(hatch none 0.5)
		(connect_pads
			(clearance 0)
		)
		(min_thickness 0.25)
		(keepout
			(tracks not_allowed)
			(vias allowed)
			(pads allowed)
			(copperpour not_allowed)
			(footprints allowed)
		)
		(placement
			(enabled no)
			(sheetname "")
		)
		(fill yes
			(thermal_gap 0.5)
			(thermal_bridge_width 0.5)
			(island_removal_mode 0)
		)
		(polygon
			(pts
				(arc
					(start 385.879848 -227.474272)
					(mid 385.249928 -227.474272)
					(end 385.879848 -227.474272)
				)
			)
		)
	)
	(zone
		(layers "B.Cu" "In13.Cu" "In15.Cu")
		(hatch none 0.5)
		(connect_pads
			(clearance 0)
		)
		(min_thickness 0.25)
		(keepout
			(tracks not_allowed)
			(vias allowed)
			(pads allowed)
			(copperpour not_allowed)
			(footprints allowed)
		)
		(placement
			(enabled no)
			(sheetname "")
		)
		(fill yes
			(thermal_gap 0.5)
			(thermal_bridge_width 0.5)
			(island_removal_mode 0)
		)
		(polygon
			(pts
				(arc
					(start 17.942052 -215.185244)
					(mid 17.274032 -215.185244)
					(end 17.942052 -215.185244)
				)
			)
		)
	)
	(zone
		(layers "B.Cu" "In13.Cu" "In15.Cu")
		(hatch none 0.5)
		(connect_pads
			(clearance 0)
		)
		(min_thickness 0.25)
		(keepout
			(tracks not_allowed)
			(vias allowed)
			(pads allowed)
			(copperpour not_allowed)
			(footprints allowed)
		)
		(placement
			(enabled no)
			(sheetname "")
		)
		(fill yes
			(thermal_gap 0.5)
			(thermal_bridge_width 0.5)
			(island_removal_mode 0)
		)
		(polygon
			(pts
				(arc
					(start 387.289802 -239.624108)
					(mid 386.659882 -239.624108)
					(end 387.289802 -239.624108)
				)
			)
		)
	)
	(zone
		(layers "B.Cu" "In13.Cu" "In15.Cu")
		(hatch none 0.5)
		(connect_pads
			(clearance 0)
		)
		(min_thickness 0.25)
		(keepout
			(tracks not_allowed)
			(vias allowed)
			(pads allowed)
			(copperpour not_allowed)
			(footprints allowed)
		)
		(placement
			(enabled no)
			(sheetname "")
		)
		(fill yes
			(thermal_gap 0.5)
			(thermal_bridge_width 0.5)
			(island_removal_mode 0)
		)
		(polygon
			(pts
				(arc
					(start 454.522078 -200.735184)
					(mid 453.854058 -200.735184)
					(end 454.522078 -200.735184)
				)
			)
		)
	)
	(zone
		(layers "B.Cu" "In13.Cu" "In15.Cu")
		(hatch none 0.5)
		(connect_pads
			(clearance 0)
		)
		(min_thickness 0.25)
		(keepout
			(tracks not_allowed)
			(vias allowed)
			(pads allowed)
			(copperpour not_allowed)
			(footprints allowed)
		)
		(placement
			(enabled no)
			(sheetname "")
		)
		(fill yes
			(thermal_gap 0.5)
			(thermal_bridge_width 0.5)
			(island_removal_mode 0)
		)
		(polygon
			(pts
				(arc
					(start 354.696014 -278.136096)
					(mid 354.066094 -278.136096)
					(end 354.696014 -278.136096)
				)
			)
		)
	)
	(zone
		(layers "B.Cu" "In13.Cu" "In15.Cu")
		(hatch none 0.5)
		(connect_pads
			(clearance 0)
		)
		(min_thickness 0.25)
		(keepout
			(tracks not_allowed)
			(vias allowed)
			(pads allowed)
			(copperpour not_allowed)
			(footprints allowed)
		)
		(placement
			(enabled no)
			(sheetname "")
		)
		(fill yes
			(thermal_gap 0.5)
			(thermal_bridge_width 0.5)
			(island_removal_mode 0)
		)
		(polygon
			(pts
				(arc
					(start 387.589776 -279.756108)
					(mid 386.959856 -279.756108)
					(end 387.589776 -279.756108)
				)
			)
		)
	)
	(zone
		(layers "B.Cu" "In13.Cu" "In15.Cu")
		(hatch none 0.5)
		(connect_pads
			(clearance 0)
		)
		(min_thickness 0.25)
		(keepout
			(tracks not_allowed)
			(vias allowed)
			(pads allowed)
			(copperpour not_allowed)
			(footprints allowed)
		)
		(placement
			(enabled no)
			(sheetname "")
		)
		(fill yes
			(thermal_gap 0.5)
			(thermal_bridge_width 0.5)
			(island_removal_mode 0)
		)
		(polygon
			(pts
				(arc
					(start 17.942052 -316.33541)
					(mid 17.274032 -316.33541)
					(end 17.942052 -316.33541)
				)
			)
		)
	)
	(zone
		(layers "B.Cu" "In13.Cu" "In15.Cu")
		(hatch none 0.5)
		(connect_pads
			(clearance 0)
		)
		(min_thickness 0.25)
		(keepout
			(tracks not_allowed)
			(vias allowed)
			(pads allowed)
			(copperpour not_allowed)
			(footprints allowed)
		)
		(placement
			(enabled no)
			(sheetname "")
		)
		(fill yes
			(thermal_gap 0.5)
			(thermal_bridge_width 0.5)
			(island_removal_mode 0)
		)
		(polygon
			(pts
				(arc
					(start 387.589776 -284.616144)
					(mid 386.959856 -284.616144)
					(end 387.589776 -284.616144)
				)
			)
		)
	)
	(zone
		(layers "B.Cu" "In13.Cu" "In15.Cu")
		(hatch none 0.5)
		(connect_pads
			(clearance 0)
		)
		(min_thickness 0.25)
		(keepout
			(tracks not_allowed)
			(vias allowed)
			(pads allowed)
			(copperpour not_allowed)
			(footprints allowed)
		)
		(placement
			(enabled no)
			(sheetname "")
		)
		(fill yes
			(thermal_gap 0.5)
			(thermal_bridge_width 0.5)
			(island_removal_mode 0)
		)
		(polygon
			(pts
				(arc
					(start 131.734306 -371.49913)
					(mid 131.066286 -371.49913)
					(end 131.734306 -371.49913)
				)
			)
		)
	)
	(zone
		(layers "B.Cu" "In13.Cu" "In15.Cu")
		(hatch none 0.5)
		(connect_pads
			(clearance 0)
		)
		(min_thickness 0.25)
		(keepout
			(tracks not_allowed)
			(vias allowed)
			(pads allowed)
			(copperpour not_allowed)
			(footprints allowed)
		)
		(placement
			(enabled no)
			(sheetname "")
		)
		(fill yes
			(thermal_gap 0.5)
			(thermal_bridge_width 0.5)
			(island_removal_mode 0)
		)
		(polygon
			(pts
				(arc
					(start 22.04212 -304.435256)
					(mid 21.3741 -304.435256)
					(end 22.04212 -304.435256)
				)
			)
		)
	)
	(zone
		(layers "B.Cu" "In13.Cu" "In15.Cu")
		(hatch none 0.5)
		(connect_pads
			(clearance 0)
		)
		(min_thickness 0.25)
		(keepout
			(tracks not_allowed)
			(vias allowed)
			(pads allowed)
			(copperpour not_allowed)
			(footprints allowed)
		)
		(placement
			(enabled no)
			(sheetname "")
		)
		(fill yes
			(thermal_gap 0.5)
			(thermal_bridge_width 0.5)
			(island_removal_mode 0)
		)
		(polygon
			(pts
				(arc
					(start 346.236036 -274.896072)
					(mid 345.606116 -274.896072)
					(end 346.236036 -274.896072)
				)
			)
		)
	)
	(zone
		(layers "B.Cu" "In13.Cu" "In15.Cu")
		(hatch none 0.5)
		(connect_pads
			(clearance 0)
		)
		(min_thickness 0.25)
		(keepout
			(tracks not_allowed)
			(vias allowed)
			(pads allowed)
			(copperpour not_allowed)
			(footprints allowed)
		)
		(placement
			(enabled no)
			(sheetname "")
		)
		(fill yes
			(thermal_gap 0.5)
			(thermal_bridge_width 0.5)
			(island_removal_mode 0)
		)
		(polygon
			(pts
				(arc
					(start 265.88212 -224.534984)
					(mid 265.2141 -224.534984)
					(end 265.88212 -224.534984)
				)
			)
		)
	)
	(zone
		(layers "B.Cu" "In13.Cu" "In15.Cu")
		(hatch none 0.5)
		(connect_pads
			(clearance 0)
		)
		(min_thickness 0.25)
		(keepout
			(tracks not_allowed)
			(vias allowed)
			(pads allowed)
			(copperpour not_allowed)
			(footprints allowed)
		)
		(placement
			(enabled no)
			(sheetname "")
		)
		(fill yes
			(thermal_gap 0.5)
			(thermal_bridge_width 0.5)
			(island_removal_mode 0)
		)
		(polygon
			(pts
				(arc
					(start 17.942052 -299.335444)
					(mid 17.274032 -299.335444)
					(end 17.942052 -299.335444)
				)
			)
		)
	)
	(zone
		(layers "B.Cu" "In13.Cu" "In15.Cu")
		(hatch none 0.5)
		(connect_pads
			(clearance 0)
		)
		(min_thickness 0.25)
		(keepout
			(tracks not_allowed)
			(vias allowed)
			(pads allowed)
			(copperpour not_allowed)
			(footprints allowed)
		)
		(placement
			(enabled no)
			(sheetname "")
		)
		(fill yes
			(thermal_gap 0.5)
			(thermal_bridge_width 0.5)
			(island_removal_mode 0)
		)
		(polygon
			(pts
				(arc
					(start 17.942052 -199.8853)
					(mid 17.274032 -199.8853)
					(end 17.942052 -199.8853)
				)
			)
		)
	)
	(zone
		(layers "B.Cu" "In13.Cu" "In15.Cu")
		(hatch none 0.5)
		(connect_pads
			(clearance 0)
		)
		(min_thickness 0.25)
		(keepout
			(tracks not_allowed)
			(vias allowed)
			(pads allowed)
			(copperpour not_allowed)
			(footprints allowed)
		)
		(placement
			(enabled no)
			(sheetname "")
		)
		(fill yes
			(thermal_gap 0.5)
			(thermal_bridge_width 0.5)
			(island_removal_mode 0)
		)
		(polygon
			(pts
				(arc
					(start 137.93978 -246.914416)
					(mid 137.30986 -246.914416)
					(end 137.93978 -246.914416)
				)
			)
		)
	)
	(zone
		(layers "B.Cu" "In13.Cu" "In15.Cu")
		(hatch none 0.5)
		(connect_pads
			(clearance 0)
		)
		(min_thickness 0.25)
		(keepout
			(tracks not_allowed)
			(vias allowed)
			(pads allowed)
			(copperpour not_allowed)
			(footprints allowed)
		)
		(placement
			(enabled no)
			(sheetname "")
		)
		(fill yes
			(thermal_gap 0.5)
			(thermal_bridge_width 0.5)
			(island_removal_mode 0)
		)
		(polygon
			(pts
				(arc
					(start 206.58201 -250.885198)
					(mid 205.91399 -250.885198)
					(end 206.58201 -250.885198)
				)
			)
		)
	)
	(zone
		(layers "B.Cu" "In13.Cu" "In15.Cu")
		(hatch none 0.5)
		(connect_pads
			(clearance 0)
		)
		(min_thickness 0.25)
		(keepout
			(tracks not_allowed)
			(vias allowed)
			(pads allowed)
			(copperpour not_allowed)
			(footprints allowed)
		)
		(placement
			(enabled no)
			(sheetname "")
		)
		(fill yes
			(thermal_gap 0.5)
			(thermal_bridge_width 0.5)
			(island_removal_mode 0)
		)
		(polygon
			(pts
				(arc
					(start 17.942052 -293.38524)
					(mid 17.274032 -293.38524)
					(end 17.942052 -293.38524)
				)
			)
		)
	)
	(zone
		(layers "B.Cu" "In13.Cu" "In15.Cu")
		(hatch none 0.5)
		(connect_pads
			(clearance 0)
		)
		(min_thickness 0.25)
		(keepout
			(tracks not_allowed)
			(vias allowed)
			(pads allowed)
			(copperpour not_allowed)
			(footprints allowed)
		)
		(placement
			(enabled no)
			(sheetname "")
		)
		(fill yes
			(thermal_gap 0.5)
			(thermal_bridge_width 0.5)
			(island_removal_mode 0)
		)
		(polygon
			(pts
				(arc
					(start 332.776068 -242.864132)
					(mid 332.146148 -242.864132)
					(end 332.776068 -242.864132)
				)
			)
		)
	)
	(zone
		(layers "B.Cu" "In13.Cu" "In15.Cu")
		(hatch none 0.5)
		(connect_pads
			(clearance 0)
		)
		(min_thickness 0.25)
		(keepout
			(tracks not_allowed)
			(vias allowed)
			(pads allowed)
			(copperpour not_allowed)
			(footprints allowed)
		)
		(placement
			(enabled no)
			(sheetname "")
		)
		(fill yes
			(thermal_gap 0.5)
			(thermal_bridge_width 0.5)
			(island_removal_mode 0)
		)
		(polygon
			(pts
				(arc
					(start 333.076042 -266.796012)
					(mid 332.446122 -266.796012)
					(end 333.076042 -266.796012)
				)
			)
		)
	)
	(zone
		(layers "B.Cu" "In13.Cu" "In15.Cu")
		(hatch none 0.5)
		(connect_pads
			(clearance 0)
		)
		(min_thickness 0.25)
		(keepout
			(tracks not_allowed)
			(vias allowed)
			(pads allowed)
			(copperpour not_allowed)
			(footprints allowed)
		)
		(placement
			(enabled no)
			(sheetname "")
		)
		(fill yes
			(thermal_gap 0.5)
			(thermal_bridge_width 0.5)
			(island_removal_mode 0)
		)
		(polygon
			(pts
				(arc
					(start 450.42201 -241.53495)
					(mid 449.75399 -241.53495)
					(end 450.42201 -241.53495)
				)
			)
		)
	)
	(zone
		(layers "B.Cu" "In13.Cu" "In15.Cu")
		(hatch none 0.5)
		(connect_pads
			(clearance 0)
		)
		(min_thickness 0.25)
		(keepout
			(tracks not_allowed)
			(vias allowed)
			(pads allowed)
			(copperpour not_allowed)
			(footprints allowed)
		)
		(placement
			(enabled no)
			(sheetname "")
		)
		(fill yes
			(thermal_gap 0.5)
			(thermal_bridge_width 0.5)
			(island_removal_mode 0)
		)
		(polygon
			(pts
				(arc
					(start 129.168906 -373.96293)
					(mid 128.500886 -373.96293)
					(end 129.168906 -373.96293)
				)
			)
		)
	)
	(zone
		(layers "B.Cu" "In13.Cu" "In15.Cu")
		(hatch none 0.5)
		(connect_pads
			(clearance 0)
		)
		(min_thickness 0.25)
		(keepout
			(tracks not_allowed)
			(vias allowed)
			(pads allowed)
			(copperpour not_allowed)
			(footprints allowed)
		)
		(placement
			(enabled no)
			(sheetname "")
		)
		(fill yes
			(thermal_gap 0.5)
			(thermal_bridge_width 0.5)
			(island_removal_mode 0)
		)
		(polygon
			(pts
				(arc
					(start 87.950294 -412.570168)
					(mid 87.282274 -412.570168)
					(end 87.950294 -412.570168)
				)
			)
		)
	)
	(zone
		(layers "B.Cu" "In13.Cu" "In15.Cu")
		(hatch none 0.5)
		(connect_pads
			(clearance 0)
		)
		(min_thickness 0.25)
		(keepout
			(tracks not_allowed)
			(vias allowed)
			(pads allowed)
			(copperpour not_allowed)
			(footprints allowed)
		)
		(placement
			(enabled no)
			(sheetname "")
		)
		(fill yes
			(thermal_gap 0.5)
			(thermal_bridge_width 0.5)
			(island_removal_mode 0)
		)
		(polygon
			(pts
				(arc
					(start 22.04212 -303.585372)
					(mid 21.3741 -303.585372)
					(end 22.04212 -303.585372)
				)
			)
		)
	)
	(zone
		(layers "B.Cu" "In13.Cu" "In15.Cu")
		(hatch none 0.5)
		(connect_pads
			(clearance 0)
		)
		(min_thickness 0.25)
		(keepout
			(tracks not_allowed)
			(vias allowed)
			(pads allowed)
			(copperpour not_allowed)
			(footprints allowed)
		)
		(placement
			(enabled no)
			(sheetname "")
		)
		(fill yes
			(thermal_gap 0.5)
			(thermal_bridge_width 0.5)
			(island_removal_mode 0)
		)
		(polygon
			(pts
				(arc
					(start 107.696 -279.756362)
					(mid 107.06608 -279.756362)
					(end 107.696 -279.756362)
				)
			)
		)
	)
	(zone
		(layers "B.Cu" "In13.Cu" "In15.Cu")
		(hatch none 0.5)
		(connect_pads
			(clearance 0)
		)
		(min_thickness 0.25)
		(keepout
			(tracks not_allowed)
			(vias allowed)
			(pads allowed)
			(copperpour not_allowed)
			(footprints allowed)
		)
		(placement
			(enabled no)
			(sheetname "")
		)
		(fill yes
			(thermal_gap 0.5)
			(thermal_bridge_width 0.5)
			(island_removal_mode 0)
		)
		(polygon
			(pts
				(arc
					(start 350.940116 -420.952168)
					(mid 350.272096 -420.952168)
					(end 350.940116 -420.952168)
				)
			)
		)
	)
	(zone
		(layers "B.Cu" "In13.Cu" "In15.Cu")
		(hatch none 0.5)
		(connect_pads
			(clearance 0)
		)
		(min_thickness 0.25)
		(keepout
			(tracks not_allowed)
			(vias allowed)
			(pads allowed)
			(copperpour not_allowed)
			(footprints allowed)
		)
		(placement
			(enabled no)
			(sheetname "")
		)
		(fill yes
			(thermal_gap 0.5)
			(thermal_bridge_width 0.5)
			(island_removal_mode 0)
		)
		(polygon
			(pts
				(arc
					(start 86.545928 -287.046162)
					(mid 85.916008 -287.046162)
					(end 86.545928 -287.046162)
				)
			)
		)
	)
	(zone
		(layers "B.Cu" "In13.Cu" "In15.Cu")
		(hatch none 0.5)
		(connect_pads
			(clearance 0)
		)
		(min_thickness 0.25)
		(keepout
			(tracks not_allowed)
			(vias allowed)
			(pads allowed)
			(copperpour not_allowed)
			(footprints allowed)
		)
		(placement
			(enabled no)
			(sheetname "")
		)
		(fill yes
			(thermal_gap 0.5)
			(thermal_bridge_width 0.5)
			(island_removal_mode 0)
		)
		(polygon
			(pts
				(arc
					(start 269.982188 -278.085042)
					(mid 269.314168 -278.085042)
					(end 269.982188 -278.085042)
				)
			)
		)
	)
	(zone
		(layers "B.Cu" "In13.Cu" "In15.Cu")
		(hatch none 0.5)
		(connect_pads
			(clearance 0)
		)
		(min_thickness 0.25)
		(keepout
			(tracks not_allowed)
			(vias allowed)
			(pads allowed)
			(copperpour not_allowed)
			(footprints allowed)
		)
		(placement
			(enabled no)
			(sheetname "")
		)
		(fill yes
			(thermal_gap 0.5)
			(thermal_bridge_width 0.5)
			(island_removal_mode 0)
		)
		(polygon
			(pts
				(arc
					(start 202.481942 -263.635236)
					(mid 201.813922 -263.635236)
					(end 202.481942 -263.635236)
				)
			)
		)
	)
	(zone
		(layers "B.Cu" "In13.Cu" "In15.Cu")
		(hatch none 0.5)
		(connect_pads
			(clearance 0)
		)
		(min_thickness 0.25)
		(keepout
			(tracks not_allowed)
			(vias allowed)
			(pads allowed)
			(copperpour not_allowed)
			(footprints allowed)
		)
		(placement
			(enabled no)
			(sheetname "")
		)
		(fill yes
			(thermal_gap 0.5)
			(thermal_bridge_width 0.5)
			(island_removal_mode 0)
		)
		(polygon
			(pts
				(arc
					(start 411.913832 -420.952168)
					(mid 411.245812 -420.952168)
					(end 411.913832 -420.952168)
				)
			)
		)
	)
	(zone
		(layers "B.Cu" "In13.Cu" "In15.Cu")
		(hatch none 0.5)
		(connect_pads
			(clearance 0)
		)
		(min_thickness 0.25)
		(keepout
			(tracks not_allowed)
			(vias allowed)
			(pads allowed)
			(copperpour not_allowed)
			(footprints allowed)
		)
		(placement
			(enabled no)
			(sheetname "")
		)
		(fill yes
			(thermal_gap 0.5)
			(thermal_bridge_width 0.5)
			(island_removal_mode 0)
		)
		(polygon
			(pts
				(arc
					(start 202.481942 -210.935316)
					(mid 201.813922 -210.935316)
					(end 202.481942 -210.935316)
				)
			)
		)
	)
	(zone
		(layers "B.Cu" "In13.Cu" "In15.Cu")
		(hatch none 0.5)
		(connect_pads
			(clearance 0)
		)
		(min_thickness 0.25)
		(keepout
			(tracks not_allowed)
			(vias allowed)
			(pads allowed)
			(copperpour not_allowed)
			(footprints allowed)
		)
		(placement
			(enabled no)
			(sheetname "")
		)
		(fill yes
			(thermal_gap 0.5)
			(thermal_bridge_width 0.5)
			(island_removal_mode 0)
		)
		(polygon
			(pts
				(arc
					(start 414.113472 -420.952168)
					(mid 413.445452 -420.952168)
					(end 414.113472 -420.952168)
				)
			)
		)
	)
	(zone
		(layers "B.Cu" "In13.Cu" "In15.Cu")
		(hatch none 0.5)
		(connect_pads
			(clearance 0)
		)
		(min_thickness 0.25)
		(keepout
			(tracks not_allowed)
			(vias allowed)
			(pads allowed)
			(copperpour not_allowed)
			(footprints allowed)
		)
		(placement
			(enabled no)
			(sheetname "")
		)
		(fill yes
			(thermal_gap 0.5)
			(thermal_bridge_width 0.5)
			(island_removal_mode 0)
		)
		(polygon
			(pts
				(arc
					(start 84.666074 -274.08632)
					(mid 84.036154 -274.08632)
					(end 84.666074 -274.08632)
				)
			)
		)
	)
	(zone
		(layers "B.Cu" "In13.Cu" "In15.Cu")
		(hatch none 0.5)
		(connect_pads
			(clearance 0)
		)
		(min_thickness 0.25)
		(keepout
			(tracks not_allowed)
			(vias allowed)
			(pads allowed)
			(copperpour not_allowed)
			(footprints allowed)
		)
		(placement
			(enabled no)
			(sheetname "")
		)
		(fill yes
			(thermal_gap 0.5)
			(thermal_bridge_width 0.5)
			(island_removal_mode 0)
		)
		(polygon
			(pts
				(arc
					(start 44.113704 -17.61236)
					(mid 43.445684 -17.61236)
					(end 44.113704 -17.61236)
				)
			)
		)
	)
	(zone
		(layers "B.Cu" "In13.Cu" "In15.Cu")
		(hatch none 0.5)
		(connect_pads
			(clearance 0)
		)
		(min_thickness 0.25)
		(keepout
			(tracks not_allowed)
			(vias allowed)
			(pads allowed)
			(copperpour not_allowed)
			(footprints allowed)
		)
		(placement
			(enabled no)
			(sheetname "")
		)
		(fill yes
			(thermal_gap 0.5)
			(thermal_bridge_width 0.5)
			(island_removal_mode 0)
		)
		(polygon
			(pts
				(arc
					(start 265.88212 -316.335156)
					(mid 265.2141 -316.335156)
					(end 265.88212 -316.335156)
				)
			)
		)
	)
	(zone
		(layers "B.Cu" "In13.Cu" "In15.Cu")
		(hatch none 0.5)
		(connect_pads
			(clearance 0)
		)
		(min_thickness 0.25)
		(keepout
			(tracks not_allowed)
			(vias allowed)
			(pads allowed)
			(copperpour not_allowed)
			(footprints allowed)
		)
		(placement
			(enabled no)
			(sheetname "")
		)
		(fill yes
			(thermal_gap 0.5)
			(thermal_bridge_width 0.5)
			(island_removal_mode 0)
		)
		(polygon
			(pts
				(arc
					(start 139.819634 -243.674392)
					(mid 139.189714 -243.674392)
					(end 139.819634 -243.674392)
				)
			)
		)
	)
	(zone
		(layers "B.Cu" "In13.Cu" "In15.Cu")
		(hatch none 0.5)
		(connect_pads
			(clearance 0)
		)
		(min_thickness 0.25)
		(keepout
			(tracks not_allowed)
			(vias allowed)
			(pads allowed)
			(copperpour not_allowed)
			(footprints allowed)
		)
		(placement
			(enabled no)
			(sheetname "")
		)
		(fill yes
			(thermal_gap 0.5)
			(thermal_bridge_width 0.5)
			(island_removal_mode 0)
		)
		(polygon
			(pts
				(arc
					(start 202.481942 -199.8853)
					(mid 201.813922 -199.8853)
					(end 202.481942 -199.8853)
				)
			)
		)
	)
	(zone
		(layers "B.Cu" "In13.Cu" "In15.Cu")
		(hatch none 0.5)
		(connect_pads
			(clearance 0)
		)
		(min_thickness 0.25)
		(keepout
			(tracks not_allowed)
			(vias allowed)
			(pads allowed)
			(copperpour not_allowed)
			(footprints allowed)
		)
		(placement
			(enabled no)
			(sheetname "")
		)
		(fill yes
			(thermal_gap 0.5)
			(thermal_bridge_width 0.5)
			(island_removal_mode 0)
		)
		(polygon
			(pts
				(arc
					(start 362.379768 -246.914162)
					(mid 361.749848 -246.914162)
					(end 362.379768 -246.914162)
				)
			)
		)
	)
	(zone
		(layers "B.Cu" "In13.Cu" "In15.Cu")
		(hatch none 0.5)
		(connect_pads
			(clearance 0)
		)
		(min_thickness 0.25)
		(keepout
			(tracks not_allowed)
			(vias allowed)
			(pads allowed)
			(copperpour not_allowed)
			(footprints allowed)
		)
		(placement
			(enabled no)
			(sheetname "")
		)
		(fill yes
			(thermal_gap 0.5)
			(thermal_bridge_width 0.5)
			(island_removal_mode 0)
		)
		(polygon
			(pts
				(arc
					(start 17.942052 -297.635422)
					(mid 17.274032 -297.635422)
					(end 17.942052 -297.635422)
				)
			)
		)
	)
	(zone
		(layers "B.Cu" "In13.Cu" "In15.Cu")
		(hatch none 0.5)
		(connect_pads
			(clearance 0)
		)
		(min_thickness 0.25)
		(keepout
			(tracks not_allowed)
			(vias allowed)
			(pads allowed)
			(copperpour not_allowed)
			(footprints allowed)
		)
		(placement
			(enabled no)
			(sheetname "")
		)
		(fill yes
			(thermal_gap 0.5)
			(thermal_bridge_width 0.5)
			(island_removal_mode 0)
		)
		(polygon
			(pts
				(arc
					(start 373.256302 -379.88113)
					(mid 372.588282 -379.88113)
					(end 373.256302 -379.88113)
				)
			)
		)
	)
	(zone
		(layers "B.Cu" "In13.Cu" "In15.Cu")
		(hatch none 0.5)
		(connect_pads
			(clearance 0)
		)
		(min_thickness 0.25)
		(keepout
			(tracks not_allowed)
			(vias allowed)
			(pads allowed)
			(copperpour not_allowed)
			(footprints allowed)
		)
		(placement
			(enabled no)
			(sheetname "")
		)
		(fill yes
			(thermal_gap 0.5)
			(thermal_bridge_width 0.5)
			(island_removal_mode 0)
		)
		(polygon
			(pts
				(arc
					(start 84.3661 -242.05438)
					(mid 83.73618 -242.05438)
					(end 84.3661 -242.05438)
				)
			)
		)
	)
	(zone
		(layers "B.Cu" "In13.Cu" "In15.Cu")
		(hatch none 0.5)
		(connect_pads
			(clearance 0)
		)
		(min_thickness 0.25)
		(keepout
			(tracks not_allowed)
			(vias allowed)
			(pads allowed)
			(copperpour not_allowed)
			(footprints allowed)
		)
		(placement
			(enabled no)
			(sheetname "")
		)
		(fill yes
			(thermal_gap 0.5)
			(thermal_bridge_width 0.5)
			(island_removal_mode 0)
		)
		(polygon
			(pts
				(arc
					(start 100.815902 -247.724422)
					(mid 100.185982 -247.724422)
					(end 100.815902 -247.724422)
				)
			)
		)
	)
	(zone
		(layers "B.Cu" "In13.Cu" "In15.Cu")
		(hatch none 0.5)
		(connect_pads
			(clearance 0)
		)
		(min_thickness 0.25)
		(keepout
			(tracks not_allowed)
			(vias allowed)
			(pads allowed)
			(copperpour not_allowed)
			(footprints allowed)
		)
		(placement
			(enabled no)
			(sheetname "")
		)
		(fill yes
			(thermal_gap 0.5)
			(thermal_bridge_width 0.5)
			(island_removal_mode 0)
		)
		(polygon
			(pts
				(arc
					(start 334.016096 -276.516084)
					(mid 333.386176 -276.516084)
					(end 334.016096 -276.516084)
				)
			)
		)
	)
	(zone
		(layers "B.Cu" "In13.Cu" "In15.Cu")
		(hatch none 0.5)
		(connect_pads
			(clearance 0)
		)
		(min_thickness 0.25)
		(keepout
			(tracks not_allowed)
			(vias allowed)
			(pads allowed)
			(copperpour not_allowed)
			(footprints allowed)
		)
		(placement
			(enabled no)
			(sheetname "")
		)
		(fill yes
			(thermal_gap 0.5)
			(thermal_bridge_width 0.5)
			(island_removal_mode 0)
		)
		(polygon
			(pts
				(arc
					(start 334.186022 -240.434114)
					(mid 333.556102 -240.434114)
					(end 334.186022 -240.434114)
				)
			)
		)
	)
	(zone
		(layers "B.Cu" "In13.Cu" "In15.Cu")
		(hatch none 0.5)
		(connect_pads
			(clearance 0)
		)
		(min_thickness 0.25)
		(keepout
			(tracks not_allowed)
			(vias allowed)
			(pads allowed)
			(copperpour not_allowed)
			(footprints allowed)
		)
		(placement
			(enabled no)
			(sheetname "")
		)
		(fill yes
			(thermal_gap 0.5)
			(thermal_bridge_width 0.5)
			(island_removal_mode 0)
		)
		(polygon
			(pts
				(arc
					(start 328.633836 -420.952168)
					(mid 327.965816 -420.952168)
					(end 328.633836 -420.952168)
				)
			)
		)
	)
	(zone
		(layers "B.Cu" "In13.Cu" "In15.Cu")
		(hatch none 0.5)
		(connect_pads
			(clearance 0)
		)
		(min_thickness 0.25)
		(keepout
			(tracks not_allowed)
			(vias allowed)
			(pads allowed)
			(copperpour not_allowed)
			(footprints allowed)
		)
		(placement
			(enabled no)
			(sheetname "")
		)
		(fill yes
			(thermal_gap 0.5)
			(thermal_bridge_width 0.5)
			(island_removal_mode 0)
		)
		(polygon
			(pts
				(arc
					(start 265.88212 -238.985044)
					(mid 265.2141 -238.985044)
					(end 265.88212 -238.985044)
				)
			)
		)
	)
	(zone
		(layers "B.Cu" "In13.Cu" "In15.Cu")
		(hatch none 0.5)
		(connect_pads
			(clearance 0)
		)
		(min_thickness 0.25)
		(keepout
			(tracks not_allowed)
			(vias allowed)
			(pads allowed)
			(copperpour not_allowed)
			(footprints allowed)
		)
		(placement
			(enabled no)
			(sheetname "")
		)
		(fill yes
			(thermal_gap 0.5)
			(thermal_bridge_width 0.5)
			(island_removal_mode 0)
		)
		(polygon
			(pts
				(arc
					(start 409.137104 -431.889916)
					(mid 408.362912 -431.889916)
					(end 409.137104 -431.889916)
				)
			)
		)
	)
	(zone
		(layers "B.Cu" "In13.Cu" "In15.Cu")
		(hatch none 0.5)
		(connect_pads
			(clearance 0)
		)
		(min_thickness 0.25)
		(keepout
			(tracks not_allowed)
			(vias allowed)
			(pads allowed)
			(copperpour not_allowed)
			(footprints allowed)
		)
		(placement
			(enabled no)
			(sheetname "")
		)
		(fill yes
			(thermal_gap 0.5)
			(thermal_bridge_width 0.5)
			(island_removal_mode 0)
		)
		(polygon
			(pts
				(arc
					(start 17.942052 -295.085262)
					(mid 17.274032 -295.085262)
					(end 17.942052 -295.085262)
				)
			)
		)
	)
	(zone
		(layers "B.Cu" "In13.Cu" "In15.Cu")
		(hatch none 0.5)
		(connect_pads
			(clearance 0)
		)
		(min_thickness 0.25)
		(keepout
			(tracks not_allowed)
			(vias allowed)
			(pads allowed)
			(copperpour not_allowed)
			(footprints allowed)
		)
		(placement
			(enabled no)
			(sheetname "")
		)
		(fill yes
			(thermal_gap 0.5)
			(thermal_bridge_width 0.5)
			(island_removal_mode 0)
		)
		(polygon
			(pts
				(arc
					(start 206.58201 -294.235378)
					(mid 205.91399 -294.235378)
					(end 206.58201 -294.235378)
				)
			)
		)
	)
	(zone
		(layers "B.Cu" "In13.Cu" "In15.Cu")
		(hatch none 0.5)
		(connect_pads
			(clearance 0)
		)
		(min_thickness 0.25)
		(keepout
			(tracks not_allowed)
			(vias allowed)
			(pads allowed)
			(copperpour not_allowed)
			(footprints allowed)
		)
		(placement
			(enabled no)
			(sheetname "")
		)
		(fill yes
			(thermal_gap 0.5)
			(thermal_bridge_width 0.5)
			(island_removal_mode 0)
		)
		(polygon
			(pts
				(arc
					(start 450.42201 -312.084974)
					(mid 449.75399 -312.084974)
					(end 450.42201 -312.084974)
				)
			)
		)
	)
	(zone
		(layers "B.Cu" "In13.Cu" "In15.Cu")
		(hatch none 0.5)
		(connect_pads
			(clearance 0)
		)
		(min_thickness 0.25)
		(keepout
			(tracks not_allowed)
			(vias allowed)
			(pads allowed)
			(copperpour not_allowed)
			(footprints allowed)
		)
		(placement
			(enabled no)
			(sheetname "")
		)
		(fill yes
			(thermal_gap 0.5)
			(thermal_bridge_width 0.5)
			(island_removal_mode 0)
		)
		(polygon
			(pts
				(arc
					(start 411.050232 -420.952168)
					(mid 410.382212 -420.952168)
					(end 411.050232 -420.952168)
				)
			)
		)
	)
	(zone
		(layers "B.Cu" "In13.Cu" "In15.Cu")
		(hatch none 0.5)
		(connect_pads
			(clearance 0)
		)
		(min_thickness 0.25)
		(keepout
			(tracks not_allowed)
			(vias allowed)
			(pads allowed)
			(copperpour not_allowed)
			(footprints allowed)
		)
		(placement
			(enabled no)
			(sheetname "")
		)
		(fill yes
			(thermal_gap 0.5)
			(thermal_bridge_width 0.5)
			(island_removal_mode 0)
		)
		(polygon
			(pts
				(arc
					(start 386.649722 -263.555988)
					(mid 386.019802 -263.555988)
					(end 386.649722 -263.555988)
				)
			)
		)
	)
	(zone
		(layers "B.Cu" "In13.Cu" "In15.Cu")
		(hatch none 0.5)
		(connect_pads
			(clearance 0)
		)
		(min_thickness 0.25)
		(keepout
			(tracks not_allowed)
			(vias allowed)
			(pads allowed)
			(copperpour not_allowed)
			(footprints allowed)
		)
		(placement
			(enabled no)
			(sheetname "")
		)
		(fill yes
			(thermal_gap 0.5)
			(thermal_bridge_width 0.5)
			(island_removal_mode 0)
		)
		(polygon
			(pts
				(arc
					(start 84.836 -255.824482)
					(mid 84.20608 -255.824482)
					(end 84.836 -255.824482)
				)
			)
		)
	)
	(zone
		(layers "B.Cu" "In13.Cu" "In15.Cu")
		(hatch none 0.5)
		(connect_pads
			(clearance 0)
		)
		(min_thickness 0.25)
		(keepout
			(tracks not_allowed)
			(vias allowed)
			(pads allowed)
			(copperpour not_allowed)
			(footprints allowed)
		)
		(placement
			(enabled no)
			(sheetname "")
		)
		(fill yes
			(thermal_gap 0.5)
			(thermal_bridge_width 0.5)
			(island_removal_mode 0)
		)
		(polygon
			(pts
				(arc
					(start 362.379768 -243.674138)
					(mid 361.749848 -243.674138)
					(end 362.379768 -243.674138)
				)
			)
		)
	)
	(zone
		(layers "B.Cu" "In13.Cu" "In15.Cu")
		(hatch none 0.5)
		(connect_pads
			(clearance 0)
		)
		(min_thickness 0.25)
		(keepout
			(tracks not_allowed)
			(vias allowed)
			(pads allowed)
			(copperpour not_allowed)
			(footprints allowed)
		)
		(placement
			(enabled no)
			(sheetname "")
		)
		(fill yes
			(thermal_gap 0.5)
			(thermal_bridge_width 0.5)
			(island_removal_mode 0)
		)
		(polygon
			(pts
				(arc
					(start 85.135974 -279.756362)
					(mid 84.506054 -279.756362)
					(end 85.135974 -279.756362)
				)
			)
		)
	)
	(zone
		(layers "B.Cu" "In13.Cu" "In15.Cu")
		(hatch none 0.5)
		(connect_pads
			(clearance 0)
		)
		(min_thickness 0.25)
		(keepout
			(tracks not_allowed)
			(vias allowed)
			(pads allowed)
			(copperpour not_allowed)
			(footprints allowed)
		)
		(placement
			(enabled no)
			(sheetname "")
		)
		(fill yes
			(thermal_gap 0.5)
			(thermal_bridge_width 0.5)
			(island_removal_mode 0)
		)
		(polygon
			(pts
				(arc
					(start 323.036692 -429.689768)
					(mid 322.2625 -429.689768)
					(end 323.036692 -429.689768)
				)
			)
		)
	)
	(zone
		(layers "B.Cu" "In13.Cu" "In15.Cu")
		(hatch none 0.5)
		(connect_pads
			(clearance 0)
		)
		(min_thickness 0.25)
		(keepout
			(tracks not_allowed)
			(vias allowed)
			(pads allowed)
			(copperpour not_allowed)
			(footprints allowed)
		)
		(placement
			(enabled no)
			(sheetname "")
		)
		(fill yes
			(thermal_gap 0.5)
			(thermal_bridge_width 0.5)
			(island_removal_mode 0)
		)
		(polygon
			(pts
				(arc
					(start 139.734036 -412.570168)
					(mid 139.066016 -412.570168)
					(end 139.734036 -412.570168)
				)
			)
		)
	)
	(zone
		(layers "B.Cu" "In13.Cu" "In15.Cu")
		(hatch none 0.5)
		(connect_pads
			(clearance 0)
		)
		(min_thickness 0.25)
		(keepout
			(tracks not_allowed)
			(vias allowed)
			(pads allowed)
			(copperpour not_allowed)
			(footprints allowed)
		)
		(placement
			(enabled no)
			(sheetname "")
		)
		(fill yes
			(thermal_gap 0.5)
			(thermal_bridge_width 0.5)
			(island_removal_mode 0)
		)
		(polygon
			(pts
				(arc
					(start 17.942052 -246.63527)
					(mid 17.274032 -246.63527)
					(end 17.942052 -246.63527)
				)
			)
		)
	)
	(zone
		(layers "B.Cu" "In13.Cu" "In15.Cu")
		(hatch none 0.5)
		(connect_pads
			(clearance 0)
		)
		(min_thickness 0.25)
		(keepout
			(tracks not_allowed)
			(vias allowed)
			(pads allowed)
			(copperpour not_allowed)
			(footprints allowed)
		)
		(placement
			(enabled no)
			(sheetname "")
		)
		(fill yes
			(thermal_gap 0.5)
			(thermal_bridge_width 0.5)
			(island_removal_mode 0)
		)
		(polygon
			(pts
				(arc
					(start 367.549684 -247.724168)
					(mid 366.919764 -247.724168)
					(end 367.549684 -247.724168)
				)
			)
		)
	)
	(zone
		(layers "B.Cu" "In13.Cu" "In15.Cu")
		(hatch none 0.5)
		(connect_pads
			(clearance 0)
		)
		(min_thickness 0.25)
		(keepout
			(tracks not_allowed)
			(vias allowed)
			(pads allowed)
			(copperpour not_allowed)
			(footprints allowed)
		)
		(placement
			(enabled no)
			(sheetname "")
		)
		(fill yes
			(thermal_gap 0.5)
			(thermal_bridge_width 0.5)
			(island_removal_mode 0)
		)
		(polygon
			(pts
				(arc
					(start 69.036946 -430.689766)
					(mid 68.262754 -430.689766)
					(end 69.036946 -430.689766)
				)
			)
		)
	)
	(zone
		(layers "B.Cu" "In13.Cu" "In15.Cu")
		(hatch none 0.5)
		(connect_pads
			(clearance 0)
		)
		(min_thickness 0.25)
		(keepout
			(tracks not_allowed)
			(vias allowed)
			(pads allowed)
			(copperpour not_allowed)
			(footprints allowed)
		)
		(placement
			(enabled no)
			(sheetname "")
		)
		(fill yes
			(thermal_gap 0.5)
			(thermal_bridge_width 0.5)
			(island_removal_mode 0)
		)
		(polygon
			(pts
				(arc
					(start 116.789708 -234.764326)
					(mid 116.159788 -234.764326)
					(end 116.789708 -234.764326)
				)
			)
		)
	)
	(zone
		(layers "B.Cu" "In13.Cu" "In15.Cu")
		(hatch none 0.5)
		(connect_pads
			(clearance 0)
		)
		(min_thickness 0.25)
		(keepout
			(tracks not_allowed)
			(vias allowed)
			(pads allowed)
			(copperpour not_allowed)
			(footprints allowed)
		)
		(placement
			(enabled no)
			(sheetname "")
		)
		(fill yes
			(thermal_gap 0.5)
			(thermal_bridge_width 0.5)
			(island_removal_mode 0)
		)
		(polygon
			(pts
				(arc
					(start 17.942052 -210.935316)
					(mid 17.274032 -210.935316)
					(end 17.942052 -210.935316)
				)
			)
		)
	)
	(zone
		(layers "B.Cu" "In13.Cu" "In15.Cu")
		(hatch none 0.5)
		(connect_pads
			(clearance 0)
		)
		(min_thickness 0.25)
		(keepout
			(tracks not_allowed)
			(vias allowed)
			(pads allowed)
			(copperpour not_allowed)
			(footprints allowed)
		)
		(placement
			(enabled no)
			(sheetname "")
		)
		(fill yes
			(thermal_gap 0.5)
			(thermal_bridge_width 0.5)
			(island_removal_mode 0)
		)
		(polygon
			(pts
				(arc
					(start 86.634066 -385.31038)
					(mid 86.004146 -385.31038)
					(end 86.634066 -385.31038)
				)
			)
		)
	)
	(zone
		(layers "B.Cu" "In13.Cu" "In15.Cu")
		(hatch none 0.5)
		(connect_pads
			(clearance 0)
		)
		(min_thickness 0.25)
		(keepout
			(tracks not_allowed)
			(vias allowed)
			(pads allowed)
			(copperpour not_allowed)
			(footprints allowed)
		)
		(placement
			(enabled no)
			(sheetname "")
		)
		(fill yes
			(thermal_gap 0.5)
			(thermal_bridge_width 0.5)
			(island_removal_mode 0)
		)
		(polygon
			(pts
				(arc
					(start 84.836 -242.864386)
					(mid 84.20608 -242.864386)
					(end 84.836 -242.864386)
				)
			)
		)
	)
	(zone
		(layers "B.Cu" "In13.Cu" "In15.Cu")
		(hatch none 0.5)
		(connect_pads
			(clearance 0)
		)
		(min_thickness 0.25)
		(keepout
			(tracks not_allowed)
			(vias allowed)
			(pads allowed)
			(copperpour not_allowed)
			(footprints allowed)
		)
		(placement
			(enabled no)
			(sheetname "")
		)
		(fill yes
			(thermal_gap 0.5)
			(thermal_bridge_width 0.5)
			(island_removal_mode 0)
		)
		(polygon
			(pts
				(arc
					(start 136.136888 -431.889916)
					(mid 135.362696 -431.889916)
					(end 136.136888 -431.889916)
				)
			)
		)
	)
	(zone
		(layers "B.Cu" "In13.Cu" "In15.Cu")
		(hatch none 0.5)
		(connect_pads
			(clearance 0)
		)
		(min_thickness 0.25)
		(keepout
			(tracks not_allowed)
			(vias allowed)
			(pads allowed)
			(copperpour not_allowed)
			(footprints allowed)
		)
		(placement
			(enabled no)
			(sheetname "")
		)
		(fill yes
			(thermal_gap 0.5)
			(thermal_bridge_width 0.5)
			(island_removal_mode 0)
		)
		(polygon
			(pts
				(arc
					(start 375.154952 -420.952168)
					(mid 374.486932 -420.952168)
					(end 375.154952 -420.952168)
				)
			)
		)
	)
	(zone
		(layers "B.Cu" "In13.Cu" "In15.Cu")
		(hatch none 0.5)
		(connect_pads
			(clearance 0)
		)
		(min_thickness 0.25)
		(keepout
			(tracks not_allowed)
			(vias allowed)
			(pads allowed)
			(copperpour not_allowed)
			(footprints allowed)
		)
		(placement
			(enabled no)
			(sheetname "")
		)
		(fill yes
			(thermal_gap 0.5)
			(thermal_bridge_width 0.5)
			(island_removal_mode 0)
		)
		(polygon
			(pts
				(arc
					(start 454.522078 -317.18504)
					(mid 453.854058 -317.18504)
					(end 454.522078 -317.18504)
				)
			)
		)
	)
	(zone
		(layers "B.Cu" "In13.Cu" "In15.Cu")
		(hatch none 0.5)
		(connect_pads
			(clearance 0)
		)
		(min_thickness 0.25)
		(keepout
			(tracks not_allowed)
			(vias allowed)
			(pads allowed)
			(copperpour not_allowed)
			(footprints allowed)
		)
		(placement
			(enabled no)
			(sheetname "")
		)
		(fill yes
			(thermal_gap 0.5)
			(thermal_bridge_width 0.5)
			(island_removal_mode 0)
		)
		(polygon
			(pts
				(arc
					(start 269.982188 -312.935112)
					(mid 269.314168 -312.935112)
					(end 269.982188 -312.935112)
				)
			)
		)
	)
	(zone
		(layers "B.Cu" "In13.Cu" "In15.Cu")
		(hatch none 0.5)
		(connect_pads
			(clearance 0)
		)
		(min_thickness 0.25)
		(keepout
			(tracks not_allowed)
			(vias allowed)
			(pads allowed)
			(copperpour not_allowed)
			(footprints allowed)
		)
		(placement
			(enabled no)
			(sheetname "")
		)
		(fill yes
			(thermal_gap 0.5)
			(thermal_bridge_width 0.5)
			(island_removal_mode 0)
		)
		(polygon
			(pts
				(arc
					(start 132.136896 -430.689766)
					(mid 131.362704 -430.689766)
					(end 132.136896 -430.689766)
				)
			)
		)
	)
	(zone
		(layers "B.Cu" "In13.Cu" "In15.Cu")
		(hatch none 0.5)
		(connect_pads
			(clearance 0)
		)
		(min_thickness 0.25)
		(keepout
			(tracks not_allowed)
			(vias allowed)
			(pads allowed)
			(copperpour not_allowed)
			(footprints allowed)
		)
		(placement
			(enabled no)
			(sheetname "")
		)
		(fill yes
			(thermal_gap 0.5)
			(thermal_bridge_width 0.5)
			(island_removal_mode 0)
		)
		(polygon
			(pts
				(arc
					(start 202.481942 -306.985416)
					(mid 201.813922 -306.985416)
					(end 202.481942 -306.985416)
				)
			)
		)
	)
	(zone
		(layers "B.Cu" "In13.Cu" "In15.Cu")
		(hatch none 0.5)
		(connect_pads
			(clearance 0)
		)
		(min_thickness 0.25)
		(keepout
			(tracks not_allowed)
			(vias allowed)
			(pads allowed)
			(copperpour not_allowed)
			(footprints allowed)
		)
		(placement
			(enabled no)
			(sheetname "")
		)
		(fill yes
			(thermal_gap 0.5)
			(thermal_bridge_width 0.5)
			(island_removal_mode 0)
		)
		(polygon
			(pts
				(arc
					(start 137.93978 -255.014476)
					(mid 137.30986 -255.014476)
					(end 137.93978 -255.014476)
				)
			)
		)
	)
	(zone
		(layers "B.Cu" "In13.Cu" "In15.Cu")
		(hatch none 0.5)
		(connect_pads
			(clearance 0)
		)
		(min_thickness 0.25)
		(keepout
			(tracks not_allowed)
			(vias allowed)
			(pads allowed)
			(copperpour not_allowed)
			(footprints allowed)
		)
		(placement
			(enabled no)
			(sheetname "")
		)
		(fill yes
			(thermal_gap 0.5)
			(thermal_bridge_width 0.5)
			(island_removal_mode 0)
		)
		(polygon
			(pts
				(arc
					(start 22.04212 -200.735438)
					(mid 21.3741 -200.735438)
					(end 22.04212 -200.735438)
				)
			)
		)
	)
	(zone
		(layers "B.Cu" "In13.Cu" "In15.Cu")
		(hatch none 0.5)
		(connect_pads
			(clearance 0)
		)
		(min_thickness 0.25)
		(keepout
			(tracks not_allowed)
			(vias allowed)
			(pads allowed)
			(copperpour not_allowed)
			(footprints allowed)
		)
		(placement
			(enabled no)
			(sheetname "")
		)
		(fill yes
			(thermal_gap 0.5)
			(thermal_bridge_width 0.5)
			(island_removal_mode 0)
		)
		(polygon
			(pts
				(arc
					(start 22.04212 -210.085432)
					(mid 21.3741 -210.085432)
					(end 22.04212 -210.085432)
				)
			)
		)
	)
	(zone
		(layers "B.Cu" "In13.Cu" "In15.Cu")
		(hatch none 0.5)
		(connect_pads
			(clearance 0)
		)
		(min_thickness 0.25)
		(keepout
			(tracks not_allowed)
			(vias allowed)
			(pads allowed)
			(copperpour not_allowed)
			(footprints allowed)
		)
		(placement
			(enabled no)
			(sheetname "")
		)
		(fill yes
			(thermal_gap 0.5)
			(thermal_bridge_width 0.5)
			(island_removal_mode 0)
		)
		(polygon
			(pts
				(arc
					(start 332.776068 -226.664266)
					(mid 332.146148 -226.664266)
					(end 332.776068 -226.664266)
				)
			)
		)
	)
	(zone
		(layers "B.Cu" "In13.Cu" "In15.Cu")
		(hatch none 0.5)
		(connect_pads
			(clearance 0)
		)
		(min_thickness 0.25)
		(keepout
			(tracks not_allowed)
			(vias allowed)
			(pads allowed)
			(copperpour not_allowed)
			(footprints allowed)
		)
		(placement
			(enabled no)
			(sheetname "")
		)
		(fill yes
			(thermal_gap 0.5)
			(thermal_bridge_width 0.5)
			(island_removal_mode 0)
		)
		(polygon
			(pts
				(arc
					(start 394.13688 -430.889918)
					(mid 393.362688 -430.889918)
					(end 394.13688 -430.889918)
				)
			)
		)
	)
	(zone
		(layers "B.Cu" "In13.Cu" "In15.Cu")
		(hatch none 0.5)
		(connect_pads
			(clearance 0)
		)
		(min_thickness 0.25)
		(keepout
			(tracks not_allowed)
			(vias allowed)
			(pads allowed)
			(copperpour not_allowed)
			(footprints allowed)
		)
		(placement
			(enabled no)
			(sheetname "")
		)
		(fill yes
			(thermal_gap 0.5)
			(thermal_bridge_width 0.5)
			(island_removal_mode 0)
		)
		(polygon
			(pts
				(arc
					(start 84.836 -231.524302)
					(mid 84.20608 -231.524302)
					(end 84.836 -231.524302)
				)
			)
		)
	)
	(zone
		(layers "B.Cu" "In13.Cu" "In15.Cu")
		(hatch none 0.5)
		(connect_pads
			(clearance 0)
		)
		(min_thickness 0.25)
		(keepout
			(tracks not_allowed)
			(vias allowed)
			(pads allowed)
			(copperpour not_allowed)
			(footprints allowed)
		)
		(placement
			(enabled no)
			(sheetname "")
		)
		(fill yes
			(thermal_gap 0.5)
			(thermal_bridge_width 0.5)
			(island_removal_mode 0)
		)
		(polygon
			(pts
				(arc
					(start 373.189754 -246.104156)
					(mid 372.559834 -246.104156)
					(end 373.189754 -246.104156)
				)
			)
		)
	)
	(zone
		(layers "B.Cu" "In13.Cu" "In15.Cu")
		(hatch none 0.5)
		(connect_pads
			(clearance 0)
		)
		(min_thickness 0.25)
		(keepout
			(tracks not_allowed)
			(vias allowed)
			(pads allowed)
			(copperpour not_allowed)
			(footprints allowed)
		)
		(placement
			(enabled no)
			(sheetname "")
		)
		(fill yes
			(thermal_gap 0.5)
			(thermal_bridge_width 0.5)
			(island_removal_mode 0)
		)
		(polygon
			(pts
				(arc
					(start 332.776068 -254.204216)
					(mid 332.146148 -254.204216)
					(end 332.776068 -254.204216)
				)
			)
		)
	)
	(zone
		(layers "B.Cu" "In13.Cu" "In15.Cu")
		(hatch none 0.5)
		(connect_pads
			(clearance 0)
		)
		(min_thickness 0.25)
		(keepout
			(tracks not_allowed)
			(vias allowed)
			(pads allowed)
			(copperpour not_allowed)
			(footprints allowed)
		)
		(placement
			(enabled no)
			(sheetname "")
		)
		(fill yes
			(thermal_gap 0.5)
			(thermal_bridge_width 0.5)
			(island_removal_mode 0)
		)
		(polygon
			(pts
				(arc
					(start 202.481942 -316.33541)
					(mid 201.813922 -316.33541)
					(end 202.481942 -316.33541)
				)
			)
		)
	)
	(zone
		(layers "B.Cu" "In13.Cu" "In15.Cu")
		(hatch none 0.5)
		(connect_pads
			(clearance 0)
		)
		(min_thickness 0.25)
		(keepout
			(tracks not_allowed)
			(vias allowed)
			(pads allowed)
			(copperpour not_allowed)
			(footprints allowed)
		)
		(placement
			(enabled no)
			(sheetname "")
		)
		(fill yes
			(thermal_gap 0.5)
			(thermal_bridge_width 0.5)
			(island_removal_mode 0)
		)
		(polygon
			(pts
				(arc
					(start 454.522078 -301.885096)
					(mid 453.854058 -301.885096)
					(end 454.522078 -301.885096)
				)
			)
		)
	)
	(zone
		(layers "B.Cu" "In13.Cu" "In15.Cu")
		(hatch none 0.5)
		(connect_pads
			(clearance 0)
		)
		(min_thickness 0.25)
		(keepout
			(tracks not_allowed)
			(vias allowed)
			(pads allowed)
			(copperpour not_allowed)
			(footprints allowed)
		)
		(placement
			(enabled no)
			(sheetname "")
		)
		(fill yes
			(thermal_gap 0.5)
			(thermal_bridge_width 0.5)
			(island_removal_mode 0)
		)
		(polygon
			(pts
				(arc
					(start 84.666074 -287.046162)
					(mid 84.036154 -287.046162)
					(end 84.666074 -287.046162)
				)
			)
		)
	)
	(zone
		(layers "B.Cu" "In13.Cu" "In15.Cu")
		(hatch none 0.5)
		(connect_pads
			(clearance 0)
		)
		(min_thickness 0.25)
		(keepout
			(tracks not_allowed)
			(vias allowed)
			(pads allowed)
			(copperpour not_allowed)
			(footprints allowed)
		)
		(placement
			(enabled no)
			(sheetname "")
		)
		(fill yes
			(thermal_gap 0.5)
			(thermal_bridge_width 0.5)
			(island_removal_mode 0)
		)
		(polygon
			(pts
				(arc
					(start 202.481942 -238.985298)
					(mid 201.813922 -238.985298)
					(end 202.481942 -238.985298)
				)
			)
		)
	)
	(zone
		(layers "B.Cu" "In13.Cu" "In15.Cu")
		(hatch none 0.5)
		(connect_pads
			(clearance 0)
		)
		(min_thickness 0.25)
		(keepout
			(tracks not_allowed)
			(vias allowed)
			(pads allowed)
			(copperpour not_allowed)
			(footprints allowed)
		)
		(placement
			(enabled no)
			(sheetname "")
		)
		(fill yes
			(thermal_gap 0.5)
			(thermal_bridge_width 0.5)
			(island_removal_mode 0)
		)
		(polygon
			(pts
				(arc
					(start 332.606142 -274.086066)
					(mid 331.976222 -274.086066)
					(end 332.606142 -274.086066)
				)
			)
		)
	)
	(zone
		(layers "B.Cu" "In13.Cu" "In15.Cu")
		(hatch none 0.5)
		(connect_pads
			(clearance 0)
		)
		(min_thickness 0.25)
		(keepout
			(tracks not_allowed)
			(vias allowed)
			(pads allowed)
			(copperpour not_allowed)
			(footprints allowed)
		)
		(placement
			(enabled no)
			(sheetname "")
		)
		(fill yes
			(thermal_gap 0.5)
			(thermal_bridge_width 0.5)
			(island_removal_mode 0)
		)
		(polygon
			(pts
				(arc
					(start 86.545928 -278.946356)
					(mid 85.916008 -278.946356)
					(end 86.545928 -278.946356)
				)
			)
		)
	)
	(zone
		(layers "B.Cu" "In13.Cu" "In15.Cu")
		(hatch none 0.5)
		(connect_pads
			(clearance 0)
		)
		(min_thickness 0.25)
		(keepout
			(tracks not_allowed)
			(vias allowed)
			(pads allowed)
			(copperpour not_allowed)
			(footprints allowed)
		)
		(placement
			(enabled no)
			(sheetname "")
		)
		(fill yes
			(thermal_gap 0.5)
			(thermal_bridge_width 0.5)
			(island_removal_mode 0)
		)
		(polygon
			(pts
				(arc
					(start 450.42201 -289.985196)
					(mid 449.75399 -289.985196)
					(end 450.42201 -289.985196)
				)
			)
		)
	)
	(zone
		(layers "B.Cu" "In13.Cu" "In15.Cu")
		(hatch none 0.5)
		(connect_pads
			(clearance 0)
		)
		(min_thickness 0.25)
		(keepout
			(tracks not_allowed)
			(vias allowed)
			(pads allowed)
			(copperpour not_allowed)
			(footprints allowed)
		)
		(placement
			(enabled no)
			(sheetname "")
		)
		(fill yes
			(thermal_gap 0.5)
			(thermal_bridge_width 0.5)
			(island_removal_mode 0)
		)
		(polygon
			(pts
				(arc
					(start 365.66983 -244.484144)
					(mid 365.03991 -244.484144)
					(end 365.66983 -244.484144)
				)
			)
		)
	)
	(zone
		(layers "B.Cu" "In13.Cu" "In15.Cu")
		(hatch none 0.5)
		(connect_pads
			(clearance 0)
		)
		(min_thickness 0.25)
		(keepout
			(tracks not_allowed)
			(vias allowed)
			(pads allowed)
			(copperpour not_allowed)
			(footprints allowed)
		)
		(placement
			(enabled no)
			(sheetname "")
		)
		(fill yes
			(thermal_gap 0.5)
			(thermal_bridge_width 0.5)
			(island_removal_mode 0)
		)
		(polygon
			(pts
				(arc
					(start 269.982188 -201.585068)
					(mid 269.314168 -201.585068)
					(end 269.982188 -201.585068)
				)
			)
		)
	)
	(zone
		(layers "B.Cu" "In13.Cu" "In15.Cu")
		(hatch none 0.5)
		(connect_pads
			(clearance 0)
		)
		(min_thickness 0.25)
		(keepout
			(tracks not_allowed)
			(vias allowed)
			(pads allowed)
			(copperpour not_allowed)
			(footprints allowed)
		)
		(placement
			(enabled no)
			(sheetname "")
		)
		(fill yes
			(thermal_gap 0.5)
			(thermal_bridge_width 0.5)
			(island_removal_mode 0)
		)
		(polygon
			(pts
				(arc
					(start 333.716122 -244.484144)
					(mid 333.086202 -244.484144)
					(end 333.716122 -244.484144)
				)
			)
		)
	)
	(zone
		(layers "B.Cu" "In13.Cu" "In15.Cu")
		(hatch none 0.5)
		(connect_pads
			(clearance 0)
		)
		(min_thickness 0.25)
		(keepout
			(tracks not_allowed)
			(vias allowed)
			(pads allowed)
			(copperpour not_allowed)
			(footprints allowed)
		)
		(placement
			(enabled no)
			(sheetname "")
		)
		(fill yes
			(thermal_gap 0.5)
			(thermal_bridge_width 0.5)
			(island_removal_mode 0)
		)
		(polygon
			(pts
				(arc
					(start 388.059676 -293.525956)
					(mid 387.429756 -293.525956)
					(end 388.059676 -293.525956)
				)
			)
		)
	)
	(zone
		(layers "B.Cu" "In13.Cu" "In15.Cu")
		(hatch none 0.5)
		(connect_pads
			(clearance 0)
		)
		(min_thickness 0.25)
		(keepout
			(tracks not_allowed)
			(vias allowed)
			(pads allowed)
			(copperpour not_allowed)
			(footprints allowed)
		)
		(placement
			(enabled no)
			(sheetname "")
		)
		(fill yes
			(thermal_gap 0.5)
			(thermal_bridge_width 0.5)
			(island_removal_mode 0)
		)
		(polygon
			(pts
				(arc
					(start 333.076042 -287.856168)
					(mid 332.446122 -287.856168)
					(end 333.076042 -287.856168)
				)
			)
		)
	)
	(zone
		(layers "B.Cu" "In13.Cu" "In15.Cu")
		(hatch none 0.5)
		(connect_pads
			(clearance 0)
		)
		(min_thickness 0.25)
		(keepout
			(tracks not_allowed)
			(vias allowed)
			(pads allowed)
			(copperpour not_allowed)
			(footprints allowed)
		)
		(placement
			(enabled no)
			(sheetname "")
		)
		(fill yes
			(thermal_gap 0.5)
			(thermal_bridge_width 0.5)
			(island_removal_mode 0)
		)
		(polygon
			(pts
				(arc
					(start 386.179822 -278.946102)
					(mid 385.549902 -278.946102)
					(end 386.179822 -278.946102)
				)
			)
		)
	)
	(zone
		(layers "B.Cu" "In13.Cu" "In15.Cu")
		(hatch none 0.5)
		(connect_pads
			(clearance 0)
		)
		(min_thickness 0.25)
		(keepout
			(tracks not_allowed)
			(vias allowed)
			(pads allowed)
			(copperpour not_allowed)
			(footprints allowed)
		)
		(placement
			(enabled no)
			(sheetname "")
		)
		(fill yes
			(thermal_gap 0.5)
			(thermal_bridge_width 0.5)
			(island_removal_mode 0)
		)
		(polygon
			(pts
				(arc
					(start 116.418106 -373.96293)
					(mid 115.750086 -373.96293)
					(end 116.418106 -373.96293)
				)
			)
		)
	)
	(zone
		(layers "B.Cu" "In13.Cu" "In15.Cu")
		(hatch none 0.5)
		(connect_pads
			(clearance 0)
		)
		(min_thickness 0.25)
		(keepout
			(tracks not_allowed)
			(vias allowed)
			(pads allowed)
			(copperpour not_allowed)
			(footprints allowed)
		)
		(placement
			(enabled no)
			(sheetname "")
		)
		(fill yes
			(thermal_gap 0.5)
			(thermal_bridge_width 0.5)
			(island_removal_mode 0)
		)
		(polygon
			(pts
				(arc
					(start 17.942052 -265.335258)
					(mid 17.274032 -265.335258)
					(end 17.942052 -265.335258)
				)
			)
		)
	)
	(zone
		(layers "B.Cu" "In13.Cu" "In15.Cu")
		(hatch none 0.5)
		(connect_pads
			(clearance 0)
		)
		(min_thickness 0.25)
		(keepout
			(tracks not_allowed)
			(vias allowed)
			(pads allowed)
			(copperpour not_allowed)
			(footprints allowed)
		)
		(placement
			(enabled no)
			(sheetname "")
		)
		(fill yes
			(thermal_gap 0.5)
			(thermal_bridge_width 0.5)
			(island_removal_mode 0)
		)
		(polygon
			(pts
				(arc
					(start 96.634046 -389.467344)
					(mid 96.004126 -389.467344)
					(end 96.634046 -389.467344)
				)
			)
		)
	)
	(zone
		(layers "B.Cu" "In13.Cu" "In15.Cu")
		(hatch none 0.5)
		(connect_pads
			(clearance 0)
		)
		(min_thickness 0.25)
		(keepout
			(tracks not_allowed)
			(vias allowed)
			(pads allowed)
			(copperpour not_allowed)
			(footprints allowed)
		)
		(placement
			(enabled no)
			(sheetname "")
		)
		(fill yes
			(thermal_gap 0.5)
			(thermal_bridge_width 0.5)
			(island_removal_mode 0)
		)
		(polygon
			(pts
				(arc
					(start 332.606142 -283.806138)
					(mid 331.976222 -283.806138)
					(end 332.606142 -283.806138)
				)
			)
		)
	)
	(zone
		(layers "B.Cu" "In13.Cu" "In15.Cu")
		(hatch none 0.5)
		(connect_pads
			(clearance 0)
		)
		(min_thickness 0.25)
		(keepout
			(tracks not_allowed)
			(vias allowed)
			(pads allowed)
			(copperpour not_allowed)
			(footprints allowed)
		)
		(placement
			(enabled no)
			(sheetname "")
		)
		(fill yes
			(thermal_gap 0.5)
			(thermal_bridge_width 0.5)
			(island_removal_mode 0)
		)
		(polygon
			(pts
				(arc
					(start 454.522078 -267.885164)
					(mid 453.854058 -267.885164)
					(end 454.522078 -267.885164)
				)
			)
		)
	)
	(zone
		(layers "B.Cu" "In13.Cu" "In15.Cu")
		(hatch none 0.5)
		(connect_pads
			(clearance 0)
		)
		(min_thickness 0.25)
		(keepout
			(tracks not_allowed)
			(vias allowed)
			(pads allowed)
			(copperpour not_allowed)
			(footprints allowed)
		)
		(placement
			(enabled no)
			(sheetname "")
		)
		(fill yes
			(thermal_gap 0.5)
			(thermal_bridge_width 0.5)
			(island_removal_mode 0)
		)
		(polygon
			(pts
				(arc
					(start 333.716122 -252.584204)
					(mid 333.086202 -252.584204)
					(end 333.716122 -252.584204)
				)
			)
		)
	)
	(zone
		(layers "B.Cu" "In13.Cu" "In15.Cu")
		(hatch none 0.5)
		(connect_pads
			(clearance 0)
		)
		(min_thickness 0.25)
		(keepout
			(tracks not_allowed)
			(vias allowed)
			(pads allowed)
			(copperpour not_allowed)
			(footprints allowed)
		)
		(placement
			(enabled no)
			(sheetname "")
		)
		(fill yes
			(thermal_gap 0.5)
			(thermal_bridge_width 0.5)
			(island_removal_mode 0)
		)
		(polygon
			(pts
				(arc
					(start 332.606142 -269.22603)
					(mid 331.976222 -269.22603)
					(end 332.606142 -269.22603)
				)
			)
		)
	)
	(zone
		(layers "B.Cu" "In13.Cu" "In15.Cu")
		(hatch none 0.5)
		(connect_pads
			(clearance 0)
		)
		(min_thickness 0.25)
		(keepout
			(tracks not_allowed)
			(vias allowed)
			(pads allowed)
			(copperpour not_allowed)
			(footprints allowed)
		)
		(placement
			(enabled no)
			(sheetname "")
		)
		(fill yes
			(thermal_gap 0.5)
			(thermal_bridge_width 0.5)
			(island_removal_mode 0)
		)
		(polygon
			(pts
				(arc
					(start 394.711682 -385.338828)
					(mid 394.043662 -385.338828)
					(end 394.711682 -385.338828)
				)
			)
		)
	)
	(zone
		(layers "B.Cu" "In13.Cu" "In15.Cu")
		(hatch none 0.5)
		(connect_pads
			(clearance 0)
		)
		(min_thickness 0.25)
		(keepout
			(tracks not_allowed)
			(vias allowed)
			(pads allowed)
			(copperpour not_allowed)
			(footprints allowed)
		)
		(placement
			(enabled no)
			(sheetname "")
		)
		(fill yes
			(thermal_gap 0.5)
			(thermal_bridge_width 0.5)
			(island_removal_mode 0)
		)
		(polygon
			(pts
				(arc
					(start 17.942052 -230.485442)
					(mid 17.274032 -230.485442)
					(end 17.942052 -230.485442)
				)
			)
		)
	)
	(zone
		(layers "B.Cu" "In13.Cu" "In15.Cu")
		(hatch none 0.5)
		(connect_pads
			(clearance 0)
		)
		(min_thickness 0.25)
		(keepout
			(tracks not_allowed)
			(vias allowed)
			(pads allowed)
			(copperpour not_allowed)
			(footprints allowed)
		)
		(placement
			(enabled no)
			(sheetname "")
		)
		(fill yes
			(thermal_gap 0.5)
			(thermal_bridge_width 0.5)
			(island_removal_mode 0)
		)
		(polygon
			(pts
				(arc
					(start 354.696014 -279.756108)
					(mid 354.066094 -279.756108)
					(end 354.696014 -279.756108)
				)
			)
		)
	)
	(zone
		(layers "B.Cu" "In13.Cu" "In15.Cu")
		(hatch none 0.5)
		(connect_pads
			(clearance 0)
		)
		(min_thickness 0.25)
		(keepout
			(tracks not_allowed)
			(vias allowed)
			(pads allowed)
			(copperpour not_allowed)
			(footprints allowed)
		)
		(placement
			(enabled no)
			(sheetname "")
		)
		(fill yes
			(thermal_gap 0.5)
			(thermal_bridge_width 0.5)
			(island_removal_mode 0)
		)
		(polygon
			(pts
				(arc
					(start 138.40968 -254.20447)
					(mid 137.77976 -254.20447)
					(end 138.40968 -254.20447)
				)
			)
		)
	)
	(zone
		(layers "B.Cu" "In13.Cu" "In15.Cu")
		(hatch none 0.5)
		(connect_pads
			(clearance 0)
		)
		(min_thickness 0.25)
		(keepout
			(tracks not_allowed)
			(vias allowed)
			(pads allowed)
			(copperpour not_allowed)
			(footprints allowed)
		)
		(placement
			(enabled no)
			(sheetname "")
		)
		(fill yes
			(thermal_gap 0.5)
			(thermal_bridge_width 0.5)
			(island_removal_mode 0)
		)
		(polygon
			(pts
				(arc
					(start 454.522078 -197.33514)
					(mid 453.854058 -197.33514)
					(end 454.522078 -197.33514)
				)
			)
		)
	)
	(zone
		(layers "B.Cu" "In13.Cu" "In15.Cu")
		(hatch none 0.5)
		(connect_pads
			(clearance 0)
		)
		(min_thickness 0.25)
		(keepout
			(tracks not_allowed)
			(vias allowed)
			(pads allowed)
			(copperpour not_allowed)
			(footprints allowed)
		)
		(placement
			(enabled no)
			(sheetname "")
		)
		(fill yes
			(thermal_gap 0.5)
			(thermal_bridge_width 0.5)
			(island_removal_mode 0)
		)
		(polygon
			(pts
				(arc
					(start 137.93978 -229.094538)
					(mid 137.30986 -229.094538)
					(end 137.93978 -229.094538)
				)
			)
		)
	)
	(zone
		(layers "B.Cu" "In13.Cu" "In15.Cu")
		(hatch none 0.5)
		(connect_pads
			(clearance 0)
		)
		(min_thickness 0.25)
		(keepout
			(tracks not_allowed)
			(vias allowed)
			(pads allowed)
			(copperpour not_allowed)
			(footprints allowed)
		)
		(placement
			(enabled no)
			(sheetname "")
		)
		(fill yes
			(thermal_gap 0.5)
			(thermal_bridge_width 0.5)
			(island_removal_mode 0)
		)
		(polygon
			(pts
				(arc
					(start 206.58201 -273.835368)
					(mid 205.91399 -273.835368)
					(end 206.58201 -273.835368)
				)
			)
		)
	)
	(zone
		(layers "B.Cu" "In13.Cu" "In15.Cu")
		(hatch none 0.5)
		(connect_pads
			(clearance 0)
		)
		(min_thickness 0.25)
		(keepout
			(tracks not_allowed)
			(vias allowed)
			(pads allowed)
			(copperpour not_allowed)
			(footprints allowed)
		)
		(placement
			(enabled no)
			(sheetname "")
		)
		(fill yes
			(thermal_gap 0.5)
			(thermal_bridge_width 0.5)
			(island_removal_mode 0)
		)
		(polygon
			(pts
				(arc
					(start 86.545928 -264.366248)
					(mid 85.916008 -264.366248)
					(end 86.545928 -264.366248)
				)
			)
		)
	)
	(zone
		(layers "B.Cu" "In13.Cu" "In15.Cu")
		(hatch none 0.5)
		(connect_pads
			(clearance 0)
		)
		(min_thickness 0.25)
		(keepout
			(tracks not_allowed)
			(vias allowed)
			(pads allowed)
			(copperpour not_allowed)
			(footprints allowed)
		)
		(placement
			(enabled no)
			(sheetname "")
		)
		(fill yes
			(thermal_gap 0.5)
			(thermal_bridge_width 0.5)
			(island_removal_mode 0)
		)
		(polygon
			(pts
				(arc
					(start 206.58201 -252.58522)
					(mid 205.91399 -252.58522)
					(end 206.58201 -252.58522)
				)
			)
		)
	)
	(zone
		(layers "B.Cu" "In13.Cu" "In15.Cu")
		(hatch none 0.5)
		(connect_pads
			(clearance 0)
		)
		(min_thickness 0.25)
		(keepout
			(tracks not_allowed)
			(vias allowed)
			(pads allowed)
			(copperpour not_allowed)
			(footprints allowed)
		)
		(placement
			(enabled no)
			(sheetname "")
		)
		(fill yes
			(thermal_gap 0.5)
			(thermal_bridge_width 0.5)
			(island_removal_mode 0)
		)
		(polygon
			(pts
				(arc
					(start 269.982188 -240.685066)
					(mid 269.314168 -240.685066)
					(end 269.982188 -240.685066)
				)
			)
		)
	)
	(zone
		(layers "B.Cu" "In13.Cu" "In15.Cu")
		(hatch none 0.5)
		(connect_pads
			(clearance 0)
		)
		(min_thickness 0.25)
		(keepout
			(tracks not_allowed)
			(vias allowed)
			(pads allowed)
			(copperpour not_allowed)
			(footprints allowed)
		)
		(placement
			(enabled no)
			(sheetname "")
		)
		(fill yes
			(thermal_gap 0.5)
			(thermal_bridge_width 0.5)
			(island_removal_mode 0)
		)
		(polygon
			(pts
				(arc
					(start 138.709654 -261.93623)
					(mid 138.079734 -261.93623)
					(end 138.709654 -261.93623)
				)
			)
		)
	)
	(zone
		(layers "B.Cu" "In13.Cu" "In15.Cu")
		(hatch none 0.5)
		(connect_pads
			(clearance 0)
		)
		(min_thickness 0.25)
		(keepout
			(tracks not_allowed)
			(vias allowed)
			(pads allowed)
			(copperpour not_allowed)
			(footprints allowed)
		)
		(placement
			(enabled no)
			(sheetname "")
		)
		(fill yes
			(thermal_gap 0.5)
			(thermal_bridge_width 0.5)
			(island_removal_mode 0)
		)
		(polygon
			(pts
				(arc
					(start 389.607552 -420.952168)
					(mid 388.939532 -420.952168)
					(end 389.607552 -420.952168)
				)
			)
		)
	)
	(zone
		(layers "B.Cu" "In13.Cu" "In15.Cu")
		(hatch none 0.5)
		(connect_pads
			(clearance 0)
		)
		(min_thickness 0.25)
		(keepout
			(tracks not_allowed)
			(vias allowed)
			(pads allowed)
			(copperpour not_allowed)
			(footprints allowed)
		)
		(placement
			(enabled no)
			(sheetname "")
		)
		(fill yes
			(thermal_gap 0.5)
			(thermal_bridge_width 0.5)
			(island_removal_mode 0)
		)
		(polygon
			(pts
				(arc
					(start 202.481942 -314.635388)
					(mid 201.813922 -314.635388)
					(end 202.481942 -314.635388)
				)
			)
		)
	)
	(zone
		(layers "B.Cu" "In13.Cu" "In15.Cu")
		(hatch none 0.5)
		(connect_pads
			(clearance 0)
		)
		(min_thickness 0.25)
		(keepout
			(tracks not_allowed)
			(vias allowed)
			(pads allowed)
			(copperpour not_allowed)
			(footprints allowed)
		)
		(placement
			(enabled no)
			(sheetname "")
		)
		(fill yes
			(thermal_gap 0.5)
			(thermal_bridge_width 0.5)
			(island_removal_mode 0)
		)
		(polygon
			(pts
				(arc
					(start 357.986076 -278.946102)
					(mid 357.356156 -278.946102)
					(end 357.986076 -278.946102)
				)
			)
		)
	)
	(zone
		(layers "B.Cu" "In13.Cu" "In15.Cu")
		(hatch none 0.5)
		(connect_pads
			(clearance 0)
		)
		(min_thickness 0.25)
		(keepout
			(tracks not_allowed)
			(vias allowed)
			(pads allowed)
			(copperpour not_allowed)
			(footprints allowed)
		)
		(placement
			(enabled no)
			(sheetname "")
		)
		(fill yes
			(thermal_gap 0.5)
			(thermal_bridge_width 0.5)
			(island_removal_mode 0)
		)
		(polygon
			(pts
				(arc
					(start 450.42201 -295.085008)
					(mid 449.75399 -295.085008)
					(end 450.42201 -295.085008)
				)
			)
		)
	)
	(zone
		(layers "B.Cu" "In13.Cu" "In15.Cu")
		(hatch none 0.5)
		(connect_pads
			(clearance 0)
		)
		(min_thickness 0.25)
		(keepout
			(tracks not_allowed)
			(vias allowed)
			(pads allowed)
			(copperpour not_allowed)
			(footprints allowed)
		)
		(placement
			(enabled no)
			(sheetname "")
		)
		(fill yes
			(thermal_gap 0.5)
			(thermal_bridge_width 0.5)
			(island_removal_mode 0)
		)
		(polygon
			(pts
				(arc
					(start 84.666074 -293.52621)
					(mid 84.036154 -293.52621)
					(end 84.666074 -293.52621)
				)
			)
		)
	)
	(zone
		(layers "B.Cu" "In13.Cu" "In15.Cu")
		(hatch none 0.5)
		(connect_pads
			(clearance 0)
		)
		(min_thickness 0.25)
		(keepout
			(tracks not_allowed)
			(vias allowed)
			(pads allowed)
			(copperpour not_allowed)
			(footprints allowed)
		)
		(placement
			(enabled no)
			(sheetname "")
		)
		(fill yes
			(thermal_gap 0.5)
			(thermal_bridge_width 0.5)
			(island_removal_mode 0)
		)
		(polygon
			(pts
				(arc
					(start 202.481942 -280.635202)
					(mid 201.813922 -280.635202)
					(end 202.481942 -280.635202)
				)
			)
		)
	)
	(zone
		(layers "B.Cu" "In13.Cu" "In15.Cu")
		(hatch none 0.5)
		(connect_pads
			(clearance 0)
		)
		(min_thickness 0.25)
		(keepout
			(tracks not_allowed)
			(vias allowed)
			(pads allowed)
			(copperpour not_allowed)
			(footprints allowed)
		)
		(placement
			(enabled no)
			(sheetname "")
		)
		(fill yes
			(thermal_gap 0.5)
			(thermal_bridge_width 0.5)
			(island_removal_mode 0)
		)
		(polygon
			(pts
				(arc
					(start 140.119608 -277.326344)
					(mid 139.489688 -277.326344)
					(end 140.119608 -277.326344)
				)
			)
		)
	)
	(zone
		(layers "B.Cu" "In13.Cu" "In15.Cu")
		(hatch none 0.5)
		(connect_pads
			(clearance 0)
		)
		(min_thickness 0.25)
		(keepout
			(tracks not_allowed)
			(vias allowed)
			(pads allowed)
			(copperpour not_allowed)
			(footprints allowed)
		)
		(placement
			(enabled no)
			(sheetname "")
		)
		(fill yes
			(thermal_gap 0.5)
			(thermal_bridge_width 0.5)
			(island_removal_mode 0)
		)
		(polygon
			(pts
				(arc
					(start 386.649722 -289.475926)
					(mid 386.019802 -289.475926)
					(end 386.649722 -289.475926)
				)
			)
		)
	)
	(zone
		(layers "B.Cu" "In13.Cu" "In15.Cu")
		(hatch none 0.5)
		(connect_pads
			(clearance 0)
		)
		(min_thickness 0.25)
		(keepout
			(tracks not_allowed)
			(vias allowed)
			(pads allowed)
			(copperpour not_allowed)
			(footprints allowed)
		)
		(placement
			(enabled no)
			(sheetname "")
		)
		(fill yes
			(thermal_gap 0.5)
			(thermal_bridge_width 0.5)
			(island_removal_mode 0)
		)
		(polygon
			(pts
				(arc
					(start 53.39334 -19.13636)
					(mid 52.72532 -19.13636)
					(end 53.39334 -19.13636)
				)
			)
		)
	)
	(zone
		(layers "B.Cu" "In13.Cu" "In15.Cu")
		(hatch none 0.5)
		(connect_pads
			(clearance 0)
		)
		(min_thickness 0.25)
		(keepout
			(tracks not_allowed)
			(vias allowed)
			(pads allowed)
			(copperpour not_allowed)
			(footprints allowed)
		)
		(placement
			(enabled no)
			(sheetname "")
		)
		(fill yes
			(thermal_gap 0.5)
			(thermal_bridge_width 0.5)
			(island_removal_mode 0)
		)
		(polygon
			(pts
				(arc
					(start 370.369846 -246.104156)
					(mid 369.739926 -246.104156)
					(end 370.369846 -246.104156)
				)
			)
		)
	)
	(zone
		(layers "B.Cu" "In13.Cu" "In15.Cu")
		(hatch none 0.5)
		(connect_pads
			(clearance 0)
		)
		(min_thickness 0.25)
		(keepout
			(tracks not_allowed)
			(vias allowed)
			(pads allowed)
			(copperpour not_allowed)
			(footprints allowed)
		)
		(placement
			(enabled no)
			(sheetname "")
		)
		(fill yes
			(thermal_gap 0.5)
			(thermal_bridge_width 0.5)
			(island_removal_mode 0)
		)
		(polygon
			(pts
				(arc
					(start 269.982188 -295.085008)
					(mid 269.314168 -295.085008)
					(end 269.982188 -295.085008)
				)
			)
		)
	)
	(zone
		(layers "B.Cu" "In13.Cu" "In15.Cu")
		(hatch none 0.5)
		(connect_pads
			(clearance 0)
		)
		(min_thickness 0.25)
		(keepout
			(tracks not_allowed)
			(vias allowed)
			(pads allowed)
			(copperpour not_allowed)
			(footprints allowed)
		)
		(placement
			(enabled no)
			(sheetname "")
		)
		(fill yes
			(thermal_gap 0.5)
			(thermal_bridge_width 0.5)
			(island_removal_mode 0)
		)
		(polygon
			(pts
				(arc
					(start 382.136904 -429.689768)
					(mid 381.362712 -429.689768)
					(end 382.136904 -429.689768)
				)
			)
		)
	)
	(zone
		(layers "B.Cu" "In13.Cu" "In15.Cu")
		(hatch none 0.5)
		(connect_pads
			(clearance 0)
		)
		(min_thickness 0.25)
		(keepout
			(tracks not_allowed)
			(vias allowed)
			(pads allowed)
			(copperpour not_allowed)
			(footprints allowed)
		)
		(placement
			(enabled no)
			(sheetname "")
		)
		(fill yes
			(thermal_gap 0.5)
			(thermal_bridge_width 0.5)
			(island_removal_mode 0)
		)
		(polygon
			(pts
				(arc
					(start 138.40968 -234.764326)
					(mid 137.77976 -234.764326)
					(end 138.40968 -234.764326)
				)
			)
		)
	)
	(zone
		(layers "B.Cu" "In13.Cu" "In15.Cu")
		(hatch none 0.5)
		(connect_pads
			(clearance 0)
		)
		(min_thickness 0.25)
		(keepout
			(tracks not_allowed)
			(vias allowed)
			(pads allowed)
			(copperpour not_allowed)
			(footprints allowed)
		)
		(placement
			(enabled no)
			(sheetname "")
		)
		(fill yes
			(thermal_gap 0.5)
			(thermal_bridge_width 0.5)
			(island_removal_mode 0)
		)
		(polygon
			(pts
				(arc
					(start 385.879848 -237.19409)
					(mid 385.249928 -237.19409)
					(end 385.879848 -237.19409)
				)
			)
		)
	)
	(zone
		(layers "B.Cu" "In13.Cu" "In15.Cu")
		(hatch none 0.5)
		(connect_pads
			(clearance 0)
		)
		(min_thickness 0.25)
		(keepout
			(tracks not_allowed)
			(vias allowed)
			(pads allowed)
			(copperpour not_allowed)
			(footprints allowed)
		)
		(placement
			(enabled no)
			(sheetname "")
		)
		(fill yes
			(thermal_gap 0.5)
			(thermal_bridge_width 0.5)
			(island_removal_mode 0)
		)
		(polygon
			(pts
				(arc
					(start 370.66982 -278.136096)
					(mid 370.0399 -278.136096)
					(end 370.66982 -278.136096)
				)
			)
		)
	)
	(zone
		(layers "B.Cu" "In13.Cu" "In15.Cu")
		(hatch none 0.5)
		(connect_pads
			(clearance 0)
		)
		(min_thickness 0.25)
		(keepout
			(tracks not_allowed)
			(vias allowed)
			(pads allowed)
			(copperpour not_allowed)
			(footprints allowed)
		)
		(placement
			(enabled no)
			(sheetname "")
		)
		(fill yes
			(thermal_gap 0.5)
			(thermal_bridge_width 0.5)
			(island_removal_mode 0)
		)
		(polygon
			(pts
				(arc
					(start 114.739674 -278.946356)
					(mid 114.109754 -278.946356)
					(end 114.739674 -278.946356)
				)
			)
		)
	)
	(zone
		(layers "B.Cu" "In13.Cu" "In15.Cu")
		(hatch none 0.5)
		(connect_pads
			(clearance 0)
		)
		(min_thickness 0.25)
		(keepout
			(tracks not_allowed)
			(vias allowed)
			(pads allowed)
			(copperpour not_allowed)
			(footprints allowed)
		)
		(placement
			(enabled no)
			(sheetname "")
		)
		(fill yes
			(thermal_gap 0.5)
			(thermal_bridge_width 0.5)
			(island_removal_mode 0)
		)
		(polygon
			(pts
				(arc
					(start 454.522078 -294.235124)
					(mid 453.854058 -294.235124)
					(end 454.522078 -294.235124)
				)
			)
		)
	)
	(zone
		(layers "B.Cu" "In13.Cu" "In15.Cu")
		(hatch none 0.5)
		(connect_pads
			(clearance 0)
		)
		(min_thickness 0.25)
		(keepout
			(tracks not_allowed)
			(vias allowed)
			(pads allowed)
			(copperpour not_allowed)
			(footprints allowed)
		)
		(placement
			(enabled no)
			(sheetname "")
		)
		(fill yes
			(thermal_gap 0.5)
			(thermal_bridge_width 0.5)
			(island_removal_mode 0)
		)
		(polygon
			(pts
				(arc
					(start 139.819634 -232.334308)
					(mid 139.189714 -232.334308)
					(end 139.819634 -232.334308)
				)
			)
		)
	)
	(zone
		(layers "B.Cu" "In13.Cu" "In15.Cu")
		(hatch none 0.5)
		(connect_pads
			(clearance 0)
		)
		(min_thickness 0.25)
		(keepout
			(tracks not_allowed)
			(vias allowed)
			(pads allowed)
			(copperpour not_allowed)
			(footprints allowed)
		)
		(placement
			(enabled no)
			(sheetname "")
		)
		(fill yes
			(thermal_gap 0.5)
			(thermal_bridge_width 0.5)
			(island_removal_mode 0)
		)
		(polygon
			(pts
				(arc
					(start 265.88212 -286.585152)
					(mid 265.2141 -286.585152)
					(end 265.88212 -286.585152)
				)
			)
		)
	)
	(zone
		(layers "B.Cu" "In13.Cu" "In15.Cu")
		(hatch none 0.5)
		(connect_pads
			(clearance 0)
		)
		(min_thickness 0.25)
		(keepout
			(tracks not_allowed)
			(vias allowed)
			(pads allowed)
			(copperpour not_allowed)
			(footprints allowed)
		)
		(placement
			(enabled no)
			(sheetname "")
		)
		(fill yes
			(thermal_gap 0.5)
			(thermal_bridge_width 0.5)
			(island_removal_mode 0)
		)
		(polygon
			(pts
				(arc
					(start 30.701488 -19.13636)
					(mid 30.033468 -19.13636)
					(end 30.701488 -19.13636)
				)
			)
		)
	)
	(zone
		(layers "B.Cu" "In13.Cu" "In15.Cu")
		(hatch none 0.5)
		(connect_pads
			(clearance 0)
		)
		(min_thickness 0.25)
		(keepout
			(tracks not_allowed)
			(vias allowed)
			(pads allowed)
			(copperpour not_allowed)
			(footprints allowed)
		)
		(placement
			(enabled no)
			(sheetname "")
		)
		(fill yes
			(thermal_gap 0.5)
			(thermal_bridge_width 0.5)
			(island_removal_mode 0)
		)
		(polygon
			(pts
				(arc
					(start 387.289802 -252.584204)
					(mid 386.659882 -252.584204)
					(end 387.289802 -252.584204)
				)
			)
		)
	)
	(zone
		(layers "B.Cu" "In13.Cu" "In15.Cu")
		(hatch none 0.5)
		(connect_pads
			(clearance 0)
		)
		(min_thickness 0.25)
		(keepout
			(tracks not_allowed)
			(vias allowed)
			(pads allowed)
			(copperpour not_allowed)
			(footprints allowed)
		)
		(placement
			(enabled no)
			(sheetname "")
		)
		(fill yes
			(thermal_gap 0.5)
			(thermal_bridge_width 0.5)
			(island_removal_mode 0)
		)
		(polygon
			(pts
				(arc
					(start 269.982188 -306.135024)
					(mid 269.314168 -306.135024)
					(end 269.982188 -306.135024)
				)
			)
		)
	)
	(zone
		(layers "B.Cu" "In13.Cu" "In15.Cu")
		(hatch none 0.5)
		(connect_pads
			(clearance 0)
		)
		(min_thickness 0.25)
		(keepout
			(tracks not_allowed)
			(vias allowed)
			(pads allowed)
			(copperpour not_allowed)
			(footprints allowed)
		)
		(placement
			(enabled no)
			(sheetname "")
		)
		(fill yes
			(thermal_gap 0.5)
			(thermal_bridge_width 0.5)
			(island_removal_mode 0)
		)
		(polygon
			(pts
				(arc
					(start 332.606142 -262.745982)
					(mid 331.976222 -262.745982)
					(end 332.606142 -262.745982)
				)
			)
		)
	)
	(zone
		(layers "B.Cu" "In13.Cu" "In15.Cu")
		(hatch none 0.5)
		(connect_pads
			(clearance 0)
		)
		(min_thickness 0.25)
		(keepout
			(tracks not_allowed)
			(vias allowed)
			(pads allowed)
			(copperpour not_allowed)
			(footprints allowed)
		)
		(placement
			(enabled no)
			(sheetname "")
		)
		(fill yes
			(thermal_gap 0.5)
			(thermal_bridge_width 0.5)
			(island_removal_mode 0)
		)
		(polygon
			(pts
				(arc
					(start 347.17609 -276.516084)
					(mid 346.54617 -276.516084)
					(end 347.17609 -276.516084)
				)
			)
		)
	)
	(zone
		(layers "B.Cu" "In13.Cu" "In15.Cu")
		(hatch none 0.5)
		(connect_pads
			(clearance 0)
		)
		(min_thickness 0.25)
		(keepout
			(tracks not_allowed)
			(vias allowed)
			(pads allowed)
			(copperpour not_allowed)
			(footprints allowed)
		)
		(placement
			(enabled no)
			(sheetname "")
		)
		(fill yes
			(thermal_gap 0.5)
			(thermal_bridge_width 0.5)
			(island_removal_mode 0)
		)
		(polygon
			(pts
				(arc
					(start 128.136904 -430.689766)
					(mid 127.362712 -430.689766)
					(end 128.136904 -430.689766)
				)
			)
		)
	)
	(zone
		(layers "B.Cu" "In13.Cu" "In15.Cu")
		(hatch none 0.5)
		(connect_pads
			(clearance 0)
		)
		(min_thickness 0.25)
		(keepout
			(tracks not_allowed)
			(vias allowed)
			(pads allowed)
			(copperpour not_allowed)
			(footprints allowed)
		)
		(placement
			(enabled no)
			(sheetname "")
		)
		(fill yes
			(thermal_gap 0.5)
			(thermal_bridge_width 0.5)
			(island_removal_mode 0)
		)
		(polygon
			(pts
				(arc
					(start 346.876116 -236.384084)
					(mid 346.246196 -236.384084)
					(end 346.876116 -236.384084)
				)
			)
		)
	)
	(zone
		(layers "B.Cu" "In13.Cu" "In15.Cu")
		(hatch none 0.5)
		(connect_pads
			(clearance 0)
		)
		(min_thickness 0.25)
		(keepout
			(tracks not_allowed)
			(vias allowed)
			(pads allowed)
			(copperpour not_allowed)
			(footprints allowed)
		)
		(placement
			(enabled no)
			(sheetname "")
		)
		(fill yes
			(thermal_gap 0.5)
			(thermal_bridge_width 0.5)
			(island_removal_mode 0)
		)
		(polygon
			(pts
				(arc
					(start 450.42201 -295.935146)
					(mid 449.75399 -295.935146)
					(end 450.42201 -295.935146)
				)
			)
		)
	)
	(zone
		(layers "B.Cu" "In13.Cu" "In15.Cu")
		(hatch none 0.5)
		(connect_pads
			(clearance 0)
		)
		(min_thickness 0.25)
		(keepout
			(tracks not_allowed)
			(vias allowed)
			(pads allowed)
			(copperpour not_allowed)
			(footprints allowed)
		)
		(placement
			(enabled no)
			(sheetname "")
		)
		(fill yes
			(thermal_gap 0.5)
			(thermal_bridge_width 0.5)
			(island_removal_mode 0)
		)
		(polygon
			(pts
				(arc
					(start 22.04212 -315.485272)
					(mid 21.3741 -315.485272)
					(end 22.04212 -315.485272)
				)
			)
		)
	)
	(zone
		(layers "B.Cu" "In13.Cu" "In15.Cu")
		(hatch none 0.5)
		(connect_pads
			(clearance 0)
		)
		(min_thickness 0.25)
		(keepout
			(tracks not_allowed)
			(vias allowed)
			(pads allowed)
			(copperpour not_allowed)
			(footprints allowed)
		)
		(placement
			(enabled no)
			(sheetname "")
		)
		(fill yes
			(thermal_gap 0.5)
			(thermal_bridge_width 0.5)
			(island_removal_mode 0)
		)
		(polygon
			(pts
				(arc
					(start 269.982188 -276.38502)
					(mid 269.314168 -276.38502)
					(end 269.982188 -276.38502)
				)
			)
		)
	)
	(zone
		(layers "B.Cu" "In13.Cu" "In15.Cu")
		(hatch none 0.5)
		(connect_pads
			(clearance 0)
		)
		(min_thickness 0.25)
		(keepout
			(tracks not_allowed)
			(vias allowed)
			(pads allowed)
			(copperpour not_allowed)
			(footprints allowed)
		)
		(placement
			(enabled no)
			(sheetname "")
		)
		(fill yes
			(thermal_gap 0.5)
			(thermal_bridge_width 0.5)
			(island_removal_mode 0)
		)
		(polygon
			(pts
				(arc
					(start 89.034112 -385.31038)
					(mid 88.404192 -385.31038)
					(end 89.034112 -385.31038)
				)
			)
		)
	)
	(zone
		(layers "B.Cu" "In13.Cu" "In15.Cu")
		(hatch none 0.5)
		(connect_pads
			(clearance 0)
		)
		(min_thickness 0.25)
		(keepout
			(tracks not_allowed)
			(vias allowed)
			(pads allowed)
			(copperpour not_allowed)
			(footprints allowed)
		)
		(placement
			(enabled no)
			(sheetname "")
		)
		(fill yes
			(thermal_gap 0.5)
			(thermal_bridge_width 0.5)
			(island_removal_mode 0)
		)
		(polygon
			(pts
				(arc
					(start 450.42201 -238.985044)
					(mid 449.75399 -238.985044)
					(end 450.42201 -238.985044)
				)
			)
		)
	)
	(zone
		(layers "B.Cu" "In13.Cu" "In15.Cu")
		(hatch none 0.5)
		(connect_pads
			(clearance 0)
		)
		(min_thickness 0.25)
		(keepout
			(tracks not_allowed)
			(vias allowed)
			(pads allowed)
			(copperpour not_allowed)
			(footprints allowed)
		)
		(placement
			(enabled no)
			(sheetname "")
		)
		(fill yes
			(thermal_gap 0.5)
			(thermal_bridge_width 0.5)
			(island_removal_mode 0)
		)
		(polygon
			(pts
				(arc
					(start 388.059676 -267.606018)
					(mid 387.429756 -267.606018)
					(end 388.059676 -267.606018)
				)
			)
		)
	)
	(zone
		(layers "B.Cu" "In13.Cu" "In15.Cu")
		(hatch none 0.5)
		(connect_pads
			(clearance 0)
		)
		(min_thickness 0.25)
		(keepout
			(tracks not_allowed)
			(vias allowed)
			(pads allowed)
			(copperpour not_allowed)
			(footprints allowed)
		)
		(placement
			(enabled no)
			(sheetname "")
		)
		(fill yes
			(thermal_gap 0.5)
			(thermal_bridge_width 0.5)
			(island_removal_mode 0)
		)
		(polygon
			(pts
				(arc
					(start 332.306168 -237.19409)
					(mid 331.676248 -237.19409)
					(end 332.306168 -237.19409)
				)
			)
		)
	)
	(zone
		(layers "B.Cu" "In13.Cu" "In15.Cu")
		(hatch none 0.5)
		(connect_pads
			(clearance 0)
		)
		(min_thickness 0.25)
		(keepout
			(tracks not_allowed)
			(vias allowed)
			(pads allowed)
			(copperpour not_allowed)
			(footprints allowed)
		)
		(placement
			(enabled no)
			(sheetname "")
		)
		(fill yes
			(thermal_gap 0.5)
			(thermal_bridge_width 0.5)
			(island_removal_mode 0)
		)
		(polygon
			(pts
				(arc
					(start 385.879848 -235.574078)
					(mid 385.249928 -235.574078)
					(end 385.879848 -235.574078)
				)
			)
		)
	)
	(zone
		(layers "B.Cu" "In13.Cu" "In15.Cu")
		(hatch none 0.5)
		(connect_pads
			(clearance 0)
		)
		(min_thickness 0.25)
		(keepout
			(tracks not_allowed)
			(vias allowed)
			(pads allowed)
			(copperpour not_allowed)
			(footprints allowed)
		)
		(placement
			(enabled no)
			(sheetname "")
		)
		(fill yes
			(thermal_gap 0.5)
			(thermal_bridge_width 0.5)
			(island_removal_mode 0)
		)
		(polygon
			(pts
				(arc
					(start 269.982188 -228.785166)
					(mid 269.314168 -228.785166)
					(end 269.982188 -228.785166)
				)
			)
		)
	)
	(zone
		(layers "B.Cu" "In13.Cu" "In15.Cu")
		(hatch none 0.5)
		(connect_pads
			(clearance 0)
		)
		(min_thickness 0.25)
		(keepout
			(tracks not_allowed)
			(vias allowed)
			(pads allowed)
			(copperpour not_allowed)
			(footprints allowed)
		)
		(placement
			(enabled no)
			(sheetname "")
		)
		(fill yes
			(thermal_gap 0.5)
			(thermal_bridge_width 0.5)
			(island_removal_mode 0)
		)
		(polygon
			(pts
				(arc
					(start 140.119608 -262.746236)
					(mid 139.489688 -262.746236)
					(end 140.119608 -262.746236)
				)
			)
		)
	)
	(zone
		(layers "B.Cu" "In13.Cu" "In15.Cu")
		(hatch none 0.5)
		(connect_pads
			(clearance 0)
		)
		(min_thickness 0.25)
		(keepout
			(tracks not_allowed)
			(vias allowed)
			(pads allowed)
			(copperpour not_allowed)
			(footprints allowed)
		)
		(placement
			(enabled no)
			(sheetname "")
		)
		(fill yes
			(thermal_gap 0.5)
			(thermal_bridge_width 0.5)
			(island_removal_mode 0)
		)
		(polygon
			(pts
				(arc
					(start 342.633808 -393.69238)
					(mid 342.003888 -393.69238)
					(end 342.633808 -393.69238)
				)
			)
		)
	)
	(zone
		(layers "B.Cu" "In13.Cu" "In15.Cu")
		(hatch none 0.5)
		(connect_pads
			(clearance 0)
		)
		(min_thickness 0.25)
		(keepout
			(tracks not_allowed)
			(vias allowed)
			(pads allowed)
			(copperpour not_allowed)
			(footprints allowed)
		)
		(placement
			(enabled no)
			(sheetname "")
		)
		(fill yes
			(thermal_gap 0.5)
			(thermal_bridge_width 0.5)
			(island_removal_mode 0)
		)
		(polygon
			(pts
				(arc
					(start 206.58201 -208.38541)
					(mid 205.91399 -208.38541)
					(end 206.58201 -208.38541)
				)
			)
		)
	)
	(zone
		(layers "B.Cu" "In13.Cu" "In15.Cu")
		(hatch none 0.5)
		(connect_pads
			(clearance 0)
		)
		(min_thickness 0.25)
		(keepout
			(tracks not_allowed)
			(vias allowed)
			(pads allowed)
			(copperpour not_allowed)
			(footprints allowed)
		)
		(placement
			(enabled no)
			(sheetname "")
		)
		(fill yes
			(thermal_gap 0.5)
			(thermal_bridge_width 0.5)
			(island_removal_mode 0)
		)
		(polygon
			(pts
				(arc
					(start 25.113488 -19.13636)
					(mid 24.445468 -19.13636)
					(end 25.113488 -19.13636)
				)
			)
		)
	)
	(zone
		(layers "B.Cu" "In13.Cu" "In15.Cu")
		(hatch none 0.5)
		(connect_pads
			(clearance 0)
		)
		(min_thickness 0.25)
		(keepout
			(tracks not_allowed)
			(vias allowed)
			(pads allowed)
			(copperpour not_allowed)
			(footprints allowed)
		)
		(placement
			(enabled no)
			(sheetname "")
		)
		(fill yes
			(thermal_gap 0.5)
			(thermal_bridge_width 0.5)
			(island_removal_mode 0)
		)
		(polygon
			(pts
				(arc
					(start 454.522078 -303.585118)
					(mid 453.854058 -303.585118)
					(end 454.522078 -303.585118)
				)
			)
		)
	)
	(zone
		(layers "B.Cu" "In13.Cu" "In15.Cu")
		(hatch none 0.5)
		(connect_pads
			(clearance 0)
		)
		(min_thickness 0.25)
		(keepout
			(tracks not_allowed)
			(vias allowed)
			(pads allowed)
			(copperpour not_allowed)
			(footprints allowed)
		)
		(placement
			(enabled no)
			(sheetname "")
		)
		(fill yes
			(thermal_gap 0.5)
			(thermal_bridge_width 0.5)
			(island_removal_mode 0)
		)
		(polygon
			(pts
				(arc
					(start 265.88212 -313.784996)
					(mid 265.2141 -313.784996)
					(end 265.88212 -313.784996)
				)
			)
		)
	)
	(zone
		(layers "B.Cu" "In13.Cu" "In15.Cu")
		(hatch none 0.5)
		(connect_pads
			(clearance 0)
		)
		(min_thickness 0.25)
		(keepout
			(tracks not_allowed)
			(vias allowed)
			(pads allowed)
			(copperpour not_allowed)
			(footprints allowed)
		)
		(placement
			(enabled no)
			(sheetname "")
		)
		(fill yes
			(thermal_gap 0.5)
			(thermal_bridge_width 0.5)
			(island_removal_mode 0)
		)
		(polygon
			(pts
				(arc
					(start 116.934234 -24.155654)
					(mid 116.266214 -24.155654)
					(end 116.934234 -24.155654)
				)
			)
		)
	)
	(zone
		(layers "B.Cu" "In13.Cu" "In15.Cu")
		(hatch none 0.5)
		(connect_pads
			(clearance 0)
		)
		(min_thickness 0.25)
		(keepout
			(tracks not_allowed)
			(vias allowed)
			(pads allowed)
			(copperpour not_allowed)
			(footprints allowed)
		)
		(placement
			(enabled no)
			(sheetname "")
		)
		(fill yes
			(thermal_gap 0.5)
			(thermal_bridge_width 0.5)
			(island_removal_mode 0)
		)
		(polygon
			(pts
				(arc
					(start 22.04212 -279.785318)
					(mid 21.3741 -279.785318)
					(end 22.04212 -279.785318)
				)
			)
		)
	)
	(zone
		(layers "B.Cu" "In13.Cu" "In15.Cu")
		(hatch none 0.5)
		(connect_pads
			(clearance 0)
		)
		(min_thickness 0.25)
		(keepout
			(tracks not_allowed)
			(vias allowed)
			(pads allowed)
			(copperpour not_allowed)
			(footprints allowed)
		)
		(placement
			(enabled no)
			(sheetname "")
		)
		(fill yes
			(thermal_gap 0.5)
			(thermal_bridge_width 0.5)
			(island_removal_mode 0)
		)
		(polygon
			(pts
				(arc
					(start 119.90959 -278.13635)
					(mid 119.27967 -278.13635)
					(end 119.90959 -278.13635)
				)
			)
		)
	)
	(zone
		(layers "B.Cu" "In13.Cu" "In15.Cu")
		(hatch none 0.5)
		(connect_pads
			(clearance 0)
		)
		(min_thickness 0.25)
		(keepout
			(tracks not_allowed)
			(vias allowed)
			(pads allowed)
			(copperpour not_allowed)
			(footprints allowed)
		)
		(placement
			(enabled no)
			(sheetname "")
		)
		(fill yes
			(thermal_gap 0.5)
			(thermal_bridge_width 0.5)
			(island_removal_mode 0)
		)
		(polygon
			(pts
				(arc
					(start 17.942052 -201.585322)
					(mid 17.274032 -201.585322)
					(end 17.942052 -201.585322)
				)
			)
		)
	)
	(zone
		(layers "B.Cu" "In13.Cu" "In15.Cu")
		(hatch none 0.5)
		(connect_pads
			(clearance 0)
		)
		(min_thickness 0.25)
		(keepout
			(tracks not_allowed)
			(vias allowed)
			(pads allowed)
			(copperpour not_allowed)
			(footprints allowed)
		)
		(placement
			(enabled no)
			(sheetname "")
		)
		(fill yes
			(thermal_gap 0.5)
			(thermal_bridge_width 0.5)
			(island_removal_mode 0)
		)
		(polygon
			(pts
				(arc
					(start 337.03387 -394.385292)
					(mid 336.40395 -394.385292)
					(end 337.03387 -394.385292)
				)
			)
		)
	)
	(zone
		(layers "B.Cu" "In13.Cu" "In15.Cu")
		(hatch none 0.5)
		(connect_pads
			(clearance 0)
		)
		(min_thickness 0.25)
		(keepout
			(tracks not_allowed)
			(vias allowed)
			(pads allowed)
			(copperpour not_allowed)
			(footprints allowed)
		)
		(placement
			(enabled no)
			(sheetname "")
		)
		(fill yes
			(thermal_gap 0.5)
			(thermal_bridge_width 0.5)
			(island_removal_mode 0)
		)
		(polygon
			(pts
				(arc
					(start 140.56868 -28.499562)
					(mid 139.90066 -28.499562)
					(end 140.56868 -28.499562)
				)
			)
		)
	)
	(zone
		(layers "B.Cu" "In13.Cu" "In15.Cu")
		(hatch none 0.5)
		(connect_pads
			(clearance 0)
		)
		(min_thickness 0.25)
		(keepout
			(tracks not_allowed)
			(vias allowed)
			(pads allowed)
			(copperpour not_allowed)
			(footprints allowed)
		)
		(placement
			(enabled no)
			(sheetname "")
		)
		(fill yes
			(thermal_gap 0.5)
			(thermal_bridge_width 0.5)
			(island_removal_mode 0)
		)
		(polygon
			(pts
				(arc
					(start 351.876106 -278.136096)
					(mid 351.246186 -278.136096)
					(end 351.876106 -278.136096)
				)
			)
		)
	)
	(zone
		(layers "B.Cu" "In13.Cu" "In15.Cu")
		(hatch none 0.5)
		(connect_pads
			(clearance 0)
		)
		(min_thickness 0.25)
		(keepout
			(tracks not_allowed)
			(vias allowed)
			(pads allowed)
			(copperpour not_allowed)
			(footprints allowed)
		)
		(placement
			(enabled no)
			(sheetname "")
		)
		(fill yes
			(thermal_gap 0.5)
			(thermal_bridge_width 0.5)
			(island_removal_mode 0)
		)
		(polygon
			(pts
				(arc
					(start 86.545928 -290.286186)
					(mid 85.916008 -290.286186)
					(end 86.545928 -290.286186)
				)
			)
		)
	)
	(zone
		(layers "B.Cu" "In13.Cu" "In15.Cu")
		(hatch none 0.5)
		(connect_pads
			(clearance 0)
		)
		(min_thickness 0.25)
		(keepout
			(tracks not_allowed)
			(vias allowed)
			(pads allowed)
			(copperpour not_allowed)
			(footprints allowed)
		)
		(placement
			(enabled no)
			(sheetname "")
		)
		(fill yes
			(thermal_gap 0.5)
			(thermal_bridge_width 0.5)
			(island_removal_mode 0)
		)
		(polygon
			(pts
				(arc
					(start 65.036954 -431.889916)
					(mid 64.262762 -431.889916)
					(end 65.036954 -431.889916)
				)
			)
		)
	)
	(zone
		(layers "B.Cu" "In13.Cu" "In15.Cu")
		(hatch none 0.5)
		(connect_pads
			(clearance 0)
		)
		(min_thickness 0.25)
		(keepout
			(tracks not_allowed)
			(vias allowed)
			(pads allowed)
			(copperpour not_allowed)
			(footprints allowed)
		)
		(placement
			(enabled no)
			(sheetname "")
		)
		(fill yes
			(thermal_gap 0.5)
			(thermal_bridge_width 0.5)
			(island_removal_mode 0)
		)
		(polygon
			(pts
				(arc
					(start 139.819634 -233.95432)
					(mid 139.189714 -233.95432)
					(end 139.819634 -233.95432)
				)
			)
		)
	)
	(zone
		(layers "B.Cu" "In13.Cu" "In15.Cu")
		(hatch none 0.5)
		(connect_pads
			(clearance 0)
		)
		(min_thickness 0.25)
		(keepout
			(tracks not_allowed)
			(vias allowed)
			(pads allowed)
			(copperpour not_allowed)
			(footprints allowed)
		)
		(placement
			(enabled no)
			(sheetname "")
		)
		(fill yes
			(thermal_gap 0.5)
			(thermal_bridge_width 0.5)
			(island_removal_mode 0)
		)
		(polygon
			(pts
				(arc
					(start 55.118254 -412.570168)
					(mid 54.450234 -412.570168)
					(end 55.118254 -412.570168)
				)
			)
		)
	)
	(zone
		(layers "B.Cu" "In13.Cu" "In15.Cu")
		(hatch none 0.5)
		(connect_pads
			(clearance 0)
		)
		(min_thickness 0.25)
		(keepout
			(tracks not_allowed)
			(vias allowed)
			(pads allowed)
			(copperpour not_allowed)
			(footprints allowed)
		)
		(placement
			(enabled no)
			(sheetname "")
		)
		(fill yes
			(thermal_gap 0.5)
			(thermal_bridge_width 0.5)
			(island_removal_mode 0)
		)
		(polygon
			(pts
				(arc
					(start 84.3661 -253.394464)
					(mid 83.73618 -253.394464)
					(end 84.3661 -253.394464)
				)
			)
		)
	)
	(zone
		(layers "B.Cu" "In13.Cu" "In15.Cu")
		(hatch none 0.5)
		(connect_pads
			(clearance 0)
		)
		(min_thickness 0.25)
		(keepout
			(tracks not_allowed)
			(vias allowed)
			(pads allowed)
			(copperpour not_allowed)
			(footprints allowed)
		)
		(placement
			(enabled no)
			(sheetname "")
		)
		(fill yes
			(thermal_gap 0.5)
			(thermal_bridge_width 0.5)
			(island_removal_mode 0)
		)
		(polygon
			(pts
				(arc
					(start 332.306168 -230.714296)
					(mid 331.676248 -230.714296)
					(end 332.306168 -230.714296)
				)
			)
		)
	)
	(zone
		(layers "B.Cu" "In13.Cu" "In15.Cu")
		(hatch none 0.5)
		(connect_pads
			(clearance 0)
		)
		(min_thickness 0.25)
		(keepout
			(tracks not_allowed)
			(vias allowed)
			(pads allowed)
			(copperpour not_allowed)
			(footprints allowed)
		)
		(placement
			(enabled no)
			(sheetname "")
		)
		(fill yes
			(thermal_gap 0.5)
			(thermal_bridge_width 0.5)
			(island_removal_mode 0)
		)
		(polygon
			(pts
				(arc
					(start 362.679742 -277.32609)
					(mid 362.049822 -277.32609)
					(end 362.679742 -277.32609)
				)
			)
		)
	)
	(zone
		(layers "B.Cu" "In13.Cu" "In15.Cu")
		(hatch none 0.5)
		(connect_pads
			(clearance 0)
		)
		(min_thickness 0.25)
		(keepout
			(tracks not_allowed)
			(vias allowed)
			(pads allowed)
			(copperpour not_allowed)
			(footprints allowed)
		)
		(placement
			(enabled no)
			(sheetname "")
		)
		(fill yes
			(thermal_gap 0.5)
			(thermal_bridge_width 0.5)
			(island_removal_mode 0)
		)
		(polygon
			(pts
				(arc
					(start 387.289802 -244.484144)
					(mid 386.659882 -244.484144)
					(end 387.289802 -244.484144)
				)
			)
		)
	)
	(zone
		(layers "B.Cu" "In13.Cu" "In15.Cu")
		(hatch none 0.5)
		(connect_pads
			(clearance 0)
		)
		(min_thickness 0.25)
		(keepout
			(tracks not_allowed)
			(vias allowed)
			(pads allowed)
			(copperpour not_allowed)
			(footprints allowed)
		)
		(placement
			(enabled no)
			(sheetname "")
		)
		(fill yes
			(thermal_gap 0.5)
			(thermal_bridge_width 0.5)
			(island_removal_mode 0)
		)
		(polygon
			(pts
				(arc
					(start 386.179822 -270.846042)
					(mid 385.549902 -270.846042)
					(end 386.179822 -270.846042)
				)
			)
		)
	)
	(zone
		(layers "B.Cu" "In13.Cu" "In15.Cu")
		(hatch none 0.5)
		(connect_pads
			(clearance 0)
		)
		(min_thickness 0.25)
		(keepout
			(tracks not_allowed)
			(vias allowed)
			(pads allowed)
			(copperpour not_allowed)
			(footprints allowed)
		)
		(placement
			(enabled no)
			(sheetname "")
		)
		(fill yes
			(thermal_gap 0.5)
			(thermal_bridge_width 0.5)
			(island_removal_mode 0)
		)
		(polygon
			(pts
				(arc
					(start 382.136904 -430.889918)
					(mid 381.362712 -430.889918)
					(end 382.136904 -430.889918)
				)
			)
		)
	)
	(zone
		(layers "B.Cu" "In13.Cu" "In15.Cu")
		(hatch none 0.5)
		(connect_pads
			(clearance 0)
		)
		(min_thickness 0.25)
		(keepout
			(tracks not_allowed)
			(vias allowed)
			(pads allowed)
			(copperpour not_allowed)
			(footprints allowed)
		)
		(placement
			(enabled no)
			(sheetname "")
		)
		(fill yes
			(thermal_gap 0.5)
			(thermal_bridge_width 0.5)
			(island_removal_mode 0)
		)
		(polygon
			(pts
				(arc
					(start 115.679728 -277.326344)
					(mid 115.049808 -277.326344)
					(end 115.679728 -277.326344)
				)
			)
		)
	)
	(zone
		(layers "B.Cu" "In13.Cu" "In15.Cu")
		(hatch none 0.5)
		(connect_pads
			(clearance 0)
		)
		(min_thickness 0.25)
		(keepout
			(tracks not_allowed)
			(vias allowed)
			(pads allowed)
			(copperpour not_allowed)
			(footprints allowed)
		)
		(placement
			(enabled no)
			(sheetname "")
		)
		(fill yes
			(thermal_gap 0.5)
			(thermal_bridge_width 0.5)
			(island_removal_mode 0)
		)
		(polygon
			(pts
				(arc
					(start 84.836 -234.764326)
					(mid 84.20608 -234.764326)
					(end 84.836 -234.764326)
				)
			)
		)
	)
	(zone
		(layers "B.Cu" "In13.Cu" "In15.Cu")
		(hatch none 0.5)
		(connect_pads
			(clearance 0)
		)
		(min_thickness 0.25)
		(keepout
			(tracks not_allowed)
			(vias allowed)
			(pads allowed)
			(copperpour not_allowed)
			(footprints allowed)
		)
		(placement
			(enabled no)
			(sheetname "")
		)
		(fill yes
			(thermal_gap 0.5)
			(thermal_bridge_width 0.5)
			(island_removal_mode 0)
		)
		(polygon
			(pts
				(arc
					(start 454.522078 -283.185108)
					(mid 453.854058 -283.185108)
					(end 454.522078 -283.185108)
				)
			)
		)
	)
	(zone
		(layers "B.Cu" "In13.Cu" "In15.Cu")
		(hatch none 0.5)
		(connect_pads
			(clearance 0)
		)
		(min_thickness 0.25)
		(keepout
			(tracks not_allowed)
			(vias allowed)
			(pads allowed)
			(copperpour not_allowed)
			(footprints allowed)
		)
		(placement
			(enabled no)
			(sheetname "")
		)
		(fill yes
			(thermal_gap 0.5)
			(thermal_bridge_width 0.5)
			(island_removal_mode 0)
		)
		(polygon
			(pts
				(arc
					(start 333.076042 -292.71595)
					(mid 332.446122 -292.71595)
					(end 333.076042 -292.71595)
				)
			)
		)
	)
	(zone
		(layers "B.Cu" "In13.Cu" "In15.Cu")
		(hatch none 0.5)
		(connect_pads
			(clearance 0)
		)
		(min_thickness 0.25)
		(keepout
			(tracks not_allowed)
			(vias allowed)
			(pads allowed)
			(copperpour not_allowed)
			(footprints allowed)
		)
		(placement
			(enabled no)
			(sheetname "")
		)
		(fill yes
			(thermal_gap 0.5)
			(thermal_bridge_width 0.5)
			(island_removal_mode 0)
		)
		(polygon
			(pts
				(arc
					(start 387.589776 -291.095938)
					(mid 386.959856 -291.095938)
					(end 387.589776 -291.095938)
				)
			)
		)
	)
	(zone
		(layers "B.Cu" "In13.Cu" "In15.Cu")
		(hatch none 0.5)
		(connect_pads
			(clearance 0)
		)
		(min_thickness 0.25)
		(keepout
			(tracks not_allowed)
			(vias allowed)
			(pads allowed)
			(copperpour not_allowed)
			(footprints allowed)
		)
		(placement
			(enabled no)
			(sheetname "")
		)
		(fill yes
			(thermal_gap 0.5)
			(thermal_bridge_width 0.5)
			(island_removal_mode 0)
		)
		(polygon
			(pts
				(arc
					(start 107.396026 -244.484398)
					(mid 106.766106 -244.484398)
					(end 107.396026 -244.484398)
				)
			)
		)
	)
	(zone
		(layers "B.Cu" "In13.Cu" "In15.Cu")
		(hatch none 0.5)
		(connect_pads
			(clearance 0)
		)
		(min_thickness 0.25)
		(keepout
			(tracks not_allowed)
			(vias allowed)
			(pads allowed)
			(copperpour not_allowed)
			(footprints allowed)
		)
		(placement
			(enabled no)
			(sheetname "")
		)
		(fill yes
			(thermal_gap 0.5)
			(thermal_bridge_width 0.5)
			(island_removal_mode 0)
		)
		(polygon
			(pts
				(arc
					(start 140.119608 -283.806392)
					(mid 139.489688 -283.806392)
					(end 140.119608 -283.806392)
				)
			)
		)
	)
	(zone
		(layers "B.Cu" "In13.Cu" "In15.Cu")
		(hatch none 0.5)
		(connect_pads
			(clearance 0)
		)
		(min_thickness 0.25)
		(keepout
			(tracks not_allowed)
			(vias allowed)
			(pads allowed)
			(copperpour not_allowed)
			(footprints allowed)
		)
		(placement
			(enabled no)
			(sheetname "")
		)
		(fill yes
			(thermal_gap 0.5)
			(thermal_bridge_width 0.5)
			(island_removal_mode 0)
		)
		(polygon
			(pts
				(arc
					(start 333.716122 -233.14406)
					(mid 333.086202 -233.14406)
					(end 333.716122 -233.14406)
				)
			)
		)
	)
	(zone
		(layers "B.Cu" "In13.Cu" "In15.Cu")
		(hatch none 0.5)
		(connect_pads
			(clearance 0)
		)
		(min_thickness 0.25)
		(keepout
			(tracks not_allowed)
			(vias allowed)
			(pads allowed)
			(copperpour not_allowed)
			(footprints allowed)
		)
		(placement
			(enabled no)
			(sheetname "")
		)
		(fill yes
			(thermal_gap 0.5)
			(thermal_bridge_width 0.5)
			(island_removal_mode 0)
		)
		(polygon
			(pts
				(arc
					(start 202.481942 -230.485442)
					(mid 201.813922 -230.485442)
					(end 202.481942 -230.485442)
				)
			)
		)
	)
	(zone
		(layers "B.Cu" "In13.Cu" "In15.Cu")
		(hatch none 0.5)
		(connect_pads
			(clearance 0)
		)
		(min_thickness 0.25)
		(keepout
			(tracks not_allowed)
			(vias allowed)
			(pads allowed)
			(copperpour not_allowed)
			(footprints allowed)
		)
		(placement
			(enabled no)
			(sheetname "")
		)
		(fill yes
			(thermal_gap 0.5)
			(thermal_bridge_width 0.5)
			(island_removal_mode 0)
		)
		(polygon
			(pts
				(arc
					(start 269.982188 -221.985078)
					(mid 269.314168 -221.985078)
					(end 269.982188 -221.985078)
				)
			)
		)
	)
	(zone
		(layers "B.Cu" "In13.Cu" "In15.Cu")
		(hatch none 0.5)
		(connect_pads
			(clearance 0)
		)
		(min_thickness 0.25)
		(keepout
			(tracks not_allowed)
			(vias allowed)
			(pads allowed)
			(copperpour not_allowed)
			(footprints allowed)
		)
		(placement
			(enabled no)
			(sheetname "")
		)
		(fill yes
			(thermal_gap 0.5)
			(thermal_bridge_width 0.5)
			(island_removal_mode 0)
		)
		(polygon
			(pts
				(arc
					(start 269.982188 -227.085144)
					(mid 269.314168 -227.085144)
					(end 269.982188 -227.085144)
				)
			)
		)
	)
	(zone
		(layers "B.Cu" "In13.Cu" "In15.Cu")
		(hatch none 0.5)
		(connect_pads
			(clearance 0)
		)
		(min_thickness 0.25)
		(keepout
			(tracks not_allowed)
			(vias allowed)
			(pads allowed)
			(copperpour not_allowed)
			(footprints allowed)
		)
		(placement
			(enabled no)
			(sheetname "")
		)
		(fill yes
			(thermal_gap 0.5)
			(thermal_bridge_width 0.5)
			(island_removal_mode 0)
		)
		(polygon
			(pts
				(arc
					(start 348.75597 -231.524048)
					(mid 348.12605 -231.524048)
					(end 348.75597 -231.524048)
				)
			)
		)
	)
	(zone
		(layers "B.Cu" "In13.Cu" "In15.Cu")
		(hatch none 0.5)
		(connect_pads
			(clearance 0)
		)
		(min_thickness 0.25)
		(keepout
			(tracks not_allowed)
			(vias allowed)
			(pads allowed)
			(copperpour not_allowed)
			(footprints allowed)
		)
		(placement
			(enabled no)
			(sheetname "")
		)
		(fill yes
			(thermal_gap 0.5)
			(thermal_bridge_width 0.5)
			(island_removal_mode 0)
		)
		(polygon
			(pts
				(arc
					(start 137.93978 -243.674392)
					(mid 137.30986 -243.674392)
					(end 137.93978 -243.674392)
				)
			)
		)
	)
	(zone
		(layers "B.Cu" "In13.Cu" "In15.Cu")
		(hatch none 0.5)
		(connect_pads
			(clearance 0)
		)
		(min_thickness 0.25)
		(keepout
			(tracks not_allowed)
			(vias allowed)
			(pads allowed)
			(copperpour not_allowed)
			(footprints allowed)
		)
		(placement
			(enabled no)
			(sheetname "")
		)
		(fill yes
			(thermal_gap 0.5)
			(thermal_bridge_width 0.5)
			(island_removal_mode 0)
		)
		(polygon
			(pts
				(arc
					(start 450.42201 -314.635134)
					(mid 449.75399 -314.635134)
					(end 450.42201 -314.635134)
				)
			)
		)
	)
	(zone
		(layers "B.Cu" "In13.Cu" "In15.Cu")
		(hatch none 0.5)
		(connect_pads
			(clearance 0)
		)
		(min_thickness 0.25)
		(keepout
			(tracks not_allowed)
			(vias allowed)
			(pads allowed)
			(copperpour not_allowed)
			(footprints allowed)
		)
		(placement
			(enabled no)
			(sheetname "")
		)
		(fill yes
			(thermal_gap 0.5)
			(thermal_bridge_width 0.5)
			(island_removal_mode 0)
		)
		(polygon
			(pts
				(arc
					(start 387.589776 -276.516084)
					(mid 386.959856 -276.516084)
					(end 387.589776 -276.516084)
				)
			)
		)
	)
	(zone
		(layers "B.Cu" "In13.Cu" "In15.Cu")
		(hatch none 0.5)
		(connect_pads
			(clearance 0)
		)
		(min_thickness 0.25)
		(keepout
			(tracks not_allowed)
			(vias allowed)
			(pads allowed)
			(copperpour not_allowed)
			(footprints allowed)
		)
		(placement
			(enabled no)
			(sheetname "")
		)
		(fill yes
			(thermal_gap 0.5)
			(thermal_bridge_width 0.5)
			(island_removal_mode 0)
		)
		(polygon
			(pts
				(arc
					(start 363.319822 -243.674138)
					(mid 362.689902 -243.674138)
					(end 363.319822 -243.674138)
				)
			)
		)
	)
	(zone
		(layers "B.Cu" "In13.Cu" "In15.Cu")
		(hatch none 0.5)
		(connect_pads
			(clearance 0)
		)
		(min_thickness 0.25)
		(keepout
			(tracks not_allowed)
			(vias allowed)
			(pads allowed)
			(copperpour not_allowed)
			(footprints allowed)
		)
		(placement
			(enabled no)
			(sheetname "")
		)
		(fill yes
			(thermal_gap 0.5)
			(thermal_bridge_width 0.5)
			(island_removal_mode 0)
		)
		(polygon
			(pts
				(arc
					(start 346.23375 -393.69238)
					(mid 345.60383 -393.69238)
					(end 346.23375 -393.69238)
				)
			)
		)
	)
	(zone
		(layers "B.Cu" "In13.Cu" "In15.Cu")
		(hatch none 0.5)
		(connect_pads
			(clearance 0)
		)
		(min_thickness 0.25)
		(keepout
			(tracks not_allowed)
			(vias allowed)
			(pads allowed)
			(copperpour not_allowed)
			(footprints allowed)
		)
		(placement
			(enabled no)
			(sheetname "")
		)
		(fill yes
			(thermal_gap 0.5)
			(thermal_bridge_width 0.5)
			(island_removal_mode 0)
		)
		(polygon
			(pts
				(arc
					(start 99.236022 -274.896326)
					(mid 98.606102 -274.896326)
					(end 99.236022 -274.896326)
				)
			)
		)
	)
	(zone
		(layers "B.Cu" "In13.Cu" "In15.Cu")
		(hatch none 0.5)
		(connect_pads
			(clearance 0)
		)
		(min_thickness 0.25)
		(keepout
			(tracks not_allowed)
			(vias allowed)
			(pads allowed)
			(copperpour not_allowed)
			(footprints allowed)
		)
		(placement
			(enabled no)
			(sheetname "")
		)
		(fill yes
			(thermal_gap 0.5)
			(thermal_bridge_width 0.5)
			(island_removal_mode 0)
		)
		(polygon
			(pts
				(arc
					(start 371.309646 -246.104156)
					(mid 370.679726 -246.104156)
					(end 371.309646 -246.104156)
				)
			)
		)
	)
	(zone
		(layers "B.Cu" "In13.Cu" "In15.Cu")
		(hatch none 0.5)
		(connect_pads
			(clearance 0)
		)
		(min_thickness 0.25)
		(keepout
			(tracks not_allowed)
			(vias allowed)
			(pads allowed)
			(copperpour not_allowed)
			(footprints allowed)
		)
		(placement
			(enabled no)
			(sheetname "")
		)
		(fill yes
			(thermal_gap 0.5)
			(thermal_bridge_width 0.5)
			(island_removal_mode 0)
		)
		(polygon
			(pts
				(arc
					(start 126.136908 -430.889918)
					(mid 125.362716 -430.889918)
					(end 126.136908 -430.889918)
				)
			)
		)
	)
	(zone
		(layers "B.Cu" "In13.Cu" "In15.Cu")
		(hatch none 0.5)
		(connect_pads
			(clearance 0)
		)
		(min_thickness 0.25)
		(keepout
			(tracks not_allowed)
			(vias allowed)
			(pads allowed)
			(copperpour not_allowed)
			(footprints allowed)
		)
		(placement
			(enabled no)
			(sheetname "")
		)
		(fill yes
			(thermal_gap 0.5)
			(thermal_bridge_width 0.5)
			(island_removal_mode 0)
		)
		(polygon
			(pts
				(arc
					(start 85.135974 -266.796266)
					(mid 84.506054 -266.796266)
					(end 85.135974 -266.796266)
				)
			)
		)
	)
	(zone
		(layers "B.Cu" "In13.Cu" "In15.Cu")
		(hatch none 0.5)
		(connect_pads
			(clearance 0)
		)
		(min_thickness 0.25)
		(keepout
			(tracks not_allowed)
			(vias allowed)
			(pads allowed)
			(copperpour not_allowed)
			(footprints allowed)
		)
		(placement
			(enabled no)
			(sheetname "")
		)
		(fill yes
			(thermal_gap 0.5)
			(thermal_bridge_width 0.5)
			(island_removal_mode 0)
		)
		(polygon
			(pts
				(arc
					(start 94.234 -389.467344)
					(mid 93.60408 -389.467344)
					(end 94.234 -389.467344)
				)
			)
		)
	)
	(zone
		(layers "B.Cu" "In13.Cu" "In15.Cu")
		(hatch none 0.5)
		(connect_pads
			(clearance 0)
		)
		(min_thickness 0.25)
		(keepout
			(tracks not_allowed)
			(vias allowed)
			(pads allowed)
			(copperpour not_allowed)
			(footprints allowed)
		)
		(placement
			(enabled no)
			(sheetname "")
		)
		(fill yes
			(thermal_gap 0.5)
			(thermal_bridge_width 0.5)
			(island_removal_mode 0)
		)
		(polygon
			(pts
				(arc
					(start 325.570596 -420.952168)
					(mid 324.902576 -420.952168)
					(end 325.570596 -420.952168)
				)
			)
		)
	)
	(zone
		(layers "B.Cu" "In13.Cu" "In15.Cu")
		(hatch none 0.5)
		(connect_pads
			(clearance 0)
		)
		(min_thickness 0.25)
		(keepout
			(tracks not_allowed)
			(vias allowed)
			(pads allowed)
			(copperpour not_allowed)
			(footprints allowed)
		)
		(placement
			(enabled no)
			(sheetname "")
		)
		(fill yes
			(thermal_gap 0.5)
			(thermal_bridge_width 0.5)
			(island_removal_mode 0)
		)
		(polygon
			(pts
				(arc
					(start 356.746048 -233.954066)
					(mid 356.116128 -233.954066)
					(end 356.746048 -233.954066)
				)
			)
		)
	)
	(zone
		(layers "B.Cu" "In13.Cu" "In15.Cu")
		(hatch none 0.5)
		(connect_pads
			(clearance 0)
		)
		(min_thickness 0.25)
		(keepout
			(tracks not_allowed)
			(vias allowed)
			(pads allowed)
			(copperpour not_allowed)
			(footprints allowed)
		)
		(placement
			(enabled no)
			(sheetname "")
		)
		(fill yes
			(thermal_gap 0.5)
			(thermal_bridge_width 0.5)
			(island_removal_mode 0)
		)
		(polygon
			(pts
				(arc
					(start 130.1369 -430.889918)
					(mid 129.362708 -430.889918)
					(end 130.1369 -430.889918)
				)
			)
		)
	)
	(zone
		(layers "B.Cu" "In13.Cu" "In15.Cu")
		(hatch none 0.5)
		(connect_pads
			(clearance 0)
		)
		(min_thickness 0.25)
		(keepout
			(tracks not_allowed)
			(vias allowed)
			(pads allowed)
			(copperpour not_allowed)
			(footprints allowed)
		)
		(placement
			(enabled no)
			(sheetname "")
		)
		(fill yes
			(thermal_gap 0.5)
			(thermal_bridge_width 0.5)
			(island_removal_mode 0)
		)
		(polygon
			(pts
				(arc
					(start 17.942052 -216.885266)
					(mid 17.274032 -216.885266)
					(end 17.942052 -216.885266)
				)
			)
		)
	)
	(zone
		(layers "B.Cu" "In13.Cu" "In15.Cu")
		(hatch none 0.5)
		(connect_pads
			(clearance 0)
		)
		(min_thickness 0.25)
		(keepout
			(tracks not_allowed)
			(vias allowed)
			(pads allowed)
			(copperpour not_allowed)
			(footprints allowed)
		)
		(placement
			(enabled no)
			(sheetname "")
		)
		(fill yes
			(thermal_gap 0.5)
			(thermal_bridge_width 0.5)
			(island_removal_mode 0)
		)
		(polygon
			(pts
				(arc
					(start 106.375454 -31.541466)
					(mid 105.707434 -31.541466)
					(end 106.375454 -31.541466)
				)
			)
		)
	)
	(zone
		(layers "B.Cu" "In13.Cu" "In15.Cu")
		(hatch none 0.5)
		(connect_pads
			(clearance 0)
		)
		(min_thickness 0.25)
		(keepout
			(tracks not_allowed)
			(vias allowed)
			(pads allowed)
			(copperpour not_allowed)
			(footprints allowed)
		)
		(placement
			(enabled no)
			(sheetname "")
		)
		(fill yes
			(thermal_gap 0.5)
			(thermal_bridge_width 0.5)
			(island_removal_mode 0)
		)
		(polygon
			(pts
				(arc
					(start 81.034128 -386.003292)
					(mid 80.404208 -386.003292)
					(end 81.034128 -386.003292)
				)
			)
		)
	)
	(zone
		(layers "B.Cu" "In13.Cu" "In15.Cu")
		(hatch none 0.5)
		(connect_pads
			(clearance 0)
		)
		(min_thickness 0.25)
		(keepout
			(tracks not_allowed)
			(vias allowed)
			(pads allowed)
			(copperpour not_allowed)
			(footprints allowed)
		)
		(placement
			(enabled no)
			(sheetname "")
		)
		(fill yes
			(thermal_gap 0.5)
			(thermal_bridge_width 0.5)
			(island_removal_mode 0)
		)
		(polygon
			(pts
				(arc
					(start 349.056198 -276.516084)
					(mid 348.426278 -276.516084)
					(end 349.056198 -276.516084)
				)
			)
		)
	)
	(zone
		(layers "B.Cu" "In13.Cu" "In15.Cu")
		(hatch none 0.5)
		(connect_pads
			(clearance 0)
		)
		(min_thickness 0.25)
		(keepout
			(tracks not_allowed)
			(vias allowed)
			(pads allowed)
			(copperpour not_allowed)
			(footprints allowed)
		)
		(placement
			(enabled no)
			(sheetname "")
		)
		(fill yes
			(thermal_gap 0.5)
			(thermal_bridge_width 0.5)
			(island_removal_mode 0)
		)
		(polygon
			(pts
				(arc
					(start 140.119608 -272.466308)
					(mid 139.489688 -272.466308)
					(end 140.119608 -272.466308)
				)
			)
		)
	)
	(zone
		(layers "B.Cu" "In13.Cu" "In15.Cu")
		(hatch none 0.5)
		(connect_pads
			(clearance 0)
		)
		(min_thickness 0.25)
		(keepout
			(tracks not_allowed)
			(vias allowed)
			(pads allowed)
			(copperpour not_allowed)
			(footprints allowed)
		)
		(placement
			(enabled no)
			(sheetname "")
		)
		(fill yes
			(thermal_gap 0.5)
			(thermal_bridge_width 0.5)
			(island_removal_mode 0)
		)
		(polygon
			(pts
				(arc
					(start 149.137116 -430.689766)
					(mid 148.362924 -430.689766)
					(end 149.137116 -430.689766)
				)
			)
		)
	)
	(zone
		(layers "B.Cu" "In13.Cu" "In15.Cu")
		(hatch none 0.5)
		(connect_pads
			(clearance 0)
		)
		(min_thickness 0.25)
		(keepout
			(tracks not_allowed)
			(vias allowed)
			(pads allowed)
			(copperpour not_allowed)
			(footprints allowed)
		)
		(placement
			(enabled no)
			(sheetname "")
		)
		(fill yes
			(thermal_gap 0.5)
			(thermal_bridge_width 0.5)
			(island_removal_mode 0)
		)
		(polygon
			(pts
				(arc
					(start 98.634042 -385.31038)
					(mid 98.004122 -385.31038)
					(end 98.634042 -385.31038)
				)
			)
		)
	)
	(zone
		(layers "B.Cu" "In13.Cu" "In15.Cu")
		(hatch none 0.5)
		(connect_pads
			(clearance 0)
		)
		(min_thickness 0.25)
		(keepout
			(tracks not_allowed)
			(vias allowed)
			(pads allowed)
			(copperpour not_allowed)
			(footprints allowed)
		)
		(placement
			(enabled no)
			(sheetname "")
		)
		(fill yes
			(thermal_gap 0.5)
			(thermal_bridge_width 0.5)
			(island_removal_mode 0)
		)
		(polygon
			(pts
				(arc
					(start 354.39604 -234.764072)
					(mid 353.76612 -234.764072)
					(end 354.39604 -234.764072)
				)
			)
		)
	)
	(zone
		(layers "B.Cu" "In13.Cu" "In15.Cu")
		(hatch none 0.5)
		(connect_pads
			(clearance 0)
		)
		(min_thickness 0.25)
		(keepout
			(tracks not_allowed)
			(vias allowed)
			(pads allowed)
			(copperpour not_allowed)
			(footprints allowed)
		)
		(placement
			(enabled no)
			(sheetname "")
		)
		(fill yes
			(thermal_gap 0.5)
			(thermal_bridge_width 0.5)
			(island_removal_mode 0)
		)
		(polygon
			(pts
				(arc
					(start 344.036904 -430.889918)
					(mid 343.262712 -430.889918)
					(end 344.036904 -430.889918)
				)
			)
		)
	)
	(zone
		(layers "B.Cu" "In13.Cu" "In15.Cu")
		(hatch none 0.5)
		(connect_pads
			(clearance 0)
		)
		(min_thickness 0.25)
		(keepout
			(tracks not_allowed)
			(vias allowed)
			(pads allowed)
			(copperpour not_allowed)
			(footprints allowed)
		)
		(placement
			(enabled no)
			(sheetname "")
		)
		(fill yes
			(thermal_gap 0.5)
			(thermal_bridge_width 0.5)
			(island_removal_mode 0)
		)
		(polygon
			(pts
				(arc
					(start 138.709654 -287.856422)
					(mid 138.079734 -287.856422)
					(end 138.709654 -287.856422)
				)
			)
		)
	)
	(zone
		(layers "B.Cu" "In13.Cu" "In15.Cu")
		(hatch none 0.5)
		(connect_pads
			(clearance 0)
		)
		(min_thickness 0.25)
		(keepout
			(tracks not_allowed)
			(vias allowed)
			(pads allowed)
			(copperpour not_allowed)
			(footprints allowed)
		)
		(placement
			(enabled no)
			(sheetname "")
		)
		(fill yes
			(thermal_gap 0.5)
			(thermal_bridge_width 0.5)
			(island_removal_mode 0)
		)
		(polygon
			(pts
				(arc
					(start 269.982188 -216.035128)
					(mid 269.314168 -216.035128)
					(end 269.982188 -216.035128)
				)
			)
		)
	)
	(zone
		(layers "B.Cu" "In13.Cu" "In15.Cu")
		(hatch none 0.5)
		(connect_pads
			(clearance 0)
		)
		(min_thickness 0.25)
		(keepout
			(tracks not_allowed)
			(vias allowed)
			(pads allowed)
			(copperpour not_allowed)
			(footprints allowed)
		)
		(placement
			(enabled no)
			(sheetname "")
		)
		(fill yes
			(thermal_gap 0.5)
			(thermal_bridge_width 0.5)
			(island_removal_mode 0)
		)
		(polygon
			(pts
				(arc
					(start 17.942052 -204.135228)
					(mid 17.274032 -204.135228)
					(end 17.942052 -204.135228)
				)
			)
		)
	)
	(zone
		(layers "B.Cu" "In13.Cu" "In15.Cu")
		(hatch none 0.5)
		(connect_pads
			(clearance 0)
		)
		(min_thickness 0.25)
		(keepout
			(tracks not_allowed)
			(vias allowed)
			(pads allowed)
			(copperpour not_allowed)
			(footprints allowed)
		)
		(placement
			(enabled no)
			(sheetname "")
		)
		(fill yes
			(thermal_gap 0.5)
			(thermal_bridge_width 0.5)
			(island_removal_mode 0)
		)
		(polygon
			(pts
				(arc
					(start 79.624174 -412.570168)
					(mid 78.956154 -412.570168)
					(end 79.624174 -412.570168)
				)
			)
		)
	)
	(zone
		(layers "B.Cu" "In13.Cu" "In15.Cu")
		(hatch none 0.5)
		(connect_pads
			(clearance 0)
		)
		(min_thickness 0.25)
		(keepout
			(tracks not_allowed)
			(vias allowed)
			(pads allowed)
			(copperpour not_allowed)
			(footprints allowed)
		)
		(placement
			(enabled no)
			(sheetname "")
		)
		(fill yes
			(thermal_gap 0.5)
			(thermal_bridge_width 0.5)
			(island_removal_mode 0)
		)
		(polygon
			(pts
				(arc
					(start 269.982188 -275.535136)
					(mid 269.314168 -275.535136)
					(end 269.982188 -275.535136)
				)
			)
		)
	)
	(zone
		(layers "B.Cu" "In13.Cu" "In15.Cu")
		(hatch none 0.5)
		(connect_pads
			(clearance 0)
		)
		(min_thickness 0.25)
		(keepout
			(tracks not_allowed)
			(vias allowed)
			(pads allowed)
			(copperpour not_allowed)
			(footprints allowed)
		)
		(placement
			(enabled no)
			(sheetname "")
		)
		(fill yes
			(thermal_gap 0.5)
			(thermal_bridge_width 0.5)
			(island_removal_mode 0)
		)
		(polygon
			(pts
				(arc
					(start 450.42201 -210.935062)
					(mid 449.75399 -210.935062)
					(end 450.42201 -210.935062)
				)
			)
		)
	)
	(zone
		(layers "B.Cu" "In13.Cu" "In15.Cu")
		(hatch none 0.5)
		(connect_pads
			(clearance 0)
		)
		(min_thickness 0.25)
		(keepout
			(tracks not_allowed)
			(vias allowed)
			(pads allowed)
			(copperpour not_allowed)
			(footprints allowed)
		)
		(placement
			(enabled no)
			(sheetname "")
		)
		(fill yes
			(thermal_gap 0.5)
			(thermal_bridge_width 0.5)
			(island_removal_mode 0)
		)
		(polygon
			(pts
				(arc
					(start 202.481942 -233.885232)
					(mid 201.813922 -233.885232)
					(end 202.481942 -233.885232)
				)
			)
		)
	)
	(zone
		(layers "B.Cu" "In13.Cu" "In15.Cu")
		(hatch none 0.5)
		(connect_pads
			(clearance 0)
		)
		(min_thickness 0.25)
		(keepout
			(tracks not_allowed)
			(vias allowed)
			(pads allowed)
			(copperpour not_allowed)
			(footprints allowed)
		)
		(placement
			(enabled no)
			(sheetname "")
		)
		(fill yes
			(thermal_gap 0.5)
			(thermal_bridge_width 0.5)
			(island_removal_mode 0)
		)
		(polygon
			(pts
				(arc
					(start 454.522078 -236.435138)
					(mid 453.854058 -236.435138)
					(end 454.522078 -236.435138)
				)
			)
		)
	)
	(zone
		(layers "B.Cu" "In13.Cu" "In15.Cu")
		(hatch none 0.5)
		(connect_pads
			(clearance 0)
		)
		(min_thickness 0.25)
		(keepout
			(tracks not_allowed)
			(vias allowed)
			(pads allowed)
			(copperpour not_allowed)
			(footprints allowed)
		)
		(placement
			(enabled no)
			(sheetname "")
		)
		(fill yes
			(thermal_gap 0.5)
			(thermal_bridge_width 0.5)
			(island_removal_mode 0)
		)
		(polygon
			(pts
				(arc
					(start 395.654276 -4.963414)
					(mid 394.986256 -4.963414)
					(end 395.654276 -4.963414)
				)
			)
		)
	)
	(zone
		(layers "B.Cu" "In13.Cu" "In15.Cu")
		(hatch none 0.5)
		(connect_pads
			(clearance 0)
		)
		(min_thickness 0.25)
		(keepout
			(tracks not_allowed)
			(vias allowed)
			(pads allowed)
			(copperpour not_allowed)
			(footprints allowed)
		)
		(placement
			(enabled no)
			(sheetname "")
		)
		(fill yes
			(thermal_gap 0.5)
			(thermal_bridge_width 0.5)
			(island_removal_mode 0)
		)
		(polygon
			(pts
				(arc
					(start 90.037158 -430.689766)
					(mid 89.262966 -430.689766)
					(end 90.037158 -430.689766)
				)
			)
		)
	)
	(zone
		(layers "B.Cu" "In13.Cu" "In15.Cu")
		(hatch none 0.5)
		(connect_pads
			(clearance 0)
		)
		(min_thickness 0.25)
		(keepout
			(tracks not_allowed)
			(vias allowed)
			(pads allowed)
			(copperpour not_allowed)
			(footprints allowed)
		)
		(placement
			(enabled no)
			(sheetname "")
		)
		(fill yes
			(thermal_gap 0.5)
			(thermal_bridge_width 0.5)
			(island_removal_mode 0)
		)
		(polygon
			(pts
				(arc
					(start 386.349748 -228.284278)
					(mid 385.719828 -228.284278)
					(end 386.349748 -228.284278)
				)
			)
		)
	)
	(zone
		(layers "B.Cu" "In13.Cu" "In15.Cu")
		(hatch none 0.5)
		(connect_pads
			(clearance 0)
		)
		(min_thickness 0.25)
		(keepout
			(tracks not_allowed)
			(vias allowed)
			(pads allowed)
			(copperpour not_allowed)
			(footprints allowed)
		)
		(placement
			(enabled no)
			(sheetname "")
		)
		(fill yes
			(thermal_gap 0.5)
			(thermal_bridge_width 0.5)
			(island_removal_mode 0)
		)
		(polygon
			(pts
				(arc
					(start 450.42201 -254.284988)
					(mid 449.75399 -254.284988)
					(end 450.42201 -254.284988)
				)
			)
		)
	)
	(zone
		(layers "B.Cu" "In13.Cu" "In15.Cu")
		(hatch none 0.5)
		(connect_pads
			(clearance 0)
		)
		(min_thickness 0.25)
		(keepout
			(tracks not_allowed)
			(vias allowed)
			(pads allowed)
			(copperpour not_allowed)
			(footprints allowed)
		)
		(placement
			(enabled no)
			(sheetname "")
		)
		(fill yes
			(thermal_gap 0.5)
			(thermal_bridge_width 0.5)
			(island_removal_mode 0)
		)
		(polygon
			(pts
				(arc
					(start 140.119608 -282.18638)
					(mid 139.489688 -282.18638)
					(end 140.119608 -282.18638)
				)
			)
		)
	)
	(zone
		(layers "B.Cu" "In13.Cu" "In15.Cu")
		(hatch none 0.5)
		(connect_pads
			(clearance 0)
		)
		(min_thickness 0.25)
		(keepout
			(tracks not_allowed)
			(vias allowed)
			(pads allowed)
			(copperpour not_allowed)
			(footprints allowed)
		)
		(placement
			(enabled no)
			(sheetname "")
		)
		(fill yes
			(thermal_gap 0.5)
			(thermal_bridge_width 0.5)
			(island_removal_mode 0)
		)
		(polygon
			(pts
				(arc
					(start 22.04212 -238.985298)
					(mid 21.3741 -238.985298)
					(end 22.04212 -238.985298)
				)
			)
		)
	)
	(zone
		(layers "B.Cu" "In13.Cu" "In15.Cu")
		(hatch none 0.5)
		(connect_pads
			(clearance 0)
		)
		(min_thickness 0.25)
		(keepout
			(tracks not_allowed)
			(vias allowed)
			(pads allowed)
			(copperpour not_allowed)
			(footprints allowed)
		)
		(placement
			(enabled no)
			(sheetname "")
		)
		(fill yes
			(thermal_gap 0.5)
			(thermal_bridge_width 0.5)
			(island_removal_mode 0)
		)
		(polygon
			(pts
				(arc
					(start 450.42201 -229.63505)
					(mid 449.75399 -229.63505)
					(end 450.42201 -229.63505)
				)
			)
		)
	)
	(zone
		(layers "B.Cu" "In13.Cu" "In15.Cu")
		(hatch none 0.5)
		(connect_pads
			(clearance 0)
		)
		(min_thickness 0.25)
		(keepout
			(tracks not_allowed)
			(vias allowed)
			(pads allowed)
			(copperpour not_allowed)
			(footprints allowed)
		)
		(placement
			(enabled no)
			(sheetname "")
		)
		(fill yes
			(thermal_gap 0.5)
			(thermal_bridge_width 0.5)
			(island_removal_mode 0)
		)
		(polygon
			(pts
				(arc
					(start 138.239754 -274.08632)
					(mid 137.609834 -274.08632)
					(end 138.239754 -274.08632)
				)
			)
		)
	)
	(zone
		(layers "B.Cu" "In13.Cu" "In15.Cu")
		(hatch none 0.5)
		(connect_pads
			(clearance 0)
		)
		(min_thickness 0.25)
		(keepout
			(tracks not_allowed)
			(vias allowed)
			(pads allowed)
			(copperpour not_allowed)
			(footprints allowed)
		)
		(placement
			(enabled no)
			(sheetname "")
		)
		(fill yes
			(thermal_gap 0.5)
			(thermal_bridge_width 0.5)
			(island_removal_mode 0)
		)
		(polygon
			(pts
				(arc
					(start 138.711686 -376.956828)
					(mid 138.043666 -376.956828)
					(end 138.711686 -376.956828)
				)
			)
		)
	)
	(zone
		(layers "B.Cu" "In13.Cu" "In15.Cu")
		(hatch none 0.5)
		(connect_pads
			(clearance 0)
		)
		(min_thickness 0.25)
		(keepout
			(tracks not_allowed)
			(vias allowed)
			(pads allowed)
			(copperpour not_allowed)
			(footprints allowed)
		)
		(placement
			(enabled no)
			(sheetname "")
		)
		(fill yes
			(thermal_gap 0.5)
			(thermal_bridge_width 0.5)
			(island_removal_mode 0)
		)
		(polygon
			(pts
				(arc
					(start 94.234 -386.003292)
					(mid 93.60408 -386.003292)
					(end 94.234 -386.003292)
				)
			)
		)
	)
	(zone
		(layers "B.Cu" "In13.Cu" "In15.Cu")
		(hatch none 0.5)
		(connect_pads
			(clearance 0)
		)
		(min_thickness 0.25)
		(keepout
			(tracks not_allowed)
			(vias allowed)
			(pads allowed)
			(copperpour not_allowed)
			(footprints allowed)
		)
		(placement
			(enabled no)
			(sheetname "")
		)
		(fill yes
			(thermal_gap 0.5)
			(thermal_bridge_width 0.5)
			(island_removal_mode 0)
		)
		(polygon
			(pts
				(arc
					(start 86.545928 -291.906198)
					(mid 85.916008 -291.906198)
					(end 86.545928 -291.906198)
				)
			)
		)
	)
	(zone
		(layers "B.Cu" "In13.Cu" "In15.Cu")
		(hatch none 0.5)
		(connect_pads
			(clearance 0)
		)
		(min_thickness 0.25)
		(keepout
			(tracks not_allowed)
			(vias allowed)
			(pads allowed)
			(copperpour not_allowed)
			(footprints allowed)
		)
		(placement
			(enabled no)
			(sheetname "")
		)
		(fill yes
			(thermal_gap 0.5)
			(thermal_bridge_width 0.5)
			(island_removal_mode 0)
		)
		(polygon
			(pts
				(arc
					(start 85.776054 -228.284532)
					(mid 85.146134 -228.284532)
					(end 85.776054 -228.284532)
				)
			)
		)
	)
	(zone
		(layers "B.Cu" "In13.Cu" "In15.Cu")
		(hatch none 0.5)
		(connect_pads
			(clearance 0)
		)
		(min_thickness 0.25)
		(keepout
			(tracks not_allowed)
			(vias allowed)
			(pads allowed)
			(copperpour not_allowed)
			(footprints allowed)
		)
		(placement
			(enabled no)
			(sheetname "")
		)
		(fill yes
			(thermal_gap 0.5)
			(thermal_bridge_width 0.5)
			(island_removal_mode 0)
		)
		(polygon
			(pts
				(arc
					(start 17.942052 -254.285242)
					(mid 17.274032 -254.285242)
					(end 17.942052 -254.285242)
				)
			)
		)
	)
	(zone
		(layers "B.Cu" "In13.Cu" "In15.Cu")
		(hatch none 0.5)
		(connect_pads
			(clearance 0)
		)
		(min_thickness 0.25)
		(keepout
			(tracks not_allowed)
			(vias allowed)
			(pads allowed)
			(copperpour not_allowed)
			(footprints allowed)
		)
		(placement
			(enabled no)
			(sheetname "")
		)
		(fill yes
			(thermal_gap 0.5)
			(thermal_bridge_width 0.5)
			(island_removal_mode 0)
		)
		(polygon
			(pts
				(arc
					(start 333.716122 -246.104156)
					(mid 333.086202 -246.104156)
					(end 333.716122 -246.104156)
				)
			)
		)
	)
	(zone
		(layers "B.Cu" "In13.Cu" "In15.Cu")
		(hatch none 0.5)
		(connect_pads
			(clearance 0)
		)
		(min_thickness 0.25)
		(keepout
			(tracks not_allowed)
			(vias allowed)
			(pads allowed)
			(copperpour not_allowed)
			(footprints allowed)
		)
		(placement
			(enabled no)
			(sheetname "")
		)
		(fill yes
			(thermal_gap 0.5)
			(thermal_bridge_width 0.5)
			(island_removal_mode 0)
		)
		(polygon
			(pts
				(arc
					(start 413.137096 -430.689766)
					(mid 412.362904 -430.689766)
					(end 413.137096 -430.689766)
				)
			)
		)
	)
	(zone
		(layers "B.Cu" "In13.Cu" "In15.Cu")
		(hatch none 0.5)
		(connect_pads
			(clearance 0)
		)
		(min_thickness 0.25)
		(keepout
			(tracks not_allowed)
			(vias allowed)
			(pads allowed)
			(copperpour not_allowed)
			(footprints allowed)
		)
		(placement
			(enabled no)
			(sheetname "")
		)
		(fill yes
			(thermal_gap 0.5)
			(thermal_bridge_width 0.5)
			(island_removal_mode 0)
		)
		(polygon
			(pts
				(arc
					(start 355.033834 -394.385292)
					(mid 354.403914 -394.385292)
					(end 355.033834 -394.385292)
				)
			)
		)
	)
	(zone
		(layers "B.Cu" "In13.Cu" "In15.Cu")
		(hatch none 0.5)
		(connect_pads
			(clearance 0)
		)
		(min_thickness 0.25)
		(keepout
			(tracks not_allowed)
			(vias allowed)
			(pads allowed)
			(copperpour not_allowed)
			(footprints allowed)
		)
		(placement
			(enabled no)
			(sheetname "")
		)
		(fill yes
			(thermal_gap 0.5)
			(thermal_bridge_width 0.5)
			(island_removal_mode 0)
		)
		(polygon
			(pts
				(arc
					(start 138.711686 -376.093228)
					(mid 138.043666 -376.093228)
					(end 138.711686 -376.093228)
				)
			)
		)
	)
	(zone
		(layers "B.Cu" "In13.Cu" "In15.Cu")
		(hatch none 0.5)
		(connect_pads
			(clearance 0)
		)
		(min_thickness 0.25)
		(keepout
			(tracks not_allowed)
			(vias allowed)
			(pads allowed)
			(copperpour not_allowed)
			(footprints allowed)
		)
		(placement
			(enabled no)
			(sheetname "")
		)
		(fill yes
			(thermal_gap 0.5)
			(thermal_bridge_width 0.5)
			(island_removal_mode 0)
		)
		(polygon
			(pts
				(arc
					(start 333.716122 -255.824228)
					(mid 333.086202 -255.824228)
					(end 333.716122 -255.824228)
				)
			)
		)
	)
	(zone
		(layers "B.Cu" "In13.Cu" "In15.Cu")
		(hatch none 0.5)
		(connect_pads
			(clearance 0)
		)
		(min_thickness 0.25)
		(keepout
			(tracks not_allowed)
			(vias allowed)
			(pads allowed)
			(copperpour not_allowed)
			(footprints allowed)
		)
		(placement
			(enabled no)
			(sheetname "")
		)
		(fill yes
			(thermal_gap 0.5)
			(thermal_bridge_width 0.5)
			(island_removal_mode 0)
		)
		(polygon
			(pts
				(arc
					(start 17.942052 -253.435358)
					(mid 17.274032 -253.435358)
					(end 17.942052 -253.435358)
				)
			)
		)
	)
	(zone
		(layers "B.Cu" "In13.Cu" "In15.Cu")
		(hatch none 0.5)
		(connect_pads
			(clearance 0)
		)
		(min_thickness 0.25)
		(keepout
			(tracks not_allowed)
			(vias allowed)
			(pads allowed)
			(copperpour not_allowed)
			(footprints allowed)
		)
		(placement
			(enabled no)
			(sheetname "")
		)
		(fill yes
			(thermal_gap 0.5)
			(thermal_bridge_width 0.5)
			(island_removal_mode 0)
		)
		(polygon
			(pts
				(arc
					(start 138.40968 -238.00435)
					(mid 137.77976 -238.00435)
					(end 138.40968 -238.00435)
				)
			)
		)
	)
	(zone
		(layers "B.Cu" "In13.Cu" "In15.Cu")
		(hatch none 0.5)
		(connect_pads
			(clearance 0)
		)
		(min_thickness 0.25)
		(keepout
			(tracks not_allowed)
			(vias allowed)
			(pads allowed)
			(copperpour not_allowed)
			(footprints allowed)
		)
		(placement
			(enabled no)
			(sheetname "")
		)
		(fill yes
			(thermal_gap 0.5)
			(thermal_bridge_width 0.5)
			(island_removal_mode 0)
		)
		(polygon
			(pts
				(arc
					(start 454.522078 -233.035094)
					(mid 453.854058 -233.035094)
					(end 454.522078 -233.035094)
				)
			)
		)
	)
	(zone
		(layers "B.Cu" "In13.Cu" "In15.Cu")
		(hatch none 0.5)
		(connect_pads
			(clearance 0)
		)
		(min_thickness 0.25)
		(keepout
			(tracks not_allowed)
			(vias allowed)
			(pads allowed)
			(copperpour not_allowed)
			(footprints allowed)
		)
		(placement
			(enabled no)
			(sheetname "")
		)
		(fill yes
			(thermal_gap 0.5)
			(thermal_bridge_width 0.5)
			(island_removal_mode 0)
		)
		(polygon
			(pts
				(arc
					(start 332.306168 -229.094284)
					(mid 331.676248 -229.094284)
					(end 332.306168 -229.094284)
				)
			)
		)
	)
	(zone
		(layers "B.Cu" "In13.Cu" "In15.Cu")
		(hatch none 0.5)
		(connect_pads
			(clearance 0)
		)
		(min_thickness 0.25)
		(keepout
			(tracks not_allowed)
			(vias allowed)
			(pads allowed)
			(copperpour not_allowed)
			(footprints allowed)
		)
		(placement
			(enabled no)
			(sheetname "")
		)
		(fill yes
			(thermal_gap 0.5)
			(thermal_bridge_width 0.5)
			(island_removal_mode 0)
		)
		(polygon
			(pts
				(arc
					(start 107.696 -276.516338)
					(mid 107.06608 -276.516338)
					(end 107.696 -276.516338)
				)
			)
		)
	)
	(zone
		(layers "B.Cu" "In13.Cu" "In15.Cu")
		(hatch none 0.5)
		(connect_pads
			(clearance 0)
		)
		(min_thickness 0.25)
		(keepout
			(tracks not_allowed)
			(vias allowed)
			(pads allowed)
			(copperpour not_allowed)
			(footprints allowed)
		)
		(placement
			(enabled no)
			(sheetname "")
		)
		(fill yes
			(thermal_gap 0.5)
			(thermal_bridge_width 0.5)
			(island_removal_mode 0)
		)
		(polygon
			(pts
				(arc
					(start 265.88212 -233.884978)
					(mid 265.2141 -233.884978)
					(end 265.88212 -233.884978)
				)
			)
		)
	)
	(zone
		(layers "B.Cu" "In13.Cu" "In15.Cu")
		(hatch none 0.5)
		(connect_pads
			(clearance 0)
		)
		(min_thickness 0.25)
		(keepout
			(tracks not_allowed)
			(vias allowed)
			(pads allowed)
			(copperpour not_allowed)
			(footprints allowed)
		)
		(placement
			(enabled no)
			(sheetname "")
		)
		(fill yes
			(thermal_gap 0.5)
			(thermal_bridge_width 0.5)
			(island_removal_mode 0)
		)
		(polygon
			(pts
				(arc
					(start 450.42201 -304.435002)
					(mid 449.75399 -304.435002)
					(end 450.42201 -304.435002)
				)
			)
		)
	)
	(zone
		(layers "B.Cu" "In13.Cu" "In15.Cu")
		(hatch none 0.5)
		(connect_pads
			(clearance 0)
		)
		(min_thickness 0.25)
		(keepout
			(tracks not_allowed)
			(vias allowed)
			(pads allowed)
			(copperpour not_allowed)
			(footprints allowed)
		)
		(placement
			(enabled no)
			(sheetname "")
		)
		(fill yes
			(thermal_gap 0.5)
			(thermal_bridge_width 0.5)
			(island_removal_mode 0)
		)
		(polygon
			(pts
				(arc
					(start 414.977072 -420.952168)
					(mid 414.309052 -420.952168)
					(end 414.977072 -420.952168)
				)
			)
		)
	)
	(zone
		(layers "B.Cu" "In13.Cu" "In15.Cu")
		(hatch none 0.5)
		(connect_pads
			(clearance 0)
		)
		(min_thickness 0.25)
		(keepout
			(tracks not_allowed)
			(vias allowed)
			(pads allowed)
			(copperpour not_allowed)
			(footprints allowed)
		)
		(placement
			(enabled no)
			(sheetname "")
		)
		(fill yes
			(thermal_gap 0.5)
			(thermal_bridge_width 0.5)
			(island_removal_mode 0)
		)
		(polygon
			(pts
				(arc
					(start 388.059676 -270.846042)
					(mid 387.429756 -270.846042)
					(end 388.059676 -270.846042)
				)
			)
		)
	)
	(zone
		(layers "B.Cu" "In13.Cu" "In15.Cu")
		(hatch none 0.5)
		(connect_pads
			(clearance 0)
		)
		(min_thickness 0.25)
		(keepout
			(tracks not_allowed)
			(vias allowed)
			(pads allowed)
			(copperpour not_allowed)
			(footprints allowed)
		)
		(placement
			(enabled no)
			(sheetname "")
		)
		(fill yes
			(thermal_gap 0.5)
			(thermal_bridge_width 0.5)
			(island_removal_mode 0)
		)
		(polygon
			(pts
				(arc
					(start 387.759702 -248.534174)
					(mid 387.129782 -248.534174)
					(end 387.759702 -248.534174)
				)
			)
		)
	)
	(zone
		(layers "B.Cu" "In13.Cu" "In15.Cu")
		(hatch none 0.5)
		(connect_pads
			(clearance 0)
		)
		(min_thickness 0.25)
		(keepout
			(tracks not_allowed)
			(vias allowed)
			(pads allowed)
			(copperpour not_allowed)
			(footprints allowed)
		)
		(placement
			(enabled no)
			(sheetname "")
		)
		(fill yes
			(thermal_gap 0.5)
			(thermal_bridge_width 0.5)
			(island_removal_mode 0)
		)
		(polygon
			(pts
				(arc
					(start 85.135974 -274.896326)
					(mid 84.506054 -274.896326)
					(end 85.135974 -274.896326)
				)
			)
		)
	)
	(zone
		(layers "B.Cu" "In13.Cu" "In15.Cu")
		(hatch none 0.5)
		(connect_pads
			(clearance 0)
		)
		(min_thickness 0.25)
		(keepout
			(tracks not_allowed)
			(vias allowed)
			(pads allowed)
			(copperpour not_allowed)
			(footprints allowed)
		)
		(placement
			(enabled no)
			(sheetname "")
		)
		(fill yes
			(thermal_gap 0.5)
			(thermal_bridge_width 0.5)
			(island_removal_mode 0)
		)
		(polygon
			(pts
				(arc
					(start 388.059676 -288.66592)
					(mid 387.429756 -288.66592)
					(end 388.059676 -288.66592)
				)
			)
		)
	)
	(zone
		(layers "B.Cu" "In13.Cu" "In15.Cu")
		(hatch none 0.5)
		(connect_pads
			(clearance 0)
		)
		(min_thickness 0.25)
		(keepout
			(tracks not_allowed)
			(vias allowed)
			(pads allowed)
			(copperpour not_allowed)
			(footprints allowed)
		)
		(placement
			(enabled no)
			(sheetname "")
		)
		(fill yes
			(thermal_gap 0.5)
			(thermal_bridge_width 0.5)
			(island_removal_mode 0)
		)
		(polygon
			(pts
				(arc
					(start 454.522078 -238.13516)
					(mid 453.854058 -238.13516)
					(end 454.522078 -238.13516)
				)
			)
		)
	)
	(zone
		(layers "B.Cu" "In13.Cu" "In15.Cu")
		(hatch none 0.5)
		(connect_pads
			(clearance 0)
		)
		(min_thickness 0.25)
		(keepout
			(tracks not_allowed)
			(vias allowed)
			(pads allowed)
			(copperpour not_allowed)
			(footprints allowed)
		)
		(placement
			(enabled no)
			(sheetname "")
		)
		(fill yes
			(thermal_gap 0.5)
			(thermal_bridge_width 0.5)
			(island_removal_mode 0)
		)
		(polygon
			(pts
				(arc
					(start 87.034116 -389.467344)
					(mid 86.404196 -389.467344)
					(end 87.034116 -389.467344)
				)
			)
		)
	)
	(zone
		(layers "B.Cu" "In13.Cu" "In15.Cu")
		(hatch none 0.5)
		(connect_pads
			(clearance 0)
		)
		(min_thickness 0.25)
		(keepout
			(tracks not_allowed)
			(vias allowed)
			(pads allowed)
			(copperpour not_allowed)
			(footprints allowed)
		)
		(placement
			(enabled no)
			(sheetname "")
		)
		(fill yes
			(thermal_gap 0.5)
			(thermal_bridge_width 0.5)
			(island_removal_mode 0)
		)
		(polygon
			(pts
				(arc
					(start 450.42201 -248.335038)
					(mid 449.75399 -248.335038)
					(end 450.42201 -248.335038)
				)
			)
		)
	)
	(zone
		(layers "B.Cu" "In13.Cu" "In15.Cu")
		(hatch none 0.5)
		(connect_pads
			(clearance 0)
		)
		(min_thickness 0.25)
		(keepout
			(tracks not_allowed)
			(vias allowed)
			(pads allowed)
			(copperpour not_allowed)
			(footprints allowed)
		)
		(placement
			(enabled no)
			(sheetname "")
		)
		(fill yes
			(thermal_gap 0.5)
			(thermal_bridge_width 0.5)
			(island_removal_mode 0)
		)
		(polygon
			(pts
				(arc
					(start 87.833962 -385.31038)
					(mid 87.204042 -385.31038)
					(end 87.833962 -385.31038)
				)
			)
		)
	)
	(zone
		(layers "B.Cu" "In13.Cu" "In15.Cu")
		(hatch none 0.5)
		(connect_pads
			(clearance 0)
		)
		(min_thickness 0.25)
		(keepout
			(tracks not_allowed)
			(vias allowed)
			(pads allowed)
			(copperpour not_allowed)
			(footprints allowed)
		)
		(placement
			(enabled no)
			(sheetname "")
		)
		(fill yes
			(thermal_gap 0.5)
			(thermal_bridge_width 0.5)
			(island_removal_mode 0)
		)
		(polygon
			(pts
				(arc
					(start 321.036696 -431.889916)
					(mid 320.262504 -431.889916)
					(end 321.036696 -431.889916)
				)
			)
		)
	)
	(zone
		(layers "B.Cu" "In13.Cu" "In15.Cu")
		(hatch none 0.5)
		(connect_pads
			(clearance 0)
		)
		(min_thickness 0.25)
		(keepout
			(tracks not_allowed)
			(vias allowed)
			(pads allowed)
			(copperpour not_allowed)
			(footprints allowed)
		)
		(placement
			(enabled no)
			(sheetname "")
		)
		(fill yes
			(thermal_gap 0.5)
			(thermal_bridge_width 0.5)
			(island_removal_mode 0)
		)
		(polygon
			(pts
				(arc
					(start 450.42201 -286.585152)
					(mid 449.75399 -286.585152)
					(end 450.42201 -286.585152)
				)
			)
		)
	)
	(zone
		(layers "B.Cu" "In13.Cu" "In15.Cu")
		(hatch none 0.5)
		(connect_pads
			(clearance 0)
		)
		(min_thickness 0.25)
		(keepout
			(tracks not_allowed)
			(vias allowed)
			(pads allowed)
			(copperpour not_allowed)
			(footprints allowed)
		)
		(placement
			(enabled no)
			(sheetname "")
		)
		(fill yes
			(thermal_gap 0.5)
			(thermal_bridge_width 0.5)
			(island_removal_mode 0)
		)
		(polygon
			(pts
				(arc
					(start 140.119608 -267.606272)
					(mid 139.489688 -267.606272)
					(end 140.119608 -267.606272)
				)
			)
		)
	)
	(zone
		(layers "B.Cu" "In13.Cu" "In15.Cu")
		(hatch none 0.5)
		(connect_pads
			(clearance 0)
		)
		(min_thickness 0.25)
		(keepout
			(tracks not_allowed)
			(vias allowed)
			(pads allowed)
			(copperpour not_allowed)
			(footprints allowed)
		)
		(placement
			(enabled no)
			(sheetname "")
		)
		(fill yes
			(thermal_gap 0.5)
			(thermal_bridge_width 0.5)
			(island_removal_mode 0)
		)
		(polygon
			(pts
				(arc
					(start 137.93978 -225.854514)
					(mid 137.30986 -225.854514)
					(end 137.93978 -225.854514)
				)
			)
		)
	)
	(zone
		(layers "B.Cu" "In13.Cu" "In15.Cu")
		(hatch none 0.5)
		(connect_pads
			(clearance 0)
		)
		(min_thickness 0.25)
		(keepout
			(tracks not_allowed)
			(vias allowed)
			(pads allowed)
			(copperpour not_allowed)
			(footprints allowed)
		)
		(placement
			(enabled no)
			(sheetname "")
		)
		(fill yes
			(thermal_gap 0.5)
			(thermal_bridge_width 0.5)
			(island_removal_mode 0)
		)
		(polygon
			(pts
				(arc
					(start 86.245954 -225.854514)
					(mid 85.616034 -225.854514)
					(end 86.245954 -225.854514)
				)
			)
		)
	)
	(zone
		(layers "B.Cu" "In13.Cu" "In15.Cu")
		(hatch none 0.5)
		(connect_pads
			(clearance 0)
		)
		(min_thickness 0.25)
		(keepout
			(tracks not_allowed)
			(vias allowed)
			(pads allowed)
			(copperpour not_allowed)
			(footprints allowed)
		)
		(placement
			(enabled no)
			(sheetname "")
		)
		(fill yes
			(thermal_gap 0.5)
			(thermal_bridge_width 0.5)
			(island_removal_mode 0)
		)
		(polygon
			(pts
				(arc
					(start 454.522078 -285.735014)
					(mid 453.854058 -285.735014)
					(end 454.522078 -285.735014)
				)
			)
		)
	)
	(zone
		(layers "B.Cu" "In13.Cu" "In15.Cu")
		(hatch none 0.5)
		(connect_pads
			(clearance 0)
		)
		(min_thickness 0.25)
		(keepout
			(tracks not_allowed)
			(vias allowed)
			(pads allowed)
			(copperpour not_allowed)
			(footprints allowed)
		)
		(placement
			(enabled no)
			(sheetname "")
		)
		(fill yes
			(thermal_gap 0.5)
			(thermal_bridge_width 0.5)
			(island_removal_mode 0)
		)
		(polygon
			(pts
				(arc
					(start 17.942052 -286.585406)
					(mid 17.274032 -286.585406)
					(end 17.942052 -286.585406)
				)
			)
		)
	)
	(zone
		(layers "B.Cu" "In13.Cu" "In15.Cu")
		(hatch none 0.5)
		(connect_pads
			(clearance 0)
		)
		(min_thickness 0.25)
		(keepout
			(tracks not_allowed)
			(vias allowed)
			(pads allowed)
			(copperpour not_allowed)
			(footprints allowed)
		)
		(placement
			(enabled no)
			(sheetname "")
		)
		(fill yes
			(thermal_gap 0.5)
			(thermal_bridge_width 0.5)
			(island_removal_mode 0)
		)
		(polygon
			(pts
				(arc
					(start 138.239754 -264.366248)
					(mid 137.609834 -264.366248)
					(end 138.239754 -264.366248)
				)
			)
		)
	)
	(zone
		(layers "B.Cu" "In13.Cu" "In15.Cu")
		(hatch none 0.5)
		(connect_pads
			(clearance 0)
		)
		(min_thickness 0.25)
		(keepout
			(tracks not_allowed)
			(vias allowed)
			(pads allowed)
			(copperpour not_allowed)
			(footprints allowed)
		)
		(placement
			(enabled no)
			(sheetname "")
		)
		(fill yes
			(thermal_gap 0.5)
			(thermal_bridge_width 0.5)
			(island_removal_mode 0)
		)
		(polygon
			(pts
				(arc
					(start 387.589776 -281.37612)
					(mid 386.959856 -281.37612)
					(end 387.589776 -281.37612)
				)
			)
		)
	)
	(zone
		(layers "B.Cu" "In13.Cu" "In15.Cu")
		(hatch none 0.5)
		(connect_pads
			(clearance 0)
		)
		(min_thickness 0.25)
		(keepout
			(tracks not_allowed)
			(vias allowed)
			(pads allowed)
			(copperpour not_allowed)
			(footprints allowed)
		)
		(placement
			(enabled no)
			(sheetname "")
		)
		(fill yes
			(thermal_gap 0.5)
			(thermal_bridge_width 0.5)
			(island_removal_mode 0)
		)
		(polygon
			(pts
				(arc
					(start 108.80598 -248.534428)
					(mid 108.17606 -248.534428)
					(end 108.80598 -248.534428)
				)
			)
		)
	)
	(zone
		(layers "B.Cu" "In13.Cu" "In15.Cu")
		(hatch none 0.5)
		(connect_pads
			(clearance 0)
		)
		(min_thickness 0.25)
		(keepout
			(tracks not_allowed)
			(vias allowed)
			(pads allowed)
			(copperpour not_allowed)
			(footprints allowed)
		)
		(placement
			(enabled no)
			(sheetname "")
		)
		(fill yes
			(thermal_gap 0.5)
			(thermal_bridge_width 0.5)
			(island_removal_mode 0)
		)
		(polygon
			(pts
				(arc
					(start 269.982188 -203.28509)
					(mid 269.314168 -203.28509)
					(end 269.982188 -203.28509)
				)
			)
		)
	)
	(zone
		(layers "B.Cu" "In13.Cu" "In15.Cu")
		(hatch none 0.5)
		(connect_pads
			(clearance 0)
		)
		(min_thickness 0.25)
		(keepout
			(tracks not_allowed)
			(vias allowed)
			(pads allowed)
			(copperpour not_allowed)
			(footprints allowed)
		)
		(placement
			(enabled no)
			(sheetname "")
		)
		(fill yes
			(thermal_gap 0.5)
			(thermal_bridge_width 0.5)
			(island_removal_mode 0)
		)
		(polygon
			(pts
				(arc
					(start 19.524472 -19.137122)
					(mid 18.856452 -19.137122)
					(end 19.524472 -19.137122)
				)
			)
		)
	)
	(zone
		(layers "B.Cu" "In13.Cu" "In15.Cu")
		(hatch none 0.5)
		(connect_pads
			(clearance 0)
		)
		(min_thickness 0.25)
		(keepout
			(tracks not_allowed)
			(vias allowed)
			(pads allowed)
			(copperpour not_allowed)
			(footprints allowed)
		)
		(placement
			(enabled no)
			(sheetname "")
		)
		(fill yes
			(thermal_gap 0.5)
			(thermal_bridge_width 0.5)
			(island_removal_mode 0)
		)
		(polygon
			(pts
				(arc
					(start 269.982188 -270.43507)
					(mid 269.314168 -270.43507)
					(end 269.982188 -270.43507)
				)
			)
		)
	)
	(zone
		(layers "B.Cu" "In13.Cu" "In15.Cu")
		(hatch none 0.5)
		(connect_pads
			(clearance 0)
		)
		(min_thickness 0.25)
		(keepout
			(tracks not_allowed)
			(vias allowed)
			(pads allowed)
			(copperpour not_allowed)
			(footprints allowed)
		)
		(placement
			(enabled no)
			(sheetname "")
		)
		(fill yes
			(thermal_gap 0.5)
			(thermal_bridge_width 0.5)
			(island_removal_mode 0)
		)
		(polygon
			(pts
				(arc
					(start 387.289802 -225.044254)
					(mid 386.659882 -225.044254)
					(end 387.289802 -225.044254)
				)
			)
		)
	)
	(zone
		(layers "B.Cu" "In13.Cu" "In15.Cu")
		(hatch none 0.5)
		(connect_pads
			(clearance 0)
		)
		(min_thickness 0.25)
		(keepout
			(tracks not_allowed)
			(vias allowed)
			(pads allowed)
			(copperpour not_allowed)
			(footprints allowed)
		)
		(placement
			(enabled no)
			(sheetname "")
		)
		(fill yes
			(thermal_gap 0.5)
			(thermal_bridge_width 0.5)
			(island_removal_mode 0)
		)
		(polygon
			(pts
				(arc
					(start 269.982188 -296.78503)
					(mid 269.314168 -296.78503)
					(end 269.982188 -296.78503)
				)
			)
		)
	)
	(zone
		(layers "B.Cu" "In13.Cu" "In15.Cu")
		(hatch none 0.5)
		(connect_pads
			(clearance 0)
		)
		(min_thickness 0.25)
		(keepout
			(tracks not_allowed)
			(vias allowed)
			(pads allowed)
			(copperpour not_allowed)
			(footprints allowed)
		)
		(placement
			(enabled no)
			(sheetname "")
		)
		(fill yes
			(thermal_gap 0.5)
			(thermal_bridge_width 0.5)
			(island_removal_mode 0)
		)
		(polygon
			(pts
				(arc
					(start 332.776068 -247.724168)
					(mid 332.146148 -247.724168)
					(end 332.776068 -247.724168)
				)
			)
		)
	)
	(zone
		(layers "B.Cu" "In13.Cu" "In15.Cu")
		(hatch none 0.5)
		(connect_pads
			(clearance 0)
		)
		(min_thickness 0.25)
		(keepout
			(tracks not_allowed)
			(vias allowed)
			(pads allowed)
			(copperpour not_allowed)
			(footprints allowed)
		)
		(placement
			(enabled no)
			(sheetname "")
		)
		(fill yes
			(thermal_gap 0.5)
			(thermal_bridge_width 0.5)
			(island_removal_mode 0)
		)
		(polygon
			(pts
				(arc
					(start 119.821706 -369.03533)
					(mid 119.153686 -369.03533)
					(end 119.821706 -369.03533)
				)
			)
		)
	)
	(zone
		(layers "B.Cu" "In13.Cu" "In15.Cu")
		(hatch none 0.5)
		(connect_pads
			(clearance 0)
		)
		(min_thickness 0.25)
		(keepout
			(tracks not_allowed)
			(vias allowed)
			(pads allowed)
			(copperpour not_allowed)
			(footprints allowed)
		)
		(placement
			(enabled no)
			(sheetname "")
		)
		(fill yes
			(thermal_gap 0.5)
			(thermal_bridge_width 0.5)
			(island_removal_mode 0)
		)
		(polygon
			(pts
				(arc
					(start 355.336094 -233.14406)
					(mid 354.706174 -233.14406)
					(end 355.336094 -233.14406)
				)
			)
		)
	)
	(zone
		(layers "B.Cu" "In13.Cu" "In15.Cu")
		(hatch none 0.5)
		(connect_pads
			(clearance 0)
		)
		(min_thickness 0.25)
		(keepout
			(tracks not_allowed)
			(vias allowed)
			(pads allowed)
			(copperpour not_allowed)
			(footprints allowed)
		)
		(placement
			(enabled no)
			(sheetname "")
		)
		(fill yes
			(thermal_gap 0.5)
			(thermal_bridge_width 0.5)
			(island_removal_mode 0)
		)
		(polygon
			(pts
				(arc
					(start 340.233762 -393.69238)
					(mid 339.603842 -393.69238)
					(end 340.233762 -393.69238)
				)
			)
		)
	)
	(zone
		(layers "B.Cu" "In13.Cu" "In15.Cu")
		(hatch none 0.5)
		(connect_pads
			(clearance 0)
		)
		(min_thickness 0.25)
		(keepout
			(tracks not_allowed)
			(vias allowed)
			(pads allowed)
			(copperpour not_allowed)
			(footprints allowed)
		)
		(placement
			(enabled no)
			(sheetname "")
		)
		(fill yes
			(thermal_gap 0.5)
			(thermal_bridge_width 0.5)
			(island_removal_mode 0)
		)
		(polygon
			(pts
				(arc
					(start 348.75597 -234.764072)
					(mid 348.12605 -234.764072)
					(end 348.75597 -234.764072)
				)
			)
		)
	)
	(zone
		(layers "B.Cu" "In13.Cu" "In15.Cu")
		(hatch none 0.5)
		(connect_pads
			(clearance 0)
		)
		(min_thickness 0.25)
		(keepout
			(tracks not_allowed)
			(vias allowed)
			(pads allowed)
			(copperpour not_allowed)
			(footprints allowed)
		)
		(placement
			(enabled no)
			(sheetname "")
		)
		(fill yes
			(thermal_gap 0.5)
			(thermal_bridge_width 0.5)
			(island_removal_mode 0)
		)
		(polygon
			(pts
				(arc
					(start 93.034104 -386.003292)
					(mid 92.404184 -386.003292)
					(end 93.034104 -386.003292)
				)
			)
		)
	)
	(zone
		(layers "B.Cu" "In13.Cu" "In15.Cu")
		(hatch none 0.5)
		(connect_pads
			(clearance 0)
		)
		(min_thickness 0.25)
		(keepout
			(tracks not_allowed)
			(vias allowed)
			(pads allowed)
			(copperpour not_allowed)
			(footprints allowed)
		)
		(placement
			(enabled no)
			(sheetname "")
		)
		(fill yes
			(thermal_gap 0.5)
			(thermal_bridge_width 0.5)
			(island_removal_mode 0)
		)
		(polygon
			(pts
				(arc
					(start 153.137108 -431.889916)
					(mid 152.362916 -431.889916)
					(end 153.137108 -431.889916)
				)
			)
		)
	)
	(zone
		(layers "B.Cu" "In13.Cu" "In15.Cu")
		(hatch none 0.5)
		(connect_pads
			(clearance 0)
		)
		(min_thickness 0.25)
		(keepout
			(tracks not_allowed)
			(vias allowed)
			(pads allowed)
			(copperpour not_allowed)
			(footprints allowed)
		)
		(placement
			(enabled no)
			(sheetname "")
		)
		(fill yes
			(thermal_gap 0.5)
			(thermal_bridge_width 0.5)
			(island_removal_mode 0)
		)
		(polygon
			(pts
				(arc
					(start 17.942052 -267.03528)
					(mid 17.274032 -267.03528)
					(end 17.942052 -267.03528)
				)
			)
		)
	)
	(zone
		(layers "B.Cu" "In13.Cu" "In15.Cu")
		(hatch none 0.5)
		(connect_pads
			(clearance 0)
		)
		(min_thickness 0.25)
		(keepout
			(tracks not_allowed)
			(vias allowed)
			(pads allowed)
			(copperpour not_allowed)
			(footprints allowed)
		)
		(placement
			(enabled no)
			(sheetname "")
		)
		(fill yes
			(thermal_gap 0.5)
			(thermal_bridge_width 0.5)
			(island_removal_mode 0)
		)
		(polygon
			(pts
				(arc
					(start 450.42201 -285.735014)
					(mid 449.75399 -285.735014)
					(end 450.42201 -285.735014)
				)
			)
		)
	)
	(zone
		(layers "B.Cu" "In13.Cu" "In15.Cu")
		(hatch none 0.5)
		(connect_pads
			(clearance 0)
		)
		(min_thickness 0.25)
		(keepout
			(tracks not_allowed)
			(vias allowed)
			(pads allowed)
			(copperpour not_allowed)
			(footprints allowed)
		)
		(placement
			(enabled no)
			(sheetname "")
		)
		(fill yes
			(thermal_gap 0.5)
			(thermal_bridge_width 0.5)
			(island_removal_mode 0)
		)
		(polygon
			(pts
				(arc
					(start 403.137116 -429.689768)
					(mid 402.362924 -429.689768)
					(end 403.137116 -429.689768)
				)
			)
		)
	)
	(zone
		(layers "B.Cu" "In13.Cu" "In15.Cu")
		(hatch none 0.5)
		(connect_pads
			(clearance 0)
		)
		(min_thickness 0.25)
		(keepout
			(tracks not_allowed)
			(vias allowed)
			(pads allowed)
			(copperpour not_allowed)
			(footprints allowed)
		)
		(placement
			(enabled no)
			(sheetname "")
		)
		(fill yes
			(thermal_gap 0.5)
			(thermal_bridge_width 0.5)
			(island_removal_mode 0)
		)
		(polygon
			(pts
				(arc
					(start 334.186022 -233.954066)
					(mid 333.556102 -233.954066)
					(end 334.186022 -233.954066)
				)
			)
		)
	)
	(zone
		(layers "B.Cu" "In13.Cu" "In15.Cu")
		(hatch none 0.5)
		(connect_pads
			(clearance 0)
		)
		(min_thickness 0.25)
		(keepout
			(tracks not_allowed)
			(vias allowed)
			(pads allowed)
			(copperpour not_allowed)
			(footprints allowed)
		)
		(placement
			(enabled no)
			(sheetname "")
		)
		(fill yes
			(thermal_gap 0.5)
			(thermal_bridge_width 0.5)
			(island_removal_mode 0)
		)
		(polygon
			(pts
				(arc
					(start 269.982188 -273.835114)
					(mid 269.314168 -273.835114)
					(end 269.982188 -273.835114)
				)
			)
		)
	)
	(zone
		(layers "B.Cu" "In13.Cu" "In15.Cu")
		(hatch none 0.5)
		(connect_pads
			(clearance 0)
		)
		(min_thickness 0.25)
		(keepout
			(tracks not_allowed)
			(vias allowed)
			(pads allowed)
			(copperpour not_allowed)
			(footprints allowed)
		)
		(placement
			(enabled no)
			(sheetname "")
		)
		(fill yes
			(thermal_gap 0.5)
			(thermal_bridge_width 0.5)
			(island_removal_mode 0)
		)
		(polygon
			(pts
				(arc
					(start 450.42201 -261.93496)
					(mid 449.75399 -261.93496)
					(end 450.42201 -261.93496)
				)
			)
		)
	)
	(zone
		(layers "B.Cu" "In13.Cu" "In15.Cu")
		(hatch none 0.5)
		(connect_pads
			(clearance 0)
		)
		(min_thickness 0.25)
		(keepout
			(tracks not_allowed)
			(vias allowed)
			(pads allowed)
			(copperpour not_allowed)
			(footprints allowed)
		)
		(placement
			(enabled no)
			(sheetname "")
		)
		(fill yes
			(thermal_gap 0.5)
			(thermal_bridge_width 0.5)
			(island_removal_mode 0)
		)
		(polygon
			(pts
				(arc
					(start 371.309646 -247.724168)
					(mid 370.679726 -247.724168)
					(end 371.309646 -247.724168)
				)
			)
		)
	)
	(zone
		(layers "B.Cu" "In13.Cu" "In15.Cu")
		(hatch none 0.5)
		(connect_pads
			(clearance 0)
		)
		(min_thickness 0.25)
		(keepout
			(tracks not_allowed)
			(vias allowed)
			(pads allowed)
			(copperpour not_allowed)
			(footprints allowed)
		)
		(placement
			(enabled no)
			(sheetname "")
		)
		(fill yes
			(thermal_gap 0.5)
			(thermal_bridge_width 0.5)
			(island_removal_mode 0)
		)
		(polygon
			(pts
				(arc
					(start 91.877134 -412.570168)
					(mid 91.209114 -412.570168)
					(end 91.877134 -412.570168)
				)
			)
		)
	)
	(zone
		(layers "B.Cu" "In13.Cu" "In15.Cu")
		(hatch none 0.5)
		(connect_pads
			(clearance 0)
		)
		(min_thickness 0.25)
		(keepout
			(tracks not_allowed)
			(vias allowed)
			(pads allowed)
			(copperpour not_allowed)
			(footprints allowed)
		)
		(placement
			(enabled no)
			(sheetname "")
		)
		(fill yes
			(thermal_gap 0.5)
			(thermal_bridge_width 0.5)
			(island_removal_mode 0)
		)
		(polygon
			(pts
				(arc
					(start 387.759702 -246.914162)
					(mid 387.129782 -246.914162)
					(end 387.759702 -246.914162)
				)
			)
		)
	)
	(zone
		(layers "B.Cu" "In13.Cu" "In15.Cu")
		(hatch none 0.5)
		(connect_pads
			(clearance 0)
		)
		(min_thickness 0.25)
		(keepout
			(tracks not_allowed)
			(vias allowed)
			(pads allowed)
			(copperpour not_allowed)
			(footprints allowed)
		)
		(placement
			(enabled no)
			(sheetname "")
		)
		(fill yes
			(thermal_gap 0.5)
			(thermal_bridge_width 0.5)
			(island_removal_mode 0)
		)
		(polygon
			(pts
				(arc
					(start 206.58201 -307.8353)
					(mid 205.91399 -307.8353)
					(end 206.58201 -307.8353)
				)
			)
		)
	)
	(zone
		(layers "B.Cu" "In13.Cu" "In15.Cu")
		(hatch none 0.5)
		(connect_pads
			(clearance 0)
		)
		(min_thickness 0.25)
		(keepout
			(tracks not_allowed)
			(vias allowed)
			(pads allowed)
			(copperpour not_allowed)
			(footprints allowed)
		)
		(placement
			(enabled no)
			(sheetname "")
		)
		(fill yes
			(thermal_gap 0.5)
			(thermal_bridge_width 0.5)
			(island_removal_mode 0)
		)
		(polygon
			(pts
				(arc
					(start 392.136884 -431.889916)
					(mid 391.362692 -431.889916)
					(end 392.136884 -431.889916)
				)
			)
		)
	)
	(zone
		(layers "B.Cu" "In13.Cu" "In15.Cu")
		(hatch none 0.5)
		(connect_pads
			(clearance 0)
		)
		(min_thickness 0.25)
		(keepout
			(tracks not_allowed)
			(vias allowed)
			(pads allowed)
			(copperpour not_allowed)
			(footprints allowed)
		)
		(placement
			(enabled no)
			(sheetname "")
		)
		(fill yes
			(thermal_gap 0.5)
			(thermal_bridge_width 0.5)
			(island_removal_mode 0)
		)
		(polygon
			(pts
				(arc
					(start 332.606142 -288.66592)
					(mid 331.976222 -288.66592)
					(end 332.606142 -288.66592)
				)
			)
		)
	)
	(zone
		(layers "B.Cu" "In13.Cu" "In15.Cu")
		(hatch none 0.5)
		(connect_pads
			(clearance 0)
		)
		(min_thickness 0.25)
		(keepout
			(tracks not_allowed)
			(vias allowed)
			(pads allowed)
			(copperpour not_allowed)
			(footprints allowed)
		)
		(placement
			(enabled no)
			(sheetname "")
		)
		(fill yes
			(thermal_gap 0.5)
			(thermal_bridge_width 0.5)
			(island_removal_mode 0)
		)
		(polygon
			(pts
				(arc
					(start 404.923752 -420.952168)
					(mid 404.255732 -420.952168)
					(end 404.923752 -420.952168)
				)
			)
		)
	)
	(zone
		(layers "B.Cu" "In13.Cu" "In15.Cu")
		(hatch none 0.5)
		(connect_pads
			(clearance 0)
		)
		(min_thickness 0.25)
		(keepout
			(tracks not_allowed)
			(vias allowed)
			(pads allowed)
			(copperpour not_allowed)
			(footprints allowed)
		)
		(placement
			(enabled no)
			(sheetname "")
		)
		(fill yes
			(thermal_gap 0.5)
			(thermal_bridge_width 0.5)
			(island_removal_mode 0)
		)
		(polygon
			(pts
				(arc
					(start 86.076028 -291.096192)
					(mid 85.446108 -291.096192)
					(end 86.076028 -291.096192)
				)
			)
		)
	)
	(zone
		(layers "B.Cu" "In13.Cu" "In15.Cu")
		(hatch none 0.5)
		(connect_pads
			(clearance 0)
		)
		(min_thickness 0.25)
		(keepout
			(tracks not_allowed)
			(vias allowed)
			(pads allowed)
			(copperpour not_allowed)
			(footprints allowed)
		)
		(placement
			(enabled no)
			(sheetname "")
		)
		(fill yes
			(thermal_gap 0.5)
			(thermal_bridge_width 0.5)
			(island_removal_mode 0)
		)
		(polygon
			(pts
				(arc
					(start 454.522078 -290.83508)
					(mid 453.854058 -290.83508)
					(end 454.522078 -290.83508)
				)
			)
		)
	)
	(zone
		(layers "B.Cu" "In13.Cu" "In15.Cu")
		(hatch none 0.5)
		(connect_pads
			(clearance 0)
		)
		(min_thickness 0.25)
		(keepout
			(tracks not_allowed)
			(vias allowed)
			(pads allowed)
			(copperpour not_allowed)
			(footprints allowed)
		)
		(placement
			(enabled no)
			(sheetname "")
		)
		(fill yes
			(thermal_gap 0.5)
			(thermal_bridge_width 0.5)
			(island_removal_mode 0)
		)
		(polygon
			(pts
				(arc
					(start 69.036946 -431.889916)
					(mid 68.262754 -431.889916)
					(end 69.036946 -431.889916)
				)
			)
		)
	)
	(zone
		(layers "B.Cu" "In13.Cu" "In15.Cu")
		(hatch none 0.5)
		(connect_pads
			(clearance 0)
		)
		(min_thickness 0.25)
		(keepout
			(tracks not_allowed)
			(vias allowed)
			(pads allowed)
			(copperpour not_allowed)
			(footprints allowed)
		)
		(placement
			(enabled no)
			(sheetname "")
		)
		(fill yes
			(thermal_gap 0.5)
			(thermal_bridge_width 0.5)
			(island_removal_mode 0)
		)
		(polygon
			(pts
				(arc
					(start 454.522078 -272.135092)
					(mid 453.854058 -272.135092)
					(end 454.522078 -272.135092)
				)
			)
		)
	)
	(zone
		(layers "B.Cu" "In13.Cu" "In15.Cu")
		(hatch none 0.5)
		(connect_pads
			(clearance 0)
		)
		(min_thickness 0.25)
		(keepout
			(tracks not_allowed)
			(vias allowed)
			(pads allowed)
			(copperpour not_allowed)
			(footprints allowed)
		)
		(placement
			(enabled no)
			(sheetname "")
		)
		(fill yes
			(thermal_gap 0.5)
			(thermal_bridge_width 0.5)
			(island_removal_mode 0)
		)
		(polygon
			(pts
				(arc
					(start 202.481942 -239.835436)
					(mid 201.813922 -239.835436)
					(end 202.481942 -239.835436)
				)
			)
		)
	)
	(zone
		(layers "B.Cu" "In13.Cu" "In15.Cu")
		(hatch none 0.5)
		(connect_pads
			(clearance 0)
		)
		(min_thickness 0.25)
		(keepout
			(tracks not_allowed)
			(vias allowed)
			(pads allowed)
			(copperpour not_allowed)
			(footprints allowed)
		)
		(placement
			(enabled no)
			(sheetname "")
		)
		(fill yes
			(thermal_gap 0.5)
			(thermal_bridge_width 0.5)
			(island_removal_mode 0)
		)
		(polygon
			(pts
				(arc
					(start 90.234008 -388.774432)
					(mid 89.604088 -388.774432)
					(end 90.234008 -388.774432)
				)
			)
		)
	)
	(zone
		(layers "B.Cu" "In13.Cu" "In15.Cu")
		(hatch none 0.5)
		(connect_pads
			(clearance 0)
		)
		(min_thickness 0.25)
		(keepout
			(tracks not_allowed)
			(vias allowed)
			(pads allowed)
			(copperpour not_allowed)
			(footprints allowed)
		)
		(placement
			(enabled no)
			(sheetname "")
		)
		(fill yes
			(thermal_gap 0.5)
			(thermal_bridge_width 0.5)
			(island_removal_mode 0)
		)
		(polygon
			(pts
				(arc
					(start 84.836 -225.044508)
					(mid 84.20608 -225.044508)
					(end 84.836 -225.044508)
				)
			)
		)
	)
	(zone
		(layers "B.Cu" "In13.Cu" "In15.Cu")
		(hatch none 0.5)
		(connect_pads
			(clearance 0)
		)
		(min_thickness 0.25)
		(keepout
			(tracks not_allowed)
			(vias allowed)
			(pads allowed)
			(copperpour not_allowed)
			(footprints allowed)
		)
		(placement
			(enabled no)
			(sheetname "")
		)
		(fill yes
			(thermal_gap 0.5)
			(thermal_bridge_width 0.5)
			(island_removal_mode 0)
		)
		(polygon
			(pts
				(arc
					(start 17.942052 -248.335292)
					(mid 17.274032 -248.335292)
					(end 17.942052 -248.335292)
				)
			)
		)
	)
	(zone
		(layers "B.Cu" "In13.Cu" "In15.Cu")
		(hatch none 0.5)
		(connect_pads
			(clearance 0)
		)
		(min_thickness 0.25)
		(keepout
			(tracks not_allowed)
			(vias allowed)
			(pads allowed)
			(copperpour not_allowed)
			(footprints allowed)
		)
		(placement
			(enabled no)
			(sheetname "")
		)
		(fill yes
			(thermal_gap 0.5)
			(thermal_bridge_width 0.5)
			(island_removal_mode 0)
		)
		(polygon
			(pts
				(arc
					(start 424.969686 -6.725158)
					(mid 424.301666 -6.725158)
					(end 424.969686 -6.725158)
				)
			)
		)
	)
	(zone
		(layers "B.Cu" "In13.Cu" "In15.Cu")
		(hatch none 0.5)
		(connect_pads
			(clearance 0)
		)
		(min_thickness 0.25)
		(keepout
			(tracks not_allowed)
			(vias allowed)
			(pads allowed)
			(copperpour not_allowed)
			(footprints allowed)
		)
		(placement
			(enabled no)
			(sheetname "")
		)
		(fill yes
			(thermal_gap 0.5)
			(thermal_bridge_width 0.5)
			(island_removal_mode 0)
		)
		(polygon
			(pts
				(arc
					(start 84.666074 -280.566368)
					(mid 84.036154 -280.566368)
					(end 84.666074 -280.566368)
				)
			)
		)
	)
	(zone
		(layers "B.Cu" "In13.Cu" "In15.Cu")
		(hatch none 0.5)
		(connect_pads
			(clearance 0)
		)
		(min_thickness 0.25)
		(keepout
			(tracks not_allowed)
			(vias allowed)
			(pads allowed)
			(copperpour not_allowed)
			(footprints allowed)
		)
		(placement
			(enabled no)
			(sheetname "")
		)
		(fill yes
			(thermal_gap 0.5)
			(thermal_bridge_width 0.5)
			(island_removal_mode 0)
		)
		(polygon
			(pts
				(arc
					(start 84.03717 -430.889918)
					(mid 83.262978 -430.889918)
					(end 84.03717 -430.889918)
				)
			)
		)
	)
	(zone
		(layers "B.Cu" "In13.Cu" "In15.Cu")
		(hatch none 0.5)
		(connect_pads
			(clearance 0)
		)
		(min_thickness 0.25)
		(keepout
			(tracks not_allowed)
			(vias allowed)
			(pads allowed)
			(copperpour not_allowed)
			(footprints allowed)
		)
		(placement
			(enabled no)
			(sheetname "")
		)
		(fill yes
			(thermal_gap 0.5)
			(thermal_bridge_width 0.5)
			(island_removal_mode 0)
		)
		(polygon
			(pts
				(arc
					(start 117.729762 -231.524302)
					(mid 117.099842 -231.524302)
					(end 117.729762 -231.524302)
				)
			)
		)
	)
	(zone
		(layers "B.Cu" "In13.Cu" "In15.Cu")
		(hatch none 0.5)
		(connect_pads
			(clearance 0)
		)
		(min_thickness 0.25)
		(keepout
			(tracks not_allowed)
			(vias allowed)
			(pads allowed)
			(copperpour not_allowed)
			(footprints allowed)
		)
		(placement
			(enabled no)
			(sheetname "")
		)
		(fill yes
			(thermal_gap 0.5)
			(thermal_bridge_width 0.5)
			(island_removal_mode 0)
		)
		(polygon
			(pts
				(arc
					(start 97.995994 -247.724422)
					(mid 97.366074 -247.724422)
					(end 97.995994 -247.724422)
				)
			)
		)
	)
	(zone
		(layers "B.Cu" "In13.Cu" "In15.Cu")
		(hatch none 0.5)
		(connect_pads
			(clearance 0)
		)
		(min_thickness 0.25)
		(keepout
			(tracks not_allowed)
			(vias allowed)
			(pads allowed)
			(copperpour not_allowed)
			(footprints allowed)
		)
		(placement
			(enabled no)
			(sheetname "")
		)
		(fill yes
			(thermal_gap 0.5)
			(thermal_bridge_width 0.5)
			(island_removal_mode 0)
		)
		(polygon
			(pts
				(arc
					(start 39.082472 -17.613122)
					(mid 38.414452 -17.613122)
					(end 39.082472 -17.613122)
				)
			)
		)
	)
	(zone
		(layers "B.Cu" "In13.Cu" "In15.Cu")
		(hatch none 0.5)
		(connect_pads
			(clearance 0)
		)
		(min_thickness 0.25)
		(keepout
			(tracks not_allowed)
			(vias allowed)
			(pads allowed)
			(copperpour not_allowed)
			(footprints allowed)
		)
		(placement
			(enabled no)
			(sheetname "")
		)
		(fill yes
			(thermal_gap 0.5)
			(thermal_bridge_width 0.5)
			(island_removal_mode 0)
		)
		(polygon
			(pts
				(arc
					(start 368.489738 -246.104156)
					(mid 367.859818 -246.104156)
					(end 368.489738 -246.104156)
				)
			)
		)
	)
	(zone
		(layers "B.Cu" "In13.Cu" "In15.Cu")
		(hatch none 0.5)
		(connect_pads
			(clearance 0)
		)
		(min_thickness 0.25)
		(keepout
			(tracks not_allowed)
			(vias allowed)
			(pads allowed)
			(copperpour not_allowed)
			(footprints allowed)
		)
		(placement
			(enabled no)
			(sheetname "")
		)
		(fill yes
			(thermal_gap 0.5)
			(thermal_bridge_width 0.5)
			(island_removal_mode 0)
		)
		(polygon
			(pts
				(arc
					(start 139.349734 -255.824482)
					(mid 138.719814 -255.824482)
					(end 139.349734 -255.824482)
				)
			)
		)
	)
	(zone
		(layers "B.Cu" "In13.Cu" "In15.Cu")
		(hatch none 0.5)
		(connect_pads
			(clearance 0)
		)
		(min_thickness 0.25)
		(keepout
			(tracks not_allowed)
			(vias allowed)
			(pads allowed)
			(copperpour not_allowed)
			(footprints allowed)
		)
		(placement
			(enabled no)
			(sheetname "")
		)
		(fill yes
			(thermal_gap 0.5)
			(thermal_bridge_width 0.5)
			(island_removal_mode 0)
		)
		(polygon
			(pts
				(arc
					(start 22.04212 -206.685388)
					(mid 21.3741 -206.685388)
					(end 22.04212 -206.685388)
				)
			)
		)
	)
	(zone
		(layers "B.Cu" "In13.Cu" "In15.Cu")
		(hatch none 0.5)
		(connect_pads
			(clearance 0)
		)
		(min_thickness 0.25)
		(keepout
			(tracks not_allowed)
			(vias allowed)
			(pads allowed)
			(copperpour not_allowed)
			(footprints allowed)
		)
		(placement
			(enabled no)
			(sheetname "")
		)
		(fill yes
			(thermal_gap 0.5)
			(thermal_bridge_width 0.5)
			(island_removal_mode 0)
		)
		(polygon
			(pts
				(arc
					(start 364.86465 -384.35026)
					(mid 364.19663 -384.35026)
					(end 364.86465 -384.35026)
				)
			)
		)
	)
	(zone
		(layers "B.Cu" "In13.Cu" "In15.Cu")
		(hatch none 0.5)
		(connect_pads
			(clearance 0)
		)
		(min_thickness 0.25)
		(keepout
			(tracks not_allowed)
			(vias allowed)
			(pads allowed)
			(copperpour not_allowed)
			(footprints allowed)
		)
		(placement
			(enabled no)
			(sheetname "")
		)
		(fill yes
			(thermal_gap 0.5)
			(thermal_bridge_width 0.5)
			(island_removal_mode 0)
		)
		(polygon
			(pts
				(arc
					(start 387.289802 -254.204216)
					(mid 386.659882 -254.204216)
					(end 387.289802 -254.204216)
				)
			)
		)
	)
	(zone
		(layers "B.Cu" "In13.Cu" "In15.Cu")
		(hatch none 0.5)
		(connect_pads
			(clearance 0)
		)
		(min_thickness 0.25)
		(keepout
			(tracks not_allowed)
			(vias allowed)
			(pads allowed)
			(copperpour not_allowed)
			(footprints allowed)
		)
		(placement
			(enabled no)
			(sheetname "")
		)
		(fill yes
			(thermal_gap 0.5)
			(thermal_bridge_width 0.5)
			(island_removal_mode 0)
		)
		(polygon
			(pts
				(arc
					(start 386.179822 -274.086066)
					(mid 385.549902 -274.086066)
					(end 386.179822 -274.086066)
				)
			)
		)
	)
	(zone
		(layers "B.Cu" "In13.Cu" "In15.Cu")
		(hatch none 0.5)
		(connect_pads
			(clearance 0)
		)
		(min_thickness 0.25)
		(keepout
			(tracks not_allowed)
			(vias allowed)
			(pads allowed)
			(copperpour not_allowed)
			(footprints allowed)
		)
		(placement
			(enabled no)
			(sheetname "")
		)
		(fill yes
			(thermal_gap 0.5)
			(thermal_bridge_width 0.5)
			(island_removal_mode 0)
		)
		(polygon
			(pts
				(arc
					(start 454.522078 -261.085076)
					(mid 453.854058 -261.085076)
					(end 454.522078 -261.085076)
				)
			)
		)
	)
	(zone
		(layers "B.Cu" "In13.Cu" "In15.Cu")
		(hatch none 0.5)
		(connect_pads
			(clearance 0)
		)
		(min_thickness 0.25)
		(keepout
			(tracks not_allowed)
			(vias allowed)
			(pads allowed)
			(copperpour not_allowed)
			(footprints allowed)
		)
		(placement
			(enabled no)
			(sheetname "")
		)
		(fill yes
			(thermal_gap 0.5)
			(thermal_bridge_width 0.5)
			(island_removal_mode 0)
		)
		(polygon
			(pts
				(arc
					(start 334.016096 -284.616144)
					(mid 333.386176 -284.616144)
					(end 334.016096 -284.616144)
				)
			)
		)
	)
	(zone
		(layers "B.Cu" "In13.Cu" "In15.Cu")
		(hatch none 0.5)
		(connect_pads
			(clearance 0)
		)
		(min_thickness 0.25)
		(keepout
			(tracks not_allowed)
			(vias allowed)
			(pads allowed)
			(copperpour not_allowed)
			(footprints allowed)
		)
		(placement
			(enabled no)
			(sheetname "")
		)
		(fill yes
			(thermal_gap 0.5)
			(thermal_bridge_width 0.5)
			(island_removal_mode 0)
		)
		(polygon
			(pts
				(arc
					(start 304.991516 -420.952168)
					(mid 304.323496 -420.952168)
					(end 304.991516 -420.952168)
				)
			)
		)
	)
	(zone
		(layers "B.Cu" "In13.Cu" "In15.Cu")
		(hatch none 0.5)
		(connect_pads
			(clearance 0)
		)
		(min_thickness 0.25)
		(keepout
			(tracks not_allowed)
			(vias allowed)
			(pads allowed)
			(copperpour not_allowed)
			(footprints allowed)
		)
		(placement
			(enabled no)
			(sheetname "")
		)
		(fill yes
			(thermal_gap 0.5)
			(thermal_bridge_width 0.5)
			(island_removal_mode 0)
		)
		(polygon
			(pts
				(arc
					(start 337.823556 -420.952168)
					(mid 337.155536 -420.952168)
					(end 337.823556 -420.952168)
				)
			)
		)
	)
	(zone
		(layers "B.Cu" "In13.Cu" "In15.Cu")
		(hatch none 0.5)
		(connect_pads
			(clearance 0)
		)
		(min_thickness 0.25)
		(keepout
			(tracks not_allowed)
			(vias allowed)
			(pads allowed)
			(copperpour not_allowed)
			(footprints allowed)
		)
		(placement
			(enabled no)
			(sheetname "")
		)
		(fill yes
			(thermal_gap 0.5)
			(thermal_bridge_width 0.5)
			(island_removal_mode 0)
		)
		(polygon
			(pts
				(arc
					(start 454.522078 -219.435172)
					(mid 453.854058 -219.435172)
					(end 454.522078 -219.435172)
				)
			)
		)
	)
	(zone
		(layers "B.Cu" "In13.Cu" "In15.Cu")
		(hatch none 0.5)
		(connect_pads
			(clearance 0)
		)
		(min_thickness 0.25)
		(keepout
			(tracks not_allowed)
			(vias allowed)
			(pads allowed)
			(copperpour not_allowed)
			(footprints allowed)
		)
		(placement
			(enabled no)
			(sheetname "")
		)
		(fill yes
			(thermal_gap 0.5)
			(thermal_bridge_width 0.5)
			(island_removal_mode 0)
		)
		(polygon
			(pts
				(arc
					(start 269.982188 -223.6851)
					(mid 269.314168 -223.6851)
					(end 269.982188 -223.6851)
				)
			)
		)
	)
	(zone
		(layers "B.Cu" "In13.Cu" "In15.Cu")
		(hatch none 0.5)
		(connect_pads
			(clearance 0)
		)
		(min_thickness 0.25)
		(keepout
			(tracks not_allowed)
			(vias allowed)
			(pads allowed)
			(copperpour not_allowed)
			(footprints allowed)
		)
		(placement
			(enabled no)
			(sheetname "")
		)
		(fill yes
			(thermal_gap 0.5)
			(thermal_bridge_width 0.5)
			(island_removal_mode 0)
		)
		(polygon
			(pts
				(arc
					(start 85.750654 -412.570168)
					(mid 85.082634 -412.570168)
					(end 85.750654 -412.570168)
				)
			)
		)
	)
	(zone
		(layers "B.Cu" "In13.Cu" "In15.Cu")
		(hatch none 0.5)
		(connect_pads
			(clearance 0)
		)
		(min_thickness 0.25)
		(keepout
			(tracks not_allowed)
			(vias allowed)
			(pads allowed)
			(copperpour not_allowed)
			(footprints allowed)
		)
		(placement
			(enabled no)
			(sheetname "")
		)
		(fill yes
			(thermal_gap 0.5)
			(thermal_bridge_width 0.5)
			(island_removal_mode 0)
		)
		(polygon
			(pts
				(arc
					(start 450.42201 -316.335156)
					(mid 449.75399 -316.335156)
					(end 450.42201 -316.335156)
				)
			)
		)
	)
	(zone
		(layers "B.Cu" "In13.Cu" "In15.Cu")
		(hatch none 0.5)
		(connect_pads
			(clearance 0)
		)
		(min_thickness 0.25)
		(keepout
			(tracks not_allowed)
			(vias allowed)
			(pads allowed)
			(copperpour not_allowed)
			(footprints allowed)
		)
		(placement
			(enabled no)
			(sheetname "")
		)
		(fill yes
			(thermal_gap 0.5)
			(thermal_bridge_width 0.5)
			(island_removal_mode 0)
		)
		(polygon
			(pts
				(arc
					(start 139.349734 -236.384338)
					(mid 138.719814 -236.384338)
					(end 139.349734 -236.384338)
				)
			)
		)
	)
	(zone
		(layers "B.Cu" "In13.Cu" "In15.Cu")
		(hatch none 0.5)
		(connect_pads
			(clearance 0)
		)
		(min_thickness 0.25)
		(keepout
			(tracks not_allowed)
			(vias allowed)
			(pads allowed)
			(copperpour not_allowed)
			(footprints allowed)
		)
		(placement
			(enabled no)
			(sheetname "")
		)
		(fill yes
			(thermal_gap 0.5)
			(thermal_bridge_width 0.5)
			(island_removal_mode 0)
		)
		(polygon
			(pts
				(arc
					(start 17.942052 -207.535272)
					(mid 17.274032 -207.535272)
					(end 17.942052 -207.535272)
				)
			)
		)
	)
	(zone
		(layers "B.Cu" "In13.Cu" "In15.Cu")
		(hatch none 0.5)
		(connect_pads
			(clearance 0)
		)
		(min_thickness 0.25)
		(keepout
			(tracks not_allowed)
			(vias allowed)
			(pads allowed)
			(copperpour not_allowed)
			(footprints allowed)
		)
		(placement
			(enabled no)
			(sheetname "")
		)
		(fill yes
			(thermal_gap 0.5)
			(thermal_bridge_width 0.5)
			(island_removal_mode 0)
		)
		(polygon
			(pts
				(arc
					(start 35.425888 -19.13636)
					(mid 34.757868 -19.13636)
					(end 35.425888 -19.13636)
				)
			)
		)
	)
	(zone
		(layers "B.Cu" "In13.Cu" "In15.Cu")
		(hatch none 0.5)
		(connect_pads
			(clearance 0)
		)
		(min_thickness 0.25)
		(keepout
			(tracks not_allowed)
			(vias allowed)
			(pads allowed)
			(copperpour not_allowed)
			(footprints allowed)
		)
		(placement
			(enabled no)
			(sheetname "")
		)
		(fill yes
			(thermal_gap 0.5)
			(thermal_bridge_width 0.5)
			(island_removal_mode 0)
		)
		(polygon
			(pts
				(arc
					(start 396.597632 -420.952168)
					(mid 395.929612 -420.952168)
					(end 396.597632 -420.952168)
				)
			)
		)
	)
	(zone
		(layers "B.Cu" "In13.Cu" "In15.Cu")
		(hatch none 0.5)
		(connect_pads
			(clearance 0)
		)
		(min_thickness 0.25)
		(keepout
			(tracks not_allowed)
			(vias allowed)
			(pads allowed)
			(copperpour not_allowed)
			(footprints allowed)
		)
		(placement
			(enabled no)
			(sheetname "")
		)
		(fill yes
			(thermal_gap 0.5)
			(thermal_bridge_width 0.5)
			(island_removal_mode 0)
		)
		(polygon
			(pts
				(arc
					(start 63.036958 -429.689768)
					(mid 62.262766 -429.689768)
					(end 63.036958 -429.689768)
				)
			)
		)
	)
	(zone
		(layers "B.Cu" "In13.Cu" "In15.Cu")
		(hatch none 0.5)
		(connect_pads
			(clearance 0)
		)
		(min_thickness 0.25)
		(keepout
			(tracks not_allowed)
			(vias allowed)
			(pads allowed)
			(copperpour not_allowed)
			(footprints allowed)
		)
		(placement
			(enabled no)
			(sheetname "")
		)
		(fill yes
			(thermal_gap 0.5)
			(thermal_bridge_width 0.5)
			(island_removal_mode 0)
		)
		(polygon
			(pts
				(arc
					(start 357.686102 -235.574078)
					(mid 357.056182 -235.574078)
					(end 357.686102 -235.574078)
				)
			)
		)
	)
	(zone
		(layers "B.Cu" "In13.Cu" "In15.Cu")
		(hatch none 0.5)
		(connect_pads
			(clearance 0)
		)
		(min_thickness 0.25)
		(keepout
			(tracks not_allowed)
			(vias allowed)
			(pads allowed)
			(copperpour not_allowed)
			(footprints allowed)
		)
		(placement
			(enabled no)
			(sheetname "")
		)
		(fill yes
			(thermal_gap 0.5)
			(thermal_bridge_width 0.5)
			(island_removal_mode 0)
		)
		(polygon
			(pts
				(arc
					(start 385.879848 -243.674138)
					(mid 385.249928 -243.674138)
					(end 385.879848 -243.674138)
				)
			)
		)
	)
	(zone
		(layers "B.Cu" "In13.Cu" "In15.Cu")
		(hatch none 0.5)
		(connect_pads
			(clearance 0)
		)
		(min_thickness 0.25)
		(keepout
			(tracks not_allowed)
			(vias allowed)
			(pads allowed)
			(copperpour not_allowed)
			(footprints allowed)
		)
		(placement
			(enabled no)
			(sheetname "")
		)
		(fill yes
			(thermal_gap 0.5)
			(thermal_bridge_width 0.5)
			(island_removal_mode 0)
		)
		(polygon
			(pts
				(arc
					(start 450.42201 -280.634948)
					(mid 449.75399 -280.634948)
					(end 450.42201 -280.634948)
				)
			)
		)
	)
	(zone
		(layers "B.Cu" "In13.Cu" "In15.Cu")
		(hatch none 0.5)
		(connect_pads
			(clearance 0)
		)
		(min_thickness 0.25)
		(keepout
			(tracks not_allowed)
			(vias allowed)
			(pads allowed)
			(copperpour not_allowed)
			(footprints allowed)
		)
		(placement
			(enabled no)
			(sheetname "")
		)
		(fill yes
			(thermal_gap 0.5)
			(thermal_bridge_width 0.5)
			(island_removal_mode 0)
		)
		(polygon
			(pts
				(arc
					(start 365.02975 -278.136096)
					(mid 364.39983 -278.136096)
					(end 365.02975 -278.136096)
				)
			)
		)
	)
	(zone
		(layers "B.Cu" "In13.Cu" "In15.Cu")
		(hatch none 0.5)
		(connect_pads
			(clearance 0)
		)
		(min_thickness 0.25)
		(keepout
			(tracks not_allowed)
			(vias allowed)
			(pads allowed)
			(copperpour not_allowed)
			(footprints allowed)
		)
		(placement
			(enabled no)
			(sheetname "")
		)
		(fill yes
			(thermal_gap 0.5)
			(thermal_bridge_width 0.5)
			(island_removal_mode 0)
		)
		(polygon
			(pts
				(arc
					(start 22.04212 -313.78525)
					(mid 21.3741 -313.78525)
					(end 22.04212 -313.78525)
				)
			)
		)
	)
	(zone
		(layers "B.Cu" "In13.Cu" "In15.Cu")
		(hatch none 0.5)
		(connect_pads
			(clearance 0)
		)
		(min_thickness 0.25)
		(keepout
			(tracks not_allowed)
			(vias allowed)
			(pads allowed)
			(copperpour not_allowed)
			(footprints allowed)
		)
		(placement
			(enabled no)
			(sheetname "")
		)
		(fill yes
			(thermal_gap 0.5)
			(thermal_bridge_width 0.5)
			(island_removal_mode 0)
		)
		(polygon
			(pts
				(arc
					(start 202.481942 -304.435256)
					(mid 201.813922 -304.435256)
					(end 202.481942 -304.435256)
				)
			)
		)
	)
	(zone
		(layers "B.Cu" "In13.Cu" "In15.Cu")
		(hatch none 0.5)
		(connect_pads
			(clearance 0)
		)
		(min_thickness 0.25)
		(keepout
			(tracks not_allowed)
			(vias allowed)
			(pads allowed)
			(copperpour not_allowed)
			(footprints allowed)
		)
		(placement
			(enabled no)
			(sheetname "")
		)
		(fill yes
			(thermal_gap 0.5)
			(thermal_bridge_width 0.5)
			(island_removal_mode 0)
		)
		(polygon
			(pts
				(arc
					(start 122.361706 -373.96293)
					(mid 121.693686 -373.96293)
					(end 122.361706 -373.96293)
				)
			)
		)
	)
	(zone
		(layers "B.Cu" "In13.Cu" "In15.Cu")
		(hatch none 0.5)
		(connect_pads
			(clearance 0)
		)
		(min_thickness 0.25)
		(keepout
			(tracks not_allowed)
			(vias allowed)
			(pads allowed)
			(copperpour not_allowed)
			(footprints allowed)
		)
		(placement
			(enabled no)
			(sheetname "")
		)
		(fill yes
			(thermal_gap 0.5)
			(thermal_bridge_width 0.5)
			(island_removal_mode 0)
		)
		(polygon
			(pts
				(arc
					(start 332.776068 -228.284278)
					(mid 332.146148 -228.284278)
					(end 332.776068 -228.284278)
				)
			)
		)
	)
	(zone
		(layers "B.Cu" "In13.Cu" "In15.Cu")
		(hatch none 0.5)
		(connect_pads
			(clearance 0)
		)
		(min_thickness 0.25)
		(keepout
			(tracks not_allowed)
			(vias allowed)
			(pads allowed)
			(copperpour not_allowed)
			(footprints allowed)
		)
		(placement
			(enabled no)
			(sheetname "")
		)
		(fill yes
			(thermal_gap 0.5)
			(thermal_bridge_width 0.5)
			(island_removal_mode 0)
		)
		(polygon
			(pts
				(arc
					(start 334.186022 -225.85426)
					(mid 333.556102 -225.85426)
					(end 334.186022 -225.85426)
				)
			)
		)
	)
	(zone
		(layers "B.Cu" "In13.Cu" "In15.Cu")
		(hatch none 0.5)
		(connect_pads
			(clearance 0)
		)
		(min_thickness 0.25)
		(keepout
			(tracks not_allowed)
			(vias allowed)
			(pads allowed)
			(copperpour not_allowed)
			(footprints allowed)
		)
		(placement
			(enabled no)
			(sheetname "")
		)
		(fill yes
			(thermal_gap 0.5)
			(thermal_bridge_width 0.5)
			(island_removal_mode 0)
		)
		(polygon
			(pts
				(arc
					(start 388.059676 -269.22603)
					(mid 387.429756 -269.22603)
					(end 388.059676 -269.22603)
				)
			)
		)
	)
	(zone
		(layers "B.Cu" "In13.Cu" "In15.Cu")
		(hatch none 0.5)
		(connect_pads
			(clearance 0)
		)
		(min_thickness 0.25)
		(keepout
			(tracks not_allowed)
			(vias allowed)
			(pads allowed)
			(copperpour not_allowed)
			(footprints allowed)
		)
		(placement
			(enabled no)
			(sheetname "")
		)
		(fill yes
			(thermal_gap 0.5)
			(thermal_bridge_width 0.5)
			(island_removal_mode 0)
		)
		(polygon
			(pts
				(arc
					(start 206.58201 -245.785386)
					(mid 205.91399 -245.785386)
					(end 206.58201 -245.785386)
				)
			)
		)
	)
	(zone
		(layers "B.Cu" "In13.Cu" "In15.Cu")
		(hatch none 0.5)
		(connect_pads
			(clearance 0)
		)
		(min_thickness 0.25)
		(keepout
			(tracks not_allowed)
			(vias allowed)
			(pads allowed)
			(copperpour not_allowed)
			(footprints allowed)
		)
		(placement
			(enabled no)
			(sheetname "")
		)
		(fill yes
			(thermal_gap 0.5)
			(thermal_bridge_width 0.5)
			(island_removal_mode 0)
		)
		(polygon
			(pts
				(arc
					(start 352.516186 -233.14406)
					(mid 351.886266 -233.14406)
					(end 352.516186 -233.14406)
				)
			)
		)
	)
	(zone
		(layers "B.Cu" "In13.Cu" "In15.Cu")
		(hatch none 0.5)
		(connect_pads
			(clearance 0)
		)
		(min_thickness 0.25)
		(keepout
			(tracks not_allowed)
			(vias allowed)
			(pads allowed)
			(copperpour not_allowed)
			(footprints allowed)
		)
		(placement
			(enabled no)
			(sheetname "")
		)
		(fill yes
			(thermal_gap 0.5)
			(thermal_bridge_width 0.5)
			(island_removal_mode 0)
		)
		(polygon
			(pts
				(arc
					(start 67.03695 -430.889918)
					(mid 66.262758 -430.889918)
					(end 67.03695 -430.889918)
				)
			)
		)
	)
	(zone
		(layers "B.Cu" "In13.Cu" "In15.Cu")
		(hatch none 0.5)
		(connect_pads
			(clearance 0)
		)
		(min_thickness 0.25)
		(keepout
			(tracks not_allowed)
			(vias allowed)
			(pads allowed)
			(copperpour not_allowed)
			(footprints allowed)
		)
		(placement
			(enabled no)
			(sheetname "")
		)
		(fill yes
			(thermal_gap 0.5)
			(thermal_bridge_width 0.5)
			(island_removal_mode 0)
		)
		(polygon
			(pts
				(arc
					(start 329.497436 -420.952168)
					(mid 328.829416 -420.952168)
					(end 329.497436 -420.952168)
				)
			)
		)
	)
	(zone
		(layers "B.Cu" "In13.Cu" "In15.Cu")
		(hatch none 0.5)
		(connect_pads
			(clearance 0)
		)
		(min_thickness 0.25)
		(keepout
			(tracks not_allowed)
			(vias allowed)
			(pads allowed)
			(copperpour not_allowed)
			(footprints allowed)
		)
		(placement
			(enabled no)
			(sheetname "")
		)
		(fill yes
			(thermal_gap 0.5)
			(thermal_bridge_width 0.5)
			(island_removal_mode 0)
		)
		(polygon
			(pts
				(arc
					(start 269.982188 -200.735184)
					(mid 269.314168 -200.735184)
					(end 269.982188 -200.735184)
				)
			)
		)
	)
	(zone
		(layers "B.Cu" "In13.Cu" "In15.Cu")
		(hatch none 0.5)
		(connect_pads
			(clearance 0)
		)
		(min_thickness 0.25)
		(keepout
			(tracks not_allowed)
			(vias allowed)
			(pads allowed)
			(copperpour not_allowed)
			(footprints allowed)
		)
		(placement
			(enabled no)
			(sheetname "")
		)
		(fill yes
			(thermal_gap 0.5)
			(thermal_bridge_width 0.5)
			(island_removal_mode 0)
		)
		(polygon
			(pts
				(arc
					(start 76.037186 -430.889918)
					(mid 75.262994 -430.889918)
					(end 76.037186 -430.889918)
				)
			)
		)
	)
	(zone
		(layers "B.Cu" "In13.Cu" "In15.Cu")
		(hatch none 0.5)
		(connect_pads
			(clearance 0)
		)
		(min_thickness 0.25)
		(keepout
			(tracks not_allowed)
			(vias allowed)
			(pads allowed)
			(copperpour not_allowed)
			(footprints allowed)
		)
		(placement
			(enabled no)
			(sheetname "")
		)
		(fill yes
			(thermal_gap 0.5)
			(thermal_bridge_width 0.5)
			(island_removal_mode 0)
		)
		(polygon
			(pts
				(arc
					(start 371.554502 -382.34493)
					(mid 370.886482 -382.34493)
					(end 371.554502 -382.34493)
				)
			)
		)
	)
	(zone
		(layers "B.Cu" "In13.Cu" "In15.Cu")
		(hatch none 0.5)
		(connect_pads
			(clearance 0)
		)
		(min_thickness 0.25)
		(keepout
			(tracks not_allowed)
			(vias allowed)
			(pads allowed)
			(copperpour not_allowed)
			(footprints allowed)
		)
		(placement
			(enabled no)
			(sheetname "")
		)
		(fill yes
			(thermal_gap 0.5)
			(thermal_bridge_width 0.5)
			(island_removal_mode 0)
		)
		(polygon
			(pts
				(arc
					(start 393.534392 -420.952168)
					(mid 392.866372 -420.952168)
					(end 393.534392 -420.952168)
				)
			)
		)
	)
	(zone
		(layers "B.Cu" "In13.Cu" "In15.Cu")
		(hatch none 0.5)
		(connect_pads
			(clearance 0)
		)
		(min_thickness 0.25)
		(keepout
			(tracks not_allowed)
			(vias allowed)
			(pads allowed)
			(copperpour not_allowed)
			(footprints allowed)
		)
		(placement
			(enabled no)
			(sheetname "")
		)
		(fill yes
			(thermal_gap 0.5)
			(thermal_bridge_width 0.5)
			(island_removal_mode 0)
		)
		(polygon
			(pts
				(arc
					(start 85.135974 -270.03629)
					(mid 84.506054 -270.03629)
					(end 85.135974 -270.03629)
				)
			)
		)
	)
	(zone
		(layers "B.Cu" "In13.Cu" "In15.Cu")
		(hatch none 0.5)
		(connect_pads
			(clearance 0)
		)
		(min_thickness 0.25)
		(keepout
			(tracks not_allowed)
			(vias allowed)
			(pads allowed)
			(copperpour not_allowed)
			(footprints allowed)
		)
		(placement
			(enabled no)
			(sheetname "")
		)
		(fill yes
			(thermal_gap 0.5)
			(thermal_bridge_width 0.5)
			(island_removal_mode 0)
		)
		(polygon
			(pts
				(arc
					(start 352.81616 -278.136096)
					(mid 352.18624 -278.136096)
					(end 352.81616 -278.136096)
				)
			)
		)
	)
	(zone
		(layers "B.Cu" "In13.Cu" "In15.Cu")
		(hatch none 0.5)
		(connect_pads
			(clearance 0)
		)
		(min_thickness 0.25)
		(keepout
			(tracks not_allowed)
			(vias allowed)
			(pads allowed)
			(copperpour not_allowed)
			(footprints allowed)
		)
		(placement
			(enabled no)
			(sheetname "")
		)
		(fill yes
			(thermal_gap 0.5)
			(thermal_bridge_width 0.5)
			(island_removal_mode 0)
		)
		(polygon
			(pts
				(arc
					(start 356.746048 -232.334054)
					(mid 356.116128 -232.334054)
					(end 356.746048 -232.334054)
				)
			)
		)
	)
	(zone
		(layers "B.Cu" "In13.Cu" "In15.Cu")
		(hatch none 0.5)
		(connect_pads
			(clearance 0)
		)
		(min_thickness 0.25)
		(keepout
			(tracks not_allowed)
			(vias allowed)
			(pads allowed)
			(copperpour not_allowed)
			(footprints allowed)
		)
		(placement
			(enabled no)
			(sheetname "")
		)
		(fill yes
			(thermal_gap 0.5)
			(thermal_bridge_width 0.5)
			(island_removal_mode 0)
		)
		(polygon
			(pts
				(arc
					(start 349.696024 -233.14406)
					(mid 349.066104 -233.14406)
					(end 349.696024 -233.14406)
				)
			)
		)
	)
	(zone
		(layers "B.Cu" "In13.Cu" "In15.Cu")
		(hatch none 0.5)
		(connect_pads
			(clearance 0)
		)
		(min_thickness 0.25)
		(keepout
			(tracks not_allowed)
			(vias allowed)
			(pads allowed)
			(copperpour not_allowed)
			(footprints allowed)
		)
		(placement
			(enabled no)
			(sheetname "")
		)
		(fill yes
			(thermal_gap 0.5)
			(thermal_bridge_width 0.5)
			(island_removal_mode 0)
		)
		(polygon
			(pts
				(arc
					(start 85.135974 -286.23641)
					(mid 84.506054 -286.23641)
					(end 85.135974 -286.23641)
				)
			)
		)
	)
	(zone
		(layers "B.Cu" "In13.Cu" "In15.Cu")
		(hatch none 0.5)
		(connect_pads
			(clearance 0)
		)
		(min_thickness 0.25)
		(keepout
			(tracks not_allowed)
			(vias allowed)
			(pads allowed)
			(copperpour not_allowed)
			(footprints allowed)
		)
		(placement
			(enabled no)
			(sheetname "")
		)
		(fill yes
			(thermal_gap 0.5)
			(thermal_bridge_width 0.5)
			(island_removal_mode 0)
		)
		(polygon
			(pts
				(arc
					(start 86.245954 -250.15444)
					(mid 85.616034 -250.15444)
					(end 86.245954 -250.15444)
				)
			)
		)
	)
	(zone
		(layers "B.Cu" "In13.Cu" "In15.Cu")
		(hatch none 0.5)
		(connect_pads
			(clearance 0)
		)
		(min_thickness 0.25)
		(keepout
			(tracks not_allowed)
			(vias allowed)
			(pads allowed)
			(copperpour not_allowed)
			(footprints allowed)
		)
		(placement
			(enabled no)
			(sheetname "")
		)
		(fill yes
			(thermal_gap 0.5)
			(thermal_bridge_width 0.5)
			(island_removal_mode 0)
		)
		(polygon
			(pts
				(arc
					(start 133.436106 -369.03533)
					(mid 132.768086 -369.03533)
					(end 133.436106 -369.03533)
				)
			)
		)
	)
	(zone
		(layers "B.Cu" "In13.Cu" "In15.Cu")
		(hatch none 0.5)
		(connect_pads
			(clearance 0)
		)
		(min_thickness 0.25)
		(keepout
			(tracks not_allowed)
			(vias allowed)
			(pads allowed)
			(copperpour not_allowed)
			(footprints allowed)
		)
		(placement
			(enabled no)
			(sheetname "")
		)
		(fill yes
			(thermal_gap 0.5)
			(thermal_bridge_width 0.5)
			(island_removal_mode 0)
		)
		(polygon
			(pts
				(arc
					(start 386.179822 -262.745982)
					(mid 385.549902 -262.745982)
					(end 386.179822 -262.745982)
				)
			)
		)
	)
	(zone
		(layers "B.Cu" "In13.Cu" "In15.Cu")
		(hatch none 0.5)
		(connect_pads
			(clearance 0)
		)
		(min_thickness 0.25)
		(keepout
			(tracks not_allowed)
			(vias allowed)
			(pads allowed)
			(copperpour not_allowed)
			(footprints allowed)
		)
		(placement
			(enabled no)
			(sheetname "")
		)
		(fill yes
			(thermal_gap 0.5)
			(thermal_bridge_width 0.5)
			(island_removal_mode 0)
		)
		(polygon
			(pts
				(arc
					(start 334.485996 -272.466054)
					(mid 333.856076 -272.466054)
					(end 334.485996 -272.466054)
				)
			)
		)
	)
	(zone
		(layers "B.Cu" "In13.Cu" "In15.Cu")
		(hatch none 0.5)
		(connect_pads
			(clearance 0)
		)
		(min_thickness 0.25)
		(keepout
			(tracks not_allowed)
			(vias allowed)
			(pads allowed)
			(copperpour not_allowed)
			(footprints allowed)
		)
		(placement
			(enabled no)
			(sheetname "")
		)
		(fill yes
			(thermal_gap 0.5)
			(thermal_bridge_width 0.5)
			(island_removal_mode 0)
		)
		(polygon
			(pts
				(arc
					(start 386.649722 -287.856168)
					(mid 386.019802 -287.856168)
					(end 386.649722 -287.856168)
				)
			)
		)
	)
	(zone
		(layers "B.Cu" "In13.Cu" "In15.Cu")
		(hatch none 0.5)
		(connect_pads
			(clearance 0)
		)
		(min_thickness 0.25)
		(keepout
			(tracks not_allowed)
			(vias allowed)
			(pads allowed)
			(copperpour not_allowed)
			(footprints allowed)
		)
		(placement
			(enabled no)
			(sheetname "")
		)
		(fill yes
			(thermal_gap 0.5)
			(thermal_bridge_width 0.5)
			(island_removal_mode 0)
		)
		(polygon
			(pts
				(arc
					(start 386.649722 -282.996132)
					(mid 386.019802 -282.996132)
					(end 386.649722 -282.996132)
				)
			)
		)
	)
	(zone
		(layers "B.Cu" "In13.Cu" "In15.Cu")
		(hatch none 0.5)
		(connect_pads
			(clearance 0)
		)
		(min_thickness 0.25)
		(keepout
			(tracks not_allowed)
			(vias allowed)
			(pads allowed)
			(copperpour not_allowed)
			(footprints allowed)
		)
		(placement
			(enabled no)
			(sheetname "")
		)
		(fill yes
			(thermal_gap 0.5)
			(thermal_bridge_width 0.5)
			(island_removal_mode 0)
		)
		(polygon
			(pts
				(arc
					(start 450.42201 -227.935028)
					(mid 449.75399 -227.935028)
					(end 450.42201 -227.935028)
				)
			)
		)
	)
	(zone
		(layers "B.Cu" "In13.Cu" "In15.Cu")
		(hatch none 0.5)
		(connect_pads
			(clearance 0)
		)
		(min_thickness 0.25)
		(keepout
			(tracks not_allowed)
			(vias allowed)
			(pads allowed)
			(copperpour not_allowed)
			(footprints allowed)
		)
		(placement
			(enabled no)
			(sheetname "")
		)
		(fill yes
			(thermal_gap 0.5)
			(thermal_bridge_width 0.5)
			(island_removal_mode 0)
		)
		(polygon
			(pts
				(arc
					(start 125.281436 -412.570168)
					(mid 124.613416 -412.570168)
					(end 125.281436 -412.570168)
				)
			)
		)
	)
	(zone
		(layers "B.Cu" "In13.Cu" "In15.Cu")
		(hatch none 0.5)
		(connect_pads
			(clearance 0)
		)
		(min_thickness 0.25)
		(keepout
			(tracks not_allowed)
			(vias allowed)
			(pads allowed)
			(copperpour not_allowed)
			(footprints allowed)
		)
		(placement
			(enabled no)
			(sheetname "")
		)
		(fill yes
			(thermal_gap 0.5)
			(thermal_bridge_width 0.5)
			(island_removal_mode 0)
		)
		(polygon
			(pts
				(arc
					(start 387.589776 -271.656048)
					(mid 386.959856 -271.656048)
					(end 387.589776 -271.656048)
				)
			)
		)
	)
	(zone
		(layers "B.Cu" "In13.Cu" "In15.Cu")
		(hatch none 0.5)
		(connect_pads
			(clearance 0)
		)
		(min_thickness 0.25)
		(keepout
			(tracks not_allowed)
			(vias allowed)
			(pads allowed)
			(copperpour not_allowed)
			(footprints allowed)
		)
		(placement
			(enabled no)
			(sheetname "")
		)
		(fill yes
			(thermal_gap 0.5)
			(thermal_bridge_width 0.5)
			(island_removal_mode 0)
		)
		(polygon
			(pts
				(arc
					(start 67.03695 -429.689768)
					(mid 66.262758 -429.689768)
					(end 67.03695 -429.689768)
				)
			)
		)
	)
	(zone
		(layers "B.Cu" "In13.Cu" "In15.Cu")
		(hatch none 0.5)
		(connect_pads
			(clearance 0)
		)
		(min_thickness 0.25)
		(keepout
			(tracks not_allowed)
			(vias allowed)
			(pads allowed)
			(copperpour not_allowed)
			(footprints allowed)
		)
		(placement
			(enabled no)
			(sheetname "")
		)
		(fill yes
			(thermal_gap 0.5)
			(thermal_bridge_width 0.5)
			(island_removal_mode 0)
		)
		(polygon
			(pts
				(arc
					(start 385.879848 -250.154186)
					(mid 385.249928 -250.154186)
					(end 385.879848 -250.154186)
				)
			)
		)
	)
	(zone
		(layers "B.Cu" "In13.Cu" "In15.Cu")
		(hatch none 0.5)
		(connect_pads
			(clearance 0)
		)
		(min_thickness 0.25)
		(keepout
			(tracks not_allowed)
			(vias allowed)
			(pads allowed)
			(copperpour not_allowed)
			(footprints allowed)
		)
		(placement
			(enabled no)
			(sheetname "")
		)
		(fill yes
			(thermal_gap 0.5)
			(thermal_bridge_width 0.5)
			(island_removal_mode 0)
		)
		(polygon
			(pts
				(arc
					(start 265.88212 -304.435002)
					(mid 265.2141 -304.435002)
					(end 265.88212 -304.435002)
				)
			)
		)
	)
	(zone
		(layers "B.Cu" "In13.Cu" "In15.Cu")
		(hatch none 0.5)
		(connect_pads
			(clearance 0)
		)
		(min_thickness 0.25)
		(keepout
			(tracks not_allowed)
			(vias allowed)
			(pads allowed)
			(copperpour not_allowed)
			(footprints allowed)
		)
		(placement
			(enabled no)
			(sheetname "")
		)
		(fill yes
			(thermal_gap 0.5)
			(thermal_bridge_width 0.5)
			(island_removal_mode 0)
		)
		(polygon
			(pts
				(arc
					(start 17.942052 -205.83525)
					(mid 17.274032 -205.83525)
					(end 17.942052 -205.83525)
				)
			)
		)
	)
	(zone
		(layers "B.Cu" "In13.Cu" "In15.Cu")
		(hatch none 0.5)
		(connect_pads
			(clearance 0)
		)
		(min_thickness 0.25)
		(keepout
			(tracks not_allowed)
			(vias allowed)
			(pads allowed)
			(copperpour not_allowed)
			(footprints allowed)
		)
		(placement
			(enabled no)
			(sheetname "")
		)
		(fill yes
			(thermal_gap 0.5)
			(thermal_bridge_width 0.5)
			(island_removal_mode 0)
		)
		(polygon
			(pts
				(arc
					(start 99.034092 -389.467344)
					(mid 98.404172 -389.467344)
					(end 99.034092 -389.467344)
				)
			)
		)
	)
	(zone
		(layers "B.Cu" "In13.Cu" "In15.Cu")
		(hatch none 0.5)
		(connect_pads
			(clearance 0)
		)
		(min_thickness 0.25)
		(keepout
			(tracks not_allowed)
			(vias allowed)
			(pads allowed)
			(copperpour not_allowed)
			(footprints allowed)
		)
		(placement
			(enabled no)
			(sheetname "")
		)
		(fill yes
			(thermal_gap 0.5)
			(thermal_bridge_width 0.5)
			(island_removal_mode 0)
		)
		(polygon
			(pts
				(arc
					(start 362.679742 -275.706078)
					(mid 362.049822 -275.706078)
					(end 362.679742 -275.706078)
				)
			)
		)
	)
	(zone
		(layers "B.Cu" "In13.Cu" "In15.Cu")
		(hatch none 0.5)
		(connect_pads
			(clearance 0)
		)
		(min_thickness 0.25)
		(keepout
			(tracks not_allowed)
			(vias allowed)
			(pads allowed)
			(copperpour not_allowed)
			(footprints allowed)
		)
		(placement
			(enabled no)
			(sheetname "")
		)
		(fill yes
			(thermal_gap 0.5)
			(thermal_bridge_width 0.5)
			(island_removal_mode 0)
		)
		(polygon
			(pts
				(arc
					(start 138.40968 -250.964446)
					(mid 137.77976 -250.964446)
					(end 138.40968 -250.964446)
				)
			)
		)
	)
	(zone
		(layers "B.Cu" "In13.Cu" "In15.Cu")
		(hatch none 0.5)
		(connect_pads
			(clearance 0)
		)
		(min_thickness 0.25)
		(keepout
			(tracks not_allowed)
			(vias allowed)
			(pads allowed)
			(copperpour not_allowed)
			(footprints allowed)
		)
		(placement
			(enabled no)
			(sheetname "")
		)
		(fill yes
			(thermal_gap 0.5)
			(thermal_bridge_width 0.5)
			(island_removal_mode 0)
		)
		(polygon
			(pts
				(arc
					(start 394.713206 -6.725158)
					(mid 394.045186 -6.725158)
					(end 394.713206 -6.725158)
				)
			)
		)
	)
	(zone
		(layers "B.Cu" "In13.Cu" "In15.Cu")
		(hatch none 0.5)
		(connect_pads
			(clearance 0)
		)
		(min_thickness 0.25)
		(keepout
			(tracks not_allowed)
			(vias allowed)
			(pads allowed)
			(copperpour not_allowed)
			(footprints allowed)
		)
		(placement
			(enabled no)
			(sheetname "")
		)
		(fill yes
			(thermal_gap 0.5)
			(thermal_bridge_width 0.5)
			(island_removal_mode 0)
		)
		(polygon
			(pts
				(arc
					(start 206.58201 -315.485272)
					(mid 205.91399 -315.485272)
					(end 206.58201 -315.485272)
				)
			)
		)
	)
	(zone
		(layers "B.Cu" "In13.Cu" "In15.Cu")
		(hatch none 0.5)
		(connect_pads
			(clearance 0)
		)
		(min_thickness 0.25)
		(keepout
			(tracks not_allowed)
			(vias allowed)
			(pads allowed)
			(copperpour not_allowed)
			(footprints allowed)
		)
		(placement
			(enabled no)
			(sheetname "")
		)
		(fill yes
			(thermal_gap 0.5)
			(thermal_bridge_width 0.5)
			(island_removal_mode 0)
		)
		(polygon
			(pts
				(arc
					(start 85.833966 -386.003292)
					(mid 85.204046 -386.003292)
					(end 85.833966 -386.003292)
				)
			)
		)
	)
	(zone
		(layers "B.Cu" "In13.Cu" "In15.Cu")
		(hatch none 0.5)
		(connect_pads
			(clearance 0)
		)
		(min_thickness 0.25)
		(keepout
			(tracks not_allowed)
			(vias allowed)
			(pads allowed)
			(copperpour not_allowed)
			(footprints allowed)
		)
		(placement
			(enabled no)
			(sheetname "")
		)
		(fill yes
			(thermal_gap 0.5)
			(thermal_bridge_width 0.5)
			(island_removal_mode 0)
		)
		(polygon
			(pts
				(arc
					(start 368.789712 -278.136096)
					(mid 368.159792 -278.136096)
					(end 368.789712 -278.136096)
				)
			)
		)
	)
	(zone
		(layers "B.Cu" "In13.Cu" "In15.Cu")
		(hatch none 0.5)
		(connect_pads
			(clearance 0)
		)
		(min_thickness 0.25)
		(keepout
			(tracks not_allowed)
			(vias allowed)
			(pads allowed)
			(copperpour not_allowed)
			(footprints allowed)
		)
		(placement
			(enabled no)
			(sheetname "")
		)
		(fill yes
			(thermal_gap 0.5)
			(thermal_bridge_width 0.5)
			(island_removal_mode 0)
		)
		(polygon
			(pts
				(arc
					(start 333.076042 -263.555988)
					(mid 332.446122 -263.555988)
					(end 333.076042 -263.555988)
				)
			)
		)
	)
	(zone
		(layers "B.Cu" "In13.Cu" "In15.Cu")
		(hatch none 0.5)
		(connect_pads
			(clearance 0)
		)
		(min_thickness 0.25)
		(keepout
			(tracks not_allowed)
			(vias allowed)
			(pads allowed)
			(copperpour not_allowed)
			(footprints allowed)
		)
		(placement
			(enabled no)
			(sheetname "")
		)
		(fill yes
			(thermal_gap 0.5)
			(thermal_bridge_width 0.5)
			(island_removal_mode 0)
		)
		(polygon
			(pts
				(arc
					(start 386.349748 -231.524048)
					(mid 385.719828 -231.524048)
					(end 386.349748 -231.524048)
				)
			)
		)
	)
	(zone
		(layers "B.Cu" "In13.Cu" "In15.Cu")
		(hatch none 0.5)
		(connect_pads
			(clearance 0)
		)
		(min_thickness 0.25)
		(keepout
			(tracks not_allowed)
			(vias allowed)
			(pads allowed)
			(copperpour not_allowed)
			(footprints allowed)
		)
		(placement
			(enabled no)
			(sheetname "")
		)
		(fill yes
			(thermal_gap 0.5)
			(thermal_bridge_width 0.5)
			(island_removal_mode 0)
		)
		(polygon
			(pts
				(arc
					(start 84.836 -241.244374)
					(mid 84.20608 -241.244374)
					(end 84.836 -241.244374)
				)
			)
		)
	)
	(zone
		(layers "B.Cu" "In13.Cu" "In15.Cu")
		(hatch none 0.5)
		(connect_pads
			(clearance 0)
		)
		(min_thickness 0.25)
		(keepout
			(tracks not_allowed)
			(vias allowed)
			(pads allowed)
			(copperpour not_allowed)
			(footprints allowed)
		)
		(placement
			(enabled no)
			(sheetname "")
		)
		(fill yes
			(thermal_gap 0.5)
			(thermal_bridge_width 0.5)
			(island_removal_mode 0)
		)
		(polygon
			(pts
				(arc
					(start 122.429778 -233.144314)
					(mid 121.799858 -233.144314)
					(end 122.429778 -233.144314)
				)
			)
		)
	)
	(zone
		(layers "B.Cu" "In13.Cu" "In15.Cu")
		(hatch none 0.5)
		(connect_pads
			(clearance 0)
		)
		(min_thickness 0.25)
		(keepout
			(tracks not_allowed)
			(vias allowed)
			(pads allowed)
			(copperpour not_allowed)
			(footprints allowed)
		)
		(placement
			(enabled no)
			(sheetname "")
		)
		(fill yes
			(thermal_gap 0.5)
			(thermal_bridge_width 0.5)
			(island_removal_mode 0)
		)
		(polygon
			(pts
				(arc
					(start 138.239754 -262.746236)
					(mid 137.609834 -262.746236)
					(end 138.239754 -262.746236)
				)
			)
		)
	)
	(zone
		(layers "B.Cu" "In13.Cu" "In15.Cu")
		(hatch none 0.5)
		(connect_pads
			(clearance 0)
		)
		(min_thickness 0.25)
		(keepout
			(tracks not_allowed)
			(vias allowed)
			(pads allowed)
			(copperpour not_allowed)
			(footprints allowed)
		)
		(placement
			(enabled no)
			(sheetname "")
		)
		(fill yes
			(thermal_gap 0.5)
			(thermal_bridge_width 0.5)
			(island_removal_mode 0)
		)
		(polygon
			(pts
				(arc
					(start 386.649722 -278.136096)
					(mid 386.019802 -278.136096)
					(end 386.649722 -278.136096)
				)
			)
		)
	)
	(zone
		(layers "B.Cu" "In13.Cu" "In15.Cu")
		(hatch none 0.5)
		(connect_pads
			(clearance 0)
		)
		(min_thickness 0.25)
		(keepout
			(tracks not_allowed)
			(vias allowed)
			(pads allowed)
			(copperpour not_allowed)
			(footprints allowed)
		)
		(placement
			(enabled no)
			(sheetname "")
		)
		(fill yes
			(thermal_gap 0.5)
			(thermal_bridge_width 0.5)
			(island_removal_mode 0)
		)
		(polygon
			(pts
				(arc
					(start 386.649722 -286.236156)
					(mid 386.019802 -286.236156)
					(end 386.649722 -286.236156)
				)
			)
		)
	)
	(zone
		(layers "B.Cu" "In13.Cu" "In15.Cu")
		(hatch none 0.5)
		(connect_pads
			(clearance 0)
		)
		(min_thickness 0.25)
		(keepout
			(tracks not_allowed)
			(vias allowed)
			(pads allowed)
			(copperpour not_allowed)
			(footprints allowed)
		)
		(placement
			(enabled no)
			(sheetname "")
		)
		(fill yes
			(thermal_gap 0.5)
			(thermal_bridge_width 0.5)
			(island_removal_mode 0)
		)
		(polygon
			(pts
				(arc
					(start 202.481942 -202.435206)
					(mid 201.813922 -202.435206)
					(end 202.481942 -202.435206)
				)
			)
		)
	)
	(zone
		(layers "B.Cu" "In13.Cu" "In15.Cu")
		(hatch none 0.5)
		(connect_pads
			(clearance 0)
		)
		(min_thickness 0.25)
		(keepout
			(tracks not_allowed)
			(vias allowed)
			(pads allowed)
			(copperpour not_allowed)
			(footprints allowed)
		)
		(placement
			(enabled no)
			(sheetname "")
		)
		(fill yes
			(thermal_gap 0.5)
			(thermal_bridge_width 0.5)
			(island_removal_mode 0)
		)
		(polygon
			(pts
				(arc
					(start 138.239754 -278.946356)
					(mid 137.609834 -278.946356)
					(end 138.239754 -278.946356)
				)
			)
		)
	)
	(zone
		(layers "B.Cu" "In13.Cu" "In15.Cu")
		(hatch none 0.5)
		(connect_pads
			(clearance 0)
		)
		(min_thickness 0.25)
		(keepout
			(tracks not_allowed)
			(vias allowed)
			(pads allowed)
			(copperpour not_allowed)
			(footprints allowed)
		)
		(placement
			(enabled no)
			(sheetname "")
		)
		(fill yes
			(thermal_gap 0.5)
			(thermal_bridge_width 0.5)
			(island_removal_mode 0)
		)
		(polygon
			(pts
				(arc
					(start 364.729776 -246.104156)
					(mid 364.099856 -246.104156)
					(end 364.729776 -246.104156)
				)
			)
		)
	)
	(zone
		(layers "B.Cu" "In13.Cu" "In15.Cu")
		(hatch none 0.5)
		(connect_pads
			(clearance 0)
		)
		(min_thickness 0.25)
		(keepout
			(tracks not_allowed)
			(vias allowed)
			(pads allowed)
			(copperpour not_allowed)
			(footprints allowed)
		)
		(placement
			(enabled no)
			(sheetname "")
		)
		(fill yes
			(thermal_gap 0.5)
			(thermal_bridge_width 0.5)
			(island_removal_mode 0)
		)
		(polygon
			(pts
				(arc
					(start 454.522078 -201.585068)
					(mid 453.854058 -201.585068)
					(end 454.522078 -201.585068)
				)
			)
		)
	)
	(zone
		(layers "B.Cu" "In13.Cu" "In15.Cu")
		(hatch none 0.5)
		(connect_pads
			(clearance 0)
		)
		(min_thickness 0.25)
		(keepout
			(tracks not_allowed)
			(vias allowed)
			(pads allowed)
			(copperpour not_allowed)
			(footprints allowed)
		)
		(placement
			(enabled no)
			(sheetname "")
		)
		(fill yes
			(thermal_gap 0.5)
			(thermal_bridge_width 0.5)
			(island_removal_mode 0)
		)
		(polygon
			(pts
				(arc
					(start 15.867888 -17.61236)
					(mid 15.199868 -17.61236)
					(end 15.867888 -17.61236)
				)
			)
		)
	)
	(zone
		(layers "B.Cu" "In13.Cu" "In15.Cu")
		(hatch none 0.5)
		(connect_pads
			(clearance 0)
		)
		(min_thickness 0.25)
		(keepout
			(tracks not_allowed)
			(vias allowed)
			(pads allowed)
			(copperpour not_allowed)
			(footprints allowed)
		)
		(placement
			(enabled no)
			(sheetname "")
		)
		(fill yes
			(thermal_gap 0.5)
			(thermal_bridge_width 0.5)
			(island_removal_mode 0)
		)
		(polygon
			(pts
				(arc
					(start 265.88212 -318.035178)
					(mid 265.2141 -318.035178)
					(end 265.88212 -318.035178)
				)
			)
		)
	)
	(zone
		(layers "B.Cu" "In13.Cu" "In15.Cu")
		(hatch none 0.5)
		(connect_pads
			(clearance 0)
		)
		(min_thickness 0.25)
		(keepout
			(tracks not_allowed)
			(vias allowed)
			(pads allowed)
			(copperpour not_allowed)
			(footprints allowed)
		)
		(placement
			(enabled no)
			(sheetname "")
		)
		(fill yes
			(thermal_gap 0.5)
			(thermal_bridge_width 0.5)
			(island_removal_mode 0)
		)
		(polygon
			(pts
				(arc
					(start 269.982188 -247.485154)
					(mid 269.314168 -247.485154)
					(end 269.982188 -247.485154)
				)
			)
		)
	)
	(zone
		(layers "B.Cu" "In13.Cu" "In15.Cu")
		(hatch none 0.5)
		(connect_pads
			(clearance 0)
		)
		(min_thickness 0.25)
		(keepout
			(tracks not_allowed)
			(vias allowed)
			(pads allowed)
			(copperpour not_allowed)
			(footprints allowed)
		)
		(placement
			(enabled no)
			(sheetname "")
		)
		(fill yes
			(thermal_gap 0.5)
			(thermal_bridge_width 0.5)
			(island_removal_mode 0)
		)
		(polygon
			(pts
				(arc
					(start 387.289802 -255.824228)
					(mid 386.659882 -255.824228)
					(end 387.289802 -255.824228)
				)
			)
		)
	)
	(zone
		(layers "B.Cu" "In13.Cu" "In15.Cu")
		(hatch none 0.5)
		(connect_pads
			(clearance 0)
		)
		(min_thickness 0.25)
		(keepout
			(tracks not_allowed)
			(vias allowed)
			(pads allowed)
			(copperpour not_allowed)
			(footprints allowed)
		)
		(placement
			(enabled no)
			(sheetname "")
		)
		(fill yes
			(thermal_gap 0.5)
			(thermal_bridge_width 0.5)
			(island_removal_mode 0)
		)
		(polygon
			(pts
				(arc
					(start 349.696024 -234.764072)
					(mid 349.066104 -234.764072)
					(end 349.696024 -234.764072)
				)
			)
		)
	)
	(zone
		(layers "B.Cu" "In13.Cu" "In15.Cu")
		(hatch none 0.5)
		(connect_pads
			(clearance 0)
		)
		(min_thickness 0.25)
		(keepout
			(tracks not_allowed)
			(vias allowed)
			(pads allowed)
			(copperpour not_allowed)
			(footprints allowed)
		)
		(placement
			(enabled no)
			(sheetname "")
		)
		(fill yes
			(thermal_gap 0.5)
			(thermal_bridge_width 0.5)
			(island_removal_mode 0)
		)
		(polygon
			(pts
				(arc
					(start 202.481942 -277.235412)
					(mid 201.813922 -277.235412)
					(end 202.481942 -277.235412)
				)
			)
		)
	)
	(zone
		(layers "B.Cu" "In13.Cu" "In15.Cu")
		(hatch none 0.5)
		(connect_pads
			(clearance 0)
		)
		(min_thickness 0.25)
		(keepout
			(tracks not_allowed)
			(vias allowed)
			(pads allowed)
			(copperpour not_allowed)
			(footprints allowed)
		)
		(placement
			(enabled no)
			(sheetname "")
		)
		(fill yes
			(thermal_gap 0.5)
			(thermal_bridge_width 0.5)
			(island_removal_mode 0)
		)
		(polygon
			(pts
				(arc
					(start 84.666074 -283.806392)
					(mid 84.036154 -283.806392)
					(end 84.666074 -283.806392)
				)
			)
		)
	)
	(zone
		(layers "B.Cu" "In13.Cu" "In15.Cu")
		(hatch none 0.5)
		(connect_pads
			(clearance 0)
		)
		(min_thickness 0.25)
		(keepout
			(tracks not_allowed)
			(vias allowed)
			(pads allowed)
			(copperpour not_allowed)
			(footprints allowed)
		)
		(placement
			(enabled no)
			(sheetname "")
		)
		(fill yes
			(thermal_gap 0.5)
			(thermal_bridge_width 0.5)
			(island_removal_mode 0)
		)
		(polygon
			(pts
				(arc
					(start 454.522078 -234.735116)
					(mid 453.854058 -234.735116)
					(end 454.522078 -234.735116)
				)
			)
		)
	)
	(zone
		(layers "B.Cu" "In13.Cu" "In15.Cu")
		(hatch none 0.5)
		(connect_pads
			(clearance 0)
		)
		(min_thickness 0.25)
		(keepout
			(tracks not_allowed)
			(vias allowed)
			(pads allowed)
			(copperpour not_allowed)
			(footprints allowed)
		)
		(placement
			(enabled no)
			(sheetname "")
		)
		(fill yes
			(thermal_gap 0.5)
			(thermal_bridge_width 0.5)
			(island_removal_mode 0)
		)
		(polygon
			(pts
				(arc
					(start 333.716122 -226.664266)
					(mid 333.086202 -226.664266)
					(end 333.716122 -226.664266)
				)
			)
		)
	)
	(zone
		(layers "B.Cu" "In13.Cu" "In15.Cu")
		(hatch none 0.5)
		(connect_pads
			(clearance 0)
		)
		(min_thickness 0.25)
		(keepout
			(tracks not_allowed)
			(vias allowed)
			(pads allowed)
			(copperpour not_allowed)
			(footprints allowed)
		)
		(placement
			(enabled no)
			(sheetname "")
		)
		(fill yes
			(thermal_gap 0.5)
			(thermal_bridge_width 0.5)
			(island_removal_mode 0)
		)
		(polygon
			(pts
				(arc
					(start 117.089682 -279.756362)
					(mid 116.459762 -279.756362)
					(end 117.089682 -279.756362)
				)
			)
		)
	)
	(zone
		(layers "B.Cu" "In13.Cu" "In15.Cu")
		(hatch none 0.5)
		(connect_pads
			(clearance 0)
		)
		(min_thickness 0.25)
		(keepout
			(tracks not_allowed)
			(vias allowed)
			(pads allowed)
			(copperpour not_allowed)
			(footprints allowed)
		)
		(placement
			(enabled no)
			(sheetname "")
		)
		(fill yes
			(thermal_gap 0.5)
			(thermal_bridge_width 0.5)
			(island_removal_mode 0)
		)
		(polygon
			(pts
				(arc
					(start 332.776068 -246.104156)
					(mid 332.146148 -246.104156)
					(end 332.776068 -246.104156)
				)
			)
		)
	)
	(zone
		(layers "B.Cu" "In13.Cu" "In15.Cu")
		(hatch none 0.5)
		(connect_pads
			(clearance 0)
		)
		(min_thickness 0.25)
		(keepout
			(tracks not_allowed)
			(vias allowed)
			(pads allowed)
			(copperpour not_allowed)
			(footprints allowed)
		)
		(placement
			(enabled no)
			(sheetname "")
		)
		(fill yes
			(thermal_gap 0.5)
			(thermal_bridge_width 0.5)
			(island_removal_mode 0)
		)
		(polygon
			(pts
				(arc
					(start 46.906688 -19.137122)
					(mid 46.238668 -19.137122)
					(end 46.906688 -19.137122)
				)
			)
		)
	)
	(zone
		(layers "B.Cu" "In13.Cu" "In15.Cu")
		(hatch none 0.5)
		(connect_pads
			(clearance 0)
		)
		(min_thickness 0.25)
		(keepout
			(tracks not_allowed)
			(vias allowed)
			(pads allowed)
			(copperpour not_allowed)
			(footprints allowed)
		)
		(placement
			(enabled no)
			(sheetname "")
		)
		(fill yes
			(thermal_gap 0.5)
			(thermal_bridge_width 0.5)
			(island_removal_mode 0)
		)
		(polygon
			(pts
				(arc
					(start 139.649708 -274.896326)
					(mid 139.019788 -274.896326)
					(end 139.649708 -274.896326)
				)
			)
		)
	)
	(zone
		(layers "B.Cu" "In13.Cu" "In15.Cu")
		(hatch none 0.5)
		(connect_pads
			(clearance 0)
		)
		(min_thickness 0.25)
		(keepout
			(tracks not_allowed)
			(vias allowed)
			(pads allowed)
			(copperpour not_allowed)
			(footprints allowed)
		)
		(placement
			(enabled no)
			(sheetname "")
		)
		(fill yes
			(thermal_gap 0.5)
			(thermal_bridge_width 0.5)
			(island_removal_mode 0)
		)
		(polygon
			(pts
				(arc
					(start 22.04212 -201.585322)
					(mid 21.3741 -201.585322)
					(end 22.04212 -201.585322)
				)
			)
		)
	)
	(zone
		(layers "B.Cu" "In13.Cu" "In15.Cu")
		(hatch none 0.5)
		(connect_pads
			(clearance 0)
		)
		(min_thickness 0.25)
		(keepout
			(tracks not_allowed)
			(vias allowed)
			(pads allowed)
			(copperpour not_allowed)
			(footprints allowed)
		)
		(placement
			(enabled no)
			(sheetname "")
		)
		(fill yes
			(thermal_gap 0.5)
			(thermal_bridge_width 0.5)
			(island_removal_mode 0)
		)
		(polygon
			(pts
				(arc
					(start 370.369846 -244.484144)
					(mid 369.739926 -244.484144)
					(end 370.369846 -244.484144)
				)
			)
		)
	)
	(zone
		(layers "B.Cu" "In13.Cu" "In15.Cu")
		(hatch none 0.5)
		(connect_pads
			(clearance 0)
		)
		(min_thickness 0.25)
		(keepout
			(tracks not_allowed)
			(vias allowed)
			(pads allowed)
			(copperpour not_allowed)
			(footprints allowed)
		)
		(placement
			(enabled no)
			(sheetname "")
		)
		(fill yes
			(thermal_gap 0.5)
			(thermal_bridge_width 0.5)
			(island_removal_mode 0)
		)
		(polygon
			(pts
				(arc
					(start 368.489738 -247.724168)
					(mid 367.859818 -247.724168)
					(end 368.489738 -247.724168)
				)
			)
		)
	)
	(zone
		(layers "B.Cu" "In13.Cu" "In15.Cu")
		(hatch none 0.5)
		(connect_pads
			(clearance 0)
		)
		(min_thickness 0.25)
		(keepout
			(tracks not_allowed)
			(vias allowed)
			(pads allowed)
			(copperpour not_allowed)
			(footprints allowed)
		)
		(placement
			(enabled no)
			(sheetname "")
		)
		(fill yes
			(thermal_gap 0.5)
			(thermal_bridge_width 0.5)
			(island_removal_mode 0)
		)
		(polygon
			(pts
				(arc
					(start 202.481942 -211.7852)
					(mid 201.813922 -211.7852)
					(end 202.481942 -211.7852)
				)
			)
		)
	)
	(zone
		(layers "B.Cu" "In13.Cu" "In15.Cu")
		(hatch none 0.5)
		(connect_pads
			(clearance 0)
		)
		(min_thickness 0.25)
		(keepout
			(tracks not_allowed)
			(vias allowed)
			(pads allowed)
			(copperpour not_allowed)
			(footprints allowed)
		)
		(placement
			(enabled no)
			(sheetname "")
		)
		(fill yes
			(thermal_gap 0.5)
			(thermal_bridge_width 0.5)
			(island_removal_mode 0)
		)
		(polygon
			(pts
				(arc
					(start 454.522078 -300.185074)
					(mid 453.854058 -300.185074)
					(end 454.522078 -300.185074)
				)
			)
		)
	)
	(zone
		(layers "B.Cu" "In13.Cu" "In15.Cu")
		(hatch none 0.5)
		(connect_pads
			(clearance 0)
		)
		(min_thickness 0.25)
		(keepout
			(tracks not_allowed)
			(vias allowed)
			(pads allowed)
			(copperpour not_allowed)
			(footprints allowed)
		)
		(placement
			(enabled no)
			(sheetname "")
		)
		(fill yes
			(thermal_gap 0.5)
			(thermal_bridge_width 0.5)
			(island_removal_mode 0)
		)
		(polygon
			(pts
				(arc
					(start 86.076028 -287.856422)
					(mid 85.446108 -287.856422)
					(end 86.076028 -287.856422)
				)
			)
		)
	)
	(zone
		(layers "B.Cu" "In13.Cu" "In15.Cu")
		(hatch none 0.5)
		(connect_pads
			(clearance 0)
		)
		(min_thickness 0.25)
		(keepout
			(tracks not_allowed)
			(vias allowed)
			(pads allowed)
			(copperpour not_allowed)
			(footprints allowed)
		)
		(placement
			(enabled no)
			(sheetname "")
		)
		(fill yes
			(thermal_gap 0.5)
			(thermal_bridge_width 0.5)
			(island_removal_mode 0)
		)
		(polygon
			(pts
				(arc
					(start 340.633812 -394.385292)
					(mid 340.003892 -394.385292)
					(end 340.633812 -394.385292)
				)
			)
		)
	)
	(zone
		(layers "B.Cu" "In13.Cu" "In15.Cu")
		(hatch none 0.5)
		(connect_pads
			(clearance 0)
		)
		(min_thickness 0.25)
		(keepout
			(tracks not_allowed)
			(vias allowed)
			(pads allowed)
			(copperpour not_allowed)
			(footprints allowed)
		)
		(placement
			(enabled no)
			(sheetname "")
		)
		(fill yes
			(thermal_gap 0.5)
			(thermal_bridge_width 0.5)
			(island_removal_mode 0)
		)
		(polygon
			(pts
				(arc
					(start 377.354592 -420.952168)
					(mid 376.686572 -420.952168)
					(end 377.354592 -420.952168)
				)
			)
		)
	)
	(zone
		(layers "B.Cu" "In13.Cu" "In15.Cu")
		(hatch none 0.5)
		(connect_pads
			(clearance 0)
		)
		(min_thickness 0.25)
		(keepout
			(tracks not_allowed)
			(vias allowed)
			(pads allowed)
			(copperpour not_allowed)
			(footprints allowed)
		)
		(placement
			(enabled no)
			(sheetname "")
		)
		(fill yes
			(thermal_gap 0.5)
			(thermal_bridge_width 0.5)
			(island_removal_mode 0)
		)
		(polygon
			(pts
				(arc
					(start 202.481942 -221.135194)
					(mid 201.813922 -221.135194)
					(end 202.481942 -221.135194)
				)
			)
		)
	)
	(zone
		(layers "B.Cu" "In13.Cu" "In15.Cu")
		(hatch none 0.5)
		(connect_pads
			(clearance 0)
		)
		(min_thickness 0.25)
		(keepout
			(tracks not_allowed)
			(vias allowed)
			(pads allowed)
			(copperpour not_allowed)
			(footprints allowed)
		)
		(placement
			(enabled no)
			(sheetname "")
		)
		(fill yes
			(thermal_gap 0.5)
			(thermal_bridge_width 0.5)
			(island_removal_mode 0)
		)
		(polygon
			(pts
				(arc
					(start 82.234024 -386.003292)
					(mid 81.604104 -386.003292)
					(end 82.234024 -386.003292)
				)
			)
		)
	)
	(zone
		(layers "B.Cu" "In13.Cu" "In15.Cu")
		(hatch none 0.5)
		(connect_pads
			(clearance 0)
		)
		(min_thickness 0.25)
		(keepout
			(tracks not_allowed)
			(vias allowed)
			(pads allowed)
			(copperpour not_allowed)
			(footprints allowed)
		)
		(placement
			(enabled no)
			(sheetname "")
		)
		(fill yes
			(thermal_gap 0.5)
			(thermal_bridge_width 0.5)
			(island_removal_mode 0)
		)
		(polygon
			(pts
				(arc
					(start 139.649708 -278.13635)
					(mid 139.019788 -278.13635)
					(end 139.649708 -278.13635)
				)
			)
		)
	)
	(zone
		(layers "B.Cu" "In13.Cu" "In15.Cu")
		(hatch none 0.5)
		(connect_pads
			(clearance 0)
		)
		(min_thickness 0.25)
		(keepout
			(tracks not_allowed)
			(vias allowed)
			(pads allowed)
			(copperpour not_allowed)
			(footprints allowed)
		)
		(placement
			(enabled no)
			(sheetname "")
		)
		(fill yes
			(thermal_gap 0.5)
			(thermal_bridge_width 0.5)
			(island_removal_mode 0)
		)
		(polygon
			(pts
				(arc
					(start 22.04212 -249.18543)
					(mid 21.3741 -249.18543)
					(end 22.04212 -249.18543)
				)
			)
		)
	)
	(zone
		(layers "B.Cu" "In13.Cu" "In15.Cu")
		(hatch none 0.5)
		(connect_pads
			(clearance 0)
		)
		(min_thickness 0.25)
		(keepout
			(tracks not_allowed)
			(vias allowed)
			(pads allowed)
			(copperpour not_allowed)
			(footprints allowed)
		)
		(placement
			(enabled no)
			(sheetname "")
		)
		(fill yes
			(thermal_gap 0.5)
			(thermal_bridge_width 0.5)
			(island_removal_mode 0)
		)
		(polygon
			(pts
				(arc
					(start 401.13712 -430.689766)
					(mid 400.362928 -430.689766)
					(end 401.13712 -430.689766)
				)
			)
		)
	)
	(zone
		(layers "B.Cu" "In13.Cu" "In15.Cu")
		(hatch none 0.5)
		(connect_pads
			(clearance 0)
		)
		(min_thickness 0.25)
		(keepout
			(tracks not_allowed)
			(vias allowed)
			(pads allowed)
			(copperpour not_allowed)
			(footprints allowed)
		)
		(placement
			(enabled no)
			(sheetname "")
		)
		(fill yes
			(thermal_gap 0.5)
			(thermal_bridge_width 0.5)
			(island_removal_mode 0)
		)
		(polygon
			(pts
				(arc
					(start 126.628906 -369.03533)
					(mid 125.960886 -369.03533)
					(end 126.628906 -369.03533)
				)
			)
		)
	)
	(zone
		(layers "B.Cu" "In13.Cu" "In15.Cu")
		(hatch none 0.5)
		(connect_pads
			(clearance 0)
		)
		(min_thickness 0.25)
		(keepout
			(tracks not_allowed)
			(vias allowed)
			(pads allowed)
			(copperpour not_allowed)
			(footprints allowed)
		)
		(placement
			(enabled no)
			(sheetname "")
		)
		(fill yes
			(thermal_gap 0.5)
			(thermal_bridge_width 0.5)
			(island_removal_mode 0)
		)
		(polygon
			(pts
				(arc
					(start 86.545928 -288.666174)
					(mid 85.916008 -288.666174)
					(end 86.545928 -288.666174)
				)
			)
		)
	)
	(zone
		(layers "B.Cu" "In13.Cu" "In15.Cu")
		(hatch none 0.5)
		(connect_pads
			(clearance 0)
		)
		(min_thickness 0.25)
		(keepout
			(tracks not_allowed)
			(vias allowed)
			(pads allowed)
			(copperpour not_allowed)
			(footprints allowed)
		)
		(placement
			(enabled no)
			(sheetname "")
		)
		(fill yes
			(thermal_gap 0.5)
			(thermal_bridge_width 0.5)
			(island_removal_mode 0)
		)
		(polygon
			(pts
				(arc
					(start 349.696024 -231.524048)
					(mid 349.066104 -231.524048)
					(end 349.696024 -231.524048)
				)
			)
		)
	)
	(zone
		(layers "B.Cu" "In13.Cu" "In15.Cu")
		(hatch none 0.5)
		(connect_pads
			(clearance 0)
		)
		(min_thickness 0.25)
		(keepout
			(tracks not_allowed)
			(vias allowed)
			(pads allowed)
			(copperpour not_allowed)
			(footprints allowed)
		)
		(placement
			(enabled no)
			(sheetname "")
		)
		(fill yes
			(thermal_gap 0.5)
			(thermal_bridge_width 0.5)
			(island_removal_mode 0)
		)
		(polygon
			(pts
				(arc
					(start 386.179822 -272.466054)
					(mid 385.549902 -272.466054)
					(end 386.179822 -272.466054)
				)
			)
		)
	)
	(zone
		(layers "B.Cu" "In13.Cu" "In15.Cu")
		(hatch none 0.5)
		(connect_pads
			(clearance 0)
		)
		(min_thickness 0.25)
		(keepout
			(tracks not_allowed)
			(vias allowed)
			(pads allowed)
			(copperpour not_allowed)
			(footprints allowed)
		)
		(placement
			(enabled no)
			(sheetname "")
		)
		(fill yes
			(thermal_gap 0.5)
			(thermal_bridge_width 0.5)
			(island_removal_mode 0)
		)
		(polygon
			(pts
				(arc
					(start 381.765302 -377.41733)
					(mid 381.097282 -377.41733)
					(end 381.765302 -377.41733)
				)
			)
		)
	)
	(zone
		(layers "B.Cu" "In13.Cu" "In15.Cu")
		(hatch none 0.5)
		(connect_pads
			(clearance 0)
		)
		(min_thickness 0.25)
		(keepout
			(tracks not_allowed)
			(vias allowed)
			(pads allowed)
			(copperpour not_allowed)
			(footprints allowed)
		)
		(placement
			(enabled no)
			(sheetname "")
		)
		(fill yes
			(thermal_gap 0.5)
			(thermal_bridge_width 0.5)
			(island_removal_mode 0)
		)
		(polygon
			(pts
				(arc
					(start 85.776054 -234.764326)
					(mid 85.146134 -234.764326)
					(end 85.776054 -234.764326)
				)
			)
		)
	)
	(zone
		(layers "B.Cu" "In13.Cu" "In15.Cu")
		(hatch none 0.5)
		(connect_pads
			(clearance 0)
		)
		(min_thickness 0.25)
		(keepout
			(tracks not_allowed)
			(vias allowed)
			(pads allowed)
			(copperpour not_allowed)
			(footprints allowed)
		)
		(placement
			(enabled no)
			(sheetname "")
		)
		(fill yes
			(thermal_gap 0.5)
			(thermal_bridge_width 0.5)
			(island_removal_mode 0)
		)
		(polygon
			(pts
				(arc
					(start 202.481942 -285.735268)
					(mid 201.813922 -285.735268)
					(end 202.481942 -285.735268)
				)
			)
		)
	)
	(zone
		(layers "B.Cu" "In13.Cu" "In15.Cu")
		(hatch none 0.5)
		(connect_pads
			(clearance 0)
		)
		(min_thickness 0.25)
		(keepout
			(tracks not_allowed)
			(vias allowed)
			(pads allowed)
			(copperpour not_allowed)
			(footprints allowed)
		)
		(placement
			(enabled no)
			(sheetname "")
		)
		(fill yes
			(thermal_gap 0.5)
			(thermal_bridge_width 0.5)
			(island_removal_mode 0)
		)
		(polygon
			(pts
				(arc
					(start 334.186022 -229.094284)
					(mid 333.556102 -229.094284)
					(end 334.186022 -229.094284)
				)
			)
		)
	)
	(zone
		(layers "B.Cu" "In13.Cu" "In15.Cu")
		(hatch none 0.5)
		(connect_pads
			(clearance 0)
		)
		(min_thickness 0.25)
		(keepout
			(tracks not_allowed)
			(vias allowed)
			(pads allowed)
			(copperpour not_allowed)
			(footprints allowed)
		)
		(placement
			(enabled no)
			(sheetname "")
		)
		(fill yes
			(thermal_gap 0.5)
			(thermal_bridge_width 0.5)
			(island_removal_mode 0)
		)
		(polygon
			(pts
				(arc
					(start 84.3661 -230.71455)
					(mid 83.73618 -230.71455)
					(end 84.3661 -230.71455)
				)
			)
		)
	)
	(zone
		(layers "B.Cu" "In13.Cu" "In15.Cu")
		(hatch none 0.5)
		(connect_pads
			(clearance 0)
		)
		(min_thickness 0.25)
		(keepout
			(tracks not_allowed)
			(vias allowed)
			(pads allowed)
			(copperpour not_allowed)
			(footprints allowed)
		)
		(placement
			(enabled no)
			(sheetname "")
		)
		(fill yes
			(thermal_gap 0.5)
			(thermal_bridge_width 0.5)
			(island_removal_mode 0)
		)
		(polygon
			(pts
				(arc
					(start 22.04212 -281.48534)
					(mid 21.3741 -281.48534)
					(end 22.04212 -281.48534)
				)
			)
		)
	)
	(zone
		(layers "B.Cu" "In13.Cu" "In15.Cu")
		(hatch none 0.5)
		(connect_pads
			(clearance 0)
		)
		(min_thickness 0.25)
		(keepout
			(tracks not_allowed)
			(vias allowed)
			(pads allowed)
			(copperpour not_allowed)
			(footprints allowed)
		)
		(placement
			(enabled no)
			(sheetname "")
		)
		(fill yes
			(thermal_gap 0.5)
			(thermal_bridge_width 0.5)
			(island_removal_mode 0)
		)
		(polygon
			(pts
				(arc
					(start 265.88212 -308.685184)
					(mid 265.2141 -308.685184)
					(end 265.88212 -308.685184)
				)
			)
		)
	)
	(zone
		(layers "B.Cu" "In13.Cu" "In15.Cu")
		(hatch none 0.5)
		(connect_pads
			(clearance 0)
		)
		(min_thickness 0.25)
		(keepout
			(tracks not_allowed)
			(vias allowed)
			(pads allowed)
			(copperpour not_allowed)
			(footprints allowed)
		)
		(placement
			(enabled no)
			(sheetname "")
		)
		(fill yes
			(thermal_gap 0.5)
			(thermal_bridge_width 0.5)
			(island_removal_mode 0)
		)
		(polygon
			(pts
				(arc
					(start 117.797834 -24.155654)
					(mid 117.129814 -24.155654)
					(end 117.797834 -24.155654)
				)
			)
		)
	)
	(zone
		(layers "B.Cu" "In13.Cu" "In15.Cu")
		(hatch none 0.5)
		(connect_pads
			(clearance 0)
		)
		(min_thickness 0.25)
		(keepout
			(tracks not_allowed)
			(vias allowed)
			(pads allowed)
			(copperpour not_allowed)
			(footprints allowed)
		)
		(placement
			(enabled no)
			(sheetname "")
		)
		(fill yes
			(thermal_gap 0.5)
			(thermal_bridge_width 0.5)
			(island_removal_mode 0)
		)
		(polygon
			(pts
				(arc
					(start 265.88212 -207.535018)
					(mid 265.2141 -207.535018)
					(end 265.88212 -207.535018)
				)
			)
		)
	)
	(zone
		(layers "B.Cu" "In13.Cu" "In15.Cu")
		(hatch none 0.5)
		(connect_pads
			(clearance 0)
		)
		(min_thickness 0.25)
		(keepout
			(tracks not_allowed)
			(vias allowed)
			(pads allowed)
			(copperpour not_allowed)
			(footprints allowed)
		)
		(placement
			(enabled no)
			(sheetname "")
		)
		(fill yes
			(thermal_gap 0.5)
			(thermal_bridge_width 0.5)
			(island_removal_mode 0)
		)
		(polygon
			(pts
				(arc
					(start 202.481942 -274.685252)
					(mid 201.813922 -274.685252)
					(end 202.481942 -274.685252)
				)
			)
		)
	)
	(zone
		(layers "B.Cu" "In13.Cu" "In15.Cu")
		(hatch none 0.5)
		(connect_pads
			(clearance 0)
		)
		(min_thickness 0.25)
		(keepout
			(tracks not_allowed)
			(vias allowed)
			(pads allowed)
			(copperpour not_allowed)
			(footprints allowed)
		)
		(placement
			(enabled no)
			(sheetname "")
		)
		(fill yes
			(thermal_gap 0.5)
			(thermal_bridge_width 0.5)
			(island_removal_mode 0)
		)
		(polygon
			(pts
				(arc
					(start 108.864654 -376.83186)
					(mid 108.196634 -376.83186)
					(end 108.864654 -376.83186)
				)
			)
		)
	)
	(zone
		(layers "B.Cu" "In13.Cu" "In15.Cu")
		(hatch none 0.5)
		(connect_pads
			(clearance 0)
		)
		(min_thickness 0.25)
		(keepout
			(tracks not_allowed)
			(vias allowed)
			(pads allowed)
			(copperpour not_allowed)
			(footprints allowed)
		)
		(placement
			(enabled no)
			(sheetname "")
		)
		(fill yes
			(thermal_gap 0.5)
			(thermal_bridge_width 0.5)
			(island_removal_mode 0)
		)
		(polygon
			(pts
				(arc
					(start 120.849644 -278.13635)
					(mid 120.219724 -278.13635)
					(end 120.849644 -278.13635)
				)
			)
		)
	)
	(zone
		(layers "B.Cu" "In13.Cu" "In15.Cu")
		(hatch none 0.5)
		(connect_pads
			(clearance 0)
		)
		(min_thickness 0.25)
		(keepout
			(tracks not_allowed)
			(vias allowed)
			(pads allowed)
			(copperpour not_allowed)
			(footprints allowed)
		)
		(placement
			(enabled no)
			(sheetname "")
		)
		(fill yes
			(thermal_gap 0.5)
			(thermal_bridge_width 0.5)
			(island_removal_mode 0)
		)
		(polygon
			(pts
				(arc
					(start 22.04212 -287.43529)
					(mid 21.3741 -287.43529)
					(end 22.04212 -287.43529)
				)
			)
		)
	)
	(zone
		(layers "B.Cu" "In13.Cu" "In15.Cu")
		(hatch none 0.5)
		(connect_pads
			(clearance 0)
		)
		(min_thickness 0.25)
		(keepout
			(tracks not_allowed)
			(vias allowed)
			(pads allowed)
			(copperpour not_allowed)
			(footprints allowed)
		)
		(placement
			(enabled no)
			(sheetname "")
		)
		(fill yes
			(thermal_gap 0.5)
			(thermal_bridge_width 0.5)
			(island_removal_mode 0)
		)
		(polygon
			(pts
				(arc
					(start 450.42201 -299.33519)
					(mid 449.75399 -299.33519)
					(end 450.42201 -299.33519)
				)
			)
		)
	)
	(zone
		(layers "B.Cu" "In13.Cu" "In15.Cu")
		(hatch none 0.5)
		(connect_pads
			(clearance 0)
		)
		(min_thickness 0.25)
		(keepout
			(tracks not_allowed)
			(vias allowed)
			(pads allowed)
			(copperpour not_allowed)
			(footprints allowed)
		)
		(placement
			(enabled no)
			(sheetname "")
		)
		(fill yes
			(thermal_gap 0.5)
			(thermal_bridge_width 0.5)
			(island_removal_mode 0)
		)
		(polygon
			(pts
				(arc
					(start 347.17609 -278.136096)
					(mid 346.54617 -278.136096)
					(end 347.17609 -278.136096)
				)
			)
		)
	)
	(zone
		(layers "B.Cu" "In13.Cu" "In15.Cu")
		(hatch none 0.5)
		(connect_pads
			(clearance 0)
		)
		(min_thickness 0.25)
		(keepout
			(tracks not_allowed)
			(vias allowed)
			(pads allowed)
			(copperpour not_allowed)
			(footprints allowed)
		)
		(placement
			(enabled no)
			(sheetname "")
		)
		(fill yes
			(thermal_gap 0.5)
			(thermal_bridge_width 0.5)
			(island_removal_mode 0)
		)
		(polygon
			(pts
				(arc
					(start 206.58201 -296.785284)
					(mid 205.91399 -296.785284)
					(end 206.58201 -296.785284)
				)
			)
		)
	)
	(zone
		(layers "B.Cu" "In13.Cu" "In15.Cu")
		(hatch none 0.5)
		(connect_pads
			(clearance 0)
		)
		(min_thickness 0.25)
		(keepout
			(tracks not_allowed)
			(vias allowed)
			(pads allowed)
			(copperpour not_allowed)
			(footprints allowed)
		)
		(placement
			(enabled no)
			(sheetname "")
		)
		(fill yes
			(thermal_gap 0.5)
			(thermal_bridge_width 0.5)
			(island_removal_mode 0)
		)
		(polygon
			(pts
				(arc
					(start 138.709654 -282.996386)
					(mid 138.079734 -282.996386)
					(end 138.709654 -282.996386)
				)
			)
		)
	)
	(zone
		(layers "B.Cu" "In13.Cu" "In15.Cu")
		(hatch none 0.5)
		(connect_pads
			(clearance 0)
		)
		(min_thickness 0.25)
		(keepout
			(tracks not_allowed)
			(vias allowed)
			(pads allowed)
			(copperpour not_allowed)
			(footprints allowed)
		)
		(placement
			(enabled no)
			(sheetname "")
		)
		(fill yes
			(thermal_gap 0.5)
			(thermal_bridge_width 0.5)
			(island_removal_mode 0)
		)
		(polygon
			(pts
				(arc
					(start 265.88212 -218.585034)
					(mid 265.2141 -218.585034)
					(end 265.88212 -218.585034)
				)
			)
		)
	)
	(zone
		(layers "B.Cu" "In13.Cu" "In15.Cu")
		(hatch none 0.5)
		(connect_pads
			(clearance 0)
		)
		(min_thickness 0.25)
		(keepout
			(tracks not_allowed)
			(vias allowed)
			(pads allowed)
			(copperpour not_allowed)
			(footprints allowed)
		)
		(placement
			(enabled no)
			(sheetname "")
		)
		(fill yes
			(thermal_gap 0.5)
			(thermal_bridge_width 0.5)
			(island_removal_mode 0)
		)
		(polygon
			(pts
				(arc
					(start 265.88212 -211.784946)
					(mid 265.2141 -211.784946)
					(end 265.88212 -211.784946)
				)
			)
		)
	)
	(zone
		(layers "B.Cu" "In13.Cu" "In15.Cu")
		(hatch none 0.5)
		(connect_pads
			(clearance 0)
		)
		(min_thickness 0.25)
		(keepout
			(tracks not_allowed)
			(vias allowed)
			(pads allowed)
			(copperpour not_allowed)
			(footprints allowed)
		)
		(placement
			(enabled no)
			(sheetname "")
		)
		(fill yes
			(thermal_gap 0.5)
			(thermal_bridge_width 0.5)
			(island_removal_mode 0)
		)
		(polygon
			(pts
				(arc
					(start 408.850592 -420.952168)
					(mid 408.182572 -420.952168)
					(end 408.850592 -420.952168)
				)
			)
		)
	)
	(zone
		(layers "B.Cu" "In13.Cu" "In15.Cu")
		(hatch none 0.5)
		(connect_pads
			(clearance 0)
		)
		(min_thickness 0.25)
		(keepout
			(tracks not_allowed)
			(vias allowed)
			(pads allowed)
			(copperpour not_allowed)
			(footprints allowed)
		)
		(placement
			(enabled no)
			(sheetname "")
		)
		(fill yes
			(thermal_gap 0.5)
			(thermal_bridge_width 0.5)
			(island_removal_mode 0)
		)
		(polygon
			(pts
				(arc
					(start 387.759702 -253.39421)
					(mid 387.129782 -253.39421)
					(end 387.759702 -253.39421)
				)
			)
		)
	)
	(zone
		(layers "B.Cu" "In13.Cu" "In15.Cu")
		(hatch none 0.5)
		(connect_pads
			(clearance 0)
		)
		(min_thickness 0.25)
		(keepout
			(tracks not_allowed)
			(vias allowed)
			(pads allowed)
			(copperpour not_allowed)
			(footprints allowed)
		)
		(placement
			(enabled no)
			(sheetname "")
		)
		(fill yes
			(thermal_gap 0.5)
			(thermal_bridge_width 0.5)
			(island_removal_mode 0)
		)
		(polygon
			(pts
				(arc
					(start 117.089682 -276.516338)
					(mid 116.459762 -276.516338)
					(end 117.089682 -276.516338)
				)
			)
		)
	)
	(zone
		(layers "B.Cu" "In13.Cu" "In15.Cu")
		(hatch none 0.5)
		(connect_pads
			(clearance 0)
		)
		(min_thickness 0.25)
		(keepout
			(tracks not_allowed)
			(vias allowed)
			(pads allowed)
			(copperpour not_allowed)
			(footprints allowed)
		)
		(placement
			(enabled no)
			(sheetname "")
		)
		(fill yes
			(thermal_gap 0.5)
			(thermal_bridge_width 0.5)
			(island_removal_mode 0)
		)
		(polygon
			(pts
				(arc
					(start 92.634054 -388.774432)
					(mid 92.004134 -388.774432)
					(end 92.634054 -388.774432)
				)
			)
		)
	)
	(zone
		(layers "B.Cu" "In13.Cu" "In15.Cu")
		(hatch none 0.5)
		(connect_pads
			(clearance 0)
		)
		(min_thickness 0.25)
		(keepout
			(tracks not_allowed)
			(vias allowed)
			(pads allowed)
			(copperpour not_allowed)
			(footprints allowed)
		)
		(placement
			(enabled no)
			(sheetname "")
		)
		(fill yes
			(thermal_gap 0.5)
			(thermal_bridge_width 0.5)
			(island_removal_mode 0)
		)
		(polygon
			(pts
				(arc
					(start 349.995998 -274.896072)
					(mid 349.366078 -274.896072)
					(end 349.995998 -274.896072)
				)
			)
		)
	)
	(zone
		(layers "B.Cu" "In13.Cu" "In15.Cu")
		(hatch none 0.5)
		(connect_pads
			(clearance 0)
		)
		(min_thickness 0.25)
		(keepout
			(tracks not_allowed)
			(vias allowed)
			(pads allowed)
			(copperpour not_allowed)
			(footprints allowed)
		)
		(placement
			(enabled no)
			(sheetname "")
		)
		(fill yes
			(thermal_gap 0.5)
			(thermal_bridge_width 0.5)
			(island_removal_mode 0)
		)
		(polygon
			(pts
				(arc
					(start 97.995994 -246.10441)
					(mid 97.366074 -246.10441)
					(end 97.995994 -246.10441)
				)
			)
		)
	)
	(zone
		(layers "B.Cu" "In13.Cu" "In15.Cu")
		(hatch none 0.5)
		(connect_pads
			(clearance 0)
		)
		(min_thickness 0.25)
		(keepout
			(tracks not_allowed)
			(vias allowed)
			(pads allowed)
			(copperpour not_allowed)
			(footprints allowed)
		)
		(placement
			(enabled no)
			(sheetname "")
		)
		(fill yes
			(thermal_gap 0.5)
			(thermal_bridge_width 0.5)
			(island_removal_mode 0)
		)
		(polygon
			(pts
				(arc
					(start 416.42792 -4.963414)
					(mid 415.7599 -4.963414)
					(end 416.42792 -4.963414)
				)
			)
		)
	)
	(zone
		(layers "B.Cu" "In13.Cu" "In15.Cu")
		(hatch none 0.5)
		(connect_pads
			(clearance 0)
		)
		(min_thickness 0.25)
		(keepout
			(tracks not_allowed)
			(vias allowed)
			(pads allowed)
			(copperpour not_allowed)
			(footprints allowed)
		)
		(placement
			(enabled no)
			(sheetname "")
		)
		(fill yes
			(thermal_gap 0.5)
			(thermal_bridge_width 0.5)
			(island_removal_mode 0)
		)
		(polygon
			(pts
				(arc
					(start 106.455972 -246.10441)
					(mid 105.826052 -246.10441)
					(end 106.455972 -246.10441)
				)
			)
		)
	)
	(zone
		(layers "B.Cu" "In13.Cu" "In15.Cu")
		(hatch none 0.5)
		(connect_pads
			(clearance 0)
		)
		(min_thickness 0.25)
		(keepout
			(tracks not_allowed)
			(vias allowed)
			(pads allowed)
			(copperpour not_allowed)
			(footprints allowed)
		)
		(placement
			(enabled no)
			(sheetname "")
		)
		(fill yes
			(thermal_gap 0.5)
			(thermal_bridge_width 0.5)
			(island_removal_mode 0)
		)
		(polygon
			(pts
				(arc
					(start 362.379768 -248.534174)
					(mid 361.749848 -248.534174)
					(end 362.379768 -248.534174)
				)
			)
		)
	)
	(zone
		(layers "B.Cu" "In13.Cu" "In15.Cu")
		(hatch none 0.5)
		(connect_pads
			(clearance 0)
		)
		(min_thickness 0.25)
		(keepout
			(tracks not_allowed)
			(vias allowed)
			(pads allowed)
			(copperpour not_allowed)
			(footprints allowed)
		)
		(placement
			(enabled no)
			(sheetname "")
		)
		(fill yes
			(thermal_gap 0.5)
			(thermal_bridge_width 0.5)
			(island_removal_mode 0)
		)
		(polygon
			(pts
				(arc
					(start 354.39604 -233.14406)
					(mid 353.76612 -233.14406)
					(end 354.39604 -233.14406)
				)
			)
		)
	)
	(zone
		(layers "B.Cu" "In13.Cu" "In15.Cu")
		(hatch none 0.5)
		(connect_pads
			(clearance 0)
		)
		(min_thickness 0.25)
		(keepout
			(tracks not_allowed)
			(vias allowed)
			(pads allowed)
			(copperpour not_allowed)
			(footprints allowed)
		)
		(placement
			(enabled no)
			(sheetname "")
		)
		(fill yes
			(thermal_gap 0.5)
			(thermal_bridge_width 0.5)
			(island_removal_mode 0)
		)
		(polygon
			(pts
				(arc
					(start 380.063502 -379.88113)
					(mid 379.395482 -379.88113)
					(end 380.063502 -379.88113)
				)
			)
		)
	)
	(zone
		(layers "B.Cu" "In13.Cu" "In15.Cu")
		(hatch none 0.5)
		(connect_pads
			(clearance 0)
		)
		(min_thickness 0.25)
		(keepout
			(tracks not_allowed)
			(vias allowed)
			(pads allowed)
			(copperpour not_allowed)
			(footprints allowed)
		)
		(placement
			(enabled no)
			(sheetname "")
		)
		(fill yes
			(thermal_gap 0.5)
			(thermal_bridge_width 0.5)
			(island_removal_mode 0)
		)
		(polygon
			(pts
				(arc
					(start 140.119608 -264.366248)
					(mid 139.489688 -264.366248)
					(end 140.119608 -264.366248)
				)
			)
		)
	)
	(zone
		(layers "B.Cu" "In13.Cu" "In15.Cu")
		(hatch none 0.5)
		(connect_pads
			(clearance 0)
		)
		(min_thickness 0.25)
		(keepout
			(tracks not_allowed)
			(vias allowed)
			(pads allowed)
			(copperpour not_allowed)
			(footprints allowed)
		)
		(placement
			(enabled no)
			(sheetname "")
		)
		(fill yes
			(thermal_gap 0.5)
			(thermal_bridge_width 0.5)
			(island_removal_mode 0)
		)
		(polygon
			(pts
				(arc
					(start 333.076042 -274.896072)
					(mid 332.446122 -274.896072)
					(end 333.076042 -274.896072)
				)
			)
		)
	)
	(zone
		(layers "B.Cu" "In13.Cu" "In15.Cu")
		(hatch none 0.5)
		(connect_pads
			(clearance 0)
		)
		(min_thickness 0.25)
		(keepout
			(tracks not_allowed)
			(vias allowed)
			(pads allowed)
			(copperpour not_allowed)
			(footprints allowed)
		)
		(placement
			(enabled no)
			(sheetname "")
		)
		(fill yes
			(thermal_gap 0.5)
			(thermal_bridge_width 0.5)
			(island_removal_mode 0)
		)
		(polygon
			(pts
				(arc
					(start 391.976102 -377.41733)
					(mid 391.308082 -377.41733)
					(end 391.976102 -377.41733)
				)
			)
		)
	)
	(zone
		(layers "B.Cu" "In13.Cu" "In15.Cu")
		(hatch none 0.5)
		(connect_pads
			(clearance 0)
		)
		(min_thickness 0.25)
		(keepout
			(tracks not_allowed)
			(vias allowed)
			(pads allowed)
			(copperpour not_allowed)
			(footprints allowed)
		)
		(placement
			(enabled no)
			(sheetname "")
		)
		(fill yes
			(thermal_gap 0.5)
			(thermal_bridge_width 0.5)
			(island_removal_mode 0)
		)
		(polygon
			(pts
				(arc
					(start 86.076028 -286.23641)
					(mid 85.446108 -286.23641)
					(end 86.076028 -286.23641)
				)
			)
		)
	)
	(zone
		(layers "B.Cu" "In13.Cu" "In15.Cu")
		(hatch none 0.5)
		(connect_pads
			(clearance 0)
		)
		(min_thickness 0.25)
		(keepout
			(tracks not_allowed)
			(vias allowed)
			(pads allowed)
			(copperpour not_allowed)
			(footprints allowed)
		)
		(placement
			(enabled no)
			(sheetname "")
		)
		(fill yes
			(thermal_gap 0.5)
			(thermal_bridge_width 0.5)
			(island_removal_mode 0)
		)
		(polygon
			(pts
				(arc
					(start 332.776068 -252.584204)
					(mid 332.146148 -252.584204)
					(end 332.776068 -252.584204)
				)
			)
		)
	)
	(zone
		(layers "B.Cu" "In13.Cu" "In15.Cu")
		(hatch none 0.5)
		(connect_pads
			(clearance 0)
		)
		(min_thickness 0.25)
		(keepout
			(tracks not_allowed)
			(vias allowed)
			(pads allowed)
			(copperpour not_allowed)
			(footprints allowed)
		)
		(placement
			(enabled no)
			(sheetname "")
		)
		(fill yes
			(thermal_gap 0.5)
			(thermal_bridge_width 0.5)
			(island_removal_mode 0)
		)
		(polygon
			(pts
				(arc
					(start 97.434146 -388.774432)
					(mid 96.804226 -388.774432)
					(end 97.434146 -388.774432)
				)
			)
		)
	)
	(zone
		(layers "B.Cu" "In13.Cu" "In15.Cu")
		(hatch none 0.5)
		(connect_pads
			(clearance 0)
		)
		(min_thickness 0.25)
		(keepout
			(tracks not_allowed)
			(vias allowed)
			(pads allowed)
			(copperpour not_allowed)
			(footprints allowed)
		)
		(placement
			(enabled no)
			(sheetname "")
		)
		(fill yes
			(thermal_gap 0.5)
			(thermal_bridge_width 0.5)
			(island_removal_mode 0)
		)
		(polygon
			(pts
				(arc
					(start 109.746034 -245.294404)
					(mid 109.116114 -245.294404)
					(end 109.746034 -245.294404)
				)
			)
		)
	)
	(zone
		(layers "B.Cu" "In13.Cu" "In15.Cu")
		(hatch none 0.5)
		(connect_pads
			(clearance 0)
		)
		(min_thickness 0.25)
		(keepout
			(tracks not_allowed)
			(vias allowed)
			(pads allowed)
			(copperpour not_allowed)
			(footprints allowed)
		)
		(placement
			(enabled no)
			(sheetname "")
		)
		(fill yes
			(thermal_gap 0.5)
			(thermal_bridge_width 0.5)
			(island_removal_mode 0)
		)
		(polygon
			(pts
				(arc
					(start 138.709654 -289.47618)
					(mid 138.079734 -289.47618)
					(end 138.709654 -289.47618)
				)
			)
		)
	)
	(zone
		(layers "B.Cu" "In13.Cu" "In15.Cu")
		(hatch none 0.5)
		(connect_pads
			(clearance 0)
		)
		(min_thickness 0.25)
		(keepout
			(tracks not_allowed)
			(vias allowed)
			(pads allowed)
			(copperpour not_allowed)
			(footprints allowed)
		)
		(placement
			(enabled no)
			(sheetname "")
		)
		(fill yes
			(thermal_gap 0.5)
			(thermal_bridge_width 0.5)
			(island_removal_mode 0)
		)
		(polygon
			(pts
				(arc
					(start 17.942052 -284.035246)
					(mid 17.274032 -284.035246)
					(end 17.942052 -284.035246)
				)
			)
		)
	)
	(zone
		(layers "B.Cu" "In13.Cu" "In15.Cu")
		(hatch none 0.5)
		(connect_pads
			(clearance 0)
		)
		(min_thickness 0.25)
		(keepout
			(tracks not_allowed)
			(vias allowed)
			(pads allowed)
			(copperpour not_allowed)
			(footprints allowed)
		)
		(placement
			(enabled no)
			(sheetname "")
		)
		(fill yes
			(thermal_gap 0.5)
			(thermal_bridge_width 0.5)
			(island_removal_mode 0)
		)
		(polygon
			(pts
				(arc
					(start 269.982188 -290.83508)
					(mid 269.314168 -290.83508)
					(end 269.982188 -290.83508)
				)
			)
		)
	)
	(zone
		(layers "B.Cu" "In13.Cu" "In15.Cu")
		(hatch none 0.5)
		(connect_pads
			(clearance 0)
		)
		(min_thickness 0.25)
		(keepout
			(tracks not_allowed)
			(vias allowed)
			(pads allowed)
			(copperpour not_allowed)
			(footprints allowed)
		)
		(placement
			(enabled no)
			(sheetname "")
		)
		(fill yes
			(thermal_gap 0.5)
			(thermal_bridge_width 0.5)
			(island_removal_mode 0)
		)
		(polygon
			(pts
				(arc
					(start 104.576118 -247.724422)
					(mid 103.946198 -247.724422)
					(end 104.576118 -247.724422)
				)
			)
		)
	)
	(zone
		(layers "B.Cu" "In13.Cu" "In15.Cu")
		(hatch none 0.5)
		(connect_pads
			(clearance 0)
		)
		(min_thickness 0.25)
		(keepout
			(tracks not_allowed)
			(vias allowed)
			(pads allowed)
			(copperpour not_allowed)
			(footprints allowed)
		)
		(placement
			(enabled no)
			(sheetname "")
		)
		(fill yes
			(thermal_gap 0.5)
			(thermal_bridge_width 0.5)
			(island_removal_mode 0)
		)
		(polygon
			(pts
				(arc
					(start 334.485996 -274.086066)
					(mid 333.856076 -274.086066)
					(end 334.485996 -274.086066)
				)
			)
		)
	)
	(zone
		(layers "B.Cu" "In13.Cu" "In15.Cu")
		(hatch none 0.5)
		(connect_pads
			(clearance 0)
		)
		(min_thickness 0.25)
		(keepout
			(tracks not_allowed)
			(vias allowed)
			(pads allowed)
			(copperpour not_allowed)
			(footprints allowed)
		)
		(placement
			(enabled no)
			(sheetname "")
		)
		(fill yes
			(thermal_gap 0.5)
			(thermal_bridge_width 0.5)
			(island_removal_mode 0)
		)
		(polygon
			(pts
				(arc
					(start 370.369846 -247.724168)
					(mid 369.739926 -247.724168)
					(end 370.369846 -247.724168)
				)
			)
		)
	)
	(zone
		(layers "B.Cu" "In13.Cu" "In15.Cu")
		(hatch none 0.5)
		(connect_pads
			(clearance 0)
		)
		(min_thickness 0.25)
		(keepout
			(tracks not_allowed)
			(vias allowed)
			(pads allowed)
			(copperpour not_allowed)
			(footprints allowed)
		)
		(placement
			(enabled no)
			(sheetname "")
		)
		(fill yes
			(thermal_gap 0.5)
			(thermal_bridge_width 0.5)
			(island_removal_mode 0)
		)
		(polygon
			(pts
				(arc
					(start 98.295968 -276.516338)
					(mid 97.666048 -276.516338)
					(end 98.295968 -276.516338)
				)
			)
		)
	)
	(zone
		(layers "B.Cu" "In13.Cu" "In15.Cu")
		(hatch none 0.5)
		(connect_pads
			(clearance 0)
		)
		(min_thickness 0.25)
		(keepout
			(tracks not_allowed)
			(vias allowed)
			(pads allowed)
			(copperpour not_allowed)
			(footprints allowed)
		)
		(placement
			(enabled no)
			(sheetname "")
		)
		(fill yes
			(thermal_gap 0.5)
			(thermal_bridge_width 0.5)
			(island_removal_mode 0)
		)
		(polygon
			(pts
				(arc
					(start 454.522078 -210.935062)
					(mid 453.854058 -210.935062)
					(end 454.522078 -210.935062)
				)
			)
		)
	)
	(zone
		(layers "B.Cu" "In13.Cu" "In15.Cu")
		(hatch none 0.5)
		(connect_pads
			(clearance 0)
		)
		(min_thickness 0.25)
		(keepout
			(tracks not_allowed)
			(vias allowed)
			(pads allowed)
			(copperpour not_allowed)
			(footprints allowed)
		)
		(placement
			(enabled no)
			(sheetname "")
		)
		(fill yes
			(thermal_gap 0.5)
			(thermal_bridge_width 0.5)
			(island_removal_mode 0)
		)
		(polygon
			(pts
				(arc
					(start 357.686102 -232.334054)
					(mid 357.056182 -232.334054)
					(end 357.686102 -232.334054)
				)
			)
		)
	)
	(zone
		(layers "B.Cu" "In13.Cu" "In15.Cu")
		(hatch none 0.5)
		(connect_pads
			(clearance 0)
		)
		(min_thickness 0.25)
		(keepout
			(tracks not_allowed)
			(vias allowed)
			(pads allowed)
			(copperpour not_allowed)
			(footprints allowed)
		)
		(placement
			(enabled no)
			(sheetname "")
		)
		(fill yes
			(thermal_gap 0.5)
			(thermal_bridge_width 0.5)
			(island_removal_mode 0)
		)
		(polygon
			(pts
				(arc
					(start 269.982188 -309.535068)
					(mid 269.314168 -309.535068)
					(end 269.982188 -309.535068)
				)
			)
		)
	)
	(zone
		(layers "B.Cu" "In13.Cu" "In15.Cu")
		(hatch none 0.5)
		(connect_pads
			(clearance 0)
		)
		(min_thickness 0.25)
		(keepout
			(tracks not_allowed)
			(vias allowed)
			(pads allowed)
			(copperpour not_allowed)
			(footprints allowed)
		)
		(placement
			(enabled no)
			(sheetname "")
		)
		(fill yes
			(thermal_gap 0.5)
			(thermal_bridge_width 0.5)
			(island_removal_mode 0)
		)
		(polygon
			(pts
				(arc
					(start 317.244476 -420.952168)
					(mid 316.576456 -420.952168)
					(end 317.244476 -420.952168)
				)
			)
		)
	)
	(zone
		(layers "B.Cu" "In13.Cu" "In15.Cu")
		(hatch none 0.5)
		(connect_pads
			(clearance 0)
		)
		(min_thickness 0.25)
		(keepout
			(tracks not_allowed)
			(vias allowed)
			(pads allowed)
			(copperpour not_allowed)
			(footprints allowed)
		)
		(placement
			(enabled no)
			(sheetname "")
		)
		(fill yes
			(thermal_gap 0.5)
			(thermal_bridge_width 0.5)
			(island_removal_mode 0)
		)
		(polygon
			(pts
				(arc
					(start 338.036916 -430.689766)
					(mid 337.262724 -430.689766)
					(end 338.036916 -430.689766)
				)
			)
		)
	)
	(zone
		(layers "B.Cu" "In13.Cu" "In15.Cu")
		(hatch none 0.5)
		(connect_pads
			(clearance 0)
		)
		(min_thickness 0.25)
		(keepout
			(tracks not_allowed)
			(vias allowed)
			(pads allowed)
			(copperpour not_allowed)
			(footprints allowed)
		)
		(placement
			(enabled no)
			(sheetname "")
		)
		(fill yes
			(thermal_gap 0.5)
			(thermal_bridge_width 0.5)
			(island_removal_mode 0)
		)
		(polygon
			(pts
				(arc
					(start 325.036688 -431.889916)
					(mid 324.262496 -431.889916)
					(end 325.036688 -431.889916)
				)
			)
		)
	)
	(zone
		(layers "B.Cu" "In13.Cu" "In15.Cu")
		(hatch none 0.5)
		(connect_pads
			(clearance 0)
		)
		(min_thickness 0.25)
		(keepout
			(tracks not_allowed)
			(vias allowed)
			(pads allowed)
			(copperpour not_allowed)
			(footprints allowed)
		)
		(placement
			(enabled no)
			(sheetname "")
		)
		(fill yes
			(thermal_gap 0.5)
			(thermal_bridge_width 0.5)
			(island_removal_mode 0)
		)
		(polygon
			(pts
				(arc
					(start 386.349748 -238.004096)
					(mid 385.719828 -238.004096)
					(end 386.349748 -238.004096)
				)
			)
		)
	)
	(zone
		(layers "B.Cu" "In13.Cu" "In15.Cu")
		(hatch none 0.5)
		(connect_pads
			(clearance 0)
		)
		(min_thickness 0.25)
		(keepout
			(tracks not_allowed)
			(vias allowed)
			(pads allowed)
			(copperpour not_allowed)
			(footprints allowed)
		)
		(placement
			(enabled no)
			(sheetname "")
		)
		(fill yes
			(thermal_gap 0.5)
			(thermal_bridge_width 0.5)
			(island_removal_mode 0)
		)
		(polygon
			(pts
				(arc
					(start 41.319704 -19.13636)
					(mid 40.651684 -19.13636)
					(end 41.319704 -19.13636)
				)
			)
		)
	)
	(zone
		(layers "B.Cu" "In13.Cu" "In15.Cu")
		(hatch none 0.5)
		(connect_pads
			(clearance 0)
		)
		(min_thickness 0.25)
		(keepout
			(tracks not_allowed)
			(vias allowed)
			(pads allowed)
			(copperpour not_allowed)
			(footprints allowed)
		)
		(placement
			(enabled no)
			(sheetname "")
		)
		(fill yes
			(thermal_gap 0.5)
			(thermal_bridge_width 0.5)
			(island_removal_mode 0)
		)
		(polygon
			(pts
				(arc
					(start 387.407912 -420.952168)
					(mid 386.739892 -420.952168)
					(end 387.407912 -420.952168)
				)
			)
		)
	)
	(zone
		(layers "B.Cu" "In13.Cu" "In15.Cu")
		(hatch none 0.5)
		(connect_pads
			(clearance 0)
		)
		(min_thickness 0.25)
		(keepout
			(tracks not_allowed)
			(vias allowed)
			(pads allowed)
			(copperpour not_allowed)
			(footprints allowed)
		)
		(placement
			(enabled no)
			(sheetname "")
		)
		(fill yes
			(thermal_gap 0.5)
			(thermal_bridge_width 0.5)
			(island_removal_mode 0)
		)
		(polygon
			(pts
				(arc
					(start 269.982188 -283.185108)
					(mid 269.314168 -283.185108)
					(end 269.982188 -283.185108)
				)
			)
		)
	)
	(zone
		(layers "B.Cu" "In13.Cu" "In15.Cu")
		(hatch none 0.5)
		(connect_pads
			(clearance 0)
		)
		(min_thickness 0.25)
		(keepout
			(tracks not_allowed)
			(vias allowed)
			(pads allowed)
			(copperpour not_allowed)
			(footprints allowed)
		)
		(placement
			(enabled no)
			(sheetname "")
		)
		(fill yes
			(thermal_gap 0.5)
			(thermal_bridge_width 0.5)
			(island_removal_mode 0)
		)
		(polygon
			(pts
				(arc
					(start 369.014502 -377.41733)
					(mid 368.346482 -377.41733)
					(end 369.014502 -377.41733)
				)
			)
		)
	)
	(zone
		(layers "B.Cu" "In13.Cu" "In15.Cu")
		(hatch none 0.5)
		(connect_pads
			(clearance 0)
		)
		(min_thickness 0.25)
		(keepout
			(tracks not_allowed)
			(vias allowed)
			(pads allowed)
			(copperpour not_allowed)
			(footprints allowed)
		)
		(placement
			(enabled no)
			(sheetname "")
		)
		(fill yes
			(thermal_gap 0.5)
			(thermal_bridge_width 0.5)
			(island_removal_mode 0)
		)
		(polygon
			(pts
				(arc
					(start 399.137124 -430.889918)
					(mid 398.362932 -430.889918)
					(end 399.137124 -430.889918)
				)
			)
		)
	)
	(zone
		(layers "B.Cu" "In13.Cu" "In15.Cu")
		(hatch none 0.5)
		(connect_pads
			(clearance 0)
		)
		(min_thickness 0.25)
		(keepout
			(tracks not_allowed)
			(vias allowed)
			(pads allowed)
			(copperpour not_allowed)
			(footprints allowed)
		)
		(placement
			(enabled no)
			(sheetname "")
		)
		(fill yes
			(thermal_gap 0.5)
			(thermal_bridge_width 0.5)
			(island_removal_mode 0)
		)
		(polygon
			(pts
				(arc
					(start 367.312702 -379.88113)
					(mid 366.644682 -379.88113)
					(end 367.312702 -379.88113)
				)
			)
		)
	)
	(zone
		(layers "B.Cu" "In13.Cu" "In15.Cu")
		(hatch none 0.5)
		(connect_pads
			(clearance 0)
		)
		(min_thickness 0.25)
		(keepout
			(tracks not_allowed)
			(vias allowed)
			(pads allowed)
			(copperpour not_allowed)
			(footprints allowed)
		)
		(placement
			(enabled no)
			(sheetname "")
		)
		(fill yes
			(thermal_gap 0.5)
			(thermal_bridge_width 0.5)
			(island_removal_mode 0)
		)
		(polygon
			(pts
				(arc
					(start 140.119608 -269.226284)
					(mid 139.489688 -269.226284)
					(end 140.119608 -269.226284)
				)
			)
		)
	)
	(zone
		(layers "B.Cu" "In13.Cu" "In15.Cu")
		(hatch none 0.5)
		(connect_pads
			(clearance 0)
		)
		(min_thickness 0.25)
		(keepout
			(tracks not_allowed)
			(vias allowed)
			(pads allowed)
			(copperpour not_allowed)
			(footprints allowed)
		)
		(placement
			(enabled no)
			(sheetname "")
		)
		(fill yes
			(thermal_gap 0.5)
			(thermal_bridge_width 0.5)
			(island_removal_mode 0)
		)
		(polygon
			(pts
				(arc
					(start 24.249888 -19.13636)
					(mid 23.581868 -19.13636)
					(end 24.249888 -19.13636)
				)
			)
		)
	)
	(zone
		(layers "B.Cu" "In13.Cu" "In15.Cu")
		(hatch none 0.5)
		(connect_pads
			(clearance 0)
		)
		(min_thickness 0.25)
		(keepout
			(tracks not_allowed)
			(vias allowed)
			(pads allowed)
			(copperpour not_allowed)
			(footprints allowed)
		)
		(placement
			(enabled no)
			(sheetname "")
		)
		(fill yes
			(thermal_gap 0.5)
			(thermal_bridge_width 0.5)
			(island_removal_mode 0)
		)
		(polygon
			(pts
				(arc
					(start 357.986076 -277.32609)
					(mid 357.356156 -277.32609)
					(end 357.986076 -277.32609)
				)
			)
		)
	)
	(zone
		(layers "B.Cu" "In13.Cu" "In15.Cu")
		(hatch none 0.5)
		(connect_pads
			(clearance 0)
		)
		(min_thickness 0.25)
		(keepout
			(tracks not_allowed)
			(vias allowed)
			(pads allowed)
			(copperpour not_allowed)
			(footprints allowed)
		)
		(placement
			(enabled no)
			(sheetname "")
		)
		(fill yes
			(thermal_gap 0.5)
			(thermal_bridge_width 0.5)
			(island_removal_mode 0)
		)
		(polygon
			(pts
				(arc
					(start 138.239754 -270.846296)
					(mid 137.609834 -270.846296)
					(end 138.239754 -270.846296)
				)
			)
		)
	)
	(zone
		(layers "B.Cu" "In13.Cu" "In15.Cu")
		(hatch none 0.5)
		(connect_pads
			(clearance 0)
		)
		(min_thickness 0.25)
		(keepout
			(tracks not_allowed)
			(vias allowed)
			(pads allowed)
			(copperpour not_allowed)
			(footprints allowed)
		)
		(placement
			(enabled no)
			(sheetname "")
		)
		(fill yes
			(thermal_gap 0.5)
			(thermal_bridge_width 0.5)
			(island_removal_mode 0)
		)
		(polygon
			(pts
				(arc
					(start 130.870706 -371.49913)
					(mid 130.202686 -371.49913)
					(end 130.870706 -371.49913)
				)
			)
		)
	)
	(zone
		(layers "B.Cu" "In13.Cu" "In15.Cu")
		(hatch none 0.5)
		(connect_pads
			(clearance 0)
		)
		(min_thickness 0.25)
		(keepout
			(tracks not_allowed)
			(vias allowed)
			(pads allowed)
			(copperpour not_allowed)
			(footprints allowed)
		)
		(placement
			(enabled no)
			(sheetname "")
		)
		(fill yes
			(thermal_gap 0.5)
			(thermal_bridge_width 0.5)
			(island_removal_mode 0)
		)
		(polygon
			(pts
				(arc
					(start 106.755946 -274.896326)
					(mid 106.126026 -274.896326)
					(end 106.755946 -274.896326)
				)
			)
		)
	)
	(zone
		(layers "B.Cu" "In13.Cu" "In15.Cu")
		(hatch none 0.5)
		(connect_pads
			(clearance 0)
		)
		(min_thickness 0.25)
		(keepout
			(tracks not_allowed)
			(vias allowed)
			(pads allowed)
			(copperpour not_allowed)
			(footprints allowed)
		)
		(placement
			(enabled no)
			(sheetname "")
		)
		(fill yes
			(thermal_gap 0.5)
			(thermal_bridge_width 0.5)
			(island_removal_mode 0)
		)
		(polygon
			(pts
				(arc
					(start 386.179822 -275.706078)
					(mid 385.549902 -275.706078)
					(end 386.179822 -275.706078)
				)
			)
		)
	)
	(zone
		(layers "B.Cu" "In13.Cu" "In15.Cu")
		(hatch none 0.5)
		(connect_pads
			(clearance 0)
		)
		(min_thickness 0.25)
		(keepout
			(tracks not_allowed)
			(vias allowed)
			(pads allowed)
			(copperpour not_allowed)
			(footprints allowed)
		)
		(placement
			(enabled no)
			(sheetname "")
		)
		(fill yes
			(thermal_gap 0.5)
			(thermal_bridge_width 0.5)
			(island_removal_mode 0)
		)
		(polygon
			(pts
				(arc
					(start 368.789712 -276.516084)
					(mid 368.159792 -276.516084)
					(end 368.789712 -276.516084)
				)
			)
		)
	)
	(zone
		(layers "B.Cu" "In13.Cu" "In15.Cu")
		(hatch none 0.5)
		(connect_pads
			(clearance 0)
		)
		(min_thickness 0.25)
		(keepout
			(tracks not_allowed)
			(vias allowed)
			(pads allowed)
			(copperpour not_allowed)
			(footprints allowed)
		)
		(placement
			(enabled no)
			(sheetname "")
		)
		(fill yes
			(thermal_gap 0.5)
			(thermal_bridge_width 0.5)
			(island_removal_mode 0)
		)
		(polygon
			(pts
				(arc
					(start 84.836 -228.284532)
					(mid 84.20608 -228.284532)
					(end 84.836 -228.284532)
				)
			)
		)
	)
	(zone
		(layers "B.Cu" "In13.Cu" "In15.Cu")
		(hatch none 0.5)
		(connect_pads
			(clearance 0)
		)
		(min_thickness 0.25)
		(keepout
			(tracks not_allowed)
			(vias allowed)
			(pads allowed)
			(copperpour not_allowed)
			(footprints allowed)
		)
		(placement
			(enabled no)
			(sheetname "")
		)
		(fill yes
			(thermal_gap 0.5)
			(thermal_bridge_width 0.5)
			(island_removal_mode 0)
		)
		(polygon
			(pts
				(arc
					(start 355.636068 -279.756108)
					(mid 355.006148 -279.756108)
					(end 355.636068 -279.756108)
				)
			)
		)
	)
	(zone
		(layers "B.Cu" "In13.Cu" "In15.Cu")
		(hatch none 0.5)
		(connect_pads
			(clearance 0)
		)
		(min_thickness 0.25)
		(keepout
			(tracks not_allowed)
			(vias allowed)
			(pads allowed)
			(copperpour not_allowed)
			(footprints allowed)
		)
		(placement
			(enabled no)
			(sheetname "")
		)
		(fill yes
			(thermal_gap 0.5)
			(thermal_bridge_width 0.5)
			(island_removal_mode 0)
		)
		(polygon
			(pts
				(arc
					(start 345.43365 -394.385292)
					(mid 344.80373 -394.385292)
					(end 345.43365 -394.385292)
				)
			)
		)
	)
	(zone
		(layers "B.Cu" "In13.Cu" "In15.Cu")
		(hatch none 0.5)
		(connect_pads
			(clearance 0)
		)
		(min_thickness 0.25)
		(keepout
			(tracks not_allowed)
			(vias allowed)
			(pads allowed)
			(copperpour not_allowed)
			(footprints allowed)
		)
		(placement
			(enabled no)
			(sheetname "")
		)
		(fill yes
			(thermal_gap 0.5)
			(thermal_bridge_width 0.5)
			(island_removal_mode 0)
		)
		(polygon
			(pts
				(arc
					(start 119.90959 -274.896326)
					(mid 119.27967 -274.896326)
					(end 119.90959 -274.896326)
				)
			)
		)
	)
	(zone
		(layers "B.Cu" "In13.Cu" "In15.Cu")
		(hatch none 0.5)
		(connect_pads
			(clearance 0)
		)
		(min_thickness 0.25)
		(keepout
			(tracks not_allowed)
			(vias allowed)
			(pads allowed)
			(copperpour not_allowed)
			(footprints allowed)
		)
		(placement
			(enabled no)
			(sheetname "")
		)
		(fill yes
			(thermal_gap 0.5)
			(thermal_bridge_width 0.5)
			(island_removal_mode 0)
		)
		(polygon
			(pts
				(arc
					(start 413.75965 -6.725158)
					(mid 413.09163 -6.725158)
					(end 413.75965 -6.725158)
				)
			)
		)
	)
	(zone
		(layers "B.Cu" "In13.Cu" "In15.Cu")
		(hatch none 0.5)
		(connect_pads
			(clearance 0)
		)
		(min_thickness 0.25)
		(keepout
			(tracks not_allowed)
			(vias allowed)
			(pads allowed)
			(copperpour not_allowed)
			(footprints allowed)
		)
		(placement
			(enabled no)
			(sheetname "")
		)
		(fill yes
			(thermal_gap 0.5)
			(thermal_bridge_width 0.5)
			(island_removal_mode 0)
		)
		(polygon
			(pts
				(arc
					(start 118.958106 -369.03533)
					(mid 118.290086 -369.03533)
					(end 118.958106 -369.03533)
				)
			)
		)
	)
	(zone
		(layers "B.Cu" "In13.Cu" "In15.Cu")
		(hatch none 0.5)
		(connect_pads
			(clearance 0)
		)
		(min_thickness 0.25)
		(keepout
			(tracks not_allowed)
			(vias allowed)
			(pads allowed)
			(copperpour not_allowed)
			(footprints allowed)
		)
		(placement
			(enabled no)
			(sheetname "")
		)
		(fill yes
			(thermal_gap 0.5)
			(thermal_bridge_width 0.5)
			(island_removal_mode 0)
		)
		(polygon
			(pts
				(arc
					(start 265.88212 -254.284988)
					(mid 265.2141 -254.284988)
					(end 265.88212 -254.284988)
				)
			)
		)
	)
	(zone
		(layers "B.Cu" "In13.Cu" "In15.Cu")
		(hatch none 0.5)
		(connect_pads
			(clearance 0)
		)
		(min_thickness 0.25)
		(keepout
			(tracks not_allowed)
			(vias allowed)
			(pads allowed)
			(copperpour not_allowed)
			(footprints allowed)
		)
		(placement
			(enabled no)
			(sheetname "")
		)
		(fill yes
			(thermal_gap 0.5)
			(thermal_bridge_width 0.5)
			(island_removal_mode 0)
		)
		(polygon
			(pts
				(arc
					(start 22.04212 -219.435426)
					(mid 21.3741 -219.435426)
					(end 22.04212 -219.435426)
				)
			)
		)
	)
	(zone
		(layers "B.Cu" "In13.Cu" "In15.Cu")
		(hatch none 0.5)
		(connect_pads
			(clearance 0)
		)
		(min_thickness 0.25)
		(keepout
			(tracks not_allowed)
			(vias allowed)
			(pads allowed)
			(copperpour not_allowed)
			(footprints allowed)
		)
		(placement
			(enabled no)
			(sheetname "")
		)
		(fill yes
			(thermal_gap 0.5)
			(thermal_bridge_width 0.5)
			(island_removal_mode 0)
		)
		(polygon
			(pts
				(arc
					(start 104.876092 -274.896326)
					(mid 104.246172 -274.896326)
					(end 104.876092 -274.896326)
				)
			)
		)
	)
	(zone
		(layers "B.Cu" "In13.Cu" "In15.Cu")
		(hatch none 0.5)
		(connect_pads
			(clearance 0)
		)
		(min_thickness 0.25)
		(keepout
			(tracks not_allowed)
			(vias allowed)
			(pads allowed)
			(copperpour not_allowed)
			(footprints allowed)
		)
		(placement
			(enabled no)
			(sheetname "")
		)
		(fill yes
			(thermal_gap 0.5)
			(thermal_bridge_width 0.5)
			(island_removal_mode 0)
		)
		(polygon
			(pts
				(arc
					(start 454.522078 -309.535068)
					(mid 453.854058 -309.535068)
					(end 454.522078 -309.535068)
				)
			)
		)
	)
	(zone
		(layers "B.Cu" "In13.Cu" "In15.Cu")
		(hatch none 0.5)
		(connect_pads
			(clearance 0)
		)
		(min_thickness 0.25)
		(keepout
			(tracks not_allowed)
			(vias allowed)
			(pads allowed)
			(copperpour not_allowed)
			(footprints allowed)
		)
		(placement
			(enabled no)
			(sheetname "")
		)
		(fill yes
			(thermal_gap 0.5)
			(thermal_bridge_width 0.5)
			(island_removal_mode 0)
		)
		(polygon
			(pts
				(arc
					(start 206.58201 -285.735268)
					(mid 205.91399 -285.735268)
					(end 206.58201 -285.735268)
				)
			)
		)
	)
	(zone
		(layers "B.Cu" "In13.Cu" "In15.Cu")
		(hatch none 0.5)
		(connect_pads
			(clearance 0)
		)
		(min_thickness 0.25)
		(keepout
			(tracks not_allowed)
			(vias allowed)
			(pads allowed)
			(copperpour not_allowed)
			(footprints allowed)
		)
		(placement
			(enabled no)
			(sheetname "")
		)
		(fill yes
			(thermal_gap 0.5)
			(thermal_bridge_width 0.5)
			(island_removal_mode 0)
		)
		(polygon
			(pts
				(arc
					(start 125.54966 -274.896326)
					(mid 124.91974 -274.896326)
					(end 125.54966 -274.896326)
				)
			)
		)
	)
	(zone
		(layers "B.Cu" "In13.Cu" "In15.Cu")
		(hatch none 0.5)
		(connect_pads
			(clearance 0)
		)
		(min_thickness 0.25)
		(keepout
			(tracks not_allowed)
			(vias allowed)
			(pads allowed)
			(copperpour not_allowed)
			(footprints allowed)
		)
		(placement
			(enabled no)
			(sheetname "")
		)
		(fill yes
			(thermal_gap 0.5)
			(thermal_bridge_width 0.5)
			(island_removal_mode 0)
		)
		(polygon
			(pts
				(arc
					(start 319.0367 -429.689768)
					(mid 318.262508 -429.689768)
					(end 319.0367 -429.689768)
				)
			)
		)
	)
	(zone
		(layers "B.Cu" "In13.Cu" "In15.Cu")
		(hatch none 0.5)
		(connect_pads
			(clearance 0)
		)
		(min_thickness 0.25)
		(keepout
			(tracks not_allowed)
			(vias allowed)
			(pads allowed)
			(copperpour not_allowed)
			(footprints allowed)
		)
		(placement
			(enabled no)
			(sheetname "")
		)
		(fill yes
			(thermal_gap 0.5)
			(thermal_bridge_width 0.5)
			(island_removal_mode 0)
		)
		(polygon
			(pts
				(arc
					(start 269.982188 -284.88513)
					(mid 269.314168 -284.88513)
					(end 269.982188 -284.88513)
				)
			)
		)
	)
	(zone
		(layers "B.Cu" "In13.Cu" "In15.Cu")
		(hatch none 0.5)
		(connect_pads
			(clearance 0)
		)
		(min_thickness 0.25)
		(keepout
			(tracks not_allowed)
			(vias allowed)
			(pads allowed)
			(copperpour not_allowed)
			(footprints allowed)
		)
		(placement
			(enabled no)
			(sheetname "")
		)
		(fill yes
			(thermal_gap 0.5)
			(thermal_bridge_width 0.5)
			(island_removal_mode 0)
		)
		(polygon
			(pts
				(arc
					(start 365.02975 -274.896072)
					(mid 364.39983 -274.896072)
					(end 365.02975 -274.896072)
				)
			)
		)
	)
	(zone
		(layers "B.Cu" "In13.Cu" "In15.Cu")
		(hatch none 0.5)
		(connect_pads
			(clearance 0)
		)
		(min_thickness 0.25)
		(keepout
			(tracks not_allowed)
			(vias allowed)
			(pads allowed)
			(copperpour not_allowed)
			(footprints allowed)
		)
		(placement
			(enabled no)
			(sheetname "")
		)
		(fill yes
			(thermal_gap 0.5)
			(thermal_bridge_width 0.5)
			(island_removal_mode 0)
		)
		(polygon
			(pts
				(arc
					(start 59.036966 -430.889918)
					(mid 58.262774 -430.889918)
					(end 59.036966 -430.889918)
				)
			)
		)
	)
	(zone
		(layers "B.Cu" "In13.Cu" "In15.Cu")
		(hatch none 0.5)
		(connect_pads
			(clearance 0)
		)
		(min_thickness 0.25)
		(keepout
			(tracks not_allowed)
			(vias allowed)
			(pads allowed)
			(copperpour not_allowed)
			(footprints allowed)
		)
		(placement
			(enabled no)
			(sheetname "")
		)
		(fill yes
			(thermal_gap 0.5)
			(thermal_bridge_width 0.5)
			(island_removal_mode 0)
		)
		(polygon
			(pts
				(arc
					(start 115.379754 -232.334308)
					(mid 114.749834 -232.334308)
					(end 115.379754 -232.334308)
				)
			)
		)
	)
	(zone
		(layers "B.Cu" "In13.Cu" "In15.Cu")
		(hatch none 0.5)
		(connect_pads
			(clearance 0)
		)
		(min_thickness 0.25)
		(keepout
			(tracks not_allowed)
			(vias allowed)
			(pads allowed)
			(copperpour not_allowed)
			(footprints allowed)
		)
		(placement
			(enabled no)
			(sheetname "")
		)
		(fill yes
			(thermal_gap 0.5)
			(thermal_bridge_width 0.5)
			(island_removal_mode 0)
		)
		(polygon
			(pts
				(arc
					(start 332.606142 -282.186126)
					(mid 331.976222 -282.186126)
					(end 332.606142 -282.186126)
				)
			)
		)
	)
	(zone
		(layers "B.Cu" "In13.Cu" "In15.Cu")
		(hatch none 0.5)
		(connect_pads
			(clearance 0)
		)
		(min_thickness 0.25)
		(keepout
			(tracks not_allowed)
			(vias allowed)
			(pads allowed)
			(copperpour not_allowed)
			(footprints allowed)
		)
		(placement
			(enabled no)
			(sheetname "")
		)
		(fill yes
			(thermal_gap 0.5)
			(thermal_bridge_width 0.5)
			(island_removal_mode 0)
		)
		(polygon
			(pts
				(arc
					(start 139.649708 -284.616398)
					(mid 139.019788 -284.616398)
					(end 139.649708 -284.616398)
				)
			)
		)
	)
	(zone
		(layers "B.Cu" "In13.Cu" "In15.Cu")
		(hatch none 0.5)
		(connect_pads
			(clearance 0)
		)
		(min_thickness 0.25)
		(keepout
			(tracks not_allowed)
			(vias allowed)
			(pads allowed)
			(copperpour not_allowed)
			(footprints allowed)
		)
		(placement
			(enabled no)
			(sheetname "")
		)
		(fill yes
			(thermal_gap 0.5)
			(thermal_bridge_width 0.5)
			(island_removal_mode 0)
		)
		(polygon
			(pts
				(arc
					(start 84.666074 -272.466308)
					(mid 84.036154 -272.466308)
					(end 84.666074 -272.466308)
				)
			)
		)
	)
	(zone
		(layers "B.Cu" "In13.Cu" "In15.Cu")
		(hatch none 0.5)
		(connect_pads
			(clearance 0)
		)
		(min_thickness 0.25)
		(keepout
			(tracks not_allowed)
			(vias allowed)
			(pads allowed)
			(copperpour not_allowed)
			(footprints allowed)
		)
		(placement
			(enabled no)
			(sheetname "")
		)
		(fill yes
			(thermal_gap 0.5)
			(thermal_bridge_width 0.5)
			(island_removal_mode 0)
		)
		(polygon
			(pts
				(arc
					(start 109.105954 -277.326344)
					(mid 108.476034 -277.326344)
					(end 109.105954 -277.326344)
				)
			)
		)
	)
	(zone
		(layers "B.Cu" "In13.Cu" "In15.Cu")
		(hatch none 0.5)
		(connect_pads
			(clearance 0)
		)
		(min_thickness 0.25)
		(keepout
			(tracks not_allowed)
			(vias allowed)
			(pads allowed)
			(copperpour not_allowed)
			(footprints allowed)
		)
		(placement
			(enabled no)
			(sheetname "")
		)
		(fill yes
			(thermal_gap 0.5)
			(thermal_bridge_width 0.5)
			(island_removal_mode 0)
		)
		(polygon
			(pts
				(arc
					(start 387.759702 -245.29415)
					(mid 387.129782 -245.29415)
					(end 387.759702 -245.29415)
				)
			)
		)
	)
	(zone
		(layers "B.Cu" "In13.Cu" "In15.Cu")
		(hatch none 0.5)
		(connect_pads
			(clearance 0)
		)
		(min_thickness 0.25)
		(keepout
			(tracks not_allowed)
			(vias allowed)
			(pads allowed)
			(copperpour not_allowed)
			(footprints allowed)
		)
		(placement
			(enabled no)
			(sheetname "")
		)
		(fill yes
			(thermal_gap 0.5)
			(thermal_bridge_width 0.5)
			(island_removal_mode 0)
		)
		(polygon
			(pts
				(arc
					(start 386.136896 -430.889918)
					(mid 385.362704 -430.889918)
					(end 386.136896 -430.889918)
				)
			)
		)
	)
	(zone
		(layers "B.Cu" "In13.Cu" "In15.Cu")
		(hatch none 0.5)
		(connect_pads
			(clearance 0)
		)
		(min_thickness 0.25)
		(keepout
			(tracks not_allowed)
			(vias allowed)
			(pads allowed)
			(copperpour not_allowed)
			(footprints allowed)
		)
		(placement
			(enabled no)
			(sheetname "")
		)
		(fill yes
			(thermal_gap 0.5)
			(thermal_bridge_width 0.5)
			(island_removal_mode 0)
		)
		(polygon
			(pts
				(arc
					(start 417.359592 -6.725158)
					(mid 416.691572 -6.725158)
					(end 417.359592 -6.725158)
				)
			)
		)
	)
	(zone
		(layers "B.Cu" "In13.Cu" "In15.Cu")
		(hatch none 0.5)
		(connect_pads
			(clearance 0)
		)
		(min_thickness 0.25)
		(keepout
			(tracks not_allowed)
			(vias allowed)
			(pads allowed)
			(copperpour not_allowed)
			(footprints allowed)
		)
		(placement
			(enabled no)
			(sheetname "")
		)
		(fill yes
			(thermal_gap 0.5)
			(thermal_bridge_width 0.5)
			(island_removal_mode 0)
		)
		(polygon
			(pts
				(arc
					(start 265.88212 -230.485188)
					(mid 265.2141 -230.485188)
					(end 265.88212 -230.485188)
				)
			)
		)
	)
	(zone
		(layers "B.Cu" "In13.Cu" "In15.Cu")
		(hatch none 0.5)
		(connect_pads
			(clearance 0)
		)
		(min_thickness 0.25)
		(keepout
			(tracks not_allowed)
			(vias allowed)
			(pads allowed)
			(copperpour not_allowed)
			(footprints allowed)
		)
		(placement
			(enabled no)
			(sheetname "")
		)
		(fill yes
			(thermal_gap 0.5)
			(thermal_bridge_width 0.5)
			(island_removal_mode 0)
		)
		(polygon
			(pts
				(arc
					(start 386.349748 -255.824228)
					(mid 385.719828 -255.824228)
					(end 386.349748 -255.824228)
				)
			)
		)
	)
	(zone
		(layers "B.Cu" "In13.Cu" "In15.Cu")
		(hatch none 0.5)
		(connect_pads
			(clearance 0)
		)
		(min_thickness 0.25)
		(keepout
			(tracks not_allowed)
			(vias allowed)
			(pads allowed)
			(copperpour not_allowed)
			(footprints allowed)
		)
		(placement
			(enabled no)
			(sheetname "")
		)
		(fill yes
			(thermal_gap 0.5)
			(thermal_bridge_width 0.5)
			(island_removal_mode 0)
		)
		(polygon
			(pts
				(arc
					(start 375.821702 -377.41733)
					(mid 375.153682 -377.41733)
					(end 375.821702 -377.41733)
				)
			)
		)
	)
	(zone
		(layers "B.Cu" "In13.Cu" "In15.Cu")
		(hatch none 0.5)
		(connect_pads
			(clearance 0)
		)
		(min_thickness 0.25)
		(keepout
			(tracks not_allowed)
			(vias allowed)
			(pads allowed)
			(copperpour not_allowed)
			(footprints allowed)
		)
		(placement
			(enabled no)
			(sheetname "")
		)
		(fill yes
			(thermal_gap 0.5)
			(thermal_bridge_width 0.5)
			(island_removal_mode 0)
		)
		(polygon
			(pts
				(arc
					(start 202.481942 -295.085262)
					(mid 201.813922 -295.085262)
					(end 202.481942 -295.085262)
				)
			)
		)
	)
	(zone
		(layers "B.Cu" "In13.Cu" "In15.Cu")
		(hatch none 0.5)
		(connect_pads
			(clearance 0)
		)
		(min_thickness 0.25)
		(keepout
			(tracks not_allowed)
			(vias allowed)
			(pads allowed)
			(copperpour not_allowed)
			(footprints allowed)
		)
		(placement
			(enabled no)
			(sheetname "")
		)
		(fill yes
			(thermal_gap 0.5)
			(thermal_bridge_width 0.5)
			(island_removal_mode 0)
		)
		(polygon
			(pts
				(arc
					(start 332.776068 -255.824228)
					(mid 332.146148 -255.824228)
					(end 332.776068 -255.824228)
				)
			)
		)
	)
	(zone
		(layers "B.Cu" "In13.Cu" "In15.Cu")
		(hatch none 0.5)
		(connect_pads
			(clearance 0)
		)
		(min_thickness 0.25)
		(keepout
			(tracks not_allowed)
			(vias allowed)
			(pads allowed)
			(copperpour not_allowed)
			(footprints allowed)
		)
		(placement
			(enabled no)
			(sheetname "")
		)
		(fill yes
			(thermal_gap 0.5)
			(thermal_bridge_width 0.5)
			(island_removal_mode 0)
		)
		(polygon
			(pts
				(arc
					(start 386.179822 -288.66592)
					(mid 385.549902 -288.66592)
					(end 386.179822 -288.66592)
				)
			)
		)
	)
	(zone
		(layers "B.Cu" "In15.Cu")
		(hatch none 0.5)
		(connect_pads
			(clearance 0)
		)
		(min_thickness 0.25)
		(keepout
			(tracks not_allowed)
			(vias allowed)
			(pads allowed)
			(copperpour not_allowed)
			(footprints allowed)
		)
		(placement
			(enabled no)
			(sheetname "")
		)
		(fill yes
			(thermal_gap 0.5)
			(thermal_bridge_width 0.5)
			(island_removal_mode 0)
		)
		(polygon
			(pts
				(arc
					(start 89.83599 -276.516338)
					(mid 89.20607 -276.516338)
					(end 89.83599 -276.516338)
				)
			)
		)
	)
	(zone
		(layers "B.Cu" "In15.Cu")
		(hatch none 0.5)
		(connect_pads
			(clearance 0)
		)
		(min_thickness 0.25)
		(keepout
			(tracks not_allowed)
			(vias allowed)
			(pads allowed)
			(copperpour not_allowed)
			(footprints allowed)
		)
		(placement
			(enabled no)
			(sheetname "")
		)
		(fill yes
			(thermal_gap 0.5)
			(thermal_bridge_width 0.5)
			(island_removal_mode 0)
		)
		(polygon
			(pts
				(arc
					(start 420.246048 -207.535018)
					(mid 419.578028 -207.535018)
					(end 420.246048 -207.535018)
				)
			)
		)
	)
	(zone
		(layers "B.Cu" "In15.Cu")
		(hatch none 0.5)
		(connect_pads
			(clearance 0)
		)
		(min_thickness 0.25)
		(keepout
			(tracks not_allowed)
			(vias allowed)
			(pads allowed)
			(copperpour not_allowed)
			(footprints allowed)
		)
		(placement
			(enabled no)
			(sheetname "")
		)
		(fill yes
			(thermal_gap 0.5)
			(thermal_bridge_width 0.5)
			(island_removal_mode 0)
		)
		(polygon
			(pts
				(arc
					(start 382.88976 -263.555988)
					(mid 382.25984 -263.555988)
					(end 382.88976 -263.555988)
				)
			)
		)
	)
	(zone
		(layers "B.Cu" "In15.Cu")
		(hatch none 0.5)
		(connect_pads
			(clearance 0)
		)
		(min_thickness 0.25)
		(keepout
			(tracks not_allowed)
			(vias allowed)
			(pads allowed)
			(copperpour not_allowed)
			(footprints allowed)
		)
		(placement
			(enabled no)
			(sheetname "")
		)
		(fill yes
			(thermal_gap 0.5)
			(thermal_bridge_width 0.5)
			(island_removal_mode 0)
		)
		(polygon
			(pts
				(arc
					(start 87.655908 -255.824482)
					(mid 87.025988 -255.824482)
					(end 87.655908 -255.824482)
				)
			)
		)
	)
	(zone
		(layers "B.Cu" "In15.Cu")
		(hatch none 0.5)
		(connect_pads
			(clearance 0)
		)
		(min_thickness 0.25)
		(keepout
			(tracks not_allowed)
			(vias allowed)
			(pads allowed)
			(copperpour not_allowed)
			(footprints allowed)
		)
		(placement
			(enabled no)
			(sheetname "")
		)
		(fill yes
			(thermal_gap 0.5)
			(thermal_bridge_width 0.5)
			(island_removal_mode 0)
		)
		(polygon
			(pts
				(arc
					(start 48.10633 -385.31038)
					(mid 47.47641 -385.31038)
					(end 48.10633 -385.31038)
				)
			)
		)
	)
	(zone
		(layers "B.Cu" "In15.Cu")
		(hatch none 0.5)
		(connect_pads
			(clearance 0)
		)
		(min_thickness 0.25)
		(keepout
			(tracks not_allowed)
			(vias allowed)
			(pads allowed)
			(copperpour not_allowed)
			(footprints allowed)
		)
		(placement
			(enabled no)
			(sheetname "")
		)
		(fill yes
			(thermal_gap 0.5)
			(thermal_bridge_width 0.5)
			(island_removal_mode 0)
		)
		(polygon
			(pts
				(arc
					(start 337.306158 -275.706078)
					(mid 336.676238 -275.706078)
					(end 337.306158 -275.706078)
				)
			)
		)
	)
	(zone
		(layers "B.Cu" "In15.Cu")
		(hatch none 0.5)
		(connect_pads
			(clearance 0)
		)
		(min_thickness 0.25)
		(keepout
			(tracks not_allowed)
			(vias allowed)
			(pads allowed)
			(copperpour not_allowed)
			(footprints allowed)
		)
		(placement
			(enabled no)
			(sheetname "")
		)
		(fill yes
			(thermal_gap 0.5)
			(thermal_bridge_width 0.5)
			(island_removal_mode 0)
		)
		(polygon
			(pts
				(arc
					(start 82.037174 -434.289962)
					(mid 81.262982 -434.289962)
					(end 82.037174 -434.289962)
				)
			)
		)
	)
	(zone
		(layers "B.Cu" "In15.Cu")
		(hatch none 0.5)
		(connect_pads
			(clearance 0)
		)
		(min_thickness 0.25)
		(keepout
			(tracks not_allowed)
			(vias allowed)
			(pads allowed)
			(copperpour not_allowed)
			(footprints allowed)
		)
		(placement
			(enabled no)
			(sheetname "")
		)
		(fill yes
			(thermal_gap 0.5)
			(thermal_bridge_width 0.5)
			(island_removal_mode 0)
		)
		(polygon
			(pts
				(arc
					(start 296.058082 -291.684964)
					(mid 295.390062 -291.684964)
					(end 296.058082 -291.684964)
				)
			)
		)
	)
	(zone
		(layers "B.Cu" "In15.Cu")
		(hatch none 0.5)
		(connect_pads
			(clearance 0)
		)
		(min_thickness 0.25)
		(keepout
			(tracks not_allowed)
			(vias allowed)
			(pads allowed)
			(copperpour not_allowed)
			(footprints allowed)
		)
		(placement
			(enabled no)
			(sheetname "")
		)
		(fill yes
			(thermal_gap 0.5)
			(thermal_bridge_width 0.5)
			(island_removal_mode 0)
		)
		(polygon
			(pts
				(arc
					(start 118.029736 -273.276314)
					(mid 117.399816 -273.276314)
					(end 118.029736 -273.276314)
				)
			)
		)
	)
	(zone
		(layers "B.Cu" "In15.Cu")
		(hatch none 0.5)
		(connect_pads
			(clearance 0)
		)
		(min_thickness 0.25)
		(keepout
			(tracks not_allowed)
			(vias allowed)
			(pads allowed)
			(copperpour not_allowed)
			(footprints allowed)
		)
		(placement
			(enabled no)
			(sheetname "")
		)
		(fill yes
			(thermal_gap 0.5)
			(thermal_bridge_width 0.5)
			(island_removal_mode 0)
		)
		(polygon
			(pts
				(arc
					(start 89.83599 -281.376374)
					(mid 89.20607 -281.376374)
					(end 89.83599 -281.376374)
				)
			)
		)
	)
	(zone
		(layers "B.Cu" "In15.Cu")
		(hatch none 0.5)
		(connect_pads
			(clearance 0)
		)
		(min_thickness 0.25)
		(keepout
			(tracks not_allowed)
			(vias allowed)
			(pads allowed)
			(copperpour not_allowed)
			(footprints allowed)
		)
		(placement
			(enabled no)
			(sheetname "")
		)
		(fill yes
			(thermal_gap 0.5)
			(thermal_bridge_width 0.5)
			(island_removal_mode 0)
		)
		(polygon
			(pts
				(arc
					(start 424.346116 -212.635084)
					(mid 423.678096 -212.635084)
					(end 424.346116 -212.635084)
				)
			)
		)
	)
	(zone
		(layers "B.Cu" "In15.Cu")
		(hatch none 0.5)
		(connect_pads
			(clearance 0)
		)
		(min_thickness 0.25)
		(keepout
			(tracks not_allowed)
			(vias allowed)
			(pads allowed)
			(copperpour not_allowed)
			(footprints allowed)
		)
		(placement
			(enabled no)
			(sheetname "")
		)
		(fill yes
			(thermal_gap 0.5)
			(thermal_bridge_width 0.5)
			(island_removal_mode 0)
		)
		(polygon
			(pts
				(arc
					(start 83.07832 -393.292838)
					(mid 82.4103 -393.292838)
					(end 83.07832 -393.292838)
				)
			)
		)
	)
	(zone
		(layers "B.Cu" "In15.Cu")
		(hatch none 0.5)
		(connect_pads
			(clearance 0)
		)
		(min_thickness 0.25)
		(keepout
			(tracks not_allowed)
			(vias allowed)
			(pads allowed)
			(copperpour not_allowed)
			(footprints allowed)
		)
		(placement
			(enabled no)
			(sheetname "")
		)
		(fill yes
			(thermal_gap 0.5)
			(thermal_bridge_width 0.5)
			(island_removal_mode 0)
		)
		(polygon
			(pts
				(arc
					(start 420.246048 -237.285022)
					(mid 419.578028 -237.285022)
					(end 420.246048 -237.285022)
				)
			)
		)
	)
	(zone
		(layers "B.Cu" "In15.Cu")
		(hatch none 0.5)
		(connect_pads
			(clearance 0)
		)
		(min_thickness 0.25)
		(keepout
			(tracks not_allowed)
			(vias allowed)
			(pads allowed)
			(copperpour not_allowed)
			(footprints allowed)
		)
		(placement
			(enabled no)
			(sheetname "")
		)
		(fill yes
			(thermal_gap 0.5)
			(thermal_bridge_width 0.5)
			(island_removal_mode 0)
		)
		(polygon
			(pts
				(arc
					(start 102.05593 -270.03629)
					(mid 101.42601 -270.03629)
					(end 102.05593 -270.03629)
				)
			)
		)
	)
	(zone
		(layers "B.Cu" "In15.Cu")
		(hatch none 0.5)
		(connect_pads
			(clearance 0)
		)
		(min_thickness 0.25)
		(keepout
			(tracks not_allowed)
			(vias allowed)
			(pads allowed)
			(copperpour not_allowed)
			(footprints allowed)
		)
		(placement
			(enabled no)
			(sheetname "")
		)
		(fill yes
			(thermal_gap 0.5)
			(thermal_bridge_width 0.5)
			(island_removal_mode 0)
		)
		(polygon
			(pts
				(arc
					(start 48.118014 -304.435256)
					(mid 47.449994 -304.435256)
					(end 48.118014 -304.435256)
				)
			)
		)
	)
	(zone
		(layers "B.Cu" "In15.Cu")
		(hatch none 0.5)
		(connect_pads
			(clearance 0)
		)
		(min_thickness 0.25)
		(keepout
			(tracks not_allowed)
			(vias allowed)
			(pads allowed)
			(copperpour not_allowed)
			(footprints allowed)
		)
		(placement
			(enabled no)
			(sheetname "")
		)
		(fill yes
			(thermal_gap 0.5)
			(thermal_bridge_width 0.5)
			(island_removal_mode 0)
		)
		(polygon
			(pts
				(arc
					(start 296.058082 -288.285174)
					(mid 295.390062 -288.285174)
					(end 296.058082 -288.285174)
				)
			)
		)
	)
	(zone
		(layers "B.Cu" "In15.Cu")
		(hatch none 0.5)
		(connect_pads
			(clearance 0)
		)
		(min_thickness 0.25)
		(keepout
			(tracks not_allowed)
			(vias allowed)
			(pads allowed)
			(copperpour not_allowed)
			(footprints allowed)
		)
		(placement
			(enabled no)
			(sheetname "")
		)
		(fill yes
			(thermal_gap 0.5)
			(thermal_bridge_width 0.5)
			(island_removal_mode 0)
		)
		(polygon
			(pts
				(arc
					(start 172.30598 -267.03528)
					(mid 171.63796 -267.03528)
					(end 172.30598 -267.03528)
				)
			)
		)
	)
	(zone
		(layers "B.Cu" "In15.Cu")
		(hatch none 0.5)
		(connect_pads
			(clearance 0)
		)
		(min_thickness 0.25)
		(keepout
			(tracks not_allowed)
			(vias allowed)
			(pads allowed)
			(copperpour not_allowed)
			(footprints allowed)
		)
		(placement
			(enabled no)
			(sheetname "")
		)
		(fill yes
			(thermal_gap 0.5)
			(thermal_bridge_width 0.5)
			(island_removal_mode 0)
		)
		(polygon
			(pts
				(arc
					(start 132.136896 -434.289962)
					(mid 131.362704 -434.289962)
					(end 132.136896 -434.289962)
				)
			)
		)
	)
	(zone
		(layers "B.Cu" "In15.Cu")
		(hatch none 0.5)
		(connect_pads
			(clearance 0)
		)
		(min_thickness 0.25)
		(keepout
			(tracks not_allowed)
			(vias allowed)
			(pads allowed)
			(copperpour not_allowed)
			(footprints allowed)
		)
		(placement
			(enabled no)
			(sheetname "")
		)
		(fill yes
			(thermal_gap 0.5)
			(thermal_bridge_width 0.5)
			(island_removal_mode 0)
		)
		(polygon
			(pts
				(arc
					(start 300.15815 -197.33514)
					(mid 299.49013 -197.33514)
					(end 300.15815 -197.33514)
				)
			)
		)
	)
	(zone
		(layers "B.Cu" "In15.Cu")
		(hatch none 0.5)
		(connect_pads
			(clearance 0)
		)
		(min_thickness 0.25)
		(keepout
			(tracks not_allowed)
			(vias allowed)
			(pads allowed)
			(copperpour not_allowed)
			(footprints allowed)
		)
		(placement
			(enabled no)
			(sheetname "")
		)
		(fill yes
			(thermal_gap 0.5)
			(thermal_bridge_width 0.5)
			(island_removal_mode 0)
		)
		(polygon
			(pts
				(arc
					(start 388.050532 -401.674838)
					(mid 387.382512 -401.674838)
					(end 388.050532 -401.674838)
				)
			)
		)
	)
	(zone
		(layers "B.Cu" "In15.Cu")
		(hatch none 0.5)
		(connect_pads
			(clearance 0)
		)
		(min_thickness 0.25)
		(keepout
			(tracks not_allowed)
			(vias allowed)
			(pads allowed)
			(copperpour not_allowed)
			(footprints allowed)
		)
		(placement
			(enabled no)
			(sheetname "")
		)
		(fill yes
			(thermal_gap 0.5)
			(thermal_bridge_width 0.5)
			(island_removal_mode 0)
		)
		(polygon
			(pts
				(arc
					(start 88.126062 -246.914416)
					(mid 87.496142 -246.914416)
					(end 88.126062 -246.914416)
				)
			)
		)
	)
	(zone
		(layers "B.Cu" "In15.Cu")
		(hatch none 0.5)
		(connect_pads
			(clearance 0)
		)
		(min_thickness 0.25)
		(keepout
			(tracks not_allowed)
			(vias allowed)
			(pads allowed)
			(copperpour not_allowed)
			(footprints allowed)
		)
		(placement
			(enabled no)
			(sheetname "")
		)
		(fill yes
			(thermal_gap 0.5)
			(thermal_bridge_width 0.5)
			(island_removal_mode 0)
		)
		(polygon
			(pts
				(arc
					(start 384.299714 -285.42615)
					(mid 383.669794 -285.42615)
					(end 384.299714 -285.42615)
				)
			)
		)
	)
	(zone
		(layers "B.Cu" "In15.Cu")
		(hatch none 0.5)
		(connect_pads
			(clearance 0)
		)
		(min_thickness 0.25)
		(keepout
			(tracks not_allowed)
			(vias allowed)
			(pads allowed)
			(copperpour not_allowed)
			(footprints allowed)
		)
		(placement
			(enabled no)
			(sheetname "")
		)
		(fill yes
			(thermal_gap 0.5)
			(thermal_bridge_width 0.5)
			(island_removal_mode 0)
		)
		(polygon
			(pts
				(arc
					(start 54.106318 -385.31038)
					(mid 53.476398 -385.31038)
					(end 54.106318 -385.31038)
				)
			)
		)
	)
	(zone
		(layers "B.Cu" "In15.Cu")
		(hatch none 0.5)
		(connect_pads
			(clearance 0)
		)
		(min_thickness 0.25)
		(keepout
			(tracks not_allowed)
			(vias allowed)
			(pads allowed)
			(copperpour not_allowed)
			(footprints allowed)
		)
		(placement
			(enabled no)
			(sheetname "")
		)
		(fill yes
			(thermal_gap 0.5)
			(thermal_bridge_width 0.5)
			(island_removal_mode 0)
		)
		(polygon
			(pts
				(arc
					(start 383.059686 -246.914162)
					(mid 382.429766 -246.914162)
					(end 383.059686 -246.914162)
				)
			)
		)
	)
	(zone
		(layers "B.Cu" "In15.Cu")
		(hatch none 0.5)
		(connect_pads
			(clearance 0)
		)
		(min_thickness 0.25)
		(keepout
			(tracks not_allowed)
			(vias allowed)
			(pads allowed)
			(copperpour not_allowed)
			(footprints allowed)
		)
		(placement
			(enabled no)
			(sheetname "")
		)
		(fill yes
			(thermal_gap 0.5)
			(thermal_bridge_width 0.5)
			(island_removal_mode 0)
		)
		(polygon
			(pts
				(arc
					(start 134.649718 -244.484398)
					(mid 134.019798 -244.484398)
					(end 134.649718 -244.484398)
				)
			)
		)
	)
	(zone
		(layers "B.Cu" "In15.Cu")
		(hatch none 0.5)
		(connect_pads
			(clearance 0)
		)
		(min_thickness 0.25)
		(keepout
			(tracks not_allowed)
			(vias allowed)
			(pads allowed)
			(copperpour not_allowed)
			(footprints allowed)
		)
		(placement
			(enabled no)
			(sheetname "")
		)
		(fill yes
			(thermal_gap 0.5)
			(thermal_bridge_width 0.5)
			(island_removal_mode 0)
		)
		(polygon
			(pts
				(arc
					(start 336.06613 -225.85426)
					(mid 335.43621 -225.85426)
					(end 336.06613 -225.85426)
				)
			)
		)
	)
	(zone
		(layers "B.Cu" "In15.Cu")
		(hatch none 0.5)
		(connect_pads
			(clearance 0)
		)
		(min_thickness 0.25)
		(keepout
			(tracks not_allowed)
			(vias allowed)
			(pads allowed)
			(copperpour not_allowed)
			(footprints allowed)
		)
		(placement
			(enabled no)
			(sheetname "")
		)
		(fill yes
			(thermal_gap 0.5)
			(thermal_bridge_width 0.5)
			(island_removal_mode 0)
		)
		(polygon
			(pts
				(arc
					(start 52.218082 -217.735404)
					(mid 51.550062 -217.735404)
					(end 52.218082 -217.735404)
				)
			)
		)
	)
	(zone
		(layers "B.Cu" "In15.Cu")
		(hatch none 0.5)
		(connect_pads
			(clearance 0)
		)
		(min_thickness 0.25)
		(keepout
			(tracks not_allowed)
			(vias allowed)
			(pads allowed)
			(copperpour not_allowed)
			(footprints allowed)
		)
		(placement
			(enabled no)
			(sheetname "")
		)
		(fill yes
			(thermal_gap 0.5)
			(thermal_bridge_width 0.5)
			(island_removal_mode 0)
		)
		(polygon
			(pts
				(arc
					(start 300.15815 -312.935112)
					(mid 299.49013 -312.935112)
					(end 300.15815 -312.935112)
				)
			)
		)
	)
	(zone
		(layers "B.Cu" "In15.Cu")
		(hatch none 0.5)
		(connect_pads
			(clearance 0)
		)
		(min_thickness 0.25)
		(keepout
			(tracks not_allowed)
			(vias allowed)
			(pads allowed)
			(copperpour not_allowed)
			(footprints allowed)
		)
		(placement
			(enabled no)
			(sheetname "")
		)
		(fill yes
			(thermal_gap 0.5)
			(thermal_bridge_width 0.5)
			(island_removal_mode 0)
		)
		(polygon
			(pts
				(arc
					(start 144.678654 -369.03533)
					(mid 144.010634 -369.03533)
					(end 144.678654 -369.03533)
				)
			)
		)
	)
	(zone
		(layers "B.Cu" "In15.Cu")
		(hatch none 0.5)
		(connect_pads
			(clearance 0)
		)
		(min_thickness 0.25)
		(keepout
			(tracks not_allowed)
			(vias allowed)
			(pads allowed)
			(copperpour not_allowed)
			(footprints allowed)
		)
		(placement
			(enabled no)
			(sheetname "")
		)
		(fill yes
			(thermal_gap 0.5)
			(thermal_bridge_width 0.5)
			(island_removal_mode 0)
		)
		(polygon
			(pts
				(arc
					(start 134.649718 -234.764326)
					(mid 134.019798 -234.764326)
					(end 134.649718 -234.764326)
				)
			)
		)
	)
	(zone
		(layers "B.Cu" "In15.Cu")
		(hatch none 0.5)
		(connect_pads
			(clearance 0)
		)
		(min_thickness 0.25)
		(keepout
			(tracks not_allowed)
			(vias allowed)
			(pads allowed)
			(copperpour not_allowed)
			(footprints allowed)
		)
		(placement
			(enabled no)
			(sheetname "")
		)
		(fill yes
			(thermal_gap 0.5)
			(thermal_bridge_width 0.5)
			(island_removal_mode 0)
		)
		(polygon
			(pts
				(arc
					(start 135.419592 -272.466308)
					(mid 134.789672 -272.466308)
					(end 135.419592 -272.466308)
				)
			)
		)
	)
	(zone
		(layers "B.Cu" "In15.Cu")
		(hatch none 0.5)
		(connect_pads
			(clearance 0)
		)
		(min_thickness 0.25)
		(keepout
			(tracks not_allowed)
			(vias allowed)
			(pads allowed)
			(copperpour not_allowed)
			(footprints allowed)
		)
		(placement
			(enabled no)
			(sheetname "")
		)
		(fill yes
			(thermal_gap 0.5)
			(thermal_bridge_width 0.5)
			(island_removal_mode 0)
		)
		(polygon
			(pts
				(arc
					(start 52.218082 -201.585322)
					(mid 51.550062 -201.585322)
					(end 52.218082 -201.585322)
				)
			)
		)
	)
	(zone
		(layers "B.Cu" "In15.Cu")
		(hatch none 0.5)
		(connect_pads
			(clearance 0)
		)
		(min_thickness 0.25)
		(keepout
			(tracks not_allowed)
			(vias allowed)
			(pads allowed)
			(copperpour not_allowed)
			(footprints allowed)
		)
		(placement
			(enabled no)
			(sheetname "")
		)
		(fill yes
			(thermal_gap 0.5)
			(thermal_bridge_width 0.5)
			(island_removal_mode 0)
		)
		(polygon
			(pts
				(arc
					(start 123.669806 -273.276314)
					(mid 123.039886 -273.276314)
					(end 123.669806 -273.276314)
				)
			)
		)
	)
	(zone
		(layers "B.Cu" "In15.Cu")
		(hatch none 0.5)
		(connect_pads
			(clearance 0)
		)
		(min_thickness 0.25)
		(keepout
			(tracks not_allowed)
			(vias allowed)
			(pads allowed)
			(copperpour not_allowed)
			(footprints allowed)
		)
		(placement
			(enabled no)
			(sheetname "")
		)
		(fill yes
			(thermal_gap 0.5)
			(thermal_bridge_width 0.5)
			(island_removal_mode 0)
		)
		(polygon
			(pts
				(arc
					(start 88.126062 -255.014476)
					(mid 87.496142 -255.014476)
					(end 88.126062 -255.014476)
				)
			)
		)
	)
	(zone
		(layers "B.Cu" "In15.Cu")
		(hatch none 0.5)
		(connect_pads
			(clearance 0)
		)
		(min_thickness 0.25)
		(keepout
			(tracks not_allowed)
			(vias allowed)
			(pads allowed)
			(copperpour not_allowed)
			(footprints allowed)
		)
		(placement
			(enabled no)
			(sheetname "")
		)
		(fill yes
			(thermal_gap 0.5)
			(thermal_bridge_width 0.5)
			(island_removal_mode 0)
		)
		(polygon
			(pts
				(arc
					(start 420.246048 -313.784996)
					(mid 419.578028 -313.784996)
					(end 420.246048 -313.784996)
				)
			)
		)
	)
	(zone
		(layers "B.Cu" "In15.Cu")
		(hatch none 0.5)
		(connect_pads
			(clearance 0)
		)
		(min_thickness 0.25)
		(keepout
			(tracks not_allowed)
			(vias allowed)
			(pads allowed)
			(copperpour not_allowed)
			(footprints allowed)
		)
		(placement
			(enabled no)
			(sheetname "")
		)
		(fill yes
			(thermal_gap 0.5)
			(thermal_bridge_width 0.5)
			(island_removal_mode 0)
		)
		(polygon
			(pts
				(arc
					(start 300.15815 -295.085008)
					(mid 299.49013 -295.085008)
					(end 300.15815 -295.085008)
				)
			)
		)
	)
	(zone
		(layers "B.Cu" "In15.Cu")
		(hatch none 0.5)
		(connect_pads
			(clearance 0)
		)
		(min_thickness 0.25)
		(keepout
			(tracks not_allowed)
			(vias allowed)
			(pads allowed)
			(copperpour not_allowed)
			(footprints allowed)
		)
		(placement
			(enabled no)
			(sheetname "")
		)
		(fill yes
			(thermal_gap 0.5)
			(thermal_bridge_width 0.5)
			(island_removal_mode 0)
		)
		(polygon
			(pts
				(arc
					(start 394.13688 -434.48986)
					(mid 393.362688 -434.48986)
					(end 394.13688 -434.48986)
				)
			)
		)
	)
	(zone
		(layers "B.Cu" "In15.Cu")
		(hatch none 0.5)
		(connect_pads
			(clearance 0)
		)
		(min_thickness 0.25)
		(keepout
			(tracks not_allowed)
			(vias allowed)
			(pads allowed)
			(copperpour not_allowed)
			(footprints allowed)
		)
		(placement
			(enabled no)
			(sheetname "")
		)
		(fill yes
			(thermal_gap 0.5)
			(thermal_bridge_width 0.5)
			(island_removal_mode 0)
		)
		(polygon
			(pts
				(arc
					(start 91.478354 -393.292838)
					(mid 90.810334 -393.292838)
					(end 91.478354 -393.292838)
				)
			)
		)
	)
	(zone
		(layers "B.Cu" "In15.Cu")
		(hatch none 0.5)
		(connect_pads
			(clearance 0)
		)
		(min_thickness 0.25)
		(keepout
			(tracks not_allowed)
			(vias allowed)
			(pads allowed)
			(copperpour not_allowed)
			(footprints allowed)
		)
		(placement
			(enabled no)
			(sheetname "")
		)
		(fill yes
			(thermal_gap 0.5)
			(thermal_bridge_width 0.5)
			(island_removal_mode 0)
		)
		(polygon
			(pts
				(arc
					(start 335.595976 -247.724168)
					(mid 334.966056 -247.724168)
					(end 335.595976 -247.724168)
				)
			)
		)
	)
	(zone
		(layers "B.Cu" "In15.Cu")
		(hatch none 0.5)
		(connect_pads
			(clearance 0)
		)
		(min_thickness 0.25)
		(keepout
			(tracks not_allowed)
			(vias allowed)
			(pads allowed)
			(copperpour not_allowed)
			(footprints allowed)
		)
		(placement
			(enabled no)
			(sheetname "")
		)
		(fill yes
			(thermal_gap 0.5)
			(thermal_bridge_width 0.5)
			(island_removal_mode 0)
		)
		(polygon
			(pts
				(arc
					(start 410.88945 -382.34493)
					(mid 410.22143 -382.34493)
					(end 410.88945 -382.34493)
				)
			)
		)
	)
	(zone
		(layers "B.Cu" "In15.Cu")
		(hatch none 0.5)
		(connect_pads
			(clearance 0)
		)
		(min_thickness 0.25)
		(keepout
			(tracks not_allowed)
			(vias allowed)
			(pads allowed)
			(copperpour not_allowed)
			(footprints allowed)
		)
		(placement
			(enabled no)
			(sheetname "")
		)
		(fill yes
			(thermal_gap 0.5)
			(thermal_bridge_width 0.5)
			(island_removal_mode 0)
		)
		(polygon
			(pts
				(arc
					(start 69.036946 -435.489858)
					(mid 68.262754 -435.489858)
					(end 69.036946 -435.489858)
				)
			)
		)
	)
	(zone
		(layers "B.Cu" "In15.Cu")
		(hatch none 0.5)
		(connect_pads
			(clearance 0)
		)
		(min_thickness 0.25)
		(keepout
			(tracks not_allowed)
			(vias allowed)
			(pads allowed)
			(copperpour not_allowed)
			(footprints allowed)
		)
		(placement
			(enabled no)
			(sheetname "")
		)
		(fill yes
			(thermal_gap 0.5)
			(thermal_bridge_width 0.5)
			(island_removal_mode 0)
		)
		(polygon
			(pts
				(arc
					(start 52.218082 -311.235344)
					(mid 51.550062 -311.235344)
					(end 52.218082 -311.235344)
				)
			)
		)
	)
	(zone
		(layers "B.Cu" "In15.Cu")
		(hatch none 0.5)
		(connect_pads
			(clearance 0)
		)
		(min_thickness 0.25)
		(keepout
			(tracks not_allowed)
			(vias allowed)
			(pads allowed)
			(copperpour not_allowed)
			(footprints allowed)
		)
		(placement
			(enabled no)
			(sheetname "")
		)
		(fill yes
			(thermal_gap 0.5)
			(thermal_bridge_width 0.5)
			(island_removal_mode 0)
		)
		(polygon
			(pts
				(arc
					(start 48.118014 -278.935434)
					(mid 47.449994 -278.935434)
					(end 48.118014 -278.935434)
				)
			)
		)
	)
	(zone
		(layers "B.Cu" "In15.Cu")
		(hatch none 0.5)
		(connect_pads
			(clearance 0)
		)
		(min_thickness 0.25)
		(keepout
			(tracks not_allowed)
			(vias allowed)
			(pads allowed)
			(copperpour not_allowed)
			(footprints allowed)
		)
		(placement
			(enabled no)
			(sheetname "")
		)
		(fill yes
			(thermal_gap 0.5)
			(thermal_bridge_width 0.5)
			(island_removal_mode 0)
		)
		(polygon
			(pts
				(arc
					(start 120.54967 -241.244374)
					(mid 119.91975 -241.244374)
					(end 120.54967 -241.244374)
				)
			)
		)
	)
	(zone
		(layers "B.Cu" "In15.Cu")
		(hatch none 0.5)
		(connect_pads
			(clearance 0)
		)
		(min_thickness 0.25)
		(keepout
			(tracks not_allowed)
			(vias allowed)
			(pads allowed)
			(copperpour not_allowed)
			(footprints allowed)
		)
		(placement
			(enabled no)
			(sheetname "")
		)
		(fill yes
			(thermal_gap 0.5)
			(thermal_bridge_width 0.5)
			(island_removal_mode 0)
		)
		(polygon
			(pts
				(arc
					(start 420.246048 -293.384986)
					(mid 419.578028 -293.384986)
					(end 420.246048 -293.384986)
				)
			)
		)
	)
	(zone
		(layers "B.Cu" "In15.Cu")
		(hatch none 0.5)
		(connect_pads
			(clearance 0)
		)
		(min_thickness 0.25)
		(keepout
			(tracks not_allowed)
			(vias allowed)
			(pads allowed)
			(copperpour not_allowed)
			(footprints allowed)
		)
		(placement
			(enabled no)
			(sheetname "")
		)
		(fill yes
			(thermal_gap 0.5)
			(thermal_bridge_width 0.5)
			(island_removal_mode 0)
		)
		(polygon
			(pts
				(arc
					(start 342.678004 -401.674838)
					(mid 342.009984 -401.674838)
					(end 342.678004 -401.674838)
				)
			)
		)
	)
	(zone
		(layers "B.Cu" "In15.Cu")
		(hatch none 0.5)
		(connect_pads
			(clearance 0)
		)
		(min_thickness 0.25)
		(keepout
			(tracks not_allowed)
			(vias allowed)
			(pads allowed)
			(copperpour not_allowed)
			(footprints allowed)
		)
		(placement
			(enabled no)
			(sheetname "")
		)
		(fill yes
			(thermal_gap 0.5)
			(thermal_bridge_width 0.5)
			(island_removal_mode 0)
		)
		(polygon
			(pts
				(arc
					(start 52.218082 -208.38541)
					(mid 51.550062 -208.38541)
					(end 52.218082 -208.38541)
				)
			)
		)
	)
	(zone
		(layers "B.Cu" "In15.Cu")
		(hatch none 0.5)
		(connect_pads
			(clearance 0)
		)
		(min_thickness 0.25)
		(keepout
			(tracks not_allowed)
			(vias allowed)
			(pads allowed)
			(copperpour not_allowed)
			(footprints allowed)
		)
		(placement
			(enabled no)
			(sheetname "")
		)
		(fill yes
			(thermal_gap 0.5)
			(thermal_bridge_width 0.5)
			(island_removal_mode 0)
		)
		(polygon
			(pts
				(arc
					(start 135.419592 -293.52621)
					(mid 134.789672 -293.52621)
					(end 135.419592 -293.52621)
				)
			)
		)
	)
	(zone
		(layers "B.Cu" "In15.Cu")
		(hatch none 0.5)
		(connect_pads
			(clearance 0)
		)
		(min_thickness 0.25)
		(keepout
			(tracks not_allowed)
			(vias allowed)
			(pads allowed)
			(copperpour not_allowed)
			(footprints allowed)
		)
		(placement
			(enabled no)
			(sheetname "")
		)
		(fill yes
			(thermal_gap 0.5)
			(thermal_bridge_width 0.5)
			(island_removal_mode 0)
		)
		(polygon
			(pts
				(arc
					(start 50.906172 -386.003292)
					(mid 50.276252 -386.003292)
					(end 50.906172 -386.003292)
				)
			)
		)
	)
	(zone
		(layers "B.Cu" "In15.Cu")
		(hatch none 0.5)
		(connect_pads
			(clearance 0)
		)
		(min_thickness 0.25)
		(keepout
			(tracks not_allowed)
			(vias allowed)
			(pads allowed)
			(copperpour not_allowed)
			(footprints allowed)
		)
		(placement
			(enabled no)
			(sheetname "")
		)
		(fill yes
			(thermal_gap 0.5)
			(thermal_bridge_width 0.5)
			(island_removal_mode 0)
		)
		(polygon
			(pts
				(arc
					(start 89.536016 -234.764326)
					(mid 88.906096 -234.764326)
					(end 89.536016 -234.764326)
				)
			)
		)
	)
	(zone
		(layers "B.Cu" "In15.Cu")
		(hatch none 0.5)
		(connect_pads
			(clearance 0)
		)
		(min_thickness 0.25)
		(keepout
			(tracks not_allowed)
			(vias allowed)
			(pads allowed)
			(copperpour not_allowed)
			(footprints allowed)
		)
		(placement
			(enabled no)
			(sheetname "")
		)
		(fill yes
			(thermal_gap 0.5)
			(thermal_bridge_width 0.5)
			(island_removal_mode 0)
		)
		(polygon
			(pts
				(arc
					(start 399.137124 -434.48986)
					(mid 398.362932 -434.48986)
					(end 399.137124 -434.48986)
				)
			)
		)
	)
	(zone
		(layers "B.Cu" "In15.Cu")
		(hatch none 0.5)
		(connect_pads
			(clearance 0)
		)
		(min_thickness 0.25)
		(keepout
			(tracks not_allowed)
			(vias allowed)
			(pads allowed)
			(copperpour not_allowed)
			(footprints allowed)
		)
		(placement
			(enabled no)
			(sheetname "")
		)
		(fill yes
			(thermal_gap 0.5)
			(thermal_bridge_width 0.5)
			(island_removal_mode 0)
		)
		(polygon
			(pts
				(arc
					(start 336.366104 -288.66592)
					(mid 335.736184 -288.66592)
					(end 336.366104 -288.66592)
				)
			)
		)
	)
	(zone
		(layers "B.Cu" "In15.Cu")
		(hatch none 0.5)
		(connect_pads
			(clearance 0)
		)
		(min_thickness 0.25)
		(keepout
			(tracks not_allowed)
			(vias allowed)
			(pads allowed)
			(copperpour not_allowed)
			(footprints allowed)
		)
		(placement
			(enabled no)
			(sheetname "")
		)
		(fill yes
			(thermal_gap 0.5)
			(thermal_bridge_width 0.5)
			(island_removal_mode 0)
		)
		(polygon
			(pts
				(arc
					(start 176.406048 -229.635304)
					(mid 175.738028 -229.635304)
					(end 176.406048 -229.635304)
				)
			)
		)
	)
	(zone
		(layers "B.Cu" "In15.Cu")
		(hatch none 0.5)
		(connect_pads
			(clearance 0)
		)
		(min_thickness 0.25)
		(keepout
			(tracks not_allowed)
			(vias allowed)
			(pads allowed)
			(copperpour not_allowed)
			(footprints allowed)
		)
		(placement
			(enabled no)
			(sheetname "")
		)
		(fill yes
			(thermal_gap 0.5)
			(thermal_bridge_width 0.5)
			(island_removal_mode 0)
		)
		(polygon
			(pts
				(arc
					(start 48.118014 -291.685218)
					(mid 47.449994 -291.685218)
					(end 48.118014 -291.685218)
				)
			)
		)
	)
	(zone
		(layers "B.Cu" "In15.Cu")
		(hatch none 0.5)
		(connect_pads
			(clearance 0)
		)
		(min_thickness 0.25)
		(keepout
			(tracks not_allowed)
			(vias allowed)
			(pads allowed)
			(copperpour not_allowed)
			(footprints allowed)
		)
		(placement
			(enabled no)
			(sheetname "")
		)
		(fill yes
			(thermal_gap 0.5)
			(thermal_bridge_width 0.5)
			(island_removal_mode 0)
		)
		(polygon
			(pts
				(arc
					(start 424.346116 -267.885164)
					(mid 423.678096 -267.885164)
					(end 424.346116 -267.885164)
				)
			)
		)
	)
	(zone
		(layers "B.Cu" "In15.Cu")
		(hatch none 0.5)
		(connect_pads
			(clearance 0)
		)
		(min_thickness 0.25)
		(keepout
			(tracks not_allowed)
			(vias allowed)
			(pads allowed)
			(copperpour not_allowed)
			(footprints allowed)
		)
		(placement
			(enabled no)
			(sheetname "")
		)
		(fill yes
			(thermal_gap 0.5)
			(thermal_bridge_width 0.5)
			(island_removal_mode 0)
		)
		(polygon
			(pts
				(arc
					(start 126.489714 -273.276314)
					(mid 125.859794 -273.276314)
					(end 126.489714 -273.276314)
				)
			)
		)
	)
	(zone
		(layers "B.Cu" "In15.Cu")
		(hatch none 0.5)
		(connect_pads
			(clearance 0)
		)
		(min_thickness 0.25)
		(keepout
			(tracks not_allowed)
			(vias allowed)
			(pads allowed)
			(copperpour not_allowed)
			(footprints allowed)
		)
		(placement
			(enabled no)
			(sheetname "")
		)
		(fill yes
			(thermal_gap 0.5)
			(thermal_bridge_width 0.5)
			(island_removal_mode 0)
		)
		(polygon
			(pts
				(arc
					(start 172.30598 -268.735302)
					(mid 171.63796 -268.735302)
					(end 172.30598 -268.735302)
				)
			)
		)
	)
	(zone
		(layers "B.Cu" "In15.Cu")
		(hatch none 0.5)
		(connect_pads
			(clearance 0)
		)
		(min_thickness 0.25)
		(keepout
			(tracks not_allowed)
			(vias allowed)
			(pads allowed)
			(copperpour not_allowed)
			(footprints allowed)
		)
		(placement
			(enabled no)
			(sheetname "")
		)
		(fill yes
			(thermal_gap 0.5)
			(thermal_bridge_width 0.5)
			(island_removal_mode 0)
		)
		(polygon
			(pts
				(arc
					(start 176.406048 -279.785318)
					(mid 175.738028 -279.785318)
					(end 176.406048 -279.785318)
				)
			)
		)
	)
	(zone
		(layers "B.Cu" "In15.Cu")
		(hatch none 0.5)
		(connect_pads
			(clearance 0)
		)
		(min_thickness 0.25)
		(keepout
			(tracks not_allowed)
			(vias allowed)
			(pads allowed)
			(copperpour not_allowed)
			(footprints allowed)
		)
		(placement
			(enabled no)
			(sheetname "")
		)
		(fill yes
			(thermal_gap 0.5)
			(thermal_bridge_width 0.5)
			(island_removal_mode 0)
		)
		(polygon
			(pts
				(arc
					(start 136.059672 -255.014476)
					(mid 135.429752 -255.014476)
					(end 136.059672 -255.014476)
				)
			)
		)
	)
	(zone
		(layers "B.Cu" "In15.Cu")
		(hatch none 0.5)
		(connect_pads
			(clearance 0)
		)
		(min_thickness 0.25)
		(keepout
			(tracks not_allowed)
			(vias allowed)
			(pads allowed)
			(copperpour not_allowed)
			(footprints allowed)
		)
		(placement
			(enabled no)
			(sheetname "")
		)
		(fill yes
			(thermal_gap 0.5)
			(thermal_bridge_width 0.5)
			(island_removal_mode 0)
		)
		(polygon
			(pts
				(arc
					(start 396.136876 -434.289962)
					(mid 395.362684 -434.289962)
					(end 396.136876 -434.289962)
				)
			)
		)
	)
	(zone
		(layers "B.Cu" "In15.Cu")
		(hatch none 0.5)
		(connect_pads
			(clearance 0)
		)
		(min_thickness 0.25)
		(keepout
			(tracks not_allowed)
			(vias allowed)
			(pads allowed)
			(copperpour not_allowed)
			(footprints allowed)
		)
		(placement
			(enabled no)
			(sheetname "")
		)
		(fill yes
			(thermal_gap 0.5)
			(thermal_bridge_width 0.5)
			(island_removal_mode 0)
		)
		(polygon
			(pts
				(arc
					(start 300.15815 -261.085076)
					(mid 299.49013 -261.085076)
					(end 300.15815 -261.085076)
				)
			)
		)
	)
	(zone
		(layers "B.Cu" "In15.Cu")
		(hatch none 0.5)
		(connect_pads
			(clearance 0)
		)
		(min_thickness 0.25)
		(keepout
			(tracks not_allowed)
			(vias allowed)
			(pads allowed)
			(copperpour not_allowed)
			(footprints allowed)
		)
		(placement
			(enabled no)
			(sheetname "")
		)
		(fill yes
			(thermal_gap 0.5)
			(thermal_bridge_width 0.5)
			(island_removal_mode 0)
		)
		(polygon
			(pts
				(arc
					(start 134.949692 -284.616398)
					(mid 134.319772 -284.616398)
					(end 134.949692 -284.616398)
				)
			)
		)
	)
	(zone
		(layers "B.Cu" "In15.Cu")
		(hatch none 0.5)
		(connect_pads
			(clearance 0)
		)
		(min_thickness 0.25)
		(keepout
			(tracks not_allowed)
			(vias allowed)
			(pads allowed)
			(copperpour not_allowed)
			(footprints allowed)
		)
		(placement
			(enabled no)
			(sheetname "")
		)
		(fill yes
			(thermal_gap 0.5)
			(thermal_bridge_width 0.5)
			(island_removal_mode 0)
		)
		(polygon
			(pts
				(arc
					(start 383.059686 -233.954066)
					(mid 382.429766 -233.954066)
					(end 383.059686 -233.954066)
				)
			)
		)
	)
	(zone
		(layers "B.Cu" "In15.Cu")
		(hatch none 0.5)
		(connect_pads
			(clearance 0)
		)
		(min_thickness 0.25)
		(keepout
			(tracks not_allowed)
			(vias allowed)
			(pads allowed)
			(copperpour not_allowed)
			(footprints allowed)
		)
		(placement
			(enabled no)
			(sheetname "")
		)
		(fill yes
			(thermal_gap 0.5)
			(thermal_bridge_width 0.5)
			(island_removal_mode 0)
		)
		(polygon
			(pts
				(arc
					(start 384.769868 -291.095938)
					(mid 384.139948 -291.095938)
					(end 384.769868 -291.095938)
				)
			)
		)
	)
	(zone
		(layers "B.Cu" "In15.Cu")
		(hatch none 0.5)
		(connect_pads
			(clearance 0)
		)
		(min_thickness 0.25)
		(keepout
			(tracks not_allowed)
			(vias allowed)
			(pads allowed)
			(copperpour not_allowed)
			(footprints allowed)
		)
		(placement
			(enabled no)
			(sheetname "")
		)
		(fill yes
			(thermal_gap 0.5)
			(thermal_bridge_width 0.5)
			(island_removal_mode 0)
		)
		(polygon
			(pts
				(arc
					(start 136.359646 -274.08632)
					(mid 135.729726 -274.08632)
					(end 136.359646 -274.08632)
				)
			)
		)
	)
	(zone
		(layers "B.Cu" "In15.Cu")
		(hatch none 0.5)
		(connect_pads
			(clearance 0)
		)
		(min_thickness 0.25)
		(keepout
			(tracks not_allowed)
			(vias allowed)
			(pads allowed)
			(copperpour not_allowed)
			(footprints allowed)
		)
		(placement
			(enabled no)
			(sheetname "")
		)
		(fill yes
			(thermal_gap 0.5)
			(thermal_bridge_width 0.5)
			(island_removal_mode 0)
		)
		(polygon
			(pts
				(arc
					(start 337.306158 -272.466054)
					(mid 336.676238 -272.466054)
					(end 337.306158 -272.466054)
				)
			)
		)
	)
	(zone
		(layers "B.Cu" "In15.Cu")
		(hatch none 0.5)
		(connect_pads
			(clearance 0)
		)
		(min_thickness 0.25)
		(keepout
			(tracks not_allowed)
			(vias allowed)
			(pads allowed)
			(copperpour not_allowed)
			(footprints allowed)
		)
		(placement
			(enabled no)
			(sheetname "")
		)
		(fill yes
			(thermal_gap 0.5)
			(thermal_bridge_width 0.5)
			(island_removal_mode 0)
		)
		(polygon
			(pts
				(arc
					(start 134.949692 -289.47618)
					(mid 134.319772 -289.47618)
					(end 134.949692 -289.47618)
				)
			)
		)
	)
	(zone
		(layers "B.Cu" "In15.Cu")
		(hatch none 0.5)
		(connect_pads
			(clearance 0)
		)
		(min_thickness 0.25)
		(keepout
			(tracks not_allowed)
			(vias allowed)
			(pads allowed)
			(copperpour not_allowed)
			(footprints allowed)
		)
		(placement
			(enabled no)
			(sheetname "")
		)
		(fill yes
			(thermal_gap 0.5)
			(thermal_bridge_width 0.5)
			(island_removal_mode 0)
		)
		(polygon
			(pts
				(arc
					(start 424.346116 -223.6851)
					(mid 423.678096 -223.6851)
					(end 424.346116 -223.6851)
				)
			)
		)
	)
	(zone
		(layers "B.Cu" "In15.Cu")
		(hatch none 0.5)
		(connect_pads
			(clearance 0)
		)
		(min_thickness 0.25)
		(keepout
			(tracks not_allowed)
			(vias allowed)
			(pads allowed)
			(copperpour not_allowed)
			(footprints allowed)
		)
		(placement
			(enabled no)
			(sheetname "")
		)
		(fill yes
			(thermal_gap 0.5)
			(thermal_bridge_width 0.5)
			(island_removal_mode 0)
		)
		(polygon
			(pts
				(arc
					(start 98.295968 -273.276314)
					(mid 97.666048 -273.276314)
					(end 98.295968 -273.276314)
				)
			)
		)
	)
	(zone
		(layers "B.Cu" "In15.Cu")
		(hatch none 0.5)
		(connect_pads
			(clearance 0)
		)
		(min_thickness 0.25)
		(keepout
			(tracks not_allowed)
			(vias allowed)
			(pads allowed)
			(copperpour not_allowed)
			(footprints allowed)
		)
		(placement
			(enabled no)
			(sheetname "")
		)
		(fill yes
			(thermal_gap 0.5)
			(thermal_bridge_width 0.5)
			(island_removal_mode 0)
		)
		(polygon
			(pts
				(arc
					(start 176.406048 -240.68532)
					(mid 175.738028 -240.68532)
					(end 176.406048 -240.68532)
				)
			)
		)
	)
	(zone
		(layers "B.Cu" "In15.Cu")
		(hatch none 0.5)
		(connect_pads
			(clearance 0)
		)
		(min_thickness 0.25)
		(keepout
			(tracks not_allowed)
			(vias allowed)
			(pads allowed)
			(copperpour not_allowed)
			(footprints allowed)
		)
		(placement
			(enabled no)
			(sheetname "")
		)
		(fill yes
			(thermal_gap 0.5)
			(thermal_bridge_width 0.5)
			(island_removal_mode 0)
		)
		(polygon
			(pts
				(arc
					(start 176.406048 -221.985332)
					(mid 175.738028 -221.985332)
					(end 176.406048 -221.985332)
				)
			)
		)
	)
	(zone
		(layers "B.Cu" "In15.Cu")
		(hatch none 0.5)
		(connect_pads
			(clearance 0)
		)
		(min_thickness 0.25)
		(keepout
			(tracks not_allowed)
			(vias allowed)
			(pads allowed)
			(copperpour not_allowed)
			(footprints allowed)
		)
		(placement
			(enabled no)
			(sheetname "")
		)
		(fill yes
			(thermal_gap 0.5)
			(thermal_bridge_width 0.5)
			(island_removal_mode 0)
		)
		(polygon
			(pts
				(arc
					(start 296.058082 -278.93518)
					(mid 295.390062 -278.93518)
					(end 296.058082 -278.93518)
				)
			)
		)
	)
	(zone
		(layers "B.Cu" "In15.Cu")
		(hatch none 0.5)
		(connect_pads
			(clearance 0)
		)
		(min_thickness 0.25)
		(keepout
			(tracks not_allowed)
			(vias allowed)
			(pads allowed)
			(copperpour not_allowed)
			(footprints allowed)
		)
		(placement
			(enabled no)
			(sheetname "")
		)
		(fill yes
			(thermal_gap 0.5)
			(thermal_bridge_width 0.5)
			(island_removal_mode 0)
		)
		(polygon
			(pts
				(arc
					(start 420.246048 -314.635134)
					(mid 419.578028 -314.635134)
					(end 420.246048 -314.635134)
				)
			)
		)
	)
	(zone
		(layers "B.Cu" "In15.Cu")
		(hatch none 0.5)
		(connect_pads
			(clearance 0)
		)
		(min_thickness 0.25)
		(keepout
			(tracks not_allowed)
			(vias allowed)
			(pads allowed)
			(copperpour not_allowed)
			(footprints allowed)
		)
		(placement
			(enabled no)
			(sheetname "")
		)
		(fill yes
			(thermal_gap 0.5)
			(thermal_bridge_width 0.5)
			(island_removal_mode 0)
		)
		(polygon
			(pts
				(arc
					(start 52.218082 -240.68532)
					(mid 51.550062 -240.68532)
					(end 52.218082 -240.68532)
				)
			)
		)
	)
	(zone
		(layers "B.Cu" "In15.Cu")
		(hatch none 0.5)
		(connect_pads
			(clearance 0)
		)
		(min_thickness 0.25)
		(keepout
			(tracks not_allowed)
			(vias allowed)
			(pads allowed)
			(copperpour not_allowed)
			(footprints allowed)
		)
		(placement
			(enabled no)
			(sheetname "")
		)
		(fill yes
			(thermal_gap 0.5)
			(thermal_bridge_width 0.5)
			(island_removal_mode 0)
		)
		(polygon
			(pts
				(arc
					(start 87.955882 -282.996386)
					(mid 87.325962 -282.996386)
					(end 87.955882 -282.996386)
				)
			)
		)
	)
	(zone
		(layers "B.Cu" "In15.Cu")
		(hatch none 0.5)
		(connect_pads
			(clearance 0)
		)
		(min_thickness 0.25)
		(keepout
			(tracks not_allowed)
			(vias allowed)
			(pads allowed)
			(copperpour not_allowed)
			(footprints allowed)
		)
		(placement
			(enabled no)
			(sheetname "")
		)
		(fill yes
			(thermal_gap 0.5)
			(thermal_bridge_width 0.5)
			(island_removal_mode 0)
		)
		(polygon
			(pts
				(arc
					(start 172.30598 -313.78525)
					(mid 171.63796 -313.78525)
					(end 172.30598 -313.78525)
				)
			)
		)
	)
	(zone
		(layers "B.Cu" "In15.Cu")
		(hatch none 0.5)
		(connect_pads
			(clearance 0)
		)
		(min_thickness 0.25)
		(keepout
			(tracks not_allowed)
			(vias allowed)
			(pads allowed)
			(copperpour not_allowed)
			(footprints allowed)
		)
		(placement
			(enabled no)
			(sheetname "")
		)
		(fill yes
			(thermal_gap 0.5)
			(thermal_bridge_width 0.5)
			(island_removal_mode 0)
		)
		(polygon
			(pts
				(arc
					(start 335.89595 -266.796012)
					(mid 335.26603 -266.796012)
					(end 335.89595 -266.796012)
				)
			)
		)
	)
	(zone
		(layers "B.Cu" "In15.Cu")
		(hatch none 0.5)
		(connect_pads
			(clearance 0)
		)
		(min_thickness 0.25)
		(keepout
			(tracks not_allowed)
			(vias allowed)
			(pads allowed)
			(copperpour not_allowed)
			(footprints allowed)
		)
		(placement
			(enabled no)
			(sheetname "")
		)
		(fill yes
			(thermal_gap 0.5)
			(thermal_bridge_width 0.5)
			(island_removal_mode 0)
		)
		(polygon
			(pts
				(arc
					(start 120.05056 -392.429238)
					(mid 119.38254 -392.429238)
					(end 120.05056 -392.429238)
				)
			)
		)
	)
	(zone
		(layers "B.Cu" "In15.Cu")
		(hatch none 0.5)
		(connect_pads
			(clearance 0)
		)
		(min_thickness 0.25)
		(keepout
			(tracks not_allowed)
			(vias allowed)
			(pads allowed)
			(copperpour not_allowed)
			(footprints allowed)
		)
		(placement
			(enabled no)
			(sheetname "")
		)
		(fill yes
			(thermal_gap 0.5)
			(thermal_bridge_width 0.5)
			(island_removal_mode 0)
		)
		(polygon
			(pts
				(arc
					(start 300.15815 -229.63505)
					(mid 299.49013 -229.63505)
					(end 300.15815 -229.63505)
				)
			)
		)
	)
	(zone
		(layers "B.Cu" "In15.Cu")
		(hatch none 0.5)
		(connect_pads
			(clearance 0)
		)
		(min_thickness 0.25)
		(keepout
			(tracks not_allowed)
			(vias allowed)
			(pads allowed)
			(copperpour not_allowed)
			(footprints allowed)
		)
		(placement
			(enabled no)
			(sheetname "")
		)
		(fill yes
			(thermal_gap 0.5)
			(thermal_bridge_width 0.5)
			(island_removal_mode 0)
		)
		(polygon
			(pts
				(arc
					(start 176.406048 -236.435392)
					(mid 175.738028 -236.435392)
					(end 176.406048 -236.435392)
				)
			)
		)
	)
	(zone
		(layers "B.Cu" "In15.Cu")
		(hatch none 0.5)
		(connect_pads
			(clearance 0)
		)
		(min_thickness 0.25)
		(keepout
			(tracks not_allowed)
			(vias allowed)
			(pads allowed)
			(copperpour not_allowed)
			(footprints allowed)
		)
		(placement
			(enabled no)
			(sheetname "")
		)
		(fill yes
			(thermal_gap 0.5)
			(thermal_bridge_width 0.5)
			(island_removal_mode 0)
		)
		(polygon
			(pts
				(arc
					(start 345.936062 -241.24412)
					(mid 345.306142 -241.24412)
					(end 345.936062 -241.24412)
				)
			)
		)
	)
	(zone
		(layers "B.Cu" "In15.Cu")
		(hatch none 0.5)
		(connect_pads
			(clearance 0)
		)
		(min_thickness 0.25)
		(keepout
			(tracks not_allowed)
			(vias allowed)
			(pads allowed)
			(copperpour not_allowed)
			(footprints allowed)
		)
		(placement
			(enabled no)
			(sheetname "")
		)
		(fill yes
			(thermal_gap 0.5)
			(thermal_bridge_width 0.5)
			(island_removal_mode 0)
		)
		(polygon
			(pts
				(arc
					(start 332.036928 -434.48986)
					(mid 331.262736 -434.48986)
					(end 332.036928 -434.48986)
				)
			)
		)
	)
	(zone
		(layers "B.Cu" "In15.Cu")
		(hatch none 0.5)
		(connect_pads
			(clearance 0)
		)
		(min_thickness 0.25)
		(keepout
			(tracks not_allowed)
			(vias allowed)
			(pads allowed)
			(copperpour not_allowed)
			(footprints allowed)
		)
		(placement
			(enabled no)
			(sheetname "")
		)
		(fill yes
			(thermal_gap 0.5)
			(thermal_bridge_width 0.5)
			(island_removal_mode 0)
		)
		(polygon
			(pts
				(arc
					(start 136.8298 -276.516338)
					(mid 136.19988 -276.516338)
					(end 136.8298 -276.516338)
				)
			)
		)
	)
	(zone
		(layers "B.Cu" "In15.Cu")
		(hatch none 0.5)
		(connect_pads
			(clearance 0)
		)
		(min_thickness 0.25)
		(keepout
			(tracks not_allowed)
			(vias allowed)
			(pads allowed)
			(copperpour not_allowed)
			(footprints allowed)
		)
		(placement
			(enabled no)
			(sheetname "")
		)
		(fill yes
			(thermal_gap 0.5)
			(thermal_bridge_width 0.5)
			(island_removal_mode 0)
		)
		(polygon
			(pts
				(arc
					(start 296.058082 -253.435104)
					(mid 295.390062 -253.435104)
					(end 296.058082 -253.435104)
				)
			)
		)
	)
	(zone
		(layers "B.Cu" "In15.Cu")
		(hatch none 0.5)
		(connect_pads
			(clearance 0)
		)
		(min_thickness 0.25)
		(keepout
			(tracks not_allowed)
			(vias allowed)
			(pads allowed)
			(copperpour not_allowed)
			(footprints allowed)
		)
		(placement
			(enabled no)
			(sheetname "")
		)
		(fill yes
			(thermal_gap 0.5)
			(thermal_bridge_width 0.5)
			(island_removal_mode 0)
		)
		(polygon
			(pts
				(arc
					(start 176.406048 -201.585322)
					(mid 175.738028 -201.585322)
					(end 176.406048 -201.585322)
				)
			)
		)
	)
	(zone
		(layers "B.Cu" "In15.Cu")
		(hatch none 0.5)
		(connect_pads
			(clearance 0)
		)
		(min_thickness 0.25)
		(keepout
			(tracks not_allowed)
			(vias allowed)
			(pads allowed)
			(copperpour not_allowed)
			(footprints allowed)
		)
		(placement
			(enabled no)
			(sheetname "")
		)
		(fill yes
			(thermal_gap 0.5)
			(thermal_bridge_width 0.5)
			(island_removal_mode 0)
		)
		(polygon
			(pts
				(arc
					(start 382.88976 -278.136096)
					(mid 382.25984 -278.136096)
					(end 382.88976 -278.136096)
				)
			)
		)
	)
	(zone
		(layers "B.Cu" "In15.Cu")
		(hatch none 0.5)
		(connect_pads
			(clearance 0)
		)
		(min_thickness 0.25)
		(keepout
			(tracks not_allowed)
			(vias allowed)
			(pads allowed)
			(copperpour not_allowed)
			(footprints allowed)
		)
		(placement
			(enabled no)
			(sheetname "")
		)
		(fill yes
			(thermal_gap 0.5)
			(thermal_bridge_width 0.5)
			(island_removal_mode 0)
		)
		(polygon
			(pts
				(arc
					(start 325.036688 -435.489858)
					(mid 324.262496 -435.489858)
					(end 325.036688 -435.489858)
				)
			)
		)
	)
	(zone
		(layers "B.Cu" "In15.Cu")
		(hatch none 0.5)
		(connect_pads
			(clearance 0)
		)
		(min_thickness 0.25)
		(keepout
			(tracks not_allowed)
			(vias allowed)
			(pads allowed)
			(copperpour not_allowed)
			(footprints allowed)
		)
		(placement
			(enabled no)
			(sheetname "")
		)
		(fill yes
			(thermal_gap 0.5)
			(thermal_bridge_width 0.5)
			(island_removal_mode 0)
		)
		(polygon
			(pts
				(arc
					(start 176.406048 -287.43529)
					(mid 175.738028 -287.43529)
					(end 176.406048 -287.43529)
				)
			)
		)
	)
	(zone
		(layers "B.Cu" "In15.Cu")
		(hatch none 0.5)
		(connect_pads
			(clearance 0)
		)
		(min_thickness 0.25)
		(keepout
			(tracks not_allowed)
			(vias allowed)
			(pads allowed)
			(copperpour not_allowed)
			(footprints allowed)
		)
		(placement
			(enabled no)
			(sheetname "")
		)
		(fill yes
			(thermal_gap 0.5)
			(thermal_bridge_width 0.5)
			(island_removal_mode 0)
		)
		(polygon
			(pts
				(arc
					(start 115.679728 -272.466308)
					(mid 115.049808 -272.466308)
					(end 115.679728 -272.466308)
				)
			)
		)
	)
	(zone
		(layers "B.Cu" "In15.Cu")
		(hatch none 0.5)
		(connect_pads
			(clearance 0)
		)
		(min_thickness 0.25)
		(keepout
			(tracks not_allowed)
			(vias allowed)
			(pads allowed)
			(copperpour not_allowed)
			(footprints allowed)
		)
		(placement
			(enabled no)
			(sheetname "")
		)
		(fill yes
			(thermal_gap 0.5)
			(thermal_bridge_width 0.5)
			(island_removal_mode 0)
		)
		(polygon
			(pts
				(arc
					(start 296.058082 -314.635134)
					(mid 295.390062 -314.635134)
					(end 296.058082 -314.635134)
				)
			)
		)
	)
	(zone
		(layers "B.Cu" "In15.Cu")
		(hatch none 0.5)
		(connect_pads
			(clearance 0)
		)
		(min_thickness 0.25)
		(keepout
			(tracks not_allowed)
			(vias allowed)
			(pads allowed)
			(copperpour not_allowed)
			(footprints allowed)
		)
		(placement
			(enabled no)
			(sheetname "")
		)
		(fill yes
			(thermal_gap 0.5)
			(thermal_bridge_width 0.5)
			(island_removal_mode 0)
		)
		(polygon
			(pts
				(arc
					(start 157.1371 -434.289962)
					(mid 156.362908 -434.289962)
					(end 157.1371 -434.289962)
				)
			)
		)
	)
	(zone
		(layers "B.Cu" "In15.Cu")
		(hatch none 0.5)
		(connect_pads
			(clearance 0)
		)
		(min_thickness 0.25)
		(keepout
			(tracks not_allowed)
			(vias allowed)
			(pads allowed)
			(copperpour not_allowed)
			(footprints allowed)
		)
		(placement
			(enabled no)
			(sheetname "")
		)
		(fill yes
			(thermal_gap 0.5)
			(thermal_bridge_width 0.5)
			(island_removal_mode 0)
		)
		(polygon
			(pts
				(arc
					(start 172.30598 -310.385206)
					(mid 171.63796 -310.385206)
					(end 172.30598 -310.385206)
				)
			)
		)
	)
	(zone
		(layers "B.Cu" "In15.Cu")
		(hatch none 0.5)
		(connect_pads
			(clearance 0)
		)
		(min_thickness 0.25)
		(keepout
			(tracks not_allowed)
			(vias allowed)
			(pads allowed)
			(copperpour not_allowed)
			(footprints allowed)
		)
		(placement
			(enabled no)
			(sheetname "")
		)
		(fill yes
			(thermal_gap 0.5)
			(thermal_bridge_width 0.5)
			(island_removal_mode 0)
		)
		(polygon
			(pts
				(arc
					(start 135.419592 -285.426404)
					(mid 134.789672 -285.426404)
					(end 135.419592 -285.426404)
				)
			)
		)
	)
	(zone
		(layers "B.Cu" "In15.Cu")
		(hatch none 0.5)
		(connect_pads
			(clearance 0)
		)
		(min_thickness 0.25)
		(keepout
			(tracks not_allowed)
			(vias allowed)
			(pads allowed)
			(copperpour not_allowed)
			(footprints allowed)
		)
		(placement
			(enabled no)
			(sheetname "")
		)
		(fill yes
			(thermal_gap 0.5)
			(thermal_bridge_width 0.5)
			(island_removal_mode 0)
		)
		(polygon
			(pts
				(arc
					(start 384.469894 -247.724168)
					(mid 383.839974 -247.724168)
					(end 384.469894 -247.724168)
				)
			)
		)
	)
	(zone
		(layers "B.Cu" "In15.Cu")
		(hatch none 0.5)
		(connect_pads
			(clearance 0)
		)
		(min_thickness 0.25)
		(keepout
			(tracks not_allowed)
			(vias allowed)
			(pads allowed)
			(copperpour not_allowed)
			(footprints allowed)
		)
		(placement
			(enabled no)
			(sheetname "")
		)
		(fill yes
			(thermal_gap 0.5)
			(thermal_bridge_width 0.5)
			(island_removal_mode 0)
		)
		(polygon
			(pts
				(arc
					(start 134.649718 -238.00435)
					(mid 134.019798 -238.00435)
					(end 134.649718 -238.00435)
				)
			)
		)
	)
	(zone
		(layers "B.Cu" "In15.Cu")
		(hatch none 0.5)
		(connect_pads
			(clearance 0)
		)
		(min_thickness 0.25)
		(keepout
			(tracks not_allowed)
			(vias allowed)
			(pads allowed)
			(copperpour not_allowed)
			(footprints allowed)
		)
		(placement
			(enabled no)
			(sheetname "")
		)
		(fill yes
			(thermal_gap 0.5)
			(thermal_bridge_width 0.5)
			(island_removal_mode 0)
		)
		(polygon
			(pts
				(arc
					(start 354.39604 -242.864132)
					(mid 353.76612 -242.864132)
					(end 354.39604 -242.864132)
				)
			)
		)
	)
	(zone
		(layers "B.Cu" "In15.Cu")
		(hatch none 0.5)
		(connect_pads
			(clearance 0)
		)
		(min_thickness 0.25)
		(keepout
			(tracks not_allowed)
			(vias allowed)
			(pads allowed)
			(copperpour not_allowed)
			(footprints allowed)
		)
		(placement
			(enabled no)
			(sheetname "")
		)
		(fill yes
			(thermal_gap 0.5)
			(thermal_bridge_width 0.5)
			(island_removal_mode 0)
		)
		(polygon
			(pts
				(arc
					(start 413.137096 -434.289962)
					(mid 412.362904 -434.289962)
					(end 413.137096 -434.289962)
				)
			)
		)
	)
	(zone
		(layers "B.Cu" "In15.Cu")
		(hatch none 0.5)
		(connect_pads
			(clearance 0)
		)
		(min_thickness 0.25)
		(keepout
			(tracks not_allowed)
			(vias allowed)
			(pads allowed)
			(copperpour not_allowed)
			(footprints allowed)
		)
		(placement
			(enabled no)
			(sheetname "")
		)
		(fill yes
			(thermal_gap 0.5)
			(thermal_bridge_width 0.5)
			(island_removal_mode 0)
		)
		(polygon
			(pts
				(arc
					(start 52.218082 -199.035416)
					(mid 51.550062 -199.035416)
					(end 52.218082 -199.035416)
				)
			)
		)
	)
	(zone
		(layers "B.Cu" "In15.Cu")
		(hatch none 0.5)
		(connect_pads
			(clearance 0)
		)
		(min_thickness 0.25)
		(keepout
			(tracks not_allowed)
			(vias allowed)
			(pads allowed)
			(copperpour not_allowed)
			(footprints allowed)
		)
		(placement
			(enabled no)
			(sheetname "")
		)
		(fill yes
			(thermal_gap 0.5)
			(thermal_bridge_width 0.5)
			(island_removal_mode 0)
		)
		(polygon
			(pts
				(arc
					(start 172.30598 -229.635304)
					(mid 171.63796 -229.635304)
					(end 172.30598 -229.635304)
				)
			)
		)
	)
	(zone
		(layers "B.Cu" "In15.Cu")
		(hatch none 0.5)
		(connect_pads
			(clearance 0)
		)
		(min_thickness 0.25)
		(keepout
			(tracks not_allowed)
			(vias allowed)
			(pads allowed)
			(copperpour not_allowed)
			(footprints allowed)
		)
		(placement
			(enabled no)
			(sheetname "")
		)
		(fill yes
			(thermal_gap 0.5)
			(thermal_bridge_width 0.5)
			(island_removal_mode 0)
		)
		(polygon
			(pts
				(arc
					(start 136.359646 -262.746236)
					(mid 135.729726 -262.746236)
					(end 136.359646 -262.746236)
				)
			)
		)
	)
	(zone
		(layers "B.Cu" "In15.Cu")
		(hatch none 0.5)
		(connect_pads
			(clearance 0)
		)
		(min_thickness 0.25)
		(keepout
			(tracks not_allowed)
			(vias allowed)
			(pads allowed)
			(copperpour not_allowed)
			(footprints allowed)
		)
		(placement
			(enabled no)
			(sheetname "")
		)
		(fill yes
			(thermal_gap 0.5)
			(thermal_bridge_width 0.5)
			(island_removal_mode 0)
		)
		(polygon
			(pts
				(arc
					(start 48.118014 -222.835216)
					(mid 47.449994 -222.835216)
					(end 48.118014 -222.835216)
				)
			)
		)
	)
	(zone
		(layers "B.Cu" "In15.Cu")
		(hatch none 0.5)
		(connect_pads
			(clearance 0)
		)
		(min_thickness 0.25)
		(keepout
			(tracks not_allowed)
			(vias allowed)
			(pads allowed)
			(copperpour not_allowed)
			(footprints allowed)
		)
		(placement
			(enabled no)
			(sheetname "")
		)
		(fill yes
			(thermal_gap 0.5)
			(thermal_bridge_width 0.5)
			(island_removal_mode 0)
		)
		(polygon
			(pts
				(arc
					(start 296.058082 -304.435002)
					(mid 295.390062 -304.435002)
					(end 296.058082 -304.435002)
				)
			)
		)
	)
	(zone
		(layers "B.Cu" "In15.Cu")
		(hatch none 0.5)
		(connect_pads
			(clearance 0)
		)
		(min_thickness 0.25)
		(keepout
			(tracks not_allowed)
			(vias allowed)
			(pads allowed)
			(copperpour not_allowed)
			(footprints allowed)
		)
		(placement
			(enabled no)
			(sheetname "")
		)
		(fill yes
			(thermal_gap 0.5)
			(thermal_bridge_width 0.5)
			(island_removal_mode 0)
		)
		(polygon
			(pts
				(arc
					(start 119.609616 -242.864386)
					(mid 118.979696 -242.864386)
					(end 119.609616 -242.864386)
				)
			)
		)
	)
	(zone
		(layers "B.Cu" "In15.Cu")
		(hatch none 0.5)
		(connect_pads
			(clearance 0)
		)
		(min_thickness 0.25)
		(keepout
			(tracks not_allowed)
			(vias allowed)
			(pads allowed)
			(copperpour not_allowed)
			(footprints allowed)
		)
		(placement
			(enabled no)
			(sheetname "")
		)
		(fill yes
			(thermal_gap 0.5)
			(thermal_bridge_width 0.5)
			(island_removal_mode 0)
		)
		(polygon
			(pts
				(arc
					(start 122.729752 -270.03629)
					(mid 122.099832 -270.03629)
					(end 122.729752 -270.03629)
				)
			)
		)
	)
	(zone
		(layers "B.Cu" "In15.Cu")
		(hatch none 0.5)
		(connect_pads
			(clearance 0)
		)
		(min_thickness 0.25)
		(keepout
			(tracks not_allowed)
			(vias allowed)
			(pads allowed)
			(copperpour not_allowed)
			(footprints allowed)
		)
		(placement
			(enabled no)
			(sheetname "")
		)
		(fill yes
			(thermal_gap 0.5)
			(thermal_bridge_width 0.5)
			(island_removal_mode 0)
		)
		(polygon
			(pts
				(arc
					(start 342.678004 -400.811238)
					(mid 342.009984 -400.811238)
					(end 342.678004 -400.811238)
				)
			)
		)
	)
	(zone
		(layers "B.Cu" "In15.Cu")
		(hatch none 0.5)
		(connect_pads
			(clearance 0)
		)
		(min_thickness 0.25)
		(keepout
			(tracks not_allowed)
			(vias allowed)
			(pads allowed)
			(copperpour not_allowed)
			(footprints allowed)
		)
		(placement
			(enabled no)
			(sheetname "")
		)
		(fill yes
			(thermal_gap 0.5)
			(thermal_bridge_width 0.5)
			(island_removal_mode 0)
		)
		(polygon
			(pts
				(arc
					(start 172.30598 -305.285394)
					(mid 171.63796 -305.285394)
					(end 172.30598 -305.285394)
				)
			)
		)
	)
	(zone
		(layers "B.Cu" "In15.Cu")
		(hatch none 0.5)
		(connect_pads
			(clearance 0)
		)
		(min_thickness 0.25)
		(keepout
			(tracks not_allowed)
			(vias allowed)
			(pads allowed)
			(copperpour not_allowed)
			(footprints allowed)
		)
		(placement
			(enabled no)
			(sheetname "")
		)
		(fill yes
			(thermal_gap 0.5)
			(thermal_bridge_width 0.5)
			(island_removal_mode 0)
		)
		(polygon
			(pts
				(arc
					(start 130.850386 -393.292838)
					(mid 130.182366 -393.292838)
					(end 130.850386 -393.292838)
				)
			)
		)
	)
	(zone
		(layers "B.Cu" "In15.Cu")
		(hatch none 0.5)
		(connect_pads
			(clearance 0)
		)
		(min_thickness 0.25)
		(keepout
			(tracks not_allowed)
			(vias allowed)
			(pads allowed)
			(copperpour not_allowed)
			(footprints allowed)
		)
		(placement
			(enabled no)
			(sheetname "")
		)
		(fill yes
			(thermal_gap 0.5)
			(thermal_bridge_width 0.5)
			(island_removal_mode 0)
		)
		(polygon
			(pts
				(arc
					(start 337.006184 -246.914162)
					(mid 336.376264 -246.914162)
					(end 337.006184 -246.914162)
				)
			)
		)
	)
	(zone
		(layers "B.Cu" "In15.Cu")
		(hatch none 0.5)
		(connect_pads
			(clearance 0)
		)
		(min_thickness 0.25)
		(keepout
			(tracks not_allowed)
			(vias allowed)
			(pads allowed)
			(copperpour not_allowed)
			(footprints allowed)
		)
		(placement
			(enabled no)
			(sheetname "")
		)
		(fill yes
			(thermal_gap 0.5)
			(thermal_bridge_width 0.5)
			(island_removal_mode 0)
		)
		(polygon
			(pts
				(arc
					(start 383.250694 -400.811238)
					(mid 382.582674 -400.811238)
					(end 383.250694 -400.811238)
				)
			)
		)
	)
	(zone
		(layers "B.Cu" "In15.Cu")
		(hatch none 0.5)
		(connect_pads
			(clearance 0)
		)
		(min_thickness 0.25)
		(keepout
			(tracks not_allowed)
			(vias allowed)
			(pads allowed)
			(copperpour not_allowed)
			(footprints allowed)
		)
		(placement
			(enabled no)
			(sheetname "")
		)
		(fill yes
			(thermal_gap 0.5)
			(thermal_bridge_width 0.5)
			(island_removal_mode 0)
		)
		(polygon
			(pts
				(arc
					(start 382.88976 -265.176)
					(mid 382.25984 -265.176)
					(end 382.88976 -265.176)
				)
			)
		)
	)
	(zone
		(layers "B.Cu" "In15.Cu")
		(hatch none 0.5)
		(connect_pads
			(clearance 0)
		)
		(min_thickness 0.25)
		(keepout
			(tracks not_allowed)
			(vias allowed)
			(pads allowed)
			(copperpour not_allowed)
			(footprints allowed)
		)
		(placement
			(enabled no)
			(sheetname "")
		)
		(fill yes
			(thermal_gap 0.5)
			(thermal_bridge_width 0.5)
			(island_removal_mode 0)
		)
		(polygon
			(pts
				(arc
					(start 52.218082 -197.335394)
					(mid 51.550062 -197.335394)
					(end 52.218082 -197.335394)
				)
			)
		)
	)
	(zone
		(layers "B.Cu" "In15.Cu")
		(hatch none 0.5)
		(connect_pads
			(clearance 0)
		)
		(min_thickness 0.25)
		(keepout
			(tracks not_allowed)
			(vias allowed)
			(pads allowed)
			(copperpour not_allowed)
			(footprints allowed)
		)
		(placement
			(enabled no)
			(sheetname "")
		)
		(fill yes
			(thermal_gap 0.5)
			(thermal_bridge_width 0.5)
			(island_removal_mode 0)
		)
		(polygon
			(pts
				(arc
					(start 300.15815 -298.485052)
					(mid 299.49013 -298.485052)
					(end 300.15815 -298.485052)
				)
			)
		)
	)
	(zone
		(layers "B.Cu" "In15.Cu")
		(hatch none 0.5)
		(connect_pads
			(clearance 0)
		)
		(min_thickness 0.25)
		(keepout
			(tracks not_allowed)
			(vias allowed)
			(pads allowed)
			(copperpour not_allowed)
			(footprints allowed)
		)
		(placement
			(enabled no)
			(sheetname "")
		)
		(fill yes
			(thermal_gap 0.5)
			(thermal_bridge_width 0.5)
			(island_removal_mode 0)
		)
		(polygon
			(pts
				(arc
					(start 383.99974 -245.29415)
					(mid 383.36982 -245.29415)
					(end 383.99974 -245.29415)
				)
			)
		)
	)
	(zone
		(layers "B.Cu" "In15.Cu")
		(hatch none 0.5)
		(connect_pads
			(clearance 0)
		)
		(min_thickness 0.25)
		(keepout
			(tracks not_allowed)
			(vias allowed)
			(pads allowed)
			(copperpour not_allowed)
			(footprints allowed)
		)
		(placement
			(enabled no)
			(sheetname "")
		)
		(fill yes
			(thermal_gap 0.5)
			(thermal_bridge_width 0.5)
			(island_removal_mode 0)
		)
		(polygon
			(pts
				(arc
					(start 101.11613 -270.03629)
					(mid 100.48621 -270.03629)
					(end 101.11613 -270.03629)
				)
			)
		)
	)
	(zone
		(layers "B.Cu" "In15.Cu")
		(hatch none 0.5)
		(connect_pads
			(clearance 0)
		)
		(min_thickness 0.25)
		(keepout
			(tracks not_allowed)
			(vias allowed)
			(pads allowed)
			(copperpour not_allowed)
			(footprints allowed)
		)
		(placement
			(enabled no)
			(sheetname "")
		)
		(fill yes
			(thermal_gap 0.5)
			(thermal_bridge_width 0.5)
			(island_removal_mode 0)
		)
		(polygon
			(pts
				(arc
					(start 48.118014 -288.285428)
					(mid 47.449994 -288.285428)
					(end 48.118014 -288.285428)
				)
			)
		)
	)
	(zone
		(layers "B.Cu" "In15.Cu")
		(hatch none 0.5)
		(connect_pads
			(clearance 0)
		)
		(min_thickness 0.25)
		(keepout
			(tracks not_allowed)
			(vias allowed)
			(pads allowed)
			(copperpour not_allowed)
			(footprints allowed)
		)
		(placement
			(enabled no)
			(sheetname "")
		)
		(fill yes
			(thermal_gap 0.5)
			(thermal_bridge_width 0.5)
			(island_removal_mode 0)
		)
		(polygon
			(pts
				(arc
					(start 309.30596 -394.385292)
					(mid 308.67604 -394.385292)
					(end 309.30596 -394.385292)
				)
			)
		)
	)
	(zone
		(layers "B.Cu" "In15.Cu")
		(hatch none 0.5)
		(connect_pads
			(clearance 0)
		)
		(min_thickness 0.25)
		(keepout
			(tracks not_allowed)
			(vias allowed)
			(pads allowed)
			(copperpour not_allowed)
			(footprints allowed)
		)
		(placement
			(enabled no)
			(sheetname "")
		)
		(fill yes
			(thermal_gap 0.5)
			(thermal_bridge_width 0.5)
			(island_removal_mode 0)
		)
		(polygon
			(pts
				(arc
					(start 424.346116 -199.035162)
					(mid 423.678096 -199.035162)
					(end 424.346116 -199.035162)
				)
			)
		)
	)
	(zone
		(layers "B.Cu" "In15.Cu")
		(hatch none 0.5)
		(connect_pads
			(clearance 0)
		)
		(min_thickness 0.25)
		(keepout
			(tracks not_allowed)
			(vias allowed)
			(pads allowed)
			(copperpour not_allowed)
			(footprints allowed)
		)
		(placement
			(enabled no)
			(sheetname "")
		)
		(fill yes
			(thermal_gap 0.5)
			(thermal_bridge_width 0.5)
			(island_removal_mode 0)
		)
		(polygon
			(pts
				(arc
					(start 157.1371 -435.489858)
					(mid 156.362908 -435.489858)
					(end 157.1371 -435.489858)
				)
			)
		)
	)
	(zone
		(layers "B.Cu" "In15.Cu")
		(hatch none 0.5)
		(connect_pads
			(clearance 0)
		)
		(min_thickness 0.25)
		(keepout
			(tracks not_allowed)
			(vias allowed)
			(pads allowed)
			(copperpour not_allowed)
			(footprints allowed)
		)
		(placement
			(enabled no)
			(sheetname "")
		)
		(fill yes
			(thermal_gap 0.5)
			(thermal_bridge_width 0.5)
			(island_removal_mode 0)
		)
		(polygon
			(pts
				(arc
					(start 420.246048 -278.93518)
					(mid 419.578028 -278.93518)
					(end 420.246048 -278.93518)
				)
			)
		)
	)
	(zone
		(layers "B.Cu" "In15.Cu")
		(hatch none 0.5)
		(connect_pads
			(clearance 0)
		)
		(min_thickness 0.25)
		(keepout
			(tracks not_allowed)
			(vias allowed)
			(pads allowed)
			(copperpour not_allowed)
			(footprints allowed)
		)
		(placement
			(enabled no)
			(sheetname "")
		)
		(fill yes
			(thermal_gap 0.5)
			(thermal_bridge_width 0.5)
			(island_removal_mode 0)
		)
		(polygon
			(pts
				(arc
					(start 384.769868 -292.71595)
					(mid 384.139948 -292.71595)
					(end 384.769868 -292.71595)
				)
			)
		)
	)
	(zone
		(layers "B.Cu" "In15.Cu")
		(hatch none 0.5)
		(connect_pads
			(clearance 0)
		)
		(min_thickness 0.25)
		(keepout
			(tracks not_allowed)
			(vias allowed)
			(pads allowed)
			(copperpour not_allowed)
			(footprints allowed)
		)
		(placement
			(enabled no)
			(sheetname "")
		)
		(fill yes
			(thermal_gap 0.5)
			(thermal_bridge_width 0.5)
			(island_removal_mode 0)
		)
		(polygon
			(pts
				(arc
					(start 300.15815 -203.28509)
					(mid 299.49013 -203.28509)
					(end 300.15815 -203.28509)
				)
			)
		)
	)
	(zone
		(layers "B.Cu" "In15.Cu")
		(hatch none 0.5)
		(connect_pads
			(clearance 0)
		)
		(min_thickness 0.25)
		(keepout
			(tracks not_allowed)
			(vias allowed)
			(pads allowed)
			(copperpour not_allowed)
			(footprints allowed)
		)
		(placement
			(enabled no)
			(sheetname "")
		)
		(fill yes
			(thermal_gap 0.5)
			(thermal_bridge_width 0.5)
			(island_removal_mode 0)
		)
		(polygon
			(pts
				(arc
					(start 97.478342 -393.292838)
					(mid 96.810322 -393.292838)
					(end 97.478342 -393.292838)
				)
			)
		)
	)
	(zone
		(layers "B.Cu" "In15.Cu")
		(hatch none 0.5)
		(connect_pads
			(clearance 0)
		)
		(min_thickness 0.25)
		(keepout
			(tracks not_allowed)
			(vias allowed)
			(pads allowed)
			(copperpour not_allowed)
			(footprints allowed)
		)
		(placement
			(enabled no)
			(sheetname "")
		)
		(fill yes
			(thermal_gap 0.5)
			(thermal_bridge_width 0.5)
			(island_removal_mode 0)
		)
		(polygon
			(pts
				(arc
					(start 165.100254 -369.03533)
					(mid 164.432234 -369.03533)
					(end 165.100254 -369.03533)
				)
			)
		)
	)
	(zone
		(layers "B.Cu" "In15.Cu")
		(hatch none 0.5)
		(connect_pads
			(clearance 0)
		)
		(min_thickness 0.25)
		(keepout
			(tracks not_allowed)
			(vias allowed)
			(pads allowed)
			(copperpour not_allowed)
			(footprints allowed)
		)
		(placement
			(enabled no)
			(sheetname "")
		)
		(fill yes
			(thermal_gap 0.5)
			(thermal_bridge_width 0.5)
			(island_removal_mode 0)
		)
		(polygon
			(pts
				(arc
					(start 388.136892 -435.489858)
					(mid 387.3627 -435.489858)
					(end 388.136892 -435.489858)
				)
			)
		)
	)
	(zone
		(layers "B.Cu" "In15.Cu")
		(hatch none 0.5)
		(connect_pads
			(clearance 0)
		)
		(min_thickness 0.25)
		(keepout
			(tracks not_allowed)
			(vias allowed)
			(pads allowed)
			(copperpour not_allowed)
			(footprints allowed)
		)
		(placement
			(enabled no)
			(sheetname "")
		)
		(fill yes
			(thermal_gap 0.5)
			(thermal_bridge_width 0.5)
			(island_removal_mode 0)
		)
		(polygon
			(pts
				(arc
					(start 120.54967 -242.864386)
					(mid 119.91975 -242.864386)
					(end 120.54967 -242.864386)
				)
			)
		)
	)
	(zone
		(layers "B.Cu" "In15.Cu")
		(hatch none 0.5)
		(connect_pads
			(clearance 0)
		)
		(min_thickness 0.25)
		(keepout
			(tracks not_allowed)
			(vias allowed)
			(pads allowed)
			(copperpour not_allowed)
			(footprints allowed)
		)
		(placement
			(enabled no)
			(sheetname "")
		)
		(fill yes
			(thermal_gap 0.5)
			(thermal_bridge_width 0.5)
			(island_removal_mode 0)
		)
		(polygon
			(pts
				(arc
					(start 424.346116 -245.785132)
					(mid 423.678096 -245.785132)
					(end 424.346116 -245.785132)
				)
			)
		)
	)
	(zone
		(layers "B.Cu" "In15.Cu")
		(hatch none 0.5)
		(connect_pads
			(clearance 0)
		)
		(min_thickness 0.25)
		(keepout
			(tracks not_allowed)
			(vias allowed)
			(pads allowed)
			(copperpour not_allowed)
			(footprints allowed)
		)
		(placement
			(enabled no)
			(sheetname "")
		)
		(fill yes
			(thermal_gap 0.5)
			(thermal_bridge_width 0.5)
			(island_removal_mode 0)
		)
		(polygon
			(pts
				(arc
					(start 81.87817 -393.292838)
					(mid 81.21015 -393.292838)
					(end 81.87817 -393.292838)
				)
			)
		)
	)
	(zone
		(layers "B.Cu" "In15.Cu")
		(hatch none 0.5)
		(connect_pads
			(clearance 0)
		)
		(min_thickness 0.25)
		(keepout
			(tracks not_allowed)
			(vias allowed)
			(pads allowed)
			(copperpour not_allowed)
			(footprints allowed)
		)
		(placement
			(enabled no)
			(sheetname "")
		)
		(fill yes
			(thermal_gap 0.5)
			(thermal_bridge_width 0.5)
			(island_removal_mode 0)
		)
		(polygon
			(pts
				(arc
					(start 48.118014 -295.085262)
					(mid 47.449994 -295.085262)
					(end 48.118014 -295.085262)
				)
			)
		)
	)
	(zone
		(layers "B.Cu" "In15.Cu")
		(hatch none 0.5)
		(connect_pads
			(clearance 0)
		)
		(min_thickness 0.25)
		(keepout
			(tracks not_allowed)
			(vias allowed)
			(pads allowed)
			(copperpour not_allowed)
			(footprints allowed)
		)
		(placement
			(enabled no)
			(sheetname "")
		)
		(fill yes
			(thermal_gap 0.5)
			(thermal_bridge_width 0.5)
			(island_removal_mode 0)
		)
		(polygon
			(pts
				(arc
					(start 86.037166 -434.289962)
					(mid 85.262974 -434.289962)
					(end 86.037166 -434.289962)
				)
			)
		)
	)
	(zone
		(layers "B.Cu" "In15.Cu")
		(hatch none 0.5)
		(connect_pads
			(clearance 0)
		)
		(min_thickness 0.25)
		(keepout
			(tracks not_allowed)
			(vias allowed)
			(pads allowed)
			(copperpour not_allowed)
			(footprints allowed)
		)
		(placement
			(enabled no)
			(sheetname "")
		)
		(fill yes
			(thermal_gap 0.5)
			(thermal_bridge_width 0.5)
			(island_removal_mode 0)
		)
		(polygon
			(pts
				(arc
					(start 352.277934 -400.811238)
					(mid 351.609914 -400.811238)
					(end 352.277934 -400.811238)
				)
			)
		)
	)
	(zone
		(layers "B.Cu" "In15.Cu")
		(hatch none 0.5)
		(connect_pads
			(clearance 0)
		)
		(min_thickness 0.25)
		(keepout
			(tracks not_allowed)
			(vias allowed)
			(pads allowed)
			(copperpour not_allowed)
			(footprints allowed)
		)
		(placement
			(enabled no)
			(sheetname "")
		)
		(fill yes
			(thermal_gap 0.5)
			(thermal_bridge_width 0.5)
			(island_removal_mode 0)
		)
		(polygon
			(pts
				(arc
					(start 172.30598 -220.28531)
					(mid 171.63796 -220.28531)
					(end 172.30598 -220.28531)
				)
			)
		)
	)
	(zone
		(layers "B.Cu" "In15.Cu")
		(hatch none 0.5)
		(connect_pads
			(clearance 0)
		)
		(min_thickness 0.25)
		(keepout
			(tracks not_allowed)
			(vias allowed)
			(pads allowed)
			(copperpour not_allowed)
			(footprints allowed)
		)
		(placement
			(enabled no)
			(sheetname "")
		)
		(fill yes
			(thermal_gap 0.5)
			(thermal_bridge_width 0.5)
			(island_removal_mode 0)
		)
		(polygon
			(pts
				(arc
					(start 327.036684 -433.289964)
					(mid 326.262492 -433.289964)
					(end 327.036684 -433.289964)
				)
			)
		)
	)
	(zone
		(layers "B.Cu" "In15.Cu")
		(hatch none 0.5)
		(connect_pads
			(clearance 0)
		)
		(min_thickness 0.25)
		(keepout
			(tracks not_allowed)
			(vias allowed)
			(pads allowed)
			(copperpour not_allowed)
			(footprints allowed)
		)
		(placement
			(enabled no)
			(sheetname "")
		)
		(fill yes
			(thermal_gap 0.5)
			(thermal_bridge_width 0.5)
			(island_removal_mode 0)
		)
		(polygon
			(pts
				(arc
					(start 52.218082 -249.18543)
					(mid 51.550062 -249.18543)
					(end 52.218082 -249.18543)
				)
			)
		)
	)
	(zone
		(layers "B.Cu" "In15.Cu")
		(hatch none 0.5)
		(connect_pads
			(clearance 0)
		)
		(min_thickness 0.25)
		(keepout
			(tracks not_allowed)
			(vias allowed)
			(pads allowed)
			(copperpour not_allowed)
			(footprints allowed)
		)
		(placement
			(enabled no)
			(sheetname "")
		)
		(fill yes
			(thermal_gap 0.5)
			(thermal_bridge_width 0.5)
			(island_removal_mode 0)
		)
		(polygon
			(pts
				(arc
					(start 337.306158 -262.745982)
					(mid 336.676238 -262.745982)
					(end 337.306158 -262.745982)
				)
			)
		)
	)
	(zone
		(layers "B.Cu" "In15.Cu")
		(hatch none 0.5)
		(connect_pads
			(clearance 0)
		)
		(min_thickness 0.25)
		(keepout
			(tracks not_allowed)
			(vias allowed)
			(pads allowed)
			(copperpour not_allowed)
			(footprints allowed)
		)
		(placement
			(enabled no)
			(sheetname "")
		)
		(fill yes
			(thermal_gap 0.5)
			(thermal_bridge_width 0.5)
			(island_removal_mode 0)
		)
		(polygon
			(pts
				(arc
					(start 384.469894 -233.14406)
					(mid 383.839974 -233.14406)
					(end 384.469894 -233.14406)
				)
			)
		)
	)
	(zone
		(layers "B.Cu" "In15.Cu")
		(hatch none 0.5)
		(connect_pads
			(clearance 0)
		)
		(min_thickness 0.25)
		(keepout
			(tracks not_allowed)
			(vias allowed)
			(pads allowed)
			(copperpour not_allowed)
			(footprints allowed)
		)
		(placement
			(enabled no)
			(sheetname "")
		)
		(fill yes
			(thermal_gap 0.5)
			(thermal_bridge_width 0.5)
			(island_removal_mode 0)
		)
		(polygon
			(pts
				(arc
					(start 87.955882 -292.716204)
					(mid 87.325962 -292.716204)
					(end 87.955882 -292.716204)
				)
			)
		)
	)
	(zone
		(layers "B.Cu" "In15.Cu")
		(hatch none 0.5)
		(connect_pads
			(clearance 0)
		)
		(min_thickness 0.25)
		(keepout
			(tracks not_allowed)
			(vias allowed)
			(pads allowed)
			(copperpour not_allowed)
			(footprints allowed)
		)
		(placement
			(enabled no)
			(sheetname "")
		)
		(fill yes
			(thermal_gap 0.5)
			(thermal_bridge_width 0.5)
			(island_removal_mode 0)
		)
		(polygon
			(pts
				(arc
					(start 172.30598 -304.435256)
					(mid 171.63796 -304.435256)
					(end 172.30598 -304.435256)
				)
			)
		)
	)
	(zone
		(layers "B.Cu" "In15.Cu")
		(hatch none 0.5)
		(connect_pads
			(clearance 0)
		)
		(min_thickness 0.25)
		(keepout
			(tracks not_allowed)
			(vias allowed)
			(pads allowed)
			(copperpour not_allowed)
			(footprints allowed)
		)
		(placement
			(enabled no)
			(sheetname "")
		)
		(fill yes
			(thermal_gap 0.5)
			(thermal_bridge_width 0.5)
			(island_removal_mode 0)
		)
		(polygon
			(pts
				(arc
					(start 420.246048 -211.784946)
					(mid 419.578028 -211.784946)
					(end 420.246048 -211.784946)
				)
			)
		)
	)
	(zone
		(layers "B.Cu" "In15.Cu")
		(hatch none 0.5)
		(connect_pads
			(clearance 0)
		)
		(min_thickness 0.25)
		(keepout
			(tracks not_allowed)
			(vias allowed)
			(pads allowed)
			(copperpour not_allowed)
			(footprints allowed)
		)
		(placement
			(enabled no)
			(sheetname "")
		)
		(fill yes
			(thermal_gap 0.5)
			(thermal_bridge_width 0.5)
			(island_removal_mode 0)
		)
		(polygon
			(pts
				(arc
					(start 136.359646 -275.706332)
					(mid 135.729726 -275.706332)
					(end 136.359646 -275.706332)
				)
			)
		)
	)
	(zone
		(layers "B.Cu" "In15.Cu")
		(hatch none 0.5)
		(connect_pads
			(clearance 0)
		)
		(min_thickness 0.25)
		(keepout
			(tracks not_allowed)
			(vias allowed)
			(pads allowed)
			(copperpour not_allowed)
			(footprints allowed)
		)
		(placement
			(enabled no)
			(sheetname "")
		)
		(fill yes
			(thermal_gap 0.5)
			(thermal_bridge_width 0.5)
			(island_removal_mode 0)
		)
		(polygon
			(pts
				(arc
					(start 380.850648 -401.674838)
					(mid 380.182628 -401.674838)
					(end 380.850648 -401.674838)
				)
			)
		)
	)
	(zone
		(layers "B.Cu" "In15.Cu")
		(hatch none 0.5)
		(connect_pads
			(clearance 0)
		)
		(min_thickness 0.25)
		(keepout
			(tracks not_allowed)
			(vias allowed)
			(pads allowed)
			(copperpour not_allowed)
			(footprints allowed)
		)
		(placement
			(enabled no)
			(sheetname "")
		)
		(fill yes
			(thermal_gap 0.5)
			(thermal_bridge_width 0.5)
			(island_removal_mode 0)
		)
		(polygon
			(pts
				(arc
					(start 424.346116 -234.735116)
					(mid 423.678096 -234.735116)
					(end 424.346116 -234.735116)
				)
			)
		)
	)
	(zone
		(layers "B.Cu" "In15.Cu")
		(hatch none 0.5)
		(connect_pads
			(clearance 0)
		)
		(min_thickness 0.25)
		(keepout
			(tracks not_allowed)
			(vias allowed)
			(pads allowed)
			(copperpour not_allowed)
			(footprints allowed)
		)
		(placement
			(enabled no)
			(sheetname "")
		)
		(fill yes
			(thermal_gap 0.5)
			(thermal_bridge_width 0.5)
			(island_removal_mode 0)
		)
		(polygon
			(pts
				(arc
					(start 420.246048 -316.335156)
					(mid 419.578028 -316.335156)
					(end 420.246048 -316.335156)
				)
			)
		)
	)
	(zone
		(layers "B.Cu" "In15.Cu")
		(hatch none 0.5)
		(connect_pads
			(clearance 0)
		)
		(min_thickness 0.25)
		(keepout
			(tracks not_allowed)
			(vias allowed)
			(pads allowed)
			(copperpour not_allowed)
			(footprints allowed)
		)
		(placement
			(enabled no)
			(sheetname "")
		)
		(fill yes
			(thermal_gap 0.5)
			(thermal_bridge_width 0.5)
			(island_removal_mode 0)
		)
		(polygon
			(pts
				(arc
					(start 99.236022 -273.276314)
					(mid 98.606102 -273.276314)
					(end 99.236022 -273.276314)
				)
			)
		)
	)
	(zone
		(layers "B.Cu" "In15.Cu")
		(hatch none 0.5)
		(connect_pads
			(clearance 0)
		)
		(min_thickness 0.25)
		(keepout
			(tracks not_allowed)
			(vias allowed)
			(pads allowed)
			(copperpour not_allowed)
			(footprints allowed)
		)
		(placement
			(enabled no)
			(sheetname "")
		)
		(fill yes
			(thermal_gap 0.5)
			(thermal_bridge_width 0.5)
			(island_removal_mode 0)
		)
		(polygon
			(pts
				(arc
					(start 424.346116 -289.135058)
					(mid 423.678096 -289.135058)
					(end 424.346116 -289.135058)
				)
			)
		)
	)
	(zone
		(layers "B.Cu" "In15.Cu")
		(hatch none 0.5)
		(connect_pads
			(clearance 0)
		)
		(min_thickness 0.25)
		(keepout
			(tracks not_allowed)
			(vias allowed)
			(pads allowed)
			(copperpour not_allowed)
			(footprints allowed)
		)
		(placement
			(enabled no)
			(sheetname "")
		)
		(fill yes
			(thermal_gap 0.5)
			(thermal_bridge_width 0.5)
			(island_removal_mode 0)
		)
		(polygon
			(pts
				(arc
					(start 135.119618 -238.814356)
					(mid 134.489698 -238.814356)
					(end 135.119618 -238.814356)
				)
			)
		)
	)
	(zone
		(layers "B.Cu" "In15.Cu")
		(hatch none 0.5)
		(connect_pads
			(clearance 0)
		)
		(min_thickness 0.25)
		(keepout
			(tracks not_allowed)
			(vias allowed)
			(pads allowed)
			(copperpour not_allowed)
			(footprints allowed)
		)
		(placement
			(enabled no)
			(sheetname "")
		)
		(fill yes
			(thermal_gap 0.5)
			(thermal_bridge_width 0.5)
			(island_removal_mode 0)
		)
		(polygon
			(pts
				(arc
					(start 300.15815 -233.035094)
					(mid 299.49013 -233.035094)
					(end 300.15815 -233.035094)
				)
			)
		)
	)
	(zone
		(layers "B.Cu" "In15.Cu")
		(hatch none 0.5)
		(connect_pads
			(clearance 0)
		)
		(min_thickness 0.25)
		(keepout
			(tracks not_allowed)
			(vias allowed)
			(pads allowed)
			(copperpour not_allowed)
			(footprints allowed)
		)
		(placement
			(enabled no)
			(sheetname "")
		)
		(fill yes
			(thermal_gap 0.5)
			(thermal_bridge_width 0.5)
			(island_removal_mode 0)
		)
		(polygon
			(pts
				(arc
					(start 424.346116 -250.884944)
					(mid 423.678096 -250.884944)
					(end 424.346116 -250.884944)
				)
			)
		)
	)
	(zone
		(layers "B.Cu" "In15.Cu")
		(hatch none 0.5)
		(connect_pads
			(clearance 0)
		)
		(min_thickness 0.25)
		(keepout
			(tracks not_allowed)
			(vias allowed)
			(pads allowed)
			(copperpour not_allowed)
			(footprints allowed)
		)
		(placement
			(enabled no)
			(sheetname "")
		)
		(fill yes
			(thermal_gap 0.5)
			(thermal_bridge_width 0.5)
			(island_removal_mode 0)
		)
		(polygon
			(pts
				(arc
					(start 421.10025 -377.41733)
					(mid 420.43223 -377.41733)
					(end 421.10025 -377.41733)
				)
			)
		)
	)
	(zone
		(layers "B.Cu" "In15.Cu")
		(hatch none 0.5)
		(connect_pads
			(clearance 0)
		)
		(min_thickness 0.25)
		(keepout
			(tracks not_allowed)
			(vias allowed)
			(pads allowed)
			(copperpour not_allowed)
			(footprints allowed)
		)
		(placement
			(enabled no)
			(sheetname "")
		)
		(fill yes
			(thermal_gap 0.5)
			(thermal_bridge_width 0.5)
			(island_removal_mode 0)
		)
		(polygon
			(pts
				(arc
					(start 87.955882 -279.756362)
					(mid 87.325962 -279.756362)
					(end 87.955882 -279.756362)
				)
			)
		)
	)
	(zone
		(layers "B.Cu" "In15.Cu")
		(hatch none 0.5)
		(connect_pads
			(clearance 0)
		)
		(min_thickness 0.25)
		(keepout
			(tracks not_allowed)
			(vias allowed)
			(pads allowed)
			(copperpour not_allowed)
			(footprints allowed)
		)
		(placement
			(enabled no)
			(sheetname "")
		)
		(fill yes
			(thermal_gap 0.5)
			(thermal_bridge_width 0.5)
			(island_removal_mode 0)
		)
		(polygon
			(pts
				(arc
					(start 52.218082 -284.885384)
					(mid 51.550062 -284.885384)
					(end 52.218082 -284.885384)
				)
			)
		)
	)
	(zone
		(layers "B.Cu" "In15.Cu")
		(hatch none 0.5)
		(connect_pads
			(clearance 0)
		)
		(min_thickness 0.25)
		(keepout
			(tracks not_allowed)
			(vias allowed)
			(pads allowed)
			(copperpour not_allowed)
			(footprints allowed)
		)
		(placement
			(enabled no)
			(sheetname "")
		)
		(fill yes
			(thermal_gap 0.5)
			(thermal_bridge_width 0.5)
			(island_removal_mode 0)
		)
		(polygon
			(pts
				(arc
					(start 98.295968 -271.656302)
					(mid 97.666048 -271.656302)
					(end 98.295968 -271.656302)
				)
			)
		)
	)
	(zone
		(layers "B.Cu" "In15.Cu")
		(hatch none 0.5)
		(connect_pads
			(clearance 0)
		)
		(min_thickness 0.25)
		(keepout
			(tracks not_allowed)
			(vias allowed)
			(pads allowed)
			(copperpour not_allowed)
			(footprints allowed)
		)
		(placement
			(enabled no)
			(sheetname "")
		)
		(fill yes
			(thermal_gap 0.5)
			(thermal_bridge_width 0.5)
			(island_removal_mode 0)
		)
		(polygon
			(pts
				(arc
					(start 89.83599 -261.93623)
					(mid 89.20607 -261.93623)
					(end 89.83599 -261.93623)
				)
			)
		)
	)
	(zone
		(layers "B.Cu" "In15.Cu")
		(hatch none 0.5)
		(connect_pads
			(clearance 0)
		)
		(min_thickness 0.25)
		(keepout
			(tracks not_allowed)
			(vias allowed)
			(pads allowed)
			(copperpour not_allowed)
			(footprints allowed)
		)
		(placement
			(enabled no)
			(sheetname "")
		)
		(fill yes
			(thermal_gap 0.5)
			(thermal_bridge_width 0.5)
			(island_removal_mode 0)
		)
		(polygon
			(pts
				(arc
					(start 296.058082 -205.834996)
					(mid 295.390062 -205.834996)
					(end 296.058082 -205.834996)
				)
			)
		)
	)
	(zone
		(layers "B.Cu" "In15.Cu")
		(hatch none 0.5)
		(connect_pads
			(clearance 0)
		)
		(min_thickness 0.25)
		(keepout
			(tracks not_allowed)
			(vias allowed)
			(pads allowed)
			(copperpour not_allowed)
			(footprints allowed)
		)
		(placement
			(enabled no)
			(sheetname "")
		)
		(fill yes
			(thermal_gap 0.5)
			(thermal_bridge_width 0.5)
			(island_removal_mode 0)
		)
		(polygon
			(pts
				(arc
					(start 52.218082 -285.735268)
					(mid 51.550062 -285.735268)
					(end 52.218082 -285.735268)
				)
			)
		)
	)
	(zone
		(layers "B.Cu" "In15.Cu")
		(hatch none 0.5)
		(connect_pads
			(clearance 0)
		)
		(min_thickness 0.25)
		(keepout
			(tracks not_allowed)
			(vias allowed)
			(pads allowed)
			(copperpour not_allowed)
			(footprints allowed)
		)
		(placement
			(enabled no)
			(sheetname "")
		)
		(fill yes
			(thermal_gap 0.5)
			(thermal_bridge_width 0.5)
			(island_removal_mode 0)
		)
		(polygon
			(pts
				(arc
					(start 52.218082 -223.685354)
					(mid 51.550062 -223.685354)
					(end 52.218082 -223.685354)
				)
			)
		)
	)
	(zone
		(layers "B.Cu" "In15.Cu")
		(hatch none 0.5)
		(connect_pads
			(clearance 0)
		)
		(min_thickness 0.25)
		(keepout
			(tracks not_allowed)
			(vias allowed)
			(pads allowed)
			(copperpour not_allowed)
			(footprints allowed)
		)
		(placement
			(enabled no)
			(sheetname "")
		)
		(fill yes
			(thermal_gap 0.5)
			(thermal_bridge_width 0.5)
			(island_removal_mode 0)
		)
		(polygon
			(pts
				(arc
					(start 89.536016 -242.864386)
					(mid 88.906096 -242.864386)
					(end 89.536016 -242.864386)
				)
			)
		)
	)
	(zone
		(layers "B.Cu" "In15.Cu")
		(hatch none 0.5)
		(connect_pads
			(clearance 0)
		)
		(min_thickness 0.25)
		(keepout
			(tracks not_allowed)
			(vias allowed)
			(pads allowed)
			(copperpour not_allowed)
			(footprints allowed)
		)
		(placement
			(enabled no)
			(sheetname "")
		)
		(fill yes
			(thermal_gap 0.5)
			(thermal_bridge_width 0.5)
			(island_removal_mode 0)
		)
		(polygon
			(pts
				(arc
					(start 382.589786 -239.624108)
					(mid 381.959866 -239.624108)
					(end 382.589786 -239.624108)
				)
			)
		)
	)
	(zone
		(layers "B.Cu" "In15.Cu")
		(hatch none 0.5)
		(connect_pads
			(clearance 0)
		)
		(min_thickness 0.25)
		(keepout
			(tracks not_allowed)
			(vias allowed)
			(pads allowed)
			(copperpour not_allowed)
			(footprints allowed)
		)
		(placement
			(enabled no)
			(sheetname "")
		)
		(fill yes
			(thermal_gap 0.5)
			(thermal_bridge_width 0.5)
			(island_removal_mode 0)
		)
		(polygon
			(pts
				(arc
					(start 143.137128 -433.289964)
					(mid 142.362936 -433.289964)
					(end 143.137128 -433.289964)
				)
			)
		)
	)
	(zone
		(layers "B.Cu" "In15.Cu")
		(hatch none 0.5)
		(connect_pads
			(clearance 0)
		)
		(min_thickness 0.25)
		(keepout
			(tracks not_allowed)
			(vias allowed)
			(pads allowed)
			(copperpour not_allowed)
			(footprints allowed)
		)
		(placement
			(enabled no)
			(sheetname "")
		)
		(fill yes
			(thermal_gap 0.5)
			(thermal_bridge_width 0.5)
			(island_removal_mode 0)
		)
		(polygon
			(pts
				(arc
					(start 80.037178 -434.48986)
					(mid 79.262986 -434.48986)
					(end 80.037178 -434.48986)
				)
			)
		)
	)
	(zone
		(layers "B.Cu" "In15.Cu")
		(hatch none 0.5)
		(connect_pads
			(clearance 0)
		)
		(min_thickness 0.25)
		(keepout
			(tracks not_allowed)
			(vias allowed)
			(pads allowed)
			(copperpour not_allowed)
			(footprints allowed)
		)
		(placement
			(enabled no)
			(sheetname "")
		)
		(fill yes
			(thermal_gap 0.5)
			(thermal_bridge_width 0.5)
			(island_removal_mode 0)
		)
		(polygon
			(pts
				(arc
					(start 335.595976 -229.904036)
					(mid 334.966056 -229.904036)
					(end 335.595976 -229.904036)
				)
			)
		)
	)
	(zone
		(layers "B.Cu" "In15.Cu")
		(hatch none 0.5)
		(connect_pads
			(clearance 0)
		)
		(min_thickness 0.25)
		(keepout
			(tracks not_allowed)
			(vias allowed)
			(pads allowed)
			(copperpour not_allowed)
			(footprints allowed)
		)
		(placement
			(enabled no)
			(sheetname "")
		)
		(fill yes
			(thermal_gap 0.5)
			(thermal_bridge_width 0.5)
			(island_removal_mode 0)
		)
		(polygon
			(pts
				(arc
					(start 337.476084 -247.724168)
					(mid 336.846164 -247.724168)
					(end 337.476084 -247.724168)
				)
			)
		)
	)
	(zone
		(layers "B.Cu" "In15.Cu")
		(hatch none 0.5)
		(connect_pads
			(clearance 0)
		)
		(min_thickness 0.25)
		(keepout
			(tracks not_allowed)
			(vias allowed)
			(pads allowed)
			(copperpour not_allowed)
			(footprints allowed)
		)
		(placement
			(enabled no)
			(sheetname "")
		)
		(fill yes
			(thermal_gap 0.5)
			(thermal_bridge_width 0.5)
			(island_removal_mode 0)
		)
		(polygon
			(pts
				(arc
					(start 300.15815 -220.285056)
					(mid 299.49013 -220.285056)
					(end 300.15815 -220.285056)
				)
			)
		)
	)
	(zone
		(layers "B.Cu" "In15.Cu")
		(hatch none 0.5)
		(connect_pads
			(clearance 0)
		)
		(min_thickness 0.25)
		(keepout
			(tracks not_allowed)
			(vias allowed)
			(pads allowed)
			(copperpour not_allowed)
			(footprints allowed)
		)
		(placement
			(enabled no)
			(sheetname "")
		)
		(fill yes
			(thermal_gap 0.5)
			(thermal_bridge_width 0.5)
			(island_removal_mode 0)
		)
		(polygon
			(pts
				(arc
					(start 52.218082 -270.435324)
					(mid 51.550062 -270.435324)
					(end 52.218082 -270.435324)
				)
			)
		)
	)
	(zone
		(layers "B.Cu" "In15.Cu")
		(hatch none 0.5)
		(connect_pads
			(clearance 0)
		)
		(min_thickness 0.25)
		(keepout
			(tracks not_allowed)
			(vias allowed)
			(pads allowed)
			(copperpour not_allowed)
			(footprints allowed)
		)
		(placement
			(enabled no)
			(sheetname "")
		)
		(fill yes
			(thermal_gap 0.5)
			(thermal_bridge_width 0.5)
			(island_removal_mode 0)
		)
		(polygon
			(pts
				(arc
					(start 347.478096 -401.674838)
					(mid 346.810076 -401.674838)
					(end 347.478096 -401.674838)
				)
			)
		)
	)
	(zone
		(layers "B.Cu" "In15.Cu")
		(hatch none 0.5)
		(connect_pads
			(clearance 0)
		)
		(min_thickness 0.25)
		(keepout
			(tracks not_allowed)
			(vias allowed)
			(pads allowed)
			(copperpour not_allowed)
			(footprints allowed)
		)
		(placement
			(enabled no)
			(sheetname "")
		)
		(fill yes
			(thermal_gap 0.5)
			(thermal_bridge_width 0.5)
			(island_removal_mode 0)
		)
		(polygon
			(pts
				(arc
					(start 88.426036 -282.18638)
					(mid 87.796116 -282.18638)
					(end 88.426036 -282.18638)
				)
			)
		)
	)
	(zone
		(layers "B.Cu" "In15.Cu")
		(hatch none 0.5)
		(connect_pads
			(clearance 0)
		)
		(min_thickness 0.25)
		(keepout
			(tracks not_allowed)
			(vias allowed)
			(pads allowed)
			(copperpour not_allowed)
			(footprints allowed)
		)
		(placement
			(enabled no)
			(sheetname "")
		)
		(fill yes
			(thermal_gap 0.5)
			(thermal_bridge_width 0.5)
			(island_removal_mode 0)
		)
		(polygon
			(pts
				(arc
					(start 134.649718 -236.384338)
					(mid 134.019798 -236.384338)
					(end 134.649718 -236.384338)
				)
			)
		)
	)
	(zone
		(layers "B.Cu" "In15.Cu")
		(hatch none 0.5)
		(connect_pads
			(clearance 0)
		)
		(min_thickness 0.25)
		(keepout
			(tracks not_allowed)
			(vias allowed)
			(pads allowed)
			(copperpour not_allowed)
			(footprints allowed)
		)
		(placement
			(enabled no)
			(sheetname "")
		)
		(fill yes
			(thermal_gap 0.5)
			(thermal_bridge_width 0.5)
			(island_removal_mode 0)
		)
		(polygon
			(pts
				(arc
					(start 89.536016 -239.624362)
					(mid 88.906096 -239.624362)
					(end 89.536016 -239.624362)
				)
			)
		)
	)
	(zone
		(layers "B.Cu" "In15.Cu")
		(hatch none 0.5)
		(connect_pads
			(clearance 0)
		)
		(min_thickness 0.25)
		(keepout
			(tracks not_allowed)
			(vias allowed)
			(pads allowed)
			(copperpour not_allowed)
			(footprints allowed)
		)
		(placement
			(enabled no)
			(sheetname "")
		)
		(fill yes
			(thermal_gap 0.5)
			(thermal_bridge_width 0.5)
			(island_removal_mode 0)
		)
		(polygon
			(pts
				(arc
					(start 104.876092 -271.656302)
					(mid 104.246172 -271.656302)
					(end 104.876092 -271.656302)
				)
			)
		)
	)
	(zone
		(layers "B.Cu" "In15.Cu")
		(hatch none 0.5)
		(connect_pads
			(clearance 0)
		)
		(min_thickness 0.25)
		(keepout
			(tracks not_allowed)
			(vias allowed)
			(pads allowed)
			(copperpour not_allowed)
			(footprints allowed)
		)
		(placement
			(enabled no)
			(sheetname "")
		)
		(fill yes
			(thermal_gap 0.5)
			(thermal_bridge_width 0.5)
			(island_removal_mode 0)
		)
		(polygon
			(pts
				(arc
					(start 337.476084 -249.34418)
					(mid 336.846164 -249.34418)
					(end 337.476084 -249.34418)
				)
			)
		)
	)
	(zone
		(layers "B.Cu" "In15.Cu")
		(hatch none 0.5)
		(connect_pads
			(clearance 0)
		)
		(min_thickness 0.25)
		(keepout
			(tracks not_allowed)
			(vias allowed)
			(pads allowed)
			(copperpour not_allowed)
			(footprints allowed)
		)
		(placement
			(enabled no)
			(sheetname "")
		)
		(fill yes
			(thermal_gap 0.5)
			(thermal_bridge_width 0.5)
			(island_removal_mode 0)
		)
		(polygon
			(pts
				(arc
					(start 384.299714 -288.66592)
					(mid 383.669794 -288.66592)
					(end 384.299714 -288.66592)
				)
			)
		)
	)
	(zone
		(layers "B.Cu" "In15.Cu")
		(hatch none 0.5)
		(connect_pads
			(clearance 0)
		)
		(min_thickness 0.25)
		(keepout
			(tracks not_allowed)
			(vias allowed)
			(pads allowed)
			(copperpour not_allowed)
			(footprints allowed)
		)
		(placement
			(enabled no)
			(sheetname "")
		)
		(fill yes
			(thermal_gap 0.5)
			(thermal_bridge_width 0.5)
			(island_removal_mode 0)
		)
		(polygon
			(pts
				(arc
					(start 48.118014 -229.635304)
					(mid 47.449994 -229.635304)
					(end 48.118014 -229.635304)
				)
			)
		)
	)
	(zone
		(layers "B.Cu" "In15.Cu")
		(hatch none 0.5)
		(connect_pads
			(clearance 0)
		)
		(min_thickness 0.25)
		(keepout
			(tracks not_allowed)
			(vias allowed)
			(pads allowed)
			(copperpour not_allowed)
			(footprints allowed)
		)
		(placement
			(enabled no)
			(sheetname "")
		)
		(fill yes
			(thermal_gap 0.5)
			(thermal_bridge_width 0.5)
			(island_removal_mode 0)
		)
		(polygon
			(pts
				(arc
					(start 135.419592 -280.566368)
					(mid 134.789672 -280.566368)
					(end 135.419592 -280.566368)
				)
			)
		)
	)
	(zone
		(layers "B.Cu" "In15.Cu")
		(hatch none 0.5)
		(connect_pads
			(clearance 0)
		)
		(min_thickness 0.25)
		(keepout
			(tracks not_allowed)
			(vias allowed)
			(pads allowed)
			(copperpour not_allowed)
			(footprints allowed)
		)
		(placement
			(enabled no)
			(sheetname "")
		)
		(fill yes
			(thermal_gap 0.5)
			(thermal_bridge_width 0.5)
			(island_removal_mode 0)
		)
		(polygon
			(pts
				(arc
					(start 176.406048 -289.135312)
					(mid 175.738028 -289.135312)
					(end 176.406048 -289.135312)
				)
			)
		)
	)
	(zone
		(layers "B.Cu" "In15.Cu")
		(hatch none 0.5)
		(connect_pads
			(clearance 0)
		)
		(min_thickness 0.25)
		(keepout
			(tracks not_allowed)
			(vias allowed)
			(pads allowed)
			(copperpour not_allowed)
			(footprints allowed)
		)
		(placement
			(enabled no)
			(sheetname "")
		)
		(fill yes
			(thermal_gap 0.5)
			(thermal_bridge_width 0.5)
			(island_removal_mode 0)
		)
		(polygon
			(pts
				(arc
					(start 89.36609 -278.946356)
					(mid 88.73617 -278.946356)
					(end 89.36609 -278.946356)
				)
			)
		)
	)
	(zone
		(layers "B.Cu" "In15.Cu")
		(hatch none 0.5)
		(connect_pads
			(clearance 0)
		)
		(min_thickness 0.25)
		(keepout
			(tracks not_allowed)
			(vias allowed)
			(pads allowed)
			(copperpour not_allowed)
			(footprints allowed)
		)
		(placement
			(enabled no)
			(sheetname "")
		)
		(fill yes
			(thermal_gap 0.5)
			(thermal_bridge_width 0.5)
			(island_removal_mode 0)
		)
		(polygon
			(pts
				(arc
					(start 155.753054 -373.96293)
					(mid 155.085034 -373.96293)
					(end 155.753054 -373.96293)
				)
			)
		)
	)
	(zone
		(layers "B.Cu" "In15.Cu")
		(hatch none 0.5)
		(connect_pads
			(clearance 0)
		)
		(min_thickness 0.25)
		(keepout
			(tracks not_allowed)
			(vias allowed)
			(pads allowed)
			(copperpour not_allowed)
			(footprints allowed)
		)
		(placement
			(enabled no)
			(sheetname "")
		)
		(fill yes
			(thermal_gap 0.5)
			(thermal_bridge_width 0.5)
			(island_removal_mode 0)
		)
		(polygon
			(pts
				(arc
					(start 88.126062 -251.774452)
					(mid 87.496142 -251.774452)
					(end 88.126062 -251.774452)
				)
			)
		)
	)
	(zone
		(layers "B.Cu" "In15.Cu")
		(hatch none 0.5)
		(connect_pads
			(clearance 0)
		)
		(min_thickness 0.25)
		(keepout
			(tracks not_allowed)
			(vias allowed)
			(pads allowed)
			(copperpour not_allowed)
			(footprints allowed)
		)
		(placement
			(enabled no)
			(sheetname "")
		)
		(fill yes
			(thermal_gap 0.5)
			(thermal_bridge_width 0.5)
			(island_removal_mode 0)
		)
		(polygon
			(pts
				(arc
					(start 69.036946 -434.289962)
					(mid 68.262754 -434.289962)
					(end 69.036946 -434.289962)
				)
			)
		)
	)
	(zone
		(layers "B.Cu" "In15.Cu")
		(hatch none 0.5)
		(connect_pads
			(clearance 0)
		)
		(min_thickness 0.25)
		(keepout
			(tracks not_allowed)
			(vias allowed)
			(pads allowed)
			(copperpour not_allowed)
			(footprints allowed)
		)
		(placement
			(enabled no)
			(sheetname "")
		)
		(fill yes
			(thermal_gap 0.5)
			(thermal_bridge_width 0.5)
			(island_removal_mode 0)
		)
		(polygon
			(pts
				(arc
					(start 89.83599 -286.23641)
					(mid 89.20607 -286.23641)
					(end 89.83599 -286.23641)
				)
			)
		)
	)
	(zone
		(layers "B.Cu" "In15.Cu")
		(hatch none 0.5)
		(connect_pads
			(clearance 0)
		)
		(min_thickness 0.25)
		(keepout
			(tracks not_allowed)
			(vias allowed)
			(pads allowed)
			(copperpour not_allowed)
			(footprints allowed)
		)
		(placement
			(enabled no)
			(sheetname "")
		)
		(fill yes
			(thermal_gap 0.5)
			(thermal_bridge_width 0.5)
			(island_removal_mode 0)
		)
		(polygon
			(pts
				(arc
					(start 176.406048 -275.53539)
					(mid 175.738028 -275.53539)
					(end 176.406048 -275.53539)
				)
			)
		)
	)
	(zone
		(layers "B.Cu" "In15.Cu")
		(hatch none 0.5)
		(connect_pads
			(clearance 0)
		)
		(min_thickness 0.25)
		(keepout
			(tracks not_allowed)
			(vias allowed)
			(pads allowed)
			(copperpour not_allowed)
			(footprints allowed)
		)
		(placement
			(enabled no)
			(sheetname "")
		)
		(fill yes
			(thermal_gap 0.5)
			(thermal_bridge_width 0.5)
			(island_removal_mode 0)
		)
		(polygon
			(pts
				(arc
					(start 300.15815 -204.985112)
					(mid 299.49013 -204.985112)
					(end 300.15815 -204.985112)
				)
			)
		)
	)
	(zone
		(layers "B.Cu" "In15.Cu")
		(hatch none 0.5)
		(connect_pads
			(clearance 0)
		)
		(min_thickness 0.25)
		(keepout
			(tracks not_allowed)
			(vias allowed)
			(pads allowed)
			(copperpour not_allowed)
			(footprints allowed)
		)
		(placement
			(enabled no)
			(sheetname "")
		)
		(fill yes
			(thermal_gap 0.5)
			(thermal_bridge_width 0.5)
			(island_removal_mode 0)
		)
		(polygon
			(pts
				(arc
					(start 296.058082 -293.384986)
					(mid 295.390062 -293.384986)
					(end 296.058082 -293.384986)
				)
			)
		)
	)
	(zone
		(layers "B.Cu" "In15.Cu")
		(hatch none 0.5)
		(connect_pads
			(clearance 0)
		)
		(min_thickness 0.25)
		(keepout
			(tracks not_allowed)
			(vias allowed)
			(pads allowed)
			(copperpour not_allowed)
			(footprints allowed)
		)
		(placement
			(enabled no)
			(sheetname "")
		)
		(fill yes
			(thermal_gap 0.5)
			(thermal_bridge_width 0.5)
			(island_removal_mode 0)
		)
		(polygon
			(pts
				(arc
					(start 89.066116 -250.15444)
					(mid 88.436196 -250.15444)
					(end 89.066116 -250.15444)
				)
			)
		)
	)
	(zone
		(layers "B.Cu" "In15.Cu")
		(hatch none 0.5)
		(connect_pads
			(clearance 0)
		)
		(min_thickness 0.25)
		(keepout
			(tracks not_allowed)
			(vias allowed)
			(pads allowed)
			(copperpour not_allowed)
			(footprints allowed)
		)
		(placement
			(enabled no)
			(sheetname "")
		)
		(fill yes
			(thermal_gap 0.5)
			(thermal_bridge_width 0.5)
			(island_removal_mode 0)
		)
		(polygon
			(pts
				(arc
					(start 384.299714 -270.846042)
					(mid 383.669794 -270.846042)
					(end 384.299714 -270.846042)
				)
			)
		)
	)
	(zone
		(layers "B.Cu" "In15.Cu")
		(hatch none 0.5)
		(connect_pads
			(clearance 0)
		)
		(min_thickness 0.25)
		(keepout
			(tracks not_allowed)
			(vias allowed)
			(pads allowed)
			(copperpour not_allowed)
			(footprints allowed)
		)
		(placement
			(enabled no)
			(sheetname "")
		)
		(fill yes
			(thermal_gap 0.5)
			(thermal_bridge_width 0.5)
			(island_removal_mode 0)
		)
		(polygon
			(pts
				(arc
					(start 390.136888 -433.289964)
					(mid 389.362696 -433.289964)
					(end 390.136888 -433.289964)
				)
			)
		)
	)
	(zone
		(layers "B.Cu" "In15.Cu")
		(hatch none 0.5)
		(connect_pads
			(clearance 0)
		)
		(min_thickness 0.25)
		(keepout
			(tracks not_allowed)
			(vias allowed)
			(pads allowed)
			(copperpour not_allowed)
			(footprints allowed)
		)
		(placement
			(enabled no)
			(sheetname "")
		)
		(fill yes
			(thermal_gap 0.5)
			(thermal_bridge_width 0.5)
			(island_removal_mode 0)
		)
		(polygon
			(pts
				(arc
					(start 382.88976 -284.616144)
					(mid 382.25984 -284.616144)
					(end 382.88976 -284.616144)
				)
			)
		)
	)
	(zone
		(layers "B.Cu" "In15.Cu")
		(hatch none 0.5)
		(connect_pads
			(clearance 0)
		)
		(min_thickness 0.25)
		(keepout
			(tracks not_allowed)
			(vias allowed)
			(pads allowed)
			(copperpour not_allowed)
			(footprints allowed)
		)
		(placement
			(enabled no)
			(sheetname "")
		)
		(fill yes
			(thermal_gap 0.5)
			(thermal_bridge_width 0.5)
			(island_removal_mode 0)
		)
		(polygon
			(pts
				(arc
					(start 117.650514 -393.292838)
					(mid 116.982494 -393.292838)
					(end 117.650514 -393.292838)
				)
			)
		)
	)
	(zone
		(layers "B.Cu" "In15.Cu")
		(hatch none 0.5)
		(connect_pads
			(clearance 0)
		)
		(min_thickness 0.25)
		(keepout
			(tracks not_allowed)
			(vias allowed)
			(pads allowed)
			(copperpour not_allowed)
			(footprints allowed)
		)
		(placement
			(enabled no)
			(sheetname "")
		)
		(fill yes
			(thermal_gap 0.5)
			(thermal_bridge_width 0.5)
			(island_removal_mode 0)
		)
		(polygon
			(pts
				(arc
					(start 296.058082 -272.984976)
					(mid 295.390062 -272.984976)
					(end 296.058082 -272.984976)
				)
			)
		)
	)
	(zone
		(layers "B.Cu" "In15.Cu")
		(hatch none 0.5)
		(connect_pads
			(clearance 0)
		)
		(min_thickness 0.25)
		(keepout
			(tracks not_allowed)
			(vias allowed)
			(pads allowed)
			(copperpour not_allowed)
			(footprints allowed)
		)
		(placement
			(enabled no)
			(sheetname "")
		)
		(fill yes
			(thermal_gap 0.5)
			(thermal_bridge_width 0.5)
			(island_removal_mode 0)
		)
		(polygon
			(pts
				(arc
					(start 383.059686 -255.014222)
					(mid 382.429766 -255.014222)
					(end 383.059686 -255.014222)
				)
			)
		)
	)
	(zone
		(layers "B.Cu" "In15.Cu")
		(hatch none 0.5)
		(connect_pads
			(clearance 0)
		)
		(min_thickness 0.25)
		(keepout
			(tracks not_allowed)
			(vias allowed)
			(pads allowed)
			(copperpour not_allowed)
			(footprints allowed)
		)
		(placement
			(enabled no)
			(sheetname "")
		)
		(fill yes
			(thermal_gap 0.5)
			(thermal_bridge_width 0.5)
			(island_removal_mode 0)
		)
		(polygon
			(pts
				(arc
					(start 352.277934 -401.674838)
					(mid 351.609914 -401.674838)
					(end 352.277934 -401.674838)
				)
			)
		)
	)
	(zone
		(layers "B.Cu" "In15.Cu")
		(hatch none 0.5)
		(connect_pads
			(clearance 0)
		)
		(min_thickness 0.25)
		(keepout
			(tracks not_allowed)
			(vias allowed)
			(pads allowed)
			(copperpour not_allowed)
			(footprints allowed)
		)
		(placement
			(enabled no)
			(sheetname "")
		)
		(fill yes
			(thermal_gap 0.5)
			(thermal_bridge_width 0.5)
			(island_removal_mode 0)
		)
		(polygon
			(pts
				(arc
					(start 420.246048 -216.885012)
					(mid 419.578028 -216.885012)
					(end 420.246048 -216.885012)
				)
			)
		)
	)
	(zone
		(layers "B.Cu" "In15.Cu")
		(hatch none 0.5)
		(connect_pads
			(clearance 0)
		)
		(min_thickness 0.25)
		(keepout
			(tracks not_allowed)
			(vias allowed)
			(pads allowed)
			(copperpour not_allowed)
			(footprints allowed)
		)
		(placement
			(enabled no)
			(sheetname "")
		)
		(fill yes
			(thermal_gap 0.5)
			(thermal_bridge_width 0.5)
			(island_removal_mode 0)
		)
		(polygon
			(pts
				(arc
					(start 136.529826 -238.00435)
					(mid 135.899906 -238.00435)
					(end 136.529826 -238.00435)
				)
			)
		)
	)
	(zone
		(layers "B.Cu" "In15.Cu")
		(hatch none 0.5)
		(connect_pads
			(clearance 0)
		)
		(min_thickness 0.25)
		(keepout
			(tracks not_allowed)
			(vias allowed)
			(pads allowed)
			(copperpour not_allowed)
			(footprints allowed)
		)
		(placement
			(enabled no)
			(sheetname "")
		)
		(fill yes
			(thermal_gap 0.5)
			(thermal_bridge_width 0.5)
			(island_removal_mode 0)
		)
		(polygon
			(pts
				(arc
					(start 392.136884 -434.289962)
					(mid 391.362692 -434.289962)
					(end 392.136884 -434.289962)
				)
			)
		)
	)
	(zone
		(layers "B.Cu" "In15.Cu")
		(hatch none 0.5)
		(connect_pads
			(clearance 0)
		)
		(min_thickness 0.25)
		(keepout
			(tracks not_allowed)
			(vias allowed)
			(pads allowed)
			(copperpour not_allowed)
			(footprints allowed)
		)
		(placement
			(enabled no)
			(sheetname "")
		)
		(fill yes
			(thermal_gap 0.5)
			(thermal_bridge_width 0.5)
			(island_removal_mode 0)
		)
		(polygon
			(pts
				(arc
					(start 384.469894 -252.584204)
					(mid 383.839974 -252.584204)
					(end 384.469894 -252.584204)
				)
			)
		)
	)
	(zone
		(layers "B.Cu" "In15.Cu")
		(hatch none 0.5)
		(connect_pads
			(clearance 0)
		)
		(min_thickness 0.25)
		(keepout
			(tracks not_allowed)
			(vias allowed)
			(pads allowed)
			(copperpour not_allowed)
			(footprints allowed)
		)
		(placement
			(enabled no)
			(sheetname "")
		)
		(fill yes
			(thermal_gap 0.5)
			(thermal_bridge_width 0.5)
			(island_removal_mode 0)
		)
		(polygon
			(pts
				(arc
					(start 417.69665 -382.34493)
					(mid 417.02863 -382.34493)
					(end 417.69665 -382.34493)
				)
			)
		)
	)
	(zone
		(layers "B.Cu" "In15.Cu")
		(hatch none 0.5)
		(connect_pads
			(clearance 0)
		)
		(min_thickness 0.25)
		(keepout
			(tracks not_allowed)
			(vias allowed)
			(pads allowed)
			(copperpour not_allowed)
			(footprints allowed)
		)
		(placement
			(enabled no)
			(sheetname "")
		)
		(fill yes
			(thermal_gap 0.5)
			(thermal_bridge_width 0.5)
			(island_removal_mode 0)
		)
		(polygon
			(pts
				(arc
					(start 382.589786 -254.204216)
					(mid 381.959866 -254.204216)
					(end 382.589786 -254.204216)
				)
			)
		)
	)
	(zone
		(layers "B.Cu" "In15.Cu")
		(hatch none 0.5)
		(connect_pads
			(clearance 0)
		)
		(min_thickness 0.25)
		(keepout
			(tracks not_allowed)
			(vias allowed)
			(pads allowed)
			(copperpour not_allowed)
			(footprints allowed)
		)
		(placement
			(enabled no)
			(sheetname "")
		)
		(fill yes
			(thermal_gap 0.5)
			(thermal_bridge_width 0.5)
			(island_removal_mode 0)
		)
		(polygon
			(pts
				(arc
					(start 136.8298 -271.656302)
					(mid 136.19988 -271.656302)
					(end 136.8298 -271.656302)
				)
			)
		)
	)
	(zone
		(layers "B.Cu" "In15.Cu")
		(hatch none 0.5)
		(connect_pads
			(clearance 0)
		)
		(min_thickness 0.25)
		(keepout
			(tracks not_allowed)
			(vias allowed)
			(pads allowed)
			(copperpour not_allowed)
			(footprints allowed)
		)
		(placement
			(enabled no)
			(sheetname "")
		)
		(fill yes
			(thermal_gap 0.5)
			(thermal_bridge_width 0.5)
			(island_removal_mode 0)
		)
		(polygon
			(pts
				(arc
					(start 424.346116 -304.435002)
					(mid 423.678096 -304.435002)
					(end 424.346116 -304.435002)
				)
			)
		)
	)
	(zone
		(layers "B.Cu" "In15.Cu")
		(hatch none 0.5)
		(connect_pads
			(clearance 0)
		)
		(min_thickness 0.25)
		(keepout
			(tracks not_allowed)
			(vias allowed)
			(pads allowed)
			(copperpour not_allowed)
			(footprints allowed)
		)
		(placement
			(enabled no)
			(sheetname "")
		)
		(fill yes
			(thermal_gap 0.5)
			(thermal_bridge_width 0.5)
			(island_removal_mode 0)
		)
		(polygon
			(pts
				(arc
					(start 368.789712 -270.036036)
					(mid 368.159792 -270.036036)
					(end 368.789712 -270.036036)
				)
			)
		)
	)
	(zone
		(layers "B.Cu" "In15.Cu")
		(hatch none 0.5)
		(connect_pads
			(clearance 0)
		)
		(min_thickness 0.25)
		(keepout
			(tracks not_allowed)
			(vias allowed)
			(pads allowed)
			(copperpour not_allowed)
			(footprints allowed)
		)
		(placement
			(enabled no)
			(sheetname "")
		)
		(fill yes
			(thermal_gap 0.5)
			(thermal_bridge_width 0.5)
			(island_removal_mode 0)
		)
		(polygon
			(pts
				(arc
					(start 89.066116 -232.334308)
					(mid 88.436196 -232.334308)
					(end 89.066116 -232.334308)
				)
			)
		)
	)
	(zone
		(layers "B.Cu" "In15.Cu")
		(hatch none 0.5)
		(connect_pads
			(clearance 0)
		)
		(min_thickness 0.25)
		(keepout
			(tracks not_allowed)
			(vias allowed)
			(pads allowed)
			(copperpour not_allowed)
			(footprints allowed)
		)
		(placement
			(enabled no)
			(sheetname "")
		)
		(fill yes
			(thermal_gap 0.5)
			(thermal_bridge_width 0.5)
			(island_removal_mode 0)
		)
		(polygon
			(pts
				(arc
					(start 55.306214 -385.31038)
					(mid 54.676294 -385.31038)
					(end 55.306214 -385.31038)
				)
			)
		)
	)
	(zone
		(layers "B.Cu" "In15.Cu")
		(hatch none 0.5)
		(connect_pads
			(clearance 0)
		)
		(min_thickness 0.25)
		(keepout
			(tracks not_allowed)
			(vias allowed)
			(pads allowed)
			(copperpour not_allowed)
			(footprints allowed)
		)
		(placement
			(enabled no)
			(sheetname "")
		)
		(fill yes
			(thermal_gap 0.5)
			(thermal_bridge_width 0.5)
			(island_removal_mode 0)
		)
		(polygon
			(pts
				(arc
					(start 300.15815 -245.785132)
					(mid 299.49013 -245.785132)
					(end 300.15815 -245.785132)
				)
			)
		)
	)
	(zone
		(layers "B.Cu" "In15.Cu")
		(hatch none 0.5)
		(connect_pads
			(clearance 0)
		)
		(min_thickness 0.25)
		(keepout
			(tracks not_allowed)
			(vias allowed)
			(pads allowed)
			(copperpour not_allowed)
			(footprints allowed)
		)
		(placement
			(enabled no)
			(sheetname "")
		)
		(fill yes
			(thermal_gap 0.5)
			(thermal_bridge_width 0.5)
			(island_removal_mode 0)
		)
		(polygon
			(pts
				(arc
					(start 123.669806 -270.03629)
					(mid 123.039886 -270.03629)
					(end 123.669806 -270.03629)
				)
			)
		)
	)
	(zone
		(layers "B.Cu" "In15.Cu")
		(hatch none 0.5)
		(connect_pads
			(clearance 0)
		)
		(min_thickness 0.25)
		(keepout
			(tracks not_allowed)
			(vias allowed)
			(pads allowed)
			(copperpour not_allowed)
			(footprints allowed)
		)
		(placement
			(enabled no)
			(sheetname "")
		)
		(fill yes
			(thermal_gap 0.5)
			(thermal_bridge_width 0.5)
			(island_removal_mode 0)
		)
		(polygon
			(pts
				(arc
					(start 87.955882 -266.796266)
					(mid 87.325962 -266.796266)
					(end 87.955882 -266.796266)
				)
			)
		)
	)
	(zone
		(layers "B.Cu" "In15.Cu")
		(hatch none 0.5)
		(connect_pads
			(clearance 0)
		)
		(min_thickness 0.25)
		(keepout
			(tracks not_allowed)
			(vias allowed)
			(pads allowed)
			(copperpour not_allowed)
			(footprints allowed)
		)
		(placement
			(enabled no)
			(sheetname "")
		)
		(fill yes
			(thermal_gap 0.5)
			(thermal_bridge_width 0.5)
			(island_removal_mode 0)
		)
		(polygon
			(pts
				(arc
					(start 349.878142 -401.674838)
					(mid 349.210122 -401.674838)
					(end 349.878142 -401.674838)
				)
			)
		)
	)
	(zone
		(layers "B.Cu" "In15.Cu")
		(hatch none 0.5)
		(connect_pads
			(clearance 0)
		)
		(min_thickness 0.25)
		(keepout
			(tracks not_allowed)
			(vias allowed)
			(pads allowed)
			(copperpour not_allowed)
			(footprints allowed)
		)
		(placement
			(enabled no)
			(sheetname "")
		)
		(fill yes
			(thermal_gap 0.5)
			(thermal_bridge_width 0.5)
			(island_removal_mode 0)
		)
		(polygon
			(pts
				(arc
					(start 296.058082 -202.434952)
					(mid 295.390062 -202.434952)
					(end 296.058082 -202.434952)
				)
			)
		)
	)
	(zone
		(layers "B.Cu" "In15.Cu")
		(hatch none 0.5)
		(connect_pads
			(clearance 0)
		)
		(min_thickness 0.25)
		(keepout
			(tracks not_allowed)
			(vias allowed)
			(pads allowed)
			(copperpour not_allowed)
			(footprints allowed)
		)
		(placement
			(enabled no)
			(sheetname "")
		)
		(fill yes
			(thermal_gap 0.5)
			(thermal_bridge_width 0.5)
			(island_removal_mode 0)
		)
		(polygon
			(pts
				(arc
					(start 121.250456 -393.292838)
					(mid 120.582436 -393.292838)
					(end 121.250456 -393.292838)
				)
			)
		)
	)
	(zone
		(layers "B.Cu" "In15.Cu")
		(hatch none 0.5)
		(connect_pads
			(clearance 0)
		)
		(min_thickness 0.25)
		(keepout
			(tracks not_allowed)
			(vias allowed)
			(pads allowed)
			(copperpour not_allowed)
			(footprints allowed)
		)
		(placement
			(enabled no)
			(sheetname "")
		)
		(fill yes
			(thermal_gap 0.5)
			(thermal_bridge_width 0.5)
			(island_removal_mode 0)
		)
		(polygon
			(pts
				(arc
					(start 424.346116 -283.185108)
					(mid 423.678096 -283.185108)
					(end 424.346116 -283.185108)
				)
			)
		)
	)
	(zone
		(layers "B.Cu" "In15.Cu")
		(hatch none 0.5)
		(connect_pads
			(clearance 0)
		)
		(min_thickness 0.25)
		(keepout
			(tracks not_allowed)
			(vias allowed)
			(pads allowed)
			(copperpour not_allowed)
			(footprints allowed)
		)
		(placement
			(enabled no)
			(sheetname "")
		)
		(fill yes
			(thermal_gap 0.5)
			(thermal_bridge_width 0.5)
			(island_removal_mode 0)
		)
		(polygon
			(pts
				(arc
					(start 119.609616 -239.624362)
					(mid 118.979696 -239.624362)
					(end 119.609616 -239.624362)
				)
			)
		)
	)
	(zone
		(layers "B.Cu" "In15.Cu")
		(hatch none 0.5)
		(connect_pads
			(clearance 0)
		)
		(min_thickness 0.25)
		(keepout
			(tracks not_allowed)
			(vias allowed)
			(pads allowed)
			(copperpour not_allowed)
			(footprints allowed)
		)
		(placement
			(enabled no)
			(sheetname "")
		)
		(fill yes
			(thermal_gap 0.5)
			(thermal_bridge_width 0.5)
			(island_removal_mode 0)
		)
		(polygon
			(pts
				(arc
					(start 103.936038 -271.656302)
					(mid 103.306118 -271.656302)
					(end 103.936038 -271.656302)
				)
			)
		)
	)
	(zone
		(layers "B.Cu" "In15.Cu")
		(hatch none 0.5)
		(connect_pads
			(clearance 0)
		)
		(min_thickness 0.25)
		(keepout
			(tracks not_allowed)
			(vias allowed)
			(pads allowed)
			(copperpour not_allowed)
			(footprints allowed)
		)
		(placement
			(enabled no)
			(sheetname "")
		)
		(fill yes
			(thermal_gap 0.5)
			(thermal_bridge_width 0.5)
			(island_removal_mode 0)
		)
		(polygon
			(pts
				(arc
					(start 384.469894 -226.664266)
					(mid 383.839974 -226.664266)
					(end 384.469894 -226.664266)
				)
			)
		)
	)
	(zone
		(layers "B.Cu" "In15.Cu")
		(hatch none 0.5)
		(connect_pads
			(clearance 0)
		)
		(min_thickness 0.25)
		(keepout
			(tracks not_allowed)
			(vias allowed)
			(pads allowed)
			(copperpour not_allowed)
			(footprints allowed)
		)
		(placement
			(enabled no)
			(sheetname "")
		)
		(fill yes
			(thermal_gap 0.5)
			(thermal_bridge_width 0.5)
			(island_removal_mode 0)
		)
		(polygon
			(pts
				(arc
					(start 420.246048 -288.285174)
					(mid 419.578028 -288.285174)
					(end 420.246048 -288.285174)
				)
			)
		)
	)
	(zone
		(layers "B.Cu" "In15.Cu")
		(hatch none 0.5)
		(connect_pads
			(clearance 0)
		)
		(min_thickness 0.25)
		(keepout
			(tracks not_allowed)
			(vias allowed)
			(pads allowed)
			(copperpour not_allowed)
			(footprints allowed)
		)
		(placement
			(enabled no)
			(sheetname "")
		)
		(fill yes
			(thermal_gap 0.5)
			(thermal_bridge_width 0.5)
			(island_removal_mode 0)
		)
		(polygon
			(pts
				(arc
					(start 300.15815 -279.785064)
					(mid 299.49013 -279.785064)
					(end 300.15815 -279.785064)
				)
			)
		)
	)
	(zone
		(layers "B.Cu" "In15.Cu")
		(hatch none 0.5)
		(connect_pads
			(clearance 0)
		)
		(min_thickness 0.25)
		(keepout
			(tracks not_allowed)
			(vias allowed)
			(pads allowed)
			(copperpour not_allowed)
			(footprints allowed)
		)
		(placement
			(enabled no)
			(sheetname "")
		)
		(fill yes
			(thermal_gap 0.5)
			(thermal_bridge_width 0.5)
			(island_removal_mode 0)
		)
		(polygon
			(pts
				(arc
					(start 145.137124 -434.289962)
					(mid 144.362932 -434.289962)
					(end 145.137124 -434.289962)
				)
			)
		)
	)
	(zone
		(layers "B.Cu" "In15.Cu")
		(hatch none 0.5)
		(connect_pads
			(clearance 0)
		)
		(min_thickness 0.25)
		(keepout
			(tracks not_allowed)
			(vias allowed)
			(pads allowed)
			(copperpour not_allowed)
			(footprints allowed)
		)
		(placement
			(enabled no)
			(sheetname "")
		)
		(fill yes
			(thermal_gap 0.5)
			(thermal_bridge_width 0.5)
			(island_removal_mode 0)
		)
		(polygon
			(pts
				(arc
					(start 89.36609 -282.18638)
					(mid 88.73617 -282.18638)
					(end 89.36609 -282.18638)
				)
			)
		)
	)
	(zone
		(layers "B.Cu" "In15.Cu")
		(hatch none 0.5)
		(connect_pads
			(clearance 0)
		)
		(min_thickness 0.25)
		(keepout
			(tracks not_allowed)
			(vias allowed)
			(pads allowed)
			(copperpour not_allowed)
			(footprints allowed)
		)
		(placement
			(enabled no)
			(sheetname "")
		)
		(fill yes
			(thermal_gap 0.5)
			(thermal_bridge_width 0.5)
			(island_removal_mode 0)
		)
		(polygon
			(pts
				(arc
					(start 134.649718 -246.10441)
					(mid 134.019798 -246.10441)
					(end 134.649718 -246.10441)
				)
			)
		)
	)
	(zone
		(layers "B.Cu" "In15.Cu")
		(hatch none 0.5)
		(connect_pads
			(clearance 0)
		)
		(min_thickness 0.25)
		(keepout
			(tracks not_allowed)
			(vias allowed)
			(pads allowed)
			(copperpour not_allowed)
			(footprints allowed)
		)
		(placement
			(enabled no)
			(sheetname "")
		)
		(fill yes
			(thermal_gap 0.5)
			(thermal_bridge_width 0.5)
			(island_removal_mode 0)
		)
		(polygon
			(pts
				(arc
					(start 337.776058 -292.71595)
					(mid 337.146138 -292.71595)
					(end 337.776058 -292.71595)
				)
			)
		)
	)
	(zone
		(layers "B.Cu" "In15.Cu")
		(hatch none 0.5)
		(connect_pads
			(clearance 0)
		)
		(min_thickness 0.25)
		(keepout
			(tracks not_allowed)
			(vias allowed)
			(pads allowed)
			(copperpour not_allowed)
			(footprints allowed)
		)
		(placement
			(enabled no)
			(sheetname "")
		)
		(fill yes
			(thermal_gap 0.5)
			(thermal_bridge_width 0.5)
			(island_removal_mode 0)
		)
		(polygon
			(pts
				(arc
					(start 382.88976 -292.71595)
					(mid 382.25984 -292.71595)
					(end 382.88976 -292.71595)
				)
			)
		)
	)
	(zone
		(layers "B.Cu" "In15.Cu")
		(hatch none 0.5)
		(connect_pads
			(clearance 0)
		)
		(min_thickness 0.25)
		(keepout
			(tracks not_allowed)
			(vias allowed)
			(pads allowed)
			(copperpour not_allowed)
			(footprints allowed)
		)
		(placement
			(enabled no)
			(sheetname "")
		)
		(fill yes
			(thermal_gap 0.5)
			(thermal_bridge_width 0.5)
			(island_removal_mode 0)
		)
		(polygon
			(pts
				(arc
					(start 424.346116 -307.835046)
					(mid 423.678096 -307.835046)
					(end 424.346116 -307.835046)
				)
			)
		)
	)
	(zone
		(layers "B.Cu" "In15.Cu")
		(hatch none 0.5)
		(connect_pads
			(clearance 0)
		)
		(min_thickness 0.25)
		(keepout
			(tracks not_allowed)
			(vias allowed)
			(pads allowed)
			(copperpour not_allowed)
			(footprints allowed)
		)
		(placement
			(enabled no)
			(sheetname "")
		)
		(fill yes
			(thermal_gap 0.5)
			(thermal_bridge_width 0.5)
			(island_removal_mode 0)
		)
		(polygon
			(pts
				(arc
					(start 136.8298 -287.856422)
					(mid 136.19988 -287.856422)
					(end 136.8298 -287.856422)
				)
			)
		)
	)
	(zone
		(layers "B.Cu" "In15.Cu")
		(hatch none 0.5)
		(connect_pads
			(clearance 0)
		)
		(min_thickness 0.25)
		(keepout
			(tracks not_allowed)
			(vias allowed)
			(pads allowed)
			(copperpour not_allowed)
			(footprints allowed)
		)
		(placement
			(enabled no)
			(sheetname "")
		)
		(fill yes
			(thermal_gap 0.5)
			(thermal_bridge_width 0.5)
			(island_removal_mode 0)
		)
		(polygon
			(pts
				(arc
					(start 336.03692 -433.289964)
					(mid 335.262728 -433.289964)
					(end 336.03692 -433.289964)
				)
			)
		)
	)
	(zone
		(layers "B.Cu" "In15.Cu")
		(hatch none 0.5)
		(connect_pads
			(clearance 0)
		)
		(min_thickness 0.25)
		(keepout
			(tracks not_allowed)
			(vias allowed)
			(pads allowed)
			(copperpour not_allowed)
			(footprints allowed)
		)
		(placement
			(enabled no)
			(sheetname "")
		)
		(fill yes
			(thermal_gap 0.5)
			(thermal_bridge_width 0.5)
			(island_removal_mode 0)
		)
		(polygon
			(pts
				(arc
					(start 89.536016 -247.724422)
					(mid 88.906096 -247.724422)
					(end 89.536016 -247.724422)
				)
			)
		)
	)
	(zone
		(layers "B.Cu" "In15.Cu")
		(hatch none 0.5)
		(connect_pads
			(clearance 0)
		)
		(min_thickness 0.25)
		(keepout
			(tracks not_allowed)
			(vias allowed)
			(pads allowed)
			(copperpour not_allowed)
			(footprints allowed)
		)
		(placement
			(enabled no)
			(sheetname "")
		)
		(fill yes
			(thermal_gap 0.5)
			(thermal_bridge_width 0.5)
			(island_removal_mode 0)
		)
		(polygon
			(pts
				(arc
					(start 52.218082 -225.385376)
					(mid 51.550062 -225.385376)
					(end 52.218082 -225.385376)
				)
			)
		)
	)
	(zone
		(layers "B.Cu" "In15.Cu")
		(hatch none 0.5)
		(connect_pads
			(clearance 0)
		)
		(min_thickness 0.25)
		(keepout
			(tracks not_allowed)
			(vias allowed)
			(pads allowed)
			(copperpour not_allowed)
			(footprints allowed)
		)
		(placement
			(enabled no)
			(sheetname "")
		)
		(fill yes
			(thermal_gap 0.5)
			(thermal_bridge_width 0.5)
			(island_removal_mode 0)
		)
		(polygon
			(pts
				(arc
					(start 383.99974 -229.094284)
					(mid 383.36982 -229.094284)
					(end 383.99974 -229.094284)
				)
			)
		)
	)
	(zone
		(layers "B.Cu" "In15.Cu")
		(hatch none 0.5)
		(connect_pads
			(clearance 0)
		)
		(min_thickness 0.25)
		(keepout
			(tracks not_allowed)
			(vias allowed)
			(pads allowed)
			(copperpour not_allowed)
			(footprints allowed)
		)
		(placement
			(enabled no)
			(sheetname "")
		)
		(fill yes
			(thermal_gap 0.5)
			(thermal_bridge_width 0.5)
			(island_removal_mode 0)
		)
		(polygon
			(pts
				(arc
					(start 134.649718 -242.864386)
					(mid 134.019798 -242.864386)
					(end 134.649718 -242.864386)
				)
			)
		)
	)
	(zone
		(layers "B.Cu" "In15.Cu")
		(hatch none 0.5)
		(connect_pads
			(clearance 0)
		)
		(min_thickness 0.25)
		(keepout
			(tracks not_allowed)
			(vias allowed)
			(pads allowed)
			(copperpour not_allowed)
			(footprints allowed)
		)
		(placement
			(enabled no)
			(sheetname "")
		)
		(fill yes
			(thermal_gap 0.5)
			(thermal_bridge_width 0.5)
			(island_removal_mode 0)
		)
		(polygon
			(pts
				(arc
					(start 132.050536 -393.292838)
					(mid 131.382516 -393.292838)
					(end 132.050536 -393.292838)
				)
			)
		)
	)
	(zone
		(layers "B.Cu" "In15.Cu")
		(hatch none 0.5)
		(connect_pads
			(clearance 0)
		)
		(min_thickness 0.25)
		(keepout
			(tracks not_allowed)
			(vias allowed)
			(pads allowed)
			(copperpour not_allowed)
			(footprints allowed)
		)
		(placement
			(enabled no)
			(sheetname "")
		)
		(fill yes
			(thermal_gap 0.5)
			(thermal_bridge_width 0.5)
			(island_removal_mode 0)
		)
		(polygon
			(pts
				(arc
					(start 154.889454 -373.96293)
					(mid 154.221434 -373.96293)
					(end 154.889454 -373.96293)
				)
			)
		)
	)
	(zone
		(layers "B.Cu" "In15.Cu")
		(hatch none 0.5)
		(connect_pads
			(clearance 0)
		)
		(min_thickness 0.25)
		(keepout
			(tracks not_allowed)
			(vias allowed)
			(pads allowed)
			(copperpour not_allowed)
			(footprints allowed)
		)
		(placement
			(enabled no)
			(sheetname "")
		)
		(fill yes
			(thermal_gap 0.5)
			(thermal_bridge_width 0.5)
			(island_removal_mode 0)
		)
		(polygon
			(pts
				(arc
					(start 371.609874 -270.036036)
					(mid 370.979954 -270.036036)
					(end 371.609874 -270.036036)
				)
			)
		)
	)
	(zone
		(layers "B.Cu" "In15.Cu")
		(hatch none 0.5)
		(connect_pads
			(clearance 0)
		)
		(min_thickness 0.25)
		(keepout
			(tracks not_allowed)
			(vias allowed)
			(pads allowed)
			(copperpour not_allowed)
			(footprints allowed)
		)
		(placement
			(enabled no)
			(sheetname "")
		)
		(fill yes
			(thermal_gap 0.5)
			(thermal_bridge_width 0.5)
			(island_removal_mode 0)
		)
		(polygon
			(pts
				(arc
					(start 136.059672 -232.334308)
					(mid 135.429752 -232.334308)
					(end 136.059672 -232.334308)
				)
			)
		)
	)
	(zone
		(layers "B.Cu" "In15.Cu")
		(hatch none 0.5)
		(connect_pads
			(clearance 0)
		)
		(min_thickness 0.25)
		(keepout
			(tracks not_allowed)
			(vias allowed)
			(pads allowed)
			(copperpour not_allowed)
			(footprints allowed)
		)
		(placement
			(enabled no)
			(sheetname "")
		)
		(fill yes
			(thermal_gap 0.5)
			(thermal_bridge_width 0.5)
			(island_removal_mode 0)
		)
		(polygon
			(pts
				(arc
					(start 342.036908 -434.289962)
					(mid 341.262716 -434.289962)
					(end 342.036908 -434.289962)
				)
			)
		)
	)
	(zone
		(layers "B.Cu" "In15.Cu")
		(hatch none 0.5)
		(connect_pads
			(clearance 0)
		)
		(min_thickness 0.25)
		(keepout
			(tracks not_allowed)
			(vias allowed)
			(pads allowed)
			(copperpour not_allowed)
			(footprints allowed)
		)
		(placement
			(enabled no)
			(sheetname "")
		)
		(fill yes
			(thermal_gap 0.5)
			(thermal_bridge_width 0.5)
			(island_removal_mode 0)
		)
		(polygon
			(pts
				(arc
					(start 382.88976 -276.516084)
					(mid 382.25984 -276.516084)
					(end 382.88976 -276.516084)
				)
			)
		)
	)
	(zone
		(layers "B.Cu" "In15.Cu")
		(hatch none 0.5)
		(connect_pads
			(clearance 0)
		)
		(min_thickness 0.25)
		(keepout
			(tracks not_allowed)
			(vias allowed)
			(pads allowed)
			(copperpour not_allowed)
			(footprints allowed)
		)
		(placement
			(enabled no)
			(sheetname "")
		)
		(fill yes
			(thermal_gap 0.5)
			(thermal_bridge_width 0.5)
			(island_removal_mode 0)
		)
		(polygon
			(pts
				(arc
					(start 383.35966 -275.706078)
					(mid 382.72974 -275.706078)
					(end 383.35966 -275.706078)
				)
			)
		)
	)
	(zone
		(layers "B.Cu" "In15.Cu")
		(hatch none 0.5)
		(connect_pads
			(clearance 0)
		)
		(min_thickness 0.25)
		(keepout
			(tracks not_allowed)
			(vias allowed)
			(pads allowed)
			(copperpour not_allowed)
			(footprints allowed)
		)
		(placement
			(enabled no)
			(sheetname "")
		)
		(fill yes
			(thermal_gap 0.5)
			(thermal_bridge_width 0.5)
			(island_removal_mode 0)
		)
		(polygon
			(pts
				(arc
					(start 337.476084 -228.284278)
					(mid 336.846164 -228.284278)
					(end 337.476084 -228.284278)
				)
			)
		)
	)
	(zone
		(layers "B.Cu" "In15.Cu")
		(hatch none 0.5)
		(connect_pads
			(clearance 0)
		)
		(min_thickness 0.25)
		(keepout
			(tracks not_allowed)
			(vias allowed)
			(pads allowed)
			(copperpour not_allowed)
			(footprints allowed)
		)
		(placement
			(enabled no)
			(sheetname "")
		)
		(fill yes
			(thermal_gap 0.5)
			(thermal_bridge_width 0.5)
			(island_removal_mode 0)
		)
		(polygon
			(pts
				(arc
					(start 424.346116 -294.235124)
					(mid 423.678096 -294.235124)
					(end 424.346116 -294.235124)
				)
			)
		)
	)
	(zone
		(layers "B.Cu" "In15.Cu")
		(hatch none 0.5)
		(connect_pads
			(clearance 0)
		)
		(min_thickness 0.25)
		(keepout
			(tracks not_allowed)
			(vias allowed)
			(pads allowed)
			(copperpour not_allowed)
			(footprints allowed)
		)
		(placement
			(enabled no)
			(sheetname "")
		)
		(fill yes
			(thermal_gap 0.5)
			(thermal_bridge_width 0.5)
			(island_removal_mode 0)
		)
		(polygon
			(pts
				(arc
					(start 420.246048 -304.435002)
					(mid 419.578028 -304.435002)
					(end 420.246048 -304.435002)
				)
			)
		)
	)
	(zone
		(layers "B.Cu" "In15.Cu")
		(hatch none 0.5)
		(connect_pads
			(clearance 0)
		)
		(min_thickness 0.25)
		(keepout
			(tracks not_allowed)
			(vias allowed)
			(pads allowed)
			(copperpour not_allowed)
			(footprints allowed)
		)
		(placement
			(enabled no)
			(sheetname "")
		)
		(fill yes
			(thermal_gap 0.5)
			(thermal_bridge_width 0.5)
			(island_removal_mode 0)
		)
		(polygon
			(pts
				(arc
					(start 296.058082 -285.735014)
					(mid 295.390062 -285.735014)
					(end 296.058082 -285.735014)
				)
			)
		)
	)
	(zone
		(layers "B.Cu" "In15.Cu")
		(hatch none 0.5)
		(connect_pads
			(clearance 0)
		)
		(min_thickness 0.25)
		(keepout
			(tracks not_allowed)
			(vias allowed)
			(pads allowed)
			(copperpour not_allowed)
			(footprints allowed)
		)
		(placement
			(enabled no)
			(sheetname "")
		)
		(fill yes
			(thermal_gap 0.5)
			(thermal_bridge_width 0.5)
			(island_removal_mode 0)
		)
		(polygon
			(pts
				(arc
					(start 335.89595 -273.27606)
					(mid 335.26603 -273.27606)
					(end 335.89595 -273.27606)
				)
			)
		)
	)
	(zone
		(layers "B.Cu" "In15.Cu")
		(hatch none 0.5)
		(connect_pads
			(clearance 0)
		)
		(min_thickness 0.25)
		(keepout
			(tracks not_allowed)
			(vias allowed)
			(pads allowed)
			(copperpour not_allowed)
			(footprints allowed)
		)
		(placement
			(enabled no)
			(sheetname "")
		)
		(fill yes
			(thermal_gap 0.5)
			(thermal_bridge_width 0.5)
			(island_removal_mode 0)
		)
		(polygon
			(pts
				(arc
					(start 396.136876 -435.489858)
					(mid 395.362684 -435.489858)
					(end 396.136876 -435.489858)
				)
			)
		)
	)
	(zone
		(layers "B.Cu" "In15.Cu")
		(hatch none 0.5)
		(connect_pads
			(clearance 0)
		)
		(min_thickness 0.25)
		(keepout
			(tracks not_allowed)
			(vias allowed)
			(pads allowed)
			(copperpour not_allowed)
			(footprints allowed)
		)
		(placement
			(enabled no)
			(sheetname "")
		)
		(fill yes
			(thermal_gap 0.5)
			(thermal_bridge_width 0.5)
			(island_removal_mode 0)
		)
		(polygon
			(pts
				(arc
					(start 176.406048 -309.535322)
					(mid 175.738028 -309.535322)
					(end 176.406048 -309.535322)
				)
			)
		)
	)
	(zone
		(layers "B.Cu" "In15.Cu")
		(hatch none 0.5)
		(connect_pads
			(clearance 0)
		)
		(min_thickness 0.25)
		(keepout
			(tracks not_allowed)
			(vias allowed)
			(pads allowed)
			(copperpour not_allowed)
			(footprints allowed)
		)
		(placement
			(enabled no)
			(sheetname "")
		)
		(fill yes
			(thermal_gap 0.5)
			(thermal_bridge_width 0.5)
			(island_removal_mode 0)
		)
		(polygon
			(pts
				(arc
					(start 420.246048 -232.184956)
					(mid 419.578028 -232.184956)
					(end 420.246048 -232.184956)
				)
			)
		)
	)
	(zone
		(layers "B.Cu" "In15.Cu")
		(hatch none 0.5)
		(connect_pads
			(clearance 0)
		)
		(min_thickness 0.25)
		(keepout
			(tracks not_allowed)
			(vias allowed)
			(pads allowed)
			(copperpour not_allowed)
			(footprints allowed)
		)
		(placement
			(enabled no)
			(sheetname "")
		)
		(fill yes
			(thermal_gap 0.5)
			(thermal_bridge_width 0.5)
			(island_removal_mode 0)
		)
		(polygon
			(pts
				(arc
					(start 89.36609 -290.286186)
					(mid 88.73617 -290.286186)
					(end 89.36609 -290.286186)
				)
			)
		)
	)
	(zone
		(layers "B.Cu" "In15.Cu")
		(hatch none 0.5)
		(connect_pads
			(clearance 0)
		)
		(min_thickness 0.25)
		(keepout
			(tracks not_allowed)
			(vias allowed)
			(pads allowed)
			(copperpour not_allowed)
			(footprints allowed)
		)
		(placement
			(enabled no)
			(sheetname "")
		)
		(fill yes
			(thermal_gap 0.5)
			(thermal_bridge_width 0.5)
			(island_removal_mode 0)
		)
		(polygon
			(pts
				(arc
					(start 53.306218 -386.003292)
					(mid 52.676298 -386.003292)
					(end 53.306218 -386.003292)
				)
			)
		)
	)
	(zone
		(layers "B.Cu" "In15.Cu")
		(hatch none 0.5)
		(connect_pads
			(clearance 0)
		)
		(min_thickness 0.25)
		(keepout
			(tracks not_allowed)
			(vias allowed)
			(pads allowed)
			(copperpour not_allowed)
			(footprints allowed)
		)
		(placement
			(enabled no)
			(sheetname "")
		)
		(fill yes
			(thermal_gap 0.5)
			(thermal_bridge_width 0.5)
			(island_removal_mode 0)
		)
		(polygon
			(pts
				(arc
					(start 296.058082 -284.034992)
					(mid 295.390062 -284.034992)
					(end 296.058082 -284.034992)
				)
			)
		)
	)
	(zone
		(layers "B.Cu" "In15.Cu")
		(hatch none 0.5)
		(connect_pads
			(clearance 0)
		)
		(min_thickness 0.25)
		(keepout
			(tracks not_allowed)
			(vias allowed)
			(pads allowed)
			(copperpour not_allowed)
			(footprints allowed)
		)
		(placement
			(enabled no)
			(sheetname "")
		)
		(fill yes
			(thermal_gap 0.5)
			(thermal_bridge_width 0.5)
			(island_removal_mode 0)
		)
		(polygon
			(pts
				(arc
					(start 300.15815 -200.735184)
					(mid 299.49013 -200.735184)
					(end 300.15815 -200.735184)
				)
			)
		)
	)
	(zone
		(layers "B.Cu" "In15.Cu")
		(hatch none 0.5)
		(connect_pads
			(clearance 0)
		)
		(min_thickness 0.25)
		(keepout
			(tracks not_allowed)
			(vias allowed)
			(pads allowed)
			(copperpour not_allowed)
			(footprints allowed)
		)
		(placement
			(enabled no)
			(sheetname "")
		)
		(fill yes
			(thermal_gap 0.5)
			(thermal_bridge_width 0.5)
			(island_removal_mode 0)
		)
		(polygon
			(pts
				(arc
					(start 48.118014 -201.585322)
					(mid 47.449994 -201.585322)
					(end 48.118014 -201.585322)
				)
			)
		)
	)
	(zone
		(layers "B.Cu" "In15.Cu")
		(hatch none 0.5)
		(connect_pads
			(clearance 0)
		)
		(min_thickness 0.25)
		(keepout
			(tracks not_allowed)
			(vias allowed)
			(pads allowed)
			(copperpour not_allowed)
			(footprints allowed)
		)
		(placement
			(enabled no)
			(sheetname "")
		)
		(fill yes
			(thermal_gap 0.5)
			(thermal_bridge_width 0.5)
			(island_removal_mode 0)
		)
		(polygon
			(pts
				(arc
					(start 335.595976 -244.484144)
					(mid 334.966056 -244.484144)
					(end 335.595976 -244.484144)
				)
			)
		)
	)
	(zone
		(layers "B.Cu" "In15.Cu")
		(hatch none 0.5)
		(connect_pads
			(clearance 0)
		)
		(min_thickness 0.25)
		(keepout
			(tracks not_allowed)
			(vias allowed)
			(pads allowed)
			(copperpour not_allowed)
			(footprints allowed)
		)
		(placement
			(enabled no)
			(sheetname "")
		)
		(fill yes
			(thermal_gap 0.5)
			(thermal_bridge_width 0.5)
			(island_removal_mode 0)
		)
		(polygon
			(pts
				(arc
					(start 336.366104 -287.045908)
					(mid 335.736184 -287.045908)
					(end 336.366104 -287.045908)
				)
			)
		)
	)
	(zone
		(layers "B.Cu" "In15.Cu")
		(hatch none 0.5)
		(connect_pads
			(clearance 0)
		)
		(min_thickness 0.25)
		(keepout
			(tracks not_allowed)
			(vias allowed)
			(pads allowed)
			(copperpour not_allowed)
			(footprints allowed)
		)
		(placement
			(enabled no)
			(sheetname "")
		)
		(fill yes
			(thermal_gap 0.5)
			(thermal_bridge_width 0.5)
			(island_removal_mode 0)
		)
		(polygon
			(pts
				(arc
					(start 397.392398 -384.35026)
					(mid 396.724378 -384.35026)
					(end 397.392398 -384.35026)
				)
			)
		)
	)
	(zone
		(layers "B.Cu" "In15.Cu")
		(hatch none 0.5)
		(connect_pads
			(clearance 0)
		)
		(min_thickness 0.25)
		(keepout
			(tracks not_allowed)
			(vias allowed)
			(pads allowed)
			(copperpour not_allowed)
			(footprints allowed)
		)
		(placement
			(enabled no)
			(sheetname "")
		)
		(fill yes
			(thermal_gap 0.5)
			(thermal_bridge_width 0.5)
			(island_removal_mode 0)
		)
		(polygon
			(pts
				(arc
					(start 306.506118 -393.69238)
					(mid 305.876198 -393.69238)
					(end 306.506118 -393.69238)
				)
			)
		)
	)
	(zone
		(layers "B.Cu" "In15.Cu")
		(hatch none 0.5)
		(connect_pads
			(clearance 0)
		)
		(min_thickness 0.25)
		(keepout
			(tracks not_allowed)
			(vias allowed)
			(pads allowed)
			(copperpour not_allowed)
			(footprints allowed)
		)
		(placement
			(enabled no)
			(sheetname "")
		)
		(fill yes
			(thermal_gap 0.5)
			(thermal_bridge_width 0.5)
			(island_removal_mode 0)
		)
		(polygon
			(pts
				(arc
					(start 335.89595 -279.756108)
					(mid 335.26603 -279.756108)
					(end 335.89595 -279.756108)
				)
			)
		)
	)
	(zone
		(layers "B.Cu" "In15.Cu")
		(hatch none 0.5)
		(connect_pads
			(clearance 0)
		)
		(min_thickness 0.25)
		(keepout
			(tracks not_allowed)
			(vias allowed)
			(pads allowed)
			(copperpour not_allowed)
			(footprints allowed)
		)
		(placement
			(enabled no)
			(sheetname "")
		)
		(fill yes
			(thermal_gap 0.5)
			(thermal_bridge_width 0.5)
			(island_removal_mode 0)
		)
		(polygon
			(pts
				(arc
					(start 337.006184 -248.534174)
					(mid 336.376264 -248.534174)
					(end 337.006184 -248.534174)
				)
			)
		)
	)
	(zone
		(layers "B.Cu" "In15.Cu")
		(hatch none 0.5)
		(connect_pads
			(clearance 0)
		)
		(min_thickness 0.25)
		(keepout
			(tracks not_allowed)
			(vias allowed)
			(pads allowed)
			(copperpour not_allowed)
			(footprints allowed)
		)
		(placement
			(enabled no)
			(sheetname "")
		)
		(fill yes
			(thermal_gap 0.5)
			(thermal_bridge_width 0.5)
			(island_removal_mode 0)
		)
		(polygon
			(pts
				(arc
					(start 80.678274 -392.429238)
					(mid 80.010254 -392.429238)
					(end 80.678274 -392.429238)
				)
			)
		)
	)
	(zone
		(layers "B.Cu" "In15.Cu")
		(hatch none 0.5)
		(connect_pads
			(clearance 0)
		)
		(min_thickness 0.25)
		(keepout
			(tracks not_allowed)
			(vias allowed)
			(pads allowed)
			(copperpour not_allowed)
			(footprints allowed)
		)
		(placement
			(enabled no)
			(sheetname "")
		)
		(fill yes
			(thermal_gap 0.5)
			(thermal_bridge_width 0.5)
			(island_removal_mode 0)
		)
		(polygon
			(pts
				(arc
					(start 118.85041 -392.429238)
					(mid 118.18239 -392.429238)
					(end 118.85041 -392.429238)
				)
			)
		)
	)
	(zone
		(layers "B.Cu" "In15.Cu")
		(hatch none 0.5)
		(connect_pads
			(clearance 0)
		)
		(min_thickness 0.25)
		(keepout
			(tracks not_allowed)
			(vias allowed)
			(pads allowed)
			(copperpour not_allowed)
			(footprints allowed)
		)
		(placement
			(enabled no)
			(sheetname "")
		)
		(fill yes
			(thermal_gap 0.5)
			(thermal_bridge_width 0.5)
			(island_removal_mode 0)
		)
		(polygon
			(pts
				(arc
					(start 134.949692 -265.176254)
					(mid 134.319772 -265.176254)
					(end 134.949692 -265.176254)
				)
			)
		)
	)
	(zone
		(layers "B.Cu" "In15.Cu")
		(hatch none 0.5)
		(connect_pads
			(clearance 0)
		)
		(min_thickness 0.25)
		(keepout
			(tracks not_allowed)
			(vias allowed)
			(pads allowed)
			(copperpour not_allowed)
			(footprints allowed)
		)
		(placement
			(enabled no)
			(sheetname "")
		)
		(fill yes
			(thermal_gap 0.5)
			(thermal_bridge_width 0.5)
			(island_removal_mode 0)
		)
		(polygon
			(pts
				(arc
					(start 48.118014 -230.485442)
					(mid 47.449994 -230.485442)
					(end 48.118014 -230.485442)
				)
			)
		)
	)
	(zone
		(layers "B.Cu" "In15.Cu")
		(hatch none 0.5)
		(connect_pads
			(clearance 0)
		)
		(min_thickness 0.25)
		(keepout
			(tracks not_allowed)
			(vias allowed)
			(pads allowed)
			(copperpour not_allowed)
			(footprints allowed)
		)
		(placement
			(enabled no)
			(sheetname "")
		)
		(fill yes
			(thermal_gap 0.5)
			(thermal_bridge_width 0.5)
			(island_removal_mode 0)
		)
		(polygon
			(pts
				(arc
					(start 296.058082 -222.834962)
					(mid 295.390062 -222.834962)
					(end 296.058082 -222.834962)
				)
			)
		)
	)
	(zone
		(layers "B.Cu" "In15.Cu")
		(hatch none 0.5)
		(connect_pads
			(clearance 0)
		)
		(min_thickness 0.25)
		(keepout
			(tracks not_allowed)
			(vias allowed)
			(pads allowed)
			(copperpour not_allowed)
			(footprints allowed)
		)
		(placement
			(enabled no)
			(sheetname "")
		)
		(fill yes
			(thermal_gap 0.5)
			(thermal_bridge_width 0.5)
			(island_removal_mode 0)
		)
		(polygon
			(pts
				(arc
					(start 130.1369 -433.289964)
					(mid 129.362708 -433.289964)
					(end 130.1369 -433.289964)
				)
			)
		)
	)
	(zone
		(layers "B.Cu" "In15.Cu")
		(hatch none 0.5)
		(connect_pads
			(clearance 0)
		)
		(min_thickness 0.25)
		(keepout
			(tracks not_allowed)
			(vias allowed)
			(pads allowed)
			(copperpour not_allowed)
			(footprints allowed)
		)
		(placement
			(enabled no)
			(sheetname "")
		)
		(fill yes
			(thermal_gap 0.5)
			(thermal_bridge_width 0.5)
			(island_removal_mode 0)
		)
		(polygon
			(pts
				(arc
					(start 382.88976 -279.756108)
					(mid 382.25984 -279.756108)
					(end 382.88976 -279.756108)
				)
			)
		)
	)
	(zone
		(layers "B.Cu" "In15.Cu")
		(hatch none 0.5)
		(connect_pads
			(clearance 0)
		)
		(min_thickness 0.25)
		(keepout
			(tracks not_allowed)
			(vias allowed)
			(pads allowed)
			(copperpour not_allowed)
			(footprints allowed)
		)
		(placement
			(enabled no)
			(sheetname "")
		)
		(fill yes
			(thermal_gap 0.5)
			(thermal_bridge_width 0.5)
			(island_removal_mode 0)
		)
		(polygon
			(pts
				(arc
					(start 135.119618 -225.854514)
					(mid 134.489698 -225.854514)
					(end 135.119618 -225.854514)
				)
			)
		)
	)
	(zone
		(layers "B.Cu" "In15.Cu")
		(hatch none 0.5)
		(connect_pads
			(clearance 0)
		)
		(min_thickness 0.25)
		(keepout
			(tracks not_allowed)
			(vias allowed)
			(pads allowed)
			(copperpour not_allowed)
			(footprints allowed)
		)
		(placement
			(enabled no)
			(sheetname "")
		)
		(fill yes
			(thermal_gap 0.5)
			(thermal_bridge_width 0.5)
			(island_removal_mode 0)
		)
		(polygon
			(pts
				(arc
					(start 296.058082 -201.585068)
					(mid 295.390062 -201.585068)
					(end 296.058082 -201.585068)
				)
			)
		)
	)
	(zone
		(layers "B.Cu" "In15.Cu")
		(hatch none 0.5)
		(connect_pads
			(clearance 0)
		)
		(min_thickness 0.25)
		(keepout
			(tracks not_allowed)
			(vias allowed)
			(pads allowed)
			(copperpour not_allowed)
			(footprints allowed)
		)
		(placement
			(enabled no)
			(sheetname "")
		)
		(fill yes
			(thermal_gap 0.5)
			(thermal_bridge_width 0.5)
			(island_removal_mode 0)
		)
		(polygon
			(pts
				(arc
					(start 420.26205 -379.88113)
					(mid 419.59403 -379.88113)
					(end 420.26205 -379.88113)
				)
			)
		)
	)
	(zone
		(layers "B.Cu" "In15.Cu")
		(hatch none 0.5)
		(connect_pads
			(clearance 0)
		)
		(min_thickness 0.25)
		(keepout
			(tracks not_allowed)
			(vias allowed)
			(pads allowed)
			(copperpour not_allowed)
			(footprints allowed)
		)
		(placement
			(enabled no)
			(sheetname "")
		)
		(fill yes
			(thermal_gap 0.5)
			(thermal_bridge_width 0.5)
			(island_removal_mode 0)
		)
		(polygon
			(pts
				(arc
					(start 424.346116 -247.485154)
					(mid 423.678096 -247.485154)
					(end 424.346116 -247.485154)
				)
			)
		)
	)
	(zone
		(layers "B.Cu" "In15.Cu")
		(hatch none 0.5)
		(connect_pads
			(clearance 0)
		)
		(min_thickness 0.25)
		(keepout
			(tracks not_allowed)
			(vias allowed)
			(pads allowed)
			(copperpour not_allowed)
			(footprints allowed)
		)
		(placement
			(enabled no)
			(sheetname "")
		)
		(fill yes
			(thermal_gap 0.5)
			(thermal_bridge_width 0.5)
			(island_removal_mode 0)
		)
		(polygon
			(pts
				(arc
					(start 88.426036 -288.666174)
					(mid 87.796116 -288.666174)
					(end 88.426036 -288.666174)
				)
			)
		)
	)
	(zone
		(layers "B.Cu" "In15.Cu")
		(hatch none 0.5)
		(connect_pads
			(clearance 0)
		)
		(min_thickness 0.25)
		(keepout
			(tracks not_allowed)
			(vias allowed)
			(pads allowed)
			(copperpour not_allowed)
			(footprints allowed)
		)
		(placement
			(enabled no)
			(sheetname "")
		)
		(fill yes
			(thermal_gap 0.5)
			(thermal_bridge_width 0.5)
			(island_removal_mode 0)
		)
		(polygon
			(pts
				(arc
					(start 135.119618 -250.15444)
					(mid 134.489698 -250.15444)
					(end 135.119618 -250.15444)
				)
			)
		)
	)
	(zone
		(layers "B.Cu" "In15.Cu")
		(hatch none 0.5)
		(connect_pads
			(clearance 0)
		)
		(min_thickness 0.25)
		(keepout
			(tracks not_allowed)
			(vias allowed)
			(pads allowed)
			(copperpour not_allowed)
			(footprints allowed)
		)
		(placement
			(enabled no)
			(sheetname "")
		)
		(fill yes
			(thermal_gap 0.5)
			(thermal_bridge_width 0.5)
			(island_removal_mode 0)
		)
		(polygon
			(pts
				(arc
					(start 88.126062 -232.334308)
					(mid 87.496142 -232.334308)
					(end 88.126062 -232.334308)
				)
			)
		)
	)
	(zone
		(layers "B.Cu" "In15.Cu")
		(hatch none 0.5)
		(connect_pads
			(clearance 0)
		)
		(min_thickness 0.25)
		(keepout
			(tracks not_allowed)
			(vias allowed)
			(pads allowed)
			(copperpour not_allowed)
			(footprints allowed)
		)
		(placement
			(enabled no)
			(sheetname "")
		)
		(fill yes
			(thermal_gap 0.5)
			(thermal_bridge_width 0.5)
			(island_removal_mode 0)
		)
		(polygon
			(pts
				(arc
					(start 352.516186 -241.24412)
					(mid 351.886266 -241.24412)
					(end 352.516186 -241.24412)
				)
			)
		)
	)
	(zone
		(layers "B.Cu" "In15.Cu")
		(hatch none 0.5)
		(connect_pads
			(clearance 0)
		)
		(min_thickness 0.25)
		(keepout
			(tracks not_allowed)
			(vias allowed)
			(pads allowed)
			(copperpour not_allowed)
			(footprints allowed)
		)
		(placement
			(enabled no)
			(sheetname "")
		)
		(fill yes
			(thermal_gap 0.5)
			(thermal_bridge_width 0.5)
			(island_removal_mode 0)
		)
		(polygon
			(pts
				(arc
					(start 424.346116 -313.784996)
					(mid 423.678096 -313.784996)
					(end 424.346116 -313.784996)
				)
			)
		)
	)
	(zone
		(layers "B.Cu" "In15.Cu")
		(hatch none 0.5)
		(connect_pads
			(clearance 0)
		)
		(min_thickness 0.25)
		(keepout
			(tracks not_allowed)
			(vias allowed)
			(pads allowed)
			(copperpour not_allowed)
			(footprints allowed)
		)
		(placement
			(enabled no)
			(sheetname "")
		)
		(fill yes
			(thermal_gap 0.5)
			(thermal_bridge_width 0.5)
			(island_removal_mode 0)
		)
		(polygon
			(pts
				(arc
					(start 336.366104 -285.42615)
					(mid 335.736184 -285.42615)
					(end 336.366104 -285.42615)
				)
			)
		)
	)
	(zone
		(layers "B.Cu" "In15.Cu")
		(hatch none 0.5)
		(connect_pads
			(clearance 0)
		)
		(min_thickness 0.25)
		(keepout
			(tracks not_allowed)
			(vias allowed)
			(pads allowed)
			(copperpour not_allowed)
			(footprints allowed)
		)
		(placement
			(enabled no)
			(sheetname "")
		)
		(fill yes
			(thermal_gap 0.5)
			(thermal_bridge_width 0.5)
			(island_removal_mode 0)
		)
		(polygon
			(pts
				(arc
					(start 384.769868 -287.856168)
					(mid 384.139948 -287.856168)
					(end 384.769868 -287.856168)
				)
			)
		)
	)
	(zone
		(layers "B.Cu" "In15.Cu")
		(hatch none 0.5)
		(connect_pads
			(clearance 0)
		)
		(min_thickness 0.25)
		(keepout
			(tracks not_allowed)
			(vias allowed)
			(pads allowed)
			(copperpour not_allowed)
			(footprints allowed)
		)
		(placement
			(enabled no)
			(sheetname "")
		)
		(fill yes
			(thermal_gap 0.5)
			(thermal_bridge_width 0.5)
			(island_removal_mode 0)
		)
		(polygon
			(pts
				(arc
					(start 172.30598 -301.035212)
					(mid 171.63796 -301.035212)
					(end 172.30598 -301.035212)
				)
			)
		)
	)
	(zone
		(layers "B.Cu" "In15.Cu")
		(hatch none 0.5)
		(connect_pads
			(clearance 0)
		)
		(min_thickness 0.25)
		(keepout
			(tracks not_allowed)
			(vias allowed)
			(pads allowed)
			(copperpour not_allowed)
			(footprints allowed)
		)
		(placement
			(enabled no)
			(sheetname "")
		)
		(fill yes
			(thermal_gap 0.5)
			(thermal_bridge_width 0.5)
			(island_removal_mode 0)
		)
		(polygon
			(pts
				(arc
					(start 354.39604 -241.24412)
					(mid 353.76612 -241.24412)
					(end 354.39604 -241.24412)
				)
			)
		)
	)
	(zone
		(layers "B.Cu" "In15.Cu")
		(hatch none 0.5)
		(connect_pads
			(clearance 0)
		)
		(min_thickness 0.25)
		(keepout
			(tracks not_allowed)
			(vias allowed)
			(pads allowed)
			(copperpour not_allowed)
			(footprints allowed)
		)
		(placement
			(enabled no)
			(sheetname "")
		)
		(fill yes
			(thermal_gap 0.5)
			(thermal_bridge_width 0.5)
			(island_removal_mode 0)
		)
		(polygon
			(pts
				(arc
					(start 300.15815 -303.585118)
					(mid 299.49013 -303.585118)
					(end 300.15815 -303.585118)
				)
			)
		)
	)
	(zone
		(layers "B.Cu" "In15.Cu")
		(hatch none 0.5)
		(connect_pads
			(clearance 0)
		)
		(min_thickness 0.25)
		(keepout
			(tracks not_allowed)
			(vias allowed)
			(pads allowed)
			(copperpour not_allowed)
			(footprints allowed)
		)
		(placement
			(enabled no)
			(sheetname "")
		)
		(fill yes
			(thermal_gap 0.5)
			(thermal_bridge_width 0.5)
			(island_removal_mode 0)
		)
		(polygon
			(pts
				(arc
					(start 336.03692 -434.48986)
					(mid 335.262728 -434.48986)
					(end 336.03692 -434.48986)
				)
			)
		)
	)
	(zone
		(layers "B.Cu" "In15.Cu")
		(hatch none 0.5)
		(connect_pads
			(clearance 0)
		)
		(min_thickness 0.25)
		(keepout
			(tracks not_allowed)
			(vias allowed)
			(pads allowed)
			(copperpour not_allowed)
			(footprints allowed)
		)
		(placement
			(enabled no)
			(sheetname "")
		)
		(fill yes
			(thermal_gap 0.5)
			(thermal_bridge_width 0.5)
			(island_removal_mode 0)
		)
		(polygon
			(pts
				(arc
					(start 335.595976 -255.824228)
					(mid 334.966056 -255.824228)
					(end 335.595976 -255.824228)
				)
			)
		)
	)
	(zone
		(layers "B.Cu" "In15.Cu")
		(hatch none 0.5)
		(connect_pads
			(clearance 0)
		)
		(min_thickness 0.25)
		(keepout
			(tracks not_allowed)
			(vias allowed)
			(pads allowed)
			(copperpour not_allowed)
			(footprints allowed)
		)
		(placement
			(enabled no)
			(sheetname "")
		)
		(fill yes
			(thermal_gap 0.5)
			(thermal_bridge_width 0.5)
			(island_removal_mode 0)
		)
		(polygon
			(pts
				(arc
					(start 337.776058 -278.136096)
					(mid 337.146138 -278.136096)
					(end 337.776058 -278.136096)
				)
			)
		)
	)
	(zone
		(layers "B.Cu" "In15.Cu")
		(hatch none 0.5)
		(connect_pads
			(clearance 0)
		)
		(min_thickness 0.25)
		(keepout
			(tracks not_allowed)
			(vias allowed)
			(pads allowed)
			(copperpour not_allowed)
			(footprints allowed)
		)
		(placement
			(enabled no)
			(sheetname "")
		)
		(fill yes
			(thermal_gap 0.5)
			(thermal_bridge_width 0.5)
			(island_removal_mode 0)
		)
		(polygon
			(pts
				(arc
					(start 52.218082 -275.53539)
					(mid 51.550062 -275.53539)
					(end 52.218082 -275.53539)
				)
			)
		)
	)
	(zone
		(layers "B.Cu" "In15.Cu")
		(hatch none 0.5)
		(connect_pads
			(clearance 0)
		)
		(min_thickness 0.25)
		(keepout
			(tracks not_allowed)
			(vias allowed)
			(pads allowed)
			(copperpour not_allowed)
			(footprints allowed)
		)
		(placement
			(enabled no)
			(sheetname "")
		)
		(fill yes
			(thermal_gap 0.5)
			(thermal_bridge_width 0.5)
			(island_removal_mode 0)
		)
		(polygon
			(pts
				(arc
					(start 420.246048 -227.935028)
					(mid 419.578028 -227.935028)
					(end 420.246048 -227.935028)
				)
			)
		)
	)
	(zone
		(layers "B.Cu" "In15.Cu")
		(hatch none 0.5)
		(connect_pads
			(clearance 0)
		)
		(min_thickness 0.25)
		(keepout
			(tracks not_allowed)
			(vias allowed)
			(pads allowed)
			(copperpour not_allowed)
			(footprints allowed)
		)
		(placement
			(enabled no)
			(sheetname "")
		)
		(fill yes
			(thermal_gap 0.5)
			(thermal_bridge_width 0.5)
			(island_removal_mode 0)
		)
		(polygon
			(pts
				(arc
					(start 351.576132 -242.864132)
					(mid 350.946212 -242.864132)
					(end 351.576132 -242.864132)
				)
			)
		)
	)
	(zone
		(layers "B.Cu" "In15.Cu")
		(hatch none 0.5)
		(connect_pads
			(clearance 0)
		)
		(min_thickness 0.25)
		(keepout
			(tracks not_allowed)
			(vias allowed)
			(pads allowed)
			(copperpour not_allowed)
			(footprints allowed)
		)
		(placement
			(enabled no)
			(sheetname "")
		)
		(fill yes
			(thermal_gap 0.5)
			(thermal_bridge_width 0.5)
			(island_removal_mode 0)
		)
		(polygon
			(pts
				(arc
					(start 352.516186 -239.624108)
					(mid 351.886266 -239.624108)
					(end 352.516186 -239.624108)
				)
			)
		)
	)
	(zone
		(layers "B.Cu" "In15.Cu")
		(hatch none 0.5)
		(connect_pads
			(clearance 0)
		)
		(min_thickness 0.25)
		(keepout
			(tracks not_allowed)
			(vias allowed)
			(pads allowed)
			(copperpour not_allowed)
			(footprints allowed)
		)
		(placement
			(enabled no)
			(sheetname "")
		)
		(fill yes
			(thermal_gap 0.5)
			(thermal_bridge_width 0.5)
			(island_removal_mode 0)
		)
		(polygon
			(pts
				(arc
					(start 168.503854 -369.03533)
					(mid 167.835834 -369.03533)
					(end 168.503854 -369.03533)
				)
			)
		)
	)
	(zone
		(layers "B.Cu" "In15.Cu")
		(hatch none 0.5)
		(connect_pads
			(clearance 0)
		)
		(min_thickness 0.25)
		(keepout
			(tracks not_allowed)
			(vias allowed)
			(pads allowed)
			(copperpour not_allowed)
			(footprints allowed)
		)
		(placement
			(enabled no)
			(sheetname "")
		)
		(fill yes
			(thermal_gap 0.5)
			(thermal_bridge_width 0.5)
			(island_removal_mode 0)
		)
		(polygon
			(pts
				(arc
					(start 48.118014 -207.535272)
					(mid 47.449994 -207.535272)
					(end 48.118014 -207.535272)
				)
			)
		)
	)
	(zone
		(layers "B.Cu" "In15.Cu")
		(hatch none 0.5)
		(connect_pads
			(clearance 0)
		)
		(min_thickness 0.25)
		(keepout
			(tracks not_allowed)
			(vias allowed)
			(pads allowed)
			(copperpour not_allowed)
			(footprints allowed)
		)
		(placement
			(enabled no)
			(sheetname "")
		)
		(fill yes
			(thermal_gap 0.5)
			(thermal_bridge_width 0.5)
			(island_removal_mode 0)
		)
		(polygon
			(pts
				(arc
					(start 176.406048 -245.785386)
					(mid 175.738028 -245.785386)
					(end 176.406048 -245.785386)
				)
			)
		)
	)
	(zone
		(layers "B.Cu" "In15.Cu")
		(hatch none 0.5)
		(connect_pads
			(clearance 0)
		)
		(min_thickness 0.25)
		(keepout
			(tracks not_allowed)
			(vias allowed)
			(pads allowed)
			(copperpour not_allowed)
			(footprints allowed)
		)
		(placement
			(enabled no)
			(sheetname "")
		)
		(fill yes
			(thermal_gap 0.5)
			(thermal_bridge_width 0.5)
			(island_removal_mode 0)
		)
		(polygon
			(pts
				(arc
					(start 89.078308 -392.429238)
					(mid 88.410288 -392.429238)
					(end 89.078308 -392.429238)
				)
			)
		)
	)
	(zone
		(layers "B.Cu" "In15.Cu")
		(hatch none 0.5)
		(connect_pads
			(clearance 0)
		)
		(min_thickness 0.25)
		(keepout
			(tracks not_allowed)
			(vias allowed)
			(pads allowed)
			(copperpour not_allowed)
			(footprints allowed)
		)
		(placement
			(enabled no)
			(sheetname "")
		)
		(fill yes
			(thermal_gap 0.5)
			(thermal_bridge_width 0.5)
			(island_removal_mode 0)
		)
		(polygon
			(pts
				(arc
					(start 342.036908 -435.489858)
					(mid 341.262716 -435.489858)
					(end 342.036908 -435.489858)
				)
			)
		)
	)
	(zone
		(layers "B.Cu" "In15.Cu")
		(hatch none 0.5)
		(connect_pads
			(clearance 0)
		)
		(min_thickness 0.25)
		(keepout
			(tracks not_allowed)
			(vias allowed)
			(pads allowed)
			(copperpour not_allowed)
			(footprints allowed)
		)
		(placement
			(enabled no)
			(sheetname "")
		)
		(fill yes
			(thermal_gap 0.5)
			(thermal_bridge_width 0.5)
			(island_removal_mode 0)
		)
		(polygon
			(pts
				(arc
					(start 373.489728 -270.036036)
					(mid 372.859808 -270.036036)
					(end 373.489728 -270.036036)
				)
			)
		)
	)
	(zone
		(layers "B.Cu" "In15.Cu")
		(hatch none 0.5)
		(connect_pads
			(clearance 0)
		)
		(min_thickness 0.25)
		(keepout
			(tracks not_allowed)
			(vias allowed)
			(pads allowed)
			(copperpour not_allowed)
			(footprints allowed)
		)
		(placement
			(enabled no)
			(sheetname "")
		)
		(fill yes
			(thermal_gap 0.5)
			(thermal_bridge_width 0.5)
			(island_removal_mode 0)
		)
		(polygon
			(pts
				(arc
					(start 374.429782 -271.656048)
					(mid 373.799862 -271.656048)
					(end 374.429782 -271.656048)
				)
			)
		)
	)
	(zone
		(layers "B.Cu" "In15.Cu")
		(hatch none 0.5)
		(connect_pads
			(clearance 0)
		)
		(min_thickness 0.25)
		(keepout
			(tracks not_allowed)
			(vias allowed)
			(pads allowed)
			(copperpour not_allowed)
			(footprints allowed)
		)
		(placement
			(enabled no)
			(sheetname "")
		)
		(fill yes
			(thermal_gap 0.5)
			(thermal_bridge_width 0.5)
			(island_removal_mode 0)
		)
		(polygon
			(pts
				(arc
					(start 335.89595 -276.516084)
					(mid 335.26603 -276.516084)
					(end 335.89595 -276.516084)
				)
			)
		)
	)
	(zone
		(layers "B.Cu" "In15.Cu")
		(hatch none 0.5)
		(connect_pads
			(clearance 0)
		)
		(min_thickness 0.25)
		(keepout
			(tracks not_allowed)
			(vias allowed)
			(pads allowed)
			(copperpour not_allowed)
			(footprints allowed)
		)
		(placement
			(enabled no)
			(sheetname "")
		)
		(fill yes
			(thermal_gap 0.5)
			(thermal_bridge_width 0.5)
			(island_removal_mode 0)
		)
		(polygon
			(pts
				(arc
					(start 337.476084 -246.104156)
					(mid 336.846164 -246.104156)
					(end 337.476084 -246.104156)
				)
			)
		)
	)
	(zone
		(layers "B.Cu" "In15.Cu")
		(hatch none 0.5)
		(connect_pads
			(clearance 0)
		)
		(min_thickness 0.25)
		(keepout
			(tracks not_allowed)
			(vias allowed)
			(pads allowed)
			(copperpour not_allowed)
			(footprints allowed)
		)
		(placement
			(enabled no)
			(sheetname "")
		)
		(fill yes
			(thermal_gap 0.5)
			(thermal_bridge_width 0.5)
			(island_removal_mode 0)
		)
		(polygon
			(pts
				(arc
					(start 321.036696 -435.489858)
					(mid 320.262504 -435.489858)
					(end 321.036696 -435.489858)
				)
			)
		)
	)
	(zone
		(layers "B.Cu" "In15.Cu")
		(hatch none 0.5)
		(connect_pads
			(clearance 0)
		)
		(min_thickness 0.25)
		(keepout
			(tracks not_allowed)
			(vias allowed)
			(pads allowed)
			(copperpour not_allowed)
			(footprints allowed)
		)
		(placement
			(enabled no)
			(sheetname "")
		)
		(fill yes
			(thermal_gap 0.5)
			(thermal_bridge_width 0.5)
			(island_removal_mode 0)
		)
		(polygon
			(pts
				(arc
					(start 420.246048 -312.084974)
					(mid 419.578028 -312.084974)
					(end 420.246048 -312.084974)
				)
			)
		)
	)
	(zone
		(layers "B.Cu" "In15.Cu")
		(hatch none 0.5)
		(connect_pads
			(clearance 0)
		)
		(min_thickness 0.25)
		(keepout
			(tracks not_allowed)
			(vias allowed)
			(pads allowed)
			(copperpour not_allowed)
			(footprints allowed)
		)
		(placement
			(enabled no)
			(sheetname "")
		)
		(fill yes
			(thermal_gap 0.5)
			(thermal_bridge_width 0.5)
			(island_removal_mode 0)
		)
		(polygon
			(pts
				(arc
					(start 339.078062 -401.674838)
					(mid 338.410042 -401.674838)
					(end 339.078062 -401.674838)
				)
			)
		)
	)
	(zone
		(layers "B.Cu" "In15.Cu")
		(hatch none 0.5)
		(connect_pads
			(clearance 0)
		)
		(min_thickness 0.25)
		(keepout
			(tracks not_allowed)
			(vias allowed)
			(pads allowed)
			(copperpour not_allowed)
			(footprints allowed)
		)
		(placement
			(enabled no)
			(sheetname "")
		)
		(fill yes
			(thermal_gap 0.5)
			(thermal_bridge_width 0.5)
			(island_removal_mode 0)
		)
		(polygon
			(pts
				(arc
					(start 376.050556 -401.674838)
					(mid 375.382536 -401.674838)
					(end 376.050556 -401.674838)
				)
			)
		)
	)
	(zone
		(layers "B.Cu" "In15.Cu")
		(hatch none 0.5)
		(connect_pads
			(clearance 0)
		)
		(min_thickness 0.25)
		(keepout
			(tracks not_allowed)
			(vias allowed)
			(pads allowed)
			(copperpour not_allowed)
			(footprints allowed)
		)
		(placement
			(enabled no)
			(sheetname "")
		)
		(fill yes
			(thermal_gap 0.5)
			(thermal_bridge_width 0.5)
			(island_removal_mode 0)
		)
		(polygon
			(pts
				(arc
					(start 135.119618 -243.674392)
					(mid 134.489698 -243.674392)
					(end 135.119618 -243.674392)
				)
			)
		)
	)
	(zone
		(layers "B.Cu" "In15.Cu")
		(hatch none 0.5)
		(connect_pads
			(clearance 0)
		)
		(min_thickness 0.25)
		(keepout
			(tracks not_allowed)
			(vias allowed)
			(pads allowed)
			(copperpour not_allowed)
			(footprints allowed)
		)
		(placement
			(enabled no)
			(sheetname "")
		)
		(fill yes
			(thermal_gap 0.5)
			(thermal_bridge_width 0.5)
			(island_removal_mode 0)
		)
		(polygon
			(pts
				(arc
					(start 88.037162 -434.48986)
					(mid 87.26297 -434.48986)
					(end 88.037162 -434.48986)
				)
			)
		)
	)
	(zone
		(layers "B.Cu" "In15.Cu")
		(hatch none 0.5)
		(connect_pads
			(clearance 0)
		)
		(min_thickness 0.25)
		(keepout
			(tracks not_allowed)
			(vias allowed)
			(pads allowed)
			(copperpour not_allowed)
			(footprints allowed)
		)
		(placement
			(enabled no)
			(sheetname "")
		)
		(fill yes
			(thermal_gap 0.5)
			(thermal_bridge_width 0.5)
			(island_removal_mode 0)
		)
		(polygon
			(pts
				(arc
					(start 386.136896 -434.48986)
					(mid 385.362704 -434.48986)
					(end 386.136896 -434.48986)
				)
			)
		)
	)
	(zone
		(layers "B.Cu" "In15.Cu")
		(hatch none 0.5)
		(connect_pads
			(clearance 0)
		)
		(min_thickness 0.25)
		(keepout
			(tracks not_allowed)
			(vias allowed)
			(pads allowed)
			(copperpour not_allowed)
			(footprints allowed)
		)
		(placement
			(enabled no)
			(sheetname "")
		)
		(fill yes
			(thermal_gap 0.5)
			(thermal_bridge_width 0.5)
			(island_removal_mode 0)
		)
		(polygon
			(pts
				(arc
					(start 136.059672 -256.634488)
					(mid 135.429752 -256.634488)
					(end 136.059672 -256.634488)
				)
			)
		)
	)
	(zone
		(layers "B.Cu" "In15.Cu")
		(hatch none 0.5)
		(connect_pads
			(clearance 0)
		)
		(min_thickness 0.25)
		(keepout
			(tracks not_allowed)
			(vias allowed)
			(pads allowed)
			(copperpour not_allowed)
			(footprints allowed)
		)
		(placement
			(enabled no)
			(sheetname "")
		)
		(fill yes
			(thermal_gap 0.5)
			(thermal_bridge_width 0.5)
			(island_removal_mode 0)
		)
		(polygon
			(pts
				(arc
					(start 84.03717 -433.289964)
					(mid 83.262978 -433.289964)
					(end 84.03717 -433.289964)
				)
			)
		)
	)
	(zone
		(layers "B.Cu" "In15.Cu")
		(hatch none 0.5)
		(connect_pads
			(clearance 0)
		)
		(min_thickness 0.25)
		(keepout
			(tracks not_allowed)
			(vias allowed)
			(pads allowed)
			(copperpour not_allowed)
			(footprints allowed)
		)
		(placement
			(enabled no)
			(sheetname "")
		)
		(fill yes
			(thermal_gap 0.5)
			(thermal_bridge_width 0.5)
			(island_removal_mode 0)
		)
		(polygon
			(pts
				(arc
					(start 337.476084 -229.904036)
					(mid 336.846164 -229.904036)
					(end 337.476084 -229.904036)
				)
			)
		)
	)
	(zone
		(layers "B.Cu" "In15.Cu")
		(hatch none 0.5)
		(connect_pads
			(clearance 0)
		)
		(min_thickness 0.25)
		(keepout
			(tracks not_allowed)
			(vias allowed)
			(pads allowed)
			(copperpour not_allowed)
			(footprints allowed)
		)
		(placement
			(enabled no)
			(sheetname "")
		)
		(fill yes
			(thermal_gap 0.5)
			(thermal_bridge_width 0.5)
			(island_removal_mode 0)
		)
		(polygon
			(pts
				(arc
					(start 300.15815 -273.835114)
					(mid 299.49013 -273.835114)
					(end 300.15815 -273.835114)
				)
			)
		)
	)
	(zone
		(layers "B.Cu" "In15.Cu")
		(hatch none 0.5)
		(connect_pads
			(clearance 0)
		)
		(min_thickness 0.25)
		(keepout
			(tracks not_allowed)
			(vias allowed)
			(pads allowed)
			(copperpour not_allowed)
			(footprints allowed)
		)
		(placement
			(enabled no)
			(sheetname "")
		)
		(fill yes
			(thermal_gap 0.5)
			(thermal_bridge_width 0.5)
			(island_removal_mode 0)
		)
		(polygon
			(pts
				(arc
					(start 420.246048 -272.984976)
					(mid 419.578028 -272.984976)
					(end 420.246048 -272.984976)
				)
			)
		)
	)
	(zone
		(layers "B.Cu" "In15.Cu")
		(hatch none 0.5)
		(connect_pads
			(clearance 0)
		)
		(min_thickness 0.25)
		(keepout
			(tracks not_allowed)
			(vias allowed)
			(pads allowed)
			(copperpour not_allowed)
			(footprints allowed)
		)
		(placement
			(enabled no)
			(sheetname "")
		)
		(fill yes
			(thermal_gap 0.5)
			(thermal_bridge_width 0.5)
			(island_removal_mode 0)
		)
		(polygon
			(pts
				(arc
					(start 296.058082 -274.684998)
					(mid 295.390062 -274.684998)
					(end 296.058082 -274.684998)
				)
			)
		)
	)
	(zone
		(layers "B.Cu" "In15.Cu")
		(hatch none 0.5)
		(connect_pads
			(clearance 0)
		)
		(min_thickness 0.25)
		(keepout
			(tracks not_allowed)
			(vias allowed)
			(pads allowed)
			(copperpour not_allowed)
			(footprints allowed)
		)
		(placement
			(enabled no)
			(sheetname "")
		)
		(fill yes
			(thermal_gap 0.5)
			(thermal_bridge_width 0.5)
			(island_removal_mode 0)
		)
		(polygon
			(pts
				(arc
					(start 120.05056 -393.292838)
					(mid 119.38254 -393.292838)
					(end 120.05056 -393.292838)
				)
			)
		)
	)
	(zone
		(layers "B.Cu" "In15.Cu")
		(hatch none 0.5)
		(connect_pads
			(clearance 0)
		)
		(min_thickness 0.25)
		(keepout
			(tracks not_allowed)
			(vias allowed)
			(pads allowed)
			(copperpour not_allowed)
			(footprints allowed)
		)
		(placement
			(enabled no)
			(sheetname "")
		)
		(fill yes
			(thermal_gap 0.5)
			(thermal_bridge_width 0.5)
			(island_removal_mode 0)
		)
		(polygon
			(pts
				(arc
					(start 117.089682 -273.276314)
					(mid 116.459762 -273.276314)
					(end 117.089682 -273.276314)
				)
			)
		)
	)
	(zone
		(layers "B.Cu" "In15.Cu")
		(hatch none 0.5)
		(connect_pads
			(clearance 0)
		)
		(min_thickness 0.25)
		(keepout
			(tracks not_allowed)
			(vias allowed)
			(pads allowed)
			(copperpour not_allowed)
			(footprints allowed)
		)
		(placement
			(enabled no)
			(sheetname "")
		)
		(fill yes
			(thermal_gap 0.5)
			(thermal_bridge_width 0.5)
			(island_removal_mode 0)
		)
		(polygon
			(pts
				(arc
					(start 176.406048 -272.135346)
					(mid 175.738028 -272.135346)
					(end 176.406048 -272.135346)
				)
			)
		)
	)
	(zone
		(layers "B.Cu" "In15.Cu")
		(hatch none 0.5)
		(connect_pads
			(clearance 0)
		)
		(min_thickness 0.25)
		(keepout
			(tracks not_allowed)
			(vias allowed)
			(pads allowed)
			(copperpour not_allowed)
			(footprints allowed)
		)
		(placement
			(enabled no)
			(sheetname "")
		)
		(fill yes
			(thermal_gap 0.5)
			(thermal_bridge_width 0.5)
			(island_removal_mode 0)
		)
		(polygon
			(pts
				(arc
					(start 52.218082 -247.485408)
					(mid 51.550062 -247.485408)
					(end 52.218082 -247.485408)
				)
			)
		)
	)
	(zone
		(layers "B.Cu" "In15.Cu")
		(hatch none 0.5)
		(connect_pads
			(clearance 0)
		)
		(min_thickness 0.25)
		(keepout
			(tracks not_allowed)
			(vias allowed)
			(pads allowed)
			(copperpour not_allowed)
			(footprints allowed)
		)
		(placement
			(enabled no)
			(sheetname "")
		)
		(fill yes
			(thermal_gap 0.5)
			(thermal_bridge_width 0.5)
			(island_removal_mode 0)
		)
		(polygon
			(pts
				(arc
					(start 87.955882 -276.516338)
					(mid 87.325962 -276.516338)
					(end 87.955882 -276.516338)
				)
			)
		)
	)
	(zone
		(layers "B.Cu" "In15.Cu")
		(hatch none 0.5)
		(connect_pads
			(clearance 0)
		)
		(min_thickness 0.25)
		(keepout
			(tracks not_allowed)
			(vias allowed)
			(pads allowed)
			(copperpour not_allowed)
			(footprints allowed)
		)
		(placement
			(enabled no)
			(sheetname "")
		)
		(fill yes
			(thermal_gap 0.5)
			(thermal_bridge_width 0.5)
			(island_removal_mode 0)
		)
		(polygon
			(pts
				(arc
					(start 401.13712 -434.289962)
					(mid 400.362928 -434.289962)
					(end 401.13712 -434.289962)
				)
			)
		)
	)
	(zone
		(layers "B.Cu" "In15.Cu")
		(hatch none 0.5)
		(connect_pads
			(clearance 0)
		)
		(min_thickness 0.25)
		(keepout
			(tracks not_allowed)
			(vias allowed)
			(pads allowed)
			(copperpour not_allowed)
			(footprints allowed)
		)
		(placement
			(enabled no)
			(sheetname "")
		)
		(fill yes
			(thermal_gap 0.5)
			(thermal_bridge_width 0.5)
			(island_removal_mode 0)
		)
		(polygon
			(pts
				(arc
					(start 420.246048 -235.585)
					(mid 419.578028 -235.585)
					(end 420.246048 -235.585)
				)
			)
		)
	)
	(zone
		(layers "B.Cu" "In15.Cu")
		(hatch none 0.5)
		(connect_pads
			(clearance 0)
		)
		(min_thickness 0.25)
		(keepout
			(tracks not_allowed)
			(vias allowed)
			(pads allowed)
			(copperpour not_allowed)
			(footprints allowed)
		)
		(placement
			(enabled no)
			(sheetname "")
		)
		(fill yes
			(thermal_gap 0.5)
			(thermal_bridge_width 0.5)
			(island_removal_mode 0)
		)
		(polygon
			(pts
				(arc
					(start 176.406048 -276.385274)
					(mid 175.738028 -276.385274)
					(end 176.406048 -276.385274)
				)
			)
		)
	)
	(zone
		(layers "B.Cu" "In15.Cu")
		(hatch none 0.5)
		(connect_pads
			(clearance 0)
		)
		(min_thickness 0.25)
		(keepout
			(tracks not_allowed)
			(vias allowed)
			(pads allowed)
			(copperpour not_allowed)
			(footprints allowed)
		)
		(placement
			(enabled no)
			(sheetname "")
		)
		(fill yes
			(thermal_gap 0.5)
			(thermal_bridge_width 0.5)
			(island_removal_mode 0)
		)
		(polygon
			(pts
				(arc
					(start 357.686102 -240.434114)
					(mid 357.056182 -240.434114)
					(end 357.686102 -240.434114)
				)
			)
		)
	)
	(zone
		(layers "B.Cu" "In15.Cu")
		(hatch none 0.5)
		(connect_pads
			(clearance 0)
		)
		(min_thickness 0.25)
		(keepout
			(tracks not_allowed)
			(vias allowed)
			(pads allowed)
			(copperpour not_allowed)
			(footprints allowed)
		)
		(placement
			(enabled no)
			(sheetname "")
		)
		(fill yes
			(thermal_gap 0.5)
			(thermal_bridge_width 0.5)
			(island_removal_mode 0)
		)
		(polygon
			(pts
				(arc
					(start 48.118014 -282.335224)
					(mid 47.449994 -282.335224)
					(end 48.118014 -282.335224)
				)
			)
		)
	)
	(zone
		(layers "B.Cu" "In15.Cu")
		(hatch none 0.5)
		(connect_pads
			(clearance 0)
		)
		(min_thickness 0.25)
		(keepout
			(tracks not_allowed)
			(vias allowed)
			(pads allowed)
			(copperpour not_allowed)
			(footprints allowed)
		)
		(placement
			(enabled no)
			(sheetname "")
		)
		(fill yes
			(thermal_gap 0.5)
			(thermal_bridge_width 0.5)
			(island_removal_mode 0)
		)
		(polygon
			(pts
				(arc
					(start 424.346116 -236.435138)
					(mid 423.678096 -236.435138)
					(end 424.346116 -236.435138)
				)
			)
		)
	)
	(zone
		(layers "B.Cu" "In15.Cu")
		(hatch none 0.5)
		(connect_pads
			(clearance 0)
		)
		(min_thickness 0.25)
		(keepout
			(tracks not_allowed)
			(vias allowed)
			(pads allowed)
			(copperpour not_allowed)
			(footprints allowed)
		)
		(placement
			(enabled no)
			(sheetname "")
		)
		(fill yes
			(thermal_gap 0.5)
			(thermal_bridge_width 0.5)
			(island_removal_mode 0)
		)
		(polygon
			(pts
				(arc
					(start 130.850386 -392.429238)
					(mid 130.182366 -392.429238)
					(end 130.850386 -392.429238)
				)
			)
		)
	)
	(zone
		(layers "B.Cu" "In15.Cu")
		(hatch none 0.5)
		(connect_pads
			(clearance 0)
		)
		(min_thickness 0.25)
		(keepout
			(tracks not_allowed)
			(vias allowed)
			(pads allowed)
			(copperpour not_allowed)
			(footprints allowed)
		)
		(placement
			(enabled no)
			(sheetname "")
		)
		(fill yes
			(thermal_gap 0.5)
			(thermal_bridge_width 0.5)
			(island_removal_mode 0)
		)
		(polygon
			(pts
				(arc
					(start 103.936038 -273.276314)
					(mid 103.306118 -273.276314)
					(end 103.936038 -273.276314)
				)
			)
		)
	)
	(zone
		(layers "B.Cu" "In15.Cu")
		(hatch none 0.5)
		(connect_pads
			(clearance 0)
		)
		(min_thickness 0.25)
		(keepout
			(tracks not_allowed)
			(vias allowed)
			(pads allowed)
			(copperpour not_allowed)
			(footprints allowed)
		)
		(placement
			(enabled no)
			(sheetname "")
		)
		(fill yes
			(thermal_gap 0.5)
			(thermal_bridge_width 0.5)
			(island_removal_mode 0)
		)
		(polygon
			(pts
				(arc
					(start 135.419592 -262.746236)
					(mid 134.789672 -262.746236)
					(end 135.419592 -262.746236)
				)
			)
		)
	)
	(zone
		(layers "B.Cu" "In15.Cu")
		(hatch none 0.5)
		(connect_pads
			(clearance 0)
		)
		(min_thickness 0.25)
		(keepout
			(tracks not_allowed)
			(vias allowed)
			(pads allowed)
			(copperpour not_allowed)
			(footprints allowed)
		)
		(placement
			(enabled no)
			(sheetname "")
		)
		(fill yes
			(thermal_gap 0.5)
			(thermal_bridge_width 0.5)
			(island_removal_mode 0)
		)
		(polygon
			(pts
				(arc
					(start 296.058082 -209.23504)
					(mid 295.390062 -209.23504)
					(end 296.058082 -209.23504)
				)
			)
		)
	)
	(zone
		(layers "B.Cu" "In15.Cu")
		(hatch none 0.5)
		(connect_pads
			(clearance 0)
		)
		(min_thickness 0.25)
		(keepout
			(tracks not_allowed)
			(vias allowed)
			(pads allowed)
			(copperpour not_allowed)
			(footprints allowed)
		)
		(placement
			(enabled no)
			(sheetname "")
		)
		(fill yes
			(thermal_gap 0.5)
			(thermal_bridge_width 0.5)
			(island_removal_mode 0)
		)
		(polygon
			(pts
				(arc
					(start 409.137104 -434.289962)
					(mid 408.362912 -434.289962)
					(end 409.137104 -434.289962)
				)
			)
		)
	)
	(zone
		(layers "B.Cu" "In15.Cu")
		(hatch none 0.5)
		(connect_pads
			(clearance 0)
		)
		(min_thickness 0.25)
		(keepout
			(tracks not_allowed)
			(vias allowed)
			(pads allowed)
			(copperpour not_allowed)
			(footprints allowed)
		)
		(placement
			(enabled no)
			(sheetname "")
		)
		(fill yes
			(thermal_gap 0.5)
			(thermal_bridge_width 0.5)
			(island_removal_mode 0)
		)
		(polygon
			(pts
				(arc
					(start 420.246048 -274.684998)
					(mid 419.578028 -274.684998)
					(end 420.246048 -274.684998)
				)
			)
		)
	)
	(zone
		(layers "B.Cu" "In15.Cu")
		(hatch none 0.5)
		(connect_pads
			(clearance 0)
		)
		(min_thickness 0.25)
		(keepout
			(tracks not_allowed)
			(vias allowed)
			(pads allowed)
			(copperpour not_allowed)
			(footprints allowed)
		)
		(placement
			(enabled no)
			(sheetname "")
		)
		(fill yes
			(thermal_gap 0.5)
			(thermal_bridge_width 0.5)
			(island_removal_mode 0)
		)
		(polygon
			(pts
				(arc
					(start 89.83599 -279.756362)
					(mid 89.20607 -279.756362)
					(end 89.83599 -279.756362)
				)
			)
		)
	)
	(zone
		(layers "B.Cu" "In15.Cu")
		(hatch none 0.5)
		(connect_pads
			(clearance 0)
		)
		(min_thickness 0.25)
		(keepout
			(tracks not_allowed)
			(vias allowed)
			(pads allowed)
			(copperpour not_allowed)
			(footprints allowed)
		)
		(placement
			(enabled no)
			(sheetname "")
		)
		(fill yes
			(thermal_gap 0.5)
			(thermal_bridge_width 0.5)
			(island_removal_mode 0)
		)
		(polygon
			(pts
				(arc
					(start 172.30598 -243.235226)
					(mid 171.63796 -243.235226)
					(end 172.30598 -243.235226)
				)
			)
		)
	)
	(zone
		(layers "B.Cu" "In15.Cu")
		(hatch none 0.5)
		(connect_pads
			(clearance 0)
		)
		(min_thickness 0.25)
		(keepout
			(tracks not_allowed)
			(vias allowed)
			(pads allowed)
			(copperpour not_allowed)
			(footprints allowed)
		)
		(placement
			(enabled no)
			(sheetname "")
		)
		(fill yes
			(thermal_gap 0.5)
			(thermal_bridge_width 0.5)
			(island_removal_mode 0)
		)
		(polygon
			(pts
				(arc
					(start 377.250452 -401.674838)
					(mid 376.582432 -401.674838)
					(end 377.250452 -401.674838)
				)
			)
		)
	)
	(zone
		(layers "B.Cu" "In15.Cu")
		(hatch none 0.5)
		(connect_pads
			(clearance 0)
		)
		(min_thickness 0.25)
		(keepout
			(tracks not_allowed)
			(vias allowed)
			(pads allowed)
			(copperpour not_allowed)
			(footprints allowed)
		)
		(placement
			(enabled no)
			(sheetname "")
		)
		(fill yes
			(thermal_gap 0.5)
			(thermal_bridge_width 0.5)
			(island_removal_mode 0)
		)
		(polygon
			(pts
				(arc
					(start 52.218082 -266.185396)
					(mid 51.550062 -266.185396)
					(end 52.218082 -266.185396)
				)
			)
		)
	)
	(zone
		(layers "B.Cu" "In15.Cu")
		(hatch none 0.5)
		(connect_pads
			(clearance 0)
		)
		(min_thickness 0.25)
		(keepout
			(tracks not_allowed)
			(vias allowed)
			(pads allowed)
			(copperpour not_allowed)
			(footprints allowed)
		)
		(placement
			(enabled no)
			(sheetname "")
		)
		(fill yes
			(thermal_gap 0.5)
			(thermal_bridge_width 0.5)
			(island_removal_mode 0)
		)
		(polygon
			(pts
				(arc
					(start 420.246048 -230.485188)
					(mid 419.578028 -230.485188)
					(end 420.246048 -230.485188)
				)
			)
		)
	)
	(zone
		(layers "B.Cu" "In15.Cu")
		(hatch none 0.5)
		(connect_pads
			(clearance 0)
		)
		(min_thickness 0.25)
		(keepout
			(tracks not_allowed)
			(vias allowed)
			(pads allowed)
			(copperpour not_allowed)
			(footprints allowed)
		)
		(placement
			(enabled no)
			(sheetname "")
		)
		(fill yes
			(thermal_gap 0.5)
			(thermal_bridge_width 0.5)
			(island_removal_mode 0)
		)
		(polygon
			(pts
				(arc
					(start 329.03668 -434.289962)
					(mid 328.262488 -434.289962)
					(end 329.03668 -434.289962)
				)
			)
		)
	)
	(zone
		(layers "B.Cu" "In15.Cu")
		(hatch none 0.5)
		(connect_pads
			(clearance 0)
		)
		(min_thickness 0.25)
		(keepout
			(tracks not_allowed)
			(vias allowed)
			(pads allowed)
			(copperpour not_allowed)
			(footprints allowed)
		)
		(placement
			(enabled no)
			(sheetname "")
		)
		(fill yes
			(thermal_gap 0.5)
			(thermal_bridge_width 0.5)
			(island_removal_mode 0)
		)
		(polygon
			(pts
				(arc
					(start 89.36609 -264.366248)
					(mid 88.73617 -264.366248)
					(end 89.36609 -264.366248)
				)
			)
		)
	)
	(zone
		(layers "B.Cu" "In15.Cu")
		(hatch none 0.5)
		(connect_pads
			(clearance 0)
		)
		(min_thickness 0.25)
		(keepout
			(tracks not_allowed)
			(vias allowed)
			(pads allowed)
			(copperpour not_allowed)
			(footprints allowed)
		)
		(placement
			(enabled no)
			(sheetname "")
		)
		(fill yes
			(thermal_gap 0.5)
			(thermal_bridge_width 0.5)
			(island_removal_mode 0)
		)
		(polygon
			(pts
				(arc
					(start 52.218082 -233.035348)
					(mid 51.550062 -233.035348)
					(end 52.218082 -233.035348)
				)
			)
		)
	)
	(zone
		(layers "B.Cu" "In15.Cu")
		(hatch none 0.5)
		(connect_pads
			(clearance 0)
		)
		(min_thickness 0.25)
		(keepout
			(tracks not_allowed)
			(vias allowed)
			(pads allowed)
			(copperpour not_allowed)
			(footprints allowed)
		)
		(placement
			(enabled no)
			(sheetname "")
		)
		(fill yes
			(thermal_gap 0.5)
			(thermal_bridge_width 0.5)
			(island_removal_mode 0)
		)
		(polygon
			(pts
				(arc
					(start 52.218082 -296.785284)
					(mid 51.550062 -296.785284)
					(end 52.218082 -296.785284)
				)
			)
		)
	)
	(zone
		(layers "B.Cu" "In15.Cu")
		(hatch none 0.5)
		(connect_pads
			(clearance 0)
		)
		(min_thickness 0.25)
		(keepout
			(tracks not_allowed)
			(vias allowed)
			(pads allowed)
			(copperpour not_allowed)
			(footprints allowed)
		)
		(placement
			(enabled no)
			(sheetname "")
		)
		(fill yes
			(thermal_gap 0.5)
			(thermal_bridge_width 0.5)
			(island_removal_mode 0)
		)
		(polygon
			(pts
				(arc
					(start 296.058082 -248.335038)
					(mid 295.390062 -248.335038)
					(end 296.058082 -248.335038)
				)
			)
		)
	)
	(zone
		(layers "B.Cu" "In15.Cu")
		(hatch none 0.5)
		(connect_pads
			(clearance 0)
		)
		(min_thickness 0.25)
		(keepout
			(tracks not_allowed)
			(vias allowed)
			(pads allowed)
			(copperpour not_allowed)
			(footprints allowed)
		)
		(placement
			(enabled no)
			(sheetname "")
		)
		(fill yes
			(thermal_gap 0.5)
			(thermal_bridge_width 0.5)
			(island_removal_mode 0)
		)
		(polygon
			(pts
				(arc
					(start 335.89595 -287.856168)
					(mid 335.26603 -287.856168)
					(end 335.89595 -287.856168)
				)
			)
		)
	)
	(zone
		(layers "B.Cu" "In15.Cu")
		(hatch none 0.5)
		(connect_pads
			(clearance 0)
		)
		(min_thickness 0.25)
		(keepout
			(tracks not_allowed)
			(vias allowed)
			(pads allowed)
			(copperpour not_allowed)
			(footprints allowed)
		)
		(placement
			(enabled no)
			(sheetname "")
		)
		(fill yes
			(thermal_gap 0.5)
			(thermal_bridge_width 0.5)
			(island_removal_mode 0)
		)
		(polygon
			(pts
				(arc
					(start 87.955882 -271.656302)
					(mid 87.325962 -271.656302)
					(end 87.955882 -271.656302)
				)
			)
		)
	)
	(zone
		(layers "B.Cu" "In15.Cu")
		(hatch none 0.5)
		(connect_pads
			(clearance 0)
		)
		(min_thickness 0.25)
		(keepout
			(tracks not_allowed)
			(vias allowed)
			(pads allowed)
			(copperpour not_allowed)
			(footprints allowed)
		)
		(placement
			(enabled no)
			(sheetname "")
		)
		(fill yes
			(thermal_gap 0.5)
			(thermal_bridge_width 0.5)
			(island_removal_mode 0)
		)
		(polygon
			(pts
				(arc
					(start 363.619796 -270.846042)
					(mid 362.989876 -270.846042)
					(end 363.619796 -270.846042)
				)
			)
		)
	)
	(zone
		(layers "B.Cu" "In15.Cu")
		(hatch none 0.5)
		(connect_pads
			(clearance 0)
		)
		(min_thickness 0.25)
		(keepout
			(tracks not_allowed)
			(vias allowed)
			(pads allowed)
			(copperpour not_allowed)
			(footprints allowed)
		)
		(placement
			(enabled no)
			(sheetname "")
		)
		(fill yes
			(thermal_gap 0.5)
			(thermal_bridge_width 0.5)
			(island_removal_mode 0)
		)
		(polygon
			(pts
				(arc
					(start 384.299714 -267.606018)
					(mid 383.669794 -267.606018)
					(end 384.299714 -267.606018)
				)
			)
		)
	)
	(zone
		(layers "B.Cu" "In15.Cu")
		(hatch none 0.5)
		(connect_pads
			(clearance 0)
		)
		(min_thickness 0.25)
		(keepout
			(tracks not_allowed)
			(vias allowed)
			(pads allowed)
			(copperpour not_allowed)
			(footprints allowed)
		)
		(placement
			(enabled no)
			(sheetname "")
		)
		(fill yes
			(thermal_gap 0.5)
			(thermal_bridge_width 0.5)
			(island_removal_mode 0)
		)
		(polygon
			(pts
				(arc
					(start 176.406048 -219.435426)
					(mid 175.738028 -219.435426)
					(end 176.406048 -219.435426)
				)
			)
		)
	)
	(zone
		(layers "B.Cu" "In15.Cu")
		(hatch none 0.5)
		(connect_pads
			(clearance 0)
		)
		(min_thickness 0.25)
		(keepout
			(tracks not_allowed)
			(vias allowed)
			(pads allowed)
			(copperpour not_allowed)
			(footprints allowed)
		)
		(placement
			(enabled no)
			(sheetname "")
		)
		(fill yes
			(thermal_gap 0.5)
			(thermal_bridge_width 0.5)
			(island_removal_mode 0)
		)
		(polygon
			(pts
				(arc
					(start 312.506106 -393.69238)
					(mid 311.876186 -393.69238)
					(end 312.506106 -393.69238)
				)
			)
		)
	)
	(zone
		(layers "B.Cu" "In15.Cu")
		(hatch none 0.5)
		(connect_pads
			(clearance 0)
		)
		(min_thickness 0.25)
		(keepout
			(tracks not_allowed)
			(vias allowed)
			(pads allowed)
			(copperpour not_allowed)
			(footprints allowed)
		)
		(placement
			(enabled no)
			(sheetname "")
		)
		(fill yes
			(thermal_gap 0.5)
			(thermal_bridge_width 0.5)
			(island_removal_mode 0)
		)
		(polygon
			(pts
				(arc
					(start 136.359646 -290.286186)
					(mid 135.729726 -290.286186)
					(end 136.359646 -290.286186)
				)
			)
		)
	)
	(zone
		(layers "B.Cu" "In15.Cu")
		(hatch none 0.5)
		(connect_pads
			(clearance 0)
		)
		(min_thickness 0.25)
		(keepout
			(tracks not_allowed)
			(vias allowed)
			(pads allowed)
			(copperpour not_allowed)
			(footprints allowed)
		)
		(placement
			(enabled no)
			(sheetname "")
		)
		(fill yes
			(thermal_gap 0.5)
			(thermal_bridge_width 0.5)
			(island_removal_mode 0)
		)
		(polygon
			(pts
				(arc
					(start 357.686102 -242.054126)
					(mid 357.056182 -242.054126)
					(end 357.686102 -242.054126)
				)
			)
		)
	)
	(zone
		(layers "B.Cu" "In15.Cu")
		(hatch none 0.5)
		(connect_pads
			(clearance 0)
		)
		(min_thickness 0.25)
		(keepout
			(tracks not_allowed)
			(vias allowed)
			(pads allowed)
			(copperpour not_allowed)
			(footprints allowed)
		)
		(placement
			(enabled no)
			(sheetname "")
		)
		(fill yes
			(thermal_gap 0.5)
			(thermal_bridge_width 0.5)
			(island_removal_mode 0)
		)
		(polygon
			(pts
				(arc
					(start 136.059672 -240.434368)
					(mid 135.429752 -240.434368)
					(end 136.059672 -240.434368)
				)
			)
		)
	)
	(zone
		(layers "B.Cu" "In15.Cu")
		(hatch none 0.5)
		(connect_pads
			(clearance 0)
		)
		(min_thickness 0.25)
		(keepout
			(tracks not_allowed)
			(vias allowed)
			(pads allowed)
			(copperpour not_allowed)
			(footprints allowed)
		)
		(placement
			(enabled no)
			(sheetname "")
		)
		(fill yes
			(thermal_gap 0.5)
			(thermal_bridge_width 0.5)
			(island_removal_mode 0)
		)
		(polygon
			(pts
				(arc
					(start 136.136888 -435.489858)
					(mid 135.362696 -435.489858)
					(end 136.136888 -435.489858)
				)
			)
		)
	)
	(zone
		(layers "B.Cu" "In15.Cu")
		(hatch none 0.5)
		(connect_pads
			(clearance 0)
		)
		(min_thickness 0.25)
		(keepout
			(tracks not_allowed)
			(vias allowed)
			(pads allowed)
			(copperpour not_allowed)
			(footprints allowed)
		)
		(placement
			(enabled no)
			(sheetname "")
		)
		(fill yes
			(thermal_gap 0.5)
			(thermal_bridge_width 0.5)
			(island_removal_mode 0)
		)
		(polygon
			(pts
				(arc
					(start 128.450594 -392.429238)
					(mid 127.782574 -392.429238)
					(end 128.450594 -392.429238)
				)
			)
		)
	)
	(zone
		(layers "B.Cu" "In15.Cu")
		(hatch none 0.5)
		(connect_pads
			(clearance 0)
		)
		(min_thickness 0.25)
		(keepout
			(tracks not_allowed)
			(vias allowed)
			(pads allowed)
			(copperpour not_allowed)
			(footprints allowed)
		)
		(placement
			(enabled no)
			(sheetname "")
		)
		(fill yes
			(thermal_gap 0.5)
			(thermal_bridge_width 0.5)
			(island_removal_mode 0)
		)
		(polygon
			(pts
				(arc
					(start 89.36609 -293.52621)
					(mid 88.73617 -293.52621)
					(end 89.36609 -293.52621)
				)
			)
		)
	)
	(zone
		(layers "B.Cu" "In15.Cu")
		(hatch none 0.5)
		(connect_pads
			(clearance 0)
		)
		(min_thickness 0.25)
		(keepout
			(tracks not_allowed)
			(vias allowed)
			(pads allowed)
			(copperpour not_allowed)
			(footprints allowed)
		)
		(placement
			(enabled no)
			(sheetname "")
		)
		(fill yes
			(thermal_gap 0.5)
			(thermal_bridge_width 0.5)
			(island_removal_mode 0)
		)
		(polygon
			(pts
				(arc
					(start 52.218082 -250.885198)
					(mid 51.550062 -250.885198)
					(end 52.218082 -250.885198)
				)
			)
		)
	)
	(zone
		(layers "B.Cu" "In15.Cu")
		(hatch none 0.5)
		(connect_pads
			(clearance 0)
		)
		(min_thickness 0.25)
		(keepout
			(tracks not_allowed)
			(vias allowed)
			(pads allowed)
			(copperpour not_allowed)
			(footprints allowed)
		)
		(placement
			(enabled no)
			(sheetname "")
		)
		(fill yes
			(thermal_gap 0.5)
			(thermal_bridge_width 0.5)
			(island_removal_mode 0)
		)
		(polygon
			(pts
				(arc
					(start 337.877912 -400.811238)
					(mid 337.209892 -400.811238)
					(end 337.877912 -400.811238)
				)
			)
		)
	)
	(zone
		(layers "B.Cu" "In15.Cu")
		(hatch none 0.5)
		(connect_pads
			(clearance 0)
		)
		(min_thickness 0.25)
		(keepout
			(tracks not_allowed)
			(vias allowed)
			(pads allowed)
			(copperpour not_allowed)
			(footprints allowed)
		)
		(placement
			(enabled no)
			(sheetname "")
		)
		(fill yes
			(thermal_gap 0.5)
			(thermal_bridge_width 0.5)
			(island_removal_mode 0)
		)
		(polygon
			(pts
				(arc
					(start 172.30598 -232.18521)
					(mid 171.63796 -232.18521)
					(end 172.30598 -232.18521)
				)
			)
		)
	)
	(zone
		(layers "B.Cu" "In15.Cu")
		(hatch none 0.5)
		(connect_pads
			(clearance 0)
		)
		(min_thickness 0.25)
		(keepout
			(tracks not_allowed)
			(vias allowed)
			(pads allowed)
			(copperpour not_allowed)
			(footprints allowed)
		)
		(placement
			(enabled no)
			(sheetname "")
		)
		(fill yes
			(thermal_gap 0.5)
			(thermal_bridge_width 0.5)
			(island_removal_mode 0)
		)
		(polygon
			(pts
				(arc
					(start 172.30598 -213.485222)
					(mid 171.63796 -213.485222)
					(end 172.30598 -213.485222)
				)
			)
		)
	)
	(zone
		(layers "B.Cu" "In15.Cu")
		(hatch none 0.5)
		(connect_pads
			(clearance 0)
		)
		(min_thickness 0.25)
		(keepout
			(tracks not_allowed)
			(vias allowed)
			(pads allowed)
			(copperpour not_allowed)
			(footprints allowed)
		)
		(placement
			(enabled no)
			(sheetname "")
		)
		(fill yes
			(thermal_gap 0.5)
			(thermal_bridge_width 0.5)
			(island_removal_mode 0)
		)
		(polygon
			(pts
				(arc
					(start 383.059686 -243.674138)
					(mid 382.429766 -243.674138)
					(end 383.059686 -243.674138)
				)
			)
		)
	)
	(zone
		(layers "B.Cu" "In15.Cu")
		(hatch none 0.5)
		(connect_pads
			(clearance 0)
		)
		(min_thickness 0.25)
		(keepout
			(tracks not_allowed)
			(vias allowed)
			(pads allowed)
			(copperpour not_allowed)
			(footprints allowed)
		)
		(placement
			(enabled no)
			(sheetname "")
		)
		(fill yes
			(thermal_gap 0.5)
			(thermal_bridge_width 0.5)
			(island_removal_mode 0)
		)
		(polygon
			(pts
				(arc
					(start 172.30598 -274.685252)
					(mid 171.63796 -274.685252)
					(end 172.30598 -274.685252)
				)
			)
		)
	)
	(zone
		(layers "B.Cu" "In15.Cu")
		(hatch none 0.5)
		(connect_pads
			(clearance 0)
		)
		(min_thickness 0.25)
		(keepout
			(tracks not_allowed)
			(vias allowed)
			(pads allowed)
			(copperpour not_allowed)
			(footprints allowed)
		)
		(placement
			(enabled no)
			(sheetname "")
		)
		(fill yes
			(thermal_gap 0.5)
			(thermal_bridge_width 0.5)
			(island_removal_mode 0)
		)
		(polygon
			(pts
				(arc
					(start 136.059672 -237.194344)
					(mid 135.429752 -237.194344)
					(end 136.059672 -237.194344)
				)
			)
		)
	)
	(zone
		(layers "B.Cu" "In15.Cu")
		(hatch none 0.5)
		(connect_pads
			(clearance 0)
		)
		(min_thickness 0.25)
		(keepout
			(tracks not_allowed)
			(vias allowed)
			(pads allowed)
			(copperpour not_allowed)
			(footprints allowed)
		)
		(placement
			(enabled no)
			(sheetname "")
		)
		(fill yes
			(thermal_gap 0.5)
			(thermal_bridge_width 0.5)
			(island_removal_mode 0)
		)
		(polygon
			(pts
				(arc
					(start 383.059686 -237.19409)
					(mid 382.429766 -237.19409)
					(end 383.059686 -237.19409)
				)
			)
		)
	)
	(zone
		(layers "B.Cu" "In15.Cu")
		(hatch none 0.5)
		(connect_pads
			(clearance 0)
		)
		(min_thickness 0.25)
		(keepout
			(tracks not_allowed)
			(vias allowed)
			(pads allowed)
			(copperpour not_allowed)
			(footprints allowed)
		)
		(placement
			(enabled no)
			(sheetname "")
		)
		(fill yes
			(thermal_gap 0.5)
			(thermal_bridge_width 0.5)
			(island_removal_mode 0)
		)
		(polygon
			(pts
				(arc
					(start 424.346116 -219.435172)
					(mid 423.678096 -219.435172)
					(end 424.346116 -219.435172)
				)
			)
		)
	)
	(zone
		(layers "B.Cu" "In15.Cu")
		(hatch none 0.5)
		(connect_pads
			(clearance 0)
		)
		(min_thickness 0.25)
		(keepout
			(tracks not_allowed)
			(vias allowed)
			(pads allowed)
			(copperpour not_allowed)
			(footprints allowed)
		)
		(placement
			(enabled no)
			(sheetname "")
		)
		(fill yes
			(thermal_gap 0.5)
			(thermal_bridge_width 0.5)
			(island_removal_mode 0)
		)
		(polygon
			(pts
				(arc
					(start 136.059672 -229.094538)
					(mid 135.429752 -229.094538)
					(end 136.059672 -229.094538)
				)
			)
		)
	)
	(zone
		(layers "B.Cu" "In15.Cu")
		(hatch none 0.5)
		(connect_pads
			(clearance 0)
		)
		(min_thickness 0.25)
		(keepout
			(tracks not_allowed)
			(vias allowed)
			(pads allowed)
			(copperpour not_allowed)
			(footprints allowed)
		)
		(placement
			(enabled no)
			(sheetname "")
		)
		(fill yes
			(thermal_gap 0.5)
			(thermal_bridge_width 0.5)
			(island_removal_mode 0)
		)
		(polygon
			(pts
				(arc
					(start 384.469894 -244.484144)
					(mid 383.839974 -244.484144)
					(end 384.469894 -244.484144)
				)
			)
		)
	)
	(zone
		(layers "B.Cu" "In15.Cu")
		(hatch none 0.5)
		(connect_pads
			(clearance 0)
		)
		(min_thickness 0.25)
		(keepout
			(tracks not_allowed)
			(vias allowed)
			(pads allowed)
			(copperpour not_allowed)
			(footprints allowed)
		)
		(placement
			(enabled no)
			(sheetname "")
		)
		(fill yes
			(thermal_gap 0.5)
			(thermal_bridge_width 0.5)
			(island_removal_mode 0)
		)
		(polygon
			(pts
				(arc
					(start 300.15815 -223.6851)
					(mid 299.49013 -223.6851)
					(end 300.15815 -223.6851)
				)
			)
		)
	)
	(zone
		(layers "B.Cu" "In15.Cu")
		(hatch none 0.5)
		(connect_pads
			(clearance 0)
		)
		(min_thickness 0.25)
		(keepout
			(tracks not_allowed)
			(vias allowed)
			(pads allowed)
			(copperpour not_allowed)
			(footprints allowed)
		)
		(placement
			(enabled no)
			(sheetname "")
		)
		(fill yes
			(thermal_gap 0.5)
			(thermal_bridge_width 0.5)
			(island_removal_mode 0)
		)
		(polygon
			(pts
				(arc
					(start 337.306158 -265.986006)
					(mid 336.676238 -265.986006)
					(end 337.306158 -265.986006)
				)
			)
		)
	)
	(zone
		(layers "B.Cu" "In15.Cu")
		(hatch none 0.5)
		(connect_pads
			(clearance 0)
		)
		(min_thickness 0.25)
		(keepout
			(tracks not_allowed)
			(vias allowed)
			(pads allowed)
			(copperpour not_allowed)
			(footprints allowed)
		)
		(placement
			(enabled no)
			(sheetname "")
		)
		(fill yes
			(thermal_gap 0.5)
			(thermal_bridge_width 0.5)
			(island_removal_mode 0)
		)
		(polygon
			(pts
				(arc
					(start 337.006184 -225.85426)
					(mid 336.376264 -225.85426)
					(end 337.006184 -225.85426)
				)
			)
		)
	)
	(zone
		(layers "B.Cu" "In15.Cu")
		(hatch none 0.5)
		(connect_pads
			(clearance 0)
		)
		(min_thickness 0.25)
		(keepout
			(tracks not_allowed)
			(vias allowed)
			(pads allowed)
			(copperpour not_allowed)
			(footprints allowed)
		)
		(placement
			(enabled no)
			(sheetname "")
		)
		(fill yes
			(thermal_gap 0.5)
			(thermal_bridge_width 0.5)
			(island_removal_mode 0)
		)
		(polygon
			(pts
				(arc
					(start 176.406048 -250.885198)
					(mid 175.738028 -250.885198)
					(end 176.406048 -250.885198)
				)
			)
		)
	)
	(zone
		(layers "B.Cu" "In15.Cu")
		(hatch none 0.5)
		(connect_pads
			(clearance 0)
		)
		(min_thickness 0.25)
		(keepout
			(tracks not_allowed)
			(vias allowed)
			(pads allowed)
			(copperpour not_allowed)
			(footprints allowed)
		)
		(placement
			(enabled no)
			(sheetname "")
		)
		(fill yes
			(thermal_gap 0.5)
			(thermal_bridge_width 0.5)
			(island_removal_mode 0)
		)
		(polygon
			(pts
				(arc
					(start 340.036912 -434.48986)
					(mid 339.26272 -434.48986)
					(end 340.036912 -434.48986)
				)
			)
		)
	)
	(zone
		(layers "B.Cu" "In15.Cu")
		(hatch none 0.5)
		(connect_pads
			(clearance 0)
		)
		(min_thickness 0.25)
		(keepout
			(tracks not_allowed)
			(vias allowed)
			(pads allowed)
			(copperpour not_allowed)
			(footprints allowed)
		)
		(placement
			(enabled no)
			(sheetname "")
		)
		(fill yes
			(thermal_gap 0.5)
			(thermal_bridge_width 0.5)
			(island_removal_mode 0)
		)
		(polygon
			(pts
				(arc
					(start 48.118014 -293.38524)
					(mid 47.449994 -293.38524)
					(end 48.118014 -293.38524)
				)
			)
		)
	)
	(zone
		(layers "B.Cu" "In15.Cu")
		(hatch none 0.5)
		(connect_pads
			(clearance 0)
		)
		(min_thickness 0.25)
		(keepout
			(tracks not_allowed)
			(vias allowed)
			(pads allowed)
			(copperpour not_allowed)
			(footprints allowed)
		)
		(placement
			(enabled no)
			(sheetname "")
		)
		(fill yes
			(thermal_gap 0.5)
			(thermal_bridge_width 0.5)
			(island_removal_mode 0)
		)
		(polygon
			(pts
				(arc
					(start 337.476084 -236.384084)
					(mid 336.846164 -236.384084)
					(end 337.476084 -236.384084)
				)
			)
		)
	)
	(zone
		(layers "B.Cu" "In15.Cu")
		(hatch none 0.5)
		(connect_pads
			(clearance 0)
		)
		(min_thickness 0.25)
		(keepout
			(tracks not_allowed)
			(vias allowed)
			(pads allowed)
			(copperpour not_allowed)
			(footprints allowed)
		)
		(placement
			(enabled no)
			(sheetname "")
		)
		(fill yes
			(thermal_gap 0.5)
			(thermal_bridge_width 0.5)
			(island_removal_mode 0)
		)
		(polygon
			(pts
				(arc
					(start 383.99974 -238.814102)
					(mid 383.36982 -238.814102)
					(end 383.99974 -238.814102)
				)
			)
		)
	)
	(zone
		(layers "B.Cu" "In15.Cu")
		(hatch none 0.5)
		(connect_pads
			(clearance 0)
		)
		(min_thickness 0.25)
		(keepout
			(tracks not_allowed)
			(vias allowed)
			(pads allowed)
			(copperpour not_allowed)
			(footprints allowed)
		)
		(placement
			(enabled no)
			(sheetname "")
		)
		(fill yes
			(thermal_gap 0.5)
			(thermal_bridge_width 0.5)
			(island_removal_mode 0)
		)
		(polygon
			(pts
				(arc
					(start 136.059672 -227.474526)
					(mid 135.429752 -227.474526)
					(end 136.059672 -227.474526)
				)
			)
		)
	)
	(zone
		(layers "B.Cu" "In15.Cu")
		(hatch none 0.5)
		(connect_pads
			(clearance 0)
		)
		(min_thickness 0.25)
		(keepout
			(tracks not_allowed)
			(vias allowed)
			(pads allowed)
			(copperpour not_allowed)
			(footprints allowed)
		)
		(placement
			(enabled no)
			(sheetname "")
		)
		(fill yes
			(thermal_gap 0.5)
			(thermal_bridge_width 0.5)
			(island_removal_mode 0)
		)
		(polygon
			(pts
				(arc
					(start 355.336094 -242.864132)
					(mid 354.706174 -242.864132)
					(end 355.336094 -242.864132)
				)
			)
		)
	)
	(zone
		(layers "B.Cu" "In15.Cu")
		(hatch none 0.5)
		(connect_pads
			(clearance 0)
		)
		(min_thickness 0.25)
		(keepout
			(tracks not_allowed)
			(vias allowed)
			(pads allowed)
			(copperpour not_allowed)
			(footprints allowed)
		)
		(placement
			(enabled no)
			(sheetname "")
		)
		(fill yes
			(thermal_gap 0.5)
			(thermal_bridge_width 0.5)
			(island_removal_mode 0)
		)
		(polygon
			(pts
				(arc
					(start 165.963854 -369.03533)
					(mid 165.295834 -369.03533)
					(end 165.963854 -369.03533)
				)
			)
		)
	)
	(zone
		(layers "B.Cu" "In15.Cu")
		(hatch none 0.5)
		(connect_pads
			(clearance 0)
		)
		(min_thickness 0.25)
		(keepout
			(tracks not_allowed)
			(vias allowed)
			(pads allowed)
			(copperpour not_allowed)
			(footprints allowed)
		)
		(placement
			(enabled no)
			(sheetname "")
		)
		(fill yes
			(thermal_gap 0.5)
			(thermal_bridge_width 0.5)
			(island_removal_mode 0)
		)
		(polygon
			(pts
				(arc
					(start 386.850382 -401.674838)
					(mid 386.182362 -401.674838)
					(end 386.850382 -401.674838)
				)
			)
		)
	)
	(zone
		(layers "B.Cu" "In15.Cu")
		(hatch none 0.5)
		(connect_pads
			(clearance 0)
		)
		(min_thickness 0.25)
		(keepout
			(tracks not_allowed)
			(vias allowed)
			(pads allowed)
			(copperpour not_allowed)
			(footprints allowed)
		)
		(placement
			(enabled no)
			(sheetname "")
		)
		(fill yes
			(thermal_gap 0.5)
			(thermal_bridge_width 0.5)
			(island_removal_mode 0)
		)
		(polygon
			(pts
				(arc
					(start 296.058082 -254.284988)
					(mid 295.390062 -254.284988)
					(end 296.058082 -254.284988)
				)
			)
		)
	)
	(zone
		(layers "B.Cu" "In15.Cu")
		(hatch none 0.5)
		(connect_pads
			(clearance 0)
		)
		(min_thickness 0.25)
		(keepout
			(tracks not_allowed)
			(vias allowed)
			(pads allowed)
			(copperpour not_allowed)
			(footprints allowed)
		)
		(placement
			(enabled no)
			(sheetname "")
		)
		(fill yes
			(thermal_gap 0.5)
			(thermal_bridge_width 0.5)
			(island_removal_mode 0)
		)
		(polygon
			(pts
				(arc
					(start 115.250468 -392.429238)
					(mid 114.582448 -392.429238)
					(end 115.250468 -392.429238)
				)
			)
		)
	)
	(zone
		(layers "B.Cu" "In15.Cu")
		(hatch none 0.5)
		(connect_pads
			(clearance 0)
		)
		(min_thickness 0.25)
		(keepout
			(tracks not_allowed)
			(vias allowed)
			(pads allowed)
			(copperpour not_allowed)
			(footprints allowed)
		)
		(placement
			(enabled no)
			(sheetname "")
		)
		(fill yes
			(thermal_gap 0.5)
			(thermal_bridge_width 0.5)
			(island_removal_mode 0)
		)
		(polygon
			(pts
				(arc
					(start 383.99974 -232.334054)
					(mid 383.36982 -232.334054)
					(end 383.99974 -232.334054)
				)
			)
		)
	)
	(zone
		(layers "B.Cu" "In15.Cu")
		(hatch none 0.5)
		(connect_pads
			(clearance 0)
		)
		(min_thickness 0.25)
		(keepout
			(tracks not_allowed)
			(vias allowed)
			(pads allowed)
			(copperpour not_allowed)
			(footprints allowed)
		)
		(placement
			(enabled no)
			(sheetname "")
		)
		(fill yes
			(thermal_gap 0.5)
			(thermal_bridge_width 0.5)
			(island_removal_mode 0)
		)
		(polygon
			(pts
				(arc
					(start 300.15815 -210.935062)
					(mid 299.49013 -210.935062)
					(end 300.15815 -210.935062)
				)
			)
		)
	)
	(zone
		(layers "B.Cu" "In15.Cu")
		(hatch none 0.5)
		(connect_pads
			(clearance 0)
		)
		(min_thickness 0.25)
		(keepout
			(tracks not_allowed)
			(vias allowed)
			(pads allowed)
			(copperpour not_allowed)
			(footprints allowed)
		)
		(placement
			(enabled no)
			(sheetname "")
		)
		(fill yes
			(thermal_gap 0.5)
			(thermal_bridge_width 0.5)
			(island_removal_mode 0)
		)
		(polygon
			(pts
				(arc
					(start 421.96385 -377.41733)
					(mid 421.29583 -377.41733)
					(end 421.96385 -377.41733)
				)
			)
		)
	)
	(zone
		(layers "B.Cu" "In15.Cu")
		(hatch none 0.5)
		(connect_pads
			(clearance 0)
		)
		(min_thickness 0.25)
		(keepout
			(tracks not_allowed)
			(vias allowed)
			(pads allowed)
			(copperpour not_allowed)
			(footprints allowed)
		)
		(placement
			(enabled no)
			(sheetname "")
		)
		(fill yes
			(thermal_gap 0.5)
			(thermal_bridge_width 0.5)
			(island_removal_mode 0)
		)
		(polygon
			(pts
				(arc
					(start 424.346116 -273.835114)
					(mid 423.678096 -273.835114)
					(end 424.346116 -273.835114)
				)
			)
		)
	)
	(zone
		(layers "B.Cu" "In15.Cu")
		(hatch none 0.5)
		(connect_pads
			(clearance 0)
		)
		(min_thickness 0.25)
		(keepout
			(tracks not_allowed)
			(vias allowed)
			(pads allowed)
			(copperpour not_allowed)
			(footprints allowed)
		)
		(placement
			(enabled no)
			(sheetname "")
		)
		(fill yes
			(thermal_gap 0.5)
			(thermal_bridge_width 0.5)
			(island_removal_mode 0)
		)
		(polygon
			(pts
				(arc
					(start 172.30598 -201.585322)
					(mid 171.63796 -201.585322)
					(end 172.30598 -201.585322)
				)
			)
		)
	)
	(zone
		(layers "B.Cu" "In15.Cu")
		(hatch none 0.5)
		(connect_pads
			(clearance 0)
		)
		(min_thickness 0.25)
		(keepout
			(tracks not_allowed)
			(vias allowed)
			(pads allowed)
			(copperpour not_allowed)
			(footprints allowed)
		)
		(placement
			(enabled no)
			(sheetname "")
		)
		(fill yes
			(thermal_gap 0.5)
			(thermal_bridge_width 0.5)
			(island_removal_mode 0)
		)
		(polygon
			(pts
				(arc
					(start 125.249686 -242.864386)
					(mid 124.619766 -242.864386)
					(end 125.249686 -242.864386)
				)
			)
		)
	)
	(zone
		(layers "B.Cu" "In15.Cu")
		(hatch none 0.5)
		(connect_pads
			(clearance 0)
		)
		(min_thickness 0.25)
		(keepout
			(tracks not_allowed)
			(vias allowed)
			(pads allowed)
			(copperpour not_allowed)
			(footprints allowed)
		)
		(placement
			(enabled no)
			(sheetname "")
		)
		(fill yes
			(thermal_gap 0.5)
			(thermal_bridge_width 0.5)
			(island_removal_mode 0)
		)
		(polygon
			(pts
				(arc
					(start 48.118014 -276.385274)
					(mid 47.449994 -276.385274)
					(end 48.118014 -276.385274)
				)
			)
		)
	)
	(zone
		(layers "B.Cu" "In15.Cu")
		(hatch none 0.5)
		(connect_pads
			(clearance 0)
		)
		(min_thickness 0.25)
		(keepout
			(tracks not_allowed)
			(vias allowed)
			(pads allowed)
			(copperpour not_allowed)
			(footprints allowed)
		)
		(placement
			(enabled no)
			(sheetname "")
		)
		(fill yes
			(thermal_gap 0.5)
			(thermal_bridge_width 0.5)
			(island_removal_mode 0)
		)
		(polygon
			(pts
				(arc
					(start 424.346116 -281.485086)
					(mid 423.678096 -281.485086)
					(end 424.346116 -281.485086)
				)
			)
		)
	)
	(zone
		(layers "B.Cu" "In15.Cu")
		(hatch none 0.5)
		(connect_pads
			(clearance 0)
		)
		(min_thickness 0.25)
		(keepout
			(tracks not_allowed)
			(vias allowed)
			(pads allowed)
			(copperpour not_allowed)
			(footprints allowed)
		)
		(placement
			(enabled no)
			(sheetname "")
		)
		(fill yes
			(thermal_gap 0.5)
			(thermal_bridge_width 0.5)
			(island_removal_mode 0)
		)
		(polygon
			(pts
				(arc
					(start 89.83599 -271.656302)
					(mid 89.20607 -271.656302)
					(end 89.83599 -271.656302)
				)
			)
		)
	)
	(zone
		(layers "B.Cu" "In15.Cu")
		(hatch none 0.5)
		(connect_pads
			(clearance 0)
		)
		(min_thickness 0.25)
		(keepout
			(tracks not_allowed)
			(vias allowed)
			(pads allowed)
			(copperpour not_allowed)
			(footprints allowed)
		)
		(placement
			(enabled no)
			(sheetname "")
		)
		(fill yes
			(thermal_gap 0.5)
			(thermal_bridge_width 0.5)
			(island_removal_mode 0)
		)
		(polygon
			(pts
				(arc
					(start 92.678504 -392.429238)
					(mid 92.010484 -392.429238)
					(end 92.678504 -392.429238)
				)
			)
		)
	)
	(zone
		(layers "B.Cu" "In15.Cu")
		(hatch none 0.5)
		(connect_pads
			(clearance 0)
		)
		(min_thickness 0.25)
		(keepout
			(tracks not_allowed)
			(vias allowed)
			(pads allowed)
			(copperpour not_allowed)
			(footprints allowed)
		)
		(placement
			(enabled no)
			(sheetname "")
		)
		(fill yes
			(thermal_gap 0.5)
			(thermal_bridge_width 0.5)
			(island_removal_mode 0)
		)
		(polygon
			(pts
				(arc
					(start 335.89595 -274.896072)
					(mid 335.26603 -274.896072)
					(end 335.89595 -274.896072)
				)
			)
		)
	)
	(zone
		(layers "B.Cu" "In15.Cu")
		(hatch none 0.5)
		(connect_pads
			(clearance 0)
		)
		(min_thickness 0.25)
		(keepout
			(tracks not_allowed)
			(vias allowed)
			(pads allowed)
			(copperpour not_allowed)
			(footprints allowed)
		)
		(placement
			(enabled no)
			(sheetname "")
		)
		(fill yes
			(thermal_gap 0.5)
			(thermal_bridge_width 0.5)
			(island_removal_mode 0)
		)
		(polygon
			(pts
				(arc
					(start 52.218082 -272.135346)
					(mid 51.550062 -272.135346)
					(end 52.218082 -272.135346)
				)
			)
		)
	)
	(zone
		(layers "B.Cu" "In15.Cu")
		(hatch none 0.5)
		(connect_pads
			(clearance 0)
		)
		(min_thickness 0.25)
		(keepout
			(tracks not_allowed)
			(vias allowed)
			(pads allowed)
			(copperpour not_allowed)
			(footprints allowed)
		)
		(placement
			(enabled no)
			(sheetname "")
		)
		(fill yes
			(thermal_gap 0.5)
			(thermal_bridge_width 0.5)
			(island_removal_mode 0)
		)
		(polygon
			(pts
				(arc
					(start 136.8298 -289.47618)
					(mid 136.19988 -289.47618)
					(end 136.8298 -289.47618)
				)
			)
		)
	)
	(zone
		(layers "B.Cu" "In15.Cu")
		(hatch none 0.5)
		(connect_pads
			(clearance 0)
		)
		(min_thickness 0.25)
		(keepout
			(tracks not_allowed)
			(vias allowed)
			(pads allowed)
			(copperpour not_allowed)
			(footprints allowed)
		)
		(placement
			(enabled no)
			(sheetname "")
		)
		(fill yes
			(thermal_gap 0.5)
			(thermal_bridge_width 0.5)
			(island_removal_mode 0)
		)
		(polygon
			(pts
				(arc
					(start 319.0367 -433.289964)
					(mid 318.262508 -433.289964)
					(end 319.0367 -433.289964)
				)
			)
		)
	)
	(zone
		(layers "B.Cu" "In15.Cu")
		(hatch none 0.5)
		(connect_pads
			(clearance 0)
		)
		(min_thickness 0.25)
		(keepout
			(tracks not_allowed)
			(vias allowed)
			(pads allowed)
			(copperpour not_allowed)
			(footprints allowed)
		)
		(placement
			(enabled no)
			(sheetname "")
		)
		(fill yes
			(thermal_gap 0.5)
			(thermal_bridge_width 0.5)
			(island_removal_mode 0)
		)
		(polygon
			(pts
				(arc
					(start 336.06613 -238.814102)
					(mid 335.43621 -238.814102)
					(end 336.06613 -238.814102)
				)
			)
		)
	)
	(zone
		(layers "B.Cu" "In15.Cu")
		(hatch none 0.5)
		(connect_pads
			(clearance 0)
		)
		(min_thickness 0.25)
		(keepout
			(tracks not_allowed)
			(vias allowed)
			(pads allowed)
			(copperpour not_allowed)
			(footprints allowed)
		)
		(placement
			(enabled no)
			(sheetname "")
		)
		(fill yes
			(thermal_gap 0.5)
			(thermal_bridge_width 0.5)
			(island_removal_mode 0)
		)
		(polygon
			(pts
				(arc
					(start 420.246048 -215.18499)
					(mid 419.578028 -215.18499)
					(end 420.246048 -215.18499)
				)
			)
		)
	)
	(zone
		(layers "B.Cu" "In15.Cu")
		(hatch none 0.5)
		(connect_pads
			(clearance 0)
		)
		(min_thickness 0.25)
		(keepout
			(tracks not_allowed)
			(vias allowed)
			(pads allowed)
			(copperpour not_allowed)
			(footprints allowed)
		)
		(placement
			(enabled no)
			(sheetname "")
		)
		(fill yes
			(thermal_gap 0.5)
			(thermal_bridge_width 0.5)
			(island_removal_mode 0)
		)
		(polygon
			(pts
				(arc
					(start 296.058082 -216.885012)
					(mid 295.390062 -216.885012)
					(end 296.058082 -216.885012)
				)
			)
		)
	)
	(zone
		(layers "B.Cu" "In15.Cu")
		(hatch none 0.5)
		(connect_pads
			(clearance 0)
		)
		(min_thickness 0.25)
		(keepout
			(tracks not_allowed)
			(vias allowed)
			(pads allowed)
			(copperpour not_allowed)
			(footprints allowed)
		)
		(placement
			(enabled no)
			(sheetname "")
		)
		(fill yes
			(thermal_gap 0.5)
			(thermal_bridge_width 0.5)
			(island_removal_mode 0)
		)
		(polygon
			(pts
				(arc
					(start 336.06613 -246.914162)
					(mid 335.43621 -246.914162)
					(end 336.06613 -246.914162)
				)
			)
		)
	)
	(zone
		(layers "B.Cu" "In15.Cu")
		(hatch none 0.5)
		(connect_pads
			(clearance 0)
		)
		(min_thickness 0.25)
		(keepout
			(tracks not_allowed)
			(vias allowed)
			(pads allowed)
			(copperpour not_allowed)
			(footprints allowed)
		)
		(placement
			(enabled no)
			(sheetname "")
		)
		(fill yes
			(thermal_gap 0.5)
			(thermal_bridge_width 0.5)
			(island_removal_mode 0)
		)
		(polygon
			(pts
				(arc
					(start 67.03695 -434.48986)
					(mid 66.262758 -434.48986)
					(end 67.03695 -434.48986)
				)
			)
		)
	)
	(zone
		(layers "B.Cu" "In15.Cu")
		(hatch none 0.5)
		(connect_pads
			(clearance 0)
		)
		(min_thickness 0.25)
		(keepout
			(tracks not_allowed)
			(vias allowed)
			(pads allowed)
			(copperpour not_allowed)
			(footprints allowed)
		)
		(placement
			(enabled no)
			(sheetname "")
		)
		(fill yes
			(thermal_gap 0.5)
			(thermal_bridge_width 0.5)
			(island_removal_mode 0)
		)
		(polygon
			(pts
				(arc
					(start 151.137112 -433.289964)
					(mid 150.36292 -433.289964)
					(end 151.137112 -433.289964)
				)
			)
		)
	)
	(zone
		(layers "B.Cu" "In15.Cu")
		(hatch none 0.5)
		(connect_pads
			(clearance 0)
		)
		(min_thickness 0.25)
		(keepout
			(tracks not_allowed)
			(vias allowed)
			(pads allowed)
			(copperpour not_allowed)
			(footprints allowed)
		)
		(placement
			(enabled no)
			(sheetname "")
		)
		(fill yes
			(thermal_gap 0.5)
			(thermal_bridge_width 0.5)
			(island_removal_mode 0)
		)
		(polygon
			(pts
				(arc
					(start 52.218082 -234.73537)
					(mid 51.550062 -234.73537)
					(end 52.218082 -234.73537)
				)
			)
		)
	)
	(zone
		(layers "B.Cu" "In15.Cu")
		(hatch none 0.5)
		(connect_pads
			(clearance 0)
		)
		(min_thickness 0.25)
		(keepout
			(tracks not_allowed)
			(vias allowed)
			(pads allowed)
			(copperpour not_allowed)
			(footprints allowed)
		)
		(placement
			(enabled no)
			(sheetname "")
		)
		(fill yes
			(thermal_gap 0.5)
			(thermal_bridge_width 0.5)
			(island_removal_mode 0)
		)
		(polygon
			(pts
				(arc
					(start 300.15815 -247.485154)
					(mid 299.49013 -247.485154)
					(end 300.15815 -247.485154)
				)
			)
		)
	)
	(zone
		(layers "B.Cu" "In15.Cu")
		(hatch none 0.5)
		(connect_pads
			(clearance 0)
		)
		(min_thickness 0.25)
		(keepout
			(tracks not_allowed)
			(vias allowed)
			(pads allowed)
			(copperpour not_allowed)
			(footprints allowed)
		)
		(placement
			(enabled no)
			(sheetname "")
		)
		(fill yes
			(thermal_gap 0.5)
			(thermal_bridge_width 0.5)
			(island_removal_mode 0)
		)
		(polygon
			(pts
				(arc
					(start 296.058082 -299.33519)
					(mid 295.390062 -299.33519)
					(end 296.058082 -299.33519)
				)
			)
		)
	)
	(zone
		(layers "B.Cu" "In15.Cu")
		(hatch none 0.5)
		(connect_pads
			(clearance 0)
		)
		(min_thickness 0.25)
		(keepout
			(tracks not_allowed)
			(vias allowed)
			(pads allowed)
			(copperpour not_allowed)
			(footprints allowed)
		)
		(placement
			(enabled no)
			(sheetname "")
		)
		(fill yes
			(thermal_gap 0.5)
			(thermal_bridge_width 0.5)
			(island_removal_mode 0)
		)
		(polygon
			(pts
				(arc
					(start 172.30598 -284.035246)
					(mid 171.63796 -284.035246)
					(end 172.30598 -284.035246)
				)
			)
		)
	)
	(zone
		(layers "B.Cu" "In15.Cu")
		(hatch none 0.5)
		(connect_pads
			(clearance 0)
		)
		(min_thickness 0.25)
		(keepout
			(tracks not_allowed)
			(vias allowed)
			(pads allowed)
			(copperpour not_allowed)
			(footprints allowed)
		)
		(placement
			(enabled no)
			(sheetname "")
		)
		(fill yes
			(thermal_gap 0.5)
			(thermal_bridge_width 0.5)
			(island_removal_mode 0)
		)
		(polygon
			(pts
				(arc
					(start 73.036938 -434.289962)
					(mid 72.262746 -434.289962)
					(end 73.036938 -434.289962)
				)
			)
		)
	)
	(zone
		(layers "B.Cu" "In15.Cu")
		(hatch none 0.5)
		(connect_pads
			(clearance 0)
		)
		(min_thickness 0.25)
		(keepout
			(tracks not_allowed)
			(vias allowed)
			(pads allowed)
			(copperpour not_allowed)
			(footprints allowed)
		)
		(placement
			(enabled no)
			(sheetname "")
		)
		(fill yes
			(thermal_gap 0.5)
			(thermal_bridge_width 0.5)
			(island_removal_mode 0)
		)
		(polygon
			(pts
				(arc
					(start 344.036904 -434.48986)
					(mid 343.262712 -434.48986)
					(end 344.036904 -434.48986)
				)
			)
		)
	)
	(zone
		(layers "B.Cu" "In15.Cu")
		(hatch none 0.5)
		(connect_pads
			(clearance 0)
		)
		(min_thickness 0.25)
		(keepout
			(tracks not_allowed)
			(vias allowed)
			(pads allowed)
			(copperpour not_allowed)
			(footprints allowed)
		)
		(placement
			(enabled no)
			(sheetname "")
		)
		(fill yes
			(thermal_gap 0.5)
			(thermal_bridge_width 0.5)
			(island_removal_mode 0)
		)
		(polygon
			(pts
				(arc
					(start 300.15815 -270.43507)
					(mid 299.49013 -270.43507)
					(end 300.15815 -270.43507)
				)
			)
		)
	)
	(zone
		(layers "B.Cu" "In15.Cu")
		(hatch none 0.5)
		(connect_pads
			(clearance 0)
		)
		(min_thickness 0.25)
		(keepout
			(tracks not_allowed)
			(vias allowed)
			(pads allowed)
			(copperpour not_allowed)
			(footprints allowed)
		)
		(placement
			(enabled no)
			(sheetname "")
		)
		(fill yes
			(thermal_gap 0.5)
			(thermal_bridge_width 0.5)
			(island_removal_mode 0)
		)
		(polygon
			(pts
				(arc
					(start 384.769868 -282.996132)
					(mid 384.139948 -282.996132)
					(end 384.769868 -282.996132)
				)
			)
		)
	)
	(zone
		(layers "B.Cu" "In15.Cu")
		(hatch none 0.5)
		(connect_pads
			(clearance 0)
		)
		(min_thickness 0.25)
		(keepout
			(tracks not_allowed)
			(vias allowed)
			(pads allowed)
			(copperpour not_allowed)
			(footprints allowed)
		)
		(placement
			(enabled no)
			(sheetname "")
		)
		(fill yes
			(thermal_gap 0.5)
			(thermal_bridge_width 0.5)
			(island_removal_mode 0)
		)
		(polygon
			(pts
				(arc
					(start 383.99974 -237.19409)
					(mid 383.36982 -237.19409)
					(end 383.99974 -237.19409)
				)
			)
		)
	)
	(zone
		(layers "B.Cu" "In15.Cu")
		(hatch none 0.5)
		(connect_pads
			(clearance 0)
		)
		(min_thickness 0.25)
		(keepout
			(tracks not_allowed)
			(vias allowed)
			(pads allowed)
			(copperpour not_allowed)
			(footprints allowed)
		)
		(placement
			(enabled no)
			(sheetname "")
		)
		(fill yes
			(thermal_gap 0.5)
			(thermal_bridge_width 0.5)
			(island_removal_mode 0)
		)
		(polygon
			(pts
				(arc
					(start 155.137104 -433.289964)
					(mid 154.362912 -433.289964)
					(end 155.137104 -433.289964)
				)
			)
		)
	)
	(zone
		(layers "B.Cu" "In15.Cu")
		(hatch none 0.5)
		(connect_pads
			(clearance 0)
		)
		(min_thickness 0.25)
		(keepout
			(tracks not_allowed)
			(vias allowed)
			(pads allowed)
			(copperpour not_allowed)
			(footprints allowed)
		)
		(placement
			(enabled no)
			(sheetname "")
		)
		(fill yes
			(thermal_gap 0.5)
			(thermal_bridge_width 0.5)
			(island_removal_mode 0)
		)
		(polygon
			(pts
				(arc
					(start 296.058082 -238.985044)
					(mid 295.390062 -238.985044)
					(end 296.058082 -238.985044)
				)
			)
		)
	)
	(zone
		(layers "B.Cu" "In15.Cu")
		(hatch none 0.5)
		(connect_pads
			(clearance 0)
		)
		(min_thickness 0.25)
		(keepout
			(tracks not_allowed)
			(vias allowed)
			(pads allowed)
			(copperpour not_allowed)
			(footprints allowed)
		)
		(placement
			(enabled no)
			(sheetname "")
		)
		(fill yes
			(thermal_gap 0.5)
			(thermal_bridge_width 0.5)
			(island_removal_mode 0)
		)
		(polygon
			(pts
				(arc
					(start 427.23943 -388.742428)
					(mid 426.57141 -388.742428)
					(end 427.23943 -388.742428)
				)
			)
		)
	)
	(zone
		(layers "B.Cu" "In15.Cu")
		(hatch none 0.5)
		(connect_pads
			(clearance 0)
		)
		(min_thickness 0.25)
		(keepout
			(tracks not_allowed)
			(vias allowed)
			(pads allowed)
			(copperpour not_allowed)
			(footprints allowed)
		)
		(placement
			(enabled no)
			(sheetname "")
		)
		(fill yes
			(thermal_gap 0.5)
			(thermal_bridge_width 0.5)
			(island_removal_mode 0)
		)
		(polygon
			(pts
				(arc
					(start 384.469894 -236.384084)
					(mid 383.839974 -236.384084)
					(end 384.469894 -236.384084)
				)
			)
		)
	)
	(zone
		(layers "B.Cu" "In15.Cu")
		(hatch none 0.5)
		(connect_pads
			(clearance 0)
		)
		(min_thickness 0.25)
		(keepout
			(tracks not_allowed)
			(vias allowed)
			(pads allowed)
			(copperpour not_allowed)
			(footprints allowed)
		)
		(placement
			(enabled no)
			(sheetname "")
		)
		(fill yes
			(thermal_gap 0.5)
			(thermal_bridge_width 0.5)
			(island_removal_mode 0)
		)
		(polygon
			(pts
				(arc
					(start 172.30598 -282.335224)
					(mid 171.63796 -282.335224)
					(end 172.30598 -282.335224)
				)
			)
		)
	)
	(zone
		(layers "B.Cu" "In15.Cu")
		(hatch none 0.5)
		(connect_pads
			(clearance 0)
		)
		(min_thickness 0.25)
		(keepout
			(tracks not_allowed)
			(vias allowed)
			(pads allowed)
			(copperpour not_allowed)
			(footprints allowed)
		)
		(placement
			(enabled no)
			(sheetname "")
		)
		(fill yes
			(thermal_gap 0.5)
			(thermal_bridge_width 0.5)
			(island_removal_mode 0)
		)
		(polygon
			(pts
				(arc
					(start 126.489714 -270.03629)
					(mid 125.859794 -270.03629)
					(end 126.489714 -270.03629)
				)
			)
		)
	)
	(zone
		(layers "B.Cu" "In15.Cu")
		(hatch none 0.5)
		(connect_pads
			(clearance 0)
		)
		(min_thickness 0.25)
		(keepout
			(tracks not_allowed)
			(vias allowed)
			(pads allowed)
			(copperpour not_allowed)
			(footprints allowed)
		)
		(placement
			(enabled no)
			(sheetname "")
		)
		(fill yes
			(thermal_gap 0.5)
			(thermal_bridge_width 0.5)
			(island_removal_mode 0)
		)
		(polygon
			(pts
				(arc
					(start 48.50638 -386.003292)
					(mid 47.87646 -386.003292)
					(end 48.50638 -386.003292)
				)
			)
		)
	)
	(zone
		(layers "B.Cu" "In15.Cu")
		(hatch none 0.5)
		(connect_pads
			(clearance 0)
		)
		(min_thickness 0.25)
		(keepout
			(tracks not_allowed)
			(vias allowed)
			(pads allowed)
			(copperpour not_allowed)
			(footprints allowed)
		)
		(placement
			(enabled no)
			(sheetname "")
		)
		(fill yes
			(thermal_gap 0.5)
			(thermal_bridge_width 0.5)
			(island_removal_mode 0)
		)
		(polygon
			(pts
				(arc
					(start 134.949692 -270.03629)
					(mid 134.319772 -270.03629)
					(end 134.949692 -270.03629)
				)
			)
		)
	)
	(zone
		(layers "B.Cu" "In15.Cu")
		(hatch none 0.5)
		(connect_pads
			(clearance 0)
		)
		(min_thickness 0.25)
		(keepout
			(tracks not_allowed)
			(vias allowed)
			(pads allowed)
			(copperpour not_allowed)
			(footprints allowed)
		)
		(placement
			(enabled no)
			(sheetname "")
		)
		(fill yes
			(thermal_gap 0.5)
			(thermal_bridge_width 0.5)
			(island_removal_mode 0)
		)
		(polygon
			(pts
				(arc
					(start 176.406048 -238.985298)
					(mid 175.738028 -238.985298)
					(end 176.406048 -238.985298)
				)
			)
		)
	)
	(zone
		(layers "B.Cu" "In15.Cu")
		(hatch none 0.5)
		(connect_pads
			(clearance 0)
		)
		(min_thickness 0.25)
		(keepout
			(tracks not_allowed)
			(vias allowed)
			(pads allowed)
			(copperpour not_allowed)
			(footprints allowed)
		)
		(placement
			(enabled no)
			(sheetname "")
		)
		(fill yes
			(thermal_gap 0.5)
			(thermal_bridge_width 0.5)
			(island_removal_mode 0)
		)
		(polygon
			(pts
				(arc
					(start 420.246048 -301.034958)
					(mid 419.578028 -301.034958)
					(end 420.246048 -301.034958)
				)
			)
		)
	)
	(zone
		(layers "B.Cu" "In15.Cu")
		(hatch none 0.5)
		(connect_pads
			(clearance 0)
		)
		(min_thickness 0.25)
		(keepout
			(tracks not_allowed)
			(vias allowed)
			(pads allowed)
			(copperpour not_allowed)
			(footprints allowed)
		)
		(placement
			(enabled no)
			(sheetname "")
		)
		(fill yes
			(thermal_gap 0.5)
			(thermal_bridge_width 0.5)
			(island_removal_mode 0)
		)
		(polygon
			(pts
				(arc
					(start 335.89595 -278.136096)
					(mid 335.26603 -278.136096)
					(end 335.89595 -278.136096)
				)
			)
		)
	)
	(zone
		(layers "B.Cu" "In15.Cu")
		(hatch none 0.5)
		(connect_pads
			(clearance 0)
		)
		(min_thickness 0.25)
		(keepout
			(tracks not_allowed)
			(vias allowed)
			(pads allowed)
			(copperpour not_allowed)
			(footprints allowed)
		)
		(placement
			(enabled no)
			(sheetname "")
		)
		(fill yes
			(thermal_gap 0.5)
			(thermal_bridge_width 0.5)
			(island_removal_mode 0)
		)
		(polygon
			(pts
				(arc
					(start 52.218082 -219.435426)
					(mid 51.550062 -219.435426)
					(end 52.218082 -219.435426)
				)
			)
		)
	)
	(zone
		(layers "B.Cu" "In15.Cu")
		(hatch none 0.5)
		(connect_pads
			(clearance 0)
		)
		(min_thickness 0.25)
		(keepout
			(tracks not_allowed)
			(vias allowed)
			(pads allowed)
			(copperpour not_allowed)
			(footprints allowed)
		)
		(placement
			(enabled no)
			(sheetname "")
		)
		(fill yes
			(thermal_gap 0.5)
			(thermal_bridge_width 0.5)
			(island_removal_mode 0)
		)
		(polygon
			(pts
				(arc
					(start 88.126062 -235.574332)
					(mid 87.496142 -235.574332)
					(end 88.126062 -235.574332)
				)
			)
		)
	)
	(zone
		(layers "B.Cu" "In15.Cu")
		(hatch none 0.5)
		(connect_pads
			(clearance 0)
		)
		(min_thickness 0.25)
		(keepout
			(tracks not_allowed)
			(vias allowed)
			(pads allowed)
			(copperpour not_allowed)
			(footprints allowed)
		)
		(placement
			(enabled no)
			(sheetname "")
		)
		(fill yes
			(thermal_gap 0.5)
			(thermal_bridge_width 0.5)
			(island_removal_mode 0)
		)
		(polygon
			(pts
				(arc
					(start 89.536016 -249.344434)
					(mid 88.906096 -249.344434)
					(end 89.536016 -249.344434)
				)
			)
		)
	)
	(zone
		(layers "B.Cu" "In15.Cu")
		(hatch none 0.5)
		(connect_pads
			(clearance 0)
		)
		(min_thickness 0.25)
		(keepout
			(tracks not_allowed)
			(vias allowed)
			(pads allowed)
			(copperpour not_allowed)
			(footprints allowed)
		)
		(placement
			(enabled no)
			(sheetname "")
		)
		(fill yes
			(thermal_gap 0.5)
			(thermal_bridge_width 0.5)
			(island_removal_mode 0)
		)
		(polygon
			(pts
				(arc
					(start 116.789708 -239.624362)
					(mid 116.159788 -239.624362)
					(end 116.789708 -239.624362)
				)
			)
		)
	)
	(zone
		(layers "B.Cu" "In15.Cu")
		(hatch none 0.5)
		(connect_pads
			(clearance 0)
		)
		(min_thickness 0.25)
		(keepout
			(tracks not_allowed)
			(vias allowed)
			(pads allowed)
			(copperpour not_allowed)
			(footprints allowed)
		)
		(placement
			(enabled no)
			(sheetname "")
		)
		(fill yes
			(thermal_gap 0.5)
			(thermal_bridge_width 0.5)
			(island_removal_mode 0)
		)
		(polygon
			(pts
				(arc
					(start 424.346116 -287.435036)
					(mid 423.678096 -287.435036)
					(end 424.346116 -287.435036)
				)
			)
		)
	)
	(zone
		(layers "B.Cu" "In15.Cu")
		(hatch none 0.5)
		(connect_pads
			(clearance 0)
		)
		(min_thickness 0.25)
		(keepout
			(tracks not_allowed)
			(vias allowed)
			(pads allowed)
			(copperpour not_allowed)
			(footprints allowed)
		)
		(placement
			(enabled no)
			(sheetname "")
		)
		(fill yes
			(thermal_gap 0.5)
			(thermal_bridge_width 0.5)
			(island_removal_mode 0)
		)
		(polygon
			(pts
				(arc
					(start 382.589786 -255.824228)
					(mid 381.959866 -255.824228)
					(end 382.589786 -255.824228)
				)
			)
		)
	)
	(zone
		(layers "B.Cu" "In15.Cu")
		(hatch none 0.5)
		(connect_pads
			(clearance 0)
		)
		(min_thickness 0.25)
		(keepout
			(tracks not_allowed)
			(vias allowed)
			(pads allowed)
			(copperpour not_allowed)
			(footprints allowed)
		)
		(placement
			(enabled no)
			(sheetname "")
		)
		(fill yes
			(thermal_gap 0.5)
			(thermal_bridge_width 0.5)
			(island_removal_mode 0)
		)
		(polygon
			(pts
				(arc
					(start 311.305956 -393.69238)
					(mid 310.676036 -393.69238)
					(end 311.305956 -393.69238)
				)
			)
		)
	)
	(zone
		(layers "B.Cu" "In15.Cu")
		(hatch none 0.5)
		(connect_pads
			(clearance 0)
		)
		(min_thickness 0.25)
		(keepout
			(tracks not_allowed)
			(vias allowed)
			(pads allowed)
			(copperpour not_allowed)
			(footprints allowed)
		)
		(placement
			(enabled no)
			(sheetname "")
		)
		(fill yes
			(thermal_gap 0.5)
			(thermal_bridge_width 0.5)
			(island_removal_mode 0)
		)
		(polygon
			(pts
				(arc
					(start 341.478108 -400.811238)
					(mid 340.810088 -400.811238)
					(end 341.478108 -400.811238)
				)
			)
		)
	)
	(zone
		(layers "B.Cu" "In15.Cu")
		(hatch none 0.5)
		(connect_pads
			(clearance 0)
		)
		(min_thickness 0.25)
		(keepout
			(tracks not_allowed)
			(vias allowed)
			(pads allowed)
			(copperpour not_allowed)
			(footprints allowed)
		)
		(placement
			(enabled no)
			(sheetname "")
		)
		(fill yes
			(thermal_gap 0.5)
			(thermal_bridge_width 0.5)
			(island_removal_mode 0)
		)
		(polygon
			(pts
				(arc
					(start 52.218082 -309.535322)
					(mid 51.550062 -309.535322)
					(end 52.218082 -309.535322)
				)
			)
		)
	)
	(zone
		(layers "B.Cu" "In15.Cu")
		(hatch none 0.5)
		(connect_pads
			(clearance 0)
		)
		(min_thickness 0.25)
		(keepout
			(tracks not_allowed)
			(vias allowed)
			(pads allowed)
			(copperpour not_allowed)
			(footprints allowed)
		)
		(placement
			(enabled no)
			(sheetname "")
		)
		(fill yes
			(thermal_gap 0.5)
			(thermal_bridge_width 0.5)
			(island_removal_mode 0)
		)
		(polygon
			(pts
				(arc
					(start 337.476084 -255.824228)
					(mid 336.846164 -255.824228)
					(end 337.476084 -255.824228)
				)
			)
		)
	)
	(zone
		(layers "B.Cu" "In15.Cu")
		(hatch none 0.5)
		(connect_pads
			(clearance 0)
		)
		(min_thickness 0.25)
		(keepout
			(tracks not_allowed)
			(vias allowed)
			(pads allowed)
			(copperpour not_allowed)
			(footprints allowed)
		)
		(placement
			(enabled no)
			(sheetname "")
		)
		(fill yes
			(thermal_gap 0.5)
			(thermal_bridge_width 0.5)
			(island_removal_mode 0)
		)
		(polygon
			(pts
				(arc
					(start 384.769868 -276.516084)
					(mid 384.139948 -276.516084)
					(end 384.769868 -276.516084)
				)
			)
		)
	)
	(zone
		(layers "B.Cu" "In15.Cu")
		(hatch none 0.5)
		(connect_pads
			(clearance 0)
		)
		(min_thickness 0.25)
		(keepout
			(tracks not_allowed)
			(vias allowed)
			(pads allowed)
			(copperpour not_allowed)
			(footprints allowed)
		)
		(placement
			(enabled no)
			(sheetname "")
		)
		(fill yes
			(thermal_gap 0.5)
			(thermal_bridge_width 0.5)
			(island_removal_mode 0)
		)
		(polygon
			(pts
				(arc
					(start 89.066116 -243.674392)
					(mid 88.436196 -243.674392)
					(end 89.066116 -243.674392)
				)
			)
		)
	)
	(zone
		(layers "B.Cu" "In15.Cu")
		(hatch none 0.5)
		(connect_pads
			(clearance 0)
		)
		(min_thickness 0.25)
		(keepout
			(tracks not_allowed)
			(vias allowed)
			(pads allowed)
			(copperpour not_allowed)
			(footprints allowed)
		)
		(placement
			(enabled no)
			(sheetname "")
		)
		(fill yes
			(thermal_gap 0.5)
			(thermal_bridge_width 0.5)
			(island_removal_mode 0)
		)
		(polygon
			(pts
				(arc
					(start 88.426036 -291.906198)
					(mid 87.796116 -291.906198)
					(end 88.426036 -291.906198)
				)
			)
		)
	)
	(zone
		(layers "B.Cu" "In15.Cu")
		(hatch none 0.5)
		(connect_pads
			(clearance 0)
		)
		(min_thickness 0.25)
		(keepout
			(tracks not_allowed)
			(vias allowed)
			(pads allowed)
			(copperpour not_allowed)
			(footprints allowed)
		)
		(placement
			(enabled no)
			(sheetname "")
		)
		(fill yes
			(thermal_gap 0.5)
			(thermal_bridge_width 0.5)
			(island_removal_mode 0)
		)
		(polygon
			(pts
				(arc
					(start 102.05593 -271.656302)
					(mid 101.42601 -271.656302)
					(end 102.05593 -271.656302)
				)
			)
		)
	)
	(zone
		(layers "B.Cu" "In15.Cu")
		(hatch none 0.5)
		(connect_pads
			(clearance 0)
		)
		(min_thickness 0.25)
		(keepout
			(tracks not_allowed)
			(vias allowed)
			(pads allowed)
			(copperpour not_allowed)
			(footprints allowed)
		)
		(placement
			(enabled no)
			(sheetname "")
		)
		(fill yes
			(thermal_gap 0.5)
			(thermal_bridge_width 0.5)
			(island_removal_mode 0)
		)
		(polygon
			(pts
				(arc
					(start 87.655908 -246.10441)
					(mid 87.025988 -246.10441)
					(end 87.655908 -246.10441)
				)
			)
		)
	)
	(zone
		(layers "B.Cu" "In15.Cu")
		(hatch none 0.5)
		(connect_pads
			(clearance 0)
		)
		(min_thickness 0.25)
		(keepout
			(tracks not_allowed)
			(vias allowed)
			(pads allowed)
			(copperpour not_allowed)
			(footprints allowed)
		)
		(placement
			(enabled no)
			(sheetname "")
		)
		(fill yes
			(thermal_gap 0.5)
			(thermal_bridge_width 0.5)
			(island_removal_mode 0)
		)
		(polygon
			(pts
				(arc
					(start 420.246048 -284.034992)
					(mid 419.578028 -284.034992)
					(end 420.246048 -284.034992)
				)
			)
		)
	)
	(zone
		(layers "B.Cu" "In15.Cu")
		(hatch none 0.5)
		(connect_pads
			(clearance 0)
		)
		(min_thickness 0.25)
		(keepout
			(tracks not_allowed)
			(vias allowed)
			(pads allowed)
			(copperpour not_allowed)
			(footprints allowed)
		)
		(placement
			(enabled no)
			(sheetname "")
		)
		(fill yes
			(thermal_gap 0.5)
			(thermal_bridge_width 0.5)
			(island_removal_mode 0)
		)
		(polygon
			(pts
				(arc
					(start 353.478084 -401.674838)
					(mid 352.810064 -401.674838)
					(end 353.478084 -401.674838)
				)
			)
		)
	)
	(zone
		(layers "B.Cu" "In15.Cu")
		(hatch none 0.5)
		(connect_pads
			(clearance 0)
		)
		(min_thickness 0.25)
		(keepout
			(tracks not_allowed)
			(vias allowed)
			(pads allowed)
			(copperpour not_allowed)
			(footprints allowed)
		)
		(placement
			(enabled no)
			(sheetname "")
		)
		(fill yes
			(thermal_gap 0.5)
			(thermal_bridge_width 0.5)
			(island_removal_mode 0)
		)
		(polygon
			(pts
				(arc
					(start 151.137112 -434.48986)
					(mid 150.36292 -434.48986)
					(end 151.137112 -434.48986)
				)
			)
		)
	)
	(zone
		(layers "B.Cu" "In15.Cu")
		(hatch none 0.5)
		(connect_pads
			(clearance 0)
		)
		(min_thickness 0.25)
		(keepout
			(tracks not_allowed)
			(vias allowed)
			(pads allowed)
			(copperpour not_allowed)
			(footprints allowed)
		)
		(placement
			(enabled no)
			(sheetname "")
		)
		(fill yes
			(thermal_gap 0.5)
			(thermal_bridge_width 0.5)
			(island_removal_mode 0)
		)
		(polygon
			(pts
				(arc
					(start 176.406048 -306.135278)
					(mid 175.738028 -306.135278)
					(end 176.406048 -306.135278)
				)
			)
		)
	)
	(zone
		(layers "B.Cu" "In15.Cu")
		(hatch none 0.5)
		(connect_pads
			(clearance 0)
		)
		(min_thickness 0.25)
		(keepout
			(tracks not_allowed)
			(vias allowed)
			(pads allowed)
			(copperpour not_allowed)
			(footprints allowed)
		)
		(placement
			(enabled no)
			(sheetname "")
		)
		(fill yes
			(thermal_gap 0.5)
			(thermal_bridge_width 0.5)
			(island_removal_mode 0)
		)
		(polygon
			(pts
				(arc
					(start 319.0367 -434.48986)
					(mid 318.262508 -434.48986)
					(end 319.0367 -434.48986)
				)
			)
		)
	)
	(zone
		(layers "B.Cu" "In15.Cu")
		(hatch none 0.5)
		(connect_pads
			(clearance 0)
		)
		(min_thickness 0.25)
		(keepout
			(tracks not_allowed)
			(vias allowed)
			(pads allowed)
			(copperpour not_allowed)
			(footprints allowed)
		)
		(placement
			(enabled no)
			(sheetname "")
		)
		(fill yes
			(thermal_gap 0.5)
			(thermal_bridge_width 0.5)
			(island_removal_mode 0)
		)
		(polygon
			(pts
				(arc
					(start 337.476084 -233.14406)
					(mid 336.846164 -233.14406)
					(end 337.476084 -233.14406)
				)
			)
		)
	)
	(zone
		(layers "B.Cu" "In15.Cu")
		(hatch none 0.5)
		(connect_pads
			(clearance 0)
		)
		(min_thickness 0.25)
		(keepout
			(tracks not_allowed)
			(vias allowed)
			(pads allowed)
			(copperpour not_allowed)
			(footprints allowed)
		)
		(placement
			(enabled no)
			(sheetname "")
		)
		(fill yes
			(thermal_gap 0.5)
			(thermal_bridge_width 0.5)
			(island_removal_mode 0)
		)
		(polygon
			(pts
				(arc
					(start 134.649718 -247.724422)
					(mid 134.019798 -247.724422)
					(end 134.649718 -247.724422)
				)
			)
		)
	)
	(zone
		(layers "B.Cu" "In15.Cu")
		(hatch none 0.5)
		(connect_pads
			(clearance 0)
		)
		(min_thickness 0.25)
		(keepout
			(tracks not_allowed)
			(vias allowed)
			(pads allowed)
			(copperpour not_allowed)
			(footprints allowed)
		)
		(placement
			(enabled no)
			(sheetname "")
		)
		(fill yes
			(thermal_gap 0.5)
			(thermal_bridge_width 0.5)
			(island_removal_mode 0)
		)
		(polygon
			(pts
				(arc
					(start 345.07805 -400.811238)
					(mid 344.41003 -400.811238)
					(end 345.07805 -400.811238)
				)
			)
		)
	)
	(zone
		(layers "B.Cu" "In15.Cu")
		(hatch none 0.5)
		(connect_pads
			(clearance 0)
		)
		(min_thickness 0.25)
		(keepout
			(tracks not_allowed)
			(vias allowed)
			(pads allowed)
			(copperpour not_allowed)
			(footprints allowed)
		)
		(placement
			(enabled no)
			(sheetname "")
		)
		(fill yes
			(thermal_gap 0.5)
			(thermal_bridge_width 0.5)
			(island_removal_mode 0)
		)
		(polygon
			(pts
				(arc
					(start 151.485854 -369.03533)
					(mid 150.817834 -369.03533)
					(end 151.485854 -369.03533)
				)
			)
		)
	)
	(zone
		(layers "B.Cu" "In15.Cu")
		(hatch none 0.5)
		(connect_pads
			(clearance 0)
		)
		(min_thickness 0.25)
		(keepout
			(tracks not_allowed)
			(vias allowed)
			(pads allowed)
			(copperpour not_allowed)
			(footprints allowed)
		)
		(placement
			(enabled no)
			(sheetname "")
		)
		(fill yes
			(thermal_gap 0.5)
			(thermal_bridge_width 0.5)
			(island_removal_mode 0)
		)
		(polygon
			(pts
				(arc
					(start 300.15815 -290.83508)
					(mid 299.49013 -290.83508)
					(end 300.15815 -290.83508)
				)
			)
		)
	)
	(zone
		(layers "B.Cu" "In15.Cu")
		(hatch none 0.5)
		(connect_pads
			(clearance 0)
		)
		(min_thickness 0.25)
		(keepout
			(tracks not_allowed)
			(vias allowed)
			(pads allowed)
			(copperpour not_allowed)
			(footprints allowed)
		)
		(placement
			(enabled no)
			(sheetname "")
		)
		(fill yes
			(thermal_gap 0.5)
			(thermal_bridge_width 0.5)
			(island_removal_mode 0)
		)
		(polygon
			(pts
				(arc
					(start 48.118014 -314.635388)
					(mid 47.449994 -314.635388)
					(end 48.118014 -314.635388)
				)
			)
		)
	)
	(zone
		(layers "B.Cu" "In15.Cu")
		(hatch none 0.5)
		(connect_pads
			(clearance 0)
		)
		(min_thickness 0.25)
		(keepout
			(tracks not_allowed)
			(vias allowed)
			(pads allowed)
			(copperpour not_allowed)
			(footprints allowed)
		)
		(placement
			(enabled no)
			(sheetname "")
		)
		(fill yes
			(thermal_gap 0.5)
			(thermal_bridge_width 0.5)
			(island_removal_mode 0)
		)
		(polygon
			(pts
				(arc
					(start 89.83599 -282.996386)
					(mid 89.20607 -282.996386)
					(end 89.83599 -282.996386)
				)
			)
		)
	)
	(zone
		(layers "B.Cu" "In15.Cu")
		(hatch none 0.5)
		(connect_pads
			(clearance 0)
		)
		(min_thickness 0.25)
		(keepout
			(tracks not_allowed)
			(vias allowed)
			(pads allowed)
			(copperpour not_allowed)
			(footprints allowed)
		)
		(placement
			(enabled no)
			(sheetname "")
		)
		(fill yes
			(thermal_gap 0.5)
			(thermal_bridge_width 0.5)
			(island_removal_mode 0)
		)
		(polygon
			(pts
				(arc
					(start 335.595976 -239.624108)
					(mid 334.966056 -239.624108)
					(end 335.595976 -239.624108)
				)
			)
		)
	)
	(zone
		(layers "B.Cu" "In15.Cu")
		(hatch none 0.5)
		(connect_pads
			(clearance 0)
		)
		(min_thickness 0.25)
		(keepout
			(tracks not_allowed)
			(vias allowed)
			(pads allowed)
			(copperpour not_allowed)
			(footprints allowed)
		)
		(placement
			(enabled no)
			(sheetname "")
		)
		(fill yes
			(thermal_gap 0.5)
			(thermal_bridge_width 0.5)
			(island_removal_mode 0)
		)
		(polygon
			(pts
				(arc
					(start 337.306158 -283.806138)
					(mid 336.676238 -283.806138)
					(end 337.306158 -283.806138)
				)
			)
		)
	)
	(zone
		(layers "B.Cu" "In15.Cu")
		(hatch none 0.5)
		(connect_pads
			(clearance 0)
		)
		(min_thickness 0.25)
		(keepout
			(tracks not_allowed)
			(vias allowed)
			(pads allowed)
			(copperpour not_allowed)
			(footprints allowed)
		)
		(placement
			(enabled no)
			(sheetname "")
		)
		(fill yes
			(thermal_gap 0.5)
			(thermal_bridge_width 0.5)
			(island_removal_mode 0)
		)
		(polygon
			(pts
				(arc
					(start 371.250464 -400.811238)
					(mid 370.582444 -400.811238)
					(end 371.250464 -400.811238)
				)
			)
		)
	)
	(zone
		(layers "B.Cu" "In15.Cu")
		(hatch none 0.5)
		(connect_pads
			(clearance 0)
		)
		(min_thickness 0.25)
		(keepout
			(tracks not_allowed)
			(vias allowed)
			(pads allowed)
			(copperpour not_allowed)
			(footprints allowed)
		)
		(placement
			(enabled no)
			(sheetname "")
		)
		(fill yes
			(thermal_gap 0.5)
			(thermal_bridge_width 0.5)
			(island_removal_mode 0)
		)
		(polygon
			(pts
				(arc
					(start 87.655908 -225.044508)
					(mid 87.025988 -225.044508)
					(end 87.655908 -225.044508)
				)
			)
		)
	)
	(zone
		(layers "B.Cu" "In15.Cu")
		(hatch none 0.5)
		(connect_pads
			(clearance 0)
		)
		(min_thickness 0.25)
		(keepout
			(tracks not_allowed)
			(vias allowed)
			(pads allowed)
			(copperpour not_allowed)
			(footprints allowed)
		)
		(placement
			(enabled no)
			(sheetname "")
		)
		(fill yes
			(thermal_gap 0.5)
			(thermal_bridge_width 0.5)
			(island_removal_mode 0)
		)
		(polygon
			(pts
				(arc
					(start 89.83599 -270.03629)
					(mid 89.20607 -270.03629)
					(end 89.83599 -270.03629)
				)
			)
		)
	)
	(zone
		(layers "B.Cu" "In15.Cu")
		(hatch none 0.5)
		(connect_pads
			(clearance 0)
		)
		(min_thickness 0.25)
		(keepout
			(tracks not_allowed)
			(vias allowed)
			(pads allowed)
			(copperpour not_allowed)
			(footprints allowed)
		)
		(placement
			(enabled no)
			(sheetname "")
		)
		(fill yes
			(thermal_gap 0.5)
			(thermal_bridge_width 0.5)
			(island_removal_mode 0)
		)
		(polygon
			(pts
				(arc
					(start 48.118014 -254.285242)
					(mid 47.449994 -254.285242)
					(end 48.118014 -254.285242)
				)
			)
		)
	)
	(zone
		(layers "B.Cu" "In15.Cu")
		(hatch none 0.5)
		(connect_pads
			(clearance 0)
		)
		(min_thickness 0.25)
		(keepout
			(tracks not_allowed)
			(vias allowed)
			(pads allowed)
			(copperpour not_allowed)
			(footprints allowed)
		)
		(placement
			(enabled no)
			(sheetname "")
		)
		(fill yes
			(thermal_gap 0.5)
			(thermal_bridge_width 0.5)
			(island_removal_mode 0)
		)
		(polygon
			(pts
				(arc
					(start 336.06613 -242.054126)
					(mid 335.43621 -242.054126)
					(end 336.06613 -242.054126)
				)
			)
		)
	)
	(zone
		(layers "B.Cu" "In15.Cu")
		(hatch none 0.5)
		(connect_pads
			(clearance 0)
		)
		(min_thickness 0.25)
		(keepout
			(tracks not_allowed)
			(vias allowed)
			(pads allowed)
			(copperpour not_allowed)
			(footprints allowed)
		)
		(placement
			(enabled no)
			(sheetname "")
		)
		(fill yes
			(thermal_gap 0.5)
			(thermal_bridge_width 0.5)
			(island_removal_mode 0)
		)
		(polygon
			(pts
				(arc
					(start 383.059686 -229.094284)
					(mid 382.429766 -229.094284)
					(end 383.059686 -229.094284)
				)
			)
		)
	)
	(zone
		(layers "B.Cu" "In15.Cu")
		(hatch none 0.5)
		(connect_pads
			(clearance 0)
		)
		(min_thickness 0.25)
		(keepout
			(tracks not_allowed)
			(vias allowed)
			(pads allowed)
			(copperpour not_allowed)
			(footprints allowed)
		)
		(placement
			(enabled no)
			(sheetname "")
		)
		(fill yes
			(thermal_gap 0.5)
			(thermal_bridge_width 0.5)
			(island_removal_mode 0)
		)
		(polygon
			(pts
				(arc
					(start 65.036954 -435.489858)
					(mid 64.262762 -435.489858)
					(end 65.036954 -435.489858)
				)
			)
		)
	)
	(zone
		(layers "B.Cu" "In15.Cu")
		(hatch none 0.5)
		(connect_pads
			(clearance 0)
		)
		(min_thickness 0.25)
		(keepout
			(tracks not_allowed)
			(vias allowed)
			(pads allowed)
			(copperpour not_allowed)
			(footprints allowed)
		)
		(placement
			(enabled no)
			(sheetname "")
		)
		(fill yes
			(thermal_gap 0.5)
			(thermal_bridge_width 0.5)
			(island_removal_mode 0)
		)
		(polygon
			(pts
				(arc
					(start 87.878412 -393.292838)
					(mid 87.210392 -393.292838)
					(end 87.878412 -393.292838)
				)
			)
		)
	)
	(zone
		(layers "B.Cu" "In15.Cu")
		(hatch none 0.5)
		(connect_pads
			(clearance 0)
		)
		(min_thickness 0.25)
		(keepout
			(tracks not_allowed)
			(vias allowed)
			(pads allowed)
			(copperpour not_allowed)
			(footprints allowed)
		)
		(placement
			(enabled no)
			(sheetname "")
		)
		(fill yes
			(thermal_gap 0.5)
			(thermal_bridge_width 0.5)
			(island_removal_mode 0)
		)
		(polygon
			(pts
				(arc
					(start 96.278192 -392.429238)
					(mid 95.610172 -392.429238)
					(end 96.278192 -392.429238)
				)
			)
		)
	)
	(zone
		(layers "B.Cu" "In15.Cu")
		(hatch none 0.5)
		(connect_pads
			(clearance 0)
		)
		(min_thickness 0.25)
		(keepout
			(tracks not_allowed)
			(vias allowed)
			(pads allowed)
			(copperpour not_allowed)
			(footprints allowed)
		)
		(placement
			(enabled no)
			(sheetname "")
		)
		(fill yes
			(thermal_gap 0.5)
			(thermal_bridge_width 0.5)
			(island_removal_mode 0)
		)
		(polygon
			(pts
				(arc
					(start 93.8784 -393.292838)
					(mid 93.21038 -393.292838)
					(end 93.8784 -393.292838)
				)
			)
		)
	)
	(zone
		(layers "B.Cu" "In15.Cu")
		(hatch none 0.5)
		(connect_pads
			(clearance 0)
		)
		(min_thickness 0.25)
		(keepout
			(tracks not_allowed)
			(vias allowed)
			(pads allowed)
			(copperpour not_allowed)
			(footprints allowed)
		)
		(placement
			(enabled no)
			(sheetname "")
		)
		(fill yes
			(thermal_gap 0.5)
			(thermal_bridge_width 0.5)
			(island_removal_mode 0)
		)
		(polygon
			(pts
				(arc
					(start 136.136888 -434.289962)
					(mid 135.362696 -434.289962)
					(end 136.136888 -434.289962)
				)
			)
		)
	)
	(zone
		(layers "B.Cu" "In15.Cu")
		(hatch none 0.5)
		(connect_pads
			(clearance 0)
		)
		(min_thickness 0.25)
		(keepout
			(tracks not_allowed)
			(vias allowed)
			(pads allowed)
			(copperpour not_allowed)
			(footprints allowed)
		)
		(placement
			(enabled no)
			(sheetname "")
		)
		(fill yes
			(thermal_gap 0.5)
			(thermal_bridge_width 0.5)
			(island_removal_mode 0)
		)
		(polygon
			(pts
				(arc
					(start 88.426036 -275.706332)
					(mid 87.796116 -275.706332)
					(end 88.426036 -275.706332)
				)
			)
		)
	)
	(zone
		(layers "B.Cu" "In15.Cu")
		(hatch none 0.5)
		(connect_pads
			(clearance 0)
		)
		(min_thickness 0.25)
		(keepout
			(tracks not_allowed)
			(vias allowed)
			(pads allowed)
			(copperpour not_allowed)
			(footprints allowed)
		)
		(placement
			(enabled no)
			(sheetname "")
		)
		(fill yes
			(thermal_gap 0.5)
			(thermal_bridge_width 0.5)
			(island_removal_mode 0)
		)
		(polygon
			(pts
				(arc
					(start 136.8298 -270.03629)
					(mid 136.19988 -270.03629)
					(end 136.8298 -270.03629)
				)
			)
		)
	)
	(zone
		(layers "B.Cu" "In15.Cu")
		(hatch none 0.5)
		(connect_pads
			(clearance 0)
		)
		(min_thickness 0.25)
		(keepout
			(tracks not_allowed)
			(vias allowed)
			(pads allowed)
			(copperpour not_allowed)
			(footprints allowed)
		)
		(placement
			(enabled no)
			(sheetname "")
		)
		(fill yes
			(thermal_gap 0.5)
			(thermal_bridge_width 0.5)
			(island_removal_mode 0)
		)
		(polygon
			(pts
				(arc
					(start 117.729762 -238.00435)
					(mid 117.099842 -238.00435)
					(end 117.729762 -238.00435)
				)
			)
		)
	)
	(zone
		(layers "B.Cu" "In15.Cu")
		(hatch none 0.5)
		(connect_pads
			(clearance 0)
		)
		(min_thickness 0.25)
		(keepout
			(tracks not_allowed)
			(vias allowed)
			(pads allowed)
			(copperpour not_allowed)
			(footprints allowed)
		)
		(placement
			(enabled no)
			(sheetname "")
		)
		(fill yes
			(thermal_gap 0.5)
			(thermal_bridge_width 0.5)
			(island_removal_mode 0)
		)
		(polygon
			(pts
				(arc
					(start 176.406048 -231.335326)
					(mid 175.738028 -231.335326)
					(end 176.406048 -231.335326)
				)
			)
		)
	)
	(zone
		(layers "B.Cu" "In15.Cu")
		(hatch none 0.5)
		(connect_pads
			(clearance 0)
		)
		(min_thickness 0.25)
		(keepout
			(tracks not_allowed)
			(vias allowed)
			(pads allowed)
			(copperpour not_allowed)
			(footprints allowed)
		)
		(placement
			(enabled no)
			(sheetname "")
		)
		(fill yes
			(thermal_gap 0.5)
			(thermal_bridge_width 0.5)
			(island_removal_mode 0)
		)
		(polygon
			(pts
				(arc
					(start 172.30598 -261.935214)
					(mid 171.63796 -261.935214)
					(end 172.30598 -261.935214)
				)
			)
		)
	)
	(zone
		(layers "B.Cu" "In15.Cu")
		(hatch none 0.5)
		(connect_pads
			(clearance 0)
		)
		(min_thickness 0.25)
		(keepout
			(tracks not_allowed)
			(vias allowed)
			(pads allowed)
			(copperpour not_allowed)
			(footprints allowed)
		)
		(placement
			(enabled no)
			(sheetname "")
		)
		(fill yes
			(thermal_gap 0.5)
			(thermal_bridge_width 0.5)
			(island_removal_mode 0)
		)
		(polygon
			(pts
				(arc
					(start 335.595976 -241.24412)
					(mid 334.966056 -241.24412)
					(end 335.595976 -241.24412)
				)
			)
		)
	)
	(zone
		(layers "B.Cu" "In15.Cu")
		(hatch none 0.5)
		(connect_pads
			(clearance 0)
		)
		(min_thickness 0.25)
		(keepout
			(tracks not_allowed)
			(vias allowed)
			(pads allowed)
			(copperpour not_allowed)
			(footprints allowed)
		)
		(placement
			(enabled no)
			(sheetname "")
		)
		(fill yes
			(thermal_gap 0.5)
			(thermal_bridge_width 0.5)
			(island_removal_mode 0)
		)
		(polygon
			(pts
				(arc
					(start 336.06613 -232.334054)
					(mid 335.43621 -232.334054)
					(end 336.06613 -232.334054)
				)
			)
		)
	)
	(zone
		(layers "B.Cu" "In15.Cu")
		(hatch none 0.5)
		(connect_pads
			(clearance 0)
		)
		(min_thickness 0.25)
		(keepout
			(tracks not_allowed)
			(vias allowed)
			(pads allowed)
			(copperpour not_allowed)
			(footprints allowed)
		)
		(placement
			(enabled no)
			(sheetname "")
		)
		(fill yes
			(thermal_gap 0.5)
			(thermal_bridge_width 0.5)
			(island_removal_mode 0)
		)
		(polygon
			(pts
				(arc
					(start 349.056198 -270.036036)
					(mid 348.426278 -270.036036)
					(end 349.056198 -270.036036)
				)
			)
		)
	)
	(zone
		(layers "B.Cu" "In15.Cu")
		(hatch none 0.5)
		(connect_pads
			(clearance 0)
		)
		(min_thickness 0.25)
		(keepout
			(tracks not_allowed)
			(vias allowed)
			(pads allowed)
			(copperpour not_allowed)
			(footprints allowed)
		)
		(placement
			(enabled no)
			(sheetname "")
		)
		(fill yes
			(thermal_gap 0.5)
			(thermal_bridge_width 0.5)
			(island_removal_mode 0)
		)
		(polygon
			(pts
				(arc
					(start 365.969804 -273.27606)
					(mid 365.339884 -273.27606)
					(end 365.969804 -273.27606)
				)
			)
		)
	)
	(zone
		(layers "B.Cu" "In15.Cu")
		(hatch none 0.5)
		(connect_pads
			(clearance 0)
		)
		(min_thickness 0.25)
		(keepout
			(tracks not_allowed)
			(vias allowed)
			(pads allowed)
			(copperpour not_allowed)
			(footprints allowed)
		)
		(placement
			(enabled no)
			(sheetname "")
		)
		(fill yes
			(thermal_gap 0.5)
			(thermal_bridge_width 0.5)
			(island_removal_mode 0)
		)
		(polygon
			(pts
				(arc
					(start 135.119618 -235.574332)
					(mid 134.489698 -235.574332)
					(end 135.119618 -235.574332)
				)
			)
		)
	)
	(zone
		(layers "B.Cu" "In15.Cu")
		(hatch none 0.5)
		(connect_pads
			(clearance 0)
		)
		(min_thickness 0.25)
		(keepout
			(tracks not_allowed)
			(vias allowed)
			(pads allowed)
			(copperpour not_allowed)
			(footprints allowed)
		)
		(placement
			(enabled no)
			(sheetname "")
		)
		(fill yes
			(thermal_gap 0.5)
			(thermal_bridge_width 0.5)
			(island_removal_mode 0)
		)
		(polygon
			(pts
				(arc
					(start 354.39604 -238.004096)
					(mid 353.76612 -238.004096)
					(end 354.39604 -238.004096)
				)
			)
		)
	)
	(zone
		(layers "B.Cu" "In15.Cu")
		(hatch none 0.5)
		(connect_pads
			(clearance 0)
		)
		(min_thickness 0.25)
		(keepout
			(tracks not_allowed)
			(vias allowed)
			(pads allowed)
			(copperpour not_allowed)
			(footprints allowed)
		)
		(placement
			(enabled no)
			(sheetname "")
		)
		(fill yes
			(thermal_gap 0.5)
			(thermal_bridge_width 0.5)
			(island_removal_mode 0)
		)
		(polygon
			(pts
				(arc
					(start 89.066116 -235.574332)
					(mid 88.436196 -235.574332)
					(end 89.066116 -235.574332)
				)
			)
		)
	)
	(zone
		(layers "B.Cu" "In15.Cu")
		(hatch none 0.5)
		(connect_pads
			(clearance 0)
		)
		(min_thickness 0.25)
		(keepout
			(tracks not_allowed)
			(vias allowed)
			(pads allowed)
			(copperpour not_allowed)
			(footprints allowed)
		)
		(placement
			(enabled no)
			(sheetname "")
		)
		(fill yes
			(thermal_gap 0.5)
			(thermal_bridge_width 0.5)
			(island_removal_mode 0)
		)
		(polygon
			(pts
				(arc
					(start 134.136892 -434.48986)
					(mid 133.3627 -434.48986)
					(end 134.136892 -434.48986)
				)
			)
		)
	)
	(zone
		(layers "B.Cu" "In15.Cu")
		(hatch none 0.5)
		(connect_pads
			(clearance 0)
		)
		(min_thickness 0.25)
		(keepout
			(tracks not_allowed)
			(vias allowed)
			(pads allowed)
			(copperpour not_allowed)
			(footprints allowed)
		)
		(placement
			(enabled no)
			(sheetname "")
		)
		(fill yes
			(thermal_gap 0.5)
			(thermal_bridge_width 0.5)
			(island_removal_mode 0)
		)
		(polygon
			(pts
				(arc
					(start 337.776058 -263.555988)
					(mid 337.146138 -263.555988)
					(end 337.776058 -263.555988)
				)
			)
		)
	)
	(zone
		(layers "B.Cu" "In15.Cu")
		(hatch none 0.5)
		(connect_pads
			(clearance 0)
		)
		(min_thickness 0.25)
		(keepout
			(tracks not_allowed)
			(vias allowed)
			(pads allowed)
			(copperpour not_allowed)
			(footprints allowed)
		)
		(placement
			(enabled no)
			(sheetname "")
		)
		(fill yes
			(thermal_gap 0.5)
			(thermal_bridge_width 0.5)
			(island_removal_mode 0)
		)
		(polygon
			(pts
				(arc
					(start 368.789712 -273.27606)
					(mid 368.159792 -273.27606)
					(end 368.789712 -273.27606)
				)
			)
		)
	)
	(zone
		(layers "B.Cu" "In15.Cu")
		(hatch none 0.5)
		(connect_pads
			(clearance 0)
		)
		(min_thickness 0.25)
		(keepout
			(tracks not_allowed)
			(vias allowed)
			(pads allowed)
			(copperpour not_allowed)
			(footprints allowed)
		)
		(placement
			(enabled no)
			(sheetname "")
		)
		(fill yes
			(thermal_gap 0.5)
			(thermal_bridge_width 0.5)
			(island_removal_mode 0)
		)
		(polygon
			(pts
				(arc
					(start 420.246048 -241.53495)
					(mid 419.578028 -241.53495)
					(end 420.246048 -241.53495)
				)
			)
		)
	)
	(zone
		(layers "B.Cu" "In15.Cu")
		(hatch none 0.5)
		(connect_pads
			(clearance 0)
		)
		(min_thickness 0.25)
		(keepout
			(tracks not_allowed)
			(vias allowed)
			(pads allowed)
			(copperpour not_allowed)
			(footprints allowed)
		)
		(placement
			(enabled no)
			(sheetname "")
		)
		(fill yes
			(thermal_gap 0.5)
			(thermal_bridge_width 0.5)
			(island_removal_mode 0)
		)
		(polygon
			(pts
				(arc
					(start 89.066116 -240.434368)
					(mid 88.436196 -240.434368)
					(end 89.066116 -240.434368)
				)
			)
		)
	)
	(zone
		(layers "B.Cu" "In15.Cu")
		(hatch none 0.5)
		(connect_pads
			(clearance 0)
		)
		(min_thickness 0.25)
		(keepout
			(tracks not_allowed)
			(vias allowed)
			(pads allowed)
			(copperpour not_allowed)
			(footprints allowed)
		)
		(placement
			(enabled no)
			(sheetname "")
		)
		(fill yes
			(thermal_gap 0.5)
			(thermal_bridge_width 0.5)
			(island_removal_mode 0)
		)
		(polygon
			(pts
				(arc
					(start 384.469894 -250.964192)
					(mid 383.839974 -250.964192)
					(end 384.469894 -250.964192)
				)
			)
		)
	)
	(zone
		(layers "B.Cu" "In15.Cu")
		(hatch none 0.5)
		(connect_pads
			(clearance 0)
		)
		(min_thickness 0.25)
		(keepout
			(tracks not_allowed)
			(vias allowed)
			(pads allowed)
			(copperpour not_allowed)
			(footprints allowed)
		)
		(placement
			(enabled no)
			(sheetname "")
		)
		(fill yes
			(thermal_gap 0.5)
			(thermal_bridge_width 0.5)
			(island_removal_mode 0)
		)
		(polygon
			(pts
				(arc
					(start 136.359646 -277.326344)
					(mid 135.729726 -277.326344)
					(end 136.359646 -277.326344)
				)
			)
		)
	)
	(zone
		(layers "B.Cu" "In15.Cu")
		(hatch none 0.5)
		(connect_pads
			(clearance 0)
		)
		(min_thickness 0.25)
		(keepout
			(tracks not_allowed)
			(vias allowed)
			(pads allowed)
			(copperpour not_allowed)
			(footprints allowed)
		)
		(placement
			(enabled no)
			(sheetname "")
		)
		(fill yes
			(thermal_gap 0.5)
			(thermal_bridge_width 0.5)
			(island_removal_mode 0)
		)
		(polygon
			(pts
				(arc
					(start 48.118014 -305.285394)
					(mid 47.449994 -305.285394)
					(end 48.118014 -305.285394)
				)
			)
		)
	)
	(zone
		(layers "B.Cu" "In15.Cu")
		(hatch none 0.5)
		(connect_pads
			(clearance 0)
		)
		(min_thickness 0.25)
		(keepout
			(tracks not_allowed)
			(vias allowed)
			(pads allowed)
			(copperpour not_allowed)
			(footprints allowed)
		)
		(placement
			(enabled no)
			(sheetname "")
		)
		(fill yes
			(thermal_gap 0.5)
			(thermal_bridge_width 0.5)
			(island_removal_mode 0)
		)
		(polygon
			(pts
				(arc
					(start 424.50385 -377.41733)
					(mid 423.83583 -377.41733)
					(end 424.50385 -377.41733)
				)
			)
		)
	)
	(zone
		(layers "B.Cu" "In15.Cu")
		(hatch none 0.5)
		(connect_pads
			(clearance 0)
		)
		(min_thickness 0.25)
		(keepout
			(tracks not_allowed)
			(vias allowed)
			(pads allowed)
			(copperpour not_allowed)
			(footprints allowed)
		)
		(placement
			(enabled no)
			(sheetname "")
		)
		(fill yes
			(thermal_gap 0.5)
			(thermal_bridge_width 0.5)
			(island_removal_mode 0)
		)
		(polygon
			(pts
				(arc
					(start 176.406048 -292.535356)
					(mid 175.738028 -292.535356)
					(end 176.406048 -292.535356)
				)
			)
		)
	)
	(zone
		(layers "B.Cu" "In15.Cu")
		(hatch none 0.5)
		(connect_pads
			(clearance 0)
		)
		(min_thickness 0.25)
		(keepout
			(tracks not_allowed)
			(vias allowed)
			(pads allowed)
			(copperpour not_allowed)
			(footprints allowed)
		)
		(placement
			(enabled no)
			(sheetname "")
		)
		(fill yes
			(thermal_gap 0.5)
			(thermal_bridge_width 0.5)
			(island_removal_mode 0)
		)
		(polygon
			(pts
				(arc
					(start 134.649718 -255.824482)
					(mid 134.019798 -255.824482)
					(end 134.649718 -255.824482)
				)
			)
		)
	)
	(zone
		(layers "B.Cu" "In15.Cu")
		(hatch none 0.5)
		(connect_pads
			(clearance 0)
		)
		(min_thickness 0.25)
		(keepout
			(tracks not_allowed)
			(vias allowed)
			(pads allowed)
			(copperpour not_allowed)
			(footprints allowed)
		)
		(placement
			(enabled no)
			(sheetname "")
		)
		(fill yes
			(thermal_gap 0.5)
			(thermal_bridge_width 0.5)
			(island_removal_mode 0)
		)
		(polygon
			(pts
				(arc
					(start 420.246048 -310.384952)
					(mid 419.578028 -310.384952)
					(end 420.246048 -310.384952)
				)
			)
		)
	)
	(zone
		(layers "B.Cu" "In15.Cu")
		(hatch none 0.5)
		(connect_pads
			(clearance 0)
		)
		(min_thickness 0.25)
		(keepout
			(tracks not_allowed)
			(vias allowed)
			(pads allowed)
			(copperpour not_allowed)
			(footprints allowed)
		)
		(placement
			(enabled no)
			(sheetname "")
		)
		(fill yes
			(thermal_gap 0.5)
			(thermal_bridge_width 0.5)
			(island_removal_mode 0)
		)
		(polygon
			(pts
				(arc
					(start 420.246048 -280.634948)
					(mid 419.578028 -280.634948)
					(end 420.246048 -280.634948)
				)
			)
		)
	)
	(zone
		(layers "B.Cu" "In15.Cu")
		(hatch none 0.5)
		(connect_pads
			(clearance 0)
		)
		(min_thickness 0.25)
		(keepout
			(tracks not_allowed)
			(vias allowed)
			(pads allowed)
			(copperpour not_allowed)
			(footprints allowed)
		)
		(placement
			(enabled no)
			(sheetname "")
		)
		(fill yes
			(thermal_gap 0.5)
			(thermal_bridge_width 0.5)
			(island_removal_mode 0)
		)
		(polygon
			(pts
				(arc
					(start 176.406048 -208.38541)
					(mid 175.738028 -208.38541)
					(end 176.406048 -208.38541)
				)
			)
		)
	)
	(zone
		(layers "B.Cu" "In15.Cu")
		(hatch none 0.5)
		(connect_pads
			(clearance 0)
		)
		(min_thickness 0.25)
		(keepout
			(tracks not_allowed)
			(vias allowed)
			(pads allowed)
			(copperpour not_allowed)
			(footprints allowed)
		)
		(placement
			(enabled no)
			(sheetname "")
		)
		(fill yes
			(thermal_gap 0.5)
			(thermal_bridge_width 0.5)
			(island_removal_mode 0)
		)
		(polygon
			(pts
				(arc
					(start 367.849658 -271.656048)
					(mid 367.219738 -271.656048)
					(end 367.849658 -271.656048)
				)
			)
		)
	)
	(zone
		(layers "B.Cu" "In15.Cu")
		(hatch none 0.5)
		(connect_pads
			(clearance 0)
		)
		(min_thickness 0.25)
		(keepout
			(tracks not_allowed)
			(vias allowed)
			(pads allowed)
			(copperpour not_allowed)
			(footprints allowed)
		)
		(placement
			(enabled no)
			(sheetname "")
		)
		(fill yes
			(thermal_gap 0.5)
			(thermal_bridge_width 0.5)
			(island_removal_mode 0)
		)
		(polygon
			(pts
				(arc
					(start 337.476084 -252.584204)
					(mid 336.846164 -252.584204)
					(end 337.476084 -252.584204)
				)
			)
		)
	)
	(zone
		(layers "B.Cu" "In15.Cu")
		(hatch none 0.5)
		(connect_pads
			(clearance 0)
		)
		(min_thickness 0.25)
		(keepout
			(tracks not_allowed)
			(vias allowed)
			(pads allowed)
			(copperpour not_allowed)
			(footprints allowed)
		)
		(placement
			(enabled no)
			(sheetname "")
		)
		(fill yes
			(thermal_gap 0.5)
			(thermal_bridge_width 0.5)
			(island_removal_mode 0)
		)
		(polygon
			(pts
				(arc
					(start 67.03695 -433.289964)
					(mid 66.262758 -433.289964)
					(end 67.03695 -433.289964)
				)
			)
		)
	)
	(zone
		(layers "B.Cu" "In15.Cu")
		(hatch none 0.5)
		(connect_pads
			(clearance 0)
		)
		(min_thickness 0.25)
		(keepout
			(tracks not_allowed)
			(vias allowed)
			(pads allowed)
			(copperpour not_allowed)
			(footprints allowed)
		)
		(placement
			(enabled no)
			(sheetname "")
		)
		(fill yes
			(thermal_gap 0.5)
			(thermal_bridge_width 0.5)
			(island_removal_mode 0)
		)
		(polygon
			(pts
				(arc
					(start 126.18974 -242.864386)
					(mid 125.55982 -242.864386)
					(end 126.18974 -242.864386)
				)
			)
		)
	)
	(zone
		(layers "B.Cu" "In15.Cu")
		(hatch none 0.5)
		(connect_pads
			(clearance 0)
		)
		(min_thickness 0.25)
		(keepout
			(tracks not_allowed)
			(vias allowed)
			(pads allowed)
			(copperpour not_allowed)
			(footprints allowed)
		)
		(placement
			(enabled no)
			(sheetname "")
		)
		(fill yes
			(thermal_gap 0.5)
			(thermal_bridge_width 0.5)
			(island_removal_mode 0)
		)
		(polygon
			(pts
				(arc
					(start 335.595976 -254.204216)
					(mid 334.966056 -254.204216)
					(end 335.595976 -254.204216)
				)
			)
		)
	)
	(zone
		(layers "B.Cu" "In15.Cu")
		(hatch none 0.5)
		(connect_pads
			(clearance 0)
		)
		(min_thickness 0.25)
		(keepout
			(tracks not_allowed)
			(vias allowed)
			(pads allowed)
			(copperpour not_allowed)
			(footprints allowed)
		)
		(placement
			(enabled no)
			(sheetname "")
		)
		(fill yes
			(thermal_gap 0.5)
			(thermal_bridge_width 0.5)
			(island_removal_mode 0)
		)
		(polygon
			(pts
				(arc
					(start 52.218082 -304.435256)
					(mid 51.550062 -304.435256)
					(end 52.218082 -304.435256)
				)
			)
		)
	)
	(zone
		(layers "B.Cu" "In15.Cu")
		(hatch none 0.5)
		(connect_pads
			(clearance 0)
		)
		(min_thickness 0.25)
		(keepout
			(tracks not_allowed)
			(vias allowed)
			(pads allowed)
			(copperpour not_allowed)
			(footprints allowed)
		)
		(placement
			(enabled no)
			(sheetname "")
		)
		(fill yes
			(thermal_gap 0.5)
			(thermal_bridge_width 0.5)
			(island_removal_mode 0)
		)
		(polygon
			(pts
				(arc
					(start 384.299714 -282.186126)
					(mid 383.669794 -282.186126)
					(end 384.299714 -282.186126)
				)
			)
		)
	)
	(zone
		(layers "B.Cu" "In15.Cu")
		(hatch none 0.5)
		(connect_pads
			(clearance 0)
		)
		(min_thickness 0.25)
		(keepout
			(tracks not_allowed)
			(vias allowed)
			(pads allowed)
			(copperpour not_allowed)
			(footprints allowed)
		)
		(placement
			(enabled no)
			(sheetname "")
		)
		(fill yes
			(thermal_gap 0.5)
			(thermal_bridge_width 0.5)
			(island_removal_mode 0)
		)
		(polygon
			(pts
				(arc
					(start 336.366104 -274.086066)
					(mid 335.736184 -274.086066)
					(end 336.366104 -274.086066)
				)
			)
		)
	)
	(zone
		(layers "B.Cu" "In15.Cu")
		(hatch none 0.5)
		(connect_pads
			(clearance 0)
		)
		(min_thickness 0.25)
		(keepout
			(tracks not_allowed)
			(vias allowed)
			(pads allowed)
			(copperpour not_allowed)
			(footprints allowed)
		)
		(placement
			(enabled no)
			(sheetname "")
		)
		(fill yes
			(thermal_gap 0.5)
			(thermal_bridge_width 0.5)
			(island_removal_mode 0)
		)
		(polygon
			(pts
				(arc
					(start 424.346116 -203.28509)
					(mid 423.678096 -203.28509)
					(end 424.346116 -203.28509)
				)
			)
		)
	)
	(zone
		(layers "B.Cu" "In15.Cu")
		(hatch none 0.5)
		(connect_pads
			(clearance 0)
		)
		(min_thickness 0.25)
		(keepout
			(tracks not_allowed)
			(vias allowed)
			(pads allowed)
			(copperpour not_allowed)
			(footprints allowed)
		)
		(placement
			(enabled no)
			(sheetname "")
		)
		(fill yes
			(thermal_gap 0.5)
			(thermal_bridge_width 0.5)
			(island_removal_mode 0)
		)
		(polygon
			(pts
				(arc
					(start 300.15815 -238.13516)
					(mid 299.49013 -238.13516)
					(end 300.15815 -238.13516)
				)
			)
		)
	)
	(zone
		(layers "B.Cu" "In15.Cu")
		(hatch none 0.5)
		(connect_pads
			(clearance 0)
		)
		(min_thickness 0.25)
		(keepout
			(tracks not_allowed)
			(vias allowed)
			(pads allowed)
			(copperpour not_allowed)
			(footprints allowed)
		)
		(placement
			(enabled no)
			(sheetname "")
		)
		(fill yes
			(thermal_gap 0.5)
			(thermal_bridge_width 0.5)
			(island_removal_mode 0)
		)
		(polygon
			(pts
				(arc
					(start 172.30598 -238.985298)
					(mid 171.63796 -238.985298)
					(end 172.30598 -238.985298)
				)
			)
		)
	)
	(zone
		(layers "B.Cu" "In15.Cu")
		(hatch none 0.5)
		(connect_pads
			(clearance 0)
		)
		(min_thickness 0.25)
		(keepout
			(tracks not_allowed)
			(vias allowed)
			(pads allowed)
			(copperpour not_allowed)
			(footprints allowed)
		)
		(placement
			(enabled no)
			(sheetname "")
		)
		(fill yes
			(thermal_gap 0.5)
			(thermal_bridge_width 0.5)
			(island_removal_mode 0)
		)
		(polygon
			(pts
				(arc
					(start 341.478108 -401.674838)
					(mid 340.810088 -401.674838)
					(end 341.478108 -401.674838)
				)
			)
		)
	)
	(zone
		(layers "B.Cu" "In15.Cu")
		(hatch none 0.5)
		(connect_pads
			(clearance 0)
		)
		(min_thickness 0.25)
		(keepout
			(tracks not_allowed)
			(vias allowed)
			(pads allowed)
			(copperpour not_allowed)
			(footprints allowed)
		)
		(placement
			(enabled no)
			(sheetname "")
		)
		(fill yes
			(thermal_gap 0.5)
			(thermal_bridge_width 0.5)
			(island_removal_mode 0)
		)
		(polygon
			(pts
				(arc
					(start 86.678262 -393.292838)
					(mid 86.010242 -393.292838)
					(end 86.678262 -393.292838)
				)
			)
		)
	)
	(zone
		(layers "B.Cu" "In15.Cu")
		(hatch none 0.5)
		(connect_pads
			(clearance 0)
		)
		(min_thickness 0.25)
		(keepout
			(tracks not_allowed)
			(vias allowed)
			(pads allowed)
			(copperpour not_allowed)
			(footprints allowed)
		)
		(placement
			(enabled no)
			(sheetname "")
		)
		(fill yes
			(thermal_gap 0.5)
			(thermal_bridge_width 0.5)
			(island_removal_mode 0)
		)
		(polygon
			(pts
				(arc
					(start 89.83599 -291.096192)
					(mid 89.20607 -291.096192)
					(end 89.83599 -291.096192)
				)
			)
		)
	)
	(zone
		(layers "B.Cu" "In15.Cu")
		(hatch none 0.5)
		(connect_pads
			(clearance 0)
		)
		(min_thickness 0.25)
		(keepout
			(tracks not_allowed)
			(vias allowed)
			(pads allowed)
			(copperpour not_allowed)
			(footprints allowed)
		)
		(placement
			(enabled no)
			(sheetname "")
		)
		(fill yes
			(thermal_gap 0.5)
			(thermal_bridge_width 0.5)
			(island_removal_mode 0)
		)
		(polygon
			(pts
				(arc
					(start 126.18974 -241.244374)
					(mid 125.55982 -241.244374)
					(end 126.18974 -241.244374)
				)
			)
		)
	)
	(zone
		(layers "B.Cu" "In15.Cu")
		(hatch none 0.5)
		(connect_pads
			(clearance 0)
		)
		(min_thickness 0.25)
		(keepout
			(tracks not_allowed)
			(vias allowed)
			(pads allowed)
			(copperpour not_allowed)
			(footprints allowed)
		)
		(placement
			(enabled no)
			(sheetname "")
		)
		(fill yes
			(thermal_gap 0.5)
			(thermal_bridge_width 0.5)
			(island_removal_mode 0)
		)
		(polygon
			(pts
				(arc
					(start 424.346116 -214.335106)
					(mid 423.678096 -214.335106)
					(end 424.346116 -214.335106)
				)
			)
		)
	)
	(zone
		(layers "B.Cu" "In15.Cu")
		(hatch none 0.5)
		(connect_pads
			(clearance 0)
		)
		(min_thickness 0.25)
		(keepout
			(tracks not_allowed)
			(vias allowed)
			(pads allowed)
			(copperpour not_allowed)
			(footprints allowed)
		)
		(placement
			(enabled no)
			(sheetname "")
		)
		(fill yes
			(thermal_gap 0.5)
			(thermal_bridge_width 0.5)
			(island_removal_mode 0)
		)
		(polygon
			(pts
				(arc
					(start 126.050548 -392.429238)
					(mid 125.382528 -392.429238)
					(end 126.050548 -392.429238)
				)
			)
		)
	)
	(zone
		(layers "B.Cu" "In15.Cu")
		(hatch none 0.5)
		(connect_pads
			(clearance 0)
		)
		(min_thickness 0.25)
		(keepout
			(tracks not_allowed)
			(vias allowed)
			(pads allowed)
			(copperpour not_allowed)
			(footprints allowed)
		)
		(placement
			(enabled no)
			(sheetname "")
		)
		(fill yes
			(thermal_gap 0.5)
			(thermal_bridge_width 0.5)
			(island_removal_mode 0)
		)
		(polygon
			(pts
				(arc
					(start 352.81616 -271.656048)
					(mid 352.18624 -271.656048)
					(end 352.81616 -271.656048)
				)
			)
		)
	)
	(zone
		(layers "B.Cu" "In15.Cu")
		(hatch none 0.5)
		(connect_pads
			(clearance 0)
		)
		(min_thickness 0.25)
		(keepout
			(tracks not_allowed)
			(vias allowed)
			(pads allowed)
			(copperpour not_allowed)
			(footprints allowed)
		)
		(placement
			(enabled no)
			(sheetname "")
		)
		(fill yes
			(thermal_gap 0.5)
			(thermal_bridge_width 0.5)
			(island_removal_mode 0)
		)
		(polygon
			(pts
				(arc
					(start 351.576132 -241.24412)
					(mid 350.946212 -241.24412)
					(end 351.576132 -241.24412)
				)
			)
		)
	)
	(zone
		(layers "B.Cu" "In15.Cu")
		(hatch none 0.5)
		(connect_pads
			(clearance 0)
		)
		(min_thickness 0.25)
		(keepout
			(tracks not_allowed)
			(vias allowed)
			(pads allowed)
			(copperpour not_allowed)
			(footprints allowed)
		)
		(placement
			(enabled no)
			(sheetname "")
		)
		(fill yes
			(thermal_gap 0.5)
			(thermal_bridge_width 0.5)
			(island_removal_mode 0)
		)
		(polygon
			(pts
				(arc
					(start 52.906168 -385.31038)
					(mid 52.276248 -385.31038)
					(end 52.906168 -385.31038)
				)
			)
		)
	)
	(zone
		(layers "B.Cu" "In15.Cu")
		(hatch none 0.5)
		(connect_pads
			(clearance 0)
		)
		(min_thickness 0.25)
		(keepout
			(tracks not_allowed)
			(vias allowed)
			(pads allowed)
			(copperpour not_allowed)
			(footprints allowed)
		)
		(placement
			(enabled no)
			(sheetname "")
		)
		(fill yes
			(thermal_gap 0.5)
			(thermal_bridge_width 0.5)
			(island_removal_mode 0)
		)
		(polygon
			(pts
				(arc
					(start 134.949692 -282.996386)
					(mid 134.319772 -282.996386)
					(end 134.949692 -282.996386)
				)
			)
		)
	)
	(zone
		(layers "B.Cu" "In15.Cu")
		(hatch none 0.5)
		(connect_pads
			(clearance 0)
		)
		(min_thickness 0.25)
		(keepout
			(tracks not_allowed)
			(vias allowed)
			(pads allowed)
			(copperpour not_allowed)
			(footprints allowed)
		)
		(placement
			(enabled no)
			(sheetname "")
		)
		(fill yes
			(thermal_gap 0.5)
			(thermal_bridge_width 0.5)
			(island_removal_mode 0)
		)
		(polygon
			(pts
				(arc
					(start 87.655908 -241.244374)
					(mid 87.025988 -241.244374)
					(end 87.655908 -241.244374)
				)
			)
		)
	)
	(zone
		(layers "B.Cu" "In15.Cu")
		(hatch none 0.5)
		(connect_pads
			(clearance 0)
		)
		(min_thickness 0.25)
		(keepout
			(tracks not_allowed)
			(vias allowed)
			(pads allowed)
			(copperpour not_allowed)
			(footprints allowed)
		)
		(placement
			(enabled no)
			(sheetname "")
		)
		(fill yes
			(thermal_gap 0.5)
			(thermal_bridge_width 0.5)
			(island_removal_mode 0)
		)
		(polygon
			(pts
				(arc
					(start 305.305968 -393.69238)
					(mid 304.676048 -393.69238)
					(end 305.305968 -393.69238)
				)
			)
		)
	)
	(zone
		(layers "B.Cu" "In15.Cu")
		(hatch none 0.5)
		(connect_pads
			(clearance 0)
		)
		(min_thickness 0.25)
		(keepout
			(tracks not_allowed)
			(vias allowed)
			(pads allowed)
			(copperpour not_allowed)
			(footprints allowed)
		)
		(placement
			(enabled no)
			(sheetname "")
		)
		(fill yes
			(thermal_gap 0.5)
			(thermal_bridge_width 0.5)
			(island_removal_mode 0)
		)
		(polygon
			(pts
				(arc
					(start 336.678016 -401.674838)
					(mid 336.009996 -401.674838)
					(end 336.678016 -401.674838)
				)
			)
		)
	)
	(zone
		(layers "B.Cu" "In15.Cu")
		(hatch none 0.5)
		(connect_pads
			(clearance 0)
		)
		(min_thickness 0.25)
		(keepout
			(tracks not_allowed)
			(vias allowed)
			(pads allowed)
			(copperpour not_allowed)
			(footprints allowed)
		)
		(placement
			(enabled no)
			(sheetname "")
		)
		(fill yes
			(thermal_gap 0.5)
			(thermal_bridge_width 0.5)
			(island_removal_mode 0)
		)
		(polygon
			(pts
				(arc
					(start 383.99974 -225.85426)
					(mid 383.36982 -225.85426)
					(end 383.99974 -225.85426)
				)
			)
		)
	)
	(zone
		(layers "B.Cu" "In15.Cu")
		(hatch none 0.5)
		(connect_pads
			(clearance 0)
		)
		(min_thickness 0.25)
		(keepout
			(tracks not_allowed)
			(vias allowed)
			(pads allowed)
			(copperpour not_allowed)
			(footprints allowed)
		)
		(placement
			(enabled no)
			(sheetname "")
		)
		(fill yes
			(thermal_gap 0.5)
			(thermal_bridge_width 0.5)
			(island_removal_mode 0)
		)
		(polygon
			(pts
				(arc
					(start 348.678246 -400.811238)
					(mid 348.010226 -400.811238)
					(end 348.678246 -400.811238)
				)
			)
		)
	)
	(zone
		(layers "B.Cu" "In15.Cu")
		(hatch none 0.5)
		(connect_pads
			(clearance 0)
		)
		(min_thickness 0.25)
		(keepout
			(tracks not_allowed)
			(vias allowed)
			(pads allowed)
			(copperpour not_allowed)
			(footprints allowed)
		)
		(placement
			(enabled no)
			(sheetname "")
		)
		(fill yes
			(thermal_gap 0.5)
			(thermal_bridge_width 0.5)
			(island_removal_mode 0)
		)
		(polygon
			(pts
				(arc
					(start 87.655908 -228.284532)
					(mid 87.025988 -228.284532)
					(end 87.655908 -228.284532)
				)
			)
		)
	)
	(zone
		(layers "B.Cu" "In15.Cu")
		(hatch none 0.5)
		(connect_pads
			(clearance 0)
		)
		(min_thickness 0.25)
		(keepout
			(tracks not_allowed)
			(vias allowed)
			(pads allowed)
			(copperpour not_allowed)
			(footprints allowed)
		)
		(placement
			(enabled no)
			(sheetname "")
		)
		(fill yes
			(thermal_gap 0.5)
			(thermal_bridge_width 0.5)
			(island_removal_mode 0)
		)
		(polygon
			(pts
				(arc
					(start 136.8298 -278.13635)
					(mid 136.19988 -278.13635)
					(end 136.8298 -278.13635)
				)
			)
		)
	)
	(zone
		(layers "B.Cu" "In15.Cu")
		(hatch none 0.5)
		(connect_pads
			(clearance 0)
		)
		(min_thickness 0.25)
		(keepout
			(tracks not_allowed)
			(vias allowed)
			(pads allowed)
			(copperpour not_allowed)
			(footprints allowed)
		)
		(placement
			(enabled no)
			(sheetname "")
		)
		(fill yes
			(thermal_gap 0.5)
			(thermal_bridge_width 0.5)
			(island_removal_mode 0)
		)
		(polygon
			(pts
				(arc
					(start 300.15815 -267.885164)
					(mid 299.49013 -267.885164)
					(end 300.15815 -267.885164)
				)
			)
		)
	)
	(zone
		(layers "B.Cu" "In15.Cu")
		(hatch none 0.5)
		(connect_pads
			(clearance 0)
		)
		(min_thickness 0.25)
		(keepout
			(tracks not_allowed)
			(vias allowed)
			(pads allowed)
			(copperpour not_allowed)
			(footprints allowed)
		)
		(placement
			(enabled no)
			(sheetname "")
		)
		(fill yes
			(thermal_gap 0.5)
			(thermal_bridge_width 0.5)
			(island_removal_mode 0)
		)
		(polygon
			(pts
				(arc
					(start 365.02975 -271.656048)
					(mid 364.39983 -271.656048)
					(end 365.02975 -271.656048)
				)
			)
		)
	)
	(zone
		(layers "B.Cu" "In15.Cu")
		(hatch none 0.5)
		(connect_pads
			(clearance 0)
		)
		(min_thickness 0.25)
		(keepout
			(tracks not_allowed)
			(vias allowed)
			(pads allowed)
			(copperpour not_allowed)
			(footprints allowed)
		)
		(placement
			(enabled no)
			(sheetname "")
		)
		(fill yes
			(thermal_gap 0.5)
			(thermal_bridge_width 0.5)
			(island_removal_mode 0)
		)
		(polygon
			(pts
				(arc
					(start 346.2782 -401.674838)
					(mid 345.61018 -401.674838)
					(end 346.2782 -401.674838)
				)
			)
		)
	)
	(zone
		(layers "B.Cu" "In15.Cu")
		(hatch none 0.5)
		(connect_pads
			(clearance 0)
		)
		(min_thickness 0.25)
		(keepout
			(tracks not_allowed)
			(vias allowed)
			(pads allowed)
			(copperpour not_allowed)
			(footprints allowed)
		)
		(placement
			(enabled no)
			(sheetname "")
		)
		(fill yes
			(thermal_gap 0.5)
			(thermal_bridge_width 0.5)
			(island_removal_mode 0)
		)
		(polygon
			(pts
				(arc
					(start 296.058082 -226.235006)
					(mid 295.390062 -226.235006)
					(end 296.058082 -226.235006)
				)
			)
		)
	)
	(zone
		(layers "B.Cu" "In15.Cu")
		(hatch none 0.5)
		(connect_pads
			(clearance 0)
		)
		(min_thickness 0.25)
		(keepout
			(tracks not_allowed)
			(vias allowed)
			(pads allowed)
			(copperpour not_allowed)
			(footprints allowed)
		)
		(placement
			(enabled no)
			(sheetname "")
		)
		(fill yes
			(thermal_gap 0.5)
			(thermal_bridge_width 0.5)
			(island_removal_mode 0)
		)
		(polygon
			(pts
				(arc
					(start 300.15815 -201.585068)
					(mid 299.49013 -201.585068)
					(end 300.15815 -201.585068)
				)
			)
		)
	)
	(zone
		(layers "B.Cu" "In15.Cu")
		(hatch none 0.5)
		(connect_pads
			(clearance 0)
		)
		(min_thickness 0.25)
		(keepout
			(tracks not_allowed)
			(vias allowed)
			(pads allowed)
			(copperpour not_allowed)
			(footprints allowed)
		)
		(placement
			(enabled no)
			(sheetname "")
		)
		(fill yes
			(thermal_gap 0.5)
			(thermal_bridge_width 0.5)
			(island_removal_mode 0)
		)
		(polygon
			(pts
				(arc
					(start 420.246048 -289.985196)
					(mid 419.578028 -289.985196)
					(end 420.246048 -289.985196)
				)
			)
		)
	)
	(zone
		(layers "B.Cu" "In15.Cu")
		(hatch none 0.5)
		(connect_pads
			(clearance 0)
		)
		(min_thickness 0.25)
		(keepout
			(tracks not_allowed)
			(vias allowed)
			(pads allowed)
			(copperpour not_allowed)
			(footprints allowed)
		)
		(placement
			(enabled no)
			(sheetname "")
		)
		(fill yes
			(thermal_gap 0.5)
			(thermal_bridge_width 0.5)
			(island_removal_mode 0)
		)
		(polygon
			(pts
				(arc
					(start 347.478096 -400.811238)
					(mid 346.810076 -400.811238)
					(end 347.478096 -400.811238)
				)
			)
		)
	)
	(zone
		(layers "B.Cu" "In15.Cu")
		(hatch none 0.5)
		(connect_pads
			(clearance 0)
		)
		(min_thickness 0.25)
		(keepout
			(tracks not_allowed)
			(vias allowed)
			(pads allowed)
			(copperpour not_allowed)
			(footprints allowed)
		)
		(placement
			(enabled no)
			(sheetname "")
		)
		(fill yes
			(thermal_gap 0.5)
			(thermal_bridge_width 0.5)
			(island_removal_mode 0)
		)
		(polygon
			(pts
				(arc
					(start 355.336094 -238.004096)
					(mid 354.706174 -238.004096)
					(end 355.336094 -238.004096)
				)
			)
		)
	)
	(zone
		(layers "B.Cu" "In15.Cu")
		(hatch none 0.5)
		(connect_pads
			(clearance 0)
		)
		(min_thickness 0.25)
		(keepout
			(tracks not_allowed)
			(vias allowed)
			(pads allowed)
			(copperpour not_allowed)
			(footprints allowed)
		)
		(placement
			(enabled no)
			(sheetname "")
		)
		(fill yes
			(thermal_gap 0.5)
			(thermal_bridge_width 0.5)
			(island_removal_mode 0)
		)
		(polygon
			(pts
				(arc
					(start 424.346116 -225.385122)
					(mid 423.678096 -225.385122)
					(end 424.346116 -225.385122)
				)
			)
		)
	)
	(zone
		(layers "B.Cu" "In15.Cu")
		(hatch none 0.5)
		(connect_pads
			(clearance 0)
		)
		(min_thickness 0.25)
		(keepout
			(tracks not_allowed)
			(vias allowed)
			(pads allowed)
			(copperpour not_allowed)
			(footprints allowed)
		)
		(placement
			(enabled no)
			(sheetname "")
		)
		(fill yes
			(thermal_gap 0.5)
			(thermal_bridge_width 0.5)
			(island_removal_mode 0)
		)
		(polygon
			(pts
				(arc
					(start 420.246048 -299.33519)
					(mid 419.578028 -299.33519)
					(end 420.246048 -299.33519)
				)
			)
		)
	)
	(zone
		(layers "B.Cu" "In15.Cu")
		(hatch none 0.5)
		(connect_pads
			(clearance 0)
		)
		(min_thickness 0.25)
		(keepout
			(tracks not_allowed)
			(vias allowed)
			(pads allowed)
			(copperpour not_allowed)
			(footprints allowed)
		)
		(placement
			(enabled no)
			(sheetname "")
		)
		(fill yes
			(thermal_gap 0.5)
			(thermal_bridge_width 0.5)
			(island_removal_mode 0)
		)
		(polygon
			(pts
				(arc
					(start 337.306158 -282.186126)
					(mid 336.676238 -282.186126)
					(end 337.306158 -282.186126)
				)
			)
		)
	)
	(zone
		(layers "B.Cu" "In15.Cu")
		(hatch none 0.5)
		(connect_pads
			(clearance 0)
		)
		(min_thickness 0.25)
		(keepout
			(tracks not_allowed)
			(vias allowed)
			(pads allowed)
			(copperpour not_allowed)
			(footprints allowed)
		)
		(placement
			(enabled no)
			(sheetname "")
		)
		(fill yes
			(thermal_gap 0.5)
			(thermal_bridge_width 0.5)
			(island_removal_mode 0)
		)
		(polygon
			(pts
				(arc
					(start 296.058082 -239.835182)
					(mid 295.390062 -239.835182)
					(end 296.058082 -239.835182)
				)
			)
		)
	)
	(zone
		(layers "B.Cu" "In15.Cu")
		(hatch none 0.5)
		(connect_pads
			(clearance 0)
		)
		(min_thickness 0.25)
		(keepout
			(tracks not_allowed)
			(vias allowed)
			(pads allowed)
			(copperpour not_allowed)
			(footprints allowed)
		)
		(placement
			(enabled no)
			(sheetname "")
		)
		(fill yes
			(thermal_gap 0.5)
			(thermal_bridge_width 0.5)
			(island_removal_mode 0)
		)
		(polygon
			(pts
				(arc
					(start 336.06613 -235.574078)
					(mid 335.43621 -235.574078)
					(end 336.06613 -235.574078)
				)
			)
		)
	)
	(zone
		(layers "B.Cu" "In15.Cu")
		(hatch none 0.5)
		(connect_pads
			(clearance 0)
		)
		(min_thickness 0.25)
		(keepout
			(tracks not_allowed)
			(vias allowed)
			(pads allowed)
			(copperpour not_allowed)
			(footprints allowed)
		)
		(placement
			(enabled no)
			(sheetname "")
		)
		(fill yes
			(thermal_gap 0.5)
			(thermal_bridge_width 0.5)
			(island_removal_mode 0)
		)
		(polygon
			(pts
				(arc
					(start 87.655908 -238.00435)
					(mid 87.025988 -238.00435)
					(end 87.655908 -238.00435)
				)
			)
		)
	)
	(zone
		(layers "B.Cu" "In15.Cu")
		(hatch none 0.5)
		(connect_pads
			(clearance 0)
		)
		(min_thickness 0.25)
		(keepout
			(tracks not_allowed)
			(vias allowed)
			(pads allowed)
			(copperpour not_allowed)
			(footprints allowed)
		)
		(placement
			(enabled no)
			(sheetname "")
		)
		(fill yes
			(thermal_gap 0.5)
			(thermal_bridge_width 0.5)
			(island_removal_mode 0)
		)
		(polygon
			(pts
				(arc
					(start 420.246048 -268.735048)
					(mid 419.578028 -268.735048)
					(end 420.246048 -268.735048)
				)
			)
		)
	)
	(zone
		(layers "B.Cu" "In15.Cu")
		(hatch none 0.5)
		(connect_pads
			(clearance 0)
		)
		(min_thickness 0.25)
		(keepout
			(tracks not_allowed)
			(vias allowed)
			(pads allowed)
			(copperpour not_allowed)
			(footprints allowed)
		)
		(placement
			(enabled no)
			(sheetname "")
		)
		(fill yes
			(thermal_gap 0.5)
			(thermal_bridge_width 0.5)
			(island_removal_mode 0)
		)
		(polygon
			(pts
				(arc
					(start 135.419592 -291.906198)
					(mid 134.789672 -291.906198)
					(end 135.419592 -291.906198)
				)
			)
		)
	)
	(zone
		(layers "B.Cu" "In15.Cu")
		(hatch none 0.5)
		(connect_pads
			(clearance 0)
		)
		(min_thickness 0.25)
		(keepout
			(tracks not_allowed)
			(vias allowed)
			(pads allowed)
			(copperpour not_allowed)
			(footprints allowed)
		)
		(placement
			(enabled no)
			(sheetname "")
		)
		(fill yes
			(thermal_gap 0.5)
			(thermal_bridge_width 0.5)
			(island_removal_mode 0)
		)
		(polygon
			(pts
				(arc
					(start 371.609874 -273.27606)
					(mid 370.979954 -273.27606)
					(end 371.609874 -273.27606)
				)
			)
		)
	)
	(zone
		(layers "B.Cu" "In15.Cu")
		(hatch none 0.5)
		(connect_pads
			(clearance 0)
		)
		(min_thickness 0.25)
		(keepout
			(tracks not_allowed)
			(vias allowed)
			(pads allowed)
			(copperpour not_allowed)
			(footprints allowed)
		)
		(placement
			(enabled no)
			(sheetname "")
		)
		(fill yes
			(thermal_gap 0.5)
			(thermal_bridge_width 0.5)
			(island_removal_mode 0)
		)
		(polygon
			(pts
				(arc
					(start 87.655908 -252.584458)
					(mid 87.025988 -252.584458)
					(end 87.655908 -252.584458)
				)
			)
		)
	)
	(zone
		(layers "B.Cu" "In15.Cu")
		(hatch none 0.5)
		(connect_pads
			(clearance 0)
		)
		(min_thickness 0.25)
		(keepout
			(tracks not_allowed)
			(vias allowed)
			(pads allowed)
			(copperpour not_allowed)
			(footprints allowed)
		)
		(placement
			(enabled no)
			(sheetname "")
		)
		(fill yes
			(thermal_gap 0.5)
			(thermal_bridge_width 0.5)
			(island_removal_mode 0)
		)
		(polygon
			(pts
				(arc
					(start 300.15815 -234.735116)
					(mid 299.49013 -234.735116)
					(end 300.15815 -234.735116)
				)
			)
		)
	)
	(zone
		(layers "B.Cu" "In15.Cu")
		(hatch none 0.5)
		(connect_pads
			(clearance 0)
		)
		(min_thickness 0.25)
		(keepout
			(tracks not_allowed)
			(vias allowed)
			(pads allowed)
			(copperpour not_allowed)
			(footprints allowed)
		)
		(placement
			(enabled no)
			(sheetname "")
		)
		(fill yes
			(thermal_gap 0.5)
			(thermal_bridge_width 0.5)
			(island_removal_mode 0)
		)
		(polygon
			(pts
				(arc
					(start 394.13688 -433.289964)
					(mid 393.362688 -433.289964)
					(end 394.13688 -433.289964)
				)
			)
		)
	)
	(zone
		(layers "B.Cu" "In15.Cu")
		(hatch none 0.5)
		(connect_pads
			(clearance 0)
		)
		(min_thickness 0.25)
		(keepout
			(tracks not_allowed)
			(vias allowed)
			(pads allowed)
			(copperpour not_allowed)
			(footprints allowed)
		)
		(placement
			(enabled no)
			(sheetname "")
		)
		(fill yes
			(thermal_gap 0.5)
			(thermal_bridge_width 0.5)
			(island_removal_mode 0)
		)
		(polygon
			(pts
				(arc
					(start 48.118014 -235.585254)
					(mid 47.449994 -235.585254)
					(end 48.118014 -235.585254)
				)
			)
		)
	)
	(zone
		(layers "B.Cu" "In15.Cu")
		(hatch none 0.5)
		(connect_pads
			(clearance 0)
		)
		(min_thickness 0.25)
		(keepout
			(tracks not_allowed)
			(vias allowed)
			(pads allowed)
			(copperpour not_allowed)
			(footprints allowed)
		)
		(placement
			(enabled no)
			(sheetname "")
		)
		(fill yes
			(thermal_gap 0.5)
			(thermal_bridge_width 0.5)
			(island_removal_mode 0)
		)
		(polygon
			(pts
				(arc
					(start 296.058082 -227.935028)
					(mid 295.390062 -227.935028)
					(end 296.058082 -227.935028)
				)
			)
		)
	)
	(zone
		(layers "B.Cu" "In15.Cu")
		(hatch none 0.5)
		(connect_pads
			(clearance 0)
		)
		(min_thickness 0.25)
		(keepout
			(tracks not_allowed)
			(vias allowed)
			(pads allowed)
			(copperpour not_allowed)
			(footprints allowed)
		)
		(placement
			(enabled no)
			(sheetname "")
		)
		(fill yes
			(thermal_gap 0.5)
			(thermal_bridge_width 0.5)
			(island_removal_mode 0)
		)
		(polygon
			(pts
				(arc
					(start 172.30598 -230.485442)
					(mid 171.63796 -230.485442)
					(end 172.30598 -230.485442)
				)
			)
		)
	)
	(zone
		(layers "B.Cu" "In15.Cu")
		(hatch none 0.5)
		(connect_pads
			(clearance 0)
		)
		(min_thickness 0.25)
		(keepout
			(tracks not_allowed)
			(vias allowed)
			(pads allowed)
			(copperpour not_allowed)
			(footprints allowed)
		)
		(placement
			(enabled no)
			(sheetname "")
		)
		(fill yes
			(thermal_gap 0.5)
			(thermal_bridge_width 0.5)
			(island_removal_mode 0)
		)
		(polygon
			(pts
				(arc
					(start 413.45485 -379.88113)
					(mid 412.78683 -379.88113)
					(end 413.45485 -379.88113)
				)
			)
		)
	)
	(zone
		(layers "B.Cu" "In15.Cu")
		(hatch none 0.5)
		(connect_pads
			(clearance 0)
		)
		(min_thickness 0.25)
		(keepout
			(tracks not_allowed)
			(vias allowed)
			(pads allowed)
			(copperpour not_allowed)
			(footprints allowed)
		)
		(placement
			(enabled no)
			(sheetname "")
		)
		(fill yes
			(thermal_gap 0.5)
			(thermal_bridge_width 0.5)
			(island_removal_mode 0)
		)
		(polygon
			(pts
				(arc
					(start 176.406048 -285.735268)
					(mid 175.738028 -285.735268)
					(end 176.406048 -285.735268)
				)
			)
		)
	)
	(zone
		(layers "B.Cu" "In15.Cu")
		(hatch none 0.5)
		(connect_pads
			(clearance 0)
		)
		(min_thickness 0.25)
		(keepout
			(tracks not_allowed)
			(vias allowed)
			(pads allowed)
			(copperpour not_allowed)
			(footprints allowed)
		)
		(placement
			(enabled no)
			(sheetname "")
		)
		(fill yes
			(thermal_gap 0.5)
			(thermal_bridge_width 0.5)
			(island_removal_mode 0)
		)
		(polygon
			(pts
				(arc
					(start 172.30598 -308.685438)
					(mid 171.63796 -308.685438)
					(end 172.30598 -308.685438)
				)
			)
		)
	)
	(zone
		(layers "B.Cu" "In15.Cu")
		(hatch none 0.5)
		(connect_pads
			(clearance 0)
		)
		(min_thickness 0.25)
		(keepout
			(tracks not_allowed)
			(vias allowed)
			(pads allowed)
			(copperpour not_allowed)
			(footprints allowed)
		)
		(placement
			(enabled no)
			(sheetname "")
		)
		(fill yes
			(thermal_gap 0.5)
			(thermal_bridge_width 0.5)
			(island_removal_mode 0)
		)
		(polygon
			(pts
				(arc
					(start 424.346116 -275.535136)
					(mid 423.678096 -275.535136)
					(end 424.346116 -275.535136)
				)
			)
		)
	)
	(zone
		(layers "B.Cu" "In15.Cu")
		(hatch none 0.5)
		(connect_pads
			(clearance 0)
		)
		(min_thickness 0.25)
		(keepout
			(tracks not_allowed)
			(vias allowed)
			(pads allowed)
			(copperpour not_allowed)
			(footprints allowed)
		)
		(placement
			(enabled no)
			(sheetname "")
		)
		(fill yes
			(thermal_gap 0.5)
			(thermal_bridge_width 0.5)
			(island_removal_mode 0)
		)
		(polygon
			(pts
				(arc
					(start 48.118014 -205.83525)
					(mid 47.449994 -205.83525)
					(end 48.118014 -205.83525)
				)
			)
		)
	)
	(zone
		(layers "B.Cu" "In15.Cu")
		(hatch none 0.5)
		(connect_pads
			(clearance 0)
		)
		(min_thickness 0.25)
		(keepout
			(tracks not_allowed)
			(vias allowed)
			(pads allowed)
			(copperpour not_allowed)
			(footprints allowed)
		)
		(placement
			(enabled no)
			(sheetname "")
		)
		(fill yes
			(thermal_gap 0.5)
			(thermal_bridge_width 0.5)
			(island_removal_mode 0)
		)
		(polygon
			(pts
				(arc
					(start 337.476084 -254.204216)
					(mid 336.846164 -254.204216)
					(end 337.476084 -254.204216)
				)
			)
		)
	)
	(zone
		(layers "B.Cu" "In15.Cu")
		(hatch none 0.5)
		(connect_pads
			(clearance 0)
		)
		(min_thickness 0.25)
		(keepout
			(tracks not_allowed)
			(vias allowed)
			(pads allowed)
			(copperpour not_allowed)
			(footprints allowed)
		)
		(placement
			(enabled no)
			(sheetname "")
		)
		(fill yes
			(thermal_gap 0.5)
			(thermal_bridge_width 0.5)
			(island_removal_mode 0)
		)
		(polygon
			(pts
				(arc
					(start 323.036692 -433.289964)
					(mid 322.2625 -433.289964)
					(end 323.036692 -433.289964)
				)
			)
		)
	)
	(zone
		(layers "B.Cu" "In15.Cu")
		(hatch none 0.5)
		(connect_pads
			(clearance 0)
		)
		(min_thickness 0.25)
		(keepout
			(tracks not_allowed)
			(vias allowed)
			(pads allowed)
			(copperpour not_allowed)
			(footprints allowed)
		)
		(placement
			(enabled no)
			(sheetname "")
		)
		(fill yes
			(thermal_gap 0.5)
			(thermal_bridge_width 0.5)
			(island_removal_mode 0)
		)
		(polygon
			(pts
				(arc
					(start 335.89595 -286.236156)
					(mid 335.26603 -286.236156)
					(end 335.89595 -286.236156)
				)
			)
		)
	)
	(zone
		(layers "B.Cu" "In15.Cu")
		(hatch none 0.5)
		(connect_pads
			(clearance 0)
		)
		(min_thickness 0.25)
		(keepout
			(tracks not_allowed)
			(vias allowed)
			(pads allowed)
			(copperpour not_allowed)
			(footprints allowed)
		)
		(placement
			(enabled no)
			(sheetname "")
		)
		(fill yes
			(thermal_gap 0.5)
			(thermal_bridge_width 0.5)
			(island_removal_mode 0)
		)
		(polygon
			(pts
				(arc
					(start 136.8298 -292.716204)
					(mid 136.19988 -292.716204)
					(end 136.8298 -292.716204)
				)
			)
		)
	)
	(zone
		(layers "B.Cu" "In15.Cu")
		(hatch none 0.5)
		(connect_pads
			(clearance 0)
		)
		(min_thickness 0.25)
		(keepout
			(tracks not_allowed)
			(vias allowed)
			(pads allowed)
			(copperpour not_allowed)
			(footprints allowed)
		)
		(placement
			(enabled no)
			(sheetname "")
		)
		(fill yes
			(thermal_gap 0.5)
			(thermal_bridge_width 0.5)
			(island_removal_mode 0)
		)
		(polygon
			(pts
				(arc
					(start 337.006184 -250.154186)
					(mid 336.376264 -250.154186)
					(end 337.006184 -250.154186)
				)
			)
		)
	)
	(zone
		(layers "B.Cu" "In15.Cu")
		(hatch none 0.5)
		(connect_pads
			(clearance 0)
		)
		(min_thickness 0.25)
		(keepout
			(tracks not_allowed)
			(vias allowed)
			(pads allowed)
			(copperpour not_allowed)
			(footprints allowed)
		)
		(placement
			(enabled no)
			(sheetname "")
		)
		(fill yes
			(thermal_gap 0.5)
			(thermal_bridge_width 0.5)
			(island_removal_mode 0)
		)
		(polygon
			(pts
				(arc
					(start 384.769868 -286.236156)
					(mid 384.139948 -286.236156)
					(end 384.769868 -286.236156)
				)
			)
		)
	)
	(zone
		(layers "B.Cu" "In15.Cu")
		(hatch none 0.5)
		(connect_pads
			(clearance 0)
		)
		(min_thickness 0.25)
		(keepout
			(tracks not_allowed)
			(vias allowed)
			(pads allowed)
			(copperpour not_allowed)
			(footprints allowed)
		)
		(placement
			(enabled no)
			(sheetname "")
		)
		(fill yes
			(thermal_gap 0.5)
			(thermal_bridge_width 0.5)
			(island_removal_mode 0)
		)
		(polygon
			(pts
				(arc
					(start 382.589786 -249.34418)
					(mid 381.959866 -249.34418)
					(end 382.589786 -249.34418)
				)
			)
		)
	)
	(zone
		(layers "B.Cu" "In15.Cu")
		(hatch none 0.5)
		(connect_pads
			(clearance 0)
		)
		(min_thickness 0.25)
		(keepout
			(tracks not_allowed)
			(vias allowed)
			(pads allowed)
			(copperpour not_allowed)
			(footprints allowed)
		)
		(placement
			(enabled no)
			(sheetname "")
		)
		(fill yes
			(thermal_gap 0.5)
			(thermal_bridge_width 0.5)
			(island_removal_mode 0)
		)
		(polygon
			(pts
				(arc
					(start 89.536016 -238.00435)
					(mid 88.906096 -238.00435)
					(end 89.536016 -238.00435)
				)
			)
		)
	)
	(zone
		(layers "B.Cu" "In15.Cu")
		(hatch none 0.5)
		(connect_pads
			(clearance 0)
		)
		(min_thickness 0.25)
		(keepout
			(tracks not_allowed)
			(vias allowed)
			(pads allowed)
			(copperpour not_allowed)
			(footprints allowed)
		)
		(placement
			(enabled no)
			(sheetname "")
		)
		(fill yes
			(thermal_gap 0.5)
			(thermal_bridge_width 0.5)
			(island_removal_mode 0)
		)
		(polygon
			(pts
				(arc
					(start 420.246048 -267.035026)
					(mid 419.578028 -267.035026)
					(end 420.246048 -267.035026)
				)
			)
		)
	)
	(zone
		(layers "B.Cu" "In15.Cu")
		(hatch none 0.5)
		(connect_pads
			(clearance 0)
		)
		(min_thickness 0.25)
		(keepout
			(tracks not_allowed)
			(vias allowed)
			(pads allowed)
			(copperpour not_allowed)
			(footprints allowed)
		)
		(placement
			(enabled no)
			(sheetname "")
		)
		(fill yes
			(thermal_gap 0.5)
			(thermal_bridge_width 0.5)
			(island_removal_mode 0)
		)
		(polygon
			(pts
				(arc
					(start 384.769868 -271.656048)
					(mid 384.139948 -271.656048)
					(end 384.769868 -271.656048)
				)
			)
		)
	)
	(zone
		(layers "B.Cu" "In15.Cu")
		(hatch none 0.5)
		(connect_pads
			(clearance 0)
		)
		(min_thickness 0.25)
		(keepout
			(tracks not_allowed)
			(vias allowed)
			(pads allowed)
			(copperpour not_allowed)
			(footprints allowed)
		)
		(placement
			(enabled no)
			(sheetname "")
		)
		(fill yes
			(thermal_gap 0.5)
			(thermal_bridge_width 0.5)
			(island_removal_mode 0)
		)
		(polygon
			(pts
				(arc
					(start 424.346116 -309.535068)
					(mid 423.678096 -309.535068)
					(end 424.346116 -309.535068)
				)
			)
		)
	)
	(zone
		(layers "B.Cu" "In15.Cu")
		(hatch none 0.5)
		(connect_pads
			(clearance 0)
		)
		(min_thickness 0.25)
		(keepout
			(tracks not_allowed)
			(vias allowed)
			(pads allowed)
			(copperpour not_allowed)
			(footprints allowed)
		)
		(placement
			(enabled no)
			(sheetname "")
		)
		(fill yes
			(thermal_gap 0.5)
			(thermal_bridge_width 0.5)
			(island_removal_mode 0)
		)
		(polygon
			(pts
				(arc
					(start 136.8298 -291.096192)
					(mid 136.19988 -291.096192)
					(end 136.8298 -291.096192)
				)
			)
		)
	)
	(zone
		(layers "B.Cu" "In15.Cu")
		(hatch none 0.5)
		(connect_pads
			(clearance 0)
		)
		(min_thickness 0.25)
		(keepout
			(tracks not_allowed)
			(vias allowed)
			(pads allowed)
			(copperpour not_allowed)
			(footprints allowed)
		)
		(placement
			(enabled no)
			(sheetname "")
		)
		(fill yes
			(thermal_gap 0.5)
			(thermal_bridge_width 0.5)
			(island_removal_mode 0)
		)
		(polygon
			(pts
				(arc
					(start 158.293054 -369.03533)
					(mid 157.625034 -369.03533)
					(end 158.293054 -369.03533)
				)
			)
		)
	)
	(zone
		(layers "B.Cu" "In15.Cu")
		(hatch none 0.5)
		(connect_pads
			(clearance 0)
		)
		(min_thickness 0.25)
		(keepout
			(tracks not_allowed)
			(vias allowed)
			(pads allowed)
			(copperpour not_allowed)
			(footprints allowed)
		)
		(placement
			(enabled no)
			(sheetname "")
		)
		(fill yes
			(thermal_gap 0.5)
			(thermal_bridge_width 0.5)
			(island_removal_mode 0)
		)
		(polygon
			(pts
				(arc
					(start 61.036962 -435.489858)
					(mid 60.26277 -435.489858)
					(end 61.036962 -435.489858)
				)
			)
		)
	)
	(zone
		(layers "B.Cu" "In15.Cu")
		(hatch none 0.5)
		(connect_pads
			(clearance 0)
		)
		(min_thickness 0.25)
		(keepout
			(tracks not_allowed)
			(vias allowed)
			(pads allowed)
			(copperpour not_allowed)
			(footprints allowed)
		)
		(placement
			(enabled no)
			(sheetname "")
		)
		(fill yes
			(thermal_gap 0.5)
			(thermal_bridge_width 0.5)
			(island_removal_mode 0)
		)
		(polygon
			(pts
				(arc
					(start 81.87817 -392.429238)
					(mid 81.21015 -392.429238)
					(end 81.87817 -392.429238)
				)
			)
		)
	)
	(zone
		(layers "B.Cu" "In15.Cu")
		(hatch none 0.5)
		(connect_pads
			(clearance 0)
		)
		(min_thickness 0.25)
		(keepout
			(tracks not_allowed)
			(vias allowed)
			(pads allowed)
			(copperpour not_allowed)
			(footprints allowed)
		)
		(placement
			(enabled no)
			(sheetname "")
		)
		(fill yes
			(thermal_gap 0.5)
			(thermal_bridge_width 0.5)
			(island_removal_mode 0)
		)
		(polygon
			(pts
				(arc
					(start 169.367454 -369.03533)
					(mid 168.699434 -369.03533)
					(end 169.367454 -369.03533)
				)
			)
		)
	)
	(zone
		(layers "B.Cu" "In15.Cu")
		(hatch none 0.5)
		(connect_pads
			(clearance 0)
		)
		(min_thickness 0.25)
		(keepout
			(tracks not_allowed)
			(vias allowed)
			(pads allowed)
			(copperpour not_allowed)
			(footprints allowed)
		)
		(placement
			(enabled no)
			(sheetname "")
		)
		(fill yes
			(thermal_gap 0.5)
			(thermal_bridge_width 0.5)
			(island_removal_mode 0)
		)
		(polygon
			(pts
				(arc
					(start 135.419592 -287.046162)
					(mid 134.789672 -287.046162)
					(end 135.419592 -287.046162)
				)
			)
		)
	)
	(zone
		(layers "B.Cu" "In15.Cu")
		(hatch none 0.5)
		(connect_pads
			(clearance 0)
		)
		(min_thickness 0.25)
		(keepout
			(tracks not_allowed)
			(vias allowed)
			(pads allowed)
			(copperpour not_allowed)
			(footprints allowed)
		)
		(placement
			(enabled no)
			(sheetname "")
		)
		(fill yes
			(thermal_gap 0.5)
			(thermal_bridge_width 0.5)
			(island_removal_mode 0)
		)
		(polygon
			(pts
				(arc
					(start 346.236036 -273.27606)
					(mid 345.606116 -273.27606)
					(end 346.236036 -273.27606)
				)
			)
		)
	)
	(zone
		(layers "B.Cu" "In15.Cu")
		(hatch none 0.5)
		(connect_pads
			(clearance 0)
		)
		(min_thickness 0.25)
		(keepout
			(tracks not_allowed)
			(vias allowed)
			(pads allowed)
			(copperpour not_allowed)
			(footprints allowed)
		)
		(placement
			(enabled no)
			(sheetname "")
		)
		(fill yes
			(thermal_gap 0.5)
			(thermal_bridge_width 0.5)
			(island_removal_mode 0)
		)
		(polygon
			(pts
				(arc
					(start 52.218082 -289.135312)
					(mid 51.550062 -289.135312)
					(end 52.218082 -289.135312)
				)
			)
		)
	)
	(zone
		(layers "B.Cu" "In15.Cu")
		(hatch none 0.5)
		(connect_pads
			(clearance 0)
		)
		(min_thickness 0.25)
		(keepout
			(tracks not_allowed)
			(vias allowed)
			(pads allowed)
			(copperpour not_allowed)
			(footprints allowed)
		)
		(placement
			(enabled no)
			(sheetname "")
		)
		(fill yes
			(thermal_gap 0.5)
			(thermal_bridge_width 0.5)
			(island_removal_mode 0)
		)
		(polygon
			(pts
				(arc
					(start 176.406048 -203.285344)
					(mid 175.738028 -203.285344)
					(end 176.406048 -203.285344)
				)
			)
		)
	)
	(zone
		(layers "B.Cu" "In15.Cu")
		(hatch none 0.5)
		(connect_pads
			(clearance 0)
		)
		(min_thickness 0.25)
		(keepout
			(tracks not_allowed)
			(vias allowed)
			(pads allowed)
			(copperpour not_allowed)
			(footprints allowed)
		)
		(placement
			(enabled no)
			(sheetname "")
		)
		(fill yes
			(thermal_gap 0.5)
			(thermal_bridge_width 0.5)
			(island_removal_mode 0)
		)
		(polygon
			(pts
				(arc
					(start 337.776058 -270.036036)
					(mid 337.146138 -270.036036)
					(end 337.776058 -270.036036)
				)
			)
		)
	)
	(zone
		(layers "B.Cu" "In15.Cu")
		(hatch none 0.5)
		(connect_pads
			(clearance 0)
		)
		(min_thickness 0.25)
		(keepout
			(tracks not_allowed)
			(vias allowed)
			(pads allowed)
			(copperpour not_allowed)
			(footprints allowed)
		)
		(placement
			(enabled no)
			(sheetname "")
		)
		(fill yes
			(thermal_gap 0.5)
			(thermal_bridge_width 0.5)
			(island_removal_mode 0)
		)
		(polygon
			(pts
				(arc
					(start 48.118014 -297.635422)
					(mid 47.449994 -297.635422)
					(end 48.118014 -297.635422)
				)
			)
		)
	)
	(zone
		(layers "B.Cu" "In15.Cu")
		(hatch none 0.5)
		(connect_pads
			(clearance 0)
		)
		(min_thickness 0.25)
		(keepout
			(tracks not_allowed)
			(vias allowed)
			(pads allowed)
			(copperpour not_allowed)
			(footprints allowed)
		)
		(placement
			(enabled no)
			(sheetname "")
		)
		(fill yes
			(thermal_gap 0.5)
			(thermal_bridge_width 0.5)
			(island_removal_mode 0)
		)
		(polygon
			(pts
				(arc
					(start 89.83599 -287.856422)
					(mid 89.20607 -287.856422)
					(end 89.83599 -287.856422)
				)
			)
		)
	)
	(zone
		(layers "B.Cu" "In15.Cu")
		(hatch none 0.5)
		(connect_pads
			(clearance 0)
		)
		(min_thickness 0.25)
		(keepout
			(tracks not_allowed)
			(vias allowed)
			(pads allowed)
			(copperpour not_allowed)
			(footprints allowed)
		)
		(placement
			(enabled no)
			(sheetname "")
		)
		(fill yes
			(thermal_gap 0.5)
			(thermal_bridge_width 0.5)
			(island_removal_mode 0)
		)
		(polygon
			(pts
				(arc
					(start 404.94585 -382.34493)
					(mid 404.27783 -382.34493)
					(end 404.94585 -382.34493)
				)
			)
		)
	)
	(zone
		(layers "B.Cu" "In15.Cu")
		(hatch none 0.5)
		(connect_pads
			(clearance 0)
		)
		(min_thickness 0.25)
		(keepout
			(tracks not_allowed)
			(vias allowed)
			(pads allowed)
			(copperpour not_allowed)
			(footprints allowed)
		)
		(placement
			(enabled no)
			(sheetname "")
		)
		(fill yes
			(thermal_gap 0.5)
			(thermal_bridge_width 0.5)
			(island_removal_mode 0)
		)
		(polygon
			(pts
				(arc
					(start 419.39845 -379.88113)
					(mid 418.73043 -379.88113)
					(end 419.39845 -379.88113)
				)
			)
		)
	)
	(zone
		(layers "B.Cu" "In15.Cu")
		(hatch none 0.5)
		(connect_pads
			(clearance 0)
		)
		(min_thickness 0.25)
		(keepout
			(tracks not_allowed)
			(vias allowed)
			(pads allowed)
			(copperpour not_allowed)
			(footprints allowed)
		)
		(placement
			(enabled no)
			(sheetname "")
		)
		(fill yes
			(thermal_gap 0.5)
			(thermal_bridge_width 0.5)
			(island_removal_mode 0)
		)
		(polygon
			(pts
				(arc
					(start 87.655908 -247.724422)
					(mid 87.025988 -247.724422)
					(end 87.655908 -247.724422)
				)
			)
		)
	)
	(zone
		(layers "B.Cu" "In15.Cu")
		(hatch none 0.5)
		(connect_pads
			(clearance 0)
		)
		(min_thickness 0.25)
		(keepout
			(tracks not_allowed)
			(vias allowed)
			(pads allowed)
			(copperpour not_allowed)
			(footprints allowed)
		)
		(placement
			(enabled no)
			(sheetname "")
		)
		(fill yes
			(thermal_gap 0.5)
			(thermal_bridge_width 0.5)
			(island_removal_mode 0)
		)
		(polygon
			(pts
				(arc
					(start 176.406048 -278.085296)
					(mid 175.738028 -278.085296)
					(end 176.406048 -278.085296)
				)
			)
		)
	)
	(zone
		(layers "B.Cu" "In15.Cu")
		(hatch none 0.5)
		(connect_pads
			(clearance 0)
		)
		(min_thickness 0.25)
		(keepout
			(tracks not_allowed)
			(vias allowed)
			(pads allowed)
			(copperpour not_allowed)
			(footprints allowed)
		)
		(placement
			(enabled no)
			(sheetname "")
		)
		(fill yes
			(thermal_gap 0.5)
			(thermal_bridge_width 0.5)
			(island_removal_mode 0)
		)
		(polygon
			(pts
				(arc
					(start 120.849644 -271.656302)
					(mid 120.219724 -271.656302)
					(end 120.849644 -271.656302)
				)
			)
		)
	)
	(zone
		(layers "B.Cu" "In15.Cu")
		(hatch none 0.5)
		(connect_pads
			(clearance 0)
		)
		(min_thickness 0.25)
		(keepout
			(tracks not_allowed)
			(vias allowed)
			(pads allowed)
			(copperpour not_allowed)
			(footprints allowed)
		)
		(placement
			(enabled no)
			(sheetname "")
		)
		(fill yes
			(thermal_gap 0.5)
			(thermal_bridge_width 0.5)
			(island_removal_mode 0)
		)
		(polygon
			(pts
				(arc
					(start 136.059672 -253.394464)
					(mid 135.429752 -253.394464)
					(end 136.059672 -253.394464)
				)
			)
		)
	)
	(zone
		(layers "B.Cu" "In15.Cu")
		(hatch none 0.5)
		(connect_pads
			(clearance 0)
		)
		(min_thickness 0.25)
		(keepout
			(tracks not_allowed)
			(vias allowed)
			(pads allowed)
			(copperpour not_allowed)
			(footprints allowed)
		)
		(placement
			(enabled no)
			(sheetname "")
		)
		(fill yes
			(thermal_gap 0.5)
			(thermal_bridge_width 0.5)
			(island_removal_mode 0)
		)
		(polygon
			(pts
				(arc
					(start 88.426036 -272.466308)
					(mid 87.796116 -272.466308)
					(end 88.426036 -272.466308)
				)
			)
		)
	)
	(zone
		(layers "B.Cu" "In15.Cu")
		(hatch none 0.5)
		(connect_pads
			(clearance 0)
		)
		(min_thickness 0.25)
		(keepout
			(tracks not_allowed)
			(vias allowed)
			(pads allowed)
			(copperpour not_allowed)
			(footprints allowed)
		)
		(placement
			(enabled no)
			(sheetname "")
		)
		(fill yes
			(thermal_gap 0.5)
			(thermal_bridge_width 0.5)
			(island_removal_mode 0)
		)
		(polygon
			(pts
				(arc
					(start 382.589786 -228.284278)
					(mid 381.959866 -228.284278)
					(end 382.589786 -228.284278)
				)
			)
		)
	)
	(zone
		(layers "B.Cu" "In15.Cu")
		(hatch none 0.5)
		(connect_pads
			(clearance 0)
		)
		(min_thickness 0.25)
		(keepout
			(tracks not_allowed)
			(vias allowed)
			(pads allowed)
			(copperpour not_allowed)
			(footprints allowed)
		)
		(placement
			(enabled no)
			(sheetname "")
		)
		(fill yes
			(thermal_gap 0.5)
			(thermal_bridge_width 0.5)
			(island_removal_mode 0)
		)
		(polygon
			(pts
				(arc
					(start 135.119618 -246.914416)
					(mid 134.489698 -246.914416)
					(end 135.119618 -246.914416)
				)
			)
		)
	)
	(zone
		(layers "B.Cu" "In15.Cu")
		(hatch none 0.5)
		(connect_pads
			(clearance 0)
		)
		(min_thickness 0.25)
		(keepout
			(tracks not_allowed)
			(vias allowed)
			(pads allowed)
			(copperpour not_allowed)
			(footprints allowed)
		)
		(placement
			(enabled no)
			(sheetname "")
		)
		(fill yes
			(thermal_gap 0.5)
			(thermal_bridge_width 0.5)
			(island_removal_mode 0)
		)
		(polygon
			(pts
				(arc
					(start 89.066116 -237.194344)
					(mid 88.436196 -237.194344)
					(end 89.066116 -237.194344)
				)
			)
		)
	)
	(zone
		(layers "B.Cu" "In15.Cu")
		(hatch none 0.5)
		(connect_pads
			(clearance 0)
		)
		(min_thickness 0.25)
		(keepout
			(tracks not_allowed)
			(vias allowed)
			(pads allowed)
			(copperpour not_allowed)
			(footprints allowed)
		)
		(placement
			(enabled no)
			(sheetname "")
		)
		(fill yes
			(thermal_gap 0.5)
			(thermal_bridge_width 0.5)
			(island_removal_mode 0)
		)
		(polygon
			(pts
				(arc
					(start 87.655908 -231.524302)
					(mid 87.025988 -231.524302)
					(end 87.655908 -231.524302)
				)
			)
		)
	)
	(zone
		(layers "B.Cu" "In15.Cu")
		(hatch none 0.5)
		(connect_pads
			(clearance 0)
		)
		(min_thickness 0.25)
		(keepout
			(tracks not_allowed)
			(vias allowed)
			(pads allowed)
			(copperpour not_allowed)
			(footprints allowed)
		)
		(placement
			(enabled no)
			(sheetname "")
		)
		(fill yes
			(thermal_gap 0.5)
			(thermal_bridge_width 0.5)
			(island_removal_mode 0)
		)
		(polygon
			(pts
				(arc
					(start 337.776058 -261.935976)
					(mid 337.146138 -261.935976)
					(end 337.776058 -261.935976)
				)
			)
		)
	)
	(zone
		(layers "B.Cu" "In15.Cu")
		(hatch none 0.5)
		(connect_pads
			(clearance 0)
		)
		(min_thickness 0.25)
		(keepout
			(tracks not_allowed)
			(vias allowed)
			(pads allowed)
			(copperpour not_allowed)
			(footprints allowed)
		)
		(placement
			(enabled no)
			(sheetname "")
		)
		(fill yes
			(thermal_gap 0.5)
			(thermal_bridge_width 0.5)
			(island_removal_mode 0)
		)
		(polygon
			(pts
				(arc
					(start 378.450602 -400.811238)
					(mid 377.782582 -400.811238)
					(end 378.450602 -400.811238)
				)
			)
		)
	)
	(zone
		(layers "B.Cu" "In15.Cu")
		(hatch none 0.5)
		(connect_pads
			(clearance 0)
		)
		(min_thickness 0.25)
		(keepout
			(tracks not_allowed)
			(vias allowed)
			(pads allowed)
			(copperpour not_allowed)
			(footprints allowed)
		)
		(placement
			(enabled no)
			(sheetname "")
		)
		(fill yes
			(thermal_gap 0.5)
			(thermal_bridge_width 0.5)
			(island_removal_mode 0)
		)
		(polygon
			(pts
				(arc
					(start 176.406048 -317.185294)
					(mid 175.738028 -317.185294)
					(end 176.406048 -317.185294)
				)
			)
		)
	)
	(zone
		(layers "B.Cu" "In15.Cu")
		(hatch none 0.5)
		(connect_pads
			(clearance 0)
		)
		(min_thickness 0.25)
		(keepout
			(tracks not_allowed)
			(vias allowed)
			(pads allowed)
			(copperpour not_allowed)
			(footprints allowed)
		)
		(placement
			(enabled no)
			(sheetname "")
		)
		(fill yes
			(thermal_gap 0.5)
			(thermal_bridge_width 0.5)
			(island_removal_mode 0)
		)
		(polygon
			(pts
				(arc
					(start 135.419592 -290.286186)
					(mid 134.789672 -290.286186)
					(end 135.419592 -290.286186)
				)
			)
		)
	)
	(zone
		(layers "B.Cu" "In15.Cu")
		(hatch none 0.5)
		(connect_pads
			(clearance 0)
		)
		(min_thickness 0.25)
		(keepout
			(tracks not_allowed)
			(vias allowed)
			(pads allowed)
			(copperpour not_allowed)
			(footprints allowed)
		)
		(placement
			(enabled no)
			(sheetname "")
		)
		(fill yes
			(thermal_gap 0.5)
			(thermal_bridge_width 0.5)
			(island_removal_mode 0)
		)
		(polygon
			(pts
				(arc
					(start 296.058082 -243.234972)
					(mid 295.390062 -243.234972)
					(end 296.058082 -243.234972)
				)
			)
		)
	)
	(zone
		(layers "B.Cu" "In15.Cu")
		(hatch none 0.5)
		(connect_pads
			(clearance 0)
		)
		(min_thickness 0.25)
		(keepout
			(tracks not_allowed)
			(vias allowed)
			(pads allowed)
			(copperpour not_allowed)
			(footprints allowed)
		)
		(placement
			(enabled no)
			(sheetname "")
		)
		(fill yes
			(thermal_gap 0.5)
			(thermal_bridge_width 0.5)
			(island_removal_mode 0)
		)
		(polygon
			(pts
				(arc
					(start 176.406048 -223.685354)
					(mid 175.738028 -223.685354)
					(end 176.406048 -223.685354)
				)
			)
		)
	)
	(zone
		(layers "B.Cu" "In15.Cu")
		(hatch none 0.5)
		(connect_pads
			(clearance 0)
		)
		(min_thickness 0.25)
		(keepout
			(tracks not_allowed)
			(vias allowed)
			(pads allowed)
			(copperpour not_allowed)
			(footprints allowed)
		)
		(placement
			(enabled no)
			(sheetname "")
		)
		(fill yes
			(thermal_gap 0.5)
			(thermal_bridge_width 0.5)
			(island_removal_mode 0)
		)
		(polygon
			(pts
				(arc
					(start 307.706014 -393.69238)
					(mid 307.076094 -393.69238)
					(end 307.706014 -393.69238)
				)
			)
		)
	)
	(zone
		(layers "B.Cu" "In15.Cu")
		(hatch none 0.5)
		(connect_pads
			(clearance 0)
		)
		(min_thickness 0.25)
		(keepout
			(tracks not_allowed)
			(vias allowed)
			(pads allowed)
			(copperpour not_allowed)
			(footprints allowed)
		)
		(placement
			(enabled no)
			(sheetname "")
		)
		(fill yes
			(thermal_gap 0.5)
			(thermal_bridge_width 0.5)
			(island_removal_mode 0)
		)
		(polygon
			(pts
				(arc
					(start 172.30598 -224.535238)
					(mid 171.63796 -224.535238)
					(end 172.30598 -224.535238)
				)
			)
		)
	)
	(zone
		(layers "B.Cu" "In15.Cu")
		(hatch none 0.5)
		(connect_pads
			(clearance 0)
		)
		(min_thickness 0.25)
		(keepout
			(tracks not_allowed)
			(vias allowed)
			(pads allowed)
			(copperpour not_allowed)
			(footprints allowed)
		)
		(placement
			(enabled no)
			(sheetname "")
		)
		(fill yes
			(thermal_gap 0.5)
			(thermal_bridge_width 0.5)
			(island_removal_mode 0)
		)
		(polygon
			(pts
				(arc
					(start 383.059686 -251.774198)
					(mid 382.429766 -251.774198)
					(end 383.059686 -251.774198)
				)
			)
		)
	)
	(zone
		(layers "B.Cu" "In15.Cu")
		(hatch none 0.5)
		(connect_pads
			(clearance 0)
		)
		(min_thickness 0.25)
		(keepout
			(tracks not_allowed)
			(vias allowed)
			(pads allowed)
			(copperpour not_allowed)
			(footprints allowed)
		)
		(placement
			(enabled no)
			(sheetname "")
		)
		(fill yes
			(thermal_gap 0.5)
			(thermal_bridge_width 0.5)
			(island_removal_mode 0)
		)
		(polygon
			(pts
				(arc
					(start 119.90959 -271.656302)
					(mid 119.27967 -271.656302)
					(end 119.90959 -271.656302)
				)
			)
		)
	)
	(zone
		(layers "B.Cu" "In15.Cu")
		(hatch none 0.5)
		(connect_pads
			(clearance 0)
		)
		(min_thickness 0.25)
		(keepout
			(tracks not_allowed)
			(vias allowed)
			(pads allowed)
			(copperpour not_allowed)
			(footprints allowed)
		)
		(placement
			(enabled no)
			(sheetname "")
		)
		(fill yes
			(thermal_gap 0.5)
			(thermal_bridge_width 0.5)
			(island_removal_mode 0)
		)
		(polygon
			(pts
				(arc
					(start 420.246048 -248.335038)
					(mid 419.578028 -248.335038)
					(end 420.246048 -248.335038)
				)
			)
		)
	)
	(zone
		(layers "B.Cu" "In15.Cu")
		(hatch none 0.5)
		(connect_pads
			(clearance 0)
		)
		(min_thickness 0.25)
		(keepout
			(tracks not_allowed)
			(vias allowed)
			(pads allowed)
			(copperpour not_allowed)
			(footprints allowed)
		)
		(placement
			(enabled no)
			(sheetname "")
		)
		(fill yes
			(thermal_gap 0.5)
			(thermal_bridge_width 0.5)
			(island_removal_mode 0)
		)
		(polygon
			(pts
				(arc
					(start 87.955882 -289.47618)
					(mid 87.325962 -289.47618)
					(end 87.955882 -289.47618)
				)
			)
		)
	)
	(zone
		(layers "B.Cu" "In15.Cu")
		(hatch none 0.5)
		(connect_pads
			(clearance 0)
		)
		(min_thickness 0.25)
		(keepout
			(tracks not_allowed)
			(vias allowed)
			(pads allowed)
			(copperpour not_allowed)
			(footprints allowed)
		)
		(placement
			(enabled no)
			(sheetname "")
		)
		(fill yes
			(thermal_gap 0.5)
			(thermal_bridge_width 0.5)
			(island_removal_mode 0)
		)
		(polygon
			(pts
				(arc
					(start 296.058082 -268.735048)
					(mid 295.390062 -268.735048)
					(end 296.058082 -268.735048)
				)
			)
		)
	)
	(zone
		(layers "B.Cu" "In15.Cu")
		(hatch none 0.5)
		(connect_pads
			(clearance 0)
		)
		(min_thickness 0.25)
		(keepout
			(tracks not_allowed)
			(vias allowed)
			(pads allowed)
			(copperpour not_allowed)
			(footprints allowed)
		)
		(placement
			(enabled no)
			(sheetname "")
		)
		(fill yes
			(thermal_gap 0.5)
			(thermal_bridge_width 0.5)
			(island_removal_mode 0)
		)
		(polygon
			(pts
				(arc
					(start 54.506368 -386.003292)
					(mid 53.876448 -386.003292)
					(end 54.506368 -386.003292)
				)
			)
		)
	)
	(zone
		(layers "B.Cu" "In15.Cu")
		(hatch none 0.5)
		(connect_pads
			(clearance 0)
		)
		(min_thickness 0.25)
		(keepout
			(tracks not_allowed)
			(vias allowed)
			(pads allowed)
			(copperpour not_allowed)
			(footprints allowed)
		)
		(placement
			(enabled no)
			(sheetname "")
		)
		(fill yes
			(thermal_gap 0.5)
			(thermal_bridge_width 0.5)
			(island_removal_mode 0)
		)
		(polygon
			(pts
				(arc
					(start 164.262054 -371.49913)
					(mid 163.594034 -371.49913)
					(end 164.262054 -371.49913)
				)
			)
		)
	)
	(zone
		(layers "B.Cu" "In15.Cu")
		(hatch none 0.5)
		(connect_pads
			(clearance 0)
		)
		(min_thickness 0.25)
		(keepout
			(tracks not_allowed)
			(vias allowed)
			(pads allowed)
			(copperpour not_allowed)
			(footprints allowed)
		)
		(placement
			(enabled no)
			(sheetname "")
		)
		(fill yes
			(thermal_gap 0.5)
			(thermal_bridge_width 0.5)
			(island_removal_mode 0)
		)
		(polygon
			(pts
				(arc
					(start 134.949692 -287.856422)
					(mid 134.319772 -287.856422)
					(end 134.949692 -287.856422)
				)
			)
		)
	)
	(zone
		(layers "B.Cu" "In15.Cu")
		(hatch none 0.5)
		(connect_pads
			(clearance 0)
		)
		(min_thickness 0.25)
		(keepout
			(tracks not_allowed)
			(vias allowed)
			(pads allowed)
			(copperpour not_allowed)
			(footprints allowed)
		)
		(placement
			(enabled no)
			(sheetname "")
		)
		(fill yes
			(thermal_gap 0.5)
			(thermal_bridge_width 0.5)
			(island_removal_mode 0)
		)
		(polygon
			(pts
				(arc
					(start 89.066116 -255.014476)
					(mid 88.436196 -255.014476)
					(end 89.066116 -255.014476)
				)
			)
		)
	)
	(zone
		(layers "B.Cu" "In15.Cu")
		(hatch none 0.5)
		(connect_pads
			(clearance 0)
		)
		(min_thickness 0.25)
		(keepout
			(tracks not_allowed)
			(vias allowed)
			(pads allowed)
			(copperpour not_allowed)
			(footprints allowed)
		)
		(placement
			(enabled no)
			(sheetname "")
		)
		(fill yes
			(thermal_gap 0.5)
			(thermal_bridge_width 0.5)
			(island_removal_mode 0)
		)
		(polygon
			(pts
				(arc
					(start 384.1369 -435.489858)
					(mid 383.362708 -435.489858)
					(end 384.1369 -435.489858)
				)
			)
		)
	)
	(zone
		(layers "B.Cu" "In15.Cu")
		(hatch none 0.5)
		(connect_pads
			(clearance 0)
		)
		(min_thickness 0.25)
		(keepout
			(tracks not_allowed)
			(vias allowed)
			(pads allowed)
			(copperpour not_allowed)
			(footprints allowed)
		)
		(placement
			(enabled no)
			(sheetname "")
		)
		(fill yes
			(thermal_gap 0.5)
			(thermal_bridge_width 0.5)
			(island_removal_mode 0)
		)
		(polygon
			(pts
				(arc
					(start 87.955882 -286.23641)
					(mid 87.325962 -286.23641)
					(end 87.955882 -286.23641)
				)
			)
		)
	)
	(zone
		(layers "B.Cu" "In15.Cu")
		(hatch none 0.5)
		(connect_pads
			(clearance 0)
		)
		(min_thickness 0.25)
		(keepout
			(tracks not_allowed)
			(vias allowed)
			(pads allowed)
			(copperpour not_allowed)
			(footprints allowed)
		)
		(placement
			(enabled no)
			(sheetname "")
		)
		(fill yes
			(thermal_gap 0.5)
			(thermal_bridge_width 0.5)
			(island_removal_mode 0)
		)
		(polygon
			(pts
				(arc
					(start 134.949692 -263.556242)
					(mid 134.319772 -263.556242)
					(end 134.949692 -263.556242)
				)
			)
		)
	)
	(zone
		(layers "B.Cu" "In15.Cu")
		(hatch none 0.5)
		(connect_pads
			(clearance 0)
		)
		(min_thickness 0.25)
		(keepout
			(tracks not_allowed)
			(vias allowed)
			(pads allowed)
			(copperpour not_allowed)
			(footprints allowed)
		)
		(placement
			(enabled no)
			(sheetname "")
		)
		(fill yes
			(thermal_gap 0.5)
			(thermal_bridge_width 0.5)
			(island_removal_mode 0)
		)
		(polygon
			(pts
				(arc
					(start 117.729762 -242.864386)
					(mid 117.099842 -242.864386)
					(end 117.729762 -242.864386)
				)
			)
		)
	)
	(zone
		(layers "B.Cu" "In15.Cu")
		(hatch none 0.5)
		(connect_pads
			(clearance 0)
		)
		(min_thickness 0.25)
		(keepout
			(tracks not_allowed)
			(vias allowed)
			(pads allowed)
			(copperpour not_allowed)
			(footprints allowed)
		)
		(placement
			(enabled no)
			(sheetname "")
		)
		(fill yes
			(thermal_gap 0.5)
			(thermal_bridge_width 0.5)
			(island_removal_mode 0)
		)
		(polygon
			(pts
				(arc
					(start 52.218082 -204.985366)
					(mid 51.550062 -204.985366)
					(end 52.218082 -204.985366)
				)
			)
		)
	)
	(zone
		(layers "B.Cu" "In15.Cu")
		(hatch none 0.5)
		(connect_pads
			(clearance 0)
		)
		(min_thickness 0.25)
		(keepout
			(tracks not_allowed)
			(vias allowed)
			(pads allowed)
			(copperpour not_allowed)
			(footprints allowed)
		)
		(placement
			(enabled no)
			(sheetname "")
		)
		(fill yes
			(thermal_gap 0.5)
			(thermal_bridge_width 0.5)
			(island_removal_mode 0)
		)
		(polygon
			(pts
				(arc
					(start 52.218082 -281.48534)
					(mid 51.550062 -281.48534)
					(end 52.218082 -281.48534)
				)
			)
		)
	)
	(zone
		(layers "B.Cu" "In15.Cu")
		(hatch none 0.5)
		(connect_pads
			(clearance 0)
		)
		(min_thickness 0.25)
		(keepout
			(tracks not_allowed)
			(vias allowed)
			(pads allowed)
			(copperpour not_allowed)
			(footprints allowed)
		)
		(placement
			(enabled no)
			(sheetname "")
		)
		(fill yes
			(thermal_gap 0.5)
			(thermal_bridge_width 0.5)
			(island_removal_mode 0)
		)
		(polygon
			(pts
				(arc
					(start 135.419592 -278.946356)
					(mid 134.789672 -278.946356)
					(end 135.419592 -278.946356)
				)
			)
		)
	)
	(zone
		(layers "B.Cu" "In15.Cu")
		(hatch none 0.5)
		(connect_pads
			(clearance 0)
		)
		(min_thickness 0.25)
		(keepout
			(tracks not_allowed)
			(vias allowed)
			(pads allowed)
			(copperpour not_allowed)
			(footprints allowed)
		)
		(placement
			(enabled no)
			(sheetname "")
		)
		(fill yes
			(thermal_gap 0.5)
			(thermal_bridge_width 0.5)
			(island_removal_mode 0)
		)
		(polygon
			(pts
				(arc
					(start 134.649718 -228.284532)
					(mid 134.019798 -228.284532)
					(end 134.649718 -228.284532)
				)
			)
		)
	)
	(zone
		(layers "B.Cu" "In15.Cu")
		(hatch none 0.5)
		(connect_pads
			(clearance 0)
		)
		(min_thickness 0.25)
		(keepout
			(tracks not_allowed)
			(vias allowed)
			(pads allowed)
			(copperpour not_allowed)
			(footprints allowed)
		)
		(placement
			(enabled no)
			(sheetname "")
		)
		(fill yes
			(thermal_gap 0.5)
			(thermal_bridge_width 0.5)
			(island_removal_mode 0)
		)
		(polygon
			(pts
				(arc
					(start 300.15815 -208.385156)
					(mid 299.49013 -208.385156)
					(end 300.15815 -208.385156)
				)
			)
		)
	)
	(zone
		(layers "B.Cu" "In15.Cu")
		(hatch none 0.5)
		(connect_pads
			(clearance 0)
		)
		(min_thickness 0.25)
		(keepout
			(tracks not_allowed)
			(vias allowed)
			(pads allowed)
			(copperpour not_allowed)
			(footprints allowed)
		)
		(placement
			(enabled no)
			(sheetname "")
		)
		(fill yes
			(thermal_gap 0.5)
			(thermal_bridge_width 0.5)
			(island_removal_mode 0)
		)
		(polygon
			(pts
				(arc
					(start 368.789712 -271.656048)
					(mid 368.159792 -271.656048)
					(end 368.789712 -271.656048)
				)
			)
		)
	)
	(zone
		(layers "B.Cu" "In15.Cu")
		(hatch none 0.5)
		(connect_pads
			(clearance 0)
		)
		(min_thickness 0.25)
		(keepout
			(tracks not_allowed)
			(vias allowed)
			(pads allowed)
			(copperpour not_allowed)
			(footprints allowed)
		)
		(placement
			(enabled no)
			(sheetname "")
		)
		(fill yes
			(thermal_gap 0.5)
			(thermal_bridge_width 0.5)
			(island_removal_mode 0)
		)
		(polygon
			(pts
				(arc
					(start 136.8298 -279.756362)
					(mid 136.19988 -279.756362)
					(end 136.8298 -279.756362)
				)
			)
		)
	)
	(zone
		(layers "B.Cu" "In15.Cu")
		(hatch none 0.5)
		(connect_pads
			(clearance 0)
		)
		(min_thickness 0.25)
		(keepout
			(tracks not_allowed)
			(vias allowed)
			(pads allowed)
			(copperpour not_allowed)
			(footprints allowed)
		)
		(placement
			(enabled no)
			(sheetname "")
		)
		(fill yes
			(thermal_gap 0.5)
			(thermal_bridge_width 0.5)
			(island_removal_mode 0)
		)
		(polygon
			(pts
				(arc
					(start 420.246048 -302.73498)
					(mid 419.578028 -302.73498)
					(end 420.246048 -302.73498)
				)
			)
		)
	)
	(zone
		(layers "B.Cu" "In15.Cu")
		(hatch none 0.5)
		(connect_pads
			(clearance 0)
		)
		(min_thickness 0.25)
		(keepout
			(tracks not_allowed)
			(vias allowed)
			(pads allowed)
			(copperpour not_allowed)
			(footprints allowed)
		)
		(placement
			(enabled no)
			(sheetname "")
		)
		(fill yes
			(thermal_gap 0.5)
			(thermal_bridge_width 0.5)
			(island_removal_mode 0)
		)
		(polygon
			(pts
				(arc
					(start 52.218082 -267.885418)
					(mid 51.550062 -267.885418)
					(end 52.218082 -267.885418)
				)
			)
		)
	)
	(zone
		(layers "B.Cu" "In15.Cu")
		(hatch none 0.5)
		(connect_pads
			(clearance 0)
		)
		(min_thickness 0.25)
		(keepout
			(tracks not_allowed)
			(vias allowed)
			(pads allowed)
			(copperpour not_allowed)
			(footprints allowed)
		)
		(placement
			(enabled no)
			(sheetname "")
		)
		(fill yes
			(thermal_gap 0.5)
			(thermal_bridge_width 0.5)
			(island_removal_mode 0)
		)
		(polygon
			(pts
				(arc
					(start 337.306158 -277.32609)
					(mid 336.676238 -277.32609)
					(end 337.306158 -277.32609)
				)
			)
		)
	)
	(zone
		(layers "B.Cu" "In15.Cu")
		(hatch none 0.5)
		(connect_pads
			(clearance 0)
		)
		(min_thickness 0.25)
		(keepout
			(tracks not_allowed)
			(vias allowed)
			(pads allowed)
			(copperpour not_allowed)
			(footprints allowed)
		)
		(placement
			(enabled no)
			(sheetname "")
		)
		(fill yes
			(thermal_gap 0.5)
			(thermal_bridge_width 0.5)
			(island_removal_mode 0)
		)
		(polygon
			(pts
				(arc
					(start 99.236022 -270.03629)
					(mid 98.606102 -270.03629)
					(end 99.236022 -270.03629)
				)
			)
		)
	)
	(zone
		(layers "B.Cu" "In15.Cu")
		(hatch none 0.5)
		(connect_pads
			(clearance 0)
		)
		(min_thickness 0.25)
		(keepout
			(tracks not_allowed)
			(vias allowed)
			(pads allowed)
			(copperpour not_allowed)
			(footprints allowed)
		)
		(placement
			(enabled no)
			(sheetname "")
		)
		(fill yes
			(thermal_gap 0.5)
			(thermal_bridge_width 0.5)
			(island_removal_mode 0)
		)
		(polygon
			(pts
				(arc
					(start 136.059672 -245.294404)
					(mid 135.429752 -245.294404)
					(end 136.059672 -245.294404)
				)
			)
		)
	)
	(zone
		(layers "B.Cu" "In15.Cu")
		(hatch none 0.5)
		(connect_pads
			(clearance 0)
		)
		(min_thickness 0.25)
		(keepout
			(tracks not_allowed)
			(vias allowed)
			(pads allowed)
			(copperpour not_allowed)
			(footprints allowed)
		)
		(placement
			(enabled no)
			(sheetname "")
		)
		(fill yes
			(thermal_gap 0.5)
			(thermal_bridge_width 0.5)
			(island_removal_mode 0)
		)
		(polygon
			(pts
				(arc
					(start 172.30598 -215.185244)
					(mid 171.63796 -215.185244)
					(end 172.30598 -215.185244)
				)
			)
		)
	)
	(zone
		(layers "B.Cu" "In15.Cu")
		(hatch none 0.5)
		(connect_pads
			(clearance 0)
		)
		(min_thickness 0.25)
		(keepout
			(tracks not_allowed)
			(vias allowed)
			(pads allowed)
			(copperpour not_allowed)
			(footprints allowed)
		)
		(placement
			(enabled no)
			(sheetname "")
		)
		(fill yes
			(thermal_gap 0.5)
			(thermal_bridge_width 0.5)
			(island_removal_mode 0)
		)
		(polygon
			(pts
				(arc
					(start 114.4397 -240.434368)
					(mid 113.80978 -240.434368)
					(end 114.4397 -240.434368)
				)
			)
		)
	)
	(zone
		(layers "B.Cu" "In15.Cu")
		(hatch none 0.5)
		(connect_pads
			(clearance 0)
		)
		(min_thickness 0.25)
		(keepout
			(tracks not_allowed)
			(vias allowed)
			(pads allowed)
			(copperpour not_allowed)
			(footprints allowed)
		)
		(placement
			(enabled no)
			(sheetname "")
		)
		(fill yes
			(thermal_gap 0.5)
			(thermal_bridge_width 0.5)
			(island_removal_mode 0)
		)
		(polygon
			(pts
				(arc
					(start 134.649718 -250.964446)
					(mid 134.019798 -250.964446)
					(end 134.649718 -250.964446)
				)
			)
		)
	)
	(zone
		(layers "B.Cu" "In15.Cu")
		(hatch none 0.5)
		(connect_pads
			(clearance 0)
		)
		(min_thickness 0.25)
		(keepout
			(tracks not_allowed)
			(vias allowed)
			(pads allowed)
			(copperpour not_allowed)
			(footprints allowed)
		)
		(placement
			(enabled no)
			(sheetname "")
		)
		(fill yes
			(thermal_gap 0.5)
			(thermal_bridge_width 0.5)
			(island_removal_mode 0)
		)
		(polygon
			(pts
				(arc
					(start 374.850406 -400.811238)
					(mid 374.182386 -400.811238)
					(end 374.850406 -400.811238)
				)
			)
		)
	)
	(zone
		(layers "B.Cu" "In15.Cu")
		(hatch none 0.5)
		(connect_pads
			(clearance 0)
		)
		(min_thickness 0.25)
		(keepout
			(tracks not_allowed)
			(vias allowed)
			(pads allowed)
			(copperpour not_allowed)
			(footprints allowed)
		)
		(placement
			(enabled no)
			(sheetname "")
		)
		(fill yes
			(thermal_gap 0.5)
			(thermal_bridge_width 0.5)
			(island_removal_mode 0)
		)
		(polygon
			(pts
				(arc
					(start 335.595976 -246.104156)
					(mid 334.966056 -246.104156)
					(end 335.595976 -246.104156)
				)
			)
		)
	)
	(zone
		(layers "B.Cu" "In15.Cu")
		(hatch none 0.5)
		(connect_pads
			(clearance 0)
		)
		(min_thickness 0.25)
		(keepout
			(tracks not_allowed)
			(vias allowed)
			(pads allowed)
			(copperpour not_allowed)
			(footprints allowed)
		)
		(placement
			(enabled no)
			(sheetname "")
		)
		(fill yes
			(thermal_gap 0.5)
			(thermal_bridge_width 0.5)
			(island_removal_mode 0)
		)
		(polygon
			(pts
				(arc
					(start 382.88976 -281.37612)
					(mid 382.25984 -281.37612)
					(end 382.88976 -281.37612)
				)
			)
		)
	)
	(zone
		(layers "B.Cu" "In15.Cu")
		(hatch none 0.5)
		(connect_pads
			(clearance 0)
		)
		(min_thickness 0.25)
		(keepout
			(tracks not_allowed)
			(vias allowed)
			(pads allowed)
			(copperpour not_allowed)
			(footprints allowed)
		)
		(placement
			(enabled no)
			(sheetname "")
		)
		(fill yes
			(thermal_gap 0.5)
			(thermal_bridge_width 0.5)
			(island_removal_mode 0)
		)
		(polygon
			(pts
				(arc
					(start 384.299714 -272.466054)
					(mid 383.669794 -272.466054)
					(end 384.299714 -272.466054)
				)
			)
		)
	)
	(zone
		(layers "B.Cu" "In15.Cu")
		(hatch none 0.5)
		(connect_pads
			(clearance 0)
		)
		(min_thickness 0.25)
		(keepout
			(tracks not_allowed)
			(vias allowed)
			(pads allowed)
			(copperpour not_allowed)
			(footprints allowed)
		)
		(placement
			(enabled no)
			(sheetname "")
		)
		(fill yes
			(thermal_gap 0.5)
			(thermal_bridge_width 0.5)
			(island_removal_mode 0)
		)
		(polygon
			(pts
				(arc
					(start 300.15815 -307.835046)
					(mid 299.49013 -307.835046)
					(end 300.15815 -307.835046)
				)
			)
		)
	)
	(zone
		(layers "B.Cu" "In15.Cu")
		(hatch none 0.5)
		(connect_pads
			(clearance 0)
		)
		(min_thickness 0.25)
		(keepout
			(tracks not_allowed)
			(vias allowed)
			(pads allowed)
			(copperpour not_allowed)
			(footprints allowed)
		)
		(placement
			(enabled no)
			(sheetname "")
		)
		(fill yes
			(thermal_gap 0.5)
			(thermal_bridge_width 0.5)
			(island_removal_mode 0)
		)
		(polygon
			(pts
				(arc
					(start 89.536016 -233.144314)
					(mid 88.906096 -233.144314)
					(end 89.536016 -233.144314)
				)
			)
		)
	)
	(zone
		(layers "B.Cu" "In15.Cu")
		(hatch none 0.5)
		(connect_pads
			(clearance 0)
		)
		(min_thickness 0.25)
		(keepout
			(tracks not_allowed)
			(vias allowed)
			(pads allowed)
			(copperpour not_allowed)
			(footprints allowed)
		)
		(placement
			(enabled no)
			(sheetname "")
		)
		(fill yes
			(thermal_gap 0.5)
			(thermal_bridge_width 0.5)
			(island_removal_mode 0)
		)
		(polygon
			(pts
				(arc
					(start 114.4397 -238.814356)
					(mid 113.80978 -238.814356)
					(end 114.4397 -238.814356)
				)
			)
		)
	)
	(zone
		(layers "B.Cu" "In15.Cu")
		(hatch none 0.5)
		(connect_pads
			(clearance 0)
		)
		(min_thickness 0.25)
		(keepout
			(tracks not_allowed)
			(vias allowed)
			(pads allowed)
			(copperpour not_allowed)
			(footprints allowed)
		)
		(placement
			(enabled no)
			(sheetname "")
		)
		(fill yes
			(thermal_gap 0.5)
			(thermal_bridge_width 0.5)
			(island_removal_mode 0)
		)
		(polygon
			(pts
				(arc
					(start 337.006184 -238.814102)
					(mid 336.376264 -238.814102)
					(end 337.006184 -238.814102)
				)
			)
		)
	)
	(zone
		(layers "B.Cu" "In15.Cu")
		(hatch none 0.5)
		(connect_pads
			(clearance 0)
		)
		(min_thickness 0.25)
		(keepout
			(tracks not_allowed)
			(vias allowed)
			(pads allowed)
			(copperpour not_allowed)
			(footprints allowed)
		)
		(placement
			(enabled no)
			(sheetname "")
		)
		(fill yes
			(thermal_gap 0.5)
			(thermal_bridge_width 0.5)
			(island_removal_mode 0)
		)
		(polygon
			(pts
				(arc
					(start 86.678262 -392.429238)
					(mid 86.010242 -392.429238)
					(end 86.678262 -392.429238)
				)
			)
		)
	)
	(zone
		(layers "B.Cu" "In15.Cu")
		(hatch none 0.5)
		(connect_pads
			(clearance 0)
		)
		(min_thickness 0.25)
		(keepout
			(tracks not_allowed)
			(vias allowed)
			(pads allowed)
			(copperpour not_allowed)
			(footprints allowed)
		)
		(placement
			(enabled no)
			(sheetname "")
		)
		(fill yes
			(thermal_gap 0.5)
			(thermal_bridge_width 0.5)
			(island_removal_mode 0)
		)
		(polygon
			(pts
				(arc
					(start 134.649718 -233.144314)
					(mid 134.019798 -233.144314)
					(end 134.649718 -233.144314)
				)
			)
		)
	)
	(zone
		(layers "B.Cu" "In15.Cu")
		(hatch none 0.5)
		(connect_pads
			(clearance 0)
		)
		(min_thickness 0.25)
		(keepout
			(tracks not_allowed)
			(vias allowed)
			(pads allowed)
			(copperpour not_allowed)
			(footprints allowed)
		)
		(placement
			(enabled no)
			(sheetname "")
		)
		(fill yes
			(thermal_gap 0.5)
			(thermal_bridge_width 0.5)
			(island_removal_mode 0)
		)
		(polygon
			(pts
				(arc
					(start 383.35966 -287.045908)
					(mid 382.72974 -287.045908)
					(end 383.35966 -287.045908)
				)
			)
		)
	)
	(zone
		(layers "B.Cu" "In15.Cu")
		(hatch none 0.5)
		(connect_pads
			(clearance 0)
		)
		(min_thickness 0.25)
		(keepout
			(tracks not_allowed)
			(vias allowed)
			(pads allowed)
			(copperpour not_allowed)
			(footprints allowed)
		)
		(placement
			(enabled no)
			(sheetname "")
		)
		(fill yes
			(thermal_gap 0.5)
			(thermal_bridge_width 0.5)
			(island_removal_mode 0)
		)
		(polygon
			(pts
				(arc
					(start 59.036966 -434.48986)
					(mid 58.262774 -434.48986)
					(end 59.036966 -434.48986)
				)
			)
		)
	)
	(zone
		(layers "B.Cu" "In15.Cu")
		(hatch none 0.5)
		(connect_pads
			(clearance 0)
		)
		(min_thickness 0.25)
		(keepout
			(tracks not_allowed)
			(vias allowed)
			(pads allowed)
			(copperpour not_allowed)
			(footprints allowed)
		)
		(placement
			(enabled no)
			(sheetname "")
		)
		(fill yes
			(thermal_gap 0.5)
			(thermal_bridge_width 0.5)
			(island_removal_mode 0)
		)
		(polygon
			(pts
				(arc
					(start 420.246048 -250.03506)
					(mid 419.578028 -250.03506)
					(end 420.246048 -250.03506)
				)
			)
		)
	)
	(zone
		(layers "B.Cu" "In15.Cu")
		(hatch none 0.5)
		(connect_pads
			(clearance 0)
		)
		(min_thickness 0.25)
		(keepout
			(tracks not_allowed)
			(vias allowed)
			(pads allowed)
			(copperpour not_allowed)
			(footprints allowed)
		)
		(placement
			(enabled no)
			(sheetname "")
		)
		(fill yes
			(thermal_gap 0.5)
			(thermal_bridge_width 0.5)
			(island_removal_mode 0)
		)
		(polygon
			(pts
				(arc
					(start 98.678238 -392.429238)
					(mid 98.010218 -392.429238)
					(end 98.678238 -392.429238)
				)
			)
		)
	)
	(zone
		(layers "B.Cu" "In15.Cu")
		(hatch none 0.5)
		(connect_pads
			(clearance 0)
		)
		(min_thickness 0.25)
		(keepout
			(tracks not_allowed)
			(vias allowed)
			(pads allowed)
			(copperpour not_allowed)
			(footprints allowed)
		)
		(placement
			(enabled no)
			(sheetname "")
		)
		(fill yes
			(thermal_gap 0.5)
			(thermal_bridge_width 0.5)
			(island_removal_mode 0)
		)
		(polygon
			(pts
				(arc
					(start 52.218082 -242.385342)
					(mid 51.550062 -242.385342)
					(end 52.218082 -242.385342)
				)
			)
		)
	)
	(zone
		(layers "B.Cu" "In15.Cu")
		(hatch none 0.5)
		(connect_pads
			(clearance 0)
		)
		(min_thickness 0.25)
		(keepout
			(tracks not_allowed)
			(vias allowed)
			(pads allowed)
			(copperpour not_allowed)
			(footprints allowed)
		)
		(placement
			(enabled no)
			(sheetname "")
		)
		(fill yes
			(thermal_gap 0.5)
			(thermal_bridge_width 0.5)
			(island_removal_mode 0)
		)
		(polygon
			(pts
				(arc
					(start 401.54225 -377.41733)
					(mid 400.87423 -377.41733)
					(end 401.54225 -377.41733)
				)
			)
		)
	)
	(zone
		(layers "B.Cu" "In15.Cu")
		(hatch none 0.5)
		(connect_pads
			(clearance 0)
		)
		(min_thickness 0.25)
		(keepout
			(tracks not_allowed)
			(vias allowed)
			(pads allowed)
			(copperpour not_allowed)
			(footprints allowed)
		)
		(placement
			(enabled no)
			(sheetname "")
		)
		(fill yes
			(thermal_gap 0.5)
			(thermal_bridge_width 0.5)
			(island_removal_mode 0)
		)
		(polygon
			(pts
				(arc
					(start 382.88976 -270.036036)
					(mid 382.25984 -270.036036)
					(end 382.88976 -270.036036)
				)
			)
		)
	)
	(zone
		(layers "B.Cu" "In15.Cu")
		(hatch none 0.5)
		(connect_pads
			(clearance 0)
		)
		(min_thickness 0.25)
		(keepout
			(tracks not_allowed)
			(vias allowed)
			(pads allowed)
			(copperpour not_allowed)
			(footprints allowed)
		)
		(placement
			(enabled no)
			(sheetname "")
		)
		(fill yes
			(thermal_gap 0.5)
			(thermal_bridge_width 0.5)
			(island_removal_mode 0)
		)
		(polygon
			(pts
				(arc
					(start 145.542254 -369.03533)
					(mid 144.874234 -369.03533)
					(end 145.542254 -369.03533)
				)
			)
		)
	)
	(zone
		(layers "B.Cu" "In15.Cu")
		(hatch none 0.5)
		(connect_pads
			(clearance 0)
		)
		(min_thickness 0.25)
		(keepout
			(tracks not_allowed)
			(vias allowed)
			(pads allowed)
			(copperpour not_allowed)
			(footprints allowed)
		)
		(placement
			(enabled no)
			(sheetname "")
		)
		(fill yes
			(thermal_gap 0.5)
			(thermal_bridge_width 0.5)
			(island_removal_mode 0)
		)
		(polygon
			(pts
				(arc
					(start 336.366104 -282.186126)
					(mid 335.736184 -282.186126)
					(end 336.366104 -282.186126)
				)
			)
		)
	)
	(zone
		(layers "B.Cu" "In15.Cu")
		(hatch none 0.5)
		(connect_pads
			(clearance 0)
		)
		(min_thickness 0.25)
		(keepout
			(tracks not_allowed)
			(vias allowed)
			(pads allowed)
			(copperpour not_allowed)
			(footprints allowed)
		)
		(placement
			(enabled no)
			(sheetname "")
		)
		(fill yes
			(thermal_gap 0.5)
			(thermal_bridge_width 0.5)
			(island_removal_mode 0)
		)
		(polygon
			(pts
				(arc
					(start 384.769868 -278.136096)
					(mid 384.139948 -278.136096)
					(end 384.769868 -278.136096)
				)
			)
		)
	)
	(zone
		(layers "B.Cu" "In15.Cu")
		(hatch none 0.5)
		(connect_pads
			(clearance 0)
		)
		(min_thickness 0.25)
		(keepout
			(tracks not_allowed)
			(vias allowed)
			(pads allowed)
			(copperpour not_allowed)
			(footprints allowed)
		)
		(placement
			(enabled no)
			(sheetname "")
		)
		(fill yes
			(thermal_gap 0.5)
			(thermal_bridge_width 0.5)
			(island_removal_mode 0)
		)
		(polygon
			(pts
				(arc
					(start 176.406048 -210.935316)
					(mid 175.738028 -210.935316)
					(end 176.406048 -210.935316)
				)
			)
		)
	)
	(zone
		(layers "B.Cu" "In15.Cu")
		(hatch none 0.5)
		(connect_pads
			(clearance 0)
		)
		(min_thickness 0.25)
		(keepout
			(tracks not_allowed)
			(vias allowed)
			(pads allowed)
			(copperpour not_allowed)
			(footprints allowed)
		)
		(placement
			(enabled no)
			(sheetname "")
		)
		(fill yes
			(thermal_gap 0.5)
			(thermal_bridge_width 0.5)
			(island_removal_mode 0)
		)
		(polygon
			(pts
				(arc
					(start 176.406048 -261.08533)
					(mid 175.738028 -261.08533)
					(end 176.406048 -261.08533)
				)
			)
		)
	)
	(zone
		(layers "B.Cu" "In15.Cu")
		(hatch none 0.5)
		(connect_pads
			(clearance 0)
		)
		(min_thickness 0.25)
		(keepout
			(tracks not_allowed)
			(vias allowed)
			(pads allowed)
			(copperpour not_allowed)
			(footprints allowed)
		)
		(placement
			(enabled no)
			(sheetname "")
		)
		(fill yes
			(thermal_gap 0.5)
			(thermal_bridge_width 0.5)
			(island_removal_mode 0)
		)
		(polygon
			(pts
				(arc
					(start 124.850652 -392.429238)
					(mid 124.182632 -392.429238)
					(end 124.850652 -392.429238)
				)
			)
		)
	)
	(zone
		(layers "B.Cu" "In15.Cu")
		(hatch none 0.5)
		(connect_pads
			(clearance 0)
		)
		(min_thickness 0.25)
		(keepout
			(tracks not_allowed)
			(vias allowed)
			(pads allowed)
			(copperpour not_allowed)
			(footprints allowed)
		)
		(placement
			(enabled no)
			(sheetname "")
		)
		(fill yes
			(thermal_gap 0.5)
			(thermal_bridge_width 0.5)
			(island_removal_mode 0)
		)
		(polygon
			(pts
				(arc
					(start 335.595976 -242.864132)
					(mid 334.966056 -242.864132)
					(end 335.595976 -242.864132)
				)
			)
		)
	)
	(zone
		(layers "B.Cu" "In15.Cu")
		(hatch none 0.5)
		(connect_pads
			(clearance 0)
		)
		(min_thickness 0.25)
		(keepout
			(tracks not_allowed)
			(vias allowed)
			(pads allowed)
			(copperpour not_allowed)
			(footprints allowed)
		)
		(placement
			(enabled no)
			(sheetname "")
		)
		(fill yes
			(thermal_gap 0.5)
			(thermal_bridge_width 0.5)
			(island_removal_mode 0)
		)
		(polygon
			(pts
				(arc
					(start 56.506364 -385.31038)
					(mid 55.876444 -385.31038)
					(end 56.506364 -385.31038)
				)
			)
		)
	)
	(zone
		(layers "B.Cu" "In15.Cu")
		(hatch none 0.5)
		(connect_pads
			(clearance 0)
		)
		(min_thickness 0.25)
		(keepout
			(tracks not_allowed)
			(vias allowed)
			(pads allowed)
			(copperpour not_allowed)
			(footprints allowed)
		)
		(placement
			(enabled no)
			(sheetname "")
		)
		(fill yes
			(thermal_gap 0.5)
			(thermal_bridge_width 0.5)
			(island_removal_mode 0)
		)
		(polygon
			(pts
				(arc
					(start 52.218082 -228.78542)
					(mid 51.550062 -228.78542)
					(end 52.218082 -228.78542)
				)
			)
		)
	)
	(zone
		(layers "B.Cu" "In15.Cu")
		(hatch none 0.5)
		(connect_pads
			(clearance 0)
		)
		(min_thickness 0.25)
		(keepout
			(tracks not_allowed)
			(vias allowed)
			(pads allowed)
			(copperpour not_allowed)
			(footprints allowed)
		)
		(placement
			(enabled no)
			(sheetname "")
		)
		(fill yes
			(thermal_gap 0.5)
			(thermal_bridge_width 0.5)
			(island_removal_mode 0)
		)
		(polygon
			(pts
				(arc
					(start 89.36609 -288.666174)
					(mid 88.73617 -288.666174)
					(end 89.36609 -288.666174)
				)
			)
		)
	)
	(zone
		(layers "B.Cu" "In15.Cu")
		(hatch none 0.5)
		(connect_pads
			(clearance 0)
		)
		(min_thickness 0.25)
		(keepout
			(tracks not_allowed)
			(vias allowed)
			(pads allowed)
			(copperpour not_allowed)
			(footprints allowed)
		)
		(placement
			(enabled no)
			(sheetname "")
		)
		(fill yes
			(thermal_gap 0.5)
			(thermal_bridge_width 0.5)
			(island_removal_mode 0)
		)
		(polygon
			(pts
				(arc
					(start 52.218082 -200.735438)
					(mid 51.550062 -200.735438)
					(end 52.218082 -200.735438)
				)
			)
		)
	)
	(zone
		(layers "B.Cu" "In15.Cu")
		(hatch none 0.5)
		(connect_pads
			(clearance 0)
		)
		(min_thickness 0.25)
		(keepout
			(tracks not_allowed)
			(vias allowed)
			(pads allowed)
			(copperpour not_allowed)
			(footprints allowed)
		)
		(placement
			(enabled no)
			(sheetname "")
		)
		(fill yes
			(thermal_gap 0.5)
			(thermal_bridge_width 0.5)
			(island_removal_mode 0)
		)
		(polygon
			(pts
				(arc
					(start 87.955882 -263.556242)
					(mid 87.325962 -263.556242)
					(end 87.955882 -263.556242)
				)
			)
		)
	)
	(zone
		(layers "B.Cu" "In15.Cu")
		(hatch none 0.5)
		(connect_pads
			(clearance 0)
		)
		(min_thickness 0.25)
		(keepout
			(tracks not_allowed)
			(vias allowed)
			(pads allowed)
			(copperpour not_allowed)
			(footprints allowed)
		)
		(placement
			(enabled no)
			(sheetname "")
		)
		(fill yes
			(thermal_gap 0.5)
			(thermal_bridge_width 0.5)
			(island_removal_mode 0)
		)
		(polygon
			(pts
				(arc
					(start 296.058082 -229.63505)
					(mid 295.390062 -229.63505)
					(end 296.058082 -229.63505)
				)
			)
		)
	)
	(zone
		(layers "B.Cu" "In15.Cu")
		(hatch none 0.5)
		(connect_pads
			(clearance 0)
		)
		(min_thickness 0.25)
		(keepout
			(tracks not_allowed)
			(vias allowed)
			(pads allowed)
			(copperpour not_allowed)
			(footprints allowed)
		)
		(placement
			(enabled no)
			(sheetname "")
		)
		(fill yes
			(thermal_gap 0.5)
			(thermal_bridge_width 0.5)
			(island_removal_mode 0)
		)
		(polygon
			(pts
				(arc
					(start 424.346116 -231.335072)
					(mid 423.678096 -231.335072)
					(end 424.346116 -231.335072)
				)
			)
		)
	)
	(zone
		(layers "B.Cu" "In15.Cu")
		(hatch none 0.5)
		(connect_pads
			(clearance 0)
		)
		(min_thickness 0.25)
		(keepout
			(tracks not_allowed)
			(vias allowed)
			(pads allowed)
			(copperpour not_allowed)
			(footprints allowed)
		)
		(placement
			(enabled no)
			(sheetname "")
		)
		(fill yes
			(thermal_gap 0.5)
			(thermal_bridge_width 0.5)
			(island_removal_mode 0)
		)
		(polygon
			(pts
				(arc
					(start 384.469894 -229.904036)
					(mid 383.839974 -229.904036)
					(end 384.469894 -229.904036)
				)
			)
		)
	)
	(zone
		(layers "B.Cu" "In15.Cu")
		(hatch none 0.5)
		(connect_pads
			(clearance 0)
		)
		(min_thickness 0.25)
		(keepout
			(tracks not_allowed)
			(vias allowed)
			(pads allowed)
			(copperpour not_allowed)
			(footprints allowed)
		)
		(placement
			(enabled no)
			(sheetname "")
		)
		(fill yes
			(thermal_gap 0.5)
			(thermal_bridge_width 0.5)
			(island_removal_mode 0)
		)
		(polygon
			(pts
				(arc
					(start 420.246048 -201.585068)
					(mid 419.578028 -201.585068)
					(end 420.246048 -201.585068)
				)
			)
		)
	)
	(zone
		(layers "B.Cu" "In15.Cu")
		(hatch none 0.5)
		(connect_pads
			(clearance 0)
		)
		(min_thickness 0.25)
		(keepout
			(tracks not_allowed)
			(vias allowed)
			(pads allowed)
			(copperpour not_allowed)
			(footprints allowed)
		)
		(placement
			(enabled no)
			(sheetname "")
		)
		(fill yes
			(thermal_gap 0.5)
			(thermal_bridge_width 0.5)
			(island_removal_mode 0)
		)
		(polygon
			(pts
				(arc
					(start 117.650514 -392.429238)
					(mid 116.982494 -392.429238)
					(end 117.650514 -392.429238)
				)
			)
		)
	)
	(zone
		(layers "B.Cu" "In15.Cu")
		(hatch none 0.5)
		(connect_pads
			(clearance 0)
		)
		(min_thickness 0.25)
		(keepout
			(tracks not_allowed)
			(vias allowed)
			(pads allowed)
			(copperpour not_allowed)
			(footprints allowed)
		)
		(placement
			(enabled no)
			(sheetname "")
		)
		(fill yes
			(thermal_gap 0.5)
			(thermal_bridge_width 0.5)
			(island_removal_mode 0)
		)
		(polygon
			(pts
				(arc
					(start 383.99974 -242.054126)
					(mid 383.36982 -242.054126)
					(end 383.99974 -242.054126)
				)
			)
		)
	)
	(zone
		(layers "B.Cu" "In15.Cu")
		(hatch none 0.5)
		(connect_pads
			(clearance 0)
		)
		(min_thickness 0.25)
		(keepout
			(tracks not_allowed)
			(vias allowed)
			(pads allowed)
			(copperpour not_allowed)
			(footprints allowed)
		)
		(placement
			(enabled no)
			(sheetname "")
		)
		(fill yes
			(thermal_gap 0.5)
			(thermal_bridge_width 0.5)
			(island_removal_mode 0)
		)
		(polygon
			(pts
				(arc
					(start 147.13712 -433.289964)
					(mid 146.362928 -433.289964)
					(end 147.13712 -433.289964)
				)
			)
		)
	)
	(zone
		(layers "B.Cu" "In15.Cu")
		(hatch none 0.5)
		(connect_pads
			(clearance 0)
		)
		(min_thickness 0.25)
		(keepout
			(tracks not_allowed)
			(vias allowed)
			(pads allowed)
			(copperpour not_allowed)
			(footprints allowed)
		)
		(placement
			(enabled no)
			(sheetname "")
		)
		(fill yes
			(thermal_gap 0.5)
			(thermal_bridge_width 0.5)
			(island_removal_mode 0)
		)
		(polygon
			(pts
				(arc
					(start 89.536016 -226.66452)
					(mid 88.906096 -226.66452)
					(end 89.536016 -226.66452)
				)
			)
		)
	)
	(zone
		(layers "B.Cu" "In15.Cu")
		(hatch none 0.5)
		(connect_pads
			(clearance 0)
		)
		(min_thickness 0.25)
		(keepout
			(tracks not_allowed)
			(vias allowed)
			(pads allowed)
			(copperpour not_allowed)
			(footprints allowed)
		)
		(placement
			(enabled no)
			(sheetname "")
		)
		(fill yes
			(thermal_gap 0.5)
			(thermal_bridge_width 0.5)
			(island_removal_mode 0)
		)
		(polygon
			(pts
				(arc
					(start 384.299714 -262.745982)
					(mid 383.669794 -262.745982)
					(end 384.299714 -262.745982)
				)
			)
		)
	)
	(zone
		(layers "B.Cu" "In15.Cu")
		(hatch none 0.5)
		(connect_pads
			(clearance 0)
		)
		(min_thickness 0.25)
		(keepout
			(tracks not_allowed)
			(vias allowed)
			(pads allowed)
			(copperpour not_allowed)
			(footprints allowed)
		)
		(placement
			(enabled no)
			(sheetname "")
		)
		(fill yes
			(thermal_gap 0.5)
			(thermal_bridge_width 0.5)
			(island_removal_mode 0)
		)
		(polygon
			(pts
				(arc
					(start 99.236022 -271.656302)
					(mid 98.606102 -271.656302)
					(end 99.236022 -271.656302)
				)
			)
		)
	)
	(zone
		(layers "B.Cu" "In15.Cu")
		(hatch none 0.5)
		(connect_pads
			(clearance 0)
		)
		(min_thickness 0.25)
		(keepout
			(tracks not_allowed)
			(vias allowed)
			(pads allowed)
			(copperpour not_allowed)
			(footprints allowed)
		)
		(placement
			(enabled no)
			(sheetname "")
		)
		(fill yes
			(thermal_gap 0.5)
			(thermal_bridge_width 0.5)
			(island_removal_mode 0)
		)
		(polygon
			(pts
				(arc
					(start 136.059672 -246.914416)
					(mid 135.429752 -246.914416)
					(end 136.059672 -246.914416)
				)
			)
		)
	)
	(zone
		(layers "B.Cu" "In15.Cu")
		(hatch none 0.5)
		(connect_pads
			(clearance 0)
		)
		(min_thickness 0.25)
		(keepout
			(tracks not_allowed)
			(vias allowed)
			(pads allowed)
			(copperpour not_allowed)
			(footprints allowed)
		)
		(placement
			(enabled no)
			(sheetname "")
		)
		(fill yes
			(thermal_gap 0.5)
			(thermal_bridge_width 0.5)
			(island_removal_mode 0)
		)
		(polygon
			(pts
				(arc
					(start 73.036938 -435.489858)
					(mid 72.262746 -435.489858)
					(end 73.036938 -435.489858)
				)
			)
		)
	)
	(zone
		(layers "B.Cu" "In15.Cu")
		(hatch none 0.5)
		(connect_pads
			(clearance 0)
		)
		(min_thickness 0.25)
		(keepout
			(tracks not_allowed)
			(vias allowed)
			(pads allowed)
			(copperpour not_allowed)
			(footprints allowed)
		)
		(placement
			(enabled no)
			(sheetname "")
		)
		(fill yes
			(thermal_gap 0.5)
			(thermal_bridge_width 0.5)
			(island_removal_mode 0)
		)
		(polygon
			(pts
				(arc
					(start 300.15815 -227.085144)
					(mid 299.49013 -227.085144)
					(end 300.15815 -227.085144)
				)
			)
		)
	)
	(zone
		(layers "B.Cu" "In15.Cu")
		(hatch none 0.5)
		(connect_pads
			(clearance 0)
		)
		(min_thickness 0.25)
		(keepout
			(tracks not_allowed)
			(vias allowed)
			(pads allowed)
			(copperpour not_allowed)
			(footprints allowed)
		)
		(placement
			(enabled no)
			(sheetname "")
		)
		(fill yes
			(thermal_gap 0.5)
			(thermal_bridge_width 0.5)
			(island_removal_mode 0)
		)
		(polygon
			(pts
				(arc
					(start 362.679742 -274.086066)
					(mid 362.049822 -274.086066)
					(end 362.679742 -274.086066)
				)
			)
		)
	)
	(zone
		(layers "B.Cu" "In15.Cu")
		(hatch none 0.5)
		(connect_pads
			(clearance 0)
		)
		(min_thickness 0.25)
		(keepout
			(tracks not_allowed)
			(vias allowed)
			(pads allowed)
			(copperpour not_allowed)
			(footprints allowed)
		)
		(placement
			(enabled no)
			(sheetname "")
		)
		(fill yes
			(thermal_gap 0.5)
			(thermal_bridge_width 0.5)
			(island_removal_mode 0)
		)
		(polygon
			(pts
				(arc
					(start 135.119618 -255.014476)
					(mid 134.489698 -255.014476)
					(end 135.119618 -255.014476)
				)
			)
		)
	)
	(zone
		(layers "B.Cu" "In15.Cu")
		(hatch none 0.5)
		(connect_pads
			(clearance 0)
		)
		(min_thickness 0.25)
		(keepout
			(tracks not_allowed)
			(vias allowed)
			(pads allowed)
			(copperpour not_allowed)
			(footprints allowed)
		)
		(placement
			(enabled no)
			(sheetname "")
		)
		(fill yes
			(thermal_gap 0.5)
			(thermal_bridge_width 0.5)
			(island_removal_mode 0)
		)
		(polygon
			(pts
				(arc
					(start 338.036916 -434.289962)
					(mid 337.262724 -434.289962)
					(end 338.036916 -434.289962)
				)
			)
		)
	)
	(zone
		(layers "B.Cu" "In15.Cu")
		(hatch none 0.5)
		(connect_pads
			(clearance 0)
		)
		(min_thickness 0.25)
		(keepout
			(tracks not_allowed)
			(vias allowed)
			(pads allowed)
			(copperpour not_allowed)
			(footprints allowed)
		)
		(placement
			(enabled no)
			(sheetname "")
		)
		(fill yes
			(thermal_gap 0.5)
			(thermal_bridge_width 0.5)
			(island_removal_mode 0)
		)
		(polygon
			(pts
				(arc
					(start 48.118014 -318.035432)
					(mid 47.449994 -318.035432)
					(end 48.118014 -318.035432)
				)
			)
		)
	)
	(zone
		(layers "B.Cu" "In15.Cu")
		(hatch none 0.5)
		(connect_pads
			(clearance 0)
		)
		(min_thickness 0.25)
		(keepout
			(tracks not_allowed)
			(vias allowed)
			(pads allowed)
			(copperpour not_allowed)
			(footprints allowed)
		)
		(placement
			(enabled no)
			(sheetname "")
		)
		(fill yes
			(thermal_gap 0.5)
			(thermal_bridge_width 0.5)
			(island_removal_mode 0)
		)
		(polygon
			(pts
				(arc
					(start 114.739674 -272.466308)
					(mid 114.109754 -272.466308)
					(end 114.739674 -272.466308)
				)
			)
		)
	)
	(zone
		(layers "B.Cu" "In15.Cu")
		(hatch none 0.5)
		(connect_pads
			(clearance 0)
		)
		(min_thickness 0.25)
		(keepout
			(tracks not_allowed)
			(vias allowed)
			(pads allowed)
			(copperpour not_allowed)
			(footprints allowed)
		)
		(placement
			(enabled no)
			(sheetname "")
		)
		(fill yes
			(thermal_gap 0.5)
			(thermal_bridge_width 0.5)
			(island_removal_mode 0)
		)
		(polygon
			(pts
				(arc
					(start 300.15815 -306.135024)
					(mid 299.49013 -306.135024)
					(end 300.15815 -306.135024)
				)
			)
		)
	)
	(zone
		(layers "B.Cu" "In15.Cu")
		(hatch none 0.5)
		(connect_pads
			(clearance 0)
		)
		(min_thickness 0.25)
		(keepout
			(tracks not_allowed)
			(vias allowed)
			(pads allowed)
			(copperpour not_allowed)
			(footprints allowed)
		)
		(placement
			(enabled no)
			(sheetname "")
		)
		(fill yes
			(thermal_gap 0.5)
			(thermal_bridge_width 0.5)
			(island_removal_mode 0)
		)
		(polygon
			(pts
				(arc
					(start 89.536016 -231.524302)
					(mid 88.906096 -231.524302)
					(end 89.536016 -231.524302)
				)
			)
		)
	)
	(zone
		(layers "B.Cu" "In15.Cu")
		(hatch none 0.5)
		(connect_pads
			(clearance 0)
		)
		(min_thickness 0.25)
		(keepout
			(tracks not_allowed)
			(vias allowed)
			(pads allowed)
			(copperpour not_allowed)
			(footprints allowed)
		)
		(placement
			(enabled no)
			(sheetname "")
		)
		(fill yes
			(thermal_gap 0.5)
			(thermal_bridge_width 0.5)
			(island_removal_mode 0)
		)
		(polygon
			(pts
				(arc
					(start 424.346116 -278.085042)
					(mid 423.678096 -278.085042)
					(end 424.346116 -278.085042)
				)
			)
		)
	)
	(zone
		(layers "B.Cu" "In15.Cu")
		(hatch none 0.5)
		(connect_pads
			(clearance 0)
		)
		(min_thickness 0.25)
		(keepout
			(tracks not_allowed)
			(vias allowed)
			(pads allowed)
			(copperpour not_allowed)
			(footprints allowed)
		)
		(placement
			(enabled no)
			(sheetname "")
		)
		(fill yes
			(thermal_gap 0.5)
			(thermal_bridge_width 0.5)
			(island_removal_mode 0)
		)
		(polygon
			(pts
				(arc
					(start 383.059686 -225.85426)
					(mid 382.429766 -225.85426)
					(end 383.059686 -225.85426)
				)
			)
		)
	)
	(zone
		(layers "B.Cu" "In15.Cu")
		(hatch none 0.5)
		(connect_pads
			(clearance 0)
		)
		(min_thickness 0.25)
		(keepout
			(tracks not_allowed)
			(vias allowed)
			(pads allowed)
			(copperpour not_allowed)
			(footprints allowed)
		)
		(placement
			(enabled no)
			(sheetname "")
		)
		(fill yes
			(thermal_gap 0.5)
			(thermal_bridge_width 0.5)
			(island_removal_mode 0)
		)
		(polygon
			(pts
				(arc
					(start 88.126062 -229.094538)
					(mid 87.496142 -229.094538)
					(end 88.126062 -229.094538)
				)
			)
		)
	)
	(zone
		(layers "B.Cu" "In15.Cu")
		(hatch none 0.5)
		(connect_pads
			(clearance 0)
		)
		(min_thickness 0.25)
		(keepout
			(tracks not_allowed)
			(vias allowed)
			(pads allowed)
			(copperpour not_allowed)
			(footprints allowed)
		)
		(placement
			(enabled no)
			(sheetname "")
		)
		(fill yes
			(thermal_gap 0.5)
			(thermal_bridge_width 0.5)
			(island_removal_mode 0)
		)
		(polygon
			(pts
				(arc
					(start 176.406048 -284.885384)
					(mid 175.738028 -284.885384)
					(end 176.406048 -284.885384)
				)
			)
		)
	)
	(zone
		(layers "B.Cu" "In15.Cu")
		(hatch none 0.5)
		(connect_pads
			(clearance 0)
		)
		(min_thickness 0.25)
		(keepout
			(tracks not_allowed)
			(vias allowed)
			(pads allowed)
			(copperpour not_allowed)
			(footprints allowed)
		)
		(placement
			(enabled no)
			(sheetname "")
		)
		(fill yes
			(thermal_gap 0.5)
			(thermal_bridge_width 0.5)
			(island_removal_mode 0)
		)
		(polygon
			(pts
				(arc
					(start 337.776058 -279.756108)
					(mid 337.146138 -279.756108)
					(end 337.776058 -279.756108)
				)
			)
		)
	)
	(zone
		(layers "B.Cu" "In15.Cu")
		(hatch none 0.5)
		(connect_pads
			(clearance 0)
		)
		(min_thickness 0.25)
		(keepout
			(tracks not_allowed)
			(vias allowed)
			(pads allowed)
			(copperpour not_allowed)
			(footprints allowed)
		)
		(placement
			(enabled no)
			(sheetname "")
		)
		(fill yes
			(thermal_gap 0.5)
			(thermal_bridge_width 0.5)
			(island_removal_mode 0)
		)
		(polygon
			(pts
				(arc
					(start 123.650502 -392.429238)
					(mid 122.982482 -392.429238)
					(end 123.650502 -392.429238)
				)
			)
		)
	)
	(zone
		(layers "B.Cu" "In15.Cu")
		(hatch none 0.5)
		(connect_pads
			(clearance 0)
		)
		(min_thickness 0.25)
		(keepout
			(tracks not_allowed)
			(vias allowed)
			(pads allowed)
			(copperpour not_allowed)
			(footprints allowed)
		)
		(placement
			(enabled no)
			(sheetname "")
		)
		(fill yes
			(thermal_gap 0.5)
			(thermal_bridge_width 0.5)
			(island_removal_mode 0)
		)
		(polygon
			(pts
				(arc
					(start 63.036958 -434.48986)
					(mid 62.262766 -434.48986)
					(end 63.036958 -434.48986)
				)
			)
		)
	)
	(zone
		(layers "B.Cu" "In15.Cu")
		(hatch none 0.5)
		(connect_pads
			(clearance 0)
		)
		(min_thickness 0.25)
		(keepout
			(tracks not_allowed)
			(vias allowed)
			(pads allowed)
			(copperpour not_allowed)
			(footprints allowed)
		)
		(placement
			(enabled no)
			(sheetname "")
		)
		(fill yes
			(thermal_gap 0.5)
			(thermal_bridge_width 0.5)
			(island_removal_mode 0)
		)
		(polygon
			(pts
				(arc
					(start 52.218082 -262.785352)
					(mid 51.550062 -262.785352)
					(end 52.218082 -262.785352)
				)
			)
		)
	)
	(zone
		(layers "B.Cu" "In15.Cu")
		(hatch none 0.5)
		(connect_pads
			(clearance 0)
		)
		(min_thickness 0.25)
		(keepout
			(tracks not_allowed)
			(vias allowed)
			(pads allowed)
			(copperpour not_allowed)
			(footprints allowed)
		)
		(placement
			(enabled no)
			(sheetname "")
		)
		(fill yes
			(thermal_gap 0.5)
			(thermal_bridge_width 0.5)
			(island_removal_mode 0)
		)
		(polygon
			(pts
				(arc
					(start 300.15815 -278.085042)
					(mid 299.49013 -278.085042)
					(end 300.15815 -278.085042)
				)
			)
		)
	)
	(zone
		(layers "B.Cu" "In15.Cu")
		(hatch none 0.5)
		(connect_pads
			(clearance 0)
		)
		(min_thickness 0.25)
		(keepout
			(tracks not_allowed)
			(vias allowed)
			(pads allowed)
			(copperpour not_allowed)
			(footprints allowed)
		)
		(placement
			(enabled no)
			(sheetname "")
		)
		(fill yes
			(thermal_gap 0.5)
			(thermal_bridge_width 0.5)
			(island_removal_mode 0)
		)
		(polygon
			(pts
				(arc
					(start 116.789708 -241.244374)
					(mid 116.159788 -241.244374)
					(end 116.789708 -241.244374)
				)
			)
		)
	)
	(zone
		(layers "B.Cu" "In15.Cu")
		(hatch none 0.5)
		(connect_pads
			(clearance 0)
		)
		(min_thickness 0.25)
		(keepout
			(tracks not_allowed)
			(vias allowed)
			(pads allowed)
			(copperpour not_allowed)
			(footprints allowed)
		)
		(placement
			(enabled no)
			(sheetname "")
		)
		(fill yes
			(thermal_gap 0.5)
			(thermal_bridge_width 0.5)
			(island_removal_mode 0)
		)
		(polygon
			(pts
				(arc
					(start 424.346116 -204.985112)
					(mid 423.678096 -204.985112)
					(end 424.346116 -204.985112)
				)
			)
		)
	)
	(zone
		(layers "B.Cu" "In15.Cu")
		(hatch none 0.5)
		(connect_pads
			(clearance 0)
		)
		(min_thickness 0.25)
		(keepout
			(tracks not_allowed)
			(vias allowed)
			(pads allowed)
			(copperpour not_allowed)
			(footprints allowed)
		)
		(placement
			(enabled no)
			(sheetname "")
		)
		(fill yes
			(thermal_gap 0.5)
			(thermal_bridge_width 0.5)
			(island_removal_mode 0)
		)
		(polygon
			(pts
				(arc
					(start 136.8298 -282.996386)
					(mid 136.19988 -282.996386)
					(end 136.8298 -282.996386)
				)
			)
		)
	)
	(zone
		(layers "B.Cu" "In15.Cu")
		(hatch none 0.5)
		(connect_pads
			(clearance 0)
		)
		(min_thickness 0.25)
		(keepout
			(tracks not_allowed)
			(vias allowed)
			(pads allowed)
			(copperpour not_allowed)
			(footprints allowed)
		)
		(placement
			(enabled no)
			(sheetname "")
		)
		(fill yes
			(thermal_gap 0.5)
			(thermal_bridge_width 0.5)
			(island_removal_mode 0)
		)
		(polygon
			(pts
				(arc
					(start 296.058082 -232.184956)
					(mid 295.390062 -232.184956)
					(end 296.058082 -232.184956)
				)
			)
		)
	)
	(zone
		(layers "B.Cu" "In15.Cu")
		(hatch none 0.5)
		(connect_pads
			(clearance 0)
		)
		(min_thickness 0.25)
		(keepout
			(tracks not_allowed)
			(vias allowed)
			(pads allowed)
			(copperpour not_allowed)
			(footprints allowed)
		)
		(placement
			(enabled no)
			(sheetname "")
		)
		(fill yes
			(thermal_gap 0.5)
			(thermal_bridge_width 0.5)
			(island_removal_mode 0)
		)
		(polygon
			(pts
				(arc
					(start 296.058082 -211.784946)
					(mid 295.390062 -211.784946)
					(end 296.058082 -211.784946)
				)
			)
		)
	)
	(zone
		(layers "B.Cu" "In15.Cu")
		(hatch none 0.5)
		(connect_pads
			(clearance 0)
		)
		(min_thickness 0.25)
		(keepout
			(tracks not_allowed)
			(vias allowed)
			(pads allowed)
			(copperpour not_allowed)
			(footprints allowed)
		)
		(placement
			(enabled no)
			(sheetname "")
		)
		(fill yes
			(thermal_gap 0.5)
			(thermal_bridge_width 0.5)
			(island_removal_mode 0)
		)
		(polygon
			(pts
				(arc
					(start 123.669806 -271.656302)
					(mid 123.039886 -271.656302)
					(end 123.669806 -271.656302)
				)
			)
		)
	)
	(zone
		(layers "B.Cu" "In15.Cu")
		(hatch none 0.5)
		(connect_pads
			(clearance 0)
		)
		(min_thickness 0.25)
		(keepout
			(tracks not_allowed)
			(vias allowed)
			(pads allowed)
			(copperpour not_allowed)
			(footprints allowed)
		)
		(placement
			(enabled no)
			(sheetname "")
		)
		(fill yes
			(thermal_gap 0.5)
			(thermal_bridge_width 0.5)
			(island_removal_mode 0)
		)
		(polygon
			(pts
				(arc
					(start 48.118014 -232.18521)
					(mid 47.449994 -232.18521)
					(end 48.118014 -232.18521)
				)
			)
		)
	)
	(zone
		(layers "B.Cu" "In15.Cu")
		(hatch none 0.5)
		(connect_pads
			(clearance 0)
		)
		(min_thickness 0.25)
		(keepout
			(tracks not_allowed)
			(vias allowed)
			(pads allowed)
			(copperpour not_allowed)
			(footprints allowed)
		)
		(placement
			(enabled no)
			(sheetname "")
		)
		(fill yes
			(thermal_gap 0.5)
			(thermal_bridge_width 0.5)
			(island_removal_mode 0)
		)
		(polygon
			(pts
				(arc
					(start 420.246048 -213.484968)
					(mid 419.578028 -213.484968)
					(end 420.246048 -213.484968)
				)
			)
		)
	)
	(zone
		(layers "B.Cu" "In15.Cu")
		(hatch none 0.5)
		(connect_pads
			(clearance 0)
		)
		(min_thickness 0.25)
		(keepout
			(tracks not_allowed)
			(vias allowed)
			(pads allowed)
			(copperpour not_allowed)
			(footprints allowed)
		)
		(placement
			(enabled no)
			(sheetname "")
		)
		(fill yes
			(thermal_gap 0.5)
			(thermal_bridge_width 0.5)
			(island_removal_mode 0)
		)
		(polygon
			(pts
				(arc
					(start 84.278216 -392.429238)
					(mid 83.610196 -392.429238)
					(end 84.278216 -392.429238)
				)
			)
		)
	)
	(zone
		(layers "B.Cu" "In15.Cu")
		(hatch none 0.5)
		(connect_pads
			(clearance 0)
		)
		(min_thickness 0.25)
		(keepout
			(tracks not_allowed)
			(vias allowed)
			(pads allowed)
			(copperpour not_allowed)
			(footprints allowed)
		)
		(placement
			(enabled no)
			(sheetname "")
		)
		(fill yes
			(thermal_gap 0.5)
			(thermal_bridge_width 0.5)
			(island_removal_mode 0)
		)
		(polygon
			(pts
				(arc
					(start 48.118014 -295.9354)
					(mid 47.449994 -295.9354)
					(end 48.118014 -295.9354)
				)
			)
		)
	)
	(zone
		(layers "B.Cu" "In15.Cu")
		(hatch none 0.5)
		(connect_pads
			(clearance 0)
		)
		(min_thickness 0.25)
		(keepout
			(tracks not_allowed)
			(vias allowed)
			(pads allowed)
			(copperpour not_allowed)
			(footprints allowed)
		)
		(placement
			(enabled no)
			(sheetname "")
		)
		(fill yes
			(thermal_gap 0.5)
			(thermal_bridge_width 0.5)
			(island_removal_mode 0)
		)
		(polygon
			(pts
				(arc
					(start 91.478354 -392.429238)
					(mid 90.810334 -392.429238)
					(end 91.478354 -392.429238)
				)
			)
		)
	)
	(zone
		(layers "B.Cu" "In15.Cu")
		(hatch none 0.5)
		(connect_pads
			(clearance 0)
		)
		(min_thickness 0.25)
		(keepout
			(tracks not_allowed)
			(vias allowed)
			(pads allowed)
			(copperpour not_allowed)
			(footprints allowed)
		)
		(placement
			(enabled no)
			(sheetname "")
		)
		(fill yes
			(thermal_gap 0.5)
			(thermal_bridge_width 0.5)
			(island_removal_mode 0)
		)
		(polygon
			(pts
				(arc
					(start 399.137124 -433.289964)
					(mid 398.362932 -433.289964)
					(end 399.137124 -433.289964)
				)
			)
		)
	)
	(zone
		(layers "B.Cu" "In15.Cu")
		(hatch none 0.5)
		(connect_pads
			(clearance 0)
		)
		(min_thickness 0.25)
		(keepout
			(tracks not_allowed)
			(vias allowed)
			(pads allowed)
			(copperpour not_allowed)
			(footprints allowed)
		)
		(placement
			(enabled no)
			(sheetname "")
		)
		(fill yes
			(thermal_gap 0.5)
			(thermal_bridge_width 0.5)
			(island_removal_mode 0)
		)
		(polygon
			(pts
				(arc
					(start 120.849644 -270.03629)
					(mid 120.219724 -270.03629)
					(end 120.849644 -270.03629)
				)
			)
		)
	)
	(zone
		(layers "B.Cu" "In15.Cu")
		(hatch none 0.5)
		(connect_pads
			(clearance 0)
		)
		(min_thickness 0.25)
		(keepout
			(tracks not_allowed)
			(vias allowed)
			(pads allowed)
			(copperpour not_allowed)
			(footprints allowed)
		)
		(placement
			(enabled no)
			(sheetname "")
		)
		(fill yes
			(thermal_gap 0.5)
			(thermal_bridge_width 0.5)
			(island_removal_mode 0)
		)
		(polygon
			(pts
				(arc
					(start 48.118014 -250.035314)
					(mid 47.449994 -250.035314)
					(end 48.118014 -250.035314)
				)
			)
		)
	)
	(zone
		(layers "B.Cu" "In15.Cu")
		(hatch none 0.5)
		(connect_pads
			(clearance 0)
		)
		(min_thickness 0.25)
		(keepout
			(tracks not_allowed)
			(vias allowed)
			(pads allowed)
			(copperpour not_allowed)
			(footprints allowed)
		)
		(placement
			(enabled no)
			(sheetname "")
		)
		(fill yes
			(thermal_gap 0.5)
			(thermal_bridge_width 0.5)
			(island_removal_mode 0)
		)
		(polygon
			(pts
				(arc
					(start 382.589786 -241.24412)
					(mid 381.959866 -241.24412)
					(end 382.589786 -241.24412)
				)
			)
		)
	)
	(zone
		(layers "B.Cu" "In15.Cu")
		(hatch none 0.5)
		(connect_pads
			(clearance 0)
		)
		(min_thickness 0.25)
		(keepout
			(tracks not_allowed)
			(vias allowed)
			(pads allowed)
			(copperpour not_allowed)
			(footprints allowed)
		)
		(placement
			(enabled no)
			(sheetname "")
		)
		(fill yes
			(thermal_gap 0.5)
			(thermal_bridge_width 0.5)
			(island_removal_mode 0)
		)
		(polygon
			(pts
				(arc
					(start 300.15815 -300.185074)
					(mid 299.49013 -300.185074)
					(end 300.15815 -300.185074)
				)
			)
		)
	)
	(zone
		(layers "B.Cu" "In15.Cu")
		(hatch none 0.5)
		(connect_pads
			(clearance 0)
		)
		(min_thickness 0.25)
		(keepout
			(tracks not_allowed)
			(vias allowed)
			(pads allowed)
			(copperpour not_allowed)
			(footprints allowed)
		)
		(placement
			(enabled no)
			(sheetname "")
		)
		(fill yes
			(thermal_gap 0.5)
			(thermal_bridge_width 0.5)
			(island_removal_mode 0)
		)
		(polygon
			(pts
				(arc
					(start 420.246048 -210.935062)
					(mid 419.578028 -210.935062)
					(end 420.246048 -210.935062)
				)
			)
		)
	)
	(zone
		(layers "B.Cu" "In15.Cu")
		(hatch none 0.5)
		(connect_pads
			(clearance 0)
		)
		(min_thickness 0.25)
		(keepout
			(tracks not_allowed)
			(vias allowed)
			(pads allowed)
			(copperpour not_allowed)
			(footprints allowed)
		)
		(placement
			(enabled no)
			(sheetname "")
		)
		(fill yes
			(thermal_gap 0.5)
			(thermal_bridge_width 0.5)
			(island_removal_mode 0)
		)
		(polygon
			(pts
				(arc
					(start 89.36609 -274.08632)
					(mid 88.73617 -274.08632)
					(end 89.36609 -274.08632)
				)
			)
		)
	)
	(zone
		(layers "B.Cu" "In15.Cu")
		(hatch none 0.5)
		(connect_pads
			(clearance 0)
		)
		(min_thickness 0.25)
		(keepout
			(tracks not_allowed)
			(vias allowed)
			(pads allowed)
			(copperpour not_allowed)
			(footprints allowed)
		)
		(placement
			(enabled no)
			(sheetname "")
		)
		(fill yes
			(thermal_gap 0.5)
			(thermal_bridge_width 0.5)
			(island_removal_mode 0)
		)
		(polygon
			(pts
				(arc
					(start 376.050556 -400.811238)
					(mid 375.382536 -400.811238)
					(end 376.050556 -400.811238)
				)
			)
		)
	)
	(zone
		(layers "B.Cu" "In15.Cu")
		(hatch none 0.5)
		(connect_pads
			(clearance 0)
		)
		(min_thickness 0.25)
		(keepout
			(tracks not_allowed)
			(vias allowed)
			(pads allowed)
			(copperpour not_allowed)
			(footprints allowed)
		)
		(placement
			(enabled no)
			(sheetname "")
		)
		(fill yes
			(thermal_gap 0.5)
			(thermal_bridge_width 0.5)
			(island_removal_mode 0)
		)
		(polygon
			(pts
				(arc
					(start 382.589786 -233.14406)
					(mid 381.959866 -233.14406)
					(end 382.589786 -233.14406)
				)
			)
		)
	)
	(zone
		(layers "B.Cu" "In15.Cu")
		(hatch none 0.5)
		(connect_pads
			(clearance 0)
		)
		(min_thickness 0.25)
		(keepout
			(tracks not_allowed)
			(vias allowed)
			(pads allowed)
			(copperpour not_allowed)
			(footprints allowed)
		)
		(placement
			(enabled no)
			(sheetname "")
		)
		(fill yes
			(thermal_gap 0.5)
			(thermal_bridge_width 0.5)
			(island_removal_mode 0)
		)
		(polygon
			(pts
				(arc
					(start 136.529826 -246.10441)
					(mid 135.899906 -246.10441)
					(end 136.529826 -246.10441)
				)
			)
		)
	)
	(zone
		(layers "B.Cu" "In15.Cu")
		(hatch none 0.5)
		(connect_pads
			(clearance 0)
		)
		(min_thickness 0.25)
		(keepout
			(tracks not_allowed)
			(vias allowed)
			(pads allowed)
			(copperpour not_allowed)
			(footprints allowed)
		)
		(placement
			(enabled no)
			(sheetname "")
		)
		(fill yes
			(thermal_gap 0.5)
			(thermal_bridge_width 0.5)
			(island_removal_mode 0)
		)
		(polygon
			(pts
				(arc
					(start 405.137112 -434.289962)
					(mid 404.36292 -434.289962)
					(end 405.137112 -434.289962)
				)
			)
		)
	)
	(zone
		(layers "B.Cu" "In15.Cu")
		(hatch none 0.5)
		(connect_pads
			(clearance 0)
		)
		(min_thickness 0.25)
		(keepout
			(tracks not_allowed)
			(vias allowed)
			(pads allowed)
			(copperpour not_allowed)
			(footprints allowed)
		)
		(placement
			(enabled no)
			(sheetname "")
		)
		(fill yes
			(thermal_gap 0.5)
			(thermal_bridge_width 0.5)
			(island_removal_mode 0)
		)
		(polygon
			(pts
				(arc
					(start 90.037158 -435.489858)
					(mid 89.262966 -435.489858)
					(end 90.037158 -435.489858)
				)
			)
		)
	)
	(zone
		(layers "B.Cu" "In15.Cu")
		(hatch none 0.5)
		(connect_pads
			(clearance 0)
		)
		(min_thickness 0.25)
		(keepout
			(tracks not_allowed)
			(vias allowed)
			(pads allowed)
			(copperpour not_allowed)
			(footprints allowed)
		)
		(placement
			(enabled no)
			(sheetname "")
		)
		(fill yes
			(thermal_gap 0.5)
			(thermal_bridge_width 0.5)
			(island_removal_mode 0)
		)
		(polygon
			(pts
				(arc
					(start 382.589786 -250.964192)
					(mid 381.959866 -250.964192)
					(end 382.589786 -250.964192)
				)
			)
		)
	)
	(zone
		(layers "B.Cu" "In15.Cu")
		(hatch none 0.5)
		(connect_pads
			(clearance 0)
		)
		(min_thickness 0.25)
		(keepout
			(tracks not_allowed)
			(vias allowed)
			(pads allowed)
			(copperpour not_allowed)
			(footprints allowed)
		)
		(placement
			(enabled no)
			(sheetname "")
		)
		(fill yes
			(thermal_gap 0.5)
			(thermal_bridge_width 0.5)
			(island_removal_mode 0)
		)
		(polygon
			(pts
				(arc
					(start 382.88976 -266.796012)
					(mid 382.25984 -266.796012)
					(end 382.88976 -266.796012)
				)
			)
		)
	)
	(zone
		(layers "B.Cu" "In15.Cu")
		(hatch none 0.5)
		(connect_pads
			(clearance 0)
		)
		(min_thickness 0.25)
		(keepout
			(tracks not_allowed)
			(vias allowed)
			(pads allowed)
			(copperpour not_allowed)
			(footprints allowed)
		)
		(placement
			(enabled no)
			(sheetname "")
		)
		(fill yes
			(thermal_gap 0.5)
			(thermal_bridge_width 0.5)
			(island_removal_mode 0)
		)
		(polygon
			(pts
				(arc
					(start 172.30598 -221.135194)
					(mid 171.63796 -221.135194)
					(end 172.30598 -221.135194)
				)
			)
		)
	)
	(zone
		(layers "B.Cu" "In15.Cu")
		(hatch none 0.5)
		(connect_pads
			(clearance 0)
		)
		(min_thickness 0.25)
		(keepout
			(tracks not_allowed)
			(vias allowed)
			(pads allowed)
			(copperpour not_allowed)
			(footprints allowed)
		)
		(placement
			(enabled no)
			(sheetname "")
		)
		(fill yes
			(thermal_gap 0.5)
			(thermal_bridge_width 0.5)
			(island_removal_mode 0)
		)
		(polygon
			(pts
				(arc
					(start 424.346116 -292.535102)
					(mid 423.678096 -292.535102)
					(end 424.346116 -292.535102)
				)
			)
		)
	)
	(zone
		(layers "B.Cu" "In15.Cu")
		(hatch none 0.5)
		(connect_pads
			(clearance 0)
		)
		(min_thickness 0.25)
		(keepout
			(tracks not_allowed)
			(vias allowed)
			(pads allowed)
			(copperpour not_allowed)
			(footprints allowed)
		)
		(placement
			(enabled no)
			(sheetname "")
		)
		(fill yes
			(thermal_gap 0.5)
			(thermal_bridge_width 0.5)
			(island_removal_mode 0)
		)
		(polygon
			(pts
				(arc
					(start 156.591254 -371.49913)
					(mid 155.923234 -371.49913)
					(end 156.591254 -371.49913)
				)
			)
		)
	)
	(zone
		(layers "B.Cu" "In15.Cu")
		(hatch none 0.5)
		(connect_pads
			(clearance 0)
		)
		(min_thickness 0.25)
		(keepout
			(tracks not_allowed)
			(vias allowed)
			(pads allowed)
			(copperpour not_allowed)
			(footprints allowed)
		)
		(placement
			(enabled no)
			(sheetname "")
		)
		(fill yes
			(thermal_gap 0.5)
			(thermal_bridge_width 0.5)
			(island_removal_mode 0)
		)
		(polygon
			(pts
				(arc
					(start 48.118014 -204.135228)
					(mid 47.449994 -204.135228)
					(end 48.118014 -204.135228)
				)
			)
		)
	)
	(zone
		(layers "B.Cu" "In15.Cu")
		(hatch none 0.5)
		(connect_pads
			(clearance 0)
		)
		(min_thickness 0.25)
		(keepout
			(tracks not_allowed)
			(vias allowed)
			(pads allowed)
			(copperpour not_allowed)
			(footprints allowed)
		)
		(placement
			(enabled no)
			(sheetname "")
		)
		(fill yes
			(thermal_gap 0.5)
			(thermal_bridge_width 0.5)
			(island_removal_mode 0)
		)
		(polygon
			(pts
				(arc
					(start 52.218082 -261.08533)
					(mid 51.550062 -261.08533)
					(end 52.218082 -261.08533)
				)
			)
		)
	)
	(zone
		(layers "B.Cu" "In15.Cu")
		(hatch none 0.5)
		(connect_pads
			(clearance 0)
		)
		(min_thickness 0.25)
		(keepout
			(tracks not_allowed)
			(vias allowed)
			(pads allowed)
			(copperpour not_allowed)
			(footprints allowed)
		)
		(placement
			(enabled no)
			(sheetname "")
		)
		(fill yes
			(thermal_gap 0.5)
			(thermal_bridge_width 0.5)
			(island_removal_mode 0)
		)
		(polygon
			(pts
				(arc
					(start 335.595976 -228.284278)
					(mid 334.966056 -228.284278)
					(end 335.595976 -228.284278)
				)
			)
		)
	)
	(zone
		(layers "B.Cu" "In15.Cu")
		(hatch none 0.5)
		(connect_pads
			(clearance 0)
		)
		(min_thickness 0.25)
		(keepout
			(tracks not_allowed)
			(vias allowed)
			(pads allowed)
			(copperpour not_allowed)
			(footprints allowed)
		)
		(placement
			(enabled no)
			(sheetname "")
		)
		(fill yes
			(thermal_gap 0.5)
			(thermal_bridge_width 0.5)
			(island_removal_mode 0)
		)
		(polygon
			(pts
				(arc
					(start 52.218082 -290.835334)
					(mid 51.550062 -290.835334)
					(end 52.218082 -290.835334)
				)
			)
		)
	)
	(zone
		(layers "B.Cu" "In15.Cu")
		(hatch none 0.5)
		(connect_pads
			(clearance 0)
		)
		(min_thickness 0.25)
		(keepout
			(tracks not_allowed)
			(vias allowed)
			(pads allowed)
			(copperpour not_allowed)
			(footprints allowed)
		)
		(placement
			(enabled no)
			(sheetname "")
		)
		(fill yes
			(thermal_gap 0.5)
			(thermal_bridge_width 0.5)
			(island_removal_mode 0)
		)
		(polygon
			(pts
				(arc
					(start 141.392402 -382.36906)
					(mid 140.724382 -382.36906)
					(end 141.392402 -382.36906)
				)
			)
		)
	)
	(zone
		(layers "B.Cu" "In15.Cu")
		(hatch none 0.5)
		(connect_pads
			(clearance 0)
		)
		(min_thickness 0.25)
		(keepout
			(tracks not_allowed)
			(vias allowed)
			(pads allowed)
			(copperpour not_allowed)
			(footprints allowed)
		)
		(placement
			(enabled no)
			(sheetname "")
		)
		(fill yes
			(thermal_gap 0.5)
			(thermal_bridge_width 0.5)
			(island_removal_mode 0)
		)
		(polygon
			(pts
				(arc
					(start 52.218082 -231.335326)
					(mid 51.550062 -231.335326)
					(end 52.218082 -231.335326)
				)
			)
		)
	)
	(zone
		(layers "B.Cu" "In15.Cu")
		(hatch none 0.5)
		(connect_pads
			(clearance 0)
		)
		(min_thickness 0.25)
		(keepout
			(tracks not_allowed)
			(vias allowed)
			(pads allowed)
			(copperpour not_allowed)
			(footprints allowed)
		)
		(placement
			(enabled no)
			(sheetname "")
		)
		(fill yes
			(thermal_gap 0.5)
			(thermal_bridge_width 0.5)
			(island_removal_mode 0)
		)
		(polygon
			(pts
				(arc
					(start 345.936062 -242.864132)
					(mid 345.306142 -242.864132)
					(end 345.936062 -242.864132)
				)
			)
		)
	)
	(zone
		(layers "B.Cu" "In15.Cu")
		(hatch none 0.5)
		(connect_pads
			(clearance 0)
		)
		(min_thickness 0.25)
		(keepout
			(tracks not_allowed)
			(vias allowed)
			(pads allowed)
			(copperpour not_allowed)
			(footprints allowed)
		)
		(placement
			(enabled no)
			(sheetname "")
		)
		(fill yes
			(thermal_gap 0.5)
			(thermal_bridge_width 0.5)
			(island_removal_mode 0)
		)
		(polygon
			(pts
				(arc
					(start 88.426036 -267.606272)
					(mid 87.796116 -267.606272)
					(end 88.426036 -267.606272)
				)
			)
		)
	)
	(zone
		(layers "B.Cu" "In15.Cu")
		(hatch none 0.5)
		(connect_pads
			(clearance 0)
		)
		(min_thickness 0.25)
		(keepout
			(tracks not_allowed)
			(vias allowed)
			(pads allowed)
			(copperpour not_allowed)
			(footprints allowed)
		)
		(placement
			(enabled no)
			(sheetname "")
		)
		(fill yes
			(thermal_gap 0.5)
			(thermal_bridge_width 0.5)
			(island_removal_mode 0)
		)
		(polygon
			(pts
				(arc
					(start 135.119618 -240.434368)
					(mid 134.489698 -240.434368)
					(end 135.119618 -240.434368)
				)
			)
		)
	)
	(zone
		(layers "B.Cu" "In15.Cu")
		(hatch none 0.5)
		(connect_pads
			(clearance 0)
		)
		(min_thickness 0.25)
		(keepout
			(tracks not_allowed)
			(vias allowed)
			(pads allowed)
			(copperpour not_allowed)
			(footprints allowed)
		)
		(placement
			(enabled no)
			(sheetname "")
		)
		(fill yes
			(thermal_gap 0.5)
			(thermal_bridge_width 0.5)
			(island_removal_mode 0)
		)
		(polygon
			(pts
				(arc
					(start 122.429778 -241.244374)
					(mid 121.799858 -241.244374)
					(end 122.429778 -241.244374)
				)
			)
		)
	)
	(zone
		(layers "B.Cu" "In15.Cu")
		(hatch none 0.5)
		(connect_pads
			(clearance 0)
		)
		(min_thickness 0.25)
		(keepout
			(tracks not_allowed)
			(vias allowed)
			(pads allowed)
			(copperpour not_allowed)
			(footprints allowed)
		)
		(placement
			(enabled no)
			(sheetname "")
		)
		(fill yes
			(thermal_gap 0.5)
			(thermal_bridge_width 0.5)
			(island_removal_mode 0)
		)
		(polygon
			(pts
				(arc
					(start 134.949692 -279.756362)
					(mid 134.319772 -279.756362)
					(end 134.949692 -279.756362)
				)
			)
		)
	)
	(zone
		(layers "B.Cu" "In15.Cu")
		(hatch none 0.5)
		(connect_pads
			(clearance 0)
		)
		(min_thickness 0.25)
		(keepout
			(tracks not_allowed)
			(vias allowed)
			(pads allowed)
			(copperpour not_allowed)
			(footprints allowed)
		)
		(placement
			(enabled no)
			(sheetname "")
		)
		(fill yes
			(thermal_gap 0.5)
			(thermal_bridge_width 0.5)
			(island_removal_mode 0)
		)
		(polygon
			(pts
				(arc
					(start 420.246048 -238.985044)
					(mid 419.578028 -238.985044)
					(end 420.246048 -238.985044)
				)
			)
		)
	)
	(zone
		(layers "B.Cu" "In15.Cu")
		(hatch none 0.5)
		(connect_pads
			(clearance 0)
		)
		(min_thickness 0.25)
		(keepout
			(tracks not_allowed)
			(vias allowed)
			(pads allowed)
			(copperpour not_allowed)
			(footprints allowed)
		)
		(placement
			(enabled no)
			(sheetname "")
		)
		(fill yes
			(thermal_gap 0.5)
			(thermal_bridge_width 0.5)
			(island_removal_mode 0)
		)
		(polygon
			(pts
				(arc
					(start 382.136904 -433.289964)
					(mid 381.362712 -433.289964)
					(end 382.136904 -433.289964)
				)
			)
		)
	)
	(zone
		(layers "B.Cu" "In15.Cu")
		(hatch none 0.5)
		(connect_pads
			(clearance 0)
		)
		(min_thickness 0.25)
		(keepout
			(tracks not_allowed)
			(vias allowed)
			(pads allowed)
			(copperpour not_allowed)
			(footprints allowed)
		)
		(placement
			(enabled no)
			(sheetname "")
		)
		(fill yes
			(thermal_gap 0.5)
			(thermal_bridge_width 0.5)
			(island_removal_mode 0)
		)
		(polygon
			(pts
				(arc
					(start 424.346116 -296.78503)
					(mid 423.678096 -296.78503)
					(end 424.346116 -296.78503)
				)
			)
		)
	)
	(zone
		(layers "B.Cu" "In15.Cu")
		(hatch none 0.5)
		(connect_pads
			(clearance 0)
		)
		(min_thickness 0.25)
		(keepout
			(tracks not_allowed)
			(vias allowed)
			(pads allowed)
			(copperpour not_allowed)
			(footprints allowed)
		)
		(placement
			(enabled no)
			(sheetname "")
		)
		(fill yes
			(thermal_gap 0.5)
			(thermal_bridge_width 0.5)
			(island_removal_mode 0)
		)
		(polygon
			(pts
				(arc
					(start 135.119618 -251.774452)
					(mid 134.489698 -251.774452)
					(end 135.119618 -251.774452)
				)
			)
		)
	)
	(zone
		(layers "B.Cu" "In15.Cu")
		(hatch none 0.5)
		(connect_pads
			(clearance 0)
		)
		(min_thickness 0.25)
		(keepout
			(tracks not_allowed)
			(vias allowed)
			(pads allowed)
			(copperpour not_allowed)
			(footprints allowed)
		)
		(placement
			(enabled no)
			(sheetname "")
		)
		(fill yes
			(thermal_gap 0.5)
			(thermal_bridge_width 0.5)
			(island_removal_mode 0)
		)
		(polygon
			(pts
				(arc
					(start 48.118014 -302.735234)
					(mid 47.449994 -302.735234)
					(end 48.118014 -302.735234)
				)
			)
		)
	)
	(zone
		(layers "B.Cu" "In15.Cu")
		(hatch none 0.5)
		(connect_pads
			(clearance 0)
		)
		(min_thickness 0.25)
		(keepout
			(tracks not_allowed)
			(vias allowed)
			(pads allowed)
			(copperpour not_allowed)
			(footprints allowed)
		)
		(placement
			(enabled no)
			(sheetname "")
		)
		(fill yes
			(thermal_gap 0.5)
			(thermal_bridge_width 0.5)
			(island_removal_mode 0)
		)
		(polygon
			(pts
				(arc
					(start 424.346116 -276.38502)
					(mid 423.678096 -276.38502)
					(end 424.346116 -276.38502)
				)
			)
		)
	)
	(zone
		(layers "B.Cu" "In15.Cu")
		(hatch none 0.5)
		(connect_pads
			(clearance 0)
		)
		(min_thickness 0.25)
		(keepout
			(tracks not_allowed)
			(vias allowed)
			(pads allowed)
			(copperpour not_allowed)
			(footprints allowed)
		)
		(placement
			(enabled no)
			(sheetname "")
		)
		(fill yes
			(thermal_gap 0.5)
			(thermal_bridge_width 0.5)
			(island_removal_mode 0)
		)
		(polygon
			(pts
				(arc
					(start 172.30598 -297.635422)
					(mid 171.63796 -297.635422)
					(end 172.30598 -297.635422)
				)
			)
		)
	)
	(zone
		(layers "B.Cu" "In15.Cu")
		(hatch none 0.5)
		(connect_pads
			(clearance 0)
		)
		(min_thickness 0.25)
		(keepout
			(tracks not_allowed)
			(vias allowed)
			(pads allowed)
			(copperpour not_allowed)
			(footprints allowed)
		)
		(placement
			(enabled no)
			(sheetname "")
		)
		(fill yes
			(thermal_gap 0.5)
			(thermal_bridge_width 0.5)
			(island_removal_mode 0)
		)
		(polygon
			(pts
				(arc
					(start 300.15815 -221.985078)
					(mid 299.49013 -221.985078)
					(end 300.15815 -221.985078)
				)
			)
		)
	)
	(zone
		(layers "B.Cu" "In15.Cu")
		(hatch none 0.5)
		(connect_pads
			(clearance 0)
		)
		(min_thickness 0.25)
		(keepout
			(tracks not_allowed)
			(vias allowed)
			(pads allowed)
			(copperpour not_allowed)
			(footprints allowed)
		)
		(placement
			(enabled no)
			(sheetname "")
		)
		(fill yes
			(thermal_gap 0.5)
			(thermal_bridge_width 0.5)
			(island_removal_mode 0)
		)
		(polygon
			(pts
				(arc
					(start 48.118014 -306.985416)
					(mid 47.449994 -306.985416)
					(end 48.118014 -306.985416)
				)
			)
		)
	)
	(zone
		(layers "B.Cu" "In15.Cu")
		(hatch none 0.5)
		(connect_pads
			(clearance 0)
		)
		(min_thickness 0.25)
		(keepout
			(tracks not_allowed)
			(vias allowed)
			(pads allowed)
			(copperpour not_allowed)
			(footprints allowed)
		)
		(placement
			(enabled no)
			(sheetname "")
		)
		(fill yes
			(thermal_gap 0.5)
			(thermal_bridge_width 0.5)
			(island_removal_mode 0)
		)
		(polygon
			(pts
				(arc
					(start 172.30598 -272.98523)
					(mid 171.63796 -272.98523)
					(end 172.30598 -272.98523)
				)
			)
		)
	)
	(zone
		(layers "B.Cu" "In15.Cu")
		(hatch none 0.5)
		(connect_pads
			(clearance 0)
		)
		(min_thickness 0.25)
		(keepout
			(tracks not_allowed)
			(vias allowed)
			(pads allowed)
			(copperpour not_allowed)
			(footprints allowed)
		)
		(placement
			(enabled no)
			(sheetname "")
		)
		(fill yes
			(thermal_gap 0.5)
			(thermal_bridge_width 0.5)
			(island_removal_mode 0)
		)
		(polygon
			(pts
				(arc
					(start 117.089682 -270.03629)
					(mid 116.459762 -270.03629)
					(end 117.089682 -270.03629)
				)
			)
		)
	)
	(zone
		(layers "B.Cu" "In15.Cu")
		(hatch none 0.5)
		(connect_pads
			(clearance 0)
		)
		(min_thickness 0.25)
		(keepout
			(tracks not_allowed)
			(vias allowed)
			(pads allowed)
			(copperpour not_allowed)
			(footprints allowed)
		)
		(placement
			(enabled no)
			(sheetname "")
		)
		(fill yes
			(thermal_gap 0.5)
			(thermal_bridge_width 0.5)
			(island_removal_mode 0)
		)
		(polygon
			(pts
				(arc
					(start 122.450606 -393.292838)
					(mid 121.782586 -393.292838)
					(end 122.450606 -393.292838)
				)
			)
		)
	)
	(zone
		(layers "B.Cu" "In15.Cu")
		(hatch none 0.5)
		(connect_pads
			(clearance 0)
		)
		(min_thickness 0.25)
		(keepout
			(tracks not_allowed)
			(vias allowed)
			(pads allowed)
			(copperpour not_allowed)
			(footprints allowed)
		)
		(placement
			(enabled no)
			(sheetname "")
		)
		(fill yes
			(thermal_gap 0.5)
			(thermal_bridge_width 0.5)
			(island_removal_mode 0)
		)
		(polygon
			(pts
				(arc
					(start 88.426036 -283.806392)
					(mid 87.796116 -283.806392)
					(end 88.426036 -283.806392)
				)
			)
		)
	)
	(zone
		(layers "B.Cu" "In15.Cu")
		(hatch none 0.5)
		(connect_pads
			(clearance 0)
		)
		(min_thickness 0.25)
		(keepout
			(tracks not_allowed)
			(vias allowed)
			(pads allowed)
			(copperpour not_allowed)
			(footprints allowed)
		)
		(placement
			(enabled no)
			(sheetname "")
		)
		(fill yes
			(thermal_gap 0.5)
			(thermal_bridge_width 0.5)
			(island_removal_mode 0)
		)
		(polygon
			(pts
				(arc
					(start 420.246048 -318.035178)
					(mid 419.578028 -318.035178)
					(end 420.246048 -318.035178)
				)
			)
		)
	)
	(zone
		(layers "B.Cu" "In15.Cu")
		(hatch none 0.5)
		(connect_pads
			(clearance 0)
		)
		(min_thickness 0.25)
		(keepout
			(tracks not_allowed)
			(vias allowed)
			(pads allowed)
			(copperpour not_allowed)
			(footprints allowed)
		)
		(placement
			(enabled no)
			(sheetname "")
		)
		(fill yes
			(thermal_gap 0.5)
			(thermal_bridge_width 0.5)
			(island_removal_mode 0)
		)
		(polygon
			(pts
				(arc
					(start 89.536016 -236.384338)
					(mid 88.906096 -236.384338)
					(end 89.536016 -236.384338)
				)
			)
		)
	)
	(zone
		(layers "B.Cu" "In15.Cu")
		(hatch none 0.5)
		(connect_pads
			(clearance 0)
		)
		(min_thickness 0.25)
		(keepout
			(tracks not_allowed)
			(vias allowed)
			(pads allowed)
			(copperpour not_allowed)
			(footprints allowed)
		)
		(placement
			(enabled no)
			(sheetname "")
		)
		(fill yes
			(thermal_gap 0.5)
			(thermal_bridge_width 0.5)
			(island_removal_mode 0)
		)
		(polygon
			(pts
				(arc
					(start 382.589786 -236.384084)
					(mid 381.959866 -236.384084)
					(end 382.589786 -236.384084)
				)
			)
		)
	)
	(zone
		(layers "B.Cu" "In15.Cu")
		(hatch none 0.5)
		(connect_pads
			(clearance 0)
		)
		(min_thickness 0.25)
		(keepout
			(tracks not_allowed)
			(vias allowed)
			(pads allowed)
			(copperpour not_allowed)
			(footprints allowed)
		)
		(placement
			(enabled no)
			(sheetname "")
		)
		(fill yes
			(thermal_gap 0.5)
			(thermal_bridge_width 0.5)
			(island_removal_mode 0)
		)
		(polygon
			(pts
				(arc
					(start 300.15815 -304.435002)
					(mid 299.49013 -304.435002)
					(end 300.15815 -304.435002)
				)
			)
		)
	)
	(zone
		(layers "B.Cu" "In15.Cu")
		(hatch none 0.5)
		(connect_pads
			(clearance 0)
		)
		(min_thickness 0.25)
		(keepout
			(tracks not_allowed)
			(vias allowed)
			(pads allowed)
			(copperpour not_allowed)
			(footprints allowed)
		)
		(placement
			(enabled no)
			(sheetname "")
		)
		(fill yes
			(thermal_gap 0.5)
			(thermal_bridge_width 0.5)
			(island_removal_mode 0)
		)
		(polygon
			(pts
				(arc
					(start 338.036916 -435.489858)
					(mid 337.262724 -435.489858)
					(end 338.036916 -435.489858)
				)
			)
		)
	)
	(zone
		(layers "B.Cu" "In15.Cu")
		(hatch none 0.5)
		(connect_pads
			(clearance 0)
		)
		(min_thickness 0.25)
		(keepout
			(tracks not_allowed)
			(vias allowed)
			(pads allowed)
			(copperpour not_allowed)
			(footprints allowed)
		)
		(placement
			(enabled no)
			(sheetname "")
		)
		(fill yes
			(thermal_gap 0.5)
			(thermal_bridge_width 0.5)
			(island_removal_mode 0)
		)
		(polygon
			(pts
				(arc
					(start 336.06613 -255.014222)
					(mid 335.43621 -255.014222)
					(end 336.06613 -255.014222)
				)
			)
		)
	)
	(zone
		(layers "B.Cu" "In15.Cu")
		(hatch none 0.5)
		(connect_pads
			(clearance 0)
		)
		(min_thickness 0.25)
		(keepout
			(tracks not_allowed)
			(vias allowed)
			(pads allowed)
			(copperpour not_allowed)
			(footprints allowed)
		)
		(placement
			(enabled no)
			(sheetname "")
		)
		(fill yes
			(thermal_gap 0.5)
			(thermal_bridge_width 0.5)
			(island_removal_mode 0)
		)
		(polygon
			(pts
				(arc
					(start 310.10606 -393.69238)
					(mid 309.47614 -393.69238)
					(end 310.10606 -393.69238)
				)
			)
		)
	)
	(zone
		(layers "B.Cu" "In15.Cu")
		(hatch none 0.5)
		(connect_pads
			(clearance 0)
		)
		(min_thickness 0.25)
		(keepout
			(tracks not_allowed)
			(vias allowed)
			(pads allowed)
			(copperpour not_allowed)
			(footprints allowed)
		)
		(placement
			(enabled no)
			(sheetname "")
		)
		(fill yes
			(thermal_gap 0.5)
			(thermal_bridge_width 0.5)
			(island_removal_mode 0)
		)
		(polygon
			(pts
				(arc
					(start 300.15815 -206.685134)
					(mid 299.49013 -206.685134)
					(end 300.15815 -206.685134)
				)
			)
		)
	)
	(zone
		(layers "B.Cu" "In15.Cu")
		(hatch none 0.5)
		(connect_pads
			(clearance 0)
		)
		(min_thickness 0.25)
		(keepout
			(tracks not_allowed)
			(vias allowed)
			(pads allowed)
			(copperpour not_allowed)
			(footprints allowed)
		)
		(placement
			(enabled no)
			(sheetname "")
		)
		(fill yes
			(thermal_gap 0.5)
			(thermal_bridge_width 0.5)
			(island_removal_mode 0)
		)
		(polygon
			(pts
				(arc
					(start 384.469894 -238.004096)
					(mid 383.839974 -238.004096)
					(end 384.469894 -238.004096)
				)
			)
		)
	)
	(zone
		(layers "B.Cu" "In15.Cu")
		(hatch none 0.5)
		(connect_pads
			(clearance 0)
		)
		(min_thickness 0.25)
		(keepout
			(tracks not_allowed)
			(vias allowed)
			(pads allowed)
			(copperpour not_allowed)
			(footprints allowed)
		)
		(placement
			(enabled no)
			(sheetname "")
		)
		(fill yes
			(thermal_gap 0.5)
			(thermal_bridge_width 0.5)
			(island_removal_mode 0)
		)
		(polygon
			(pts
				(arc
					(start 296.058082 -215.18499)
					(mid 295.390062 -215.18499)
					(end 296.058082 -215.18499)
				)
			)
		)
	)
	(zone
		(layers "B.Cu" "In15.Cu")
		(hatch none 0.5)
		(connect_pads
			(clearance 0)
		)
		(min_thickness 0.25)
		(keepout
			(tracks not_allowed)
			(vias allowed)
			(pads allowed)
			(copperpour not_allowed)
			(footprints allowed)
		)
		(placement
			(enabled no)
			(sheetname "")
		)
		(fill yes
			(thermal_gap 0.5)
			(thermal_bridge_width 0.5)
			(island_removal_mode 0)
		)
		(polygon
			(pts
				(arc
					(start 172.30598 -302.735234)
					(mid 171.63796 -302.735234)
					(end 172.30598 -302.735234)
				)
			)
		)
	)
	(zone
		(layers "B.Cu" "In15.Cu")
		(hatch none 0.5)
		(connect_pads
			(clearance 0)
		)
		(min_thickness 0.25)
		(keepout
			(tracks not_allowed)
			(vias allowed)
			(pads allowed)
			(copperpour not_allowed)
			(footprints allowed)
		)
		(placement
			(enabled no)
			(sheetname "")
		)
		(fill yes
			(thermal_gap 0.5)
			(thermal_bridge_width 0.5)
			(island_removal_mode 0)
		)
		(polygon
			(pts
				(arc
					(start 337.306158 -287.045908)
					(mid 336.676238 -287.045908)
					(end 337.306158 -287.045908)
				)
			)
		)
	)
	(zone
		(layers "B.Cu" "In15.Cu")
		(hatch none 0.5)
		(connect_pads
			(clearance 0)
		)
		(min_thickness 0.25)
		(keepout
			(tracks not_allowed)
			(vias allowed)
			(pads allowed)
			(copperpour not_allowed)
			(footprints allowed)
		)
		(placement
			(enabled no)
			(sheetname "")
		)
		(fill yes
			(thermal_gap 0.5)
			(thermal_bridge_width 0.5)
			(island_removal_mode 0)
		)
		(polygon
			(pts
				(arc
					(start 48.118014 -221.135194)
					(mid 47.449994 -221.135194)
					(end 48.118014 -221.135194)
				)
			)
		)
	)
	(zone
		(layers "B.Cu" "In15.Cu")
		(hatch none 0.5)
		(connect_pads
			(clearance 0)
		)
		(min_thickness 0.25)
		(keepout
			(tracks not_allowed)
			(vias allowed)
			(pads allowed)
			(copperpour not_allowed)
			(footprints allowed)
		)
		(placement
			(enabled no)
			(sheetname "")
		)
		(fill yes
			(thermal_gap 0.5)
			(thermal_bridge_width 0.5)
			(island_removal_mode 0)
		)
		(polygon
			(pts
				(arc
					(start 116.789708 -242.864386)
					(mid 116.159788 -242.864386)
					(end 116.789708 -242.864386)
				)
			)
		)
	)
	(zone
		(layers "B.Cu" "In15.Cu")
		(hatch none 0.5)
		(connect_pads
			(clearance 0)
		)
		(min_thickness 0.25)
		(keepout
			(tracks not_allowed)
			(vias allowed)
			(pads allowed)
			(copperpour not_allowed)
			(footprints allowed)
		)
		(placement
			(enabled no)
			(sheetname "")
		)
		(fill yes
			(thermal_gap 0.5)
			(thermal_bridge_width 0.5)
			(island_removal_mode 0)
		)
		(polygon
			(pts
				(arc
					(start 48.118014 -284.035246)
					(mid 47.449994 -284.035246)
					(end 48.118014 -284.035246)
				)
			)
		)
	)
	(zone
		(layers "B.Cu" "In15.Cu")
		(hatch none 0.5)
		(connect_pads
			(clearance 0)
		)
		(min_thickness 0.25)
		(keepout
			(tracks not_allowed)
			(vias allowed)
			(pads allowed)
			(copperpour not_allowed)
			(footprints allowed)
		)
		(placement
			(enabled no)
			(sheetname "")
		)
		(fill yes
			(thermal_gap 0.5)
			(thermal_bridge_width 0.5)
			(island_removal_mode 0)
		)
		(polygon
			(pts
				(arc
					(start 48.118014 -246.63527)
					(mid 47.449994 -246.63527)
					(end 48.118014 -246.63527)
				)
			)
		)
	)
	(zone
		(layers "B.Cu" "In15.Cu")
		(hatch none 0.5)
		(connect_pads
			(clearance 0)
		)
		(min_thickness 0.25)
		(keepout
			(tracks not_allowed)
			(vias allowed)
			(pads allowed)
			(copperpour not_allowed)
			(footprints allowed)
		)
		(placement
			(enabled no)
			(sheetname "")
		)
		(fill yes
			(thermal_gap 0.5)
			(thermal_bridge_width 0.5)
			(island_removal_mode 0)
		)
		(polygon
			(pts
				(arc
					(start 352.516186 -242.864132)
					(mid 351.886266 -242.864132)
					(end 352.516186 -242.864132)
				)
			)
		)
	)
	(zone
		(layers "B.Cu" "In15.Cu")
		(hatch none 0.5)
		(connect_pads
			(clearance 0)
		)
		(min_thickness 0.25)
		(keepout
			(tracks not_allowed)
			(vias allowed)
			(pads allowed)
			(copperpour not_allowed)
			(footprints allowed)
		)
		(placement
			(enabled no)
			(sheetname "")
		)
		(fill yes
			(thermal_gap 0.5)
			(thermal_bridge_width 0.5)
			(island_removal_mode 0)
		)
		(polygon
			(pts
				(arc
					(start 424.346116 -261.085076)
					(mid 423.678096 -261.085076)
					(end 424.346116 -261.085076)
				)
			)
		)
	)
	(zone
		(layers "B.Cu" "In15.Cu")
		(hatch none 0.5)
		(connect_pads
			(clearance 0)
		)
		(min_thickness 0.25)
		(keepout
			(tracks not_allowed)
			(vias allowed)
			(pads allowed)
			(copperpour not_allowed)
			(footprints allowed)
		)
		(placement
			(enabled no)
			(sheetname "")
		)
		(fill yes
			(thermal_gap 0.5)
			(thermal_bridge_width 0.5)
			(island_removal_mode 0)
		)
		(polygon
			(pts
				(arc
					(start 172.30598 -278.935434)
					(mid 171.63796 -278.935434)
					(end 172.30598 -278.935434)
				)
			)
		)
	)
	(zone
		(layers "B.Cu" "In15.Cu")
		(hatch none 0.5)
		(connect_pads
			(clearance 0)
		)
		(min_thickness 0.25)
		(keepout
			(tracks not_allowed)
			(vias allowed)
			(pads allowed)
			(copperpour not_allowed)
			(footprints allowed)
		)
		(placement
			(enabled no)
			(sheetname "")
		)
		(fill yes
			(thermal_gap 0.5)
			(thermal_bridge_width 0.5)
			(island_removal_mode 0)
		)
		(polygon
			(pts
				(arc
					(start 172.30598 -289.98545)
					(mid 171.63796 -289.98545)
					(end 172.30598 -289.98545)
				)
			)
		)
	)
	(zone
		(layers "B.Cu" "In15.Cu")
		(hatch none 0.5)
		(connect_pads
			(clearance 0)
		)
		(min_thickness 0.25)
		(keepout
			(tracks not_allowed)
			(vias allowed)
			(pads allowed)
			(copperpour not_allowed)
			(footprints allowed)
		)
		(placement
			(enabled no)
			(sheetname "")
		)
		(fill yes
			(thermal_gap 0.5)
			(thermal_bridge_width 0.5)
			(island_removal_mode 0)
		)
		(polygon
			(pts
				(arc
					(start 336.06613 -229.094284)
					(mid 335.43621 -229.094284)
					(end 336.06613 -229.094284)
				)
			)
		)
	)
	(zone
		(layers "B.Cu" "In15.Cu")
		(hatch none 0.5)
		(connect_pads
			(clearance 0)
		)
		(min_thickness 0.25)
		(keepout
			(tracks not_allowed)
			(vias allowed)
			(pads allowed)
			(copperpour not_allowed)
			(footprints allowed)
		)
		(placement
			(enabled no)
			(sheetname "")
		)
		(fill yes
			(thermal_gap 0.5)
			(thermal_bridge_width 0.5)
			(island_removal_mode 0)
		)
		(polygon
			(pts
				(arc
					(start 89.536016 -252.584458)
					(mid 88.906096 -252.584458)
					(end 89.536016 -252.584458)
				)
			)
		)
	)
	(zone
		(layers "B.Cu" "In15.Cu")
		(hatch none 0.5)
		(connect_pads
			(clearance 0)
		)
		(min_thickness 0.25)
		(keepout
			(tracks not_allowed)
			(vias allowed)
			(pads allowed)
			(copperpour not_allowed)
			(footprints allowed)
		)
		(placement
			(enabled no)
			(sheetname "")
		)
		(fill yes
			(thermal_gap 0.5)
			(thermal_bridge_width 0.5)
			(island_removal_mode 0)
		)
		(polygon
			(pts
				(arc
					(start 424.346116 -264.48512)
					(mid 423.678096 -264.48512)
					(end 424.346116 -264.48512)
				)
			)
		)
	)
	(zone
		(layers "B.Cu" "In15.Cu")
		(hatch none 0.5)
		(connect_pads
			(clearance 0)
		)
		(min_thickness 0.25)
		(keepout
			(tracks not_allowed)
			(vias allowed)
			(pads allowed)
			(copperpour not_allowed)
			(footprints allowed)
		)
		(placement
			(enabled no)
			(sheetname "")
		)
		(fill yes
			(thermal_gap 0.5)
			(thermal_bridge_width 0.5)
			(island_removal_mode 0)
		)
		(polygon
			(pts
				(arc
					(start 424.346116 -290.83508)
					(mid 423.678096 -290.83508)
					(end 424.346116 -290.83508)
				)
			)
		)
	)
	(zone
		(layers "B.Cu" "In15.Cu")
		(hatch none 0.5)
		(connect_pads
			(clearance 0)
		)
		(min_thickness 0.25)
		(keepout
			(tracks not_allowed)
			(vias allowed)
			(pads allowed)
			(copperpour not_allowed)
			(footprints allowed)
		)
		(placement
			(enabled no)
			(sheetname "")
		)
		(fill yes
			(thermal_gap 0.5)
			(thermal_bridge_width 0.5)
			(island_removal_mode 0)
		)
		(polygon
			(pts
				(arc
					(start 134.949692 -274.896326)
					(mid 134.319772 -274.896326)
					(end 134.949692 -274.896326)
				)
			)
		)
	)
	(zone
		(layers "B.Cu" "In15.Cu")
		(hatch none 0.5)
		(connect_pads
			(clearance 0)
		)
		(min_thickness 0.25)
		(keepout
			(tracks not_allowed)
			(vias allowed)
			(pads allowed)
			(copperpour not_allowed)
			(footprints allowed)
		)
		(placement
			(enabled no)
			(sheetname "")
		)
		(fill yes
			(thermal_gap 0.5)
			(thermal_bridge_width 0.5)
			(island_removal_mode 0)
		)
		(polygon
			(pts
				(arc
					(start 337.306158 -288.66592)
					(mid 336.676238 -288.66592)
					(end 337.306158 -288.66592)
				)
			)
		)
	)
	(zone
		(layers "B.Cu" "In15.Cu")
		(hatch none 0.5)
		(connect_pads
			(clearance 0)
		)
		(min_thickness 0.25)
		(keepout
			(tracks not_allowed)
			(vias allowed)
			(pads allowed)
			(copperpour not_allowed)
			(footprints allowed)
		)
		(placement
			(enabled no)
			(sheetname "")
		)
		(fill yes
			(thermal_gap 0.5)
			(thermal_bridge_width 0.5)
			(island_removal_mode 0)
		)
		(polygon
			(pts
				(arc
					(start 88.426036 -290.286186)
					(mid 87.796116 -290.286186)
					(end 88.426036 -290.286186)
				)
			)
		)
	)
	(zone
		(layers "B.Cu" "In15.Cu")
		(hatch none 0.5)
		(connect_pads
			(clearance 0)
		)
		(min_thickness 0.25)
		(keepout
			(tracks not_allowed)
			(vias allowed)
			(pads allowed)
			(copperpour not_allowed)
			(footprints allowed)
		)
		(placement
			(enabled no)
			(sheetname "")
		)
		(fill yes
			(thermal_gap 0.5)
			(thermal_bridge_width 0.5)
			(island_removal_mode 0)
		)
		(polygon
			(pts
				(arc
					(start 172.30598 -286.585406)
					(mid 171.63796 -286.585406)
					(end 172.30598 -286.585406)
				)
			)
		)
	)
	(zone
		(layers "B.Cu" "In15.Cu")
		(hatch none 0.5)
		(connect_pads
			(clearance 0)
		)
		(min_thickness 0.25)
		(keepout
			(tracks not_allowed)
			(vias allowed)
			(pads allowed)
			(copperpour not_allowed)
			(footprints allowed)
		)
		(placement
			(enabled no)
			(sheetname "")
		)
		(fill yes
			(thermal_gap 0.5)
			(thermal_bridge_width 0.5)
			(island_removal_mode 0)
		)
		(polygon
			(pts
				(arc
					(start 311.706006 -394.385292)
					(mid 311.076086 -394.385292)
					(end 311.706006 -394.385292)
				)
			)
		)
	)
	(zone
		(layers "B.Cu" "In15.Cu")
		(hatch none 0.5)
		(connect_pads
			(clearance 0)
		)
		(min_thickness 0.25)
		(keepout
			(tracks not_allowed)
			(vias allowed)
			(pads allowed)
			(copperpour not_allowed)
			(footprints allowed)
		)
		(placement
			(enabled no)
			(sheetname "")
		)
		(fill yes
			(thermal_gap 0.5)
			(thermal_bridge_width 0.5)
			(island_removal_mode 0)
		)
		(polygon
			(pts
				(arc
					(start 48.118014 -280.635202)
					(mid 47.449994 -280.635202)
					(end 48.118014 -280.635202)
				)
			)
		)
	)
	(zone
		(layers "B.Cu" "In15.Cu")
		(hatch none 0.5)
		(connect_pads
			(clearance 0)
		)
		(min_thickness 0.25)
		(keepout
			(tracks not_allowed)
			(vias allowed)
			(pads allowed)
			(copperpour not_allowed)
			(footprints allowed)
		)
		(placement
			(enabled no)
			(sheetname "")
		)
		(fill yes
			(thermal_gap 0.5)
			(thermal_bridge_width 0.5)
			(island_removal_mode 0)
		)
		(polygon
			(pts
				(arc
					(start 373.65051 -400.811238)
					(mid 372.98249 -400.811238)
					(end 373.65051 -400.811238)
				)
			)
		)
	)
	(zone
		(layers "B.Cu" "In15.Cu")
		(hatch none 0.5)
		(connect_pads
			(clearance 0)
		)
		(min_thickness 0.25)
		(keepout
			(tracks not_allowed)
			(vias allowed)
			(pads allowed)
			(copperpour not_allowed)
			(footprints allowed)
		)
		(placement
			(enabled no)
			(sheetname "")
		)
		(fill yes
			(thermal_gap 0.5)
			(thermal_bridge_width 0.5)
			(island_removal_mode 0)
		)
		(polygon
			(pts
				(arc
					(start 136.359646 -270.846296)
					(mid 135.729726 -270.846296)
					(end 136.359646 -270.846296)
				)
			)
		)
	)
	(zone
		(layers "B.Cu" "In15.Cu")
		(hatch none 0.5)
		(connect_pads
			(clearance 0)
		)
		(min_thickness 0.25)
		(keepout
			(tracks not_allowed)
			(vias allowed)
			(pads allowed)
			(copperpour not_allowed)
			(footprints allowed)
		)
		(placement
			(enabled no)
			(sheetname "")
		)
		(fill yes
			(thermal_gap 0.5)
			(thermal_bridge_width 0.5)
			(island_removal_mode 0)
		)
		(polygon
			(pts
				(arc
					(start 48.118014 -227.935282)
					(mid 47.449994 -227.935282)
					(end 48.118014 -227.935282)
				)
			)
		)
	)
	(zone
		(layers "B.Cu" "In15.Cu")
		(hatch none 0.5)
		(connect_pads
			(clearance 0)
		)
		(min_thickness 0.25)
		(keepout
			(tracks not_allowed)
			(vias allowed)
			(pads allowed)
			(copperpour not_allowed)
			(footprints allowed)
		)
		(placement
			(enabled no)
			(sheetname "")
		)
		(fill yes
			(thermal_gap 0.5)
			(thermal_bridge_width 0.5)
			(island_removal_mode 0)
		)
		(polygon
			(pts
				(arc
					(start 337.006184 -245.29415)
					(mid 336.376264 -245.29415)
					(end 337.006184 -245.29415)
				)
			)
		)
	)
	(zone
		(layers "B.Cu" "In15.Cu")
		(hatch none 0.5)
		(connect_pads
			(clearance 0)
		)
		(min_thickness 0.25)
		(keepout
			(tracks not_allowed)
			(vias allowed)
			(pads allowed)
			(copperpour not_allowed)
			(footprints allowed)
		)
		(placement
			(enabled no)
			(sheetname "")
		)
		(fill yes
			(thermal_gap 0.5)
			(thermal_bridge_width 0.5)
			(island_removal_mode 0)
		)
		(polygon
			(pts
				(arc
					(start 337.306158 -274.086066)
					(mid 336.676238 -274.086066)
					(end 337.306158 -274.086066)
				)
			)
		)
	)
	(zone
		(layers "B.Cu" "In15.Cu")
		(hatch none 0.5)
		(connect_pads
			(clearance 0)
		)
		(min_thickness 0.25)
		(keepout
			(tracks not_allowed)
			(vias allowed)
			(pads allowed)
			(copperpour not_allowed)
			(footprints allowed)
		)
		(placement
			(enabled no)
			(sheetname "")
		)
		(fill yes
			(thermal_gap 0.5)
			(thermal_bridge_width 0.5)
			(island_removal_mode 0)
		)
		(polygon
			(pts
				(arc
					(start 384.299714 -274.086066)
					(mid 383.669794 -274.086066)
					(end 384.299714 -274.086066)
				)
			)
		)
	)
	(zone
		(layers "B.Cu" "In15.Cu")
		(hatch none 0.5)
		(connect_pads
			(clearance 0)
		)
		(min_thickness 0.25)
		(keepout
			(tracks not_allowed)
			(vias allowed)
			(pads allowed)
			(copperpour not_allowed)
			(footprints allowed)
		)
		(placement
			(enabled no)
			(sheetname "")
		)
		(fill yes
			(thermal_gap 0.5)
			(thermal_bridge_width 0.5)
			(island_removal_mode 0)
		)
		(polygon
			(pts
				(arc
					(start 89.36609 -277.326344)
					(mid 88.73617 -277.326344)
					(end 89.36609 -277.326344)
				)
			)
		)
	)
	(zone
		(layers "B.Cu" "In15.Cu")
		(hatch none 0.5)
		(connect_pads
			(clearance 0)
		)
		(min_thickness 0.25)
		(keepout
			(tracks not_allowed)
			(vias allowed)
			(pads allowed)
			(copperpour not_allowed)
			(footprints allowed)
		)
		(placement
			(enabled no)
			(sheetname "")
		)
		(fill yes
			(thermal_gap 0.5)
			(thermal_bridge_width 0.5)
			(island_removal_mode 0)
		)
		(polygon
			(pts
				(arc
					(start 304.106072 -393.69238)
					(mid 303.476152 -393.69238)
					(end 304.106072 -393.69238)
				)
			)
		)
	)
	(zone
		(layers "B.Cu" "In15.Cu")
		(hatch none 0.5)
		(connect_pads
			(clearance 0)
		)
		(min_thickness 0.25)
		(keepout
			(tracks not_allowed)
			(vias allowed)
			(pads allowed)
			(copperpour not_allowed)
			(footprints allowed)
		)
		(placement
			(enabled no)
			(sheetname "")
		)
		(fill yes
			(thermal_gap 0.5)
			(thermal_bridge_width 0.5)
			(island_removal_mode 0)
		)
		(polygon
			(pts
				(arc
					(start 325.036688 -434.289962)
					(mid 324.262496 -434.289962)
					(end 325.036688 -434.289962)
				)
			)
		)
	)
	(zone
		(layers "B.Cu" "In15.Cu")
		(hatch none 0.5)
		(connect_pads
			(clearance 0)
		)
		(min_thickness 0.25)
		(keepout
			(tracks not_allowed)
			(vias allowed)
			(pads allowed)
			(copperpour not_allowed)
			(footprints allowed)
		)
		(placement
			(enabled no)
			(sheetname "")
		)
		(fill yes
			(thermal_gap 0.5)
			(thermal_bridge_width 0.5)
			(island_removal_mode 0)
		)
		(polygon
			(pts
				(arc
					(start 159.156654 -369.03533)
					(mid 158.488634 -369.03533)
					(end 159.156654 -369.03533)
				)
			)
		)
	)
	(zone
		(layers "B.Cu" "In15.Cu")
		(hatch none 0.5)
		(connect_pads
			(clearance 0)
		)
		(min_thickness 0.25)
		(keepout
			(tracks not_allowed)
			(vias allowed)
			(pads allowed)
			(copperpour not_allowed)
			(footprints allowed)
		)
		(placement
			(enabled no)
			(sheetname "")
		)
		(fill yes
			(thermal_gap 0.5)
			(thermal_bridge_width 0.5)
			(island_removal_mode 0)
		)
		(polygon
			(pts
				(arc
					(start 420.246048 -226.235006)
					(mid 419.578028 -226.235006)
					(end 420.246048 -226.235006)
				)
			)
		)
	)
	(zone
		(layers "B.Cu" "In15.Cu")
		(hatch none 0.5)
		(connect_pads
			(clearance 0)
		)
		(min_thickness 0.25)
		(keepout
			(tracks not_allowed)
			(vias allowed)
			(pads allowed)
			(copperpour not_allowed)
			(footprints allowed)
		)
		(placement
			(enabled no)
			(sheetname "")
		)
		(fill yes
			(thermal_gap 0.5)
			(thermal_bridge_width 0.5)
			(island_removal_mode 0)
		)
		(polygon
			(pts
				(arc
					(start 425.36745 -377.41733)
					(mid 424.69943 -377.41733)
					(end 425.36745 -377.41733)
				)
			)
		)
	)
	(zone
		(layers "B.Cu" "In15.Cu")
		(hatch none 0.5)
		(connect_pads
			(clearance 0)
		)
		(min_thickness 0.25)
		(keepout
			(tracks not_allowed)
			(vias allowed)
			(pads allowed)
			(copperpour not_allowed)
			(footprints allowed)
		)
		(placement
			(enabled no)
			(sheetname "")
		)
		(fill yes
			(thermal_gap 0.5)
			(thermal_bridge_width 0.5)
			(island_removal_mode 0)
		)
		(polygon
			(pts
				(arc
					(start 300.15815 -231.335072)
					(mid 299.49013 -231.335072)
					(end 300.15815 -231.335072)
				)
			)
		)
	)
	(zone
		(layers "B.Cu" "In15.Cu")
		(hatch none 0.5)
		(connect_pads
			(clearance 0)
		)
		(min_thickness 0.25)
		(keepout
			(tracks not_allowed)
			(vias allowed)
			(pads allowed)
			(copperpour not_allowed)
			(footprints allowed)
		)
		(placement
			(enabled no)
			(sheetname "")
		)
		(fill yes
			(thermal_gap 0.5)
			(thermal_bridge_width 0.5)
			(island_removal_mode 0)
		)
		(polygon
			(pts
				(arc
					(start 300.15815 -289.135058)
					(mid 299.49013 -289.135058)
					(end 300.15815 -289.135058)
				)
			)
		)
	)
	(zone
		(layers "B.Cu" "In15.Cu")
		(hatch none 0.5)
		(connect_pads
			(clearance 0)
		)
		(min_thickness 0.25)
		(keepout
			(tracks not_allowed)
			(vias allowed)
			(pads allowed)
			(copperpour not_allowed)
			(footprints allowed)
		)
		(placement
			(enabled no)
			(sheetname "")
		)
		(fill yes
			(thermal_gap 0.5)
			(thermal_bridge_width 0.5)
			(island_removal_mode 0)
		)
		(polygon
			(pts
				(arc
					(start 118.85041 -393.292838)
					(mid 118.18239 -393.292838)
					(end 118.85041 -393.292838)
				)
			)
		)
	)
	(zone
		(layers "B.Cu" "In15.Cu")
		(hatch none 0.5)
		(connect_pads
			(clearance 0)
		)
		(min_thickness 0.25)
		(keepout
			(tracks not_allowed)
			(vias allowed)
			(pads allowed)
			(copperpour not_allowed)
			(footprints allowed)
		)
		(placement
			(enabled no)
			(sheetname "")
		)
		(fill yes
			(thermal_gap 0.5)
			(thermal_bridge_width 0.5)
			(island_removal_mode 0)
		)
		(polygon
			(pts
				(arc
					(start 340.277958 -400.811238)
					(mid 339.609938 -400.811238)
					(end 340.277958 -400.811238)
				)
			)
		)
	)
	(zone
		(layers "B.Cu" "In15.Cu")
		(hatch none 0.5)
		(connect_pads
			(clearance 0)
		)
		(min_thickness 0.25)
		(keepout
			(tracks not_allowed)
			(vias allowed)
			(pads allowed)
			(copperpour not_allowed)
			(footprints allowed)
		)
		(placement
			(enabled no)
			(sheetname "")
		)
		(fill yes
			(thermal_gap 0.5)
			(thermal_bridge_width 0.5)
			(island_removal_mode 0)
		)
		(polygon
			(pts
				(arc
					(start 50.506376 -385.31038)
					(mid 49.876456 -385.31038)
					(end 50.506376 -385.31038)
				)
			)
		)
	)
	(zone
		(layers "B.Cu" "In15.Cu")
		(hatch none 0.5)
		(connect_pads
			(clearance 0)
		)
		(min_thickness 0.25)
		(keepout
			(tracks not_allowed)
			(vias allowed)
			(pads allowed)
			(copperpour not_allowed)
			(footprints allowed)
		)
		(placement
			(enabled no)
			(sheetname "")
		)
		(fill yes
			(thermal_gap 0.5)
			(thermal_bridge_width 0.5)
			(island_removal_mode 0)
		)
		(polygon
			(pts
				(arc
					(start 122.429778 -242.864386)
					(mid 121.799858 -242.864386)
					(end 122.429778 -242.864386)
				)
			)
		)
	)
	(zone
		(layers "B.Cu" "In15.Cu")
		(hatch none 0.5)
		(connect_pads
			(clearance 0)
		)
		(min_thickness 0.25)
		(keepout
			(tracks not_allowed)
			(vias allowed)
			(pads allowed)
			(copperpour not_allowed)
			(footprints allowed)
		)
		(placement
			(enabled no)
			(sheetname "")
		)
		(fill yes
			(thermal_gap 0.5)
			(thermal_bridge_width 0.5)
			(island_removal_mode 0)
		)
		(polygon
			(pts
				(arc
					(start 52.218082 -269.58544)
					(mid 51.550062 -269.58544)
					(end 52.218082 -269.58544)
				)
			)
		)
	)
	(zone
		(layers "B.Cu" "In15.Cu")
		(hatch none 0.5)
		(connect_pads
			(clearance 0)
		)
		(min_thickness 0.25)
		(keepout
			(tracks not_allowed)
			(vias allowed)
			(pads allowed)
			(copperpour not_allowed)
			(footprints allowed)
		)
		(placement
			(enabled no)
			(sheetname "")
		)
		(fill yes
			(thermal_gap 0.5)
			(thermal_bridge_width 0.5)
			(island_removal_mode 0)
		)
		(polygon
			(pts
				(arc
					(start 52.218082 -317.185294)
					(mid 51.550062 -317.185294)
					(end 52.218082 -317.185294)
				)
			)
		)
	)
	(zone
		(layers "B.Cu" "In15.Cu")
		(hatch none 0.5)
		(connect_pads
			(clearance 0)
		)
		(min_thickness 0.25)
		(keepout
			(tracks not_allowed)
			(vias allowed)
			(pads allowed)
			(copperpour not_allowed)
			(footprints allowed)
		)
		(placement
			(enabled no)
			(sheetname "")
		)
		(fill yes
			(thermal_gap 0.5)
			(thermal_bridge_width 0.5)
			(island_removal_mode 0)
		)
		(polygon
			(pts
				(arc
					(start 172.30598 -285.735268)
					(mid 171.63796 -285.735268)
					(end 172.30598 -285.735268)
				)
			)
		)
	)
	(zone
		(layers "B.Cu" "In15.Cu")
		(hatch none 0.5)
		(connect_pads
			(clearance 0)
		)
		(min_thickness 0.25)
		(keepout
			(tracks not_allowed)
			(vias allowed)
			(pads allowed)
			(copperpour not_allowed)
			(footprints allowed)
		)
		(placement
			(enabled no)
			(sheetname "")
		)
		(fill yes
			(thermal_gap 0.5)
			(thermal_bridge_width 0.5)
			(island_removal_mode 0)
		)
		(polygon
			(pts
				(arc
					(start 420.246048 -198.185024)
					(mid 419.578028 -198.185024)
					(end 420.246048 -198.185024)
				)
			)
		)
	)
	(zone
		(layers "B.Cu" "In15.Cu")
		(hatch none 0.5)
		(connect_pads
			(clearance 0)
		)
		(min_thickness 0.25)
		(keepout
			(tracks not_allowed)
			(vias allowed)
			(pads allowed)
			(copperpour not_allowed)
			(footprints allowed)
		)
		(placement
			(enabled no)
			(sheetname "")
		)
		(fill yes
			(thermal_gap 0.5)
			(thermal_bridge_width 0.5)
			(island_removal_mode 0)
		)
		(polygon
			(pts
				(arc
					(start 89.066116 -246.914416)
					(mid 88.436196 -246.914416)
					(end 89.066116 -246.914416)
				)
			)
		)
	)
	(zone
		(layers "B.Cu" "In15.Cu")
		(hatch none 0.5)
		(connect_pads
			(clearance 0)
		)
		(min_thickness 0.25)
		(keepout
			(tracks not_allowed)
			(vias allowed)
			(pads allowed)
			(copperpour not_allowed)
			(footprints allowed)
		)
		(placement
			(enabled no)
			(sheetname "")
		)
		(fill yes
			(thermal_gap 0.5)
			(thermal_bridge_width 0.5)
			(island_removal_mode 0)
		)
		(polygon
			(pts
				(arc
					(start 134.949692 -261.93623)
					(mid 134.319772 -261.93623)
					(end 134.949692 -261.93623)
				)
			)
		)
	)
	(zone
		(layers "B.Cu" "In15.Cu")
		(hatch none 0.5)
		(connect_pads
			(clearance 0)
		)
		(min_thickness 0.25)
		(keepout
			(tracks not_allowed)
			(vias allowed)
			(pads allowed)
			(copperpour not_allowed)
			(footprints allowed)
		)
		(placement
			(enabled no)
			(sheetname "")
		)
		(fill yes
			(thermal_gap 0.5)
			(thermal_bridge_width 0.5)
			(island_removal_mode 0)
		)
		(polygon
			(pts
				(arc
					(start 424.346116 -311.23509)
					(mid 423.678096 -311.23509)
					(end 424.346116 -311.23509)
				)
			)
		)
	)
	(zone
		(layers "B.Cu" "In15.Cu")
		(hatch none 0.5)
		(connect_pads
			(clearance 0)
		)
		(min_thickness 0.25)
		(keepout
			(tracks not_allowed)
			(vias allowed)
			(pads allowed)
			(copperpour not_allowed)
			(footprints allowed)
		)
		(placement
			(enabled no)
			(sheetname "")
		)
		(fill yes
			(thermal_gap 0.5)
			(thermal_bridge_width 0.5)
			(island_removal_mode 0)
		)
		(polygon
			(pts
				(arc
					(start 87.955882 -291.096192)
					(mid 87.325962 -291.096192)
					(end 87.955882 -291.096192)
				)
			)
		)
	)
	(zone
		(layers "B.Cu" "In15.Cu")
		(hatch none 0.5)
		(connect_pads
			(clearance 0)
		)
		(min_thickness 0.25)
		(keepout
			(tracks not_allowed)
			(vias allowed)
			(pads allowed)
			(copperpour not_allowed)
			(footprints allowed)
		)
		(placement
			(enabled no)
			(sheetname "")
		)
		(fill yes
			(thermal_gap 0.5)
			(thermal_bridge_width 0.5)
			(island_removal_mode 0)
		)
		(polygon
			(pts
				(arc
					(start 116.450364 -392.429238)
					(mid 115.782344 -392.429238)
					(end 116.450364 -392.429238)
				)
			)
		)
	)
	(zone
		(layers "B.Cu" "In15.Cu")
		(hatch none 0.5)
		(connect_pads
			(clearance 0)
		)
		(min_thickness 0.25)
		(keepout
			(tracks not_allowed)
			(vias allowed)
			(pads allowed)
			(copperpour not_allowed)
			(footprints allowed)
		)
		(placement
			(enabled no)
			(sheetname "")
		)
		(fill yes
			(thermal_gap 0.5)
			(thermal_bridge_width 0.5)
			(island_removal_mode 0)
		)
		(polygon
			(pts
				(arc
					(start 346.236036 -271.656048)
					(mid 345.606116 -271.656048)
					(end 346.236036 -271.656048)
				)
			)
		)
	)
	(zone
		(layers "B.Cu" "In15.Cu")
		(hatch none 0.5)
		(connect_pads
			(clearance 0)
		)
		(min_thickness 0.25)
		(keepout
			(tracks not_allowed)
			(vias allowed)
			(pads allowed)
			(copperpour not_allowed)
			(footprints allowed)
		)
		(placement
			(enabled no)
			(sheetname "")
		)
		(fill yes
			(thermal_gap 0.5)
			(thermal_bridge_width 0.5)
			(island_removal_mode 0)
		)
		(polygon
			(pts
				(arc
					(start 335.595976 -226.664266)
					(mid 334.966056 -226.664266)
					(end 335.595976 -226.664266)
				)
			)
		)
	)
	(zone
		(layers "B.Cu" "In15.Cu")
		(hatch none 0.5)
		(connect_pads
			(clearance 0)
		)
		(min_thickness 0.25)
		(keepout
			(tracks not_allowed)
			(vias allowed)
			(pads allowed)
			(copperpour not_allowed)
			(footprints allowed)
		)
		(placement
			(enabled no)
			(sheetname "")
		)
		(fill yes
			(thermal_gap 0.5)
			(thermal_bridge_width 0.5)
			(island_removal_mode 0)
		)
		(polygon
			(pts
				(arc
					(start 343.878154 -400.811238)
					(mid 343.210134 -400.811238)
					(end 343.878154 -400.811238)
				)
			)
		)
	)
	(zone
		(layers "B.Cu" "In15.Cu")
		(hatch none 0.5)
		(connect_pads
			(clearance 0)
		)
		(min_thickness 0.25)
		(keepout
			(tracks not_allowed)
			(vias allowed)
			(pads allowed)
			(copperpour not_allowed)
			(footprints allowed)
		)
		(placement
			(enabled no)
			(sheetname "")
		)
		(fill yes
			(thermal_gap 0.5)
			(thermal_bridge_width 0.5)
			(island_removal_mode 0)
		)
		(polygon
			(pts
				(arc
					(start 335.595976 -238.004096)
					(mid 334.966056 -238.004096)
					(end 335.595976 -238.004096)
				)
			)
		)
	)
	(zone
		(layers "B.Cu" "In15.Cu")
		(hatch none 0.5)
		(connect_pads
			(clearance 0)
		)
		(min_thickness 0.25)
		(keepout
			(tracks not_allowed)
			(vias allowed)
			(pads allowed)
			(copperpour not_allowed)
			(footprints allowed)
		)
		(placement
			(enabled no)
			(sheetname "")
		)
		(fill yes
			(thermal_gap 0.5)
			(thermal_bridge_width 0.5)
			(island_removal_mode 0)
		)
		(polygon
			(pts
				(arc
					(start 136.529826 -247.724422)
					(mid 135.899906 -247.724422)
					(end 136.529826 -247.724422)
				)
			)
		)
	)
	(zone
		(layers "B.Cu" "In15.Cu")
		(hatch none 0.5)
		(connect_pads
			(clearance 0)
		)
		(min_thickness 0.25)
		(keepout
			(tracks not_allowed)
			(vias allowed)
			(pads allowed)
			(copperpour not_allowed)
			(footprints allowed)
		)
		(placement
			(enabled no)
			(sheetname "")
		)
		(fill yes
			(thermal_gap 0.5)
			(thermal_bridge_width 0.5)
			(island_removal_mode 0)
		)
		(polygon
			(pts
				(arc
					(start 141.392402 -376.83186)
					(mid 140.724382 -376.83186)
					(end 141.392402 -376.83186)
				)
			)
		)
	)
	(zone
		(layers "B.Cu" "In15.Cu")
		(hatch none 0.5)
		(connect_pads
			(clearance 0)
		)
		(min_thickness 0.25)
		(keepout
			(tracks not_allowed)
			(vias allowed)
			(pads allowed)
			(copperpour not_allowed)
			(footprints allowed)
		)
		(placement
			(enabled no)
			(sheetname "")
		)
		(fill yes
			(thermal_gap 0.5)
			(thermal_bridge_width 0.5)
			(island_removal_mode 0)
		)
		(polygon
			(pts
				(arc
					(start 48.118014 -286.585406)
					(mid 47.449994 -286.585406)
					(end 48.118014 -286.585406)
				)
			)
		)
	)
	(zone
		(layers "B.Cu" "In15.Cu")
		(hatch none 0.5)
		(connect_pads
			(clearance 0)
		)
		(min_thickness 0.25)
		(keepout
			(tracks not_allowed)
			(vias allowed)
			(pads allowed)
			(copperpour not_allowed)
			(footprints allowed)
		)
		(placement
			(enabled no)
			(sheetname "")
		)
		(fill yes
			(thermal_gap 0.5)
			(thermal_bridge_width 0.5)
			(island_removal_mode 0)
		)
		(polygon
			(pts
				(arc
					(start 363.619796 -269.22603)
					(mid 362.989876 -269.22603)
					(end 363.619796 -269.22603)
				)
			)
		)
	)
	(zone
		(layers "B.Cu" "In15.Cu")
		(hatch none 0.5)
		(connect_pads
			(clearance 0)
		)
		(min_thickness 0.25)
		(keepout
			(tracks not_allowed)
			(vias allowed)
			(pads allowed)
			(copperpour not_allowed)
			(footprints allowed)
		)
		(placement
			(enabled no)
			(sheetname "")
		)
		(fill yes
			(thermal_gap 0.5)
			(thermal_bridge_width 0.5)
			(island_removal_mode 0)
		)
		(polygon
			(pts
				(arc
					(start 52.218082 -229.635304)
					(mid 51.550062 -229.635304)
					(end 52.218082 -229.635304)
				)
			)
		)
	)
	(zone
		(layers "B.Cu" "In15.Cu")
		(hatch none 0.5)
		(connect_pads
			(clearance 0)
		)
		(min_thickness 0.25)
		(keepout
			(tracks not_allowed)
			(vias allowed)
			(pads allowed)
			(copperpour not_allowed)
			(footprints allowed)
		)
		(placement
			(enabled no)
			(sheetname "")
		)
		(fill yes
			(thermal_gap 0.5)
			(thermal_bridge_width 0.5)
			(island_removal_mode 0)
		)
		(polygon
			(pts
				(arc
					(start 122.729752 -271.656302)
					(mid 122.099832 -271.656302)
					(end 122.729752 -271.656302)
				)
			)
		)
	)
	(zone
		(layers "B.Cu" "In15.Cu")
		(hatch none 0.5)
		(connect_pads
			(clearance 0)
		)
		(min_thickness 0.25)
		(keepout
			(tracks not_allowed)
			(vias allowed)
			(pads allowed)
			(copperpour not_allowed)
			(footprints allowed)
		)
		(placement
			(enabled no)
			(sheetname "")
		)
		(fill yes
			(thermal_gap 0.5)
			(thermal_bridge_width 0.5)
			(island_removal_mode 0)
		)
		(polygon
			(pts
				(arc
					(start 383.35966 -277.32609)
					(mid 382.72974 -277.32609)
					(end 383.35966 -277.32609)
				)
			)
		)
	)
	(zone
		(layers "B.Cu" "In15.Cu")
		(hatch none 0.5)
		(connect_pads
			(clearance 0)
		)
		(min_thickness 0.25)
		(keepout
			(tracks not_allowed)
			(vias allowed)
			(pads allowed)
			(copperpour not_allowed)
			(footprints allowed)
		)
		(placement
			(enabled no)
			(sheetname "")
		)
		(fill yes
			(thermal_gap 0.5)
			(thermal_bridge_width 0.5)
			(island_removal_mode 0)
		)
		(polygon
			(pts
				(arc
					(start 176.406048 -262.785352)
					(mid 175.738028 -262.785352)
					(end 176.406048 -262.785352)
				)
			)
		)
	)
	(zone
		(layers "B.Cu" "In15.Cu")
		(hatch none 0.5)
		(connect_pads
			(clearance 0)
		)
		(min_thickness 0.25)
		(keepout
			(tracks not_allowed)
			(vias allowed)
			(pads allowed)
			(copperpour not_allowed)
			(footprints allowed)
		)
		(placement
			(enabled no)
			(sheetname "")
		)
		(fill yes
			(thermal_gap 0.5)
			(thermal_bridge_width 0.5)
			(island_removal_mode 0)
		)
		(polygon
			(pts
				(arc
					(start 335.89595 -291.095938)
					(mid 335.26603 -291.095938)
					(end 335.89595 -291.095938)
				)
			)
		)
	)
	(zone
		(layers "B.Cu" "In15.Cu")
		(hatch none 0.5)
		(connect_pads
			(clearance 0)
		)
		(min_thickness 0.25)
		(keepout
			(tracks not_allowed)
			(vias allowed)
			(pads allowed)
			(copperpour not_allowed)
			(footprints allowed)
		)
		(placement
			(enabled no)
			(sheetname "")
		)
		(fill yes
			(thermal_gap 0.5)
			(thermal_bridge_width 0.5)
			(island_removal_mode 0)
		)
		(polygon
			(pts
				(arc
					(start 363.619796 -274.086066)
					(mid 362.989876 -274.086066)
					(end 363.619796 -274.086066)
				)
			)
		)
	)
	(zone
		(layers "B.Cu" "In15.Cu")
		(hatch none 0.5)
		(connect_pads
			(clearance 0)
		)
		(min_thickness 0.25)
		(keepout
			(tracks not_allowed)
			(vias allowed)
			(pads allowed)
			(copperpour not_allowed)
			(footprints allowed)
		)
		(placement
			(enabled no)
			(sheetname "")
		)
		(fill yes
			(thermal_gap 0.5)
			(thermal_bridge_width 0.5)
			(island_removal_mode 0)
		)
		(polygon
			(pts
				(arc
					(start 384.769868 -284.616144)
					(mid 384.139948 -284.616144)
					(end 384.769868 -284.616144)
				)
			)
		)
	)
	(zone
		(layers "B.Cu" "In15.Cu")
		(hatch none 0.5)
		(connect_pads
			(clearance 0)
		)
		(min_thickness 0.25)
		(keepout
			(tracks not_allowed)
			(vias allowed)
			(pads allowed)
			(copperpour not_allowed)
			(footprints allowed)
		)
		(placement
			(enabled no)
			(sheetname "")
		)
		(fill yes
			(thermal_gap 0.5)
			(thermal_bridge_width 0.5)
			(island_removal_mode 0)
		)
		(polygon
			(pts
				(arc
					(start 404.08225 -382.34493)
					(mid 403.41423 -382.34493)
					(end 404.08225 -382.34493)
				)
			)
		)
	)
	(zone
		(layers "B.Cu" "In15.Cu")
		(hatch none 0.5)
		(connect_pads
			(clearance 0)
		)
		(min_thickness 0.25)
		(keepout
			(tracks not_allowed)
			(vias allowed)
			(pads allowed)
			(copperpour not_allowed)
			(footprints allowed)
		)
		(placement
			(enabled no)
			(sheetname "")
		)
		(fill yes
			(thermal_gap 0.5)
			(thermal_bridge_width 0.5)
			(island_removal_mode 0)
		)
		(polygon
			(pts
				(arc
					(start 336.366104 -264.365994)
					(mid 335.736184 -264.365994)
					(end 336.366104 -264.365994)
				)
			)
		)
	)
	(zone
		(layers "B.Cu" "In15.Cu")
		(hatch none 0.5)
		(connect_pads
			(clearance 0)
		)
		(min_thickness 0.25)
		(keepout
			(tracks not_allowed)
			(vias allowed)
			(pads allowed)
			(copperpour not_allowed)
			(footprints allowed)
		)
		(placement
			(enabled no)
			(sheetname "")
		)
		(fill yes
			(thermal_gap 0.5)
			(thermal_bridge_width 0.5)
			(island_removal_mode 0)
		)
		(polygon
			(pts
				(arc
					(start 337.306158 -280.566114)
					(mid 336.676238 -280.566114)
					(end 337.306158 -280.566114)
				)
			)
		)
	)
	(zone
		(layers "B.Cu" "In15.Cu")
		(hatch none 0.5)
		(connect_pads
			(clearance 0)
		)
		(min_thickness 0.25)
		(keepout
			(tracks not_allowed)
			(vias allowed)
			(pads allowed)
			(copperpour not_allowed)
			(footprints allowed)
		)
		(placement
			(enabled no)
			(sheetname "")
		)
		(fill yes
			(thermal_gap 0.5)
			(thermal_bridge_width 0.5)
			(island_removal_mode 0)
		)
		(polygon
			(pts
				(arc
					(start 300.15815 -212.635084)
					(mid 299.49013 -212.635084)
					(end 300.15815 -212.635084)
				)
			)
		)
	)
	(zone
		(layers "B.Cu" "In15.Cu")
		(hatch none 0.5)
		(connect_pads
			(clearance 0)
		)
		(min_thickness 0.25)
		(keepout
			(tracks not_allowed)
			(vias allowed)
			(pads allowed)
			(copperpour not_allowed)
			(footprints allowed)
		)
		(placement
			(enabled no)
			(sheetname "")
		)
		(fill yes
			(thermal_gap 0.5)
			(thermal_bridge_width 0.5)
			(island_removal_mode 0)
		)
		(polygon
			(pts
				(arc
					(start 52.218082 -238.135414)
					(mid 51.550062 -238.135414)
					(end 52.218082 -238.135414)
				)
			)
		)
	)
	(zone
		(layers "B.Cu" "In15.Cu")
		(hatch none 0.5)
		(connect_pads
			(clearance 0)
		)
		(min_thickness 0.25)
		(keepout
			(tracks not_allowed)
			(vias allowed)
			(pads allowed)
			(copperpour not_allowed)
			(footprints allowed)
		)
		(placement
			(enabled no)
			(sheetname "")
		)
		(fill yes
			(thermal_gap 0.5)
			(thermal_bridge_width 0.5)
			(island_removal_mode 0)
		)
		(polygon
			(pts
				(arc
					(start 337.776058 -286.236156)
					(mid 337.146138 -286.236156)
					(end 337.776058 -286.236156)
				)
			)
		)
	)
	(zone
		(layers "B.Cu" "In15.Cu")
		(hatch none 0.5)
		(connect_pads
			(clearance 0)
		)
		(min_thickness 0.25)
		(keepout
			(tracks not_allowed)
			(vias allowed)
			(pads allowed)
			(copperpour not_allowed)
			(footprints allowed)
		)
		(placement
			(enabled no)
			(sheetname "")
		)
		(fill yes
			(thermal_gap 0.5)
			(thermal_bridge_width 0.5)
			(island_removal_mode 0)
		)
		(polygon
			(pts
				(arc
					(start 115.679728 -270.846296)
					(mid 115.049808 -270.846296)
					(end 115.679728 -270.846296)
				)
			)
		)
	)
	(zone
		(layers "B.Cu" "In15.Cu")
		(hatch none 0.5)
		(connect_pads
			(clearance 0)
		)
		(min_thickness 0.25)
		(keepout
			(tracks not_allowed)
			(vias allowed)
			(pads allowed)
			(copperpour not_allowed)
			(footprints allowed)
		)
		(placement
			(enabled no)
			(sheetname "")
		)
		(fill yes
			(thermal_gap 0.5)
			(thermal_bridge_width 0.5)
			(island_removal_mode 0)
		)
		(polygon
			(pts
				(arc
					(start 172.30598 -276.385274)
					(mid 171.63796 -276.385274)
					(end 172.30598 -276.385274)
				)
			)
		)
	)
	(zone
		(layers "B.Cu" "In15.Cu")
		(hatch none 0.5)
		(connect_pads
			(clearance 0)
		)
		(min_thickness 0.25)
		(keepout
			(tracks not_allowed)
			(vias allowed)
			(pads allowed)
			(copperpour not_allowed)
			(footprints allowed)
		)
		(placement
			(enabled no)
			(sheetname "")
		)
		(fill yes
			(thermal_gap 0.5)
			(thermal_bridge_width 0.5)
			(island_removal_mode 0)
		)
		(polygon
			(pts
				(arc
					(start 337.776058 -289.475926)
					(mid 337.146138 -289.475926)
					(end 337.776058 -289.475926)
				)
			)
		)
	)
	(zone
		(layers "B.Cu" "In15.Cu")
		(hatch none 0.5)
		(connect_pads
			(clearance 0)
		)
		(min_thickness 0.25)
		(keepout
			(tracks not_allowed)
			(vias allowed)
			(pads allowed)
			(copperpour not_allowed)
			(footprints allowed)
		)
		(placement
			(enabled no)
			(sheetname "")
		)
		(fill yes
			(thermal_gap 0.5)
			(thermal_bridge_width 0.5)
			(island_removal_mode 0)
		)
		(polygon
			(pts
				(arc
					(start 336.366104 -291.905944)
					(mid 335.736184 -291.905944)
					(end 336.366104 -291.905944)
				)
			)
		)
	)
	(zone
		(layers "B.Cu" "In15.Cu")
		(hatch none 0.5)
		(connect_pads
			(clearance 0)
		)
		(min_thickness 0.25)
		(keepout
			(tracks not_allowed)
			(vias allowed)
			(pads allowed)
			(copperpour not_allowed)
			(footprints allowed)
		)
		(placement
			(enabled no)
			(sheetname "")
		)
		(fill yes
			(thermal_gap 0.5)
			(thermal_bridge_width 0.5)
			(island_removal_mode 0)
		)
		(polygon
			(pts
				(arc
					(start 335.595976 -252.584204)
					(mid 334.966056 -252.584204)
					(end 335.595976 -252.584204)
				)
			)
		)
	)
	(zone
		(layers "B.Cu" "In15.Cu")
		(hatch none 0.5)
		(connect_pads
			(clearance 0)
		)
		(min_thickness 0.25)
		(keepout
			(tracks not_allowed)
			(vias allowed)
			(pads allowed)
			(copperpour not_allowed)
			(footprints allowed)
		)
		(placement
			(enabled no)
			(sheetname "")
		)
		(fill yes
			(thermal_gap 0.5)
			(thermal_bridge_width 0.5)
			(island_removal_mode 0)
		)
		(polygon
			(pts
				(arc
					(start 172.30598 -291.685218)
					(mid 171.63796 -291.685218)
					(end 172.30598 -291.685218)
				)
			)
		)
	)
	(zone
		(layers "B.Cu" "In15.Cu")
		(hatch none 0.5)
		(connect_pads
			(clearance 0)
		)
		(min_thickness 0.25)
		(keepout
			(tracks not_allowed)
			(vias allowed)
			(pads allowed)
			(copperpour not_allowed)
			(footprints allowed)
		)
		(placement
			(enabled no)
			(sheetname "")
		)
		(fill yes
			(thermal_gap 0.5)
			(thermal_bridge_width 0.5)
			(island_removal_mode 0)
		)
		(polygon
			(pts
				(arc
					(start 347.17609 -270.036036)
					(mid 346.54617 -270.036036)
					(end 347.17609 -270.036036)
				)
			)
		)
	)
	(zone
		(layers "B.Cu" "In15.Cu")
		(hatch none 0.5)
		(connect_pads
			(clearance 0)
		)
		(min_thickness 0.25)
		(keepout
			(tracks not_allowed)
			(vias allowed)
			(pads allowed)
			(copperpour not_allowed)
			(footprints allowed)
		)
		(placement
			(enabled no)
			(sheetname "")
		)
		(fill yes
			(thermal_gap 0.5)
			(thermal_bridge_width 0.5)
			(island_removal_mode 0)
		)
		(polygon
			(pts
				(arc
					(start 83.07832 -392.429238)
					(mid 82.4103 -392.429238)
					(end 83.07832 -392.429238)
				)
			)
		)
	)
	(zone
		(layers "B.Cu" "In15.Cu")
		(hatch none 0.5)
		(connect_pads
			(clearance 0)
		)
		(min_thickness 0.25)
		(keepout
			(tracks not_allowed)
			(vias allowed)
			(pads allowed)
			(copperpour not_allowed)
			(footprints allowed)
		)
		(placement
			(enabled no)
			(sheetname "")
		)
		(fill yes
			(thermal_gap 0.5)
			(thermal_bridge_width 0.5)
			(island_removal_mode 0)
		)
		(polygon
			(pts
				(arc
					(start 130.1369 -434.48986)
					(mid 129.362708 -434.48986)
					(end 130.1369 -434.48986)
				)
			)
		)
	)
	(zone
		(layers "B.Cu" "In15.Cu")
		(hatch none 0.5)
		(connect_pads
			(clearance 0)
		)
		(min_thickness 0.25)
		(keepout
			(tracks not_allowed)
			(vias allowed)
			(pads allowed)
			(copperpour not_allowed)
			(footprints allowed)
		)
		(placement
			(enabled no)
			(sheetname "")
		)
		(fill yes
			(thermal_gap 0.5)
			(thermal_bridge_width 0.5)
			(island_removal_mode 0)
		)
		(polygon
			(pts
				(arc
					(start 371.609874 -271.656048)
					(mid 370.979954 -271.656048)
					(end 371.609874 -271.656048)
				)
			)
		)
	)
	(zone
		(layers "B.Cu" "In15.Cu")
		(hatch none 0.5)
		(connect_pads
			(clearance 0)
		)
		(min_thickness 0.25)
		(keepout
			(tracks not_allowed)
			(vias allowed)
			(pads allowed)
			(copperpour not_allowed)
			(footprints allowed)
		)
		(placement
			(enabled no)
			(sheetname "")
		)
		(fill yes
			(thermal_gap 0.5)
			(thermal_bridge_width 0.5)
			(island_removal_mode 0)
		)
		(polygon
			(pts
				(arc
					(start 415.15665 -377.41733)
					(mid 414.48863 -377.41733)
					(end 415.15665 -377.41733)
				)
			)
		)
	)
	(zone
		(layers "B.Cu" "In15.Cu")
		(hatch none 0.5)
		(connect_pads
			(clearance 0)
		)
		(min_thickness 0.25)
		(keepout
			(tracks not_allowed)
			(vias allowed)
			(pads allowed)
			(copperpour not_allowed)
			(footprints allowed)
		)
		(placement
			(enabled no)
			(sheetname "")
		)
		(fill yes
			(thermal_gap 0.5)
			(thermal_bridge_width 0.5)
			(island_removal_mode 0)
		)
		(polygon
			(pts
				(arc
					(start 383.059686 -245.29415)
					(mid 382.429766 -245.29415)
					(end 383.059686 -245.29415)
				)
			)
		)
	)
	(zone
		(layers "B.Cu" "In15.Cu")
		(hatch none 0.5)
		(connect_pads
			(clearance 0)
		)
		(min_thickness 0.25)
		(keepout
			(tracks not_allowed)
			(vias allowed)
			(pads allowed)
			(copperpour not_allowed)
			(footprints allowed)
		)
		(placement
			(enabled no)
			(sheetname "")
		)
		(fill yes
			(thermal_gap 0.5)
			(thermal_bridge_width 0.5)
			(island_removal_mode 0)
		)
		(polygon
			(pts
				(arc
					(start 153.137108 -435.489858)
					(mid 152.362916 -435.489858)
					(end 153.137108 -435.489858)
				)
			)
		)
	)
	(zone
		(layers "B.Cu" "In15.Cu")
		(hatch none 0.5)
		(connect_pads
			(clearance 0)
		)
		(min_thickness 0.25)
		(keepout
			(tracks not_allowed)
			(vias allowed)
			(pads allowed)
			(copperpour not_allowed)
			(footprints allowed)
		)
		(placement
			(enabled no)
			(sheetname "")
		)
		(fill yes
			(thermal_gap 0.5)
			(thermal_bridge_width 0.5)
			(island_removal_mode 0)
		)
		(polygon
			(pts
				(arc
					(start 176.406048 -210.085432)
					(mid 175.738028 -210.085432)
					(end 176.406048 -210.085432)
				)
			)
		)
	)
	(zone
		(layers "B.Cu" "In15.Cu")
		(hatch none 0.5)
		(connect_pads
			(clearance 0)
		)
		(min_thickness 0.25)
		(keepout
			(tracks not_allowed)
			(vias allowed)
			(pads allowed)
			(copperpour not_allowed)
			(footprints allowed)
		)
		(placement
			(enabled no)
			(sheetname "")
		)
		(fill yes
			(thermal_gap 0.5)
			(thermal_bridge_width 0.5)
			(island_removal_mode 0)
		)
		(polygon
			(pts
				(arc
					(start 90.278458 -393.292838)
					(mid 89.610438 -393.292838)
					(end 90.278458 -393.292838)
				)
			)
		)
	)
	(zone
		(layers "B.Cu" "In15.Cu")
		(hatch none 0.5)
		(connect_pads
			(clearance 0)
		)
		(min_thickness 0.25)
		(keepout
			(tracks not_allowed)
			(vias allowed)
			(pads allowed)
			(copperpour not_allowed)
			(footprints allowed)
		)
		(placement
			(enabled no)
			(sheetname "")
		)
		(fill yes
			(thermal_gap 0.5)
			(thermal_bridge_width 0.5)
			(island_removal_mode 0)
		)
		(polygon
			(pts
				(arc
					(start 65.036954 -434.289962)
					(mid 64.262762 -434.289962)
					(end 65.036954 -434.289962)
				)
			)
		)
	)
	(zone
		(layers "B.Cu" "In15.Cu")
		(hatch none 0.5)
		(connect_pads
			(clearance 0)
		)
		(min_thickness 0.25)
		(keepout
			(tracks not_allowed)
			(vias allowed)
			(pads allowed)
			(copperpour not_allowed)
			(footprints allowed)
		)
		(placement
			(enabled no)
			(sheetname "")
		)
		(fill yes
			(thermal_gap 0.5)
			(thermal_bridge_width 0.5)
			(island_removal_mode 0)
		)
		(polygon
			(pts
				(arc
					(start 383.35966 -285.42615)
					(mid 382.72974 -285.42615)
					(end 383.35966 -285.42615)
				)
			)
		)
	)
	(zone
		(layers "B.Cu" "In15.Cu")
		(hatch none 0.5)
		(connect_pads
			(clearance 0)
		)
		(min_thickness 0.25)
		(keepout
			(tracks not_allowed)
			(vias allowed)
			(pads allowed)
			(copperpour not_allowed)
			(footprints allowed)
		)
		(placement
			(enabled no)
			(sheetname "")
		)
		(fill yes
			(thermal_gap 0.5)
			(thermal_bridge_width 0.5)
			(island_removal_mode 0)
		)
		(polygon
			(pts
				(arc
					(start 382.88976 -273.27606)
					(mid 382.25984 -273.27606)
					(end 382.88976 -273.27606)
				)
			)
		)
	)
	(zone
		(layers "B.Cu" "In15.Cu")
		(hatch none 0.5)
		(connect_pads
			(clearance 0)
		)
		(min_thickness 0.25)
		(keepout
			(tracks not_allowed)
			(vias allowed)
			(pads allowed)
			(copperpour not_allowed)
			(footprints allowed)
		)
		(placement
			(enabled no)
			(sheetname "")
		)
		(fill yes
			(thermal_gap 0.5)
			(thermal_bridge_width 0.5)
			(island_removal_mode 0)
		)
		(polygon
			(pts
				(arc
					(start 176.406048 -315.485272)
					(mid 175.738028 -315.485272)
					(end 176.406048 -315.485272)
				)
			)
		)
	)
	(zone
		(layers "B.Cu" "In15.Cu")
		(hatch none 0.5)
		(connect_pads
			(clearance 0)
		)
		(min_thickness 0.25)
		(keepout
			(tracks not_allowed)
			(vias allowed)
			(pads allowed)
			(copperpour not_allowed)
			(footprints allowed)
		)
		(placement
			(enabled no)
			(sheetname "")
		)
		(fill yes
			(thermal_gap 0.5)
			(thermal_bridge_width 0.5)
			(island_removal_mode 0)
		)
		(polygon
			(pts
				(arc
					(start 424.346116 -269.585186)
					(mid 423.678096 -269.585186)
					(end 424.346116 -269.585186)
				)
			)
		)
	)
	(zone
		(layers "B.Cu" "In15.Cu")
		(hatch none 0.5)
		(connect_pads
			(clearance 0)
		)
		(min_thickness 0.25)
		(keepout
			(tracks not_allowed)
			(vias allowed)
			(pads allowed)
			(copperpour not_allowed)
			(footprints allowed)
		)
		(placement
			(enabled no)
			(sheetname "")
		)
		(fill yes
			(thermal_gap 0.5)
			(thermal_bridge_width 0.5)
			(island_removal_mode 0)
		)
		(polygon
			(pts
				(arc
					(start 95.078296 -392.429238)
					(mid 94.410276 -392.429238)
					(end 95.078296 -392.429238)
				)
			)
		)
	)
	(zone
		(layers "B.Cu" "In15.Cu")
		(hatch none 0.5)
		(connect_pads
			(clearance 0)
		)
		(min_thickness 0.25)
		(keepout
			(tracks not_allowed)
			(vias allowed)
			(pads allowed)
			(copperpour not_allowed)
			(footprints allowed)
		)
		(placement
			(enabled no)
			(sheetname "")
		)
		(fill yes
			(thermal_gap 0.5)
			(thermal_bridge_width 0.5)
			(island_removal_mode 0)
		)
		(polygon
			(pts
				(arc
					(start 176.406048 -197.335394)
					(mid 175.738028 -197.335394)
					(end 176.406048 -197.335394)
				)
			)
		)
	)
	(zone
		(layers "B.Cu" "In15.Cu")
		(hatch none 0.5)
		(connect_pads
			(clearance 0)
		)
		(min_thickness 0.25)
		(keepout
			(tracks not_allowed)
			(vias allowed)
			(pads allowed)
			(copperpour not_allowed)
			(footprints allowed)
		)
		(placement
			(enabled no)
			(sheetname "")
		)
		(fill yes
			(thermal_gap 0.5)
			(thermal_bridge_width 0.5)
			(island_removal_mode 0)
		)
		(polygon
			(pts
				(arc
					(start 88.037162 -433.289964)
					(mid 87.26297 -433.289964)
					(end 88.037162 -433.289964)
				)
			)
		)
	)
	(zone
		(layers "B.Cu" "In15.Cu")
		(hatch none 0.5)
		(connect_pads
			(clearance 0)
		)
		(min_thickness 0.25)
		(keepout
			(tracks not_allowed)
			(vias allowed)
			(pads allowed)
			(copperpour not_allowed)
			(footprints allowed)
		)
		(placement
			(enabled no)
			(sheetname "")
		)
		(fill yes
			(thermal_gap 0.5)
			(thermal_bridge_width 0.5)
			(island_removal_mode 0)
		)
		(polygon
			(pts
				(arc
					(start 420.246048 -204.134974)
					(mid 419.578028 -204.134974)
					(end 420.246048 -204.134974)
				)
			)
		)
	)
	(zone
		(layers "B.Cu" "In15.Cu")
		(hatch none 0.5)
		(connect_pads
			(clearance 0)
		)
		(min_thickness 0.25)
		(keepout
			(tracks not_allowed)
			(vias allowed)
			(pads allowed)
			(copperpour not_allowed)
			(footprints allowed)
		)
		(placement
			(enabled no)
			(sheetname "")
		)
		(fill yes
			(thermal_gap 0.5)
			(thermal_bridge_width 0.5)
			(island_removal_mode 0)
		)
		(polygon
			(pts
				(arc
					(start 136.529826 -254.20447)
					(mid 135.899906 -254.20447)
					(end 136.529826 -254.20447)
				)
			)
		)
	)
	(zone
		(layers "B.Cu" "In15.Cu")
		(hatch none 0.5)
		(connect_pads
			(clearance 0)
		)
		(min_thickness 0.25)
		(keepout
			(tracks not_allowed)
			(vias allowed)
			(pads allowed)
			(copperpour not_allowed)
			(footprints allowed)
		)
		(placement
			(enabled no)
			(sheetname "")
		)
		(fill yes
			(thermal_gap 0.5)
			(thermal_bridge_width 0.5)
			(island_removal_mode 0)
		)
		(polygon
			(pts
				(arc
					(start 176.406048 -295.085262)
					(mid 175.738028 -295.085262)
					(end 176.406048 -295.085262)
				)
			)
		)
	)
	(zone
		(layers "B.Cu" "In15.Cu")
		(hatch none 0.5)
		(connect_pads
			(clearance 0)
		)
		(min_thickness 0.25)
		(keepout
			(tracks not_allowed)
			(vias allowed)
			(pads allowed)
			(copperpour not_allowed)
			(footprints allowed)
		)
		(placement
			(enabled no)
			(sheetname "")
		)
		(fill yes
			(thermal_gap 0.5)
			(thermal_bridge_width 0.5)
			(island_removal_mode 0)
		)
		(polygon
			(pts
				(arc
					(start 337.476084 -242.864132)
					(mid 336.846164 -242.864132)
					(end 337.476084 -242.864132)
				)
			)
		)
	)
	(zone
		(layers "B.Cu" "In15.Cu")
		(hatch none 0.5)
		(connect_pads
			(clearance 0)
		)
		(min_thickness 0.25)
		(keepout
			(tracks not_allowed)
			(vias allowed)
			(pads allowed)
			(copperpour not_allowed)
			(footprints allowed)
		)
		(placement
			(enabled no)
			(sheetname "")
		)
		(fill yes
			(thermal_gap 0.5)
			(thermal_bridge_width 0.5)
			(island_removal_mode 0)
		)
		(polygon
			(pts
				(arc
					(start 126.489714 -271.656302)
					(mid 125.859794 -271.656302)
					(end 126.489714 -271.656302)
				)
			)
		)
	)
	(zone
		(layers "B.Cu" "In15.Cu")
		(hatch none 0.5)
		(connect_pads
			(clearance 0)
		)
		(min_thickness 0.25)
		(keepout
			(tracks not_allowed)
			(vias allowed)
			(pads allowed)
			(copperpour not_allowed)
			(footprints allowed)
		)
		(placement
			(enabled no)
			(sheetname "")
		)
		(fill yes
			(thermal_gap 0.5)
			(thermal_bridge_width 0.5)
			(island_removal_mode 0)
		)
		(polygon
			(pts
				(arc
					(start 134.949692 -271.656302)
					(mid 134.319772 -271.656302)
					(end 134.949692 -271.656302)
				)
			)
		)
	)
	(zone
		(layers "B.Cu" "In15.Cu")
		(hatch none 0.5)
		(connect_pads
			(clearance 0)
		)
		(min_thickness 0.25)
		(keepout
			(tracks not_allowed)
			(vias allowed)
			(pads allowed)
			(copperpour not_allowed)
			(footprints allowed)
		)
		(placement
			(enabled no)
			(sheetname "")
		)
		(fill yes
			(thermal_gap 0.5)
			(thermal_bridge_width 0.5)
			(island_removal_mode 0)
		)
		(polygon
			(pts
				(arc
					(start 424.346116 -216.035128)
					(mid 423.678096 -216.035128)
					(end 424.346116 -216.035128)
				)
			)
		)
	)
	(zone
		(layers "B.Cu" "In15.Cu")
		(hatch none 0.5)
		(connect_pads
			(clearance 0)
		)
		(min_thickness 0.25)
		(keepout
			(tracks not_allowed)
			(vias allowed)
			(pads allowed)
			(copperpour not_allowed)
			(footprints allowed)
		)
		(placement
			(enabled no)
			(sheetname "")
		)
		(fill yes
			(thermal_gap 0.5)
			(thermal_bridge_width 0.5)
			(island_removal_mode 0)
		)
		(polygon
			(pts
				(arc
					(start 370.66982 -270.036036)
					(mid 370.0399 -270.036036)
					(end 370.66982 -270.036036)
				)
			)
		)
	)
	(zone
		(layers "B.Cu" "In15.Cu")
		(hatch none 0.5)
		(connect_pads
			(clearance 0)
		)
		(min_thickness 0.25)
		(keepout
			(tracks not_allowed)
			(vias allowed)
			(pads allowed)
			(copperpour not_allowed)
			(footprints allowed)
		)
		(placement
			(enabled no)
			(sheetname "")
		)
		(fill yes
			(thermal_gap 0.5)
			(thermal_bridge_width 0.5)
			(island_removal_mode 0)
		)
		(polygon
			(pts
				(arc
					(start 61.036962 -434.289962)
					(mid 60.26277 -434.289962)
					(end 61.036962 -434.289962)
				)
			)
		)
	)
	(zone
		(layers "B.Cu" "In15.Cu")
		(hatch none 0.5)
		(connect_pads
			(clearance 0)
		)
		(min_thickness 0.25)
		(keepout
			(tracks not_allowed)
			(vias allowed)
			(pads allowed)
			(copperpour not_allowed)
			(footprints allowed)
		)
		(placement
			(enabled no)
			(sheetname "")
		)
		(fill yes
			(thermal_gap 0.5)
			(thermal_bridge_width 0.5)
			(island_removal_mode 0)
		)
		(polygon
			(pts
				(arc
					(start 384.1369 -434.289962)
					(mid 383.362708 -434.289962)
					(end 384.1369 -434.289962)
				)
			)
		)
	)
	(zone
		(layers "B.Cu" "In15.Cu")
		(hatch none 0.5)
		(connect_pads
			(clearance 0)
		)
		(min_thickness 0.25)
		(keepout
			(tracks not_allowed)
			(vias allowed)
			(pads allowed)
			(copperpour not_allowed)
			(footprints allowed)
		)
		(placement
			(enabled no)
			(sheetname "")
		)
		(fill yes
			(thermal_gap 0.5)
			(thermal_bridge_width 0.5)
			(island_removal_mode 0)
		)
		(polygon
			(pts
				(arc
					(start 52.218082 -210.935316)
					(mid 51.550062 -210.935316)
					(end 52.218082 -210.935316)
				)
			)
		)
	)
	(zone
		(layers "B.Cu" "In15.Cu")
		(hatch none 0.5)
		(connect_pads
			(clearance 0)
		)
		(min_thickness 0.25)
		(keepout
			(tracks not_allowed)
			(vias allowed)
			(pads allowed)
			(copperpour not_allowed)
			(footprints allowed)
		)
		(placement
			(enabled no)
			(sheetname "")
		)
		(fill yes
			(thermal_gap 0.5)
			(thermal_bridge_width 0.5)
			(island_removal_mode 0)
		)
		(polygon
			(pts
				(arc
					(start 296.058082 -251.735082)
					(mid 295.390062 -251.735082)
					(end 296.058082 -251.735082)
				)
			)
		)
	)
	(zone
		(layers "B.Cu" "In15.Cu")
		(hatch none 0.5)
		(connect_pads
			(clearance 0)
		)
		(min_thickness 0.25)
		(keepout
			(tracks not_allowed)
			(vias allowed)
			(pads allowed)
			(copperpour not_allowed)
			(footprints allowed)
		)
		(placement
			(enabled no)
			(sheetname "")
		)
		(fill yes
			(thermal_gap 0.5)
			(thermal_bridge_width 0.5)
			(island_removal_mode 0)
		)
		(polygon
			(pts
				(arc
					(start 382.88976 -291.095938)
					(mid 382.25984 -291.095938)
					(end 382.88976 -291.095938)
				)
			)
		)
	)
	(zone
		(layers "B.Cu" "In15.Cu")
		(hatch none 0.5)
		(connect_pads
			(clearance 0)
		)
		(min_thickness 0.25)
		(keepout
			(tracks not_allowed)
			(vias allowed)
			(pads allowed)
			(copperpour not_allowed)
			(footprints allowed)
		)
		(placement
			(enabled no)
			(sheetname "")
		)
		(fill yes
			(thermal_gap 0.5)
			(thermal_bridge_width 0.5)
			(island_removal_mode 0)
		)
		(polygon
			(pts
				(arc
					(start 400.67865 -377.41733)
					(mid 400.01063 -377.41733)
					(end 400.67865 -377.41733)
				)
			)
		)
	)
	(zone
		(layers "B.Cu" "In15.Cu")
		(hatch none 0.5)
		(connect_pads
			(clearance 0)
		)
		(min_thickness 0.25)
		(keepout
			(tracks not_allowed)
			(vias allowed)
			(pads allowed)
			(copperpour not_allowed)
			(footprints allowed)
		)
		(placement
			(enabled no)
			(sheetname "")
		)
		(fill yes
			(thermal_gap 0.5)
			(thermal_bridge_width 0.5)
			(island_removal_mode 0)
		)
		(polygon
			(pts
				(arc
					(start 71.036942 -433.289964)
					(mid 70.26275 -433.289964)
					(end 71.036942 -433.289964)
				)
			)
		)
	)
	(zone
		(layers "B.Cu" "In15.Cu")
		(hatch none 0.5)
		(connect_pads
			(clearance 0)
		)
		(min_thickness 0.25)
		(keepout
			(tracks not_allowed)
			(vias allowed)
			(pads allowed)
			(copperpour not_allowed)
			(footprints allowed)
		)
		(placement
			(enabled no)
			(sheetname "")
		)
		(fill yes
			(thermal_gap 0.5)
			(thermal_bridge_width 0.5)
			(island_removal_mode 0)
		)
		(polygon
			(pts
				(arc
					(start 87.655908 -226.66452)
					(mid 87.025988 -226.66452)
					(end 87.655908 -226.66452)
				)
			)
		)
	)
	(zone
		(layers "B.Cu" "In15.Cu")
		(hatch none 0.5)
		(connect_pads
			(clearance 0)
		)
		(min_thickness 0.25)
		(keepout
			(tracks not_allowed)
			(vias allowed)
			(pads allowed)
			(copperpour not_allowed)
			(footprints allowed)
		)
		(placement
			(enabled no)
			(sheetname "")
		)
		(fill yes
			(thermal_gap 0.5)
			(thermal_bridge_width 0.5)
			(island_removal_mode 0)
		)
		(polygon
			(pts
				(arc
					(start 136.529826 -226.66452)
					(mid 135.899906 -226.66452)
					(end 136.529826 -226.66452)
				)
			)
		)
	)
	(zone
		(layers "B.Cu" "In15.Cu")
		(hatch none 0.5)
		(connect_pads
			(clearance 0)
		)
		(min_thickness 0.25)
		(keepout
			(tracks not_allowed)
			(vias allowed)
			(pads allowed)
			(copperpour not_allowed)
			(footprints allowed)
		)
		(placement
			(enabled no)
			(sheetname "")
		)
		(fill yes
			(thermal_gap 0.5)
			(thermal_bridge_width 0.5)
			(island_removal_mode 0)
		)
		(polygon
			(pts
				(arc
					(start 420.246048 -276.38502)
					(mid 419.578028 -276.38502)
					(end 420.246048 -276.38502)
				)
			)
		)
	)
	(zone
		(layers "B.Cu" "In15.Cu")
		(hatch none 0.5)
		(connect_pads
			(clearance 0)
		)
		(min_thickness 0.25)
		(keepout
			(tracks not_allowed)
			(vias allowed)
			(pads allowed)
			(copperpour not_allowed)
			(footprints allowed)
		)
		(placement
			(enabled no)
			(sheetname "")
		)
		(fill yes
			(thermal_gap 0.5)
			(thermal_bridge_width 0.5)
			(island_removal_mode 0)
		)
		(polygon
			(pts
				(arc
					(start 89.536016 -246.10441)
					(mid 88.906096 -246.10441)
					(end 89.536016 -246.10441)
				)
			)
		)
	)
	(zone
		(layers "B.Cu" "In15.Cu")
		(hatch none 0.5)
		(connect_pads
			(clearance 0)
		)
		(min_thickness 0.25)
		(keepout
			(tracks not_allowed)
			(vias allowed)
			(pads allowed)
			(copperpour not_allowed)
			(footprints allowed)
		)
		(placement
			(enabled no)
			(sheetname "")
		)
		(fill yes
			(thermal_gap 0.5)
			(thermal_bridge_width 0.5)
			(island_removal_mode 0)
		)
		(polygon
			(pts
				(arc
					(start 171.239434 -376.956828)
					(mid 170.571414 -376.956828)
					(end 171.239434 -376.956828)
				)
			)
		)
	)
	(zone
		(layers "B.Cu" "In15.Cu")
		(hatch none 0.5)
		(connect_pads
			(clearance 0)
		)
		(min_thickness 0.25)
		(keepout
			(tracks not_allowed)
			(vias allowed)
			(pads allowed)
			(copperpour not_allowed)
			(footprints allowed)
		)
		(placement
			(enabled no)
			(sheetname "")
		)
		(fill yes
			(thermal_gap 0.5)
			(thermal_bridge_width 0.5)
			(island_removal_mode 0)
		)
		(polygon
			(pts
				(arc
					(start 135.419592 -264.366248)
					(mid 134.789672 -264.366248)
					(end 135.419592 -264.366248)
				)
			)
		)
	)
	(zone
		(layers "B.Cu" "In15.Cu")
		(hatch none 0.5)
		(connect_pads
			(clearance 0)
		)
		(min_thickness 0.25)
		(keepout
			(tracks not_allowed)
			(vias allowed)
			(pads allowed)
			(copperpour not_allowed)
			(footprints allowed)
		)
		(placement
			(enabled no)
			(sheetname "")
		)
		(fill yes
			(thermal_gap 0.5)
			(thermal_bridge_width 0.5)
			(island_removal_mode 0)
		)
		(polygon
			(pts
				(arc
					(start 296.058082 -263.634982)
					(mid 295.390062 -263.634982)
					(end 296.058082 -263.634982)
				)
			)
		)
	)
	(zone
		(layers "B.Cu" "In15.Cu")
		(hatch none 0.5)
		(connect_pads
			(clearance 0)
		)
		(min_thickness 0.25)
		(keepout
			(tracks not_allowed)
			(vias allowed)
			(pads allowed)
			(copperpour not_allowed)
			(footprints allowed)
		)
		(placement
			(enabled no)
			(sheetname "")
		)
		(fill yes
			(thermal_gap 0.5)
			(thermal_bridge_width 0.5)
			(island_removal_mode 0)
		)
		(polygon
			(pts
				(arc
					(start 372.45036 -401.674838)
					(mid 371.78234 -401.674838)
					(end 372.45036 -401.674838)
				)
			)
		)
	)
	(zone
		(layers "B.Cu" "In15.Cu")
		(hatch none 0.5)
		(connect_pads
			(clearance 0)
		)
		(min_thickness 0.25)
		(keepout
			(tracks not_allowed)
			(vias allowed)
			(pads allowed)
			(copperpour not_allowed)
			(footprints allowed)
		)
		(placement
			(enabled no)
			(sheetname "")
		)
		(fill yes
			(thermal_gap 0.5)
			(thermal_bridge_width 0.5)
			(island_removal_mode 0)
		)
		(polygon
			(pts
				(arc
					(start 420.246048 -254.284988)
					(mid 419.578028 -254.284988)
					(end 420.246048 -254.284988)
				)
			)
		)
	)
	(zone
		(layers "B.Cu" "In15.Cu")
		(hatch none 0.5)
		(connect_pads
			(clearance 0)
		)
		(min_thickness 0.25)
		(keepout
			(tracks not_allowed)
			(vias allowed)
			(pads allowed)
			(copperpour not_allowed)
			(footprints allowed)
		)
		(placement
			(enabled no)
			(sheetname "")
		)
		(fill yes
			(thermal_gap 0.5)
			(thermal_bridge_width 0.5)
			(island_removal_mode 0)
		)
		(polygon
			(pts
				(arc
					(start 115.379754 -240.434368)
					(mid 114.749834 -240.434368)
					(end 115.379754 -240.434368)
				)
			)
		)
	)
	(zone
		(layers "B.Cu" "In15.Cu")
		(hatch none 0.5)
		(connect_pads
			(clearance 0)
		)
		(min_thickness 0.25)
		(keepout
			(tracks not_allowed)
			(vias allowed)
			(pads allowed)
			(copperpour not_allowed)
			(footprints allowed)
		)
		(placement
			(enabled no)
			(sheetname "")
		)
		(fill yes
			(thermal_gap 0.5)
			(thermal_bridge_width 0.5)
			(island_removal_mode 0)
		)
		(polygon
			(pts
				(arc
					(start 383.35966 -283.806138)
					(mid 382.72974 -283.806138)
					(end 383.35966 -283.806138)
				)
			)
		)
	)
	(zone
		(layers "B.Cu" "In15.Cu")
		(hatch none 0.5)
		(connect_pads
			(clearance 0)
		)
		(min_thickness 0.25)
		(keepout
			(tracks not_allowed)
			(vias allowed)
			(pads allowed)
			(copperpour not_allowed)
			(footprints allowed)
		)
		(placement
			(enabled no)
			(sheetname "")
		)
		(fill yes
			(thermal_gap 0.5)
			(thermal_bridge_width 0.5)
			(island_removal_mode 0)
		)
		(polygon
			(pts
				(arc
					(start 89.536016 -228.284532)
					(mid 88.906096 -228.284532)
					(end 89.536016 -228.284532)
				)
			)
		)
	)
	(zone
		(layers "B.Cu" "In15.Cu")
		(hatch none 0.5)
		(connect_pads
			(clearance 0)
		)
		(min_thickness 0.25)
		(keepout
			(tracks not_allowed)
			(vias allowed)
			(pads allowed)
			(copperpour not_allowed)
			(footprints allowed)
		)
		(placement
			(enabled no)
			(sheetname "")
		)
		(fill yes
			(thermal_gap 0.5)
			(thermal_bridge_width 0.5)
			(island_removal_mode 0)
		)
		(polygon
			(pts
				(arc
					(start 135.419592 -275.706332)
					(mid 134.789672 -275.706332)
					(end 135.419592 -275.706332)
				)
			)
		)
	)
	(zone
		(layers "B.Cu" "In15.Cu")
		(hatch none 0.5)
		(connect_pads
			(clearance 0)
		)
		(min_thickness 0.25)
		(keepout
			(tracks not_allowed)
			(vias allowed)
			(pads allowed)
			(copperpour not_allowed)
			(footprints allowed)
		)
		(placement
			(enabled no)
			(sheetname "")
		)
		(fill yes
			(thermal_gap 0.5)
			(thermal_bridge_width 0.5)
			(island_removal_mode 0)
		)
		(polygon
			(pts
				(arc
					(start 300.15815 -264.48512)
					(mid 299.49013 -264.48512)
					(end 300.15815 -264.48512)
				)
			)
		)
	)
	(zone
		(layers "B.Cu" "In15.Cu")
		(hatch none 0.5)
		(connect_pads
			(clearance 0)
		)
		(min_thickness 0.25)
		(keepout
			(tracks not_allowed)
			(vias allowed)
			(pads allowed)
			(copperpour not_allowed)
			(footprints allowed)
		)
		(placement
			(enabled no)
			(sheetname "")
		)
		(fill yes
			(thermal_gap 0.5)
			(thermal_bridge_width 0.5)
			(island_removal_mode 0)
		)
		(polygon
			(pts
				(arc
					(start 172.30598 -204.135228)
					(mid 171.63796 -204.135228)
					(end 172.30598 -204.135228)
				)
			)
		)
	)
	(zone
		(layers "B.Cu" "In15.Cu")
		(hatch none 0.5)
		(connect_pads
			(clearance 0)
		)
		(min_thickness 0.25)
		(keepout
			(tracks not_allowed)
			(vias allowed)
			(pads allowed)
			(copperpour not_allowed)
			(footprints allowed)
		)
		(placement
			(enabled no)
			(sheetname "")
		)
		(fill yes
			(thermal_gap 0.5)
			(thermal_bridge_width 0.5)
			(island_removal_mode 0)
		)
		(polygon
			(pts
				(arc
					(start 300.15815 -276.38502)
					(mid 299.49013 -276.38502)
					(end 300.15815 -276.38502)
				)
			)
		)
	)
	(zone
		(layers "B.Cu" "In15.Cu")
		(hatch none 0.5)
		(connect_pads
			(clearance 0)
		)
		(min_thickness 0.25)
		(keepout
			(tracks not_allowed)
			(vias allowed)
			(pads allowed)
			(copperpour not_allowed)
			(footprints allowed)
		)
		(placement
			(enabled no)
			(sheetname "")
		)
		(fill yes
			(thermal_gap 0.5)
			(thermal_bridge_width 0.5)
			(island_removal_mode 0)
		)
		(polygon
			(pts
				(arc
					(start 300.15815 -266.185142)
					(mid 299.49013 -266.185142)
					(end 300.15815 -266.185142)
				)
			)
		)
	)
	(zone
		(layers "B.Cu" "In15.Cu")
		(hatch none 0.5)
		(connect_pads
			(clearance 0)
		)
		(min_thickness 0.25)
		(keepout
			(tracks not_allowed)
			(vias allowed)
			(pads allowed)
			(copperpour not_allowed)
			(footprints allowed)
		)
		(placement
			(enabled no)
			(sheetname "")
		)
		(fill yes
			(thermal_gap 0.5)
			(thermal_bridge_width 0.5)
			(island_removal_mode 0)
		)
		(polygon
			(pts
				(arc
					(start 149.137116 -435.489858)
					(mid 148.362924 -435.489858)
					(end 149.137116 -435.489858)
				)
			)
		)
	)
	(zone
		(layers "B.Cu" "In15.Cu")
		(hatch none 0.5)
		(connect_pads
			(clearance 0)
		)
		(min_thickness 0.25)
		(keepout
			(tracks not_allowed)
			(vias allowed)
			(pads allowed)
			(copperpour not_allowed)
			(footprints allowed)
		)
		(placement
			(enabled no)
			(sheetname "")
		)
		(fill yes
			(thermal_gap 0.5)
			(thermal_bridge_width 0.5)
			(island_removal_mode 0)
		)
		(polygon
			(pts
				(arc
					(start 383.35966 -293.525956)
					(mid 382.72974 -293.525956)
					(end 383.35966 -293.525956)
				)
			)
		)
	)
	(zone
		(layers "B.Cu" "In15.Cu")
		(hatch none 0.5)
		(connect_pads
			(clearance 0)
		)
		(min_thickness 0.25)
		(keepout
			(tracks not_allowed)
			(vias allowed)
			(pads allowed)
			(copperpour not_allowed)
			(footprints allowed)
		)
		(placement
			(enabled no)
			(sheetname "")
		)
		(fill yes
			(thermal_gap 0.5)
			(thermal_bridge_width 0.5)
			(island_removal_mode 0)
		)
		(polygon
			(pts
				(arc
					(start 336.366104 -290.285932)
					(mid 335.736184 -290.285932)
					(end 336.366104 -290.285932)
				)
			)
		)
	)
	(zone
		(layers "B.Cu" "In15.Cu")
		(hatch none 0.5)
		(connect_pads
			(clearance 0)
		)
		(min_thickness 0.25)
		(keepout
			(tracks not_allowed)
			(vias allowed)
			(pads allowed)
			(copperpour not_allowed)
			(footprints allowed)
		)
		(placement
			(enabled no)
			(sheetname "")
		)
		(fill yes
			(thermal_gap 0.5)
			(thermal_bridge_width 0.5)
			(island_removal_mode 0)
		)
		(polygon
			(pts
				(arc
					(start 420.246048 -291.684964)
					(mid 419.578028 -291.684964)
					(end 420.246048 -291.684964)
				)
			)
		)
	)
	(zone
		(layers "B.Cu" "In15.Cu")
		(hatch none 0.5)
		(connect_pads
			(clearance 0)
		)
		(min_thickness 0.25)
		(keepout
			(tracks not_allowed)
			(vias allowed)
			(pads allowed)
			(copperpour not_allowed)
			(footprints allowed)
		)
		(placement
			(enabled no)
			(sheetname "")
		)
		(fill yes
			(thermal_gap 0.5)
			(thermal_bridge_width 0.5)
			(island_removal_mode 0)
		)
		(polygon
			(pts
				(arc
					(start 335.89595 -281.37612)
					(mid 335.26603 -281.37612)
					(end 335.89595 -281.37612)
				)
			)
		)
	)
	(zone
		(layers "B.Cu" "In15.Cu")
		(hatch none 0.5)
		(connect_pads
			(clearance 0)
		)
		(min_thickness 0.25)
		(keepout
			(tracks not_allowed)
			(vias allowed)
			(pads allowed)
			(copperpour not_allowed)
			(footprints allowed)
		)
		(placement
			(enabled no)
			(sheetname "")
		)
		(fill yes
			(thermal_gap 0.5)
			(thermal_bridge_width 0.5)
			(island_removal_mode 0)
		)
		(polygon
			(pts
				(arc
					(start 296.058082 -282.33497)
					(mid 295.390062 -282.33497)
					(end 296.058082 -282.33497)
				)
			)
		)
	)
	(zone
		(layers "B.Cu" "In15.Cu")
		(hatch none 0.5)
		(connect_pads
			(clearance 0)
		)
		(min_thickness 0.25)
		(keepout
			(tracks not_allowed)
			(vias allowed)
			(pads allowed)
			(copperpour not_allowed)
			(footprints allowed)
		)
		(placement
			(enabled no)
			(sheetname "")
		)
		(fill yes
			(thermal_gap 0.5)
			(thermal_bridge_width 0.5)
			(island_removal_mode 0)
		)
		(polygon
			(pts
				(arc
					(start 296.058082 -297.635168)
					(mid 295.390062 -297.635168)
					(end 296.058082 -297.635168)
				)
			)
		)
	)
	(zone
		(layers "B.Cu" "In15.Cu")
		(hatch none 0.5)
		(connect_pads
			(clearance 0)
		)
		(min_thickness 0.25)
		(keepout
			(tracks not_allowed)
			(vias allowed)
			(pads allowed)
			(copperpour not_allowed)
			(footprints allowed)
		)
		(placement
			(enabled no)
			(sheetname "")
		)
		(fill yes
			(thermal_gap 0.5)
			(thermal_bridge_width 0.5)
			(island_removal_mode 0)
		)
		(polygon
			(pts
				(arc
					(start 136.529826 -233.144314)
					(mid 135.899906 -233.144314)
					(end 136.529826 -233.144314)
				)
			)
		)
	)
	(zone
		(layers "B.Cu" "In15.Cu")
		(hatch none 0.5)
		(connect_pads
			(clearance 0)
		)
		(min_thickness 0.25)
		(keepout
			(tracks not_allowed)
			(vias allowed)
			(pads allowed)
			(copperpour not_allowed)
			(footprints allowed)
		)
		(placement
			(enabled no)
			(sheetname "")
		)
		(fill yes
			(thermal_gap 0.5)
			(thermal_bridge_width 0.5)
			(island_removal_mode 0)
		)
		(polygon
			(pts
				(arc
					(start 337.476084 -244.484144)
					(mid 336.846164 -244.484144)
					(end 337.476084 -244.484144)
				)
			)
		)
	)
	(zone
		(layers "B.Cu" "In15.Cu")
		(hatch none 0.5)
		(connect_pads
			(clearance 0)
		)
		(min_thickness 0.25)
		(keepout
			(tracks not_allowed)
			(vias allowed)
			(pads allowed)
			(copperpour not_allowed)
			(footprints allowed)
		)
		(placement
			(enabled no)
			(sheetname "")
		)
		(fill yes
			(thermal_gap 0.5)
			(thermal_bridge_width 0.5)
			(island_removal_mode 0)
		)
		(polygon
			(pts
				(arc
					(start 420.246048 -205.834996)
					(mid 419.578028 -205.834996)
					(end 420.246048 -205.834996)
				)
			)
		)
	)
	(zone
		(layers "B.Cu" "In15.Cu")
		(hatch none 0.5)
		(connect_pads
			(clearance 0)
		)
		(min_thickness 0.25)
		(keepout
			(tracks not_allowed)
			(vias allowed)
			(pads allowed)
			(copperpour not_allowed)
			(footprints allowed)
		)
		(placement
			(enabled no)
			(sheetname "")
		)
		(fill yes
			(thermal_gap 0.5)
			(thermal_bridge_width 0.5)
			(island_removal_mode 0)
		)
		(polygon
			(pts
				(arc
					(start 397.392398 -390.75106)
					(mid 396.724378 -390.75106)
					(end 397.392398 -390.75106)
				)
			)
		)
	)
	(zone
		(layers "B.Cu" "In15.Cu")
		(hatch none 0.5)
		(connect_pads
			(clearance 0)
		)
		(min_thickness 0.25)
		(keepout
			(tracks not_allowed)
			(vias allowed)
			(pads allowed)
			(copperpour not_allowed)
			(footprints allowed)
		)
		(placement
			(enabled no)
			(sheetname "")
		)
		(fill yes
			(thermal_gap 0.5)
			(thermal_bridge_width 0.5)
			(island_removal_mode 0)
		)
		(polygon
			(pts
				(arc
					(start 135.419592 -277.326344)
					(mid 134.789672 -277.326344)
					(end 135.419592 -277.326344)
				)
			)
		)
	)
	(zone
		(layers "B.Cu" "In15.Cu")
		(hatch none 0.5)
		(connect_pads
			(clearance 0)
		)
		(min_thickness 0.25)
		(keepout
			(tracks not_allowed)
			(vias allowed)
			(pads allowed)
			(copperpour not_allowed)
			(footprints allowed)
		)
		(placement
			(enabled no)
			(sheetname "")
		)
		(fill yes
			(thermal_gap 0.5)
			(thermal_bridge_width 0.5)
			(island_removal_mode 0)
		)
		(polygon
			(pts
				(arc
					(start 119.609616 -241.244374)
					(mid 118.979696 -241.244374)
					(end 119.609616 -241.244374)
				)
			)
		)
	)
	(zone
		(layers "B.Cu" "In15.Cu")
		(hatch none 0.5)
		(connect_pads
			(clearance 0)
		)
		(min_thickness 0.25)
		(keepout
			(tracks not_allowed)
			(vias allowed)
			(pads allowed)
			(copperpour not_allowed)
			(footprints allowed)
		)
		(placement
			(enabled no)
			(sheetname "")
		)
		(fill yes
			(thermal_gap 0.5)
			(thermal_bridge_width 0.5)
			(island_removal_mode 0)
		)
		(polygon
			(pts
				(arc
					(start 424.346116 -272.135092)
					(mid 423.678096 -272.135092)
					(end 424.346116 -272.135092)
				)
			)
		)
	)
	(zone
		(layers "B.Cu" "In15.Cu")
		(hatch none 0.5)
		(connect_pads
			(clearance 0)
		)
		(min_thickness 0.25)
		(keepout
			(tracks not_allowed)
			(vias allowed)
			(pads allowed)
			(copperpour not_allowed)
			(footprints allowed)
		)
		(placement
			(enabled no)
			(sheetname "")
		)
		(fill yes
			(thermal_gap 0.5)
			(thermal_bridge_width 0.5)
			(island_removal_mode 0)
		)
		(polygon
			(pts
				(arc
					(start 384.769868 -274.896072)
					(mid 384.139948 -274.896072)
					(end 384.769868 -274.896072)
				)
			)
		)
	)
	(zone
		(layers "B.Cu" "In15.Cu")
		(hatch none 0.5)
		(connect_pads
			(clearance 0)
		)
		(min_thickness 0.25)
		(keepout
			(tracks not_allowed)
			(vias allowed)
			(pads allowed)
			(copperpour not_allowed)
			(footprints allowed)
		)
		(placement
			(enabled no)
			(sheetname "")
		)
		(fill yes
			(thermal_gap 0.5)
			(thermal_bridge_width 0.5)
			(island_removal_mode 0)
		)
		(polygon
			(pts
				(arc
					(start 420.246048 -224.534984)
					(mid 419.578028 -224.534984)
					(end 420.246048 -224.534984)
				)
			)
		)
	)
	(zone
		(layers "B.Cu" "In15.Cu")
		(hatch none 0.5)
		(connect_pads
			(clearance 0)
		)
		(min_thickness 0.25)
		(keepout
			(tracks not_allowed)
			(vias allowed)
			(pads allowed)
			(copperpour not_allowed)
			(footprints allowed)
		)
		(placement
			(enabled no)
			(sheetname "")
		)
		(fill yes
			(thermal_gap 0.5)
			(thermal_bridge_width 0.5)
			(island_removal_mode 0)
		)
		(polygon
			(pts
				(arc
					(start 176.406048 -267.885418)
					(mid 175.738028 -267.885418)
					(end 176.406048 -267.885418)
				)
			)
		)
	)
	(zone
		(layers "B.Cu" "In15.Cu")
		(hatch none 0.5)
		(connect_pads
			(clearance 0)
		)
		(min_thickness 0.25)
		(keepout
			(tracks not_allowed)
			(vias allowed)
			(pads allowed)
			(copperpour not_allowed)
			(footprints allowed)
		)
		(placement
			(enabled no)
			(sheetname "")
		)
		(fill yes
			(thermal_gap 0.5)
			(thermal_bridge_width 0.5)
			(island_removal_mode 0)
		)
		(polygon
			(pts
				(arc
					(start 300.15815 -249.185176)
					(mid 299.49013 -249.185176)
					(end 300.15815 -249.185176)
				)
			)
		)
	)
	(zone
		(layers "B.Cu" "In15.Cu")
		(hatch none 0.5)
		(connect_pads
			(clearance 0)
		)
		(min_thickness 0.25)
		(keepout
			(tracks not_allowed)
			(vias allowed)
			(pads allowed)
			(copperpour not_allowed)
			(footprints allowed)
		)
		(placement
			(enabled no)
			(sheetname "")
		)
		(fill yes
			(thermal_gap 0.5)
			(thermal_bridge_width 0.5)
			(island_removal_mode 0)
		)
		(polygon
			(pts
				(arc
					(start 424.346116 -208.385156)
					(mid 423.678096 -208.385156)
					(end 424.346116 -208.385156)
				)
			)
		)
	)
	(zone
		(layers "B.Cu" "In15.Cu")
		(hatch none 0.5)
		(connect_pads
			(clearance 0)
		)
		(min_thickness 0.25)
		(keepout
			(tracks not_allowed)
			(vias allowed)
			(pads allowed)
			(copperpour not_allowed)
			(footprints allowed)
		)
		(placement
			(enabled no)
			(sheetname "")
		)
		(fill yes
			(thermal_gap 0.5)
			(thermal_bridge_width 0.5)
			(island_removal_mode 0)
		)
		(polygon
			(pts
				(arc
					(start 336.06613 -245.29415)
					(mid 335.43621 -245.29415)
					(end 336.06613 -245.29415)
				)
			)
		)
	)
	(zone
		(layers "B.Cu" "In15.Cu")
		(hatch none 0.5)
		(connect_pads
			(clearance 0)
		)
		(min_thickness 0.25)
		(keepout
			(tracks not_allowed)
			(vias allowed)
			(pads allowed)
			(copperpour not_allowed)
			(footprints allowed)
		)
		(placement
			(enabled no)
			(sheetname "")
		)
		(fill yes
			(thermal_gap 0.5)
			(thermal_bridge_width 0.5)
			(island_removal_mode 0)
		)
		(polygon
			(pts
				(arc
					(start 48.118014 -239.835436)
					(mid 47.449994 -239.835436)
					(end 48.118014 -239.835436)
				)
			)
		)
	)
	(zone
		(layers "B.Cu" "In15.Cu")
		(hatch none 0.5)
		(connect_pads
			(clearance 0)
		)
		(min_thickness 0.25)
		(keepout
			(tracks not_allowed)
			(vias allowed)
			(pads allowed)
			(copperpour not_allowed)
			(footprints allowed)
		)
		(placement
			(enabled no)
			(sheetname "")
		)
		(fill yes
			(thermal_gap 0.5)
			(thermal_bridge_width 0.5)
			(island_removal_mode 0)
		)
		(polygon
			(pts
				(arc
					(start 300.15815 -228.785166)
					(mid 299.49013 -228.785166)
					(end 300.15815 -228.785166)
				)
			)
		)
	)
	(zone
		(layers "B.Cu" "In15.Cu")
		(hatch none 0.5)
		(connect_pads
			(clearance 0)
		)
		(min_thickness 0.25)
		(keepout
			(tracks not_allowed)
			(vias allowed)
			(pads allowed)
			(copperpour not_allowed)
			(footprints allowed)
		)
		(placement
			(enabled no)
			(sheetname "")
		)
		(fill yes
			(thermal_gap 0.5)
			(thermal_bridge_width 0.5)
			(island_removal_mode 0)
		)
		(polygon
			(pts
				(arc
					(start 134.649718 -249.344434)
					(mid 134.019798 -249.344434)
					(end 134.649718 -249.344434)
				)
			)
		)
	)
	(zone
		(layers "B.Cu" "In15.Cu")
		(hatch none 0.5)
		(connect_pads
			(clearance 0)
		)
		(min_thickness 0.25)
		(keepout
			(tracks not_allowed)
			(vias allowed)
			(pads allowed)
			(copperpour not_allowed)
			(footprints allowed)
		)
		(placement
			(enabled no)
			(sheetname "")
		)
		(fill yes
			(thermal_gap 0.5)
			(thermal_bridge_width 0.5)
			(island_removal_mode 0)
		)
		(polygon
			(pts
				(arc
					(start 384.469894 -241.24412)
					(mid 383.839974 -241.24412)
					(end 384.469894 -241.24412)
				)
			)
		)
	)
	(zone
		(layers "B.Cu" "In15.Cu")
		(hatch none 0.5)
		(connect_pads
			(clearance 0)
		)
		(min_thickness 0.25)
		(keepout
			(tracks not_allowed)
			(vias allowed)
			(pads allowed)
			(copperpour not_allowed)
			(footprints allowed)
		)
		(placement
			(enabled no)
			(sheetname "")
		)
		(fill yes
			(thermal_gap 0.5)
			(thermal_bridge_width 0.5)
			(island_removal_mode 0)
		)
		(polygon
			(pts
				(arc
					(start 382.589786 -226.664266)
					(mid 381.959866 -226.664266)
					(end 382.589786 -226.664266)
				)
			)
		)
	)
	(zone
		(layers "B.Cu" "In15.Cu")
		(hatch none 0.5)
		(connect_pads
			(clearance 0)
		)
		(min_thickness 0.25)
		(keepout
			(tracks not_allowed)
			(vias allowed)
			(pads allowed)
			(copperpour not_allowed)
			(footprints allowed)
		)
		(placement
			(enabled no)
			(sheetname "")
		)
		(fill yes
			(thermal_gap 0.5)
			(thermal_bridge_width 0.5)
			(island_removal_mode 0)
		)
		(polygon
			(pts
				(arc
					(start 336.06613 -230.714296)
					(mid 335.43621 -230.714296)
					(end 336.06613 -230.714296)
				)
			)
		)
	)
	(zone
		(layers "B.Cu" "In15.Cu")
		(hatch none 0.5)
		(connect_pads
			(clearance 0)
		)
		(min_thickness 0.25)
		(keepout
			(tracks not_allowed)
			(vias allowed)
			(pads allowed)
			(copperpour not_allowed)
			(footprints allowed)
		)
		(placement
			(enabled no)
			(sheetname "")
		)
		(fill yes
			(thermal_gap 0.5)
			(thermal_bridge_width 0.5)
			(island_removal_mode 0)
		)
		(polygon
			(pts
				(arc
					(start 116.789708 -238.00435)
					(mid 116.159788 -238.00435)
					(end 116.789708 -238.00435)
				)
			)
		)
	)
	(zone
		(layers "B.Cu" "In15.Cu")
		(hatch none 0.5)
		(connect_pads
			(clearance 0)
		)
		(min_thickness 0.25)
		(keepout
			(tracks not_allowed)
			(vias allowed)
			(pads allowed)
			(copperpour not_allowed)
			(footprints allowed)
		)
		(placement
			(enabled no)
			(sheetname "")
		)
		(fill yes
			(thermal_gap 0.5)
			(thermal_bridge_width 0.5)
			(island_removal_mode 0)
		)
		(polygon
			(pts
				(arc
					(start 300.15815 -296.78503)
					(mid 299.49013 -296.78503)
					(end 300.15815 -296.78503)
				)
			)
		)
	)
	(zone
		(layers "B.Cu" "In15.Cu")
		(hatch none 0.5)
		(connect_pads
			(clearance 0)
		)
		(min_thickness 0.25)
		(keepout
			(tracks not_allowed)
			(vias allowed)
			(pads allowed)
			(copperpour not_allowed)
			(footprints allowed)
		)
		(placement
			(enabled no)
			(sheetname "")
		)
		(fill yes
			(thermal_gap 0.5)
			(thermal_bridge_width 0.5)
			(island_removal_mode 0)
		)
		(polygon
			(pts
				(arc
					(start 384.299714 -278.946102)
					(mid 383.669794 -278.946102)
					(end 384.299714 -278.946102)
				)
			)
		)
	)
	(zone
		(layers "B.Cu" "In15.Cu")
		(hatch none 0.5)
		(connect_pads
			(clearance 0)
		)
		(min_thickness 0.25)
		(keepout
			(tracks not_allowed)
			(vias allowed)
			(pads allowed)
			(copperpour not_allowed)
			(footprints allowed)
		)
		(placement
			(enabled no)
			(sheetname "")
		)
		(fill yes
			(thermal_gap 0.5)
			(thermal_bridge_width 0.5)
			(island_removal_mode 0)
		)
		(polygon
			(pts
				(arc
					(start 420.246048 -295.085008)
					(mid 419.578028 -295.085008)
					(end 420.246048 -295.085008)
				)
			)
		)
	)
	(zone
		(layers "B.Cu" "In15.Cu")
		(hatch none 0.5)
		(connect_pads
			(clearance 0)
		)
		(min_thickness 0.25)
		(keepout
			(tracks not_allowed)
			(vias allowed)
			(pads allowed)
			(copperpour not_allowed)
			(footprints allowed)
		)
		(placement
			(enabled no)
			(sheetname "")
		)
		(fill yes
			(thermal_gap 0.5)
			(thermal_bridge_width 0.5)
			(island_removal_mode 0)
		)
		(polygon
			(pts
				(arc
					(start 420.246048 -233.884978)
					(mid 419.578028 -233.884978)
					(end 420.246048 -233.884978)
				)
			)
		)
	)
	(zone
		(layers "B.Cu" "In15.Cu")
		(hatch none 0.5)
		(connect_pads
			(clearance 0)
		)
		(min_thickness 0.25)
		(keepout
			(tracks not_allowed)
			(vias allowed)
			(pads allowed)
			(copperpour not_allowed)
			(footprints allowed)
		)
		(placement
			(enabled no)
			(sheetname "")
		)
		(fill yes
			(thermal_gap 0.5)
			(thermal_bridge_width 0.5)
			(island_removal_mode 0)
		)
		(polygon
			(pts
				(arc
					(start 354.39604 -239.624108)
					(mid 353.76612 -239.624108)
					(end 354.39604 -239.624108)
				)
			)
		)
	)
	(zone
		(layers "B.Cu" "In15.Cu")
		(hatch none 0.5)
		(connect_pads
			(clearance 0)
		)
		(min_thickness 0.25)
		(keepout
			(tracks not_allowed)
			(vias allowed)
			(pads allowed)
			(copperpour not_allowed)
			(footprints allowed)
		)
		(placement
			(enabled no)
			(sheetname "")
		)
		(fill yes
			(thermal_gap 0.5)
			(thermal_bridge_width 0.5)
			(island_removal_mode 0)
		)
		(polygon
			(pts
				(arc
					(start 356.746048 -240.434114)
					(mid 356.116128 -240.434114)
					(end 356.746048 -240.434114)
				)
			)
		)
	)
	(zone
		(layers "B.Cu" "In15.Cu")
		(hatch none 0.5)
		(connect_pads
			(clearance 0)
		)
		(min_thickness 0.25)
		(keepout
			(tracks not_allowed)
			(vias allowed)
			(pads allowed)
			(copperpour not_allowed)
			(footprints allowed)
		)
		(placement
			(enabled no)
			(sheetname "")
		)
		(fill yes
			(thermal_gap 0.5)
			(thermal_bridge_width 0.5)
			(island_removal_mode 0)
		)
		(polygon
			(pts
				(arc
					(start 336.366104 -275.706078)
					(mid 335.736184 -275.706078)
					(end 336.366104 -275.706078)
				)
			)
		)
	)
	(zone
		(layers "B.Cu" "In15.Cu")
		(hatch none 0.5)
		(connect_pads
			(clearance 0)
		)
		(min_thickness 0.25)
		(keepout
			(tracks not_allowed)
			(vias allowed)
			(pads allowed)
			(copperpour not_allowed)
			(footprints allowed)
		)
		(placement
			(enabled no)
			(sheetname "")
		)
		(fill yes
			(thermal_gap 0.5)
			(thermal_bridge_width 0.5)
			(island_removal_mode 0)
		)
		(polygon
			(pts
				(arc
					(start 388.136892 -434.289962)
					(mid 387.3627 -434.289962)
					(end 388.136892 -434.289962)
				)
			)
		)
	)
	(zone
		(layers "B.Cu" "In15.Cu")
		(hatch none 0.5)
		(connect_pads
			(clearance 0)
		)
		(min_thickness 0.25)
		(keepout
			(tracks not_allowed)
			(vias allowed)
			(pads allowed)
			(copperpour not_allowed)
			(footprints allowed)
		)
		(placement
			(enabled no)
			(sheetname "")
		)
		(fill yes
			(thermal_gap 0.5)
			(thermal_bridge_width 0.5)
			(island_removal_mode 0)
		)
		(polygon
			(pts
				(arc
					(start 346.0369 -435.489858)
					(mid 345.262708 -435.489858)
					(end 346.0369 -435.489858)
				)
			)
		)
	)
	(zone
		(layers "B.Cu" "In15.Cu")
		(hatch none 0.5)
		(connect_pads
			(clearance 0)
		)
		(min_thickness 0.25)
		(keepout
			(tracks not_allowed)
			(vias allowed)
			(pads allowed)
			(copperpour not_allowed)
			(footprints allowed)
		)
		(placement
			(enabled no)
			(sheetname "")
		)
		(fill yes
			(thermal_gap 0.5)
			(thermal_bridge_width 0.5)
			(island_removal_mode 0)
		)
		(polygon
			(pts
				(arc
					(start 172.30598 -299.335444)
					(mid 171.63796 -299.335444)
					(end 172.30598 -299.335444)
				)
			)
		)
	)
	(zone
		(layers "B.Cu" "In15.Cu")
		(hatch none 0.5)
		(connect_pads
			(clearance 0)
		)
		(min_thickness 0.25)
		(keepout
			(tracks not_allowed)
			(vias allowed)
			(pads allowed)
			(copperpour not_allowed)
			(footprints allowed)
		)
		(placement
			(enabled no)
			(sheetname "")
		)
		(fill yes
			(thermal_gap 0.5)
			(thermal_bridge_width 0.5)
			(island_removal_mode 0)
		)
		(polygon
			(pts
				(arc
					(start 80.678274 -393.292838)
					(mid 80.010254 -393.292838)
					(end 80.678274 -393.292838)
				)
			)
		)
	)
	(zone
		(layers "B.Cu" "In15.Cu")
		(hatch none 0.5)
		(connect_pads
			(clearance 0)
		)
		(min_thickness 0.25)
		(keepout
			(tracks not_allowed)
			(vias allowed)
			(pads allowed)
			(copperpour not_allowed)
			(footprints allowed)
		)
		(placement
			(enabled no)
			(sheetname "")
		)
		(fill yes
			(thermal_gap 0.5)
			(thermal_bridge_width 0.5)
			(island_removal_mode 0)
		)
		(polygon
			(pts
				(arc
					(start 48.118014 -209.235294)
					(mid 47.449994 -209.235294)
					(end 48.118014 -209.235294)
				)
			)
		)
	)
	(zone
		(layers "B.Cu" "In15.Cu")
		(hatch none 0.5)
		(connect_pads
			(clearance 0)
		)
		(min_thickness 0.25)
		(keepout
			(tracks not_allowed)
			(vias allowed)
			(pads allowed)
			(copperpour not_allowed)
			(footprints allowed)
		)
		(placement
			(enabled no)
			(sheetname "")
		)
		(fill yes
			(thermal_gap 0.5)
			(thermal_bridge_width 0.5)
			(island_removal_mode 0)
		)
		(polygon
			(pts
				(arc
					(start 300.15815 -210.085178)
					(mid 299.49013 -210.085178)
					(end 300.15815 -210.085178)
				)
			)
		)
	)
	(zone
		(layers "B.Cu" "In15.Cu")
		(hatch none 0.5)
		(connect_pads
			(clearance 0)
		)
		(min_thickness 0.25)
		(keepout
			(tracks not_allowed)
			(vias allowed)
			(pads allowed)
			(copperpour not_allowed)
			(footprints allowed)
		)
		(placement
			(enabled no)
			(sheetname "")
		)
		(fill yes
			(thermal_gap 0.5)
			(thermal_bridge_width 0.5)
			(island_removal_mode 0)
		)
		(polygon
			(pts
				(arc
					(start 132.136896 -435.489858)
					(mid 131.362704 -435.489858)
					(end 132.136896 -435.489858)
				)
			)
		)
	)
	(zone
		(layers "B.Cu" "In15.Cu")
		(hatch none 0.5)
		(connect_pads
			(clearance 0)
		)
		(min_thickness 0.25)
		(keepout
			(tracks not_allowed)
			(vias allowed)
			(pads allowed)
			(copperpour not_allowed)
			(footprints allowed)
		)
		(placement
			(enabled no)
			(sheetname "")
		)
		(fill yes
			(thermal_gap 0.5)
			(thermal_bridge_width 0.5)
			(island_removal_mode 0)
		)
		(polygon
			(pts
				(arc
					(start 134.949692 -273.276314)
					(mid 134.319772 -273.276314)
					(end 134.949692 -273.276314)
				)
			)
		)
	)
	(zone
		(layers "B.Cu" "In15.Cu")
		(hatch none 0.5)
		(connect_pads
			(clearance 0)
		)
		(min_thickness 0.25)
		(keepout
			(tracks not_allowed)
			(vias allowed)
			(pads allowed)
			(copperpour not_allowed)
			(footprints allowed)
		)
		(placement
			(enabled no)
			(sheetname "")
		)
		(fill yes
			(thermal_gap 0.5)
			(thermal_bridge_width 0.5)
			(island_removal_mode 0)
		)
		(polygon
			(pts
				(arc
					(start 296.058082 -276.38502)
					(mid 295.390062 -276.38502)
					(end 296.058082 -276.38502)
				)
			)
		)
	)
	(zone
		(layers "B.Cu" "In15.Cu")
		(hatch none 0.5)
		(connect_pads
			(clearance 0)
		)
		(min_thickness 0.25)
		(keepout
			(tracks not_allowed)
			(vias allowed)
			(pads allowed)
			(copperpour not_allowed)
			(footprints allowed)
		)
		(placement
			(enabled no)
			(sheetname "")
		)
		(fill yes
			(thermal_gap 0.5)
			(thermal_bridge_width 0.5)
			(island_removal_mode 0)
		)
		(polygon
			(pts
				(arc
					(start 383.99974 -235.574078)
					(mid 383.36982 -235.574078)
					(end 383.99974 -235.574078)
				)
			)
		)
	)
	(zone
		(layers "B.Cu" "In15.Cu")
		(hatch none 0.5)
		(connect_pads
			(clearance 0)
		)
		(min_thickness 0.25)
		(keepout
			(tracks not_allowed)
			(vias allowed)
			(pads allowed)
			(copperpour not_allowed)
			(footprints allowed)
		)
		(placement
			(enabled no)
			(sheetname "")
		)
		(fill yes
			(thermal_gap 0.5)
			(thermal_bridge_width 0.5)
			(island_removal_mode 0)
		)
		(polygon
			(pts
				(arc
					(start 48.118014 -268.735302)
					(mid 47.449994 -268.735302)
					(end 48.118014 -268.735302)
				)
			)
		)
	)
	(zone
		(layers "B.Cu" "In15.Cu")
		(hatch none 0.5)
		(connect_pads
			(clearance 0)
		)
		(min_thickness 0.25)
		(keepout
			(tracks not_allowed)
			(vias allowed)
			(pads allowed)
			(copperpour not_allowed)
			(footprints allowed)
		)
		(placement
			(enabled no)
			(sheetname "")
		)
		(fill yes
			(thermal_gap 0.5)
			(thermal_bridge_width 0.5)
			(island_removal_mode 0)
		)
		(polygon
			(pts
				(arc
					(start 88.426036 -280.566368)
					(mid 87.796116 -280.566368)
					(end 88.426036 -280.566368)
				)
			)
		)
	)
	(zone
		(layers "B.Cu" "In15.Cu")
		(hatch none 0.5)
		(connect_pads
			(clearance 0)
		)
		(min_thickness 0.25)
		(keepout
			(tracks not_allowed)
			(vias allowed)
			(pads allowed)
			(copperpour not_allowed)
			(footprints allowed)
		)
		(placement
			(enabled no)
			(sheetname "")
		)
		(fill yes
			(thermal_gap 0.5)
			(thermal_bridge_width 0.5)
			(island_removal_mode 0)
		)
		(polygon
			(pts
				(arc
					(start 89.066116 -225.854514)
					(mid 88.436196 -225.854514)
					(end 89.066116 -225.854514)
				)
			)
		)
	)
	(zone
		(layers "B.Cu" "In15.Cu")
		(hatch none 0.5)
		(connect_pads
			(clearance 0)
		)
		(min_thickness 0.25)
		(keepout
			(tracks not_allowed)
			(vias allowed)
			(pads allowed)
			(copperpour not_allowed)
			(footprints allowed)
		)
		(placement
			(enabled no)
			(sheetname "")
		)
		(fill yes
			(thermal_gap 0.5)
			(thermal_bridge_width 0.5)
			(island_removal_mode 0)
		)
		(polygon
			(pts
				(arc
					(start 133.250432 -392.429238)
					(mid 132.582412 -392.429238)
					(end 133.250432 -392.429238)
				)
			)
		)
	)
	(zone
		(layers "B.Cu" "In15.Cu")
		(hatch none 0.5)
		(connect_pads
			(clearance 0)
		)
		(min_thickness 0.25)
		(keepout
			(tracks not_allowed)
			(vias allowed)
			(pads allowed)
			(copperpour not_allowed)
			(footprints allowed)
		)
		(placement
			(enabled no)
			(sheetname "")
		)
		(fill yes
			(thermal_gap 0.5)
			(thermal_bridge_width 0.5)
			(island_removal_mode 0)
		)
		(polygon
			(pts
				(arc
					(start 348.678246 -401.674838)
					(mid 348.010226 -401.674838)
					(end 348.678246 -401.674838)
				)
			)
		)
	)
	(zone
		(layers "B.Cu" "In15.Cu")
		(hatch none 0.5)
		(connect_pads
			(clearance 0)
		)
		(min_thickness 0.25)
		(keepout
			(tracks not_allowed)
			(vias allowed)
			(pads allowed)
			(copperpour not_allowed)
			(footprints allowed)
		)
		(placement
			(enabled no)
			(sheetname "")
		)
		(fill yes
			(thermal_gap 0.5)
			(thermal_bridge_width 0.5)
			(island_removal_mode 0)
		)
		(polygon
			(pts
				(arc
					(start 48.118014 -272.98523)
					(mid 47.449994 -272.98523)
					(end 48.118014 -272.98523)
				)
			)
		)
	)
	(zone
		(layers "B.Cu" "In15.Cu")
		(hatch none 0.5)
		(connect_pads
			(clearance 0)
		)
		(min_thickness 0.25)
		(keepout
			(tracks not_allowed)
			(vias allowed)
			(pads allowed)
			(copperpour not_allowed)
			(footprints allowed)
		)
		(placement
			(enabled no)
			(sheetname "")
		)
		(fill yes
			(thermal_gap 0.5)
			(thermal_bridge_width 0.5)
			(island_removal_mode 0)
		)
		(polygon
			(pts
				(arc
					(start 424.346116 -252.584966)
					(mid 423.678096 -252.584966)
					(end 424.346116 -252.584966)
				)
			)
		)
	)
	(zone
		(layers "B.Cu" "In15.Cu")
		(hatch none 0.5)
		(connect_pads
			(clearance 0)
		)
		(min_thickness 0.25)
		(keepout
			(tracks not_allowed)
			(vias allowed)
			(pads allowed)
			(copperpour not_allowed)
			(footprints allowed)
		)
		(placement
			(enabled no)
			(sheetname "")
		)
		(fill yes
			(thermal_gap 0.5)
			(thermal_bridge_width 0.5)
			(island_removal_mode 0)
		)
		(polygon
			(pts
				(arc
					(start 296.058082 -213.484968)
					(mid 295.390062 -213.484968)
					(end 296.058082 -213.484968)
				)
			)
		)
	)
	(zone
		(layers "B.Cu" "In15.Cu")
		(hatch none 0.5)
		(connect_pads
			(clearance 0)
		)
		(min_thickness 0.25)
		(keepout
			(tracks not_allowed)
			(vias allowed)
			(pads allowed)
			(copperpour not_allowed)
			(footprints allowed)
		)
		(placement
			(enabled no)
			(sheetname "")
		)
		(fill yes
			(thermal_gap 0.5)
			(thermal_bridge_width 0.5)
			(island_removal_mode 0)
		)
		(polygon
			(pts
				(arc
					(start 296.058082 -244.934994)
					(mid 295.390062 -244.934994)
					(end 296.058082 -244.934994)
				)
			)
		)
	)
	(zone
		(layers "B.Cu" "In15.Cu")
		(hatch none 0.5)
		(connect_pads
			(clearance 0)
		)
		(min_thickness 0.25)
		(keepout
			(tracks not_allowed)
			(vias allowed)
			(pads allowed)
			(copperpour not_allowed)
			(footprints allowed)
		)
		(placement
			(enabled no)
			(sheetname "")
		)
		(fill yes
			(thermal_gap 0.5)
			(thermal_bridge_width 0.5)
			(island_removal_mode 0)
		)
		(polygon
			(pts
				(arc
					(start 379.650498 -401.674838)
					(mid 378.982478 -401.674838)
					(end 379.650498 -401.674838)
				)
			)
		)
	)
	(zone
		(layers "B.Cu" "In15.Cu")
		(hatch none 0.5)
		(connect_pads
			(clearance 0)
		)
		(min_thickness 0.25)
		(keepout
			(tracks not_allowed)
			(vias allowed)
			(pads allowed)
			(copperpour not_allowed)
			(footprints allowed)
		)
		(placement
			(enabled no)
			(sheetname "")
		)
		(fill yes
			(thermal_gap 0.5)
			(thermal_bridge_width 0.5)
			(island_removal_mode 0)
		)
		(polygon
			(pts
				(arc
					(start 172.30598 -318.035432)
					(mid 171.63796 -318.035432)
					(end 172.30598 -318.035432)
				)
			)
		)
	)
	(zone
		(layers "B.Cu" "In15.Cu")
		(hatch none 0.5)
		(connect_pads
			(clearance 0)
		)
		(min_thickness 0.25)
		(keepout
			(tracks not_allowed)
			(vias allowed)
			(pads allowed)
			(copperpour not_allowed)
			(footprints allowed)
		)
		(placement
			(enabled no)
			(sheetname "")
		)
		(fill yes
			(thermal_gap 0.5)
			(thermal_bridge_width 0.5)
			(island_removal_mode 0)
		)
		(polygon
			(pts
				(arc
					(start 420.246048 -244.934994)
					(mid 419.578028 -244.934994)
					(end 420.246048 -244.934994)
				)
			)
		)
	)
	(zone
		(layers "B.Cu" "In15.Cu")
		(hatch none 0.5)
		(connect_pads
			(clearance 0)
		)
		(min_thickness 0.25)
		(keepout
			(tracks not_allowed)
			(vias allowed)
			(pads allowed)
			(copperpour not_allowed)
			(footprints allowed)
		)
		(placement
			(enabled no)
			(sheetname "")
		)
		(fill yes
			(thermal_gap 0.5)
			(thermal_bridge_width 0.5)
			(island_removal_mode 0)
		)
		(polygon
			(pts
				(arc
					(start 88.426036 -274.08632)
					(mid 87.796116 -274.08632)
					(end 88.426036 -274.08632)
				)
			)
		)
	)
	(zone
		(layers "B.Cu" "In15.Cu")
		(hatch none 0.5)
		(connect_pads
			(clearance 0)
		)
		(min_thickness 0.25)
		(keepout
			(tracks not_allowed)
			(vias allowed)
			(pads allowed)
			(copperpour not_allowed)
			(footprints allowed)
		)
		(placement
			(enabled no)
			(sheetname "")
		)
		(fill yes
			(thermal_gap 0.5)
			(thermal_bridge_width 0.5)
			(island_removal_mode 0)
		)
		(polygon
			(pts
				(arc
					(start 296.058082 -235.585)
					(mid 295.390062 -235.585)
					(end 296.058082 -235.585)
				)
			)
		)
	)
	(zone
		(layers "B.Cu" "In15.Cu")
		(hatch none 0.5)
		(connect_pads
			(clearance 0)
		)
		(min_thickness 0.25)
		(keepout
			(tracks not_allowed)
			(vias allowed)
			(pads allowed)
			(copperpour not_allowed)
			(footprints allowed)
		)
		(placement
			(enabled no)
			(sheetname "")
		)
		(fill yes
			(thermal_gap 0.5)
			(thermal_bridge_width 0.5)
			(island_removal_mode 0)
		)
		(polygon
			(pts
				(arc
					(start 296.058082 -318.035178)
					(mid 295.390062 -318.035178)
					(end 296.058082 -318.035178)
				)
			)
		)
	)
	(zone
		(layers "B.Cu" "In15.Cu")
		(hatch none 0.5)
		(connect_pads
			(clearance 0)
		)
		(min_thickness 0.25)
		(keepout
			(tracks not_allowed)
			(vias allowed)
			(pads allowed)
			(copperpour not_allowed)
			(footprints allowed)
		)
		(placement
			(enabled no)
			(sheetname "")
		)
		(fill yes
			(thermal_gap 0.5)
			(thermal_bridge_width 0.5)
			(island_removal_mode 0)
		)
		(polygon
			(pts
				(arc
					(start 424.346116 -221.985078)
					(mid 423.678096 -221.985078)
					(end 424.346116 -221.985078)
				)
			)
		)
	)
	(zone
		(layers "B.Cu" "In15.Cu")
		(hatch none 0.5)
		(connect_pads
			(clearance 0)
		)
		(min_thickness 0.25)
		(keepout
			(tracks not_allowed)
			(vias allowed)
			(pads allowed)
			(copperpour not_allowed)
			(footprints allowed)
		)
		(placement
			(enabled no)
			(sheetname "")
		)
		(fill yes
			(thermal_gap 0.5)
			(thermal_bridge_width 0.5)
			(island_removal_mode 0)
		)
		(polygon
			(pts
				(arc
					(start 172.30598 -248.335292)
					(mid 171.63796 -248.335292)
					(end 172.30598 -248.335292)
				)
			)
		)
	)
	(zone
		(layers "B.Cu" "In15.Cu")
		(hatch none 0.5)
		(connect_pads
			(clearance 0)
		)
		(min_thickness 0.25)
		(keepout
			(tracks not_allowed)
			(vias allowed)
			(pads allowed)
			(copperpour not_allowed)
			(footprints allowed)
		)
		(placement
			(enabled no)
			(sheetname "")
		)
		(fill yes
			(thermal_gap 0.5)
			(thermal_bridge_width 0.5)
			(island_removal_mode 0)
		)
		(polygon
			(pts
				(arc
					(start 384.45059 -401.674838)
					(mid 383.78257 -401.674838)
					(end 384.45059 -401.674838)
				)
			)
		)
	)
	(zone
		(layers "B.Cu" "In15.Cu")
		(hatch none 0.5)
		(connect_pads
			(clearance 0)
		)
		(min_thickness 0.25)
		(keepout
			(tracks not_allowed)
			(vias allowed)
			(pads allowed)
			(copperpour not_allowed)
			(footprints allowed)
		)
		(placement
			(enabled no)
			(sheetname "")
		)
		(fill yes
			(thermal_gap 0.5)
			(thermal_bridge_width 0.5)
			(island_removal_mode 0)
		)
		(polygon
			(pts
				(arc
					(start 93.8784 -392.429238)
					(mid 93.21038 -392.429238)
					(end 93.8784 -392.429238)
				)
			)
		)
	)
	(zone
		(layers "B.Cu" "In15.Cu")
		(hatch none 0.5)
		(connect_pads
			(clearance 0)
		)
		(min_thickness 0.25)
		(keepout
			(tracks not_allowed)
			(vias allowed)
			(pads allowed)
			(copperpour not_allowed)
			(footprints allowed)
		)
		(placement
			(enabled no)
			(sheetname "")
		)
		(fill yes
			(thermal_gap 0.5)
			(thermal_bridge_width 0.5)
			(island_removal_mode 0)
		)
		(polygon
			(pts
				(arc
					(start 420.246048 -218.585034)
					(mid 419.578028 -218.585034)
					(end 420.246048 -218.585034)
				)
			)
		)
	)
	(zone
		(layers "B.Cu" "In15.Cu")
		(hatch none 0.5)
		(connect_pads
			(clearance 0)
		)
		(min_thickness 0.25)
		(keepout
			(tracks not_allowed)
			(vias allowed)
			(pads allowed)
			(copperpour not_allowed)
			(footprints allowed)
		)
		(placement
			(enabled no)
			(sheetname "")
		)
		(fill yes
			(thermal_gap 0.5)
			(thermal_bridge_width 0.5)
			(island_removal_mode 0)
		)
		(polygon
			(pts
				(arc
					(start 300.15815 -281.485086)
					(mid 299.49013 -281.485086)
					(end 300.15815 -281.485086)
				)
			)
		)
	)
	(zone
		(layers "B.Cu" "In15.Cu")
		(hatch none 0.5)
		(connect_pads
			(clearance 0)
		)
		(min_thickness 0.25)
		(keepout
			(tracks not_allowed)
			(vias allowed)
			(pads allowed)
			(copperpour not_allowed)
			(footprints allowed)
		)
		(placement
			(enabled no)
			(sheetname "")
		)
		(fill yes
			(thermal_gap 0.5)
			(thermal_bridge_width 0.5)
			(island_removal_mode 0)
		)
		(polygon
			(pts
				(arc
					(start 383.99974 -230.714296)
					(mid 383.36982 -230.714296)
					(end 383.99974 -230.714296)
				)
			)
		)
	)
	(zone
		(layers "B.Cu" "In15.Cu")
		(hatch none 0.5)
		(connect_pads
			(clearance 0)
		)
		(min_thickness 0.25)
		(keepout
			(tracks not_allowed)
			(vias allowed)
			(pads allowed)
			(copperpour not_allowed)
			(footprints allowed)
		)
		(placement
			(enabled no)
			(sheetname "")
		)
		(fill yes
			(thermal_gap 0.5)
			(thermal_bridge_width 0.5)
			(island_removal_mode 0)
		)
		(polygon
			(pts
				(arc
					(start 135.119618 -245.294404)
					(mid 134.489698 -245.294404)
					(end 135.119618 -245.294404)
				)
			)
		)
	)
	(zone
		(layers "B.Cu" "In15.Cu")
		(hatch none 0.5)
		(connect_pads
			(clearance 0)
		)
		(min_thickness 0.25)
		(keepout
			(tracks not_allowed)
			(vias allowed)
			(pads allowed)
			(copperpour not_allowed)
			(footprints allowed)
		)
		(placement
			(enabled no)
			(sheetname "")
		)
		(fill yes
			(thermal_gap 0.5)
			(thermal_bridge_width 0.5)
			(island_removal_mode 0)
		)
		(polygon
			(pts
				(arc
					(start 317.036704 -434.289962)
					(mid 316.262512 -434.289962)
					(end 317.036704 -434.289962)
				)
			)
		)
	)
	(zone
		(layers "B.Cu" "In15.Cu")
		(hatch none 0.5)
		(connect_pads
			(clearance 0)
		)
		(min_thickness 0.25)
		(keepout
			(tracks not_allowed)
			(vias allowed)
			(pads allowed)
			(copperpour not_allowed)
			(footprints allowed)
		)
		(placement
			(enabled no)
			(sheetname "")
		)
		(fill yes
			(thermal_gap 0.5)
			(thermal_bridge_width 0.5)
			(island_removal_mode 0)
		)
		(polygon
			(pts
				(arc
					(start 382.136904 -434.48986)
					(mid 381.362712 -434.48986)
					(end 382.136904 -434.48986)
				)
			)
		)
	)
	(zone
		(layers "B.Cu" "In15.Cu")
		(hatch none 0.5)
		(connect_pads
			(clearance 0)
		)
		(min_thickness 0.25)
		(keepout
			(tracks not_allowed)
			(vias allowed)
			(pads allowed)
			(copperpour not_allowed)
			(footprints allowed)
		)
		(placement
			(enabled no)
			(sheetname "")
		)
		(fill yes
			(thermal_gap 0.5)
			(thermal_bridge_width 0.5)
			(island_removal_mode 0)
		)
		(polygon
			(pts
				(arc
					(start 136.529826 -244.484398)
					(mid 135.899906 -244.484398)
					(end 136.529826 -244.484398)
				)
			)
		)
	)
	(zone
		(layers "B.Cu" "In15.Cu")
		(hatch none 0.5)
		(connect_pads
			(clearance 0)
		)
		(min_thickness 0.25)
		(keepout
			(tracks not_allowed)
			(vias allowed)
			(pads allowed)
			(copperpour not_allowed)
			(footprints allowed)
		)
		(placement
			(enabled no)
			(sheetname "")
		)
		(fill yes
			(thermal_gap 0.5)
			(thermal_bridge_width 0.5)
			(island_removal_mode 0)
		)
		(polygon
			(pts
				(arc
					(start 149.784054 -371.49913)
					(mid 149.116034 -371.49913)
					(end 149.784054 -371.49913)
				)
			)
		)
	)
	(zone
		(layers "B.Cu" "In15.Cu")
		(hatch none 0.5)
		(connect_pads
			(clearance 0)
		)
		(min_thickness 0.25)
		(keepout
			(tracks not_allowed)
			(vias allowed)
			(pads allowed)
			(copperpour not_allowed)
			(footprints allowed)
		)
		(placement
			(enabled no)
			(sheetname "")
		)
		(fill yes
			(thermal_gap 0.5)
			(thermal_bridge_width 0.5)
			(island_removal_mode 0)
		)
		(polygon
			(pts
				(arc
					(start 76.037186 -434.48986)
					(mid 75.262994 -434.48986)
					(end 76.037186 -434.48986)
				)
			)
		)
	)
	(zone
		(layers "B.Cu" "In15.Cu")
		(hatch none 0.5)
		(connect_pads
			(clearance 0)
		)
		(min_thickness 0.25)
		(keepout
			(tracks not_allowed)
			(vias allowed)
			(pads allowed)
			(copperpour not_allowed)
			(footprints allowed)
		)
		(placement
			(enabled no)
			(sheetname "")
		)
		(fill yes
			(thermal_gap 0.5)
			(thermal_bridge_width 0.5)
			(island_removal_mode 0)
		)
		(polygon
			(pts
				(arc
					(start 172.30598 -218.585288)
					(mid 171.63796 -218.585288)
					(end 172.30598 -218.585288)
				)
			)
		)
	)
	(zone
		(layers "B.Cu" "In15.Cu")
		(hatch none 0.5)
		(connect_pads
			(clearance 0)
		)
		(min_thickness 0.25)
		(keepout
			(tracks not_allowed)
			(vias allowed)
			(pads allowed)
			(copperpour not_allowed)
			(footprints allowed)
		)
		(placement
			(enabled no)
			(sheetname "")
		)
		(fill yes
			(thermal_gap 0.5)
			(thermal_bridge_width 0.5)
			(island_removal_mode 0)
		)
		(polygon
			(pts
				(arc
					(start 128.450594 -393.292838)
					(mid 127.782574 -393.292838)
					(end 128.450594 -393.292838)
				)
			)
		)
	)
	(zone
		(layers "B.Cu" "In15.Cu")
		(hatch none 0.5)
		(connect_pads
			(clearance 0)
		)
		(min_thickness 0.25)
		(keepout
			(tracks not_allowed)
			(vias allowed)
			(pads allowed)
			(copperpour not_allowed)
			(footprints allowed)
		)
		(placement
			(enabled no)
			(sheetname "")
		)
		(fill yes
			(thermal_gap 0.5)
			(thermal_bridge_width 0.5)
			(island_removal_mode 0)
		)
		(polygon
			(pts
				(arc
					(start 296.058082 -207.535018)
					(mid 295.390062 -207.535018)
					(end 296.058082 -207.535018)
				)
			)
		)
	)
	(zone
		(layers "B.Cu" "In15.Cu")
		(hatch none 0.5)
		(connect_pads
			(clearance 0)
		)
		(min_thickness 0.25)
		(keepout
			(tracks not_allowed)
			(vias allowed)
			(pads allowed)
			(copperpour not_allowed)
			(footprints allowed)
		)
		(placement
			(enabled no)
			(sheetname "")
		)
		(fill yes
			(thermal_gap 0.5)
			(thermal_bridge_width 0.5)
			(island_removal_mode 0)
		)
		(polygon
			(pts
				(arc
					(start 114.739674 -274.08632)
					(mid 114.109754 -274.08632)
					(end 114.739674 -274.08632)
				)
			)
		)
	)
	(zone
		(layers "B.Cu" "In15.Cu")
		(hatch none 0.5)
		(connect_pads
			(clearance 0)
		)
		(min_thickness 0.25)
		(keepout
			(tracks not_allowed)
			(vias allowed)
			(pads allowed)
			(copperpour not_allowed)
			(footprints allowed)
		)
		(placement
			(enabled no)
			(sheetname "")
		)
		(fill yes
			(thermal_gap 0.5)
			(thermal_bridge_width 0.5)
			(island_removal_mode 0)
		)
		(polygon
			(pts
				(arc
					(start 89.83599 -278.13635)
					(mid 89.20607 -278.13635)
					(end 89.83599 -278.13635)
				)
			)
		)
	)
	(zone
		(layers "B.Cu" "In15.Cu")
		(hatch none 0.5)
		(connect_pads
			(clearance 0)
		)
		(min_thickness 0.25)
		(keepout
			(tracks not_allowed)
			(vias allowed)
			(pads allowed)
			(copperpour not_allowed)
			(footprints allowed)
		)
		(placement
			(enabled no)
			(sheetname "")
		)
		(fill yes
			(thermal_gap 0.5)
			(thermal_bridge_width 0.5)
			(island_removal_mode 0)
		)
		(polygon
			(pts
				(arc
					(start 172.30598 -233.885232)
					(mid 171.63796 -233.885232)
					(end 172.30598 -233.885232)
				)
			)
		)
	)
	(zone
		(layers "B.Cu" "In15.Cu")
		(hatch none 0.5)
		(connect_pads
			(clearance 0)
		)
		(min_thickness 0.25)
		(keepout
			(tracks not_allowed)
			(vias allowed)
			(pads allowed)
			(copperpour not_allowed)
			(footprints allowed)
		)
		(placement
			(enabled no)
			(sheetname "")
		)
		(fill yes
			(thermal_gap 0.5)
			(thermal_bridge_width 0.5)
			(island_removal_mode 0)
		)
		(polygon
			(pts
				(arc
					(start 337.306158 -264.365994)
					(mid 336.676238 -264.365994)
					(end 337.306158 -264.365994)
				)
			)
		)
	)
	(zone
		(layers "B.Cu" "In15.Cu")
		(hatch none 0.5)
		(connect_pads
			(clearance 0)
		)
		(min_thickness 0.25)
		(keepout
			(tracks not_allowed)
			(vias allowed)
			(pads allowed)
			(copperpour not_allowed)
			(footprints allowed)
		)
		(placement
			(enabled no)
			(sheetname "")
		)
		(fill yes
			(thermal_gap 0.5)
			(thermal_bridge_width 0.5)
			(island_removal_mode 0)
		)
		(polygon
			(pts
				(arc
					(start 88.126062 -237.194344)
					(mid 87.496142 -237.194344)
					(end 88.126062 -237.194344)
				)
			)
		)
	)
	(zone
		(layers "B.Cu" "In15.Cu")
		(hatch none 0.5)
		(connect_pads
			(clearance 0)
		)
		(min_thickness 0.25)
		(keepout
			(tracks not_allowed)
			(vias allowed)
			(pads allowed)
			(copperpour not_allowed)
			(footprints allowed)
		)
		(placement
			(enabled no)
			(sheetname "")
		)
		(fill yes
			(thermal_gap 0.5)
			(thermal_bridge_width 0.5)
			(island_removal_mode 0)
		)
		(polygon
			(pts
				(arc
					(start 88.426036 -278.946356)
					(mid 87.796116 -278.946356)
					(end 88.426036 -278.946356)
				)
			)
		)
	)
	(zone
		(layers "B.Cu" "In15.Cu")
		(hatch none 0.5)
		(connect_pads
			(clearance 0)
		)
		(min_thickness 0.25)
		(keepout
			(tracks not_allowed)
			(vias allowed)
			(pads allowed)
			(copperpour not_allowed)
			(footprints allowed)
		)
		(placement
			(enabled no)
			(sheetname "")
		)
		(fill yes
			(thermal_gap 0.5)
			(thermal_bridge_width 0.5)
			(island_removal_mode 0)
		)
		(polygon
			(pts
				(arc
					(start 384.299714 -275.706078)
					(mid 383.669794 -275.706078)
					(end 384.299714 -275.706078)
				)
			)
		)
	)
	(zone
		(layers "B.Cu" "In15.Cu")
		(hatch none 0.5)
		(connect_pads
			(clearance 0)
		)
		(min_thickness 0.25)
		(keepout
			(tracks not_allowed)
			(vias allowed)
			(pads allowed)
			(copperpour not_allowed)
			(footprints allowed)
		)
		(placement
			(enabled no)
			(sheetname "")
		)
		(fill yes
			(thermal_gap 0.5)
			(thermal_bridge_width 0.5)
			(island_removal_mode 0)
		)
		(polygon
			(pts
				(arc
					(start 129.65049 -393.292838)
					(mid 128.98247 -393.292838)
					(end 129.65049 -393.292838)
				)
			)
		)
	)
	(zone
		(layers "B.Cu" "In15.Cu")
		(hatch none 0.5)
		(connect_pads
			(clearance 0)
		)
		(min_thickness 0.25)
		(keepout
			(tracks not_allowed)
			(vias allowed)
			(pads allowed)
			(copperpour not_allowed)
			(footprints allowed)
		)
		(placement
			(enabled no)
			(sheetname "")
		)
		(fill yes
			(thermal_gap 0.5)
			(thermal_bridge_width 0.5)
			(island_removal_mode 0)
		)
		(polygon
			(pts
				(arc
					(start 300.15815 -294.235124)
					(mid 299.49013 -294.235124)
					(end 300.15815 -294.235124)
				)
			)
		)
	)
	(zone
		(layers "B.Cu" "In15.Cu")
		(hatch none 0.5)
		(connect_pads
			(clearance 0)
		)
		(min_thickness 0.25)
		(keepout
			(tracks not_allowed)
			(vias allowed)
			(pads allowed)
			(copperpour not_allowed)
			(footprints allowed)
		)
		(placement
			(enabled no)
			(sheetname "")
		)
		(fill yes
			(thermal_gap 0.5)
			(thermal_bridge_width 0.5)
			(island_removal_mode 0)
		)
		(polygon
			(pts
				(arc
					(start 134.949692 -286.23641)
					(mid 134.319772 -286.23641)
					(end 134.949692 -286.23641)
				)
			)
		)
	)
	(zone
		(layers "B.Cu" "In15.Cu")
		(hatch none 0.5)
		(connect_pads
			(clearance 0)
		)
		(min_thickness 0.25)
		(keepout
			(tracks not_allowed)
			(vias allowed)
			(pads allowed)
			(copperpour not_allowed)
			(footprints allowed)
		)
		(placement
			(enabled no)
			(sheetname "")
		)
		(fill yes
			(thermal_gap 0.5)
			(thermal_bridge_width 0.5)
			(island_removal_mode 0)
		)
		(polygon
			(pts
				(arc
					(start 135.419592 -283.806392)
					(mid 134.789672 -283.806392)
					(end 135.419592 -283.806392)
				)
			)
		)
	)
	(zone
		(layers "B.Cu" "In15.Cu")
		(hatch none 0.5)
		(connect_pads
			(clearance 0)
		)
		(min_thickness 0.25)
		(keepout
			(tracks not_allowed)
			(vias allowed)
			(pads allowed)
			(copperpour not_allowed)
			(footprints allowed)
		)
		(placement
			(enabled no)
			(sheetname "")
		)
		(fill yes
			(thermal_gap 0.5)
			(thermal_bridge_width 0.5)
			(island_removal_mode 0)
		)
		(polygon
			(pts
				(arc
					(start 120.54967 -239.624362)
					(mid 119.91975 -239.624362)
					(end 120.54967 -239.624362)
				)
			)
		)
	)
	(zone
		(layers "B.Cu" "In15.Cu")
		(hatch none 0.5)
		(connect_pads
			(clearance 0)
		)
		(min_thickness 0.25)
		(keepout
			(tracks not_allowed)
			(vias allowed)
			(pads allowed)
			(copperpour not_allowed)
			(footprints allowed)
		)
		(placement
			(enabled no)
			(sheetname "")
		)
		(fill yes
			(thermal_gap 0.5)
			(thermal_bridge_width 0.5)
			(island_removal_mode 0)
		)
		(polygon
			(pts
				(arc
					(start 351.876106 -273.27606)
					(mid 351.246186 -273.27606)
					(end 351.876106 -273.27606)
				)
			)
		)
	)
	(zone
		(layers "B.Cu" "In15.Cu")
		(hatch none 0.5)
		(connect_pads
			(clearance 0)
		)
		(min_thickness 0.25)
		(keepout
			(tracks not_allowed)
			(vias allowed)
			(pads allowed)
			(copperpour not_allowed)
			(footprints allowed)
		)
		(placement
			(enabled no)
			(sheetname "")
		)
		(fill yes
			(thermal_gap 0.5)
			(thermal_bridge_width 0.5)
			(island_removal_mode 0)
		)
		(polygon
			(pts
				(arc
					(start 383.35966 -282.186126)
					(mid 382.72974 -282.186126)
					(end 383.35966 -282.186126)
				)
			)
		)
	)
	(zone
		(layers "B.Cu" "In15.Cu")
		(hatch none 0.5)
		(connect_pads
			(clearance 0)
		)
		(min_thickness 0.25)
		(keepout
			(tracks not_allowed)
			(vias allowed)
			(pads allowed)
			(copperpour not_allowed)
			(footprints allowed)
		)
		(placement
			(enabled no)
			(sheetname "")
		)
		(fill yes
			(thermal_gap 0.5)
			(thermal_bridge_width 0.5)
			(island_removal_mode 0)
		)
		(polygon
			(pts
				(arc
					(start 305.706018 -394.385292)
					(mid 305.076098 -394.385292)
					(end 305.706018 -394.385292)
				)
			)
		)
	)
	(zone
		(layers "B.Cu" "In15.Cu")
		(hatch none 0.5)
		(connect_pads
			(clearance 0)
		)
		(min_thickness 0.25)
		(keepout
			(tracks not_allowed)
			(vias allowed)
			(pads allowed)
			(copperpour not_allowed)
			(footprints allowed)
		)
		(placement
			(enabled no)
			(sheetname "")
		)
		(fill yes
			(thermal_gap 0.5)
			(thermal_bridge_width 0.5)
			(island_removal_mode 0)
		)
		(polygon
			(pts
				(arc
					(start 348.75597 -242.864132)
					(mid 348.12605 -242.864132)
					(end 348.75597 -242.864132)
				)
			)
		)
	)
	(zone
		(layers "B.Cu" "In15.Cu")
		(hatch none 0.5)
		(connect_pads
			(clearance 0)
		)
		(min_thickness 0.25)
		(keepout
			(tracks not_allowed)
			(vias allowed)
			(pads allowed)
			(copperpour not_allowed)
			(footprints allowed)
		)
		(placement
			(enabled no)
			(sheetname "")
		)
		(fill yes
			(thermal_gap 0.5)
			(thermal_bridge_width 0.5)
			(island_removal_mode 0)
		)
		(polygon
			(pts
				(arc
					(start 88.126062 -225.854514)
					(mid 87.496142 -225.854514)
					(end 88.126062 -225.854514)
				)
			)
		)
	)
	(zone
		(layers "B.Cu" "In15.Cu")
		(hatch none 0.5)
		(connect_pads
			(clearance 0)
		)
		(min_thickness 0.25)
		(keepout
			(tracks not_allowed)
			(vias allowed)
			(pads allowed)
			(copperpour not_allowed)
			(footprints allowed)
		)
		(placement
			(enabled no)
			(sheetname "")
		)
		(fill yes
			(thermal_gap 0.5)
			(thermal_bridge_width 0.5)
			(island_removal_mode 0)
		)
		(polygon
			(pts
				(arc
					(start 300.15815 -254.284988)
					(mid 299.49013 -254.284988)
					(end 300.15815 -254.284988)
				)
			)
		)
	)
	(zone
		(layers "B.Cu" "In15.Cu")
		(hatch none 0.5)
		(connect_pads
			(clearance 0)
		)
		(min_thickness 0.25)
		(keepout
			(tracks not_allowed)
			(vias allowed)
			(pads allowed)
			(copperpour not_allowed)
			(footprints allowed)
		)
		(placement
			(enabled no)
			(sheetname "")
		)
		(fill yes
			(thermal_gap 0.5)
			(thermal_bridge_width 0.5)
			(island_removal_mode 0)
		)
		(polygon
			(pts
				(arc
					(start 125.54966 -273.276314)
					(mid 124.91974 -273.276314)
					(end 125.54966 -273.276314)
				)
			)
		)
	)
	(zone
		(layers "B.Cu" "In15.Cu")
		(hatch none 0.5)
		(connect_pads
			(clearance 0)
		)
		(min_thickness 0.25)
		(keepout
			(tracks not_allowed)
			(vias allowed)
			(pads allowed)
			(copperpour not_allowed)
			(footprints allowed)
		)
		(placement
			(enabled no)
			(sheetname "")
		)
		(fill yes
			(thermal_gap 0.5)
			(thermal_bridge_width 0.5)
			(island_removal_mode 0)
		)
		(polygon
			(pts
				(arc
					(start 357.686102 -238.814102)
					(mid 357.056182 -238.814102)
					(end 357.686102 -238.814102)
				)
			)
		)
	)
	(zone
		(layers "B.Cu" "In15.Cu")
		(hatch none 0.5)
		(connect_pads
			(clearance 0)
		)
		(min_thickness 0.25)
		(keepout
			(tracks not_allowed)
			(vias allowed)
			(pads allowed)
			(copperpour not_allowed)
			(footprints allowed)
		)
		(placement
			(enabled no)
			(sheetname "")
		)
		(fill yes
			(thermal_gap 0.5)
			(thermal_bridge_width 0.5)
			(island_removal_mode 0)
		)
		(polygon
			(pts
				(arc
					(start 134.949692 -291.096192)
					(mid 134.319772 -291.096192)
					(end 134.949692 -291.096192)
				)
			)
		)
	)
	(zone
		(layers "B.Cu" "In15.Cu")
		(hatch none 0.5)
		(connect_pads
			(clearance 0)
		)
		(min_thickness 0.25)
		(keepout
			(tracks not_allowed)
			(vias allowed)
			(pads allowed)
			(copperpour not_allowed)
			(footprints allowed)
		)
		(placement
			(enabled no)
			(sheetname "")
		)
		(fill yes
			(thermal_gap 0.5)
			(thermal_bridge_width 0.5)
			(island_removal_mode 0)
		)
		(polygon
			(pts
				(arc
					(start 136.529826 -241.244374)
					(mid 135.899906 -241.244374)
					(end 136.529826 -241.244374)
				)
			)
		)
	)
	(zone
		(layers "B.Cu" "In15.Cu")
		(hatch none 0.5)
		(connect_pads
			(clearance 0)
		)
		(min_thickness 0.25)
		(keepout
			(tracks not_allowed)
			(vias allowed)
			(pads allowed)
			(copperpour not_allowed)
			(footprints allowed)
		)
		(placement
			(enabled no)
			(sheetname "")
		)
		(fill yes
			(thermal_gap 0.5)
			(thermal_bridge_width 0.5)
			(island_removal_mode 0)
		)
		(polygon
			(pts
				(arc
					(start 351.078038 -400.811238)
					(mid 350.410018 -400.811238)
					(end 351.078038 -400.811238)
				)
			)
		)
	)
	(zone
		(layers "B.Cu" "In15.Cu")
		(hatch none 0.5)
		(connect_pads
			(clearance 0)
		)
		(min_thickness 0.25)
		(keepout
			(tracks not_allowed)
			(vias allowed)
			(pads allowed)
			(copperpour not_allowed)
			(footprints allowed)
		)
		(placement
			(enabled no)
			(sheetname "")
		)
		(fill yes
			(thermal_gap 0.5)
			(thermal_bridge_width 0.5)
			(island_removal_mode 0)
		)
		(polygon
			(pts
				(arc
					(start 88.126062 -240.434368)
					(mid 87.496142 -240.434368)
					(end 88.126062 -240.434368)
				)
			)
		)
	)
	(zone
		(layers "B.Cu" "In15.Cu")
		(hatch none 0.5)
		(connect_pads
			(clearance 0)
		)
		(min_thickness 0.25)
		(keepout
			(tracks not_allowed)
			(vias allowed)
			(pads allowed)
			(copperpour not_allowed)
			(footprints allowed)
		)
		(placement
			(enabled no)
			(sheetname "")
		)
		(fill yes
			(thermal_gap 0.5)
			(thermal_bridge_width 0.5)
			(island_removal_mode 0)
		)
		(polygon
			(pts
				(arc
					(start 424.346116 -284.88513)
					(mid 423.678096 -284.88513)
					(end 424.346116 -284.88513)
				)
			)
		)
	)
	(zone
		(layers "B.Cu" "In15.Cu")
		(hatch none 0.5)
		(connect_pads
			(clearance 0)
		)
		(min_thickness 0.25)
		(keepout
			(tracks not_allowed)
			(vias allowed)
			(pads allowed)
			(copperpour not_allowed)
			(footprints allowed)
		)
		(placement
			(enabled no)
			(sheetname "")
		)
		(fill yes
			(thermal_gap 0.5)
			(thermal_bridge_width 0.5)
			(island_removal_mode 0)
		)
		(polygon
			(pts
				(arc
					(start 337.306158 -291.905944)
					(mid 336.676238 -291.905944)
					(end 337.306158 -291.905944)
				)
			)
		)
	)
	(zone
		(layers "B.Cu" "In15.Cu")
		(hatch none 0.5)
		(connect_pads
			(clearance 0)
		)
		(min_thickness 0.25)
		(keepout
			(tracks not_allowed)
			(vias allowed)
			(pads allowed)
			(copperpour not_allowed)
			(footprints allowed)
		)
		(placement
			(enabled no)
			(sheetname "")
		)
		(fill yes
			(thermal_gap 0.5)
			(thermal_bridge_width 0.5)
			(island_removal_mode 0)
		)
		(polygon
			(pts
				(arc
					(start 306.905914 -394.385292)
					(mid 306.275994 -394.385292)
					(end 306.905914 -394.385292)
				)
			)
		)
	)
	(zone
		(layers "B.Cu" "In15.Cu")
		(hatch none 0.5)
		(connect_pads
			(clearance 0)
		)
		(min_thickness 0.25)
		(keepout
			(tracks not_allowed)
			(vias allowed)
			(pads allowed)
			(copperpour not_allowed)
			(footprints allowed)
		)
		(placement
			(enabled no)
			(sheetname "")
		)
		(fill yes
			(thermal_gap 0.5)
			(thermal_bridge_width 0.5)
			(island_removal_mode 0)
		)
		(polygon
			(pts
				(arc
					(start 134.949692 -278.13635)
					(mid 134.319772 -278.13635)
					(end 134.949692 -278.13635)
				)
			)
		)
	)
	(zone
		(layers "B.Cu" "In15.Cu")
		(hatch none 0.5)
		(connect_pads
			(clearance 0)
		)
		(min_thickness 0.25)
		(keepout
			(tracks not_allowed)
			(vias allowed)
			(pads allowed)
			(copperpour not_allowed)
			(footprints allowed)
		)
		(placement
			(enabled no)
			(sheetname "")
		)
		(fill yes
			(thermal_gap 0.5)
			(thermal_bridge_width 0.5)
			(island_removal_mode 0)
		)
		(polygon
			(pts
				(arc
					(start 374.429782 -270.036036)
					(mid 373.799862 -270.036036)
					(end 374.429782 -270.036036)
				)
			)
		)
	)
	(zone
		(layers "B.Cu" "In15.Cu")
		(hatch none 0.5)
		(connect_pads
			(clearance 0)
		)
		(min_thickness 0.25)
		(keepout
			(tracks not_allowed)
			(vias allowed)
			(pads allowed)
			(copperpour not_allowed)
			(footprints allowed)
		)
		(placement
			(enabled no)
			(sheetname "")
		)
		(fill yes
			(thermal_gap 0.5)
			(thermal_bridge_width 0.5)
			(island_removal_mode 0)
		)
		(polygon
			(pts
				(arc
					(start 420.246048 -209.23504)
					(mid 419.578028 -209.23504)
					(end 420.246048 -209.23504)
				)
			)
		)
	)
	(zone
		(layers "B.Cu" "In15.Cu")
		(hatch none 0.5)
		(connect_pads
			(clearance 0)
		)
		(min_thickness 0.25)
		(keepout
			(tracks not_allowed)
			(vias allowed)
			(pads allowed)
			(copperpour not_allowed)
			(footprints allowed)
		)
		(placement
			(enabled no)
			(sheetname "")
		)
		(fill yes
			(thermal_gap 0.5)
			(thermal_bridge_width 0.5)
			(island_removal_mode 0)
		)
		(polygon
			(pts
				(arc
					(start 135.119618 -242.05438)
					(mid 134.489698 -242.05438)
					(end 135.119618 -242.05438)
				)
			)
		)
	)
	(zone
		(layers "B.Cu" "In15.Cu")
		(hatch none 0.5)
		(connect_pads
			(clearance 0)
		)
		(min_thickness 0.25)
		(keepout
			(tracks not_allowed)
			(vias allowed)
			(pads allowed)
			(copperpour not_allowed)
			(footprints allowed)
		)
		(placement
			(enabled no)
			(sheetname "")
		)
		(fill yes
			(thermal_gap 0.5)
			(thermal_bridge_width 0.5)
			(island_removal_mode 0)
		)
		(polygon
			(pts
				(arc
					(start 176.406048 -238.135414)
					(mid 175.738028 -238.135414)
					(end 176.406048 -238.135414)
				)
			)
		)
	)
	(zone
		(layers "B.Cu" "In15.Cu")
		(hatch none 0.5)
		(connect_pads
			(clearance 0)
		)
		(min_thickness 0.25)
		(keepout
			(tracks not_allowed)
			(vias allowed)
			(pads allowed)
			(copperpour not_allowed)
			(footprints allowed)
		)
		(placement
			(enabled no)
			(sheetname "")
		)
		(fill yes
			(thermal_gap 0.5)
			(thermal_bridge_width 0.5)
			(island_removal_mode 0)
		)
		(polygon
			(pts
				(arc
					(start 48.118014 -263.635236)
					(mid 47.449994 -263.635236)
					(end 48.118014 -263.635236)
				)
			)
		)
	)
	(zone
		(layers "B.Cu" "In15.Cu")
		(hatch none 0.5)
		(connect_pads
			(clearance 0)
		)
		(min_thickness 0.25)
		(keepout
			(tracks not_allowed)
			(vias allowed)
			(pads allowed)
			(copperpour not_allowed)
			(footprints allowed)
		)
		(placement
			(enabled no)
			(sheetname "")
		)
		(fill yes
			(thermal_gap 0.5)
			(thermal_bridge_width 0.5)
			(island_removal_mode 0)
		)
		(polygon
			(pts
				(arc
					(start 347.17609 -271.656048)
					(mid 346.54617 -271.656048)
					(end 347.17609 -271.656048)
				)
			)
		)
	)
	(zone
		(layers "B.Cu" "In15.Cu")
		(hatch none 0.5)
		(connect_pads
			(clearance 0)
		)
		(min_thickness 0.25)
		(keepout
			(tracks not_allowed)
			(vias allowed)
			(pads allowed)
			(copperpour not_allowed)
			(footprints allowed)
		)
		(placement
			(enabled no)
			(sheetname "")
		)
		(fill yes
			(thermal_gap 0.5)
			(thermal_bridge_width 0.5)
			(island_removal_mode 0)
		)
		(polygon
			(pts
				(arc
					(start 337.006184 -235.574078)
					(mid 336.376264 -235.574078)
					(end 337.006184 -235.574078)
				)
			)
		)
	)
	(zone
		(layers "B.Cu" "In15.Cu")
		(hatch none 0.5)
		(connect_pads
			(clearance 0)
		)
		(min_thickness 0.25)
		(keepout
			(tracks not_allowed)
			(vias allowed)
			(pads allowed)
			(copperpour not_allowed)
			(footprints allowed)
		)
		(placement
			(enabled no)
			(sheetname "")
		)
		(fill yes
			(thermal_gap 0.5)
			(thermal_bridge_width 0.5)
			(island_removal_mode 0)
		)
		(polygon
			(pts
				(arc
					(start 336.06613 -248.534174)
					(mid 335.43621 -248.534174)
					(end 336.06613 -248.534174)
				)
			)
		)
	)
	(zone
		(layers "B.Cu" "In15.Cu")
		(hatch none 0.5)
		(connect_pads
			(clearance 0)
		)
		(min_thickness 0.25)
		(keepout
			(tracks not_allowed)
			(vias allowed)
			(pads allowed)
			(copperpour not_allowed)
			(footprints allowed)
		)
		(placement
			(enabled no)
			(sheetname "")
		)
		(fill yes
			(thermal_gap 0.5)
			(thermal_bridge_width 0.5)
			(island_removal_mode 0)
		)
		(polygon
			(pts
				(arc
					(start 136.359646 -280.566368)
					(mid 135.729726 -280.566368)
					(end 136.359646 -280.566368)
				)
			)
		)
	)
	(zone
		(layers "B.Cu" "In15.Cu")
		(hatch none 0.5)
		(connect_pads
			(clearance 0)
		)
		(min_thickness 0.25)
		(keepout
			(tracks not_allowed)
			(vias allowed)
			(pads allowed)
			(copperpour not_allowed)
			(footprints allowed)
		)
		(placement
			(enabled no)
			(sheetname "")
		)
		(fill yes
			(thermal_gap 0.5)
			(thermal_bridge_width 0.5)
			(island_removal_mode 0)
		)
		(polygon
			(pts
				(arc
					(start 134.949692 -266.796266)
					(mid 134.319772 -266.796266)
					(end 134.949692 -266.796266)
				)
			)
		)
	)
	(zone
		(layers "B.Cu" "In15.Cu")
		(hatch none 0.5)
		(connect_pads
			(clearance 0)
		)
		(min_thickness 0.25)
		(keepout
			(tracks not_allowed)
			(vias allowed)
			(pads allowed)
			(copperpour not_allowed)
			(footprints allowed)
		)
		(placement
			(enabled no)
			(sheetname "")
		)
		(fill yes
			(thermal_gap 0.5)
			(thermal_bridge_width 0.5)
			(island_removal_mode 0)
		)
		(polygon
			(pts
				(arc
					(start 172.30598 -314.635388)
					(mid 171.63796 -314.635388)
					(end 172.30598 -314.635388)
				)
			)
		)
	)
	(zone
		(layers "B.Cu" "In15.Cu")
		(hatch none 0.5)
		(connect_pads
			(clearance 0)
		)
		(min_thickness 0.25)
		(keepout
			(tracks not_allowed)
			(vias allowed)
			(pads allowed)
			(copperpour not_allowed)
			(footprints allowed)
		)
		(placement
			(enabled no)
			(sheetname "")
		)
		(fill yes
			(thermal_gap 0.5)
			(thermal_bridge_width 0.5)
			(island_removal_mode 0)
		)
		(polygon
			(pts
				(arc
					(start 424.346116 -279.785064)
					(mid 423.678096 -279.785064)
					(end 424.346116 -279.785064)
				)
			)
		)
	)
	(zone
		(layers "B.Cu" "In15.Cu")
		(hatch none 0.5)
		(connect_pads
			(clearance 0)
		)
		(min_thickness 0.25)
		(keepout
			(tracks not_allowed)
			(vias allowed)
			(pads allowed)
			(copperpour not_allowed)
			(footprints allowed)
		)
		(placement
			(enabled no)
			(sheetname "")
		)
		(fill yes
			(thermal_gap 0.5)
			(thermal_bridge_width 0.5)
			(island_removal_mode 0)
		)
		(polygon
			(pts
				(arc
					(start 98.678238 -393.292838)
					(mid 98.010218 -393.292838)
					(end 98.678238 -393.292838)
				)
			)
		)
	)
	(zone
		(layers "B.Cu" "In15.Cu")
		(hatch none 0.5)
		(connect_pads
			(clearance 0)
		)
		(min_thickness 0.25)
		(keepout
			(tracks not_allowed)
			(vias allowed)
			(pads allowed)
			(copperpour not_allowed)
			(footprints allowed)
		)
		(placement
			(enabled no)
			(sheetname "")
		)
		(fill yes
			(thermal_gap 0.5)
			(thermal_bridge_width 0.5)
			(island_removal_mode 0)
		)
		(polygon
			(pts
				(arc
					(start 420.246048 -295.935146)
					(mid 419.578028 -295.935146)
					(end 420.246048 -295.935146)
				)
			)
		)
	)
	(zone
		(layers "B.Cu" "In15.Cu")
		(hatch none 0.5)
		(connect_pads
			(clearance 0)
		)
		(min_thickness 0.25)
		(keepout
			(tracks not_allowed)
			(vias allowed)
			(pads allowed)
			(copperpour not_allowed)
			(footprints allowed)
		)
		(placement
			(enabled no)
			(sheetname "")
		)
		(fill yes
			(thermal_gap 0.5)
			(thermal_bridge_width 0.5)
			(island_removal_mode 0)
		)
		(polygon
			(pts
				(arc
					(start 126.050548 -393.292838)
					(mid 125.382528 -393.292838)
					(end 126.050548 -393.292838)
				)
			)
		)
	)
	(zone
		(layers "B.Cu" "In15.Cu")
		(hatch none 0.5)
		(connect_pads
			(clearance 0)
		)
		(min_thickness 0.25)
		(keepout
			(tracks not_allowed)
			(vias allowed)
			(pads allowed)
			(copperpour not_allowed)
			(footprints allowed)
		)
		(placement
			(enabled no)
			(sheetname "")
		)
		(fill yes
			(thermal_gap 0.5)
			(thermal_bridge_width 0.5)
			(island_removal_mode 0)
		)
		(polygon
			(pts
				(arc
					(start 176.406048 -298.485306)
					(mid 175.738028 -298.485306)
					(end 176.406048 -298.485306)
				)
			)
		)
	)
	(zone
		(layers "B.Cu" "In15.Cu")
		(hatch none 0.5)
		(connect_pads
			(clearance 0)
		)
		(min_thickness 0.25)
		(keepout
			(tracks not_allowed)
			(vias allowed)
			(pads allowed)
			(copperpour not_allowed)
			(footprints allowed)
		)
		(placement
			(enabled no)
			(sheetname "")
		)
		(fill yes
			(thermal_gap 0.5)
			(thermal_bridge_width 0.5)
			(island_removal_mode 0)
		)
		(polygon
			(pts
				(arc
					(start 136.359646 -278.946356)
					(mid 135.729726 -278.946356)
					(end 136.359646 -278.946356)
				)
			)
		)
	)
	(zone
		(layers "B.Cu" "In15.Cu")
		(hatch none 0.5)
		(connect_pads
			(clearance 0)
		)
		(min_thickness 0.25)
		(keepout
			(tracks not_allowed)
			(vias allowed)
			(pads allowed)
			(copperpour not_allowed)
			(footprints allowed)
		)
		(placement
			(enabled no)
			(sheetname "")
		)
		(fill yes
			(thermal_gap 0.5)
			(thermal_bridge_width 0.5)
			(island_removal_mode 0)
		)
		(polygon
			(pts
				(arc
					(start 337.006184 -243.674138)
					(mid 336.376264 -243.674138)
					(end 337.006184 -243.674138)
				)
			)
		)
	)
	(zone
		(layers "B.Cu" "In15.Cu")
		(hatch none 0.5)
		(connect_pads
			(clearance 0)
		)
		(min_thickness 0.25)
		(keepout
			(tracks not_allowed)
			(vias allowed)
			(pads allowed)
			(copperpour not_allowed)
			(footprints allowed)
		)
		(placement
			(enabled no)
			(sheetname "")
		)
		(fill yes
			(thermal_gap 0.5)
			(thermal_bridge_width 0.5)
			(island_removal_mode 0)
		)
		(polygon
			(pts
				(arc
					(start 300.15815 -269.585186)
					(mid 299.49013 -269.585186)
					(end 300.15815 -269.585186)
				)
			)
		)
	)
	(zone
		(layers "B.Cu" "In15.Cu")
		(hatch none 0.5)
		(connect_pads
			(clearance 0)
		)
		(min_thickness 0.25)
		(keepout
			(tracks not_allowed)
			(vias allowed)
			(pads allowed)
			(copperpour not_allowed)
			(footprints allowed)
		)
		(placement
			(enabled no)
			(sheetname "")
		)
		(fill yes
			(thermal_gap 0.5)
			(thermal_bridge_width 0.5)
			(island_removal_mode 0)
		)
		(polygon
			(pts
				(arc
					(start 420.246048 -239.835182)
					(mid 419.578028 -239.835182)
					(end 420.246048 -239.835182)
				)
			)
		)
	)
	(zone
		(layers "B.Cu" "In15.Cu")
		(hatch none 0.5)
		(connect_pads
			(clearance 0)
		)
		(min_thickness 0.25)
		(keepout
			(tracks not_allowed)
			(vias allowed)
			(pads allowed)
			(copperpour not_allowed)
			(footprints allowed)
		)
		(placement
			(enabled no)
			(sheetname "")
		)
		(fill yes
			(thermal_gap 0.5)
			(thermal_bridge_width 0.5)
			(island_removal_mode 0)
		)
		(polygon
			(pts
				(arc
					(start 336.366104 -267.606018)
					(mid 335.736184 -267.606018)
					(end 336.366104 -267.606018)
				)
			)
		)
	)
	(zone
		(layers "B.Cu" "In15.Cu")
		(hatch none 0.5)
		(connect_pads
			(clearance 0)
		)
		(min_thickness 0.25)
		(keepout
			(tracks not_allowed)
			(vias allowed)
			(pads allowed)
			(copperpour not_allowed)
			(footprints allowed)
		)
		(placement
			(enabled no)
			(sheetname "")
		)
		(fill yes
			(thermal_gap 0.5)
			(thermal_bridge_width 0.5)
			(island_removal_mode 0)
		)
		(polygon
			(pts
				(arc
					(start 89.36609 -275.706332)
					(mid 88.73617 -275.706332)
					(end 89.36609 -275.706332)
				)
			)
		)
	)
	(zone
		(layers "B.Cu" "In15.Cu")
		(hatch none 0.5)
		(connect_pads
			(clearance 0)
		)
		(min_thickness 0.25)
		(keepout
			(tracks not_allowed)
			(vias allowed)
			(pads allowed)
			(copperpour not_allowed)
			(footprints allowed)
		)
		(placement
			(enabled no)
			(sheetname "")
		)
		(fill yes
			(thermal_gap 0.5)
			(thermal_bridge_width 0.5)
			(island_removal_mode 0)
		)
		(polygon
			(pts
				(arc
					(start 365.02975 -270.036036)
					(mid 364.39983 -270.036036)
					(end 365.02975 -270.036036)
				)
			)
		)
	)
	(zone
		(layers "B.Cu" "In15.Cu")
		(hatch none 0.5)
		(connect_pads
			(clearance 0)
		)
		(min_thickness 0.25)
		(keepout
			(tracks not_allowed)
			(vias allowed)
			(pads allowed)
			(copperpour not_allowed)
			(footprints allowed)
		)
		(placement
			(enabled no)
			(sheetname "")
		)
		(fill yes
			(thermal_gap 0.5)
			(thermal_bridge_width 0.5)
			(island_removal_mode 0)
		)
		(polygon
			(pts
				(arc
					(start 382.050544 -400.811238)
					(mid 381.382524 -400.811238)
					(end 382.050544 -400.811238)
				)
			)
		)
	)
	(zone
		(layers "B.Cu" "In15.Cu")
		(hatch none 0.5)
		(connect_pads
			(clearance 0)
		)
		(min_thickness 0.25)
		(keepout
			(tracks not_allowed)
			(vias allowed)
			(pads allowed)
			(copperpour not_allowed)
			(footprints allowed)
		)
		(placement
			(enabled no)
			(sheetname "")
		)
		(fill yes
			(thermal_gap 0.5)
			(thermal_bridge_width 0.5)
			(island_removal_mode 0)
		)
		(polygon
			(pts
				(arc
					(start 383.059686 -253.39421)
					(mid 382.429766 -253.39421)
					(end 383.059686 -253.39421)
				)
			)
		)
	)
	(zone
		(layers "B.Cu" "In15.Cu")
		(hatch none 0.5)
		(connect_pads
			(clearance 0)
		)
		(min_thickness 0.25)
		(keepout
			(tracks not_allowed)
			(vias allowed)
			(pads allowed)
			(copperpour not_allowed)
			(footprints allowed)
		)
		(placement
			(enabled no)
			(sheetname "")
		)
		(fill yes
			(thermal_gap 0.5)
			(thermal_bridge_width 0.5)
			(island_removal_mode 0)
		)
		(polygon
			(pts
				(arc
					(start 176.406048 -269.58544)
					(mid 175.738028 -269.58544)
					(end 176.406048 -269.58544)
				)
			)
		)
	)
	(zone
		(layers "B.Cu" "In15.Cu")
		(hatch none 0.5)
		(connect_pads
			(clearance 0)
		)
		(min_thickness 0.25)
		(keepout
			(tracks not_allowed)
			(vias allowed)
			(pads allowed)
			(copperpour not_allowed)
			(footprints allowed)
		)
		(placement
			(enabled no)
			(sheetname "")
		)
		(fill yes
			(thermal_gap 0.5)
			(thermal_bridge_width 0.5)
			(island_removal_mode 0)
		)
		(polygon
			(pts
				(arc
					(start 424.346116 -317.18504)
					(mid 423.678096 -317.18504)
					(end 424.346116 -317.18504)
				)
			)
		)
	)
	(zone
		(layers "B.Cu" "In15.Cu")
		(hatch none 0.5)
		(connect_pads
			(clearance 0)
		)
		(min_thickness 0.25)
		(keepout
			(tracks not_allowed)
			(vias allowed)
			(pads allowed)
			(copperpour not_allowed)
			(footprints allowed)
		)
		(placement
			(enabled no)
			(sheetname "")
		)
		(fill yes
			(thermal_gap 0.5)
			(thermal_bridge_width 0.5)
			(island_removal_mode 0)
		)
		(polygon
			(pts
				(arc
					(start 296.058082 -265.335004)
					(mid 295.390062 -265.335004)
					(end 296.058082 -265.335004)
				)
			)
		)
	)
	(zone
		(layers "B.Cu" "In15.Cu")
		(hatch none 0.5)
		(connect_pads
			(clearance 0)
		)
		(min_thickness 0.25)
		(keepout
			(tracks not_allowed)
			(vias allowed)
			(pads allowed)
			(copperpour not_allowed)
			(footprints allowed)
		)
		(placement
			(enabled no)
			(sheetname "")
		)
		(fill yes
			(thermal_gap 0.5)
			(thermal_bridge_width 0.5)
			(island_removal_mode 0)
		)
		(polygon
			(pts
				(arc
					(start 300.15815 -275.535136)
					(mid 299.49013 -275.535136)
					(end 300.15815 -275.535136)
				)
			)
		)
	)
	(zone
		(layers "B.Cu" "In15.Cu")
		(hatch none 0.5)
		(connect_pads
			(clearance 0)
		)
		(min_thickness 0.25)
		(keepout
			(tracks not_allowed)
			(vias allowed)
			(pads allowed)
			(copperpour not_allowed)
			(footprints allowed)
		)
		(placement
			(enabled no)
			(sheetname "")
		)
		(fill yes
			(thermal_gap 0.5)
			(thermal_bridge_width 0.5)
			(island_removal_mode 0)
		)
		(polygon
			(pts
				(arc
					(start 136.059672 -225.854514)
					(mid 135.429752 -225.854514)
					(end 136.059672 -225.854514)
				)
			)
		)
	)
	(zone
		(layers "B.Cu" "In15.Cu")
		(hatch none 0.5)
		(connect_pads
			(clearance 0)
		)
		(min_thickness 0.25)
		(keepout
			(tracks not_allowed)
			(vias allowed)
			(pads allowed)
			(copperpour not_allowed)
			(footprints allowed)
		)
		(placement
			(enabled no)
			(sheetname "")
		)
		(fill yes
			(thermal_gap 0.5)
			(thermal_bridge_width 0.5)
			(island_removal_mode 0)
		)
		(polygon
			(pts
				(arc
					(start 424.346116 -201.585068)
					(mid 423.678096 -201.585068)
					(end 424.346116 -201.585068)
				)
			)
		)
	)
	(zone
		(layers "B.Cu" "In15.Cu")
		(hatch none 0.5)
		(connect_pads
			(clearance 0)
		)
		(min_thickness 0.25)
		(keepout
			(tracks not_allowed)
			(vias allowed)
			(pads allowed)
			(copperpour not_allowed)
			(footprints allowed)
		)
		(placement
			(enabled no)
			(sheetname "")
		)
		(fill yes
			(thermal_gap 0.5)
			(thermal_bridge_width 0.5)
			(island_removal_mode 0)
		)
		(polygon
			(pts
				(arc
					(start 136.529826 -239.624362)
					(mid 135.899906 -239.624362)
					(end 136.529826 -239.624362)
				)
			)
		)
	)
	(zone
		(layers "B.Cu" "In15.Cu")
		(hatch none 0.5)
		(connect_pads
			(clearance 0)
		)
		(min_thickness 0.25)
		(keepout
			(tracks not_allowed)
			(vias allowed)
			(pads allowed)
			(copperpour not_allowed)
			(footprints allowed)
		)
		(placement
			(enabled no)
			(sheetname "")
		)
		(fill yes
			(thermal_gap 0.5)
			(thermal_bridge_width 0.5)
			(island_removal_mode 0)
		)
		(polygon
			(pts
				(arc
					(start 296.058082 -230.485188)
					(mid 295.390062 -230.485188)
					(end 296.058082 -230.485188)
				)
			)
		)
	)
	(zone
		(layers "B.Cu" "In15.Cu")
		(hatch none 0.5)
		(connect_pads
			(clearance 0)
		)
		(min_thickness 0.25)
		(keepout
			(tracks not_allowed)
			(vias allowed)
			(pads allowed)
			(copperpour not_allowed)
			(footprints allowed)
		)
		(placement
			(enabled no)
			(sheetname "")
		)
		(fill yes
			(thermal_gap 0.5)
			(thermal_bridge_width 0.5)
			(island_removal_mode 0)
		)
		(polygon
			(pts
				(arc
					(start 176.406048 -312.935366)
					(mid 175.738028 -312.935366)
					(end 176.406048 -312.935366)
				)
			)
		)
	)
	(zone
		(layers "B.Cu" "In15.Cu")
		(hatch none 0.5)
		(connect_pads
			(clearance 0)
		)
		(min_thickness 0.25)
		(keepout
			(tracks not_allowed)
			(vias allowed)
			(pads allowed)
			(copperpour not_allowed)
			(footprints allowed)
		)
		(placement
			(enabled no)
			(sheetname "")
		)
		(fill yes
			(thermal_gap 0.5)
			(thermal_bridge_width 0.5)
			(island_removal_mode 0)
		)
		(polygon
			(pts
				(arc
					(start 48.118014 -248.335292)
					(mid 47.449994 -248.335292)
					(end 48.118014 -248.335292)
				)
			)
		)
	)
	(zone
		(layers "B.Cu" "In15.Cu")
		(hatch none 0.5)
		(connect_pads
			(clearance 0)
		)
		(min_thickness 0.25)
		(keepout
			(tracks not_allowed)
			(vias allowed)
			(pads allowed)
			(copperpour not_allowed)
			(footprints allowed)
		)
		(placement
			(enabled no)
			(sheetname "")
		)
		(fill yes
			(thermal_gap 0.5)
			(thermal_bridge_width 0.5)
			(island_removal_mode 0)
		)
		(polygon
			(pts
				(arc
					(start 296.058082 -289.985196)
					(mid 295.390062 -289.985196)
					(end 296.058082 -289.985196)
				)
			)
		)
	)
	(zone
		(layers "B.Cu" "In15.Cu")
		(hatch none 0.5)
		(connect_pads
			(clearance 0)
		)
		(min_thickness 0.25)
		(keepout
			(tracks not_allowed)
			(vias allowed)
			(pads allowed)
			(copperpour not_allowed)
			(footprints allowed)
		)
		(placement
			(enabled no)
			(sheetname "")
		)
		(fill yes
			(thermal_gap 0.5)
			(thermal_bridge_width 0.5)
			(island_removal_mode 0)
		)
		(polygon
			(pts
				(arc
					(start 135.419592 -288.666174)
					(mid 134.789672 -288.666174)
					(end 135.419592 -288.666174)
				)
			)
		)
	)
	(zone
		(layers "B.Cu" "In15.Cu")
		(hatch none 0.5)
		(connect_pads
			(clearance 0)
		)
		(min_thickness 0.25)
		(keepout
			(tracks not_allowed)
			(vias allowed)
			(pads allowed)
			(copperpour not_allowed)
			(footprints allowed)
		)
		(placement
			(enabled no)
			(sheetname "")
		)
		(fill yes
			(thermal_gap 0.5)
			(thermal_bridge_width 0.5)
			(island_removal_mode 0)
		)
		(polygon
			(pts
				(arc
					(start 296.058082 -305.28514)
					(mid 295.390062 -305.28514)
					(end 296.058082 -305.28514)
				)
			)
		)
	)
	(zone
		(layers "B.Cu" "In15.Cu")
		(hatch none 0.5)
		(connect_pads
			(clearance 0)
		)
		(min_thickness 0.25)
		(keepout
			(tracks not_allowed)
			(vias allowed)
			(pads allowed)
			(copperpour not_allowed)
			(footprints allowed)
		)
		(placement
			(enabled no)
			(sheetname "")
		)
		(fill yes
			(thermal_gap 0.5)
			(thermal_bridge_width 0.5)
			(island_removal_mode 0)
		)
		(polygon
			(pts
				(arc
					(start 389.250428 -401.674838)
					(mid 388.582408 -401.674838)
					(end 389.250428 -401.674838)
				)
			)
		)
	)
	(zone
		(layers "B.Cu" "In15.Cu")
		(hatch none 0.5)
		(connect_pads
			(clearance 0)
		)
		(min_thickness 0.25)
		(keepout
			(tracks not_allowed)
			(vias allowed)
			(pads allowed)
			(copperpour not_allowed)
			(footprints allowed)
		)
		(placement
			(enabled no)
			(sheetname "")
		)
		(fill yes
			(thermal_gap 0.5)
			(thermal_bridge_width 0.5)
			(island_removal_mode 0)
		)
		(polygon
			(pts
				(arc
					(start 336.366104 -283.806138)
					(mid 335.736184 -283.806138)
					(end 336.366104 -283.806138)
				)
			)
		)
	)
	(zone
		(layers "B.Cu" "In15.Cu")
		(hatch none 0.5)
		(connect_pads
			(clearance 0)
		)
		(min_thickness 0.25)
		(keepout
			(tracks not_allowed)
			(vias allowed)
			(pads allowed)
			(copperpour not_allowed)
			(footprints allowed)
		)
		(placement
			(enabled no)
			(sheetname "")
		)
		(fill yes
			(thermal_gap 0.5)
			(thermal_bridge_width 0.5)
			(island_removal_mode 0)
		)
		(polygon
			(pts
				(arc
					(start 337.476084 -234.764072)
					(mid 336.846164 -234.764072)
					(end 337.476084 -234.764072)
				)
			)
		)
	)
	(zone
		(layers "B.Cu" "In15.Cu")
		(hatch none 0.5)
		(connect_pads
			(clearance 0)
		)
		(min_thickness 0.25)
		(keepout
			(tracks not_allowed)
			(vias allowed)
			(pads allowed)
			(copperpour not_allowed)
			(footprints allowed)
		)
		(placement
			(enabled no)
			(sheetname "")
		)
		(fill yes
			(thermal_gap 0.5)
			(thermal_bridge_width 0.5)
			(island_removal_mode 0)
		)
		(polygon
			(pts
				(arc
					(start 296.058082 -302.73498)
					(mid 295.390062 -302.73498)
					(end 296.058082 -302.73498)
				)
			)
		)
	)
	(zone
		(layers "B.Cu" "In15.Cu")
		(hatch none 0.5)
		(connect_pads
			(clearance 0)
		)
		(min_thickness 0.25)
		(keepout
			(tracks not_allowed)
			(vias allowed)
			(pads allowed)
			(copperpour not_allowed)
			(footprints allowed)
		)
		(placement
			(enabled no)
			(sheetname "")
		)
		(fill yes
			(thermal_gap 0.5)
			(thermal_bridge_width 0.5)
			(island_removal_mode 0)
		)
		(polygon
			(pts
				(arc
					(start 52.218082 -301.88535)
					(mid 51.550062 -301.88535)
					(end 52.218082 -301.88535)
				)
			)
		)
	)
	(zone
		(layers "B.Cu" "In15.Cu")
		(hatch none 0.5)
		(connect_pads
			(clearance 0)
		)
		(min_thickness 0.25)
		(keepout
			(tracks not_allowed)
			(vias allowed)
			(pads allowed)
			(copperpour not_allowed)
			(footprints allowed)
		)
		(placement
			(enabled no)
			(sheetname "")
		)
		(fill yes
			(thermal_gap 0.5)
			(thermal_bridge_width 0.5)
			(island_removal_mode 0)
		)
		(polygon
			(pts
				(arc
					(start 296.058082 -313.784996)
					(mid 295.390062 -313.784996)
					(end 296.058082 -313.784996)
				)
			)
		)
	)
	(zone
		(layers "B.Cu" "In15.Cu")
		(hatch none 0.5)
		(connect_pads
			(clearance 0)
		)
		(min_thickness 0.25)
		(keepout
			(tracks not_allowed)
			(vias allowed)
			(pads allowed)
			(copperpour not_allowed)
			(footprints allowed)
		)
		(placement
			(enabled no)
			(sheetname "")
		)
		(fill yes
			(thermal_gap 0.5)
			(thermal_bridge_width 0.5)
			(island_removal_mode 0)
		)
		(polygon
			(pts
				(arc
					(start 136.529826 -250.964446)
					(mid 135.899906 -250.964446)
					(end 136.529826 -250.964446)
				)
			)
		)
	)
	(zone
		(layers "B.Cu" "In15.Cu")
		(hatch none 0.5)
		(connect_pads
			(clearance 0)
		)
		(min_thickness 0.25)
		(keepout
			(tracks not_allowed)
			(vias allowed)
			(pads allowed)
			(copperpour not_allowed)
			(footprints allowed)
		)
		(placement
			(enabled no)
			(sheetname "")
		)
		(fill yes
			(thermal_gap 0.5)
			(thermal_bridge_width 0.5)
			(island_removal_mode 0)
		)
		(polygon
			(pts
				(arc
					(start 382.589786 -229.904036)
					(mid 381.959866 -229.904036)
					(end 382.589786 -229.904036)
				)
			)
		)
	)
	(zone
		(layers "B.Cu" "In15.Cu")
		(hatch none 0.5)
		(connect_pads
			(clearance 0)
		)
		(min_thickness 0.25)
		(keepout
			(tracks not_allowed)
			(vias allowed)
			(pads allowed)
			(copperpour not_allowed)
			(footprints allowed)
		)
		(placement
			(enabled no)
			(sheetname "")
		)
		(fill yes
			(thermal_gap 0.5)
			(thermal_bridge_width 0.5)
			(island_removal_mode 0)
		)
		(polygon
			(pts
				(arc
					(start 134.649718 -229.90429)
					(mid 134.019798 -229.90429)
					(end 134.649718 -229.90429)
				)
			)
		)
	)
	(zone
		(layers "B.Cu" "In15.Cu")
		(hatch none 0.5)
		(connect_pads
			(clearance 0)
		)
		(min_thickness 0.25)
		(keepout
			(tracks not_allowed)
			(vias allowed)
			(pads allowed)
			(copperpour not_allowed)
			(footprints allowed)
		)
		(placement
			(enabled no)
			(sheetname "")
		)
		(fill yes
			(thermal_gap 0.5)
			(thermal_bridge_width 0.5)
			(island_removal_mode 0)
		)
		(polygon
			(pts
				(arc
					(start 88.126062 -227.474526)
					(mid 87.496142 -227.474526)
					(end 88.126062 -227.474526)
				)
			)
		)
	)
	(zone
		(layers "B.Cu" "In15.Cu")
		(hatch none 0.5)
		(connect_pads
			(clearance 0)
		)
		(min_thickness 0.25)
		(keepout
			(tracks not_allowed)
			(vias allowed)
			(pads allowed)
			(copperpour not_allowed)
			(footprints allowed)
		)
		(placement
			(enabled no)
			(sheetname "")
		)
		(fill yes
			(thermal_gap 0.5)
			(thermal_bridge_width 0.5)
			(island_removal_mode 0)
		)
		(polygon
			(pts
				(arc
					(start 87.878412 -392.429238)
					(mid 87.210392 -392.429238)
					(end 87.878412 -392.429238)
				)
			)
		)
	)
	(zone
		(layers "B.Cu" "In15.Cu")
		(hatch none 0.5)
		(connect_pads
			(clearance 0)
		)
		(min_thickness 0.25)
		(keepout
			(tracks not_allowed)
			(vias allowed)
			(pads allowed)
			(copperpour not_allowed)
			(footprints allowed)
		)
		(placement
			(enabled no)
			(sheetname "")
		)
		(fill yes
			(thermal_gap 0.5)
			(thermal_bridge_width 0.5)
			(island_removal_mode 0)
		)
		(polygon
			(pts
				(arc
					(start 88.126062 -245.294404)
					(mid 87.496142 -245.294404)
					(end 88.126062 -245.294404)
				)
			)
		)
	)
	(zone
		(layers "B.Cu" "In15.Cu")
		(hatch none 0.5)
		(connect_pads
			(clearance 0)
		)
		(min_thickness 0.25)
		(keepout
			(tracks not_allowed)
			(vias allowed)
			(pads allowed)
			(copperpour not_allowed)
			(footprints allowed)
		)
		(placement
			(enabled no)
			(sheetname "")
		)
		(fill yes
			(thermal_gap 0.5)
			(thermal_bridge_width 0.5)
			(island_removal_mode 0)
		)
		(polygon
			(pts
				(arc
					(start 337.006184 -237.19409)
					(mid 336.376264 -237.19409)
					(end 337.006184 -237.19409)
				)
			)
		)
	)
	(zone
		(layers "B.Cu" "In15.Cu")
		(hatch none 0.5)
		(connect_pads
			(clearance 0)
		)
		(min_thickness 0.25)
		(keepout
			(tracks not_allowed)
			(vias allowed)
			(pads allowed)
			(copperpour not_allowed)
			(footprints allowed)
		)
		(placement
			(enabled no)
			(sheetname "")
		)
		(fill yes
			(thermal_gap 0.5)
			(thermal_bridge_width 0.5)
			(island_removal_mode 0)
		)
		(polygon
			(pts
				(arc
					(start 427.23943 -387.878828)
					(mid 426.57141 -387.878828)
					(end 427.23943 -387.878828)
				)
			)
		)
	)
	(zone
		(layers "B.Cu" "In15.Cu")
		(hatch none 0.5)
		(connect_pads
			(clearance 0)
		)
		(min_thickness 0.25)
		(keepout
			(tracks not_allowed)
			(vias allowed)
			(pads allowed)
			(copperpour not_allowed)
			(footprints allowed)
		)
		(placement
			(enabled no)
			(sheetname "")
		)
		(fill yes
			(thermal_gap 0.5)
			(thermal_bridge_width 0.5)
			(island_removal_mode 0)
		)
		(polygon
			(pts
				(arc
					(start 420.246048 -221.13494)
					(mid 419.578028 -221.13494)
					(end 420.246048 -221.13494)
				)
			)
		)
	)
	(zone
		(layers "B.Cu" "In15.Cu")
		(hatch none 0.5)
		(connect_pads
			(clearance 0)
		)
		(min_thickness 0.25)
		(keepout
			(tracks not_allowed)
			(vias allowed)
			(pads allowed)
			(copperpour not_allowed)
			(footprints allowed)
		)
		(placement
			(enabled no)
			(sheetname "")
		)
		(fill yes
			(thermal_gap 0.5)
			(thermal_bridge_width 0.5)
			(island_removal_mode 0)
		)
		(polygon
			(pts
				(arc
					(start 116.450364 -393.292838)
					(mid 115.782344 -393.292838)
					(end 116.450364 -393.292838)
				)
			)
		)
	)
	(zone
		(layers "B.Cu" "In15.Cu")
		(hatch none 0.5)
		(connect_pads
			(clearance 0)
		)
		(min_thickness 0.25)
		(keepout
			(tracks not_allowed)
			(vias allowed)
			(pads allowed)
			(copperpour not_allowed)
			(footprints allowed)
		)
		(placement
			(enabled no)
			(sheetname "")
		)
		(fill yes
			(thermal_gap 0.5)
			(thermal_bridge_width 0.5)
			(island_removal_mode 0)
		)
		(polygon
			(pts
				(arc
					(start 382.050544 -401.674838)
					(mid 381.382524 -401.674838)
					(end 382.050544 -401.674838)
				)
			)
		)
	)
	(zone
		(layers "B.Cu" "In15.Cu")
		(hatch none 0.5)
		(connect_pads
			(clearance 0)
		)
		(min_thickness 0.25)
		(keepout
			(tracks not_allowed)
			(vias allowed)
			(pads allowed)
			(copperpour not_allowed)
			(footprints allowed)
		)
		(placement
			(enabled no)
			(sheetname "")
		)
		(fill yes
			(thermal_gap 0.5)
			(thermal_bridge_width 0.5)
			(island_removal_mode 0)
		)
		(polygon
			(pts
				(arc
					(start 172.30598 -235.585254)
					(mid 171.63796 -235.585254)
					(end 172.30598 -235.585254)
				)
			)
		)
	)
	(zone
		(layers "B.Cu" "In15.Cu")
		(hatch none 0.5)
		(connect_pads
			(clearance 0)
		)
		(min_thickness 0.25)
		(keepout
			(tracks not_allowed)
			(vias allowed)
			(pads allowed)
			(copperpour not_allowed)
			(footprints allowed)
		)
		(placement
			(enabled no)
			(sheetname "")
		)
		(fill yes
			(thermal_gap 0.5)
			(thermal_bridge_width 0.5)
			(island_removal_mode 0)
		)
		(polygon
			(pts
				(arc
					(start 163.398454 -371.49913)
					(mid 162.730434 -371.49913)
					(end 163.398454 -371.49913)
				)
			)
		)
	)
	(zone
		(layers "B.Cu" "In15.Cu")
		(hatch none 0.5)
		(connect_pads
			(clearance 0)
		)
		(min_thickness 0.25)
		(keepout
			(tracks not_allowed)
			(vias allowed)
			(pads allowed)
			(copperpour not_allowed)
			(footprints allowed)
		)
		(placement
			(enabled no)
			(sheetname "")
		)
		(fill yes
			(thermal_gap 0.5)
			(thermal_bridge_width 0.5)
			(island_removal_mode 0)
		)
		(polygon
			(pts
				(arc
					(start 424.346116 -242.385088)
					(mid 423.678096 -242.385088)
					(end 424.346116 -242.385088)
				)
			)
		)
	)
	(zone
		(layers "B.Cu" "In15.Cu")
		(hatch none 0.5)
		(connect_pads
			(clearance 0)
		)
		(min_thickness 0.25)
		(keepout
			(tracks not_allowed)
			(vias allowed)
			(pads allowed)
			(copperpour not_allowed)
			(footprints allowed)
		)
		(placement
			(enabled no)
			(sheetname "")
		)
		(fill yes
			(thermal_gap 0.5)
			(thermal_bridge_width 0.5)
			(island_removal_mode 0)
		)
		(polygon
			(pts
				(arc
					(start 48.118014 -289.98545)
					(mid 47.449994 -289.98545)
					(end 48.118014 -289.98545)
				)
			)
		)
	)
	(zone
		(layers "B.Cu" "In15.Cu")
		(hatch none 0.5)
		(connect_pads
			(clearance 0)
		)
		(min_thickness 0.25)
		(keepout
			(tracks not_allowed)
			(vias allowed)
			(pads allowed)
			(copperpour not_allowed)
			(footprints allowed)
		)
		(placement
			(enabled no)
			(sheetname "")
		)
		(fill yes
			(thermal_gap 0.5)
			(thermal_bridge_width 0.5)
			(island_removal_mode 0)
		)
		(polygon
			(pts
				(arc
					(start 367.849658 -270.036036)
					(mid 367.219738 -270.036036)
					(end 367.849658 -270.036036)
				)
			)
		)
	)
	(zone
		(layers "B.Cu" "In15.Cu")
		(hatch none 0.5)
		(connect_pads
			(clearance 0)
		)
		(min_thickness 0.25)
		(keepout
			(tracks not_allowed)
			(vias allowed)
			(pads allowed)
			(copperpour not_allowed)
			(footprints allowed)
		)
		(placement
			(enabled no)
			(sheetname "")
		)
		(fill yes
			(thermal_gap 0.5)
			(thermal_bridge_width 0.5)
			(island_removal_mode 0)
		)
		(polygon
			(pts
				(arc
					(start 420.246048 -263.634982)
					(mid 419.578028 -263.634982)
					(end 420.246048 -263.634982)
				)
			)
		)
	)
	(zone
		(layers "B.Cu" "In15.Cu")
		(hatch none 0.5)
		(connect_pads
			(clearance 0)
		)
		(min_thickness 0.25)
		(keepout
			(tracks not_allowed)
			(vias allowed)
			(pads allowed)
			(copperpour not_allowed)
			(footprints allowed)
		)
		(placement
			(enabled no)
			(sheetname "")
		)
		(fill yes
			(thermal_gap 0.5)
			(thermal_bridge_width 0.5)
			(island_removal_mode 0)
		)
		(polygon
			(pts
				(arc
					(start 143.137128 -434.48986)
					(mid 142.362936 -434.48986)
					(end 143.137128 -434.48986)
				)
			)
		)
	)
	(zone
		(layers "B.Cu" "In15.Cu")
		(hatch none 0.5)
		(connect_pads
			(clearance 0)
		)
		(min_thickness 0.25)
		(keepout
			(tracks not_allowed)
			(vias allowed)
			(pads allowed)
			(copperpour not_allowed)
			(footprints allowed)
		)
		(placement
			(enabled no)
			(sheetname "")
		)
		(fill yes
			(thermal_gap 0.5)
			(thermal_bridge_width 0.5)
			(island_removal_mode 0)
		)
		(polygon
			(pts
				(arc
					(start 172.30598 -237.285276)
					(mid 171.63796 -237.285276)
					(end 172.30598 -237.285276)
				)
			)
		)
	)
	(zone
		(layers "B.Cu" "In15.Cu")
		(hatch none 0.5)
		(connect_pads
			(clearance 0)
		)
		(min_thickness 0.25)
		(keepout
			(tracks not_allowed)
			(vias allowed)
			(pads allowed)
			(copperpour not_allowed)
			(footprints allowed)
		)
		(placement
			(enabled no)
			(sheetname "")
		)
		(fill yes
			(thermal_gap 0.5)
			(thermal_bridge_width 0.5)
			(island_removal_mode 0)
		)
		(polygon
			(pts
				(arc
					(start 89.078308 -393.292838)
					(mid 88.410288 -393.292838)
					(end 89.078308 -393.292838)
				)
			)
		)
	)
	(zone
		(layers "B.Cu" "In15.Cu")
		(hatch none 0.5)
		(connect_pads
			(clearance 0)
		)
		(min_thickness 0.25)
		(keepout
			(tracks not_allowed)
			(vias allowed)
			(pads allowed)
			(copperpour not_allowed)
			(footprints allowed)
		)
		(placement
			(enabled no)
			(sheetname "")
		)
		(fill yes
			(thermal_gap 0.5)
			(thermal_bridge_width 0.5)
			(island_removal_mode 0)
		)
		(polygon
			(pts
				(arc
					(start 296.058082 -308.685184)
					(mid 295.390062 -308.685184)
					(end 296.058082 -308.685184)
				)
			)
		)
	)
	(zone
		(layers "B.Cu" "In15.Cu")
		(hatch none 0.5)
		(connect_pads
			(clearance 0)
		)
		(min_thickness 0.25)
		(keepout
			(tracks not_allowed)
			(vias allowed)
			(pads allowed)
			(copperpour not_allowed)
			(footprints allowed)
		)
		(placement
			(enabled no)
			(sheetname "")
		)
		(fill yes
			(thermal_gap 0.5)
			(thermal_bridge_width 0.5)
			(island_removal_mode 0)
		)
		(polygon
			(pts
				(arc
					(start 384.469894 -225.044254)
					(mid 383.839974 -225.044254)
					(end 384.469894 -225.044254)
				)
			)
		)
	)
	(zone
		(layers "B.Cu" "In15.Cu")
		(hatch none 0.5)
		(connect_pads
			(clearance 0)
		)
		(min_thickness 0.25)
		(keepout
			(tracks not_allowed)
			(vias allowed)
			(pads allowed)
			(copperpour not_allowed)
			(footprints allowed)
		)
		(placement
			(enabled no)
			(sheetname "")
		)
		(fill yes
			(thermal_gap 0.5)
			(thermal_bridge_width 0.5)
			(island_removal_mode 0)
		)
		(polygon
			(pts
				(arc
					(start 383.35966 -272.466054)
					(mid 382.72974 -272.466054)
					(end 383.35966 -272.466054)
				)
			)
		)
	)
	(zone
		(layers "B.Cu" "In15.Cu")
		(hatch none 0.5)
		(connect_pads
			(clearance 0)
		)
		(min_thickness 0.25)
		(keepout
			(tracks not_allowed)
			(vias allowed)
			(pads allowed)
			(copperpour not_allowed)
			(footprints allowed)
		)
		(placement
			(enabled no)
			(sheetname "")
		)
		(fill yes
			(thermal_gap 0.5)
			(thermal_bridge_width 0.5)
			(island_removal_mode 0)
		)
		(polygon
			(pts
				(arc
					(start 296.058082 -316.335156)
					(mid 295.390062 -316.335156)
					(end 296.058082 -316.335156)
				)
			)
		)
	)
	(zone
		(layers "B.Cu" "In15.Cu")
		(hatch none 0.5)
		(connect_pads
			(clearance 0)
		)
		(min_thickness 0.25)
		(keepout
			(tracks not_allowed)
			(vias allowed)
			(pads allowed)
			(copperpour not_allowed)
			(footprints allowed)
		)
		(placement
			(enabled no)
			(sheetname "")
		)
		(fill yes
			(thermal_gap 0.5)
			(thermal_bridge_width 0.5)
			(island_removal_mode 0)
		)
		(polygon
			(pts
				(arc
					(start 134.949692 -281.376374)
					(mid 134.319772 -281.376374)
					(end 134.949692 -281.376374)
				)
			)
		)
	)
	(zone
		(layers "B.Cu" "In15.Cu")
		(hatch none 0.5)
		(connect_pads
			(clearance 0)
		)
		(min_thickness 0.25)
		(keepout
			(tracks not_allowed)
			(vias allowed)
			(pads allowed)
			(copperpour not_allowed)
			(footprints allowed)
		)
		(placement
			(enabled no)
			(sheetname "")
		)
		(fill yes
			(thermal_gap 0.5)
			(thermal_bridge_width 0.5)
			(island_removal_mode 0)
		)
		(polygon
			(pts
				(arc
					(start 52.218082 -214.33536)
					(mid 51.550062 -214.33536)
					(end 52.218082 -214.33536)
				)
			)
		)
	)
	(zone
		(layers "B.Cu" "In15.Cu")
		(hatch none 0.5)
		(connect_pads
			(clearance 0)
		)
		(min_thickness 0.25)
		(keepout
			(tracks not_allowed)
			(vias allowed)
			(pads allowed)
			(copperpour not_allowed)
			(footprints allowed)
		)
		(placement
			(enabled no)
			(sheetname "")
		)
		(fill yes
			(thermal_gap 0.5)
			(thermal_bridge_width 0.5)
			(island_removal_mode 0)
		)
		(polygon
			(pts
				(arc
					(start 399.84045 -379.88113)
					(mid 399.17243 -379.88113)
					(end 399.84045 -379.88113)
				)
			)
		)
	)
	(zone
		(layers "B.Cu" "In15.Cu")
		(hatch none 0.5)
		(connect_pads
			(clearance 0)
		)
		(min_thickness 0.25)
		(keepout
			(tracks not_allowed)
			(vias allowed)
			(pads allowed)
			(copperpour not_allowed)
			(footprints allowed)
		)
		(placement
			(enabled no)
			(sheetname "")
		)
		(fill yes
			(thermal_gap 0.5)
			(thermal_bridge_width 0.5)
			(island_removal_mode 0)
		)
		(polygon
			(pts
				(arc
					(start 135.119618 -253.394464)
					(mid 134.489698 -253.394464)
					(end 135.119618 -253.394464)
				)
			)
		)
	)
	(zone
		(layers "B.Cu" "In15.Cu")
		(hatch none 0.5)
		(connect_pads
			(clearance 0)
		)
		(min_thickness 0.25)
		(keepout
			(tracks not_allowed)
			(vias allowed)
			(pads allowed)
			(copperpour not_allowed)
			(footprints allowed)
		)
		(placement
			(enabled no)
			(sheetname "")
		)
		(fill yes
			(thermal_gap 0.5)
			(thermal_bridge_width 0.5)
			(island_removal_mode 0)
		)
		(polygon
			(pts
				(arc
					(start 88.426036 -270.846296)
					(mid 87.796116 -270.846296)
					(end 88.426036 -270.846296)
				)
			)
		)
	)
	(zone
		(layers "B.Cu" "In15.Cu")
		(hatch none 0.5)
		(connect_pads
			(clearance 0)
		)
		(min_thickness 0.25)
		(keepout
			(tracks not_allowed)
			(vias allowed)
			(pads allowed)
			(copperpour not_allowed)
			(footprints allowed)
		)
		(placement
			(enabled no)
			(sheetname "")
		)
		(fill yes
			(thermal_gap 0.5)
			(thermal_bridge_width 0.5)
			(island_removal_mode 0)
		)
		(polygon
			(pts
				(arc
					(start 296.058082 -295.085008)
					(mid 295.390062 -295.085008)
					(end 296.058082 -295.085008)
				)
			)
		)
	)
	(zone
		(layers "B.Cu" "In15.Cu")
		(hatch none 0.5)
		(connect_pads
			(clearance 0)
		)
		(min_thickness 0.25)
		(keepout
			(tracks not_allowed)
			(vias allowed)
			(pads allowed)
			(copperpour not_allowed)
			(footprints allowed)
		)
		(placement
			(enabled no)
			(sheetname "")
		)
		(fill yes
			(thermal_gap 0.5)
			(thermal_bridge_width 0.5)
			(island_removal_mode 0)
		)
		(polygon
			(pts
				(arc
					(start 384.469894 -255.824228)
					(mid 383.839974 -255.824228)
					(end 384.469894 -255.824228)
				)
			)
		)
	)
	(zone
		(layers "B.Cu" "In15.Cu")
		(hatch none 0.5)
		(connect_pads
			(clearance 0)
		)
		(min_thickness 0.25)
		(keepout
			(tracks not_allowed)
			(vias allowed)
			(pads allowed)
			(copperpour not_allowed)
			(footprints allowed)
		)
		(placement
			(enabled no)
			(sheetname "")
		)
		(fill yes
			(thermal_gap 0.5)
			(thermal_bridge_width 0.5)
			(island_removal_mode 0)
		)
		(polygon
			(pts
				(arc
					(start 172.30598 -205.83525)
					(mid 171.63796 -205.83525)
					(end 172.30598 -205.83525)
				)
			)
		)
	)
	(zone
		(layers "B.Cu" "In15.Cu")
		(hatch none 0.5)
		(connect_pads
			(clearance 0)
		)
		(min_thickness 0.25)
		(keepout
			(tracks not_allowed)
			(vias allowed)
			(pads allowed)
			(copperpour not_allowed)
			(footprints allowed)
		)
		(placement
			(enabled no)
			(sheetname "")
		)
		(fill yes
			(thermal_gap 0.5)
			(thermal_bridge_width 0.5)
			(island_removal_mode 0)
		)
		(polygon
			(pts
				(arc
					(start 337.476084 -239.624108)
					(mid 336.846164 -239.624108)
					(end 337.476084 -239.624108)
				)
			)
		)
	)
	(zone
		(layers "B.Cu" "In15.Cu")
		(hatch none 0.5)
		(connect_pads
			(clearance 0)
		)
		(min_thickness 0.25)
		(keepout
			(tracks not_allowed)
			(vias allowed)
			(pads allowed)
			(copperpour not_allowed)
			(footprints allowed)
		)
		(placement
			(enabled no)
			(sheetname "")
		)
		(fill yes
			(thermal_gap 0.5)
			(thermal_bridge_width 0.5)
			(island_removal_mode 0)
		)
		(polygon
			(pts
				(arc
					(start 424.346116 -249.185176)
					(mid 423.678096 -249.185176)
					(end 424.346116 -249.185176)
				)
			)
		)
	)
	(zone
		(layers "B.Cu" "In15.Cu")
		(hatch none 0.5)
		(connect_pads
			(clearance 0)
		)
		(min_thickness 0.25)
		(keepout
			(tracks not_allowed)
			(vias allowed)
			(pads allowed)
			(copperpour not_allowed)
			(footprints allowed)
		)
		(placement
			(enabled no)
			(sheetname "")
		)
		(fill yes
			(thermal_gap 0.5)
			(thermal_bridge_width 0.5)
			(island_removal_mode 0)
		)
		(polygon
			(pts
				(arc
					(start 172.30598 -207.535272)
					(mid 171.63796 -207.535272)
					(end 172.30598 -207.535272)
				)
			)
		)
	)
	(zone
		(layers "B.Cu" "In15.Cu")
		(hatch none 0.5)
		(connect_pads
			(clearance 0)
		)
		(min_thickness 0.25)
		(keepout
			(tracks not_allowed)
			(vias allowed)
			(pads allowed)
			(copperpour not_allowed)
			(footprints allowed)
		)
		(placement
			(enabled no)
			(sheetname "")
		)
		(fill yes
			(thermal_gap 0.5)
			(thermal_bridge_width 0.5)
			(island_removal_mode 0)
		)
		(polygon
			(pts
				(arc
					(start 337.006184 -233.954066)
					(mid 336.376264 -233.954066)
					(end 337.006184 -233.954066)
				)
			)
		)
	)
	(zone
		(layers "B.Cu" "In15.Cu")
		(hatch none 0.5)
		(connect_pads
			(clearance 0)
		)
		(min_thickness 0.25)
		(keepout
			(tracks not_allowed)
			(vias allowed)
			(pads allowed)
			(copperpour not_allowed)
			(footprints allowed)
		)
		(placement
			(enabled no)
			(sheetname "")
		)
		(fill yes
			(thermal_gap 0.5)
			(thermal_bridge_width 0.5)
			(island_removal_mode 0)
		)
		(polygon
			(pts
				(arc
					(start 424.346116 -266.185142)
					(mid 423.678096 -266.185142)
					(end 424.346116 -266.185142)
				)
			)
		)
	)
	(zone
		(layers "B.Cu" "In15.Cu")
		(hatch none 0.5)
		(connect_pads
			(clearance 0)
		)
		(min_thickness 0.25)
		(keepout
			(tracks not_allowed)
			(vias allowed)
			(pads allowed)
			(copperpour not_allowed)
			(footprints allowed)
		)
		(placement
			(enabled no)
			(sheetname "")
		)
		(fill yes
			(thermal_gap 0.5)
			(thermal_bridge_width 0.5)
			(island_removal_mode 0)
		)
		(polygon
			(pts
				(arc
					(start 420.246048 -222.834962)
					(mid 419.578028 -222.834962)
					(end 420.246048 -222.834962)
				)
			)
		)
	)
	(zone
		(layers "B.Cu" "In15.Cu")
		(hatch none 0.5)
		(connect_pads
			(clearance 0)
		)
		(min_thickness 0.25)
		(keepout
			(tracks not_allowed)
			(vias allowed)
			(pads allowed)
			(copperpour not_allowed)
			(footprints allowed)
		)
		(placement
			(enabled no)
			(sheetname "")
		)
		(fill yes
			(thermal_gap 0.5)
			(thermal_bridge_width 0.5)
			(island_removal_mode 0)
		)
		(polygon
			(pts
				(arc
					(start 136.359646 -283.806392)
					(mid 135.729726 -283.806392)
					(end 136.359646 -283.806392)
				)
			)
		)
	)
	(zone
		(layers "B.Cu" "In15.Cu")
		(hatch none 0.5)
		(connect_pads
			(clearance 0)
		)
		(min_thickness 0.25)
		(keepout
			(tracks not_allowed)
			(vias allowed)
			(pads allowed)
			(copperpour not_allowed)
			(footprints allowed)
		)
		(placement
			(enabled no)
			(sheetname "")
		)
		(fill yes
			(thermal_gap 0.5)
			(thermal_bridge_width 0.5)
			(island_removal_mode 0)
		)
		(polygon
			(pts
				(arc
					(start 390.136888 -434.48986)
					(mid 389.362696 -434.48986)
					(end 390.136888 -434.48986)
				)
			)
		)
	)
	(zone
		(layers "B.Cu" "In15.Cu")
		(hatch none 0.5)
		(connect_pads
			(clearance 0)
		)
		(min_thickness 0.25)
		(keepout
			(tracks not_allowed)
			(vias allowed)
			(pads allowed)
			(copperpour not_allowed)
			(footprints allowed)
		)
		(placement
			(enabled no)
			(sheetname "")
		)
		(fill yes
			(thermal_gap 0.5)
			(thermal_bridge_width 0.5)
			(island_removal_mode 0)
		)
		(polygon
			(pts
				(arc
					(start 349.878142 -400.811238)
					(mid 349.210122 -400.811238)
					(end 349.878142 -400.811238)
				)
			)
		)
	)
	(zone
		(layers "B.Cu" "In15.Cu")
		(hatch none 0.5)
		(connect_pads
			(clearance 0)
		)
		(min_thickness 0.25)
		(keepout
			(tracks not_allowed)
			(vias allowed)
			(pads allowed)
			(copperpour not_allowed)
			(footprints allowed)
		)
		(placement
			(enabled no)
			(sheetname "")
		)
		(fill yes
			(thermal_gap 0.5)
			(thermal_bridge_width 0.5)
			(island_removal_mode 0)
		)
		(polygon
			(pts
				(arc
					(start 86.037166 -435.489858)
					(mid 85.262974 -435.489858)
					(end 86.037166 -435.489858)
				)
			)
		)
	)
	(zone
		(layers "B.Cu" "In15.Cu")
		(hatch none 0.5)
		(connect_pads
			(clearance 0)
		)
		(min_thickness 0.25)
		(keepout
			(tracks not_allowed)
			(vias allowed)
			(pads allowed)
			(copperpour not_allowed)
			(footprints allowed)
		)
		(placement
			(enabled no)
			(sheetname "")
		)
		(fill yes
			(thermal_gap 0.5)
			(thermal_bridge_width 0.5)
			(island_removal_mode 0)
		)
		(polygon
			(pts
				(arc
					(start 384.769868 -289.475926)
					(mid 384.139948 -289.475926)
					(end 384.769868 -289.475926)
				)
			)
		)
	)
	(zone
		(layers "B.Cu" "In15.Cu")
		(hatch none 0.5)
		(connect_pads
			(clearance 0)
		)
		(min_thickness 0.25)
		(keepout
			(tracks not_allowed)
			(vias allowed)
			(pads allowed)
			(copperpour not_allowed)
			(footprints allowed)
		)
		(placement
			(enabled no)
			(sheetname "")
		)
		(fill yes
			(thermal_gap 0.5)
			(thermal_bridge_width 0.5)
			(island_removal_mode 0)
		)
		(polygon
			(pts
				(arc
					(start 134.649718 -226.66452)
					(mid 134.019798 -226.66452)
					(end 134.649718 -226.66452)
				)
			)
		)
	)
	(zone
		(layers "B.Cu" "In15.Cu")
		(hatch none 0.5)
		(connect_pads
			(clearance 0)
		)
		(min_thickness 0.25)
		(keepout
			(tracks not_allowed)
			(vias allowed)
			(pads allowed)
			(copperpour not_allowed)
			(footprints allowed)
		)
		(placement
			(enabled no)
			(sheetname "")
		)
		(fill yes
			(thermal_gap 0.5)
			(thermal_bridge_width 0.5)
			(island_removal_mode 0)
		)
		(polygon
			(pts
				(arc
					(start 138.136884 -433.289964)
					(mid 137.362692 -433.289964)
					(end 138.136884 -433.289964)
				)
			)
		)
	)
	(zone
		(layers "B.Cu" "In15.Cu")
		(hatch none 0.5)
		(connect_pads
			(clearance 0)
		)
		(min_thickness 0.25)
		(keepout
			(tracks not_allowed)
			(vias allowed)
			(pads allowed)
			(copperpour not_allowed)
			(footprints allowed)
		)
		(placement
			(enabled no)
			(sheetname "")
		)
		(fill yes
			(thermal_gap 0.5)
			(thermal_bridge_width 0.5)
			(island_removal_mode 0)
		)
		(polygon
			(pts
				(arc
					(start 351.576132 -239.624108)
					(mid 350.946212 -239.624108)
					(end 351.576132 -239.624108)
				)
			)
		)
	)
	(zone
		(layers "B.Cu" "In15.Cu")
		(hatch none 0.5)
		(connect_pads
			(clearance 0)
		)
		(min_thickness 0.25)
		(keepout
			(tracks not_allowed)
			(vias allowed)
			(pads allowed)
			(copperpour not_allowed)
			(footprints allowed)
		)
		(placement
			(enabled no)
			(sheetname "")
		)
		(fill yes
			(thermal_gap 0.5)
			(thermal_bridge_width 0.5)
			(island_removal_mode 0)
		)
		(polygon
			(pts
				(arc
					(start 362.679742 -272.466054)
					(mid 362.049822 -272.466054)
					(end 362.679742 -272.466054)
				)
			)
		)
	)
	(zone
		(layers "B.Cu" "In15.Cu")
		(hatch none 0.5)
		(connect_pads
			(clearance 0)
		)
		(min_thickness 0.25)
		(keepout
			(tracks not_allowed)
			(vias allowed)
			(pads allowed)
			(copperpour not_allowed)
			(footprints allowed)
		)
		(placement
			(enabled no)
			(sheetname "")
		)
		(fill yes
			(thermal_gap 0.5)
			(thermal_bridge_width 0.5)
			(island_removal_mode 0)
		)
		(polygon
			(pts
				(arc
					(start 126.18974 -239.624362)
					(mid 125.55982 -239.624362)
					(end 126.18974 -239.624362)
				)
			)
		)
	)
	(zone
		(layers "B.Cu" "In15.Cu")
		(hatch none 0.5)
		(connect_pads
			(clearance 0)
		)
		(min_thickness 0.25)
		(keepout
			(tracks not_allowed)
			(vias allowed)
			(pads allowed)
			(copperpour not_allowed)
			(footprints allowed)
		)
		(placement
			(enabled no)
			(sheetname "")
		)
		(fill yes
			(thermal_gap 0.5)
			(thermal_bridge_width 0.5)
			(island_removal_mode 0)
		)
		(polygon
			(pts
				(arc
					(start 296.058082 -301.034958)
					(mid 295.390062 -301.034958)
					(end 296.058082 -301.034958)
				)
			)
		)
	)
	(zone
		(layers "B.Cu" "In15.Cu")
		(hatch none 0.5)
		(connect_pads
			(clearance 0)
		)
		(min_thickness 0.25)
		(keepout
			(tracks not_allowed)
			(vias allowed)
			(pads allowed)
			(copperpour not_allowed)
			(footprints allowed)
		)
		(placement
			(enabled no)
			(sheetname "")
		)
		(fill yes
			(thermal_gap 0.5)
			(thermal_bridge_width 0.5)
			(island_removal_mode 0)
		)
		(polygon
			(pts
				(arc
					(start 383.35966 -274.086066)
					(mid 382.72974 -274.086066)
					(end 383.35966 -274.086066)
				)
			)
		)
	)
	(zone
		(layers "B.Cu" "In15.Cu")
		(hatch none 0.5)
		(connect_pads
			(clearance 0)
		)
		(min_thickness 0.25)
		(keepout
			(tracks not_allowed)
			(vias allowed)
			(pads allowed)
			(copperpour not_allowed)
			(footprints allowed)
		)
		(placement
			(enabled no)
			(sheetname "")
		)
		(fill yes
			(thermal_gap 0.5)
			(thermal_bridge_width 0.5)
			(island_removal_mode 0)
		)
		(polygon
			(pts
				(arc
					(start 121.250456 -392.429238)
					(mid 120.582436 -392.429238)
					(end 121.250456 -392.429238)
				)
			)
		)
	)
	(zone
		(layers "B.Cu" "In15.Cu")
		(hatch none 0.5)
		(connect_pads
			(clearance 0)
		)
		(min_thickness 0.25)
		(keepout
			(tracks not_allowed)
			(vias allowed)
			(pads allowed)
			(copperpour not_allowed)
			(footprints allowed)
		)
		(placement
			(enabled no)
			(sheetname "")
		)
		(fill yes
			(thermal_gap 0.5)
			(thermal_bridge_width 0.5)
			(island_removal_mode 0)
		)
		(polygon
			(pts
				(arc
					(start 335.89595 -292.71595)
					(mid 335.26603 -292.71595)
					(end 335.89595 -292.71595)
				)
			)
		)
	)
	(zone
		(layers "B.Cu" "In15.Cu")
		(hatch none 0.5)
		(connect_pads
			(clearance 0)
		)
		(min_thickness 0.25)
		(keepout
			(tracks not_allowed)
			(vias allowed)
			(pads allowed)
			(copperpour not_allowed)
			(footprints allowed)
		)
		(placement
			(enabled no)
			(sheetname "")
		)
		(fill yes
			(thermal_gap 0.5)
			(thermal_bridge_width 0.5)
			(island_removal_mode 0)
		)
		(polygon
			(pts
				(arc
					(start 84.03717 -434.48986)
					(mid 83.262978 -434.48986)
					(end 84.03717 -434.48986)
				)
			)
		)
	)
	(zone
		(layers "B.Cu" "In15.Cu")
		(hatch none 0.5)
		(connect_pads
			(clearance 0)
		)
		(min_thickness 0.25)
		(keepout
			(tracks not_allowed)
			(vias allowed)
			(pads allowed)
			(copperpour not_allowed)
			(footprints allowed)
		)
		(placement
			(enabled no)
			(sheetname "")
		)
		(fill yes
			(thermal_gap 0.5)
			(thermal_bridge_width 0.5)
			(island_removal_mode 0)
		)
		(polygon
			(pts
				(arc
					(start 48.118014 -241.535204)
					(mid 47.449994 -241.535204)
					(end 48.118014 -241.535204)
				)
			)
		)
	)
	(zone
		(layers "B.Cu" "In15.Cu")
		(hatch none 0.5)
		(connect_pads
			(clearance 0)
		)
		(min_thickness 0.25)
		(keepout
			(tracks not_allowed)
			(vias allowed)
			(pads allowed)
			(copperpour not_allowed)
			(footprints allowed)
		)
		(placement
			(enabled no)
			(sheetname "")
		)
		(fill yes
			(thermal_gap 0.5)
			(thermal_bridge_width 0.5)
			(island_removal_mode 0)
		)
		(polygon
			(pts
				(arc
					(start 97.478342 -392.429238)
					(mid 96.810322 -392.429238)
					(end 97.478342 -392.429238)
				)
			)
		)
	)
	(zone
		(layers "B.Cu" "In15.Cu")
		(hatch none 0.5)
		(connect_pads
			(clearance 0)
		)
		(min_thickness 0.25)
		(keepout
			(tracks not_allowed)
			(vias allowed)
			(pads allowed)
			(copperpour not_allowed)
			(footprints allowed)
		)
		(placement
			(enabled no)
			(sheetname "")
		)
		(fill yes
			(thermal_gap 0.5)
			(thermal_bridge_width 0.5)
			(island_removal_mode 0)
		)
		(polygon
			(pts
				(arc
					(start 172.30598 -293.38524)
					(mid 171.63796 -293.38524)
					(end 172.30598 -293.38524)
				)
			)
		)
	)
	(zone
		(layers "B.Cu" "In15.Cu")
		(hatch none 0.5)
		(connect_pads
			(clearance 0)
		)
		(min_thickness 0.25)
		(keepout
			(tracks not_allowed)
			(vias allowed)
			(pads allowed)
			(copperpour not_allowed)
			(footprints allowed)
		)
		(placement
			(enabled no)
			(sheetname "")
		)
		(fill yes
			(thermal_gap 0.5)
			(thermal_bridge_width 0.5)
			(island_removal_mode 0)
		)
		(polygon
			(pts
				(arc
					(start 383.99974 -227.474272)
					(mid 383.36982 -227.474272)
					(end 383.99974 -227.474272)
				)
			)
		)
	)
	(zone
		(layers "B.Cu" "In15.Cu")
		(hatch none 0.5)
		(connect_pads
			(clearance 0)
		)
		(min_thickness 0.25)
		(keepout
			(tracks not_allowed)
			(vias allowed)
			(pads allowed)
			(copperpour not_allowed)
			(footprints allowed)
		)
		(placement
			(enabled no)
			(sheetname "")
		)
		(fill yes
			(thermal_gap 0.5)
			(thermal_bridge_width 0.5)
			(island_removal_mode 0)
		)
		(polygon
			(pts
				(arc
					(start 334.036924 -435.489858)
					(mid 333.262732 -435.489858)
					(end 334.036924 -435.489858)
				)
			)
		)
	)
	(zone
		(layers "B.Cu" "In15.Cu")
		(hatch none 0.5)
		(connect_pads
			(clearance 0)
		)
		(min_thickness 0.25)
		(keepout
			(tracks not_allowed)
			(vias allowed)
			(pads allowed)
			(copperpour not_allowed)
			(footprints allowed)
		)
		(placement
			(enabled no)
			(sheetname "")
		)
		(fill yes
			(thermal_gap 0.5)
			(thermal_bridge_width 0.5)
			(island_removal_mode 0)
		)
		(polygon
			(pts
				(arc
					(start 101.11613 -271.656302)
					(mid 100.48621 -271.656302)
					(end 101.11613 -271.656302)
				)
			)
		)
	)
	(zone
		(layers "B.Cu" "In15.Cu")
		(hatch none 0.5)
		(connect_pads
			(clearance 0)
		)
		(min_thickness 0.25)
		(keepout
			(tracks not_allowed)
			(vias allowed)
			(pads allowed)
			(copperpour not_allowed)
			(footprints allowed)
		)
		(placement
			(enabled no)
			(sheetname "")
		)
		(fill yes
			(thermal_gap 0.5)
			(thermal_bridge_width 0.5)
			(island_removal_mode 0)
		)
		(polygon
			(pts
				(arc
					(start 87.655908 -239.624362)
					(mid 87.025988 -239.624362)
					(end 87.655908 -239.624362)
				)
			)
		)
	)
	(zone
		(layers "B.Cu" "In15.Cu")
		(hatch none 0.5)
		(connect_pads
			(clearance 0)
		)
		(min_thickness 0.25)
		(keepout
			(tracks not_allowed)
			(vias allowed)
			(pads allowed)
			(copperpour not_allowed)
			(footprints allowed)
		)
		(placement
			(enabled no)
			(sheetname "")
		)
		(fill yes
			(thermal_gap 0.5)
			(thermal_bridge_width 0.5)
			(island_removal_mode 0)
		)
		(polygon
			(pts
				(arc
					(start 49.306226 -385.31038)
					(mid 48.676306 -385.31038)
					(end 49.306226 -385.31038)
				)
			)
		)
	)
	(zone
		(layers "B.Cu" "In15.Cu")
		(hatch none 0.5)
		(connect_pads
			(clearance 0)
		)
		(min_thickness 0.25)
		(keepout
			(tracks not_allowed)
			(vias allowed)
			(pads allowed)
			(copperpour not_allowed)
			(footprints allowed)
		)
		(placement
			(enabled no)
			(sheetname "")
		)
		(fill yes
			(thermal_gap 0.5)
			(thermal_bridge_width 0.5)
			(island_removal_mode 0)
		)
		(polygon
			(pts
				(arc
					(start 119.90959 -270.03629)
					(mid 119.27967 -270.03629)
					(end 119.90959 -270.03629)
				)
			)
		)
	)
	(zone
		(layers "B.Cu" "In15.Cu")
		(hatch none 0.5)
		(connect_pads
			(clearance 0)
		)
		(min_thickness 0.25)
		(keepout
			(tracks not_allowed)
			(vias allowed)
			(pads allowed)
			(copperpour not_allowed)
			(footprints allowed)
		)
		(placement
			(enabled no)
			(sheetname "")
		)
		(fill yes
			(thermal_gap 0.5)
			(thermal_bridge_width 0.5)
			(island_removal_mode 0)
		)
		(polygon
			(pts
				(arc
					(start 52.218082 -312.935366)
					(mid 51.550062 -312.935366)
					(end 52.218082 -312.935366)
				)
			)
		)
	)
	(zone
		(layers "B.Cu" "In15.Cu")
		(hatch none 0.5)
		(connect_pads
			(clearance 0)
		)
		(min_thickness 0.25)
		(keepout
			(tracks not_allowed)
			(vias allowed)
			(pads allowed)
			(copperpour not_allowed)
			(footprints allowed)
		)
		(placement
			(enabled no)
			(sheetname "")
		)
		(fill yes
			(thermal_gap 0.5)
			(thermal_bridge_width 0.5)
			(island_removal_mode 0)
		)
		(polygon
			(pts
				(arc
					(start 300.15815 -262.785098)
					(mid 299.49013 -262.785098)
					(end 300.15815 -262.785098)
				)
			)
		)
	)
	(zone
		(layers "B.Cu" "In15.Cu")
		(hatch none 0.5)
		(connect_pads
			(clearance 0)
		)
		(min_thickness 0.25)
		(keepout
			(tracks not_allowed)
			(vias allowed)
			(pads allowed)
			(copperpour not_allowed)
			(footprints allowed)
		)
		(placement
			(enabled no)
			(sheetname "")
		)
		(fill yes
			(thermal_gap 0.5)
			(thermal_bridge_width 0.5)
			(island_removal_mode 0)
		)
		(polygon
			(pts
				(arc
					(start 335.595976 -236.384084)
					(mid 334.966056 -236.384084)
					(end 335.595976 -236.384084)
				)
			)
		)
	)
	(zone
		(layers "B.Cu" "In15.Cu")
		(hatch none 0.5)
		(connect_pads
			(clearance 0)
		)
		(min_thickness 0.25)
		(keepout
			(tracks not_allowed)
			(vias allowed)
			(pads allowed)
			(copperpour not_allowed)
			(footprints allowed)
		)
		(placement
			(enabled no)
			(sheetname "")
		)
		(fill yes
			(thermal_gap 0.5)
			(thermal_bridge_width 0.5)
			(island_removal_mode 0)
		)
		(polygon
			(pts
				(arc
					(start 48.118014 -218.585288)
					(mid 47.449994 -218.585288)
					(end 48.118014 -218.585288)
				)
			)
		)
	)
	(zone
		(layers "B.Cu" "In15.Cu")
		(hatch none 0.5)
		(connect_pads
			(clearance 0)
		)
		(min_thickness 0.25)
		(keepout
			(tracks not_allowed)
			(vias allowed)
			(pads allowed)
			(copperpour not_allowed)
			(footprints allowed)
		)
		(placement
			(enabled no)
			(sheetname "")
		)
		(fill yes
			(thermal_gap 0.5)
			(thermal_bridge_width 0.5)
			(island_removal_mode 0)
		)
		(polygon
			(pts
				(arc
					(start 48.118014 -301.035212)
					(mid 47.449994 -301.035212)
					(end 48.118014 -301.035212)
				)
			)
		)
	)
	(zone
		(layers "B.Cu" "In15.Cu")
		(hatch none 0.5)
		(connect_pads
			(clearance 0)
		)
		(min_thickness 0.25)
		(keepout
			(tracks not_allowed)
			(vias allowed)
			(pads allowed)
			(copperpour not_allowed)
			(footprints allowed)
		)
		(placement
			(enabled no)
			(sheetname "")
		)
		(fill yes
			(thermal_gap 0.5)
			(thermal_bridge_width 0.5)
			(island_removal_mode 0)
		)
		(polygon
			(pts
				(arc
					(start 89.36609 -283.806392)
					(mid 88.73617 -283.806392)
					(end 89.36609 -283.806392)
				)
			)
		)
	)
	(zone
		(layers "B.Cu" "In15.Cu")
		(hatch none 0.5)
		(connect_pads
			(clearance 0)
		)
		(min_thickness 0.25)
		(keepout
			(tracks not_allowed)
			(vias allowed)
			(pads allowed)
			(copperpour not_allowed)
			(footprints allowed)
		)
		(placement
			(enabled no)
			(sheetname "")
		)
		(fill yes
			(thermal_gap 0.5)
			(thermal_bridge_width 0.5)
			(island_removal_mode 0)
		)
		(polygon
			(pts
				(arc
					(start 114.4397 -242.05438)
					(mid 113.80978 -242.05438)
					(end 114.4397 -242.05438)
				)
			)
		)
	)
	(zone
		(layers "B.Cu" "In15.Cu")
		(hatch none 0.5)
		(connect_pads
			(clearance 0)
		)
		(min_thickness 0.25)
		(keepout
			(tracks not_allowed)
			(vias allowed)
			(pads allowed)
			(copperpour not_allowed)
			(footprints allowed)
		)
		(placement
			(enabled no)
			(sheetname "")
		)
		(fill yes
			(thermal_gap 0.5)
			(thermal_bridge_width 0.5)
			(island_removal_mode 0)
		)
		(polygon
			(pts
				(arc
					(start 136.359646 -264.366248)
					(mid 135.729726 -264.366248)
					(end 136.359646 -264.366248)
				)
			)
		)
	)
	(zone
		(layers "B.Cu" "In15.Cu")
		(hatch none 0.5)
		(connect_pads
			(clearance 0)
		)
		(min_thickness 0.25)
		(keepout
			(tracks not_allowed)
			(vias allowed)
			(pads allowed)
			(copperpour not_allowed)
			(footprints allowed)
		)
		(placement
			(enabled no)
			(sheetname "")
		)
		(fill yes
			(thermal_gap 0.5)
			(thermal_bridge_width 0.5)
			(island_removal_mode 0)
		)
		(polygon
			(pts
				(arc
					(start 374.429782 -273.27606)
					(mid 373.799862 -273.27606)
					(end 374.429782 -273.27606)
				)
			)
		)
	)
	(zone
		(layers "B.Cu" "In15.Cu")
		(hatch none 0.5)
		(connect_pads
			(clearance 0)
		)
		(min_thickness 0.25)
		(keepout
			(tracks not_allowed)
			(vias allowed)
			(pads allowed)
			(copperpour not_allowed)
			(footprints allowed)
		)
		(placement
			(enabled no)
			(sheetname "")
		)
		(fill yes
			(thermal_gap 0.5)
			(thermal_bridge_width 0.5)
			(island_removal_mode 0)
		)
		(polygon
			(pts
				(arc
					(start 136.359646 -291.906198)
					(mid 135.729726 -291.906198)
					(end 136.359646 -291.906198)
				)
			)
		)
	)
	(zone
		(layers "B.Cu" "In15.Cu")
		(hatch none 0.5)
		(connect_pads
			(clearance 0)
		)
		(min_thickness 0.25)
		(keepout
			(tracks not_allowed)
			(vias allowed)
			(pads allowed)
			(copperpour not_allowed)
			(footprints allowed)
		)
		(placement
			(enabled no)
			(sheetname "")
		)
		(fill yes
			(thermal_gap 0.5)
			(thermal_bridge_width 0.5)
			(island_removal_mode 0)
		)
		(polygon
			(pts
				(arc
					(start 384.299714 -269.22603)
					(mid 383.669794 -269.22603)
					(end 384.299714 -269.22603)
				)
			)
		)
	)
	(zone
		(layers "B.Cu" "In15.Cu")
		(hatch none 0.5)
		(connect_pads
			(clearance 0)
		)
		(min_thickness 0.25)
		(keepout
			(tracks not_allowed)
			(vias allowed)
			(pads allowed)
			(copperpour not_allowed)
			(footprints allowed)
		)
		(placement
			(enabled no)
			(sheetname "")
		)
		(fill yes
			(thermal_gap 0.5)
			(thermal_bridge_width 0.5)
			(island_removal_mode 0)
		)
		(polygon
			(pts
				(arc
					(start 48.118014 -226.23526)
					(mid 47.449994 -226.23526)
					(end 48.118014 -226.23526)
				)
			)
		)
	)
	(zone
		(layers "B.Cu" "In15.Cu")
		(hatch none 0.5)
		(connect_pads
			(clearance 0)
		)
		(min_thickness 0.25)
		(keepout
			(tracks not_allowed)
			(vias allowed)
			(pads allowed)
			(copperpour not_allowed)
			(footprints allowed)
		)
		(placement
			(enabled no)
			(sheetname "")
		)
		(fill yes
			(thermal_gap 0.5)
			(thermal_bridge_width 0.5)
			(island_removal_mode 0)
		)
		(polygon
			(pts
				(arc
					(start 87.955882 -281.376374)
					(mid 87.325962 -281.376374)
					(end 87.955882 -281.376374)
				)
			)
		)
	)
	(zone
		(layers "B.Cu" "In15.Cu")
		(hatch none 0.5)
		(connect_pads
			(clearance 0)
		)
		(min_thickness 0.25)
		(keepout
			(tracks not_allowed)
			(vias allowed)
			(pads allowed)
			(copperpour not_allowed)
			(footprints allowed)
		)
		(placement
			(enabled no)
			(sheetname "")
		)
		(fill yes
			(thermal_gap 0.5)
			(thermal_bridge_width 0.5)
			(island_removal_mode 0)
		)
		(polygon
			(pts
				(arc
					(start 312.905902 -394.385292)
					(mid 312.275982 -394.385292)
					(end 312.905902 -394.385292)
				)
			)
		)
	)
	(zone
		(layers "B.Cu" "In15.Cu")
		(hatch none 0.5)
		(connect_pads
			(clearance 0)
		)
		(min_thickness 0.25)
		(keepout
			(tracks not_allowed)
			(vias allowed)
			(pads allowed)
			(copperpour not_allowed)
			(footprints allowed)
		)
		(placement
			(enabled no)
			(sheetname "")
		)
		(fill yes
			(thermal_gap 0.5)
			(thermal_bridge_width 0.5)
			(island_removal_mode 0)
		)
		(polygon
			(pts
				(arc
					(start 135.119618 -229.094538)
					(mid 134.489698 -229.094538)
					(end 135.119618 -229.094538)
				)
			)
		)
	)
	(zone
		(layers "B.Cu" "In15.Cu")
		(hatch none 0.5)
		(connect_pads
			(clearance 0)
		)
		(min_thickness 0.25)
		(keepout
			(tracks not_allowed)
			(vias allowed)
			(pads allowed)
			(copperpour not_allowed)
			(footprints allowed)
		)
		(placement
			(enabled no)
			(sheetname "")
		)
		(fill yes
			(thermal_gap 0.5)
			(thermal_bridge_width 0.5)
			(island_removal_mode 0)
		)
		(polygon
			(pts
				(arc
					(start 52.218082 -315.485272)
					(mid 51.550062 -315.485272)
					(end 52.218082 -315.485272)
				)
			)
		)
	)
	(zone
		(layers "B.Cu" "In15.Cu")
		(hatch none 0.5)
		(connect_pads
			(clearance 0)
		)
		(min_thickness 0.25)
		(keepout
			(tracks not_allowed)
			(vias allowed)
			(pads allowed)
			(copperpour not_allowed)
			(footprints allowed)
		)
		(placement
			(enabled no)
			(sheetname "")
		)
		(fill yes
			(thermal_gap 0.5)
			(thermal_bridge_width 0.5)
			(island_removal_mode 0)
		)
		(polygon
			(pts
				(arc
					(start 384.299714 -280.566114)
					(mid 383.669794 -280.566114)
					(end 384.299714 -280.566114)
				)
			)
		)
	)
	(zone
		(layers "B.Cu" "In15.Cu")
		(hatch none 0.5)
		(connect_pads
			(clearance 0)
		)
		(min_thickness 0.25)
		(keepout
			(tracks not_allowed)
			(vias allowed)
			(pads allowed)
			(copperpour not_allowed)
			(footprints allowed)
		)
		(placement
			(enabled no)
			(sheetname "")
		)
		(fill yes
			(thermal_gap 0.5)
			(thermal_bridge_width 0.5)
			(island_removal_mode 0)
		)
		(polygon
			(pts
				(arc
					(start 373.489728 -273.27606)
					(mid 372.859808 -273.27606)
					(end 373.489728 -273.27606)
				)
			)
		)
	)
	(zone
		(layers "B.Cu" "In15.Cu")
		(hatch none 0.5)
		(connect_pads
			(clearance 0)
		)
		(min_thickness 0.25)
		(keepout
			(tracks not_allowed)
			(vias allowed)
			(pads allowed)
			(copperpour not_allowed)
			(footprints allowed)
		)
		(placement
			(enabled no)
			(sheetname "")
		)
		(fill yes
			(thermal_gap 0.5)
			(thermal_bridge_width 0.5)
			(island_removal_mode 0)
		)
		(polygon
			(pts
				(arc
					(start 362.679742 -269.22603)
					(mid 362.049822 -269.22603)
					(end 362.679742 -269.22603)
				)
			)
		)
	)
	(zone
		(layers "B.Cu" "In15.Cu")
		(hatch none 0.5)
		(connect_pads
			(clearance 0)
		)
		(min_thickness 0.25)
		(keepout
			(tracks not_allowed)
			(vias allowed)
			(pads allowed)
			(copperpour not_allowed)
			(footprints allowed)
		)
		(placement
			(enabled no)
			(sheetname "")
		)
		(fill yes
			(thermal_gap 0.5)
			(thermal_bridge_width 0.5)
			(island_removal_mode 0)
		)
		(polygon
			(pts
				(arc
					(start 87.955882 -287.856422)
					(mid 87.325962 -287.856422)
					(end 87.955882 -287.856422)
				)
			)
		)
	)
	(zone
		(layers "B.Cu" "In15.Cu")
		(hatch none 0.5)
		(connect_pads
			(clearance 0)
		)
		(min_thickness 0.25)
		(keepout
			(tracks not_allowed)
			(vias allowed)
			(pads allowed)
			(copperpour not_allowed)
			(footprints allowed)
		)
		(placement
			(enabled no)
			(sheetname "")
		)
		(fill yes
			(thermal_gap 0.5)
			(thermal_bridge_width 0.5)
			(island_removal_mode 0)
		)
		(polygon
			(pts
				(arc
					(start 365.02975 -273.27606)
					(mid 364.39983 -273.27606)
					(end 365.02975 -273.27606)
				)
			)
		)
	)
	(zone
		(layers "B.Cu" "In15.Cu")
		(hatch none 0.5)
		(connect_pads
			(clearance 0)
		)
		(min_thickness 0.25)
		(keepout
			(tracks not_allowed)
			(vias allowed)
			(pads allowed)
			(copperpour not_allowed)
			(footprints allowed)
		)
		(placement
			(enabled no)
			(sheetname "")
		)
		(fill yes
			(thermal_gap 0.5)
			(thermal_bridge_width 0.5)
			(island_removal_mode 0)
		)
		(polygon
			(pts
				(arc
					(start 56.90616 -386.003292)
					(mid 56.27624 -386.003292)
					(end 56.90616 -386.003292)
				)
			)
		)
	)
	(zone
		(layers "B.Cu" "In15.Cu")
		(hatch none 0.5)
		(connect_pads
			(clearance 0)
		)
		(min_thickness 0.25)
		(keepout
			(tracks not_allowed)
			(vias allowed)
			(pads allowed)
			(copperpour not_allowed)
			(footprints allowed)
		)
		(placement
			(enabled no)
			(sheetname "")
		)
		(fill yes
			(thermal_gap 0.5)
			(thermal_bridge_width 0.5)
			(island_removal_mode 0)
		)
		(polygon
			(pts
				(arc
					(start 120.849644 -273.276314)
					(mid 120.219724 -273.276314)
					(end 120.849644 -273.276314)
				)
			)
		)
	)
	(zone
		(layers "B.Cu" "In15.Cu")
		(hatch none 0.5)
		(connect_pads
			(clearance 0)
		)
		(min_thickness 0.25)
		(keepout
			(tracks not_allowed)
			(vias allowed)
			(pads allowed)
			(copperpour not_allowed)
			(footprints allowed)
		)
		(placement
			(enabled no)
			(sheetname "")
		)
		(fill yes
			(thermal_gap 0.5)
			(thermal_bridge_width 0.5)
			(island_removal_mode 0)
		)
		(polygon
			(pts
				(arc
					(start 89.066116 -248.534428)
					(mid 88.436196 -248.534428)
					(end 89.066116 -248.534428)
				)
			)
		)
	)
	(zone
		(layers "B.Cu" "In15.Cu")
		(hatch none 0.5)
		(connect_pads
			(clearance 0)
		)
		(min_thickness 0.25)
		(keepout
			(tracks not_allowed)
			(vias allowed)
			(pads allowed)
			(copperpour not_allowed)
			(footprints allowed)
		)
		(placement
			(enabled no)
			(sheetname "")
		)
		(fill yes
			(thermal_gap 0.5)
			(thermal_bridge_width 0.5)
			(island_removal_mode 0)
		)
		(polygon
			(pts
				(arc
					(start 420.246048 -297.635168)
					(mid 419.578028 -297.635168)
					(end 420.246048 -297.635168)
				)
			)
		)
	)
	(zone
		(layers "B.Cu" "In15.Cu")
		(hatch none 0.5)
		(connect_pads
			(clearance 0)
		)
		(min_thickness 0.25)
		(keepout
			(tracks not_allowed)
			(vias allowed)
			(pads allowed)
			(copperpour not_allowed)
			(footprints allowed)
		)
		(placement
			(enabled no)
			(sheetname "")
		)
		(fill yes
			(thermal_gap 0.5)
			(thermal_bridge_width 0.5)
			(island_removal_mode 0)
		)
		(polygon
			(pts
				(arc
					(start 134.649718 -241.244374)
					(mid 134.019798 -241.244374)
					(end 134.649718 -241.244374)
				)
			)
		)
	)
	(zone
		(layers "B.Cu" "In15.Cu")
		(hatch none 0.5)
		(connect_pads
			(clearance 0)
		)
		(min_thickness 0.25)
		(keepout
			(tracks not_allowed)
			(vias allowed)
			(pads allowed)
			(copperpour not_allowed)
			(footprints allowed)
		)
		(placement
			(enabled no)
			(sheetname "")
		)
		(fill yes
			(thermal_gap 0.5)
			(thermal_bridge_width 0.5)
			(island_removal_mode 0)
		)
		(polygon
			(pts
				(arc
					(start 176.406048 -307.8353)
					(mid 175.738028 -307.8353)
					(end 176.406048 -307.8353)
				)
			)
		)
	)
	(zone
		(layers "B.Cu" "In15.Cu")
		(hatch none 0.5)
		(connect_pads
			(clearance 0)
		)
		(min_thickness 0.25)
		(keepout
			(tracks not_allowed)
			(vias allowed)
			(pads allowed)
			(copperpour not_allowed)
			(footprints allowed)
		)
		(placement
			(enabled no)
			(sheetname "")
		)
		(fill yes
			(thermal_gap 0.5)
			(thermal_bridge_width 0.5)
			(island_removal_mode 0)
		)
		(polygon
			(pts
				(arc
					(start 382.589786 -231.524048)
					(mid 381.959866 -231.524048)
					(end 382.589786 -231.524048)
				)
			)
		)
	)
	(zone
		(layers "B.Cu" "In15.Cu")
		(hatch none 0.5)
		(connect_pads
			(clearance 0)
		)
		(min_thickness 0.25)
		(keepout
			(tracks not_allowed)
			(vias allowed)
			(pads allowed)
			(copperpour not_allowed)
			(footprints allowed)
		)
		(placement
			(enabled no)
			(sheetname "")
		)
		(fill yes
			(thermal_gap 0.5)
			(thermal_bridge_width 0.5)
			(island_removal_mode 0)
		)
		(polygon
			(pts
				(arc
					(start 337.877912 -401.674838)
					(mid 337.209892 -401.674838)
					(end 337.877912 -401.674838)
				)
			)
		)
	)
	(zone
		(layers "B.Cu" "In15.Cu")
		(hatch none 0.5)
		(connect_pads
			(clearance 0)
		)
		(min_thickness 0.25)
		(keepout
			(tracks not_allowed)
			(vias allowed)
			(pads allowed)
			(copperpour not_allowed)
			(footprints allowed)
		)
		(placement
			(enabled no)
			(sheetname "")
		)
		(fill yes
			(thermal_gap 0.5)
			(thermal_bridge_width 0.5)
			(island_removal_mode 0)
		)
		(polygon
			(pts
				(arc
					(start 134.649718 -239.624362)
					(mid 134.019798 -239.624362)
					(end 134.649718 -239.624362)
				)
			)
		)
	)
	(zone
		(layers "B.Cu" "In15.Cu")
		(hatch none 0.5)
		(connect_pads
			(clearance 0)
		)
		(min_thickness 0.25)
		(keepout
			(tracks not_allowed)
			(vias allowed)
			(pads allowed)
			(copperpour not_allowed)
			(footprints allowed)
		)
		(placement
			(enabled no)
			(sheetname "")
		)
		(fill yes
			(thermal_gap 0.5)
			(thermal_bridge_width 0.5)
			(island_removal_mode 0)
		)
		(polygon
			(pts
				(arc
					(start 296.058082 -267.035026)
					(mid 295.390062 -267.035026)
					(end 296.058082 -267.035026)
				)
			)
		)
	)
	(zone
		(layers "B.Cu" "In15.Cu")
		(hatch none 0.5)
		(connect_pads
			(clearance 0)
		)
		(min_thickness 0.25)
		(keepout
			(tracks not_allowed)
			(vias allowed)
			(pads allowed)
			(copperpour not_allowed)
			(footprints allowed)
		)
		(placement
			(enabled no)
			(sheetname "")
		)
		(fill yes
			(thermal_gap 0.5)
			(thermal_bridge_width 0.5)
			(island_removal_mode 0)
		)
		(polygon
			(pts
				(arc
					(start 140.13688 -434.289962)
					(mid 139.362688 -434.289962)
					(end 140.13688 -434.289962)
				)
			)
		)
	)
	(zone
		(layers "B.Cu" "In15.Cu")
		(hatch none 0.5)
		(connect_pads
			(clearance 0)
		)
		(min_thickness 0.25)
		(keepout
			(tracks not_allowed)
			(vias allowed)
			(pads allowed)
			(copperpour not_allowed)
			(footprints allowed)
		)
		(placement
			(enabled no)
			(sheetname "")
		)
		(fill yes
			(thermal_gap 0.5)
			(thermal_bridge_width 0.5)
			(island_removal_mode 0)
		)
		(polygon
			(pts
				(arc
					(start 384.469894 -228.284278)
					(mid 383.839974 -228.284278)
					(end 384.469894 -228.284278)
				)
			)
		)
	)
	(zone
		(layers "B.Cu" "In15.Cu")
		(hatch none 0.5)
		(connect_pads
			(clearance 0)
		)
		(min_thickness 0.25)
		(keepout
			(tracks not_allowed)
			(vias allowed)
			(pads allowed)
			(copperpour not_allowed)
			(footprints allowed)
		)
		(placement
			(enabled no)
			(sheetname "")
		)
		(fill yes
			(thermal_gap 0.5)
			(thermal_bridge_width 0.5)
			(island_removal_mode 0)
		)
		(polygon
			(pts
				(arc
					(start 172.30598 -253.435358)
					(mid 171.63796 -253.435358)
					(end 172.30598 -253.435358)
				)
			)
		)
	)
	(zone
		(layers "B.Cu" "In15.Cu")
		(hatch none 0.5)
		(connect_pads
			(clearance 0)
		)
		(min_thickness 0.25)
		(keepout
			(tracks not_allowed)
			(vias allowed)
			(pads allowed)
			(copperpour not_allowed)
			(footprints allowed)
		)
		(placement
			(enabled no)
			(sheetname "")
		)
		(fill yes
			(thermal_gap 0.5)
			(thermal_bridge_width 0.5)
			(island_removal_mode 0)
		)
		(polygon
			(pts
				(arc
					(start 337.006184 -255.014222)
					(mid 336.376264 -255.014222)
					(end 337.006184 -255.014222)
				)
			)
		)
	)
	(zone
		(layers "B.Cu" "In15.Cu")
		(hatch none 0.5)
		(connect_pads
			(clearance 0)
		)
		(min_thickness 0.25)
		(keepout
			(tracks not_allowed)
			(vias allowed)
			(pads allowed)
			(copperpour not_allowed)
			(footprints allowed)
		)
		(placement
			(enabled no)
			(sheetname "")
		)
		(fill yes
			(thermal_gap 0.5)
			(thermal_bridge_width 0.5)
			(island_removal_mode 0)
		)
		(polygon
			(pts
				(arc
					(start 383.250694 -401.674838)
					(mid 382.582674 -401.674838)
					(end 383.250694 -401.674838)
				)
			)
		)
	)
	(zone
		(layers "B.Cu" "In15.Cu")
		(hatch none 0.5)
		(connect_pads
			(clearance 0)
		)
		(min_thickness 0.25)
		(keepout
			(tracks not_allowed)
			(vias allowed)
			(pads allowed)
			(copperpour not_allowed)
			(footprints allowed)
		)
		(placement
			(enabled no)
			(sheetname "")
		)
		(fill yes
			(thermal_gap 0.5)
			(thermal_bridge_width 0.5)
			(island_removal_mode 0)
		)
		(polygon
			(pts
				(arc
					(start 424.346116 -210.085178)
					(mid 423.678096 -210.085178)
					(end 424.346116 -210.085178)
				)
			)
		)
	)
	(zone
		(layers "B.Cu" "In15.Cu")
		(hatch none 0.5)
		(connect_pads
			(clearance 0)
		)
		(min_thickness 0.25)
		(keepout
			(tracks not_allowed)
			(vias allowed)
			(pads allowed)
			(copperpour not_allowed)
			(footprints allowed)
		)
		(placement
			(enabled no)
			(sheetname "")
		)
		(fill yes
			(thermal_gap 0.5)
			(thermal_bridge_width 0.5)
			(island_removal_mode 0)
		)
		(polygon
			(pts
				(arc
					(start 392.136884 -435.489858)
					(mid 391.362692 -435.489858)
					(end 392.136884 -435.489858)
				)
			)
		)
	)
	(zone
		(layers "B.Cu" "In15.Cu")
		(hatch none 0.5)
		(connect_pads
			(clearance 0)
		)
		(min_thickness 0.25)
		(keepout
			(tracks not_allowed)
			(vias allowed)
			(pads allowed)
			(copperpour not_allowed)
			(footprints allowed)
		)
		(placement
			(enabled no)
			(sheetname "")
		)
		(fill yes
			(thermal_gap 0.5)
			(thermal_bridge_width 0.5)
			(island_removal_mode 0)
		)
		(polygon
			(pts
				(arc
					(start 300.15815 -240.685066)
					(mid 299.49013 -240.685066)
					(end 300.15815 -240.685066)
				)
			)
		)
	)
	(zone
		(layers "B.Cu" "In15.Cu")
		(hatch none 0.5)
		(connect_pads
			(clearance 0)
		)
		(min_thickness 0.25)
		(keepout
			(tracks not_allowed)
			(vias allowed)
			(pads allowed)
			(copperpour not_allowed)
			(footprints allowed)
		)
		(placement
			(enabled no)
			(sheetname "")
		)
		(fill yes
			(thermal_gap 0.5)
			(thermal_bridge_width 0.5)
			(island_removal_mode 0)
		)
		(polygon
			(pts
				(arc
					(start 424.346116 -303.585118)
					(mid 423.678096 -303.585118)
					(end 424.346116 -303.585118)
				)
			)
		)
	)
	(zone
		(layers "B.Cu" "In15.Cu")
		(hatch none 0.5)
		(connect_pads
			(clearance 0)
		)
		(min_thickness 0.25)
		(keepout
			(tracks not_allowed)
			(vias allowed)
			(pads allowed)
			(copperpour not_allowed)
			(footprints allowed)
		)
		(placement
			(enabled no)
			(sheetname "")
		)
		(fill yes
			(thermal_gap 0.5)
			(thermal_bridge_width 0.5)
			(island_removal_mode 0)
		)
		(polygon
			(pts
				(arc
					(start 172.30598 -210.935316)
					(mid 171.63796 -210.935316)
					(end 172.30598 -210.935316)
				)
			)
		)
	)
	(zone
		(layers "B.Cu" "In15.Cu")
		(hatch none 0.5)
		(connect_pads
			(clearance 0)
		)
		(min_thickness 0.25)
		(keepout
			(tracks not_allowed)
			(vias allowed)
			(pads allowed)
			(copperpour not_allowed)
			(footprints allowed)
		)
		(placement
			(enabled no)
			(sheetname "")
		)
		(fill yes
			(thermal_gap 0.5)
			(thermal_bridge_width 0.5)
			(island_removal_mode 0)
		)
		(polygon
			(pts
				(arc
					(start 51.706272 -385.31038)
					(mid 51.076352 -385.31038)
					(end 51.706272 -385.31038)
				)
			)
		)
	)
	(zone
		(layers "B.Cu" "In15.Cu")
		(hatch none 0.5)
		(connect_pads
			(clearance 0)
		)
		(min_thickness 0.25)
		(keepout
			(tracks not_allowed)
			(vias allowed)
			(pads allowed)
			(copperpour not_allowed)
			(footprints allowed)
		)
		(placement
			(enabled no)
			(sheetname "")
		)
		(fill yes
			(thermal_gap 0.5)
			(thermal_bridge_width 0.5)
			(island_removal_mode 0)
		)
		(polygon
			(pts
				(arc
					(start 296.058082 -224.534984)
					(mid 295.390062 -224.534984)
					(end 296.058082 -224.534984)
				)
			)
		)
	)
	(zone
		(layers "B.Cu" "In15.Cu")
		(hatch none 0.5)
		(connect_pads
			(clearance 0)
		)
		(min_thickness 0.25)
		(keepout
			(tracks not_allowed)
			(vias allowed)
			(pads allowed)
			(copperpour not_allowed)
			(footprints allowed)
		)
		(placement
			(enabled no)
			(sheetname "")
		)
		(fill yes
			(thermal_gap 0.5)
			(thermal_bridge_width 0.5)
			(island_removal_mode 0)
		)
		(polygon
			(pts
				(arc
					(start 71.036942 -434.48986)
					(mid 70.26275 -434.48986)
					(end 71.036942 -434.48986)
				)
			)
		)
	)
	(zone
		(layers "B.Cu" "In15.Cu")
		(hatch none 0.5)
		(connect_pads
			(clearance 0)
		)
		(min_thickness 0.25)
		(keepout
			(tracks not_allowed)
			(vias allowed)
			(pads allowed)
			(copperpour not_allowed)
			(footprints allowed)
		)
		(placement
			(enabled no)
			(sheetname "")
		)
		(fill yes
			(thermal_gap 0.5)
			(thermal_bridge_width 0.5)
			(island_removal_mode 0)
		)
		(polygon
			(pts
				(arc
					(start 383.35966 -264.365994)
					(mid 382.72974 -264.365994)
					(end 383.35966 -264.365994)
				)
			)
		)
	)
	(zone
		(layers "B.Cu" "In15.Cu")
		(hatch none 0.5)
		(connect_pads
			(clearance 0)
		)
		(min_thickness 0.25)
		(keepout
			(tracks not_allowed)
			(vias allowed)
			(pads allowed)
			(copperpour not_allowed)
			(footprints allowed)
		)
		(placement
			(enabled no)
			(sheetname "")
		)
		(fill yes
			(thermal_gap 0.5)
			(thermal_bridge_width 0.5)
			(island_removal_mode 0)
		)
		(polygon
			(pts
				(arc
					(start 52.218082 -210.085432)
					(mid 51.550062 -210.085432)
					(end 52.218082 -210.085432)
				)
			)
		)
	)
	(zone
		(layers "B.Cu" "In15.Cu")
		(hatch none 0.5)
		(connect_pads
			(clearance 0)
		)
		(min_thickness 0.25)
		(keepout
			(tracks not_allowed)
			(vias allowed)
			(pads allowed)
			(copperpour not_allowed)
			(footprints allowed)
		)
		(placement
			(enabled no)
			(sheetname "")
		)
		(fill yes
			(thermal_gap 0.5)
			(thermal_bridge_width 0.5)
			(island_removal_mode 0)
		)
		(polygon
			(pts
				(arc
					(start 349.056198 -271.656048)
					(mid 348.426278 -271.656048)
					(end 349.056198 -271.656048)
				)
			)
		)
	)
	(zone
		(layers "B.Cu" "In15.Cu")
		(hatch none 0.5)
		(connect_pads
			(clearance 0)
		)
		(min_thickness 0.25)
		(keepout
			(tracks not_allowed)
			(vias allowed)
			(pads allowed)
			(copperpour not_allowed)
			(footprints allowed)
		)
		(placement
			(enabled no)
			(sheetname "")
		)
		(fill yes
			(thermal_gap 0.5)
			(thermal_bridge_width 0.5)
			(island_removal_mode 0)
		)
		(polygon
			(pts
				(arc
					(start 296.058082 -204.134974)
					(mid 295.390062 -204.134974)
					(end 296.058082 -204.134974)
				)
			)
		)
	)
	(zone
		(layers "B.Cu" "In15.Cu")
		(hatch none 0.5)
		(connect_pads
			(clearance 0)
		)
		(min_thickness 0.25)
		(keepout
			(tracks not_allowed)
			(vias allowed)
			(pads allowed)
			(copperpour not_allowed)
			(footprints allowed)
		)
		(placement
			(enabled no)
			(sheetname "")
		)
		(fill yes
			(thermal_gap 0.5)
			(thermal_bridge_width 0.5)
			(island_removal_mode 0)
		)
		(polygon
			(pts
				(arc
					(start 384.769868 -279.756108)
					(mid 384.139948 -279.756108)
					(end 384.769868 -279.756108)
				)
			)
		)
	)
	(zone
		(layers "B.Cu" "In15.Cu")
		(hatch none 0.5)
		(connect_pads
			(clearance 0)
		)
		(min_thickness 0.25)
		(keepout
			(tracks not_allowed)
			(vias allowed)
			(pads allowed)
			(copperpour not_allowed)
			(footprints allowed)
		)
		(placement
			(enabled no)
			(sheetname "")
		)
		(fill yes
			(thermal_gap 0.5)
			(thermal_bridge_width 0.5)
			(island_removal_mode 0)
		)
		(polygon
			(pts
				(arc
					(start 89.066116 -227.474526)
					(mid 88.436196 -227.474526)
					(end 89.066116 -227.474526)
				)
			)
		)
	)
	(zone
		(layers "B.Cu" "In15.Cu")
		(hatch none 0.5)
		(connect_pads
			(clearance 0)
		)
		(min_thickness 0.25)
		(keepout
			(tracks not_allowed)
			(vias allowed)
			(pads allowed)
			(copperpour not_allowed)
			(footprints allowed)
		)
		(placement
			(enabled no)
			(sheetname "")
		)
		(fill yes
			(thermal_gap 0.5)
			(thermal_bridge_width 0.5)
			(island_removal_mode 0)
		)
		(polygon
			(pts
				(arc
					(start 78.037182 -435.489858)
					(mid 77.26299 -435.489858)
					(end 78.037182 -435.489858)
				)
			)
		)
	)
	(zone
		(layers "B.Cu" "In15.Cu")
		(hatch none 0.5)
		(connect_pads
			(clearance 0)
		)
		(min_thickness 0.25)
		(keepout
			(tracks not_allowed)
			(vias allowed)
			(pads allowed)
			(copperpour not_allowed)
			(footprints allowed)
		)
		(placement
			(enabled no)
			(sheetname "")
		)
		(fill yes
			(thermal_gap 0.5)
			(thermal_bridge_width 0.5)
			(island_removal_mode 0)
		)
		(polygon
			(pts
				(arc
					(start 383.35966 -278.946102)
					(mid 382.72974 -278.946102)
					(end 383.35966 -278.946102)
				)
			)
		)
	)
	(zone
		(layers "B.Cu" "In15.Cu")
		(hatch none 0.5)
		(connect_pads
			(clearance 0)
		)
		(min_thickness 0.25)
		(keepout
			(tracks not_allowed)
			(vias allowed)
			(pads allowed)
			(copperpour not_allowed)
			(footprints allowed)
		)
		(placement
			(enabled no)
			(sheetname "")
		)
		(fill yes
			(thermal_gap 0.5)
			(thermal_bridge_width 0.5)
			(island_removal_mode 0)
		)
		(polygon
			(pts
				(arc
					(start 135.419592 -282.18638)
					(mid 134.789672 -282.18638)
					(end 135.419592 -282.18638)
				)
			)
		)
	)
	(zone
		(layers "B.Cu" "In15.Cu")
		(hatch none 0.5)
		(connect_pads
			(clearance 0)
		)
		(min_thickness 0.25)
		(keepout
			(tracks not_allowed)
			(vias allowed)
			(pads allowed)
			(copperpour not_allowed)
			(footprints allowed)
		)
		(placement
			(enabled no)
			(sheetname "")
		)
		(fill yes
			(thermal_gap 0.5)
			(thermal_bridge_width 0.5)
			(island_removal_mode 0)
		)
		(polygon
			(pts
				(arc
					(start 337.006184 -230.714296)
					(mid 336.376264 -230.714296)
					(end 337.006184 -230.714296)
				)
			)
		)
	)
	(zone
		(layers "B.Cu" "In15.Cu")
		(hatch none 0.5)
		(connect_pads
			(clearance 0)
		)
		(min_thickness 0.25)
		(keepout
			(tracks not_allowed)
			(vias allowed)
			(pads allowed)
			(copperpour not_allowed)
			(footprints allowed)
		)
		(placement
			(enabled no)
			(sheetname "")
		)
		(fill yes
			(thermal_gap 0.5)
			(thermal_bridge_width 0.5)
			(island_removal_mode 0)
		)
		(polygon
			(pts
				(arc
					(start 145.137124 -435.489858)
					(mid 144.362932 -435.489858)
					(end 145.137124 -435.489858)
				)
			)
		)
	)
	(zone
		(layers "B.Cu" "In15.Cu")
		(hatch none 0.5)
		(connect_pads
			(clearance 0)
		)
		(min_thickness 0.25)
		(keepout
			(tracks not_allowed)
			(vias allowed)
			(pads allowed)
			(copperpour not_allowed)
			(footprints allowed)
		)
		(placement
			(enabled no)
			(sheetname "")
		)
		(fill yes
			(thermal_gap 0.5)
			(thermal_bridge_width 0.5)
			(island_removal_mode 0)
		)
		(polygon
			(pts
				(arc
					(start 102.05593 -273.276314)
					(mid 101.42601 -273.276314)
					(end 102.05593 -273.276314)
				)
			)
		)
	)
	(zone
		(layers "B.Cu" "In15.Cu")
		(hatch none 0.5)
		(connect_pads
			(clearance 0)
		)
		(min_thickness 0.25)
		(keepout
			(tracks not_allowed)
			(vias allowed)
			(pads allowed)
			(copperpour not_allowed)
			(footprints allowed)
		)
		(placement
			(enabled no)
			(sheetname "")
		)
		(fill yes
			(thermal_gap 0.5)
			(thermal_bridge_width 0.5)
			(island_removal_mode 0)
		)
		(polygon
			(pts
				(arc
					(start 300.15815 -313.784996)
					(mid 299.49013 -313.784996)
					(end 300.15815 -313.784996)
				)
			)
		)
	)
	(zone
		(layers "B.Cu" "In15.Cu")
		(hatch none 0.5)
		(connect_pads
			(clearance 0)
		)
		(min_thickness 0.25)
		(keepout
			(tracks not_allowed)
			(vias allowed)
			(pads allowed)
			(copperpour not_allowed)
			(footprints allowed)
		)
		(placement
			(enabled no)
			(sheetname "")
		)
		(fill yes
			(thermal_gap 0.5)
			(thermal_bridge_width 0.5)
			(island_removal_mode 0)
		)
		(polygon
			(pts
				(arc
					(start 377.250452 -400.811238)
					(mid 376.582432 -400.811238)
					(end 377.250452 -400.811238)
				)
			)
		)
	)
	(zone
		(layers "B.Cu" "In15.Cu")
		(hatch none 0.5)
		(connect_pads
			(clearance 0)
		)
		(min_thickness 0.25)
		(keepout
			(tracks not_allowed)
			(vias allowed)
			(pads allowed)
			(copperpour not_allowed)
			(footprints allowed)
		)
		(placement
			(enabled no)
			(sheetname "")
		)
		(fill yes
			(thermal_gap 0.5)
			(thermal_bridge_width 0.5)
			(island_removal_mode 0)
		)
		(polygon
			(pts
				(arc
					(start 84.278216 -393.292838)
					(mid 83.610196 -393.292838)
					(end 84.278216 -393.292838)
				)
			)
		)
	)
	(zone
		(layers "B.Cu" "In15.Cu")
		(hatch none 0.5)
		(connect_pads
			(clearance 0)
		)
		(min_thickness 0.25)
		(keepout
			(tracks not_allowed)
			(vias allowed)
			(pads allowed)
			(copperpour not_allowed)
			(footprints allowed)
		)
		(placement
			(enabled no)
			(sheetname "")
		)
		(fill yes
			(thermal_gap 0.5)
			(thermal_bridge_width 0.5)
			(island_removal_mode 0)
		)
		(polygon
			(pts
				(arc
					(start 336.06613 -227.474272)
					(mid 335.43621 -227.474272)
					(end 336.06613 -227.474272)
				)
			)
		)
	)
	(zone
		(layers "B.Cu" "In15.Cu")
		(hatch none 0.5)
		(connect_pads
			(clearance 0)
		)
		(min_thickness 0.25)
		(keepout
			(tracks not_allowed)
			(vias allowed)
			(pads allowed)
			(copperpour not_allowed)
			(footprints allowed)
		)
		(placement
			(enabled no)
			(sheetname "")
		)
		(fill yes
			(thermal_gap 0.5)
			(thermal_bridge_width 0.5)
			(island_removal_mode 0)
		)
		(polygon
			(pts
				(arc
					(start 336.678016 -400.811238)
					(mid 336.009996 -400.811238)
					(end 336.678016 -400.811238)
				)
			)
		)
	)
	(zone
		(layers "B.Cu" "In15.Cu")
		(hatch none 0.5)
		(connect_pads
			(clearance 0)
		)
		(min_thickness 0.25)
		(keepout
			(tracks not_allowed)
			(vias allowed)
			(pads allowed)
			(copperpour not_allowed)
			(footprints allowed)
		)
		(placement
			(enabled no)
			(sheetname "")
		)
		(fill yes
			(thermal_gap 0.5)
			(thermal_bridge_width 0.5)
			(island_removal_mode 0)
		)
		(polygon
			(pts
				(arc
					(start 335.89595 -289.475926)
					(mid 335.26603 -289.475926)
					(end 335.89595 -289.475926)
				)
			)
		)
	)
	(zone
		(layers "B.Cu" "In15.Cu")
		(hatch none 0.5)
		(connect_pads
			(clearance 0)
		)
		(min_thickness 0.25)
		(keepout
			(tracks not_allowed)
			(vias allowed)
			(pads allowed)
			(copperpour not_allowed)
			(footprints allowed)
		)
		(placement
			(enabled no)
			(sheetname "")
		)
		(fill yes
			(thermal_gap 0.5)
			(thermal_bridge_width 0.5)
			(island_removal_mode 0)
		)
		(polygon
			(pts
				(arc
					(start 176.406048 -217.735404)
					(mid 175.738028 -217.735404)
					(end 176.406048 -217.735404)
				)
			)
		)
	)
	(zone
		(layers "B.Cu" "In15.Cu")
		(hatch none 0.5)
		(connect_pads
			(clearance 0)
		)
		(min_thickness 0.25)
		(keepout
			(tracks not_allowed)
			(vias allowed)
			(pads allowed)
			(copperpour not_allowed)
			(footprints allowed)
		)
		(placement
			(enabled no)
			(sheetname "")
		)
		(fill yes
			(thermal_gap 0.5)
			(thermal_bridge_width 0.5)
			(island_removal_mode 0)
		)
		(polygon
			(pts
				(arc
					(start 389.250428 -400.811238)
					(mid 388.582408 -400.811238)
					(end 389.250428 -400.811238)
				)
			)
		)
	)
	(zone
		(layers "B.Cu" "In15.Cu")
		(hatch none 0.5)
		(connect_pads
			(clearance 0)
		)
		(min_thickness 0.25)
		(keepout
			(tracks not_allowed)
			(vias allowed)
			(pads allowed)
			(copperpour not_allowed)
			(footprints allowed)
		)
		(placement
			(enabled no)
			(sheetname "")
		)
		(fill yes
			(thermal_gap 0.5)
			(thermal_bridge_width 0.5)
			(island_removal_mode 0)
		)
		(polygon
			(pts
				(arc
					(start 427.23943 -385.338828)
					(mid 426.57141 -385.338828)
					(end 427.23943 -385.338828)
				)
			)
		)
	)
	(zone
		(layers "B.Cu" "In15.Cu")
		(hatch none 0.5)
		(connect_pads
			(clearance 0)
		)
		(min_thickness 0.25)
		(keepout
			(tracks not_allowed)
			(vias allowed)
			(pads allowed)
			(copperpour not_allowed)
			(footprints allowed)
		)
		(placement
			(enabled no)
			(sheetname "")
		)
		(fill yes
			(thermal_gap 0.5)
			(thermal_bridge_width 0.5)
			(island_removal_mode 0)
		)
		(polygon
			(pts
				(arc
					(start 351.078038 -401.674838)
					(mid 350.410018 -401.674838)
					(end 351.078038 -401.674838)
				)
			)
		)
	)
	(zone
		(layers "B.Cu" "In15.Cu")
		(hatch none 0.5)
		(connect_pads
			(clearance 0)
		)
		(min_thickness 0.25)
		(keepout
			(tracks not_allowed)
			(vias allowed)
			(pads allowed)
			(copperpour not_allowed)
			(footprints allowed)
		)
		(placement
			(enabled no)
			(sheetname "")
		)
		(fill yes
			(thermal_gap 0.5)
			(thermal_bridge_width 0.5)
			(island_removal_mode 0)
		)
		(polygon
			(pts
				(arc
					(start 329.03668 -435.489858)
					(mid 328.262488 -435.489858)
					(end 329.03668 -435.489858)
				)
			)
		)
	)
	(zone
		(layers "B.Cu" "In15.Cu")
		(hatch none 0.5)
		(connect_pads
			(clearance 0)
		)
		(min_thickness 0.25)
		(keepout
			(tracks not_allowed)
			(vias allowed)
			(pads allowed)
			(copperpour not_allowed)
			(footprints allowed)
		)
		(placement
			(enabled no)
			(sheetname "")
		)
		(fill yes
			(thermal_gap 0.5)
			(thermal_bridge_width 0.5)
			(island_removal_mode 0)
		)
		(polygon
			(pts
				(arc
					(start 365.969804 -270.036036)
					(mid 365.339884 -270.036036)
					(end 365.969804 -270.036036)
				)
			)
		)
	)
	(zone
		(layers "B.Cu" "In15.Cu")
		(hatch none 0.5)
		(connect_pads
			(clearance 0)
		)
		(min_thickness 0.25)
		(keepout
			(tracks not_allowed)
			(vias allowed)
			(pads allowed)
			(copperpour not_allowed)
			(footprints allowed)
		)
		(placement
			(enabled no)
			(sheetname "")
		)
		(fill yes
			(thermal_gap 0.5)
			(thermal_bridge_width 0.5)
			(island_removal_mode 0)
		)
		(polygon
			(pts
				(arc
					(start 335.89595 -271.656048)
					(mid 335.26603 -271.656048)
					(end 335.89595 -271.656048)
				)
			)
		)
	)
	(zone
		(layers "B.Cu" "In15.Cu")
		(hatch none 0.5)
		(connect_pads
			(clearance 0)
		)
		(min_thickness 0.25)
		(keepout
			(tracks not_allowed)
			(vias allowed)
			(pads allowed)
			(copperpour not_allowed)
			(footprints allowed)
		)
		(placement
			(enabled no)
			(sheetname "")
		)
		(fill yes
			(thermal_gap 0.5)
			(thermal_bridge_width 0.5)
			(island_removal_mode 0)
		)
		(polygon
			(pts
				(arc
					(start 371.250464 -401.674838)
					(mid 370.582444 -401.674838)
					(end 371.250464 -401.674838)
				)
			)
		)
	)
	(zone
		(layers "B.Cu" "In15.Cu")
		(hatch none 0.5)
		(connect_pads
			(clearance 0)
		)
		(min_thickness 0.25)
		(keepout
			(tracks not_allowed)
			(vias allowed)
			(pads allowed)
			(copperpour not_allowed)
			(footprints allowed)
		)
		(placement
			(enabled no)
			(sheetname "")
		)
		(fill yes
			(thermal_gap 0.5)
			(thermal_bridge_width 0.5)
			(island_removal_mode 0)
		)
		(polygon
			(pts
				(arc
					(start 300.15815 -242.385088)
					(mid 299.49013 -242.385088)
					(end 300.15815 -242.385088)
				)
			)
		)
	)
	(zone
		(layers "B.Cu" "In15.Cu")
		(hatch none 0.5)
		(connect_pads
			(clearance 0)
		)
		(min_thickness 0.25)
		(keepout
			(tracks not_allowed)
			(vias allowed)
			(pads allowed)
			(copperpour not_allowed)
			(footprints allowed)
		)
		(placement
			(enabled no)
			(sheetname "")
		)
		(fill yes
			(thermal_gap 0.5)
			(thermal_bridge_width 0.5)
			(island_removal_mode 0)
		)
		(polygon
			(pts
				(arc
					(start 89.36609 -270.846296)
					(mid 88.73617 -270.846296)
					(end 89.36609 -270.846296)
				)
			)
		)
	)
	(zone
		(layers "B.Cu" "In15.Cu")
		(hatch none 0.5)
		(connect_pads
			(clearance 0)
		)
		(min_thickness 0.25)
		(keepout
			(tracks not_allowed)
			(vias allowed)
			(pads allowed)
			(copperpour not_allowed)
			(footprints allowed)
		)
		(placement
			(enabled no)
			(sheetname "")
		)
		(fill yes
			(thermal_gap 0.5)
			(thermal_bridge_width 0.5)
			(island_removal_mode 0)
		)
		(polygon
			(pts
				(arc
					(start 52.218082 -303.585372)
					(mid 51.550062 -303.585372)
					(end 52.218082 -303.585372)
				)
			)
		)
	)
	(zone
		(layers "B.Cu" "In15.Cu")
		(hatch none 0.5)
		(connect_pads
			(clearance 0)
		)
		(min_thickness 0.25)
		(keepout
			(tracks not_allowed)
			(vias allowed)
			(pads allowed)
			(copperpour not_allowed)
			(footprints allowed)
		)
		(placement
			(enabled no)
			(sheetname "")
		)
		(fill yes
			(thermal_gap 0.5)
			(thermal_bridge_width 0.5)
			(island_removal_mode 0)
		)
		(polygon
			(pts
				(arc
					(start 337.006184 -240.434114)
					(mid 336.376264 -240.434114)
					(end 337.006184 -240.434114)
				)
			)
		)
	)
	(zone
		(layers "B.Cu" "In15.Cu")
		(hatch none 0.5)
		(connect_pads
			(clearance 0)
		)
		(min_thickness 0.25)
		(keepout
			(tracks not_allowed)
			(vias allowed)
			(pads allowed)
			(copperpour not_allowed)
			(footprints allowed)
		)
		(placement
			(enabled no)
			(sheetname "")
		)
		(fill yes
			(thermal_gap 0.5)
			(thermal_bridge_width 0.5)
			(island_removal_mode 0)
		)
		(polygon
			(pts
				(arc
					(start 356.746048 -242.054126)
					(mid 356.116128 -242.054126)
					(end 356.746048 -242.054126)
				)
			)
		)
	)
	(zone
		(layers "B.Cu" "In15.Cu")
		(hatch none 0.5)
		(connect_pads
			(clearance 0)
		)
		(min_thickness 0.25)
		(keepout
			(tracks not_allowed)
			(vias allowed)
			(pads allowed)
			(copperpour not_allowed)
			(footprints allowed)
		)
		(placement
			(enabled no)
			(sheetname "")
		)
		(fill yes
			(thermal_gap 0.5)
			(thermal_bridge_width 0.5)
			(island_removal_mode 0)
		)
		(polygon
			(pts
				(arc
					(start 337.006184 -253.39421)
					(mid 336.376264 -253.39421)
					(end 337.006184 -253.39421)
				)
			)
		)
	)
	(zone
		(layers "B.Cu" "In15.Cu")
		(hatch none 0.5)
		(connect_pads
			(clearance 0)
		)
		(min_thickness 0.25)
		(keepout
			(tracks not_allowed)
			(vias allowed)
			(pads allowed)
			(copperpour not_allowed)
			(footprints allowed)
		)
		(placement
			(enabled no)
			(sheetname "")
		)
		(fill yes
			(thermal_gap 0.5)
			(thermal_bridge_width 0.5)
			(island_removal_mode 0)
		)
		(polygon
			(pts
				(arc
					(start 336.366104 -280.566114)
					(mid 335.736184 -280.566114)
					(end 336.366104 -280.566114)
				)
			)
		)
	)
	(zone
		(layers "B.Cu" "In15.Cu")
		(hatch none 0.5)
		(connect_pads
			(clearance 0)
		)
		(min_thickness 0.25)
		(keepout
			(tracks not_allowed)
			(vias allowed)
			(pads allowed)
			(copperpour not_allowed)
			(footprints allowed)
		)
		(placement
			(enabled no)
			(sheetname "")
		)
		(fill yes
			(thermal_gap 0.5)
			(thermal_bridge_width 0.5)
			(island_removal_mode 0)
		)
		(polygon
			(pts
				(arc
					(start 48.118014 -299.335444)
					(mid 47.449994 -299.335444)
					(end 48.118014 -299.335444)
				)
			)
		)
	)
	(zone
		(layers "B.Cu" "In15.Cu")
		(hatch none 0.5)
		(connect_pads
			(clearance 0)
		)
		(min_thickness 0.25)
		(keepout
			(tracks not_allowed)
			(vias allowed)
			(pads allowed)
			(copperpour not_allowed)
			(footprints allowed)
		)
		(placement
			(enabled no)
			(sheetname "")
		)
		(fill yes
			(thermal_gap 0.5)
			(thermal_bridge_width 0.5)
			(island_removal_mode 0)
		)
		(polygon
			(pts
				(arc
					(start 349.995998 -271.656048)
					(mid 349.366078 -271.656048)
					(end 349.995998 -271.656048)
				)
			)
		)
	)
	(zone
		(layers "B.Cu" "In15.Cu")
		(hatch none 0.5)
		(connect_pads
			(clearance 0)
		)
		(min_thickness 0.25)
		(keepout
			(tracks not_allowed)
			(vias allowed)
			(pads allowed)
			(copperpour not_allowed)
			(footprints allowed)
		)
		(placement
			(enabled no)
			(sheetname "")
		)
		(fill yes
			(thermal_gap 0.5)
			(thermal_bridge_width 0.5)
			(island_removal_mode 0)
		)
		(polygon
			(pts
				(arc
					(start 87.955882 -278.13635)
					(mid 87.325962 -278.13635)
					(end 87.955882 -278.13635)
				)
			)
		)
	)
	(zone
		(layers "B.Cu" "In15.Cu")
		(hatch none 0.5)
		(connect_pads
			(clearance 0)
		)
		(min_thickness 0.25)
		(keepout
			(tracks not_allowed)
			(vias allowed)
			(pads allowed)
			(copperpour not_allowed)
			(footprints allowed)
		)
		(placement
			(enabled no)
			(sheetname "")
		)
		(fill yes
			(thermal_gap 0.5)
			(thermal_bridge_width 0.5)
			(island_removal_mode 0)
		)
		(polygon
			(pts
				(arc
					(start 48.118014 -277.235412)
					(mid 47.449994 -277.235412)
					(end 48.118014 -277.235412)
				)
			)
		)
	)
	(zone
		(layers "B.Cu" "In15.Cu")
		(hatch none 0.5)
		(connect_pads
			(clearance 0)
		)
		(min_thickness 0.25)
		(keepout
			(tracks not_allowed)
			(vias allowed)
			(pads allowed)
			(copperpour not_allowed)
			(footprints allowed)
		)
		(placement
			(enabled no)
			(sheetname "")
		)
		(fill yes
			(thermal_gap 0.5)
			(thermal_bridge_width 0.5)
			(island_removal_mode 0)
		)
		(polygon
			(pts
				(arc
					(start 171.239434 -379.496828)
					(mid 170.571414 -379.496828)
					(end 171.239434 -379.496828)
				)
			)
		)
	)
	(zone
		(layers "B.Cu" "In15.Cu")
		(hatch none 0.5)
		(connect_pads
			(clearance 0)
		)
		(min_thickness 0.25)
		(keepout
			(tracks not_allowed)
			(vias allowed)
			(pads allowed)
			(copperpour not_allowed)
			(footprints allowed)
		)
		(placement
			(enabled no)
			(sheetname "")
		)
		(fill yes
			(thermal_gap 0.5)
			(thermal_bridge_width 0.5)
			(island_removal_mode 0)
		)
		(polygon
			(pts
				(arc
					(start 383.35966 -265.986006)
					(mid 382.72974 -265.986006)
					(end 383.35966 -265.986006)
				)
			)
		)
	)
	(zone
		(layers "B.Cu" "In15.Cu")
		(hatch none 0.5)
		(connect_pads
			(clearance 0)
		)
		(min_thickness 0.25)
		(keepout
			(tracks not_allowed)
			(vias allowed)
			(pads allowed)
			(copperpour not_allowed)
			(footprints allowed)
		)
		(placement
			(enabled no)
			(sheetname "")
		)
		(fill yes
			(thermal_gap 0.5)
			(thermal_bridge_width 0.5)
			(island_removal_mode 0)
		)
		(polygon
			(pts
				(arc
					(start 52.106322 -386.003292)
					(mid 51.476402 -386.003292)
					(end 52.106322 -386.003292)
				)
			)
		)
	)
	(zone
		(layers "B.Cu" "In15.Cu")
		(hatch none 0.5)
		(connect_pads
			(clearance 0)
		)
		(min_thickness 0.25)
		(keepout
			(tracks not_allowed)
			(vias allowed)
			(pads allowed)
			(copperpour not_allowed)
			(footprints allowed)
		)
		(placement
			(enabled no)
			(sheetname "")
		)
		(fill yes
			(thermal_gap 0.5)
			(thermal_bridge_width 0.5)
			(island_removal_mode 0)
		)
		(polygon
			(pts
				(arc
					(start 332.036928 -433.289964)
					(mid 331.262736 -433.289964)
					(end 332.036928 -433.289964)
				)
			)
		)
	)
	(zone
		(layers "B.Cu" "In15.Cu")
		(hatch none 0.5)
		(connect_pads
			(clearance 0)
		)
		(min_thickness 0.25)
		(keepout
			(tracks not_allowed)
			(vias allowed)
			(pads allowed)
			(copperpour not_allowed)
			(footprints allowed)
		)
		(placement
			(enabled no)
			(sheetname "")
		)
		(fill yes
			(thermal_gap 0.5)
			(thermal_bridge_width 0.5)
			(island_removal_mode 0)
		)
		(polygon
			(pts
				(arc
					(start 88.126062 -256.634488)
					(mid 87.496142 -256.634488)
					(end 88.126062 -256.634488)
				)
			)
		)
	)
	(zone
		(layers "B.Cu" "In15.Cu")
		(hatch none 0.5)
		(connect_pads
			(clearance 0)
		)
		(min_thickness 0.25)
		(keepout
			(tracks not_allowed)
			(vias allowed)
			(pads allowed)
			(copperpour not_allowed)
			(footprints allowed)
		)
		(placement
			(enabled no)
			(sheetname "")
		)
		(fill yes
			(thermal_gap 0.5)
			(thermal_bridge_width 0.5)
			(island_removal_mode 0)
		)
		(polygon
			(pts
				(arc
					(start 136.529826 -229.90429)
					(mid 135.899906 -229.90429)
					(end 136.529826 -229.90429)
				)
			)
		)
	)
	(zone
		(layers "B.Cu" "In15.Cu")
		(hatch none 0.5)
		(connect_pads
			(clearance 0)
		)
		(min_thickness 0.25)
		(keepout
			(tracks not_allowed)
			(vias allowed)
			(pads allowed)
			(copperpour not_allowed)
			(footprints allowed)
		)
		(placement
			(enabled no)
			(sheetname "")
		)
		(fill yes
			(thermal_gap 0.5)
			(thermal_bridge_width 0.5)
			(island_removal_mode 0)
		)
		(polygon
			(pts
				(arc
					(start 89.36609 -272.466308)
					(mid 88.73617 -272.466308)
					(end 89.36609 -272.466308)
				)
			)
		)
	)
	(zone
		(layers "B.Cu" "In15.Cu")
		(hatch none 0.5)
		(connect_pads
			(clearance 0)
		)
		(min_thickness 0.25)
		(keepout
			(tracks not_allowed)
			(vias allowed)
			(pads allowed)
			(copperpour not_allowed)
			(footprints allowed)
		)
		(placement
			(enabled no)
			(sheetname "")
		)
		(fill yes
			(thermal_gap 0.5)
			(thermal_bridge_width 0.5)
			(island_removal_mode 0)
		)
		(polygon
			(pts
				(arc
					(start 89.83599 -263.556242)
					(mid 89.20607 -263.556242)
					(end 89.83599 -263.556242)
				)
			)
		)
	)
	(zone
		(layers "B.Cu" "In15.Cu")
		(hatch none 0.5)
		(connect_pads
			(clearance 0)
		)
		(min_thickness 0.25)
		(keepout
			(tracks not_allowed)
			(vias allowed)
			(pads allowed)
			(copperpour not_allowed)
			(footprints allowed)
		)
		(placement
			(enabled no)
			(sheetname "")
		)
		(fill yes
			(thermal_gap 0.5)
			(thermal_bridge_width 0.5)
			(island_removal_mode 0)
		)
		(polygon
			(pts
				(arc
					(start 135.419592 -274.08632)
					(mid 134.789672 -274.08632)
					(end 135.419592 -274.08632)
				)
			)
		)
	)
	(zone
		(layers "B.Cu" "In15.Cu")
		(hatch none 0.5)
		(connect_pads
			(clearance 0)
		)
		(min_thickness 0.25)
		(keepout
			(tracks not_allowed)
			(vias allowed)
			(pads allowed)
			(copperpour not_allowed)
			(footprints allowed)
		)
		(placement
			(enabled no)
			(sheetname "")
		)
		(fill yes
			(thermal_gap 0.5)
			(thermal_bridge_width 0.5)
			(island_removal_mode 0)
		)
		(polygon
			(pts
				(arc
					(start 76.037186 -433.289964)
					(mid 75.262994 -433.289964)
					(end 76.037186 -433.289964)
				)
			)
		)
	)
	(zone
		(layers "B.Cu" "In15.Cu")
		(hatch none 0.5)
		(connect_pads
			(clearance 0)
		)
		(min_thickness 0.25)
		(keepout
			(tracks not_allowed)
			(vias allowed)
			(pads allowed)
			(copperpour not_allowed)
			(footprints allowed)
		)
		(placement
			(enabled no)
			(sheetname "")
		)
		(fill yes
			(thermal_gap 0.5)
			(thermal_bridge_width 0.5)
			(island_removal_mode 0)
		)
		(polygon
			(pts
				(arc
					(start 384.469894 -234.764072)
					(mid 383.839974 -234.764072)
					(end 384.469894 -234.764072)
				)
			)
		)
	)
	(zone
		(layers "B.Cu" "In15.Cu")
		(hatch none 0.5)
		(connect_pads
			(clearance 0)
		)
		(min_thickness 0.25)
		(keepout
			(tracks not_allowed)
			(vias allowed)
			(pads allowed)
			(copperpour not_allowed)
			(footprints allowed)
		)
		(placement
			(enabled no)
			(sheetname "")
		)
		(fill yes
			(thermal_gap 0.5)
			(thermal_bridge_width 0.5)
			(island_removal_mode 0)
		)
		(polygon
			(pts
				(arc
					(start 136.059672 -235.574332)
					(mid 135.429752 -235.574332)
					(end 136.059672 -235.574332)
				)
			)
		)
	)
	(zone
		(layers "B.Cu" "In15.Cu")
		(hatch none 0.5)
		(connect_pads
			(clearance 0)
		)
		(min_thickness 0.25)
		(keepout
			(tracks not_allowed)
			(vias allowed)
			(pads allowed)
			(copperpour not_allowed)
			(footprints allowed)
		)
		(placement
			(enabled no)
			(sheetname "")
		)
		(fill yes
			(thermal_gap 0.5)
			(thermal_bridge_width 0.5)
			(island_removal_mode 0)
		)
		(polygon
			(pts
				(arc
					(start 118.029736 -271.656302)
					(mid 117.399816 -271.656302)
					(end 118.029736 -271.656302)
				)
			)
		)
	)
	(zone
		(layers "B.Cu" "In15.Cu")
		(hatch none 0.5)
		(connect_pads
			(clearance 0)
		)
		(min_thickness 0.25)
		(keepout
			(tracks not_allowed)
			(vias allowed)
			(pads allowed)
			(copperpour not_allowed)
			(footprints allowed)
		)
		(placement
			(enabled no)
			(sheetname "")
		)
		(fill yes
			(thermal_gap 0.5)
			(thermal_bridge_width 0.5)
			(island_removal_mode 0)
		)
		(polygon
			(pts
				(arc
					(start 172.30598 -265.335258)
					(mid 171.63796 -265.335258)
					(end 172.30598 -265.335258)
				)
			)
		)
	)
	(zone
		(layers "B.Cu" "In15.Cu")
		(hatch none 0.5)
		(connect_pads
			(clearance 0)
		)
		(min_thickness 0.25)
		(keepout
			(tracks not_allowed)
			(vias allowed)
			(pads allowed)
			(copperpour not_allowed)
			(footprints allowed)
		)
		(placement
			(enabled no)
			(sheetname "")
		)
		(fill yes
			(thermal_gap 0.5)
			(thermal_bridge_width 0.5)
			(island_removal_mode 0)
		)
		(polygon
			(pts
				(arc
					(start 96.278192 -393.292838)
					(mid 95.610172 -393.292838)
					(end 96.278192 -393.292838)
				)
			)
		)
	)
	(zone
		(layers "B.Cu" "In15.Cu")
		(hatch none 0.5)
		(connect_pads
			(clearance 0)
		)
		(min_thickness 0.25)
		(keepout
			(tracks not_allowed)
			(vias allowed)
			(pads allowed)
			(copperpour not_allowed)
			(footprints allowed)
		)
		(placement
			(enabled no)
			(sheetname "")
		)
		(fill yes
			(thermal_gap 0.5)
			(thermal_bridge_width 0.5)
			(island_removal_mode 0)
		)
		(polygon
			(pts
				(arc
					(start 136.8298 -274.896326)
					(mid 136.19988 -274.896326)
					(end 136.8298 -274.896326)
				)
			)
		)
	)
	(zone
		(layers "B.Cu" "In15.Cu")
		(hatch none 0.5)
		(connect_pads
			(clearance 0)
		)
		(min_thickness 0.25)
		(keepout
			(tracks not_allowed)
			(vias allowed)
			(pads allowed)
			(copperpour not_allowed)
			(footprints allowed)
		)
		(placement
			(enabled no)
			(sheetname "")
		)
		(fill yes
			(thermal_gap 0.5)
			(thermal_bridge_width 0.5)
			(island_removal_mode 0)
		)
		(polygon
			(pts
				(arc
					(start 89.36609 -280.566368)
					(mid 88.73617 -280.566368)
					(end 89.36609 -280.566368)
				)
			)
		)
	)
	(zone
		(layers "B.Cu" "In15.Cu")
		(hatch none 0.5)
		(connect_pads
			(clearance 0)
		)
		(min_thickness 0.25)
		(keepout
			(tracks not_allowed)
			(vias allowed)
			(pads allowed)
			(copperpour not_allowed)
			(footprints allowed)
		)
		(placement
			(enabled no)
			(sheetname "")
		)
		(fill yes
			(thermal_gap 0.5)
			(thermal_bridge_width 0.5)
			(island_removal_mode 0)
		)
		(polygon
			(pts
				(arc
					(start 300.15815 -238.985044)
					(mid 299.49013 -238.985044)
					(end 300.15815 -238.985044)
				)
			)
		)
	)
	(zone
		(layers "B.Cu" "In15.Cu")
		(hatch none 0.5)
		(connect_pads
			(clearance 0)
		)
		(min_thickness 0.25)
		(keepout
			(tracks not_allowed)
			(vias allowed)
			(pads allowed)
			(copperpour not_allowed)
			(footprints allowed)
		)
		(placement
			(enabled no)
			(sheetname "")
		)
		(fill yes
			(thermal_gap 0.5)
			(thermal_bridge_width 0.5)
			(island_removal_mode 0)
		)
		(polygon
			(pts
				(arc
					(start 424.346116 -227.085144)
					(mid 423.678096 -227.085144)
					(end 424.346116 -227.085144)
				)
			)
		)
	)
	(zone
		(layers "B.Cu" "In15.Cu")
		(hatch none 0.5)
		(connect_pads
			(clearance 0)
		)
		(min_thickness 0.25)
		(keepout
			(tracks not_allowed)
			(vias allowed)
			(pads allowed)
			(copperpour not_allowed)
			(footprints allowed)
		)
		(placement
			(enabled no)
			(sheetname "")
		)
		(fill yes
			(thermal_gap 0.5)
			(thermal_bridge_width 0.5)
			(island_removal_mode 0)
		)
		(polygon
			(pts
				(arc
					(start 176.406048 -234.73537)
					(mid 175.738028 -234.73537)
					(end 176.406048 -234.73537)
				)
			)
		)
	)
	(zone
		(layers "B.Cu" "In15.Cu")
		(hatch none 0.5)
		(connect_pads
			(clearance 0)
		)
		(min_thickness 0.25)
		(keepout
			(tracks not_allowed)
			(vias allowed)
			(pads allowed)
			(copperpour not_allowed)
			(footprints allowed)
		)
		(placement
			(enabled no)
			(sheetname "")
		)
		(fill yes
			(thermal_gap 0.5)
			(thermal_bridge_width 0.5)
			(island_removal_mode 0)
		)
		(polygon
			(pts
				(arc
					(start 117.729762 -239.624362)
					(mid 117.099842 -239.624362)
					(end 117.729762 -239.624362)
				)
			)
		)
	)
	(zone
		(layers "B.Cu" "In15.Cu")
		(hatch none 0.5)
		(connect_pads
			(clearance 0)
		)
		(min_thickness 0.25)
		(keepout
			(tracks not_allowed)
			(vias allowed)
			(pads allowed)
			(copperpour not_allowed)
			(footprints allowed)
		)
		(placement
			(enabled no)
			(sheetname "")
		)
		(fill yes
			(thermal_gap 0.5)
			(thermal_bridge_width 0.5)
			(island_removal_mode 0)
		)
		(polygon
			(pts
				(arc
					(start 424.346116 -197.33514)
					(mid 423.678096 -197.33514)
					(end 424.346116 -197.33514)
				)
			)
		)
	)
	(zone
		(layers "B.Cu" "In15.Cu")
		(hatch none 0.5)
		(connect_pads
			(clearance 0)
		)
		(min_thickness 0.25)
		(keepout
			(tracks not_allowed)
			(vias allowed)
			(pads allowed)
			(copperpour not_allowed)
			(footprints allowed)
		)
		(placement
			(enabled no)
			(sheetname "")
		)
		(fill yes
			(thermal_gap 0.5)
			(thermal_bridge_width 0.5)
			(island_removal_mode 0)
		)
		(polygon
			(pts
				(arc
					(start 136.8298 -263.556242)
					(mid 136.19988 -263.556242)
					(end 136.8298 -263.556242)
				)
			)
		)
	)
	(zone
		(layers "B.Cu" "In15.Cu")
		(hatch none 0.5)
		(connect_pads
			(clearance 0)
		)
		(min_thickness 0.25)
		(keepout
			(tracks not_allowed)
			(vias allowed)
			(pads allowed)
			(copperpour not_allowed)
			(footprints allowed)
		)
		(placement
			(enabled no)
			(sheetname "")
		)
		(fill yes
			(thermal_gap 0.5)
			(thermal_bridge_width 0.5)
			(island_removal_mode 0)
		)
		(polygon
			(pts
				(arc
					(start 407.48585 -377.41733)
					(mid 406.81783 -377.41733)
					(end 407.48585 -377.41733)
				)
			)
		)
	)
	(zone
		(layers "B.Cu" "In15.Cu")
		(hatch none 0.5)
		(connect_pads
			(clearance 0)
		)
		(min_thickness 0.25)
		(keepout
			(tracks not_allowed)
			(vias allowed)
			(pads allowed)
			(copperpour not_allowed)
			(footprints allowed)
		)
		(placement
			(enabled no)
			(sheetname "")
		)
		(fill yes
			(thermal_gap 0.5)
			(thermal_bridge_width 0.5)
			(island_removal_mode 0)
		)
		(polygon
			(pts
				(arc
					(start 352.81616 -273.27606)
					(mid 352.18624 -273.27606)
					(end 352.81616 -273.27606)
				)
			)
		)
	)
	(zone
		(layers "B.Cu" "In15.Cu")
		(hatch none 0.5)
		(connect_pads
			(clearance 0)
		)
		(min_thickness 0.25)
		(keepout
			(tracks not_allowed)
			(vias allowed)
			(pads allowed)
			(copperpour not_allowed)
			(footprints allowed)
		)
		(placement
			(enabled no)
			(sheetname "")
		)
		(fill yes
			(thermal_gap 0.5)
			(thermal_bridge_width 0.5)
			(island_removal_mode 0)
		)
		(polygon
			(pts
				(arc
					(start 356.746048 -238.814102)
					(mid 356.116128 -238.814102)
					(end 356.746048 -238.814102)
				)
			)
		)
	)
	(zone
		(layers "B.Cu" "In15.Cu")
		(hatch none 0.5)
		(connect_pads
			(clearance 0)
		)
		(min_thickness 0.25)
		(keepout
			(tracks not_allowed)
			(vias allowed)
			(pads allowed)
			(copperpour not_allowed)
			(footprints allowed)
		)
		(placement
			(enabled no)
			(sheetname "")
		)
		(fill yes
			(thermal_gap 0.5)
			(thermal_bridge_width 0.5)
			(island_removal_mode 0)
		)
		(polygon
			(pts
				(arc
					(start 420.246048 -306.985162)
					(mid 419.578028 -306.985162)
					(end 420.246048 -306.985162)
				)
			)
		)
	)
	(zone
		(layers "B.Cu" "In15.Cu")
		(hatch none 0.5)
		(connect_pads
			(clearance 0)
		)
		(min_thickness 0.25)
		(keepout
			(tracks not_allowed)
			(vias allowed)
			(pads allowed)
			(copperpour not_allowed)
			(footprints allowed)
		)
		(placement
			(enabled no)
			(sheetname "")
		)
		(fill yes
			(thermal_gap 0.5)
			(thermal_bridge_width 0.5)
			(island_removal_mode 0)
		)
		(polygon
			(pts
				(arc
					(start 171.239434 -376.093228)
					(mid 170.571414 -376.093228)
					(end 171.239434 -376.093228)
				)
			)
		)
	)
	(zone
		(layers "B.Cu" "In15.Cu")
		(hatch none 0.5)
		(connect_pads
			(clearance 0)
		)
		(min_thickness 0.25)
		(keepout
			(tracks not_allowed)
			(vias allowed)
			(pads allowed)
			(copperpour not_allowed)
			(footprints allowed)
		)
		(placement
			(enabled no)
			(sheetname "")
		)
		(fill yes
			(thermal_gap 0.5)
			(thermal_bridge_width 0.5)
			(island_removal_mode 0)
		)
		(polygon
			(pts
				(arc
					(start 337.476084 -250.964192)
					(mid 336.846164 -250.964192)
					(end 337.476084 -250.964192)
				)
			)
		)
	)
	(zone
		(layers "B.Cu" "In15.Cu")
		(hatch none 0.5)
		(connect_pads
			(clearance 0)
		)
		(min_thickness 0.25)
		(keepout
			(tracks not_allowed)
			(vias allowed)
			(pads allowed)
			(copperpour not_allowed)
			(footprints allowed)
		)
		(placement
			(enabled no)
			(sheetname "")
		)
		(fill yes
			(thermal_gap 0.5)
			(thermal_bridge_width 0.5)
			(island_removal_mode 0)
		)
		(polygon
			(pts
				(arc
					(start 382.88976 -289.475926)
					(mid 382.25984 -289.475926)
					(end 382.88976 -289.475926)
				)
			)
		)
	)
	(zone
		(layers "B.Cu" "In15.Cu")
		(hatch none 0.5)
		(connect_pads
			(clearance 0)
		)
		(min_thickness 0.25)
		(keepout
			(tracks not_allowed)
			(vias allowed)
			(pads allowed)
			(copperpour not_allowed)
			(footprints allowed)
		)
		(placement
			(enabled no)
			(sheetname "")
		)
		(fill yes
			(thermal_gap 0.5)
			(thermal_bridge_width 0.5)
			(island_removal_mode 0)
		)
		(polygon
			(pts
				(arc
					(start 296.058082 -261.93496)
					(mid 295.390062 -261.93496)
					(end 296.058082 -261.93496)
				)
			)
		)
	)
	(zone
		(layers "B.Cu" "In15.Cu")
		(hatch none 0.5)
		(connect_pads
			(clearance 0)
		)
		(min_thickness 0.25)
		(keepout
			(tracks not_allowed)
			(vias allowed)
			(pads allowed)
			(copperpour not_allowed)
			(footprints allowed)
		)
		(placement
			(enabled no)
			(sheetname "")
		)
		(fill yes
			(thermal_gap 0.5)
			(thermal_bridge_width 0.5)
			(island_removal_mode 0)
		)
		(polygon
			(pts
				(arc
					(start 424.346116 -301.885096)
					(mid 423.678096 -301.885096)
					(end 424.346116 -301.885096)
				)
			)
		)
	)
	(zone
		(layers "B.Cu" "In15.Cu")
		(hatch none 0.5)
		(connect_pads
			(clearance 0)
		)
		(min_thickness 0.25)
		(keepout
			(tracks not_allowed)
			(vias allowed)
			(pads allowed)
			(copperpour not_allowed)
			(footprints allowed)
		)
		(placement
			(enabled no)
			(sheetname "")
		)
		(fill yes
			(thermal_gap 0.5)
			(thermal_bridge_width 0.5)
			(island_removal_mode 0)
		)
		(polygon
			(pts
				(arc
					(start 88.126062 -233.95432)
					(mid 87.496142 -233.95432)
					(end 88.126062 -233.95432)
				)
			)
		)
	)
	(zone
		(layers "B.Cu" "In15.Cu")
		(hatch none 0.5)
		(connect_pads
			(clearance 0)
		)
		(min_thickness 0.25)
		(keepout
			(tracks not_allowed)
			(vias allowed)
			(pads allowed)
			(copperpour not_allowed)
			(footprints allowed)
		)
		(placement
			(enabled no)
			(sheetname "")
		)
		(fill yes
			(thermal_gap 0.5)
			(thermal_bridge_width 0.5)
			(island_removal_mode 0)
		)
		(polygon
			(pts
				(arc
					(start 85.478366 -393.292838)
					(mid 84.810346 -393.292838)
					(end 85.478366 -393.292838)
				)
			)
		)
	)
	(zone
		(layers "B.Cu" "In15.Cu")
		(hatch none 0.5)
		(connect_pads
			(clearance 0)
		)
		(min_thickness 0.25)
		(keepout
			(tracks not_allowed)
			(vias allowed)
			(pads allowed)
			(copperpour not_allowed)
			(footprints allowed)
		)
		(placement
			(enabled no)
			(sheetname "")
		)
		(fill yes
			(thermal_gap 0.5)
			(thermal_bridge_width 0.5)
			(island_removal_mode 0)
		)
		(polygon
			(pts
				(arc
					(start 420.246048 -285.735014)
					(mid 419.578028 -285.735014)
					(end 420.246048 -285.735014)
				)
			)
		)
	)
	(zone
		(layers "B.Cu" "In15.Cu")
		(hatch none 0.5)
		(connect_pads
			(clearance 0)
		)
		(min_thickness 0.25)
		(keepout
			(tracks not_allowed)
			(vias allowed)
			(pads allowed)
			(copperpour not_allowed)
			(footprints allowed)
		)
		(placement
			(enabled no)
			(sheetname "")
		)
		(fill yes
			(thermal_gap 0.5)
			(thermal_bridge_width 0.5)
			(island_removal_mode 0)
		)
		(polygon
			(pts
				(arc
					(start 420.246048 -243.234972)
					(mid 419.578028 -243.234972)
					(end 420.246048 -243.234972)
				)
			)
		)
	)
	(zone
		(layers "B.Cu" "In15.Cu")
		(hatch none 0.5)
		(connect_pads
			(clearance 0)
		)
		(min_thickness 0.25)
		(keepout
			(tracks not_allowed)
			(vias allowed)
			(pads allowed)
			(copperpour not_allowed)
			(footprints allowed)
		)
		(placement
			(enabled no)
			(sheetname "")
		)
		(fill yes
			(thermal_gap 0.5)
			(thermal_bridge_width 0.5)
			(island_removal_mode 0)
		)
		(polygon
			(pts
				(arc
					(start 336.06613 -233.954066)
					(mid 335.43621 -233.954066)
					(end 336.06613 -233.954066)
				)
			)
		)
	)
	(zone
		(layers "B.Cu" "In15.Cu")
		(hatch none 0.5)
		(connect_pads
			(clearance 0)
		)
		(min_thickness 0.25)
		(keepout
			(tracks not_allowed)
			(vias allowed)
			(pads allowed)
			(copperpour not_allowed)
			(footprints allowed)
		)
		(placement
			(enabled no)
			(sheetname "")
		)
		(fill yes
			(thermal_gap 0.5)
			(thermal_bridge_width 0.5)
			(island_removal_mode 0)
		)
		(polygon
			(pts
				(arc
					(start 424.346116 -228.785166)
					(mid 423.678096 -228.785166)
					(end 424.346116 -228.785166)
				)
			)
		)
	)
	(zone
		(layers "B.Cu" "In15.Cu")
		(hatch none 0.5)
		(connect_pads
			(clearance 0)
		)
		(min_thickness 0.25)
		(keepout
			(tracks not_allowed)
			(vias allowed)
			(pads allowed)
			(copperpour not_allowed)
			(footprints allowed)
		)
		(placement
			(enabled no)
			(sheetname "")
		)
		(fill yes
			(thermal_gap 0.5)
			(thermal_bridge_width 0.5)
			(island_removal_mode 0)
		)
		(polygon
			(pts
				(arc
					(start 383.99974 -253.39421)
					(mid 383.36982 -253.39421)
					(end 383.99974 -253.39421)
				)
			)
		)
	)
	(zone
		(layers "B.Cu" "In15.Cu")
		(hatch none 0.5)
		(connect_pads
			(clearance 0)
		)
		(min_thickness 0.25)
		(keepout
			(tracks not_allowed)
			(vias allowed)
			(pads allowed)
			(copperpour not_allowed)
			(footprints allowed)
		)
		(placement
			(enabled no)
			(sheetname "")
		)
		(fill yes
			(thermal_gap 0.5)
			(thermal_bridge_width 0.5)
			(island_removal_mode 0)
		)
		(polygon
			(pts
				(arc
					(start 176.406048 -216.035382)
					(mid 175.738028 -216.035382)
					(end 176.406048 -216.035382)
				)
			)
		)
	)
	(zone
		(layers "B.Cu" "In15.Cu")
		(hatch none 0.5)
		(connect_pads
			(clearance 0)
		)
		(min_thickness 0.25)
		(keepout
			(tracks not_allowed)
			(vias allowed)
			(pads allowed)
			(copperpour not_allowed)
			(footprints allowed)
		)
		(placement
			(enabled no)
			(sheetname "")
		)
		(fill yes
			(thermal_gap 0.5)
			(thermal_bridge_width 0.5)
			(island_removal_mode 0)
		)
		(polygon
			(pts
				(arc
					(start 300.15815 -309.535068)
					(mid 299.49013 -309.535068)
					(end 300.15815 -309.535068)
				)
			)
		)
	)
	(zone
		(layers "B.Cu" "In15.Cu")
		(hatch none 0.5)
		(connect_pads
			(clearance 0)
		)
		(min_thickness 0.25)
		(keepout
			(tracks not_allowed)
			(vias allowed)
			(pads allowed)
			(copperpour not_allowed)
			(footprints allowed)
		)
		(placement
			(enabled no)
			(sheetname "")
		)
		(fill yes
			(thermal_gap 0.5)
			(thermal_bridge_width 0.5)
			(island_removal_mode 0)
		)
		(polygon
			(pts
				(arc
					(start 349.696024 -241.24412)
					(mid 349.066104 -241.24412)
					(end 349.696024 -241.24412)
				)
			)
		)
	)
	(zone
		(layers "B.Cu" "In15.Cu")
		(hatch none 0.5)
		(connect_pads
			(clearance 0)
		)
		(min_thickness 0.25)
		(keepout
			(tracks not_allowed)
			(vias allowed)
			(pads allowed)
			(copperpour not_allowed)
			(footprints allowed)
		)
		(placement
			(enabled no)
			(sheetname "")
		)
		(fill yes
			(thermal_gap 0.5)
			(thermal_bridge_width 0.5)
			(island_removal_mode 0)
		)
		(polygon
			(pts
				(arc
					(start 382.589786 -238.004096)
					(mid 381.959866 -238.004096)
					(end 382.589786 -238.004096)
				)
			)
		)
	)
	(zone
		(layers "B.Cu" "In15.Cu")
		(hatch none 0.5)
		(connect_pads
			(clearance 0)
		)
		(min_thickness 0.25)
		(keepout
			(tracks not_allowed)
			(vias allowed)
			(pads allowed)
			(copperpour not_allowed)
			(footprints allowed)
		)
		(placement
			(enabled no)
			(sheetname "")
		)
		(fill yes
			(thermal_gap 0.5)
			(thermal_bridge_width 0.5)
			(island_removal_mode 0)
		)
		(polygon
			(pts
				(arc
					(start 384.299714 -283.806138)
					(mid 383.669794 -283.806138)
					(end 384.299714 -283.806138)
				)
			)
		)
	)
	(zone
		(layers "B.Cu" "In15.Cu")
		(hatch none 0.5)
		(connect_pads
			(clearance 0)
		)
		(min_thickness 0.25)
		(keepout
			(tracks not_allowed)
			(vias allowed)
			(pads allowed)
			(copperpour not_allowed)
			(footprints allowed)
		)
		(placement
			(enabled no)
			(sheetname "")
		)
		(fill yes
			(thermal_gap 0.5)
			(thermal_bridge_width 0.5)
			(island_removal_mode 0)
		)
		(polygon
			(pts
				(arc
					(start 89.36609 -262.746236)
					(mid 88.73617 -262.746236)
					(end 89.36609 -262.746236)
				)
			)
		)
	)
	(zone
		(layers "B.Cu" "In15.Cu")
		(hatch none 0.5)
		(connect_pads
			(clearance 0)
		)
		(min_thickness 0.25)
		(keepout
			(tracks not_allowed)
			(vias allowed)
			(pads allowed)
			(copperpour not_allowed)
			(footprints allowed)
		)
		(placement
			(enabled no)
			(sheetname "")
		)
		(fill yes
			(thermal_gap 0.5)
			(thermal_bridge_width 0.5)
			(island_removal_mode 0)
		)
		(polygon
			(pts
				(arc
					(start 48.118014 -312.085228)
					(mid 47.449994 -312.085228)
					(end 48.118014 -312.085228)
				)
			)
		)
	)
	(zone
		(layers "B.Cu" "In15.Cu")
		(hatch none 0.5)
		(connect_pads
			(clearance 0)
		)
		(min_thickness 0.25)
		(keepout
			(tracks not_allowed)
			(vias allowed)
			(pads allowed)
			(copperpour not_allowed)
			(footprints allowed)
		)
		(placement
			(enabled no)
			(sheetname "")
		)
		(fill yes
			(thermal_gap 0.5)
			(thermal_bridge_width 0.5)
			(island_removal_mode 0)
		)
		(polygon
			(pts
				(arc
					(start 345.936062 -239.624108)
					(mid 345.306142 -239.624108)
					(end 345.936062 -239.624108)
				)
			)
		)
	)
	(zone
		(layers "B.Cu" "In15.Cu")
		(hatch none 0.5)
		(connect_pads
			(clearance 0)
		)
		(min_thickness 0.25)
		(keepout
			(tracks not_allowed)
			(vias allowed)
			(pads allowed)
			(copperpour not_allowed)
			(footprints allowed)
		)
		(placement
			(enabled no)
			(sheetname "")
		)
		(fill yes
			(thermal_gap 0.5)
			(thermal_bridge_width 0.5)
			(island_removal_mode 0)
		)
		(polygon
			(pts
				(arc
					(start 176.406048 -233.035348)
					(mid 175.738028 -233.035348)
					(end 176.406048 -233.035348)
				)
			)
		)
	)
	(zone
		(layers "B.Cu" "In15.Cu")
		(hatch none 0.5)
		(connect_pads
			(clearance 0)
		)
		(min_thickness 0.25)
		(keepout
			(tracks not_allowed)
			(vias allowed)
			(pads allowed)
			(copperpour not_allowed)
			(footprints allowed)
		)
		(placement
			(enabled no)
			(sheetname "")
		)
		(fill yes
			(thermal_gap 0.5)
			(thermal_bridge_width 0.5)
			(island_removal_mode 0)
		)
		(polygon
			(pts
				(arc
					(start 88.126062 -243.674392)
					(mid 87.496142 -243.674392)
					(end 88.126062 -243.674392)
				)
			)
		)
	)
	(zone
		(layers "B.Cu" "In15.Cu")
		(hatch none 0.5)
		(connect_pads
			(clearance 0)
		)
		(min_thickness 0.25)
		(keepout
			(tracks not_allowed)
			(vias allowed)
			(pads allowed)
			(copperpour not_allowed)
			(footprints allowed)
		)
		(placement
			(enabled no)
			(sheetname "")
		)
		(fill yes
			(thermal_gap 0.5)
			(thermal_bridge_width 0.5)
			(island_removal_mode 0)
		)
		(polygon
			(pts
				(arc
					(start 89.066116 -253.394464)
					(mid 88.436196 -253.394464)
					(end 89.066116 -253.394464)
				)
			)
		)
	)
	(zone
		(layers "B.Cu" "In15.Cu")
		(hatch none 0.5)
		(connect_pads
			(clearance 0)
		)
		(min_thickness 0.25)
		(keepout
			(tracks not_allowed)
			(vias allowed)
			(pads allowed)
			(copperpour not_allowed)
			(footprints allowed)
		)
		(placement
			(enabled no)
			(sheetname "")
		)
		(fill yes
			(thermal_gap 0.5)
			(thermal_bridge_width 0.5)
			(island_removal_mode 0)
		)
		(polygon
			(pts
				(arc
					(start 136.529826 -252.584458)
					(mid 135.899906 -252.584458)
					(end 136.529826 -252.584458)
				)
			)
		)
	)
	(zone
		(layers "B.Cu" "In15.Cu")
		(hatch none 0.5)
		(connect_pads
			(clearance 0)
		)
		(min_thickness 0.25)
		(keepout
			(tracks not_allowed)
			(vias allowed)
			(pads allowed)
			(copperpour not_allowed)
			(footprints allowed)
		)
		(placement
			(enabled no)
			(sheetname "")
		)
		(fill yes
			(thermal_gap 0.5)
			(thermal_bridge_width 0.5)
			(island_removal_mode 0)
		)
		(polygon
			(pts
				(arc
					(start 52.218082 -294.235378)
					(mid 51.550062 -294.235378)
					(end 52.218082 -294.235378)
				)
			)
		)
	)
	(zone
		(layers "B.Cu" "In15.Cu")
		(hatch none 0.5)
		(connect_pads
			(clearance 0)
		)
		(min_thickness 0.25)
		(keepout
			(tracks not_allowed)
			(vias allowed)
			(pads allowed)
			(copperpour not_allowed)
			(footprints allowed)
		)
		(placement
			(enabled no)
			(sheetname "")
		)
		(fill yes
			(thermal_gap 0.5)
			(thermal_bridge_width 0.5)
			(island_removal_mode 0)
		)
		(polygon
			(pts
				(arc
					(start 89.36609 -287.046162)
					(mid 88.73617 -287.046162)
					(end 89.36609 -287.046162)
				)
			)
		)
	)
	(zone
		(layers "B.Cu" "In15.Cu")
		(hatch none 0.5)
		(connect_pads
			(clearance 0)
		)
		(min_thickness 0.25)
		(keepout
			(tracks not_allowed)
			(vias allowed)
			(pads allowed)
			(copperpour not_allowed)
			(footprints allowed)
		)
		(placement
			(enabled no)
			(sheetname "")
		)
		(fill yes
			(thermal_gap 0.5)
			(thermal_bridge_width 0.5)
			(island_removal_mode 0)
		)
		(polygon
			(pts
				(arc
					(start 48.118014 -285.735268)
					(mid 47.449994 -285.735268)
					(end 48.118014 -285.735268)
				)
			)
		)
	)
	(zone
		(layers "B.Cu" "In15.Cu")
		(hatch none 0.5)
		(connect_pads
			(clearance 0)
		)
		(min_thickness 0.25)
		(keepout
			(tracks not_allowed)
			(vias allowed)
			(pads allowed)
			(copperpour not_allowed)
			(footprints allowed)
		)
		(placement
			(enabled no)
			(sheetname "")
		)
		(fill yes
			(thermal_gap 0.5)
			(thermal_bridge_width 0.5)
			(island_removal_mode 0)
		)
		(polygon
			(pts
				(arc
					(start 88.426036 -262.746236)
					(mid 87.796116 -262.746236)
					(end 88.426036 -262.746236)
				)
			)
		)
	)
	(zone
		(layers "B.Cu" "In15.Cu")
		(hatch none 0.5)
		(connect_pads
			(clearance 0)
		)
		(min_thickness 0.25)
		(keepout
			(tracks not_allowed)
			(vias allowed)
			(pads allowed)
			(copperpour not_allowed)
			(footprints allowed)
		)
		(placement
			(enabled no)
			(sheetname "")
		)
		(fill yes
			(thermal_gap 0.5)
			(thermal_bridge_width 0.5)
			(island_removal_mode 0)
		)
		(polygon
			(pts
				(arc
					(start 385.650486 -400.811238)
					(mid 384.982466 -400.811238)
					(end 385.650486 -400.811238)
				)
			)
		)
	)
	(zone
		(layers "B.Cu" "In15.Cu")
		(hatch none 0.5)
		(connect_pads
			(clearance 0)
		)
		(min_thickness 0.25)
		(keepout
			(tracks not_allowed)
			(vias allowed)
			(pads allowed)
			(copperpour not_allowed)
			(footprints allowed)
		)
		(placement
			(enabled no)
			(sheetname "")
		)
		(fill yes
			(thermal_gap 0.5)
			(thermal_bridge_width 0.5)
			(island_removal_mode 0)
		)
		(polygon
			(pts
				(arc
					(start 136.529826 -242.864386)
					(mid 135.899906 -242.864386)
					(end 136.529826 -242.864386)
				)
			)
		)
	)
	(zone
		(layers "B.Cu" "In15.Cu")
		(hatch none 0.5)
		(connect_pads
			(clearance 0)
		)
		(min_thickness 0.25)
		(keepout
			(tracks not_allowed)
			(vias allowed)
			(pads allowed)
			(copperpour not_allowed)
			(footprints allowed)
		)
		(placement
			(enabled no)
			(sheetname "")
		)
		(fill yes
			(thermal_gap 0.5)
			(thermal_bridge_width 0.5)
			(island_removal_mode 0)
		)
		(polygon
			(pts
				(arc
					(start 354.67798 -401.674838)
					(mid 354.00996 -401.674838)
					(end 354.67798 -401.674838)
				)
			)
		)
	)
	(zone
		(layers "B.Cu" "In15.Cu")
		(hatch none 0.5)
		(connect_pads
			(clearance 0)
		)
		(min_thickness 0.25)
		(keepout
			(tracks not_allowed)
			(vias allowed)
			(pads allowed)
			(copperpour not_allowed)
			(footprints allowed)
		)
		(placement
			(enabled no)
			(sheetname "")
		)
		(fill yes
			(thermal_gap 0.5)
			(thermal_bridge_width 0.5)
			(island_removal_mode 0)
		)
		(polygon
			(pts
				(arc
					(start 383.059686 -248.534174)
					(mid 382.429766 -248.534174)
					(end 383.059686 -248.534174)
				)
			)
		)
	)
	(zone
		(layers "B.Cu" "In15.Cu")
		(hatch none 0.5)
		(connect_pads
			(clearance 0)
		)
		(min_thickness 0.25)
		(keepout
			(tracks not_allowed)
			(vias allowed)
			(pads allowed)
			(copperpour not_allowed)
			(footprints allowed)
		)
		(placement
			(enabled no)
			(sheetname "")
		)
		(fill yes
			(thermal_gap 0.5)
			(thermal_bridge_width 0.5)
			(island_removal_mode 0)
		)
		(polygon
			(pts
				(arc
					(start 339.078062 -400.811238)
					(mid 338.410042 -400.811238)
					(end 339.078062 -400.811238)
				)
			)
		)
	)
	(zone
		(layers "B.Cu" "In15.Cu")
		(hatch none 0.5)
		(connect_pads
			(clearance 0)
		)
		(min_thickness 0.25)
		(keepout
			(tracks not_allowed)
			(vias allowed)
			(pads allowed)
			(copperpour not_allowed)
			(footprints allowed)
		)
		(placement
			(enabled no)
			(sheetname "")
		)
		(fill yes
			(thermal_gap 0.5)
			(thermal_bridge_width 0.5)
			(island_removal_mode 0)
		)
		(polygon
			(pts
				(arc
					(start 336.06613 -256.634234)
					(mid 335.43621 -256.634234)
					(end 336.06613 -256.634234)
				)
			)
		)
	)
	(zone
		(layers "B.Cu" "In15.Cu")
		(hatch none 0.5)
		(connect_pads
			(clearance 0)
		)
		(min_thickness 0.25)
		(keepout
			(tracks not_allowed)
			(vias allowed)
			(pads allowed)
			(copperpour not_allowed)
			(footprints allowed)
		)
		(placement
			(enabled no)
			(sheetname "")
		)
		(fill yes
			(thermal_gap 0.5)
			(thermal_bridge_width 0.5)
			(island_removal_mode 0)
		)
		(polygon
			(pts
				(arc
					(start 48.118014 -213.485222)
					(mid 47.449994 -213.485222)
					(end 48.118014 -213.485222)
				)
			)
		)
	)
	(zone
		(layers "B.Cu" "In15.Cu")
		(hatch none 0.5)
		(connect_pads
			(clearance 0)
		)
		(min_thickness 0.25)
		(keepout
			(tracks not_allowed)
			(vias allowed)
			(pads allowed)
			(copperpour not_allowed)
			(footprints allowed)
		)
		(placement
			(enabled no)
			(sheetname "")
		)
		(fill yes
			(thermal_gap 0.5)
			(thermal_bridge_width 0.5)
			(island_removal_mode 0)
		)
		(polygon
			(pts
				(arc
					(start 89.066116 -242.05438)
					(mid 88.436196 -242.05438)
					(end 89.066116 -242.05438)
				)
			)
		)
	)
	(zone
		(layers "B.Cu" "In15.Cu")
		(hatch none 0.5)
		(connect_pads
			(clearance 0)
		)
		(min_thickness 0.25)
		(keepout
			(tracks not_allowed)
			(vias allowed)
			(pads allowed)
			(copperpour not_allowed)
			(footprints allowed)
		)
		(placement
			(enabled no)
			(sheetname "")
		)
		(fill yes
			(thermal_gap 0.5)
			(thermal_bridge_width 0.5)
			(island_removal_mode 0)
		)
		(polygon
			(pts
				(arc
					(start 308.90591 -393.69238)
					(mid 308.27599 -393.69238)
					(end 308.90591 -393.69238)
				)
			)
		)
	)
	(zone
		(layers "B.Cu" "In15.Cu")
		(hatch none 0.5)
		(connect_pads
			(clearance 0)
		)
		(min_thickness 0.25)
		(keepout
			(tracks not_allowed)
			(vias allowed)
			(pads allowed)
			(copperpour not_allowed)
			(footprints allowed)
		)
		(placement
			(enabled no)
			(sheetname "")
		)
		(fill yes
			(thermal_gap 0.5)
			(thermal_bridge_width 0.5)
			(island_removal_mode 0)
		)
		(polygon
			(pts
				(arc
					(start 336.366104 -270.846042)
					(mid 335.736184 -270.846042)
					(end 336.366104 -270.846042)
				)
			)
		)
	)
	(zone
		(layers "B.Cu" "In15.Cu")
		(hatch none 0.5)
		(connect_pads
			(clearance 0)
		)
		(min_thickness 0.25)
		(keepout
			(tracks not_allowed)
			(vias allowed)
			(pads allowed)
			(copperpour not_allowed)
			(footprints allowed)
		)
		(placement
			(enabled no)
			(sheetname "")
		)
		(fill yes
			(thermal_gap 0.5)
			(thermal_bridge_width 0.5)
			(island_removal_mode 0)
		)
		(polygon
			(pts
				(arc
					(start 411.1371 -434.48986)
					(mid 410.362908 -434.48986)
					(end 411.1371 -434.48986)
				)
			)
		)
	)
	(zone
		(layers "B.Cu" "In15.Cu")
		(hatch none 0.5)
		(connect_pads
			(clearance 0)
		)
		(min_thickness 0.25)
		(keepout
			(tracks not_allowed)
			(vias allowed)
			(pads allowed)
			(copperpour not_allowed)
			(footprints allowed)
		)
		(placement
			(enabled no)
			(sheetname "")
		)
		(fill yes
			(thermal_gap 0.5)
			(thermal_bridge_width 0.5)
			(island_removal_mode 0)
		)
		(polygon
			(pts
				(arc
					(start 52.218082 -203.285344)
					(mid 51.550062 -203.285344)
					(end 52.218082 -203.285344)
				)
			)
		)
	)
	(zone
		(layers "B.Cu" "In15.Cu")
		(hatch none 0.5)
		(connect_pads
			(clearance 0)
		)
		(min_thickness 0.25)
		(keepout
			(tracks not_allowed)
			(vias allowed)
			(pads allowed)
			(copperpour not_allowed)
			(footprints allowed)
		)
		(placement
			(enabled no)
			(sheetname "")
		)
		(fill yes
			(thermal_gap 0.5)
			(thermal_bridge_width 0.5)
			(island_removal_mode 0)
		)
		(polygon
			(pts
				(arc
					(start 337.776058 -276.516084)
					(mid 337.146138 -276.516084)
					(end 337.776058 -276.516084)
				)
			)
		)
	)
	(zone
		(layers "B.Cu" "In15.Cu")
		(hatch none 0.5)
		(connect_pads
			(clearance 0)
		)
		(min_thickness 0.25)
		(keepout
			(tracks not_allowed)
			(vias allowed)
			(pads allowed)
			(copperpour not_allowed)
			(footprints allowed)
		)
		(placement
			(enabled no)
			(sheetname "")
		)
		(fill yes
			(thermal_gap 0.5)
			(thermal_bridge_width 0.5)
			(island_removal_mode 0)
		)
		(polygon
			(pts
				(arc
					(start 172.30598 -277.235412)
					(mid 171.63796 -277.235412)
					(end 172.30598 -277.235412)
				)
			)
		)
	)
	(zone
		(layers "B.Cu" "In15.Cu")
		(hatch none 0.5)
		(connect_pads
			(clearance 0)
		)
		(min_thickness 0.25)
		(keepout
			(tracks not_allowed)
			(vias allowed)
			(pads allowed)
			(copperpour not_allowed)
			(footprints allowed)
		)
		(placement
			(enabled no)
			(sheetname "")
		)
		(fill yes
			(thermal_gap 0.5)
			(thermal_bridge_width 0.5)
			(island_removal_mode 0)
		)
		(polygon
			(pts
				(arc
					(start 48.118014 -244.935248)
					(mid 47.449994 -244.935248)
					(end 48.118014 -244.935248)
				)
			)
		)
	)
	(zone
		(layers "B.Cu" "In15.Cu")
		(hatch none 0.5)
		(connect_pads
			(clearance 0)
		)
		(min_thickness 0.25)
		(keepout
			(tracks not_allowed)
			(vias allowed)
			(pads allowed)
			(copperpour not_allowed)
			(footprints allowed)
		)
		(placement
			(enabled no)
			(sheetname "")
		)
		(fill yes
			(thermal_gap 0.5)
			(thermal_bridge_width 0.5)
			(island_removal_mode 0)
		)
		(polygon
			(pts
				(arc
					(start 176.406048 -283.185362)
					(mid 175.738028 -283.185362)
					(end 176.406048 -283.185362)
				)
			)
		)
	)
	(zone
		(layers "B.Cu" "In15.Cu")
		(hatch none 0.5)
		(connect_pads
			(clearance 0)
		)
		(min_thickness 0.25)
		(keepout
			(tracks not_allowed)
			(vias allowed)
			(pads allowed)
			(copperpour not_allowed)
			(footprints allowed)
		)
		(placement
			(enabled no)
			(sheetname "")
		)
		(fill yes
			(thermal_gap 0.5)
			(thermal_bridge_width 0.5)
			(island_removal_mode 0)
		)
		(polygon
			(pts
				(arc
					(start 384.769868 -263.555988)
					(mid 384.139948 -263.555988)
					(end 384.769868 -263.555988)
				)
			)
		)
	)
	(zone
		(layers "B.Cu" "In15.Cu")
		(hatch none 0.5)
		(connect_pads
			(clearance 0)
		)
		(min_thickness 0.25)
		(keepout
			(tracks not_allowed)
			(vias allowed)
			(pads allowed)
			(copperpour not_allowed)
			(footprints allowed)
		)
		(placement
			(enabled no)
			(sheetname "")
		)
		(fill yes
			(thermal_gap 0.5)
			(thermal_bridge_width 0.5)
			(island_removal_mode 0)
		)
		(polygon
			(pts
				(arc
					(start 89.83599 -273.276314)
					(mid 89.20607 -273.276314)
					(end 89.83599 -273.276314)
				)
			)
		)
	)
	(zone
		(layers "B.Cu" "In15.Cu")
		(hatch none 0.5)
		(connect_pads
			(clearance 0)
		)
		(min_thickness 0.25)
		(keepout
			(tracks not_allowed)
			(vias allowed)
			(pads allowed)
			(copperpour not_allowed)
			(footprints allowed)
		)
		(placement
			(enabled no)
			(sheetname "")
		)
		(fill yes
			(thermal_gap 0.5)
			(thermal_bridge_width 0.5)
			(island_removal_mode 0)
		)
		(polygon
			(pts
				(arc
					(start 407.137108 -433.289964)
					(mid 406.362916 -433.289964)
					(end 407.137108 -433.289964)
				)
			)
		)
	)
	(zone
		(layers "B.Cu" "In15.Cu")
		(hatch none 0.5)
		(connect_pads
			(clearance 0)
		)
		(min_thickness 0.25)
		(keepout
			(tracks not_allowed)
			(vias allowed)
			(pads allowed)
			(copperpour not_allowed)
			(footprints allowed)
		)
		(placement
			(enabled no)
			(sheetname "")
		)
		(fill yes
			(thermal_gap 0.5)
			(thermal_bridge_width 0.5)
			(island_removal_mode 0)
		)
		(polygon
			(pts
				(arc
					(start 127.250698 -392.429238)
					(mid 126.582678 -392.429238)
					(end 127.250698 -392.429238)
				)
			)
		)
	)
	(zone
		(layers "B.Cu" "In15.Cu")
		(hatch none 0.5)
		(connect_pads
			(clearance 0)
		)
		(min_thickness 0.25)
		(keepout
			(tracks not_allowed)
			(vias allowed)
			(pads allowed)
			(copperpour not_allowed)
			(footprints allowed)
		)
		(placement
			(enabled no)
			(sheetname "")
		)
		(fill yes
			(thermal_gap 0.5)
			(thermal_bridge_width 0.5)
			(island_removal_mode 0)
		)
		(polygon
			(pts
				(arc
					(start 172.30598 -226.23526)
					(mid 171.63796 -226.23526)
					(end 172.30598 -226.23526)
				)
			)
		)
	)
	(zone
		(layers "B.Cu" "In15.Cu")
		(hatch none 0.5)
		(connect_pads
			(clearance 0)
		)
		(min_thickness 0.25)
		(keepout
			(tracks not_allowed)
			(vias allowed)
			(pads allowed)
			(copperpour not_allowed)
			(footprints allowed)
		)
		(placement
			(enabled no)
			(sheetname "")
		)
		(fill yes
			(thermal_gap 0.5)
			(thermal_bridge_width 0.5)
			(island_removal_mode 0)
		)
		(polygon
			(pts
				(arc
					(start 48.118014 -251.735336)
					(mid 47.449994 -251.735336)
					(end 48.118014 -251.735336)
				)
			)
		)
	)
	(zone
		(layers "B.Cu" "In15.Cu")
		(hatch none 0.5)
		(connect_pads
			(clearance 0)
		)
		(min_thickness 0.25)
		(keepout
			(tracks not_allowed)
			(vias allowed)
			(pads allowed)
			(copperpour not_allowed)
			(footprints allowed)
		)
		(placement
			(enabled no)
			(sheetname "")
		)
		(fill yes
			(thermal_gap 0.5)
			(thermal_bridge_width 0.5)
			(island_removal_mode 0)
		)
		(polygon
			(pts
				(arc
					(start 335.89595 -284.616144)
					(mid 335.26603 -284.616144)
					(end 335.89595 -284.616144)
				)
			)
		)
	)
	(zone
		(layers "B.Cu" "In15.Cu")
		(hatch none 0.5)
		(connect_pads
			(clearance 0)
		)
		(min_thickness 0.25)
		(keepout
			(tracks not_allowed)
			(vias allowed)
			(pads allowed)
			(copperpour not_allowed)
			(footprints allowed)
		)
		(placement
			(enabled no)
			(sheetname "")
		)
		(fill yes
			(thermal_gap 0.5)
			(thermal_bridge_width 0.5)
			(island_removal_mode 0)
		)
		(polygon
			(pts
				(arc
					(start 420.246048 -246.635016)
					(mid 419.578028 -246.635016)
					(end 420.246048 -246.635016)
				)
			)
		)
	)
	(zone
		(layers "B.Cu" "In15.Cu")
		(hatch none 0.5)
		(connect_pads
			(clearance 0)
		)
		(min_thickness 0.25)
		(keepout
			(tracks not_allowed)
			(vias allowed)
			(pads allowed)
			(copperpour not_allowed)
			(footprints allowed)
		)
		(placement
			(enabled no)
			(sheetname "")
		)
		(fill yes
			(thermal_gap 0.5)
			(thermal_bridge_width 0.5)
			(island_removal_mode 0)
		)
		(polygon
			(pts
				(arc
					(start 122.429778 -239.624362)
					(mid 121.799858 -239.624362)
					(end 122.429778 -239.624362)
				)
			)
		)
	)
	(zone
		(layers "B.Cu" "In15.Cu")
		(hatch none 0.5)
		(connect_pads
			(clearance 0)
		)
		(min_thickness 0.25)
		(keepout
			(tracks not_allowed)
			(vias allowed)
			(pads allowed)
			(copperpour not_allowed)
			(footprints allowed)
		)
		(placement
			(enabled no)
			(sheetname "")
		)
		(fill yes
			(thermal_gap 0.5)
			(thermal_bridge_width 0.5)
			(island_removal_mode 0)
		)
		(polygon
			(pts
				(arc
					(start 157.454854 -371.49913)
					(mid 156.786834 -371.49913)
					(end 157.454854 -371.49913)
				)
			)
		)
	)
	(zone
		(layers "B.Cu" "In15.Cu")
		(hatch none 0.5)
		(connect_pads
			(clearance 0)
		)
		(min_thickness 0.25)
		(keepout
			(tracks not_allowed)
			(vias allowed)
			(pads allowed)
			(copperpour not_allowed)
			(footprints allowed)
		)
		(placement
			(enabled no)
			(sheetname "")
		)
		(fill yes
			(thermal_gap 0.5)
			(thermal_bridge_width 0.5)
			(island_removal_mode 0)
		)
		(polygon
			(pts
				(arc
					(start 397.392398 -385.21386)
					(mid 396.724378 -385.21386)
					(end 397.392398 -385.21386)
				)
			)
		)
	)
	(zone
		(layers "B.Cu" "In15.Cu")
		(hatch none 0.5)
		(connect_pads
			(clearance 0)
		)
		(min_thickness 0.25)
		(keepout
			(tracks not_allowed)
			(vias allowed)
			(pads allowed)
			(copperpour not_allowed)
			(footprints allowed)
		)
		(placement
			(enabled no)
			(sheetname "")
		)
		(fill yes
			(thermal_gap 0.5)
			(thermal_bridge_width 0.5)
			(island_removal_mode 0)
		)
		(polygon
			(pts
				(arc
					(start 401.13712 -435.489858)
					(mid 400.362928 -435.489858)
					(end 401.13712 -435.489858)
				)
			)
		)
	)
	(zone
		(layers "B.Cu" "In15.Cu")
		(hatch none 0.5)
		(connect_pads
			(clearance 0)
		)
		(min_thickness 0.25)
		(keepout
			(tracks not_allowed)
			(vias allowed)
			(pads allowed)
			(copperpour not_allowed)
			(footprints allowed)
		)
		(placement
			(enabled no)
			(sheetname "")
		)
		(fill yes
			(thermal_gap 0.5)
			(thermal_bridge_width 0.5)
			(island_removal_mode 0)
		)
		(polygon
			(pts
				(arc
					(start 351.876106 -271.656048)
					(mid 351.246186 -271.656048)
					(end 351.876106 -271.656048)
				)
			)
		)
	)
	(zone
		(layers "B.Cu" "In15.Cu")
		(hatch none 0.5)
		(connect_pads
			(clearance 0)
		)
		(min_thickness 0.25)
		(keepout
			(tracks not_allowed)
			(vias allowed)
			(pads allowed)
			(copperpour not_allowed)
			(footprints allowed)
		)
		(placement
			(enabled no)
			(sheetname "")
		)
		(fill yes
			(thermal_gap 0.5)
			(thermal_bridge_width 0.5)
			(island_removal_mode 0)
		)
		(polygon
			(pts
				(arc
					(start 414.29305 -377.41733)
					(mid 413.62503 -377.41733)
					(end 414.29305 -377.41733)
				)
			)
		)
	)
	(zone
		(layers "B.Cu" "In15.Cu")
		(hatch none 0.5)
		(connect_pads
			(clearance 0)
		)
		(min_thickness 0.25)
		(keepout
			(tracks not_allowed)
			(vias allowed)
			(pads allowed)
			(copperpour not_allowed)
			(footprints allowed)
		)
		(placement
			(enabled no)
			(sheetname "")
		)
		(fill yes
			(thermal_gap 0.5)
			(thermal_bridge_width 0.5)
			(island_removal_mode 0)
		)
		(polygon
			(pts
				(arc
					(start 337.776058 -284.616144)
					(mid 337.146138 -284.616144)
					(end 337.776058 -284.616144)
				)
			)
		)
	)
	(zone
		(layers "B.Cu" "In15.Cu")
		(hatch none 0.5)
		(connect_pads
			(clearance 0)
		)
		(min_thickness 0.25)
		(keepout
			(tracks not_allowed)
			(vias allowed)
			(pads allowed)
			(copperpour not_allowed)
			(footprints allowed)
		)
		(placement
			(enabled no)
			(sheetname "")
		)
		(fill yes
			(thermal_gap 0.5)
			(thermal_bridge_width 0.5)
			(island_removal_mode 0)
		)
		(polygon
			(pts
				(arc
					(start 424.346116 -240.685066)
					(mid 423.678096 -240.685066)
					(end 424.346116 -240.685066)
				)
			)
		)
	)
	(zone
		(layers "B.Cu" "In15.Cu")
		(hatch none 0.5)
		(connect_pads
			(clearance 0)
		)
		(min_thickness 0.25)
		(keepout
			(tracks not_allowed)
			(vias allowed)
			(pads allowed)
			(copperpour not_allowed)
			(footprints allowed)
		)
		(placement
			(enabled no)
			(sheetname "")
		)
		(fill yes
			(thermal_gap 0.5)
			(thermal_bridge_width 0.5)
			(island_removal_mode 0)
		)
		(polygon
			(pts
				(arc
					(start 336.06613 -251.774198)
					(mid 335.43621 -251.774198)
					(end 336.06613 -251.774198)
				)
			)
		)
	)
	(zone
		(layers "B.Cu" "In15.Cu")
		(hatch none 0.5)
		(connect_pads
			(clearance 0)
		)
		(min_thickness 0.25)
		(keepout
			(tracks not_allowed)
			(vias allowed)
			(pads allowed)
			(copperpour not_allowed)
			(footprints allowed)
		)
		(placement
			(enabled no)
			(sheetname "")
		)
		(fill yes
			(thermal_gap 0.5)
			(thermal_bridge_width 0.5)
			(island_removal_mode 0)
		)
		(polygon
			(pts
				(arc
					(start 384.469894 -254.204216)
					(mid 383.839974 -254.204216)
					(end 384.469894 -254.204216)
				)
			)
		)
	)
	(zone
		(layers "B.Cu" "In15.Cu")
		(hatch none 0.5)
		(connect_pads
			(clearance 0)
		)
		(min_thickness 0.25)
		(keepout
			(tracks not_allowed)
			(vias allowed)
			(pads allowed)
			(copperpour not_allowed)
			(footprints allowed)
		)
		(placement
			(enabled no)
			(sheetname "")
		)
		(fill yes
			(thermal_gap 0.5)
			(thermal_bridge_width 0.5)
			(island_removal_mode 0)
		)
		(polygon
			(pts
				(arc
					(start 300.15815 -283.185108)
					(mid 299.49013 -283.185108)
					(end 300.15815 -283.185108)
				)
			)
		)
	)
	(zone
		(layers "B.Cu" "In15.Cu")
		(hatch none 0.5)
		(connect_pads
			(clearance 0)
		)
		(min_thickness 0.25)
		(keepout
			(tracks not_allowed)
			(vias allowed)
			(pads allowed)
			(copperpour not_allowed)
			(footprints allowed)
		)
		(placement
			(enabled no)
			(sheetname "")
		)
		(fill yes
			(thermal_gap 0.5)
			(thermal_bridge_width 0.5)
			(island_removal_mode 0)
		)
		(polygon
			(pts
				(arc
					(start 52.218082 -279.785318)
					(mid 51.550062 -279.785318)
					(end 52.218082 -279.785318)
				)
			)
		)
	)
	(zone
		(layers "B.Cu" "In15.Cu")
		(hatch none 0.5)
		(connect_pads
			(clearance 0)
		)
		(min_thickness 0.25)
		(keepout
			(tracks not_allowed)
			(vias allowed)
			(pads allowed)
			(copperpour not_allowed)
			(footprints allowed)
		)
		(placement
			(enabled no)
			(sheetname "")
		)
		(fill yes
			(thermal_gap 0.5)
			(thermal_bridge_width 0.5)
			(island_removal_mode 0)
		)
		(polygon
			(pts
				(arc
					(start 98.295968 -270.03629)
					(mid 97.666048 -270.03629)
					(end 98.295968 -270.03629)
				)
			)
		)
	)
	(zone
		(layers "B.Cu" "In15.Cu")
		(hatch none 0.5)
		(connect_pads
			(clearance 0)
		)
		(min_thickness 0.25)
		(keepout
			(tracks not_allowed)
			(vias allowed)
			(pads allowed)
			(copperpour not_allowed)
			(footprints allowed)
		)
		(placement
			(enabled no)
			(sheetname "")
		)
		(fill yes
			(thermal_gap 0.5)
			(thermal_bridge_width 0.5)
			(island_removal_mode 0)
		)
		(polygon
			(pts
				(arc
					(start 384.299714 -264.365994)
					(mid 383.669794 -264.365994)
					(end 384.299714 -264.365994)
				)
			)
		)
	)
	(zone
		(layers "B.Cu" "In15.Cu")
		(hatch none 0.5)
		(connect_pads
			(clearance 0)
		)
		(min_thickness 0.25)
		(keepout
			(tracks not_allowed)
			(vias allowed)
			(pads allowed)
			(copperpour not_allowed)
			(footprints allowed)
		)
		(placement
			(enabled no)
			(sheetname "")
		)
		(fill yes
			(thermal_gap 0.5)
			(thermal_bridge_width 0.5)
			(island_removal_mode 0)
		)
		(polygon
			(pts
				(arc
					(start 337.776058 -282.996132)
					(mid 337.146138 -282.996132)
					(end 337.776058 -282.996132)
				)
			)
		)
	)
	(zone
		(layers "B.Cu" "In15.Cu")
		(hatch none 0.5)
		(connect_pads
			(clearance 0)
		)
		(min_thickness 0.25)
		(keepout
			(tracks not_allowed)
			(vias allowed)
			(pads allowed)
			(copperpour not_allowed)
			(footprints allowed)
		)
		(placement
			(enabled no)
			(sheetname "")
		)
		(fill yes
			(thermal_gap 0.5)
			(thermal_bridge_width 0.5)
			(island_removal_mode 0)
		)
		(polygon
			(pts
				(arc
					(start 420.246048 -308.685184)
					(mid 419.578028 -308.685184)
					(end 420.246048 -308.685184)
				)
			)
		)
	)
	(zone
		(layers "B.Cu" "In15.Cu")
		(hatch none 0.5)
		(connect_pads
			(clearance 0)
		)
		(min_thickness 0.25)
		(keepout
			(tracks not_allowed)
			(vias allowed)
			(pads allowed)
			(copperpour not_allowed)
			(footprints allowed)
		)
		(placement
			(enabled no)
			(sheetname "")
		)
		(fill yes
			(thermal_gap 0.5)
			(thermal_bridge_width 0.5)
			(island_removal_mode 0)
		)
		(polygon
			(pts
				(arc
					(start 337.476084 -238.004096)
					(mid 336.846164 -238.004096)
					(end 337.476084 -238.004096)
				)
			)
		)
	)
	(zone
		(layers "B.Cu" "In15.Cu")
		(hatch none 0.5)
		(connect_pads
			(clearance 0)
		)
		(min_thickness 0.25)
		(keepout
			(tracks not_allowed)
			(vias allowed)
			(pads allowed)
			(copperpour not_allowed)
			(footprints allowed)
		)
		(placement
			(enabled no)
			(sheetname "")
		)
		(fill yes
			(thermal_gap 0.5)
			(thermal_bridge_width 0.5)
			(island_removal_mode 0)
		)
		(polygon
			(pts
				(arc
					(start 135.119618 -232.334308)
					(mid 134.489698 -232.334308)
					(end 135.119618 -232.334308)
				)
			)
		)
	)
	(zone
		(layers "B.Cu" "In15.Cu")
		(hatch none 0.5)
		(connect_pads
			(clearance 0)
		)
		(min_thickness 0.25)
		(keepout
			(tracks not_allowed)
			(vias allowed)
			(pads allowed)
			(copperpour not_allowed)
			(footprints allowed)
		)
		(placement
			(enabled no)
			(sheetname "")
		)
		(fill yes
			(thermal_gap 0.5)
			(thermal_bridge_width 0.5)
			(island_removal_mode 0)
		)
		(polygon
			(pts
				(arc
					(start 296.058082 -280.634948)
					(mid 295.390062 -280.634948)
					(end 296.058082 -280.634948)
				)
			)
		)
	)
	(zone
		(layers "B.Cu" "In15.Cu")
		(hatch none 0.5)
		(connect_pads
			(clearance 0)
		)
		(min_thickness 0.25)
		(keepout
			(tracks not_allowed)
			(vias allowed)
			(pads allowed)
			(copperpour not_allowed)
			(footprints allowed)
		)
		(placement
			(enabled no)
			(sheetname "")
		)
		(fill yes
			(thermal_gap 0.5)
			(thermal_bridge_width 0.5)
			(island_removal_mode 0)
		)
		(polygon
			(pts
				(arc
					(start 136.059672 -233.95432)
					(mid 135.429752 -233.95432)
					(end 136.059672 -233.95432)
				)
			)
		)
	)
	(zone
		(layers "B.Cu" "In15.Cu")
		(hatch none 0.5)
		(connect_pads
			(clearance 0)
		)
		(min_thickness 0.25)
		(keepout
			(tracks not_allowed)
			(vias allowed)
			(pads allowed)
			(copperpour not_allowed)
			(footprints allowed)
		)
		(placement
			(enabled no)
			(sheetname "")
		)
		(fill yes
			(thermal_gap 0.5)
			(thermal_bridge_width 0.5)
			(island_removal_mode 0)
		)
		(polygon
			(pts
				(arc
					(start 48.118014 -224.535238)
					(mid 47.449994 -224.535238)
					(end 48.118014 -224.535238)
				)
			)
		)
	)
	(zone
		(layers "B.Cu" "In15.Cu")
		(hatch none 0.5)
		(connect_pads
			(clearance 0)
		)
		(min_thickness 0.25)
		(keepout
			(tracks not_allowed)
			(vias allowed)
			(pads allowed)
			(copperpour not_allowed)
			(footprints allowed)
		)
		(placement
			(enabled no)
			(sheetname "")
		)
		(fill yes
			(thermal_gap 0.5)
			(thermal_bridge_width 0.5)
			(island_removal_mode 0)
		)
		(polygon
			(pts
				(arc
					(start 336.06613 -240.434114)
					(mid 335.43621 -240.434114)
					(end 336.06613 -240.434114)
				)
			)
		)
	)
	(zone
		(layers "B.Cu" "In15.Cu")
		(hatch none 0.5)
		(connect_pads
			(clearance 0)
		)
		(min_thickness 0.25)
		(keepout
			(tracks not_allowed)
			(vias allowed)
			(pads allowed)
			(copperpour not_allowed)
			(footprints allowed)
		)
		(placement
			(enabled no)
			(sheetname "")
		)
		(fill yes
			(thermal_gap 0.5)
			(thermal_bridge_width 0.5)
			(island_removal_mode 0)
		)
		(polygon
			(pts
				(arc
					(start 337.006184 -229.094284)
					(mid 336.376264 -229.094284)
					(end 337.006184 -229.094284)
				)
			)
		)
	)
	(zone
		(layers "B.Cu" "In15.Cu")
		(hatch none 0.5)
		(connect_pads
			(clearance 0)
		)
		(min_thickness 0.25)
		(keepout
			(tracks not_allowed)
			(vias allowed)
			(pads allowed)
			(copperpour not_allowed)
			(footprints allowed)
		)
		(placement
			(enabled no)
			(sheetname "")
		)
		(fill yes
			(thermal_gap 0.5)
			(thermal_bridge_width 0.5)
			(island_removal_mode 0)
		)
		(polygon
			(pts
				(arc
					(start 82.037174 -435.489858)
					(mid 81.262982 -435.489858)
					(end 82.037174 -435.489858)
				)
			)
		)
	)
	(zone
		(layers "B.Cu" "In15.Cu")
		(hatch none 0.5)
		(connect_pads
			(clearance 0)
		)
		(min_thickness 0.25)
		(keepout
			(tracks not_allowed)
			(vias allowed)
			(pads allowed)
			(copperpour not_allowed)
			(footprints allowed)
		)
		(placement
			(enabled no)
			(sheetname "")
		)
		(fill yes
			(thermal_gap 0.5)
			(thermal_bridge_width 0.5)
			(island_removal_mode 0)
		)
		(polygon
			(pts
				(arc
					(start 336.06613 -237.19409)
					(mid 335.43621 -237.19409)
					(end 336.06613 -237.19409)
				)
			)
		)
	)
	(zone
		(layers "B.Cu" "In15.Cu")
		(hatch none 0.5)
		(connect_pads
			(clearance 0)
		)
		(min_thickness 0.25)
		(keepout
			(tracks not_allowed)
			(vias allowed)
			(pads allowed)
			(copperpour not_allowed)
			(footprints allowed)
		)
		(placement
			(enabled no)
			(sheetname "")
		)
		(fill yes
			(thermal_gap 0.5)
			(thermal_bridge_width 0.5)
			(island_removal_mode 0)
		)
		(polygon
			(pts
				(arc
					(start 136.529826 -255.824482)
					(mid 135.899906 -255.824482)
					(end 136.529826 -255.824482)
				)
			)
		)
	)
	(zone
		(layers "B.Cu" "In15.Cu")
		(hatch none 0.5)
		(connect_pads
			(clearance 0)
		)
		(min_thickness 0.25)
		(keepout
			(tracks not_allowed)
			(vias allowed)
			(pads allowed)
			(copperpour not_allowed)
			(footprints allowed)
		)
		(placement
			(enabled no)
			(sheetname "")
		)
		(fill yes
			(thermal_gap 0.5)
			(thermal_bridge_width 0.5)
			(island_removal_mode 0)
		)
		(polygon
			(pts
				(arc
					(start 89.066116 -229.094538)
					(mid 88.436196 -229.094538)
					(end 89.066116 -229.094538)
				)
			)
		)
	)
	(zone
		(layers "B.Cu" "In15.Cu")
		(hatch none 0.5)
		(connect_pads
			(clearance 0)
		)
		(min_thickness 0.25)
		(keepout
			(tracks not_allowed)
			(vias allowed)
			(pads allowed)
			(copperpour not_allowed)
			(footprints allowed)
		)
		(placement
			(enabled no)
			(sheetname "")
		)
		(fill yes
			(thermal_gap 0.5)
			(thermal_bridge_width 0.5)
			(island_removal_mode 0)
		)
		(polygon
			(pts
				(arc
					(start 119.90959 -273.276314)
					(mid 119.27967 -273.276314)
					(end 119.90959 -273.276314)
				)
			)
		)
	)
	(zone
		(layers "B.Cu" "In15.Cu")
		(hatch none 0.5)
		(connect_pads
			(clearance 0)
		)
		(min_thickness 0.25)
		(keepout
			(tracks not_allowed)
			(vias allowed)
			(pads allowed)
			(copperpour not_allowed)
			(footprints allowed)
		)
		(placement
			(enabled no)
			(sheetname "")
		)
		(fill yes
			(thermal_gap 0.5)
			(thermal_bridge_width 0.5)
			(island_removal_mode 0)
		)
		(polygon
			(pts
				(arc
					(start 383.99974 -256.634234)
					(mid 383.36982 -256.634234)
					(end 383.99974 -256.634234)
				)
			)
		)
	)
	(zone
		(layers "B.Cu" "In15.Cu")
		(hatch none 0.5)
		(connect_pads
			(clearance 0)
		)
		(min_thickness 0.25)
		(keepout
			(tracks not_allowed)
			(vias allowed)
			(pads allowed)
			(copperpour not_allowed)
			(footprints allowed)
		)
		(placement
			(enabled no)
			(sheetname "")
		)
		(fill yes
			(thermal_gap 0.5)
			(thermal_bridge_width 0.5)
			(island_removal_mode 0)
		)
		(polygon
			(pts
				(arc
					(start 136.8298 -281.376374)
					(mid 136.19988 -281.376374)
					(end 136.8298 -281.376374)
				)
			)
		)
	)
	(zone
		(layers "B.Cu" "In15.Cu")
		(hatch none 0.5)
		(connect_pads
			(clearance 0)
		)
		(min_thickness 0.25)
		(keepout
			(tracks not_allowed)
			(vias allowed)
			(pads allowed)
			(copperpour not_allowed)
			(footprints allowed)
		)
		(placement
			(enabled no)
			(sheetname "")
		)
		(fill yes
			(thermal_gap 0.5)
			(thermal_bridge_width 0.5)
			(island_removal_mode 0)
		)
		(polygon
			(pts
				(arc
					(start 388.050532 -400.811238)
					(mid 387.382512 -400.811238)
					(end 388.050532 -400.811238)
				)
			)
		)
	)
	(zone
		(layers "B.Cu" "In15.Cu")
		(hatch none 0.5)
		(connect_pads
			(clearance 0)
		)
		(min_thickness 0.25)
		(keepout
			(tracks not_allowed)
			(vias allowed)
			(pads allowed)
			(copperpour not_allowed)
			(footprints allowed)
		)
		(placement
			(enabled no)
			(sheetname "")
		)
		(fill yes
			(thermal_gap 0.5)
			(thermal_bridge_width 0.5)
			(island_removal_mode 0)
		)
		(polygon
			(pts
				(arc
					(start 89.536016 -244.484398)
					(mid 88.906096 -244.484398)
					(end 89.536016 -244.484398)
				)
			)
		)
	)
	(zone
		(layers "B.Cu" "In15.Cu")
		(hatch none 0.5)
		(connect_pads
			(clearance 0)
		)
		(min_thickness 0.25)
		(keepout
			(tracks not_allowed)
			(vias allowed)
			(pads allowed)
			(copperpour not_allowed)
			(footprints allowed)
		)
		(placement
			(enabled no)
			(sheetname "")
		)
		(fill yes
			(thermal_gap 0.5)
			(thermal_bridge_width 0.5)
			(island_removal_mode 0)
		)
		(polygon
			(pts
				(arc
					(start 337.776058 -291.095938)
					(mid 337.146138 -291.095938)
					(end 337.776058 -291.095938)
				)
			)
		)
	)
	(zone
		(layers "B.Cu" "In15.Cu")
		(hatch none 0.5)
		(connect_pads
			(clearance 0)
		)
		(min_thickness 0.25)
		(keepout
			(tracks not_allowed)
			(vias allowed)
			(pads allowed)
			(copperpour not_allowed)
			(footprints allowed)
		)
		(placement
			(enabled no)
			(sheetname "")
		)
		(fill yes
			(thermal_gap 0.5)
			(thermal_bridge_width 0.5)
			(island_removal_mode 0)
		)
		(polygon
			(pts
				(arc
					(start 335.89595 -265.176)
					(mid 335.26603 -265.176)
					(end 335.89595 -265.176)
				)
			)
		)
	)
	(zone
		(layers "B.Cu" "In15.Cu")
		(hatch none 0.5)
		(connect_pads
			(clearance 0)
		)
		(min_thickness 0.25)
		(keepout
			(tracks not_allowed)
			(vias allowed)
			(pads allowed)
			(copperpour not_allowed)
			(footprints allowed)
		)
		(placement
			(enabled no)
			(sheetname "")
		)
		(fill yes
			(thermal_gap 0.5)
			(thermal_bridge_width 0.5)
			(island_removal_mode 0)
		)
		(polygon
			(pts
				(arc
					(start 296.058082 -295.935146)
					(mid 295.390062 -295.935146)
					(end 296.058082 -295.935146)
				)
			)
		)
	)
	(zone
		(layers "B.Cu" "In15.Cu")
		(hatch none 0.5)
		(connect_pads
			(clearance 0)
		)
		(min_thickness 0.25)
		(keepout
			(tracks not_allowed)
			(vias allowed)
			(pads allowed)
			(copperpour not_allowed)
			(footprints allowed)
		)
		(placement
			(enabled no)
			(sheetname "")
		)
		(fill yes
			(thermal_gap 0.5)
			(thermal_bridge_width 0.5)
			(island_removal_mode 0)
		)
		(polygon
			(pts
				(arc
					(start 420.246048 -286.585152)
					(mid 419.578028 -286.585152)
					(end 420.246048 -286.585152)
				)
			)
		)
	)
	(zone
		(layers "B.Cu" "In15.Cu")
		(hatch none 0.5)
		(connect_pads
			(clearance 0)
		)
		(min_thickness 0.25)
		(keepout
			(tracks not_allowed)
			(vias allowed)
			(pads allowed)
			(copperpour not_allowed)
			(footprints allowed)
		)
		(placement
			(enabled no)
			(sheetname "")
		)
		(fill yes
			(thermal_gap 0.5)
			(thermal_bridge_width 0.5)
			(island_removal_mode 0)
		)
		(polygon
			(pts
				(arc
					(start 172.30598 -198.185278)
					(mid 171.63796 -198.185278)
					(end 172.30598 -198.185278)
				)
			)
		)
	)
	(zone
		(layers "B.Cu" "In15.Cu")
		(hatch none 0.5)
		(connect_pads
			(clearance 0)
		)
		(min_thickness 0.25)
		(keepout
			(tracks not_allowed)
			(vias allowed)
			(pads allowed)
			(copperpour not_allowed)
			(footprints allowed)
		)
		(placement
			(enabled no)
			(sheetname "")
		)
		(fill yes
			(thermal_gap 0.5)
			(thermal_bridge_width 0.5)
			(island_removal_mode 0)
		)
		(polygon
			(pts
				(arc
					(start 63.036958 -433.289964)
					(mid 62.262766 -433.289964)
					(end 63.036958 -433.289964)
				)
			)
		)
	)
	(zone
		(layers "B.Cu" "In15.Cu")
		(hatch none 0.5)
		(connect_pads
			(clearance 0)
		)
		(min_thickness 0.25)
		(keepout
			(tracks not_allowed)
			(vias allowed)
			(pads allowed)
			(copperpour not_allowed)
			(footprints allowed)
		)
		(placement
			(enabled no)
			(sheetname "")
		)
		(fill yes
			(thermal_gap 0.5)
			(thermal_bridge_width 0.5)
			(island_removal_mode 0)
		)
		(polygon
			(pts
				(arc
					(start 383.99974 -255.014222)
					(mid 383.36982 -255.014222)
					(end 383.99974 -255.014222)
				)
			)
		)
	)
	(zone
		(layers "B.Cu" "In15.Cu")
		(hatch none 0.5)
		(connect_pads
			(clearance 0)
		)
		(min_thickness 0.25)
		(keepout
			(tracks not_allowed)
			(vias allowed)
			(pads allowed)
			(copperpour not_allowed)
			(footprints allowed)
		)
		(placement
			(enabled no)
			(sheetname "")
		)
		(fill yes
			(thermal_gap 0.5)
			(thermal_bridge_width 0.5)
			(island_removal_mode 0)
		)
		(polygon
			(pts
				(arc
					(start 89.536016 -250.964446)
					(mid 88.906096 -250.964446)
					(end 89.536016 -250.964446)
				)
			)
		)
	)
	(zone
		(layers "B.Cu" "In15.Cu")
		(hatch none 0.5)
		(connect_pads
			(clearance 0)
		)
		(min_thickness 0.25)
		(keepout
			(tracks not_allowed)
			(vias allowed)
			(pads allowed)
			(copperpour not_allowed)
			(footprints allowed)
		)
		(placement
			(enabled no)
			(sheetname "")
		)
		(fill yes
			(thermal_gap 0.5)
			(thermal_bridge_width 0.5)
			(island_removal_mode 0)
		)
		(polygon
			(pts
				(arc
					(start 136.359646 -267.606272)
					(mid 135.729726 -267.606272)
					(end 136.359646 -267.606272)
				)
			)
		)
	)
	(zone
		(layers "B.Cu" "In15.Cu")
		(hatch none 0.5)
		(connect_pads
			(clearance 0)
		)
		(min_thickness 0.25)
		(keepout
			(tracks not_allowed)
			(vias allowed)
			(pads allowed)
			(copperpour not_allowed)
			(footprints allowed)
		)
		(placement
			(enabled no)
			(sheetname "")
		)
		(fill yes
			(thermal_gap 0.5)
			(thermal_bridge_width 0.5)
			(island_removal_mode 0)
		)
		(polygon
			(pts
				(arc
					(start 148.082254 -373.96293)
					(mid 147.414234 -373.96293)
					(end 148.082254 -373.96293)
				)
			)
		)
	)
	(zone
		(layers "B.Cu" "In15.Cu")
		(hatch none 0.5)
		(connect_pads
			(clearance 0)
		)
		(min_thickness 0.25)
		(keepout
			(tracks not_allowed)
			(vias allowed)
			(pads allowed)
			(copperpour not_allowed)
			(footprints allowed)
		)
		(placement
			(enabled no)
			(sheetname "")
		)
		(fill yes
			(thermal_gap 0.5)
			(thermal_bridge_width 0.5)
			(island_removal_mode 0)
		)
		(polygon
			(pts
				(arc
					(start 48.118014 -199.8853)
					(mid 47.449994 -199.8853)
					(end 48.118014 -199.8853)
				)
			)
		)
	)
	(zone
		(layers "B.Cu" "In15.Cu")
		(hatch none 0.5)
		(connect_pads
			(clearance 0)
		)
		(min_thickness 0.25)
		(keepout
			(tracks not_allowed)
			(vias allowed)
			(pads allowed)
			(copperpour not_allowed)
			(footprints allowed)
		)
		(placement
			(enabled no)
			(sheetname "")
		)
		(fill yes
			(thermal_gap 0.5)
			(thermal_bridge_width 0.5)
			(island_removal_mode 0)
		)
		(polygon
			(pts
				(arc
					(start 136.059672 -230.71455)
					(mid 135.429752 -230.71455)
					(end 136.059672 -230.71455)
				)
			)
		)
	)
	(zone
		(layers "B.Cu" "In15.Cu")
		(hatch none 0.5)
		(connect_pads
			(clearance 0)
		)
		(min_thickness 0.25)
		(keepout
			(tracks not_allowed)
			(vias allowed)
			(pads allowed)
			(copperpour not_allowed)
			(footprints allowed)
		)
		(placement
			(enabled no)
			(sheetname "")
		)
		(fill yes
			(thermal_gap 0.5)
			(thermal_bridge_width 0.5)
			(island_removal_mode 0)
		)
		(polygon
			(pts
				(arc
					(start 176.406048 -199.035416)
					(mid 175.738028 -199.035416)
					(end 176.406048 -199.035416)
				)
			)
		)
	)
	(zone
		(layers "B.Cu" "In15.Cu")
		(hatch none 0.5)
		(connect_pads
			(clearance 0)
		)
		(min_thickness 0.25)
		(keepout
			(tracks not_allowed)
			(vias allowed)
			(pads allowed)
			(copperpour not_allowed)
			(footprints allowed)
		)
		(placement
			(enabled no)
			(sheetname "")
		)
		(fill yes
			(thermal_gap 0.5)
			(thermal_bridge_width 0.5)
			(island_removal_mode 0)
		)
		(polygon
			(pts
				(arc
					(start 89.066116 -238.814356)
					(mid 88.436196 -238.814356)
					(end 89.066116 -238.814356)
				)
			)
		)
	)
	(zone
		(layers "B.Cu" "In15.Cu")
		(hatch none 0.5)
		(connect_pads
			(clearance 0)
		)
		(min_thickness 0.25)
		(keepout
			(tracks not_allowed)
			(vias allowed)
			(pads allowed)
			(copperpour not_allowed)
			(footprints allowed)
		)
		(placement
			(enabled no)
			(sheetname "")
		)
		(fill yes
			(thermal_gap 0.5)
			(thermal_bridge_width 0.5)
			(island_removal_mode 0)
		)
		(polygon
			(pts
				(arc
					(start 367.849658 -273.27606)
					(mid 367.219738 -273.27606)
					(end 367.849658 -273.27606)
				)
			)
		)
	)
	(zone
		(layers "B.Cu" "In15.Cu")
		(hatch none 0.5)
		(connect_pads
			(clearance 0)
		)
		(min_thickness 0.25)
		(keepout
			(tracks not_allowed)
			(vias allowed)
			(pads allowed)
			(copperpour not_allowed)
			(footprints allowed)
		)
		(placement
			(enabled no)
			(sheetname "")
		)
		(fill yes
			(thermal_gap 0.5)
			(thermal_bridge_width 0.5)
			(island_removal_mode 0)
		)
		(polygon
			(pts
				(arc
					(start 424.346116 -220.285056)
					(mid 423.678096 -220.285056)
					(end 424.346116 -220.285056)
				)
			)
		)
	)
	(zone
		(layers "B.Cu" "In15.Cu")
		(hatch none 0.5)
		(connect_pads
			(clearance 0)
		)
		(min_thickness 0.25)
		(keepout
			(tracks not_allowed)
			(vias allowed)
			(pads allowed)
			(copperpour not_allowed)
			(footprints allowed)
		)
		(placement
			(enabled no)
			(sheetname "")
		)
		(fill yes
			(thermal_gap 0.5)
			(thermal_bridge_width 0.5)
			(island_removal_mode 0)
		)
		(polygon
			(pts
				(arc
					(start 424.346116 -217.73515)
					(mid 423.678096 -217.73515)
					(end 424.346116 -217.73515)
				)
			)
		)
	)
	(zone
		(layers "B.Cu" "In15.Cu")
		(hatch none 0.5)
		(connect_pads
			(clearance 0)
		)
		(min_thickness 0.25)
		(keepout
			(tracks not_allowed)
			(vias allowed)
			(pads allowed)
			(copperpour not_allowed)
			(footprints allowed)
		)
		(placement
			(enabled no)
			(sheetname "")
		)
		(fill yes
			(thermal_gap 0.5)
			(thermal_bridge_width 0.5)
			(island_removal_mode 0)
		)
		(polygon
			(pts
				(arc
					(start 323.036692 -434.48986)
					(mid 322.2625 -434.48986)
					(end 323.036692 -434.48986)
				)
			)
		)
	)
	(zone
		(layers "B.Cu" "In15.Cu")
		(hatch none 0.5)
		(connect_pads
			(clearance 0)
		)
		(min_thickness 0.25)
		(keepout
			(tracks not_allowed)
			(vias allowed)
			(pads allowed)
			(copperpour not_allowed)
			(footprints allowed)
		)
		(placement
			(enabled no)
			(sheetname "")
		)
		(fill yes
			(thermal_gap 0.5)
			(thermal_bridge_width 0.5)
			(island_removal_mode 0)
		)
		(polygon
			(pts
				(arc
					(start 135.419592 -265.98626)
					(mid 134.789672 -265.98626)
					(end 135.419592 -265.98626)
				)
			)
		)
	)
	(zone
		(layers "B.Cu" "In15.Cu")
		(hatch none 0.5)
		(connect_pads
			(clearance 0)
		)
		(min_thickness 0.25)
		(keepout
			(tracks not_allowed)
			(vias allowed)
			(pads allowed)
			(copperpour not_allowed)
			(footprints allowed)
		)
		(placement
			(enabled no)
			(sheetname "")
		)
		(fill yes
			(thermal_gap 0.5)
			(thermal_bridge_width 0.5)
			(island_removal_mode 0)
		)
		(polygon
			(pts
				(arc
					(start 136.059672 -242.05438)
					(mid 135.429752 -242.05438)
					(end 136.059672 -242.05438)
				)
			)
		)
	)
	(zone
		(layers "B.Cu" "In15.Cu")
		(hatch none 0.5)
		(connect_pads
			(clearance 0)
		)
		(min_thickness 0.25)
		(keepout
			(tracks not_allowed)
			(vias allowed)
			(pads allowed)
			(copperpour not_allowed)
			(footprints allowed)
		)
		(placement
			(enabled no)
			(sheetname "")
		)
		(fill yes
			(thermal_gap 0.5)
			(thermal_bridge_width 0.5)
			(island_removal_mode 0)
		)
		(polygon
			(pts
				(arc
					(start 88.426036 -285.426404)
					(mid 87.796116 -285.426404)
					(end 88.426036 -285.426404)
				)
			)
		)
	)
	(zone
		(layers "B.Cu" "In15.Cu")
		(hatch none 0.5)
		(connect_pads
			(clearance 0)
		)
		(min_thickness 0.25)
		(keepout
			(tracks not_allowed)
			(vias allowed)
			(pads allowed)
			(copperpour not_allowed)
			(footprints allowed)
		)
		(placement
			(enabled no)
			(sheetname "")
		)
		(fill yes
			(thermal_gap 0.5)
			(thermal_bridge_width 0.5)
			(island_removal_mode 0)
		)
		(polygon
			(pts
				(arc
					(start 383.059686 -227.474272)
					(mid 382.429766 -227.474272)
					(end 383.059686 -227.474272)
				)
			)
		)
	)
	(zone
		(layers "B.Cu" "In15.Cu")
		(hatch none 0.5)
		(connect_pads
			(clearance 0)
		)
		(min_thickness 0.25)
		(keepout
			(tracks not_allowed)
			(vias allowed)
			(pads allowed)
			(copperpour not_allowed)
			(footprints allowed)
		)
		(placement
			(enabled no)
			(sheetname "")
		)
		(fill yes
			(thermal_gap 0.5)
			(thermal_bridge_width 0.5)
			(island_removal_mode 0)
		)
		(polygon
			(pts
				(arc
					(start 172.30598 -295.085262)
					(mid 171.63796 -295.085262)
					(end 172.30598 -295.085262)
				)
			)
		)
	)
	(zone
		(layers "B.Cu" "In15.Cu")
		(hatch none 0.5)
		(connect_pads
			(clearance 0)
		)
		(min_thickness 0.25)
		(keepout
			(tracks not_allowed)
			(vias allowed)
			(pads allowed)
			(copperpour not_allowed)
			(footprints allowed)
		)
		(placement
			(enabled no)
			(sheetname "")
		)
		(fill yes
			(thermal_gap 0.5)
			(thermal_bridge_width 0.5)
			(island_removal_mode 0)
		)
		(polygon
			(pts
				(arc
					(start 48.118014 -215.185244)
					(mid 47.449994 -215.185244)
					(end 48.118014 -215.185244)
				)
			)
		)
	)
	(zone
		(layers "B.Cu" "In15.Cu")
		(hatch none 0.5)
		(connect_pads
			(clearance 0)
		)
		(min_thickness 0.25)
		(keepout
			(tracks not_allowed)
			(vias allowed)
			(pads allowed)
			(copperpour not_allowed)
			(footprints allowed)
		)
		(placement
			(enabled no)
			(sheetname "")
		)
		(fill yes
			(thermal_gap 0.5)
			(thermal_bridge_width 0.5)
			(island_removal_mode 0)
		)
		(polygon
			(pts
				(arc
					(start 95.078296 -393.292838)
					(mid 94.410276 -393.292838)
					(end 95.078296 -393.292838)
				)
			)
		)
	)
	(zone
		(layers "B.Cu" "In15.Cu")
		(hatch none 0.5)
		(connect_pads
			(clearance 0)
		)
		(min_thickness 0.25)
		(keepout
			(tracks not_allowed)
			(vias allowed)
			(pads allowed)
			(copperpour not_allowed)
			(footprints allowed)
		)
		(placement
			(enabled no)
			(sheetname "")
		)
		(fill yes
			(thermal_gap 0.5)
			(thermal_bridge_width 0.5)
			(island_removal_mode 0)
		)
		(polygon
			(pts
				(arc
					(start 308.106064 -394.385292)
					(mid 307.476144 -394.385292)
					(end 308.106064 -394.385292)
				)
			)
		)
	)
	(zone
		(layers "B.Cu" "In15.Cu")
		(hatch none 0.5)
		(connect_pads
			(clearance 0)
		)
		(min_thickness 0.25)
		(keepout
			(tracks not_allowed)
			(vias allowed)
			(pads allowed)
			(copperpour not_allowed)
			(footprints allowed)
		)
		(placement
			(enabled no)
			(sheetname "")
		)
		(fill yes
			(thermal_gap 0.5)
			(thermal_bridge_width 0.5)
			(island_removal_mode 0)
		)
		(polygon
			(pts
				(arc
					(start 87.655908 -242.864386)
					(mid 87.025988 -242.864386)
					(end 87.655908 -242.864386)
				)
			)
		)
	)
	(zone
		(layers "B.Cu" "In15.Cu")
		(hatch none 0.5)
		(connect_pads
			(clearance 0)
		)
		(min_thickness 0.25)
		(keepout
			(tracks not_allowed)
			(vias allowed)
			(pads allowed)
			(copperpour not_allowed)
			(footprints allowed)
		)
		(placement
			(enabled no)
			(sheetname "")
		)
		(fill yes
			(thermal_gap 0.5)
			(thermal_bridge_width 0.5)
			(island_removal_mode 0)
		)
		(polygon
			(pts
				(arc
					(start 125.54966 -271.656302)
					(mid 124.91974 -271.656302)
					(end 125.54966 -271.656302)
				)
			)
		)
	)
	(zone
		(layers "B.Cu" "In15.Cu")
		(hatch none 0.5)
		(connect_pads
			(clearance 0)
		)
		(min_thickness 0.25)
		(keepout
			(tracks not_allowed)
			(vias allowed)
			(pads allowed)
			(copperpour not_allowed)
			(footprints allowed)
		)
		(placement
			(enabled no)
			(sheetname "")
		)
		(fill yes
			(thermal_gap 0.5)
			(thermal_bridge_width 0.5)
			(island_removal_mode 0)
		)
		(polygon
			(pts
				(arc
					(start 114.739674 -270.846296)
					(mid 114.109754 -270.846296)
					(end 114.739674 -270.846296)
				)
			)
		)
	)
	(zone
		(layers "B.Cu" "In15.Cu")
		(hatch none 0.5)
		(connect_pads
			(clearance 0)
		)
		(min_thickness 0.25)
		(keepout
			(tracks not_allowed)
			(vias allowed)
			(pads allowed)
			(copperpour not_allowed)
			(footprints allowed)
		)
		(placement
			(enabled no)
			(sheetname "")
		)
		(fill yes
			(thermal_gap 0.5)
			(thermal_bridge_width 0.5)
			(island_removal_mode 0)
		)
		(polygon
			(pts
				(arc
					(start 118.029736 -270.03629)
					(mid 117.399816 -270.03629)
					(end 118.029736 -270.03629)
				)
			)
		)
	)
	(zone
		(layers "B.Cu" "In15.Cu")
		(hatch none 0.5)
		(connect_pads
			(clearance 0)
		)
		(min_thickness 0.25)
		(keepout
			(tracks not_allowed)
			(vias allowed)
			(pads allowed)
			(copperpour not_allowed)
			(footprints allowed)
		)
		(placement
			(enabled no)
			(sheetname "")
		)
		(fill yes
			(thermal_gap 0.5)
			(thermal_bridge_width 0.5)
			(island_removal_mode 0)
		)
		(polygon
			(pts
				(arc
					(start 134.949692 -292.716204)
					(mid 134.319772 -292.716204)
					(end 134.949692 -292.716204)
				)
			)
		)
	)
	(zone
		(layers "B.Cu" "In15.Cu")
		(hatch none 0.5)
		(connect_pads
			(clearance 0)
		)
		(min_thickness 0.25)
		(keepout
			(tracks not_allowed)
			(vias allowed)
			(pads allowed)
			(copperpour not_allowed)
			(footprints allowed)
		)
		(placement
			(enabled no)
			(sheetname "")
		)
		(fill yes
			(thermal_gap 0.5)
			(thermal_bridge_width 0.5)
			(island_removal_mode 0)
		)
		(polygon
			(pts
				(arc
					(start 48.118014 -237.285276)
					(mid 47.449994 -237.285276)
					(end 48.118014 -237.285276)
				)
			)
		)
	)
	(zone
		(layers "B.Cu" "In15.Cu")
		(hatch none 0.5)
		(connect_pads
			(clearance 0)
		)
		(min_thickness 0.25)
		(keepout
			(tracks not_allowed)
			(vias allowed)
			(pads allowed)
			(copperpour not_allowed)
			(footprints allowed)
		)
		(placement
			(enabled no)
			(sheetname "")
		)
		(fill yes
			(thermal_gap 0.5)
			(thermal_bridge_width 0.5)
			(island_removal_mode 0)
		)
		(polygon
			(pts
				(arc
					(start 87.955882 -265.176254)
					(mid 87.325962 -265.176254)
					(end 87.955882 -265.176254)
				)
			)
		)
	)
	(zone
		(layers "B.Cu" "In15.Cu")
		(hatch none 0.5)
		(connect_pads
			(clearance 0)
		)
		(min_thickness 0.25)
		(keepout
			(tracks not_allowed)
			(vias allowed)
			(pads allowed)
			(copperpour not_allowed)
			(footprints allowed)
		)
		(placement
			(enabled no)
			(sheetname "")
		)
		(fill yes
			(thermal_gap 0.5)
			(thermal_bridge_width 0.5)
			(island_removal_mode 0)
		)
		(polygon
			(pts
				(arc
					(start 384.769868 -266.796012)
					(mid 384.139948 -266.796012)
					(end 384.769868 -266.796012)
				)
			)
		)
	)
	(zone
		(layers "B.Cu" "In15.Cu")
		(hatch none 0.5)
		(connect_pads
			(clearance 0)
		)
		(min_thickness 0.25)
		(keepout
			(tracks not_allowed)
			(vias allowed)
			(pads allowed)
			(copperpour not_allowed)
			(footprints allowed)
		)
		(placement
			(enabled no)
			(sheetname "")
		)
		(fill yes
			(thermal_gap 0.5)
			(thermal_bridge_width 0.5)
			(island_removal_mode 0)
		)
		(polygon
			(pts
				(arc
					(start 176.406048 -220.28531)
					(mid 175.738028 -220.28531)
					(end 176.406048 -220.28531)
				)
			)
		)
	)
	(zone
		(layers "B.Cu" "In15.Cu")
		(hatch none 0.5)
		(connect_pads
			(clearance 0)
		)
		(min_thickness 0.25)
		(keepout
			(tracks not_allowed)
			(vias allowed)
			(pads allowed)
			(copperpour not_allowed)
			(footprints allowed)
		)
		(placement
			(enabled no)
			(sheetname "")
		)
		(fill yes
			(thermal_gap 0.5)
			(thermal_bridge_width 0.5)
			(island_removal_mode 0)
		)
		(polygon
			(pts
				(arc
					(start 398.97685 -379.88113)
					(mid 398.30883 -379.88113)
					(end 398.97685 -379.88113)
				)
			)
		)
	)
	(zone
		(layers "B.Cu" "In15.Cu")
		(hatch none 0.5)
		(connect_pads
			(clearance 0)
		)
		(min_thickness 0.25)
		(keepout
			(tracks not_allowed)
			(vias allowed)
			(pads allowed)
			(copperpour not_allowed)
			(footprints allowed)
		)
		(placement
			(enabled no)
			(sheetname "")
		)
		(fill yes
			(thermal_gap 0.5)
			(thermal_bridge_width 0.5)
			(island_removal_mode 0)
		)
		(polygon
			(pts
				(arc
					(start 176.406048 -294.235378)
					(mid 175.738028 -294.235378)
					(end 176.406048 -294.235378)
				)
			)
		)
	)
	(zone
		(layers "B.Cu" "In15.Cu")
		(hatch none 0.5)
		(connect_pads
			(clearance 0)
		)
		(min_thickness 0.25)
		(keepout
			(tracks not_allowed)
			(vias allowed)
			(pads allowed)
			(copperpour not_allowed)
			(footprints allowed)
		)
		(placement
			(enabled no)
			(sheetname "")
		)
		(fill yes
			(thermal_gap 0.5)
			(thermal_bridge_width 0.5)
			(island_removal_mode 0)
		)
		(polygon
			(pts
				(arc
					(start 52.218082 -254.285242)
					(mid 51.550062 -254.285242)
					(end 52.218082 -254.285242)
				)
			)
		)
	)
	(zone
		(layers "B.Cu" "In15.Cu")
		(hatch none 0.5)
		(connect_pads
			(clearance 0)
		)
		(min_thickness 0.25)
		(keepout
			(tracks not_allowed)
			(vias allowed)
			(pads allowed)
			(copperpour not_allowed)
			(footprints allowed)
		)
		(placement
			(enabled no)
			(sheetname "")
		)
		(fill yes
			(thermal_gap 0.5)
			(thermal_bridge_width 0.5)
			(island_removal_mode 0)
		)
		(polygon
			(pts
				(arc
					(start 337.776058 -266.796012)
					(mid 337.146138 -266.796012)
					(end 337.776058 -266.796012)
				)
			)
		)
	)
	(zone
		(layers "B.Cu" "In15.Cu")
		(hatch none 0.5)
		(connect_pads
			(clearance 0)
		)
		(min_thickness 0.25)
		(keepout
			(tracks not_allowed)
			(vias allowed)
			(pads allowed)
			(copperpour not_allowed)
			(footprints allowed)
		)
		(placement
			(enabled no)
			(sheetname "")
		)
		(fill yes
			(thermal_gap 0.5)
			(thermal_bridge_width 0.5)
			(island_removal_mode 0)
		)
		(polygon
			(pts
				(arc
					(start 296.058082 -220.285056)
					(mid 295.390062 -220.285056)
					(end 296.058082 -220.285056)
				)
			)
		)
	)
	(zone
		(layers "B.Cu" "In15.Cu")
		(hatch none 0.5)
		(connect_pads
			(clearance 0)
		)
		(min_thickness 0.25)
		(keepout
			(tracks not_allowed)
			(vias allowed)
			(pads allowed)
			(copperpour not_allowed)
			(footprints allowed)
		)
		(placement
			(enabled no)
			(sheetname "")
		)
		(fill yes
			(thermal_gap 0.5)
			(thermal_bridge_width 0.5)
			(island_removal_mode 0)
		)
		(polygon
			(pts
				(arc
					(start 424.346116 -238.985044)
					(mid 423.678096 -238.985044)
					(end 424.346116 -238.985044)
				)
			)
		)
	)
	(zone
		(layers "B.Cu" "In15.Cu")
		(hatch none 0.5)
		(connect_pads
			(clearance 0)
		)
		(min_thickness 0.25)
		(keepout
			(tracks not_allowed)
			(vias allowed)
			(pads allowed)
			(copperpour not_allowed)
			(footprints allowed)
		)
		(placement
			(enabled no)
			(sheetname "")
		)
		(fill yes
			(thermal_gap 0.5)
			(thermal_bridge_width 0.5)
			(island_removal_mode 0)
		)
		(polygon
			(pts
				(arc
					(start 128.136904 -434.289962)
					(mid 127.362712 -434.289962)
					(end 128.136904 -434.289962)
				)
			)
		)
	)
	(zone
		(layers "B.Cu" "In15.Cu")
		(hatch none 0.5)
		(connect_pads
			(clearance 0)
		)
		(min_thickness 0.25)
		(keepout
			(tracks not_allowed)
			(vias allowed)
			(pads allowed)
			(copperpour not_allowed)
			(footprints allowed)
		)
		(placement
			(enabled no)
			(sheetname "")
		)
		(fill yes
			(thermal_gap 0.5)
			(thermal_bridge_width 0.5)
			(island_removal_mode 0)
		)
		(polygon
			(pts
				(arc
					(start 378.450602 -401.674838)
					(mid 377.782582 -401.674838)
					(end 378.450602 -401.674838)
				)
			)
		)
	)
	(zone
		(layers "B.Cu" "In15.Cu")
		(hatch none 0.5)
		(connect_pads
			(clearance 0)
		)
		(min_thickness 0.25)
		(keepout
			(tracks not_allowed)
			(vias allowed)
			(pads allowed)
			(copperpour not_allowed)
			(footprints allowed)
		)
		(placement
			(enabled no)
			(sheetname "")
		)
		(fill yes
			(thermal_gap 0.5)
			(thermal_bridge_width 0.5)
			(island_removal_mode 0)
		)
		(polygon
			(pts
				(arc
					(start 115.379754 -238.814356)
					(mid 114.749834 -238.814356)
					(end 115.379754 -238.814356)
				)
			)
		)
	)
	(zone
		(layers "B.Cu" "In15.Cu")
		(hatch none 0.5)
		(connect_pads
			(clearance 0)
		)
		(min_thickness 0.25)
		(keepout
			(tracks not_allowed)
			(vias allowed)
			(pads allowed)
			(copperpour not_allowed)
			(footprints allowed)
		)
		(placement
			(enabled no)
			(sheetname "")
		)
		(fill yes
			(thermal_gap 0.5)
			(thermal_bridge_width 0.5)
			(island_removal_mode 0)
		)
		(polygon
			(pts
				(arc
					(start 424.346116 -306.135024)
					(mid 423.678096 -306.135024)
					(end 424.346116 -306.135024)
				)
			)
		)
	)
	(zone
		(layers "B.Cu" "In15.Cu")
		(hatch none 0.5)
		(connect_pads
			(clearance 0)
		)
		(min_thickness 0.25)
		(keepout
			(tracks not_allowed)
			(vias allowed)
			(pads allowed)
			(copperpour not_allowed)
			(footprints allowed)
		)
		(placement
			(enabled no)
			(sheetname "")
		)
		(fill yes
			(thermal_gap 0.5)
			(thermal_bridge_width 0.5)
			(island_removal_mode 0)
		)
		(polygon
			(pts
				(arc
					(start 136.8298 -266.796266)
					(mid 136.19988 -266.796266)
					(end 136.8298 -266.796266)
				)
			)
		)
	)
	(zone
		(layers "B.Cu" "In15.Cu")
		(hatch none 0.5)
		(connect_pads
			(clearance 0)
		)
		(min_thickness 0.25)
		(keepout
			(tracks not_allowed)
			(vias allowed)
			(pads allowed)
			(copperpour not_allowed)
			(footprints allowed)
		)
		(placement
			(enabled no)
			(sheetname "")
		)
		(fill yes
			(thermal_gap 0.5)
			(thermal_bridge_width 0.5)
			(island_removal_mode 0)
		)
		(polygon
			(pts
				(arc
					(start 427.23943 -384.475228)
					(mid 426.57141 -384.475228)
					(end 427.23943 -384.475228)
				)
			)
		)
	)
	(zone
		(layers "B.Cu" "In15.Cu")
		(hatch none 0.5)
		(connect_pads
			(clearance 0)
		)
		(min_thickness 0.25)
		(keepout
			(tracks not_allowed)
			(vias allowed)
			(pads allowed)
			(copperpour not_allowed)
			(footprints allowed)
		)
		(placement
			(enabled no)
			(sheetname "")
		)
		(fill yes
			(thermal_gap 0.5)
			(thermal_bridge_width 0.5)
			(island_removal_mode 0)
		)
		(polygon
			(pts
				(arc
					(start 87.955882 -274.896326)
					(mid 87.325962 -274.896326)
					(end 87.955882 -274.896326)
				)
			)
		)
	)
	(zone
		(layers "B.Cu" "In15.Cu")
		(hatch none 0.5)
		(connect_pads
			(clearance 0)
		)
		(min_thickness 0.25)
		(keepout
			(tracks not_allowed)
			(vias allowed)
			(pads allowed)
			(copperpour not_allowed)
			(footprints allowed)
		)
		(placement
			(enabled no)
			(sheetname "")
		)
		(fill yes
			(thermal_gap 0.5)
			(thermal_bridge_width 0.5)
			(island_removal_mode 0)
		)
		(polygon
			(pts
				(arc
					(start 384.469894 -239.624108)
					(mid 383.839974 -239.624108)
					(end 384.469894 -239.624108)
				)
			)
		)
	)
	(zone
		(layers "B.Cu" "In15.Cu")
		(hatch none 0.5)
		(connect_pads
			(clearance 0)
		)
		(min_thickness 0.25)
		(keepout
			(tracks not_allowed)
			(vias allowed)
			(pads allowed)
			(copperpour not_allowed)
			(footprints allowed)
		)
		(placement
			(enabled no)
			(sheetname "")
		)
		(fill yes
			(thermal_gap 0.5)
			(thermal_bridge_width 0.5)
			(island_removal_mode 0)
		)
		(polygon
			(pts
				(arc
					(start 150.647654 -371.49913)
					(mid 149.979634 -371.49913)
					(end 150.647654 -371.49913)
				)
			)
		)
	)
	(zone
		(layers "B.Cu" "In15.Cu")
		(hatch none 0.5)
		(connect_pads
			(clearance 0)
		)
		(min_thickness 0.25)
		(keepout
			(tracks not_allowed)
			(vias allowed)
			(pads allowed)
			(copperpour not_allowed)
			(footprints allowed)
		)
		(placement
			(enabled no)
			(sheetname "")
		)
		(fill yes
			(thermal_gap 0.5)
			(thermal_bridge_width 0.5)
			(island_removal_mode 0)
		)
		(polygon
			(pts
				(arc
					(start 172.30598 -288.285428)
					(mid 171.63796 -288.285428)
					(end 172.30598 -288.285428)
				)
			)
		)
	)
	(zone
		(layers "B.Cu" "In15.Cu")
		(hatch none 0.5)
		(connect_pads
			(clearance 0)
		)
		(min_thickness 0.25)
		(keepout
			(tracks not_allowed)
			(vias allowed)
			(pads allowed)
			(copperpour not_allowed)
			(footprints allowed)
		)
		(placement
			(enabled no)
			(sheetname "")
		)
		(fill yes
			(thermal_gap 0.5)
			(thermal_bridge_width 0.5)
			(island_removal_mode 0)
		)
		(polygon
			(pts
				(arc
					(start 424.346116 -229.63505)
					(mid 423.678096 -229.63505)
					(end 424.346116 -229.63505)
				)
			)
		)
	)
	(zone
		(layers "B.Cu" "In15.Cu")
		(hatch none 0.5)
		(connect_pads
			(clearance 0)
		)
		(min_thickness 0.25)
		(keepout
			(tracks not_allowed)
			(vias allowed)
			(pads allowed)
			(copperpour not_allowed)
			(footprints allowed)
		)
		(placement
			(enabled no)
			(sheetname "")
		)
		(fill yes
			(thermal_gap 0.5)
			(thermal_bridge_width 0.5)
			(island_removal_mode 0)
		)
		(polygon
			(pts
				(arc
					(start 296.058082 -237.285022)
					(mid 295.390062 -237.285022)
					(end 296.058082 -237.285022)
				)
			)
		)
	)
	(zone
		(layers "B.Cu" "In15.Cu")
		(hatch none 0.5)
		(connect_pads
			(clearance 0)
		)
		(min_thickness 0.25)
		(keepout
			(tracks not_allowed)
			(vias allowed)
			(pads allowed)
			(copperpour not_allowed)
			(footprints allowed)
		)
		(placement
			(enabled no)
			(sheetname "")
		)
		(fill yes
			(thermal_gap 0.5)
			(thermal_bridge_width 0.5)
			(island_removal_mode 0)
		)
		(polygon
			(pts
				(arc
					(start 296.058082 -210.935062)
					(mid 295.390062 -210.935062)
					(end 296.058082 -210.935062)
				)
			)
		)
	)
	(zone
		(layers "B.Cu" "In15.Cu")
		(hatch none 0.5)
		(connect_pads
			(clearance 0)
		)
		(min_thickness 0.25)
		(keepout
			(tracks not_allowed)
			(vias allowed)
			(pads allowed)
			(copperpour not_allowed)
			(footprints allowed)
		)
		(placement
			(enabled no)
			(sheetname "")
		)
		(fill yes
			(thermal_gap 0.5)
			(thermal_bridge_width 0.5)
			(island_removal_mode 0)
		)
		(polygon
			(pts
				(arc
					(start 136.059672 -248.534428)
					(mid 135.429752 -248.534428)
					(end 136.059672 -248.534428)
				)
			)
		)
	)
	(zone
		(layers "B.Cu" "In15.Cu")
		(hatch none 0.5)
		(connect_pads
			(clearance 0)
		)
		(min_thickness 0.25)
		(keepout
			(tracks not_allowed)
			(vias allowed)
			(pads allowed)
			(copperpour not_allowed)
			(footprints allowed)
		)
		(placement
			(enabled no)
			(sheetname "")
		)
		(fill yes
			(thermal_gap 0.5)
			(thermal_bridge_width 0.5)
			(island_removal_mode 0)
		)
		(polygon
			(pts
				(arc
					(start 349.696024 -239.624108)
					(mid 349.066104 -239.624108)
					(end 349.696024 -239.624108)
				)
			)
		)
	)
	(zone
		(layers "B.Cu" "In15.Cu")
		(hatch none 0.5)
		(connect_pads
			(clearance 0)
		)
		(min_thickness 0.25)
		(keepout
			(tracks not_allowed)
			(vias allowed)
			(pads allowed)
			(copperpour not_allowed)
			(footprints allowed)
		)
		(placement
			(enabled no)
			(sheetname "")
		)
		(fill yes
			(thermal_gap 0.5)
			(thermal_bridge_width 0.5)
			(island_removal_mode 0)
		)
		(polygon
			(pts
				(arc
					(start 135.119618 -227.474526)
					(mid 134.489698 -227.474526)
					(end 135.119618 -227.474526)
				)
			)
		)
	)
	(zone
		(layers "B.Cu" "In15.Cu")
		(hatch none 0.5)
		(connect_pads
			(clearance 0)
		)
		(min_thickness 0.25)
		(keepout
			(tracks not_allowed)
			(vias allowed)
			(pads allowed)
			(copperpour not_allowed)
			(footprints allowed)
		)
		(placement
			(enabled no)
			(sheetname "")
		)
		(fill yes
			(thermal_gap 0.5)
			(thermal_bridge_width 0.5)
			(island_removal_mode 0)
		)
		(polygon
			(pts
				(arc
					(start 296.058082 -312.084974)
					(mid 295.390062 -312.084974)
					(end 296.058082 -312.084974)
				)
			)
		)
	)
	(zone
		(layers "B.Cu" "In15.Cu")
		(hatch none 0.5)
		(connect_pads
			(clearance 0)
		)
		(min_thickness 0.25)
		(keepout
			(tracks not_allowed)
			(vias allowed)
			(pads allowed)
			(copperpour not_allowed)
			(footprints allowed)
		)
		(placement
			(enabled no)
			(sheetname "")
		)
		(fill yes
			(thermal_gap 0.5)
			(thermal_bridge_width 0.5)
			(island_removal_mode 0)
		)
		(polygon
			(pts
				(arc
					(start 300.15815 -287.435036)
					(mid 299.49013 -287.435036)
					(end 300.15815 -287.435036)
				)
			)
		)
	)
	(zone
		(layers "B.Cu" "In15.Cu")
		(hatch none 0.5)
		(connect_pads
			(clearance 0)
		)
		(min_thickness 0.25)
		(keepout
			(tracks not_allowed)
			(vias allowed)
			(pads allowed)
			(copperpour not_allowed)
			(footprints allowed)
		)
		(placement
			(enabled no)
			(sheetname "")
		)
		(fill yes
			(thermal_gap 0.5)
			(thermal_bridge_width 0.5)
			(island_removal_mode 0)
		)
		(polygon
			(pts
				(arc
					(start 48.118014 -216.885266)
					(mid 47.449994 -216.885266)
					(end 48.118014 -216.885266)
				)
			)
		)
	)
	(zone
		(layers "B.Cu" "In15.Cu")
		(hatch none 0.5)
		(connect_pads
			(clearance 0)
		)
		(min_thickness 0.25)
		(keepout
			(tracks not_allowed)
			(vias allowed)
			(pads allowed)
			(copperpour not_allowed)
			(footprints allowed)
		)
		(placement
			(enabled no)
			(sheetname "")
		)
		(fill yes
			(thermal_gap 0.5)
			(thermal_bridge_width 0.5)
			(island_removal_mode 0)
		)
		(polygon
			(pts
				(arc
					(start 148.945854 -373.96293)
					(mid 148.277834 -373.96293)
					(end 148.945854 -373.96293)
				)
			)
		)
	)
	(zone
		(layers "B.Cu" "In15.Cu")
		(hatch none 0.5)
		(connect_pads
			(clearance 0)
		)
		(min_thickness 0.25)
		(keepout
			(tracks not_allowed)
			(vias allowed)
			(pads allowed)
			(copperpour not_allowed)
			(footprints allowed)
		)
		(placement
			(enabled no)
			(sheetname "")
		)
		(fill yes
			(thermal_gap 0.5)
			(thermal_bridge_width 0.5)
			(island_removal_mode 0)
		)
		(polygon
			(pts
				(arc
					(start 132.050536 -392.429238)
					(mid 131.382516 -392.429238)
					(end 132.050536 -392.429238)
				)
			)
		)
	)
	(zone
		(layers "B.Cu" "In15.Cu")
		(hatch none 0.5)
		(connect_pads
			(clearance 0)
		)
		(min_thickness 0.25)
		(keepout
			(tracks not_allowed)
			(vias allowed)
			(pads allowed)
			(copperpour not_allowed)
			(footprints allowed)
		)
		(placement
			(enabled no)
			(sheetname "")
		)
		(fill yes
			(thermal_gap 0.5)
			(thermal_bridge_width 0.5)
			(island_removal_mode 0)
		)
		(polygon
			(pts
				(arc
					(start 153.137108 -434.289962)
					(mid 152.362916 -434.289962)
					(end 153.137108 -434.289962)
				)
			)
		)
	)
	(zone
		(layers "B.Cu" "In15.Cu")
		(hatch none 0.5)
		(connect_pads
			(clearance 0)
		)
		(min_thickness 0.25)
		(keepout
			(tracks not_allowed)
			(vias allowed)
			(pads allowed)
			(copperpour not_allowed)
			(footprints allowed)
		)
		(placement
			(enabled no)
			(sheetname "")
		)
		(fill yes
			(thermal_gap 0.5)
			(thermal_bridge_width 0.5)
			(island_removal_mode 0)
		)
		(polygon
			(pts
				(arc
					(start 176.406048 -301.88535)
					(mid 175.738028 -301.88535)
					(end 176.406048 -301.88535)
				)
			)
		)
	)
	(zone
		(layers "B.Cu" "In15.Cu")
		(hatch none 0.5)
		(connect_pads
			(clearance 0)
		)
		(min_thickness 0.25)
		(keepout
			(tracks not_allowed)
			(vias allowed)
			(pads allowed)
			(copperpour not_allowed)
			(footprints allowed)
		)
		(placement
			(enabled no)
			(sheetname "")
		)
		(fill yes
			(thermal_gap 0.5)
			(thermal_bridge_width 0.5)
			(island_removal_mode 0)
		)
		(polygon
			(pts
				(arc
					(start 384.299714 -290.285932)
					(mid 383.669794 -290.285932)
					(end 384.299714 -290.285932)
				)
			)
		)
	)
	(zone
		(layers "B.Cu" "In15.Cu")
		(hatch none 0.5)
		(connect_pads
			(clearance 0)
		)
		(min_thickness 0.25)
		(keepout
			(tracks not_allowed)
			(vias allowed)
			(pads allowed)
			(copperpour not_allowed)
			(footprints allowed)
		)
		(placement
			(enabled no)
			(sheetname "")
		)
		(fill yes
			(thermal_gap 0.5)
			(thermal_bridge_width 0.5)
			(island_removal_mode 0)
		)
		(polygon
			(pts
				(arc
					(start 104.876092 -273.276314)
					(mid 104.246172 -273.276314)
					(end 104.876092 -273.276314)
				)
			)
		)
	)
	(zone
		(layers "B.Cu" "In15.Cu")
		(hatch none 0.5)
		(connect_pads
			(clearance 0)
		)
		(min_thickness 0.25)
		(keepout
			(tracks not_allowed)
			(vias allowed)
			(pads allowed)
			(copperpour not_allowed)
			(footprints allowed)
		)
		(placement
			(enabled no)
			(sheetname "")
		)
		(fill yes
			(thermal_gap 0.5)
			(thermal_bridge_width 0.5)
			(island_removal_mode 0)
		)
		(polygon
			(pts
				(arc
					(start 172.30598 -316.33541)
					(mid 171.63796 -316.33541)
					(end 172.30598 -316.33541)
				)
			)
		)
	)
	(zone
		(layers "B.Cu" "In15.Cu")
		(hatch none 0.5)
		(connect_pads
			(clearance 0)
		)
		(min_thickness 0.25)
		(keepout
			(tracks not_allowed)
			(vias allowed)
			(pads allowed)
			(copperpour not_allowed)
			(footprints allowed)
		)
		(placement
			(enabled no)
			(sheetname "")
		)
		(fill yes
			(thermal_gap 0.5)
			(thermal_bridge_width 0.5)
			(island_removal_mode 0)
		)
		(polygon
			(pts
				(arc
					(start 89.536016 -254.20447)
					(mid 88.906096 -254.20447)
					(end 89.536016 -254.20447)
				)
			)
		)
	)
	(zone
		(layers "B.Cu" "In15.Cu")
		(hatch none 0.5)
		(connect_pads
			(clearance 0)
		)
		(min_thickness 0.25)
		(keepout
			(tracks not_allowed)
			(vias allowed)
			(pads allowed)
			(copperpour not_allowed)
			(footprints allowed)
		)
		(placement
			(enabled no)
			(sheetname "")
		)
		(fill yes
			(thermal_gap 0.5)
			(thermal_bridge_width 0.5)
			(island_removal_mode 0)
		)
		(polygon
			(pts
				(arc
					(start 172.30598 -202.435206)
					(mid 171.63796 -202.435206)
					(end 172.30598 -202.435206)
				)
			)
		)
	)
	(zone
		(layers "B.Cu" "In15.Cu")
		(hatch none 0.5)
		(connect_pads
			(clearance 0)
		)
		(min_thickness 0.25)
		(keepout
			(tracks not_allowed)
			(vias allowed)
			(pads allowed)
			(copperpour not_allowed)
			(footprints allowed)
		)
		(placement
			(enabled no)
			(sheetname "")
		)
		(fill yes
			(thermal_gap 0.5)
			(thermal_bridge_width 0.5)
			(island_removal_mode 0)
		)
		(polygon
			(pts
				(arc
					(start 136.529826 -234.764326)
					(mid 135.899906 -234.764326)
					(end 136.529826 -234.764326)
				)
			)
		)
	)
	(zone
		(layers "B.Cu" "In15.Cu")
		(hatch none 0.5)
		(connect_pads
			(clearance 0)
		)
		(min_thickness 0.25)
		(keepout
			(tracks not_allowed)
			(vias allowed)
			(pads allowed)
			(copperpour not_allowed)
			(footprints allowed)
		)
		(placement
			(enabled no)
			(sheetname "")
		)
		(fill yes
			(thermal_gap 0.5)
			(thermal_bridge_width 0.5)
			(island_removal_mode 0)
		)
		(polygon
			(pts
				(arc
					(start 176.406048 -311.235344)
					(mid 175.738028 -311.235344)
					(end 176.406048 -311.235344)
				)
			)
		)
	)
	(zone
		(layers "B.Cu" "In15.Cu")
		(hatch none 0.5)
		(connect_pads
			(clearance 0)
		)
		(min_thickness 0.25)
		(keepout
			(tracks not_allowed)
			(vias allowed)
			(pads allowed)
			(copperpour not_allowed)
			(footprints allowed)
		)
		(placement
			(enabled no)
			(sheetname "")
		)
		(fill yes
			(thermal_gap 0.5)
			(thermal_bridge_width 0.5)
			(island_removal_mode 0)
		)
		(polygon
			(pts
				(arc
					(start 52.218082 -306.135278)
					(mid 51.550062 -306.135278)
					(end 52.218082 -306.135278)
				)
			)
		)
	)
	(zone
		(layers "B.Cu" "In15.Cu")
		(hatch none 0.5)
		(connect_pads
			(clearance 0)
		)
		(min_thickness 0.25)
		(keepout
			(tracks not_allowed)
			(vias allowed)
			(pads allowed)
			(copperpour not_allowed)
			(footprints allowed)
		)
		(placement
			(enabled no)
			(sheetname "")
		)
		(fill yes
			(thermal_gap 0.5)
			(thermal_bridge_width 0.5)
			(island_removal_mode 0)
		)
		(polygon
			(pts
				(arc
					(start 411.1371 -433.289964)
					(mid 410.362908 -433.289964)
					(end 411.1371 -433.289964)
				)
			)
		)
	)
	(zone
		(layers "B.Cu" "In15.Cu")
		(hatch none 0.5)
		(connect_pads
			(clearance 0)
		)
		(min_thickness 0.25)
		(keepout
			(tracks not_allowed)
			(vias allowed)
			(pads allowed)
			(copperpour not_allowed)
			(footprints allowed)
		)
		(placement
			(enabled no)
			(sheetname "")
		)
		(fill yes
			(thermal_gap 0.5)
			(thermal_bridge_width 0.5)
			(island_removal_mode 0)
		)
		(polygon
			(pts
				(arc
					(start 424.346116 -200.735184)
					(mid 423.678096 -200.735184)
					(end 424.346116 -200.735184)
				)
			)
		)
	)
	(zone
		(layers "B.Cu" "In15.Cu")
		(hatch none 0.5)
		(connect_pads
			(clearance 0)
		)
		(min_thickness 0.25)
		(keepout
			(tracks not_allowed)
			(vias allowed)
			(pads allowed)
			(copperpour not_allowed)
			(footprints allowed)
		)
		(placement
			(enabled no)
			(sheetname "")
		)
		(fill yes
			(thermal_gap 0.5)
			(thermal_bridge_width 0.5)
			(island_removal_mode 0)
		)
		(polygon
			(pts
				(arc
					(start 123.650502 -393.292838)
					(mid 122.982482 -393.292838)
					(end 123.650502 -393.292838)
				)
			)
		)
	)
	(zone
		(layers "B.Cu" "In15.Cu")
		(hatch none 0.5)
		(connect_pads
			(clearance 0)
		)
		(min_thickness 0.25)
		(keepout
			(tracks not_allowed)
			(vias allowed)
			(pads allowed)
			(copperpour not_allowed)
			(footprints allowed)
		)
		(placement
			(enabled no)
			(sheetname "")
		)
		(fill yes
			(thermal_gap 0.5)
			(thermal_bridge_width 0.5)
			(island_removal_mode 0)
		)
		(polygon
			(pts
				(arc
					(start 346.876116 -241.24412)
					(mid 346.246196 -241.24412)
					(end 346.876116 -241.24412)
				)
			)
		)
	)
	(zone
		(layers "B.Cu" "In15.Cu")
		(hatch none 0.5)
		(connect_pads
			(clearance 0)
		)
		(min_thickness 0.25)
		(keepout
			(tracks not_allowed)
			(vias allowed)
			(pads allowed)
			(copperpour not_allowed)
			(footprints allowed)
		)
		(placement
			(enabled no)
			(sheetname "")
		)
		(fill yes
			(thermal_gap 0.5)
			(thermal_bridge_width 0.5)
			(island_removal_mode 0)
		)
		(polygon
			(pts
				(arc
					(start 403.137116 -433.289964)
					(mid 402.362924 -433.289964)
					(end 403.137116 -433.289964)
				)
			)
		)
	)
	(zone
		(layers "B.Cu" "In15.Cu")
		(hatch none 0.5)
		(connect_pads
			(clearance 0)
		)
		(min_thickness 0.25)
		(keepout
			(tracks not_allowed)
			(vias allowed)
			(pads allowed)
			(copperpour not_allowed)
			(footprints allowed)
		)
		(placement
			(enabled no)
			(sheetname "")
		)
		(fill yes
			(thermal_gap 0.5)
			(thermal_bridge_width 0.5)
			(island_removal_mode 0)
		)
		(polygon
			(pts
				(arc
					(start 300.15815 -199.035162)
					(mid 299.49013 -199.035162)
					(end 300.15815 -199.035162)
				)
			)
		)
	)
	(zone
		(layers "B.Cu" "In15.Cu")
		(hatch none 0.5)
		(connect_pads
			(clearance 0)
		)
		(min_thickness 0.25)
		(keepout
			(tracks not_allowed)
			(vias allowed)
			(pads allowed)
			(copperpour not_allowed)
			(footprints allowed)
		)
		(placement
			(enabled no)
			(sheetname "")
		)
		(fill yes
			(thermal_gap 0.5)
			(thermal_bridge_width 0.5)
			(island_removal_mode 0)
		)
		(polygon
			(pts
				(arc
					(start 85.478366 -392.429238)
					(mid 84.810346 -392.429238)
					(end 85.478366 -392.429238)
				)
			)
		)
	)
	(zone
		(layers "B.Cu" "In15.Cu")
		(hatch none 0.5)
		(connect_pads
			(clearance 0)
		)
		(min_thickness 0.25)
		(keepout
			(tracks not_allowed)
			(vias allowed)
			(pads allowed)
			(copperpour not_allowed)
			(footprints allowed)
		)
		(placement
			(enabled no)
			(sheetname "")
		)
		(fill yes
			(thermal_gap 0.5)
			(thermal_bridge_width 0.5)
			(island_removal_mode 0)
		)
		(polygon
			(pts
				(arc
					(start 383.35966 -290.285932)
					(mid 382.72974 -290.285932)
					(end 383.35966 -290.285932)
				)
			)
		)
	)
	(zone
		(layers "B.Cu" "In15.Cu")
		(hatch none 0.5)
		(connect_pads
			(clearance 0)
		)
		(min_thickness 0.25)
		(keepout
			(tracks not_allowed)
			(vias allowed)
			(pads allowed)
			(copperpour not_allowed)
			(footprints allowed)
		)
		(placement
			(enabled no)
			(sheetname "")
		)
		(fill yes
			(thermal_gap 0.5)
			(thermal_bridge_width 0.5)
			(island_removal_mode 0)
		)
		(polygon
			(pts
				(arc
					(start 337.476084 -231.524048)
					(mid 336.846164 -231.524048)
					(end 337.476084 -231.524048)
				)
			)
		)
	)
	(zone
		(layers "B.Cu" "In15.Cu")
		(hatch none 0.5)
		(connect_pads
			(clearance 0)
		)
		(min_thickness 0.25)
		(keepout
			(tracks not_allowed)
			(vias allowed)
			(pads allowed)
			(copperpour not_allowed)
			(footprints allowed)
		)
		(placement
			(enabled no)
			(sheetname "")
		)
		(fill yes
			(thermal_gap 0.5)
			(thermal_bridge_width 0.5)
			(island_removal_mode 0)
		)
		(polygon
			(pts
				(arc
					(start 134.649718 -231.524302)
					(mid 134.019798 -231.524302)
					(end 134.649718 -231.524302)
				)
			)
		)
	)
	(zone
		(layers "B.Cu" "In15.Cu")
		(hatch none 0.5)
		(connect_pads
			(clearance 0)
		)
		(min_thickness 0.25)
		(keepout
			(tracks not_allowed)
			(vias allowed)
			(pads allowed)
			(copperpour not_allowed)
			(footprints allowed)
		)
		(placement
			(enabled no)
			(sheetname "")
		)
		(fill yes
			(thermal_gap 0.5)
			(thermal_bridge_width 0.5)
			(island_removal_mode 0)
		)
		(polygon
			(pts
				(arc
					(start 420.246048 -261.93496)
					(mid 419.578028 -261.93496)
					(end 420.246048 -261.93496)
				)
			)
		)
	)
	(zone
		(layers "B.Cu" "In15.Cu")
		(hatch none 0.5)
		(connect_pads
			(clearance 0)
		)
		(min_thickness 0.25)
		(keepout
			(tracks not_allowed)
			(vias allowed)
			(pads allowed)
			(copperpour not_allowed)
			(footprints allowed)
		)
		(placement
			(enabled no)
			(sheetname "")
		)
		(fill yes
			(thermal_gap 0.5)
			(thermal_bridge_width 0.5)
			(island_removal_mode 0)
		)
		(polygon
			(pts
				(arc
					(start 420.246048 -253.435104)
					(mid 419.578028 -253.435104)
					(end 420.246048 -253.435104)
				)
			)
		)
	)
	(zone
		(layers "B.Cu" "In15.Cu")
		(hatch none 0.5)
		(connect_pads
			(clearance 0)
		)
		(min_thickness 0.25)
		(keepout
			(tracks not_allowed)
			(vias allowed)
			(pads allowed)
			(copperpour not_allowed)
			(footprints allowed)
		)
		(placement
			(enabled no)
			(sheetname "")
		)
		(fill yes
			(thermal_gap 0.5)
			(thermal_bridge_width 0.5)
			(island_removal_mode 0)
		)
		(polygon
			(pts
				(arc
					(start 346.236036 -270.036036)
					(mid 345.606116 -270.036036)
					(end 346.236036 -270.036036)
				)
			)
		)
	)
	(zone
		(layers "B.Cu" "In15.Cu")
		(hatch none 0.5)
		(connect_pads
			(clearance 0)
		)
		(min_thickness 0.25)
		(keepout
			(tracks not_allowed)
			(vias allowed)
			(pads allowed)
			(copperpour not_allowed)
			(footprints allowed)
		)
		(placement
			(enabled no)
			(sheetname "")
		)
		(fill yes
			(thermal_gap 0.5)
			(thermal_bridge_width 0.5)
			(island_removal_mode 0)
		)
		(polygon
			(pts
				(arc
					(start 89.36609 -285.426404)
					(mid 88.73617 -285.426404)
					(end 89.36609 -285.426404)
				)
			)
		)
	)
	(zone
		(layers "B.Cu" "In15.Cu")
		(hatch none 0.5)
		(connect_pads
			(clearance 0)
		)
		(min_thickness 0.25)
		(keepout
			(tracks not_allowed)
			(vias allowed)
			(pads allowed)
			(copperpour not_allowed)
			(footprints allowed)
		)
		(placement
			(enabled no)
			(sheetname "")
		)
		(fill yes
			(thermal_gap 0.5)
			(thermal_bridge_width 0.5)
			(island_removal_mode 0)
		)
		(polygon
			(pts
				(arc
					(start 336.366104 -269.22603)
					(mid 335.736184 -269.22603)
					(end 336.366104 -269.22603)
				)
			)
		)
	)
	(zone
		(layers "B.Cu" "In15.Cu")
		(hatch none 0.5)
		(connect_pads
			(clearance 0)
		)
		(min_thickness 0.25)
		(keepout
			(tracks not_allowed)
			(vias allowed)
			(pads allowed)
			(copperpour not_allowed)
			(footprints allowed)
		)
		(placement
			(enabled no)
			(sheetname "")
		)
		(fill yes
			(thermal_gap 0.5)
			(thermal_bridge_width 0.5)
			(island_removal_mode 0)
		)
		(polygon
			(pts
				(arc
					(start 172.30598 -254.285242)
					(mid 171.63796 -254.285242)
					(end 172.30598 -254.285242)
				)
			)
		)
	)
	(zone
		(layers "B.Cu" "In15.Cu")
		(hatch none 0.5)
		(connect_pads
			(clearance 0)
		)
		(min_thickness 0.25)
		(keepout
			(tracks not_allowed)
			(vias allowed)
			(pads allowed)
			(copperpour not_allowed)
			(footprints allowed)
		)
		(placement
			(enabled no)
			(sheetname "")
		)
		(fill yes
			(thermal_gap 0.5)
			(thermal_bridge_width 0.5)
			(island_removal_mode 0)
		)
		(polygon
			(pts
				(arc
					(start 336.366104 -262.745982)
					(mid 335.736184 -262.745982)
					(end 336.366104 -262.745982)
				)
			)
		)
	)
	(zone
		(layers "B.Cu" "In15.Cu")
		(hatch none 0.5)
		(connect_pads
			(clearance 0)
		)
		(min_thickness 0.25)
		(keepout
			(tracks not_allowed)
			(vias allowed)
			(pads allowed)
			(copperpour not_allowed)
			(footprints allowed)
		)
		(placement
			(enabled no)
			(sheetname "")
		)
		(fill yes
			(thermal_gap 0.5)
			(thermal_bridge_width 0.5)
			(island_removal_mode 0)
		)
		(polygon
			(pts
				(arc
					(start 424.346116 -295.085008)
					(mid 423.678096 -295.085008)
					(end 424.346116 -295.085008)
				)
			)
		)
	)
	(zone
		(layers "B.Cu" "In15.Cu")
		(hatch none 0.5)
		(connect_pads
			(clearance 0)
		)
		(min_thickness 0.25)
		(keepout
			(tracks not_allowed)
			(vias allowed)
			(pads allowed)
			(copperpour not_allowed)
			(footprints allowed)
		)
		(placement
			(enabled no)
			(sheetname "")
		)
		(fill yes
			(thermal_gap 0.5)
			(thermal_bridge_width 0.5)
			(island_removal_mode 0)
		)
		(polygon
			(pts
				(arc
					(start 52.218082 -264.485374)
					(mid 51.550062 -264.485374)
					(end 52.218082 -264.485374)
				)
			)
		)
	)
	(zone
		(layers "B.Cu" "In15.Cu")
		(hatch none 0.5)
		(connect_pads
			(clearance 0)
		)
		(min_thickness 0.25)
		(keepout
			(tracks not_allowed)
			(vias allowed)
			(pads allowed)
			(copperpour not_allowed)
			(footprints allowed)
		)
		(placement
			(enabled no)
			(sheetname "")
		)
		(fill yes
			(thermal_gap 0.5)
			(thermal_bridge_width 0.5)
			(island_removal_mode 0)
		)
		(polygon
			(pts
				(arc
					(start 355.336094 -241.24412)
					(mid 354.706174 -241.24412)
					(end 355.336094 -241.24412)
				)
			)
		)
	)
	(zone
		(layers "B.Cu" "In15.Cu")
		(hatch none 0.5)
		(connect_pads
			(clearance 0)
		)
		(min_thickness 0.25)
		(keepout
			(tracks not_allowed)
			(vias allowed)
			(pads allowed)
			(copperpour not_allowed)
			(footprints allowed)
		)
		(placement
			(enabled no)
			(sheetname "")
		)
		(fill yes
			(thermal_gap 0.5)
			(thermal_bridge_width 0.5)
			(island_removal_mode 0)
		)
		(polygon
			(pts
				(arc
					(start 126.136908 -433.289964)
					(mid 125.362716 -433.289964)
					(end 126.136908 -433.289964)
				)
			)
		)
	)
	(zone
		(layers "B.Cu" "In15.Cu")
		(hatch none 0.5)
		(connect_pads
			(clearance 0)
		)
		(min_thickness 0.25)
		(keepout
			(tracks not_allowed)
			(vias allowed)
			(pads allowed)
			(copperpour not_allowed)
			(footprints allowed)
		)
		(placement
			(enabled no)
			(sheetname "")
		)
		(fill yes
			(thermal_gap 0.5)
			(thermal_bridge_width 0.5)
			(island_removal_mode 0)
		)
		(polygon
			(pts
				(arc
					(start 345.07805 -401.674838)
					(mid 344.41003 -401.674838)
					(end 345.07805 -401.674838)
				)
			)
		)
	)
	(zone
		(layers "B.Cu" "In15.Cu")
		(hatch none 0.5)
		(connect_pads
			(clearance 0)
		)
		(min_thickness 0.25)
		(keepout
			(tracks not_allowed)
			(vias allowed)
			(pads allowed)
			(copperpour not_allowed)
			(footprints allowed)
		)
		(placement
			(enabled no)
			(sheetname "")
		)
		(fill yes
			(thermal_gap 0.5)
			(thermal_bridge_width 0.5)
			(island_removal_mode 0)
		)
		(polygon
			(pts
				(arc
					(start 172.30598 -295.9354)
					(mid 171.63796 -295.9354)
					(end 172.30598 -295.9354)
				)
			)
		)
	)
	(zone
		(layers "B.Cu" "In15.Cu")
		(hatch none 0.5)
		(connect_pads
			(clearance 0)
		)
		(min_thickness 0.25)
		(keepout
			(tracks not_allowed)
			(vias allowed)
			(pads allowed)
			(copperpour not_allowed)
			(footprints allowed)
		)
		(placement
			(enabled no)
			(sheetname "")
		)
		(fill yes
			(thermal_gap 0.5)
			(thermal_bridge_width 0.5)
			(island_removal_mode 0)
		)
		(polygon
			(pts
				(arc
					(start 172.30598 -312.085228)
					(mid 171.63796 -312.085228)
					(end 172.30598 -312.085228)
				)
			)
		)
	)
	(zone
		(layers "B.Cu" "In15.Cu")
		(hatch none 0.5)
		(connect_pads
			(clearance 0)
		)
		(min_thickness 0.25)
		(keepout
			(tracks not_allowed)
			(vias allowed)
			(pads allowed)
			(copperpour not_allowed)
			(footprints allowed)
		)
		(placement
			(enabled no)
			(sheetname "")
		)
		(fill yes
			(thermal_gap 0.5)
			(thermal_bridge_width 0.5)
			(island_removal_mode 0)
		)
		(polygon
			(pts
				(arc
					(start 87.955882 -273.276314)
					(mid 87.325962 -273.276314)
					(end 87.955882 -273.276314)
				)
			)
		)
	)
	(zone
		(layers "B.Cu" "In15.Cu")
		(hatch none 0.5)
		(connect_pads
			(clearance 0)
		)
		(min_thickness 0.25)
		(keepout
			(tracks not_allowed)
			(vias allowed)
			(pads allowed)
			(copperpour not_allowed)
			(footprints allowed)
		)
		(placement
			(enabled no)
			(sheetname "")
		)
		(fill yes
			(thermal_gap 0.5)
			(thermal_bridge_width 0.5)
			(island_removal_mode 0)
		)
		(polygon
			(pts
				(arc
					(start 348.75597 -241.24412)
					(mid 348.12605 -241.24412)
					(end 348.75597 -241.24412)
				)
			)
		)
	)
	(zone
		(layers "B.Cu" "In15.Cu")
		(hatch none 0.5)
		(connect_pads
			(clearance 0)
		)
		(min_thickness 0.25)
		(keepout
			(tracks not_allowed)
			(vias allowed)
			(pads allowed)
			(copperpour not_allowed)
			(footprints allowed)
		)
		(placement
			(enabled no)
			(sheetname "")
		)
		(fill yes
			(thermal_gap 0.5)
			(thermal_bridge_width 0.5)
			(island_removal_mode 0)
		)
		(polygon
			(pts
				(arc
					(start 296.058082 -306.985162)
					(mid 295.390062 -306.985162)
					(end 296.058082 -306.985162)
				)
			)
		)
	)
	(zone
		(layers "B.Cu" "In15.Cu")
		(hatch none 0.5)
		(connect_pads
			(clearance 0)
		)
		(min_thickness 0.25)
		(keepout
			(tracks not_allowed)
			(vias allowed)
			(pads allowed)
			(copperpour not_allowed)
			(footprints allowed)
		)
		(placement
			(enabled no)
			(sheetname "")
		)
		(fill yes
			(thermal_gap 0.5)
			(thermal_bridge_width 0.5)
			(island_removal_mode 0)
		)
		(polygon
			(pts
				(arc
					(start 296.058082 -199.885046)
					(mid 295.390062 -199.885046)
					(end 296.058082 -199.885046)
				)
			)
		)
	)
	(zone
		(layers "B.Cu" "In15.Cu")
		(hatch none 0.5)
		(connect_pads
			(clearance 0)
		)
		(min_thickness 0.25)
		(keepout
			(tracks not_allowed)
			(vias allowed)
			(pads allowed)
			(copperpour not_allowed)
			(footprints allowed)
		)
		(placement
			(enabled no)
			(sheetname "")
		)
		(fill yes
			(thermal_gap 0.5)
			(thermal_bridge_width 0.5)
			(island_removal_mode 0)
		)
		(polygon
			(pts
				(arc
					(start 346.0369 -434.289962)
					(mid 345.262708 -434.289962)
					(end 346.0369 -434.289962)
				)
			)
		)
	)
	(zone
		(layers "B.Cu" "In15.Cu")
		(hatch none 0.5)
		(connect_pads
			(clearance 0)
		)
		(min_thickness 0.25)
		(keepout
			(tracks not_allowed)
			(vias allowed)
			(pads allowed)
			(copperpour not_allowed)
			(footprints allowed)
		)
		(placement
			(enabled no)
			(sheetname "")
		)
		(fill yes
			(thermal_gap 0.5)
			(thermal_bridge_width 0.5)
			(island_removal_mode 0)
		)
		(polygon
			(pts
				(arc
					(start 370.66982 -271.656048)
					(mid 370.0399 -271.656048)
					(end 370.66982 -271.656048)
				)
			)
		)
	)
	(zone
		(layers "B.Cu" "In15.Cu")
		(hatch none 0.5)
		(connect_pads
			(clearance 0)
		)
		(min_thickness 0.25)
		(keepout
			(tracks not_allowed)
			(vias allowed)
			(pads allowed)
			(copperpour not_allowed)
			(footprints allowed)
		)
		(placement
			(enabled no)
			(sheetname "")
		)
		(fill yes
			(thermal_gap 0.5)
			(thermal_bridge_width 0.5)
			(island_removal_mode 0)
		)
		(polygon
			(pts
				(arc
					(start 127.250698 -393.292838)
					(mid 126.582678 -393.292838)
					(end 127.250698 -393.292838)
				)
			)
		)
	)
	(zone
		(layers "B.Cu" "In15.Cu")
		(hatch none 0.5)
		(connect_pads
			(clearance 0)
		)
		(min_thickness 0.25)
		(keepout
			(tracks not_allowed)
			(vias allowed)
			(pads allowed)
			(copperpour not_allowed)
			(footprints allowed)
		)
		(placement
			(enabled no)
			(sheetname "")
		)
		(fill yes
			(thermal_gap 0.5)
			(thermal_bridge_width 0.5)
			(island_removal_mode 0)
		)
		(polygon
			(pts
				(arc
					(start 383.99974 -243.674138)
					(mid 383.36982 -243.674138)
					(end 383.99974 -243.674138)
				)
			)
		)
	)
	(zone
		(layers "B.Cu" "In15.Cu")
		(hatch none 0.5)
		(connect_pads
			(clearance 0)
		)
		(min_thickness 0.25)
		(keepout
			(tracks not_allowed)
			(vias allowed)
			(pads allowed)
			(copperpour not_allowed)
			(footprints allowed)
		)
		(placement
			(enabled no)
			(sheetname "")
		)
		(fill yes
			(thermal_gap 0.5)
			(thermal_bridge_width 0.5)
			(island_removal_mode 0)
		)
		(polygon
			(pts
				(arc
					(start 52.218082 -307.8353)
					(mid 51.550062 -307.8353)
					(end 52.218082 -307.8353)
				)
			)
		)
	)
	(zone
		(layers "B.Cu" "In15.Cu")
		(hatch none 0.5)
		(connect_pads
			(clearance 0)
		)
		(min_thickness 0.25)
		(keepout
			(tracks not_allowed)
			(vias allowed)
			(pads allowed)
			(copperpour not_allowed)
			(footprints allowed)
		)
		(placement
			(enabled no)
			(sheetname "")
		)
		(fill yes
			(thermal_gap 0.5)
			(thermal_bridge_width 0.5)
			(island_removal_mode 0)
		)
		(polygon
			(pts
				(arc
					(start 337.306158 -293.525956)
					(mid 336.676238 -293.525956)
					(end 337.306158 -293.525956)
				)
			)
		)
	)
	(zone
		(layers "B.Cu" "In15.Cu")
		(hatch none 0.5)
		(connect_pads
			(clearance 0)
		)
		(min_thickness 0.25)
		(keepout
			(tracks not_allowed)
			(vias allowed)
			(pads allowed)
			(copperpour not_allowed)
			(footprints allowed)
		)
		(placement
			(enabled no)
			(sheetname "")
		)
		(fill yes
			(thermal_gap 0.5)
			(thermal_bridge_width 0.5)
			(island_removal_mode 0)
		)
		(polygon
			(pts
				(arc
					(start 334.036924 -434.289962)
					(mid 333.262732 -434.289962)
					(end 334.036924 -434.289962)
				)
			)
		)
	)
	(zone
		(layers "B.Cu" "In15.Cu")
		(hatch none 0.5)
		(connect_pads
			(clearance 0)
		)
		(min_thickness 0.25)
		(keepout
			(tracks not_allowed)
			(vias allowed)
			(pads allowed)
			(copperpour not_allowed)
			(footprints allowed)
		)
		(placement
			(enabled no)
			(sheetname "")
		)
		(fill yes
			(thermal_gap 0.5)
			(thermal_bridge_width 0.5)
			(island_removal_mode 0)
		)
		(polygon
			(pts
				(arc
					(start 383.35966 -291.905944)
					(mid 382.72974 -291.905944)
					(end 383.35966 -291.905944)
				)
			)
		)
	)
	(zone
		(layers "B.Cu" "In15.Cu")
		(hatch none 0.5)
		(connect_pads
			(clearance 0)
		)
		(min_thickness 0.25)
		(keepout
			(tracks not_allowed)
			(vias allowed)
			(pads allowed)
			(copperpour not_allowed)
			(footprints allowed)
		)
		(placement
			(enabled no)
			(sheetname "")
		)
		(fill yes
			(thermal_gap 0.5)
			(thermal_bridge_width 0.5)
			(island_removal_mode 0)
		)
		(polygon
			(pts
				(arc
					(start 349.995998 -273.27606)
					(mid 349.366078 -273.27606)
					(end 349.995998 -273.27606)
				)
			)
		)
	)
	(zone
		(layers "B.Cu" "In15.Cu")
		(hatch none 0.5)
		(connect_pads
			(clearance 0)
		)
		(min_thickness 0.25)
		(keepout
			(tracks not_allowed)
			(vias allowed)
			(pads allowed)
			(copperpour not_allowed)
			(footprints allowed)
		)
		(placement
			(enabled no)
			(sheetname "")
		)
		(fill yes
			(thermal_gap 0.5)
			(thermal_bridge_width 0.5)
			(island_removal_mode 0)
		)
		(polygon
			(pts
				(arc
					(start 420.246048 -251.735082)
					(mid 419.578028 -251.735082)
					(end 420.246048 -251.735082)
				)
			)
		)
	)
	(zone
		(layers "B.Cu" "In15.Cu")
		(hatch none 0.5)
		(connect_pads
			(clearance 0)
		)
		(min_thickness 0.25)
		(keepout
			(tracks not_allowed)
			(vias allowed)
			(pads allowed)
			(copperpour not_allowed)
			(footprints allowed)
		)
		(placement
			(enabled no)
			(sheetname "")
		)
		(fill yes
			(thermal_gap 0.5)
			(thermal_bridge_width 0.5)
			(island_removal_mode 0)
		)
		(polygon
			(pts
				(arc
					(start 52.218082 -212.635338)
					(mid 51.550062 -212.635338)
					(end 52.218082 -212.635338)
				)
			)
		)
	)
	(zone
		(layers "B.Cu" "In15.Cu")
		(hatch none 0.5)
		(connect_pads
			(clearance 0)
		)
		(min_thickness 0.25)
		(keepout
			(tracks not_allowed)
			(vias allowed)
			(pads allowed)
			(copperpour not_allowed)
			(footprints allowed)
		)
		(placement
			(enabled no)
			(sheetname "")
		)
		(fill yes
			(thermal_gap 0.5)
			(thermal_bridge_width 0.5)
			(island_removal_mode 0)
		)
		(polygon
			(pts
				(arc
					(start 172.30598 -199.8853)
					(mid 171.63796 -199.8853)
					(end 172.30598 -199.8853)
				)
			)
		)
	)
	(zone
		(layers "B.Cu" "In15.Cu")
		(hatch none 0.5)
		(connect_pads
			(clearance 0)
		)
		(min_thickness 0.25)
		(keepout
			(tracks not_allowed)
			(vias allowed)
			(pads allowed)
			(copperpour not_allowed)
			(footprints allowed)
		)
		(placement
			(enabled no)
			(sheetname "")
		)
		(fill yes
			(thermal_gap 0.5)
			(thermal_bridge_width 0.5)
			(island_removal_mode 0)
		)
		(polygon
			(pts
				(arc
					(start 90.278458 -392.429238)
					(mid 89.610438 -392.429238)
					(end 90.278458 -392.429238)
				)
			)
		)
	)
	(zone
		(layers "B.Cu" "In15.Cu")
		(hatch none 0.5)
		(connect_pads
			(clearance 0)
		)
		(min_thickness 0.25)
		(keepout
			(tracks not_allowed)
			(vias allowed)
			(pads allowed)
			(copperpour not_allowed)
			(footprints allowed)
		)
		(placement
			(enabled no)
			(sheetname "")
		)
		(fill yes
			(thermal_gap 0.5)
			(thermal_bridge_width 0.5)
			(island_removal_mode 0)
		)
		(polygon
			(pts
				(arc
					(start 424.346116 -285.735014)
					(mid 423.678096 -285.735014)
					(end 424.346116 -285.735014)
				)
			)
		)
	)
	(zone
		(layers "B.Cu" "In15.Cu")
		(hatch none 0.5)
		(connect_pads
			(clearance 0)
		)
		(min_thickness 0.25)
		(keepout
			(tracks not_allowed)
			(vias allowed)
			(pads allowed)
			(copperpour not_allowed)
			(footprints allowed)
		)
		(placement
			(enabled no)
			(sheetname "")
		)
		(fill yes
			(thermal_gap 0.5)
			(thermal_bridge_width 0.5)
			(island_removal_mode 0)
		)
		(polygon
			(pts
				(arc
					(start 373.489728 -271.656048)
					(mid 372.859808 -271.656048)
					(end 373.489728 -271.656048)
				)
			)
		)
	)
	(zone
		(layers "B.Cu" "In15.Cu")
		(hatch none 0.5)
		(connect_pads
			(clearance 0)
		)
		(min_thickness 0.25)
		(keepout
			(tracks not_allowed)
			(vias allowed)
			(pads allowed)
			(copperpour not_allowed)
			(footprints allowed)
		)
		(placement
			(enabled no)
			(sheetname "")
		)
		(fill yes
			(thermal_gap 0.5)
			(thermal_bridge_width 0.5)
			(island_removal_mode 0)
		)
		(polygon
			(pts
				(arc
					(start 89.066116 -233.95432)
					(mid 88.436196 -233.95432)
					(end 89.066116 -233.95432)
				)
			)
		)
	)
	(zone
		(layers "B.Cu" "In15.Cu")
		(hatch none 0.5)
		(connect_pads
			(clearance 0)
		)
		(min_thickness 0.25)
		(keepout
			(tracks not_allowed)
			(vias allowed)
			(pads allowed)
			(copperpour not_allowed)
			(footprints allowed)
		)
		(placement
			(enabled no)
			(sheetname "")
		)
		(fill yes
			(thermal_gap 0.5)
			(thermal_bridge_width 0.5)
			(island_removal_mode 0)
		)
		(polygon
			(pts
				(arc
					(start 374.850406 -401.674838)
					(mid 374.182386 -401.674838)
					(end 374.850406 -401.674838)
				)
			)
		)
	)
	(zone
		(layers "B.Cu" "In15.Cu")
		(hatch none 0.5)
		(connect_pads
			(clearance 0)
		)
		(min_thickness 0.25)
		(keepout
			(tracks not_allowed)
			(vias allowed)
			(pads allowed)
			(copperpour not_allowed)
			(footprints allowed)
		)
		(placement
			(enabled no)
			(sheetname "")
		)
		(fill yes
			(thermal_gap 0.5)
			(thermal_bridge_width 0.5)
			(island_removal_mode 0)
		)
		(polygon
			(pts
				(arc
					(start 52.218082 -298.485306)
					(mid 51.550062 -298.485306)
					(end 52.218082 -298.485306)
				)
			)
		)
	)
	(zone
		(layers "B.Cu" "In15.Cu")
		(hatch none 0.5)
		(connect_pads
			(clearance 0)
		)
		(min_thickness 0.25)
		(keepout
			(tracks not_allowed)
			(vias allowed)
			(pads allowed)
			(copperpour not_allowed)
			(footprints allowed)
		)
		(placement
			(enabled no)
			(sheetname "")
		)
		(fill yes
			(thermal_gap 0.5)
			(thermal_bridge_width 0.5)
			(island_removal_mode 0)
		)
		(polygon
			(pts
				(arc
					(start 424.346116 -298.485052)
					(mid 423.678096 -298.485052)
					(end 424.346116 -298.485052)
				)
			)
		)
	)
	(zone
		(layers "B.Cu" "In15.Cu")
		(hatch none 0.5)
		(connect_pads
			(clearance 0)
		)
		(min_thickness 0.25)
		(keepout
			(tracks not_allowed)
			(vias allowed)
			(pads allowed)
			(copperpour not_allowed)
			(footprints allowed)
		)
		(placement
			(enabled no)
			(sheetname "")
		)
		(fill yes
			(thermal_gap 0.5)
			(thermal_bridge_width 0.5)
			(island_removal_mode 0)
		)
		(polygon
			(pts
				(arc
					(start 424.346116 -262.785098)
					(mid 423.678096 -262.785098)
					(end 424.346116 -262.785098)
				)
			)
		)
	)
	(zone
		(layers "B.Cu" "In15.Cu")
		(hatch none 0.5)
		(connect_pads
			(clearance 0)
		)
		(min_thickness 0.25)
		(keepout
			(tracks not_allowed)
			(vias allowed)
			(pads allowed)
			(copperpour not_allowed)
			(footprints allowed)
		)
		(placement
			(enabled no)
			(sheetname "")
		)
		(fill yes
			(thermal_gap 0.5)
			(thermal_bridge_width 0.5)
			(island_removal_mode 0)
		)
		(polygon
			(pts
				(arc
					(start 172.30598 -211.7852)
					(mid 171.63796 -211.7852)
					(end 172.30598 -211.7852)
				)
			)
		)
	)
	(zone
		(layers "B.Cu" "In15.Cu")
		(hatch none 0.5)
		(connect_pads
			(clearance 0)
		)
		(min_thickness 0.25)
		(keepout
			(tracks not_allowed)
			(vias allowed)
			(pads allowed)
			(copperpour not_allowed)
			(footprints allowed)
		)
		(placement
			(enabled no)
			(sheetname "")
		)
		(fill yes
			(thermal_gap 0.5)
			(thermal_bridge_width 0.5)
			(island_removal_mode 0)
		)
		(polygon
			(pts
				(arc
					(start 88.426036 -287.046162)
					(mid 87.796116 -287.046162)
					(end 88.426036 -287.046162)
				)
			)
		)
	)
	(zone
		(layers "B.Cu" "In15.Cu")
		(hatch none 0.5)
		(connect_pads
			(clearance 0)
		)
		(min_thickness 0.25)
		(keepout
			(tracks not_allowed)
			(vias allowed)
			(pads allowed)
			(copperpour not_allowed)
			(footprints allowed)
		)
		(placement
			(enabled no)
			(sheetname "")
		)
		(fill yes
			(thermal_gap 0.5)
			(thermal_bridge_width 0.5)
			(island_removal_mode 0)
		)
		(polygon
			(pts
				(arc
					(start 92.678504 -393.292838)
					(mid 92.010484 -393.292838)
					(end 92.678504 -393.292838)
				)
			)
		)
	)
	(zone
		(layers "B.Cu" "In15.Cu")
		(hatch none 0.5)
		(connect_pads
			(clearance 0)
		)
		(min_thickness 0.25)
		(keepout
			(tracks not_allowed)
			(vias allowed)
			(pads allowed)
			(copperpour not_allowed)
			(footprints allowed)
		)
		(placement
			(enabled no)
			(sheetname "")
		)
		(fill yes
			(thermal_gap 0.5)
			(thermal_bridge_width 0.5)
			(island_removal_mode 0)
		)
		(polygon
			(pts
				(arc
					(start 383.35966 -288.66592)
					(mid 382.72974 -288.66592)
					(end 383.35966 -288.66592)
				)
			)
		)
	)
	(zone
		(layers "B.Cu" "In15.Cu")
		(hatch none 0.5)
		(connect_pads
			(clearance 0)
		)
		(min_thickness 0.25)
		(keepout
			(tracks not_allowed)
			(vias allowed)
			(pads allowed)
			(copperpour not_allowed)
			(footprints allowed)
		)
		(placement
			(enabled no)
			(sheetname "")
		)
		(fill yes
			(thermal_gap 0.5)
			(thermal_bridge_width 0.5)
			(island_removal_mode 0)
		)
		(polygon
			(pts
				(arc
					(start 383.35966 -270.846042)
					(mid 382.72974 -270.846042)
					(end 383.35966 -270.846042)
				)
			)
		)
	)
	(zone
		(layers "B.Cu" "In15.Cu")
		(hatch none 0.5)
		(connect_pads
			(clearance 0)
		)
		(min_thickness 0.25)
		(keepout
			(tracks not_allowed)
			(vias allowed)
			(pads allowed)
			(copperpour not_allowed)
			(footprints allowed)
		)
		(placement
			(enabled no)
			(sheetname "")
		)
		(fill yes
			(thermal_gap 0.5)
			(thermal_bridge_width 0.5)
			(island_removal_mode 0)
		)
		(polygon
			(pts
				(arc
					(start 340.277958 -401.674838)
					(mid 339.609938 -401.674838)
					(end 340.277958 -401.674838)
				)
			)
		)
	)
	(zone
		(layers "B.Cu" "In15.Cu")
		(hatch none 0.5)
		(connect_pads
			(clearance 0)
		)
		(min_thickness 0.25)
		(keepout
			(tracks not_allowed)
			(vias allowed)
			(pads allowed)
			(copperpour not_allowed)
			(footprints allowed)
		)
		(placement
			(enabled no)
			(sheetname "")
		)
		(fill yes
			(thermal_gap 0.5)
			(thermal_bridge_width 0.5)
			(island_removal_mode 0)
		)
		(polygon
			(pts
				(arc
					(start 48.118014 -210.935316)
					(mid 47.449994 -210.935316)
					(end 48.118014 -210.935316)
				)
			)
		)
	)
	(zone
		(layers "B.Cu" "In15.Cu")
		(hatch none 0.5)
		(connect_pads
			(clearance 0)
		)
		(min_thickness 0.25)
		(keepout
			(tracks not_allowed)
			(vias allowed)
			(pads allowed)
			(copperpour not_allowed)
			(footprints allowed)
		)
		(placement
			(enabled no)
			(sheetname "")
		)
		(fill yes
			(thermal_gap 0.5)
			(thermal_bridge_width 0.5)
			(island_removal_mode 0)
		)
		(polygon
			(pts
				(arc
					(start 335.595976 -231.524048)
					(mid 334.966056 -231.524048)
					(end 335.595976 -231.524048)
				)
			)
		)
	)
	(zone
		(layers "B.Cu" "In15.Cu")
		(hatch none 0.5)
		(connect_pads
			(clearance 0)
		)
		(min_thickness 0.25)
		(keepout
			(tracks not_allowed)
			(vias allowed)
			(pads allowed)
			(copperpour not_allowed)
			(footprints allowed)
		)
		(placement
			(enabled no)
			(sheetname "")
		)
		(fill yes
			(thermal_gap 0.5)
			(thermal_bridge_width 0.5)
			(island_removal_mode 0)
		)
		(polygon
			(pts
				(arc
					(start 129.65049 -392.429238)
					(mid 128.98247 -392.429238)
					(end 129.65049 -392.429238)
				)
			)
		)
	)
	(zone
		(layers "B.Cu" "In15.Cu")
		(hatch none 0.5)
		(connect_pads
			(clearance 0)
		)
		(min_thickness 0.25)
		(keepout
			(tracks not_allowed)
			(vias allowed)
			(pads allowed)
			(copperpour not_allowed)
			(footprints allowed)
		)
		(placement
			(enabled no)
			(sheetname "")
		)
		(fill yes
			(thermal_gap 0.5)
			(thermal_bridge_width 0.5)
			(island_removal_mode 0)
		)
		(polygon
			(pts
				(arc
					(start 176.406048 -281.48534)
					(mid 175.738028 -281.48534)
					(end 176.406048 -281.48534)
				)
			)
		)
	)
	(zone
		(layers "B.Cu" "In15.Cu")
		(hatch none 0.5)
		(connect_pads
			(clearance 0)
		)
		(min_thickness 0.25)
		(keepout
			(tracks not_allowed)
			(vias allowed)
			(pads allowed)
			(copperpour not_allowed)
			(footprints allowed)
		)
		(placement
			(enabled no)
			(sheetname "")
		)
		(fill yes
			(thermal_gap 0.5)
			(thermal_bridge_width 0.5)
			(island_removal_mode 0)
		)
		(polygon
			(pts
				(arc
					(start 176.406048 -273.835368)
					(mid 175.738028 -273.835368)
					(end 176.406048 -273.835368)
				)
			)
		)
	)
	(zone
		(layers "B.Cu" "In15.Cu")
		(hatch none 0.5)
		(connect_pads
			(clearance 0)
		)
		(min_thickness 0.25)
		(keepout
			(tracks not_allowed)
			(vias allowed)
			(pads allowed)
			(copperpour not_allowed)
			(footprints allowed)
		)
		(placement
			(enabled no)
			(sheetname "")
		)
		(fill yes
			(thermal_gap 0.5)
			(thermal_bridge_width 0.5)
			(island_removal_mode 0)
		)
		(polygon
			(pts
				(arc
					(start 296.058082 -221.13494)
					(mid 295.390062 -221.13494)
					(end 296.058082 -221.13494)
				)
			)
		)
	)
	(zone
		(layers "B.Cu" "In15.Cu")
		(hatch none 0.5)
		(connect_pads
			(clearance 0)
		)
		(min_thickness 0.25)
		(keepout
			(tracks not_allowed)
			(vias allowed)
			(pads allowed)
			(copperpour not_allowed)
			(footprints allowed)
		)
		(placement
			(enabled no)
			(sheetname "")
		)
		(fill yes
			(thermal_gap 0.5)
			(thermal_bridge_width 0.5)
			(island_removal_mode 0)
		)
		(polygon
			(pts
				(arc
					(start 87.955882 -270.03629)
					(mid 87.325962 -270.03629)
					(end 87.955882 -270.03629)
				)
			)
		)
	)
	(zone
		(layers "B.Cu" "In15.Cu")
		(hatch none 0.5)
		(connect_pads
			(clearance 0)
		)
		(min_thickness 0.25)
		(keepout
			(tracks not_allowed)
			(vias allowed)
			(pads allowed)
			(copperpour not_allowed)
			(footprints allowed)
		)
		(placement
			(enabled no)
			(sheetname "")
		)
		(fill yes
			(thermal_gap 0.5)
			(thermal_bridge_width 0.5)
			(island_removal_mode 0)
		)
		(polygon
			(pts
				(arc
					(start 335.595976 -233.14406)
					(mid 334.966056 -233.14406)
					(end 335.595976 -233.14406)
				)
			)
		)
	)
	(zone
		(layers "B.Cu" "In15.Cu")
		(hatch none 0.5)
		(connect_pads
			(clearance 0)
		)
		(min_thickness 0.25)
		(keepout
			(tracks not_allowed)
			(vias allowed)
			(pads allowed)
			(copperpour not_allowed)
			(footprints allowed)
		)
		(placement
			(enabled no)
			(sheetname "")
		)
		(fill yes
			(thermal_gap 0.5)
			(thermal_bridge_width 0.5)
			(island_removal_mode 0)
		)
		(polygon
			(pts
				(arc
					(start 420.246048 -229.63505)
					(mid 419.578028 -229.63505)
					(end 420.246048 -229.63505)
				)
			)
		)
	)
	(zone
		(layers "B.Cu" "In15.Cu")
		(hatch none 0.5)
		(connect_pads
			(clearance 0)
		)
		(min_thickness 0.25)
		(keepout
			(tracks not_allowed)
			(vias allowed)
			(pads allowed)
			(copperpour not_allowed)
			(footprints allowed)
		)
		(placement
			(enabled no)
			(sheetname "")
		)
		(fill yes
			(thermal_gap 0.5)
			(thermal_bridge_width 0.5)
			(island_removal_mode 0)
		)
		(polygon
			(pts
				(arc
					(start 384.299714 -291.905944)
					(mid 383.669794 -291.905944)
					(end 384.299714 -291.905944)
				)
			)
		)
	)
	(zone
		(layers "B.Cu" "In15.Cu")
		(hatch none 0.5)
		(connect_pads
			(clearance 0)
		)
		(min_thickness 0.25)
		(keepout
			(tracks not_allowed)
			(vias allowed)
			(pads allowed)
			(copperpour not_allowed)
			(footprints allowed)
		)
		(placement
			(enabled no)
			(sheetname "")
		)
		(fill yes
			(thermal_gap 0.5)
			(thermal_bridge_width 0.5)
			(island_removal_mode 0)
		)
		(polygon
			(pts
				(arc
					(start 52.218082 -220.28531)
					(mid 51.550062 -220.28531)
					(end 52.218082 -220.28531)
				)
			)
		)
	)
	(zone
		(layers "B.Cu" "In15.Cu")
		(hatch none 0.5)
		(connect_pads
			(clearance 0)
		)
		(min_thickness 0.25)
		(keepout
			(tracks not_allowed)
			(vias allowed)
			(pads allowed)
			(copperpour not_allowed)
			(footprints allowed)
		)
		(placement
			(enabled no)
			(sheetname "")
		)
		(fill yes
			(thermal_gap 0.5)
			(thermal_bridge_width 0.5)
			(island_removal_mode 0)
		)
		(polygon
			(pts
				(arc
					(start 373.65051 -401.674838)
					(mid 372.98249 -401.674838)
					(end 373.65051 -401.674838)
				)
			)
		)
	)
	(zone
		(layers "B.Cu" "In15.Cu")
		(hatch none 0.5)
		(connect_pads
			(clearance 0)
		)
		(min_thickness 0.25)
		(keepout
			(tracks not_allowed)
			(vias allowed)
			(pads allowed)
			(copperpour not_allowed)
			(footprints allowed)
		)
		(placement
			(enabled no)
			(sheetname "")
		)
		(fill yes
			(thermal_gap 0.5)
			(thermal_bridge_width 0.5)
			(island_removal_mode 0)
		)
		(polygon
			(pts
				(arc
					(start 52.218082 -252.58522)
					(mid 51.550062 -252.58522)
					(end 52.218082 -252.58522)
				)
			)
		)
	)
	(zone
		(layers "B.Cu" "In15.Cu")
		(hatch none 0.5)
		(connect_pads
			(clearance 0)
		)
		(min_thickness 0.25)
		(keepout
			(tracks not_allowed)
			(vias allowed)
			(pads allowed)
			(copperpour not_allowed)
			(footprints allowed)
		)
		(placement
			(enabled no)
			(sheetname "")
		)
		(fill yes
			(thermal_gap 0.5)
			(thermal_bridge_width 0.5)
			(island_removal_mode 0)
		)
		(polygon
			(pts
				(arc
					(start 383.99974 -246.914162)
					(mid 383.36982 -246.914162)
					(end 383.99974 -246.914162)
				)
			)
		)
	)
	(zone
		(layers "B.Cu" "In15.Cu")
		(hatch none 0.5)
		(connect_pads
			(clearance 0)
		)
		(min_thickness 0.25)
		(keepout
			(tracks not_allowed)
			(vias allowed)
			(pads allowed)
			(copperpour not_allowed)
			(footprints allowed)
		)
		(placement
			(enabled no)
			(sheetname "")
		)
		(fill yes
			(thermal_gap 0.5)
			(thermal_bridge_width 0.5)
			(island_removal_mode 0)
		)
		(polygon
			(pts
				(arc
					(start 176.406048 -227.085398)
					(mid 175.738028 -227.085398)
					(end 176.406048 -227.085398)
				)
			)
		)
	)
	(zone
		(layers "B.Cu" "In15.Cu")
		(hatch none 0.5)
		(connect_pads
			(clearance 0)
		)
		(min_thickness 0.25)
		(keepout
			(tracks not_allowed)
			(vias allowed)
			(pads allowed)
			(copperpour not_allowed)
			(footprints allowed)
		)
		(placement
			(enabled no)
			(sheetname "")
		)
		(fill yes
			(thermal_gap 0.5)
			(thermal_bridge_width 0.5)
			(island_removal_mode 0)
		)
		(polygon
			(pts
				(arc
					(start 87.655908 -236.384338)
					(mid 87.025988 -236.384338)
					(end 87.655908 -236.384338)
				)
			)
		)
	)
	(zone
		(layers "B.Cu" "In15.Cu")
		(hatch none 0.5)
		(connect_pads
			(clearance 0)
		)
		(min_thickness 0.25)
		(keepout
			(tracks not_allowed)
			(vias allowed)
			(pads allowed)
			(copperpour not_allowed)
			(footprints allowed)
		)
		(placement
			(enabled no)
			(sheetname "")
		)
		(fill yes
			(thermal_gap 0.5)
			(thermal_bridge_width 0.5)
			(island_removal_mode 0)
		)
		(polygon
			(pts
				(arc
					(start 149.137116 -434.289962)
					(mid 148.362924 -434.289962)
					(end 149.137116 -434.289962)
				)
			)
		)
	)
	(zone
		(layers "B.Cu" "In15.Cu")
		(hatch none 0.5)
		(connect_pads
			(clearance 0)
		)
		(min_thickness 0.25)
		(keepout
			(tracks not_allowed)
			(vias allowed)
			(pads allowed)
			(copperpour not_allowed)
			(footprints allowed)
		)
		(placement
			(enabled no)
			(sheetname "")
		)
		(fill yes
			(thermal_gap 0.5)
			(thermal_bridge_width 0.5)
			(island_removal_mode 0)
		)
		(polygon
			(pts
				(arc
					(start 172.30598 -209.235294)
					(mid 171.63796 -209.235294)
					(end 172.30598 -209.235294)
				)
			)
		)
	)
	(zone
		(layers "B.Cu" "In15.Cu")
		(hatch none 0.5)
		(connect_pads
			(clearance 0)
		)
		(min_thickness 0.25)
		(keepout
			(tracks not_allowed)
			(vias allowed)
			(pads allowed)
			(copperpour not_allowed)
			(footprints allowed)
		)
		(placement
			(enabled no)
			(sheetname "")
		)
		(fill yes
			(thermal_gap 0.5)
			(thermal_bridge_width 0.5)
			(island_removal_mode 0)
		)
		(polygon
			(pts
				(arc
					(start 52.218082 -238.985298)
					(mid 51.550062 -238.985298)
					(end 52.218082 -238.985298)
				)
			)
		)
	)
	(zone
		(layers "B.Cu" "In15.Cu")
		(hatch none 0.5)
		(connect_pads
			(clearance 0)
		)
		(min_thickness 0.25)
		(keepout
			(tracks not_allowed)
			(vias allowed)
			(pads allowed)
			(copperpour not_allowed)
			(footprints allowed)
		)
		(placement
			(enabled no)
			(sheetname "")
		)
		(fill yes
			(thermal_gap 0.5)
			(thermal_bridge_width 0.5)
			(island_removal_mode 0)
		)
		(polygon
			(pts
				(arc
					(start 48.118014 -211.7852)
					(mid 47.449994 -211.7852)
					(end 48.118014 -211.7852)
				)
			)
		)
	)
	(zone
		(layers "B.Cu" "In15.Cu")
		(hatch none 0.5)
		(connect_pads
			(clearance 0)
		)
		(min_thickness 0.25)
		(keepout
			(tracks not_allowed)
			(vias allowed)
			(pads allowed)
			(copperpour not_allowed)
			(footprints allowed)
		)
		(placement
			(enabled no)
			(sheetname "")
		)
		(fill yes
			(thermal_gap 0.5)
			(thermal_bridge_width 0.5)
			(island_removal_mode 0)
		)
		(polygon
			(pts
				(arc
					(start 300.15815 -250.884944)
					(mid 299.49013 -250.884944)
					(end 300.15815 -250.884944)
				)
			)
		)
	)
	(zone
		(layers "B.Cu" "In15.Cu")
		(hatch none 0.5)
		(connect_pads
			(clearance 0)
		)
		(min_thickness 0.25)
		(keepout
			(tracks not_allowed)
			(vias allowed)
			(pads allowed)
			(copperpour not_allowed)
			(footprints allowed)
		)
		(placement
			(enabled no)
			(sheetname "")
		)
		(fill yes
			(thermal_gap 0.5)
			(thermal_bridge_width 0.5)
			(island_removal_mode 0)
		)
		(polygon
			(pts
				(arc
					(start 386.850382 -400.811238)
					(mid 386.182362 -400.811238)
					(end 386.850382 -400.811238)
				)
			)
		)
	)
	(zone
		(layers "B.Cu" "In15.Cu")
		(hatch none 0.5)
		(connect_pads
			(clearance 0)
		)
		(min_thickness 0.25)
		(keepout
			(tracks not_allowed)
			(vias allowed)
			(pads allowed)
			(copperpour not_allowed)
			(footprints allowed)
		)
		(placement
			(enabled no)
			(sheetname "")
		)
		(fill yes
			(thermal_gap 0.5)
			(thermal_bridge_width 0.5)
			(island_removal_mode 0)
		)
		(polygon
			(pts
				(arc
					(start 52.218082 -283.185362)
					(mid 51.550062 -283.185362)
					(end 52.218082 -283.185362)
				)
			)
		)
	)
	(zone
		(layers "B.Cu" "In15.Cu")
		(hatch none 0.5)
		(connect_pads
			(clearance 0)
		)
		(min_thickness 0.25)
		(keepout
			(tracks not_allowed)
			(vias allowed)
			(pads allowed)
			(copperpour not_allowed)
			(footprints allowed)
		)
		(placement
			(enabled no)
			(sheetname "")
		)
		(fill yes
			(thermal_gap 0.5)
			(thermal_bridge_width 0.5)
			(island_removal_mode 0)
		)
		(polygon
			(pts
				(arc
					(start 336.366104 -277.32609)
					(mid 335.736184 -277.32609)
					(end 336.366104 -277.32609)
				)
			)
		)
	)
	(zone
		(layers "B.Cu" "In15.Cu")
		(hatch none 0.5)
		(connect_pads
			(clearance 0)
		)
		(min_thickness 0.25)
		(keepout
			(tracks not_allowed)
			(vias allowed)
			(pads allowed)
			(copperpour not_allowed)
			(footprints allowed)
		)
		(placement
			(enabled no)
			(sheetname "")
		)
		(fill yes
			(thermal_gap 0.5)
			(thermal_bridge_width 0.5)
			(island_removal_mode 0)
		)
		(polygon
			(pts
				(arc
					(start 424.346116 -206.685134)
					(mid 423.678096 -206.685134)
					(end 424.346116 -206.685134)
				)
			)
		)
	)
	(zone
		(layers "B.Cu" "In15.Cu")
		(hatch none 0.5)
		(connect_pads
			(clearance 0)
		)
		(min_thickness 0.25)
		(keepout
			(tracks not_allowed)
			(vias allowed)
			(pads allowed)
			(copperpour not_allowed)
			(footprints allowed)
		)
		(placement
			(enabled no)
			(sheetname "")
		)
		(fill yes
			(thermal_gap 0.5)
			(thermal_bridge_width 0.5)
			(island_removal_mode 0)
		)
		(polygon
			(pts
				(arc
					(start 172.30598 -241.535204)
					(mid 171.63796 -241.535204)
					(end 172.30598 -241.535204)
				)
			)
		)
	)
	(zone
		(layers "B.Cu" "In15.Cu")
		(hatch none 0.5)
		(connect_pads
			(clearance 0)
		)
		(min_thickness 0.25)
		(keepout
			(tracks not_allowed)
			(vias allowed)
			(pads allowed)
			(copperpour not_allowed)
			(footprints allowed)
		)
		(placement
			(enabled no)
			(sheetname "")
		)
		(fill yes
			(thermal_gap 0.5)
			(thermal_bridge_width 0.5)
			(island_removal_mode 0)
		)
		(polygon
			(pts
				(arc
					(start 383.059686 -250.154186)
					(mid 382.429766 -250.154186)
					(end 383.059686 -250.154186)
				)
			)
		)
	)
	(zone
		(layers "B.Cu" "In15.Cu")
		(hatch none 0.5)
		(connect_pads
			(clearance 0)
		)
		(min_thickness 0.25)
		(keepout
			(tracks not_allowed)
			(vias allowed)
			(pads allowed)
			(copperpour not_allowed)
			(footprints allowed)
		)
		(placement
			(enabled no)
			(sheetname "")
		)
		(fill yes
			(thermal_gap 0.5)
			(thermal_bridge_width 0.5)
			(island_removal_mode 0)
		)
		(polygon
			(pts
				(arc
					(start 48.118014 -220.28531)
					(mid 47.449994 -220.28531)
					(end 48.118014 -220.28531)
				)
			)
		)
	)
	(zone
		(layers "B.Cu" "In15.Cu")
		(hatch none 0.5)
		(connect_pads
			(clearance 0)
		)
		(min_thickness 0.25)
		(keepout
			(tracks not_allowed)
			(vias allowed)
			(pads allowed)
			(copperpour not_allowed)
			(footprints allowed)
		)
		(placement
			(enabled no)
			(sheetname "")
		)
		(fill yes
			(thermal_gap 0.5)
			(thermal_bridge_width 0.5)
			(island_removal_mode 0)
		)
		(polygon
			(pts
				(arc
					(start 403.137116 -434.48986)
					(mid 402.362924 -434.48986)
					(end 403.137116 -434.48986)
				)
			)
		)
	)
	(zone
		(layers "B.Cu" "In15.Cu")
		(hatch none 0.5)
		(connect_pads
			(clearance 0)
		)
		(min_thickness 0.25)
		(keepout
			(tracks not_allowed)
			(vias allowed)
			(pads allowed)
			(copperpour not_allowed)
			(footprints allowed)
		)
		(placement
			(enabled no)
			(sheetname "")
		)
		(fill yes
			(thermal_gap 0.5)
			(thermal_bridge_width 0.5)
			(island_removal_mode 0)
		)
		(polygon
			(pts
				(arc
					(start 337.006184 -242.054126)
					(mid 336.376264 -242.054126)
					(end 337.006184 -242.054126)
				)
			)
		)
	)
	(zone
		(layers "B.Cu" "In15.Cu")
		(hatch none 0.5)
		(connect_pads
			(clearance 0)
		)
		(min_thickness 0.25)
		(keepout
			(tracks not_allowed)
			(vias allowed)
			(pads allowed)
			(copperpour not_allowed)
			(footprints allowed)
		)
		(placement
			(enabled no)
			(sheetname "")
		)
		(fill yes
			(thermal_gap 0.5)
			(thermal_bridge_width 0.5)
			(island_removal_mode 0)
		)
		(polygon
			(pts
				(arc
					(start 115.250468 -393.292838)
					(mid 114.582448 -393.292838)
					(end 115.250468 -393.292838)
				)
			)
		)
	)
	(zone
		(layers "B.Cu" "In15.Cu")
		(hatch none 0.5)
		(connect_pads
			(clearance 0)
		)
		(min_thickness 0.25)
		(keepout
			(tracks not_allowed)
			(vias allowed)
			(pads allowed)
			(copperpour not_allowed)
			(footprints allowed)
		)
		(placement
			(enabled no)
			(sheetname "")
		)
		(fill yes
			(thermal_gap 0.5)
			(thermal_bridge_width 0.5)
			(island_removal_mode 0)
		)
		(polygon
			(pts
				(arc
					(start 161.696654 -373.96293)
					(mid 161.028634 -373.96293)
					(end 161.696654 -373.96293)
				)
			)
		)
	)
	(zone
		(layers "B.Cu" "In15.Cu")
		(hatch none 0.5)
		(connect_pads
			(clearance 0)
		)
		(min_thickness 0.25)
		(keepout
			(tracks not_allowed)
			(vias allowed)
			(pads allowed)
			(copperpour not_allowed)
			(footprints allowed)
		)
		(placement
			(enabled no)
			(sheetname "")
		)
		(fill yes
			(thermal_gap 0.5)
			(thermal_bridge_width 0.5)
			(island_removal_mode 0)
		)
		(polygon
			(pts
				(arc
					(start 420.246048 -199.885046)
					(mid 419.578028 -199.885046)
					(end 420.246048 -199.885046)
				)
			)
		)
	)
	(zone
		(layers "B.Cu" "In15.Cu")
		(hatch none 0.5)
		(connect_pads
			(clearance 0)
		)
		(min_thickness 0.25)
		(keepout
			(tracks not_allowed)
			(vias allowed)
			(pads allowed)
			(copperpour not_allowed)
			(footprints allowed)
		)
		(placement
			(enabled no)
			(sheetname "")
		)
		(fill yes
			(thermal_gap 0.5)
			(thermal_bridge_width 0.5)
			(island_removal_mode 0)
		)
		(polygon
			(pts
				(arc
					(start 406.64765 -379.88113)
					(mid 405.97963 -379.88113)
					(end 406.64765 -379.88113)
				)
			)
		)
	)
	(zone
		(layers "B.Cu" "In15.Cu")
		(hatch none 0.5)
		(connect_pads
			(clearance 0)
		)
		(min_thickness 0.25)
		(keepout
			(tracks not_allowed)
			(vias allowed)
			(pads allowed)
			(copperpour not_allowed)
			(footprints allowed)
		)
		(placement
			(enabled no)
			(sheetname "")
		)
		(fill yes
			(thermal_gap 0.5)
			(thermal_bridge_width 0.5)
			(island_removal_mode 0)
		)
		(polygon
			(pts
				(arc
					(start 300.15815 -311.23509)
					(mid 299.49013 -311.23509)
					(end 300.15815 -311.23509)
				)
			)
		)
	)
	(zone
		(layers "B.Cu" "In15.Cu")
		(hatch none 0.5)
		(connect_pads
			(clearance 0)
		)
		(min_thickness 0.25)
		(keepout
			(tracks not_allowed)
			(vias allowed)
			(pads allowed)
			(copperpour not_allowed)
			(footprints allowed)
		)
		(placement
			(enabled no)
			(sheetname "")
		)
		(fill yes
			(thermal_gap 0.5)
			(thermal_bridge_width 0.5)
			(island_removal_mode 0)
		)
		(polygon
			(pts
				(arc
					(start 353.478084 -400.811238)
					(mid 352.810064 -400.811238)
					(end 353.478084 -400.811238)
				)
			)
		)
	)
	(zone
		(layers "B.Cu" "In15.Cu")
		(hatch none 0.5)
		(connect_pads
			(clearance 0)
		)
		(min_thickness 0.25)
		(keepout
			(tracks not_allowed)
			(vias allowed)
			(pads allowed)
			(copperpour not_allowed)
			(footprints allowed)
		)
		(placement
			(enabled no)
			(sheetname "")
		)
		(fill yes
			(thermal_gap 0.5)
			(thermal_bridge_width 0.5)
			(island_removal_mode 0)
		)
		(polygon
			(pts
				(arc
					(start 87.655908 -229.90429)
					(mid 87.025988 -229.90429)
					(end 87.655908 -229.90429)
				)
			)
		)
	)
	(zone
		(layers "B.Cu" "In15.Cu")
		(hatch none 0.5)
		(connect_pads
			(clearance 0)
		)
		(min_thickness 0.25)
		(keepout
			(tracks not_allowed)
			(vias allowed)
			(pads allowed)
			(copperpour not_allowed)
			(footprints allowed)
		)
		(placement
			(enabled no)
			(sheetname "")
		)
		(fill yes
			(thermal_gap 0.5)
			(thermal_bridge_width 0.5)
			(island_removal_mode 0)
		)
		(polygon
			(pts
				(arc
					(start 88.126062 -230.71455)
					(mid 87.496142 -230.71455)
					(end 88.126062 -230.71455)
				)
			)
		)
	)
	(zone
		(layers "B.Cu" "In15.Cu")
		(hatch none 0.5)
		(connect_pads
			(clearance 0)
		)
		(min_thickness 0.25)
		(keepout
			(tracks not_allowed)
			(vias allowed)
			(pads allowed)
			(copperpour not_allowed)
			(footprints allowed)
		)
		(placement
			(enabled no)
			(sheetname "")
		)
		(fill yes
			(thermal_gap 0.5)
			(thermal_bridge_width 0.5)
			(island_removal_mode 0)
		)
		(polygon
			(pts
				(arc
					(start 122.450606 -392.429238)
					(mid 121.782586 -392.429238)
					(end 122.450606 -392.429238)
				)
			)
		)
	)
	(zone
		(layers "B.Cu" "In15.Cu")
		(hatch none 0.5)
		(connect_pads
			(clearance 0)
		)
		(min_thickness 0.25)
		(keepout
			(tracks not_allowed)
			(vias allowed)
			(pads allowed)
			(copperpour not_allowed)
			(footprints allowed)
		)
		(placement
			(enabled no)
			(sheetname "")
		)
		(fill yes
			(thermal_gap 0.5)
			(thermal_bridge_width 0.5)
			(island_removal_mode 0)
		)
		(polygon
			(pts
				(arc
					(start 336.366104 -278.946102)
					(mid 335.736184 -278.946102)
					(end 336.366104 -278.946102)
				)
			)
		)
	)
	(zone
		(layers "B.Cu" "In15.Cu")
		(hatch none 0.5)
		(connect_pads
			(clearance 0)
		)
		(min_thickness 0.25)
		(keepout
			(tracks not_allowed)
			(vias allowed)
			(pads allowed)
			(copperpour not_allowed)
			(footprints allowed)
		)
		(placement
			(enabled no)
			(sheetname "")
		)
		(fill yes
			(thermal_gap 0.5)
			(thermal_bridge_width 0.5)
			(island_removal_mode 0)
		)
		(polygon
			(pts
				(arc
					(start 344.036904 -433.289964)
					(mid 343.262712 -433.289964)
					(end 344.036904 -433.289964)
				)
			)
		)
	)
	(zone
		(layers "B.Cu" "In15.Cu")
		(hatch none 0.5)
		(connect_pads
			(clearance 0)
		)
		(min_thickness 0.25)
		(keepout
			(tracks not_allowed)
			(vias allowed)
			(pads allowed)
			(copperpour not_allowed)
			(footprints allowed)
		)
		(placement
			(enabled no)
			(sheetname "")
		)
		(fill yes
			(thermal_gap 0.5)
			(thermal_bridge_width 0.5)
			(island_removal_mode 0)
		)
		(polygon
			(pts
				(arc
					(start 101.11613 -273.276314)
					(mid 100.48621 -273.276314)
					(end 101.11613 -273.276314)
				)
			)
		)
	)
	(zone
		(layers "B.Cu" "In15.Cu")
		(hatch none 0.5)
		(connect_pads
			(clearance 0)
		)
		(min_thickness 0.25)
		(keepout
			(tracks not_allowed)
			(vias allowed)
			(pads allowed)
			(copperpour not_allowed)
			(footprints allowed)
		)
		(placement
			(enabled no)
			(sheetname "")
		)
		(fill yes
			(thermal_gap 0.5)
			(thermal_bridge_width 0.5)
			(island_removal_mode 0)
		)
		(polygon
			(pts
				(arc
					(start 52.218082 -206.685388)
					(mid 51.550062 -206.685388)
					(end 52.218082 -206.685388)
				)
			)
		)
	)
	(zone
		(layers "B.Cu" "In15.Cu")
		(hatch none 0.5)
		(connect_pads
			(clearance 0)
		)
		(min_thickness 0.25)
		(keepout
			(tracks not_allowed)
			(vias allowed)
			(pads allowed)
			(copperpour not_allowed)
			(footprints allowed)
		)
		(placement
			(enabled no)
			(sheetname "")
		)
		(fill yes
			(thermal_gap 0.5)
			(thermal_bridge_width 0.5)
			(island_removal_mode 0)
		)
		(polygon
			(pts
				(arc
					(start 335.89595 -263.555988)
					(mid 335.26603 -263.555988)
					(end 335.89595 -263.555988)
				)
			)
		)
	)
	(zone
		(layers "B.Cu" "In15.Cu")
		(hatch none 0.5)
		(connect_pads
			(clearance 0)
		)
		(min_thickness 0.25)
		(keepout
			(tracks not_allowed)
			(vias allowed)
			(pads allowed)
			(copperpour not_allowed)
			(footprints allowed)
		)
		(placement
			(enabled no)
			(sheetname "")
		)
		(fill yes
			(thermal_gap 0.5)
			(thermal_bridge_width 0.5)
			(island_removal_mode 0)
		)
		(polygon
			(pts
				(arc
					(start 136.529826 -225.044508)
					(mid 135.899906 -225.044508)
					(end 136.529826 -225.044508)
				)
			)
		)
	)
	(zone
		(layers "B.Cu" "In15.Cu")
		(hatch none 0.5)
		(connect_pads
			(clearance 0)
		)
		(min_thickness 0.25)
		(keepout
			(tracks not_allowed)
			(vias allowed)
			(pads allowed)
			(copperpour not_allowed)
			(footprints allowed)
		)
		(placement
			(enabled no)
			(sheetname "")
		)
		(fill yes
			(thermal_gap 0.5)
			(thermal_bridge_width 0.5)
			(island_removal_mode 0)
		)
		(polygon
			(pts
				(arc
					(start 136.359646 -285.426404)
					(mid 135.729726 -285.426404)
					(end 136.359646 -285.426404)
				)
			)
		)
	)
	(zone
		(layers "B.Cu" "In15.Cu")
		(hatch none 0.5)
		(connect_pads
			(clearance 0)
		)
		(min_thickness 0.25)
		(keepout
			(tracks not_allowed)
			(vias allowed)
			(pads allowed)
			(copperpour not_allowed)
			(footprints allowed)
		)
		(placement
			(enabled no)
			(sheetname "")
		)
		(fill yes
			(thermal_gap 0.5)
			(thermal_bridge_width 0.5)
			(island_removal_mode 0)
		)
		(polygon
			(pts
				(arc
					(start 300.15815 -216.035128)
					(mid 299.49013 -216.035128)
					(end 300.15815 -216.035128)
				)
			)
		)
	)
	(zone
		(layers "B.Cu" "In15.Cu")
		(hatch none 0.5)
		(connect_pads
			(clearance 0)
		)
		(min_thickness 0.25)
		(keepout
			(tracks not_allowed)
			(vias allowed)
			(pads allowed)
			(copperpour not_allowed)
			(footprints allowed)
		)
		(placement
			(enabled no)
			(sheetname "")
		)
		(fill yes
			(thermal_gap 0.5)
			(thermal_bridge_width 0.5)
			(island_removal_mode 0)
		)
		(polygon
			(pts
				(arc
					(start 337.306158 -270.846042)
					(mid 336.676238 -270.846042)
					(end 337.306158 -270.846042)
				)
			)
		)
	)
	(zone
		(layers "B.Cu" "In15.Cu")
		(hatch none 0.5)
		(connect_pads
			(clearance 0)
		)
		(min_thickness 0.25)
		(keepout
			(tracks not_allowed)
			(vias allowed)
			(pads allowed)
			(copperpour not_allowed)
			(footprints allowed)
		)
		(placement
			(enabled no)
			(sheetname "")
		)
		(fill yes
			(thermal_gap 0.5)
			(thermal_bridge_width 0.5)
			(island_removal_mode 0)
		)
		(polygon
			(pts
				(arc
					(start 384.769868 -273.27606)
					(mid 384.139948 -273.27606)
					(end 384.769868 -273.27606)
				)
			)
		)
	)
	(zone
		(layers "B.Cu" "In15.Cu")
		(hatch none 0.5)
		(connect_pads
			(clearance 0)
		)
		(min_thickness 0.25)
		(keepout
			(tracks not_allowed)
			(vias allowed)
			(pads allowed)
			(copperpour not_allowed)
			(footprints allowed)
		)
		(placement
			(enabled no)
			(sheetname "")
		)
		(fill yes
			(thermal_gap 0.5)
			(thermal_bridge_width 0.5)
			(island_removal_mode 0)
		)
		(polygon
			(pts
				(arc
					(start 52.218082 -227.085398)
					(mid 51.550062 -227.085398)
					(end 52.218082 -227.085398)
				)
			)
		)
	)
	(zone
		(layers "B.Cu" "In15.Cu")
		(hatch none 0.5)
		(connect_pads
			(clearance 0)
		)
		(min_thickness 0.25)
		(keepout
			(tracks not_allowed)
			(vias allowed)
			(pads allowed)
			(copperpour not_allowed)
			(footprints allowed)
		)
		(placement
			(enabled no)
			(sheetname "")
		)
		(fill yes
			(thermal_gap 0.5)
			(thermal_bridge_width 0.5)
			(island_removal_mode 0)
		)
		(polygon
			(pts
				(arc
					(start 89.83599 -266.796266)
					(mid 89.20607 -266.796266)
					(end 89.83599 -266.796266)
				)
			)
		)
	)
	(zone
		(layers "B.Cu" "In15.Cu")
		(hatch none 0.5)
		(connect_pads
			(clearance 0)
		)
		(min_thickness 0.25)
		(keepout
			(tracks not_allowed)
			(vias allowed)
			(pads allowed)
			(copperpour not_allowed)
			(footprints allowed)
		)
		(placement
			(enabled no)
			(sheetname "")
		)
		(fill yes
			(thermal_gap 0.5)
			(thermal_bridge_width 0.5)
			(island_removal_mode 0)
		)
		(polygon
			(pts
				(arc
					(start 380.850648 -400.811238)
					(mid 380.182628 -400.811238)
					(end 380.850648 -400.811238)
				)
			)
		)
	)
	(zone
		(layers "B.Cu" "In15.Cu")
		(hatch none 0.5)
		(connect_pads
			(clearance 0)
		)
		(min_thickness 0.25)
		(keepout
			(tracks not_allowed)
			(vias allowed)
			(pads allowed)
			(copperpour not_allowed)
			(footprints allowed)
		)
		(placement
			(enabled no)
			(sheetname "")
		)
		(fill yes
			(thermal_gap 0.5)
			(thermal_bridge_width 0.5)
			(island_removal_mode 0)
		)
		(polygon
			(pts
				(arc
					(start 355.336094 -239.624108)
					(mid 354.706174 -239.624108)
					(end 355.336094 -239.624108)
				)
			)
		)
	)
	(zone
		(layers "B.Cu" "In15.Cu")
		(hatch none 0.5)
		(connect_pads
			(clearance 0)
		)
		(min_thickness 0.25)
		(keepout
			(tracks not_allowed)
			(vias allowed)
			(pads allowed)
			(copperpour not_allowed)
			(footprints allowed)
		)
		(placement
			(enabled no)
			(sheetname "")
		)
		(fill yes
			(thermal_gap 0.5)
			(thermal_bridge_width 0.5)
			(island_removal_mode 0)
		)
		(polygon
			(pts
				(arc
					(start 383.35966 -262.745982)
					(mid 382.72974 -262.745982)
					(end 383.35966 -262.745982)
				)
			)
		)
	)
	(zone
		(layers "B.Cu" "In15.Cu")
		(hatch none 0.5)
		(connect_pads
			(clearance 0)
		)
		(min_thickness 0.25)
		(keepout
			(tracks not_allowed)
			(vias allowed)
			(pads allowed)
			(copperpour not_allowed)
			(footprints allowed)
		)
		(placement
			(enabled no)
			(sheetname "")
		)
		(fill yes
			(thermal_gap 0.5)
			(thermal_bridge_width 0.5)
			(island_removal_mode 0)
		)
		(polygon
			(pts
				(arc
					(start 89.83599 -284.616398)
					(mid 89.20607 -284.616398)
					(end 89.83599 -284.616398)
				)
			)
		)
	)
	(zone
		(layers "B.Cu" "In15.Cu")
		(hatch none 0.5)
		(connect_pads
			(clearance 0)
		)
		(min_thickness 0.25)
		(keepout
			(tracks not_allowed)
			(vias allowed)
			(pads allowed)
			(copperpour not_allowed)
			(footprints allowed)
		)
		(placement
			(enabled no)
			(sheetname "")
		)
		(fill yes
			(thermal_gap 0.5)
			(thermal_bridge_width 0.5)
			(island_removal_mode 0)
		)
		(polygon
			(pts
				(arc
					(start 176.406048 -254.285242)
					(mid 175.738028 -254.285242)
					(end 176.406048 -254.285242)
				)
			)
		)
	)
	(zone
		(layers "B.Cu" "In15.Cu")
		(hatch none 0.5)
		(connect_pads
			(clearance 0)
		)
		(min_thickness 0.25)
		(keepout
			(tracks not_allowed)
			(vias allowed)
			(pads allowed)
			(copperpour not_allowed)
			(footprints allowed)
		)
		(placement
			(enabled no)
			(sheetname "")
		)
		(fill yes
			(thermal_gap 0.5)
			(thermal_bridge_width 0.5)
			(island_removal_mode 0)
		)
		(polygon
			(pts
				(arc
					(start 125.249686 -241.244374)
					(mid 124.619766 -241.244374)
					(end 125.249686 -241.244374)
				)
			)
		)
	)
	(zone
		(layers "B.Cu" "In15.Cu")
		(hatch none 0.5)
		(connect_pads
			(clearance 0)
		)
		(min_thickness 0.25)
		(keepout
			(tracks not_allowed)
			(vias allowed)
			(pads allowed)
			(copperpour not_allowed)
			(footprints allowed)
		)
		(placement
			(enabled no)
			(sheetname "")
		)
		(fill yes
			(thermal_gap 0.5)
			(thermal_bridge_width 0.5)
			(island_removal_mode 0)
		)
		(polygon
			(pts
				(arc
					(start 123.369578 -242.864386)
					(mid 122.739658 -242.864386)
					(end 123.369578 -242.864386)
				)
			)
		)
	)
	(zone
		(layers "B.Cu" "In15.Cu")
		(hatch none 0.5)
		(connect_pads
			(clearance 0)
		)
		(min_thickness 0.25)
		(keepout
			(tracks not_allowed)
			(vias allowed)
			(pads allowed)
			(copperpour not_allowed)
			(footprints allowed)
		)
		(placement
			(enabled no)
			(sheetname "")
		)
		(fill yes
			(thermal_gap 0.5)
			(thermal_bridge_width 0.5)
			(island_removal_mode 0)
		)
		(polygon
			(pts
				(arc
					(start 296.058082 -286.585152)
					(mid 295.390062 -286.585152)
					(end 296.058082 -286.585152)
				)
			)
		)
	)
	(zone
		(layers "B.Cu" "In15.Cu")
		(hatch none 0.5)
		(connect_pads
			(clearance 0)
		)
		(min_thickness 0.25)
		(keepout
			(tracks not_allowed)
			(vias allowed)
			(pads allowed)
			(copperpour not_allowed)
			(footprints allowed)
		)
		(placement
			(enabled no)
			(sheetname "")
		)
		(fill yes
			(thermal_gap 0.5)
			(thermal_bridge_width 0.5)
			(island_removal_mode 0)
		)
		(polygon
			(pts
				(arc
					(start 136.8298 -273.276314)
					(mid 136.19988 -273.276314)
					(end 136.8298 -273.276314)
				)
			)
		)
	)
	(zone
		(layers "B.Cu" "In15.Cu")
		(hatch none 0.5)
		(connect_pads
			(clearance 0)
		)
		(min_thickness 0.25)
		(keepout
			(tracks not_allowed)
			(vias allowed)
			(pads allowed)
			(copperpour not_allowed)
			(footprints allowed)
		)
		(placement
			(enabled no)
			(sheetname "")
		)
		(fill yes
			(thermal_gap 0.5)
			(thermal_bridge_width 0.5)
			(island_removal_mode 0)
		)
		(polygon
			(pts
				(arc
					(start 384.769868 -270.036036)
					(mid 384.139948 -270.036036)
					(end 384.769868 -270.036036)
				)
			)
		)
	)
	(zone
		(layers "B.Cu" "In15.Cu")
		(hatch none 0.5)
		(connect_pads
			(clearance 0)
		)
		(min_thickness 0.25)
		(keepout
			(tracks not_allowed)
			(vias allowed)
			(pads allowed)
			(copperpour not_allowed)
			(footprints allowed)
		)
		(placement
			(enabled no)
			(sheetname "")
		)
		(fill yes
			(thermal_gap 0.5)
			(thermal_bridge_width 0.5)
			(island_removal_mode 0)
		)
		(polygon
			(pts
				(arc
					(start 123.369578 -239.624362)
					(mid 122.739658 -239.624362)
					(end 123.369578 -239.624362)
				)
			)
		)
	)
	(zone
		(layers "B.Cu" "In15.Cu")
		(hatch none 0.5)
		(connect_pads
			(clearance 0)
		)
		(min_thickness 0.25)
		(keepout
			(tracks not_allowed)
			(vias allowed)
			(pads allowed)
			(copperpour not_allowed)
			(footprints allowed)
		)
		(placement
			(enabled no)
			(sheetname "")
		)
		(fill yes
			(thermal_gap 0.5)
			(thermal_bridge_width 0.5)
			(island_removal_mode 0)
		)
		(polygon
			(pts
				(arc
					(start 48.118014 -308.685438)
					(mid 47.449994 -308.685438)
					(end 48.118014 -308.685438)
				)
			)
		)
	)
	(zone
		(layers "B.Cu" "In15.Cu")
		(hatch none 0.5)
		(connect_pads
			(clearance 0)
		)
		(min_thickness 0.25)
		(keepout
			(tracks not_allowed)
			(vias allowed)
			(pads allowed)
			(copperpour not_allowed)
			(footprints allowed)
		)
		(placement
			(enabled no)
			(sheetname "")
		)
		(fill yes
			(thermal_gap 0.5)
			(thermal_bridge_width 0.5)
			(island_removal_mode 0)
		)
		(polygon
			(pts
				(arc
					(start 349.995998 -270.036036)
					(mid 349.366078 -270.036036)
					(end 349.995998 -270.036036)
				)
			)
		)
	)
	(zone
		(layers "B.Cu" "In15.Cu")
		(hatch none 0.5)
		(connect_pads
			(clearance 0)
		)
		(min_thickness 0.25)
		(keepout
			(tracks not_allowed)
			(vias allowed)
			(pads allowed)
			(copperpour not_allowed)
			(footprints allowed)
		)
		(placement
			(enabled no)
			(sheetname "")
		)
		(fill yes
			(thermal_gap 0.5)
			(thermal_bridge_width 0.5)
			(island_removal_mode 0)
		)
		(polygon
			(pts
				(arc
					(start 383.059686 -240.434114)
					(mid 382.429766 -240.434114)
					(end 383.059686 -240.434114)
				)
			)
		)
	)
	(zone
		(layers "B.Cu" "In15.Cu")
		(hatch none 0.5)
		(connect_pads
			(clearance 0)
		)
		(min_thickness 0.25)
		(keepout
			(tracks not_allowed)
			(vias allowed)
			(pads allowed)
			(copperpour not_allowed)
			(footprints allowed)
		)
		(placement
			(enabled no)
			(sheetname "")
		)
		(fill yes
			(thermal_gap 0.5)
			(thermal_bridge_width 0.5)
			(island_removal_mode 0)
		)
		(polygon
			(pts
				(arc
					(start 162.560254 -373.96293)
					(mid 161.892234 -373.96293)
					(end 162.560254 -373.96293)
				)
			)
		)
	)
	(zone
		(layers "B.Cu" "In15.Cu")
		(hatch none 0.5)
		(connect_pads
			(clearance 0)
		)
		(min_thickness 0.25)
		(keepout
			(tracks not_allowed)
			(vias allowed)
			(pads allowed)
			(copperpour not_allowed)
			(footprints allowed)
		)
		(placement
			(enabled no)
			(sheetname "")
		)
		(fill yes
			(thermal_gap 0.5)
			(thermal_bridge_width 0.5)
			(island_removal_mode 0)
		)
		(polygon
			(pts
				(arc
					(start 300.15815 -225.385122)
					(mid 299.49013 -225.385122)
					(end 300.15815 -225.385122)
				)
			)
		)
	)
	(zone
		(layers "B.Cu" "In15.Cu")
		(hatch none 0.5)
		(connect_pads
			(clearance 0)
		)
		(min_thickness 0.25)
		(keepout
			(tracks not_allowed)
			(vias allowed)
			(pads allowed)
			(copperpour not_allowed)
			(footprints allowed)
		)
		(placement
			(enabled no)
			(sheetname "")
		)
		(fill yes
			(thermal_gap 0.5)
			(thermal_bridge_width 0.5)
			(island_removal_mode 0)
		)
		(polygon
			(pts
				(arc
					(start 117.729762 -241.244374)
					(mid 117.099842 -241.244374)
					(end 117.729762 -241.244374)
				)
			)
		)
	)
	(zone
		(layers "B.Cu" "In15.Cu")
		(hatch none 0.5)
		(connect_pads
			(clearance 0)
		)
		(min_thickness 0.25)
		(keepout
			(tracks not_allowed)
			(vias allowed)
			(pads allowed)
			(copperpour not_allowed)
			(footprints allowed)
		)
		(placement
			(enabled no)
			(sheetname "")
		)
		(fill yes
			(thermal_gap 0.5)
			(thermal_bridge_width 0.5)
			(island_removal_mode 0)
		)
		(polygon
			(pts
				(arc
					(start 176.406048 -242.385342)
					(mid 175.738028 -242.385342)
					(end 176.406048 -242.385342)
				)
			)
		)
	)
	(zone
		(layers "B.Cu" "In15.Cu")
		(hatch none 0.5)
		(connect_pads
			(clearance 0)
		)
		(min_thickness 0.25)
		(keepout
			(tracks not_allowed)
			(vias allowed)
			(pads allowed)
			(copperpour not_allowed)
			(footprints allowed)
		)
		(placement
			(enabled no)
			(sheetname "")
		)
		(fill yes
			(thermal_gap 0.5)
			(thermal_bridge_width 0.5)
			(island_removal_mode 0)
		)
		(polygon
			(pts
				(arc
					(start 89.536016 -241.244374)
					(mid 88.906096 -241.244374)
					(end 89.536016 -241.244374)
				)
			)
		)
	)
	(zone
		(layers "B.Cu" "In15.Cu")
		(hatch none 0.5)
		(connect_pads
			(clearance 0)
		)
		(min_thickness 0.25)
		(keepout
			(tracks not_allowed)
			(vias allowed)
			(pads allowed)
			(copperpour not_allowed)
			(footprints allowed)
		)
		(placement
			(enabled no)
			(sheetname "")
		)
		(fill yes
			(thermal_gap 0.5)
			(thermal_bridge_width 0.5)
			(island_removal_mode 0)
		)
		(polygon
			(pts
				(arc
					(start 315.036708 -433.289964)
					(mid 314.262516 -433.289964)
					(end 315.036708 -433.289964)
				)
			)
		)
	)
	(zone
		(layers "B.Cu" "In15.Cu")
		(hatch none 0.5)
		(connect_pads
			(clearance 0)
		)
		(min_thickness 0.25)
		(keepout
			(tracks not_allowed)
			(vias allowed)
			(pads allowed)
			(copperpour not_allowed)
			(footprints allowed)
		)
		(placement
			(enabled no)
			(sheetname "")
		)
		(fill yes
			(thermal_gap 0.5)
			(thermal_bridge_width 0.5)
			(island_removal_mode 0)
		)
		(polygon
			(pts
				(arc
					(start 296.058082 -250.03506)
					(mid 295.390062 -250.03506)
					(end 296.058082 -250.03506)
				)
			)
		)
	)
	(zone
		(layers "B.Cu" "In15.Cu")
		(hatch none 0.5)
		(connect_pads
			(clearance 0)
		)
		(min_thickness 0.25)
		(keepout
			(tracks not_allowed)
			(vias allowed)
			(pads allowed)
			(copperpour not_allowed)
			(footprints allowed)
		)
		(placement
			(enabled no)
			(sheetname "")
		)
		(fill yes
			(thermal_gap 0.5)
			(thermal_bridge_width 0.5)
			(island_removal_mode 0)
		)
		(polygon
			(pts
				(arc
					(start 48.118014 -267.03528)
					(mid 47.449994 -267.03528)
					(end 48.118014 -267.03528)
				)
			)
		)
	)
	(zone
		(layers "B.Cu" "In15.Cu")
		(hatch none 0.5)
		(connect_pads
			(clearance 0)
		)
		(min_thickness 0.25)
		(keepout
			(tracks not_allowed)
			(vias allowed)
			(pads allowed)
			(copperpour not_allowed)
			(footprints allowed)
		)
		(placement
			(enabled no)
			(sheetname "")
		)
		(fill yes
			(thermal_gap 0.5)
			(thermal_bridge_width 0.5)
			(island_removal_mode 0)
		)
		(polygon
			(pts
				(arc
					(start 407.137108 -434.48986)
					(mid 406.362916 -434.48986)
					(end 407.137108 -434.48986)
				)
			)
		)
	)
	(zone
		(layers "B.Cu" "In15.Cu")
		(hatch none 0.5)
		(connect_pads
			(clearance 0)
		)
		(min_thickness 0.25)
		(keepout
			(tracks not_allowed)
			(vias allowed)
			(pads allowed)
			(copperpour not_allowed)
			(footprints allowed)
		)
		(placement
			(enabled no)
			(sheetname "")
		)
		(fill yes
			(thermal_gap 0.5)
			(thermal_bridge_width 0.5)
			(island_removal_mode 0)
		)
		(polygon
			(pts
				(arc
					(start 296.058082 -218.585034)
					(mid 295.390062 -218.585034)
					(end 296.058082 -218.585034)
				)
			)
		)
	)
	(zone
		(layers "B.Cu" "In15.Cu")
		(hatch none 0.5)
		(connect_pads
			(clearance 0)
		)
		(min_thickness 0.25)
		(keepout
			(tracks not_allowed)
			(vias allowed)
			(pads allowed)
			(copperpour not_allowed)
			(footprints allowed)
		)
		(placement
			(enabled no)
			(sheetname "")
		)
		(fill yes
			(thermal_gap 0.5)
			(thermal_bridge_width 0.5)
			(island_removal_mode 0)
		)
		(polygon
			(pts
				(arc
					(start 136.529826 -228.284532)
					(mid 135.899906 -228.284532)
					(end 136.529826 -228.284532)
				)
			)
		)
	)
	(zone
		(layers "B.Cu" "In15.Cu")
		(hatch none 0.5)
		(connect_pads
			(clearance 0)
		)
		(min_thickness 0.25)
		(keepout
			(tracks not_allowed)
			(vias allowed)
			(pads allowed)
			(copperpour not_allowed)
			(footprints allowed)
		)
		(placement
			(enabled no)
			(sheetname "")
		)
		(fill yes
			(thermal_gap 0.5)
			(thermal_bridge_width 0.5)
			(island_removal_mode 0)
		)
		(polygon
			(pts
				(arc
					(start 424.346116 -300.185074)
					(mid 423.678096 -300.185074)
					(end 424.346116 -300.185074)
				)
			)
		)
	)
	(zone
		(layers "B.Cu" "In15.Cu")
		(hatch none 0.5)
		(connect_pads
			(clearance 0)
		)
		(min_thickness 0.25)
		(keepout
			(tracks not_allowed)
			(vias allowed)
			(pads allowed)
			(copperpour not_allowed)
			(footprints allowed)
		)
		(placement
			(enabled no)
			(sheetname "")
		)
		(fill yes
			(thermal_gap 0.5)
			(thermal_bridge_width 0.5)
			(island_removal_mode 0)
		)
		(polygon
			(pts
				(arc
					(start 136.529826 -236.384338)
					(mid 135.899906 -236.384338)
					(end 136.529826 -236.384338)
				)
			)
		)
	)
	(zone
		(layers "B.Cu" "In15.Cu")
		(hatch none 0.5)
		(connect_pads
			(clearance 0)
		)
		(min_thickness 0.25)
		(keepout
			(tracks not_allowed)
			(vias allowed)
			(pads allowed)
			(copperpour not_allowed)
			(footprints allowed)
		)
		(placement
			(enabled no)
			(sheetname "")
		)
		(fill yes
			(thermal_gap 0.5)
			(thermal_bridge_width 0.5)
			(island_removal_mode 0)
		)
		(polygon
			(pts
				(arc
					(start 135.119618 -230.71455)
					(mid 134.489698 -230.71455)
					(end 135.119618 -230.71455)
				)
			)
		)
	)
	(zone
		(layers "B.Cu" "In15.Cu")
		(hatch none 0.5)
		(connect_pads
			(clearance 0)
		)
		(min_thickness 0.25)
		(keepout
			(tracks not_allowed)
			(vias allowed)
			(pads allowed)
			(copperpour not_allowed)
			(footprints allowed)
		)
		(placement
			(enabled no)
			(sheetname "")
		)
		(fill yes
			(thermal_gap 0.5)
			(thermal_bridge_width 0.5)
			(island_removal_mode 0)
		)
		(polygon
			(pts
				(arc
					(start 315.036708 -434.48986)
					(mid 314.262516 -434.48986)
					(end 315.036708 -434.48986)
				)
			)
		)
	)
	(zone
		(layers "B.Cu" "In15.Cu")
		(hatch none 0.5)
		(connect_pads
			(clearance 0)
		)
		(min_thickness 0.25)
		(keepout
			(tracks not_allowed)
			(vias allowed)
			(pads allowed)
			(copperpour not_allowed)
			(footprints allowed)
		)
		(placement
			(enabled no)
			(sheetname "")
		)
		(fill yes
			(thermal_gap 0.5)
			(thermal_bridge_width 0.5)
			(island_removal_mode 0)
		)
		(polygon
			(pts
				(arc
					(start 172.30598 -227.935282)
					(mid 171.63796 -227.935282)
					(end 172.30598 -227.935282)
				)
			)
		)
	)
	(zone
		(layers "B.Cu" "In15.Cu")
		(hatch none 0.5)
		(connect_pads
			(clearance 0)
		)
		(min_thickness 0.25)
		(keepout
			(tracks not_allowed)
			(vias allowed)
			(pads allowed)
			(copperpour not_allowed)
			(footprints allowed)
		)
		(placement
			(enabled no)
			(sheetname "")
		)
		(fill yes
			(thermal_gap 0.5)
			(thermal_bridge_width 0.5)
			(island_removal_mode 0)
		)
		(polygon
			(pts
				(arc
					(start 336.06613 -243.674138)
					(mid 335.43621 -243.674138)
					(end 336.06613 -243.674138)
				)
			)
		)
	)
	(zone
		(layers "B.Cu" "In15.Cu")
		(hatch none 0.5)
		(connect_pads
			(clearance 0)
		)
		(min_thickness 0.25)
		(keepout
			(tracks not_allowed)
			(vias allowed)
			(pads allowed)
			(copperpour not_allowed)
			(footprints allowed)
		)
		(placement
			(enabled no)
			(sheetname "")
		)
		(fill yes
			(thermal_gap 0.5)
			(thermal_bridge_width 0.5)
			(island_removal_mode 0)
		)
		(polygon
			(pts
				(arc
					(start 176.406048 -270.435324)
					(mid 175.738028 -270.435324)
					(end 176.406048 -270.435324)
				)
			)
		)
	)
	(zone
		(layers "B.Cu" "In15.Cu")
		(hatch none 0.5)
		(connect_pads
			(clearance 0)
		)
		(min_thickness 0.25)
		(keepout
			(tracks not_allowed)
			(vias allowed)
			(pads allowed)
			(copperpour not_allowed)
			(footprints allowed)
		)
		(placement
			(enabled no)
			(sheetname "")
		)
		(fill yes
			(thermal_gap 0.5)
			(thermal_bridge_width 0.5)
			(island_removal_mode 0)
		)
		(polygon
			(pts
				(arc
					(start 300.15815 -219.435172)
					(mid 299.49013 -219.435172)
					(end 300.15815 -219.435172)
				)
			)
		)
	)
	(zone
		(layers "B.Cu" "In15.Cu")
		(hatch none 0.5)
		(connect_pads
			(clearance 0)
		)
		(min_thickness 0.25)
		(keepout
			(tracks not_allowed)
			(vias allowed)
			(pads allowed)
			(copperpour not_allowed)
			(footprints allowed)
		)
		(placement
			(enabled no)
			(sheetname "")
		)
		(fill yes
			(thermal_gap 0.5)
			(thermal_bridge_width 0.5)
			(island_removal_mode 0)
		)
		(polygon
			(pts
				(arc
					(start 87.655908 -244.484398)
					(mid 87.025988 -244.484398)
					(end 87.655908 -244.484398)
				)
			)
		)
	)
	(zone
		(layers "B.Cu" "In15.Cu")
		(hatch none 0.5)
		(connect_pads
			(clearance 0)
		)
		(min_thickness 0.25)
		(keepout
			(tracks not_allowed)
			(vias allowed)
			(pads allowed)
			(copperpour not_allowed)
			(footprints allowed)
		)
		(placement
			(enabled no)
			(sheetname "")
		)
		(fill yes
			(thermal_gap 0.5)
			(thermal_bridge_width 0.5)
			(island_removal_mode 0)
		)
		(polygon
			(pts
				(arc
					(start 176.406048 -266.185396)
					(mid 175.738028 -266.185396)
					(end 176.406048 -266.185396)
				)
			)
		)
	)
	(zone
		(layers "B.Cu" "In15.Cu")
		(hatch none 0.5)
		(connect_pads
			(clearance 0)
		)
		(min_thickness 0.25)
		(keepout
			(tracks not_allowed)
			(vias allowed)
			(pads allowed)
			(copperpour not_allowed)
			(footprints allowed)
		)
		(placement
			(enabled no)
			(sheetname "")
		)
		(fill yes
			(thermal_gap 0.5)
			(thermal_bridge_width 0.5)
			(island_removal_mode 0)
		)
		(polygon
			(pts
				(arc
					(start 382.589786 -234.764072)
					(mid 381.959866 -234.764072)
					(end 382.589786 -234.764072)
				)
			)
		)
	)
	(zone
		(layers "B.Cu" "In15.Cu")
		(hatch none 0.5)
		(connect_pads
			(clearance 0)
		)
		(min_thickness 0.25)
		(keepout
			(tracks not_allowed)
			(vias allowed)
			(pads allowed)
			(copperpour not_allowed)
			(footprints allowed)
		)
		(placement
			(enabled no)
			(sheetname "")
		)
		(fill yes
			(thermal_gap 0.5)
			(thermal_bridge_width 0.5)
			(island_removal_mode 0)
		)
		(polygon
			(pts
				(arc
					(start 48.118014 -265.335258)
					(mid 47.449994 -265.335258)
					(end 48.118014 -265.335258)
				)
			)
		)
	)
	(zone
		(layers "B.Cu" "In15.Cu")
		(hatch none 0.5)
		(connect_pads
			(clearance 0)
		)
		(min_thickness 0.25)
		(keepout
			(tracks not_allowed)
			(vias allowed)
			(pads allowed)
			(copperpour not_allowed)
			(footprints allowed)
		)
		(placement
			(enabled no)
			(sheetname "")
		)
		(fill yes
			(thermal_gap 0.5)
			(thermal_bridge_width 0.5)
			(island_removal_mode 0)
		)
		(polygon
			(pts
				(arc
					(start 52.218082 -313.78525)
					(mid 51.550062 -313.78525)
					(end 52.218082 -313.78525)
				)
			)
		)
	)
	(zone
		(layers "B.Cu" "In15.Cu")
		(hatch none 0.5)
		(connect_pads
			(clearance 0)
		)
		(min_thickness 0.25)
		(keepout
			(tracks not_allowed)
			(vias allowed)
			(pads allowed)
			(copperpour not_allowed)
			(footprints allowed)
		)
		(placement
			(enabled no)
			(sheetname "")
		)
		(fill yes
			(thermal_gap 0.5)
			(thermal_bridge_width 0.5)
			(island_removal_mode 0)
		)
		(polygon
			(pts
				(arc
					(start 89.36609 -291.906198)
					(mid 88.73617 -291.906198)
					(end 89.36609 -291.906198)
				)
			)
		)
	)
	(zone
		(layers "B.Cu" "In15.Cu")
		(hatch none 0.5)
		(connect_pads
			(clearance 0)
		)
		(min_thickness 0.25)
		(keepout
			(tracks not_allowed)
			(vias allowed)
			(pads allowed)
			(copperpour not_allowed)
			(footprints allowed)
		)
		(placement
			(enabled no)
			(sheetname "")
		)
		(fill yes
			(thermal_gap 0.5)
			(thermal_bridge_width 0.5)
			(island_removal_mode 0)
		)
		(polygon
			(pts
				(arc
					(start 172.30598 -280.635202)
					(mid 171.63796 -280.635202)
					(end 172.30598 -280.635202)
				)
			)
		)
	)
	(zone
		(layers "B.Cu" "In15.Cu")
		(hatch none 0.5)
		(connect_pads
			(clearance 0)
		)
		(min_thickness 0.25)
		(keepout
			(tracks not_allowed)
			(vias allowed)
			(pads allowed)
			(copperpour not_allowed)
			(footprints allowed)
		)
		(placement
			(enabled no)
			(sheetname "")
		)
		(fill yes
			(thermal_gap 0.5)
			(thermal_bridge_width 0.5)
			(island_removal_mode 0)
		)
		(polygon
			(pts
				(arc
					(start 52.218082 -216.035382)
					(mid 51.550062 -216.035382)
					(end 52.218082 -216.035382)
				)
			)
		)
	)
	(zone
		(layers "B.Cu" "In15.Cu")
		(hatch none 0.5)
		(connect_pads
			(clearance 0)
		)
		(min_thickness 0.25)
		(keepout
			(tracks not_allowed)
			(vias allowed)
			(pads allowed)
			(copperpour not_allowed)
			(footprints allowed)
		)
		(placement
			(enabled no)
			(sheetname "")
		)
		(fill yes
			(thermal_gap 0.5)
			(thermal_bridge_width 0.5)
			(island_removal_mode 0)
		)
		(polygon
			(pts
				(arc
					(start 348.75597 -239.624108)
					(mid 348.12605 -239.624108)
					(end 348.75597 -239.624108)
				)
			)
		)
	)
	(zone
		(layers "B.Cu" "In15.Cu")
		(hatch none 0.5)
		(connect_pads
			(clearance 0)
		)
		(min_thickness 0.25)
		(keepout
			(tracks not_allowed)
			(vias allowed)
			(pads allowed)
			(copperpour not_allowed)
			(footprints allowed)
		)
		(placement
			(enabled no)
			(sheetname "")
		)
		(fill yes
			(thermal_gap 0.5)
			(thermal_bridge_width 0.5)
			(island_removal_mode 0)
		)
		(polygon
			(pts
				(arc
					(start 321.036696 -434.289962)
					(mid 320.262504 -434.289962)
					(end 321.036696 -434.289962)
				)
			)
		)
	)
	(zone
		(layers "B.Cu" "In15.Cu")
		(hatch none 0.5)
		(connect_pads
			(clearance 0)
		)
		(min_thickness 0.25)
		(keepout
			(tracks not_allowed)
			(vias allowed)
			(pads allowed)
			(copperpour not_allowed)
			(footprints allowed)
		)
		(placement
			(enabled no)
			(sheetname "")
		)
		(fill yes
			(thermal_gap 0.5)
			(thermal_bridge_width 0.5)
			(island_removal_mode 0)
		)
		(polygon
			(pts
				(arc
					(start 136.359646 -272.466308)
					(mid 135.729726 -272.466308)
					(end 136.359646 -272.466308)
				)
			)
		)
	)
	(zone
		(layers "B.Cu" "In15.Cu")
		(hatch none 0.5)
		(connect_pads
			(clearance 0)
		)
		(min_thickness 0.25)
		(keepout
			(tracks not_allowed)
			(vias allowed)
			(pads allowed)
			(copperpour not_allowed)
			(footprints allowed)
		)
		(placement
			(enabled no)
			(sheetname "")
		)
		(fill yes
			(thermal_gap 0.5)
			(thermal_bridge_width 0.5)
			(island_removal_mode 0)
		)
		(polygon
			(pts
				(arc
					(start 346.2782 -400.811238)
					(mid 345.61018 -400.811238)
					(end 346.2782 -400.811238)
				)
			)
		)
	)
	(zone
		(layers "B.Cu" "In15.Cu")
		(hatch none 0.5)
		(connect_pads
			(clearance 0)
		)
		(min_thickness 0.25)
		(keepout
			(tracks not_allowed)
			(vias allowed)
			(pads allowed)
			(copperpour not_allowed)
			(footprints allowed)
		)
		(placement
			(enabled no)
			(sheetname "")
		)
		(fill yes
			(thermal_gap 0.5)
			(thermal_bridge_width 0.5)
			(island_removal_mode 0)
		)
		(polygon
			(pts
				(arc
					(start 349.696024 -242.864132)
					(mid 349.066104 -242.864132)
					(end 349.696024 -242.864132)
				)
			)
		)
	)
	(zone
		(layers "B.Cu" "In15.Cu")
		(hatch none 0.5)
		(connect_pads
			(clearance 0)
		)
		(min_thickness 0.25)
		(keepout
			(tracks not_allowed)
			(vias allowed)
			(pads allowed)
			(copperpour not_allowed)
			(footprints allowed)
		)
		(placement
			(enabled no)
			(sheetname "")
		)
		(fill yes
			(thermal_gap 0.5)
			(thermal_bridge_width 0.5)
			(island_removal_mode 0)
		)
		(polygon
			(pts
				(arc
					(start 176.406048 -212.635338)
					(mid 175.738028 -212.635338)
					(end 176.406048 -212.635338)
				)
			)
		)
	)
	(zone
		(layers "B.Cu" "In15.Cu")
		(hatch none 0.5)
		(connect_pads
			(clearance 0)
		)
		(min_thickness 0.25)
		(keepout
			(tracks not_allowed)
			(vias allowed)
			(pads allowed)
			(copperpour not_allowed)
			(footprints allowed)
		)
		(placement
			(enabled no)
			(sheetname "")
		)
		(fill yes
			(thermal_gap 0.5)
			(thermal_bridge_width 0.5)
			(island_removal_mode 0)
		)
		(polygon
			(pts
				(arc
					(start 383.059686 -232.334054)
					(mid 382.429766 -232.334054)
					(end 383.059686 -232.334054)
				)
			)
		)
	)
	(zone
		(layers "B.Cu" "In15.Cu")
		(hatch none 0.5)
		(connect_pads
			(clearance 0)
		)
		(min_thickness 0.25)
		(keepout
			(tracks not_allowed)
			(vias allowed)
			(pads allowed)
			(copperpour not_allowed)
			(footprints allowed)
		)
		(placement
			(enabled no)
			(sheetname "")
		)
		(fill yes
			(thermal_gap 0.5)
			(thermal_bridge_width 0.5)
			(island_removal_mode 0)
		)
		(polygon
			(pts
				(arc
					(start 304.506122 -394.385292)
					(mid 303.876202 -394.385292)
					(end 304.506122 -394.385292)
				)
			)
		)
	)
	(zone
		(layers "B.Cu" "In15.Cu")
		(hatch none 0.5)
		(connect_pads
			(clearance 0)
		)
		(min_thickness 0.25)
		(keepout
			(tracks not_allowed)
			(vias allowed)
			(pads allowed)
			(copperpour not_allowed)
			(footprints allowed)
		)
		(placement
			(enabled no)
			(sheetname "")
		)
		(fill yes
			(thermal_gap 0.5)
			(thermal_bridge_width 0.5)
			(island_removal_mode 0)
		)
		(polygon
			(pts
				(arc
					(start 382.589786 -242.864132)
					(mid 381.959866 -242.864132)
					(end 382.589786 -242.864132)
				)
			)
		)
	)
	(zone
		(layers "B.Cu" "In15.Cu")
		(hatch none 0.5)
		(connect_pads
			(clearance 0)
		)
		(min_thickness 0.25)
		(keepout
			(tracks not_allowed)
			(vias allowed)
			(pads allowed)
			(copperpour not_allowed)
			(footprints allowed)
		)
		(placement
			(enabled no)
			(sheetname "")
		)
		(fill yes
			(thermal_gap 0.5)
			(thermal_bridge_width 0.5)
			(island_removal_mode 0)
		)
		(polygon
			(pts
				(arc
					(start 343.878154 -401.674838)
					(mid 343.210134 -401.674838)
					(end 343.878154 -401.674838)
				)
			)
		)
	)
	(zone
		(layers "B.Cu" "In15.Cu")
		(hatch none 0.5)
		(connect_pads
			(clearance 0)
		)
		(min_thickness 0.25)
		(keepout
			(tracks not_allowed)
			(vias allowed)
			(pads allowed)
			(copperpour not_allowed)
			(footprints allowed)
		)
		(placement
			(enabled no)
			(sheetname "")
		)
		(fill yes
			(thermal_gap 0.5)
			(thermal_bridge_width 0.5)
			(island_removal_mode 0)
		)
		(polygon
			(pts
				(arc
					(start 335.89595 -270.036036)
					(mid 335.26603 -270.036036)
					(end 335.89595 -270.036036)
				)
			)
		)
	)
	(zone
		(layers "B.Cu" "In15.Cu")
		(hatch none 0.5)
		(connect_pads
			(clearance 0)
		)
		(min_thickness 0.25)
		(keepout
			(tracks not_allowed)
			(vias allowed)
			(pads allowed)
			(copperpour not_allowed)
			(footprints allowed)
		)
		(placement
			(enabled no)
			(sheetname "")
		)
		(fill yes
			(thermal_gap 0.5)
			(thermal_bridge_width 0.5)
			(island_removal_mode 0)
		)
		(polygon
			(pts
				(arc
					(start 134.136892 -433.289964)
					(mid 133.3627 -433.289964)
					(end 134.136892 -433.289964)
				)
			)
		)
	)
	(zone
		(layers "B.Cu" "In15.Cu")
		(hatch none 0.5)
		(connect_pads
			(clearance 0)
		)
		(min_thickness 0.25)
		(keepout
			(tracks not_allowed)
			(vias allowed)
			(pads allowed)
			(copperpour not_allowed)
			(footprints allowed)
		)
		(placement
			(enabled no)
			(sheetname "")
		)
		(fill yes
			(thermal_gap 0.5)
			(thermal_bridge_width 0.5)
			(island_removal_mode 0)
		)
		(polygon
			(pts
				(arc
					(start 386.136896 -433.289964)
					(mid 385.362704 -433.289964)
					(end 386.136896 -433.289964)
				)
			)
		)
	)
	(zone
		(layers "B.Cu" "In15.Cu")
		(hatch none 0.5)
		(connect_pads
			(clearance 0)
		)
		(min_thickness 0.25)
		(keepout
			(tracks not_allowed)
			(vias allowed)
			(pads allowed)
			(copperpour not_allowed)
			(footprints allowed)
		)
		(placement
			(enabled no)
			(sheetname "")
		)
		(fill yes
			(thermal_gap 0.5)
			(thermal_bridge_width 0.5)
			(island_removal_mode 0)
		)
		(polygon
			(pts
				(arc
					(start 335.595976 -225.044254)
					(mid 334.966056 -225.044254)
					(end 335.595976 -225.044254)
				)
			)
		)
	)
	(zone
		(layers "B.Cu" "In15.Cu")
		(hatch none 0.5)
		(connect_pads
			(clearance 0)
		)
		(min_thickness 0.25)
		(keepout
			(tracks not_allowed)
			(vias allowed)
			(pads allowed)
			(copperpour not_allowed)
			(footprints allowed)
		)
		(placement
			(enabled no)
			(sheetname "")
		)
		(fill yes
			(thermal_gap 0.5)
			(thermal_bridge_width 0.5)
			(island_removal_mode 0)
		)
		(polygon
			(pts
				(arc
					(start 296.058082 -277.235158)
					(mid 295.390062 -277.235158)
					(end 296.058082 -277.235158)
				)
			)
		)
	)
	(zone
		(layers "B.Cu" "In15.Cu")
		(hatch none 0.5)
		(connect_pads
			(clearance 0)
		)
		(min_thickness 0.25)
		(keepout
			(tracks not_allowed)
			(vias allowed)
			(pads allowed)
			(copperpour not_allowed)
			(footprints allowed)
		)
		(placement
			(enabled no)
			(sheetname "")
		)
		(fill yes
			(thermal_gap 0.5)
			(thermal_bridge_width 0.5)
			(island_removal_mode 0)
		)
		(polygon
			(pts
				(arc
					(start 172.30598 -216.885266)
					(mid 171.63796 -216.885266)
					(end 172.30598 -216.885266)
				)
			)
		)
	)
	(zone
		(layers "B.Cu" "In15.Cu")
		(hatch none 0.5)
		(connect_pads
			(clearance 0)
		)
		(min_thickness 0.25)
		(keepout
			(tracks not_allowed)
			(vias allowed)
			(pads allowed)
			(copperpour not_allowed)
			(footprints allowed)
		)
		(placement
			(enabled no)
			(sheetname "")
		)
		(fill yes
			(thermal_gap 0.5)
			(thermal_bridge_width 0.5)
			(island_removal_mode 0)
		)
		(polygon
			(pts
				(arc
					(start 420.246048 -282.33497)
					(mid 419.578028 -282.33497)
					(end 420.246048 -282.33497)
				)
			)
		)
	)
	(zone
		(layers "B.Cu" "In15.Cu")
		(hatch none 0.5)
		(connect_pads
			(clearance 0)
		)
		(min_thickness 0.25)
		(keepout
			(tracks not_allowed)
			(vias allowed)
			(pads allowed)
			(copperpour not_allowed)
			(footprints allowed)
		)
		(placement
			(enabled no)
			(sheetname "")
		)
		(fill yes
			(thermal_gap 0.5)
			(thermal_bridge_width 0.5)
			(island_removal_mode 0)
		)
		(polygon
			(pts
				(arc
					(start 87.655908 -233.144314)
					(mid 87.025988 -233.144314)
					(end 87.655908 -233.144314)
				)
			)
		)
	)
	(zone
		(layers "B.Cu" "In15.Cu")
		(hatch none 0.5)
		(connect_pads
			(clearance 0)
		)
		(min_thickness 0.25)
		(keepout
			(tracks not_allowed)
			(vias allowed)
			(pads allowed)
			(copperpour not_allowed)
			(footprints allowed)
		)
		(placement
			(enabled no)
			(sheetname "")
		)
		(fill yes
			(thermal_gap 0.5)
			(thermal_bridge_width 0.5)
			(island_removal_mode 0)
		)
		(polygon
			(pts
				(arc
					(start 424.346116 -233.035094)
					(mid 423.678096 -233.035094)
					(end 424.346116 -233.035094)
				)
			)
		)
	)
	(zone
		(layers "B.Cu" "In15.Cu")
		(hatch none 0.5)
		(connect_pads
			(clearance 0)
		)
		(min_thickness 0.25)
		(keepout
			(tracks not_allowed)
			(vias allowed)
			(pads allowed)
			(copperpour not_allowed)
			(footprints allowed)
		)
		(placement
			(enabled no)
			(sheetname "")
		)
		(fill yes
			(thermal_gap 0.5)
			(thermal_bridge_width 0.5)
			(island_removal_mode 0)
		)
		(polygon
			(pts
				(arc
					(start 424.346116 -270.43507)
					(mid 423.678096 -270.43507)
					(end 424.346116 -270.43507)
				)
			)
		)
	)
	(zone
		(layers "B.Cu" "In15.Cu")
		(hatch none 0.5)
		(connect_pads
			(clearance 0)
		)
		(min_thickness 0.25)
		(keepout
			(tracks not_allowed)
			(vias allowed)
			(pads allowed)
			(copperpour not_allowed)
			(footprints allowed)
		)
		(placement
			(enabled no)
			(sheetname "")
		)
		(fill yes
			(thermal_gap 0.5)
			(thermal_bridge_width 0.5)
			(island_removal_mode 0)
		)
		(polygon
			(pts
				(arc
					(start 382.88976 -271.656048)
					(mid 382.25984 -271.656048)
					(end 382.88976 -271.656048)
				)
			)
		)
	)
	(zone
		(layers "B.Cu" "In15.Cu")
		(hatch none 0.5)
		(connect_pads
			(clearance 0)
		)
		(min_thickness 0.25)
		(keepout
			(tracks not_allowed)
			(vias allowed)
			(pads allowed)
			(copperpour not_allowed)
			(footprints allowed)
		)
		(placement
			(enabled no)
			(sheetname "")
		)
		(fill yes
			(thermal_gap 0.5)
			(thermal_bridge_width 0.5)
			(island_removal_mode 0)
		)
		(polygon
			(pts
				(arc
					(start 172.30598 -263.635236)
					(mid 171.63796 -263.635236)
					(end 172.30598 -263.635236)
				)
			)
		)
	)
	(zone
		(layers "B.Cu" "In15.Cu")
		(hatch none 0.5)
		(connect_pads
			(clearance 0)
		)
		(min_thickness 0.25)
		(keepout
			(tracks not_allowed)
			(vias allowed)
			(pads allowed)
			(copperpour not_allowed)
			(footprints allowed)
		)
		(placement
			(enabled no)
			(sheetname "")
		)
		(fill yes
			(thermal_gap 0.5)
			(thermal_bridge_width 0.5)
			(island_removal_mode 0)
		)
		(polygon
			(pts
				(arc
					(start 48.118014 -198.185278)
					(mid 47.449994 -198.185278)
					(end 48.118014 -198.185278)
				)
			)
		)
	)
	(zone
		(layers "B.Cu" "In15.Cu")
		(hatch none 0.5)
		(connect_pads
			(clearance 0)
		)
		(min_thickness 0.25)
		(keepout
			(tracks not_allowed)
			(vias allowed)
			(pads allowed)
			(copperpour not_allowed)
			(footprints allowed)
		)
		(placement
			(enabled no)
			(sheetname "")
		)
		(fill yes
			(thermal_gap 0.5)
			(thermal_bridge_width 0.5)
			(island_removal_mode 0)
		)
		(polygon
			(pts
				(arc
					(start 136.059672 -238.814356)
					(mid 135.429752 -238.814356)
					(end 136.059672 -238.814356)
				)
			)
		)
	)
	(zone
		(layers "B.Cu" "In15.Cu")
		(hatch none 0.5)
		(connect_pads
			(clearance 0)
		)
		(min_thickness 0.25)
		(keepout
			(tracks not_allowed)
			(vias allowed)
			(pads allowed)
			(copperpour not_allowed)
			(footprints allowed)
		)
		(placement
			(enabled no)
			(sheetname "")
		)
		(fill yes
			(thermal_gap 0.5)
			(thermal_bridge_width 0.5)
			(island_removal_mode 0)
		)
		(polygon
			(pts
				(arc
					(start 300.15815 -284.88513)
					(mid 299.49013 -284.88513)
					(end 300.15815 -284.88513)
				)
			)
		)
	)
	(zone
		(layers "B.Cu" "In15.Cu")
		(hatch none 0.5)
		(connect_pads
			(clearance 0)
		)
		(min_thickness 0.25)
		(keepout
			(tracks not_allowed)
			(vias allowed)
			(pads allowed)
			(copperpour not_allowed)
			(footprints allowed)
		)
		(placement
			(enabled no)
			(sheetname "")
		)
		(fill yes
			(thermal_gap 0.5)
			(thermal_bridge_width 0.5)
			(island_removal_mode 0)
		)
		(polygon
			(pts
				(arc
					(start 143.840454 -371.49913)
					(mid 143.172434 -371.49913)
					(end 143.840454 -371.49913)
				)
			)
		)
	)
	(zone
		(layers "B.Cu" "In15.Cu")
		(hatch none 0.5)
		(connect_pads
			(clearance 0)
		)
		(min_thickness 0.25)
		(keepout
			(tracks not_allowed)
			(vias allowed)
			(pads allowed)
			(copperpour not_allowed)
			(footprints allowed)
		)
		(placement
			(enabled no)
			(sheetname "")
		)
		(fill yes
			(thermal_gap 0.5)
			(thermal_bridge_width 0.5)
			(island_removal_mode 0)
		)
		(polygon
			(pts
				(arc
					(start 48.118014 -261.935214)
					(mid 47.449994 -261.935214)
					(end 48.118014 -261.935214)
				)
			)
		)
	)
	(zone
		(layers "B.Cu" "In15.Cu")
		(hatch none 0.5)
		(connect_pads
			(clearance 0)
		)
		(min_thickness 0.25)
		(keepout
			(tracks not_allowed)
			(vias allowed)
			(pads allowed)
			(copperpour not_allowed)
			(footprints allowed)
		)
		(placement
			(enabled no)
			(sheetname "")
		)
		(fill yes
			(thermal_gap 0.5)
			(thermal_bridge_width 0.5)
			(island_removal_mode 0)
		)
		(polygon
			(pts
				(arc
					(start 296.058082 -233.884978)
					(mid 295.390062 -233.884978)
					(end 296.058082 -233.884978)
				)
			)
		)
	)
	(zone
		(layers "B.Cu" "In15.Cu")
		(hatch none 0.5)
		(connect_pads
			(clearance 0)
		)
		(min_thickness 0.25)
		(keepout
			(tracks not_allowed)
			(vias allowed)
			(pads allowed)
			(copperpour not_allowed)
			(footprints allowed)
		)
		(placement
			(enabled no)
			(sheetname "")
		)
		(fill yes
			(thermal_gap 0.5)
			(thermal_bridge_width 0.5)
			(island_removal_mode 0)
		)
		(polygon
			(pts
				(arc
					(start 346.876116 -242.864132)
					(mid 346.246196 -242.864132)
					(end 346.876116 -242.864132)
				)
			)
		)
	)
	(zone
		(layers "B.Cu" "In15.Cu")
		(hatch none 0.5)
		(connect_pads
			(clearance 0)
		)
		(min_thickness 0.25)
		(keepout
			(tracks not_allowed)
			(vias allowed)
			(pads allowed)
			(copperpour not_allowed)
			(footprints allowed)
		)
		(placement
			(enabled no)
			(sheetname "")
		)
		(fill yes
			(thermal_gap 0.5)
			(thermal_bridge_width 0.5)
			(island_removal_mode 0)
		)
		(polygon
			(pts
				(arc
					(start 424.346116 -254.284988)
					(mid 423.678096 -254.284988)
					(end 424.346116 -254.284988)
				)
			)
		)
	)
	(zone
		(layers "B.Cu" "In15.Cu")
		(hatch none 0.5)
		(connect_pads
			(clearance 0)
		)
		(min_thickness 0.25)
		(keepout
			(tracks not_allowed)
			(vias allowed)
			(pads allowed)
			(copperpour not_allowed)
			(footprints allowed)
		)
		(placement
			(enabled no)
			(sheetname "")
		)
		(fill yes
			(thermal_gap 0.5)
			(thermal_bridge_width 0.5)
			(island_removal_mode 0)
		)
		(polygon
			(pts
				(arc
					(start 300.15815 -272.135092)
					(mid 299.49013 -272.135092)
					(end 300.15815 -272.135092)
				)
			)
		)
	)
	(zone
		(layers "B.Cu" "In15.Cu")
		(hatch none 0.5)
		(connect_pads
			(clearance 0)
		)
		(min_thickness 0.25)
		(keepout
			(tracks not_allowed)
			(vias allowed)
			(pads allowed)
			(copperpour not_allowed)
			(footprints allowed)
		)
		(placement
			(enabled no)
			(sheetname "")
		)
		(fill yes
			(thermal_gap 0.5)
			(thermal_bridge_width 0.5)
			(island_removal_mode 0)
		)
		(polygon
			(pts
				(arc
					(start 134.949692 -276.516338)
					(mid 134.319772 -276.516338)
					(end 134.949692 -276.516338)
				)
			)
		)
	)
	(zone
		(layers "B.Cu" "In15.Cu")
		(hatch none 0.5)
		(connect_pads
			(clearance 0)
		)
		(min_thickness 0.25)
		(keepout
			(tracks not_allowed)
			(vias allowed)
			(pads allowed)
			(copperpour not_allowed)
			(footprints allowed)
		)
		(placement
			(enabled no)
			(sheetname "")
		)
		(fill yes
			(thermal_gap 0.5)
			(thermal_bridge_width 0.5)
			(island_removal_mode 0)
		)
		(polygon
			(pts
				(arc
					(start 382.88976 -274.896072)
					(mid 382.25984 -274.896072)
					(end 382.88976 -274.896072)
				)
			)
		)
	)
	(zone
		(layers "B.Cu" "In15.Cu")
		(hatch none 0.5)
		(connect_pads
			(clearance 0)
		)
		(min_thickness 0.25)
		(keepout
			(tracks not_allowed)
			(vias allowed)
			(pads allowed)
			(copperpour not_allowed)
			(footprints allowed)
		)
		(placement
			(enabled no)
			(sheetname "")
		)
		(fill yes
			(thermal_gap 0.5)
			(thermal_bridge_width 0.5)
			(island_removal_mode 0)
		)
		(polygon
			(pts
				(arc
					(start 48.118014 -202.435206)
					(mid 47.449994 -202.435206)
					(end 48.118014 -202.435206)
				)
			)
		)
	)
	(zone
		(layers "B.Cu" "In15.Cu")
		(hatch none 0.5)
		(connect_pads
			(clearance 0)
		)
		(min_thickness 0.25)
		(keepout
			(tracks not_allowed)
			(vias allowed)
			(pads allowed)
			(copperpour not_allowed)
			(footprints allowed)
		)
		(placement
			(enabled no)
			(sheetname "")
		)
		(fill yes
			(thermal_gap 0.5)
			(thermal_bridge_width 0.5)
			(island_removal_mode 0)
		)
		(polygon
			(pts
				(arc
					(start 89.83599 -289.47618)
					(mid 89.20607 -289.47618)
					(end 89.83599 -289.47618)
				)
			)
		)
	)
	(zone
		(layers "B.Cu" "In15.Cu")
		(hatch none 0.5)
		(connect_pads
			(clearance 0)
		)
		(min_thickness 0.25)
		(keepout
			(tracks not_allowed)
			(vias allowed)
			(pads allowed)
			(copperpour not_allowed)
			(footprints allowed)
		)
		(placement
			(enabled no)
			(sheetname "")
		)
		(fill yes
			(thermal_gap 0.5)
			(thermal_bridge_width 0.5)
			(island_removal_mode 0)
		)
		(polygon
			(pts
				(arc
					(start 136.359646 -282.18638)
					(mid 135.729726 -282.18638)
					(end 136.359646 -282.18638)
				)
			)
		)
	)
	(zone
		(layers "B.Cu" "In15.Cu")
		(hatch none 0.5)
		(connect_pads
			(clearance 0)
		)
		(min_thickness 0.25)
		(keepout
			(tracks not_allowed)
			(vias allowed)
			(pads allowed)
			(copperpour not_allowed)
			(footprints allowed)
		)
		(placement
			(enabled no)
			(sheetname "")
		)
		(fill yes
			(thermal_gap 0.5)
			(thermal_bridge_width 0.5)
			(island_removal_mode 0)
		)
		(polygon
			(pts
				(arc
					(start 88.426036 -277.326344)
					(mid 87.796116 -277.326344)
					(end 88.426036 -277.326344)
				)
			)
		)
	)
	(zone
		(layers "B.Cu" "In15.Cu")
		(hatch none 0.5)
		(connect_pads
			(clearance 0)
		)
		(min_thickness 0.25)
		(keepout
			(tracks not_allowed)
			(vias allowed)
			(pads allowed)
			(copperpour not_allowed)
			(footprints allowed)
		)
		(placement
			(enabled no)
			(sheetname "")
		)
		(fill yes
			(thermal_gap 0.5)
			(thermal_bridge_width 0.5)
			(island_removal_mode 0)
		)
		(polygon
			(pts
				(arc
					(start 140.13688 -435.489858)
					(mid 139.362688 -435.489858)
					(end 140.13688 -435.489858)
				)
			)
		)
	)
	(zone
		(layers "B.Cu" "In15.Cu")
		(hatch none 0.5)
		(connect_pads
			(clearance 0)
		)
		(min_thickness 0.25)
		(keepout
			(tracks not_allowed)
			(vias allowed)
			(pads allowed)
			(copperpour not_allowed)
			(footprints allowed)
		)
		(placement
			(enabled no)
			(sheetname "")
		)
		(fill yes
			(thermal_gap 0.5)
			(thermal_bridge_width 0.5)
			(island_removal_mode 0)
		)
		(polygon
			(pts
				(arc
					(start 397.392398 -389.88746)
					(mid 396.724378 -389.88746)
					(end 397.392398 -389.88746)
				)
			)
		)
	)
	(zone
		(layers "B.Cu" "In15.Cu")
		(hatch none 0.5)
		(connect_pads
			(clearance 0)
		)
		(min_thickness 0.25)
		(keepout
			(tracks not_allowed)
			(vias allowed)
			(pads allowed)
			(copperpour not_allowed)
			(footprints allowed)
		)
		(placement
			(enabled no)
			(sheetname "")
		)
		(fill yes
			(thermal_gap 0.5)
			(thermal_bridge_width 0.5)
			(island_removal_mode 0)
		)
		(polygon
			(pts
				(arc
					(start 296.058082 -198.185024)
					(mid 295.390062 -198.185024)
					(end 296.058082 -198.185024)
				)
			)
		)
	)
	(zone
		(layers "B.Cu" "In15.Cu")
		(hatch none 0.5)
		(connect_pads
			(clearance 0)
		)
		(min_thickness 0.25)
		(keepout
			(tracks not_allowed)
			(vias allowed)
			(pads allowed)
			(copperpour not_allowed)
			(footprints allowed)
		)
		(placement
			(enabled no)
			(sheetname "")
		)
		(fill yes
			(thermal_gap 0.5)
			(thermal_bridge_width 0.5)
			(island_removal_mode 0)
		)
		(polygon
			(pts
				(arc
					(start 337.476084 -226.664266)
					(mid 336.846164 -226.664266)
					(end 337.476084 -226.664266)
				)
			)
		)
	)
	(zone
		(layers "B.Cu" "In15.Cu")
		(hatch none 0.5)
		(connect_pads
			(clearance 0)
		)
		(min_thickness 0.25)
		(keepout
			(tracks not_allowed)
			(vias allowed)
			(pads allowed)
			(copperpour not_allowed)
			(footprints allowed)
		)
		(placement
			(enabled no)
			(sheetname "")
		)
		(fill yes
			(thermal_gap 0.5)
			(thermal_bridge_width 0.5)
			(island_removal_mode 0)
		)
		(polygon
			(pts
				(arc
					(start 141.392402 -375.96826)
					(mid 140.724382 -375.96826)
					(end 141.392402 -375.96826)
				)
			)
		)
	)
	(zone
		(layers "B.Cu" "In15.Cu")
		(hatch none 0.5)
		(connect_pads
			(clearance 0)
		)
		(min_thickness 0.25)
		(keepout
			(tracks not_allowed)
			(vias allowed)
			(pads allowed)
			(copperpour not_allowed)
			(footprints allowed)
		)
		(placement
			(enabled no)
			(sheetname "")
		)
		(fill yes
			(thermal_gap 0.5)
			(thermal_bridge_width 0.5)
			(island_removal_mode 0)
		)
		(polygon
			(pts
				(arc
					(start 59.036966 -433.289964)
					(mid 58.262774 -433.289964)
					(end 59.036966 -433.289964)
				)
			)
		)
	)
	(zone
		(layers "B.Cu" "In15.Cu")
		(hatch none 0.5)
		(connect_pads
			(clearance 0)
		)
		(min_thickness 0.25)
		(keepout
			(tracks not_allowed)
			(vias allowed)
			(pads allowed)
			(copperpour not_allowed)
			(footprints allowed)
		)
		(placement
			(enabled no)
			(sheetname "")
		)
		(fill yes
			(thermal_gap 0.5)
			(thermal_bridge_width 0.5)
			(island_removal_mode 0)
		)
		(polygon
			(pts
				(arc
					(start 383.99974 -233.954066)
					(mid 383.36982 -233.954066)
					(end 383.99974 -233.954066)
				)
			)
		)
	)
	(zone
		(layers "B.Cu" "In15.Cu")
		(hatch none 0.5)
		(connect_pads
			(clearance 0)
		)
		(min_thickness 0.25)
		(keepout
			(tracks not_allowed)
			(vias allowed)
			(pads allowed)
			(copperpour not_allowed)
			(footprints allowed)
		)
		(placement
			(enabled no)
			(sheetname "")
		)
		(fill yes
			(thermal_gap 0.5)
			(thermal_bridge_width 0.5)
			(island_removal_mode 0)
		)
		(polygon
			(pts
				(arc
					(start 300.15815 -301.885096)
					(mid 299.49013 -301.885096)
					(end 300.15815 -301.885096)
				)
			)
		)
	)
	(zone
		(layers "B.Cu" "In15.Cu")
		(hatch none 0.5)
		(connect_pads
			(clearance 0)
		)
		(min_thickness 0.25)
		(keepout
			(tracks not_allowed)
			(vias allowed)
			(pads allowed)
			(copperpour not_allowed)
			(footprints allowed)
		)
		(placement
			(enabled no)
			(sheetname "")
		)
		(fill yes
			(thermal_gap 0.5)
			(thermal_bridge_width 0.5)
			(island_removal_mode 0)
		)
		(polygon
			(pts
				(arc
					(start 337.006184 -232.334054)
					(mid 336.376264 -232.334054)
					(end 337.006184 -232.334054)
				)
			)
		)
	)
	(zone
		(layers "B.Cu" "In15.Cu")
		(hatch none 0.5)
		(connect_pads
			(clearance 0)
		)
		(min_thickness 0.25)
		(keepout
			(tracks not_allowed)
			(vias allowed)
			(pads allowed)
			(copperpour not_allowed)
			(footprints allowed)
		)
		(placement
			(enabled no)
			(sheetname "")
		)
		(fill yes
			(thermal_gap 0.5)
			(thermal_bridge_width 0.5)
			(island_removal_mode 0)
		)
		(polygon
			(pts
				(arc
					(start 171.239434 -380.360428)
					(mid 170.571414 -380.360428)
					(end 171.239434 -380.360428)
				)
			)
		)
	)
	(zone
		(layers "B.Cu" "In15.Cu")
		(hatch none 0.5)
		(connect_pads
			(clearance 0)
		)
		(min_thickness 0.25)
		(keepout
			(tracks not_allowed)
			(vias allowed)
			(pads allowed)
			(copperpour not_allowed)
			(footprints allowed)
		)
		(placement
			(enabled no)
			(sheetname "")
		)
		(fill yes
			(thermal_gap 0.5)
			(thermal_bridge_width 0.5)
			(island_removal_mode 0)
		)
		(polygon
			(pts
				(arc
					(start 363.619796 -272.466054)
					(mid 362.989876 -272.466054)
					(end 363.619796 -272.466054)
				)
			)
		)
	)
	(zone
		(layers "B.Cu" "In15.Cu")
		(hatch none 0.5)
		(connect_pads
			(clearance 0)
		)
		(min_thickness 0.25)
		(keepout
			(tracks not_allowed)
			(vias allowed)
			(pads allowed)
			(copperpour not_allowed)
			(footprints allowed)
		)
		(placement
			(enabled no)
			(sheetname "")
		)
		(fill yes
			(thermal_gap 0.5)
			(thermal_bridge_width 0.5)
			(island_removal_mode 0)
		)
		(polygon
			(pts
				(arc
					(start 48.118014 -238.985298)
					(mid 47.449994 -238.985298)
					(end 48.118014 -238.985298)
				)
			)
		)
	)
	(zone
		(layers "B.Cu" "In15.Cu")
		(hatch none 0.5)
		(connect_pads
			(clearance 0)
		)
		(min_thickness 0.25)
		(keepout
			(tracks not_allowed)
			(vias allowed)
			(pads allowed)
			(copperpour not_allowed)
			(footprints allowed)
		)
		(placement
			(enabled no)
			(sheetname "")
		)
		(fill yes
			(thermal_gap 0.5)
			(thermal_bridge_width 0.5)
			(island_removal_mode 0)
		)
		(polygon
			(pts
				(arc
					(start 383.059686 -235.574078)
					(mid 382.429766 -235.574078)
					(end 383.059686 -235.574078)
				)
			)
		)
	)
	(zone
		(layers "B.Cu" "In15.Cu")
		(hatch none 0.5)
		(connect_pads
			(clearance 0)
		)
		(min_thickness 0.25)
		(keepout
			(tracks not_allowed)
			(vias allowed)
			(pads allowed)
			(copperpour not_allowed)
			(footprints allowed)
		)
		(placement
			(enabled no)
			(sheetname "")
		)
		(fill yes
			(thermal_gap 0.5)
			(thermal_bridge_width 0.5)
			(island_removal_mode 0)
		)
		(polygon
			(pts
				(arc
					(start 48.118014 -233.885232)
					(mid 47.449994 -233.885232)
					(end 48.118014 -233.885232)
				)
			)
		)
	)
	(zone
		(layers "B.Cu" "In15.Cu")
		(hatch none 0.5)
		(connect_pads
			(clearance 0)
		)
		(min_thickness 0.25)
		(keepout
			(tracks not_allowed)
			(vias allowed)
			(pads allowed)
			(copperpour not_allowed)
			(footprints allowed)
		)
		(placement
			(enabled no)
			(sheetname "")
		)
		(fill yes
			(thermal_gap 0.5)
			(thermal_bridge_width 0.5)
			(island_removal_mode 0)
		)
		(polygon
			(pts
				(arc
					(start 135.119618 -237.194344)
					(mid 134.489698 -237.194344)
					(end 135.119618 -237.194344)
				)
			)
		)
	)
	(zone
		(layers "B.Cu" "In15.Cu")
		(hatch none 0.5)
		(connect_pads
			(clearance 0)
		)
		(min_thickness 0.25)
		(keepout
			(tracks not_allowed)
			(vias allowed)
			(pads allowed)
			(copperpour not_allowed)
			(footprints allowed)
		)
		(placement
			(enabled no)
			(sheetname "")
		)
		(fill yes
			(thermal_gap 0.5)
			(thermal_bridge_width 0.5)
			(island_removal_mode 0)
		)
		(polygon
			(pts
				(arc
					(start 382.88976 -282.996132)
					(mid 382.25984 -282.996132)
					(end 382.88976 -282.996132)
				)
			)
		)
	)
	(zone
		(layers "B.Cu" "In15.Cu")
		(hatch none 0.5)
		(connect_pads
			(clearance 0)
		)
		(min_thickness 0.25)
		(keepout
			(tracks not_allowed)
			(vias allowed)
			(pads allowed)
			(copperpour not_allowed)
			(footprints allowed)
		)
		(placement
			(enabled no)
			(sheetname "")
		)
		(fill yes
			(thermal_gap 0.5)
			(thermal_bridge_width 0.5)
			(island_removal_mode 0)
		)
		(polygon
			(pts
				(arc
					(start 48.118014 -316.33541)
					(mid 47.449994 -316.33541)
					(end 48.118014 -316.33541)
				)
			)
		)
	)
	(zone
		(layers "B.Cu" "In15.Cu")
		(hatch none 0.5)
		(connect_pads
			(clearance 0)
		)
		(min_thickness 0.25)
		(keepout
			(tracks not_allowed)
			(vias allowed)
			(pads allowed)
			(copperpour not_allowed)
			(footprints allowed)
		)
		(placement
			(enabled no)
			(sheetname "")
		)
		(fill yes
			(thermal_gap 0.5)
			(thermal_bridge_width 0.5)
			(island_removal_mode 0)
		)
		(polygon
			(pts
				(arc
					(start 52.218082 -278.085296)
					(mid 51.550062 -278.085296)
					(end 52.218082 -278.085296)
				)
			)
		)
	)
	(zone
		(layers "B.Cu" "In15.Cu")
		(hatch none 0.5)
		(connect_pads
			(clearance 0)
		)
		(min_thickness 0.25)
		(keepout
			(tracks not_allowed)
			(vias allowed)
			(pads allowed)
			(copperpour not_allowed)
			(footprints allowed)
		)
		(placement
			(enabled no)
			(sheetname "")
		)
		(fill yes
			(thermal_gap 0.5)
			(thermal_bridge_width 0.5)
			(island_removal_mode 0)
		)
		(polygon
			(pts
				(arc
					(start 408.34945 -377.41733)
					(mid 407.68143 -377.41733)
					(end 408.34945 -377.41733)
				)
			)
		)
	)
	(zone
		(layers "B.Cu" "In15.Cu")
		(hatch none 0.5)
		(connect_pads
			(clearance 0)
		)
		(min_thickness 0.25)
		(keepout
			(tracks not_allowed)
			(vias allowed)
			(pads allowed)
			(copperpour not_allowed)
			(footprints allowed)
		)
		(placement
			(enabled no)
			(sheetname "")
		)
		(fill yes
			(thermal_gap 0.5)
			(thermal_bridge_width 0.5)
			(island_removal_mode 0)
		)
		(polygon
			(pts
				(arc
					(start 300.15815 -317.18504)
					(mid 299.49013 -317.18504)
					(end 300.15815 -317.18504)
				)
			)
		)
	)
	(zone
		(layers "B.Cu" "In15.Cu")
		(hatch none 0.5)
		(connect_pads
			(clearance 0)
		)
		(min_thickness 0.25)
		(keepout
			(tracks not_allowed)
			(vias allowed)
			(pads allowed)
			(copperpour not_allowed)
			(footprints allowed)
		)
		(placement
			(enabled no)
			(sheetname "")
		)
		(fill yes
			(thermal_gap 0.5)
			(thermal_bridge_width 0.5)
			(island_removal_mode 0)
		)
		(polygon
			(pts
				(arc
					(start 384.469894 -246.104156)
					(mid 383.839974 -246.104156)
					(end 384.469894 -246.104156)
				)
			)
		)
	)
	(zone
		(layers "B.Cu" "In15.Cu")
		(hatch none 0.5)
		(connect_pads
			(clearance 0)
		)
		(min_thickness 0.25)
		(keepout
			(tracks not_allowed)
			(vias allowed)
			(pads allowed)
			(copperpour not_allowed)
			(footprints allowed)
		)
		(placement
			(enabled no)
			(sheetname "")
		)
		(fill yes
			(thermal_gap 0.5)
			(thermal_bridge_width 0.5)
			(island_removal_mode 0)
		)
		(polygon
			(pts
				(arc
					(start 88.426036 -269.226284)
					(mid 87.796116 -269.226284)
					(end 88.426036 -269.226284)
				)
			)
		)
	)
	(zone
		(layers "B.Cu" "In15.Cu")
		(hatch none 0.5)
		(connect_pads
			(clearance 0)
		)
		(min_thickness 0.25)
		(keepout
			(tracks not_allowed)
			(vias allowed)
			(pads allowed)
			(copperpour not_allowed)
			(footprints allowed)
		)
		(placement
			(enabled no)
			(sheetname "")
		)
		(fill yes
			(thermal_gap 0.5)
			(thermal_bridge_width 0.5)
			(island_removal_mode 0)
		)
		(polygon
			(pts
				(arc
					(start 383.059686 -238.814102)
					(mid 382.429766 -238.814102)
					(end 383.059686 -238.814102)
				)
			)
		)
	)
	(zone
		(layers "B.Cu" "In15.Cu")
		(hatch none 0.5)
		(connect_pads
			(clearance 0)
		)
		(min_thickness 0.25)
		(keepout
			(tracks not_allowed)
			(vias allowed)
			(pads allowed)
			(copperpour not_allowed)
			(footprints allowed)
		)
		(placement
			(enabled no)
			(sheetname "")
		)
		(fill yes
			(thermal_gap 0.5)
			(thermal_bridge_width 0.5)
			(island_removal_mode 0)
		)
		(polygon
			(pts
				(arc
					(start 176.406048 -304.435256)
					(mid 175.738028 -304.435256)
					(end 176.406048 -304.435256)
				)
			)
		)
	)
	(zone
		(layers "B.Cu" "In15.Cu")
		(hatch none 0.5)
		(connect_pads
			(clearance 0)
		)
		(min_thickness 0.25)
		(keepout
			(tracks not_allowed)
			(vias allowed)
			(pads allowed)
			(copperpour not_allowed)
			(footprints allowed)
		)
		(placement
			(enabled no)
			(sheetname "")
		)
		(fill yes
			(thermal_gap 0.5)
			(thermal_bridge_width 0.5)
			(island_removal_mode 0)
		)
		(polygon
			(pts
				(arc
					(start 382.589786 -244.484144)
					(mid 381.959866 -244.484144)
					(end 382.589786 -244.484144)
				)
			)
		)
	)
	(zone
		(layers "B.Cu" "In15.Cu")
		(hatch none 0.5)
		(connect_pads
			(clearance 0)
		)
		(min_thickness 0.25)
		(keepout
			(tracks not_allowed)
			(vias allowed)
			(pads allowed)
			(copperpour not_allowed)
			(footprints allowed)
		)
		(placement
			(enabled no)
			(sheetname "")
		)
		(fill yes
			(thermal_gap 0.5)
			(thermal_bridge_width 0.5)
			(island_removal_mode 0)
		)
		(polygon
			(pts
				(arc
					(start 133.250432 -393.292838)
					(mid 132.582412 -393.292838)
					(end 133.250432 -393.292838)
				)
			)
		)
	)
	(zone
		(layers "B.Cu" "In15.Cu")
		(hatch none 0.5)
		(connect_pads
			(clearance 0)
		)
		(min_thickness 0.25)
		(keepout
			(tracks not_allowed)
			(vias allowed)
			(pads allowed)
			(copperpour not_allowed)
			(footprints allowed)
		)
		(placement
			(enabled no)
			(sheetname "")
		)
		(fill yes
			(thermal_gap 0.5)
			(thermal_bridge_width 0.5)
			(island_removal_mode 0)
		)
		(polygon
			(pts
				(arc
					(start 176.406048 -252.58522)
					(mid 175.738028 -252.58522)
					(end 176.406048 -252.58522)
				)
			)
		)
	)
	(zone
		(layers "B.Cu" "In15.Cu")
		(hatch none 0.5)
		(connect_pads
			(clearance 0)
		)
		(min_thickness 0.25)
		(keepout
			(tracks not_allowed)
			(vias allowed)
			(pads allowed)
			(copperpour not_allowed)
			(footprints allowed)
		)
		(placement
			(enabled no)
			(sheetname "")
		)
		(fill yes
			(thermal_gap 0.5)
			(thermal_bridge_width 0.5)
			(island_removal_mode 0)
		)
		(polygon
			(pts
				(arc
					(start 384.469894 -231.524048)
					(mid 383.839974 -231.524048)
					(end 384.469894 -231.524048)
				)
			)
		)
	)
	(zone
		(layers "B.Cu" "In15.Cu")
		(hatch none 0.5)
		(connect_pads
			(clearance 0)
		)
		(min_thickness 0.25)
		(keepout
			(tracks not_allowed)
			(vias allowed)
			(pads allowed)
			(copperpour not_allowed)
			(footprints allowed)
		)
		(placement
			(enabled no)
			(sheetname "")
		)
		(fill yes
			(thermal_gap 0.5)
			(thermal_bridge_width 0.5)
			(island_removal_mode 0)
		)
		(polygon
			(pts
				(arc
					(start 337.776058 -271.656048)
					(mid 337.146138 -271.656048)
					(end 337.776058 -271.656048)
				)
			)
		)
	)
	(zone
		(layers "B.Cu" "In15.Cu")
		(hatch none 0.5)
		(connect_pads
			(clearance 0)
		)
		(min_thickness 0.25)
		(keepout
			(tracks not_allowed)
			(vias allowed)
			(pads allowed)
			(copperpour not_allowed)
			(footprints allowed)
		)
		(placement
			(enabled no)
			(sheetname "")
		)
		(fill yes
			(thermal_gap 0.5)
			(thermal_bridge_width 0.5)
			(island_removal_mode 0)
		)
		(polygon
			(pts
				(arc
					(start 138.136884 -434.48986)
					(mid 137.362692 -434.48986)
					(end 138.136884 -434.48986)
				)
			)
		)
	)
	(zone
		(layers "B.Cu" "In15.Cu")
		(hatch none 0.5)
		(connect_pads
			(clearance 0)
		)
		(min_thickness 0.25)
		(keepout
			(tracks not_allowed)
			(vias allowed)
			(pads allowed)
			(copperpour not_allowed)
			(footprints allowed)
		)
		(placement
			(enabled no)
			(sheetname "")
		)
		(fill yes
			(thermal_gap 0.5)
			(thermal_bridge_width 0.5)
			(island_removal_mode 0)
		)
		(polygon
			(pts
				(arc
					(start 172.30598 -222.835216)
					(mid 171.63796 -222.835216)
					(end 172.30598 -222.835216)
				)
			)
		)
	)
	(zone
		(layers "B.Cu" "In15.Cu")
		(hatch none 0.5)
		(connect_pads
			(clearance 0)
		)
		(min_thickness 0.25)
		(keepout
			(tracks not_allowed)
			(vias allowed)
			(pads allowed)
			(copperpour not_allowed)
			(footprints allowed)
		)
		(placement
			(enabled no)
			(sheetname "")
		)
		(fill yes
			(thermal_gap 0.5)
			(thermal_bridge_width 0.5)
			(island_removal_mode 0)
		)
		(polygon
			(pts
				(arc
					(start 382.88976 -287.856168)
					(mid 382.25984 -287.856168)
					(end 382.88976 -287.856168)
				)
			)
		)
	)
	(zone
		(layers "B.Cu" "In15.Cu")
		(hatch none 0.5)
		(connect_pads
			(clearance 0)
		)
		(min_thickness 0.25)
		(keepout
			(tracks not_allowed)
			(vias allowed)
			(pads allowed)
			(copperpour not_allowed)
			(footprints allowed)
		)
		(placement
			(enabled no)
			(sheetname "")
		)
		(fill yes
			(thermal_gap 0.5)
			(thermal_bridge_width 0.5)
			(island_removal_mode 0)
		)
		(polygon
			(pts
				(arc
					(start 420.246048 -202.434952)
					(mid 419.578028 -202.434952)
					(end 420.246048 -202.434952)
				)
			)
		)
	)
	(zone
		(layers "B.Cu" "In15.Cu")
		(hatch none 0.5)
		(connect_pads
			(clearance 0)
		)
		(min_thickness 0.25)
		(keepout
			(tracks not_allowed)
			(vias allowed)
			(pads allowed)
			(copperpour not_allowed)
			(footprints allowed)
		)
		(placement
			(enabled no)
			(sheetname "")
		)
		(fill yes
			(thermal_gap 0.5)
			(thermal_bridge_width 0.5)
			(island_removal_mode 0)
		)
		(polygon
			(pts
				(arc
					(start 300.15815 -315.485018)
					(mid 299.49013 -315.485018)
					(end 300.15815 -315.485018)
				)
			)
		)
	)
	(zone
		(layers "B.Cu" "In15.Cu")
		(hatch none 0.5)
		(connect_pads
			(clearance 0)
		)
		(min_thickness 0.25)
		(keepout
			(tracks not_allowed)
			(vias allowed)
			(pads allowed)
			(copperpour not_allowed)
			(footprints allowed)
		)
		(placement
			(enabled no)
			(sheetname "")
		)
		(fill yes
			(thermal_gap 0.5)
			(thermal_bridge_width 0.5)
			(island_removal_mode 0)
		)
		(polygon
			(pts
				(arc
					(start 346.876116 -239.624108)
					(mid 346.246196 -239.624108)
					(end 346.876116 -239.624108)
				)
			)
		)
	)
	(zone
		(layers "B.Cu" "In15.Cu")
		(hatch none 0.5)
		(connect_pads
			(clearance 0)
		)
		(min_thickness 0.25)
		(keepout
			(tracks not_allowed)
			(vias allowed)
			(pads allowed)
			(copperpour not_allowed)
			(footprints allowed)
		)
		(placement
			(enabled no)
			(sheetname "")
		)
		(fill yes
			(thermal_gap 0.5)
			(thermal_bridge_width 0.5)
			(island_removal_mode 0)
		)
		(polygon
			(pts
				(arc
					(start 385.650486 -401.674838)
					(mid 384.982466 -401.674838)
					(end 385.650486 -401.674838)
				)
			)
		)
	)
	(zone
		(layers "B.Cu" "In15.Cu")
		(hatch none 0.5)
		(connect_pads
			(clearance 0)
		)
		(min_thickness 0.25)
		(keepout
			(tracks not_allowed)
			(vias allowed)
			(pads allowed)
			(copperpour not_allowed)
			(footprints allowed)
		)
		(placement
			(enabled no)
			(sheetname "")
		)
		(fill yes
			(thermal_gap 0.5)
			(thermal_bridge_width 0.5)
			(island_removal_mode 0)
		)
		(polygon
			(pts
				(arc
					(start 141.392402 -381.50546)
					(mid 140.724382 -381.50546)
					(end 141.392402 -381.50546)
				)
			)
		)
	)
	(zone
		(layers "B.Cu" "In15.Cu")
		(hatch none 0.5)
		(connect_pads
			(clearance 0)
		)
		(min_thickness 0.25)
		(keepout
			(tracks not_allowed)
			(vias allowed)
			(pads allowed)
			(copperpour not_allowed)
			(footprints allowed)
		)
		(placement
			(enabled no)
			(sheetname "")
		)
		(fill yes
			(thermal_gap 0.5)
			(thermal_bridge_width 0.5)
			(island_removal_mode 0)
		)
		(polygon
			(pts
				(arc
					(start 382.88976 -261.935976)
					(mid 382.25984 -261.935976)
					(end 382.88976 -261.935976)
				)
			)
		)
	)
	(zone
		(layers "B.Cu" "In15.Cu")
		(hatch none 0.5)
		(connect_pads
			(clearance 0)
		)
		(min_thickness 0.25)
		(keepout
			(tracks not_allowed)
			(vias allowed)
			(pads allowed)
			(copperpour not_allowed)
			(footprints allowed)
		)
		(placement
			(enabled no)
			(sheetname "")
		)
		(fill yes
			(thermal_gap 0.5)
			(thermal_bridge_width 0.5)
			(island_removal_mode 0)
		)
		(polygon
			(pts
				(arc
					(start 48.118014 -253.435358)
					(mid 47.449994 -253.435358)
					(end 48.118014 -253.435358)
				)
			)
		)
	)
	(zone
		(layers "B.Cu" "In15.Cu")
		(hatch none 0.5)
		(connect_pads
			(clearance 0)
		)
		(min_thickness 0.25)
		(keepout
			(tracks not_allowed)
			(vias allowed)
			(pads allowed)
			(copperpour not_allowed)
			(footprints allowed)
		)
		(placement
			(enabled no)
			(sheetname "")
		)
		(fill yes
			(thermal_gap 0.5)
			(thermal_bridge_width 0.5)
			(island_removal_mode 0)
		)
		(polygon
			(pts
				(arc
					(start 125.54966 -270.03629)
					(mid 124.91974 -270.03629)
					(end 125.54966 -270.03629)
				)
			)
		)
	)
	(zone
		(layers "B.Cu" "In15.Cu")
		(hatch none 0.5)
		(connect_pads
			(clearance 0)
		)
		(min_thickness 0.25)
		(keepout
			(tracks not_allowed)
			(vias allowed)
			(pads allowed)
			(copperpour not_allowed)
			(footprints allowed)
		)
		(placement
			(enabled no)
			(sheetname "")
		)
		(fill yes
			(thermal_gap 0.5)
			(thermal_bridge_width 0.5)
			(island_removal_mode 0)
		)
		(polygon
			(pts
				(arc
					(start 411.75305 -382.34493)
					(mid 411.08503 -382.34493)
					(end 411.75305 -382.34493)
				)
			)
		)
	)
	(zone
		(layers "B.Cu" "In15.Cu")
		(hatch none 0.5)
		(connect_pads
			(clearance 0)
		)
		(min_thickness 0.25)
		(keepout
			(tracks not_allowed)
			(vias allowed)
			(pads allowed)
			(copperpour not_allowed)
			(footprints allowed)
		)
		(placement
			(enabled no)
			(sheetname "")
		)
		(fill yes
			(thermal_gap 0.5)
			(thermal_bridge_width 0.5)
			(island_removal_mode 0)
		)
		(polygon
			(pts
				(arc
					(start 384.45059 -400.811238)
					(mid 383.78257 -400.811238)
					(end 384.45059 -400.811238)
				)
			)
		)
	)
	(zone
		(layers "B.Cu" "In15.Cu")
		(hatch none 0.5)
		(connect_pads
			(clearance 0)
		)
		(min_thickness 0.25)
		(keepout
			(tracks not_allowed)
			(vias allowed)
			(pads allowed)
			(copperpour not_allowed)
			(footprints allowed)
		)
		(placement
			(enabled no)
			(sheetname "")
		)
		(fill yes
			(thermal_gap 0.5)
			(thermal_bridge_width 0.5)
			(island_removal_mode 0)
		)
		(polygon
			(pts
				(arc
					(start 176.406048 -200.735438)
					(mid 175.738028 -200.735438)
					(end 176.406048 -200.735438)
				)
			)
		)
	)
	(zone
		(layers "B.Cu" "In15.Cu")
		(hatch none 0.5)
		(connect_pads
			(clearance 0)
		)
		(min_thickness 0.25)
		(keepout
			(tracks not_allowed)
			(vias allowed)
			(pads allowed)
			(copperpour not_allowed)
			(footprints allowed)
		)
		(placement
			(enabled no)
			(sheetname "")
		)
		(fill yes
			(thermal_gap 0.5)
			(thermal_bridge_width 0.5)
			(island_removal_mode 0)
		)
		(polygon
			(pts
				(arc
					(start 336.366104 -272.466054)
					(mid 335.736184 -272.466054)
					(end 336.366104 -272.466054)
				)
			)
		)
	)
	(zone
		(layers "B.Cu" "In15.Cu")
		(hatch none 0.5)
		(connect_pads
			(clearance 0)
		)
		(min_thickness 0.25)
		(keepout
			(tracks not_allowed)
			(vias allowed)
			(pads allowed)
			(copperpour not_allowed)
			(footprints allowed)
		)
		(placement
			(enabled no)
			(sheetname "")
		)
		(fill yes
			(thermal_gap 0.5)
			(thermal_bridge_width 0.5)
			(island_removal_mode 0)
		)
		(polygon
			(pts
				(arc
					(start 176.406048 -225.385376)
					(mid 175.738028 -225.385376)
					(end 176.406048 -225.385376)
				)
			)
		)
	)
	(zone
		(layers "B.Cu" "In15.Cu")
		(hatch none 0.5)
		(connect_pads
			(clearance 0)
		)
		(min_thickness 0.25)
		(keepout
			(tracks not_allowed)
			(vias allowed)
			(pads allowed)
			(copperpour not_allowed)
			(footprints allowed)
		)
		(placement
			(enabled no)
			(sheetname "")
		)
		(fill yes
			(thermal_gap 0.5)
			(thermal_bridge_width 0.5)
			(island_removal_mode 0)
		)
		(polygon
			(pts
				(arc
					(start 296.058082 -310.384952)
					(mid 295.390062 -310.384952)
					(end 296.058082 -310.384952)
				)
			)
		)
	)
	(zone
		(layers "B.Cu" "In15.Cu")
		(hatch none 0.5)
		(connect_pads
			(clearance 0)
		)
		(min_thickness 0.25)
		(keepout
			(tracks not_allowed)
			(vias allowed)
			(pads allowed)
			(copperpour not_allowed)
			(footprints allowed)
		)
		(placement
			(enabled no)
			(sheetname "")
		)
		(fill yes
			(thermal_gap 0.5)
			(thermal_bridge_width 0.5)
			(island_removal_mode 0)
		)
		(polygon
			(pts
				(arc
					(start 136.359646 -269.226284)
					(mid 135.729726 -269.226284)
					(end 136.359646 -269.226284)
				)
			)
		)
	)
	(zone
		(layers "B.Cu" "In15.Cu")
		(hatch none 0.5)
		(connect_pads
			(clearance 0)
		)
		(min_thickness 0.25)
		(keepout
			(tracks not_allowed)
			(vias allowed)
			(pads allowed)
			(copperpour not_allowed)
			(footprints allowed)
		)
		(placement
			(enabled no)
			(sheetname "")
		)
		(fill yes
			(thermal_gap 0.5)
			(thermal_bridge_width 0.5)
			(island_removal_mode 0)
		)
		(polygon
			(pts
				(arc
					(start 383.059686 -230.714296)
					(mid 382.429766 -230.714296)
					(end 383.059686 -230.714296)
				)
			)
		)
	)
	(zone
		(layers "B.Cu" "In15.Cu")
		(hatch none 0.5)
		(connect_pads
			(clearance 0)
		)
		(min_thickness 0.25)
		(keepout
			(tracks not_allowed)
			(vias allowed)
			(pads allowed)
			(copperpour not_allowed)
			(footprints allowed)
		)
		(placement
			(enabled no)
			(sheetname "")
		)
		(fill yes
			(thermal_gap 0.5)
			(thermal_bridge_width 0.5)
			(island_removal_mode 0)
		)
		(polygon
			(pts
				(arc
					(start 135.119618 -248.534428)
					(mid 134.489698 -248.534428)
					(end 135.119618 -248.534428)
				)
			)
		)
	)
	(zone
		(layers "B.Cu" "In15.Cu")
		(hatch none 0.5)
		(connect_pads
			(clearance 0)
		)
		(min_thickness 0.25)
		(keepout
			(tracks not_allowed)
			(vias allowed)
			(pads allowed)
			(copperpour not_allowed)
			(footprints allowed)
		)
		(placement
			(enabled no)
			(sheetname "")
		)
		(fill yes
			(thermal_gap 0.5)
			(thermal_bridge_width 0.5)
			(island_removal_mode 0)
		)
		(polygon
			(pts
				(arc
					(start 125.249686 -239.624362)
					(mid 124.619766 -239.624362)
					(end 125.249686 -239.624362)
				)
			)
		)
	)
	(zone
		(layers "B.Cu" "In15.Cu")
		(hatch none 0.5)
		(connect_pads
			(clearance 0)
		)
		(min_thickness 0.25)
		(keepout
			(tracks not_allowed)
			(vias allowed)
			(pads allowed)
			(copperpour not_allowed)
			(footprints allowed)
		)
		(placement
			(enabled no)
			(sheetname "")
		)
		(fill yes
			(thermal_gap 0.5)
			(thermal_bridge_width 0.5)
			(island_removal_mode 0)
		)
		(polygon
			(pts
				(arc
					(start 176.406048 -300.185328)
					(mid 175.738028 -300.185328)
					(end 176.406048 -300.185328)
				)
			)
		)
	)
	(zone
		(layers "B.Cu" "In15.Cu")
		(hatch none 0.5)
		(connect_pads
			(clearance 0)
		)
		(min_thickness 0.25)
		(keepout
			(tracks not_allowed)
			(vias allowed)
			(pads allowed)
			(copperpour not_allowed)
			(footprints allowed)
		)
		(placement
			(enabled no)
			(sheetname "")
		)
		(fill yes
			(thermal_gap 0.5)
			(thermal_bridge_width 0.5)
			(island_removal_mode 0)
		)
		(polygon
			(pts
				(arc
					(start 300.15815 -217.73515)
					(mid 299.49013 -217.73515)
					(end 300.15815 -217.73515)
				)
			)
		)
	)
	(zone
		(layers "B.Cu" "In15.Cu")
		(hatch none 0.5)
		(connect_pads
			(clearance 0)
		)
		(min_thickness 0.25)
		(keepout
			(tracks not_allowed)
			(vias allowed)
			(pads allowed)
			(copperpour not_allowed)
			(footprints allowed)
		)
		(placement
			(enabled no)
			(sheetname "")
		)
		(fill yes
			(thermal_gap 0.5)
			(thermal_bridge_width 0.5)
			(island_removal_mode 0)
		)
		(polygon
			(pts
				(arc
					(start 89.536016 -229.90429)
					(mid 88.906096 -229.90429)
					(end 89.536016 -229.90429)
				)
			)
		)
	)
	(zone
		(layers "B.Cu" "In15.Cu")
		(hatch none 0.5)
		(connect_pads
			(clearance 0)
		)
		(min_thickness 0.25)
		(keepout
			(tracks not_allowed)
			(vias allowed)
			(pads allowed)
			(copperpour not_allowed)
			(footprints allowed)
		)
		(placement
			(enabled no)
			(sheetname "")
		)
		(fill yes
			(thermal_gap 0.5)
			(thermal_bridge_width 0.5)
			(island_removal_mode 0)
		)
		(polygon
			(pts
				(arc
					(start 172.30598 -246.63527)
					(mid 171.63796 -246.63527)
					(end 172.30598 -246.63527)
				)
			)
		)
	)
	(zone
		(layers "B.Cu" "In15.Cu")
		(hatch none 0.5)
		(connect_pads
			(clearance 0)
		)
		(min_thickness 0.25)
		(keepout
			(tracks not_allowed)
			(vias allowed)
			(pads allowed)
			(copperpour not_allowed)
			(footprints allowed)
		)
		(placement
			(enabled no)
			(sheetname "")
		)
		(fill yes
			(thermal_gap 0.5)
			(thermal_bridge_width 0.5)
			(island_removal_mode 0)
		)
		(polygon
			(pts
				(arc
					(start 87.655908 -254.20447)
					(mid 87.025988 -254.20447)
					(end 87.655908 -254.20447)
				)
			)
		)
	)
	(zone
		(layers "B.Cu" "In15.Cu")
		(hatch none 0.5)
		(connect_pads
			(clearance 0)
		)
		(min_thickness 0.25)
		(keepout
			(tracks not_allowed)
			(vias allowed)
			(pads allowed)
			(copperpour not_allowed)
			(footprints allowed)
		)
		(placement
			(enabled no)
			(sheetname "")
		)
		(fill yes
			(thermal_gap 0.5)
			(thermal_bridge_width 0.5)
			(island_removal_mode 0)
		)
		(polygon
			(pts
				(arc
					(start 337.306158 -285.42615)
					(mid 336.676238 -285.42615)
					(end 337.306158 -285.42615)
				)
			)
		)
	)
	(zone
		(layers "B.Cu" "In15.Cu")
		(hatch none 0.5)
		(connect_pads
			(clearance 0)
		)
		(min_thickness 0.25)
		(keepout
			(tracks not_allowed)
			(vias allowed)
			(pads allowed)
			(copperpour not_allowed)
			(footprints allowed)
		)
		(placement
			(enabled no)
			(sheetname "")
		)
		(fill yes
			(thermal_gap 0.5)
			(thermal_bridge_width 0.5)
			(island_removal_mode 0)
		)
		(polygon
			(pts
				(arc
					(start 147.13712 -434.48986)
					(mid 146.362928 -434.48986)
					(end 147.13712 -434.48986)
				)
			)
		)
	)
	(zone
		(layers "B.Cu" "In15.Cu")
		(hatch none 0.5)
		(connect_pads
			(clearance 0)
		)
		(min_thickness 0.25)
		(keepout
			(tracks not_allowed)
			(vias allowed)
			(pads allowed)
			(copperpour not_allowed)
			(footprints allowed)
		)
		(placement
			(enabled no)
			(sheetname "")
		)
		(fill yes
			(thermal_gap 0.5)
			(thermal_bridge_width 0.5)
			(island_removal_mode 0)
		)
		(polygon
			(pts
				(arc
					(start 136.8298 -284.616398)
					(mid 136.19988 -284.616398)
					(end 136.8298 -284.616398)
				)
			)
		)
	)
	(zone
		(layers "B.Cu" "In15.Cu")
		(hatch none 0.5)
		(connect_pads
			(clearance 0)
		)
		(min_thickness 0.25)
		(keepout
			(tracks not_allowed)
			(vias allowed)
			(pads allowed)
			(copperpour not_allowed)
			(footprints allowed)
		)
		(placement
			(enabled no)
			(sheetname "")
		)
		(fill yes
			(thermal_gap 0.5)
			(thermal_bridge_width 0.5)
			(island_removal_mode 0)
		)
		(polygon
			(pts
				(arc
					(start 340.036912 -433.289964)
					(mid 339.26272 -433.289964)
					(end 340.036912 -433.289964)
				)
			)
		)
	)
	(zone
		(layers "B.Cu" "In15.Cu")
		(hatch none 0.5)
		(connect_pads
			(clearance 0)
		)
		(min_thickness 0.25)
		(keepout
			(tracks not_allowed)
			(vias allowed)
			(pads allowed)
			(copperpour not_allowed)
			(footprints allowed)
		)
		(placement
			(enabled no)
			(sheetname "")
		)
		(fill yes
			(thermal_gap 0.5)
			(thermal_bridge_width 0.5)
			(island_removal_mode 0)
		)
		(polygon
			(pts
				(arc
					(start 172.30598 -239.835436)
					(mid 171.63796 -239.835436)
					(end 172.30598 -239.835436)
				)
			)
		)
	)
	(zone
		(layers "B.Cu" "In15.Cu")
		(hatch none 0.5)
		(connect_pads
			(clearance 0)
		)
		(min_thickness 0.25)
		(keepout
			(tracks not_allowed)
			(vias allowed)
			(pads allowed)
			(copperpour not_allowed)
			(footprints allowed)
		)
		(placement
			(enabled no)
			(sheetname "")
		)
		(fill yes
			(thermal_gap 0.5)
			(thermal_bridge_width 0.5)
			(island_removal_mode 0)
		)
		(polygon
			(pts
				(arc
					(start 337.476084 -241.24412)
					(mid 336.846164 -241.24412)
					(end 337.476084 -241.24412)
				)
			)
		)
	)
	(zone
		(layers "B.Cu" "In15.Cu")
		(hatch none 0.5)
		(connect_pads
			(clearance 0)
		)
		(min_thickness 0.25)
		(keepout
			(tracks not_allowed)
			(vias allowed)
			(pads allowed)
			(copperpour not_allowed)
			(footprints allowed)
		)
		(placement
			(enabled no)
			(sheetname "")
		)
		(fill yes
			(thermal_gap 0.5)
			(thermal_bridge_width 0.5)
			(island_removal_mode 0)
		)
		(polygon
			(pts
				(arc
					(start 88.126062 -248.534428)
					(mid 87.496142 -248.534428)
					(end 88.126062 -248.534428)
				)
			)
		)
	)
	(zone
		(layers "B.Cu" "In15.Cu")
		(hatch none 0.5)
		(connect_pads
			(clearance 0)
		)
		(min_thickness 0.25)
		(keepout
			(tracks not_allowed)
			(vias allowed)
			(pads allowed)
			(copperpour not_allowed)
			(footprints allowed)
		)
		(placement
			(enabled no)
			(sheetname "")
		)
		(fill yes
			(thermal_gap 0.5)
			(thermal_bridge_width 0.5)
			(island_removal_mode 0)
		)
		(polygon
			(pts
				(arc
					(start 52.218082 -273.835368)
					(mid 51.550062 -273.835368)
					(end 52.218082 -273.835368)
				)
			)
		)
	)
	(zone
		(layers "B.Cu" "In15.Cu")
		(hatch none 0.5)
		(connect_pads
			(clearance 0)
		)
		(min_thickness 0.25)
		(keepout
			(tracks not_allowed)
			(vias allowed)
			(pads allowed)
			(copperpour not_allowed)
			(footprints allowed)
		)
		(placement
			(enabled no)
			(sheetname "")
		)
		(fill yes
			(thermal_gap 0.5)
			(thermal_bridge_width 0.5)
			(island_removal_mode 0)
		)
		(polygon
			(pts
				(arc
					(start 424.346116 -238.13516)
					(mid 423.678096 -238.13516)
					(end 424.346116 -238.13516)
				)
			)
		)
	)
	(zone
		(layers "B.Cu" "In15.Cu")
		(hatch none 0.5)
		(connect_pads
			(clearance 0)
		)
		(min_thickness 0.25)
		(keepout
			(tracks not_allowed)
			(vias allowed)
			(pads allowed)
			(copperpour not_allowed)
			(footprints allowed)
		)
		(placement
			(enabled no)
			(sheetname "")
		)
		(fill yes
			(thermal_gap 0.5)
			(thermal_bridge_width 0.5)
			(island_removal_mode 0)
		)
		(polygon
			(pts
				(arc
					(start 134.649718 -254.20447)
					(mid 134.019798 -254.20447)
					(end 134.649718 -254.20447)
				)
			)
		)
	)
	(zone
		(layers "B.Cu" "In15.Cu")
		(hatch none 0.5)
		(connect_pads
			(clearance 0)
		)
		(min_thickness 0.25)
		(keepout
			(tracks not_allowed)
			(vias allowed)
			(pads allowed)
			(copperpour not_allowed)
			(footprints allowed)
		)
		(placement
			(enabled no)
			(sheetname "")
		)
		(fill yes
			(thermal_gap 0.5)
			(thermal_bridge_width 0.5)
			(island_removal_mode 0)
		)
		(polygon
			(pts
				(arc
					(start 405.137112 -435.489858)
					(mid 404.36292 -435.489858)
					(end 405.137112 -435.489858)
				)
			)
		)
	)
	(zone
		(layers "B.Cu" "In15.Cu")
		(hatch none 0.5)
		(connect_pads
			(clearance 0)
		)
		(min_thickness 0.25)
		(keepout
			(tracks not_allowed)
			(vias allowed)
			(pads allowed)
			(copperpour not_allowed)
			(footprints allowed)
		)
		(placement
			(enabled no)
			(sheetname "")
		)
		(fill yes
			(thermal_gap 0.5)
			(thermal_bridge_width 0.5)
			(island_removal_mode 0)
		)
		(polygon
			(pts
				(arc
					(start 300.15815 -236.435138)
					(mid 299.49013 -236.435138)
					(end 300.15815 -236.435138)
				)
			)
		)
	)
	(zone
		(layers "B.Cu" "In15.Cu")
		(hatch none 0.5)
		(connect_pads
			(clearance 0)
		)
		(min_thickness 0.25)
		(keepout
			(tracks not_allowed)
			(vias allowed)
			(pads allowed)
			(copperpour not_allowed)
			(footprints allowed)
		)
		(placement
			(enabled no)
			(sheetname "")
		)
		(fill yes
			(thermal_gap 0.5)
			(thermal_bridge_width 0.5)
			(island_removal_mode 0)
		)
		(polygon
			(pts
				(arc
					(start 49.706276 -386.003292)
					(mid 49.076356 -386.003292)
					(end 49.706276 -386.003292)
				)
			)
		)
	)
	(zone
		(layers "B.Cu" "In15.Cu")
		(hatch none 0.5)
		(connect_pads
			(clearance 0)
		)
		(min_thickness 0.25)
		(keepout
			(tracks not_allowed)
			(vias allowed)
			(pads allowed)
			(copperpour not_allowed)
			(footprints allowed)
		)
		(placement
			(enabled no)
			(sheetname "")
		)
		(fill yes
			(thermal_gap 0.5)
			(thermal_bridge_width 0.5)
			(island_removal_mode 0)
		)
		(polygon
			(pts
				(arc
					(start 89.066116 -230.71455)
					(mid 88.436196 -230.71455)
					(end 89.066116 -230.71455)
				)
			)
		)
	)
	(zone
		(layers "B.Cu" "In15.Cu")
		(hatch none 0.5)
		(connect_pads
			(clearance 0)
		)
		(min_thickness 0.25)
		(keepout
			(tracks not_allowed)
			(vias allowed)
			(pads allowed)
			(copperpour not_allowed)
			(footprints allowed)
		)
		(placement
			(enabled no)
			(sheetname "")
		)
		(fill yes
			(thermal_gap 0.5)
			(thermal_bridge_width 0.5)
			(island_removal_mode 0)
		)
		(polygon
			(pts
				(arc
					(start 337.776058 -274.896072)
					(mid 337.146138 -274.896072)
					(end 337.776058 -274.896072)
				)
			)
		)
	)
	(zone
		(layers "B.Cu" "In15.Cu")
		(hatch none 0.5)
		(connect_pads
			(clearance 0)
		)
		(min_thickness 0.25)
		(keepout
			(tracks not_allowed)
			(vias allowed)
			(pads allowed)
			(copperpour not_allowed)
			(footprints allowed)
		)
		(placement
			(enabled no)
			(sheetname "")
		)
		(fill yes
			(thermal_gap 0.5)
			(thermal_bridge_width 0.5)
			(island_removal_mode 0)
		)
		(polygon
			(pts
				(arc
					(start 300.15815 -214.335106)
					(mid 299.49013 -214.335106)
					(end 300.15815 -214.335106)
				)
			)
		)
	)
	(zone
		(layers "B.Cu" "In15.Cu")
		(hatch none 0.5)
		(connect_pads
			(clearance 0)
		)
		(min_thickness 0.25)
		(keepout
			(tracks not_allowed)
			(vias allowed)
			(pads allowed)
			(copperpour not_allowed)
			(footprints allowed)
		)
		(placement
			(enabled no)
			(sheetname "")
		)
		(fill yes
			(thermal_gap 0.5)
			(thermal_bridge_width 0.5)
			(island_removal_mode 0)
		)
		(polygon
			(pts
				(arc
					(start 354.67798 -400.811238)
					(mid 354.00996 -400.811238)
					(end 354.67798 -400.811238)
				)
			)
		)
	)
	(zone
		(layers "B.Cu" "In15.Cu")
		(hatch none 0.5)
		(connect_pads
			(clearance 0)
		)
		(min_thickness 0.25)
		(keepout
			(tracks not_allowed)
			(vias allowed)
			(pads allowed)
			(copperpour not_allowed)
			(footprints allowed)
		)
		(placement
			(enabled no)
			(sheetname "")
		)
		(fill yes
			(thermal_gap 0.5)
			(thermal_bridge_width 0.5)
			(island_removal_mode 0)
		)
		(polygon
			(pts
				(arc
					(start 337.776058 -287.856168)
					(mid 337.146138 -287.856168)
					(end 337.776058 -287.856168)
				)
			)
		)
	)
	(zone
		(layers "B.Cu" "In15.Cu")
		(hatch none 0.5)
		(connect_pads
			(clearance 0)
		)
		(min_thickness 0.25)
		(keepout
			(tracks not_allowed)
			(vias allowed)
			(pads allowed)
			(copperpour not_allowed)
			(footprints allowed)
		)
		(placement
			(enabled no)
			(sheetname "")
		)
		(fill yes
			(thermal_gap 0.5)
			(thermal_bridge_width 0.5)
			(island_removal_mode 0)
		)
		(polygon
			(pts
				(arc
					(start 55.706264 -386.003292)
					(mid 55.076344 -386.003292)
					(end 55.706264 -386.003292)
				)
			)
		)
	)
	(zone
		(layers "B.Cu" "In15.Cu")
		(hatch none 0.5)
		(connect_pads
			(clearance 0)
		)
		(min_thickness 0.25)
		(keepout
			(tracks not_allowed)
			(vias allowed)
			(pads allowed)
			(copperpour not_allowed)
			(footprints allowed)
		)
		(placement
			(enabled no)
			(sheetname "")
		)
		(fill yes
			(thermal_gap 0.5)
			(thermal_bridge_width 0.5)
			(island_removal_mode 0)
		)
		(polygon
			(pts
				(arc
					(start 382.88976 -286.236156)
					(mid 382.25984 -286.236156)
					(end 382.88976 -286.236156)
				)
			)
		)
	)
	(zone
		(layers "B.Cu" "In15.Cu")
		(hatch none 0.5)
		(connect_pads
			(clearance 0)
		)
		(min_thickness 0.25)
		(keepout
			(tracks not_allowed)
			(vias allowed)
			(pads allowed)
			(copperpour not_allowed)
			(footprints allowed)
		)
		(placement
			(enabled no)
			(sheetname "")
		)
		(fill yes
			(thermal_gap 0.5)
			(thermal_bridge_width 0.5)
			(island_removal_mode 0)
		)
		(polygon
			(pts
				(arc
					(start 136.359646 -287.046162)
					(mid 135.729726 -287.046162)
					(end 136.359646 -287.046162)
				)
			)
		)
	)
	(zone
		(layers "B.Cu" "In15.Cu")
		(hatch none 0.5)
		(connect_pads
			(clearance 0)
		)
		(min_thickness 0.25)
		(keepout
			(tracks not_allowed)
			(vias allowed)
			(pads allowed)
			(copperpour not_allowed)
			(footprints allowed)
		)
		(placement
			(enabled no)
			(sheetname "")
		)
		(fill yes
			(thermal_gap 0.5)
			(thermal_bridge_width 0.5)
			(island_removal_mode 0)
		)
		(polygon
			(pts
				(arc
					(start 336.06613 -253.39421)
					(mid 335.43621 -253.39421)
					(end 336.06613 -253.39421)
				)
			)
		)
	)
	(zone
		(layers "B.Cu" "In15.Cu")
		(hatch none 0.5)
		(connect_pads
			(clearance 0)
		)
		(min_thickness 0.25)
		(keepout
			(tracks not_allowed)
			(vias allowed)
			(pads allowed)
			(copperpour not_allowed)
			(footprints allowed)
		)
		(placement
			(enabled no)
			(sheetname "")
		)
		(fill yes
			(thermal_gap 0.5)
			(thermal_bridge_width 0.5)
			(island_removal_mode 0)
		)
		(polygon
			(pts
				(arc
					(start 122.729752 -273.276314)
					(mid 122.099832 -273.276314)
					(end 122.729752 -273.276314)
				)
			)
		)
	)
	(zone
		(layers "B.Cu" "In15.Cu")
		(hatch none 0.5)
		(connect_pads
			(clearance 0)
		)
		(min_thickness 0.25)
		(keepout
			(tracks not_allowed)
			(vias allowed)
			(pads allowed)
			(copperpour not_allowed)
			(footprints allowed)
		)
		(placement
			(enabled no)
			(sheetname "")
		)
		(fill yes
			(thermal_gap 0.5)
			(thermal_bridge_width 0.5)
			(island_removal_mode 0)
		)
		(polygon
			(pts
				(arc
					(start 176.406048 -313.78525)
					(mid 175.738028 -313.78525)
					(end 176.406048 -313.78525)
				)
			)
		)
	)
	(zone
		(layers "B.Cu" "In15.Cu")
		(hatch none 0.5)
		(connect_pads
			(clearance 0)
		)
		(min_thickness 0.25)
		(keepout
			(tracks not_allowed)
			(vias allowed)
			(pads allowed)
			(copperpour not_allowed)
			(footprints allowed)
		)
		(placement
			(enabled no)
			(sheetname "")
		)
		(fill yes
			(thermal_gap 0.5)
			(thermal_bridge_width 0.5)
			(island_removal_mode 0)
		)
		(polygon
			(pts
				(arc
					(start 337.306158 -278.946102)
					(mid 336.676238 -278.946102)
					(end 337.306158 -278.946102)
				)
			)
		)
	)
	(zone
		(layers "B.Cu" "In15.Cu")
		(hatch none 0.5)
		(connect_pads
			(clearance 0)
		)
		(min_thickness 0.25)
		(keepout
			(tracks not_allowed)
			(vias allowed)
			(pads allowed)
			(copperpour not_allowed)
			(footprints allowed)
		)
		(placement
			(enabled no)
			(sheetname "")
		)
		(fill yes
			(thermal_gap 0.5)
			(thermal_bridge_width 0.5)
			(island_removal_mode 0)
		)
		(polygon
			(pts
				(arc
					(start 80.037178 -433.289964)
					(mid 79.262986 -433.289964)
					(end 80.037178 -433.289964)
				)
			)
		)
	)
	(zone
		(layers "B.Cu" "In15.Cu")
		(hatch none 0.5)
		(connect_pads
			(clearance 0)
		)
		(min_thickness 0.25)
		(keepout
			(tracks not_allowed)
			(vias allowed)
			(pads allowed)
			(copperpour not_allowed)
			(footprints allowed)
		)
		(placement
			(enabled no)
			(sheetname "")
		)
		(fill yes
			(thermal_gap 0.5)
			(thermal_bridge_width 0.5)
			(island_removal_mode 0)
		)
		(polygon
			(pts
				(arc
					(start 384.299714 -287.045908)
					(mid 383.669794 -287.045908)
					(end 384.299714 -287.045908)
				)
			)
		)
	)
	(zone
		(layers "B.Cu" "In15.Cu")
		(hatch none 0.5)
		(connect_pads
			(clearance 0)
		)
		(min_thickness 0.25)
		(keepout
			(tracks not_allowed)
			(vias allowed)
			(pads allowed)
			(copperpour not_allowed)
			(footprints allowed)
		)
		(placement
			(enabled no)
			(sheetname "")
		)
		(fill yes
			(thermal_gap 0.5)
			(thermal_bridge_width 0.5)
			(island_removal_mode 0)
		)
		(polygon
			(pts
				(arc
					(start 424.346116 -210.935062)
					(mid 423.678096 -210.935062)
					(end 424.346116 -210.935062)
				)
			)
		)
	)
	(zone
		(layers "B.Cu" "In15.Cu")
		(hatch none 0.5)
		(connect_pads
			(clearance 0)
		)
		(min_thickness 0.25)
		(keepout
			(tracks not_allowed)
			(vias allowed)
			(pads allowed)
			(copperpour not_allowed)
			(footprints allowed)
		)
		(placement
			(enabled no)
			(sheetname "")
		)
		(fill yes
			(thermal_gap 0.5)
			(thermal_bridge_width 0.5)
			(island_removal_mode 0)
		)
		(polygon
			(pts
				(arc
					(start 136.359646 -288.666174)
					(mid 135.729726 -288.666174)
					(end 136.359646 -288.666174)
				)
			)
		)
	)
	(zone
		(layers "B.Cu" "In15.Cu")
		(hatch none 0.5)
		(connect_pads
			(clearance 0)
		)
		(min_thickness 0.25)
		(keepout
			(tracks not_allowed)
			(vias allowed)
			(pads allowed)
			(copperpour not_allowed)
			(footprints allowed)
		)
		(placement
			(enabled no)
			(sheetname "")
		)
		(fill yes
			(thermal_gap 0.5)
			(thermal_bridge_width 0.5)
			(island_removal_mode 0)
		)
		(polygon
			(pts
				(arc
					(start 420.246048 -277.235158)
					(mid 419.578028 -277.235158)
					(end 420.246048 -277.235158)
				)
			)
		)
	)
	(zone
		(layers "B.Cu" "In15.Cu")
		(hatch none 0.5)
		(connect_pads
			(clearance 0)
		)
		(min_thickness 0.25)
		(keepout
			(tracks not_allowed)
			(vias allowed)
			(pads allowed)
			(copperpour not_allowed)
			(footprints allowed)
		)
		(placement
			(enabled no)
			(sheetname "")
		)
		(fill yes
			(thermal_gap 0.5)
			(thermal_bridge_width 0.5)
			(island_removal_mode 0)
		)
		(polygon
			(pts
				(arc
					(start 176.406048 -247.485408)
					(mid 175.738028 -247.485408)
					(end 176.406048 -247.485408)
				)
			)
		)
	)
	(zone
		(layers "B.Cu" "In15.Cu")
		(hatch none 0.5)
		(connect_pads
			(clearance 0)
		)
		(min_thickness 0.25)
		(keepout
			(tracks not_allowed)
			(vias allowed)
			(pads allowed)
			(copperpour not_allowed)
			(footprints allowed)
		)
		(placement
			(enabled no)
			(sheetname "")
		)
		(fill yes
			(thermal_gap 0.5)
			(thermal_bridge_width 0.5)
			(island_removal_mode 0)
		)
		(polygon
			(pts
				(arc
					(start 335.595976 -234.764072)
					(mid 334.966056 -234.764072)
					(end 335.595976 -234.764072)
				)
			)
		)
	)
	(zone
		(layers "B.Cu" "In15.Cu")
		(hatch none 0.5)
		(connect_pads
			(clearance 0)
		)
		(min_thickness 0.25)
		(keepout
			(tracks not_allowed)
			(vias allowed)
			(pads allowed)
			(copperpour not_allowed)
			(footprints allowed)
		)
		(placement
			(enabled no)
			(sheetname "")
		)
		(fill yes
			(thermal_gap 0.5)
			(thermal_bridge_width 0.5)
			(island_removal_mode 0)
		)
		(polygon
			(pts
				(arc
					(start 52.218082 -287.43529)
					(mid 51.550062 -287.43529)
					(end 52.218082 -287.43529)
				)
			)
		)
	)
	(zone
		(layers "B.Cu" "In15.Cu")
		(hatch none 0.5)
		(connect_pads
			(clearance 0)
		)
		(min_thickness 0.25)
		(keepout
			(tracks not_allowed)
			(vias allowed)
			(pads allowed)
			(copperpour not_allowed)
			(footprints allowed)
		)
		(placement
			(enabled no)
			(sheetname "")
		)
		(fill yes
			(thermal_gap 0.5)
			(thermal_bridge_width 0.5)
			(island_removal_mode 0)
		)
		(polygon
			(pts
				(arc
					(start 135.119618 -233.95432)
					(mid 134.489698 -233.95432)
					(end 135.119618 -233.95432)
				)
			)
		)
	)
	(zone
		(layers "B.Cu" "In15.Cu")
		(hatch none 0.5)
		(connect_pads
			(clearance 0)
		)
		(min_thickness 0.25)
		(keepout
			(tracks not_allowed)
			(vias allowed)
			(pads allowed)
			(copperpour not_allowed)
			(footprints allowed)
		)
		(placement
			(enabled no)
			(sheetname "")
		)
		(fill yes
			(thermal_gap 0.5)
			(thermal_bridge_width 0.5)
			(island_removal_mode 0)
		)
		(polygon
			(pts
				(arc
					(start 87.655908 -234.764326)
					(mid 87.025988 -234.764326)
					(end 87.655908 -234.764326)
				)
			)
		)
	)
	(zone
		(layers "B.Cu" "In15.Cu")
		(hatch none 0.5)
		(connect_pads
			(clearance 0)
		)
		(min_thickness 0.25)
		(keepout
			(tracks not_allowed)
			(vias allowed)
			(pads allowed)
			(copperpour not_allowed)
			(footprints allowed)
		)
		(placement
			(enabled no)
			(sheetname "")
		)
		(fill yes
			(thermal_gap 0.5)
			(thermal_bridge_width 0.5)
			(island_removal_mode 0)
		)
		(polygon
			(pts
				(arc
					(start 176.406048 -264.485374)
					(mid 175.738028 -264.485374)
					(end 176.406048 -264.485374)
				)
			)
		)
	)
	(zone
		(layers "B.Cu" "In15.Cu")
		(hatch none 0.5)
		(connect_pads
			(clearance 0)
		)
		(min_thickness 0.25)
		(keepout
			(tracks not_allowed)
			(vias allowed)
			(pads allowed)
			(copperpour not_allowed)
			(footprints allowed)
		)
		(placement
			(enabled no)
			(sheetname "")
		)
		(fill yes
			(thermal_gap 0.5)
			(thermal_bridge_width 0.5)
			(island_removal_mode 0)
		)
		(polygon
			(pts
				(arc
					(start 424.346116 -315.485018)
					(mid 423.678096 -315.485018)
					(end 424.346116 -315.485018)
				)
			)
		)
	)
	(zone
		(layers "B.Cu" "In15.Cu")
		(hatch none 0.5)
		(connect_pads
			(clearance 0)
		)
		(min_thickness 0.25)
		(keepout
			(tracks not_allowed)
			(vias allowed)
			(pads allowed)
			(copperpour not_allowed)
			(footprints allowed)
		)
		(placement
			(enabled no)
			(sheetname "")
		)
		(fill yes
			(thermal_gap 0.5)
			(thermal_bridge_width 0.5)
			(island_removal_mode 0)
		)
		(polygon
			(pts
				(arc
					(start 52.218082 -276.385274)
					(mid 51.550062 -276.385274)
					(end 52.218082 -276.385274)
				)
			)
		)
	)
	(zone
		(layers "B.Cu" "In15.Cu")
		(hatch none 0.5)
		(connect_pads
			(clearance 0)
		)
		(min_thickness 0.25)
		(keepout
			(tracks not_allowed)
			(vias allowed)
			(pads allowed)
			(copperpour not_allowed)
			(footprints allowed)
		)
		(placement
			(enabled no)
			(sheetname "")
		)
		(fill yes
			(thermal_gap 0.5)
			(thermal_bridge_width 0.5)
			(island_removal_mode 0)
		)
		(polygon
			(pts
				(arc
					(start 123.369578 -241.244374)
					(mid 122.739658 -241.244374)
					(end 123.369578 -241.244374)
				)
			)
		)
	)
	(zone
		(layers "B.Cu" "In15.Cu")
		(hatch none 0.5)
		(connect_pads
			(clearance 0)
		)
		(min_thickness 0.25)
		(keepout
			(tracks not_allowed)
			(vias allowed)
			(pads allowed)
			(copperpour not_allowed)
			(footprints allowed)
		)
		(placement
			(enabled no)
			(sheetname "")
		)
		(fill yes
			(thermal_gap 0.5)
			(thermal_bridge_width 0.5)
			(island_removal_mode 0)
		)
		(polygon
			(pts
				(arc
					(start 176.406048 -206.685388)
					(mid 175.738028 -206.685388)
					(end 176.406048 -206.685388)
				)
			)
		)
	)
	(zone
		(layers "B.Cu" "In15.Cu")
		(hatch none 0.5)
		(connect_pads
			(clearance 0)
		)
		(min_thickness 0.25)
		(keepout
			(tracks not_allowed)
			(vias allowed)
			(pads allowed)
			(copperpour not_allowed)
			(footprints allowed)
		)
		(placement
			(enabled no)
			(sheetname "")
		)
		(fill yes
			(thermal_gap 0.5)
			(thermal_bridge_width 0.5)
			(island_removal_mode 0)
		)
		(polygon
			(pts
				(arc
					(start 317.036704 -435.489858)
					(mid 316.262512 -435.489858)
					(end 317.036704 -435.489858)
				)
			)
		)
	)
	(zone
		(layers "B.Cu" "In15.Cu")
		(hatch none 0.5)
		(connect_pads
			(clearance 0)
		)
		(min_thickness 0.25)
		(keepout
			(tracks not_allowed)
			(vias allowed)
			(pads allowed)
			(copperpour not_allowed)
			(footprints allowed)
		)
		(placement
			(enabled no)
			(sheetname "")
		)
		(fill yes
			(thermal_gap 0.5)
			(thermal_bridge_width 0.5)
			(island_removal_mode 0)
		)
		(polygon
			(pts
				(arc
					(start 142.976854 -371.49913)
					(mid 142.308834 -371.49913)
					(end 142.976854 -371.49913)
				)
			)
		)
	)
	(zone
		(layers "B.Cu" "In15.Cu")
		(hatch none 0.5)
		(connect_pads
			(clearance 0)
		)
		(min_thickness 0.25)
		(keepout
			(tracks not_allowed)
			(vias allowed)
			(pads allowed)
			(copperpour not_allowed)
			(footprints allowed)
		)
		(placement
			(enabled no)
			(sheetname "")
		)
		(fill yes
			(thermal_gap 0.5)
			(thermal_bridge_width 0.5)
			(island_removal_mode 0)
		)
		(polygon
			(pts
				(arc
					(start 88.126062 -238.814356)
					(mid 87.496142 -238.814356)
					(end 88.126062 -238.814356)
				)
			)
		)
	)
	(zone
		(layers "B.Cu" "In15.Cu")
		(hatch none 0.5)
		(connect_pads
			(clearance 0)
		)
		(min_thickness 0.25)
		(keepout
			(tracks not_allowed)
			(vias allowed)
			(pads allowed)
			(copperpour not_allowed)
			(footprints allowed)
		)
		(placement
			(enabled no)
			(sheetname "")
		)
		(fill yes
			(thermal_gap 0.5)
			(thermal_bridge_width 0.5)
			(island_removal_mode 0)
		)
		(polygon
			(pts
				(arc
					(start 114.739674 -269.226284)
					(mid 114.109754 -269.226284)
					(end 114.739674 -269.226284)
				)
			)
		)
	)
	(zone
		(layers "B.Cu" "In15.Cu")
		(hatch none 0.5)
		(connect_pads
			(clearance 0)
		)
		(min_thickness 0.25)
		(keepout
			(tracks not_allowed)
			(vias allowed)
			(pads allowed)
			(copperpour not_allowed)
			(footprints allowed)
		)
		(placement
			(enabled no)
			(sheetname "")
		)
		(fill yes
			(thermal_gap 0.5)
			(thermal_bridge_width 0.5)
			(island_removal_mode 0)
		)
		(polygon
			(pts
				(arc
					(start 90.037158 -434.289962)
					(mid 89.262966 -434.289962)
					(end 90.037158 -434.289962)
				)
			)
		)
	)
	(zone
		(layers "B.Cu" "In15.Cu")
		(hatch none 0.5)
		(connect_pads
			(clearance 0)
		)
		(min_thickness 0.25)
		(keepout
			(tracks not_allowed)
			(vias allowed)
			(pads allowed)
			(copperpour not_allowed)
			(footprints allowed)
		)
		(placement
			(enabled no)
			(sheetname "")
		)
		(fill yes
			(thermal_gap 0.5)
			(thermal_bridge_width 0.5)
			(island_removal_mode 0)
		)
		(polygon
			(pts
				(arc
					(start 135.419592 -270.846296)
					(mid 134.789672 -270.846296)
					(end 135.419592 -270.846296)
				)
			)
		)
	)
	(zone
		(layers "B.Cu" "In15.Cu")
		(hatch none 0.5)
		(connect_pads
			(clearance 0)
		)
		(min_thickness 0.25)
		(keepout
			(tracks not_allowed)
			(vias allowed)
			(pads allowed)
			(copperpour not_allowed)
			(footprints allowed)
		)
		(placement
			(enabled no)
			(sheetname "")
		)
		(fill yes
			(thermal_gap 0.5)
			(thermal_bridge_width 0.5)
			(island_removal_mode 0)
		)
		(polygon
			(pts
				(arc
					(start 172.30598 -250.035314)
					(mid 171.63796 -250.035314)
					(end 172.30598 -250.035314)
				)
			)
		)
	)
	(zone
		(layers "B.Cu" "In15.Cu")
		(hatch none 0.5)
		(connect_pads
			(clearance 0)
		)
		(min_thickness 0.25)
		(keepout
			(tracks not_allowed)
			(vias allowed)
			(pads allowed)
			(copperpour not_allowed)
			(footprints allowed)
		)
		(placement
			(enabled no)
			(sheetname "")
		)
		(fill yes
			(thermal_gap 0.5)
			(thermal_bridge_width 0.5)
			(island_removal_mode 0)
		)
		(polygon
			(pts
				(arc
					(start 420.246048 -265.335004)
					(mid 419.578028 -265.335004)
					(end 420.246048 -265.335004)
				)
			)
		)
	)
	(zone
		(layers "B.Cu" "In15.Cu")
		(hatch none 0.5)
		(connect_pads
			(clearance 0)
		)
		(min_thickness 0.25)
		(keepout
			(tracks not_allowed)
			(vias allowed)
			(pads allowed)
			(copperpour not_allowed)
			(footprints allowed)
		)
		(placement
			(enabled no)
			(sheetname "")
		)
		(fill yes
			(thermal_gap 0.5)
			(thermal_bridge_width 0.5)
			(island_removal_mode 0)
		)
		(polygon
			(pts
				(arc
					(start 176.406048 -296.785284)
					(mid 175.738028 -296.785284)
					(end 176.406048 -296.785284)
				)
			)
		)
	)
	(zone
		(layers "B.Cu" "In15.Cu")
		(hatch none 0.5)
		(connect_pads
			(clearance 0)
		)
		(min_thickness 0.25)
		(keepout
			(tracks not_allowed)
			(vias allowed)
			(pads allowed)
			(copperpour not_allowed)
			(footprints allowed)
		)
		(placement
			(enabled no)
			(sheetname "")
		)
		(fill yes
			(thermal_gap 0.5)
			(thermal_bridge_width 0.5)
			(island_removal_mode 0)
		)
		(polygon
			(pts
				(arc
					(start 412.59125 -379.88113)
					(mid 411.92323 -379.88113)
					(end 412.59125 -379.88113)
				)
			)
		)
	)
	(zone
		(layers "B.Cu" "In15.Cu")
		(hatch none 0.5)
		(connect_pads
			(clearance 0)
		)
		(min_thickness 0.25)
		(keepout
			(tracks not_allowed)
			(vias allowed)
			(pads allowed)
			(copperpour not_allowed)
			(footprints allowed)
		)
		(placement
			(enabled no)
			(sheetname "")
		)
		(fill yes
			(thermal_gap 0.5)
			(thermal_bridge_width 0.5)
			(island_removal_mode 0)
		)
		(polygon
			(pts
				(arc
					(start 420.246048 -305.28514)
					(mid 419.578028 -305.28514)
					(end 420.246048 -305.28514)
				)
			)
		)
	)
	(zone
		(layers "B.Cu" "In15.Cu")
		(hatch none 0.5)
		(connect_pads
			(clearance 0)
		)
		(min_thickness 0.25)
		(keepout
			(tracks not_allowed)
			(vias allowed)
			(pads allowed)
			(copperpour not_allowed)
			(footprints allowed)
		)
		(placement
			(enabled no)
			(sheetname "")
		)
		(fill yes
			(thermal_gap 0.5)
			(thermal_bridge_width 0.5)
			(island_removal_mode 0)
		)
		(polygon
			(pts
				(arc
					(start 124.850652 -393.292838)
					(mid 124.182632 -393.292838)
					(end 124.850652 -393.292838)
				)
			)
		)
	)
	(zone
		(layers "B.Cu" "In15.Cu")
		(hatch none 0.5)
		(connect_pads
			(clearance 0)
		)
		(min_thickness 0.25)
		(keepout
			(tracks not_allowed)
			(vias allowed)
			(pads allowed)
			(copperpour not_allowed)
			(footprints allowed)
		)
		(placement
			(enabled no)
			(sheetname "")
		)
		(fill yes
			(thermal_gap 0.5)
			(thermal_bridge_width 0.5)
			(island_removal_mode 0)
		)
		(polygon
			(pts
				(arc
					(start 48.118014 -313.78525)
					(mid 47.449994 -313.78525)
					(end 48.118014 -313.78525)
				)
			)
		)
	)
	(zone
		(layers "B.Cu" "In15.Cu")
		(hatch none 0.5)
		(connect_pads
			(clearance 0)
		)
		(min_thickness 0.25)
		(keepout
			(tracks not_allowed)
			(vias allowed)
			(pads allowed)
			(copperpour not_allowed)
			(footprints allowed)
		)
		(placement
			(enabled no)
			(sheetname "")
		)
		(fill yes
			(thermal_gap 0.5)
			(thermal_bridge_width 0.5)
			(island_removal_mode 0)
		)
		(polygon
			(pts
				(arc
					(start 89.536016 -255.824482)
					(mid 88.906096 -255.824482)
					(end 89.536016 -255.824482)
				)
			)
		)
	)
	(zone
		(layers "B.Cu" "In15.Cu")
		(hatch none 0.5)
		(connect_pads
			(clearance 0)
		)
		(min_thickness 0.25)
		(keepout
			(tracks not_allowed)
			(vias allowed)
			(pads allowed)
			(copperpour not_allowed)
			(footprints allowed)
		)
		(placement
			(enabled no)
			(sheetname "")
		)
		(fill yes
			(thermal_gap 0.5)
			(thermal_bridge_width 0.5)
			(island_removal_mode 0)
		)
		(polygon
			(pts
				(arc
					(start 52.218082 -295.085262)
					(mid 51.550062 -295.085262)
					(end 52.218082 -295.085262)
				)
			)
		)
	)
	(zone
		(layers "B.Cu" "In15.Cu")
		(hatch none 0.5)
		(connect_pads
			(clearance 0)
		)
		(min_thickness 0.25)
		(keepout
			(tracks not_allowed)
			(vias allowed)
			(pads allowed)
			(copperpour not_allowed)
			(footprints allowed)
		)
		(placement
			(enabled no)
			(sheetname "")
		)
		(fill yes
			(thermal_gap 0.5)
			(thermal_bridge_width 0.5)
			(island_removal_mode 0)
		)
		(polygon
			(pts
				(arc
					(start 337.306158 -290.285932)
					(mid 336.676238 -290.285932)
					(end 337.306158 -290.285932)
				)
			)
		)
	)
	(zone
		(layers "B.Cu" "In15.Cu")
		(hatch none 0.5)
		(connect_pads
			(clearance 0)
		)
		(min_thickness 0.25)
		(keepout
			(tracks not_allowed)
			(vias allowed)
			(pads allowed)
			(copperpour not_allowed)
			(footprints allowed)
		)
		(placement
			(enabled no)
			(sheetname "")
		)
		(fill yes
			(thermal_gap 0.5)
			(thermal_bridge_width 0.5)
			(island_removal_mode 0)
		)
		(polygon
			(pts
				(arc
					(start 176.406048 -303.585372)
					(mid 175.738028 -303.585372)
					(end 176.406048 -303.585372)
				)
			)
		)
	)
	(zone
		(layers "B.Cu" "In15.Cu")
		(hatch none 0.5)
		(connect_pads
			(clearance 0)
		)
		(min_thickness 0.25)
		(keepout
			(tracks not_allowed)
			(vias allowed)
			(pads allowed)
			(copperpour not_allowed)
			(footprints allowed)
		)
		(placement
			(enabled no)
			(sheetname "")
		)
		(fill yes
			(thermal_gap 0.5)
			(thermal_bridge_width 0.5)
			(island_removal_mode 0)
		)
		(polygon
			(pts
				(arc
					(start 48.118014 -310.385206)
					(mid 47.449994 -310.385206)
					(end 48.118014 -310.385206)
				)
			)
		)
	)
	(zone
		(layers "B.Cu" "In15.Cu")
		(hatch none 0.5)
		(connect_pads
			(clearance 0)
		)
		(min_thickness 0.25)
		(keepout
			(tracks not_allowed)
			(vias allowed)
			(pads allowed)
			(copperpour not_allowed)
			(footprints allowed)
		)
		(placement
			(enabled no)
			(sheetname "")
		)
		(fill yes
			(thermal_gap 0.5)
			(thermal_bridge_width 0.5)
			(island_removal_mode 0)
		)
		(polygon
			(pts
				(arc
					(start 300.15815 -292.535102)
					(mid 299.49013 -292.535102)
					(end 300.15815 -292.535102)
				)
			)
		)
	)
	(zone
		(layers "B.Cu" "In15.Cu")
		(hatch none 0.5)
		(connect_pads
			(clearance 0)
		)
		(min_thickness 0.25)
		(keepout
			(tracks not_allowed)
			(vias allowed)
			(pads allowed)
			(copperpour not_allowed)
			(footprints allowed)
		)
		(placement
			(enabled no)
			(sheetname "")
		)
		(fill yes
			(thermal_gap 0.5)
			(thermal_bridge_width 0.5)
			(island_removal_mode 0)
		)
		(polygon
			(pts
				(arc
					(start 383.99974 -248.534174)
					(mid 383.36982 -248.534174)
					(end 383.99974 -248.534174)
				)
			)
		)
	)
	(zone
		(layers "B.Cu" "In15.Cu")
		(hatch none 0.5)
		(connect_pads
			(clearance 0)
		)
		(min_thickness 0.25)
		(keepout
			(tracks not_allowed)
			(vias allowed)
			(pads allowed)
			(copperpour not_allowed)
			(footprints allowed)
		)
		(placement
			(enabled no)
			(sheetname "")
		)
		(fill yes
			(thermal_gap 0.5)
			(thermal_bridge_width 0.5)
			(island_removal_mode 0)
		)
		(polygon
			(pts
				(arc
					(start 383.99974 -240.434114)
					(mid 383.36982 -240.434114)
					(end 383.99974 -240.434114)
				)
			)
		)
	)
	(zone
		(layers "B.Cu" "In15.Cu")
		(hatch none 0.5)
		(connect_pads
			(clearance 0)
		)
		(min_thickness 0.25)
		(keepout
			(tracks not_allowed)
			(vias allowed)
			(pads allowed)
			(copperpour not_allowed)
			(footprints allowed)
		)
		(placement
			(enabled no)
			(sheetname "")
		)
		(fill yes
			(thermal_gap 0.5)
			(thermal_bridge_width 0.5)
			(island_removal_mode 0)
		)
		(polygon
			(pts
				(arc
					(start 413.137096 -435.489858)
					(mid 412.362904 -435.489858)
					(end 413.137096 -435.489858)
				)
			)
		)
	)
	(zone
		(layers "B.Cu" "In15.Cu")
		(hatch none 0.5)
		(connect_pads
			(clearance 0)
		)
		(min_thickness 0.25)
		(keepout
			(tracks not_allowed)
			(vias allowed)
			(pads allowed)
			(copperpour not_allowed)
			(footprints allowed)
		)
		(placement
			(enabled no)
			(sheetname "")
		)
		(fill yes
			(thermal_gap 0.5)
			(thermal_bridge_width 0.5)
			(island_removal_mode 0)
		)
		(polygon
			(pts
				(arc
					(start 52.218082 -221.985332)
					(mid 51.550062 -221.985332)
					(end 52.218082 -221.985332)
				)
			)
		)
	)
	(zone
		(layers "B.Cu" "In15.Cu")
		(hatch none 0.5)
		(connect_pads
			(clearance 0)
		)
		(min_thickness 0.25)
		(keepout
			(tracks not_allowed)
			(vias allowed)
			(pads allowed)
			(copperpour not_allowed)
			(footprints allowed)
		)
		(placement
			(enabled no)
			(sheetname "")
		)
		(fill yes
			(thermal_gap 0.5)
			(thermal_bridge_width 0.5)
			(island_removal_mode 0)
		)
		(polygon
			(pts
				(arc
					(start 78.037182 -434.289962)
					(mid 77.26299 -434.289962)
					(end 78.037182 -434.289962)
				)
			)
		)
	)
	(zone
		(layers "B.Cu" "In15.Cu")
		(hatch none 0.5)
		(connect_pads
			(clearance 0)
		)
		(min_thickness 0.25)
		(keepout
			(tracks not_allowed)
			(vias allowed)
			(pads allowed)
			(copperpour not_allowed)
			(footprints allowed)
		)
		(placement
			(enabled no)
			(sheetname "")
		)
		(fill yes
			(thermal_gap 0.5)
			(thermal_bridge_width 0.5)
			(island_removal_mode 0)
		)
		(polygon
			(pts
				(arc
					(start 176.406048 -204.985366)
					(mid 175.738028 -204.985366)
					(end 176.406048 -204.985366)
				)
			)
		)
	)
	(zone
		(layers "B.Cu" "In15.Cu")
		(hatch none 0.5)
		(connect_pads
			(clearance 0)
		)
		(min_thickness 0.25)
		(keepout
			(tracks not_allowed)
			(vias allowed)
			(pads allowed)
			(copperpour not_allowed)
			(footprints allowed)
		)
		(placement
			(enabled no)
			(sheetname "")
		)
		(fill yes
			(thermal_gap 0.5)
			(thermal_bridge_width 0.5)
			(island_removal_mode 0)
		)
		(polygon
			(pts
				(arc
					(start 347.17609 -273.27606)
					(mid 346.54617 -273.27606)
					(end 347.17609 -273.27606)
				)
			)
		)
	)
	(zone
		(layers "B.Cu" "In15.Cu")
		(hatch none 0.5)
		(connect_pads
			(clearance 0)
		)
		(min_thickness 0.25)
		(keepout
			(tracks not_allowed)
			(vias allowed)
			(pads allowed)
			(copperpour not_allowed)
			(footprints allowed)
		)
		(placement
			(enabled no)
			(sheetname "")
		)
		(fill yes
			(thermal_gap 0.5)
			(thermal_bridge_width 0.5)
			(island_removal_mode 0)
		)
		(polygon
			(pts
				(arc
					(start 115.679728 -269.226284)
					(mid 115.049808 -269.226284)
					(end 115.679728 -269.226284)
				)
			)
		)
	)
	(zone
		(layers "B.Cu" "In15.Cu")
		(hatch none 0.5)
		(connect_pads
			(clearance 0)
		)
		(min_thickness 0.25)
		(keepout
			(tracks not_allowed)
			(vias allowed)
			(pads allowed)
			(copperpour not_allowed)
			(footprints allowed)
		)
		(placement
			(enabled no)
			(sheetname "")
		)
		(fill yes
			(thermal_gap 0.5)
			(thermal_bridge_width 0.5)
			(island_removal_mode 0)
		)
		(polygon
			(pts
				(arc
					(start 136.529826 -231.524302)
					(mid 135.899906 -231.524302)
					(end 136.529826 -231.524302)
				)
			)
		)
	)
	(zone
		(layers "B.Cu" "In15.Cu")
		(hatch none 0.5)
		(connect_pads
			(clearance 0)
		)
		(min_thickness 0.25)
		(keepout
			(tracks not_allowed)
			(vias allowed)
			(pads allowed)
			(copperpour not_allowed)
			(footprints allowed)
		)
		(placement
			(enabled no)
			(sheetname "")
		)
		(fill yes
			(thermal_gap 0.5)
			(thermal_bridge_width 0.5)
			(island_removal_mode 0)
		)
		(polygon
			(pts
				(arc
					(start 155.137104 -434.48986)
					(mid 154.362912 -434.48986)
					(end 155.137104 -434.48986)
				)
			)
		)
	)
	(zone
		(layers "B.Cu" "In15.Cu")
		(hatch none 0.5)
		(connect_pads
			(clearance 0)
		)
		(min_thickness 0.25)
		(keepout
			(tracks not_allowed)
			(vias allowed)
			(pads allowed)
			(copperpour not_allowed)
			(footprints allowed)
		)
		(placement
			(enabled no)
			(sheetname "")
		)
		(fill yes
			(thermal_gap 0.5)
			(thermal_bridge_width 0.5)
			(island_removal_mode 0)
		)
		(polygon
			(pts
				(arc
					(start 370.66982 -273.27606)
					(mid 370.0399 -273.27606)
					(end 370.66982 -273.27606)
				)
			)
		)
	)
	(zone
		(layers "B.Cu" "In15.Cu")
		(hatch none 0.5)
		(connect_pads
			(clearance 0)
		)
		(min_thickness 0.25)
		(keepout
			(tracks not_allowed)
			(vias allowed)
			(pads allowed)
			(copperpour not_allowed)
			(footprints allowed)
		)
		(placement
			(enabled no)
			(sheetname "")
		)
		(fill yes
			(thermal_gap 0.5)
			(thermal_bridge_width 0.5)
			(island_removal_mode 0)
		)
		(polygon
			(pts
				(arc
					(start 337.776058 -273.27606)
					(mid 337.146138 -273.27606)
					(end 337.776058 -273.27606)
				)
			)
		)
	)
	(zone
		(layers "B.Cu" "In15.Cu")
		(hatch none 0.5)
		(connect_pads
			(clearance 0)
		)
		(min_thickness 0.25)
		(keepout
			(tracks not_allowed)
			(vias allowed)
			(pads allowed)
			(copperpour not_allowed)
			(footprints allowed)
		)
		(placement
			(enabled no)
			(sheetname "")
		)
		(fill yes
			(thermal_gap 0.5)
			(thermal_bridge_width 0.5)
			(island_removal_mode 0)
		)
		(polygon
			(pts
				(arc
					(start 382.589786 -246.104156)
					(mid 381.959866 -246.104156)
					(end 382.589786 -246.104156)
				)
			)
		)
	)
	(zone
		(layers "B.Cu" "In15.Cu")
		(hatch none 0.5)
		(connect_pads
			(clearance 0)
		)
		(min_thickness 0.25)
		(keepout
			(tracks not_allowed)
			(vias allowed)
			(pads allowed)
			(copperpour not_allowed)
			(footprints allowed)
		)
		(placement
			(enabled no)
			(sheetname "")
		)
		(fill yes
			(thermal_gap 0.5)
			(thermal_bridge_width 0.5)
			(island_removal_mode 0)
		)
		(polygon
			(pts
				(arc
					(start 424.346116 -312.935112)
					(mid 423.678096 -312.935112)
					(end 424.346116 -312.935112)
				)
			)
		)
	)
	(zone
		(layers "B.Cu" "In15.Cu")
		(hatch none 0.5)
		(connect_pads
			(clearance 0)
		)
		(min_thickness 0.25)
		(keepout
			(tracks not_allowed)
			(vias allowed)
			(pads allowed)
			(copperpour not_allowed)
			(footprints allowed)
		)
		(placement
			(enabled no)
			(sheetname "")
		)
		(fill yes
			(thermal_gap 0.5)
			(thermal_bridge_width 0.5)
			(island_removal_mode 0)
		)
		(polygon
			(pts
				(arc
					(start 48.118014 -243.235226)
					(mid 47.449994 -243.235226)
					(end 48.118014 -243.235226)
				)
			)
		)
	)
	(zone
		(layers "B.Cu" "In15.Cu")
		(hatch none 0.5)
		(connect_pads
			(clearance 0)
		)
		(min_thickness 0.25)
		(keepout
			(tracks not_allowed)
			(vias allowed)
			(pads allowed)
			(copperpour not_allowed)
			(footprints allowed)
		)
		(placement
			(enabled no)
			(sheetname "")
		)
		(fill yes
			(thermal_gap 0.5)
			(thermal_bridge_width 0.5)
			(island_removal_mode 0)
		)
		(polygon
			(pts
				(arc
					(start 327.036684 -434.48986)
					(mid 326.262492 -434.48986)
					(end 327.036684 -434.48986)
				)
			)
		)
	)
	(zone
		(layers "B.Cu" "In15.Cu")
		(hatch none 0.5)
		(connect_pads
			(clearance 0)
		)
		(min_thickness 0.25)
		(keepout
			(tracks not_allowed)
			(vias allowed)
			(pads allowed)
			(copperpour not_allowed)
			(footprints allowed)
		)
		(placement
			(enabled no)
			(sheetname "")
		)
		(fill yes
			(thermal_gap 0.5)
			(thermal_bridge_width 0.5)
			(island_removal_mode 0)
		)
		(polygon
			(pts
				(arc
					(start 136.059672 -243.674392)
					(mid 135.429752 -243.674392)
					(end 136.059672 -243.674392)
				)
			)
		)
	)
	(zone
		(layers "B.Cu" "In15.Cu")
		(hatch none 0.5)
		(connect_pads
			(clearance 0)
		)
		(min_thickness 0.25)
		(keepout
			(tracks not_allowed)
			(vias allowed)
			(pads allowed)
			(copperpour not_allowed)
			(footprints allowed)
		)
		(placement
			(enabled no)
			(sheetname "")
		)
		(fill yes
			(thermal_gap 0.5)
			(thermal_bridge_width 0.5)
			(island_removal_mode 0)
		)
		(polygon
			(pts
				(arc
					(start 176.406048 -228.78542)
					(mid 175.738028 -228.78542)
					(end 176.406048 -228.78542)
				)
			)
		)
	)
	(zone
		(layers "B.Cu" "In15.Cu")
		(hatch none 0.5)
		(connect_pads
			(clearance 0)
		)
		(min_thickness 0.25)
		(keepout
			(tracks not_allowed)
			(vias allowed)
			(pads allowed)
			(copperpour not_allowed)
			(footprints allowed)
		)
		(placement
			(enabled no)
			(sheetname "")
		)
		(fill yes
			(thermal_gap 0.5)
			(thermal_bridge_width 0.5)
			(island_removal_mode 0)
		)
		(polygon
			(pts
				(arc
					(start 172.30598 -244.935248)
					(mid 171.63796 -244.935248)
					(end 172.30598 -244.935248)
				)
			)
		)
	)
	(zone
		(layers "B.Cu" "In15.Cu")
		(hatch none 0.5)
		(connect_pads
			(clearance 0)
		)
		(min_thickness 0.25)
		(keepout
			(tracks not_allowed)
			(vias allowed)
			(pads allowed)
			(copperpour not_allowed)
			(footprints allowed)
		)
		(placement
			(enabled no)
			(sheetname "")
		)
		(fill yes
			(thermal_gap 0.5)
			(thermal_bridge_width 0.5)
			(island_removal_mode 0)
		)
		(polygon
			(pts
				(arc
					(start 89.066116 -245.294404)
					(mid 88.436196 -245.294404)
					(end 89.066116 -245.294404)
				)
			)
		)
	)
	(zone
		(layers "B.Cu" "In15.Cu")
		(hatch none 0.5)
		(connect_pads
			(clearance 0)
		)
		(min_thickness 0.25)
		(keepout
			(tracks not_allowed)
			(vias allowed)
			(pads allowed)
			(copperpour not_allowed)
			(footprints allowed)
		)
		(placement
			(enabled no)
			(sheetname "")
		)
		(fill yes
			(thermal_gap 0.5)
			(thermal_bridge_width 0.5)
			(island_removal_mode 0)
		)
		(polygon
			(pts
				(arc
					(start 296.058082 -241.53495)
					(mid 295.390062 -241.53495)
					(end 296.058082 -241.53495)
				)
			)
		)
	)
	(zone
		(layers "B.Cu" "In15.Cu")
		(hatch none 0.5)
		(connect_pads
			(clearance 0)
		)
		(min_thickness 0.25)
		(keepout
			(tracks not_allowed)
			(vias allowed)
			(pads allowed)
			(copperpour not_allowed)
			(footprints allowed)
		)
		(placement
			(enabled no)
			(sheetname "")
		)
		(fill yes
			(thermal_gap 0.5)
			(thermal_bridge_width 0.5)
			(island_removal_mode 0)
		)
		(polygon
			(pts
				(arc
					(start 152.349454 -369.03533)
					(mid 151.681434 -369.03533)
					(end 152.349454 -369.03533)
				)
			)
		)
	)
	(zone
		(layers "B.Cu" "In15.Cu")
		(hatch none 0.5)
		(connect_pads
			(clearance 0)
		)
		(min_thickness 0.25)
		(keepout
			(tracks not_allowed)
			(vias allowed)
			(pads allowed)
			(copperpour not_allowed)
			(footprints allowed)
		)
		(placement
			(enabled no)
			(sheetname "")
		)
		(fill yes
			(thermal_gap 0.5)
			(thermal_bridge_width 0.5)
			(island_removal_mode 0)
		)
		(polygon
			(pts
				(arc
					(start 52.218082 -236.435392)
					(mid 51.550062 -236.435392)
					(end 52.218082 -236.435392)
				)
			)
		)
	)
	(zone
		(layers "B.Cu" "In15.Cu")
		(hatch none 0.5)
		(connect_pads
			(clearance 0)
		)
		(min_thickness 0.25)
		(keepout
			(tracks not_allowed)
			(vias allowed)
			(pads allowed)
			(copperpour not_allowed)
			(footprints allowed)
		)
		(placement
			(enabled no)
			(sheetname "")
		)
		(fill yes
			(thermal_gap 0.5)
			(thermal_bridge_width 0.5)
			(island_removal_mode 0)
		)
		(polygon
			(pts
				(arc
					(start 349.056198 -273.27606)
					(mid 348.426278 -273.27606)
					(end 349.056198 -273.27606)
				)
			)
		)
	)
	(zone
		(layers "B.Cu" "In15.Cu")
		(hatch none 0.5)
		(connect_pads
			(clearance 0)
		)
		(min_thickness 0.25)
		(keepout
			(tracks not_allowed)
			(vias allowed)
			(pads allowed)
			(copperpour not_allowed)
			(footprints allowed)
		)
		(placement
			(enabled no)
			(sheetname "")
		)
		(fill yes
			(thermal_gap 0.5)
			(thermal_bridge_width 0.5)
			(island_removal_mode 0)
		)
		(polygon
			(pts
				(arc
					(start 337.776058 -281.37612)
					(mid 337.146138 -281.37612)
					(end 337.776058 -281.37612)
				)
			)
		)
	)
	(zone
		(layers "B.Cu" "In15.Cu")
		(hatch none 0.5)
		(connect_pads
			(clearance 0)
		)
		(min_thickness 0.25)
		(keepout
			(tracks not_allowed)
			(vias allowed)
			(pads allowed)
			(copperpour not_allowed)
			(footprints allowed)
		)
		(placement
			(enabled no)
			(sheetname "")
		)
		(fill yes
			(thermal_gap 0.5)
			(thermal_bridge_width 0.5)
			(island_removal_mode 0)
		)
		(polygon
			(pts
				(arc
					(start 176.406048 -214.33536)
					(mid 175.738028 -214.33536)
					(end 176.406048 -214.33536)
				)
			)
		)
	)
	(zone
		(layers "B.Cu" "In15.Cu")
		(hatch none 0.5)
		(connect_pads
			(clearance 0)
		)
		(min_thickness 0.25)
		(keepout
			(tracks not_allowed)
			(vias allowed)
			(pads allowed)
			(copperpour not_allowed)
			(footprints allowed)
		)
		(placement
			(enabled no)
			(sheetname "")
		)
		(fill yes
			(thermal_gap 0.5)
			(thermal_bridge_width 0.5)
			(island_removal_mode 0)
		)
		(polygon
			(pts
				(arc
					(start 383.35966 -280.566114)
					(mid 382.72974 -280.566114)
					(end 383.35966 -280.566114)
				)
			)
		)
	)
	(zone
		(layers "B.Cu" "In15.Cu")
		(hatch none 0.5)
		(connect_pads
			(clearance 0)
		)
		(min_thickness 0.25)
		(keepout
			(tracks not_allowed)
			(vias allowed)
			(pads allowed)
			(copperpour not_allowed)
			(footprints allowed)
		)
		(placement
			(enabled no)
			(sheetname "")
		)
		(fill yes
			(thermal_gap 0.5)
			(thermal_bridge_width 0.5)
			(island_removal_mode 0)
		)
		(polygon
			(pts
				(arc
					(start 89.83599 -292.716204)
					(mid 89.20607 -292.716204)
					(end 89.83599 -292.716204)
				)
			)
		)
	)
	(zone
		(layers "B.Cu" "In15.Cu")
		(hatch none 0.5)
		(connect_pads
			(clearance 0)
		)
		(min_thickness 0.25)
		(keepout
			(tracks not_allowed)
			(vias allowed)
			(pads allowed)
			(copperpour not_allowed)
			(footprints allowed)
		)
		(placement
			(enabled no)
			(sheetname "")
		)
		(fill yes
			(thermal_gap 0.5)
			(thermal_bridge_width 0.5)
			(island_removal_mode 0)
		)
		(polygon
			(pts
				(arc
					(start 310.50611 -394.385292)
					(mid 309.87619 -394.385292)
					(end 310.50611 -394.385292)
				)
			)
		)
	)
	(zone
		(layers "B.Cu" "In15.Cu")
		(hatch none 0.5)
		(connect_pads
			(clearance 0)
		)
		(min_thickness 0.25)
		(keepout
			(tracks not_allowed)
			(vias allowed)
			(pads allowed)
			(copperpour not_allowed)
			(footprints allowed)
		)
		(placement
			(enabled no)
			(sheetname "")
		)
		(fill yes
			(thermal_gap 0.5)
			(thermal_bridge_width 0.5)
			(island_removal_mode 0)
		)
		(polygon
			(pts
				(arc
					(start 362.679742 -270.846042)
					(mid 362.049822 -270.846042)
					(end 362.679742 -270.846042)
				)
			)
		)
	)
	(zone
		(layers "B.Cu" "In15.Cu")
		(hatch none 0.5)
		(connect_pads
			(clearance 0)
		)
		(min_thickness 0.25)
		(keepout
			(tracks not_allowed)
			(vias allowed)
			(pads allowed)
			(copperpour not_allowed)
			(footprints allowed)
		)
		(placement
			(enabled no)
			(sheetname "")
		)
		(fill yes
			(thermal_gap 0.5)
			(thermal_bridge_width 0.5)
			(island_removal_mode 0)
		)
		(polygon
			(pts
				(arc
					(start 126.136908 -434.48986)
					(mid 125.362716 -434.48986)
					(end 126.136908 -434.48986)
				)
			)
		)
	)
	(zone
		(layers "B.Cu" "In15.Cu")
		(hatch none 0.5)
		(connect_pads
			(clearance 0)
		)
		(min_thickness 0.25)
		(keepout
			(tracks not_allowed)
			(vias allowed)
			(pads allowed)
			(copperpour not_allowed)
			(footprints allowed)
		)
		(placement
			(enabled no)
			(sheetname "")
		)
		(fill yes
			(thermal_gap 0.5)
			(thermal_bridge_width 0.5)
			(island_removal_mode 0)
		)
		(polygon
			(pts
				(arc
					(start 382.589786 -247.724168)
					(mid 381.959866 -247.724168)
					(end 382.589786 -247.724168)
				)
			)
		)
	)
	(zone
		(layers "B.Cu" "In15.Cu")
		(hatch none 0.5)
		(connect_pads
			(clearance 0)
		)
		(min_thickness 0.25)
		(keepout
			(tracks not_allowed)
			(vias allowed)
			(pads allowed)
			(copperpour not_allowed)
			(footprints allowed)
		)
		(placement
			(enabled no)
			(sheetname "")
		)
		(fill yes
			(thermal_gap 0.5)
			(thermal_bridge_width 0.5)
			(island_removal_mode 0)
		)
		(polygon
			(pts
				(arc
					(start 89.83599 -274.896326)
					(mid 89.20607 -274.896326)
					(end 89.83599 -274.896326)
				)
			)
		)
	)
	(zone
		(layers "B.Cu" "In15.Cu")
		(hatch none 0.5)
		(connect_pads
			(clearance 0)
		)
		(min_thickness 0.25)
		(keepout
			(tracks not_allowed)
			(vias allowed)
			(pads allowed)
			(copperpour not_allowed)
			(footprints allowed)
		)
		(placement
			(enabled no)
			(sheetname "")
		)
		(fill yes
			(thermal_gap 0.5)
			(thermal_bridge_width 0.5)
			(island_removal_mode 0)
		)
		(polygon
			(pts
				(arc
					(start 384.769868 -281.37612)
					(mid 384.139948 -281.37612)
					(end 384.769868 -281.37612)
				)
			)
		)
	)
	(zone
		(layers "B.Cu" "In15.Cu")
		(hatch none 0.5)
		(connect_pads
			(clearance 0)
		)
		(min_thickness 0.25)
		(keepout
			(tracks not_allowed)
			(vias allowed)
			(pads allowed)
			(copperpour not_allowed)
			(footprints allowed)
		)
		(placement
			(enabled no)
			(sheetname "")
		)
		(fill yes
			(thermal_gap 0.5)
			(thermal_bridge_width 0.5)
			(island_removal_mode 0)
		)
		(polygon
			(pts
				(arc
					(start 384.299714 -277.32609)
					(mid 383.669794 -277.32609)
					(end 384.299714 -277.32609)
				)
			)
		)
	)
	(zone
		(layers "B.Cu" "In15.Cu")
		(hatch none 0.5)
		(connect_pads
			(clearance 0)
		)
		(min_thickness 0.25)
		(keepout
			(tracks not_allowed)
			(vias allowed)
			(pads allowed)
			(copperpour not_allowed)
			(footprints allowed)
		)
		(placement
			(enabled no)
			(sheetname "")
		)
		(fill yes
			(thermal_gap 0.5)
			(thermal_bridge_width 0.5)
			(island_removal_mode 0)
		)
		(polygon
			(pts
				(arc
					(start 337.006184 -227.474272)
					(mid 336.376264 -227.474272)
					(end 337.006184 -227.474272)
				)
			)
		)
	)
	(zone
		(layers "B.Cu" "In15.Cu")
		(hatch none 0.5)
		(connect_pads
			(clearance 0)
		)
		(min_thickness 0.25)
		(keepout
			(tracks not_allowed)
			(vias allowed)
			(pads allowed)
			(copperpour not_allowed)
			(footprints allowed)
		)
		(placement
			(enabled no)
			(sheetname "")
		)
		(fill yes
			(thermal_gap 0.5)
			(thermal_bridge_width 0.5)
			(island_removal_mode 0)
		)
		(polygon
			(pts
				(arc
					(start 176.406048 -249.18543)
					(mid 175.738028 -249.18543)
					(end 176.406048 -249.18543)
				)
			)
		)
	)
	(zone
		(layers "B.Cu" "In15.Cu")
		(hatch none 0.5)
		(connect_pads
			(clearance 0)
		)
		(min_thickness 0.25)
		(keepout
			(tracks not_allowed)
			(vias allowed)
			(pads allowed)
			(copperpour not_allowed)
			(footprints allowed)
		)
		(placement
			(enabled no)
			(sheetname "")
		)
		(fill yes
			(thermal_gap 0.5)
			(thermal_bridge_width 0.5)
			(island_removal_mode 0)
		)
		(polygon
			(pts
				(arc
					(start 405.78405 -379.88113)
					(mid 405.11603 -379.88113)
					(end 405.78405 -379.88113)
				)
			)
		)
	)
	(zone
		(layers "B.Cu" "In15.Cu")
		(hatch none 0.5)
		(connect_pads
			(clearance 0)
		)
		(min_thickness 0.25)
		(keepout
			(tracks not_allowed)
			(vias allowed)
			(pads allowed)
			(copperpour not_allowed)
			(footprints allowed)
		)
		(placement
			(enabled no)
			(sheetname "")
		)
		(fill yes
			(thermal_gap 0.5)
			(thermal_bridge_width 0.5)
			(island_removal_mode 0)
		)
		(polygon
			(pts
				(arc
					(start 384.469894 -242.864132)
					(mid 383.839974 -242.864132)
					(end 384.469894 -242.864132)
				)
			)
		)
	)
	(zone
		(layers "B.Cu" "In15.Cu")
		(hatch none 0.5)
		(connect_pads
			(clearance 0)
		)
		(min_thickness 0.25)
		(keepout
			(tracks not_allowed)
			(vias allowed)
			(pads allowed)
			(copperpour not_allowed)
			(footprints allowed)
		)
		(placement
			(enabled no)
			(sheetname "")
		)
		(fill yes
			(thermal_gap 0.5)
			(thermal_bridge_width 0.5)
			(island_removal_mode 0)
		)
		(polygon
			(pts
				(arc
					(start 300.15815 -285.735014)
					(mid 299.49013 -285.735014)
					(end 300.15815 -285.735014)
				)
			)
		)
	)
	(zone
		(layers "B.Cu" "In15.Cu")
		(hatch none 0.5)
		(connect_pads
			(clearance 0)
		)
		(min_thickness 0.25)
		(keepout
			(tracks not_allowed)
			(vias allowed)
			(pads allowed)
			(copperpour not_allowed)
			(footprints allowed)
		)
		(placement
			(enabled no)
			(sheetname "")
		)
		(fill yes
			(thermal_gap 0.5)
			(thermal_bridge_width 0.5)
			(island_removal_mode 0)
		)
		(polygon
			(pts
				(arc
					(start 372.45036 -400.811238)
					(mid 371.78234 -400.811238)
					(end 372.45036 -400.811238)
				)
			)
		)
	)
	(zone
		(layers "B.Cu" "In15.Cu")
		(hatch none 0.5)
		(connect_pads
			(clearance 0)
		)
		(min_thickness 0.25)
		(keepout
			(tracks not_allowed)
			(vias allowed)
			(pads allowed)
			(copperpour not_allowed)
			(footprints allowed)
		)
		(placement
			(enabled no)
			(sheetname "")
		)
		(fill yes
			(thermal_gap 0.5)
			(thermal_bridge_width 0.5)
			(island_removal_mode 0)
		)
		(polygon
			(pts
				(arc
					(start 418.56025 -382.34493)
					(mid 417.89223 -382.34493)
					(end 418.56025 -382.34493)
				)
			)
		)
	)
	(zone
		(layers "B.Cu" "In15.Cu")
		(hatch none 0.5)
		(connect_pads
			(clearance 0)
		)
		(min_thickness 0.25)
		(keepout
			(tracks not_allowed)
			(vias allowed)
			(pads allowed)
			(copperpour not_allowed)
			(footprints allowed)
		)
		(placement
			(enabled no)
			(sheetname "")
		)
		(fill yes
			(thermal_gap 0.5)
			(thermal_bridge_width 0.5)
			(island_removal_mode 0)
		)
		(polygon
			(pts
				(arc
					(start 89.36609 -265.98626)
					(mid 88.73617 -265.98626)
					(end 89.36609 -265.98626)
				)
			)
		)
	)
	(zone
		(layers "B.Cu" "In15.Cu")
		(hatch none 0.5)
		(connect_pads
			(clearance 0)
		)
		(min_thickness 0.25)
		(keepout
			(tracks not_allowed)
			(vias allowed)
			(pads allowed)
			(copperpour not_allowed)
			(footprints allowed)
		)
		(placement
			(enabled no)
			(sheetname "")
		)
		(fill yes
			(thermal_gap 0.5)
			(thermal_bridge_width 0.5)
			(island_removal_mode 0)
		)
		(polygon
			(pts
				(arc
					(start 335.89595 -282.996132)
					(mid 335.26603 -282.996132)
					(end 335.89595 -282.996132)
				)
			)
		)
	)
	(zone
		(layers "B.Cu" "In15.Cu")
		(hatch none 0.5)
		(connect_pads
			(clearance 0)
		)
		(min_thickness 0.25)
		(keepout
			(tracks not_allowed)
			(vias allowed)
			(pads allowed)
			(copperpour not_allowed)
			(footprints allowed)
		)
		(placement
			(enabled no)
			(sheetname "")
		)
		(fill yes
			(thermal_gap 0.5)
			(thermal_bridge_width 0.5)
			(island_removal_mode 0)
		)
		(polygon
			(pts
				(arc
					(start 172.30598 -251.735336)
					(mid 171.63796 -251.735336)
					(end 172.30598 -251.735336)
				)
			)
		)
	)
	(zone
		(layers "B.Cu" "In15.Cu")
		(hatch none 0.5)
		(connect_pads
			(clearance 0)
		)
		(min_thickness 0.25)
		(keepout
			(tracks not_allowed)
			(vias allowed)
			(pads allowed)
			(copperpour not_allowed)
			(footprints allowed)
		)
		(placement
			(enabled no)
			(sheetname "")
		)
		(fill yes
			(thermal_gap 0.5)
			(thermal_bridge_width 0.5)
			(island_removal_mode 0)
		)
		(polygon
			(pts
				(arc
					(start 379.650498 -400.811238)
					(mid 378.982478 -400.811238)
					(end 379.650498 -400.811238)
				)
			)
		)
	)
	(zone
		(layers "B.Cu" "In15.Cu")
		(hatch none 0.5)
		(connect_pads
			(clearance 0)
		)
		(min_thickness 0.25)
		(keepout
			(tracks not_allowed)
			(vias allowed)
			(pads allowed)
			(copperpour not_allowed)
			(footprints allowed)
		)
		(placement
			(enabled no)
			(sheetname "")
		)
		(fill yes
			(thermal_gap 0.5)
			(thermal_bridge_width 0.5)
			(island_removal_mode 0)
		)
		(polygon
			(pts
				(arc
					(start 117.089682 -271.656302)
					(mid 116.459762 -271.656302)
					(end 117.089682 -271.656302)
				)
			)
		)
	)
	(zone
		(layers "B.Cu" "In15.Cu")
		(hatch none 0.5)
		(connect_pads
			(clearance 0)
		)
		(min_thickness 0.25)
		(keepout
			(tracks not_allowed)
			(vias allowed)
			(pads allowed)
			(copperpour not_allowed)
			(footprints allowed)
		)
		(placement
			(enabled no)
			(sheetname "")
		)
		(fill yes
			(thermal_gap 0.5)
			(thermal_bridge_width 0.5)
			(island_removal_mode 0)
		)
		(polygon
			(pts
				(arc
					(start 88.126062 -242.05438)
					(mid 87.496142 -242.05438)
					(end 88.126062 -242.05438)
				)
			)
		)
	)
	(zone
		(layers "B.Cu" "In15.Cu")
		(hatch none 0.5)
		(connect_pads
			(clearance 0)
		)
		(min_thickness 0.25)
		(keepout
			(tracks not_allowed)
			(vias allowed)
			(pads allowed)
			(copperpour not_allowed)
			(footprints allowed)
		)
		(placement
			(enabled no)
			(sheetname "")
		)
		(fill yes
			(thermal_gap 0.5)
			(thermal_bridge_width 0.5)
			(island_removal_mode 0)
		)
		(polygon
			(pts
				(arc
					(start 115.679728 -274.08632)
					(mid 115.049808 -274.08632)
					(end 115.679728 -274.08632)
				)
			)
		)
	)
	(zone
		(layers "B.Cu" "In15.Cu")
		(hatch none 0.5)
		(connect_pads
			(clearance 0)
		)
		(min_thickness 0.25)
		(keepout
			(tracks not_allowed)
			(vias allowed)
			(pads allowed)
			(copperpour not_allowed)
			(footprints allowed)
		)
		(placement
			(enabled no)
			(sheetname "")
		)
		(fill yes
			(thermal_gap 0.5)
			(thermal_bridge_width 0.5)
			(island_removal_mode 0)
		)
		(polygon
			(pts
				(arc
					(start 52.218082 -245.785386)
					(mid 51.550062 -245.785386)
					(end 52.218082 -245.785386)
				)
			)
		)
	)
	(zone
		(layers "B.Cu" "In15.Cu")
		(hatch none 0.5)
		(connect_pads
			(clearance 0)
		)
		(min_thickness 0.25)
		(keepout
			(tracks not_allowed)
			(vias allowed)
			(pads allowed)
			(copperpour not_allowed)
			(footprints allowed)
		)
		(placement
			(enabled no)
			(sheetname "")
		)
		(fill yes
			(thermal_gap 0.5)
			(thermal_bridge_width 0.5)
			(island_removal_mode 0)
		)
		(polygon
			(pts
				(arc
					(start 300.15815 -252.584966)
					(mid 299.49013 -252.584966)
					(end 300.15815 -252.584966)
				)
			)
		)
	)
	(zone
		(layers "B.Cu" "In15.Cu")
		(hatch none 0.5)
		(connect_pads
			(clearance 0)
		)
		(min_thickness 0.25)
		(keepout
			(tracks not_allowed)
			(vias allowed)
			(pads allowed)
			(copperpour not_allowed)
			(footprints allowed)
		)
		(placement
			(enabled no)
			(sheetname "")
		)
		(fill yes
			(thermal_gap 0.5)
			(thermal_bridge_width 0.5)
			(island_removal_mode 0)
		)
		(polygon
			(pts
				(arc
					(start 365.969804 -271.656048)
					(mid 365.339884 -271.656048)
					(end 365.969804 -271.656048)
				)
			)
		)
	)
	(zone
		(layers "B.Cu" "In15.Cu")
		(hatch none 0.5)
		(connect_pads
			(clearance 0)
		)
		(min_thickness 0.25)
		(keepout
			(tracks not_allowed)
			(vias allowed)
			(pads allowed)
			(copperpour not_allowed)
			(footprints allowed)
		)
		(placement
			(enabled no)
			(sheetname "")
		)
		(fill yes
			(thermal_gap 0.5)
			(thermal_bridge_width 0.5)
			(island_removal_mode 0)
		)
		(polygon
			(pts
				(arc
					(start 52.218082 -292.535356)
					(mid 51.550062 -292.535356)
					(end 52.218082 -292.535356)
				)
			)
		)
	)
	(zone
		(layers "B.Cu" "In15.Cu")
		(hatch none 0.5)
		(connect_pads
			(clearance 0)
		)
		(min_thickness 0.25)
		(keepout
			(tracks not_allowed)
			(vias allowed)
			(pads allowed)
			(copperpour not_allowed)
			(footprints allowed)
		)
		(placement
			(enabled no)
			(sheetname "")
		)
		(fill yes
			(thermal_gap 0.5)
			(thermal_bridge_width 0.5)
			(island_removal_mode 0)
		)
		(polygon
			(pts
				(arc
					(start 87.955882 -284.616398)
					(mid 87.325962 -284.616398)
					(end 87.955882 -284.616398)
				)
			)
		)
	)
	(zone
		(layers "B.Cu" "In15.Cu")
		(hatch none 0.5)
		(connect_pads
			(clearance 0)
		)
		(min_thickness 0.25)
		(keepout
			(tracks not_allowed)
			(vias allowed)
			(pads allowed)
			(copperpour not_allowed)
			(footprints allowed)
		)
		(placement
			(enabled no)
			(sheetname "")
		)
		(fill yes
			(thermal_gap 0.5)
			(thermal_bridge_width 0.5)
			(island_removal_mode 0)
		)
		(polygon
			(pts
				(arc
					(start 88.126062 -253.394464)
					(mid 87.496142 -253.394464)
					(end 88.126062 -253.394464)
				)
			)
		)
	)
	(zone
		(layers "B.Cu" "In15.Cu")
		(hatch none 0.5)
		(connect_pads
			(clearance 0)
		)
		(min_thickness 0.25)
		(keepout
			(tracks not_allowed)
			(vias allowed)
			(pads allowed)
			(copperpour not_allowed)
			(footprints allowed)
		)
		(placement
			(enabled no)
			(sheetname "")
		)
		(fill yes
			(thermal_gap 0.5)
			(thermal_bridge_width 0.5)
			(island_removal_mode 0)
		)
		(polygon
			(pts
				(arc
					(start 52.218082 -300.185328)
					(mid 51.550062 -300.185328)
					(end 52.218082 -300.185328)
				)
			)
		)
	)
	(zone
		(layers "B.Cu" "In15.Cu")
		(hatch none 0.5)
		(connect_pads
			(clearance 0)
		)
		(min_thickness 0.25)
		(keepout
			(tracks not_allowed)
			(vias allowed)
			(pads allowed)
			(copperpour not_allowed)
			(footprints allowed)
		)
		(placement
			(enabled no)
			(sheetname "")
		)
		(fill yes
			(thermal_gap 0.5)
			(thermal_bridge_width 0.5)
			(island_removal_mode 0)
		)
		(polygon
			(pts
				(arc
					(start 136.8298 -286.23641)
					(mid 136.19988 -286.23641)
					(end 136.8298 -286.23641)
				)
			)
		)
	)
	(zone
		(layers "B.Cu" "In15.Cu")
		(hatch none 0.5)
		(connect_pads
			(clearance 0)
		)
		(min_thickness 0.25)
		(keepout
			(tracks not_allowed)
			(vias allowed)
			(pads allowed)
			(copperpour not_allowed)
			(footprints allowed)
		)
		(placement
			(enabled no)
			(sheetname "")
		)
		(fill yes
			(thermal_gap 0.5)
			(thermal_bridge_width 0.5)
			(island_removal_mode 0)
		)
		(polygon
			(pts
				(arc
					(start 172.30598 -306.985416)
					(mid 171.63796 -306.985416)
					(end 172.30598 -306.985416)
				)
			)
		)
	)
	(zone
		(layers "B.Cu" "In15.Cu")
		(hatch none 0.5)
		(connect_pads
			(clearance 0)
		)
		(min_thickness 0.25)
		(keepout
			(tracks not_allowed)
			(vias allowed)
			(pads allowed)
			(copperpour not_allowed)
			(footprints allowed)
		)
		(placement
			(enabled no)
			(sheetname "")
		)
		(fill yes
			(thermal_gap 0.5)
			(thermal_bridge_width 0.5)
			(island_removal_mode 0)
		)
		(polygon
			(pts
				(arc
					(start 115.379754 -242.05438)
					(mid 114.749834 -242.05438)
					(end 115.379754 -242.05438)
				)
			)
		)
	)
	(zone
		(layers "B.Cu" "In15.Cu")
		(hatch none 0.5)
		(connect_pads
			(clearance 0)
		)
		(min_thickness 0.25)
		(keepout
			(tracks not_allowed)
			(vias allowed)
			(pads allowed)
			(copperpour not_allowed)
			(footprints allowed)
		)
		(placement
			(enabled no)
			(sheetname "")
		)
		(fill yes
			(thermal_gap 0.5)
			(thermal_bridge_width 0.5)
			(island_removal_mode 0)
		)
		(polygon
			(pts
				(arc
					(start 383.059686 -242.054126)
					(mid 382.429766 -242.054126)
					(end 383.059686 -242.054126)
				)
			)
		)
	)
	(zone
		(layers "B.Cu" "In15.Cu")
		(hatch none 0.5)
		(connect_pads
			(clearance 0)
		)
		(min_thickness 0.25)
		(keepout
			(tracks not_allowed)
			(vias allowed)
			(pads allowed)
			(copperpour not_allowed)
			(footprints allowed)
		)
		(placement
			(enabled no)
			(sheetname "")
		)
		(fill yes
			(thermal_gap 0.5)
			(thermal_bridge_width 0.5)
			(island_removal_mode 0)
		)
		(polygon
			(pts
				(arc
					(start 409.137104 -435.489858)
					(mid 408.362912 -435.489858)
					(end 409.137104 -435.489858)
				)
			)
		)
	)
	(zone
		(layers "B.Cu" "In15.Cu")
		(hatch none 0.5)
		(connect_pads
			(clearance 0)
		)
		(min_thickness 0.25)
		(keepout
			(tracks not_allowed)
			(vias allowed)
			(pads allowed)
			(copperpour not_allowed)
			(footprints allowed)
		)
		(placement
			(enabled no)
			(sheetname "")
		)
		(fill yes
			(thermal_gap 0.5)
			(thermal_bridge_width 0.5)
			(island_removal_mode 0)
		)
		(polygon
			(pts
				(arc
					(start 296.058082 -246.635016)
					(mid 295.390062 -246.635016)
					(end 296.058082 -246.635016)
				)
			)
		)
	)
	(zone
		(layers "B.Cu" "In15.Cu")
		(hatch none 0.5)
		(connect_pads
			(clearance 0)
		)
		(min_thickness 0.25)
		(keepout
			(tracks not_allowed)
			(vias allowed)
			(pads allowed)
			(copperpour not_allowed)
			(footprints allowed)
		)
		(placement
			(enabled no)
			(sheetname "")
		)
		(fill yes
			(thermal_gap 0.5)
			(thermal_bridge_width 0.5)
			(island_removal_mode 0)
		)
		(polygon
			(pts
				(arc
					(start 176.406048 -290.835334)
					(mid 175.738028 -290.835334)
					(end 176.406048 -290.835334)
				)
			)
		)
	)
	(zone
		(layers "B.Cu" "In15.Cu")
		(hatch none 0.5)
		(connect_pads
			(clearance 0)
		)
		(min_thickness 0.25)
		(keepout
			(tracks not_allowed)
			(vias allowed)
			(pads allowed)
			(copperpour not_allowed)
			(footprints allowed)
		)
		(placement
			(enabled no)
			(sheetname "")
		)
		(fill yes
			(thermal_gap 0.5)
			(thermal_bridge_width 0.5)
			(island_removal_mode 0)
		)
		(polygon
			(pts
				(arc
					(start 420.246048 -220.285056)
					(mid 419.578028 -220.285056)
					(end 420.246048 -220.285056)
				)
			)
		)
	)
	(zone
		(layers "B.Cu" "In15.Cu")
		(hatch none 0.5)
		(connect_pads
			(clearance 0)
		)
		(min_thickness 0.25)
		(keepout
			(tracks not_allowed)
			(vias allowed)
			(pads allowed)
			(copperpour not_allowed)
			(footprints allowed)
		)
		(placement
			(enabled no)
			(sheetname "")
		)
		(fill yes
			(thermal_gap 0.5)
			(thermal_bridge_width 0.5)
			(island_removal_mode 0)
		)
		(polygon
			(pts
				(arc
					(start 88.426036 -264.366248)
					(mid 87.796116 -264.366248)
					(end 88.426036 -264.366248)
				)
			)
		)
	)
	(zone
		(layers "B.Cu" "In15.Cu")
		(hatch none 0.5)
		(connect_pads
			(clearance 0)
		)
		(min_thickness 0.25)
		(keepout
			(tracks not_allowed)
			(vias allowed)
			(pads allowed)
			(copperpour not_allowed)
			(footprints allowed)
		)
		(placement
			(enabled no)
			(sheetname "")
		)
		(fill yes
			(thermal_gap 0.5)
			(thermal_bridge_width 0.5)
			(island_removal_mode 0)
		)
		(polygon
			(pts
				(arc
					(start 48.118014 -274.685252)
					(mid 47.449994 -274.685252)
					(end 48.118014 -274.685252)
				)
			)
		)
	)
	(zone
		(layers "B.Cu" "In15.Cu")
		(hatch none 0.5)
		(connect_pads
			(clearance 0)
		)
		(min_thickness 0.25)
		(keepout
			(tracks not_allowed)
			(vias allowed)
			(pads allowed)
			(copperpour not_allowed)
			(footprints allowed)
		)
		(placement
			(enabled no)
			(sheetname "")
		)
		(fill yes
			(thermal_gap 0.5)
			(thermal_bridge_width 0.5)
			(island_removal_mode 0)
		)
		(polygon
			(pts
				(arc
					(start 128.136904 -435.489858)
					(mid 127.362712 -435.489858)
					(end 128.136904 -435.489858)
				)
			)
		)
	)
	(zone
		(layer "In1.Cu")
		(hatch none 0.5)
		(connect_pads
			(clearance 0)
		)
		(min_thickness 0.25)
		(keepout
			(tracks not_allowed)
			(vias allowed)
			(pads allowed)
			(copperpour not_allowed)
			(footprints allowed)
		)
		(placement
			(enabled no)
			(sheetname "")
		)
		(fill
			(thermal_gap 0.5)
			(thermal_bridge_width 0.5)
			(island_removal_mode 0)
		)
		(polygon
			(pts
				(arc
					(start 85.188806 -389.467344)
					(mid 84.807806 -389.467344)
					(end 85.188806 -389.467344)
				)
			)
		)
	)
	(zone
		(layer "In1.Cu")
		(hatch none 0.5)
		(connect_pads
			(clearance 0)
		)
		(min_thickness 0.25)
		(keepout
			(tracks not_allowed)
			(vias allowed)
			(pads allowed)
			(copperpour not_allowed)
			(footprints allowed)
		)
		(placement
			(enabled no)
			(sheetname "")
		)
		(fill
			(thermal_gap 0.5)
			(thermal_bridge_width 0.5)
			(island_removal_mode 0)
		)
		(polygon
			(pts
				(arc
					(start 450.8373 -267.282168)
					(mid 450.83358 -267.291148)
					(end 450.8246 -267.294868)
				)
				(arc
					(start 449.3514 -267.294868)
					(mid 449.34242 -267.291148)
					(end 449.3387 -267.282168)
				)
				(arc
					(start 449.3387 -266.78763)
					(mid 449.34242 -266.77865)
					(end 449.3514 -266.77493)
				)
				(arc
					(start 450.8246 -266.77493)
					(mid 450.83358 -266.77865)
					(end 450.8373 -266.78763)
				)
			)
		)
	)
	(zone
		(layer "In1.Cu")
		(hatch none 0.5)
		(connect_pads
			(clearance 0)
		)
		(min_thickness 0.25)
		(keepout
			(tracks not_allowed)
			(vias allowed)
			(pads allowed)
			(copperpour not_allowed)
			(footprints allowed)
		)
		(placement
			(enabled no)
			(sheetname "")
		)
		(fill
			(thermal_gap 0.5)
			(thermal_bridge_width 0.5)
			(island_removal_mode 0)
		)
		(polygon
			(pts
				(arc
					(start 285.485332 -266.432284)
					(mid 285.481612 -266.441264)
					(end 285.472632 -266.444984)
				)
				(arc
					(start 283.999432 -266.444984)
					(mid 283.990452 -266.441264)
					(end 283.986732 -266.432284)
				)
				(arc
					(start 283.986732 -265.937746)
					(mid 283.990452 -265.928766)
					(end 283.999432 -265.925046)
				)
				(arc
					(start 285.472632 -265.925046)
					(mid 285.481612 -265.928766)
					(end 285.485332 -265.937746)
				)
			)
		)
	)
	(zone
		(layer "In1.Cu")
		(hatch none 0.5)
		(connect_pads
			(clearance 0)
		)
		(min_thickness 0.25)
		(keepout
			(tracks not_allowed)
			(vias allowed)
			(pads allowed)
			(copperpour not_allowed)
			(footprints allowed)
		)
		(placement
			(enabled no)
			(sheetname "")
		)
		(fill
			(thermal_gap 0.5)
			(thermal_bridge_width 0.5)
			(island_removal_mode 0)
		)
		(polygon
			(pts
				(arc
					(start 281.385264 -248.58218)
					(mid 281.381544 -248.59116)
					(end 281.372564 -248.59488)
				)
				(arc
					(start 279.899364 -248.59488)
					(mid 279.890384 -248.59116)
					(end 279.886664 -248.58218)
				)
				(arc
					(start 279.886664 -248.087642)
					(mid 279.890384 -248.078662)
					(end 279.899364 -248.074942)
				)
				(arc
					(start 281.372564 -248.074942)
					(mid 281.381544 -248.078662)
					(end 281.385264 -248.087642)
				)
			)
		)
	)
	(zone
		(layer "In1.Cu")
		(hatch none 0.5)
		(connect_pads
			(clearance 0)
		)
		(min_thickness 0.25)
		(keepout
			(tracks not_allowed)
			(vias allowed)
			(pads allowed)
			(copperpour not_allowed)
			(footprints allowed)
		)
		(placement
			(enabled no)
			(sheetname "")
		)
		(fill
			(thermal_gap 0.5)
			(thermal_bridge_width 0.5)
			(island_removal_mode 0)
		)
		(polygon
			(pts
				(arc
					(start 304.017426 -276.632162)
					(mid 304.013706 -276.641142)
					(end 304.004726 -276.644862)
				)
				(arc
					(start 302.531526 -276.644862)
					(mid 302.522546 -276.641142)
					(end 302.518826 -276.632162)
				)
				(arc
					(start 302.518826 -276.137624)
					(mid 302.522546 -276.128644)
					(end 302.531526 -276.124924)
				)
				(arc
					(start 304.004726 -276.124924)
					(mid 304.013706 -276.128644)
					(end 304.017426 -276.137624)
				)
			)
		)
	)
	(zone
		(layer "In1.Cu")
		(hatch none 0.5)
		(connect_pads
			(clearance 0)
		)
		(min_thickness 0.25)
		(keepout
			(tracks not_allowed)
			(vias allowed)
			(pads allowed)
			(copperpour not_allowed)
			(footprints allowed)
		)
		(placement
			(enabled no)
			(sheetname "")
		)
		(fill
			(thermal_gap 0.5)
			(thermal_bridge_width 0.5)
			(island_removal_mode 0)
		)
		(polygon
			(pts
				(arc
					(start 357.862124 -388.647178)
					(mid 357.852888 -388.667102)
					(end 357.849678 -388.688834)
				)
				(arc
					(start 357.849678 -388.883398)
					(mid 357.871996 -388.93728)
					(end 357.925878 -388.959598)
				)
				(arc
					(start 358.611678 -388.959598)
					(mid 358.66556 -388.93728)
					(end 358.687878 -388.883398)
				)
				(arc
					(start 358.687878 -388.688834)
					(mid 358.68471 -388.66709)
					(end 358.675432 -388.647178)
				)
				(arc
					(start 358.482646 -388.351014)
					(mid 358.470424 -388.30933)
					(end 358.4829 -388.267702)
				)
				(arc
					(start 358.675432 -387.974078)
					(mid 358.684668 -387.954154)
					(end 358.687878 -387.932422)
				)
				(arc
					(start 358.687878 -387.737858)
					(mid 358.66556 -387.683976)
					(end 358.611678 -387.661658)
				)
				(arc
					(start 357.925878 -387.661658)
					(mid 357.871996 -387.683976)
					(end 357.849678 -387.737858)
				)
				(arc
					(start 357.849678 -387.933692)
					(mid 357.852846 -387.955436)
					(end 357.862124 -387.975348)
				)
				(arc
					(start 358.054656 -388.268972)
					(mid 358.067058 -388.310628)
					(end 358.054656 -388.352284)
				)
			)
		)
	)
	(zone
		(layer "In1.Cu")
		(hatch none 0.5)
		(connect_pads
			(clearance 0)
		)
		(min_thickness 0.25)
		(keepout
			(tracks not_allowed)
			(vias allowed)
			(pads allowed)
			(copperpour not_allowed)
			(footprints allowed)
		)
		(placement
			(enabled no)
			(sheetname "")
		)
		(fill
			(thermal_gap 0.5)
			(thermal_bridge_width 0.5)
			(island_removal_mode 0)
		)
		(polygon
			(pts
				(arc
					(start 195.353432 -198.43242)
					(mid 195.349712 -198.4414)
					(end 195.340732 -198.44512)
				)
				(arc
					(start 193.867532 -198.44512)
					(mid 193.858552 -198.4414)
					(end 193.854832 -198.43242)
				)
				(arc
					(start 193.854832 -197.937882)
					(mid 193.858552 -197.928902)
					(end 193.867532 -197.925182)
				)
				(arc
					(start 195.340732 -197.925182)
					(mid 195.349712 -197.928902)
					(end 195.353432 -197.937882)
				)
			)
		)
	)
	(zone
		(layer "In1.Cu")
		(hatch none 0.5)
		(connect_pads
			(clearance 0)
		)
		(min_thickness 0.25)
		(keepout
			(tracks not_allowed)
			(vias allowed)
			(pads allowed)
			(copperpour not_allowed)
			(footprints allowed)
		)
		(placement
			(enabled no)
			(sheetname "")
		)
		(fill
			(thermal_gap 0.5)
			(thermal_bridge_width 0.5)
			(island_removal_mode 0)
		)
		(polygon
			(pts
				(arc
					(start 304.770028 -399.143474)
					(mid 304.465228 -399.143474)
					(end 304.770028 -399.143474)
				)
			)
		)
	)
	(zone
		(layer "In1.Cu")
		(hatch none 0.5)
		(connect_pads
			(clearance 0)
		)
		(min_thickness 0.25)
		(keepout
			(tracks not_allowed)
			(vias allowed)
			(pads allowed)
			(copperpour not_allowed)
			(footprints allowed)
		)
		(placement
			(enabled no)
			(sheetname "")
		)
		(fill
			(thermal_gap 0.5)
			(thermal_bridge_width 0.5)
			(island_removal_mode 0)
		)
		(polygon
			(pts
				(arc
					(start 60.177426 -266.432538)
					(mid 60.173706 -266.441518)
					(end 60.164726 -266.445238)
				)
				(arc
					(start 58.691526 -266.445238)
					(mid 58.682546 -266.441518)
					(end 58.678826 -266.432538)
				)
				(arc
					(start 58.678826 -265.938)
					(mid 58.682546 -265.92902)
					(end 58.691526 -265.9253)
				)
				(arc
					(start 60.164726 -265.9253)
					(mid 60.173706 -265.92902)
					(end 60.177426 -265.938)
				)
			)
		)
	)
	(zone
		(layer "In1.Cu")
		(hatch none 0.5)
		(connect_pads
			(clearance 0)
		)
		(min_thickness 0.25)
		(keepout
			(tracks not_allowed)
			(vias allowed)
			(pads allowed)
			(copperpour not_allowed)
			(footprints allowed)
		)
		(placement
			(enabled no)
			(sheetname "")
		)
		(fill
			(thermal_gap 0.5)
			(thermal_bridge_width 0.5)
			(island_removal_mode 0)
		)
		(polygon
			(pts
				(arc
					(start 375.47042 -399.143474)
					(mid 375.16562 -399.143474)
					(end 375.47042 -399.143474)
				)
			)
		)
	)
	(zone
		(layer "In1.Cu")
		(hatch none 0.5)
		(connect_pads
			(clearance 0)
		)
		(min_thickness 0.25)
		(keepout
			(tracks not_allowed)
			(vias allowed)
			(pads allowed)
			(copperpour not_allowed)
			(footprints allowed)
		)
		(placement
			(enabled no)
			(sheetname "")
		)
		(fill
			(thermal_gap 0.5)
			(thermal_bridge_width 0.5)
			(island_removal_mode 0)
		)
		(polygon
			(pts
				(arc
					(start 417.217352 -231.582214)
					(mid 417.213632 -231.591194)
					(end 417.204652 -231.594914)
				)
				(arc
					(start 415.731452 -231.594914)
					(mid 415.722472 -231.591194)
					(end 415.718752 -231.582214)
				)
				(arc
					(start 415.718752 -231.087676)
					(mid 415.722472 -231.078696)
					(end 415.731452 -231.074976)
				)
				(arc
					(start 417.204652 -231.074976)
					(mid 417.213632 -231.078696)
					(end 417.217352 -231.087676)
				)
			)
		)
	)
	(zone
		(layer "In1.Cu")
		(hatch none 0.5)
		(connect_pads
			(clearance 0)
		)
		(min_thickness 0.25)
		(keepout
			(tracks not_allowed)
			(vias allowed)
			(pads allowed)
			(copperpour not_allowed)
			(footprints allowed)
		)
		(placement
			(enabled no)
			(sheetname "")
		)
		(fill
			(thermal_gap 0.5)
			(thermal_bridge_width 0.5)
			(island_removal_mode 0)
		)
		(polygon
			(pts
				(arc
					(start 410.68879 -394.385292)
					(mid 410.30779 -394.385292)
					(end 410.68879 -394.385292)
				)
			)
		)
	)
	(zone
		(layer "In1.Cu")
		(hatch none 0.5)
		(connect_pads
			(clearance 0)
		)
		(min_thickness 0.25)
		(keepout
			(tracks not_allowed)
			(vias allowed)
			(pads allowed)
			(copperpour not_allowed)
			(footprints allowed)
		)
		(placement
			(enabled no)
			(sheetname "")
		)
		(fill
			(thermal_gap 0.5)
			(thermal_bridge_width 0.5)
			(island_removal_mode 0)
		)
		(polygon
			(pts
				(arc
					(start 33.445196 -232.432352)
					(mid 33.441476 -232.441332)
					(end 33.432496 -232.445052)
				)
				(arc
					(start 31.959296 -232.445052)
					(mid 31.950316 -232.441332)
					(end 31.946596 -232.432352)
				)
				(arc
					(start 31.946596 -231.937814)
					(mid 31.950316 -231.928834)
					(end 31.959296 -231.925114)
				)
				(arc
					(start 33.432496 -231.925114)
					(mid 33.441476 -231.928834)
					(end 33.445196 -231.937814)
				)
			)
		)
	)
	(zone
		(layer "In1.Cu")
		(hatch none 0.5)
		(connect_pads
			(clearance 0)
		)
		(min_thickness 0.25)
		(keepout
			(tracks not_allowed)
			(vias allowed)
			(pads allowed)
			(copperpour not_allowed)
			(footprints allowed)
		)
		(placement
			(enabled no)
			(sheetname "")
		)
		(fill
			(thermal_gap 0.5)
			(thermal_bridge_width 0.5)
			(island_removal_mode 0)
		)
		(polygon
			(pts
				(arc
					(start 380.270258 -399.143474)
					(mid 379.965458 -399.143474)
					(end 380.270258 -399.143474)
				)
			)
		)
	)
	(zone
		(layer "In1.Cu")
		(hatch none 0.5)
		(connect_pads
			(clearance 0)
		)
		(min_thickness 0.25)
		(keepout
			(tracks not_allowed)
			(vias allowed)
			(pads allowed)
			(copperpour not_allowed)
			(footprints allowed)
		)
		(placement
			(enabled no)
			(sheetname "")
		)
		(fill
			(thermal_gap 0.5)
			(thermal_bridge_width 0.5)
			(island_removal_mode 0)
		)
		(polygon
			(pts
				(arc
					(start 288.929318 -221.382082)
					(mid 288.925598 -221.391062)
					(end 288.916618 -221.394782)
				)
				(arc
					(start 287.443418 -221.394782)
					(mid 287.434438 -221.391062)
					(end 287.430718 -221.382082)
				)
				(arc
					(start 287.430718 -220.887544)
					(mid 287.434438 -220.878564)
					(end 287.443418 -220.874844)
				)
				(arc
					(start 288.916618 -220.874844)
					(mid 288.925598 -220.878564)
					(end 288.929318 -220.887544)
				)
			)
		)
	)
	(zone
		(layer "In1.Cu")
		(hatch none 0.5)
		(connect_pads
			(clearance 0)
		)
		(min_thickness 0.25)
		(keepout
			(tracks not_allowed)
			(vias allowed)
			(pads allowed)
			(copperpour not_allowed)
			(footprints allowed)
		)
		(placement
			(enabled no)
			(sheetname "")
		)
		(fill
			(thermal_gap 0.5)
			(thermal_bridge_width 0.5)
			(island_removal_mode 0)
		)
		(polygon
			(pts
				(arc
					(start 435.749446 -212.032088)
					(mid 435.745726 -212.041068)
					(end 435.736746 -212.044788)
				)
				(arc
					(start 434.263546 -212.044788)
					(mid 434.254566 -212.041068)
					(end 434.250846 -212.032088)
				)
				(arc
					(start 434.250846 -211.53755)
					(mid 434.254566 -211.52857)
					(end 434.263546 -211.52485)
				)
				(arc
					(start 435.736746 -211.52485)
					(mid 435.745726 -211.52857)
					(end 435.749446 -211.53755)
				)
			)
		)
	)
	(zone
		(layer "In1.Cu")
		(hatch none 0.5)
		(connect_pads
			(clearance 0)
		)
		(min_thickness 0.25)
		(keepout
			(tracks not_allowed)
			(vias allowed)
			(pads allowed)
			(copperpour not_allowed)
			(footprints allowed)
		)
		(placement
			(enabled no)
			(sheetname "")
		)
		(fill
			(thermal_gap 0.5)
			(thermal_bridge_width 0.5)
			(island_removal_mode 0)
		)
		(polygon
			(pts
				(arc
					(start 266.29741 -299.582332)
					(mid 266.29369 -299.591312)
					(end 266.28471 -299.595032)
				)
				(arc
					(start 264.81151 -299.595032)
					(mid 264.80253 -299.591312)
					(end 264.79881 -299.582332)
				)
				(arc
					(start 264.79881 -299.087794)
					(mid 264.80253 -299.078814)
					(end 264.81151 -299.075094)
				)
				(arc
					(start 266.28471 -299.075094)
					(mid 266.29369 -299.078814)
					(end 266.29741 -299.087794)
				)
			)
		)
	)
	(zone
		(layer "In1.Cu")
		(hatch none 0.5)
		(connect_pads
			(clearance 0)
		)
		(min_thickness 0.25)
		(keepout
			(tracks not_allowed)
			(vias allowed)
			(pads allowed)
			(copperpour not_allowed)
			(footprints allowed)
		)
		(placement
			(enabled no)
			(sheetname "")
		)
		(fill
			(thermal_gap 0.5)
			(thermal_bridge_width 0.5)
			(island_removal_mode 0)
		)
		(polygon
			(pts
				(arc
					(start 288.929318 -290.232338)
					(mid 288.925598 -290.241318)
					(end 288.916618 -290.245038)
				)
				(arc
					(start 287.443418 -290.245038)
					(mid 287.434438 -290.241318)
					(end 287.430718 -290.232338)
				)
				(arc
					(start 287.430718 -289.7378)
					(mid 287.434438 -289.72882)
					(end 287.443418 -289.7251)
				)
				(arc
					(start 288.916618 -289.7251)
					(mid 288.925598 -289.72882)
					(end 288.929318 -289.7378)
				)
			)
		)
	)
	(zone
		(layer "In1.Cu")
		(hatch none 0.5)
		(connect_pads
			(clearance 0)
		)
		(min_thickness 0.25)
		(keepout
			(tracks not_allowed)
			(vias allowed)
			(pads allowed)
			(copperpour not_allowed)
			(footprints allowed)
		)
		(placement
			(enabled no)
			(sheetname "")
		)
		(fill
			(thermal_gap 0.5)
			(thermal_bridge_width 0.5)
			(island_removal_mode 0)
		)
		(polygon
			(pts
				(arc
					(start 18.357342 -250.282456)
					(mid 18.353622 -250.291436)
					(end 18.344642 -250.295156)
				)
				(arc
					(start 16.871442 -250.295156)
					(mid 16.862462 -250.291436)
					(end 16.858742 -250.282456)
				)
				(arc
					(start 16.858742 -249.787918)
					(mid 16.862462 -249.778938)
					(end 16.871442 -249.775218)
				)
				(arc
					(start 18.344642 -249.775218)
					(mid 18.353622 -249.778938)
					(end 18.357342 -249.787918)
				)
			)
		)
	)
	(zone
		(layer "In1.Cu")
		(hatch none 0.5)
		(connect_pads
			(clearance 0)
		)
		(min_thickness 0.25)
		(keepout
			(tracks not_allowed)
			(vias allowed)
			(pads allowed)
			(copperpour not_allowed)
			(footprints allowed)
		)
		(placement
			(enabled no)
			(sheetname "")
		)
		(fill
			(thermal_gap 0.5)
			(thermal_bridge_width 0.5)
			(island_removal_mode 0)
		)
		(polygon
			(pts
				(arc
					(start 37.545264 -231.582468)
					(mid 37.541544 -231.591448)
					(end 37.532564 -231.595168)
				)
				(arc
					(start 36.059364 -231.595168)
					(mid 36.050384 -231.591448)
					(end 36.046664 -231.582468)
				)
				(arc
					(start 36.046664 -231.08793)
					(mid 36.050384 -231.07895)
					(end 36.059364 -231.07523)
				)
				(arc
					(start 37.532564 -231.07523)
					(mid 37.541544 -231.07895)
					(end 37.545264 -231.08793)
				)
			)
		)
	)
	(zone
		(layer "In1.Cu")
		(hatch none 0.5)
		(connect_pads
			(clearance 0)
		)
		(min_thickness 0.25)
		(keepout
			(tracks not_allowed)
			(vias allowed)
			(pads allowed)
			(copperpour not_allowed)
			(footprints allowed)
		)
		(placement
			(enabled no)
			(sheetname "")
		)
		(fill
			(thermal_gap 0.5)
			(thermal_bridge_width 0.5)
			(island_removal_mode 0)
		)
		(polygon
			(pts
				(arc
					(start 22.45741 -287.682432)
					(mid 22.45369 -287.691412)
					(end 22.44471 -287.695132)
				)
				(arc
					(start 20.97151 -287.695132)
					(mid 20.96253 -287.691412)
					(end 20.95881 -287.682432)
				)
				(arc
					(start 20.95881 -287.187894)
					(mid 20.96253 -287.178914)
					(end 20.97151 -287.175194)
				)
				(arc
					(start 22.44471 -287.175194)
					(mid 22.45369 -287.178914)
					(end 22.45741 -287.187894)
				)
			)
		)
	)
	(zone
		(layer "In1.Cu")
		(hatch none 0.5)
		(connect_pads
			(clearance 0)
		)
		(min_thickness 0.25)
		(keepout
			(tracks not_allowed)
			(vias allowed)
			(pads allowed)
			(copperpour not_allowed)
			(footprints allowed)
		)
		(placement
			(enabled no)
			(sheetname "")
		)
		(fill
			(thermal_gap 0.5)
			(thermal_bridge_width 0.5)
			(island_removal_mode 0)
		)
		(polygon
			(pts
				(arc
					(start 424.761406 -317.432182)
					(mid 424.757686 -317.441162)
					(end 424.748706 -317.444882)
				)
				(arc
					(start 423.275506 -317.444882)
					(mid 423.266526 -317.441162)
					(end 423.262806 -317.432182)
				)
				(arc
					(start 423.262806 -316.937644)
					(mid 423.266526 -316.928664)
					(end 423.275506 -316.924944)
				)
				(arc
					(start 424.748706 -316.924944)
					(mid 424.757686 -316.928664)
					(end 424.761406 -316.937644)
				)
			)
		)
	)
	(zone
		(layer "In1.Cu")
		(hatch none 0.5)
		(connect_pads
			(clearance 0)
		)
		(min_thickness 0.25)
		(keepout
			(tracks not_allowed)
			(vias allowed)
			(pads allowed)
			(copperpour not_allowed)
			(footprints allowed)
		)
		(placement
			(enabled no)
			(sheetname "")
		)
		(fill
			(thermal_gap 0.5)
			(thermal_bridge_width 0.5)
			(island_removal_mode 0)
		)
		(polygon
			(pts
				(arc
					(start 147.818602 -391.319258)
					(mid 147.945602 -391.446258)
					(end 148.072602 -391.319258)
				)
				(arc
					(start 148.072602 -391.243058)
					(mid 147.945602 -391.116058)
					(end 147.818602 -391.243058)
				)
			)
		)
	)
	(zone
		(layer "In1.Cu")
		(hatch none 0.5)
		(connect_pads
			(clearance 0)
		)
		(min_thickness 0.25)
		(keepout
			(tracks not_allowed)
			(vias allowed)
			(pads allowed)
			(copperpour not_allowed)
			(footprints allowed)
		)
		(placement
			(enabled no)
			(sheetname "")
		)
		(fill
			(thermal_gap 0.5)
			(thermal_bridge_width 0.5)
			(island_removal_mode 0)
		)
		(polygon
			(pts
				(arc
					(start 52.633372 -227.33254)
					(mid 52.629652 -227.34152)
					(end 52.620672 -227.34524)
				)
				(arc
					(start 51.147472 -227.34524)
					(mid 51.138492 -227.34152)
					(end 51.134772 -227.33254)
				)
				(arc
					(start 51.134772 -226.838002)
					(mid 51.138492 -226.829022)
					(end 51.147472 -226.825302)
				)
				(arc
					(start 52.620672 -226.825302)
					(mid 52.629652 -226.829022)
					(end 52.633372 -226.838002)
				)
			)
		)
	)
	(zone
		(layer "In1.Cu")
		(hatch none 0.5)
		(connect_pads
			(clearance 0)
		)
		(min_thickness 0.25)
		(keepout
			(tracks not_allowed)
			(vias allowed)
			(pads allowed)
			(copperpour not_allowed)
			(footprints allowed)
		)
		(placement
			(enabled no)
			(sheetname "")
		)
		(fill
			(thermal_gap 0.5)
			(thermal_bridge_width 0.5)
			(island_removal_mode 0)
		)
		(polygon
			(pts
				(arc
					(start 180.265324 -213.732364)
					(mid 180.261604 -213.741344)
					(end 180.252624 -213.745064)
				)
				(arc
					(start 178.779424 -213.745064)
					(mid 178.770444 -213.741344)
					(end 178.766724 -213.732364)
				)
				(arc
					(start 178.766724 -213.237826)
					(mid 178.770444 -213.228846)
					(end 178.779424 -213.225126)
				)
				(arc
					(start 180.252624 -213.225126)
					(mid 180.261604 -213.228846)
					(end 180.265324 -213.237826)
				)
			)
		)
	)
	(zone
		(layer "In1.Cu")
		(hatch none 0.5)
		(connect_pads
			(clearance 0)
		)
		(min_thickness 0.25)
		(keepout
			(tracks not_allowed)
			(vias allowed)
			(pads allowed)
			(copperpour not_allowed)
			(footprints allowed)
		)
		(placement
			(enabled no)
			(sheetname "")
		)
		(fill
			(thermal_gap 0.5)
			(thermal_bridge_width 0.5)
			(island_removal_mode 0)
		)
		(polygon
			(pts
				(arc
					(start 85.98916 -388.774432)
					(mid 85.60816 -388.774432)
					(end 85.98916 -388.774432)
				)
			)
		)
	)
	(zone
		(layer "In1.Cu")
		(hatch none 0.5)
		(connect_pads
			(clearance 0)
		)
		(min_thickness 0.25)
		(keepout
			(tracks not_allowed)
			(vias allowed)
			(pads allowed)
			(copperpour not_allowed)
			(footprints allowed)
		)
		(placement
			(enabled no)
			(sheetname "")
		)
		(fill
			(thermal_gap 0.5)
			(thermal_bridge_width 0.5)
			(island_removal_mode 0)
		)
		(polygon
			(pts
				(arc
					(start 18.357342 -263.882378)
					(mid 18.353622 -263.891358)
					(end 18.344642 -263.895078)
				)
				(arc
					(start 16.871442 -263.895078)
					(mid 16.862462 -263.891358)
					(end 16.858742 -263.882378)
				)
				(arc
					(start 16.858742 -263.38784)
					(mid 16.862462 -263.37886)
					(end 16.871442 -263.37514)
				)
				(arc
					(start 18.344642 -263.37514)
					(mid 18.353622 -263.37886)
					(end 18.357342 -263.38784)
				)
			)
		)
	)
	(zone
		(layer "In1.Cu")
		(hatch none 0.5)
		(connect_pads
			(clearance 0)
		)
		(min_thickness 0.25)
		(keepout
			(tracks not_allowed)
			(vias allowed)
			(pads allowed)
			(copperpour not_allowed)
			(footprints allowed)
		)
		(placement
			(enabled no)
			(sheetname "")
		)
		(fill
			(thermal_gap 0.5)
			(thermal_bridge_width 0.5)
			(island_removal_mode 0)
		)
		(polygon
			(pts
				(arc
					(start 40.98925 -316.582552)
					(mid 40.98553 -316.591532)
					(end 40.97655 -316.595252)
				)
				(arc
					(start 39.50335 -316.595252)
					(mid 39.49437 -316.591532)
					(end 39.49065 -316.582552)
				)
				(arc
					(start 39.49065 -316.088014)
					(mid 39.49437 -316.079034)
					(end 39.50335 -316.075314)
				)
				(arc
					(start 40.97655 -316.075314)
					(mid 40.98553 -316.079034)
					(end 40.98925 -316.088014)
				)
			)
		)
	)
	(zone
		(layer "In1.Cu")
		(hatch none 0.5)
		(connect_pads
			(clearance 0)
		)
		(min_thickness 0.25)
		(keepout
			(tracks not_allowed)
			(vias allowed)
			(pads allowed)
			(copperpour not_allowed)
			(footprints allowed)
		)
		(placement
			(enabled no)
			(sheetname "")
		)
		(fill
			(thermal_gap 0.5)
			(thermal_bridge_width 0.5)
			(island_removal_mode 0)
		)
		(polygon
			(pts
				(arc
					(start 417.217352 -238.382302)
					(mid 417.213632 -238.391282)
					(end 417.204652 -238.395002)
				)
				(arc
					(start 415.731452 -238.395002)
					(mid 415.722472 -238.391282)
					(end 415.718752 -238.382302)
				)
				(arc
					(start 415.718752 -237.887764)
					(mid 415.722472 -237.878784)
					(end 415.731452 -237.875064)
				)
				(arc
					(start 417.204652 -237.875064)
					(mid 417.213632 -237.878784)
					(end 417.217352 -237.887764)
				)
			)
		)
	)
	(zone
		(layer "In1.Cu")
		(hatch none 0.5)
		(connect_pads
			(clearance 0)
		)
		(min_thickness 0.25)
		(keepout
			(tracks not_allowed)
			(vias allowed)
			(pads allowed)
			(copperpour not_allowed)
			(footprints allowed)
		)
		(placement
			(enabled no)
			(sheetname "")
		)
		(fill
			(thermal_gap 0.5)
			(thermal_bridge_width 0.5)
			(island_removal_mode 0)
		)
		(polygon
			(pts
				(arc
					(start 165.177216 -251.982478)
					(mid 165.173496 -251.991458)
					(end 165.164516 -251.995178)
				)
				(arc
					(start 163.691316 -251.995178)
					(mid 163.682336 -251.991458)
					(end 163.678616 -251.982478)
				)
				(arc
					(start 163.678616 -251.48794)
					(mid 163.682336 -251.47896)
					(end 163.691316 -251.47524)
				)
				(arc
					(start 165.164516 -251.47524)
					(mid 165.173496 -251.47896)
					(end 165.177216 -251.48794)
				)
			)
		)
	)
	(zone
		(layer "In1.Cu")
		(hatch none 0.5)
		(connect_pads
			(clearance 0)
		)
		(min_thickness 0.25)
		(keepout
			(tracks not_allowed)
			(vias allowed)
			(pads allowed)
			(copperpour not_allowed)
			(footprints allowed)
		)
		(placement
			(enabled no)
			(sheetname "")
		)
		(fill
			(thermal_gap 0.5)
			(thermal_bridge_width 0.5)
			(island_removal_mode 0)
		)
		(polygon
			(pts
				(arc
					(start 447.393568 -283.43225)
					(mid 447.389848 -283.44123)
					(end 447.380868 -283.44495)
				)
				(arc
					(start 445.907668 -283.44495)
					(mid 445.898688 -283.44123)
					(end 445.894968 -283.43225)
				)
				(arc
					(start 445.894968 -282.937712)
					(mid 445.898688 -282.928732)
					(end 445.907668 -282.925012)
				)
				(arc
					(start 447.380868 -282.925012)
					(mid 447.389848 -282.928732)
					(end 447.393568 -282.937712)
				)
			)
		)
	)
	(zone
		(layer "In1.Cu")
		(hatch none 0.5)
		(connect_pads
			(clearance 0)
		)
		(min_thickness 0.25)
		(keepout
			(tracks not_allowed)
			(vias allowed)
			(pads allowed)
			(copperpour not_allowed)
			(footprints allowed)
		)
		(placement
			(enabled no)
			(sheetname "")
		)
		(fill
			(thermal_gap 0.5)
			(thermal_bridge_width 0.5)
			(island_removal_mode 0)
		)
		(polygon
			(pts
				(arc
					(start 23.697692 -17.967198)
					(mid 23.72001 -18.02108)
					(end 23.773892 -18.043398)
				)
				(arc
					(start 23.969472 -18.043398)
					(mid 23.991348 -18.040266)
					(end 24.011382 -18.030952)
				)
				(arc
					(start 24.305006 -17.83842)
					(mid 24.346662 -17.826018)
					(end 24.388318 -17.83842)
				)
				(arc
					(start 24.683212 -18.030952)
					(mid 24.703136 -18.040188)
					(end 24.724868 -18.043398)
				)
				(arc
					(start 24.919432 -18.043398)
					(mid 24.973314 -18.02108)
					(end 24.995632 -17.967198)
				)
				(arc
					(start 24.995632 -17.281398)
					(mid 24.973314 -17.227516)
					(end 24.919432 -17.205198)
				)
				(arc
					(start 24.724868 -17.205198)
					(mid 24.703124 -17.208366)
					(end 24.683212 -17.217644)
				)
				(arc
					(start 24.387048 -17.41043)
					(mid 24.345364 -17.422652)
					(end 24.303736 -17.410176)
				)
				(arc
					(start 24.010112 -17.217644)
					(mid 23.990188 -17.208408)
					(end 23.968456 -17.205198)
				)
				(arc
					(start 23.773892 -17.205198)
					(mid 23.72001 -17.227516)
					(end 23.697692 -17.281398)
				)
			)
		)
	)
	(zone
		(layer "In1.Cu")
		(hatch none 0.5)
		(connect_pads
			(clearance 0)
		)
		(min_thickness 0.25)
		(keepout
			(tracks not_allowed)
			(vias allowed)
			(pads allowed)
			(copperpour not_allowed)
			(footprints allowed)
		)
		(placement
			(enabled no)
			(sheetname "")
		)
		(fill
			(thermal_gap 0.5)
			(thermal_bridge_width 0.5)
			(island_removal_mode 0)
		)
		(polygon
			(pts
				(arc
					(start 131.760976 -386.003292)
					(mid 131.379976 -386.003292)
					(end 131.760976 -386.003292)
				)
			)
		)
	)
	(zone
		(layer "In1.Cu")
		(hatch none 0.5)
		(connect_pads
			(clearance 0)
		)
		(min_thickness 0.25)
		(keepout
			(tracks not_allowed)
			(vias allowed)
			(pads allowed)
			(copperpour not_allowed)
			(footprints allowed)
		)
		(placement
			(enabled no)
			(sheetname "")
		)
		(fill
			(thermal_gap 0.5)
			(thermal_bridge_width 0.5)
			(island_removal_mode 0)
		)
		(polygon
			(pts
				(arc
					(start 454.937368 -238.382302)
					(mid 454.933648 -238.391282)
					(end 454.924668 -238.395002)
				)
				(arc
					(start 453.451468 -238.395002)
					(mid 453.442488 -238.391282)
					(end 453.438768 -238.382302)
				)
				(arc
					(start 453.438768 -237.887764)
					(mid 453.442488 -237.878784)
					(end 453.451468 -237.875064)
				)
				(arc
					(start 454.924668 -237.875064)
					(mid 454.933648 -237.878784)
					(end 454.937368 -237.887764)
				)
			)
		)
	)
	(zone
		(layer "In1.Cu")
		(hatch none 0.5)
		(connect_pads
			(clearance 0)
		)
		(min_thickness 0.25)
		(keepout
			(tracks not_allowed)
			(vias allowed)
			(pads allowed)
			(copperpour not_allowed)
			(footprints allowed)
		)
		(placement
			(enabled no)
			(sheetname "")
		)
		(fill
			(thermal_gap 0.5)
			(thermal_bridge_width 0.5)
			(island_removal_mode 0)
		)
		(polygon
			(pts
				(arc
					(start 413.117284 -314.882276)
					(mid 413.113564 -314.891256)
					(end 413.104584 -314.894976)
				)
				(arc
					(start 411.631384 -314.894976)
					(mid 411.622404 -314.891256)
					(end 411.618684 -314.882276)
				)
				(arc
					(start 411.618684 -314.387738)
					(mid 411.622404 -314.378758)
					(end 411.631384 -314.375038)
				)
				(arc
					(start 413.104584 -314.375038)
					(mid 413.113564 -314.378758)
					(end 413.117284 -314.387738)
				)
			)
		)
	)
	(zone
		(layer "In1.Cu")
		(hatch none 0.5)
		(connect_pads
			(clearance 0)
		)
		(min_thickness 0.25)
		(keepout
			(tracks not_allowed)
			(vias allowed)
			(pads allowed)
			(copperpour not_allowed)
			(footprints allowed)
		)
		(placement
			(enabled no)
			(sheetname "")
		)
		(fill
			(thermal_gap 0.5)
			(thermal_bridge_width 0.5)
			(island_removal_mode 0)
		)
		(polygon
			(pts
				(arc
					(start 30.001464 -211.182458)
					(mid 29.997744 -211.191438)
					(end 29.988764 -211.195158)
				)
				(arc
					(start 28.515564 -211.195158)
					(mid 28.506584 -211.191438)
					(end 28.502864 -211.182458)
				)
				(arc
					(start 28.502864 -210.68792)
					(mid 28.506584 -210.67894)
					(end 28.515564 -210.67522)
				)
				(arc
					(start 29.988764 -210.67522)
					(mid 29.997744 -210.67894)
					(end 30.001464 -210.68792)
				)
			)
		)
	)
	(zone
		(layer "In1.Cu")
		(hatch none 0.5)
		(connect_pads
			(clearance 0)
		)
		(min_thickness 0.25)
		(keepout
			(tracks not_allowed)
			(vias allowed)
			(pads allowed)
			(copperpour not_allowed)
			(footprints allowed)
		)
		(placement
			(enabled no)
			(sheetname "")
		)
		(fill
			(thermal_gap 0.5)
			(thermal_bridge_width 0.5)
			(island_removal_mode 0)
		)
		(polygon
			(pts
				(arc
					(start 169.277284 -217.982546)
					(mid 169.273564 -217.991526)
					(end 169.264584 -217.995246)
				)
				(arc
					(start 167.791384 -217.995246)
					(mid 167.782404 -217.991526)
					(end 167.778684 -217.982546)
				)
				(arc
					(start 167.778684 -217.488008)
					(mid 167.782404 -217.479028)
					(end 167.791384 -217.475308)
				)
				(arc
					(start 169.264584 -217.475308)
					(mid 169.273564 -217.479028)
					(end 169.277284 -217.488008)
				)
			)
		)
	)
	(zone
		(layer "In1.Cu")
		(hatch none 0.5)
		(connect_pads
			(clearance 0)
		)
		(min_thickness 0.25)
		(keepout
			(tracks not_allowed)
			(vias allowed)
			(pads allowed)
			(copperpour not_allowed)
			(footprints allowed)
		)
		(placement
			(enabled no)
			(sheetname "")
		)
		(fill
			(thermal_gap 0.5)
			(thermal_bridge_width 0.5)
			(island_removal_mode 0)
		)
		(polygon
			(pts
				(arc
					(start 428.205392 -276.632162)
					(mid 428.201672 -276.641142)
					(end 428.192692 -276.644862)
				)
				(arc
					(start 426.719492 -276.644862)
					(mid 426.710512 -276.641142)
					(end 426.706792 -276.632162)
				)
				(arc
					(start 426.706792 -276.137624)
					(mid 426.710512 -276.128644)
					(end 426.719492 -276.124924)
				)
				(arc
					(start 428.192692 -276.124924)
					(mid 428.201672 -276.128644)
					(end 428.205392 -276.137624)
				)
			)
		)
	)
	(zone
		(layer "In1.Cu")
		(hatch none 0.5)
		(connect_pads
			(clearance 0)
		)
		(min_thickness 0.25)
		(keepout
			(tracks not_allowed)
			(vias allowed)
			(pads allowed)
			(copperpour not_allowed)
			(footprints allowed)
		)
		(placement
			(enabled no)
			(sheetname "")
		)
		(fill
			(thermal_gap 0.5)
			(thermal_bridge_width 0.5)
			(island_removal_mode 0)
		)
		(polygon
			(pts
				(arc
					(start 296.473372 -293.632128)
					(mid 296.469652 -293.641108)
					(end 296.460672 -293.644828)
				)
				(arc
					(start 294.987472 -293.644828)
					(mid 294.978492 -293.641108)
					(end 294.974772 -293.632128)
				)
				(arc
					(start 294.974772 -293.13759)
					(mid 294.978492 -293.12861)
					(end 294.987472 -293.12489)
				)
				(arc
					(start 296.460672 -293.12489)
					(mid 296.469652 -293.12861)
					(end 296.473372 -293.13759)
				)
			)
		)
	)
	(zone
		(layer "In1.Cu")
		(hatch none 0.5)
		(connect_pads
			(clearance 0)
		)
		(min_thickness 0.25)
		(keepout
			(tracks not_allowed)
			(vias allowed)
			(pads allowed)
			(copperpour not_allowed)
			(footprints allowed)
		)
		(placement
			(enabled no)
			(sheetname "")
		)
		(fill
			(thermal_gap 0.5)
			(thermal_bridge_width 0.5)
			(island_removal_mode 0)
		)
		(polygon
			(pts
				(arc
					(start 450.8373 -209.482182)
					(mid 450.83358 -209.491162)
					(end 450.8246 -209.494882)
				)
				(arc
					(start 449.3514 -209.494882)
					(mid 449.34242 -209.491162)
					(end 449.3387 -209.482182)
				)
				(arc
					(start 449.3387 -208.987644)
					(mid 449.34242 -208.978664)
					(end 449.3514 -208.974944)
				)
				(arc
					(start 450.8246 -208.974944)
					(mid 450.83358 -208.978664)
					(end 450.8373 -208.987644)
				)
			)
		)
	)
	(zone
		(layer "In1.Cu")
		(hatch none 0.5)
		(connect_pads
			(clearance 0)
		)
		(min_thickness 0.25)
		(keepout
			(tracks not_allowed)
			(vias allowed)
			(pads allowed)
			(copperpour not_allowed)
			(footprints allowed)
		)
		(placement
			(enabled no)
			(sheetname "")
		)
		(fill
			(thermal_gap 0.5)
			(thermal_bridge_width 0.5)
			(island_removal_mode 0)
		)
		(polygon
			(pts
				(arc
					(start 266.29741 -301.2821)
					(mid 266.29369 -301.29108)
					(end 266.28471 -301.2948)
				)
				(arc
					(start 264.81151 -301.2948)
					(mid 264.80253 -301.29108)
					(end 264.79881 -301.2821)
				)
				(arc
					(start 264.79881 -300.787562)
					(mid 264.80253 -300.778582)
					(end 264.81151 -300.774862)
				)
				(arc
					(start 266.28471 -300.774862)
					(mid 266.29369 -300.778582)
					(end 266.29741 -300.787562)
				)
			)
		)
	)
	(zone
		(layer "In1.Cu")
		(hatch none 0.5)
		(connect_pads
			(clearance 0)
		)
		(min_thickness 0.25)
		(keepout
			(tracks not_allowed)
			(vias allowed)
			(pads allowed)
			(copperpour not_allowed)
			(footprints allowed)
		)
		(placement
			(enabled no)
			(sheetname "")
		)
		(fill
			(thermal_gap 0.5)
			(thermal_bridge_width 0.5)
			(island_removal_mode 0)
		)
		(polygon
			(pts
				(arc
					(start 285.485332 -233.282236)
					(mid 285.481612 -233.291216)
					(end 285.472632 -233.294936)
				)
				(arc
					(start 283.999432 -233.294936)
					(mid 283.990452 -233.291216)
					(end 283.986732 -233.282236)
				)
				(arc
					(start 283.986732 -232.787698)
					(mid 283.990452 -232.778718)
					(end 283.999432 -232.774998)
				)
				(arc
					(start 285.472632 -232.774998)
					(mid 285.481612 -232.778718)
					(end 285.485332 -232.787698)
				)
			)
		)
	)
	(zone
		(layer "In1.Cu")
		(hatch none 0.5)
		(connect_pads
			(clearance 0)
		)
		(min_thickness 0.25)
		(keepout
			(tracks not_allowed)
			(vias allowed)
			(pads allowed)
			(copperpour not_allowed)
			(footprints allowed)
		)
		(placement
			(enabled no)
			(sheetname "")
		)
		(fill
			(thermal_gap 0.5)
			(thermal_bridge_width 0.5)
			(island_removal_mode 0)
		)
		(polygon
			(pts
				(arc
					(start 176.821338 -302.132492)
					(mid 176.817618 -302.141472)
					(end 176.808638 -302.145192)
				)
				(arc
					(start 175.335438 -302.145192)
					(mid 175.326458 -302.141472)
					(end 175.322738 -302.132492)
				)
				(arc
					(start 175.322738 -301.637954)
					(mid 175.326458 -301.628974)
					(end 175.335438 -301.625254)
				)
				(arc
					(start 176.808638 -301.625254)
					(mid 176.817618 -301.628974)
					(end 176.821338 -301.637954)
				)
			)
		)
	)
	(zone
		(layer "In1.Cu")
		(hatch none 0.5)
		(connect_pads
			(clearance 0)
		)
		(min_thickness 0.25)
		(keepout
			(tracks not_allowed)
			(vias allowed)
			(pads allowed)
			(copperpour not_allowed)
			(footprints allowed)
		)
		(placement
			(enabled no)
			(sheetname "")
		)
		(fill
			(thermal_gap 0.5)
			(thermal_bridge_width 0.5)
			(island_removal_mode 0)
		)
		(polygon
			(pts
				(arc
					(start 265.87831 -299.33519)
					(mid 265.21791 -299.33519)
					(end 265.87831 -299.33519)
				)
			)
		)
	)
	(zone
		(layer "In1.Cu")
		(hatch none 0.5)
		(connect_pads
			(clearance 0)
		)
		(min_thickness 0.25)
		(keepout
			(tracks not_allowed)
			(vias allowed)
			(pads allowed)
			(copperpour not_allowed)
			(footprints allowed)
		)
		(placement
			(enabled no)
			(sheetname "")
		)
		(fill
			(thermal_gap 0.5)
			(thermal_bridge_width 0.5)
			(island_removal_mode 0)
		)
		(polygon
			(pts
				(arc
					(start 165.177216 -240.082578)
					(mid 165.173496 -240.091558)
					(end 165.164516 -240.095278)
				)
				(arc
					(start 163.691316 -240.095278)
					(mid 163.682336 -240.091558)
					(end 163.678616 -240.082578)
				)
				(arc
					(start 163.678616 -239.58804)
					(mid 163.682336 -239.57906)
					(end 163.691316 -239.57534)
				)
				(arc
					(start 165.164516 -239.57534)
					(mid 165.173496 -239.57906)
					(end 165.177216 -239.58804)
				)
			)
		)
	)
	(zone
		(layer "In1.Cu")
		(hatch none 0.5)
		(connect_pads
			(clearance 0)
		)
		(min_thickness 0.25)
		(keepout
			(tracks not_allowed)
			(vias allowed)
			(pads allowed)
			(copperpour not_allowed)
			(footprints allowed)
		)
		(placement
			(enabled no)
			(sheetname "")
		)
		(fill
			(thermal_gap 0.5)
			(thermal_bridge_width 0.5)
			(island_removal_mode 0)
		)
		(polygon
			(pts
				(arc
					(start 184.365392 -297.032426)
					(mid 184.361672 -297.041406)
					(end 184.352692 -297.045126)
				)
				(arc
					(start 182.879492 -297.045126)
					(mid 182.870512 -297.041406)
					(end 182.866792 -297.032426)
				)
				(arc
					(start 182.866792 -296.537888)
					(mid 182.870512 -296.528908)
					(end 182.879492 -296.525188)
				)
				(arc
					(start 184.352692 -296.525188)
					(mid 184.361672 -296.528908)
					(end 184.365392 -296.537888)
				)
			)
		)
	)
	(zone
		(layer "In1.Cu")
		(hatch none 0.5)
		(connect_pads
			(clearance 0)
		)
		(min_thickness 0.25)
		(keepout
			(tracks not_allowed)
			(vias allowed)
			(pads allowed)
			(copperpour not_allowed)
			(footprints allowed)
		)
		(placement
			(enabled no)
			(sheetname "")
		)
		(fill
			(thermal_gap 0.5)
			(thermal_bridge_width 0.5)
			(island_removal_mode 0)
		)
		(polygon
			(pts
				(arc
					(start 435.749446 -302.982122)
					(mid 435.745726 -302.991102)
					(end 435.736746 -302.994822)
				)
				(arc
					(start 434.263546 -302.994822)
					(mid 434.254566 -302.991102)
					(end 434.250846 -302.982122)
				)
				(arc
					(start 434.250846 -302.487584)
					(mid 434.254566 -302.478604)
					(end 434.263546 -302.474884)
				)
				(arc
					(start 435.736746 -302.474884)
					(mid 435.745726 -302.478604)
					(end 435.749446 -302.487584)
				)
			)
		)
	)
	(zone
		(layer "In1.Cu")
		(hatch none 0.5)
		(connect_pads
			(clearance 0)
		)
		(min_thickness 0.25)
		(keepout
			(tracks not_allowed)
			(vias allowed)
			(pads allowed)
			(copperpour not_allowed)
			(footprints allowed)
		)
		(placement
			(enabled no)
			(sheetname "")
		)
		(fill
			(thermal_gap 0.5)
			(thermal_bridge_width 0.5)
			(island_removal_mode 0)
		)
		(polygon
			(pts
				(arc
					(start 424.761406 -283.43225)
					(mid 424.757686 -283.44123)
					(end 424.748706 -283.44495)
				)
				(arc
					(start 423.275506 -283.44495)
					(mid 423.266526 -283.44123)
					(end 423.262806 -283.43225)
				)
				(arc
					(start 423.262806 -282.937712)
					(mid 423.266526 -282.928732)
					(end 423.275506 -282.925012)
				)
				(arc
					(start 424.748706 -282.925012)
					(mid 424.757686 -282.928732)
					(end 424.761406 -282.937712)
				)
			)
		)
	)
	(zone
		(layer "In1.Cu")
		(hatch none 0.5)
		(connect_pads
			(clearance 0)
		)
		(min_thickness 0.25)
		(keepout
			(tracks not_allowed)
			(vias allowed)
			(pads allowed)
			(copperpour not_allowed)
			(footprints allowed)
		)
		(placement
			(enabled no)
			(sheetname "")
		)
		(fill
			(thermal_gap 0.5)
			(thermal_bridge_width 0.5)
			(island_removal_mode 0)
		)
		(polygon
			(pts
				(arc
					(start 270.397478 -219.682314)
					(mid 270.393758 -219.691294)
					(end 270.384778 -219.695014)
				)
				(arc
					(start 268.911578 -219.695014)
					(mid 268.902598 -219.691294)
					(end 268.898878 -219.682314)
				)
				(arc
					(start 268.898878 -219.187776)
					(mid 268.902598 -219.178796)
					(end 268.911578 -219.175076)
				)
				(arc
					(start 270.384778 -219.175076)
					(mid 270.393758 -219.178796)
					(end 270.397478 -219.187776)
				)
			)
		)
	)
	(zone
		(layer "In1.Cu")
		(hatch none 0.5)
		(connect_pads
			(clearance 0)
		)
		(min_thickness 0.25)
		(keepout
			(tracks not_allowed)
			(vias allowed)
			(pads allowed)
			(copperpour not_allowed)
			(footprints allowed)
		)
		(placement
			(enabled no)
			(sheetname "")
		)
		(fill
			(thermal_gap 0.5)
			(thermal_bridge_width 0.5)
			(island_removal_mode 0)
		)
		(polygon
			(pts
				(arc
					(start 56.077358 -206.082392)
					(mid 56.073638 -206.091372)
					(end 56.064658 -206.095092)
				)
				(arc
					(start 54.591458 -206.095092)
					(mid 54.582478 -206.091372)
					(end 54.578758 -206.082392)
				)
				(arc
					(start 54.578758 -205.587854)
					(mid 54.582478 -205.578874)
					(end 54.591458 -205.575154)
				)
				(arc
					(start 56.064658 -205.575154)
					(mid 56.073638 -205.578874)
					(end 56.077358 -205.587854)
				)
			)
		)
	)
	(zone
		(layer "In1.Cu")
		(hatch none 0.5)
		(connect_pads
			(clearance 0)
		)
		(min_thickness 0.25)
		(keepout
			(tracks not_allowed)
			(vias allowed)
			(pads allowed)
			(copperpour not_allowed)
			(footprints allowed)
		)
		(placement
			(enabled no)
			(sheetname "")
		)
		(fill
			(thermal_gap 0.5)
			(thermal_bridge_width 0.5)
			(island_removal_mode 0)
		)
		(polygon
			(pts
				(arc
					(start 296.473372 -279.182322)
					(mid 296.469652 -279.191302)
					(end 296.460672 -279.195022)
				)
				(arc
					(start 294.987472 -279.195022)
					(mid 294.978492 -279.191302)
					(end 294.974772 -279.182322)
				)
				(arc
					(start 294.974772 -278.687784)
					(mid 294.978492 -278.678804)
					(end 294.987472 -278.675084)
				)
				(arc
					(start 296.460672 -278.675084)
					(mid 296.469652 -278.678804)
					(end 296.473372 -278.687784)
				)
			)
		)
	)
	(zone
		(layer "In1.Cu")
		(hatch none 0.5)
		(connect_pads
			(clearance 0)
		)
		(min_thickness 0.25)
		(keepout
			(tracks not_allowed)
			(vias allowed)
			(pads allowed)
			(copperpour not_allowed)
			(footprints allowed)
		)
		(placement
			(enabled no)
			(sheetname "")
		)
		(fill
			(thermal_gap 0.5)
			(thermal_bridge_width 0.5)
			(island_removal_mode 0)
		)
		(polygon
			(pts
				(arc
					(start 89.698068 -390.761474)
					(mid 89.393268 -390.761474)
					(end 89.698068 -390.761474)
				)
			)
		)
	)
	(zone
		(layer "In1.Cu")
		(hatch none 0.5)
		(connect_pads
			(clearance 0)
		)
		(min_thickness 0.25)
		(keepout
			(tracks not_allowed)
			(vias allowed)
			(pads allowed)
			(copperpour not_allowed)
			(footprints allowed)
		)
		(placement
			(enabled no)
			(sheetname "")
		)
		(fill
			(thermal_gap 0.5)
			(thermal_bridge_width 0.5)
			(island_removal_mode 0)
		)
		(polygon
			(pts
				(arc
					(start 37.545264 -201.832464)
					(mid 37.541544 -201.841444)
					(end 37.532564 -201.845164)
				)
				(arc
					(start 36.059364 -201.845164)
					(mid 36.050384 -201.841444)
					(end 36.046664 -201.832464)
				)
				(arc
					(start 36.046664 -201.337926)
					(mid 36.050384 -201.328946)
					(end 36.059364 -201.325226)
				)
				(arc
					(start 37.532564 -201.325226)
					(mid 37.541544 -201.328946)
					(end 37.545264 -201.337926)
				)
			)
		)
	)
	(zone
		(layer "In1.Cu")
		(hatch none 0.5)
		(connect_pads
			(clearance 0)
		)
		(min_thickness 0.25)
		(keepout
			(tracks not_allowed)
			(vias allowed)
			(pads allowed)
			(copperpour not_allowed)
			(footprints allowed)
		)
		(placement
			(enabled no)
			(sheetname "")
		)
		(fill
			(thermal_gap 0.5)
			(thermal_bridge_width 0.5)
			(island_removal_mode 0)
		)
		(polygon
			(pts
				(arc
					(start 128.49098 -383.440686)
					(mid 128.61798 -383.567686)
					(end 128.74498 -383.440686)
				)
				(arc
					(start 128.74498 -383.364486)
					(mid 128.61798 -383.237486)
					(end 128.49098 -383.364486)
				)
			)
		)
	)
	(zone
		(layer "In1.Cu")
		(hatch none 0.5)
		(connect_pads
			(clearance 0)
		)
		(min_thickness 0.25)
		(keepout
			(tracks not_allowed)
			(vias allowed)
			(pads allowed)
			(copperpour not_allowed)
			(footprints allowed)
		)
		(placement
			(enabled no)
			(sheetname "")
		)
		(fill
			(thermal_gap 0.5)
			(thermal_bridge_width 0.5)
			(island_removal_mode 0)
		)
		(polygon
			(pts
				(arc
					(start 432.30546 -220.532198)
					(mid 432.30174 -220.541178)
					(end 432.29276 -220.544898)
				)
				(arc
					(start 430.81956 -220.544898)
					(mid 430.81058 -220.541178)
					(end 430.80686 -220.532198)
				)
				(arc
					(start 430.80686 -220.03766)
					(mid 430.81058 -220.02868)
					(end 430.81956 -220.02496)
				)
				(arc
					(start 432.29276 -220.02496)
					(mid 432.30174 -220.02868)
					(end 432.30546 -220.03766)
				)
			)
		)
	)
	(zone
		(layer "In1.Cu")
		(hatch none 0.5)
		(connect_pads
			(clearance 0)
		)
		(min_thickness 0.25)
		(keepout
			(tracks not_allowed)
			(vias allowed)
			(pads allowed)
			(copperpour not_allowed)
			(footprints allowed)
		)
		(placement
			(enabled no)
			(sheetname "")
		)
		(fill
			(thermal_gap 0.5)
			(thermal_bridge_width 0.5)
			(island_removal_mode 0)
		)
		(polygon
			(pts
				(arc
					(start 187.809378 -224.78238)
					(mid 187.805658 -224.79136)
					(end 187.796678 -224.79508)
				)
				(arc
					(start 186.323478 -224.79508)
					(mid 186.314498 -224.79136)
					(end 186.310778 -224.78238)
				)
				(arc
					(start 186.310778 -224.287842)
					(mid 186.314498 -224.278862)
					(end 186.323478 -224.275142)
				)
				(arc
					(start 187.796678 -224.275142)
					(mid 187.805658 -224.278862)
					(end 187.809378 -224.287842)
				)
			)
		)
	)
	(zone
		(layer "In1.Cu")
		(hatch none 0.5)
		(connect_pads
			(clearance 0)
		)
		(min_thickness 0.25)
		(keepout
			(tracks not_allowed)
			(vias allowed)
			(pads allowed)
			(copperpour not_allowed)
			(footprints allowed)
		)
		(placement
			(enabled no)
			(sheetname "")
		)
		(fill
			(thermal_gap 0.5)
			(thermal_bridge_width 0.5)
			(island_removal_mode 0)
		)
		(polygon
			(pts
				(arc
					(start 61.061092 -389.467344)
					(mid 60.680092 -389.467344)
					(end 61.061092 -389.467344)
				)
			)
		)
	)
	(zone
		(layer "In1.Cu")
		(hatch none 0.5)
		(connect_pads
			(clearance 0)
		)
		(min_thickness 0.25)
		(keepout
			(tracks not_allowed)
			(vias allowed)
			(pads allowed)
			(copperpour not_allowed)
			(footprints allowed)
		)
		(placement
			(enabled no)
			(sheetname "")
		)
		(fill
			(thermal_gap 0.5)
			(thermal_bridge_width 0.5)
			(island_removal_mode 0)
		)
		(polygon
			(pts
				(arc
					(start 165.177216 -284.282388)
					(mid 165.173496 -284.291368)
					(end 165.164516 -284.295088)
				)
				(arc
					(start 163.691316 -284.295088)
					(mid 163.682336 -284.291368)
					(end 163.678616 -284.282388)
				)
				(arc
					(start 163.678616 -283.78785)
					(mid 163.682336 -283.77887)
					(end 163.691316 -283.77515)
				)
				(arc
					(start 165.164516 -283.77515)
					(mid 165.173496 -283.77887)
					(end 165.177216 -283.78785)
				)
			)
		)
	)
	(zone
		(layer "In1.Cu")
		(hatch none 0.5)
		(connect_pads
			(clearance 0)
		)
		(min_thickness 0.25)
		(keepout
			(tracks not_allowed)
			(vias allowed)
			(pads allowed)
			(copperpour not_allowed)
			(footprints allowed)
		)
		(placement
			(enabled no)
			(sheetname "")
		)
		(fill
			(thermal_gap 0.5)
			(thermal_bridge_width 0.5)
			(island_removal_mode 0)
		)
		(polygon
			(pts
				(arc
					(start 176.821338 -206.93253)
					(mid 176.817618 -206.94151)
					(end 176.808638 -206.94523)
				)
				(arc
					(start 175.335438 -206.94523)
					(mid 175.326458 -206.94151)
					(end 175.322738 -206.93253)
				)
				(arc
					(start 175.322738 -206.437992)
					(mid 175.326458 -206.429012)
					(end 175.335438 -206.425292)
				)
				(arc
					(start 176.808638 -206.425292)
					(mid 176.817618 -206.429012)
					(end 176.821338 -206.437992)
				)
			)
		)
	)
	(zone
		(layer "In1.Cu")
		(hatch none 0.5)
		(connect_pads
			(clearance 0)
		)
		(min_thickness 0.25)
		(keepout
			(tracks not_allowed)
			(vias allowed)
			(pads allowed)
			(copperpour not_allowed)
			(footprints allowed)
		)
		(placement
			(enabled no)
			(sheetname "")
		)
		(fill
			(thermal_gap 0.5)
			(thermal_bridge_width 0.5)
			(island_removal_mode 0)
		)
		(polygon
			(pts
				(arc
					(start 56.077358 -308.93258)
					(mid 56.073638 -308.94156)
					(end 56.064658 -308.94528)
				)
				(arc
					(start 54.591458 -308.94528)
					(mid 54.582478 -308.94156)
					(end 54.578758 -308.93258)
				)
				(arc
					(start 54.578758 -308.438042)
					(mid 54.582478 -308.429062)
					(end 54.591458 -308.425342)
				)
				(arc
					(start 56.064658 -308.425342)
					(mid 56.073638 -308.429062)
					(end 56.077358 -308.438042)
				)
			)
		)
	)
	(zone
		(layer "In1.Cu")
		(hatch none 0.5)
		(connect_pads
			(clearance 0)
		)
		(min_thickness 0.25)
		(keepout
			(tracks not_allowed)
			(vias allowed)
			(pads allowed)
			(copperpour not_allowed)
			(footprints allowed)
		)
		(placement
			(enabled no)
			(sheetname "")
		)
		(fill
			(thermal_gap 0.5)
			(thermal_bridge_width 0.5)
			(island_removal_mode 0)
		)
		(polygon
			(pts
				(arc
					(start 40.98925 -307.232558)
					(mid 40.98553 -307.241538)
					(end 40.97655 -307.245258)
				)
				(arc
					(start 39.50335 -307.245258)
					(mid 39.49437 -307.241538)
					(end 39.49065 -307.232558)
				)
				(arc
					(start 39.49065 -306.73802)
					(mid 39.49437 -306.72904)
					(end 39.50335 -306.72532)
				)
				(arc
					(start 40.97655 -306.72532)
					(mid 40.98553 -306.72904)
					(end 40.98925 -306.73802)
				)
			)
		)
	)
	(zone
		(layer "In1.Cu")
		(hatch none 0.5)
		(connect_pads
			(clearance 0)
		)
		(min_thickness 0.25)
		(keepout
			(tracks not_allowed)
			(vias allowed)
			(pads allowed)
			(copperpour not_allowed)
			(footprints allowed)
		)
		(placement
			(enabled no)
			(sheetname "")
		)
		(fill
			(thermal_gap 0.5)
			(thermal_bridge_width 0.5)
			(island_removal_mode 0)
		)
		(polygon
			(pts
				(arc
					(start 172.72127 -230.732584)
					(mid 172.71755 -230.741564)
					(end 172.70857 -230.745284)
				)
				(arc
					(start 171.23537 -230.745284)
					(mid 171.22639 -230.741564)
					(end 171.22267 -230.732584)
				)
				(arc
					(start 171.22267 -230.238046)
					(mid 171.22639 -230.229066)
					(end 171.23537 -230.225346)
				)
				(arc
					(start 172.70857 -230.225346)
					(mid 172.71755 -230.229066)
					(end 172.72127 -230.238046)
				)
			)
		)
	)
	(zone
		(layer "In1.Cu")
		(hatch none 0.5)
		(connect_pads
			(clearance 0)
		)
		(min_thickness 0.25)
		(keepout
			(tracks not_allowed)
			(vias allowed)
			(pads allowed)
			(copperpour not_allowed)
			(footprints allowed)
		)
		(placement
			(enabled no)
			(sheetname "")
		)
		(fill
			(thermal_gap 0.5)
			(thermal_bridge_width 0.5)
			(island_removal_mode 0)
		)
		(polygon
			(pts
				(arc
					(start 266.29741 -277.4823)
					(mid 266.29369 -277.49128)
					(end 266.28471 -277.495)
				)
				(arc
					(start 264.81151 -277.495)
					(mid 264.80253 -277.49128)
					(end 264.79881 -277.4823)
				)
				(arc
					(start 264.79881 -276.987762)
					(mid 264.80253 -276.978782)
					(end 264.81151 -276.975062)
				)
				(arc
					(start 266.28471 -276.975062)
					(mid 266.29369 -276.978782)
					(end 266.29741 -276.987762)
				)
			)
		)
	)
	(zone
		(layer "In1.Cu")
		(hatch none 0.5)
		(connect_pads
			(clearance 0)
		)
		(min_thickness 0.25)
		(keepout
			(tracks not_allowed)
			(vias allowed)
			(pads allowed)
			(copperpour not_allowed)
			(footprints allowed)
		)
		(placement
			(enabled no)
			(sheetname "")
		)
		(fill
			(thermal_gap 0.5)
			(thermal_bridge_width 0.5)
			(island_removal_mode 0)
		)
		(polygon
			(pts
				(arc
					(start 435.749446 -274.93214)
					(mid 435.745726 -274.94112)
					(end 435.736746 -274.94484)
				)
				(arc
					(start 434.263546 -274.94484)
					(mid 434.254566 -274.94112)
					(end 434.250846 -274.93214)
				)
				(arc
					(start 434.250846 -274.437602)
					(mid 434.254566 -274.428622)
					(end 434.263546 -274.424902)
				)
				(arc
					(start 435.736746 -274.424902)
					(mid 435.745726 -274.428622)
					(end 435.749446 -274.437602)
				)
			)
		)
	)
	(zone
		(layer "In1.Cu")
		(hatch none 0.5)
		(connect_pads
			(clearance 0)
		)
		(min_thickness 0.25)
		(keepout
			(tracks not_allowed)
			(vias allowed)
			(pads allowed)
			(copperpour not_allowed)
			(footprints allowed)
		)
		(placement
			(enabled no)
			(sheetname "")
		)
		(fill
			(thermal_gap 0.5)
			(thermal_bridge_width 0.5)
			(island_removal_mode 0)
		)
		(polygon
			(pts
				(arc
					(start 48.533304 -254.532384)
					(mid 48.529584 -254.541364)
					(end 48.520604 -254.545084)
				)
				(arc
					(start 47.047404 -254.545084)
					(mid 47.038424 -254.541364)
					(end 47.034704 -254.532384)
				)
				(arc
					(start 47.034704 -254.037846)
					(mid 47.038424 -254.028866)
					(end 47.047404 -254.025146)
				)
				(arc
					(start 48.520604 -254.025146)
					(mid 48.529584 -254.028866)
					(end 48.533304 -254.037846)
				)
			)
		)
	)
	(zone
		(layer "In1.Cu")
		(hatch none 0.5)
		(connect_pads
			(clearance 0)
		)
		(min_thickness 0.25)
		(keepout
			(tracks not_allowed)
			(vias allowed)
			(pads allowed)
			(copperpour not_allowed)
			(footprints allowed)
		)
		(placement
			(enabled no)
			(sheetname "")
		)
		(fill
			(thermal_gap 0.5)
			(thermal_bridge_width 0.5)
			(island_removal_mode 0)
		)
		(polygon
			(pts
				(arc
					(start 30.001464 -285.98241)
					(mid 29.997744 -285.99139)
					(end 29.988764 -285.99511)
				)
				(arc
					(start 28.515564 -285.99511)
					(mid 28.506584 -285.99139)
					(end 28.502864 -285.98241)
				)
				(arc
					(start 28.502864 -285.487872)
					(mid 28.506584 -285.478892)
					(end 28.515564 -285.475172)
				)
				(arc
					(start 29.988764 -285.475172)
					(mid 29.997744 -285.478892)
					(end 30.001464 -285.487872)
				)
			)
		)
	)
	(zone
		(layer "In1.Cu")
		(hatch none 0.5)
		(connect_pads
			(clearance 0)
		)
		(min_thickness 0.25)
		(keepout
			(tracks not_allowed)
			(vias allowed)
			(pads allowed)
			(copperpour not_allowed)
			(footprints allowed)
		)
		(placement
			(enabled no)
			(sheetname "")
		)
		(fill
			(thermal_gap 0.5)
			(thermal_bridge_width 0.5)
			(island_removal_mode 0)
		)
		(polygon
			(pts
				(arc
					(start 300.57344 -285.132272)
					(mid 300.56972 -285.141252)
					(end 300.56074 -285.144972)
				)
				(arc
					(start 299.08754 -285.144972)
					(mid 299.07856 -285.141252)
					(end 299.07484 -285.132272)
				)
				(arc
					(start 299.07484 -284.637734)
					(mid 299.07856 -284.628754)
					(end 299.08754 -284.625034)
				)
				(arc
					(start 300.56074 -284.625034)
					(mid 300.56972 -284.628754)
					(end 300.57344 -284.637734)
				)
			)
		)
	)
	(zone
		(layer "In1.Cu")
		(hatch none 0.5)
		(connect_pads
			(clearance 0)
		)
		(min_thickness 0.25)
		(keepout
			(tracks not_allowed)
			(vias allowed)
			(pads allowed)
			(copperpour not_allowed)
			(footprints allowed)
		)
		(placement
			(enabled no)
			(sheetname "")
		)
		(fill
			(thermal_gap 0.5)
			(thermal_bridge_width 0.5)
			(island_removal_mode 0)
		)
		(polygon
			(pts
				(arc
					(start 273.841464 -293.632128)
					(mid 273.837744 -293.641108)
					(end 273.828764 -293.644828)
				)
				(arc
					(start 272.355564 -293.644828)
					(mid 272.346584 -293.641108)
					(end 272.342864 -293.632128)
				)
				(arc
					(start 272.342864 -293.13759)
					(mid 272.346584 -293.12861)
					(end 272.355564 -293.12489)
				)
				(arc
					(start 273.828764 -293.12489)
					(mid 273.837744 -293.12861)
					(end 273.841464 -293.13759)
				)
			)
		)
	)
	(zone
		(layer "In1.Cu")
		(hatch none 0.5)
		(connect_pads
			(clearance 0)
		)
		(min_thickness 0.25)
		(keepout
			(tracks not_allowed)
			(vias allowed)
			(pads allowed)
			(copperpour not_allowed)
			(footprints allowed)
		)
		(placement
			(enabled no)
			(sheetname "")
		)
		(fill
			(thermal_gap 0.5)
			(thermal_bridge_width 0.5)
			(island_removal_mode 0)
		)
		(polygon
			(pts
				(arc
					(start 310.190896 -399.701258)
					(mid 310.317896 -399.828258)
					(end 310.444896 -399.701258)
				)
				(arc
					(start 310.444896 -399.625058)
					(mid 310.317896 -399.498058)
					(end 310.190896 -399.625058)
				)
			)
		)
	)
	(zone
		(layer "In1.Cu")
		(hatch none 0.5)
		(connect_pads
			(clearance 0)
		)
		(min_thickness 0.25)
		(keepout
			(tracks not_allowed)
			(vias allowed)
			(pads allowed)
			(copperpour not_allowed)
			(footprints allowed)
		)
		(placement
			(enabled no)
			(sheetname "")
		)
		(fill
			(thermal_gap 0.5)
			(thermal_bridge_width 0.5)
			(island_removal_mode 0)
		)
		(polygon
			(pts
				(arc
					(start 83.98891 -386.003292)
					(mid 83.60791 -386.003292)
					(end 83.98891 -386.003292)
				)
			)
		)
	)
	(zone
		(layer "In1.Cu")
		(hatch none 0.5)
		(connect_pads
			(clearance 0)
		)
		(min_thickness 0.25)
		(keepout
			(tracks not_allowed)
			(vias allowed)
			(pads allowed)
			(copperpour not_allowed)
			(footprints allowed)
		)
		(placement
			(enabled no)
			(sheetname "")
		)
		(fill
			(thermal_gap 0.5)
			(thermal_bridge_width 0.5)
			(island_removal_mode 0)
		)
		(polygon
			(pts
				(arc
					(start 285.485332 -263.03224)
					(mid 285.481612 -263.04122)
					(end 285.472632 -263.04494)
				)
				(arc
					(start 283.999432 -263.04494)
					(mid 283.990452 -263.04122)
					(end 283.986732 -263.03224)
				)
				(arc
					(start 283.986732 -262.537702)
					(mid 283.990452 -262.528722)
					(end 283.999432 -262.525002)
				)
				(arc
					(start 285.472632 -262.525002)
					(mid 285.481612 -262.528722)
					(end 285.485332 -262.537702)
				)
			)
		)
	)
	(zone
		(layer "In1.Cu")
		(hatch none 0.5)
		(connect_pads
			(clearance 0)
		)
		(min_thickness 0.25)
		(keepout
			(tracks not_allowed)
			(vias allowed)
			(pads allowed)
			(copperpour not_allowed)
			(footprints allowed)
		)
		(placement
			(enabled no)
			(sheetname "")
		)
		(fill
			(thermal_gap 0.5)
			(thermal_bridge_width 0.5)
			(island_removal_mode 0)
		)
		(polygon
			(pts
				(arc
					(start 300.57344 -210.33232)
					(mid 300.56972 -210.3413)
					(end 300.56074 -210.34502)
				)
				(arc
					(start 299.08754 -210.34502)
					(mid 299.07856 -210.3413)
					(end 299.07484 -210.33232)
				)
				(arc
					(start 299.07484 -209.837782)
					(mid 299.07856 -209.828802)
					(end 299.08754 -209.825082)
				)
				(arc
					(start 300.56074 -209.825082)
					(mid 300.56972 -209.828802)
					(end 300.57344 -209.837782)
				)
			)
		)
	)
	(zone
		(layer "In1.Cu")
		(hatch none 0.5)
		(connect_pads
			(clearance 0)
		)
		(min_thickness 0.25)
		(keepout
			(tracks not_allowed)
			(vias allowed)
			(pads allowed)
			(copperpour not_allowed)
			(footprints allowed)
		)
		(placement
			(enabled no)
			(sheetname "")
		)
		(fill
			(thermal_gap 0.5)
			(thermal_bridge_width 0.5)
			(island_removal_mode 0)
		)
		(polygon
			(pts
				(arc
					(start 296.473372 -204.382116)
					(mid 296.469652 -204.391096)
					(end 296.460672 -204.394816)
				)
				(arc
					(start 294.987472 -204.394816)
					(mid 294.978492 -204.391096)
					(end 294.974772 -204.382116)
				)
				(arc
					(start 294.974772 -203.887578)
					(mid 294.978492 -203.878598)
					(end 294.987472 -203.874878)
				)
				(arc
					(start 296.460672 -203.874878)
					(mid 296.469652 -203.878598)
					(end 296.473372 -203.887578)
				)
			)
		)
	)
	(zone
		(layer "In1.Cu")
		(hatch none 0.5)
		(connect_pads
			(clearance 0)
		)
		(min_thickness 0.25)
		(keepout
			(tracks not_allowed)
			(vias allowed)
			(pads allowed)
			(copperpour not_allowed)
			(footprints allowed)
		)
		(placement
			(enabled no)
			(sheetname "")
		)
		(fill
			(thermal_gap 0.5)
			(thermal_bridge_width 0.5)
			(island_removal_mode 0)
		)
		(polygon
			(pts
				(arc
					(start 56.077358 -263.882378)
					(mid 56.073638 -263.891358)
					(end 56.064658 -263.895078)
				)
				(arc
					(start 54.591458 -263.895078)
					(mid 54.582478 -263.891358)
					(end 54.578758 -263.882378)
				)
				(arc
					(start 54.578758 -263.38784)
					(mid 54.582478 -263.37886)
					(end 54.591458 -263.37514)
				)
				(arc
					(start 56.064658 -263.37514)
					(mid 56.073638 -263.37886)
					(end 56.077358 -263.38784)
				)
			)
		)
	)
	(zone
		(layer "In1.Cu")
		(hatch none 0.5)
		(connect_pads
			(clearance 0)
		)
		(min_thickness 0.25)
		(keepout
			(tracks not_allowed)
			(vias allowed)
			(pads allowed)
			(copperpour not_allowed)
			(footprints allowed)
		)
		(placement
			(enabled no)
			(sheetname "")
		)
		(fill
			(thermal_gap 0.5)
			(thermal_bridge_width 0.5)
			(island_removal_mode 0)
		)
		(polygon
			(pts
				(arc
					(start 199.4535 -289.382454)
					(mid 199.44978 -289.391434)
					(end 199.4408 -289.395154)
				)
				(arc
					(start 197.9676 -289.395154)
					(mid 197.95862 -289.391434)
					(end 197.9549 -289.382454)
				)
				(arc
					(start 197.9549 -288.887916)
					(mid 197.95862 -288.878936)
					(end 197.9676 -288.875216)
				)
				(arc
					(start 199.4408 -288.875216)
					(mid 199.44978 -288.878936)
					(end 199.4535 -288.887916)
				)
			)
		)
	)
	(zone
		(layer "In1.Cu")
		(hatch none 0.5)
		(connect_pads
			(clearance 0)
		)
		(min_thickness 0.25)
		(keepout
			(tracks not_allowed)
			(vias allowed)
			(pads allowed)
			(copperpour not_allowed)
			(footprints allowed)
		)
		(placement
			(enabled no)
			(sheetname "")
		)
		(fill
			(thermal_gap 0.5)
			(thermal_bridge_width 0.5)
			(island_removal_mode 0)
		)
		(polygon
			(pts
				(arc
					(start 266.29741 -241.782092)
					(mid 266.29369 -241.791072)
					(end 266.28471 -241.794792)
				)
				(arc
					(start 264.81151 -241.794792)
					(mid 264.80253 -241.791072)
					(end 264.79881 -241.782092)
				)
				(arc
					(start 264.79881 -241.287554)
					(mid 264.80253 -241.278574)
					(end 264.81151 -241.274854)
				)
				(arc
					(start 266.28471 -241.274854)
					(mid 266.29369 -241.278574)
					(end 266.29741 -241.287554)
				)
			)
		)
	)
	(zone
		(layer "In1.Cu")
		(hatch none 0.5)
		(connect_pads
			(clearance 0)
		)
		(min_thickness 0.25)
		(keepout
			(tracks not_allowed)
			(vias allowed)
			(pads allowed)
			(copperpour not_allowed)
			(footprints allowed)
		)
		(placement
			(enabled no)
			(sheetname "")
		)
		(fill
			(thermal_gap 0.5)
			(thermal_bridge_width 0.5)
			(island_removal_mode 0)
		)
		(polygon
			(pts
				(arc
					(start 202.897232 -277.482554)
					(mid 202.893512 -277.491534)
					(end 202.884532 -277.495254)
				)
				(arc
					(start 201.411332 -277.495254)
					(mid 201.402352 -277.491534)
					(end 201.398632 -277.482554)
				)
				(arc
					(start 201.398632 -276.988016)
					(mid 201.402352 -276.979036)
					(end 201.411332 -276.975316)
				)
				(arc
					(start 202.884532 -276.975316)
					(mid 202.893512 -276.979036)
					(end 202.897232 -276.988016)
				)
			)
		)
	)
	(zone
		(layer "In1.Cu")
		(hatch none 0.5)
		(connect_pads
			(clearance 0)
		)
		(min_thickness 0.25)
		(keepout
			(tracks not_allowed)
			(vias allowed)
			(pads allowed)
			(copperpour not_allowed)
			(footprints allowed)
		)
		(placement
			(enabled no)
			(sheetname "")
		)
		(fill
			(thermal_gap 0.5)
			(thermal_bridge_width 0.5)
			(island_removal_mode 0)
		)
		(polygon
			(pts
				(arc
					(start 56.077358 -291.93236)
					(mid 56.073638 -291.94134)
					(end 56.064658 -291.94506)
				)
				(arc
					(start 54.591458 -291.94506)
					(mid 54.582478 -291.94134)
					(end 54.578758 -291.93236)
				)
				(arc
					(start 54.578758 -291.437822)
					(mid 54.582478 -291.428842)
					(end 54.591458 -291.425122)
				)
				(arc
					(start 56.064658 -291.425122)
					(mid 56.073638 -291.428842)
					(end 56.077358 -291.437822)
				)
			)
		)
	)
	(zone
		(layer "In1.Cu")
		(hatch none 0.5)
		(connect_pads
			(clearance 0)
		)
		(min_thickness 0.25)
		(keepout
			(tracks not_allowed)
			(vias allowed)
			(pads allowed)
			(copperpour not_allowed)
			(footprints allowed)
		)
		(placement
			(enabled no)
			(sheetname "")
		)
		(fill
			(thermal_gap 0.5)
			(thermal_bridge_width 0.5)
			(island_removal_mode 0)
		)
		(polygon
			(pts
				(arc
					(start 378.490988 -399.701258)
					(mid 378.617988 -399.828258)
					(end 378.744988 -399.701258)
				)
				(arc
					(start 378.744988 -399.625058)
					(mid 378.617988 -399.498058)
					(end 378.490988 -399.625058)
				)
			)
		)
	)
	(zone
		(layer "In1.Cu")
		(hatch none 0.5)
		(connect_pads
			(clearance 0)
		)
		(min_thickness 0.25)
		(keepout
			(tracks not_allowed)
			(vias allowed)
			(pads allowed)
			(copperpour not_allowed)
			(footprints allowed)
		)
		(placement
			(enabled no)
			(sheetname "")
		)
		(fill
			(thermal_gap 0.5)
			(thermal_bridge_width 0.5)
			(island_removal_mode 0)
		)
		(polygon
			(pts
				(arc
					(start 206.9973 -272.382488)
					(mid 206.99358 -272.391468)
					(end 206.9846 -272.395188)
				)
				(arc
					(start 205.5114 -272.395188)
					(mid 205.50242 -272.391468)
					(end 205.4987 -272.382488)
				)
				(arc
					(start 205.4987 -271.88795)
					(mid 205.50242 -271.87897)
					(end 205.5114 -271.87525)
				)
				(arc
					(start 206.9846 -271.87525)
					(mid 206.99358 -271.87897)
					(end 206.9973 -271.88795)
				)
			)
		)
	)
	(zone
		(layer "In1.Cu")
		(hatch none 0.5)
		(connect_pads
			(clearance 0)
		)
		(min_thickness 0.25)
		(keepout
			(tracks not_allowed)
			(vias allowed)
			(pads allowed)
			(copperpour not_allowed)
			(footprints allowed)
		)
		(placement
			(enabled no)
			(sheetname "")
		)
		(fill
			(thermal_gap 0.5)
			(thermal_bridge_width 0.5)
			(island_removal_mode 0)
		)
		(polygon
			(pts
				(arc
					(start 296.473372 -296.182288)
					(mid 296.469652 -296.191268)
					(end 296.460672 -296.194988)
				)
				(arc
					(start 294.987472 -296.194988)
					(mid 294.978492 -296.191268)
					(end 294.974772 -296.182288)
				)
				(arc
					(start 294.974772 -295.68775)
					(mid 294.978492 -295.67877)
					(end 294.987472 -295.67505)
				)
				(arc
					(start 296.460672 -295.67505)
					(mid 296.469652 -295.67877)
					(end 296.473372 -295.68775)
				)
			)
		)
	)
	(zone
		(layer "In1.Cu")
		(hatch none 0.5)
		(connect_pads
			(clearance 0)
		)
		(min_thickness 0.25)
		(keepout
			(tracks not_allowed)
			(vias allowed)
			(pads allowed)
			(copperpour not_allowed)
			(footprints allowed)
		)
		(placement
			(enabled no)
			(sheetname "")
		)
		(fill
			(thermal_gap 0.5)
			(thermal_bridge_width 0.5)
			(island_removal_mode 0)
		)
		(polygon
			(pts
				(arc
					(start 172.72127 -280.882344)
					(mid 172.71755 -280.891324)
					(end 172.70857 -280.895044)
				)
				(arc
					(start 171.23537 -280.895044)
					(mid 171.22639 -280.891324)
					(end 171.22267 -280.882344)
				)
				(arc
					(start 171.22267 -280.387806)
					(mid 171.22639 -280.378826)
					(end 171.23537 -280.375106)
				)
				(arc
					(start 172.70857 -280.375106)
					(mid 172.71755 -280.378826)
					(end 172.72127 -280.387806)
				)
			)
		)
	)
	(zone
		(layer "In1.Cu")
		(hatch none 0.5)
		(connect_pads
			(clearance 0)
		)
		(min_thickness 0.25)
		(keepout
			(tracks not_allowed)
			(vias allowed)
			(pads allowed)
			(copperpour not_allowed)
			(footprints allowed)
		)
		(placement
			(enabled no)
			(sheetname "")
		)
		(fill
			(thermal_gap 0.5)
			(thermal_bridge_width 0.5)
			(island_removal_mode 0)
		)
		(polygon
			(pts
				(arc
					(start 195.353432 -215.432386)
					(mid 195.349712 -215.441366)
					(end 195.340732 -215.445086)
				)
				(arc
					(start 193.867532 -215.445086)
					(mid 193.858552 -215.441366)
					(end 193.854832 -215.432386)
				)
				(arc
					(start 193.854832 -214.937848)
					(mid 193.858552 -214.928868)
					(end 193.867532 -214.925148)
				)
				(arc
					(start 195.340732 -214.925148)
					(mid 195.349712 -214.928868)
					(end 195.353432 -214.937848)
				)
			)
		)
	)
	(zone
		(layer "In1.Cu")
		(hatch none 0.5)
		(connect_pads
			(clearance 0)
		)
		(min_thickness 0.25)
		(keepout
			(tracks not_allowed)
			(vias allowed)
			(pads allowed)
			(copperpour not_allowed)
			(footprints allowed)
		)
		(placement
			(enabled no)
			(sheetname "")
		)
		(fill
			(thermal_gap 0.5)
			(thermal_bridge_width 0.5)
			(island_removal_mode 0)
		)
		(polygon
			(pts
				(arc
					(start 288.929318 -198.432166)
					(mid 288.925598 -198.441146)
					(end 288.916618 -198.444866)
				)
				(arc
					(start 287.443418 -198.444866)
					(mid 287.434438 -198.441146)
					(end 287.430718 -198.432166)
				)
				(arc
					(start 287.430718 -197.937628)
					(mid 287.434438 -197.928648)
					(end 287.443418 -197.924928)
				)
				(arc
					(start 288.916618 -197.924928)
					(mid 288.925598 -197.928648)
					(end 288.929318 -197.937628)
				)
			)
		)
	)
	(zone
		(layer "In1.Cu")
		(hatch none 0.5)
		(connect_pads
			(clearance 0)
		)
		(min_thickness 0.25)
		(keepout
			(tracks not_allowed)
			(vias allowed)
			(pads allowed)
			(copperpour not_allowed)
			(footprints allowed)
		)
		(placement
			(enabled no)
			(sheetname "")
		)
		(fill
			(thermal_gap 0.5)
			(thermal_bridge_width 0.5)
			(island_removal_mode 0)
		)
		(polygon
			(pts
				(arc
					(start 22.45741 -211.182458)
					(mid 22.45369 -211.191438)
					(end 22.44471 -211.195158)
				)
				(arc
					(start 20.97151 -211.195158)
					(mid 20.96253 -211.191438)
					(end 20.95881 -211.182458)
				)
				(arc
					(start 20.95881 -210.68792)
					(mid 20.96253 -210.67894)
					(end 20.97151 -210.67522)
				)
				(arc
					(start 22.44471 -210.67522)
					(mid 22.45369 -210.67894)
					(end 22.45741 -210.68792)
				)
			)
		)
	)
	(zone
		(layer "In1.Cu")
		(hatch none 0.5)
		(connect_pads
			(clearance 0)
		)
		(min_thickness 0.25)
		(keepout
			(tracks not_allowed)
			(vias allowed)
			(pads allowed)
			(copperpour not_allowed)
			(footprints allowed)
		)
		(placement
			(enabled no)
			(sheetname "")
		)
		(fill
			(thermal_gap 0.5)
			(thermal_bridge_width 0.5)
			(island_removal_mode 0)
		)
		(polygon
			(pts
				(arc
					(start 281.385264 -314.032138)
					(mid 281.381544 -314.041118)
					(end 281.372564 -314.044838)
				)
				(arc
					(start 279.899364 -314.044838)
					(mid 279.890384 -314.041118)
					(end 279.886664 -314.032138)
				)
				(arc
					(start 279.886664 -313.5376)
					(mid 279.890384 -313.52862)
					(end 279.899364 -313.5249)
				)
				(arc
					(start 281.372564 -313.5249)
					(mid 281.381544 -313.52862)
					(end 281.385264 -313.5376)
				)
			)
		)
	)
	(zone
		(layer "In1.Cu")
		(hatch none 0.5)
		(connect_pads
			(clearance 0)
		)
		(min_thickness 0.25)
		(keepout
			(tracks not_allowed)
			(vias allowed)
			(pads allowed)
			(copperpour not_allowed)
			(footprints allowed)
		)
		(placement
			(enabled no)
			(sheetname "")
		)
		(fill
			(thermal_gap 0.5)
			(thermal_bridge_width 0.5)
			(island_removal_mode 0)
		)
		(polygon
			(pts
				(arc
					(start 337.18881 -393.69238)
					(mid 336.80781 -393.69238)
					(end 337.18881 -393.69238)
				)
			)
		)
	)
	(zone
		(layer "In1.Cu")
		(hatch none 0.5)
		(connect_pads
			(clearance 0)
		)
		(min_thickness 0.25)
		(keepout
			(tracks not_allowed)
			(vias allowed)
			(pads allowed)
			(copperpour not_allowed)
			(footprints allowed)
		)
		(placement
			(enabled no)
			(sheetname "")
		)
		(fill
			(thermal_gap 0.5)
			(thermal_bridge_width 0.5)
			(island_removal_mode 0)
		)
		(polygon
			(pts
				(arc
					(start 266.29741 -265.582146)
					(mid 266.29369 -265.591126)
					(end 266.28471 -265.594846)
				)
				(arc
					(start 264.81151 -265.594846)
					(mid 264.80253 -265.591126)
					(end 264.79881 -265.582146)
				)
				(arc
					(start 264.79881 -265.087608)
					(mid 264.80253 -265.078628)
					(end 264.81151 -265.074908)
				)
				(arc
					(start 266.28471 -265.074908)
					(mid 266.29369 -265.078628)
					(end 266.29741 -265.087608)
				)
			)
		)
	)
	(zone
		(layer "In1.Cu")
		(hatch none 0.5)
		(connect_pads
			(clearance 0)
		)
		(min_thickness 0.25)
		(keepout
			(tracks not_allowed)
			(vias allowed)
			(pads allowed)
			(copperpour not_allowed)
			(footprints allowed)
		)
		(placement
			(enabled no)
			(sheetname "")
		)
		(fill
			(thermal_gap 0.5)
			(thermal_bridge_width 0.5)
			(island_removal_mode 0)
		)
		(polygon
			(pts
				(arc
					(start 270.397478 -291.082222)
					(mid 270.393758 -291.091202)
					(end 270.384778 -291.094922)
				)
				(arc
					(start 268.911578 -291.094922)
					(mid 268.902598 -291.091202)
					(end 268.898878 -291.082222)
				)
				(arc
					(start 268.898878 -290.587684)
					(mid 268.902598 -290.578704)
					(end 268.911578 -290.574984)
				)
				(arc
					(start 270.384778 -290.574984)
					(mid 270.393758 -290.578704)
					(end 270.397478 -290.587684)
				)
			)
		)
	)
	(zone
		(layer "In1.Cu")
		(hatch none 0.5)
		(connect_pads
			(clearance 0)
		)
		(min_thickness 0.25)
		(keepout
			(tracks not_allowed)
			(vias allowed)
			(pads allowed)
			(copperpour not_allowed)
			(footprints allowed)
		)
		(placement
			(enabled no)
			(sheetname "")
		)
		(fill
			(thermal_gap 0.5)
			(thermal_bridge_width 0.5)
			(island_removal_mode 0)
		)
		(polygon
			(pts
				(arc
					(start 428.205392 -267.282168)
					(mid 428.201672 -267.291148)
					(end 428.192692 -267.294868)
				)
				(arc
					(start 426.719492 -267.294868)
					(mid 426.710512 -267.291148)
					(end 426.706792 -267.282168)
				)
				(arc
					(start 426.706792 -266.78763)
					(mid 426.710512 -266.77865)
					(end 426.719492 -266.77493)
				)
				(arc
					(start 428.192692 -266.77493)
					(mid 428.201672 -266.77865)
					(end 428.205392 -266.78763)
				)
			)
		)
	)
	(zone
		(layer "In1.Cu")
		(hatch none 0.5)
		(connect_pads
			(clearance 0)
		)
		(min_thickness 0.25)
		(keepout
			(tracks not_allowed)
			(vias allowed)
			(pads allowed)
			(copperpour not_allowed)
			(footprints allowed)
		)
		(placement
			(enabled no)
			(sheetname "")
		)
		(fill
			(thermal_gap 0.5)
			(thermal_bridge_width 0.5)
			(island_removal_mode 0)
		)
		(polygon
			(pts
				(arc
					(start 187.809378 -296.182542)
					(mid 187.805658 -296.191522)
					(end 187.796678 -296.195242)
				)
				(arc
					(start 186.323478 -296.195242)
					(mid 186.314498 -296.191522)
					(end 186.310778 -296.182542)
				)
				(arc
					(start 186.310778 -295.688004)
					(mid 186.314498 -295.679024)
					(end 186.323478 -295.675304)
				)
				(arc
					(start 187.796678 -295.675304)
					(mid 187.805658 -295.679024)
					(end 187.809378 -295.688004)
				)
			)
		)
	)
	(zone
		(layer "In1.Cu")
		(hatch none 0.5)
		(connect_pads
			(clearance 0)
		)
		(min_thickness 0.25)
		(keepout
			(tracks not_allowed)
			(vias allowed)
			(pads allowed)
			(copperpour not_allowed)
			(footprints allowed)
		)
		(placement
			(enabled no)
			(sheetname "")
		)
		(fill
			(thermal_gap 0.5)
			(thermal_bridge_width 0.5)
			(island_removal_mode 0)
		)
		(polygon
			(pts
				(arc
					(start 300.57344 -315.73216)
					(mid 300.56972 -315.74114)
					(end 300.56074 -315.74486)
				)
				(arc
					(start 299.08754 -315.74486)
					(mid 299.07856 -315.74114)
					(end 299.07484 -315.73216)
				)
				(arc
					(start 299.07484 -315.237622)
					(mid 299.07856 -315.228642)
					(end 299.08754 -315.224922)
				)
				(arc
					(start 300.56074 -315.224922)
					(mid 300.56972 -315.228642)
					(end 300.57344 -315.237622)
				)
			)
		)
	)
	(zone
		(layer "In1.Cu")
		(hatch none 0.5)
		(connect_pads
			(clearance 0)
		)
		(min_thickness 0.25)
		(keepout
			(tracks not_allowed)
			(vias allowed)
			(pads allowed)
			(copperpour not_allowed)
			(footprints allowed)
		)
		(placement
			(enabled no)
			(sheetname "")
		)
		(fill
			(thermal_gap 0.5)
			(thermal_bridge_width 0.5)
			(island_removal_mode 0)
		)
		(polygon
			(pts
				(arc
					(start 443.2935 -253.682246)
					(mid 443.28978 -253.691226)
					(end 443.2808 -253.694946)
				)
				(arc
					(start 441.8076 -253.694946)
					(mid 441.79862 -253.691226)
					(end 441.7949 -253.682246)
				)
				(arc
					(start 441.7949 -253.187708)
					(mid 441.79862 -253.178728)
					(end 441.8076 -253.175008)
				)
				(arc
					(start 443.2808 -253.175008)
					(mid 443.28978 -253.178728)
					(end 443.2935 -253.187708)
				)
			)
		)
	)
	(zone
		(layer "In1.Cu")
		(hatch none 0.5)
		(connect_pads
			(clearance 0)
		)
		(min_thickness 0.25)
		(keepout
			(tracks not_allowed)
			(vias allowed)
			(pads allowed)
			(copperpour not_allowed)
			(footprints allowed)
		)
		(placement
			(enabled no)
			(sheetname "")
		)
		(fill
			(thermal_gap 0.5)
			(thermal_bridge_width 0.5)
			(island_removal_mode 0)
		)
		(polygon
			(pts
				(arc
					(start 60.770516 -390.761474)
					(mid 60.465716 -390.761474)
					(end 60.770516 -390.761474)
				)
			)
		)
	)
	(zone
		(layer "In1.Cu")
		(hatch none 0.5)
		(connect_pads
			(clearance 0)
		)
		(min_thickness 0.25)
		(keepout
			(tracks not_allowed)
			(vias allowed)
			(pads allowed)
			(copperpour not_allowed)
			(footprints allowed)
		)
		(placement
			(enabled no)
			(sheetname "")
		)
		(fill
			(thermal_gap 0.5)
			(thermal_bridge_width 0.5)
			(island_removal_mode 0)
		)
		(polygon
			(pts
				(arc
					(start 454.937368 -280.032206)
					(mid 454.933648 -280.041186)
					(end 454.924668 -280.044906)
				)
				(arc
					(start 453.451468 -280.044906)
					(mid 453.442488 -280.041186)
					(end 453.438768 -280.032206)
				)
				(arc
					(start 453.438768 -279.537668)
					(mid 453.442488 -279.528688)
					(end 453.451468 -279.524968)
				)
				(arc
					(start 454.924668 -279.524968)
					(mid 454.933648 -279.528688)
					(end 454.937368 -279.537668)
				)
			)
		)
	)
	(zone
		(layer "In1.Cu")
		(hatch none 0.5)
		(connect_pads
			(clearance 0)
		)
		(min_thickness 0.25)
		(keepout
			(tracks not_allowed)
			(vias allowed)
			(pads allowed)
			(copperpour not_allowed)
			(footprints allowed)
		)
		(placement
			(enabled no)
			(sheetname "")
		)
		(fill
			(thermal_gap 0.5)
			(thermal_bridge_width 0.5)
			(island_removal_mode 0)
		)
		(polygon
			(pts
				(arc
					(start 37.545264 -246.032528)
					(mid 37.541544 -246.041508)
					(end 37.532564 -246.045228)
				)
				(arc
					(start 36.059364 -246.045228)
					(mid 36.050384 -246.041508)
					(end 36.046664 -246.032528)
				)
				(arc
					(start 36.046664 -245.53799)
					(mid 36.050384 -245.52901)
					(end 36.059364 -245.52529)
				)
				(arc
					(start 37.532564 -245.52529)
					(mid 37.541544 -245.52901)
					(end 37.545264 -245.53799)
				)
			)
		)
	)
	(zone
		(layer "In1.Cu")
		(hatch none 0.5)
		(connect_pads
			(clearance 0)
		)
		(min_thickness 0.25)
		(keepout
			(tracks not_allowed)
			(vias allowed)
			(pads allowed)
			(copperpour not_allowed)
			(footprints allowed)
		)
		(placement
			(enabled no)
			(sheetname "")
		)
		(fill
			(thermal_gap 0.5)
			(thermal_bridge_width 0.5)
			(island_removal_mode 0)
		)
		(polygon
			(pts
				(arc
					(start 265.87831 -301.034958)
					(mid 265.21791 -301.034958)
					(end 265.87831 -301.034958)
				)
			)
		)
	)
	(zone
		(layer "In1.Cu")
		(hatch none 0.5)
		(connect_pads
			(clearance 0)
		)
		(min_thickness 0.25)
		(keepout
			(tracks not_allowed)
			(vias allowed)
			(pads allowed)
			(copperpour not_allowed)
			(footprints allowed)
		)
		(placement
			(enabled no)
			(sheetname "")
		)
		(fill
			(thermal_gap 0.5)
			(thermal_bridge_width 0.5)
			(island_removal_mode 0)
		)
		(polygon
			(pts
				(arc
					(start 33.445196 -201.832464)
					(mid 33.441476 -201.841444)
					(end 33.432496 -201.845164)
				)
				(arc
					(start 31.959296 -201.845164)
					(mid 31.950316 -201.841444)
					(end 31.946596 -201.832464)
				)
				(arc
					(start 31.946596 -201.337926)
					(mid 31.950316 -201.328946)
					(end 31.959296 -201.325226)
				)
				(arc
					(start 33.432496 -201.325226)
					(mid 33.441476 -201.328946)
					(end 33.445196 -201.337926)
				)
			)
		)
	)
	(zone
		(layer "In1.Cu")
		(hatch none 0.5)
		(connect_pads
			(clearance 0)
		)
		(min_thickness 0.25)
		(keepout
			(tracks not_allowed)
			(vias allowed)
			(pads allowed)
			(copperpour not_allowed)
			(footprints allowed)
		)
		(placement
			(enabled no)
			(sheetname "")
		)
		(fill
			(thermal_gap 0.5)
			(thermal_bridge_width 0.5)
			(island_removal_mode 0)
		)
		(polygon
			(pts
				(arc
					(start 313.170062 -399.143474)
					(mid 312.865262 -399.143474)
					(end 313.170062 -399.143474)
				)
			)
		)
	)
	(zone
		(layer "In1.Cu")
		(hatch none 0.5)
		(connect_pads
			(clearance 0)
		)
		(min_thickness 0.25)
		(keepout
			(tracks not_allowed)
			(vias allowed)
			(pads allowed)
			(copperpour not_allowed)
			(footprints allowed)
		)
		(placement
			(enabled no)
			(sheetname "")
		)
		(fill
			(thermal_gap 0.5)
			(thermal_bridge_width 0.5)
			(island_removal_mode 0)
		)
		(polygon
			(pts
				(arc
					(start 56.077358 -237.532418)
					(mid 56.073638 -237.541398)
					(end 56.064658 -237.545118)
				)
				(arc
					(start 54.591458 -237.545118)
					(mid 54.582478 -237.541398)
					(end 54.578758 -237.532418)
				)
				(arc
					(start 54.578758 -237.03788)
					(mid 54.582478 -237.0289)
					(end 54.591458 -237.02518)
				)
				(arc
					(start 56.064658 -237.02518)
					(mid 56.073638 -237.0289)
					(end 56.077358 -237.03788)
				)
			)
		)
	)
	(zone
		(layer "In1.Cu")
		(hatch none 0.5)
		(connect_pads
			(clearance 0)
		)
		(min_thickness 0.25)
		(keepout
			(tracks not_allowed)
			(vias allowed)
			(pads allowed)
			(copperpour not_allowed)
			(footprints allowed)
		)
		(placement
			(enabled no)
			(sheetname "")
		)
		(fill
			(thermal_gap 0.5)
			(thermal_bridge_width 0.5)
			(island_removal_mode 0)
		)
		(polygon
			(pts
				(arc
					(start 87.298276 -383.92227)
					(mid 86.993476 -383.92227)
					(end 87.298276 -383.92227)
				)
			)
		)
	)
	(zone
		(layer "In1.Cu")
		(hatch none 0.5)
		(connect_pads
			(clearance 0)
		)
		(min_thickness 0.25)
		(keepout
			(tracks not_allowed)
			(vias allowed)
			(pads allowed)
			(copperpour not_allowed)
			(footprints allowed)
		)
		(placement
			(enabled no)
			(sheetname "")
		)
		(fill
			(thermal_gap 0.5)
			(thermal_bridge_width 0.5)
			(island_removal_mode 0)
		)
		(polygon
			(pts
				(arc
					(start 33.445196 -316.582552)
					(mid 33.441476 -316.591532)
					(end 33.432496 -316.595252)
				)
				(arc
					(start 31.959296 -316.595252)
					(mid 31.950316 -316.591532)
					(end 31.946596 -316.582552)
				)
				(arc
					(start 31.946596 -316.088014)
					(mid 31.950316 -316.079034)
					(end 31.959296 -316.075314)
				)
				(arc
					(start 33.432496 -316.075314)
					(mid 33.441476 -316.079034)
					(end 33.445196 -316.088014)
				)
			)
		)
	)
	(zone
		(layer "In1.Cu")
		(hatch none 0.5)
		(connect_pads
			(clearance 0)
		)
		(min_thickness 0.25)
		(keepout
			(tracks not_allowed)
			(vias allowed)
			(pads allowed)
			(copperpour not_allowed)
			(footprints allowed)
		)
		(placement
			(enabled no)
			(sheetname "")
		)
		(fill
			(thermal_gap 0.5)
			(thermal_bridge_width 0.5)
			(island_removal_mode 0)
		)
		(polygon
			(pts
				(arc
					(start 22.45741 -311.482486)
					(mid 22.45369 -311.491466)
					(end 22.44471 -311.495186)
				)
				(arc
					(start 20.97151 -311.495186)
					(mid 20.96253 -311.491466)
					(end 20.95881 -311.482486)
				)
				(arc
					(start 20.95881 -310.987948)
					(mid 20.96253 -310.978968)
					(end 20.97151 -310.975248)
				)
				(arc
					(start 22.44471 -310.975248)
					(mid 22.45369 -310.978968)
					(end 22.45741 -310.987948)
				)
			)
		)
	)
	(zone
		(layer "In1.Cu")
		(hatch none 0.5)
		(connect_pads
			(clearance 0)
		)
		(min_thickness 0.25)
		(keepout
			(tracks not_allowed)
			(vias allowed)
			(pads allowed)
			(copperpour not_allowed)
			(footprints allowed)
		)
		(placement
			(enabled no)
			(sheetname "")
		)
		(fill
			(thermal_gap 0.5)
			(thermal_bridge_width 0.5)
			(island_removal_mode 0)
		)
		(polygon
			(pts
				(arc
					(start 273.841464 -245.182136)
					(mid 273.837744 -245.191116)
					(end 273.828764 -245.194836)
				)
				(arc
					(start 272.355564 -245.194836)
					(mid 272.346584 -245.191116)
					(end 272.342864 -245.182136)
				)
				(arc
					(start 272.342864 -244.687598)
					(mid 272.346584 -244.678618)
					(end 272.355564 -244.674898)
				)
				(arc
					(start 273.828764 -244.674898)
					(mid 273.837744 -244.678618)
					(end 273.841464 -244.687598)
				)
			)
		)
	)
	(zone
		(layer "In1.Cu")
		(hatch none 0.5)
		(connect_pads
			(clearance 0)
		)
		(min_thickness 0.25)
		(keepout
			(tracks not_allowed)
			(vias allowed)
			(pads allowed)
			(copperpour not_allowed)
			(footprints allowed)
		)
		(placement
			(enabled no)
			(sheetname "")
		)
		(fill
			(thermal_gap 0.5)
			(thermal_bridge_width 0.5)
			(island_removal_mode 0)
		)
		(polygon
			(pts
				(arc
					(start 351.588832 -393.69238)
					(mid 351.207832 -393.69238)
					(end 351.588832 -393.69238)
				)
			)
		)
	)
	(zone
		(layer "In1.Cu")
		(hatch none 0.5)
		(connect_pads
			(clearance 0)
		)
		(min_thickness 0.25)
		(keepout
			(tracks not_allowed)
			(vias allowed)
			(pads allowed)
			(copperpour not_allowed)
			(footprints allowed)
		)
		(placement
			(enabled no)
			(sheetname "")
		)
		(fill
			(thermal_gap 0.5)
			(thermal_bridge_width 0.5)
			(island_removal_mode 0)
		)
		(polygon
			(pts
				(arc
					(start 56.077358 -293.632382)
					(mid 56.073638 -293.641362)
					(end 56.064658 -293.645082)
				)
				(arc
					(start 54.591458 -293.645082)
					(mid 54.582478 -293.641362)
					(end 54.578758 -293.632382)
				)
				(arc
					(start 54.578758 -293.137844)
					(mid 54.582478 -293.128864)
					(end 54.591458 -293.125144)
				)
				(arc
					(start 56.064658 -293.125144)
					(mid 56.073638 -293.128864)
					(end 56.077358 -293.137844)
				)
			)
		)
	)
	(zone
		(layer "In1.Cu")
		(hatch none 0.5)
		(connect_pads
			(clearance 0)
		)
		(min_thickness 0.25)
		(keepout
			(tracks not_allowed)
			(vias allowed)
			(pads allowed)
			(copperpour not_allowed)
			(footprints allowed)
		)
		(placement
			(enabled no)
			(sheetname "")
		)
		(fill
			(thermal_gap 0.5)
			(thermal_bridge_width 0.5)
			(island_removal_mode 0)
		)
		(polygon
			(pts
				(arc
					(start 273.841464 -307.232304)
					(mid 273.837744 -307.241284)
					(end 273.828764 -307.245004)
				)
				(arc
					(start 272.355564 -307.245004)
					(mid 272.346584 -307.241284)
					(end 272.342864 -307.232304)
				)
				(arc
					(start 272.342864 -306.737766)
					(mid 272.346584 -306.728786)
					(end 272.355564 -306.725066)
				)
				(arc
					(start 273.828764 -306.725066)
					(mid 273.837744 -306.728786)
					(end 273.841464 -306.737766)
				)
			)
		)
	)
	(zone
		(layer "In1.Cu")
		(hatch none 0.5)
		(connect_pads
			(clearance 0)
		)
		(min_thickness 0.25)
		(keepout
			(tracks not_allowed)
			(vias allowed)
			(pads allowed)
			(copperpour not_allowed)
			(footprints allowed)
		)
		(placement
			(enabled no)
			(sheetname "")
		)
		(fill
			(thermal_gap 0.5)
			(thermal_bridge_width 0.5)
			(island_removal_mode 0)
		)
		(polygon
			(pts
				(arc
					(start 195.353432 -307.232558)
					(mid 195.349712 -307.241538)
					(end 195.340732 -307.245258)
				)
				(arc
					(start 193.867532 -307.245258)
					(mid 193.858552 -307.241538)
					(end 193.854832 -307.232558)
				)
				(arc
					(start 193.854832 -306.73802)
					(mid 193.858552 -306.72904)
					(end 193.867532 -306.72532)
				)
				(arc
					(start 195.340732 -306.72532)
					(mid 195.349712 -306.72904)
					(end 195.353432 -306.73802)
				)
			)
		)
	)
	(zone
		(layer "In1.Cu")
		(hatch none 0.5)
		(connect_pads
			(clearance 0)
		)
		(min_thickness 0.25)
		(keepout
			(tracks not_allowed)
			(vias allowed)
			(pads allowed)
			(copperpour not_allowed)
			(footprints allowed)
		)
		(placement
			(enabled no)
			(sheetname "")
		)
		(fill
			(thermal_gap 0.5)
			(thermal_bridge_width 0.5)
			(island_removal_mode 0)
		)
		(polygon
			(pts
				(arc
					(start 428.205392 -218.832176)
					(mid 428.201672 -218.841156)
					(end 428.192692 -218.844876)
				)
				(arc
					(start 426.719492 -218.844876)
					(mid 426.710512 -218.841156)
					(end 426.706792 -218.832176)
				)
				(arc
					(start 426.706792 -218.337638)
					(mid 426.710512 -218.328658)
					(end 426.719492 -218.324938)
				)
				(arc
					(start 428.192692 -218.324938)
					(mid 428.201672 -218.328658)
					(end 428.205392 -218.337638)
				)
			)
		)
	)
	(zone
		(layer "In1.Cu")
		(hatch none 0.5)
		(connect_pads
			(clearance 0)
		)
		(min_thickness 0.25)
		(keepout
			(tracks not_allowed)
			(vias allowed)
			(pads allowed)
			(copperpour not_allowed)
			(footprints allowed)
		)
		(placement
			(enabled no)
			(sheetname "")
		)
		(fill
			(thermal_gap 0.5)
			(thermal_bridge_width 0.5)
			(island_removal_mode 0)
		)
		(polygon
			(pts
				(arc
					(start 165.177216 -206.082392)
					(mid 165.173496 -206.091372)
					(end 165.164516 -206.095092)
				)
				(arc
					(start 163.691316 -206.095092)
					(mid 163.682336 -206.091372)
					(end 163.678616 -206.082392)
				)
				(arc
					(start 163.678616 -205.587854)
					(mid 163.682336 -205.578874)
					(end 163.691316 -205.575154)
				)
				(arc
					(start 165.164516 -205.575154)
					(mid 165.173496 -205.578874)
					(end 165.177216 -205.587854)
				)
			)
		)
	)
	(zone
		(layer "In1.Cu")
		(hatch none 0.5)
		(connect_pads
			(clearance 0)
		)
		(min_thickness 0.25)
		(keepout
			(tracks not_allowed)
			(vias allowed)
			(pads allowed)
			(copperpour not_allowed)
			(footprints allowed)
		)
		(placement
			(enabled no)
			(sheetname "")
		)
		(fill
			(thermal_gap 0.5)
			(thermal_bridge_width 0.5)
			(island_removal_mode 0)
		)
		(polygon
			(pts
				(arc
					(start 285.485332 -302.132238)
					(mid 285.481612 -302.141218)
					(end 285.472632 -302.144938)
				)
				(arc
					(start 283.999432 -302.144938)
					(mid 283.990452 -302.141218)
					(end 283.986732 -302.132238)
				)
				(arc
					(start 283.986732 -301.6377)
					(mid 283.990452 -301.62872)
					(end 283.999432 -301.625)
				)
				(arc
					(start 285.472632 -301.625)
					(mid 285.481612 -301.62872)
					(end 285.485332 -301.6377)
				)
			)
		)
	)
	(zone
		(layer "In1.Cu")
		(hatch none 0.5)
		(connect_pads
			(clearance 0)
		)
		(min_thickness 0.25)
		(keepout
			(tracks not_allowed)
			(vias allowed)
			(pads allowed)
			(copperpour not_allowed)
			(footprints allowed)
		)
		(placement
			(enabled no)
			(sheetname "")
		)
		(fill
			(thermal_gap 0.5)
			(thermal_bridge_width 0.5)
			(island_removal_mode 0)
		)
		(polygon
			(pts
				(arc
					(start 447.393568 -292.782244)
					(mid 447.389848 -292.791224)
					(end 447.380868 -292.794944)
				)
				(arc
					(start 445.907668 -292.794944)
					(mid 445.898688 -292.791224)
					(end 445.894968 -292.782244)
				)
				(arc
					(start 445.894968 -292.287706)
					(mid 445.898688 -292.278726)
					(end 445.907668 -292.275006)
				)
				(arc
					(start 447.380868 -292.275006)
					(mid 447.389848 -292.278726)
					(end 447.393568 -292.287706)
				)
			)
		)
	)
	(zone
		(layer "In1.Cu")
		(hatch none 0.5)
		(connect_pads
			(clearance 0)
		)
		(min_thickness 0.25)
		(keepout
			(tracks not_allowed)
			(vias allowed)
			(pads allowed)
			(copperpour not_allowed)
			(footprints allowed)
		)
		(placement
			(enabled no)
			(sheetname "")
		)
		(fill
			(thermal_gap 0.5)
			(thermal_bridge_width 0.5)
			(island_removal_mode 0)
		)
		(polygon
			(pts
				(arc
					(start 418.689028 -397.156432)
					(mid 418.308028 -397.156432)
					(end 418.689028 -397.156432)
				)
			)
		)
	)
	(zone
		(layer "In1.Cu")
		(hatch none 0.5)
		(connect_pads
			(clearance 0)
		)
		(min_thickness 0.25)
		(keepout
			(tracks not_allowed)
			(vias allowed)
			(pads allowed)
			(copperpour not_allowed)
			(footprints allowed)
		)
		(placement
			(enabled no)
			(sheetname "")
		)
		(fill
			(thermal_gap 0.5)
			(thermal_bridge_width 0.5)
			(island_removal_mode 0)
		)
		(polygon
			(pts
				(arc
					(start 288.929318 -251.982224)
					(mid 288.925598 -251.991204)
					(end 288.916618 -251.994924)
				)
				(arc
					(start 287.443418 -251.994924)
					(mid 287.434438 -251.991204)
					(end 287.430718 -251.982224)
				)
				(arc
					(start 287.430718 -251.487686)
					(mid 287.434438 -251.478706)
					(end 287.443418 -251.474986)
				)
				(arc
					(start 288.916618 -251.474986)
					(mid 288.925598 -251.478706)
					(end 288.929318 -251.487686)
				)
			)
		)
	)
	(zone
		(layer "In1.Cu")
		(hatch none 0.5)
		(connect_pads
			(clearance 0)
		)
		(min_thickness 0.25)
		(keepout
			(tracks not_allowed)
			(vias allowed)
			(pads allowed)
			(copperpour not_allowed)
			(footprints allowed)
		)
		(placement
			(enabled no)
			(sheetname "")
		)
		(fill
			(thermal_gap 0.5)
			(thermal_bridge_width 0.5)
			(island_removal_mode 0)
		)
		(polygon
			(pts
				(arc
					(start 45.089318 -229.882446)
					(mid 45.085598 -229.891426)
					(end 45.076618 -229.895146)
				)
				(arc
					(start 43.603418 -229.895146)
					(mid 43.594438 -229.891426)
					(end 43.590718 -229.882446)
				)
				(arc
					(start 43.590718 -229.387908)
					(mid 43.594438 -229.378928)
					(end 43.603418 -229.375208)
				)
				(arc
					(start 45.076618 -229.375208)
					(mid 45.085598 -229.378928)
					(end 45.089318 -229.387908)
				)
			)
		)
	)
	(zone
		(layer "In1.Cu")
		(hatch none 0.5)
		(connect_pads
			(clearance 0)
		)
		(min_thickness 0.25)
		(keepout
			(tracks not_allowed)
			(vias allowed)
			(pads allowed)
			(copperpour not_allowed)
			(footprints allowed)
		)
		(placement
			(enabled no)
			(sheetname "")
		)
		(fill
			(thermal_gap 0.5)
			(thermal_bridge_width 0.5)
			(island_removal_mode 0)
		)
		(polygon
			(pts
				(arc
					(start 285.485332 -220.532198)
					(mid 285.481612 -220.541178)
					(end 285.472632 -220.544898)
				)
				(arc
					(start 283.999432 -220.544898)
					(mid 283.990452 -220.541178)
					(end 283.986732 -220.532198)
				)
				(arc
					(start 283.986732 -220.03766)
					(mid 283.990452 -220.02868)
					(end 283.999432 -220.02496)
				)
				(arc
					(start 285.472632 -220.02496)
					(mid 285.481612 -220.02868)
					(end 285.485332 -220.03766)
				)
			)
		)
	)
	(zone
		(layer "In1.Cu")
		(hatch none 0.5)
		(connect_pads
			(clearance 0)
		)
		(min_thickness 0.25)
		(keepout
			(tracks not_allowed)
			(vias allowed)
			(pads allowed)
			(copperpour not_allowed)
			(footprints allowed)
		)
		(placement
			(enabled no)
			(sheetname "")
		)
		(fill
			(thermal_gap 0.5)
			(thermal_bridge_width 0.5)
			(island_removal_mode 0)
		)
		(polygon
			(pts
				(arc
					(start 191.909446 -236.682534)
					(mid 191.905726 -236.691514)
					(end 191.896746 -236.695234)
				)
				(arc
					(start 190.423546 -236.695234)
					(mid 190.414566 -236.691514)
					(end 190.410846 -236.682534)
				)
				(arc
					(start 190.410846 -236.187996)
					(mid 190.414566 -236.179016)
					(end 190.423546 -236.175296)
				)
				(arc
					(start 191.896746 -236.175296)
					(mid 191.905726 -236.179016)
					(end 191.909446 -236.187996)
				)
			)
		)
	)
	(zone
		(layer "In1.Cu")
		(hatch none 0.5)
		(connect_pads
			(clearance 0)
		)
		(min_thickness 0.25)
		(keepout
			(tracks not_allowed)
			(vias allowed)
			(pads allowed)
			(copperpour not_allowed)
			(footprints allowed)
		)
		(placement
			(enabled no)
			(sheetname "")
		)
		(fill
			(thermal_gap 0.5)
			(thermal_bridge_width 0.5)
			(island_removal_mode 0)
		)
		(polygon
			(pts
				(arc
					(start 195.353432 -254.532384)
					(mid 195.349712 -254.541364)
					(end 195.340732 -254.545084)
				)
				(arc
					(start 193.867532 -254.545084)
					(mid 193.858552 -254.541364)
					(end 193.854832 -254.532384)
				)
				(arc
					(start 193.854832 -254.037846)
					(mid 193.858552 -254.028866)
					(end 193.867532 -254.025146)
				)
				(arc
					(start 195.340732 -254.025146)
					(mid 195.349712 -254.028866)
					(end 195.353432 -254.037846)
				)
			)
		)
	)
	(zone
		(layer "In1.Cu")
		(hatch none 0.5)
		(connect_pads
			(clearance 0)
		)
		(min_thickness 0.25)
		(keepout
			(tracks not_allowed)
			(vias allowed)
			(pads allowed)
			(copperpour not_allowed)
			(footprints allowed)
		)
		(placement
			(enabled no)
			(sheetname "")
		)
		(fill
			(thermal_gap 0.5)
			(thermal_bridge_width 0.5)
			(island_removal_mode 0)
		)
		(polygon
			(pts
				(arc
					(start 40.98925 -212.032342)
					(mid 40.98553 -212.041322)
					(end 40.97655 -212.045042)
				)
				(arc
					(start 39.50335 -212.045042)
					(mid 39.49437 -212.041322)
					(end 39.49065 -212.032342)
				)
				(arc
					(start 39.49065 -211.537804)
					(mid 39.49437 -211.528824)
					(end 39.50335 -211.525104)
				)
				(arc
					(start 40.97655 -211.525104)
					(mid 40.98553 -211.528824)
					(end 40.98925 -211.537804)
				)
			)
		)
	)
	(zone
		(layer "In1.Cu")
		(hatch none 0.5)
		(connect_pads
			(clearance 0)
		)
		(min_thickness 0.25)
		(keepout
			(tracks not_allowed)
			(vias allowed)
			(pads allowed)
			(copperpour not_allowed)
			(footprints allowed)
		)
		(placement
			(enabled no)
			(sheetname "")
		)
		(fill
			(thermal_gap 0.5)
			(thermal_bridge_width 0.5)
			(island_removal_mode 0)
		)
		(polygon
			(pts
				(arc
					(start 273.841464 -240.082324)
					(mid 273.837744 -240.091304)
					(end 273.828764 -240.095024)
				)
				(arc
					(start 272.355564 -240.095024)
					(mid 272.346584 -240.091304)
					(end 272.342864 -240.082324)
				)
				(arc
					(start 272.342864 -239.587786)
					(mid 272.346584 -239.578806)
					(end 272.355564 -239.575086)
				)
				(arc
					(start 273.828764 -239.575086)
					(mid 273.837744 -239.578806)
					(end 273.841464 -239.587786)
				)
			)
		)
	)
	(zone
		(layer "In1.Cu")
		(hatch none 0.5)
		(connect_pads
			(clearance 0)
		)
		(min_thickness 0.25)
		(keepout
			(tracks not_allowed)
			(vias allowed)
			(pads allowed)
			(copperpour not_allowed)
			(footprints allowed)
		)
		(placement
			(enabled no)
			(sheetname "")
		)
		(fill
			(thermal_gap 0.5)
			(thermal_bridge_width 0.5)
			(island_removal_mode 0)
		)
		(polygon
			(pts
				(arc
					(start 184.365392 -304.682398)
					(mid 184.361672 -304.691378)
					(end 184.352692 -304.695098)
				)
				(arc
					(start 182.879492 -304.695098)
					(mid 182.870512 -304.691378)
					(end 182.866792 -304.682398)
				)
				(arc
					(start 182.866792 -304.18786)
					(mid 182.870512 -304.17888)
					(end 182.879492 -304.17516)
				)
				(arc
					(start 184.352692 -304.17516)
					(mid 184.361672 -304.17888)
					(end 184.365392 -304.18786)
				)
			)
		)
	)
	(zone
		(layer "In1.Cu")
		(hatch none 0.5)
		(connect_pads
			(clearance 0)
		)
		(min_thickness 0.25)
		(keepout
			(tracks not_allowed)
			(vias allowed)
			(pads allowed)
			(copperpour not_allowed)
			(footprints allowed)
		)
		(placement
			(enabled no)
			(sheetname "")
		)
		(fill
			(thermal_gap 0.5)
			(thermal_bridge_width 0.5)
			(island_removal_mode 0)
		)
		(polygon
			(pts
				(arc
					(start 270.397478 -268.132306)
					(mid 270.393758 -268.141286)
					(end 270.384778 -268.145006)
				)
				(arc
					(start 268.911578 -268.145006)
					(mid 268.902598 -268.141286)
					(end 268.898878 -268.132306)
				)
				(arc
					(start 268.898878 -267.637768)
					(mid 268.902598 -267.628788)
					(end 268.911578 -267.625068)
				)
				(arc
					(start 270.384778 -267.625068)
					(mid 270.393758 -267.628788)
					(end 270.397478 -267.637768)
				)
			)
		)
	)
	(zone
		(layer "In1.Cu")
		(hatch none 0.5)
		(connect_pads
			(clearance 0)
		)
		(min_thickness 0.25)
		(keepout
			(tracks not_allowed)
			(vias allowed)
			(pads allowed)
			(copperpour not_allowed)
			(footprints allowed)
		)
		(placement
			(enabled no)
			(sheetname "")
		)
		(fill
			(thermal_gap 0.5)
			(thermal_bridge_width 0.5)
			(island_removal_mode 0)
		)
		(polygon
			(pts
				(arc
					(start 307.170074 -392.30427)
					(mid 306.865274 -392.30427)
					(end 307.170074 -392.30427)
				)
			)
		)
	)
	(zone
		(layer "In1.Cu")
		(hatch none 0.5)
		(connect_pads
			(clearance 0)
		)
		(min_thickness 0.25)
		(keepout
			(tracks not_allowed)
			(vias allowed)
			(pads allowed)
			(copperpour not_allowed)
			(footprints allowed)
		)
		(placement
			(enabled no)
			(sheetname "")
		)
		(fill
			(thermal_gap 0.5)
			(thermal_bridge_width 0.5)
			(island_removal_mode 0)
		)
		(polygon
			(pts
				(arc
					(start 202.897232 -301.282354)
					(mid 202.893512 -301.291334)
					(end 202.884532 -301.295054)
				)
				(arc
					(start 201.411332 -301.295054)
					(mid 201.402352 -301.291334)
					(end 201.398632 -301.282354)
				)
				(arc
					(start 201.398632 -300.787816)
					(mid 201.402352 -300.778836)
					(end 201.411332 -300.775116)
				)
				(arc
					(start 202.884532 -300.775116)
					(mid 202.893512 -300.778836)
					(end 202.897232 -300.787816)
				)
			)
		)
	)
	(zone
		(layer "In1.Cu")
		(hatch none 0.5)
		(connect_pads
			(clearance 0)
		)
		(min_thickness 0.25)
		(keepout
			(tracks not_allowed)
			(vias allowed)
			(pads allowed)
			(copperpour not_allowed)
			(footprints allowed)
		)
		(placement
			(enabled no)
			(sheetname "")
		)
		(fill
			(thermal_gap 0.5)
			(thermal_bridge_width 0.5)
			(island_removal_mode 0)
		)
		(polygon
			(pts
				(arc
					(start 443.2935 -215.432132)
					(mid 443.28978 -215.441112)
					(end 443.2808 -215.444832)
				)
				(arc
					(start 441.8076 -215.444832)
					(mid 441.79862 -215.441112)
					(end 441.7949 -215.432132)
				)
				(arc
					(start 441.7949 -214.937594)
					(mid 441.79862 -214.928614)
					(end 441.8076 -214.924894)
				)
				(arc
					(start 443.2808 -214.924894)
					(mid 443.28978 -214.928614)
					(end 443.2935 -214.937594)
				)
			)
		)
	)
	(zone
		(layer "In1.Cu")
		(hatch none 0.5)
		(connect_pads
			(clearance 0)
		)
		(min_thickness 0.25)
		(keepout
			(tracks not_allowed)
			(vias allowed)
			(pads allowed)
			(copperpour not_allowed)
			(footprints allowed)
		)
		(placement
			(enabled no)
			(sheetname "")
		)
		(fill
			(thermal_gap 0.5)
			(thermal_bridge_width 0.5)
			(island_removal_mode 0)
		)
		(polygon
			(pts
				(arc
					(start 371.870224 -392.30427)
					(mid 371.565424 -392.30427)
					(end 371.870224 -392.30427)
				)
			)
		)
	)
	(zone
		(layer "In1.Cu")
		(hatch none 0.5)
		(connect_pads
			(clearance 0)
		)
		(min_thickness 0.25)
		(keepout
			(tracks not_allowed)
			(vias allowed)
			(pads allowed)
			(copperpour not_allowed)
			(footprints allowed)
		)
		(placement
			(enabled no)
			(sheetname "")
		)
		(fill
			(thermal_gap 0.5)
			(thermal_bridge_width 0.5)
			(island_removal_mode 0)
		)
		(polygon
			(pts
				(arc
					(start 40.98925 -220.532452)
					(mid 40.98553 -220.541432)
					(end 40.97655 -220.545152)
				)
				(arc
					(start 39.50335 -220.545152)
					(mid 39.49437 -220.541432)
					(end 39.49065 -220.532452)
				)
				(arc
					(start 39.49065 -220.037914)
					(mid 39.49437 -220.028934)
					(end 39.50335 -220.025214)
				)
				(arc
					(start 40.97655 -220.025214)
					(mid 40.98553 -220.028934)
					(end 40.98925 -220.037914)
				)
			)
		)
	)
	(zone
		(layer "In1.Cu")
		(hatch none 0.5)
		(connect_pads
			(clearance 0)
		)
		(min_thickness 0.25)
		(keepout
			(tracks not_allowed)
			(vias allowed)
			(pads allowed)
			(copperpour not_allowed)
			(footprints allowed)
		)
		(placement
			(enabled no)
			(sheetname "")
		)
		(fill
			(thermal_gap 0.5)
			(thermal_bridge_width 0.5)
			(island_removal_mode 0)
		)
		(polygon
			(pts
				(arc
					(start 48.533304 -212.032342)
					(mid 48.529584 -212.041322)
					(end 48.520604 -212.045042)
				)
				(arc
					(start 47.047404 -212.045042)
					(mid 47.038424 -212.041322)
					(end 47.034704 -212.032342)
				)
				(arc
					(start 47.034704 -211.537804)
					(mid 47.038424 -211.528824)
					(end 47.047404 -211.525104)
				)
				(arc
					(start 48.520604 -211.525104)
					(mid 48.529584 -211.528824)
					(end 48.533304 -211.537804)
				)
			)
		)
	)
	(zone
		(layer "In1.Cu")
		(hatch none 0.5)
		(connect_pads
			(clearance 0)
		)
		(min_thickness 0.25)
		(keepout
			(tracks not_allowed)
			(vias allowed)
			(pads allowed)
			(copperpour not_allowed)
			(footprints allowed)
		)
		(placement
			(enabled no)
			(sheetname "")
		)
		(fill
			(thermal_gap 0.5)
			(thermal_bridge_width 0.5)
			(island_removal_mode 0)
		)
		(polygon
			(pts
				(arc
					(start 454.937368 -197.582282)
					(mid 454.933648 -197.591262)
					(end 454.924668 -197.594982)
				)
				(arc
					(start 453.451468 -197.594982)
					(mid 453.442488 -197.591262)
					(end 453.438768 -197.582282)
				)
				(arc
					(start 453.438768 -197.087744)
					(mid 453.442488 -197.078764)
					(end 453.451468 -197.075044)
				)
				(arc
					(start 454.924668 -197.075044)
					(mid 454.933648 -197.078764)
					(end 454.937368 -197.087744)
				)
			)
		)
	)
	(zone
		(layer "In1.Cu")
		(hatch none 0.5)
		(connect_pads
			(clearance 0)
		)
		(min_thickness 0.25)
		(keepout
			(tracks not_allowed)
			(vias allowed)
			(pads allowed)
			(copperpour not_allowed)
			(footprints allowed)
		)
		(placement
			(enabled no)
			(sheetname "")
		)
		(fill
			(thermal_gap 0.5)
			(thermal_bridge_width 0.5)
			(island_removal_mode 0)
		)
		(polygon
			(pts
				(arc
					(start 206.5782 -220.28531)
					(mid 205.9178 -220.28531)
					(end 206.5782 -220.28531)
				)
			)
		)
	)
	(zone
		(layer "In1.Cu")
		(hatch none 0.5)
		(connect_pads
			(clearance 0)
		)
		(min_thickness 0.25)
		(keepout
			(tracks not_allowed)
			(vias allowed)
			(pads allowed)
			(copperpour not_allowed)
			(footprints allowed)
		)
		(placement
			(enabled no)
			(sheetname "")
		)
		(fill
			(thermal_gap 0.5)
			(thermal_bridge_width 0.5)
			(island_removal_mode 0)
		)
		(polygon
			(pts
				(arc
					(start 37.545264 -240.932462)
					(mid 37.541544 -240.941442)
					(end 37.532564 -240.945162)
				)
				(arc
					(start 36.059364 -240.945162)
					(mid 36.050384 -240.941442)
					(end 36.046664 -240.932462)
				)
				(arc
					(start 36.046664 -240.437924)
					(mid 36.050384 -240.428944)
					(end 36.059364 -240.425224)
				)
				(arc
					(start 37.532564 -240.425224)
					(mid 37.541544 -240.428944)
					(end 37.545264 -240.437924)
				)
			)
		)
	)
	(zone
		(layer "In1.Cu")
		(hatch none 0.5)
		(connect_pads
			(clearance 0)
		)
		(min_thickness 0.25)
		(keepout
			(tracks not_allowed)
			(vias allowed)
			(pads allowed)
			(copperpour not_allowed)
			(footprints allowed)
		)
		(placement
			(enabled no)
			(sheetname "")
		)
		(fill
			(thermal_gap 0.5)
			(thermal_bridge_width 0.5)
			(island_removal_mode 0)
		)
		(polygon
			(pts
				(arc
					(start 45.089318 -201.832464)
					(mid 45.085598 -201.841444)
					(end 45.076618 -201.845164)
				)
				(arc
					(start 43.603418 -201.845164)
					(mid 43.594438 -201.841444)
					(end 43.590718 -201.832464)
				)
				(arc
					(start 43.590718 -201.337926)
					(mid 43.594438 -201.328946)
					(end 43.603418 -201.325226)
				)
				(arc
					(start 45.076618 -201.325226)
					(mid 45.085598 -201.328946)
					(end 45.089318 -201.337926)
				)
			)
		)
	)
	(zone
		(layer "In1.Cu")
		(hatch none 0.5)
		(connect_pads
			(clearance 0)
		)
		(min_thickness 0.25)
		(keepout
			(tracks not_allowed)
			(vias allowed)
			(pads allowed)
			(copperpour not_allowed)
			(footprints allowed)
		)
		(placement
			(enabled no)
			(sheetname "")
		)
		(fill
			(thermal_gap 0.5)
			(thermal_bridge_width 0.5)
			(island_removal_mode 0)
		)
		(polygon
			(pts
				(arc
					(start 443.2935 -284.282134)
					(mid 443.28978 -284.291114)
					(end 443.2808 -284.294834)
				)
				(arc
					(start 441.8076 -284.294834)
					(mid 441.79862 -284.291114)
					(end 441.7949 -284.282134)
				)
				(arc
					(start 441.7949 -283.787596)
					(mid 441.79862 -283.778616)
					(end 441.8076 -283.774896)
				)
				(arc
					(start 443.2808 -283.774896)
					(mid 443.28978 -283.778616)
					(end 443.2935 -283.787596)
				)
			)
		)
	)
	(zone
		(layer "In1.Cu")
		(hatch none 0.5)
		(connect_pads
			(clearance 0)
		)
		(min_thickness 0.25)
		(keepout
			(tracks not_allowed)
			(vias allowed)
			(pads allowed)
			(copperpour not_allowed)
			(footprints allowed)
		)
		(placement
			(enabled no)
			(sheetname "")
		)
		(fill
			(thermal_gap 0.5)
			(thermal_bridge_width 0.5)
			(island_removal_mode 0)
		)
		(polygon
			(pts
				(arc
					(start 443.2935 -273.232118)
					(mid 443.28978 -273.241098)
					(end 443.2808 -273.244818)
				)
				(arc
					(start 441.8076 -273.244818)
					(mid 441.79862 -273.241098)
					(end 441.7949 -273.232118)
				)
				(arc
					(start 441.7949 -272.73758)
					(mid 441.79862 -272.7286)
					(end 441.8076 -272.72488)
				)
				(arc
					(start 443.2808 -272.72488)
					(mid 443.28978 -272.7286)
					(end 443.2935 -272.73758)
				)
			)
		)
	)
	(zone
		(layer "In1.Cu")
		(hatch none 0.5)
		(connect_pads
			(clearance 0)
		)
		(min_thickness 0.25)
		(keepout
			(tracks not_allowed)
			(vias allowed)
			(pads allowed)
			(copperpour not_allowed)
			(footprints allowed)
		)
		(placement
			(enabled no)
			(sheetname "")
		)
		(fill
			(thermal_gap 0.5)
			(thermal_bridge_width 0.5)
			(island_removal_mode 0)
		)
		(polygon
			(pts
				(arc
					(start 296.473372 -286.832294)
					(mid 296.469652 -286.841274)
					(end 296.460672 -286.844994)
				)
				(arc
					(start 294.987472 -286.844994)
					(mid 294.978492 -286.841274)
					(end 294.974772 -286.832294)
				)
				(arc
					(start 294.974772 -286.337756)
					(mid 294.978492 -286.328776)
					(end 294.987472 -286.325056)
				)
				(arc
					(start 296.460672 -286.325056)
					(mid 296.469652 -286.328776)
					(end 296.473372 -286.337756)
				)
			)
		)
	)
	(zone
		(layer "In1.Cu")
		(hatch none 0.5)
		(connect_pads
			(clearance 0)
		)
		(min_thickness 0.25)
		(keepout
			(tracks not_allowed)
			(vias allowed)
			(pads allowed)
			(copperpour not_allowed)
			(footprints allowed)
		)
		(placement
			(enabled no)
			(sheetname "")
		)
		(fill
			(thermal_gap 0.5)
			(thermal_bridge_width 0.5)
			(island_removal_mode 0)
		)
		(polygon
			(pts
				(arc
					(start 30.001464 -229.882446)
					(mid 29.997744 -229.891426)
					(end 29.988764 -229.895146)
				)
				(arc
					(start 28.515564 -229.895146)
					(mid 28.506584 -229.891426)
					(end 28.502864 -229.882446)
				)
				(arc
					(start 28.502864 -229.387908)
					(mid 28.506584 -229.378928)
					(end 28.515564 -229.375208)
				)
				(arc
					(start 29.988764 -229.375208)
					(mid 29.997744 -229.378928)
					(end 30.001464 -229.387908)
				)
			)
		)
	)
	(zone
		(layer "In1.Cu")
		(hatch none 0.5)
		(connect_pads
			(clearance 0)
		)
		(min_thickness 0.25)
		(keepout
			(tracks not_allowed)
			(vias allowed)
			(pads allowed)
			(copperpour not_allowed)
			(footprints allowed)
		)
		(placement
			(enabled no)
			(sheetname "")
		)
		(fill
			(thermal_gap 0.5)
			(thermal_bridge_width 0.5)
			(island_removal_mode 0)
		)
		(polygon
			(pts
				(arc
					(start 435.749446 -217.132154)
					(mid 435.745726 -217.141134)
					(end 435.736746 -217.144854)
				)
				(arc
					(start 434.263546 -217.144854)
					(mid 434.254566 -217.141134)
					(end 434.250846 -217.132154)
				)
				(arc
					(start 434.250846 -216.637616)
					(mid 434.254566 -216.628636)
					(end 434.263546 -216.624916)
				)
				(arc
					(start 435.736746 -216.624916)
					(mid 435.745726 -216.628636)
					(end 435.749446 -216.637616)
				)
			)
		)
	)
	(zone
		(layer "In1.Cu")
		(hatch none 0.5)
		(connect_pads
			(clearance 0)
		)
		(min_thickness 0.25)
		(keepout
			(tracks not_allowed)
			(vias allowed)
			(pads allowed)
			(copperpour not_allowed)
			(footprints allowed)
		)
		(placement
			(enabled no)
			(sheetname "")
		)
		(fill
			(thermal_gap 0.5)
			(thermal_bridge_width 0.5)
			(island_removal_mode 0)
		)
		(polygon
			(pts
				(arc
					(start 25.901396 -305.532536)
					(mid 25.897676 -305.541516)
					(end 25.888696 -305.545236)
				)
				(arc
					(start 24.415496 -305.545236)
					(mid 24.406516 -305.541516)
					(end 24.402796 -305.532536)
				)
				(arc
					(start 24.402796 -305.037998)
					(mid 24.406516 -305.029018)
					(end 24.415496 -305.025298)
				)
				(arc
					(start 25.888696 -305.025298)
					(mid 25.897676 -305.029018)
					(end 25.901396 -305.037998)
				)
			)
		)
	)
	(zone
		(layer "In1.Cu")
		(hatch none 0.5)
		(connect_pads
			(clearance 0)
		)
		(min_thickness 0.25)
		(keepout
			(tracks not_allowed)
			(vias allowed)
			(pads allowed)
			(copperpour not_allowed)
			(footprints allowed)
		)
		(placement
			(enabled no)
			(sheetname "")
		)
		(fill
			(thermal_gap 0.5)
			(thermal_bridge_width 0.5)
			(island_removal_mode 0)
		)
		(polygon
			(pts
				(arc
					(start 293.029386 -306.382166)
					(mid 293.025666 -306.391146)
					(end 293.016686 -306.394866)
				)
				(arc
					(start 291.543486 -306.394866)
					(mid 291.534506 -306.391146)
					(end 291.530786 -306.382166)
				)
				(arc
					(start 291.530786 -305.887628)
					(mid 291.534506 -305.878648)
					(end 291.543486 -305.874928)
				)
				(arc
					(start 293.016686 -305.874928)
					(mid 293.025666 -305.878648)
					(end 293.029386 -305.887628)
				)
			)
		)
	)
	(zone
		(layer "In1.Cu")
		(hatch none 0.5)
		(connect_pads
			(clearance 0)
		)
		(min_thickness 0.25)
		(keepout
			(tracks not_allowed)
			(vias allowed)
			(pads allowed)
			(copperpour not_allowed)
			(footprints allowed)
		)
		(placement
			(enabled no)
			(sheetname "")
		)
		(fill
			(thermal_gap 0.5)
			(thermal_bridge_width 0.5)
			(island_removal_mode 0)
		)
		(polygon
			(pts
				(arc
					(start 45.089318 -261.332472)
					(mid 45.085598 -261.341452)
					(end 45.076618 -261.345172)
				)
				(arc
					(start 43.603418 -261.345172)
					(mid 43.594438 -261.341452)
					(end 43.590718 -261.332472)
				)
				(arc
					(start 43.590718 -260.837934)
					(mid 43.594438 -260.828954)
					(end 43.603418 -260.825234)
				)
				(arc
					(start 45.076618 -260.825234)
					(mid 45.085598 -260.828954)
					(end 45.089318 -260.837934)
				)
			)
		)
	)
	(zone
		(layer "In1.Cu")
		(hatch none 0.5)
		(connect_pads
			(clearance 0)
		)
		(min_thickness 0.25)
		(keepout
			(tracks not_allowed)
			(vias allowed)
			(pads allowed)
			(copperpour not_allowed)
			(footprints allowed)
		)
		(placement
			(enabled no)
			(sheetname "")
		)
		(fill
			(thermal_gap 0.5)
			(thermal_bridge_width 0.5)
			(island_removal_mode 0)
		)
		(polygon
			(pts
				(arc
					(start 25.901396 -202.682348)
					(mid 25.897676 -202.691328)
					(end 25.888696 -202.695048)
				)
				(arc
					(start 24.415496 -202.695048)
					(mid 24.406516 -202.691328)
					(end 24.402796 -202.682348)
				)
				(arc
					(start 24.402796 -202.18781)
					(mid 24.406516 -202.17883)
					(end 24.415496 -202.17511)
				)
				(arc
					(start 25.888696 -202.17511)
					(mid 25.897676 -202.17883)
					(end 25.901396 -202.18781)
				)
			)
		)
	)
	(zone
		(layer "In1.Cu")
		(hatch none 0.5)
		(connect_pads
			(clearance 0)
		)
		(min_thickness 0.25)
		(keepout
			(tracks not_allowed)
			(vias allowed)
			(pads allowed)
			(copperpour not_allowed)
			(footprints allowed)
		)
		(placement
			(enabled no)
			(sheetname "")
		)
		(fill
			(thermal_gap 0.5)
			(thermal_bridge_width 0.5)
			(island_removal_mode 0)
		)
		(polygon
			(pts
				(arc
					(start 30.001464 -249.432572)
					(mid 29.997744 -249.441552)
					(end 29.988764 -249.445272)
				)
				(arc
					(start 28.515564 -249.445272)
					(mid 28.506584 -249.441552)
					(end 28.502864 -249.432572)
				)
				(arc
					(start 28.502864 -248.938034)
					(mid 28.506584 -248.929054)
					(end 28.515564 -248.925334)
				)
				(arc
					(start 29.988764 -248.925334)
					(mid 29.997744 -248.929054)
					(end 30.001464 -248.938034)
				)
			)
		)
	)
	(zone
		(layer "In1.Cu")
		(hatch none 0.5)
		(connect_pads
			(clearance 0)
		)
		(min_thickness 0.25)
		(keepout
			(tracks not_allowed)
			(vias allowed)
			(pads allowed)
			(copperpour not_allowed)
			(footprints allowed)
		)
		(placement
			(enabled no)
			(sheetname "")
		)
		(fill
			(thermal_gap 0.5)
			(thermal_bridge_width 0.5)
			(island_removal_mode 0)
		)
		(polygon
			(pts
				(arc
					(start 432.30546 -233.282236)
					(mid 432.30174 -233.291216)
					(end 432.29276 -233.294936)
				)
				(arc
					(start 430.81956 -233.294936)
					(mid 430.81058 -233.291216)
					(end 430.80686 -233.282236)
				)
				(arc
					(start 430.80686 -232.787698)
					(mid 430.81058 -232.778718)
					(end 430.81956 -232.774998)
				)
				(arc
					(start 432.29276 -232.774998)
					(mid 432.30174 -232.778718)
					(end 432.30546 -232.787698)
				)
			)
		)
	)
	(zone
		(layer "In1.Cu")
		(hatch none 0.5)
		(connect_pads
			(clearance 0)
		)
		(min_thickness 0.25)
		(keepout
			(tracks not_allowed)
			(vias allowed)
			(pads allowed)
			(copperpour not_allowed)
			(footprints allowed)
		)
		(placement
			(enabled no)
			(sheetname "")
		)
		(fill
			(thermal_gap 0.5)
			(thermal_bridge_width 0.5)
			(island_removal_mode 0)
		)
		(polygon
			(pts
				(arc
					(start 266.29741 -218.832176)
					(mid 266.29369 -218.841156)
					(end 266.28471 -218.844876)
				)
				(arc
					(start 264.81151 -218.844876)
					(mid 264.80253 -218.841156)
					(end 264.79881 -218.832176)
				)
				(arc
					(start 264.79881 -218.337638)
					(mid 264.80253 -218.328658)
					(end 264.81151 -218.324938)
				)
				(arc
					(start 266.28471 -218.324938)
					(mid 266.29369 -218.328658)
					(end 266.29741 -218.337638)
				)
			)
		)
	)
	(zone
		(layer "In1.Cu")
		(hatch none 0.5)
		(connect_pads
			(clearance 0)
		)
		(min_thickness 0.25)
		(keepout
			(tracks not_allowed)
			(vias allowed)
			(pads allowed)
			(copperpour not_allowed)
			(footprints allowed)
		)
		(placement
			(enabled no)
			(sheetname "")
		)
		(fill
			(thermal_gap 0.5)
			(thermal_bridge_width 0.5)
			(island_removal_mode 0)
		)
		(polygon
			(pts
				(arc
					(start 439.849514 -222.23222)
					(mid 439.845794 -222.2412)
					(end 439.836814 -222.24492)
				)
				(arc
					(start 438.363614 -222.24492)
					(mid 438.354634 -222.2412)
					(end 438.350914 -222.23222)
				)
				(arc
					(start 438.350914 -221.737682)
					(mid 438.354634 -221.728702)
					(end 438.363614 -221.724982)
				)
				(arc
					(start 439.836814 -221.724982)
					(mid 439.845794 -221.728702)
					(end 439.849514 -221.737682)
				)
			)
		)
	)
	(zone
		(layer "In1.Cu")
		(hatch none 0.5)
		(connect_pads
			(clearance 0)
		)
		(min_thickness 0.25)
		(keepout
			(tracks not_allowed)
			(vias allowed)
			(pads allowed)
			(copperpour not_allowed)
			(footprints allowed)
		)
		(placement
			(enabled no)
			(sheetname "")
		)
		(fill
			(thermal_gap 0.5)
			(thermal_bridge_width 0.5)
			(island_removal_mode 0)
		)
		(polygon
			(pts
				(arc
					(start 25.901396 -279.182576)
					(mid 25.897676 -279.191556)
					(end 25.888696 -279.195276)
				)
				(arc
					(start 24.415496 -279.195276)
					(mid 24.406516 -279.191556)
					(end 24.402796 -279.182576)
				)
				(arc
					(start 24.402796 -278.688038)
					(mid 24.406516 -278.679058)
					(end 24.415496 -278.675338)
				)
				(arc
					(start 25.888696 -278.675338)
					(mid 25.897676 -278.679058)
					(end 25.901396 -278.688038)
				)
			)
		)
	)
	(zone
		(layer "In1.Cu")
		(hatch none 0.5)
		(connect_pads
			(clearance 0)
		)
		(min_thickness 0.25)
		(keepout
			(tracks not_allowed)
			(vias allowed)
			(pads allowed)
			(copperpour not_allowed)
			(footprints allowed)
		)
		(placement
			(enabled no)
			(sheetname "")
		)
		(fill
			(thermal_gap 0.5)
			(thermal_bridge_width 0.5)
			(island_removal_mode 0)
		)
		(polygon
			(pts
				(arc
					(start 407.998168 -399.143474)
					(mid 407.693368 -399.143474)
					(end 407.998168 -399.143474)
				)
			)
		)
	)
	(zone
		(layer "In1.Cu")
		(hatch none 0.5)
		(connect_pads
			(clearance 0)
		)
		(min_thickness 0.25)
		(keepout
			(tracks not_allowed)
			(vias allowed)
			(pads allowed)
			(copperpour not_allowed)
			(footprints allowed)
		)
		(placement
			(enabled no)
			(sheetname "")
		)
		(fill
			(thermal_gap 0.5)
			(thermal_bridge_width 0.5)
			(island_removal_mode 0)
		)
		(polygon
			(pts
				(arc
					(start 315.0997 -379.360684)
					(mid 315.119624 -379.36992)
					(end 315.141356 -379.37313)
				)
				(arc
					(start 315.33592 -379.37313)
					(mid 315.389802 -379.350812)
					(end 315.41212 -379.29693)
				)
				(arc
					(start 315.41212 -378.61113)
					(mid 315.389802 -378.557248)
					(end 315.33592 -378.53493)
				)
				(arc
					(start 315.141356 -378.53493)
					(mid 315.119612 -378.538098)
					(end 315.0997 -378.547376)
				)
				(arc
					(start 314.803536 -378.740162)
					(mid 314.761852 -378.752384)
					(end 314.720224 -378.739908)
				)
				(arc
					(start 314.4266 -378.547376)
					(mid 314.406676 -378.53814)
					(end 314.384944 -378.53493)
				)
				(arc
					(start 314.19038 -378.53493)
					(mid 314.136498 -378.557248)
					(end 314.11418 -378.61113)
				)
				(arc
					(start 314.11418 -379.29693)
					(mid 314.136498 -379.350812)
					(end 314.19038 -379.37313)
				)
				(arc
					(start 314.386214 -379.37313)
					(mid 314.407958 -379.369962)
					(end 314.42787 -379.360684)
				)
				(arc
					(start 314.721494 -379.168152)
					(mid 314.76315 -379.15575)
					(end 314.804806 -379.168152)
				)
			)
		)
	)
	(zone
		(layer "In1.Cu")
		(hatch none 0.5)
		(connect_pads
			(clearance 0)
		)
		(min_thickness 0.25)
		(keepout
			(tracks not_allowed)
			(vias allowed)
			(pads allowed)
			(copperpour not_allowed)
			(footprints allowed)
		)
		(placement
			(enabled no)
			(sheetname "")
		)
		(fill
			(thermal_gap 0.5)
			(thermal_bridge_width 0.5)
			(island_removal_mode 0)
		)
		(polygon
			(pts
				(arc
					(start 443.2935 -265.582146)
					(mid 443.28978 -265.591126)
					(end 443.2808 -265.594846)
				)
				(arc
					(start 441.8076 -265.594846)
					(mid 441.79862 -265.591126)
					(end 441.7949 -265.582146)
				)
				(arc
					(start 441.7949 -265.087608)
					(mid 441.79862 -265.078628)
					(end 441.8076 -265.074908)
				)
				(arc
					(start 443.2808 -265.074908)
					(mid 443.28978 -265.078628)
					(end 443.2935 -265.087608)
				)
			)
		)
	)
	(zone
		(layer "In1.Cu")
		(hatch none 0.5)
		(connect_pads
			(clearance 0)
		)
		(min_thickness 0.25)
		(keepout
			(tracks not_allowed)
			(vias allowed)
			(pads allowed)
			(copperpour not_allowed)
			(footprints allowed)
		)
		(placement
			(enabled no)
			(sheetname "")
		)
		(fill
			(thermal_gap 0.5)
			(thermal_bridge_width 0.5)
			(island_removal_mode 0)
		)
		(polygon
			(pts
				(arc
					(start 187.809378 -314.88253)
					(mid 187.805658 -314.89151)
					(end 187.796678 -314.89523)
				)
				(arc
					(start 186.323478 -314.89523)
					(mid 186.314498 -314.89151)
					(end 186.310778 -314.88253)
				)
				(arc
					(start 186.310778 -314.387992)
					(mid 186.314498 -314.379012)
					(end 186.323478 -314.375292)
				)
				(arc
					(start 187.796678 -314.375292)
					(mid 187.805658 -314.379012)
					(end 187.809378 -314.387992)
				)
			)
		)
	)
	(zone
		(layer "In1.Cu")
		(hatch none 0.5)
		(connect_pads
			(clearance 0)
		)
		(min_thickness 0.25)
		(keepout
			(tracks not_allowed)
			(vias allowed)
			(pads allowed)
			(copperpour not_allowed)
			(footprints allowed)
		)
		(placement
			(enabled no)
			(sheetname "")
		)
		(fill
			(thermal_gap 0.5)
			(thermal_bridge_width 0.5)
			(island_removal_mode 0)
		)
		(polygon
			(pts
				(arc
					(start 56.077358 -240.082578)
					(mid 56.073638 -240.091558)
					(end 56.064658 -240.095278)
				)
				(arc
					(start 54.591458 -240.095278)
					(mid 54.582478 -240.091558)
					(end 54.578758 -240.082578)
				)
				(arc
					(start 54.578758 -239.58804)
					(mid 54.582478 -239.57906)
					(end 54.591458 -239.57534)
				)
				(arc
					(start 56.064658 -239.57534)
					(mid 56.073638 -239.57906)
					(end 56.077358 -239.58804)
				)
			)
		)
	)
	(zone
		(layer "In1.Cu")
		(hatch none 0.5)
		(connect_pads
			(clearance 0)
		)
		(min_thickness 0.25)
		(keepout
			(tracks not_allowed)
			(vias allowed)
			(pads allowed)
			(copperpour not_allowed)
			(footprints allowed)
		)
		(placement
			(enabled no)
			(sheetname "")
		)
		(fill
			(thermal_gap 0.5)
			(thermal_bridge_width 0.5)
			(island_removal_mode 0)
		)
		(polygon
			(pts
				(arc
					(start 443.2935 -297.88231)
					(mid 443.28978 -297.89129)
					(end 443.2808 -297.89501)
				)
				(arc
					(start 441.8076 -297.89501)
					(mid 441.79862 -297.89129)
					(end 441.7949 -297.88231)
				)
				(arc
					(start 441.7949 -297.387772)
					(mid 441.79862 -297.378792)
					(end 441.8076 -297.375072)
				)
				(arc
					(start 443.2808 -297.375072)
					(mid 443.28978 -297.378792)
					(end 443.2935 -297.387772)
				)
			)
		)
	)
	(zone
		(layer "In1.Cu")
		(hatch none 0.5)
		(connect_pads
			(clearance 0)
		)
		(min_thickness 0.25)
		(keepout
			(tracks not_allowed)
			(vias allowed)
			(pads allowed)
			(copperpour not_allowed)
			(footprints allowed)
		)
		(placement
			(enabled no)
			(sheetname "")
		)
		(fill
			(thermal_gap 0.5)
			(thermal_bridge_width 0.5)
			(island_removal_mode 0)
		)
		(polygon
			(pts
				(arc
					(start 16.92148 -107.466892)
					(mid 16.914041 -107.448931)
					(end 16.89608 -107.441492)
				)
				(arc
					(start 16.680942 -107.441492)
					(mid 16.662981 -107.434053)
					(end 16.655542 -107.416092)
				)
				(arc
					(start 16.655542 -107.406948)
					(mid 16.648103 -107.388987)
					(end 16.630142 -107.381548)
				)
				(arc
					(start 16.515334 -107.381548)
					(mid 16.445452 -107.410757)
					(end 16.416782 -107.480862)
				)
				(arc
					(start 16.416782 -107.782106)
					(mid 16.445452 -107.852211)
					(end 16.515334 -107.88142)
				)
				(arc
					(start 16.630142 -107.88142)
					(mid 16.648103 -107.873981)
					(end 16.655542 -107.85602)
				)
				(arc
					(start 16.655542 -107.846876)
					(mid 16.662981 -107.828915)
					(end 16.680942 -107.821476)
				)
				(arc
					(start 16.89608 -107.821476)
					(mid 16.914041 -107.814037)
					(end 16.92148 -107.796076)
				)
			)
		)
	)
	(zone
		(layer "In1.Cu")
		(hatch none 0.5)
		(connect_pads
			(clearance 0)
		)
		(min_thickness 0.25)
		(keepout
			(tracks not_allowed)
			(vias allowed)
			(pads allowed)
			(copperpour not_allowed)
			(footprints allowed)
		)
		(placement
			(enabled no)
			(sheetname "")
		)
		(fill
			(thermal_gap 0.5)
			(thermal_bridge_width 0.5)
			(island_removal_mode 0)
		)
		(polygon
			(pts
				(arc
					(start 18.357342 -310.632348)
					(mid 18.353622 -310.641328)
					(end 18.344642 -310.645048)
				)
				(arc
					(start 16.871442 -310.645048)
					(mid 16.862462 -310.641328)
					(end 16.858742 -310.632348)
				)
				(arc
					(start 16.858742 -310.13781)
					(mid 16.862462 -310.12883)
					(end 16.871442 -310.12511)
				)
				(arc
					(start 18.344642 -310.12511)
					(mid 18.353622 -310.12883)
					(end 18.357342 -310.13781)
				)
			)
		)
	)
	(zone
		(layer "In1.Cu")
		(hatch none 0.5)
		(connect_pads
			(clearance 0)
		)
		(min_thickness 0.25)
		(keepout
			(tracks not_allowed)
			(vias allowed)
			(pads allowed)
			(copperpour not_allowed)
			(footprints allowed)
		)
		(placement
			(enabled no)
			(sheetname "")
		)
		(fill
			(thermal_gap 0.5)
			(thermal_bridge_width 0.5)
			(island_removal_mode 0)
		)
		(polygon
			(pts
				(arc
					(start 130.56108 -389.467344)
					(mid 130.18008 -389.467344)
					(end 130.56108 -389.467344)
				)
			)
		)
	)
	(zone
		(layer "In1.Cu")
		(hatch none 0.5)
		(connect_pads
			(clearance 0)
		)
		(min_thickness 0.25)
		(keepout
			(tracks not_allowed)
			(vias allowed)
			(pads allowed)
			(copperpour not_allowed)
			(footprints allowed)
		)
		(placement
			(enabled no)
			(sheetname "")
		)
		(fill
			(thermal_gap 0.5)
			(thermal_bridge_width 0.5)
			(island_removal_mode 0)
		)
		(polygon
			(pts
				(arc
					(start 48.533304 -202.682348)
					(mid 48.529584 -202.691328)
					(end 48.520604 -202.695048)
				)
				(arc
					(start 47.047404 -202.695048)
					(mid 47.038424 -202.691328)
					(end 47.034704 -202.682348)
				)
				(arc
					(start 47.034704 -202.18781)
					(mid 47.038424 -202.17883)
					(end 47.047404 -202.17511)
				)
				(arc
					(start 48.520604 -202.17511)
					(mid 48.529584 -202.17883)
					(end 48.533304 -202.18781)
				)
			)
		)
	)
	(zone
		(layer "In1.Cu")
		(hatch none 0.5)
		(connect_pads
			(clearance 0)
		)
		(min_thickness 0.25)
		(keepout
			(tracks not_allowed)
			(vias allowed)
			(pads allowed)
			(copperpour not_allowed)
			(footprints allowed)
		)
		(placement
			(enabled no)
			(sheetname "")
		)
		(fill
			(thermal_gap 0.5)
			(thermal_bridge_width 0.5)
			(island_removal_mode 0)
		)
		(polygon
			(pts
				(arc
					(start 84.318856 -391.319258)
					(mid 84.445856 -391.446258)
					(end 84.572856 -391.319258)
				)
				(arc
					(start 84.572856 -391.243058)
					(mid 84.445856 -391.116058)
					(end 84.318856 -391.243058)
				)
			)
		)
	)
	(zone
		(layer "In1.Cu")
		(hatch none 0.5)
		(connect_pads
			(clearance 0)
		)
		(min_thickness 0.25)
		(keepout
			(tracks not_allowed)
			(vias allowed)
			(pads allowed)
			(copperpour not_allowed)
			(footprints allowed)
		)
		(placement
			(enabled no)
			(sheetname "")
		)
		(fill
			(thermal_gap 0.5)
			(thermal_bridge_width 0.5)
			(island_removal_mode 0)
		)
		(polygon
			(pts
				(arc
					(start 48.533304 -318.282574)
					(mid 48.529584 -318.291554)
					(end 48.520604 -318.295274)
				)
				(arc
					(start 47.047404 -318.295274)
					(mid 47.038424 -318.291554)
					(end 47.034704 -318.282574)
				)
				(arc
					(start 47.034704 -317.788036)
					(mid 47.038424 -317.779056)
					(end 47.047404 -317.775336)
				)
				(arc
					(start 48.520604 -317.775336)
					(mid 48.529584 -317.779056)
					(end 48.533304 -317.788036)
				)
			)
		)
	)
	(zone
		(layer "In1.Cu")
		(hatch none 0.5)
		(connect_pads
			(clearance 0)
		)
		(min_thickness 0.25)
		(keepout
			(tracks not_allowed)
			(vias allowed)
			(pads allowed)
			(copperpour not_allowed)
			(footprints allowed)
		)
		(placement
			(enabled no)
			(sheetname "")
		)
		(fill
			(thermal_gap 0.5)
			(thermal_bridge_width 0.5)
			(island_removal_mode 0)
		)
		(polygon
			(pts
				(arc
					(start 380.161292 -393.69238)
					(mid 379.780292 -393.69238)
					(end 380.161292 -393.69238)
				)
			)
		)
	)
	(zone
		(layer "In1.Cu")
		(hatch none 0.5)
		(connect_pads
			(clearance 0)
		)
		(min_thickness 0.25)
		(keepout
			(tracks not_allowed)
			(vias allowed)
			(pads allowed)
			(copperpour not_allowed)
			(footprints allowed)
		)
		(placement
			(enabled no)
			(sheetname "")
		)
		(fill
			(thermal_gap 0.5)
			(thermal_bridge_width 0.5)
			(island_removal_mode 0)
		)
		(polygon
			(pts
				(arc
					(start 450.8373 -310.632094)
					(mid 450.83358 -310.641074)
					(end 450.8246 -310.644794)
				)
				(arc
					(start 449.3514 -310.644794)
					(mid 449.34242 -310.641074)
					(end 449.3387 -310.632094)
				)
				(arc
					(start 449.3387 -310.137556)
					(mid 449.34242 -310.128576)
					(end 449.3514 -310.124856)
				)
				(arc
					(start 450.8246 -310.124856)
					(mid 450.83358 -310.128576)
					(end 450.8373 -310.137556)
				)
			)
		)
	)
	(zone
		(layer "In1.Cu")
		(hatch none 0.5)
		(connect_pads
			(clearance 0)
		)
		(min_thickness 0.25)
		(keepout
			(tracks not_allowed)
			(vias allowed)
			(pads allowed)
			(copperpour not_allowed)
			(footprints allowed)
		)
		(placement
			(enabled no)
			(sheetname "")
		)
		(fill
			(thermal_gap 0.5)
			(thermal_bridge_width 0.5)
			(island_removal_mode 0)
		)
		(polygon
			(pts
				(arc
					(start 303.461166 -393.69238)
					(mid 303.080166 -393.69238)
					(end 303.461166 -393.69238)
				)
			)
		)
	)
	(zone
		(layer "In1.Cu")
		(hatch none 0.5)
		(connect_pads
			(clearance 0)
		)
		(min_thickness 0.25)
		(keepout
			(tracks not_allowed)
			(vias allowed)
			(pads allowed)
			(copperpour not_allowed)
			(footprints allowed)
		)
		(placement
			(enabled no)
			(sheetname "")
		)
		(fill
			(thermal_gap 0.5)
			(thermal_bridge_width 0.5)
			(island_removal_mode 0)
		)
		(polygon
			(pts
				(arc
					(start 18.357342 -295.332404)
					(mid 18.353622 -295.341384)
					(end 18.344642 -295.345104)
				)
				(arc
					(start 16.871442 -295.345104)
					(mid 16.862462 -295.341384)
					(end 16.858742 -295.332404)
				)
				(arc
					(start 16.858742 -294.837866)
					(mid 16.862462 -294.828886)
					(end 16.871442 -294.825166)
				)
				(arc
					(start 18.344642 -294.825166)
					(mid 18.353622 -294.828886)
					(end 18.357342 -294.837866)
				)
			)
		)
	)
	(zone
		(layer "In1.Cu")
		(hatch none 0.5)
		(connect_pads
			(clearance 0)
		)
		(min_thickness 0.25)
		(keepout
			(tracks not_allowed)
			(vias allowed)
			(pads allowed)
			(copperpour not_allowed)
			(footprints allowed)
		)
		(placement
			(enabled no)
			(sheetname "")
		)
		(fill
			(thermal_gap 0.5)
			(thermal_bridge_width 0.5)
			(island_removal_mode 0)
		)
		(polygon
			(pts
				(arc
					(start 195.353432 -246.882412)
					(mid 195.349712 -246.891392)
					(end 195.340732 -246.895112)
				)
				(arc
					(start 193.867532 -246.895112)
					(mid 193.858552 -246.891392)
					(end 193.854832 -246.882412)
				)
				(arc
					(start 193.854832 -246.387874)
					(mid 193.858552 -246.378894)
					(end 193.867532 -246.375174)
				)
				(arc
					(start 195.340732 -246.375174)
					(mid 195.349712 -246.378894)
					(end 195.353432 -246.387874)
				)
			)
		)
	)
	(zone
		(layer "In1.Cu")
		(hatch none 0.5)
		(connect_pads
			(clearance 0)
		)
		(min_thickness 0.25)
		(keepout
			(tracks not_allowed)
			(vias allowed)
			(pads allowed)
			(copperpour not_allowed)
			(footprints allowed)
		)
		(placement
			(enabled no)
			(sheetname "")
		)
		(fill
			(thermal_gap 0.5)
			(thermal_bridge_width 0.5)
			(island_removal_mode 0)
		)
		(polygon
			(pts
				(arc
					(start 300.57344 -206.932276)
					(mid 300.56972 -206.941256)
					(end 300.56074 -206.944976)
				)
				(arc
					(start 299.08754 -206.944976)
					(mid 299.07856 -206.941256)
					(end 299.07484 -206.932276)
				)
				(arc
					(start 299.07484 -206.437738)
					(mid 299.07856 -206.428758)
					(end 299.08754 -206.425038)
				)
				(arc
					(start 300.56074 -206.425038)
					(mid 300.56972 -206.428758)
					(end 300.57344 -206.437738)
				)
			)
		)
	)
	(zone
		(layer "In1.Cu")
		(hatch none 0.5)
		(connect_pads
			(clearance 0)
		)
		(min_thickness 0.25)
		(keepout
			(tracks not_allowed)
			(vias allowed)
			(pads allowed)
			(copperpour not_allowed)
			(footprints allowed)
		)
		(placement
			(enabled no)
			(sheetname "")
		)
		(fill
			(thermal_gap 0.5)
			(thermal_bridge_width 0.5)
			(island_removal_mode 0)
		)
		(polygon
			(pts
				(arc
					(start 413.117284 -229.882192)
					(mid 413.113564 -229.891172)
					(end 413.104584 -229.894892)
				)
				(arc
					(start 411.631384 -229.894892)
					(mid 411.622404 -229.891172)
					(end 411.618684 -229.882192)
				)
				(arc
					(start 411.618684 -229.387654)
					(mid 411.622404 -229.378674)
					(end 411.631384 -229.374954)
				)
				(arc
					(start 413.104584 -229.374954)
					(mid 413.113564 -229.378674)
					(end 413.117284 -229.387654)
				)
			)
		)
	)
	(zone
		(layer "In1.Cu")
		(hatch none 0.5)
		(connect_pads
			(clearance 0)
		)
		(min_thickness 0.25)
		(keepout
			(tracks not_allowed)
			(vias allowed)
			(pads allowed)
			(copperpour not_allowed)
			(footprints allowed)
		)
		(placement
			(enabled no)
			(sheetname "")
		)
		(fill
			(thermal_gap 0.5)
			(thermal_bridge_width 0.5)
			(island_removal_mode 0)
		)
		(polygon
			(pts
				(arc
					(start 308.117494 -254.53213)
					(mid 308.113774 -254.54111)
					(end 308.104794 -254.54483)
				)
				(arc
					(start 306.631594 -254.54483)
					(mid 306.622614 -254.54111)
					(end 306.618894 -254.53213)
				)
				(arc
					(start 306.618894 -254.037592)
					(mid 306.622614 -254.028612)
					(end 306.631594 -254.024892)
				)
				(arc
					(start 308.104794 -254.024892)
					(mid 308.113774 -254.028612)
					(end 308.117494 -254.037592)
				)
			)
		)
	)
	(zone
		(layer "In1.Cu")
		(hatch none 0.5)
		(connect_pads
			(clearance 0)
		)
		(min_thickness 0.25)
		(keepout
			(tracks not_allowed)
			(vias allowed)
			(pads allowed)
			(copperpour not_allowed)
			(footprints allowed)
		)
		(placement
			(enabled no)
			(sheetname "")
		)
		(fill
			(thermal_gap 0.5)
			(thermal_bridge_width 0.5)
			(island_removal_mode 0)
		)
		(polygon
			(pts
				(arc
					(start 145.37944 -32.13989)
					(mid 145.401758 -32.193772)
					(end 145.45564 -32.21609)
				)
				(arc
					(start 145.81124 -32.21609)
					(mid 145.865122 -32.193772)
					(end 145.88744 -32.13989)
				)
				(arc
					(start 145.88744 -30.23489)
					(mid 145.865122 -30.181008)
					(end 145.81124 -30.15869)
				)
				(arc
					(start 145.45564 -30.15869)
					(mid 145.401758 -30.181008)
					(end 145.37944 -30.23489)
				)
			)
		)
	)
	(zone
		(layer "In1.Cu")
		(hatch none 0.5)
		(connect_pads
			(clearance 0)
		)
		(min_thickness 0.25)
		(keepout
			(tracks not_allowed)
			(vias allowed)
			(pads allowed)
			(copperpour not_allowed)
			(footprints allowed)
		)
		(placement
			(enabled no)
			(sheetname "")
		)
		(fill
			(thermal_gap 0.5)
			(thermal_bridge_width 0.5)
			(island_removal_mode 0)
		)
		(polygon
			(pts
				(arc
					(start 428.205392 -273.232118)
					(mid 428.201672 -273.241098)
					(end 428.192692 -273.244818)
				)
				(arc
					(start 426.719492 -273.244818)
					(mid 426.710512 -273.241098)
					(end 426.706792 -273.232118)
				)
				(arc
					(start 426.706792 -272.73758)
					(mid 426.710512 -272.7286)
					(end 426.719492 -272.72488)
				)
				(arc
					(start 428.192692 -272.72488)
					(mid 428.201672 -272.7286)
					(end 428.205392 -272.73758)
				)
			)
		)
	)
	(zone
		(layer "In1.Cu")
		(hatch none 0.5)
		(connect_pads
			(clearance 0)
		)
		(min_thickness 0.25)
		(keepout
			(tracks not_allowed)
			(vias allowed)
			(pads allowed)
			(copperpour not_allowed)
			(footprints allowed)
		)
		(placement
			(enabled no)
			(sheetname "")
		)
		(fill
			(thermal_gap 0.5)
			(thermal_bridge_width 0.5)
			(island_removal_mode 0)
		)
		(polygon
			(pts
				(arc
					(start 187.809378 -226.482402)
					(mid 187.805658 -226.491382)
					(end 187.796678 -226.495102)
				)
				(arc
					(start 186.323478 -226.495102)
					(mid 186.314498 -226.491382)
					(end 186.310778 -226.482402)
				)
				(arc
					(start 186.310778 -225.987864)
					(mid 186.314498 -225.978884)
					(end 186.323478 -225.975164)
				)
				(arc
					(start 187.796678 -225.975164)
					(mid 187.805658 -225.978884)
					(end 187.809378 -225.987864)
				)
			)
		)
	)
	(zone
		(layer "In1.Cu")
		(hatch none 0.5)
		(connect_pads
			(clearance 0)
		)
		(min_thickness 0.25)
		(keepout
			(tracks not_allowed)
			(vias allowed)
			(pads allowed)
			(copperpour not_allowed)
			(footprints allowed)
		)
		(placement
			(enabled no)
			(sheetname "")
		)
		(fill
			(thermal_gap 0.5)
			(thermal_bridge_width 0.5)
			(island_removal_mode 0)
		)
		(polygon
			(pts
				(arc
					(start 195.353432 -279.182576)
					(mid 195.349712 -279.191556)
					(end 195.340732 -279.195276)
				)
				(arc
					(start 193.867532 -279.195276)
					(mid 193.858552 -279.191556)
					(end 193.854832 -279.182576)
				)
				(arc
					(start 193.854832 -278.688038)
					(mid 193.858552 -278.679058)
					(end 193.867532 -278.675338)
				)
				(arc
					(start 195.340732 -278.675338)
					(mid 195.349712 -278.679058)
					(end 195.353432 -278.688038)
				)
			)
		)
	)
	(zone
		(layer "In1.Cu")
		(hatch none 0.5)
		(connect_pads
			(clearance 0)
		)
		(min_thickness 0.25)
		(keepout
			(tracks not_allowed)
			(vias allowed)
			(pads allowed)
			(copperpour not_allowed)
			(footprints allowed)
		)
		(placement
			(enabled no)
			(sheetname "")
		)
		(fill
			(thermal_gap 0.5)
			(thermal_bridge_width 0.5)
			(island_removal_mode 0)
		)
		(polygon
			(pts
				(arc
					(start 351.697798 -392.30427)
					(mid 351.392998 -392.30427)
					(end 351.697798 -392.30427)
				)
			)
		)
	)
	(zone
		(layer "In1.Cu")
		(hatch none 0.5)
		(connect_pads
			(clearance 0)
		)
		(min_thickness 0.25)
		(keepout
			(tracks not_allowed)
			(vias allowed)
			(pads allowed)
			(copperpour not_allowed)
			(footprints allowed)
		)
		(placement
			(enabled no)
			(sheetname "")
		)
		(fill
			(thermal_gap 0.5)
			(thermal_bridge_width 0.5)
			(island_removal_mode 0)
		)
		(polygon
			(pts
				(arc
					(start 60.191142 -391.319258)
					(mid 60.318142 -391.446258)
					(end 60.445142 -391.319258)
				)
				(arc
					(start 60.445142 -391.243058)
					(mid 60.318142 -391.116058)
					(end 60.191142 -391.243058)
				)
			)
		)
	)
	(zone
		(layer "In1.Cu")
		(hatch none 0.5)
		(connect_pads
			(clearance 0)
		)
		(min_thickness 0.25)
		(keepout
			(tracks not_allowed)
			(vias allowed)
			(pads allowed)
			(copperpour not_allowed)
			(footprints allowed)
		)
		(placement
			(enabled no)
			(sheetname "")
		)
		(fill
			(thermal_gap 0.5)
			(thermal_bridge_width 0.5)
			(island_removal_mode 0)
		)
		(polygon
			(pts
				(arc
					(start 123.90882 -36.929568)
					(mid 123.962702 -36.90725)
					(end 123.98502 -36.853368)
				)
				(arc
					(start 123.98502 -36.497768)
					(mid 123.962702 -36.443886)
					(end 123.90882 -36.421568)
				)
				(arc
					(start 122.00382 -36.421568)
					(mid 121.949938 -36.443886)
					(end 121.92762 -36.497768)
				)
				(arc
					(start 121.92762 -36.853368)
					(mid 121.949938 -36.90725)
					(end 122.00382 -36.929568)
				)
			)
		)
	)
	(zone
		(layer "In1.Cu")
		(hatch none 0.5)
		(connect_pads
			(clearance 0)
		)
		(min_thickness 0.25)
		(keepout
			(tracks not_allowed)
			(vias allowed)
			(pads allowed)
			(copperpour not_allowed)
			(footprints allowed)
		)
		(placement
			(enabled no)
			(sheetname "")
		)
		(fill
			(thermal_gap 0.5)
			(thermal_bridge_width 0.5)
			(island_removal_mode 0)
		)
		(polygon
			(pts
				(arc
					(start 30.001464 -217.982546)
					(mid 29.997744 -217.991526)
					(end 29.988764 -217.995246)
				)
				(arc
					(start 28.515564 -217.995246)
					(mid 28.506584 -217.991526)
					(end 28.502864 -217.982546)
				)
				(arc
					(start 28.502864 -217.488008)
					(mid 28.506584 -217.479028)
					(end 28.515564 -217.475308)
				)
				(arc
					(start 29.988764 -217.475308)
					(mid 29.997744 -217.479028)
					(end 30.001464 -217.488008)
				)
			)
		)
	)
	(zone
		(layer "In1.Cu")
		(hatch none 0.5)
		(connect_pads
			(clearance 0)
		)
		(min_thickness 0.25)
		(keepout
			(tracks not_allowed)
			(vias allowed)
			(pads allowed)
			(copperpour not_allowed)
			(footprints allowed)
		)
		(placement
			(enabled no)
			(sheetname "")
		)
		(fill
			(thermal_gap 0.5)
			(thermal_bridge_width 0.5)
			(island_removal_mode 0)
		)
		(polygon
			(pts
				(arc
					(start 131.760976 -389.467344)
					(mid 131.379976 -389.467344)
					(end 131.760976 -389.467344)
				)
			)
		)
	)
	(zone
		(layer "In1.Cu")
		(hatch none 0.5)
		(connect_pads
			(clearance 0)
		)
		(min_thickness 0.25)
		(keepout
			(tracks not_allowed)
			(vias allowed)
			(pads allowed)
			(copperpour not_allowed)
			(footprints allowed)
		)
		(placement
			(enabled no)
			(sheetname "")
		)
		(fill
			(thermal_gap 0.5)
			(thermal_bridge_width 0.5)
			(island_removal_mode 0)
		)
		(polygon
			(pts
				(arc
					(start 412.68904 -397.156432)
					(mid 412.30804 -397.156432)
					(end 412.68904 -397.156432)
				)
			)
		)
	)
	(zone
		(layer "In1.Cu")
		(hatch none 0.5)
		(connect_pads
			(clearance 0)
		)
		(min_thickness 0.25)
		(keepout
			(tracks not_allowed)
			(vias allowed)
			(pads allowed)
			(copperpour not_allowed)
			(footprints allowed)
		)
		(placement
			(enabled no)
			(sheetname "")
		)
		(fill
			(thermal_gap 0.5)
			(thermal_bridge_width 0.5)
			(island_removal_mode 0)
		)
		(polygon
			(pts
				(arc
					(start 206.5782 -217.735404)
					(mid 205.9178 -217.735404)
					(end 206.5782 -217.735404)
				)
			)
		)
	)
	(zone
		(layer "In1.Cu")
		(hatch none 0.5)
		(connect_pads
			(clearance 0)
		)
		(min_thickness 0.25)
		(keepout
			(tracks not_allowed)
			(vias allowed)
			(pads allowed)
			(copperpour not_allowed)
			(footprints allowed)
		)
		(placement
			(enabled no)
			(sheetname "")
		)
		(fill
			(thermal_gap 0.5)
			(thermal_bridge_width 0.5)
			(island_removal_mode 0)
		)
		(polygon
			(pts
				(arc
					(start 25.901396 -290.232592)
					(mid 25.897676 -290.241572)
					(end 25.888696 -290.245292)
				)
				(arc
					(start 24.415496 -290.245292)
					(mid 24.406516 -290.241572)
					(end 24.402796 -290.232592)
				)
				(arc
					(start 24.402796 -289.738054)
					(mid 24.406516 -289.729074)
					(end 24.415496 -289.725354)
				)
				(arc
					(start 25.888696 -289.725354)
					(mid 25.897676 -289.729074)
					(end 25.901396 -289.738054)
				)
			)
		)
	)
	(zone
		(layer "In1.Cu")
		(hatch none 0.5)
		(connect_pads
			(clearance 0)
		)
		(min_thickness 0.25)
		(keepout
			(tracks not_allowed)
			(vias allowed)
			(pads allowed)
			(copperpour not_allowed)
			(footprints allowed)
		)
		(placement
			(enabled no)
			(sheetname "")
		)
		(fill
			(thermal_gap 0.5)
			(thermal_bridge_width 0.5)
			(island_removal_mode 0)
		)
		(polygon
			(pts
				(arc
					(start 25.901396 -229.882446)
					(mid 25.897676 -229.891426)
					(end 25.888696 -229.895146)
				)
				(arc
					(start 24.415496 -229.895146)
					(mid 24.406516 -229.891426)
					(end 24.402796 -229.882446)
				)
				(arc
					(start 24.402796 -229.387908)
					(mid 24.406516 -229.378928)
					(end 24.415496 -229.375208)
				)
				(arc
					(start 25.888696 -229.375208)
					(mid 25.897676 -229.378928)
					(end 25.901396 -229.387908)
				)
			)
		)
	)
	(zone
		(layer "In1.Cu")
		(hatch none 0.5)
		(connect_pads
			(clearance 0)
		)
		(min_thickness 0.25)
		(keepout
			(tracks not_allowed)
			(vias allowed)
			(pads allowed)
			(copperpour not_allowed)
			(footprints allowed)
		)
		(placement
			(enabled no)
			(sheetname "")
		)
		(fill
			(thermal_gap 0.5)
			(thermal_bridge_width 0.5)
			(island_removal_mode 0)
		)
		(polygon
			(pts
				(arc
					(start 87.588852 -386.003292)
					(mid 87.207852 -386.003292)
					(end 87.588852 -386.003292)
				)
			)
		)
	)
	(zone
		(layer "In1.Cu")
		(hatch none 0.5)
		(connect_pads
			(clearance 0)
		)
		(min_thickness 0.25)
		(keepout
			(tracks not_allowed)
			(vias allowed)
			(pads allowed)
			(copperpour not_allowed)
			(footprints allowed)
		)
		(placement
			(enabled no)
			(sheetname "")
		)
		(fill
			(thermal_gap 0.5)
			(thermal_bridge_width 0.5)
			(island_removal_mode 0)
		)
		(polygon
			(pts
				(arc
					(start 288.929318 -248.58218)
					(mid 288.925598 -248.59116)
					(end 288.916618 -248.59488)
				)
				(arc
					(start 287.443418 -248.59488)
					(mid 287.434438 -248.59116)
					(end 287.430718 -248.58218)
				)
				(arc
					(start 287.430718 -248.087642)
					(mid 287.434438 -248.078662)
					(end 287.443418 -248.074942)
				)
				(arc
					(start 288.916618 -248.074942)
					(mid 288.925598 -248.078662)
					(end 288.929318 -248.087642)
				)
			)
		)
	)
	(zone
		(layer "In1.Cu")
		(hatch none 0.5)
		(connect_pads
			(clearance 0)
		)
		(min_thickness 0.25)
		(keepout
			(tracks not_allowed)
			(vias allowed)
			(pads allowed)
			(copperpour not_allowed)
			(footprints allowed)
		)
		(placement
			(enabled no)
			(sheetname "")
		)
		(fill
			(thermal_gap 0.5)
			(thermal_bridge_width 0.5)
			(island_removal_mode 0)
		)
		(polygon
			(pts
				(arc
					(start 419.998144 -399.143474)
					(mid 419.693344 -399.143474)
					(end 419.998144 -399.143474)
				)
			)
		)
	)
	(zone
		(layer "In1.Cu")
		(hatch none 0.5)
		(connect_pads
			(clearance 0)
		)
		(min_thickness 0.25)
		(keepout
			(tracks not_allowed)
			(vias allowed)
			(pads allowed)
			(copperpour not_allowed)
			(footprints allowed)
		)
		(placement
			(enabled no)
			(sheetname "")
		)
		(fill
			(thermal_gap 0.5)
			(thermal_bridge_width 0.5)
			(island_removal_mode 0)
		)
		(polygon
			(pts
				(arc
					(start 18.357342 -248.582434)
					(mid 18.353622 -248.591414)
					(end 18.344642 -248.595134)
				)
				(arc
					(start 16.871442 -248.595134)
					(mid 16.862462 -248.591414)
					(end 16.858742 -248.582434)
				)
				(arc
					(start 16.858742 -248.087896)
					(mid 16.862462 -248.078916)
					(end 16.871442 -248.075196)
				)
				(arc
					(start 18.344642 -248.075196)
					(mid 18.353622 -248.078916)
					(end 18.357342 -248.087896)
				)
			)
		)
	)
	(zone
		(layer "In1.Cu")
		(hatch none 0.5)
		(connect_pads
			(clearance 0)
		)
		(min_thickness 0.25)
		(keepout
			(tracks not_allowed)
			(vias allowed)
			(pads allowed)
			(copperpour not_allowed)
			(footprints allowed)
		)
		(placement
			(enabled no)
			(sheetname "")
		)
		(fill
			(thermal_gap 0.5)
			(thermal_bridge_width 0.5)
			(island_removal_mode 0)
		)
		(polygon
			(pts
				(arc
					(start 435.749446 -297.88231)
					(mid 435.745726 -297.89129)
					(end 435.736746 -297.89501)
				)
				(arc
					(start 434.263546 -297.89501)
					(mid 434.254566 -297.89129)
					(end 434.250846 -297.88231)
				)
				(arc
					(start 434.250846 -297.387772)
					(mid 434.254566 -297.378792)
					(end 434.263546 -297.375072)
				)
				(arc
					(start 435.736746 -297.375072)
					(mid 435.745726 -297.378792)
					(end 435.749446 -297.387772)
				)
			)
		)
	)
	(zone
		(layer "In1.Cu")
		(hatch none 0.5)
		(connect_pads
			(clearance 0)
		)
		(min_thickness 0.25)
		(keepout
			(tracks not_allowed)
			(vias allowed)
			(pads allowed)
			(copperpour not_allowed)
			(footprints allowed)
		)
		(placement
			(enabled no)
			(sheetname "")
		)
		(fill
			(thermal_gap 0.5)
			(thermal_bridge_width 0.5)
			(island_removal_mode 0)
		)
		(polygon
			(pts
				(arc
					(start 37.545264 -275.782532)
					(mid 37.541544 -275.791512)
					(end 37.532564 -275.795232)
				)
				(arc
					(start 36.059364 -275.795232)
					(mid 36.050384 -275.791512)
					(end 36.046664 -275.782532)
				)
				(arc
					(start 36.046664 -275.287994)
					(mid 36.050384 -275.279014)
					(end 36.059364 -275.275294)
				)
				(arc
					(start 37.532564 -275.275294)
					(mid 37.541544 -275.279014)
					(end 37.545264 -275.287994)
				)
			)
		)
	)
	(zone
		(layer "In1.Cu")
		(hatch none 0.5)
		(connect_pads
			(clearance 0)
		)
		(min_thickness 0.25)
		(keepout
			(tracks not_allowed)
			(vias allowed)
			(pads allowed)
			(copperpour not_allowed)
			(footprints allowed)
		)
		(placement
			(enabled no)
			(sheetname "")
		)
		(fill
			(thermal_gap 0.5)
			(thermal_bridge_width 0.5)
			(island_removal_mode 0)
		)
		(polygon
			(pts
				(arc
					(start 450.8373 -301.2821)
					(mid 450.83358 -301.29108)
					(end 450.8246 -301.2948)
				)
				(arc
					(start 449.3514 -301.2948)
					(mid 449.34242 -301.29108)
					(end 449.3387 -301.2821)
				)
				(arc
					(start 449.3387 -300.787562)
					(mid 449.34242 -300.778582)
					(end 449.3514 -300.774862)
				)
				(arc
					(start 450.8246 -300.774862)
					(mid 450.83358 -300.778582)
					(end 450.8373 -300.787562)
				)
			)
		)
	)
	(zone
		(layer "In1.Cu")
		(hatch none 0.5)
		(connect_pads
			(clearance 0)
		)
		(min_thickness 0.25)
		(keepout
			(tracks not_allowed)
			(vias allowed)
			(pads allowed)
			(copperpour not_allowed)
			(footprints allowed)
		)
		(placement
			(enabled no)
			(sheetname "")
		)
		(fill
			(thermal_gap 0.5)
			(thermal_bridge_width 0.5)
			(island_removal_mode 0)
		)
		(polygon
			(pts
				(arc
					(start 37.545264 -216.282524)
					(mid 37.541544 -216.291504)
					(end 37.532564 -216.295224)
				)
				(arc
					(start 36.059364 -216.295224)
					(mid 36.050384 -216.291504)
					(end 36.046664 -216.282524)
				)
				(arc
					(start 36.046664 -215.787986)
					(mid 36.050384 -215.779006)
					(end 36.059364 -215.775286)
				)
				(arc
					(start 37.532564 -215.775286)
					(mid 37.541544 -215.779006)
					(end 37.545264 -215.787986)
				)
			)
		)
	)
	(zone
		(layer "In1.Cu")
		(hatch none 0.5)
		(connect_pads
			(clearance 0)
		)
		(min_thickness 0.25)
		(keepout
			(tracks not_allowed)
			(vias allowed)
			(pads allowed)
			(copperpour not_allowed)
			(footprints allowed)
		)
		(placement
			(enabled no)
			(sheetname "")
		)
		(fill
			(thermal_gap 0.5)
			(thermal_bridge_width 0.5)
			(island_removal_mode 0)
		)
		(polygon
			(pts
				(arc
					(start 45.089318 -317.432436)
					(mid 45.085598 -317.441416)
					(end 45.076618 -317.445136)
				)
				(arc
					(start 43.603418 -317.445136)
					(mid 43.594438 -317.441416)
					(end 43.590718 -317.432436)
				)
				(arc
					(start 43.590718 -316.937898)
					(mid 43.594438 -316.928918)
					(end 43.603418 -316.925198)
				)
				(arc
					(start 45.076618 -316.925198)
					(mid 45.085598 -316.928918)
					(end 45.089318 -316.937898)
				)
			)
		)
	)
	(zone
		(layer "In1.Cu")
		(hatch none 0.5)
		(connect_pads
			(clearance 0)
		)
		(min_thickness 0.25)
		(keepout
			(tracks not_allowed)
			(vias allowed)
			(pads allowed)
			(copperpour not_allowed)
			(footprints allowed)
		)
		(placement
			(enabled no)
			(sheetname "")
		)
		(fill
			(thermal_gap 0.5)
			(thermal_bridge_width 0.5)
			(island_removal_mode 0)
		)
		(polygon
			(pts
				(arc
					(start 118.561104 -389.467344)
					(mid 118.180104 -389.467344)
					(end 118.561104 -389.467344)
				)
			)
		)
	)
	(zone
		(layer "In1.Cu")
		(hatch none 0.5)
		(connect_pads
			(clearance 0)
		)
		(min_thickness 0.25)
		(keepout
			(tracks not_allowed)
			(vias allowed)
			(pads allowed)
			(copperpour not_allowed)
			(footprints allowed)
		)
		(placement
			(enabled no)
			(sheetname "")
		)
		(fill
			(thermal_gap 0.5)
			(thermal_bridge_width 0.5)
			(island_removal_mode 0)
		)
		(polygon
			(pts
				(arc
					(start 52.633372 -200.98258)
					(mid 52.629652 -200.99156)
					(end 52.620672 -200.99528)
				)
				(arc
					(start 51.147472 -200.99528)
					(mid 51.138492 -200.99156)
					(end 51.134772 -200.98258)
				)
				(arc
					(start 51.134772 -200.488042)
					(mid 51.138492 -200.479062)
					(end 51.147472 -200.475342)
				)
				(arc
					(start 52.620672 -200.475342)
					(mid 52.629652 -200.479062)
					(end 52.633372 -200.488042)
				)
			)
		)
	)
	(zone
		(layer "In1.Cu")
		(hatch none 0.5)
		(connect_pads
			(clearance 0)
		)
		(min_thickness 0.25)
		(keepout
			(tracks not_allowed)
			(vias allowed)
			(pads allowed)
			(copperpour not_allowed)
			(footprints allowed)
		)
		(placement
			(enabled no)
			(sheetname "")
		)
		(fill
			(thermal_gap 0.5)
			(thermal_bridge_width 0.5)
			(island_removal_mode 0)
		)
		(polygon
			(pts
				(arc
					(start 153.198068 -383.92227)
					(mid 152.893268 -383.92227)
					(end 153.198068 -383.92227)
				)
			)
		)
	)
	(zone
		(layer "In1.Cu")
		(hatch none 0.5)
		(connect_pads
			(clearance 0)
		)
		(min_thickness 0.25)
		(keepout
			(tracks not_allowed)
			(vias allowed)
			(pads allowed)
			(copperpour not_allowed)
			(footprints allowed)
		)
		(placement
			(enabled no)
			(sheetname "")
		)
		(fill
			(thermal_gap 0.5)
			(thermal_bridge_width 0.5)
			(island_removal_mode 0)
		)
		(polygon
			(pts
				(arc
					(start 373.690896 -399.701258)
					(mid 373.817896 -399.828258)
					(end 373.944896 -399.701258)
				)
				(arc
					(start 373.944896 -399.625058)
					(mid 373.817896 -399.498058)
					(end 373.690896 -399.625058)
				)
			)
		)
	)
	(zone
		(layer "In1.Cu")
		(hatch none 0.5)
		(connect_pads
			(clearance 0)
		)
		(min_thickness 0.25)
		(keepout
			(tracks not_allowed)
			(vias allowed)
			(pads allowed)
			(copperpour not_allowed)
			(footprints allowed)
		)
		(placement
			(enabled no)
			(sheetname "")
		)
		(fill
			(thermal_gap 0.5)
			(thermal_bridge_width 0.5)
			(island_removal_mode 0)
		)
		(polygon
			(pts
				(arc
					(start 195.353432 -302.982376)
					(mid 195.349712 -302.991356)
					(end 195.340732 -302.995076)
				)
				(arc
					(start 193.867532 -302.995076)
					(mid 193.858552 -302.991356)
					(end 193.854832 -302.982376)
				)
				(arc
					(start 193.854832 -302.487838)
					(mid 193.858552 -302.478858)
					(end 193.867532 -302.475138)
				)
				(arc
					(start 195.340732 -302.475138)
					(mid 195.349712 -302.478858)
					(end 195.353432 -302.487838)
				)
			)
		)
	)
	(zone
		(layer "In1.Cu")
		(hatch none 0.5)
		(connect_pads
			(clearance 0)
		)
		(min_thickness 0.25)
		(keepout
			(tracks not_allowed)
			(vias allowed)
			(pads allowed)
			(copperpour not_allowed)
			(footprints allowed)
		)
		(placement
			(enabled no)
			(sheetname "")
		)
		(fill
			(thermal_gap 0.5)
			(thermal_bridge_width 0.5)
			(island_removal_mode 0)
		)
		(polygon
			(pts
				(arc
					(start 18.357342 -234.132374)
					(mid 18.353622 -234.141354)
					(end 18.344642 -234.145074)
				)
				(arc
					(start 16.871442 -234.145074)
					(mid 16.862462 -234.141354)
					(end 16.858742 -234.132374)
				)
				(arc
					(start 16.858742 -233.637836)
					(mid 16.862462 -233.628856)
					(end 16.871442 -233.625136)
				)
				(arc
					(start 18.344642 -233.625136)
					(mid 18.353622 -233.628856)
					(end 18.357342 -233.637836)
				)
			)
		)
	)
	(zone
		(layer "In1.Cu")
		(hatch none 0.5)
		(connect_pads
			(clearance 0)
		)
		(min_thickness 0.25)
		(keepout
			(tracks not_allowed)
			(vias allowed)
			(pads allowed)
			(copperpour not_allowed)
			(footprints allowed)
		)
		(placement
			(enabled no)
			(sheetname "")
		)
		(fill
			(thermal_gap 0.5)
			(thermal_bridge_width 0.5)
			(island_removal_mode 0)
		)
		(polygon
			(pts
				(arc
					(start 413.117284 -220.532198)
					(mid 413.113564 -220.541178)
					(end 413.104584 -220.544898)
				)
				(arc
					(start 411.631384 -220.544898)
					(mid 411.622404 -220.541178)
					(end 411.618684 -220.532198)
				)
				(arc
					(start 411.618684 -220.03766)
					(mid 411.622404 -220.02868)
					(end 411.631384 -220.02496)
				)
				(arc
					(start 413.104584 -220.02496)
					(mid 413.113564 -220.02868)
					(end 413.117284 -220.03766)
				)
			)
		)
	)
	(zone
		(layer "In1.Cu")
		(hatch none 0.5)
		(connect_pads
			(clearance 0)
		)
		(min_thickness 0.25)
		(keepout
			(tracks not_allowed)
			(vias allowed)
			(pads allowed)
			(copperpour not_allowed)
			(footprints allowed)
		)
		(placement
			(enabled no)
			(sheetname "")
		)
		(fill
			(thermal_gap 0.5)
			(thermal_bridge_width 0.5)
			(island_removal_mode 0)
		)
		(polygon
			(pts
				(arc
					(start 315.570108 -399.143474)
					(mid 315.265308 -399.143474)
					(end 315.570108 -399.143474)
				)
			)
		)
	)
	(zone
		(layer "In1.Cu")
		(hatch none 0.5)
		(connect_pads
			(clearance 0)
		)
		(min_thickness 0.25)
		(keepout
			(tracks not_allowed)
			(vias allowed)
			(pads allowed)
			(copperpour not_allowed)
			(footprints allowed)
		)
		(placement
			(enabled no)
			(sheetname "")
		)
		(fill
			(thermal_gap 0.5)
			(thermal_bridge_width 0.5)
			(island_removal_mode 0)
		)
		(polygon
			(pts
				(arc
					(start 164.61867 -383.440686)
					(mid 164.74567 -383.567686)
					(end 164.87267 -383.440686)
				)
				(arc
					(start 164.87267 -383.364486)
					(mid 164.74567 -383.237486)
					(end 164.61867 -383.364486)
				)
			)
		)
	)
	(zone
		(layer "In1.Cu")
		(hatch none 0.5)
		(connect_pads
			(clearance 0)
		)
		(min_thickness 0.25)
		(keepout
			(tracks not_allowed)
			(vias allowed)
			(pads allowed)
			(copperpour not_allowed)
			(footprints allowed)
		)
		(placement
			(enabled no)
			(sheetname "")
		)
		(fill
			(thermal_gap 0.5)
			(thermal_bridge_width 0.5)
			(island_removal_mode 0)
		)
		(polygon
			(pts
				(arc
					(start 195.353432 -262.182356)
					(mid 195.349712 -262.191336)
					(end 195.340732 -262.195056)
				)
				(arc
					(start 193.867532 -262.195056)
					(mid 193.858552 -262.191336)
					(end 193.854832 -262.182356)
				)
				(arc
					(start 193.854832 -261.687818)
					(mid 193.858552 -261.678838)
					(end 193.867532 -261.675118)
				)
				(arc
					(start 195.340732 -261.675118)
					(mid 195.349712 -261.678838)
					(end 195.353432 -261.687818)
				)
			)
		)
	)
	(zone
		(layer "In1.Cu")
		(hatch none 0.5)
		(connect_pads
			(clearance 0)
		)
		(min_thickness 0.25)
		(keepout
			(tracks not_allowed)
			(vias allowed)
			(pads allowed)
			(copperpour not_allowed)
			(footprints allowed)
		)
		(placement
			(enabled no)
			(sheetname "")
		)
		(fill
			(thermal_gap 0.5)
			(thermal_bridge_width 0.5)
			(island_removal_mode 0)
		)
		(polygon
			(pts
				(arc
					(start 33.445196 -263.882378)
					(mid 33.441476 -263.891358)
					(end 33.432496 -263.895078)
				)
				(arc
					(start 31.959296 -263.895078)
					(mid 31.950316 -263.891358)
					(end 31.946596 -263.882378)
				)
				(arc
					(start 31.946596 -263.38784)
					(mid 31.950316 -263.37886)
					(end 31.959296 -263.37514)
				)
				(arc
					(start 33.432496 -263.37514)
					(mid 33.441476 -263.37886)
					(end 33.445196 -263.38784)
				)
			)
		)
	)
	(zone
		(layer "In1.Cu")
		(hatch none 0.5)
		(connect_pads
			(clearance 0)
		)
		(min_thickness 0.25)
		(keepout
			(tracks not_allowed)
			(vias allowed)
			(pads allowed)
			(copperpour not_allowed)
			(footprints allowed)
		)
		(placement
			(enabled no)
			(sheetname "")
		)
		(fill
			(thermal_gap 0.5)
			(thermal_bridge_width 0.5)
			(island_removal_mode 0)
		)
		(polygon
			(pts
				(arc
					(start 184.365392 -205.232508)
					(mid 184.361672 -205.241488)
					(end 184.352692 -205.245208)
				)
				(arc
					(start 182.879492 -205.245208)
					(mid 182.870512 -205.241488)
					(end 182.866792 -205.232508)
				)
				(arc
					(start 182.866792 -204.73797)
					(mid 182.870512 -204.72899)
					(end 182.879492 -204.72527)
				)
				(arc
					(start 184.352692 -204.72527)
					(mid 184.361672 -204.72899)
					(end 184.365392 -204.73797)
				)
			)
		)
	)
	(zone
		(layer "In1.Cu")
		(hatch none 0.5)
		(connect_pads
			(clearance 0)
		)
		(min_thickness 0.25)
		(keepout
			(tracks not_allowed)
			(vias allowed)
			(pads allowed)
			(copperpour not_allowed)
			(footprints allowed)
		)
		(placement
			(enabled no)
			(sheetname "")
		)
		(fill
			(thermal_gap 0.5)
			(thermal_bridge_width 0.5)
			(island_removal_mode 0)
		)
		(polygon
			(pts
				(arc
					(start 408.61869 -391.822686)
					(mid 408.74569 -391.949686)
					(end 408.87269 -391.822686)
				)
				(arc
					(start 408.87269 -391.746486)
					(mid 408.74569 -391.619486)
					(end 408.61869 -391.746486)
				)
			)
		)
	)
	(zone
		(layer "In1.Cu")
		(hatch none 0.5)
		(connect_pads
			(clearance 0)
		)
		(min_thickness 0.25)
		(keepout
			(tracks not_allowed)
			(vias allowed)
			(pads allowed)
			(copperpour not_allowed)
			(footprints allowed)
		)
		(placement
			(enabled no)
			(sheetname "")
		)
		(fill
			(thermal_gap 0.5)
			(thermal_bridge_width 0.5)
			(island_removal_mode 0)
		)
		(polygon
			(pts
				(arc
					(start 176.821338 -242.632484)
					(mid 176.817618 -242.641464)
					(end 176.808638 -242.645184)
				)
				(arc
					(start 175.335438 -242.645184)
					(mid 175.326458 -242.641464)
					(end 175.322738 -242.632484)
				)
				(arc
					(start 175.322738 -242.137946)
					(mid 175.326458 -242.128966)
					(end 175.335438 -242.125246)
				)
				(arc
					(start 176.808638 -242.125246)
					(mid 176.817618 -242.128966)
					(end 176.821338 -242.137946)
				)
			)
		)
	)
	(zone
		(layer "In1.Cu")
		(hatch none 0.5)
		(connect_pads
			(clearance 0)
		)
		(min_thickness 0.25)
		(keepout
			(tracks not_allowed)
			(vias allowed)
			(pads allowed)
			(copperpour not_allowed)
			(footprints allowed)
		)
		(placement
			(enabled no)
			(sheetname "")
		)
		(fill
			(thermal_gap 0.5)
			(thermal_bridge_width 0.5)
			(island_removal_mode 0)
		)
		(polygon
			(pts
				(arc
					(start 176.821338 -275.782532)
					(mid 176.817618 -275.791512)
					(end 176.808638 -275.795232)
				)
				(arc
					(start 175.335438 -275.795232)
					(mid 175.326458 -275.791512)
					(end 175.322738 -275.782532)
				)
				(arc
					(start 175.322738 -275.287994)
					(mid 175.326458 -275.279014)
					(end 175.335438 -275.275294)
				)
				(arc
					(start 176.808638 -275.275294)
					(mid 176.817618 -275.279014)
					(end 176.821338 -275.287994)
				)
			)
		)
	)
	(zone
		(layer "In1.Cu")
		(hatch none 0.5)
		(connect_pads
			(clearance 0)
		)
		(min_thickness 0.25)
		(keepout
			(tracks not_allowed)
			(vias allowed)
			(pads allowed)
			(copperpour not_allowed)
			(footprints allowed)
		)
		(placement
			(enabled no)
			(sheetname "")
		)
		(fill
			(thermal_gap 0.5)
			(thermal_bridge_width 0.5)
			(island_removal_mode 0)
		)
		(polygon
			(pts
				(arc
					(start 60.177426 -227.33254)
					(mid 60.173706 -227.34152)
					(end 60.164726 -227.34524)
				)
				(arc
					(start 58.691526 -227.34524)
					(mid 58.682546 -227.34152)
					(end 58.678826 -227.33254)
				)
				(arc
					(start 58.678826 -226.838002)
					(mid 58.682546 -226.829022)
					(end 58.691526 -226.825302)
				)
				(arc
					(start 60.164726 -226.825302)
					(mid 60.173706 -226.829022)
					(end 60.177426 -226.838002)
				)
			)
		)
	)
	(zone
		(layer "In1.Cu")
		(hatch none 0.5)
		(connect_pads
			(clearance 0)
		)
		(min_thickness 0.25)
		(keepout
			(tracks not_allowed)
			(vias allowed)
			(pads allowed)
			(copperpour not_allowed)
			(footprints allowed)
		)
		(placement
			(enabled no)
			(sheetname "")
		)
		(fill
			(thermal_gap 0.5)
			(thermal_bridge_width 0.5)
			(island_removal_mode 0)
		)
		(polygon
			(pts
				(arc
					(start 30.001464 -231.582468)
					(mid 29.997744 -231.591448)
					(end 29.988764 -231.595168)
				)
				(arc
					(start 28.515564 -231.595168)
					(mid 28.506584 -231.591448)
					(end 28.502864 -231.582468)
				)
				(arc
					(start 28.502864 -231.08793)
					(mid 28.506584 -231.07895)
					(end 28.515564 -231.07523)
				)
				(arc
					(start 29.988764 -231.07523)
					(mid 29.997744 -231.07895)
					(end 30.001464 -231.08793)
				)
			)
		)
	)
	(zone
		(layer "In1.Cu")
		(hatch none 0.5)
		(connect_pads
			(clearance 0)
		)
		(min_thickness 0.25)
		(keepout
			(tracks not_allowed)
			(vias allowed)
			(pads allowed)
			(copperpour not_allowed)
			(footprints allowed)
		)
		(placement
			(enabled no)
			(sheetname "")
		)
		(fill
			(thermal_gap 0.5)
			(thermal_bridge_width 0.5)
			(island_removal_mode 0)
		)
		(polygon
			(pts
				(arc
					(start 443.2935 -267.282168)
					(mid 443.28978 -267.291148)
					(end 443.2808 -267.294868)
				)
				(arc
					(start 441.8076 -267.294868)
					(mid 441.79862 -267.291148)
					(end 441.7949 -267.282168)
				)
				(arc
					(start 441.7949 -266.78763)
					(mid 441.79862 -266.77865)
					(end 441.8076 -266.77493)
				)
				(arc
					(start 443.2808 -266.77493)
					(mid 443.28978 -266.77865)
					(end 443.2935 -266.78763)
				)
			)
		)
	)
	(zone
		(layer "In1.Cu")
		(hatch none 0.5)
		(connect_pads
			(clearance 0)
		)
		(min_thickness 0.25)
		(keepout
			(tracks not_allowed)
			(vias allowed)
			(pads allowed)
			(copperpour not_allowed)
			(footprints allowed)
		)
		(placement
			(enabled no)
			(sheetname "")
		)
		(fill
			(thermal_gap 0.5)
			(thermal_bridge_width 0.5)
			(island_removal_mode 0)
		)
		(polygon
			(pts
				(arc
					(start 95.698056 -383.92227)
					(mid 95.393256 -383.92227)
					(end 95.698056 -383.92227)
				)
			)
		)
	)
	(zone
		(layer "In1.Cu")
		(hatch none 0.5)
		(connect_pads
			(clearance 0)
		)
		(min_thickness 0.25)
		(keepout
			(tracks not_allowed)
			(vias allowed)
			(pads allowed)
			(copperpour not_allowed)
			(footprints allowed)
		)
		(placement
			(enabled no)
			(sheetname "")
		)
		(fill
			(thermal_gap 0.5)
			(thermal_bridge_width 0.5)
			(island_removal_mode 0)
		)
		(polygon
			(pts
				(arc
					(start 411.018736 -399.701258)
					(mid 411.145736 -399.828258)
					(end 411.272736 -399.701258)
				)
				(arc
					(start 411.272736 -399.625058)
					(mid 411.145736 -399.498058)
					(end 411.018736 -399.625058)
				)
			)
		)
	)
	(zone
		(layer "In1.Cu")
		(hatch none 0.5)
		(connect_pads
			(clearance 0)
		)
		(min_thickness 0.25)
		(keepout
			(tracks not_allowed)
			(vias allowed)
			(pads allowed)
			(copperpour not_allowed)
			(footprints allowed)
		)
		(placement
			(enabled no)
			(sheetname "")
		)
		(fill
			(thermal_gap 0.5)
			(thermal_bridge_width 0.5)
			(island_removal_mode 0)
		)
		(polygon
			(pts
				(arc
					(start 37.545264 -269.832582)
					(mid 37.541544 -269.841562)
					(end 37.532564 -269.845282)
				)
				(arc
					(start 36.059364 -269.845282)
					(mid 36.050384 -269.841562)
					(end 36.046664 -269.832582)
				)
				(arc
					(start 36.046664 -269.338044)
					(mid 36.050384 -269.329064)
					(end 36.059364 -269.325344)
				)
				(arc
					(start 37.532564 -269.325344)
					(mid 37.541544 -269.329064)
					(end 37.545264 -269.338044)
				)
			)
		)
	)
	(zone
		(layer "In1.Cu")
		(hatch none 0.5)
		(connect_pads
			(clearance 0)
		)
		(min_thickness 0.25)
		(keepout
			(tracks not_allowed)
			(vias allowed)
			(pads allowed)
			(copperpour not_allowed)
			(footprints allowed)
		)
		(placement
			(enabled no)
			(sheetname "")
		)
		(fill
			(thermal_gap 0.5)
			(thermal_bridge_width 0.5)
			(island_removal_mode 0)
		)
		(polygon
			(pts
				(arc
					(start 80.71866 -391.319258)
					(mid 80.84566 -391.446258)
					(end 80.97266 -391.319258)
				)
				(arc
					(start 80.97266 -391.243058)
					(mid 80.84566 -391.116058)
					(end 80.71866 -391.243058)
				)
			)
		)
	)
	(zone
		(layer "In1.Cu")
		(hatch none 0.5)
		(connect_pads
			(clearance 0)
		)
		(min_thickness 0.25)
		(keepout
			(tracks not_allowed)
			(vias allowed)
			(pads allowed)
			(copperpour not_allowed)
			(footprints allowed)
		)
		(placement
			(enabled no)
			(sheetname "")
		)
		(fill
			(thermal_gap 0.5)
			(thermal_bridge_width 0.5)
			(island_removal_mode 0)
		)
		(polygon
			(pts
				(arc
					(start 97.989136 -388.774432)
					(mid 97.608136 -388.774432)
					(end 97.989136 -388.774432)
				)
			)
		)
	)
	(zone
		(layer "In1.Cu")
		(hatch none 0.5)
		(connect_pads
			(clearance 0)
		)
		(min_thickness 0.25)
		(keepout
			(tracks not_allowed)
			(vias allowed)
			(pads allowed)
			(copperpour not_allowed)
			(footprints allowed)
		)
		(placement
			(enabled no)
			(sheetname "")
		)
		(fill
			(thermal_gap 0.5)
			(thermal_bridge_width 0.5)
			(island_removal_mode 0)
		)
		(polygon
			(pts
				(arc
					(start 126.961138 -389.467344)
					(mid 126.580138 -389.467344)
					(end 126.961138 -389.467344)
				)
			)
		)
	)
	(zone
		(layer "In1.Cu")
		(hatch none 0.5)
		(connect_pads
			(clearance 0)
		)
		(min_thickness 0.25)
		(keepout
			(tracks not_allowed)
			(vias allowed)
			(pads allowed)
			(copperpour not_allowed)
			(footprints allowed)
		)
		(placement
			(enabled no)
			(sheetname "")
		)
		(fill
			(thermal_gap 0.5)
			(thermal_bridge_width 0.5)
			(island_removal_mode 0)
		)
		(polygon
			(pts
				(arc
					(start 376.090942 -391.822686)
					(mid 376.217942 -391.949686)
					(end 376.344942 -391.822686)
				)
				(arc
					(start 376.344942 -391.746486)
					(mid 376.217942 -391.619486)
					(end 376.090942 -391.746486)
				)
			)
		)
	)
	(zone
		(layer "In1.Cu")
		(hatch none 0.5)
		(connect_pads
			(clearance 0)
		)
		(min_thickness 0.25)
		(keepout
			(tracks not_allowed)
			(vias allowed)
			(pads allowed)
			(copperpour not_allowed)
			(footprints allowed)
		)
		(placement
			(enabled no)
			(sheetname "")
		)
		(fill
			(thermal_gap 0.5)
			(thermal_bridge_width 0.5)
			(island_removal_mode 0)
		)
		(polygon
			(pts
				(arc
					(start 45.089318 -242.632484)
					(mid 45.085598 -242.641464)
					(end 45.076618 -242.645184)
				)
				(arc
					(start 43.603418 -242.645184)
					(mid 43.594438 -242.641464)
					(end 43.590718 -242.632484)
				)
				(arc
					(start 43.590718 -242.137946)
					(mid 43.594438 -242.128966)
					(end 43.603418 -242.125246)
				)
				(arc
					(start 45.076618 -242.125246)
					(mid 45.085598 -242.128966)
					(end 45.089318 -242.137946)
				)
			)
		)
	)
	(zone
		(layer "In1.Cu")
		(hatch none 0.5)
		(connect_pads
			(clearance 0)
		)
		(min_thickness 0.25)
		(keepout
			(tracks not_allowed)
			(vias allowed)
			(pads allowed)
			(copperpour not_allowed)
			(footprints allowed)
		)
		(placement
			(enabled no)
			(sheetname "")
		)
		(fill
			(thermal_gap 0.5)
			(thermal_bridge_width 0.5)
			(island_removal_mode 0)
		)
		(polygon
			(pts
				(arc
					(start 165.177216 -246.882412)
					(mid 165.173496 -246.891392)
					(end 165.164516 -246.895112)
				)
				(arc
					(start 163.691316 -246.895112)
					(mid 163.682336 -246.891392)
					(end 163.678616 -246.882412)
				)
				(arc
					(start 163.678616 -246.387874)
					(mid 163.682336 -246.378894)
					(end 163.691316 -246.375174)
				)
				(arc
					(start 165.164516 -246.375174)
					(mid 165.173496 -246.378894)
					(end 165.177216 -246.387874)
				)
			)
		)
	)
	(zone
		(layer "In1.Cu")
		(hatch none 0.5)
		(connect_pads
			(clearance 0)
		)
		(min_thickness 0.25)
		(keepout
			(tracks not_allowed)
			(vias allowed)
			(pads allowed)
			(copperpour not_allowed)
			(footprints allowed)
		)
		(placement
			(enabled no)
			(sheetname "")
		)
		(fill
			(thermal_gap 0.5)
			(thermal_bridge_width 0.5)
			(island_removal_mode 0)
		)
		(polygon
			(pts
				(arc
					(start 321.860926 -394.385292)
					(mid 321.479926 -394.385292)
					(end 321.860926 -394.385292)
				)
			)
		)
	)
	(zone
		(layer "In1.Cu")
		(hatch none 0.5)
		(connect_pads
			(clearance 0)
		)
		(min_thickness 0.25)
		(keepout
			(tracks not_allowed)
			(vias allowed)
			(pads allowed)
			(copperpour not_allowed)
			(footprints allowed)
		)
		(placement
			(enabled no)
			(sheetname "")
		)
		(fill
			(thermal_gap 0.5)
			(thermal_bridge_width 0.5)
			(island_removal_mode 0)
		)
		(polygon
			(pts
				(arc
					(start 195.353432 -299.582586)
					(mid 195.349712 -299.591566)
					(end 195.340732 -299.595286)
				)
				(arc
					(start 193.867532 -299.595286)
					(mid 193.858552 -299.591566)
					(end 193.854832 -299.582586)
				)
				(arc
					(start 193.854832 -299.088048)
					(mid 193.858552 -299.079068)
					(end 193.867532 -299.075348)
				)
				(arc
					(start 195.340732 -299.075348)
					(mid 195.349712 -299.079068)
					(end 195.353432 -299.088048)
				)
			)
		)
	)
	(zone
		(layer "In1.Cu")
		(hatch none 0.5)
		(connect_pads
			(clearance 0)
		)
		(min_thickness 0.25)
		(keepout
			(tracks not_allowed)
			(vias allowed)
			(pads allowed)
			(copperpour not_allowed)
			(footprints allowed)
		)
		(placement
			(enabled no)
			(sheetname "")
		)
		(fill
			(thermal_gap 0.5)
			(thermal_bridge_width 0.5)
			(island_removal_mode 0)
		)
		(polygon
			(pts
				(arc
					(start 332.311248 -381.824484)
					(mid 332.331172 -381.83372)
					(end 332.352904 -381.83693)
				)
				(arc
					(start 332.547468 -381.83693)
					(mid 332.60135 -381.814612)
					(end 332.623668 -381.76073)
				)
				(arc
					(start 332.623668 -381.07493)
					(mid 332.60135 -381.021048)
					(end 332.547468 -380.99873)
				)
				(arc
					(start 332.352904 -380.99873)
					(mid 332.33116 -381.001898)
					(end 332.311248 -381.011176)
				)
				(arc
					(start 332.015084 -381.203962)
					(mid 331.9734 -381.216184)
					(end 331.931772 -381.203708)
				)
				(arc
					(start 331.638148 -381.011176)
					(mid 331.618224 -381.00194)
					(end 331.596492 -380.99873)
				)
				(arc
					(start 331.401928 -380.99873)
					(mid 331.348046 -381.021048)
					(end 331.325728 -381.07493)
				)
				(arc
					(start 331.325728 -381.76073)
					(mid 331.348046 -381.814612)
					(end 331.401928 -381.83693)
				)
				(arc
					(start 331.597762 -381.83693)
					(mid 331.619506 -381.833762)
					(end 331.639418 -381.824484)
				)
				(arc
					(start 331.933042 -381.631952)
					(mid 331.974698 -381.61955)
					(end 332.016354 -381.631952)
				)
			)
		)
	)
	(zone
		(layer "In1.Cu")
		(hatch none 0.5)
		(connect_pads
			(clearance 0)
		)
		(min_thickness 0.25)
		(keepout
			(tracks not_allowed)
			(vias allowed)
			(pads allowed)
			(copperpour not_allowed)
			(footprints allowed)
		)
		(placement
			(enabled no)
			(sheetname "")
		)
		(fill
			(thermal_gap 0.5)
			(thermal_bridge_width 0.5)
			(island_removal_mode 0)
		)
		(polygon
			(pts
				(arc
					(start 45.089318 -275.782532)
					(mid 45.085598 -275.791512)
					(end 45.076618 -275.795232)
				)
				(arc
					(start 43.603418 -275.795232)
					(mid 43.594438 -275.791512)
					(end 43.590718 -275.782532)
				)
				(arc
					(start 43.590718 -275.287994)
					(mid 43.594438 -275.279014)
					(end 43.603418 -275.275294)
				)
				(arc
					(start 45.076618 -275.275294)
					(mid 45.085598 -275.279014)
					(end 45.089318 -275.287994)
				)
			)
		)
	)
	(zone
		(layer "In1.Cu")
		(hatch none 0.5)
		(connect_pads
			(clearance 0)
		)
		(min_thickness 0.25)
		(keepout
			(tracks not_allowed)
			(vias allowed)
			(pads allowed)
			(copperpour not_allowed)
			(footprints allowed)
		)
		(placement
			(enabled no)
			(sheetname "")
		)
		(fill
			(thermal_gap 0.5)
			(thermal_bridge_width 0.5)
			(island_removal_mode 0)
		)
		(polygon
			(pts
				(arc
					(start 187.809378 -207.782414)
					(mid 187.805658 -207.791394)
					(end 187.796678 -207.795114)
				)
				(arc
					(start 186.323478 -207.795114)
					(mid 186.314498 -207.791394)
					(end 186.310778 -207.782414)
				)
				(arc
					(start 186.310778 -207.287876)
					(mid 186.314498 -207.278896)
					(end 186.323478 -207.275176)
				)
				(arc
					(start 187.796678 -207.275176)
					(mid 187.805658 -207.278896)
					(end 187.809378 -207.287876)
				)
			)
		)
	)
	(zone
		(layer "In1.Cu")
		(hatch none 0.5)
		(connect_pads
			(clearance 0)
		)
		(min_thickness 0.25)
		(keepout
			(tracks not_allowed)
			(vias allowed)
			(pads allowed)
			(copperpour not_allowed)
			(footprints allowed)
		)
		(placement
			(enabled no)
			(sheetname "")
		)
		(fill
			(thermal_gap 0.5)
			(thermal_bridge_width 0.5)
			(island_removal_mode 0)
		)
		(polygon
			(pts
				(arc
					(start 343.188798 -397.156432)
					(mid 342.807798 -397.156432)
					(end 343.188798 -397.156432)
				)
			)
		)
	)
	(zone
		(layer "In1.Cu")
		(hatch none 0.5)
		(connect_pads
			(clearance 0)
		)
		(min_thickness 0.25)
		(keepout
			(tracks not_allowed)
			(vias allowed)
			(pads allowed)
			(copperpour not_allowed)
			(footprints allowed)
		)
		(placement
			(enabled no)
			(sheetname "")
		)
		(fill
			(thermal_gap 0.5)
			(thermal_bridge_width 0.5)
			(island_removal_mode 0)
		)
		(polygon
			(pts
				(arc
					(start 33.445196 -308.93258)
					(mid 33.441476 -308.94156)
					(end 33.432496 -308.94528)
				)
				(arc
					(start 31.959296 -308.94528)
					(mid 31.950316 -308.94156)
					(end 31.946596 -308.93258)
				)
				(arc
					(start 31.946596 -308.438042)
					(mid 31.950316 -308.429062)
					(end 31.959296 -308.425342)
				)
				(arc
					(start 33.432496 -308.425342)
					(mid 33.441476 -308.429062)
					(end 33.445196 -308.438042)
				)
			)
		)
	)
	(zone
		(layer "In1.Cu")
		(hatch none 0.5)
		(connect_pads
			(clearance 0)
		)
		(min_thickness 0.25)
		(keepout
			(tracks not_allowed)
			(vias allowed)
			(pads allowed)
			(copperpour not_allowed)
			(footprints allowed)
		)
		(placement
			(enabled no)
			(sheetname "")
		)
		(fill
			(thermal_gap 0.5)
			(thermal_bridge_width 0.5)
			(island_removal_mode 0)
		)
		(polygon
			(pts
				(arc
					(start 454.937368 -225.632264)
					(mid 454.933648 -225.641244)
					(end 454.924668 -225.644964)
				)
				(arc
					(start 453.451468 -225.644964)
					(mid 453.442488 -225.641244)
					(end 453.438768 -225.632264)
				)
				(arc
					(start 453.438768 -225.137726)
					(mid 453.442488 -225.128746)
					(end 453.451468 -225.125026)
				)
				(arc
					(start 454.924668 -225.125026)
					(mid 454.933648 -225.128746)
					(end 454.937368 -225.137726)
				)
			)
		)
	)
	(zone
		(layer "In1.Cu")
		(hatch none 0.5)
		(connect_pads
			(clearance 0)
		)
		(min_thickness 0.25)
		(keepout
			(tracks not_allowed)
			(vias allowed)
			(pads allowed)
			(copperpour not_allowed)
			(footprints allowed)
		)
		(placement
			(enabled no)
			(sheetname "")
		)
		(fill
			(thermal_gap 0.5)
			(thermal_bridge_width 0.5)
			(island_removal_mode 0)
		)
		(polygon
			(pts
				(arc
					(start 180.265324 -301.282354)
					(mid 180.261604 -301.291334)
					(end 180.252624 -301.295054)
				)
				(arc
					(start 178.779424 -301.295054)
					(mid 178.770444 -301.291334)
					(end 178.766724 -301.282354)
				)
				(arc
					(start 178.766724 -300.787816)
					(mid 178.770444 -300.778836)
					(end 178.779424 -300.775116)
				)
				(arc
					(start 180.252624 -300.775116)
					(mid 180.261604 -300.778836)
					(end 180.265324 -300.787816)
				)
			)
		)
	)
	(zone
		(layer "In1.Cu")
		(hatch none 0.5)
		(connect_pads
			(clearance 0)
		)
		(min_thickness 0.25)
		(keepout
			(tracks not_allowed)
			(vias allowed)
			(pads allowed)
			(copperpour not_allowed)
			(footprints allowed)
		)
		(placement
			(enabled no)
			(sheetname "")
		)
		(fill
			(thermal_gap 0.5)
			(thermal_bridge_width 0.5)
			(island_removal_mode 0)
		)
		(polygon
			(pts
				(arc
					(start 184.365392 -220.532452)
					(mid 184.361672 -220.541432)
					(end 184.352692 -220.545152)
				)
				(arc
					(start 182.879492 -220.545152)
					(mid 182.870512 -220.541432)
					(end 182.866792 -220.532452)
				)
				(arc
					(start 182.866792 -220.037914)
					(mid 182.870512 -220.028934)
					(end 182.879492 -220.025214)
				)
				(arc
					(start 184.352692 -220.025214)
					(mid 184.361672 -220.028934)
					(end 184.365392 -220.037914)
				)
			)
		)
	)
	(zone
		(layer "In1.Cu")
		(hatch none 0.5)
		(connect_pads
			(clearance 0)
		)
		(min_thickness 0.25)
		(keepout
			(tracks not_allowed)
			(vias allowed)
			(pads allowed)
			(copperpour not_allowed)
			(footprints allowed)
		)
		(placement
			(enabled no)
			(sheetname "")
		)
		(fill
			(thermal_gap 0.5)
			(thermal_bridge_width 0.5)
			(island_removal_mode 0)
		)
		(polygon
			(pts
				(arc
					(start 22.45741 -231.582468)
					(mid 22.45369 -231.591448)
					(end 22.44471 -231.595168)
				)
				(arc
					(start 20.97151 -231.595168)
					(mid 20.96253 -231.591448)
					(end 20.95881 -231.582468)
				)
				(arc
					(start 20.95881 -231.08793)
					(mid 20.96253 -231.07895)
					(end 20.97151 -231.07523)
				)
				(arc
					(start 22.44471 -231.07523)
					(mid 22.45369 -231.07895)
					(end 22.45741 -231.08793)
				)
			)
		)
	)
	(zone
		(layer "In1.Cu")
		(hatch none 0.5)
		(connect_pads
			(clearance 0)
		)
		(min_thickness 0.25)
		(keepout
			(tracks not_allowed)
			(vias allowed)
			(pads allowed)
			(copperpour not_allowed)
			(footprints allowed)
		)
		(placement
			(enabled no)
			(sheetname "")
		)
		(fill
			(thermal_gap 0.5)
			(thermal_bridge_width 0.5)
			(island_removal_mode 0)
		)
		(polygon
			(pts
				(arc
					(start 49.861216 -388.774432)
					(mid 49.480216 -388.774432)
					(end 49.861216 -388.774432)
				)
			)
		)
	)
	(zone
		(layer "In1.Cu")
		(hatch none 0.5)
		(connect_pads
			(clearance 0)
		)
		(min_thickness 0.25)
		(keepout
			(tracks not_allowed)
			(vias allowed)
			(pads allowed)
			(copperpour not_allowed)
			(footprints allowed)
		)
		(placement
			(enabled no)
			(sheetname "")
		)
		(fill
			(thermal_gap 0.5)
			(thermal_bridge_width 0.5)
			(island_removal_mode 0)
		)
		(polygon
			(pts
				(arc
					(start 418.689028 -393.69238)
					(mid 418.308028 -393.69238)
					(end 418.689028 -393.69238)
				)
			)
		)
	)
	(zone
		(layer "In1.Cu")
		(hatch none 0.5)
		(connect_pads
			(clearance 0)
		)
		(min_thickness 0.25)
		(keepout
			(tracks not_allowed)
			(vias allowed)
			(pads allowed)
			(copperpour not_allowed)
			(footprints allowed)
		)
		(placement
			(enabled no)
			(sheetname "")
		)
		(fill
			(thermal_gap 0.5)
			(thermal_bridge_width 0.5)
			(island_removal_mode 0)
		)
		(polygon
			(pts
				(arc
					(start 357.838248 -379.360684)
					(mid 357.858172 -379.36992)
					(end 357.879904 -379.37313)
				)
				(arc
					(start 358.074468 -379.37313)
					(mid 358.12835 -379.350812)
					(end 358.150668 -379.29693)
				)
				(arc
					(start 358.150668 -378.61113)
					(mid 358.12835 -378.557248)
					(end 358.074468 -378.53493)
				)
				(arc
					(start 357.879904 -378.53493)
					(mid 357.85816 -378.538098)
					(end 357.838248 -378.547376)
				)
				(arc
					(start 357.542084 -378.740162)
					(mid 357.5004 -378.752384)
					(end 357.458772 -378.739908)
				)
				(arc
					(start 357.165148 -378.547376)
					(mid 357.145224 -378.53814)
					(end 357.123492 -378.53493)
				)
				(arc
					(start 356.928928 -378.53493)
					(mid 356.875046 -378.557248)
					(end 356.852728 -378.61113)
				)
				(arc
					(start 356.852728 -379.29693)
					(mid 356.875046 -379.350812)
					(end 356.928928 -379.37313)
				)
				(arc
					(start 357.124762 -379.37313)
					(mid 357.146506 -379.369962)
					(end 357.166418 -379.360684)
				)
				(arc
					(start 357.460042 -379.168152)
					(mid 357.501698 -379.15575)
					(end 357.543354 -379.168152)
				)
			)
		)
	)
	(zone
		(layer "In1.Cu")
		(hatch none 0.5)
		(connect_pads
			(clearance 0)
		)
		(min_thickness 0.25)
		(keepout
			(tracks not_allowed)
			(vias allowed)
			(pads allowed)
			(copperpour not_allowed)
			(footprints allowed)
		)
		(placement
			(enabled no)
			(sheetname "")
		)
		(fill
			(thermal_gap 0.5)
			(thermal_bridge_width 0.5)
			(island_removal_mode 0)
		)
		(polygon
			(pts
				(arc
					(start 383.761234 -397.156432)
					(mid 383.380234 -397.156432)
					(end 383.761234 -397.156432)
				)
			)
		)
	)
	(zone
		(layer "In1.Cu")
		(hatch none 0.5)
		(connect_pads
			(clearance 0)
		)
		(min_thickness 0.25)
		(keepout
			(tracks not_allowed)
			(vias allowed)
			(pads allowed)
			(copperpour not_allowed)
			(footprints allowed)
		)
		(placement
			(enabled no)
			(sheetname "")
		)
		(fill
			(thermal_gap 0.5)
			(thermal_bridge_width 0.5)
			(island_removal_mode 0)
		)
		(polygon
			(pts
				(arc
					(start 184.365392 -281.732482)
					(mid 184.361672 -281.741462)
					(end 184.352692 -281.745182)
				)
				(arc
					(start 182.879492 -281.745182)
					(mid 182.870512 -281.741462)
					(end 182.866792 -281.732482)
				)
				(arc
					(start 182.866792 -281.237944)
					(mid 182.870512 -281.228964)
					(end 182.879492 -281.225244)
				)
				(arc
					(start 184.352692 -281.225244)
					(mid 184.361672 -281.228964)
					(end 184.365392 -281.237944)
				)
			)
		)
	)
	(zone
		(layer "In1.Cu")
		(hatch none 0.5)
		(connect_pads
			(clearance 0)
		)
		(min_thickness 0.25)
		(keepout
			(tracks not_allowed)
			(vias allowed)
			(pads allowed)
			(copperpour not_allowed)
			(footprints allowed)
		)
		(placement
			(enabled no)
			(sheetname "")
		)
		(fill
			(thermal_gap 0.5)
			(thermal_bridge_width 0.5)
			(island_removal_mode 0)
		)
		(polygon
			(pts
				(arc
					(start 118.270274 -390.761474)
					(mid 117.965474 -390.761474)
					(end 118.270274 -390.761474)
				)
			)
		)
	)
	(zone
		(layer "In1.Cu")
		(hatch none 0.5)
		(connect_pads
			(clearance 0)
		)
		(min_thickness 0.25)
		(keepout
			(tracks not_allowed)
			(vias allowed)
			(pads allowed)
			(copperpour not_allowed)
			(footprints allowed)
		)
		(placement
			(enabled no)
			(sheetname "")
		)
		(fill
			(thermal_gap 0.5)
			(thermal_bridge_width 0.5)
			(island_removal_mode 0)
		)
		(polygon
			(pts
				(arc
					(start 305.390804 -399.701258)
					(mid 305.517804 -399.828258)
					(end 305.644804 -399.701258)
				)
				(arc
					(start 305.644804 -399.625058)
					(mid 305.517804 -399.498058)
					(end 305.390804 -399.625058)
				)
			)
		)
	)
	(zone
		(layer "In1.Cu")
		(hatch none 0.5)
		(connect_pads
			(clearance 0)
		)
		(min_thickness 0.25)
		(keepout
			(tracks not_allowed)
			(vias allowed)
			(pads allowed)
			(copperpour not_allowed)
			(footprints allowed)
		)
		(placement
			(enabled no)
			(sheetname "")
		)
		(fill
			(thermal_gap 0.5)
			(thermal_bridge_width 0.5)
			(island_removal_mode 0)
		)
		(polygon
			(pts
				(arc
					(start 343.588594 -397.849344)
					(mid 343.207594 -397.849344)
					(end 343.588594 -397.849344)
				)
			)
		)
	)
	(zone
		(layer "In1.Cu")
		(hatch none 0.5)
		(connect_pads
			(clearance 0)
		)
		(min_thickness 0.25)
		(keepout
			(tracks not_allowed)
			(vias allowed)
			(pads allowed)
			(copperpour not_allowed)
			(footprints allowed)
		)
		(placement
			(enabled no)
			(sheetname "")
		)
		(fill
			(thermal_gap 0.5)
			(thermal_bridge_width 0.5)
			(island_removal_mode 0)
		)
		(polygon
			(pts
				(arc
					(start 304.017426 -250.282202)
					(mid 304.013706 -250.291182)
					(end 304.004726 -250.294902)
				)
				(arc
					(start 302.531526 -250.294902)
					(mid 302.522546 -250.291182)
					(end 302.518826 -250.282202)
				)
				(arc
					(start 302.518826 -249.787664)
					(mid 302.522546 -249.778684)
					(end 302.531526 -249.774964)
				)
				(arc
					(start 304.004726 -249.774964)
					(mid 304.013706 -249.778684)
					(end 304.017426 -249.787664)
				)
			)
		)
	)
	(zone
		(layer "In1.Cu")
		(hatch none 0.5)
		(connect_pads
			(clearance 0)
		)
		(min_thickness 0.25)
		(keepout
			(tracks not_allowed)
			(vias allowed)
			(pads allowed)
			(copperpour not_allowed)
			(footprints allowed)
		)
		(placement
			(enabled no)
			(sheetname "")
		)
		(fill
			(thermal_gap 0.5)
			(thermal_bridge_width 0.5)
			(island_removal_mode 0)
		)
		(polygon
			(pts
				(arc
					(start 288.929318 -318.28232)
					(mid 288.925598 -318.2913)
					(end 288.916618 -318.29502)
				)
				(arc
					(start 287.443418 -318.29502)
					(mid 287.434438 -318.2913)
					(end 287.430718 -318.28232)
				)
				(arc
					(start 287.430718 -317.787782)
					(mid 287.434438 -317.778802)
					(end 287.443418 -317.775082)
				)
				(arc
					(start 288.916618 -317.775082)
					(mid 288.925598 -317.778802)
					(end 288.929318 -317.787782)
				)
			)
		)
	)
	(zone
		(layer "In1.Cu")
		(hatch none 0.5)
		(connect_pads
			(clearance 0)
		)
		(min_thickness 0.25)
		(keepout
			(tracks not_allowed)
			(vias allowed)
			(pads allowed)
			(copperpour not_allowed)
			(footprints allowed)
		)
		(placement
			(enabled no)
			(sheetname "")
		)
		(fill
			(thermal_gap 0.5)
			(thermal_bridge_width 0.5)
			(island_removal_mode 0)
		)
		(polygon
			(pts
				(arc
					(start 18.357342 -302.982376)
					(mid 18.353622 -302.991356)
					(end 18.344642 -302.995076)
				)
				(arc
					(start 16.871442 -302.995076)
					(mid 16.862462 -302.991356)
					(end 16.858742 -302.982376)
				)
				(arc
					(start 16.858742 -302.487838)
					(mid 16.862462 -302.478858)
					(end 16.871442 -302.475138)
				)
				(arc
					(start 18.344642 -302.475138)
					(mid 18.353622 -302.478858)
					(end 18.357342 -302.487838)
				)
			)
		)
	)
	(zone
		(layer "In1.Cu")
		(hatch none 0.5)
		(connect_pads
			(clearance 0)
		)
		(min_thickness 0.25)
		(keepout
			(tracks not_allowed)
			(vias allowed)
			(pads allowed)
			(copperpour not_allowed)
			(footprints allowed)
		)
		(placement
			(enabled no)
			(sheetname "")
		)
		(fill
			(thermal_gap 0.5)
			(thermal_bridge_width 0.5)
			(island_removal_mode 0)
		)
		(polygon
			(pts
				(arc
					(start 199.4535 -197.582536)
					(mid 199.44978 -197.591516)
					(end 199.4408 -197.595236)
				)
				(arc
					(start 197.9676 -197.595236)
					(mid 197.95862 -197.591516)
					(end 197.9549 -197.582536)
				)
				(arc
					(start 197.9549 -197.087998)
					(mid 197.95862 -197.079018)
					(end 197.9676 -197.075298)
				)
				(arc
					(start 199.4408 -197.075298)
					(mid 199.44978 -197.079018)
					(end 199.4535 -197.087998)
				)
			)
		)
	)
	(zone
		(layer "In1.Cu")
		(hatch none 0.5)
		(connect_pads
			(clearance 0)
		)
		(min_thickness 0.25)
		(keepout
			(tracks not_allowed)
			(vias allowed)
			(pads allowed)
			(copperpour not_allowed)
			(footprints allowed)
		)
		(placement
			(enabled no)
			(sheetname "")
		)
		(fill
			(thermal_gap 0.5)
			(thermal_bridge_width 0.5)
			(island_removal_mode 0)
		)
		(polygon
			(pts
				(arc
					(start 45.089318 -212.88248)
					(mid 45.085598 -212.89146)
					(end 45.076618 -212.89518)
				)
				(arc
					(start 43.603418 -212.89518)
					(mid 43.594438 -212.89146)
					(end 43.590718 -212.88248)
				)
				(arc
					(start 43.590718 -212.387942)
					(mid 43.594438 -212.378962)
					(end 43.603418 -212.375242)
				)
				(arc
					(start 45.076618 -212.375242)
					(mid 45.085598 -212.378962)
					(end 45.089318 -212.387942)
				)
			)
		)
	)
	(zone
		(layer "In1.Cu")
		(hatch none 0.5)
		(connect_pads
			(clearance 0)
		)
		(min_thickness 0.25)
		(keepout
			(tracks not_allowed)
			(vias allowed)
			(pads allowed)
			(copperpour not_allowed)
			(footprints allowed)
		)
		(placement
			(enabled no)
			(sheetname "")
		)
		(fill
			(thermal_gap 0.5)
			(thermal_bridge_width 0.5)
			(island_removal_mode 0)
		)
		(polygon
			(pts
				(arc
					(start 300.57344 -314.032138)
					(mid 300.56972 -314.041118)
					(end 300.56074 -314.044838)
				)
				(arc
					(start 299.08754 -314.044838)
					(mid 299.07856 -314.041118)
					(end 299.07484 -314.032138)
				)
				(arc
					(start 299.07484 -313.5376)
					(mid 299.07856 -313.52862)
					(end 299.08754 -313.5249)
				)
				(arc
					(start 300.56074 -313.5249)
					(mid 300.56972 -313.52862)
					(end 300.57344 -313.5376)
				)
			)
		)
	)
	(zone
		(layer "In1.Cu")
		(hatch none 0.5)
		(connect_pads
			(clearance 0)
		)
		(min_thickness 0.25)
		(keepout
			(tracks not_allowed)
			(vias allowed)
			(pads allowed)
			(copperpour not_allowed)
			(footprints allowed)
		)
		(placement
			(enabled no)
			(sheetname "")
		)
		(fill
			(thermal_gap 0.5)
			(thermal_bridge_width 0.5)
			(island_removal_mode 0)
		)
		(polygon
			(pts
				(arc
					(start 308.117494 -206.932276)
					(mid 308.113774 -206.941256)
					(end 308.104794 -206.944976)
				)
				(arc
					(start 306.631594 -206.944976)
					(mid 306.622614 -206.941256)
					(end 306.618894 -206.932276)
				)
				(arc
					(start 306.618894 -206.437738)
					(mid 306.622614 -206.428758)
					(end 306.631594 -206.425038)
				)
				(arc
					(start 308.104794 -206.425038)
					(mid 308.113774 -206.428758)
					(end 308.117494 -206.437738)
				)
			)
		)
	)
	(zone
		(layer "In1.Cu")
		(hatch none 0.5)
		(connect_pads
			(clearance 0)
		)
		(min_thickness 0.25)
		(keepout
			(tracks not_allowed)
			(vias allowed)
			(pads allowed)
			(copperpour not_allowed)
			(footprints allowed)
		)
		(placement
			(enabled no)
			(sheetname "")
		)
		(fill
			(thermal_gap 0.5)
			(thermal_bridge_width 0.5)
			(island_removal_mode 0)
		)
		(polygon
			(pts
				(arc
					(start 206.5782 -249.18543)
					(mid 205.9178 -249.18543)
					(end 206.5782 -249.18543)
				)
			)
		)
	)
	(zone
		(layer "In1.Cu")
		(hatch none 0.5)
		(connect_pads
			(clearance 0)
		)
		(min_thickness 0.25)
		(keepout
			(tracks not_allowed)
			(vias allowed)
			(pads allowed)
			(copperpour not_allowed)
			(footprints allowed)
		)
		(placement
			(enabled no)
			(sheetname "")
		)
		(fill
			(thermal_gap 0.5)
			(thermal_bridge_width 0.5)
			(island_removal_mode 0)
		)
		(polygon
			(pts
				(arc
					(start 454.937368 -242.63223)
					(mid 454.933648 -242.64121)
					(end 454.924668 -242.64493)
				)
				(arc
					(start 453.451468 -242.64493)
					(mid 453.442488 -242.64121)
					(end 453.438768 -242.63223)
				)
				(arc
					(start 453.438768 -242.137692)
					(mid 453.442488 -242.128712)
					(end 453.451468 -242.124992)
				)
				(arc
					(start 454.924668 -242.124992)
					(mid 454.933648 -242.128712)
					(end 454.937368 -242.137692)
				)
			)
		)
	)
	(zone
		(layer "In1.Cu")
		(hatch none 0.5)
		(connect_pads
			(clearance 0)
		)
		(min_thickness 0.25)
		(keepout
			(tracks not_allowed)
			(vias allowed)
			(pads allowed)
			(copperpour not_allowed)
			(footprints allowed)
		)
		(placement
			(enabled no)
			(sheetname "")
		)
		(fill
			(thermal_gap 0.5)
			(thermal_bridge_width 0.5)
			(island_removal_mode 0)
		)
		(polygon
			(pts
				(arc
					(start 447.393568 -314.032138)
					(mid 447.389848 -314.041118)
					(end 447.380868 -314.044838)
				)
				(arc
					(start 445.907668 -314.044838)
					(mid 445.898688 -314.041118)
					(end 445.894968 -314.032138)
				)
				(arc
					(start 445.894968 -313.5376)
					(mid 445.898688 -313.52862)
					(end 445.907668 -313.5249)
				)
				(arc
					(start 447.380868 -313.5249)
					(mid 447.389848 -313.52862)
					(end 447.393568 -313.5376)
				)
			)
		)
	)
	(zone
		(layer "In1.Cu")
		(hatch none 0.5)
		(connect_pads
			(clearance 0)
		)
		(min_thickness 0.25)
		(keepout
			(tracks not_allowed)
			(vias allowed)
			(pads allowed)
			(copperpour not_allowed)
			(footprints allowed)
		)
		(placement
			(enabled no)
			(sheetname "")
		)
		(fill
			(thermal_gap 0.5)
			(thermal_bridge_width 0.5)
			(island_removal_mode 0)
		)
		(polygon
			(pts
				(arc
					(start 55.39105 -391.319258)
					(mid 55.51805 -391.446258)
					(end 55.64505 -391.319258)
				)
				(arc
					(start 55.64505 -391.243058)
					(mid 55.51805 -391.116058)
					(end 55.39105 -391.243058)
				)
			)
		)
	)
	(zone
		(layer "In1.Cu")
		(hatch none 0.5)
		(connect_pads
			(clearance 0)
		)
		(min_thickness 0.25)
		(keepout
			(tracks not_allowed)
			(vias allowed)
			(pads allowed)
			(copperpour not_allowed)
			(footprints allowed)
		)
		(placement
			(enabled no)
			(sheetname "")
		)
		(fill
			(thermal_gap 0.5)
			(thermal_bridge_width 0.5)
			(island_removal_mode 0)
		)
		(polygon
			(pts
				(arc
					(start 153.089102 -388.774432)
					(mid 152.708102 -388.774432)
					(end 153.089102 -388.774432)
				)
			)
		)
	)
	(zone
		(layer "In1.Cu")
		(hatch none 0.5)
		(connect_pads
			(clearance 0)
		)
		(min_thickness 0.25)
		(keepout
			(tracks not_allowed)
			(vias allowed)
			(pads allowed)
			(copperpour not_allowed)
			(footprints allowed)
		)
		(placement
			(enabled no)
			(sheetname "")
		)
		(fill
			(thermal_gap 0.5)
			(thermal_bridge_width 0.5)
			(island_removal_mode 0)
		)
		(polygon
			(pts
				(arc
					(start 60.177426 -220.532452)
					(mid 60.173706 -220.541432)
					(end 60.164726 -220.545152)
				)
				(arc
					(start 58.691526 -220.545152)
					(mid 58.682546 -220.541432)
					(end 58.678826 -220.532452)
				)
				(arc
					(start 58.678826 -220.037914)
					(mid 58.682546 -220.028934)
					(end 58.691526 -220.025214)
				)
				(arc
					(start 60.164726 -220.025214)
					(mid 60.173706 -220.028934)
					(end 60.177426 -220.037914)
				)
			)
		)
	)
	(zone
		(layer "In1.Cu")
		(hatch none 0.5)
		(connect_pads
			(clearance 0)
		)
		(min_thickness 0.25)
		(keepout
			(tracks not_allowed)
			(vias allowed)
			(pads allowed)
			(copperpour not_allowed)
			(footprints allowed)
		)
		(placement
			(enabled no)
			(sheetname "")
		)
		(fill
			(thermal_gap 0.5)
			(thermal_bridge_width 0.5)
			(island_removal_mode 0)
		)
		(polygon
			(pts
				(arc
					(start 155.598114 -383.92227)
					(mid 155.293314 -383.92227)
					(end 155.598114 -383.92227)
				)
			)
		)
	)
	(zone
		(layer "In1.Cu")
		(hatch none 0.5)
		(connect_pads
			(clearance 0)
		)
		(min_thickness 0.25)
		(keepout
			(tracks not_allowed)
			(vias allowed)
			(pads allowed)
			(copperpour not_allowed)
			(footprints allowed)
		)
		(placement
			(enabled no)
			(sheetname "")
		)
		(fill
			(thermal_gap 0.5)
			(thermal_bridge_width 0.5)
			(island_removal_mode 0)
		)
		(polygon
			(pts
				(arc
					(start 439.849514 -205.232254)
					(mid 439.845794 -205.241234)
					(end 439.836814 -205.244954)
				)
				(arc
					(start 438.363614 -205.244954)
					(mid 438.354634 -205.241234)
					(end 438.350914 -205.232254)
				)
				(arc
					(start 438.350914 -204.737716)
					(mid 438.354634 -204.728736)
					(end 438.363614 -204.725016)
				)
				(arc
					(start 439.836814 -204.725016)
					(mid 439.845794 -204.728736)
					(end 439.849514 -204.737716)
				)
			)
		)
	)
	(zone
		(layer "In1.Cu")
		(hatch none 0.5)
		(connect_pads
			(clearance 0)
		)
		(min_thickness 0.25)
		(keepout
			(tracks not_allowed)
			(vias allowed)
			(pads allowed)
			(copperpour not_allowed)
			(footprints allowed)
		)
		(placement
			(enabled no)
			(sheetname "")
		)
		(fill
			(thermal_gap 0.5)
			(thermal_bridge_width 0.5)
			(island_removal_mode 0)
		)
		(polygon
			(pts
				(arc
					(start 30.001464 -302.132492)
					(mid 29.997744 -302.141472)
					(end 29.988764 -302.145192)
				)
				(arc
					(start 28.515564 -302.145192)
					(mid 28.506584 -302.141472)
					(end 28.502864 -302.132492)
				)
				(arc
					(start 28.502864 -301.637954)
					(mid 28.506584 -301.628974)
					(end 28.515564 -301.625254)
				)
				(arc
					(start 29.988764 -301.625254)
					(mid 29.997744 -301.628974)
					(end 30.001464 -301.637954)
				)
			)
		)
	)
	(zone
		(layer "In1.Cu")
		(hatch none 0.5)
		(connect_pads
			(clearance 0)
		)
		(min_thickness 0.25)
		(keepout
			(tracks not_allowed)
			(vias allowed)
			(pads allowed)
			(copperpour not_allowed)
			(footprints allowed)
		)
		(placement
			(enabled no)
			(sheetname "")
		)
		(fill
			(thermal_gap 0.5)
			(thermal_bridge_width 0.5)
			(island_removal_mode 0)
		)
		(polygon
			(pts
				(arc
					(start 184.365392 -274.08251)
					(mid 184.361672 -274.09149)
					(end 184.352692 -274.09521)
				)
				(arc
					(start 182.879492 -274.09521)
					(mid 182.870512 -274.09149)
					(end 182.866792 -274.08251)
				)
				(arc
					(start 182.866792 -273.587972)
					(mid 182.870512 -273.578992)
					(end 182.879492 -273.575272)
				)
				(arc
					(start 184.352692 -273.575272)
					(mid 184.361672 -273.578992)
					(end 184.365392 -273.587972)
				)
			)
		)
	)
	(zone
		(layer "In1.Cu")
		(hatch none 0.5)
		(connect_pads
			(clearance 0)
		)
		(min_thickness 0.25)
		(keepout
			(tracks not_allowed)
			(vias allowed)
			(pads allowed)
			(copperpour not_allowed)
			(footprints allowed)
		)
		(placement
			(enabled no)
			(sheetname "")
		)
		(fill
			(thermal_gap 0.5)
			(thermal_bridge_width 0.5)
			(island_removal_mode 0)
		)
		(polygon
			(pts
				(arc
					(start 22.45741 -315.732414)
					(mid 22.45369 -315.741394)
					(end 22.44471 -315.745114)
				)
				(arc
					(start 20.97151 -315.745114)
					(mid 20.96253 -315.741394)
					(end 20.95881 -315.732414)
				)
				(arc
					(start 20.95881 -315.237876)
					(mid 20.96253 -315.228896)
					(end 20.97151 -315.225176)
				)
				(arc
					(start 22.44471 -315.225176)
					(mid 22.45369 -315.228896)
					(end 22.45741 -315.237876)
				)
			)
		)
	)
	(zone
		(layer "In1.Cu")
		(hatch none 0.5)
		(connect_pads
			(clearance 0)
		)
		(min_thickness 0.25)
		(keepout
			(tracks not_allowed)
			(vias allowed)
			(pads allowed)
			(copperpour not_allowed)
			(footprints allowed)
		)
		(placement
			(enabled no)
			(sheetname "")
		)
		(fill
			(thermal_gap 0.5)
			(thermal_bridge_width 0.5)
			(island_removal_mode 0)
		)
		(polygon
			(pts
				(arc
					(start 40.98925 -232.432352)
					(mid 40.98553 -232.441332)
					(end 40.97655 -232.445052)
				)
				(arc
					(start 39.50335 -232.445052)
					(mid 39.49437 -232.441332)
					(end 39.49065 -232.432352)
				)
				(arc
					(start 39.49065 -231.937814)
					(mid 39.49437 -231.928834)
					(end 39.50335 -231.925114)
				)
				(arc
					(start 40.97655 -231.925114)
					(mid 40.98553 -231.928834)
					(end 40.98925 -231.937814)
				)
			)
		)
	)
	(zone
		(layer "In1.Cu")
		(hatch none 0.5)
		(connect_pads
			(clearance 0)
		)
		(min_thickness 0.25)
		(keepout
			(tracks not_allowed)
			(vias allowed)
			(pads allowed)
			(copperpour not_allowed)
			(footprints allowed)
		)
		(placement
			(enabled no)
			(sheetname "")
		)
		(fill
			(thermal_gap 0.5)
			(thermal_bridge_width 0.5)
			(island_removal_mode 0)
		)
		(polygon
			(pts
				(arc
					(start 184.365392 -270.682466)
					(mid 184.361672 -270.691446)
					(end 184.352692 -270.695166)
				)
				(arc
					(start 182.879492 -270.695166)
					(mid 182.870512 -270.691446)
					(end 182.866792 -270.682466)
				)
				(arc
					(start 182.866792 -270.187928)
					(mid 182.870512 -270.178948)
					(end 182.879492 -270.175228)
				)
				(arc
					(start 184.352692 -270.175228)
					(mid 184.361672 -270.178948)
					(end 184.365392 -270.187928)
				)
			)
		)
	)
	(zone
		(layer "In1.Cu")
		(hatch none 0.5)
		(connect_pads
			(clearance 0)
		)
		(min_thickness 0.25)
		(keepout
			(tracks not_allowed)
			(vias allowed)
			(pads allowed)
			(copperpour not_allowed)
			(footprints allowed)
		)
		(placement
			(enabled no)
			(sheetname "")
		)
		(fill
			(thermal_gap 0.5)
			(thermal_bridge_width 0.5)
			(island_removal_mode 0)
		)
		(polygon
			(pts
				(arc
					(start 413.117284 -226.482148)
					(mid 413.113564 -226.491128)
					(end 413.104584 -226.494848)
				)
				(arc
					(start 411.631384 -226.494848)
					(mid 411.622404 -226.491128)
					(end 411.618684 -226.482148)
				)
				(arc
					(start 411.618684 -225.98761)
					(mid 411.622404 -225.97863)
					(end 411.631384 -225.97491)
				)
				(arc
					(start 413.104584 -225.97491)
					(mid 413.113564 -225.97863)
					(end 413.117284 -225.98761)
				)
			)
		)
	)
	(zone
		(layer "In1.Cu")
		(hatch none 0.5)
		(connect_pads
			(clearance 0)
		)
		(min_thickness 0.25)
		(keepout
			(tracks not_allowed)
			(vias allowed)
			(pads allowed)
			(copperpour not_allowed)
			(footprints allowed)
		)
		(placement
			(enabled no)
			(sheetname "")
		)
		(fill
			(thermal_gap 0.5)
			(thermal_bridge_width 0.5)
			(island_removal_mode 0)
		)
		(polygon
			(pts
				(arc
					(start 308.117494 -252.832108)
					(mid 308.113774 -252.841088)
					(end 308.104794 -252.844808)
				)
				(arc
					(start 306.631594 -252.844808)
					(mid 306.622614 -252.841088)
					(end 306.618894 -252.832108)
				)
				(arc
					(start 306.618894 -252.33757)
					(mid 306.622614 -252.32859)
					(end 306.631594 -252.32487)
				)
				(arc
					(start 308.104794 -252.32487)
					(mid 308.113774 -252.32859)
					(end 308.117494 -252.33757)
				)
			)
		)
	)
	(zone
		(layer "In1.Cu")
		(hatch none 0.5)
		(connect_pads
			(clearance 0)
		)
		(min_thickness 0.25)
		(keepout
			(tracks not_allowed)
			(vias allowed)
			(pads allowed)
			(copperpour not_allowed)
			(footprints allowed)
		)
		(placement
			(enabled no)
			(sheetname "")
		)
		(fill
			(thermal_gap 0.5)
			(thermal_bridge_width 0.5)
			(island_removal_mode 0)
		)
		(polygon
			(pts
				(arc
					(start 199.4535 -309.782464)
					(mid 199.44978 -309.791444)
					(end 199.4408 -309.795164)
				)
				(arc
					(start 197.9676 -309.795164)
					(mid 197.95862 -309.791444)
					(end 197.9549 -309.782464)
				)
				(arc
					(start 197.9549 -309.287926)
					(mid 197.95862 -309.278946)
					(end 197.9676 -309.275226)
				)
				(arc
					(start 199.4408 -309.275226)
					(mid 199.44978 -309.278946)
					(end 199.4535 -309.287926)
				)
			)
		)
	)
	(zone
		(layer "In1.Cu")
		(hatch none 0.5)
		(connect_pads
			(clearance 0)
		)
		(min_thickness 0.25)
		(keepout
			(tracks not_allowed)
			(vias allowed)
			(pads allowed)
			(copperpour not_allowed)
			(footprints allowed)
		)
		(placement
			(enabled no)
			(sheetname "")
		)
		(fill
			(thermal_gap 0.5)
			(thermal_bridge_width 0.5)
			(island_removal_mode 0)
		)
		(polygon
			(pts
				(arc
					(start 413.117284 -253.682246)
					(mid 413.113564 -253.691226)
					(end 413.104584 -253.694946)
				)
				(arc
					(start 411.631384 -253.694946)
					(mid 411.622404 -253.691226)
					(end 411.618684 -253.682246)
				)
				(arc
					(start 411.618684 -253.187708)
					(mid 411.622404 -253.178728)
					(end 411.631384 -253.175008)
				)
				(arc
					(start 413.104584 -253.175008)
					(mid 413.113564 -253.178728)
					(end 413.117284 -253.187708)
				)
			)
		)
	)
	(zone
		(layer "In1.Cu")
		(hatch none 0.5)
		(connect_pads
			(clearance 0)
		)
		(min_thickness 0.25)
		(keepout
			(tracks not_allowed)
			(vias allowed)
			(pads allowed)
			(copperpour not_allowed)
			(footprints allowed)
		)
		(placement
			(enabled no)
			(sheetname "")
		)
		(fill
			(thermal_gap 0.5)
			(thermal_bridge_width 0.5)
			(island_removal_mode 0)
		)
		(polygon
			(pts
				(arc
					(start 48.533304 -224.78238)
					(mid 48.529584 -224.79136)
					(end 48.520604 -224.79508)
				)
				(arc
					(start 47.047404 -224.79508)
					(mid 47.038424 -224.79136)
					(end 47.034704 -224.78238)
				)
				(arc
					(start 47.034704 -224.287842)
					(mid 47.038424 -224.278862)
					(end 47.047404 -224.275142)
				)
				(arc
					(start 48.520604 -224.275142)
					(mid 48.529584 -224.278862)
					(end 48.533304 -224.287842)
				)
			)
		)
	)
	(zone
		(layer "In1.Cu")
		(hatch none 0.5)
		(connect_pads
			(clearance 0)
		)
		(min_thickness 0.25)
		(keepout
			(tracks not_allowed)
			(vias allowed)
			(pads allowed)
			(copperpour not_allowed)
			(footprints allowed)
		)
		(placement
			(enabled no)
			(sheetname "")
		)
		(fill
			(thermal_gap 0.5)
			(thermal_bridge_width 0.5)
			(island_removal_mode 0)
		)
		(polygon
			(pts
				(arc
					(start 443.2935 -239.232186)
					(mid 443.28978 -239.241166)
					(end 443.2808 -239.244886)
				)
				(arc
					(start 441.8076 -239.244886)
					(mid 441.79862 -239.241166)
					(end 441.7949 -239.232186)
				)
				(arc
					(start 441.7949 -238.737648)
					(mid 441.79862 -238.728668)
					(end 441.8076 -238.724948)
				)
				(arc
					(start 443.2808 -238.724948)
					(mid 443.28978 -238.728668)
					(end 443.2935 -238.737648)
				)
			)
		)
	)
	(zone
		(layer "In1.Cu")
		(hatch none 0.5)
		(connect_pads
			(clearance 0)
		)
		(min_thickness 0.25)
		(keepout
			(tracks not_allowed)
			(vias allowed)
			(pads allowed)
			(copperpour not_allowed)
			(footprints allowed)
		)
		(placement
			(enabled no)
			(sheetname "")
		)
		(fill
			(thermal_gap 0.5)
			(thermal_bridge_width 0.5)
			(island_removal_mode 0)
		)
		(polygon
			(pts
				(arc
					(start 420.618666 -391.822686)
					(mid 420.745666 -391.949686)
					(end 420.872666 -391.822686)
				)
				(arc
					(start 420.872666 -391.746486)
					(mid 420.745666 -391.619486)
					(end 420.618666 -391.746486)
				)
			)
		)
	)
	(zone
		(layer "In1.Cu")
		(hatch none 0.5)
		(connect_pads
			(clearance 0)
		)
		(min_thickness 0.25)
		(keepout
			(tracks not_allowed)
			(vias allowed)
			(pads allowed)
			(copperpour not_allowed)
			(footprints allowed)
		)
		(placement
			(enabled no)
			(sheetname "")
		)
		(fill
			(thermal_gap 0.5)
			(thermal_bridge_width 0.5)
			(island_removal_mode 0)
		)
		(polygon
			(pts
				(arc
					(start 191.909446 -315.732414)
					(mid 191.905726 -315.741394)
					(end 191.896746 -315.745114)
				)
				(arc
					(start 190.423546 -315.745114)
					(mid 190.414566 -315.741394)
					(end 190.410846 -315.732414)
				)
				(arc
					(start 190.410846 -315.237876)
					(mid 190.414566 -315.228896)
					(end 190.423546 -315.225176)
				)
				(arc
					(start 191.896746 -315.225176)
					(mid 191.905726 -315.228896)
					(end 191.909446 -315.237876)
				)
			)
		)
	)
	(zone
		(layer "In1.Cu")
		(hatch none 0.5)
		(connect_pads
			(clearance 0)
		)
		(min_thickness 0.25)
		(keepout
			(tracks not_allowed)
			(vias allowed)
			(pads allowed)
			(copperpour not_allowed)
			(footprints allowed)
		)
		(placement
			(enabled no)
			(sheetname "")
		)
		(fill
			(thermal_gap 0.5)
			(thermal_bridge_width 0.5)
			(island_removal_mode 0)
		)
		(polygon
			(pts
				(arc
					(start 48.533304 -310.632348)
					(mid 48.529584 -310.641328)
					(end 48.520604 -310.645048)
				)
				(arc
					(start 47.047404 -310.645048)
					(mid 47.038424 -310.641328)
					(end 47.034704 -310.632348)
				)
				(arc
					(start 47.034704 -310.13781)
					(mid 47.038424 -310.12883)
					(end 47.047404 -310.12511)
				)
				(arc
					(start 48.520604 -310.12511)
					(mid 48.529584 -310.12883)
					(end 48.533304 -310.13781)
				)
			)
		)
	)
	(zone
		(layer "In1.Cu")
		(hatch none 0.5)
		(connect_pads
			(clearance 0)
		)
		(min_thickness 0.25)
		(keepout
			(tracks not_allowed)
			(vias allowed)
			(pads allowed)
			(copperpour not_allowed)
			(footprints allowed)
		)
		(placement
			(enabled no)
			(sheetname "")
		)
		(fill
			(thermal_gap 0.5)
			(thermal_bridge_width 0.5)
			(island_removal_mode 0)
		)
		(polygon
			(pts
				(arc
					(start 84.89823 -383.92227)
					(mid 84.59343 -383.92227)
					(end 84.89823 -383.92227)
				)
			)
		)
	)
	(zone
		(layer "In1.Cu")
		(hatch none 0.5)
		(connect_pads
			(clearance 0)
		)
		(min_thickness 0.25)
		(keepout
			(tracks not_allowed)
			(vias allowed)
			(pads allowed)
			(copperpour not_allowed)
			(footprints allowed)
		)
		(placement
			(enabled no)
			(sheetname "")
		)
		(fill
			(thermal_gap 0.5)
			(thermal_bridge_width 0.5)
			(island_removal_mode 0)
		)
		(polygon
			(pts
				(arc
					(start 450.8373 -253.682246)
					(mid 450.83358 -253.691226)
					(end 450.8246 -253.694946)
				)
				(arc
					(start 449.3514 -253.694946)
					(mid 449.34242 -253.691226)
					(end 449.3387 -253.682246)
				)
				(arc
					(start 449.3387 -253.187708)
					(mid 449.34242 -253.178728)
					(end 449.3514 -253.175008)
				)
				(arc
					(start 450.8246 -253.175008)
					(mid 450.83358 -253.178728)
					(end 450.8373 -253.187708)
				)
			)
		)
	)
	(zone
		(layer "In1.Cu")
		(hatch none 0.5)
		(connect_pads
			(clearance 0)
		)
		(min_thickness 0.25)
		(keepout
			(tracks not_allowed)
			(vias allowed)
			(pads allowed)
			(copperpour not_allowed)
			(footprints allowed)
		)
		(placement
			(enabled no)
			(sheetname "")
		)
		(fill
			(thermal_gap 0.5)
			(thermal_bridge_width 0.5)
			(island_removal_mode 0)
		)
		(polygon
			(pts
				(arc
					(start 199.4535 -251.13234)
					(mid 199.44978 -251.14132)
					(end 199.4408 -251.14504)
				)
				(arc
					(start 197.9676 -251.14504)
					(mid 197.95862 -251.14132)
					(end 197.9549 -251.13234)
				)
				(arc
					(start 197.9549 -250.637802)
					(mid 197.95862 -250.628822)
					(end 197.9676 -250.625102)
				)
				(arc
					(start 199.4408 -250.625102)
					(mid 199.44978 -250.628822)
					(end 199.4535 -250.637802)
				)
			)
		)
	)
	(zone
		(layer "In1.Cu")
		(hatch none 0.5)
		(connect_pads
			(clearance 0)
		)
		(min_thickness 0.25)
		(keepout
			(tracks not_allowed)
			(vias allowed)
			(pads allowed)
			(copperpour not_allowed)
			(footprints allowed)
		)
		(placement
			(enabled no)
			(sheetname "")
		)
		(fill
			(thermal_gap 0.5)
			(thermal_bridge_width 0.5)
			(island_removal_mode 0)
		)
		(polygon
			(pts
				(arc
					(start 371.761258 -393.69238)
					(mid 371.380258 -393.69238)
					(end 371.761258 -393.69238)
				)
			)
		)
	)
	(zone
		(layer "In1.Cu")
		(hatch none 0.5)
		(connect_pads
			(clearance 0)
		)
		(min_thickness 0.25)
		(keepout
			(tracks not_allowed)
			(vias allowed)
			(pads allowed)
			(copperpour not_allowed)
			(footprints allowed)
		)
		(placement
			(enabled no)
			(sheetname "")
		)
		(fill
			(thermal_gap 0.5)
			(thermal_bridge_width 0.5)
			(island_removal_mode 0)
		)
		(polygon
			(pts
				(arc
					(start 404.397972 -399.143474)
					(mid 404.093172 -399.143474)
					(end 404.397972 -399.143474)
				)
			)
		)
	)
	(zone
		(layer "In1.Cu")
		(hatch none 0.5)
		(connect_pads
			(clearance 0)
		)
		(min_thickness 0.25)
		(keepout
			(tracks not_allowed)
			(vias allowed)
			(pads allowed)
			(copperpour not_allowed)
			(footprints allowed)
		)
		(placement
			(enabled no)
			(sheetname "")
		)
		(fill
			(thermal_gap 0.5)
			(thermal_bridge_width 0.5)
			(island_removal_mode 0)
		)
		(polygon
			(pts
				(arc
					(start 304.017426 -240.082324)
					(mid 304.013706 -240.091304)
					(end 304.004726 -240.095024)
				)
				(arc
					(start 302.531526 -240.095024)
					(mid 302.522546 -240.091304)
					(end 302.518826 -240.082324)
				)
				(arc
					(start 302.518826 -239.587786)
					(mid 302.522546 -239.578806)
					(end 302.531526 -239.575086)
				)
				(arc
					(start 304.004726 -239.575086)
					(mid 304.013706 -239.578806)
					(end 304.017426 -239.587786)
				)
			)
		)
	)
	(zone
		(layer "In1.Cu")
		(hatch none 0.5)
		(connect_pads
			(clearance 0)
		)
		(min_thickness 0.25)
		(keepout
			(tracks not_allowed)
			(vias allowed)
			(pads allowed)
			(copperpour not_allowed)
			(footprints allowed)
		)
		(placement
			(enabled no)
			(sheetname "")
		)
		(fill
			(thermal_gap 0.5)
			(thermal_bridge_width 0.5)
			(island_removal_mode 0)
		)
		(polygon
			(pts
				(arc
					(start 277.941532 -220.532198)
					(mid 277.937812 -220.541178)
					(end 277.928832 -220.544898)
				)
				(arc
					(start 276.455632 -220.544898)
					(mid 276.446652 -220.541178)
					(end 276.442932 -220.532198)
				)
				(arc
					(start 276.442932 -220.03766)
					(mid 276.446652 -220.02868)
					(end 276.455632 -220.02496)
				)
				(arc
					(start 277.928832 -220.02496)
					(mid 277.937812 -220.02868)
					(end 277.941532 -220.03766)
				)
			)
		)
	)
	(zone
		(layer "In1.Cu")
		(hatch none 0.5)
		(connect_pads
			(clearance 0)
		)
		(min_thickness 0.25)
		(keepout
			(tracks not_allowed)
			(vias allowed)
			(pads allowed)
			(copperpour not_allowed)
			(footprints allowed)
		)
		(placement
			(enabled no)
			(sheetname "")
		)
		(fill
			(thermal_gap 0.5)
			(thermal_bridge_width 0.5)
			(island_removal_mode 0)
		)
		(polygon
			(pts
				(arc
					(start 439.849514 -216.28227)
					(mid 439.845794 -216.29125)
					(end 439.836814 -216.29497)
				)
				(arc
					(start 438.363614 -216.29497)
					(mid 438.354634 -216.29125)
					(end 438.350914 -216.28227)
				)
				(arc
					(start 438.350914 -215.787732)
					(mid 438.354634 -215.778752)
					(end 438.363614 -215.775032)
				)
				(arc
					(start 439.836814 -215.775032)
					(mid 439.845794 -215.778752)
					(end 439.849514 -215.787732)
				)
			)
		)
	)
	(zone
		(layer "In1.Cu")
		(hatch none 0.5)
		(connect_pads
			(clearance 0)
		)
		(min_thickness 0.25)
		(keepout
			(tracks not_allowed)
			(vias allowed)
			(pads allowed)
			(copperpour not_allowed)
			(footprints allowed)
		)
		(placement
			(enabled no)
			(sheetname "")
		)
		(fill
			(thermal_gap 0.5)
			(thermal_bridge_width 0.5)
			(island_removal_mode 0)
		)
		(polygon
			(pts
				(arc
					(start 172.72127 -253.6825)
					(mid 172.71755 -253.69148)
					(end 172.70857 -253.6952)
				)
				(arc
					(start 171.23537 -253.6952)
					(mid 171.22639 -253.69148)
					(end 171.22267 -253.6825)
				)
				(arc
					(start 171.22267 -253.187962)
					(mid 171.22639 -253.178982)
					(end 171.23537 -253.175262)
				)
				(arc
					(start 172.70857 -253.175262)
					(mid 172.71755 -253.178982)
					(end 172.72127 -253.187962)
				)
			)
		)
	)
	(zone
		(layer "In1.Cu")
		(hatch none 0.5)
		(connect_pads
			(clearance 0)
		)
		(min_thickness 0.25)
		(keepout
			(tracks not_allowed)
			(vias allowed)
			(pads allowed)
			(copperpour not_allowed)
			(footprints allowed)
		)
		(placement
			(enabled no)
			(sheetname "")
		)
		(fill
			(thermal_gap 0.5)
			(thermal_bridge_width 0.5)
			(island_removal_mode 0)
		)
		(polygon
			(pts
				(arc
					(start 439.849514 -197.582282)
					(mid 439.845794 -197.591262)
					(end 439.836814 -197.594982)
				)
				(arc
					(start 438.363614 -197.594982)
					(mid 438.354634 -197.591262)
					(end 438.350914 -197.582282)
				)
				(arc
					(start 438.350914 -197.087744)
					(mid 438.354634 -197.078764)
					(end 438.363614 -197.075044)
				)
				(arc
					(start 439.836814 -197.075044)
					(mid 439.845794 -197.078764)
					(end 439.849514 -197.087744)
				)
			)
		)
	)
	(zone
		(layer "In1.Cu")
		(hatch none 0.5)
		(connect_pads
			(clearance 0)
		)
		(min_thickness 0.25)
		(keepout
			(tracks not_allowed)
			(vias allowed)
			(pads allowed)
			(copperpour not_allowed)
			(footprints allowed)
		)
		(placement
			(enabled no)
			(sheetname "")
		)
		(fill
			(thermal_gap 0.5)
			(thermal_bridge_width 0.5)
			(island_removal_mode 0)
		)
		(polygon
			(pts
				(arc
					(start 149.888702 -386.003292)
					(mid 149.507702 -386.003292)
					(end 149.888702 -386.003292)
				)
			)
		)
	)
	(zone
		(layer "In1.Cu")
		(hatch none 0.5)
		(connect_pads
			(clearance 0)
		)
		(min_thickness 0.25)
		(keepout
			(tracks not_allowed)
			(vias allowed)
			(pads allowed)
			(copperpour not_allowed)
			(footprints allowed)
		)
		(placement
			(enabled no)
			(sheetname "")
		)
		(fill
			(thermal_gap 0.5)
			(thermal_bridge_width 0.5)
			(island_removal_mode 0)
		)
		(polygon
			(pts
				(arc
					(start 443.2935 -211.182204)
					(mid 443.28978 -211.191184)
					(end 443.2808 -211.194904)
				)
				(arc
					(start 441.8076 -211.194904)
					(mid 441.79862 -211.191184)
					(end 441.7949 -211.182204)
				)
				(arc
					(start 441.7949 -210.687666)
					(mid 441.79862 -210.678686)
					(end 441.8076 -210.674966)
				)
				(arc
					(start 443.2808 -210.674966)
					(mid 443.28978 -210.678686)
					(end 443.2935 -210.687666)
				)
			)
		)
	)
	(zone
		(layer "In1.Cu")
		(hatch none 0.5)
		(connect_pads
			(clearance 0)
		)
		(min_thickness 0.25)
		(keepout
			(tracks not_allowed)
			(vias allowed)
			(pads allowed)
			(copperpour not_allowed)
			(footprints allowed)
		)
		(placement
			(enabled no)
			(sheetname "")
		)
		(fill
			(thermal_gap 0.5)
			(thermal_bridge_width 0.5)
			(island_removal_mode 0)
		)
		(polygon
			(pts
				(arc
					(start 169.277284 -278.332438)
					(mid 169.273564 -278.341418)
					(end 169.264584 -278.345138)
				)
				(arc
					(start 167.791384 -278.345138)
					(mid 167.782404 -278.341418)
					(end 167.778684 -278.332438)
				)
				(arc
					(start 167.778684 -277.8379)
					(mid 167.782404 -277.82892)
					(end 167.791384 -277.8252)
				)
				(arc
					(start 169.264584 -277.8252)
					(mid 169.273564 -277.82892)
					(end 169.277284 -277.8379)
				)
			)
		)
	)
	(zone
		(layer "In1.Cu")
		(hatch none 0.5)
		(connect_pads
			(clearance 0)
		)
		(min_thickness 0.25)
		(keepout
			(tracks not_allowed)
			(vias allowed)
			(pads allowed)
			(copperpour not_allowed)
			(footprints allowed)
		)
		(placement
			(enabled no)
			(sheetname "")
		)
		(fill
			(thermal_gap 0.5)
			(thermal_bridge_width 0.5)
			(island_removal_mode 0)
		)
		(polygon
			(pts
				(arc
					(start 202.897232 -230.732584)
					(mid 202.893512 -230.741564)
					(end 202.884532 -230.745284)
				)
				(arc
					(start 201.411332 -230.745284)
					(mid 201.402352 -230.741564)
					(end 201.398632 -230.732584)
				)
				(arc
					(start 201.398632 -230.238046)
					(mid 201.402352 -230.229066)
					(end 201.411332 -230.225346)
				)
				(arc
					(start 202.884532 -230.225346)
					(mid 202.893512 -230.229066)
					(end 202.897232 -230.238046)
				)
			)
		)
	)
	(zone
		(layer "In1.Cu")
		(hatch none 0.5)
		(connect_pads
			(clearance 0)
		)
		(min_thickness 0.25)
		(keepout
			(tracks not_allowed)
			(vias allowed)
			(pads allowed)
			(copperpour not_allowed)
			(footprints allowed)
		)
		(placement
			(enabled no)
			(sheetname "")
		)
		(fill
			(thermal_gap 0.5)
			(thermal_bridge_width 0.5)
			(island_removal_mode 0)
		)
		(polygon
			(pts
				(arc
					(start 116.491004 -391.319258)
					(mid 116.618004 -391.446258)
					(end 116.745004 -391.319258)
				)
				(arc
					(start 116.745004 -391.243058)
					(mid 116.618004 -391.116058)
					(end 116.491004 -391.243058)
				)
			)
		)
	)
	(zone
		(layer "In1.Cu")
		(hatch none 0.5)
		(connect_pads
			(clearance 0)
		)
		(min_thickness 0.25)
		(keepout
			(tracks not_allowed)
			(vias allowed)
			(pads allowed)
			(copperpour not_allowed)
			(footprints allowed)
		)
		(placement
			(enabled no)
			(sheetname "")
		)
		(fill
			(thermal_gap 0.5)
			(thermal_bridge_width 0.5)
			(island_removal_mode 0)
		)
		(polygon
			(pts
				(arc
					(start 58.661046 -386.003292)
					(mid 58.280046 -386.003292)
					(end 58.661046 -386.003292)
				)
			)
		)
	)
	(zone
		(layer "In1.Cu")
		(hatch none 0.5)
		(connect_pads
			(clearance 0)
		)
		(min_thickness 0.25)
		(keepout
			(tracks not_allowed)
			(vias allowed)
			(pads allowed)
			(copperpour not_allowed)
			(footprints allowed)
		)
		(placement
			(enabled no)
			(sheetname "")
		)
		(fill
			(thermal_gap 0.5)
			(thermal_bridge_width 0.5)
			(island_removal_mode 0)
		)
		(polygon
			(pts
				(arc
					(start 53.861208 -389.467344)
					(mid 53.480208 -389.467344)
					(end 53.861208 -389.467344)
				)
			)
		)
	)
	(zone
		(layer "In1.Cu")
		(hatch none 0.5)
		(connect_pads
			(clearance 0)
		)
		(min_thickness 0.25)
		(keepout
			(tracks not_allowed)
			(vias allowed)
			(pads allowed)
			(copperpour not_allowed)
			(footprints allowed)
		)
		(placement
			(enabled no)
			(sheetname "")
		)
		(fill
			(thermal_gap 0.5)
			(thermal_bridge_width 0.5)
			(island_removal_mode 0)
		)
		(polygon
			(pts
				(arc
					(start 202.897232 -267.282422)
					(mid 202.893512 -267.291402)
					(end 202.884532 -267.295122)
				)
				(arc
					(start 201.411332 -267.295122)
					(mid 201.402352 -267.291402)
					(end 201.398632 -267.282422)
				)
				(arc
					(start 201.398632 -266.787884)
					(mid 201.402352 -266.778904)
					(end 201.411332 -266.775184)
				)
				(arc
					(start 202.884532 -266.775184)
					(mid 202.893512 -266.778904)
					(end 202.897232 -266.787884)
				)
			)
		)
	)
	(zone
		(layer "In1.Cu")
		(hatch none 0.5)
		(connect_pads
			(clearance 0)
		)
		(min_thickness 0.25)
		(keepout
			(tracks not_allowed)
			(vias allowed)
			(pads allowed)
			(copperpour not_allowed)
			(footprints allowed)
		)
		(placement
			(enabled no)
			(sheetname "")
		)
		(fill
			(thermal_gap 0.5)
			(thermal_bridge_width 0.5)
			(island_removal_mode 0)
		)
		(polygon
			(pts
				(arc
					(start 413.117284 -293.632128)
					(mid 413.113564 -293.641108)
					(end 413.104584 -293.644828)
				)
				(arc
					(start 411.631384 -293.644828)
					(mid 411.622404 -293.641108)
					(end 411.618684 -293.632128)
				)
				(arc
					(start 411.618684 -293.13759)
					(mid 411.622404 -293.12861)
					(end 411.631384 -293.12489)
				)
				(arc
					(start 413.104584 -293.12489)
					(mid 413.113564 -293.12861)
					(end 413.117284 -293.13759)
				)
			)
		)
	)
	(zone
		(layer "In1.Cu")
		(hatch none 0.5)
		(connect_pads
			(clearance 0)
		)
		(min_thickness 0.25)
		(keepout
			(tracks not_allowed)
			(vias allowed)
			(pads allowed)
			(copperpour not_allowed)
			(footprints allowed)
		)
		(placement
			(enabled no)
			(sheetname "")
		)
		(fill
			(thermal_gap 0.5)
			(thermal_bridge_width 0.5)
			(island_removal_mode 0)
		)
		(polygon
			(pts
				(arc
					(start 285.485332 -294.482266)
					(mid 285.481612 -294.491246)
					(end 285.472632 -294.494966)
				)
				(arc
					(start 283.999432 -294.494966)
					(mid 283.990452 -294.491246)
					(end 283.986732 -294.482266)
				)
				(arc
					(start 283.986732 -293.987728)
					(mid 283.990452 -293.978748)
					(end 283.999432 -293.975028)
				)
				(arc
					(start 285.472632 -293.975028)
					(mid 285.481612 -293.978748)
					(end 285.485332 -293.987728)
				)
			)
		)
	)
	(zone
		(layer "In1.Cu")
		(hatch none 0.5)
		(connect_pads
			(clearance 0)
		)
		(min_thickness 0.25)
		(keepout
			(tracks not_allowed)
			(vias allowed)
			(pads allowed)
			(copperpour not_allowed)
			(footprints allowed)
		)
		(placement
			(enabled no)
			(sheetname "")
		)
		(fill
			(thermal_gap 0.5)
			(thermal_bridge_width 0.5)
			(island_removal_mode 0)
		)
		(polygon
			(pts
				(arc
					(start 281.385264 -201.83221)
					(mid 281.381544 -201.84119)
					(end 281.372564 -201.84491)
				)
				(arc
					(start 279.899364 -201.84491)
					(mid 279.890384 -201.84119)
					(end 279.886664 -201.83221)
				)
				(arc
					(start 279.886664 -201.337672)
					(mid 279.890384 -201.328692)
					(end 279.899364 -201.324972)
				)
				(arc
					(start 281.372564 -201.324972)
					(mid 281.381544 -201.328692)
					(end 281.385264 -201.337672)
				)
			)
		)
	)
	(zone
		(layer "In1.Cu")
		(hatch none 0.5)
		(connect_pads
			(clearance 0)
		)
		(min_thickness 0.25)
		(keepout
			(tracks not_allowed)
			(vias allowed)
			(pads allowed)
			(copperpour not_allowed)
			(footprints allowed)
		)
		(placement
			(enabled no)
			(sheetname "")
		)
		(fill
			(thermal_gap 0.5)
			(thermal_bridge_width 0.5)
			(island_removal_mode 0)
		)
		(polygon
			(pts
				(arc
					(start 338.388706 -397.156432)
					(mid 338.007706 -397.156432)
					(end 338.388706 -397.156432)
				)
			)
		)
	)
	(zone
		(layer "In1.Cu")
		(hatch none 0.5)
		(connect_pads
			(clearance 0)
		)
		(min_thickness 0.25)
		(keepout
			(tracks not_allowed)
			(vias allowed)
			(pads allowed)
			(copperpour not_allowed)
			(footprints allowed)
		)
		(placement
			(enabled no)
			(sheetname "")
		)
		(fill
			(thermal_gap 0.5)
			(thermal_bridge_width 0.5)
			(island_removal_mode 0)
		)
		(polygon
			(pts
				(arc
					(start 374.5611 -397.849344)
					(mid 374.1801 -397.849344)
					(end 374.5611 -397.849344)
				)
			)
		)
	)
	(zone
		(layer "In1.Cu")
		(hatch none 0.5)
		(connect_pads
			(clearance 0)
		)
		(min_thickness 0.25)
		(keepout
			(tracks not_allowed)
			(vias allowed)
			(pads allowed)
			(copperpour not_allowed)
			(footprints allowed)
		)
		(placement
			(enabled no)
			(sheetname "")
		)
		(fill
			(thermal_gap 0.5)
			(thermal_bridge_width 0.5)
			(island_removal_mode 0)
		)
		(polygon
			(pts
				(arc
					(start 301.4853 -379.360684)
					(mid 301.505224 -379.36992)
					(end 301.526956 -379.37313)
				)
				(arc
					(start 301.72152 -379.37313)
					(mid 301.775402 -379.350812)
					(end 301.79772 -379.29693)
				)
				(arc
					(start 301.79772 -378.61113)
					(mid 301.775402 -378.557248)
					(end 301.72152 -378.53493)
				)
				(arc
					(start 301.526956 -378.53493)
					(mid 301.505212 -378.538098)
					(end 301.4853 -378.547376)
				)
				(arc
					(start 301.189136 -378.740162)
					(mid 301.147452 -378.752384)
					(end 301.105824 -378.739908)
				)
				(arc
					(start 300.8122 -378.547376)
					(mid 300.792276 -378.53814)
					(end 300.770544 -378.53493)
				)
				(arc
					(start 300.57598 -378.53493)
					(mid 300.522098 -378.557248)
					(end 300.49978 -378.61113)
				)
				(arc
					(start 300.49978 -379.29693)
					(mid 300.522098 -379.350812)
					(end 300.57598 -379.37313)
				)
				(arc
					(start 300.771814 -379.37313)
					(mid 300.793558 -379.369962)
					(end 300.81347 -379.360684)
				)
				(arc
					(start 301.107094 -379.168152)
					(mid 301.14875 -379.15575)
					(end 301.190406 -379.168152)
				)
			)
		)
	)
	(zone
		(layer "In1.Cu")
		(hatch none 0.5)
		(connect_pads
			(clearance 0)
		)
		(min_thickness 0.25)
		(keepout
			(tracks not_allowed)
			(vias allowed)
			(pads allowed)
			(copperpour not_allowed)
			(footprints allowed)
		)
		(placement
			(enabled no)
			(sheetname "")
		)
		(fill
			(thermal_gap 0.5)
			(thermal_bridge_width 0.5)
			(island_removal_mode 0)
		)
		(polygon
			(pts
				(arc
					(start 165.177216 -267.282422)
					(mid 165.173496 -267.291402)
					(end 165.164516 -267.295122)
				)
				(arc
					(start 163.691316 -267.295122)
					(mid 163.682336 -267.291402)
					(end 163.678616 -267.282422)
				)
				(arc
					(start 163.678616 -266.787884)
					(mid 163.682336 -266.778904)
					(end 163.691316 -266.775184)
				)
				(arc
					(start 165.164516 -266.775184)
					(mid 165.173496 -266.778904)
					(end 165.177216 -266.787884)
				)
			)
		)
	)
	(zone
		(layer "In1.Cu")
		(hatch none 0.5)
		(connect_pads
			(clearance 0)
		)
		(min_thickness 0.25)
		(keepout
			(tracks not_allowed)
			(vias allowed)
			(pads allowed)
			(copperpour not_allowed)
			(footprints allowed)
		)
		(placement
			(enabled no)
			(sheetname "")
		)
		(fill
			(thermal_gap 0.5)
			(thermal_bridge_width 0.5)
			(island_removal_mode 0)
		)
		(polygon
			(pts
				(arc
					(start 435.749446 -251.982224)
					(mid 435.745726 -251.991204)
					(end 435.736746 -251.994924)
				)
				(arc
					(start 434.263546 -251.994924)
					(mid 434.254566 -251.991204)
					(end 434.250846 -251.982224)
				)
				(arc
					(start 434.250846 -251.487686)
					(mid 434.254566 -251.478706)
					(end 434.263546 -251.474986)
				)
				(arc
					(start 435.736746 -251.474986)
					(mid 435.745726 -251.478706)
					(end 435.749446 -251.487686)
				)
			)
		)
	)
	(zone
		(layer "In1.Cu")
		(hatch none 0.5)
		(connect_pads
			(clearance 0)
		)
		(min_thickness 0.25)
		(keepout
			(tracks not_allowed)
			(vias allowed)
			(pads allowed)
			(copperpour not_allowed)
			(footprints allowed)
		)
		(placement
			(enabled no)
			(sheetname "")
		)
		(fill
			(thermal_gap 0.5)
			(thermal_bridge_width 0.5)
			(island_removal_mode 0)
		)
		(polygon
			(pts
				(arc
					(start 417.217352 -313.182254)
					(mid 417.213632 -313.191234)
					(end 417.204652 -313.194954)
				)
				(arc
					(start 415.731452 -313.194954)
					(mid 415.722472 -313.191234)
					(end 415.718752 -313.182254)
				)
				(arc
					(start 415.718752 -312.687716)
					(mid 415.722472 -312.678736)
					(end 415.731452 -312.675016)
				)
				(arc
					(start 417.204652 -312.675016)
					(mid 417.213632 -312.678736)
					(end 417.217352 -312.687716)
				)
			)
		)
	)
	(zone
		(layer "In1.Cu")
		(hatch none 0.5)
		(connect_pads
			(clearance 0)
		)
		(min_thickness 0.25)
		(keepout
			(tracks not_allowed)
			(vias allowed)
			(pads allowed)
			(copperpour not_allowed)
			(footprints allowed)
		)
		(placement
			(enabled no)
			(sheetname "")
		)
		(fill
			(thermal_gap 0.5)
			(thermal_bridge_width 0.5)
			(island_removal_mode 0)
		)
		(polygon
			(pts
				(arc
					(start 428.205392 -239.232186)
					(mid 428.201672 -239.241166)
					(end 428.192692 -239.244886)
				)
				(arc
					(start 426.719492 -239.244886)
					(mid 426.710512 -239.241166)
					(end 426.706792 -239.232186)
				)
				(arc
					(start 426.706792 -238.737648)
					(mid 426.710512 -238.728668)
					(end 426.719492 -238.724948)
				)
				(arc
					(start 428.192692 -238.724948)
					(mid 428.201672 -238.728668)
					(end 428.205392 -238.737648)
				)
			)
		)
	)
	(zone
		(layer "In1.Cu")
		(hatch none 0.5)
		(connect_pads
			(clearance 0)
		)
		(min_thickness 0.25)
		(keepout
			(tracks not_allowed)
			(vias allowed)
			(pads allowed)
			(copperpour not_allowed)
			(footprints allowed)
		)
		(placement
			(enabled no)
			(sheetname "")
		)
		(fill
			(thermal_gap 0.5)
			(thermal_bridge_width 0.5)
			(island_removal_mode 0)
		)
		(polygon
			(pts
				(arc
					(start 340.318598 -391.822686)
					(mid 340.445598 -391.949686)
					(end 340.572598 -391.822686)
				)
				(arc
					(start 340.572598 -391.746486)
					(mid 340.445598 -391.619486)
					(end 340.318598 -391.746486)
				)
			)
		)
	)
	(zone
		(layer "In1.Cu")
		(hatch none 0.5)
		(connect_pads
			(clearance 0)
		)
		(min_thickness 0.25)
		(keepout
			(tracks not_allowed)
			(vias allowed)
			(pads allowed)
			(copperpour not_allowed)
			(footprints allowed)
		)
		(placement
			(enabled no)
			(sheetname "")
		)
		(fill
			(thermal_gap 0.5)
			(thermal_bridge_width 0.5)
			(island_removal_mode 0)
		)
		(polygon
			(pts
				(arc
					(start 296.473372 -221.382082)
					(mid 296.469652 -221.391062)
					(end 296.460672 -221.394782)
				)
				(arc
					(start 294.987472 -221.394782)
					(mid 294.978492 -221.391062)
					(end 294.974772 -221.382082)
				)
				(arc
					(start 294.974772 -220.887544)
					(mid 294.978492 -220.878564)
					(end 294.987472 -220.874844)
				)
				(arc
					(start 296.460672 -220.874844)
					(mid 296.469652 -220.878564)
					(end 296.473372 -220.887544)
				)
			)
		)
	)
	(zone
		(layer "In1.Cu")
		(hatch none 0.5)
		(connect_pads
			(clearance 0)
		)
		(min_thickness 0.25)
		(keepout
			(tracks not_allowed)
			(vias allowed)
			(pads allowed)
			(copperpour not_allowed)
			(footprints allowed)
		)
		(placement
			(enabled no)
			(sheetname "")
		)
		(fill
			(thermal_gap 0.5)
			(thermal_bridge_width 0.5)
			(island_removal_mode 0)
		)
		(polygon
			(pts
				(arc
					(start 180.265324 -206.082392)
					(mid 180.261604 -206.091372)
					(end 180.252624 -206.095092)
				)
				(arc
					(start 178.779424 -206.095092)
					(mid 178.770444 -206.091372)
					(end 178.766724 -206.082392)
				)
				(arc
					(start 178.766724 -205.587854)
					(mid 178.770444 -205.578874)
					(end 178.779424 -205.575154)
				)
				(arc
					(start 180.252624 -205.575154)
					(mid 180.261604 -205.578874)
					(end 180.265324 -205.587854)
				)
			)
		)
	)
	(zone
		(layer "In1.Cu")
		(hatch none 0.5)
		(connect_pads
			(clearance 0)
		)
		(min_thickness 0.25)
		(keepout
			(tracks not_allowed)
			(vias allowed)
			(pads allowed)
			(copperpour not_allowed)
			(footprints allowed)
		)
		(placement
			(enabled no)
			(sheetname "")
		)
		(fill
			(thermal_gap 0.5)
			(thermal_bridge_width 0.5)
			(island_removal_mode 0)
		)
		(polygon
			(pts
				(arc
					(start 349.188786 -393.69238)
					(mid 348.807786 -393.69238)
					(end 349.188786 -393.69238)
				)
			)
		)
	)
	(zone
		(layer "In1.Cu")
		(hatch none 0.5)
		(connect_pads
			(clearance 0)
		)
		(min_thickness 0.25)
		(keepout
			(tracks not_allowed)
			(vias allowed)
			(pads allowed)
			(copperpour not_allowed)
			(footprints allowed)
		)
		(placement
			(enabled no)
			(sheetname "")
		)
		(fill
			(thermal_gap 0.5)
			(thermal_bridge_width 0.5)
			(island_removal_mode 0)
		)
		(polygon
			(pts
				(arc
					(start 417.217352 -274.082256)
					(mid 417.213632 -274.091236)
					(end 417.204652 -274.094956)
				)
				(arc
					(start 415.731452 -274.094956)
					(mid 415.722472 -274.091236)
					(end 415.718752 -274.082256)
				)
				(arc
					(start 415.718752 -273.587718)
					(mid 415.722472 -273.578738)
					(end 415.731452 -273.575018)
				)
				(arc
					(start 417.204652 -273.575018)
					(mid 417.213632 -273.578738)
					(end 417.217352 -273.587718)
				)
			)
		)
	)
	(zone
		(layer "In1.Cu")
		(hatch none 0.5)
		(connect_pads
			(clearance 0)
		)
		(min_thickness 0.25)
		(keepout
			(tracks not_allowed)
			(vias allowed)
			(pads allowed)
			(copperpour not_allowed)
			(footprints allowed)
		)
		(placement
			(enabled no)
			(sheetname "")
		)
		(fill
			(thermal_gap 0.5)
			(thermal_bridge_width 0.5)
			(island_removal_mode 0)
		)
		(polygon
			(pts
				(arc
					(start 454.937368 -268.132306)
					(mid 454.933648 -268.141286)
					(end 454.924668 -268.145006)
				)
				(arc
					(start 453.451468 -268.145006)
					(mid 453.442488 -268.141286)
					(end 453.438768 -268.132306)
				)
				(arc
					(start 453.438768 -267.637768)
					(mid 453.442488 -267.628788)
					(end 453.451468 -267.625068)
				)
				(arc
					(start 454.924668 -267.625068)
					(mid 454.933648 -267.628788)
					(end 454.937368 -267.637768)
				)
			)
		)
	)
	(zone
		(layer "In1.Cu")
		(hatch none 0.5)
		(connect_pads
			(clearance 0)
		)
		(min_thickness 0.25)
		(keepout
			(tracks not_allowed)
			(vias allowed)
			(pads allowed)
			(copperpour not_allowed)
			(footprints allowed)
		)
		(placement
			(enabled no)
			(sheetname "")
		)
		(fill
			(thermal_gap 0.5)
			(thermal_bridge_width 0.5)
			(island_removal_mode 0)
		)
		(polygon
			(pts
				(arc
					(start 303.860962 -394.385292)
					(mid 303.479962 -394.385292)
					(end 303.860962 -394.385292)
				)
			)
		)
	)
	(zone
		(layer "In1.Cu")
		(hatch none 0.5)
		(connect_pads
			(clearance 0)
		)
		(min_thickness 0.25)
		(keepout
			(tracks not_allowed)
			(vias allowed)
			(pads allowed)
			(copperpour not_allowed)
			(footprints allowed)
		)
		(placement
			(enabled no)
			(sheetname "")
		)
		(fill
			(thermal_gap 0.5)
			(thermal_bridge_width 0.5)
			(island_removal_mode 0)
		)
		(polygon
			(pts
				(arc
					(start 420.661338 -308.932326)
					(mid 420.657618 -308.941306)
					(end 420.648638 -308.945026)
				)
				(arc
					(start 419.175438 -308.945026)
					(mid 419.166458 -308.941306)
					(end 419.162738 -308.932326)
				)
				(arc
					(start 419.162738 -308.437788)
					(mid 419.166458 -308.428808)
					(end 419.175438 -308.425088)
				)
				(arc
					(start 420.648638 -308.425088)
					(mid 420.657618 -308.428808)
					(end 420.661338 -308.437788)
				)
			)
		)
	)
	(zone
		(layer "In1.Cu")
		(hatch none 0.5)
		(connect_pads
			(clearance 0)
		)
		(min_thickness 0.25)
		(keepout
			(tracks not_allowed)
			(vias allowed)
			(pads allowed)
			(copperpour not_allowed)
			(footprints allowed)
		)
		(placement
			(enabled no)
			(sheetname "")
		)
		(fill
			(thermal_gap 0.5)
			(thermal_bridge_width 0.5)
			(island_removal_mode 0)
		)
		(polygon
			(pts
				(arc
					(start 12.532106 -106.85653)
					(mid 12.554424 -106.910412)
					(end 12.608306 -106.93273)
				)
				(arc
					(start 12.963906 -106.93273)
					(mid 13.017788 -106.910412)
					(end 13.040106 -106.85653)
				)
				(arc
					(start 13.040106 -104.95153)
					(mid 13.017788 -104.897648)
					(end 12.963906 -104.87533)
				)
				(arc
					(start 12.608306 -104.87533)
					(mid 12.554424 -104.897648)
					(end 12.532106 -104.95153)
				)
			)
		)
	)
	(zone
		(layer "In1.Cu")
		(hatch none 0.5)
		(connect_pads
			(clearance 0)
		)
		(min_thickness 0.25)
		(keepout
			(tracks not_allowed)
			(vias allowed)
			(pads allowed)
			(copperpour not_allowed)
			(footprints allowed)
		)
		(placement
			(enabled no)
			(sheetname "")
		)
		(fill
			(thermal_gap 0.5)
			(thermal_bridge_width 0.5)
			(island_removal_mode 0)
		)
		(polygon
			(pts
				(arc
					(start 346.89796 -392.30427)
					(mid 346.59316 -392.30427)
					(end 346.89796 -392.30427)
				)
			)
		)
	)
	(zone
		(layer "In1.Cu")
		(hatch none 0.5)
		(connect_pads
			(clearance 0)
		)
		(min_thickness 0.25)
		(keepout
			(tracks not_allowed)
			(vias allowed)
			(pads allowed)
			(copperpour not_allowed)
			(footprints allowed)
		)
		(placement
			(enabled no)
			(sheetname "")
		)
		(fill
			(thermal_gap 0.5)
			(thermal_bridge_width 0.5)
			(island_removal_mode 0)
		)
		(polygon
			(pts
				(arc
					(start 25.901396 -308.93258)
					(mid 25.897676 -308.94156)
					(end 25.888696 -308.94528)
				)
				(arc
					(start 24.415496 -308.94528)
					(mid 24.406516 -308.94156)
					(end 24.402796 -308.93258)
				)
				(arc
					(start 24.402796 -308.438042)
					(mid 24.406516 -308.429062)
					(end 24.415496 -308.425342)
				)
				(arc
					(start 25.888696 -308.425342)
					(mid 25.897676 -308.429062)
					(end 25.901396 -308.438042)
				)
			)
		)
	)
	(zone
		(layer "In1.Cu")
		(hatch none 0.5)
		(connect_pads
			(clearance 0)
		)
		(min_thickness 0.25)
		(keepout
			(tracks not_allowed)
			(vias allowed)
			(pads allowed)
			(copperpour not_allowed)
			(footprints allowed)
		)
		(placement
			(enabled no)
			(sheetname "")
		)
		(fill
			(thermal_gap 0.5)
			(thermal_bridge_width 0.5)
			(island_removal_mode 0)
		)
		(polygon
			(pts
				(arc
					(start 454.937368 -219.682314)
					(mid 454.933648 -219.691294)
					(end 454.924668 -219.695014)
				)
				(arc
					(start 453.451468 -219.695014)
					(mid 453.442488 -219.691294)
					(end 453.438768 -219.682314)
				)
				(arc
					(start 453.438768 -219.187776)
					(mid 453.442488 -219.178796)
					(end 453.451468 -219.175076)
				)
				(arc
					(start 454.924668 -219.175076)
					(mid 454.933648 -219.178796)
					(end 454.937368 -219.187776)
				)
			)
		)
	)
	(zone
		(layer "In1.Cu")
		(hatch none 0.5)
		(connect_pads
			(clearance 0)
		)
		(min_thickness 0.25)
		(keepout
			(tracks not_allowed)
			(vias allowed)
			(pads allowed)
			(copperpour not_allowed)
			(footprints allowed)
		)
		(placement
			(enabled no)
			(sheetname "")
		)
		(fill
			(thermal_gap 0.5)
			(thermal_bridge_width 0.5)
			(island_removal_mode 0)
		)
		(polygon
			(pts
				(arc
					(start 281.385264 -299.582332)
					(mid 281.381544 -299.591312)
					(end 281.372564 -299.595032)
				)
				(arc
					(start 279.899364 -299.595032)
					(mid 279.890384 -299.591312)
					(end 279.886664 -299.582332)
				)
				(arc
					(start 279.886664 -299.087794)
					(mid 279.890384 -299.078814)
					(end 279.899364 -299.075094)
				)
				(arc
					(start 281.372564 -299.075094)
					(mid 281.381544 -299.078814)
					(end 281.385264 -299.087794)
				)
			)
		)
	)
	(zone
		(layer "In1.Cu")
		(hatch none 0.5)
		(connect_pads
			(clearance 0)
		)
		(min_thickness 0.25)
		(keepout
			(tracks not_allowed)
			(vias allowed)
			(pads allowed)
			(copperpour not_allowed)
			(footprints allowed)
		)
		(placement
			(enabled no)
			(sheetname "")
		)
		(fill
			(thermal_gap 0.5)
			(thermal_bridge_width 0.5)
			(island_removal_mode 0)
		)
		(polygon
			(pts
				(arc
					(start 18.357342 -297.882564)
					(mid 18.353622 -297.891544)
					(end 18.344642 -297.895264)
				)
				(arc
					(start 16.871442 -297.895264)
					(mid 16.862462 -297.891544)
					(end 16.858742 -297.882564)
				)
				(arc
					(start 16.858742 -297.388026)
					(mid 16.862462 -297.379046)
					(end 16.871442 -297.375326)
				)
				(arc
					(start 18.344642 -297.375326)
					(mid 18.353622 -297.379046)
					(end 18.357342 -297.388026)
				)
			)
		)
	)
	(zone
		(layer "In1.Cu")
		(hatch none 0.5)
		(connect_pads
			(clearance 0)
		)
		(min_thickness 0.25)
		(keepout
			(tracks not_allowed)
			(vias allowed)
			(pads allowed)
			(copperpour not_allowed)
			(footprints allowed)
		)
		(placement
			(enabled no)
			(sheetname "")
		)
		(fill
			(thermal_gap 0.5)
			(thermal_bridge_width 0.5)
			(island_removal_mode 0)
		)
		(polygon
			(pts
				(arc
					(start 281.385264 -296.182288)
					(mid 281.381544 -296.191268)
					(end 281.372564 -296.194988)
				)
				(arc
					(start 279.899364 -296.194988)
					(mid 279.890384 -296.191268)
					(end 279.886664 -296.182288)
				)
				(arc
					(start 279.886664 -295.68775)
					(mid 279.890384 -295.67877)
					(end 279.899364 -295.67505)
				)
				(arc
					(start 281.372564 -295.67505)
					(mid 281.381544 -295.67877)
					(end 281.385264 -295.68775)
				)
			)
		)
	)
	(zone
		(layer "In1.Cu")
		(hatch none 0.5)
		(connect_pads
			(clearance 0)
		)
		(min_thickness 0.25)
		(keepout
			(tracks not_allowed)
			(vias allowed)
			(pads allowed)
			(copperpour not_allowed)
			(footprints allowed)
		)
		(placement
			(enabled no)
			(sheetname "")
		)
		(fill
			(thermal_gap 0.5)
			(thermal_bridge_width 0.5)
			(island_removal_mode 0)
		)
		(polygon
			(pts
				(arc
					(start 293.029386 -229.032308)
					(mid 293.025666 -229.041288)
					(end 293.016686 -229.045008)
				)
				(arc
					(start 291.543486 -229.045008)
					(mid 291.534506 -229.041288)
					(end 291.530786 -229.032308)
				)
				(arc
					(start 291.530786 -228.53777)
					(mid 291.534506 -228.52879)
					(end 291.543486 -228.52507)
				)
				(arc
					(start 293.016686 -228.52507)
					(mid 293.025666 -228.52879)
					(end 293.029386 -228.53777)
				)
			)
		)
	)
	(zone
		(layer "In1.Cu")
		(hatch none 0.5)
		(connect_pads
			(clearance 0)
		)
		(min_thickness 0.25)
		(keepout
			(tracks not_allowed)
			(vias allowed)
			(pads allowed)
			(copperpour not_allowed)
			(footprints allowed)
		)
		(placement
			(enabled no)
			(sheetname "")
		)
		(fill
			(thermal_gap 0.5)
			(thermal_bridge_width 0.5)
			(island_removal_mode 0)
		)
		(polygon
			(pts
				(arc
					(start 195.353432 -245.18239)
					(mid 195.349712 -245.19137)
					(end 195.340732 -245.19509)
				)
				(arc
					(start 193.867532 -245.19509)
					(mid 193.858552 -245.19137)
					(end 193.854832 -245.18239)
				)
				(arc
					(start 193.854832 -244.687852)
					(mid 193.858552 -244.678872)
					(end 193.867532 -244.675152)
				)
				(arc
					(start 195.340732 -244.675152)
					(mid 195.349712 -244.678872)
					(end 195.353432 -244.687852)
				)
			)
		)
	)
	(zone
		(layer "In1.Cu")
		(hatch none 0.5)
		(connect_pads
			(clearance 0)
		)
		(min_thickness 0.25)
		(keepout
			(tracks not_allowed)
			(vias allowed)
			(pads allowed)
			(copperpour not_allowed)
			(footprints allowed)
		)
		(placement
			(enabled no)
			(sheetname "")
		)
		(fill
			(thermal_gap 0.5)
			(thermal_bridge_width 0.5)
			(island_removal_mode 0)
		)
		(polygon
			(pts
				(arc
					(start 206.5782 -240.68532)
					(mid 205.9178 -240.68532)
					(end 206.5782 -240.68532)
				)
			)
		)
	)
	(zone
		(layer "In1.Cu")
		(hatch none 0.5)
		(connect_pads
			(clearance 0)
		)
		(min_thickness 0.25)
		(keepout
			(tracks not_allowed)
			(vias allowed)
			(pads allowed)
			(copperpour not_allowed)
			(footprints allowed)
		)
		(placement
			(enabled no)
			(sheetname "")
		)
		(fill
			(thermal_gap 0.5)
			(thermal_bridge_width 0.5)
			(island_removal_mode 0)
		)
		(polygon
			(pts
				(arc
					(start 439.849514 -254.53213)
					(mid 439.845794 -254.54111)
					(end 439.836814 -254.54483)
				)
				(arc
					(start 438.363614 -254.54483)
					(mid 438.354634 -254.54111)
					(end 438.350914 -254.53213)
				)
				(arc
					(start 438.350914 -254.037592)
					(mid 438.354634 -254.028612)
					(end 438.363614 -254.024892)
				)
				(arc
					(start 439.836814 -254.024892)
					(mid 439.845794 -254.028612)
					(end 439.849514 -254.037592)
				)
			)
		)
	)
	(zone
		(layer "In1.Cu")
		(hatch none 0.5)
		(connect_pads
			(clearance 0)
		)
		(min_thickness 0.25)
		(keepout
			(tracks not_allowed)
			(vias allowed)
			(pads allowed)
			(copperpour not_allowed)
			(footprints allowed)
		)
		(placement
			(enabled no)
			(sheetname "")
		)
		(fill
			(thermal_gap 0.5)
			(thermal_bridge_width 0.5)
			(island_removal_mode 0)
		)
		(polygon
			(pts
				(arc
					(start 443.2935 -262.182102)
					(mid 443.28978 -262.191082)
					(end 443.2808 -262.194802)
				)
				(arc
					(start 441.8076 -262.194802)
					(mid 441.79862 -262.191082)
					(end 441.7949 -262.182102)
				)
				(arc
					(start 441.7949 -261.687564)
					(mid 441.79862 -261.678584)
					(end 441.8076 -261.674864)
				)
				(arc
					(start 443.2808 -261.674864)
					(mid 443.28978 -261.678584)
					(end 443.2935 -261.687564)
				)
			)
		)
	)
	(zone
		(layer "In1.Cu")
		(hatch none 0.5)
		(connect_pads
			(clearance 0)
		)
		(min_thickness 0.25)
		(keepout
			(tracks not_allowed)
			(vias allowed)
			(pads allowed)
			(copperpour not_allowed)
			(footprints allowed)
		)
		(placement
			(enabled no)
			(sheetname "")
		)
		(fill
			(thermal_gap 0.5)
			(thermal_bridge_width 0.5)
			(island_removal_mode 0)
		)
		(polygon
			(pts
				(arc
					(start 148.688806 -389.467344)
					(mid 148.307806 -389.467344)
					(end 148.688806 -389.467344)
				)
			)
		)
	)
	(zone
		(layer "In1.Cu")
		(hatch none 0.5)
		(connect_pads
			(clearance 0)
		)
		(min_thickness 0.25)
		(keepout
			(tracks not_allowed)
			(vias allowed)
			(pads allowed)
			(copperpour not_allowed)
			(footprints allowed)
		)
		(placement
			(enabled no)
			(sheetname "")
		)
		(fill
			(thermal_gap 0.5)
			(thermal_bridge_width 0.5)
			(island_removal_mode 0)
		)
		(polygon
			(pts
				(arc
					(start 202.897232 -240.082578)
					(mid 202.893512 -240.091558)
					(end 202.884532 -240.095278)
				)
				(arc
					(start 201.411332 -240.095278)
					(mid 201.402352 -240.091558)
					(end 201.398632 -240.082578)
				)
				(arc
					(start 201.398632 -239.58804)
					(mid 201.402352 -239.57906)
					(end 201.411332 -239.57534)
				)
				(arc
					(start 202.884532 -239.57534)
					(mid 202.893512 -239.57906)
					(end 202.897232 -239.58804)
				)
			)
		)
	)
	(zone
		(layer "In1.Cu")
		(hatch none 0.5)
		(connect_pads
			(clearance 0)
		)
		(min_thickness 0.25)
		(keepout
			(tracks not_allowed)
			(vias allowed)
			(pads allowed)
			(copperpour not_allowed)
			(footprints allowed)
		)
		(placement
			(enabled no)
			(sheetname "")
		)
		(fill
			(thermal_gap 0.5)
			(thermal_bridge_width 0.5)
			(island_removal_mode 0)
		)
		(polygon
			(pts
				(arc
					(start 293.029386 -249.432318)
					(mid 293.025666 -249.441298)
					(end 293.016686 -249.445018)
				)
				(arc
					(start 291.543486 -249.445018)
					(mid 291.534506 -249.441298)
					(end 291.530786 -249.432318)
				)
				(arc
					(start 291.530786 -248.93778)
					(mid 291.534506 -248.9288)
					(end 291.543486 -248.92508)
				)
				(arc
					(start 293.016686 -248.92508)
					(mid 293.025666 -248.9288)
					(end 293.029386 -248.93778)
				)
			)
		)
	)
	(zone
		(layer "In1.Cu")
		(hatch none 0.5)
		(connect_pads
			(clearance 0)
		)
		(min_thickness 0.25)
		(keepout
			(tracks not_allowed)
			(vias allowed)
			(pads allowed)
			(copperpour not_allowed)
			(footprints allowed)
		)
		(placement
			(enabled no)
			(sheetname "")
		)
		(fill
			(thermal_gap 0.5)
			(thermal_bridge_width 0.5)
			(island_removal_mode 0)
		)
		(polygon
			(pts
				(arc
					(start 417.217352 -227.332286)
					(mid 417.213632 -227.341266)
					(end 417.204652 -227.344986)
				)
				(arc
					(start 415.731452 -227.344986)
					(mid 415.722472 -227.341266)
					(end 415.718752 -227.332286)
				)
				(arc
					(start 415.718752 -226.837748)
					(mid 415.722472 -226.828768)
					(end 415.731452 -226.825048)
				)
				(arc
					(start 417.204652 -226.825048)
					(mid 417.213632 -226.828768)
					(end 417.217352 -226.837748)
				)
			)
		)
	)
	(zone
		(layer "In1.Cu")
		(hatch none 0.5)
		(connect_pads
			(clearance 0)
		)
		(min_thickness 0.25)
		(keepout
			(tracks not_allowed)
			(vias allowed)
			(pads allowed)
			(copperpour not_allowed)
			(footprints allowed)
		)
		(placement
			(enabled no)
			(sheetname "")
		)
		(fill
			(thermal_gap 0.5)
			(thermal_bridge_width 0.5)
			(island_removal_mode 0)
		)
		(polygon
			(pts
				(arc
					(start 164.288724 -389.467344)
					(mid 163.907724 -389.467344)
					(end 164.288724 -389.467344)
				)
			)
		)
	)
	(zone
		(layer "In1.Cu")
		(hatch none 0.5)
		(connect_pads
			(clearance 0)
		)
		(min_thickness 0.25)
		(keepout
			(tracks not_allowed)
			(vias allowed)
			(pads allowed)
			(copperpour not_allowed)
			(footprints allowed)
		)
		(placement
			(enabled no)
			(sheetname "")
		)
		(fill
			(thermal_gap 0.5)
			(thermal_bridge_width 0.5)
			(island_removal_mode 0)
		)
		(polygon
			(pts
				(arc
					(start 206.5782 -307.8353)
					(mid 205.9178 -307.8353)
					(end 206.5782 -307.8353)
				)
			)
		)
	)
	(zone
		(layer "In1.Cu")
		(hatch none 0.5)
		(connect_pads
			(clearance 0)
		)
		(min_thickness 0.25)
		(keepout
			(tracks not_allowed)
			(vias allowed)
			(pads allowed)
			(copperpour not_allowed)
			(footprints allowed)
		)
		(placement
			(enabled no)
			(sheetname "")
		)
		(fill
			(thermal_gap 0.5)
			(thermal_bridge_width 0.5)
			(island_removal_mode 0)
		)
		(polygon
			(pts
				(arc
					(start 308.117494 -197.582282)
					(mid 308.113774 -197.591262)
					(end 308.104794 -197.594982)
				)
				(arc
					(start 306.631594 -197.594982)
					(mid 306.622614 -197.591262)
					(end 306.618894 -197.582282)
				)
				(arc
					(start 306.618894 -197.087744)
					(mid 306.622614 -197.078764)
					(end 306.631594 -197.075044)
				)
				(arc
					(start 308.104794 -197.075044)
					(mid 308.113774 -197.078764)
					(end 308.117494 -197.087744)
				)
			)
		)
	)
	(zone
		(layer "In1.Cu")
		(hatch none 0.5)
		(connect_pads
			(clearance 0)
		)
		(min_thickness 0.25)
		(keepout
			(tracks not_allowed)
			(vias allowed)
			(pads allowed)
			(copperpour not_allowed)
			(footprints allowed)
		)
		(placement
			(enabled no)
			(sheetname "")
		)
		(fill
			(thermal_gap 0.5)
			(thermal_bridge_width 0.5)
			(island_removal_mode 0)
		)
		(polygon
			(pts
				(arc
					(start 195.353432 -293.632382)
					(mid 195.349712 -293.641362)
					(end 195.340732 -293.645082)
				)
				(arc
					(start 193.867532 -293.645082)
					(mid 193.858552 -293.641362)
					(end 193.854832 -293.632382)
				)
				(arc
					(start 193.854832 -293.137844)
					(mid 193.858552 -293.128864)
					(end 193.867532 -293.125144)
				)
				(arc
					(start 195.340732 -293.125144)
					(mid 195.349712 -293.128864)
					(end 195.353432 -293.137844)
				)
			)
		)
	)
	(zone
		(layer "In1.Cu")
		(hatch none 0.5)
		(connect_pads
			(clearance 0)
		)
		(min_thickness 0.25)
		(keepout
			(tracks not_allowed)
			(vias allowed)
			(pads allowed)
			(copperpour not_allowed)
			(footprints allowed)
		)
		(placement
			(enabled no)
			(sheetname "")
		)
		(fill
			(thermal_gap 0.5)
			(thermal_bridge_width 0.5)
			(island_removal_mode 0)
		)
		(polygon
			(pts
				(arc
					(start 277.941532 -227.332286)
					(mid 277.937812 -227.341266)
					(end 277.928832 -227.344986)
				)
				(arc
					(start 276.455632 -227.344986)
					(mid 276.446652 -227.341266)
					(end 276.442932 -227.332286)
				)
				(arc
					(start 276.442932 -226.837748)
					(mid 276.446652 -226.828768)
					(end 276.455632 -226.825048)
				)
				(arc
					(start 277.928832 -226.825048)
					(mid 277.937812 -226.828768)
					(end 277.941532 -226.837748)
				)
			)
		)
	)
	(zone
		(layer "In1.Cu")
		(hatch none 0.5)
		(connect_pads
			(clearance 0)
		)
		(min_thickness 0.25)
		(keepout
			(tracks not_allowed)
			(vias allowed)
			(pads allowed)
			(copperpour not_allowed)
			(footprints allowed)
		)
		(placement
			(enabled no)
			(sheetname "")
		)
		(fill
			(thermal_gap 0.5)
			(thermal_bridge_width 0.5)
			(island_removal_mode 0)
		)
		(polygon
			(pts
				(arc
					(start 420.661338 -209.482182)
					(mid 420.657618 -209.491162)
					(end 420.648638 -209.494882)
				)
				(arc
					(start 419.175438 -209.494882)
					(mid 419.166458 -209.491162)
					(end 419.162738 -209.482182)
				)
				(arc
					(start 419.162738 -208.987644)
					(mid 419.166458 -208.978664)
					(end 419.175438 -208.974944)
				)
				(arc
					(start 420.648638 -208.974944)
					(mid 420.657618 -208.978664)
					(end 420.661338 -208.987644)
				)
			)
		)
	)
	(zone
		(layer "In1.Cu")
		(hatch none 0.5)
		(connect_pads
			(clearance 0)
		)
		(min_thickness 0.25)
		(keepout
			(tracks not_allowed)
			(vias allowed)
			(pads allowed)
			(copperpour not_allowed)
			(footprints allowed)
		)
		(placement
			(enabled no)
			(sheetname "")
		)
		(fill
			(thermal_gap 0.5)
			(thermal_bridge_width 0.5)
			(island_removal_mode 0)
		)
		(polygon
			(pts
				(arc
					(start 18.357342 -274.932394)
					(mid 18.353622 -274.941374)
					(end 18.344642 -274.945094)
				)
				(arc
					(start 16.871442 -274.945094)
					(mid 16.862462 -274.941374)
					(end 16.858742 -274.932394)
				)
				(arc
					(start 16.858742 -274.437856)
					(mid 16.862462 -274.428876)
					(end 16.871442 -274.425156)
				)
				(arc
					(start 18.344642 -274.425156)
					(mid 18.353622 -274.428876)
					(end 18.357342 -274.437856)
				)
			)
		)
	)
	(zone
		(layer "In1.Cu")
		(hatch none 0.5)
		(connect_pads
			(clearance 0)
		)
		(min_thickness 0.25)
		(keepout
			(tracks not_allowed)
			(vias allowed)
			(pads allowed)
			(copperpour not_allowed)
			(footprints allowed)
		)
		(placement
			(enabled no)
			(sheetname "")
		)
		(fill
			(thermal_gap 0.5)
			(thermal_bridge_width 0.5)
			(island_removal_mode 0)
		)
		(polygon
			(pts
				(arc
					(start 413.117284 -215.432132)
					(mid 413.113564 -215.441112)
					(end 413.104584 -215.444832)
				)
				(arc
					(start 411.631384 -215.444832)
					(mid 411.622404 -215.441112)
					(end 411.618684 -215.432132)
				)
				(arc
					(start 411.618684 -214.937594)
					(mid 411.622404 -214.928614)
					(end 411.631384 -214.924894)
				)
				(arc
					(start 413.104584 -214.924894)
					(mid 413.113564 -214.928614)
					(end 413.117284 -214.937594)
				)
			)
		)
	)
	(zone
		(layer "In1.Cu")
		(hatch none 0.5)
		(connect_pads
			(clearance 0)
		)
		(min_thickness 0.25)
		(keepout
			(tracks not_allowed)
			(vias allowed)
			(pads allowed)
			(copperpour not_allowed)
			(footprints allowed)
		)
		(placement
			(enabled no)
			(sheetname "")
		)
		(fill
			(thermal_gap 0.5)
			(thermal_bridge_width 0.5)
			(island_removal_mode 0)
		)
		(polygon
			(pts
				(arc
					(start 300.57344 -295.33215)
					(mid 300.56972 -295.34113)
					(end 300.56074 -295.34485)
				)
				(arc
					(start 299.08754 -295.34485)
					(mid 299.07856 -295.34113)
					(end 299.07484 -295.33215)
				)
				(arc
					(start 299.07484 -294.837612)
					(mid 299.07856 -294.828632)
					(end 299.08754 -294.824912)
				)
				(arc
					(start 300.56074 -294.824912)
					(mid 300.56972 -294.828632)
					(end 300.57344 -294.837612)
				)
			)
		)
	)
	(zone
		(layer "In1.Cu")
		(hatch none 0.5)
		(connect_pads
			(clearance 0)
		)
		(min_thickness 0.25)
		(keepout
			(tracks not_allowed)
			(vias allowed)
			(pads allowed)
			(copperpour not_allowed)
			(footprints allowed)
		)
		(placement
			(enabled no)
			(sheetname "")
		)
		(fill
			(thermal_gap 0.5)
			(thermal_bridge_width 0.5)
			(island_removal_mode 0)
		)
		(polygon
			(pts
				(arc
					(start 447.393568 -223.932242)
					(mid 447.389848 -223.941222)
					(end 447.380868 -223.944942)
				)
				(arc
					(start 445.907668 -223.944942)
					(mid 445.898688 -223.941222)
					(end 445.894968 -223.932242)
				)
				(arc
					(start 445.894968 -223.437704)
					(mid 445.898688 -223.428724)
					(end 445.907668 -223.425004)
				)
				(arc
					(start 447.380868 -223.425004)
					(mid 447.389848 -223.428724)
					(end 447.393568 -223.437704)
				)
			)
		)
	)
	(zone
		(layer "In1.Cu")
		(hatch none 0.5)
		(connect_pads
			(clearance 0)
		)
		(min_thickness 0.25)
		(keepout
			(tracks not_allowed)
			(vias allowed)
			(pads allowed)
			(copperpour not_allowed)
			(footprints allowed)
		)
		(placement
			(enabled no)
			(sheetname "")
		)
		(fill
			(thermal_gap 0.5)
			(thermal_bridge_width 0.5)
			(island_removal_mode 0)
		)
		(polygon
			(pts
				(arc
					(start 293.029386 -247.732296)
					(mid 293.025666 -247.741276)
					(end 293.016686 -247.744996)
				)
				(arc
					(start 291.543486 -247.744996)
					(mid 291.534506 -247.741276)
					(end 291.530786 -247.732296)
				)
				(arc
					(start 291.530786 -247.237758)
					(mid 291.534506 -247.228778)
					(end 291.543486 -247.225058)
				)
				(arc
					(start 293.016686 -247.225058)
					(mid 293.025666 -247.228778)
					(end 293.029386 -247.237758)
				)
			)
		)
	)
	(zone
		(layer "In1.Cu")
		(hatch none 0.5)
		(connect_pads
			(clearance 0)
		)
		(min_thickness 0.25)
		(keepout
			(tracks not_allowed)
			(vias allowed)
			(pads allowed)
			(copperpour not_allowed)
			(footprints allowed)
		)
		(placement
			(enabled no)
			(sheetname "")
		)
		(fill
			(thermal_gap 0.5)
			(thermal_bridge_width 0.5)
			(island_removal_mode 0)
		)
		(polygon
			(pts
				(arc
					(start 417.217352 -216.28227)
					(mid 417.213632 -216.29125)
					(end 417.204652 -216.29497)
				)
				(arc
					(start 415.731452 -216.29497)
					(mid 415.722472 -216.29125)
					(end 415.718752 -216.28227)
				)
				(arc
					(start 415.718752 -215.787732)
					(mid 415.722472 -215.778752)
					(end 415.731452 -215.775032)
				)
				(arc
					(start 417.204652 -215.775032)
					(mid 417.213632 -215.778752)
					(end 417.217352 -215.787732)
				)
			)
		)
	)
	(zone
		(layer "In1.Cu")
		(hatch none 0.5)
		(connect_pads
			(clearance 0)
		)
		(min_thickness 0.25)
		(keepout
			(tracks not_allowed)
			(vias allowed)
			(pads allowed)
			(copperpour not_allowed)
			(footprints allowed)
		)
		(placement
			(enabled no)
			(sheetname "")
		)
		(fill
			(thermal_gap 0.5)
			(thermal_bridge_width 0.5)
			(island_removal_mode 0)
		)
		(polygon
			(pts
				(arc
					(start 405.018748 -391.822686)
					(mid 405.145748 -391.949686)
					(end 405.272748 -391.822686)
				)
				(arc
					(start 405.272748 -391.746486)
					(mid 405.145748 -391.619486)
					(end 405.018748 -391.746486)
				)
			)
		)
	)
	(zone
		(layer "In1.Cu")
		(hatch none 0.5)
		(connect_pads
			(clearance 0)
		)
		(min_thickness 0.25)
		(keepout
			(tracks not_allowed)
			(vias allowed)
			(pads allowed)
			(copperpour not_allowed)
			(footprints allowed)
		)
		(placement
			(enabled no)
			(sheetname "")
		)
		(fill
			(thermal_gap 0.5)
			(thermal_bridge_width 0.5)
			(island_removal_mode 0)
		)
		(polygon
			(pts
				(arc
					(start 270.397478 -227.332286)
					(mid 270.393758 -227.341266)
					(end 270.384778 -227.344986)
				)
				(arc
					(start 268.911578 -227.344986)
					(mid 268.902598 -227.341266)
					(end 268.898878 -227.332286)
				)
				(arc
					(start 268.898878 -226.837748)
					(mid 268.902598 -226.828768)
					(end 268.911578 -226.825048)
				)
				(arc
					(start 270.384778 -226.825048)
					(mid 270.393758 -226.828768)
					(end 270.397478 -226.837748)
				)
			)
		)
	)
	(zone
		(layer "In1.Cu")
		(hatch none 0.5)
		(connect_pads
			(clearance 0)
		)
		(min_thickness 0.25)
		(keepout
			(tracks not_allowed)
			(vias allowed)
			(pads allowed)
			(copperpour not_allowed)
			(footprints allowed)
		)
		(placement
			(enabled no)
			(sheetname "")
		)
		(fill
			(thermal_gap 0.5)
			(thermal_bridge_width 0.5)
			(island_removal_mode 0)
		)
		(polygon
			(pts
				(arc
					(start 56.077358 -268.982444)
					(mid 56.073638 -268.991424)
					(end 56.064658 -268.995144)
				)
				(arc
					(start 54.591458 -268.995144)
					(mid 54.582478 -268.991424)
					(end 54.578758 -268.982444)
				)
				(arc
					(start 54.578758 -268.487906)
					(mid 54.582478 -268.478926)
					(end 54.591458 -268.475206)
				)
				(arc
					(start 56.064658 -268.475206)
					(mid 56.073638 -268.478926)
					(end 56.077358 -268.487906)
				)
			)
		)
	)
	(zone
		(layer "In1.Cu")
		(hatch none 0.5)
		(connect_pads
			(clearance 0)
		)
		(min_thickness 0.25)
		(keepout
			(tracks not_allowed)
			(vias allowed)
			(pads allowed)
			(copperpour not_allowed)
			(footprints allowed)
		)
		(placement
			(enabled no)
			(sheetname "")
		)
		(fill
			(thermal_gap 0.5)
			(thermal_bridge_width 0.5)
			(island_removal_mode 0)
		)
		(polygon
			(pts
				(arc
					(start 206.5782 -303.585372)
					(mid 205.9178 -303.585372)
					(end 206.5782 -303.585372)
				)
			)
		)
	)
	(zone
		(layer "In1.Cu")
		(hatch none 0.5)
		(connect_pads
			(clearance 0)
		)
		(min_thickness 0.25)
		(keepout
			(tracks not_allowed)
			(vias allowed)
			(pads allowed)
			(copperpour not_allowed)
			(footprints allowed)
		)
		(placement
			(enabled no)
			(sheetname "")
		)
		(fill
			(thermal_gap 0.5)
			(thermal_bridge_width 0.5)
			(island_removal_mode 0)
		)
		(polygon
			(pts
				(arc
					(start 33.445196 -304.682398)
					(mid 33.441476 -304.691378)
					(end 33.432496 -304.695098)
				)
				(arc
					(start 31.959296 -304.695098)
					(mid 31.950316 -304.691378)
					(end 31.946596 -304.682398)
				)
				(arc
					(start 31.946596 -304.18786)
					(mid 31.950316 -304.17888)
					(end 31.959296 -304.17516)
				)
				(arc
					(start 33.432496 -304.17516)
					(mid 33.441476 -304.17888)
					(end 33.445196 -304.18786)
				)
			)
		)
	)
	(zone
		(layer "In1.Cu")
		(hatch none 0.5)
		(connect_pads
			(clearance 0)
		)
		(min_thickness 0.25)
		(keepout
			(tracks not_allowed)
			(vias allowed)
			(pads allowed)
			(copperpour not_allowed)
			(footprints allowed)
		)
		(placement
			(enabled no)
			(sheetname "")
		)
		(fill
			(thermal_gap 0.5)
			(thermal_bridge_width 0.5)
			(island_removal_mode 0)
		)
		(polygon
			(pts
				(arc
					(start 270.397478 -249.432318)
					(mid 270.393758 -249.441298)
					(end 270.384778 -249.445018)
				)
				(arc
					(start 268.911578 -249.445018)
					(mid 268.902598 -249.441298)
					(end 268.898878 -249.432318)
				)
				(arc
					(start 268.898878 -248.93778)
					(mid 268.902598 -248.9288)
					(end 268.911578 -248.92508)
				)
				(arc
					(start 270.384778 -248.92508)
					(mid 270.393758 -248.9288)
					(end 270.397478 -248.93778)
				)
			)
		)
	)
	(zone
		(layer "In1.Cu")
		(hatch none 0.5)
		(connect_pads
			(clearance 0)
		)
		(min_thickness 0.25)
		(keepout
			(tracks not_allowed)
			(vias allowed)
			(pads allowed)
			(copperpour not_allowed)
			(footprints allowed)
		)
		(placement
			(enabled no)
			(sheetname "")
		)
		(fill
			(thermal_gap 0.5)
			(thermal_bridge_width 0.5)
			(island_removal_mode 0)
		)
		(polygon
			(pts
				(arc
					(start 281.385264 -310.632094)
					(mid 281.381544 -310.641074)
					(end 281.372564 -310.644794)
				)
				(arc
					(start 279.899364 -310.644794)
					(mid 279.890384 -310.641074)
					(end 279.886664 -310.632094)
				)
				(arc
					(start 279.886664 -310.137556)
					(mid 279.890384 -310.128576)
					(end 279.899364 -310.124856)
				)
				(arc
					(start 281.372564 -310.124856)
					(mid 281.381544 -310.128576)
					(end 281.385264 -310.137556)
				)
			)
		)
	)
	(zone
		(layer "In1.Cu")
		(hatch none 0.5)
		(connect_pads
			(clearance 0)
		)
		(min_thickness 0.25)
		(keepout
			(tracks not_allowed)
			(vias allowed)
			(pads allowed)
			(copperpour not_allowed)
			(footprints allowed)
		)
		(placement
			(enabled no)
			(sheetname "")
		)
		(fill
			(thermal_gap 0.5)
			(thermal_bridge_width 0.5)
			(island_removal_mode 0)
		)
		(polygon
			(pts
				(arc
					(start 33.445196 -318.282574)
					(mid 33.441476 -318.291554)
					(end 33.432496 -318.295274)
				)
				(arc
					(start 31.959296 -318.295274)
					(mid 31.950316 -318.291554)
					(end 31.946596 -318.282574)
				)
				(arc
					(start 31.946596 -317.788036)
					(mid 31.950316 -317.779056)
					(end 31.959296 -317.775336)
				)
				(arc
					(start 33.432496 -317.775336)
					(mid 33.441476 -317.779056)
					(end 33.445196 -317.788036)
				)
			)
		)
	)
	(zone
		(layer "In1.Cu")
		(hatch none 0.5)
		(connect_pads
			(clearance 0)
		)
		(min_thickness 0.25)
		(keepout
			(tracks not_allowed)
			(vias allowed)
			(pads allowed)
			(copperpour not_allowed)
			(footprints allowed)
		)
		(placement
			(enabled no)
			(sheetname "")
		)
		(fill
			(thermal_gap 0.5)
			(thermal_bridge_width 0.5)
			(island_removal_mode 0)
		)
		(polygon
			(pts
				(arc
					(start 447.393568 -306.382166)
					(mid 447.389848 -306.391146)
					(end 447.380868 -306.394866)
				)
				(arc
					(start 445.907668 -306.394866)
					(mid 445.898688 -306.391146)
					(end 445.894968 -306.382166)
				)
				(arc
					(start 445.894968 -305.887628)
					(mid 445.898688 -305.878648)
					(end 445.907668 -305.874928)
				)
				(arc
					(start 447.380868 -305.874928)
					(mid 447.389848 -305.878648)
					(end 447.393568 -305.887628)
				)
			)
		)
	)
	(zone
		(layer "In1.Cu")
		(hatch none 0.5)
		(connect_pads
			(clearance 0)
		)
		(min_thickness 0.25)
		(keepout
			(tracks not_allowed)
			(vias allowed)
			(pads allowed)
			(copperpour not_allowed)
			(footprints allowed)
		)
		(placement
			(enabled no)
			(sheetname "")
		)
		(fill
			(thermal_gap 0.5)
			(thermal_bridge_width 0.5)
			(island_removal_mode 0)
		)
		(polygon
			(pts
				(arc
					(start 402.618702 -399.701258)
					(mid 402.745702 -399.828258)
					(end 402.872702 -399.701258)
				)
				(arc
					(start 402.872702 -399.625058)
					(mid 402.745702 -399.498058)
					(end 402.618702 -399.625058)
				)
			)
		)
	)
	(zone
		(layer "In1.Cu")
		(hatch none 0.5)
		(connect_pads
			(clearance 0)
		)
		(min_thickness 0.25)
		(keepout
			(tracks not_allowed)
			(vias allowed)
			(pads allowed)
			(copperpour not_allowed)
			(footprints allowed)
		)
		(placement
			(enabled no)
			(sheetname "")
		)
		(fill
			(thermal_gap 0.5)
			(thermal_bridge_width 0.5)
			(island_removal_mode 0)
		)
		(polygon
			(pts
				(arc
					(start 206.5782 -227.085398)
					(mid 205.9178 -227.085398)
					(end 206.5782 -227.085398)
				)
			)
		)
	)
	(zone
		(layer "In1.Cu")
		(hatch none 0.5)
		(connect_pads
			(clearance 0)
		)
		(min_thickness 0.25)
		(keepout
			(tracks not_allowed)
			(vias allowed)
			(pads allowed)
			(copperpour not_allowed)
			(footprints allowed)
		)
		(placement
			(enabled no)
			(sheetname "")
		)
		(fill
			(thermal_gap 0.5)
			(thermal_bridge_width 0.5)
			(island_removal_mode 0)
		)
		(polygon
			(pts
				(arc
					(start 311.6961 -384.288284)
					(mid 311.716024 -384.29752)
					(end 311.737756 -384.30073)
				)
				(arc
					(start 311.93232 -384.30073)
					(mid 311.986202 -384.278412)
					(end 312.00852 -384.22453)
				)
				(arc
					(start 312.00852 -383.53873)
					(mid 311.986202 -383.484848)
					(end 311.93232 -383.46253)
				)
				(arc
					(start 311.737756 -383.46253)
					(mid 311.716012 -383.465698)
					(end 311.6961 -383.474976)
				)
				(arc
					(start 311.399936 -383.667762)
					(mid 311.358252 -383.679984)
					(end 311.316624 -383.667508)
				)
				(arc
					(start 311.023 -383.474976)
					(mid 311.003076 -383.46574)
					(end 310.981344 -383.46253)
				)
				(arc
					(start 310.78678 -383.46253)
					(mid 310.732898 -383.484848)
					(end 310.71058 -383.53873)
				)
				(arc
					(start 310.71058 -384.22453)
					(mid 310.732898 -384.278412)
					(end 310.78678 -384.30073)
				)
				(arc
					(start 310.982614 -384.30073)
					(mid 311.004358 -384.297562)
					(end 311.02427 -384.288284)
				)
				(arc
					(start 311.317894 -384.095752)
					(mid 311.35955 -384.08335)
					(end 311.401206 -384.095752)
				)
			)
		)
	)
	(zone
		(layer "In1.Cu")
		(hatch none 0.5)
		(connect_pads
			(clearance 0)
		)
		(min_thickness 0.25)
		(keepout
			(tracks not_allowed)
			(vias allowed)
			(pads allowed)
			(copperpour not_allowed)
			(footprints allowed)
		)
		(placement
			(enabled no)
			(sheetname "")
		)
		(fill
			(thermal_gap 0.5)
			(thermal_bridge_width 0.5)
			(island_removal_mode 0)
		)
		(polygon
			(pts
				(arc
					(start 121.76125 -388.774432)
					(mid 121.38025 -388.774432)
					(end 121.76125 -388.774432)
				)
			)
		)
	)
	(zone
		(layer "In1.Cu")
		(hatch none 0.5)
		(connect_pads
			(clearance 0)
		)
		(min_thickness 0.25)
		(keepout
			(tracks not_allowed)
			(vias allowed)
			(pads allowed)
			(copperpour not_allowed)
			(footprints allowed)
		)
		(placement
			(enabled no)
			(sheetname "")
		)
		(fill
			(thermal_gap 0.5)
			(thermal_bridge_width 0.5)
			(island_removal_mode 0)
		)
		(polygon
			(pts
				(arc
					(start 176.821338 -287.682432)
					(mid 176.817618 -287.691412)
					(end 176.808638 -287.695132)
				)
				(arc
					(start 175.335438 -287.695132)
					(mid 175.326458 -287.691412)
					(end 175.322738 -287.682432)
				)
				(arc
					(start 175.322738 -287.187894)
					(mid 175.326458 -287.178914)
					(end 175.335438 -287.175194)
				)
				(arc
					(start 176.808638 -287.175194)
					(mid 176.817618 -287.178914)
					(end 176.821338 -287.187894)
				)
			)
		)
	)
	(zone
		(layer "In1.Cu")
		(hatch none 0.5)
		(connect_pads
			(clearance 0)
		)
		(min_thickness 0.25)
		(keepout
			(tracks not_allowed)
			(vias allowed)
			(pads allowed)
			(copperpour not_allowed)
			(footprints allowed)
		)
		(placement
			(enabled no)
			(sheetname "")
		)
		(fill
			(thermal_gap 0.5)
			(thermal_bridge_width 0.5)
			(island_removal_mode 0)
		)
		(polygon
			(pts
				(arc
					(start 131.983226 -33.607756)
					(mid 131.960908 -33.661638)
					(end 131.907026 -33.683956)
				)
				(arc
					(start 131.481576 -33.683956)
					(mid 131.427694 -33.661638)
					(end 131.405376 -33.607756)
				)
				(arc
					(start 131.405376 -32.439356)
					(mid 131.427694 -32.385474)
					(end 131.481576 -32.363156)
				)
				(arc
					(start 131.907026 -32.363156)
					(mid 131.960908 -32.385474)
					(end 131.983226 -32.439356)
				)
			)
		)
	)
	(zone
		(layer "In1.Cu")
		(hatch none 0.5)
		(connect_pads
			(clearance 0)
		)
		(min_thickness 0.25)
		(keepout
			(tracks not_allowed)
			(vias allowed)
			(pads allowed)
			(copperpour not_allowed)
			(footprints allowed)
		)
		(placement
			(enabled no)
			(sheetname "")
		)
		(fill
			(thermal_gap 0.5)
			(thermal_bridge_width 0.5)
			(island_removal_mode 0)
		)
		(polygon
			(pts
				(arc
					(start 206.5782 -289.135312)
					(mid 205.9178 -289.135312)
					(end 206.5782 -289.135312)
				)
			)
		)
	)
	(zone
		(layer "In1.Cu")
		(hatch none 0.5)
		(connect_pads
			(clearance 0)
		)
		(min_thickness 0.25)
		(keepout
			(tracks not_allowed)
			(vias allowed)
			(pads allowed)
			(copperpour not_allowed)
			(footprints allowed)
		)
		(placement
			(enabled no)
			(sheetname "")
		)
		(fill
			(thermal_gap 0.5)
			(thermal_bridge_width 0.5)
			(island_removal_mode 0)
		)
		(polygon
			(pts
				(arc
					(start 439.849514 -220.532198)
					(mid 439.845794 -220.541178)
					(end 439.836814 -220.544898)
				)
				(arc
					(start 438.363614 -220.544898)
					(mid 438.354634 -220.541178)
					(end 438.350914 -220.532198)
				)
				(arc
					(start 438.350914 -220.03766)
					(mid 438.354634 -220.02868)
					(end 438.363614 -220.02496)
				)
				(arc
					(start 439.836814 -220.02496)
					(mid 439.845794 -220.02868)
					(end 439.849514 -220.03766)
				)
			)
		)
	)
	(zone
		(layer "In1.Cu")
		(hatch none 0.5)
		(connect_pads
			(clearance 0)
		)
		(min_thickness 0.25)
		(keepout
			(tracks not_allowed)
			(vias allowed)
			(pads allowed)
			(copperpour not_allowed)
			(footprints allowed)
		)
		(placement
			(enabled no)
			(sheetname "")
		)
		(fill
			(thermal_gap 0.5)
			(thermal_bridge_width 0.5)
			(island_removal_mode 0)
		)
		(polygon
			(pts
				(arc
					(start 313.3979 -381.824484)
					(mid 313.417824 -381.83372)
					(end 313.439556 -381.83693)
				)
				(arc
					(start 313.63412 -381.83693)
					(mid 313.688002 -381.814612)
					(end 313.71032 -381.76073)
				)
				(arc
					(start 313.71032 -381.07493)
					(mid 313.688002 -381.021048)
					(end 313.63412 -380.99873)
				)
				(arc
					(start 313.439556 -380.99873)
					(mid 313.417812 -381.001898)
					(end 313.3979 -381.011176)
				)
				(arc
					(start 313.101736 -381.203962)
					(mid 313.060052 -381.216184)
					(end 313.018424 -381.203708)
				)
				(arc
					(start 312.7248 -381.011176)
					(mid 312.704876 -381.00194)
					(end 312.683144 -380.99873)
				)
				(arc
					(start 312.48858 -380.99873)
					(mid 312.434698 -381.021048)
					(end 312.41238 -381.07493)
				)
				(arc
					(start 312.41238 -381.76073)
					(mid 312.434698 -381.814612)
					(end 312.48858 -381.83693)
				)
				(arc
					(start 312.684414 -381.83693)
					(mid 312.706158 -381.833762)
					(end 312.72607 -381.824484)
				)
				(arc
					(start 313.019694 -381.631952)
					(mid 313.06135 -381.61955)
					(end 313.103006 -381.631952)
				)
			)
		)
	)
	(zone
		(layer "In1.Cu")
		(hatch none 0.5)
		(connect_pads
			(clearance 0)
		)
		(min_thickness 0.25)
		(keepout
			(tracks not_allowed)
			(vias allowed)
			(pads allowed)
			(copperpour not_allowed)
			(footprints allowed)
		)
		(placement
			(enabled no)
			(sheetname "")
		)
		(fill
			(thermal_gap 0.5)
			(thermal_bridge_width 0.5)
			(island_removal_mode 0)
		)
		(polygon
			(pts
				(arc
					(start 122.961146 -388.774432)
					(mid 122.580146 -388.774432)
					(end 122.961146 -388.774432)
				)
			)
		)
	)
	(zone
		(layer "In1.Cu")
		(hatch none 0.5)
		(connect_pads
			(clearance 0)
		)
		(min_thickness 0.25)
		(keepout
			(tracks not_allowed)
			(vias allowed)
			(pads allowed)
			(copperpour not_allowed)
			(footprints allowed)
		)
		(placement
			(enabled no)
			(sheetname "")
		)
		(fill
			(thermal_gap 0.5)
			(thermal_bridge_width 0.5)
			(island_removal_mode 0)
		)
		(polygon
			(pts
				(arc
					(start 52.633372 -295.332404)
					(mid 52.629652 -295.341384)
					(end 52.620672 -295.345104)
				)
				(arc
					(start 51.147472 -295.345104)
					(mid 51.138492 -295.341384)
					(end 51.134772 -295.332404)
				)
				(arc
					(start 51.134772 -294.837866)
					(mid 51.138492 -294.828886)
					(end 51.147472 -294.825166)
				)
				(arc
					(start 52.620672 -294.825166)
					(mid 52.629652 -294.828886)
					(end 52.633372 -294.837866)
				)
			)
		)
	)
	(zone
		(layer "In1.Cu")
		(hatch none 0.5)
		(connect_pads
			(clearance 0)
		)
		(min_thickness 0.25)
		(keepout
			(tracks not_allowed)
			(vias allowed)
			(pads allowed)
			(copperpour not_allowed)
			(footprints allowed)
		)
		(placement
			(enabled no)
			(sheetname "")
		)
		(fill
			(thermal_gap 0.5)
			(thermal_bridge_width 0.5)
			(island_removal_mode 0)
		)
		(polygon
			(pts
				(arc
					(start 285.485332 -270.682212)
					(mid 285.481612 -270.691192)
					(end 285.472632 -270.694912)
				)
				(arc
					(start 283.999432 -270.694912)
					(mid 283.990452 -270.691192)
					(end 283.986732 -270.682212)
				)
				(arc
					(start 283.986732 -270.187674)
					(mid 283.990452 -270.178694)
					(end 283.999432 -270.174974)
				)
				(arc
					(start 285.472632 -270.174974)
					(mid 285.481612 -270.178694)
					(end 285.485332 -270.187674)
				)
			)
		)
	)
	(zone
		(layer "In1.Cu")
		(hatch none 0.5)
		(connect_pads
			(clearance 0)
		)
		(min_thickness 0.25)
		(keepout
			(tracks not_allowed)
			(vias allowed)
			(pads allowed)
			(copperpour not_allowed)
			(footprints allowed)
		)
		(placement
			(enabled no)
			(sheetname "")
		)
		(fill
			(thermal_gap 0.5)
			(thermal_bridge_width 0.5)
			(island_removal_mode 0)
		)
		(polygon
			(pts
				(arc
					(start 308.117494 -275.782278)
					(mid 308.113774 -275.791258)
					(end 308.104794 -275.794978)
				)
				(arc
					(start 306.631594 -275.794978)
					(mid 306.622614 -275.791258)
					(end 306.618894 -275.782278)
				)
				(arc
					(start 306.618894 -275.28774)
					(mid 306.622614 -275.27876)
					(end 306.631594 -275.27504)
				)
				(arc
					(start 308.104794 -275.27504)
					(mid 308.113774 -275.27876)
					(end 308.117494 -275.28774)
				)
			)
		)
	)
	(zone
		(layer "In1.Cu")
		(hatch none 0.5)
		(connect_pads
			(clearance 0)
		)
		(min_thickness 0.25)
		(keepout
			(tracks not_allowed)
			(vias allowed)
			(pads allowed)
			(copperpour not_allowed)
			(footprints allowed)
		)
		(placement
			(enabled no)
			(sheetname "")
		)
		(fill
			(thermal_gap 0.5)
			(thermal_bridge_width 0.5)
			(island_removal_mode 0)
		)
		(polygon
			(pts
				(arc
					(start 117.6909 -383.440686)
					(mid 117.8179 -383.567686)
					(end 117.9449 -383.440686)
				)
				(arc
					(start 117.9449 -383.364486)
					(mid 117.8179 -383.237486)
					(end 117.6909 -383.364486)
				)
			)
		)
	)
	(zone
		(layer "In1.Cu")
		(hatch none 0.5)
		(connect_pads
			(clearance 0)
		)
		(min_thickness 0.25)
		(keepout
			(tracks not_allowed)
			(vias allowed)
			(pads allowed)
			(copperpour not_allowed)
			(footprints allowed)
		)
		(placement
			(enabled no)
			(sheetname "")
		)
		(fill
			(thermal_gap 0.5)
			(thermal_bridge_width 0.5)
			(island_removal_mode 0)
		)
		(polygon
			(pts
				(arc
					(start 417.217352 -268.132306)
					(mid 417.213632 -268.141286)
					(end 417.204652 -268.145006)
				)
				(arc
					(start 415.731452 -268.145006)
					(mid 415.722472 -268.141286)
					(end 415.718752 -268.132306)
				)
				(arc
					(start 415.718752 -267.637768)
					(mid 415.722472 -267.628788)
					(end 415.731452 -267.625068)
				)
				(arc
					(start 417.204652 -267.625068)
					(mid 417.213632 -267.628788)
					(end 417.217352 -267.637768)
				)
			)
		)
	)
	(zone
		(layer "In1.Cu")
		(hatch none 0.5)
		(connect_pads
			(clearance 0)
		)
		(min_thickness 0.25)
		(keepout
			(tracks not_allowed)
			(vias allowed)
			(pads allowed)
			(copperpour not_allowed)
			(footprints allowed)
		)
		(placement
			(enabled no)
			(sheetname "")
		)
		(fill
			(thermal_gap 0.5)
			(thermal_bridge_width 0.5)
			(island_removal_mode 0)
		)
		(polygon
			(pts
				(arc
					(start 424.761406 -281.732228)
					(mid 424.757686 -281.741208)
					(end 424.748706 -281.744928)
				)
				(arc
					(start 423.275506 -281.744928)
					(mid 423.266526 -281.741208)
					(end 423.262806 -281.732228)
				)
				(arc
					(start 423.262806 -281.23769)
					(mid 423.266526 -281.22871)
					(end 423.275506 -281.22499)
				)
				(arc
					(start 424.748706 -281.22499)
					(mid 424.757686 -281.22871)
					(end 424.761406 -281.23769)
				)
			)
		)
	)
	(zone
		(layer "In1.Cu")
		(hatch none 0.5)
		(connect_pads
			(clearance 0)
		)
		(min_thickness 0.25)
		(keepout
			(tracks not_allowed)
			(vias allowed)
			(pads allowed)
			(copperpour not_allowed)
			(footprints allowed)
		)
		(placement
			(enabled no)
			(sheetname "")
		)
		(fill
			(thermal_gap 0.5)
			(thermal_bridge_width 0.5)
			(island_removal_mode 0)
		)
		(polygon
			(pts
				(arc
					(start 40.98925 -267.282422)
					(mid 40.98553 -267.291402)
					(end 40.97655 -267.295122)
				)
				(arc
					(start 39.50335 -267.295122)
					(mid 39.49437 -267.291402)
					(end 39.49065 -267.282422)
				)
				(arc
					(start 39.49065 -266.787884)
					(mid 39.49437 -266.778904)
					(end 39.50335 -266.775184)
				)
				(arc
					(start 40.97655 -266.775184)
					(mid 40.98553 -266.778904)
					(end 40.98925 -266.787884)
				)
			)
		)
	)
	(zone
		(layer "In1.Cu")
		(hatch none 0.5)
		(connect_pads
			(clearance 0)
		)
		(min_thickness 0.25)
		(keepout
			(tracks not_allowed)
			(vias allowed)
			(pads allowed)
			(copperpour not_allowed)
			(footprints allowed)
		)
		(placement
			(enabled no)
			(sheetname "")
		)
		(fill
			(thermal_gap 0.5)
			(thermal_bridge_width 0.5)
			(island_removal_mode 0)
		)
		(polygon
			(pts
				(arc
					(start 443.2935 -226.482148)
					(mid 443.28978 -226.491128)
					(end 443.2808 -226.494848)
				)
				(arc
					(start 441.8076 -226.494848)
					(mid 441.79862 -226.491128)
					(end 441.7949 -226.482148)
				)
				(arc
					(start 441.7949 -225.98761)
					(mid 441.79862 -225.97863)
					(end 441.8076 -225.97491)
				)
				(arc
					(start 443.2808 -225.97491)
					(mid 443.28978 -225.97863)
					(end 443.2935 -225.98761)
				)
			)
		)
	)
	(zone
		(layer "In1.Cu")
		(hatch none 0.5)
		(connect_pads
			(clearance 0)
		)
		(min_thickness 0.25)
		(keepout
			(tracks not_allowed)
			(vias allowed)
			(pads allowed)
			(copperpour not_allowed)
			(footprints allowed)
		)
		(placement
			(enabled no)
			(sheetname "")
		)
		(fill
			(thermal_gap 0.5)
			(thermal_bridge_width 0.5)
			(island_removal_mode 0)
		)
		(polygon
			(pts
				(arc
					(start 184.365392 -249.432572)
					(mid 184.361672 -249.441552)
					(end 184.352692 -249.445272)
				)
				(arc
					(start 182.879492 -249.445272)
					(mid 182.870512 -249.441552)
					(end 182.866792 -249.432572)
				)
				(arc
					(start 182.866792 -248.938034)
					(mid 182.870512 -248.929054)
					(end 182.879492 -248.925334)
				)
				(arc
					(start 184.352692 -248.925334)
					(mid 184.361672 -248.929054)
					(end 184.365392 -248.938034)
				)
			)
		)
	)
	(zone
		(layer "In1.Cu")
		(hatch none 0.5)
		(connect_pads
			(clearance 0)
		)
		(min_thickness 0.25)
		(keepout
			(tracks not_allowed)
			(vias allowed)
			(pads allowed)
			(copperpour not_allowed)
			(footprints allowed)
		)
		(placement
			(enabled no)
			(sheetname "")
		)
		(fill
			(thermal_gap 0.5)
			(thermal_bridge_width 0.5)
			(island_removal_mode 0)
		)
		(polygon
			(pts
				(arc
					(start 454.937368 -298.732194)
					(mid 454.933648 -298.741174)
					(end 454.924668 -298.744894)
				)
				(arc
					(start 453.451468 -298.744894)
					(mid 453.442488 -298.741174)
					(end 453.438768 -298.732194)
				)
				(arc
					(start 453.438768 -298.237656)
					(mid 453.442488 -298.228676)
					(end 453.451468 -298.224956)
				)
				(arc
					(start 454.924668 -298.224956)
					(mid 454.933648 -298.228676)
					(end 454.937368 -298.237656)
				)
			)
		)
	)
	(zone
		(layer "In1.Cu")
		(hatch none 0.5)
		(connect_pads
			(clearance 0)
		)
		(min_thickness 0.25)
		(keepout
			(tracks not_allowed)
			(vias allowed)
			(pads allowed)
			(copperpour not_allowed)
			(footprints allowed)
		)
		(placement
			(enabled no)
			(sheetname "")
		)
		(fill
			(thermal_gap 0.5)
			(thermal_bridge_width 0.5)
			(island_removal_mode 0)
		)
		(polygon
			(pts
				(arc
					(start 176.821338 -227.33254)
					(mid 176.817618 -227.34152)
					(end 176.808638 -227.34524)
				)
				(arc
					(start 175.335438 -227.34524)
					(mid 175.326458 -227.34152)
					(end 175.322738 -227.33254)
				)
				(arc
					(start 175.322738 -226.838002)
					(mid 175.326458 -226.829022)
					(end 175.335438 -226.825302)
				)
				(arc
					(start 176.808638 -226.825302)
					(mid 176.817618 -226.829022)
					(end 176.821338 -226.838002)
				)
			)
		)
	)
	(zone
		(layer "In1.Cu")
		(hatch none 0.5)
		(connect_pads
			(clearance 0)
		)
		(min_thickness 0.25)
		(keepout
			(tracks not_allowed)
			(vias allowed)
			(pads allowed)
			(copperpour not_allowed)
			(footprints allowed)
		)
		(placement
			(enabled no)
			(sheetname "")
		)
		(fill
			(thermal_gap 0.5)
			(thermal_bridge_width 0.5)
			(island_removal_mode 0)
		)
		(polygon
			(pts
				(arc
					(start 180.265324 -235.832396)
					(mid 180.261604 -235.841376)
					(end 180.252624 -235.845096)
				)
				(arc
					(start 178.779424 -235.845096)
					(mid 178.770444 -235.841376)
					(end 178.766724 -235.832396)
				)
				(arc
					(start 178.766724 -235.337858)
					(mid 178.770444 -235.328878)
					(end 178.779424 -235.325158)
				)
				(arc
					(start 180.252624 -235.325158)
					(mid 180.261604 -235.328878)
					(end 180.265324 -235.337858)
				)
			)
		)
	)
	(zone
		(layer "In1.Cu")
		(hatch none 0.5)
		(connect_pads
			(clearance 0)
		)
		(min_thickness 0.25)
		(keepout
			(tracks not_allowed)
			(vias allowed)
			(pads allowed)
			(copperpour not_allowed)
			(footprints allowed)
		)
		(placement
			(enabled no)
			(sheetname "")
		)
		(fill
			(thermal_gap 0.5)
			(thermal_bridge_width 0.5)
			(island_removal_mode 0)
		)
		(polygon
			(pts
				(arc
					(start 450.8373 -234.13212)
					(mid 450.83358 -234.1411)
					(end 450.8246 -234.14482)
				)
				(arc
					(start 449.3514 -234.14482)
					(mid 449.34242 -234.1411)
					(end 449.3387 -234.13212)
				)
				(arc
					(start 449.3387 -233.637582)
					(mid 449.34242 -233.628602)
					(end 449.3514 -233.624882)
				)
				(arc
					(start 450.8246 -233.624882)
					(mid 450.83358 -233.628602)
					(end 450.8373 -233.637582)
				)
			)
		)
	)
	(zone
		(layer "In1.Cu")
		(hatch none 0.5)
		(connect_pads
			(clearance 0)
		)
		(min_thickness 0.25)
		(keepout
			(tracks not_allowed)
			(vias allowed)
			(pads allowed)
			(copperpour not_allowed)
			(footprints allowed)
		)
		(placement
			(enabled no)
			(sheetname "")
		)
		(fill
			(thermal_gap 0.5)
			(thermal_bridge_width 0.5)
			(island_removal_mode 0)
		)
		(polygon
			(pts
				(arc
					(start 165.177216 -213.732364)
					(mid 165.173496 -213.741344)
					(end 165.164516 -213.745064)
				)
				(arc
					(start 163.691316 -213.745064)
					(mid 163.682336 -213.741344)
					(end 163.678616 -213.732364)
				)
				(arc
					(start 163.678616 -213.237826)
					(mid 163.682336 -213.228846)
					(end 163.691316 -213.225126)
				)
				(arc
					(start 165.164516 -213.225126)
					(mid 165.173496 -213.228846)
					(end 165.177216 -213.237826)
				)
			)
		)
	)
	(zone
		(layer "In1.Cu")
		(hatch none 0.5)
		(connect_pads
			(clearance 0)
		)
		(min_thickness 0.25)
		(keepout
			(tracks not_allowed)
			(vias allowed)
			(pads allowed)
			(copperpour not_allowed)
			(footprints allowed)
		)
		(placement
			(enabled no)
			(sheetname "")
		)
		(fill
			(thermal_gap 0.5)
			(thermal_bridge_width 0.5)
			(island_removal_mode 0)
		)
		(polygon
			(pts
				(arc
					(start 48.533304 -243.482368)
					(mid 48.529584 -243.491348)
					(end 48.520604 -243.495068)
				)
				(arc
					(start 47.047404 -243.495068)
					(mid 47.038424 -243.491348)
					(end 47.034704 -243.482368)
				)
				(arc
					(start 47.034704 -242.98783)
					(mid 47.038424 -242.97885)
					(end 47.047404 -242.97513)
				)
				(arc
					(start 48.520604 -242.97513)
					(mid 48.529584 -242.97885)
					(end 48.533304 -242.98783)
				)
			)
		)
	)
	(zone
		(layer "In1.Cu")
		(hatch none 0.5)
		(connect_pads
			(clearance 0)
		)
		(min_thickness 0.25)
		(keepout
			(tracks not_allowed)
			(vias allowed)
			(pads allowed)
			(copperpour not_allowed)
			(footprints allowed)
		)
		(placement
			(enabled no)
			(sheetname "")
		)
		(fill
			(thermal_gap 0.5)
			(thermal_bridge_width 0.5)
			(island_removal_mode 0)
		)
		(polygon
			(pts
				(arc
					(start 195.353432 -296.182542)
					(mid 195.349712 -296.191522)
					(end 195.340732 -296.195242)
				)
				(arc
					(start 193.867532 -296.195242)
					(mid 193.858552 -296.191522)
					(end 193.854832 -296.182542)
				)
				(arc
					(start 193.854832 -295.688004)
					(mid 193.858552 -295.679024)
					(end 193.867532 -295.675304)
				)
				(arc
					(start 195.340732 -295.675304)
					(mid 195.349712 -295.679024)
					(end 195.353432 -295.688004)
				)
			)
		)
	)
	(zone
		(layer "In1.Cu")
		(hatch none 0.5)
		(connect_pads
			(clearance 0)
		)
		(min_thickness 0.25)
		(keepout
			(tracks not_allowed)
			(vias allowed)
			(pads allowed)
			(copperpour not_allowed)
			(footprints allowed)
		)
		(placement
			(enabled no)
			(sheetname "")
		)
		(fill
			(thermal_gap 0.5)
			(thermal_bridge_width 0.5)
			(island_removal_mode 0)
		)
		(polygon
			(pts
				(arc
					(start 454.937368 -203.532232)
					(mid 454.933648 -203.541212)
					(end 454.924668 -203.544932)
				)
				(arc
					(start 453.451468 -203.544932)
					(mid 453.442488 -203.541212)
					(end 453.438768 -203.532232)
				)
				(arc
					(start 453.438768 -203.037694)
					(mid 453.442488 -203.028714)
					(end 453.451468 -203.024994)
				)
				(arc
					(start 454.924668 -203.024994)
					(mid 454.933648 -203.028714)
					(end 454.937368 -203.037694)
				)
			)
		)
	)
	(zone
		(layer "In1.Cu")
		(hatch none 0.5)
		(connect_pads
			(clearance 0)
		)
		(min_thickness 0.25)
		(keepout
			(tracks not_allowed)
			(vias allowed)
			(pads allowed)
			(copperpour not_allowed)
			(footprints allowed)
		)
		(placement
			(enabled no)
			(sheetname "")
		)
		(fill
			(thermal_gap 0.5)
			(thermal_bridge_width 0.5)
			(island_removal_mode 0)
		)
		(polygon
			(pts
				(arc
					(start 417.217352 -276.632162)
					(mid 417.213632 -276.641142)
					(end 417.204652 -276.644862)
				)
				(arc
					(start 415.731452 -276.644862)
					(mid 415.722472 -276.641142)
					(end 415.718752 -276.632162)
				)
				(arc
					(start 415.718752 -276.137624)
					(mid 415.722472 -276.128644)
					(end 415.731452 -276.124924)
				)
				(arc
					(start 417.204652 -276.124924)
					(mid 417.213632 -276.128644)
					(end 417.217352 -276.137624)
				)
			)
		)
	)
	(zone
		(layer "In1.Cu")
		(hatch none 0.5)
		(connect_pads
			(clearance 0)
		)
		(min_thickness 0.25)
		(keepout
			(tracks not_allowed)
			(vias allowed)
			(pads allowed)
			(copperpour not_allowed)
			(footprints allowed)
		)
		(placement
			(enabled no)
			(sheetname "")
		)
		(fill
			(thermal_gap 0.5)
			(thermal_bridge_width 0.5)
			(island_removal_mode 0)
		)
		(polygon
			(pts
				(arc
					(start 345.118436 -399.701258)
					(mid 345.245436 -399.828258)
					(end 345.372436 -399.701258)
				)
				(arc
					(start 345.372436 -399.625058)
					(mid 345.245436 -399.498058)
					(end 345.118436 -399.625058)
				)
			)
		)
	)
	(zone
		(layer "In1.Cu")
		(hatch none 0.5)
		(connect_pads
			(clearance 0)
		)
		(min_thickness 0.25)
		(keepout
			(tracks not_allowed)
			(vias allowed)
			(pads allowed)
			(copperpour not_allowed)
			(footprints allowed)
		)
		(placement
			(enabled no)
			(sheetname "")
		)
		(fill
			(thermal_gap 0.5)
			(thermal_bridge_width 0.5)
			(island_removal_mode 0)
		)
		(polygon
			(pts
				(arc
					(start 22.45741 -254.532384)
					(mid 22.45369 -254.541364)
					(end 22.44471 -254.545084)
				)
				(arc
					(start 20.97151 -254.545084)
					(mid 20.96253 -254.541364)
					(end 20.95881 -254.532384)
				)
				(arc
					(start 20.95881 -254.037846)
					(mid 20.96253 -254.028866)
					(end 20.97151 -254.025146)
				)
				(arc
					(start 22.44471 -254.025146)
					(mid 22.45369 -254.028866)
					(end 22.45741 -254.037846)
				)
			)
		)
	)
	(zone
		(layer "In1.Cu")
		(hatch none 0.5)
		(connect_pads
			(clearance 0)
		)
		(min_thickness 0.25)
		(keepout
			(tracks not_allowed)
			(vias allowed)
			(pads allowed)
			(copperpour not_allowed)
			(footprints allowed)
		)
		(placement
			(enabled no)
			(sheetname "")
		)
		(fill
			(thermal_gap 0.5)
			(thermal_bridge_width 0.5)
			(island_removal_mode 0)
		)
		(polygon
			(pts
				(arc
					(start 206.5782 -214.33536)
					(mid 205.9178 -214.33536)
					(end 206.5782 -214.33536)
				)
			)
		)
	)
	(zone
		(layer "In1.Cu")
		(hatch none 0.5)
		(connect_pads
			(clearance 0)
		)
		(min_thickness 0.25)
		(keepout
			(tracks not_allowed)
			(vias allowed)
			(pads allowed)
			(copperpour not_allowed)
			(footprints allowed)
		)
		(placement
			(enabled no)
			(sheetname "")
		)
		(fill
			(thermal_gap 0.5)
			(thermal_bridge_width 0.5)
			(island_removal_mode 0)
		)
		(polygon
			(pts
				(arc
					(start 296.473372 -239.232186)
					(mid 296.469652 -239.241166)
					(end 296.460672 -239.244886)
				)
				(arc
					(start 294.987472 -239.244886)
					(mid 294.978492 -239.241166)
					(end 294.974772 -239.232186)
				)
				(arc
					(start 294.974772 -238.737648)
					(mid 294.978492 -238.728668)
					(end 294.987472 -238.724948)
				)
				(arc
					(start 296.460672 -238.724948)
					(mid 296.469652 -238.728668)
					(end 296.473372 -238.737648)
				)
			)
		)
	)
	(zone
		(layer "In1.Cu")
		(hatch none 0.5)
		(connect_pads
			(clearance 0)
		)
		(min_thickness 0.25)
		(keepout
			(tracks not_allowed)
			(vias allowed)
			(pads allowed)
			(copperpour not_allowed)
			(footprints allowed)
		)
		(placement
			(enabled no)
			(sheetname "")
		)
		(fill
			(thermal_gap 0.5)
			(thermal_bridge_width 0.5)
			(island_removal_mode 0)
		)
		(polygon
			(pts
				(arc
					(start 266.29741 -295.33215)
					(mid 266.29369 -295.34113)
					(end 266.28471 -295.34485)
				)
				(arc
					(start 264.81151 -295.34485)
					(mid 264.80253 -295.34113)
					(end 264.79881 -295.33215)
				)
				(arc
					(start 264.79881 -294.837612)
					(mid 264.80253 -294.828632)
					(end 264.81151 -294.824912)
				)
				(arc
					(start 266.28471 -294.824912)
					(mid 266.29369 -294.828632)
					(end 266.29741 -294.837612)
				)
			)
		)
	)
	(zone
		(layer "In1.Cu")
		(hatch none 0.5)
		(connect_pads
			(clearance 0)
		)
		(min_thickness 0.25)
		(keepout
			(tracks not_allowed)
			(vias allowed)
			(pads allowed)
			(copperpour not_allowed)
			(footprints allowed)
		)
		(placement
			(enabled no)
			(sheetname "")
		)
		(fill
			(thermal_gap 0.5)
			(thermal_bridge_width 0.5)
			(island_removal_mode 0)
		)
		(polygon
			(pts
				(arc
					(start 416.398202 -392.30427)
					(mid 416.093402 -392.30427)
					(end 416.398202 -392.30427)
				)
			)
		)
	)
	(zone
		(layer "In1.Cu")
		(hatch none 0.5)
		(connect_pads
			(clearance 0)
		)
		(min_thickness 0.25)
		(keepout
			(tracks not_allowed)
			(vias allowed)
			(pads allowed)
			(copperpour not_allowed)
			(footprints allowed)
		)
		(placement
			(enabled no)
			(sheetname "")
		)
		(fill
			(thermal_gap 0.5)
			(thermal_bridge_width 0.5)
			(island_removal_mode 0)
		)
		(polygon
			(pts
				(arc
					(start 25.901396 -299.582586)
					(mid 25.897676 -299.591566)
					(end 25.888696 -299.595286)
				)
				(arc
					(start 24.415496 -299.595286)
					(mid 24.406516 -299.591566)
					(end 24.402796 -299.582586)
				)
				(arc
					(start 24.402796 -299.088048)
					(mid 24.406516 -299.079068)
					(end 24.415496 -299.075348)
				)
				(arc
					(start 25.888696 -299.075348)
					(mid 25.897676 -299.079068)
					(end 25.901396 -299.088048)
				)
			)
		)
	)
	(zone
		(layer "In1.Cu")
		(hatch none 0.5)
		(connect_pads
			(clearance 0)
		)
		(min_thickness 0.25)
		(keepout
			(tracks not_allowed)
			(vias allowed)
			(pads allowed)
			(copperpour not_allowed)
			(footprints allowed)
		)
		(placement
			(enabled no)
			(sheetname "")
		)
		(fill
			(thermal_gap 0.5)
			(thermal_bridge_width 0.5)
			(island_removal_mode 0)
		)
		(polygon
			(pts
				(arc
					(start 60.177426 -252.832362)
					(mid 60.173706 -252.841342)
					(end 60.164726 -252.845062)
				)
				(arc
					(start 58.691526 -252.845062)
					(mid 58.682546 -252.841342)
					(end 58.678826 -252.832362)
				)
				(arc
					(start 58.678826 -252.337824)
					(mid 58.682546 -252.328844)
					(end 58.691526 -252.325124)
				)
				(arc
					(start 60.164726 -252.325124)
					(mid 60.173706 -252.328844)
					(end 60.177426 -252.337824)
				)
			)
		)
	)
	(zone
		(layer "In1.Cu")
		(hatch none 0.5)
		(connect_pads
			(clearance 0)
		)
		(min_thickness 0.25)
		(keepout
			(tracks not_allowed)
			(vias allowed)
			(pads allowed)
			(copperpour not_allowed)
			(footprints allowed)
		)
		(placement
			(enabled no)
			(sheetname "")
		)
		(fill
			(thermal_gap 0.5)
			(thermal_bridge_width 0.5)
			(island_removal_mode 0)
		)
		(polygon
			(pts
				(arc
					(start 90.788998 -388.774432)
					(mid 90.407998 -388.774432)
					(end 90.788998 -388.774432)
				)
			)
		)
	)
	(zone
		(layer "In1.Cu")
		(hatch none 0.5)
		(connect_pads
			(clearance 0)
		)
		(min_thickness 0.25)
		(keepout
			(tracks not_allowed)
			(vias allowed)
			(pads allowed)
			(copperpour not_allowed)
			(footprints allowed)
		)
		(placement
			(enabled no)
			(sheetname "")
		)
		(fill
			(thermal_gap 0.5)
			(thermal_bridge_width 0.5)
			(island_removal_mode 0)
		)
		(polygon
			(pts
				(arc
					(start 169.277284 -276.632416)
					(mid 169.273564 -276.641396)
					(end 169.264584 -276.645116)
				)
				(arc
					(start 167.791384 -276.645116)
					(mid 167.782404 -276.641396)
					(end 167.778684 -276.632416)
				)
				(arc
					(start 167.778684 -276.137878)
					(mid 167.782404 -276.128898)
					(end 167.791384 -276.125178)
				)
				(arc
					(start 169.264584 -276.125178)
					(mid 169.273564 -276.128898)
					(end 169.277284 -276.137878)
				)
			)
		)
	)
	(zone
		(layer "In1.Cu")
		(hatch none 0.5)
		(connect_pads
			(clearance 0)
		)
		(min_thickness 0.25)
		(keepout
			(tracks not_allowed)
			(vias allowed)
			(pads allowed)
			(copperpour not_allowed)
			(footprints allowed)
		)
		(placement
			(enabled no)
			(sheetname "")
		)
		(fill
			(thermal_gap 0.5)
			(thermal_bridge_width 0.5)
			(island_removal_mode 0)
		)
		(polygon
			(pts
				(arc
					(start 266.29741 -262.182102)
					(mid 266.29369 -262.191082)
					(end 266.28471 -262.194802)
				)
				(arc
					(start 264.81151 -262.194802)
					(mid 264.80253 -262.191082)
					(end 264.79881 -262.182102)
				)
				(arc
					(start 264.79881 -261.687564)
					(mid 264.80253 -261.678584)
					(end 264.81151 -261.674864)
				)
				(arc
					(start 266.28471 -261.674864)
					(mid 266.29369 -261.678584)
					(end 266.29741 -261.687564)
				)
			)
		)
	)
	(zone
		(layer "In1.Cu")
		(hatch none 0.5)
		(connect_pads
			(clearance 0)
		)
		(min_thickness 0.25)
		(keepout
			(tracks not_allowed)
			(vias allowed)
			(pads allowed)
			(copperpour not_allowed)
			(footprints allowed)
		)
		(placement
			(enabled no)
			(sheetname "")
		)
		(fill
			(thermal_gap 0.5)
			(thermal_bridge_width 0.5)
			(island_removal_mode 0)
		)
		(polygon
			(pts
				(arc
					(start 165.177216 -218.83243)
					(mid 165.173496 -218.84141)
					(end 165.164516 -218.84513)
				)
				(arc
					(start 163.691316 -218.84513)
					(mid 163.682336 -218.84141)
					(end 163.678616 -218.83243)
				)
				(arc
					(start 163.678616 -218.337892)
					(mid 163.682336 -218.328912)
					(end 163.691316 -218.325192)
				)
				(arc
					(start 165.164516 -218.325192)
					(mid 165.173496 -218.328912)
					(end 165.177216 -218.337892)
				)
			)
		)
	)
	(zone
		(layer "In1.Cu")
		(hatch none 0.5)
		(connect_pads
			(clearance 0)
		)
		(min_thickness 0.25)
		(keepout
			(tracks not_allowed)
			(vias allowed)
			(pads allowed)
			(copperpour not_allowed)
			(footprints allowed)
		)
		(placement
			(enabled no)
			(sheetname "")
		)
		(fill
			(thermal_gap 0.5)
			(thermal_bridge_width 0.5)
			(island_removal_mode 0)
		)
		(polygon
			(pts
				(arc
					(start 428.205392 -206.082138)
					(mid 428.201672 -206.091118)
					(end 428.192692 -206.094838)
				)
				(arc
					(start 426.719492 -206.094838)
					(mid 426.710512 -206.091118)
					(end 426.706792 -206.082138)
				)
				(arc
					(start 426.706792 -205.5876)
					(mid 426.710512 -205.57862)
					(end 426.719492 -205.5749)
				)
				(arc
					(start 428.192692 -205.5749)
					(mid 428.201672 -205.57862)
					(end 428.205392 -205.5876)
				)
			)
		)
	)
	(zone
		(layer "In1.Cu")
		(hatch none 0.5)
		(connect_pads
			(clearance 0)
		)
		(min_thickness 0.25)
		(keepout
			(tracks not_allowed)
			(vias allowed)
			(pads allowed)
			(copperpour not_allowed)
			(footprints allowed)
		)
		(placement
			(enabled no)
			(sheetname "")
		)
		(fill
			(thermal_gap 0.5)
			(thermal_bridge_width 0.5)
			(island_removal_mode 0)
		)
		(polygon
			(pts
				(arc
					(start 202.897232 -299.582586)
					(mid 202.893512 -299.591566)
					(end 202.884532 -299.595286)
				)
				(arc
					(start 201.411332 -299.595286)
					(mid 201.402352 -299.591566)
					(end 201.398632 -299.582586)
				)
				(arc
					(start 201.398632 -299.088048)
					(mid 201.402352 -299.079068)
					(end 201.411332 -299.075348)
				)
				(arc
					(start 202.884532 -299.075348)
					(mid 202.893512 -299.079068)
					(end 202.897232 -299.088048)
				)
			)
		)
	)
	(zone
		(layer "In1.Cu")
		(hatch none 0.5)
		(connect_pads
			(clearance 0)
		)
		(min_thickness 0.25)
		(keepout
			(tracks not_allowed)
			(vias allowed)
			(pads allowed)
			(copperpour not_allowed)
			(footprints allowed)
		)
		(placement
			(enabled no)
			(sheetname "")
		)
		(fill
			(thermal_gap 0.5)
			(thermal_bridge_width 0.5)
			(island_removal_mode 0)
		)
		(polygon
			(pts
				(arc
					(start 56.077358 -207.782414)
					(mid 56.073638 -207.791394)
					(end 56.064658 -207.795114)
				)
				(arc
					(start 54.591458 -207.795114)
					(mid 54.582478 -207.791394)
					(end 54.578758 -207.782414)
				)
				(arc
					(start 54.578758 -207.287876)
					(mid 54.582478 -207.278896)
					(end 54.591458 -207.275176)
				)
				(arc
					(start 56.064658 -207.275176)
					(mid 56.073638 -207.278896)
					(end 56.077358 -207.287876)
				)
			)
		)
	)
	(zone
		(layer "In1.Cu")
		(hatch none 0.5)
		(connect_pads
			(clearance 0)
		)
		(min_thickness 0.25)
		(keepout
			(tracks not_allowed)
			(vias allowed)
			(pads allowed)
			(copperpour not_allowed)
			(footprints allowed)
		)
		(placement
			(enabled no)
			(sheetname "")
		)
		(fill
			(thermal_gap 0.5)
			(thermal_bridge_width 0.5)
			(island_removal_mode 0)
		)
		(polygon
			(pts
				(arc
					(start 270.397478 -225.632264)
					(mid 270.393758 -225.641244)
					(end 270.384778 -225.644964)
				)
				(arc
					(start 268.911578 -225.644964)
					(mid 268.902598 -225.641244)
					(end 268.898878 -225.632264)
				)
				(arc
					(start 268.898878 -225.137726)
					(mid 268.902598 -225.128746)
					(end 268.911578 -225.125026)
				)
				(arc
					(start 270.384778 -225.125026)
					(mid 270.393758 -225.128746)
					(end 270.397478 -225.137726)
				)
			)
		)
	)
	(zone
		(layer "In1.Cu")
		(hatch none 0.5)
		(connect_pads
			(clearance 0)
		)
		(min_thickness 0.25)
		(keepout
			(tracks not_allowed)
			(vias allowed)
			(pads allowed)
			(copperpour not_allowed)
			(footprints allowed)
		)
		(placement
			(enabled no)
			(sheetname "")
		)
		(fill
			(thermal_gap 0.5)
			(thermal_bridge_width 0.5)
			(island_removal_mode 0)
		)
		(polygon
			(pts
				(arc
					(start 206.9973 -229.032562)
					(mid 206.99358 -229.041542)
					(end 206.9846 -229.045262)
				)
				(arc
					(start 205.5114 -229.045262)
					(mid 205.50242 -229.041542)
					(end 205.4987 -229.032562)
				)
				(arc
					(start 205.4987 -228.538024)
					(mid 205.50242 -228.529044)
					(end 205.5114 -228.525324)
				)
				(arc
					(start 206.9846 -228.525324)
					(mid 206.99358 -228.529044)
					(end 206.9973 -228.538024)
				)
			)
		)
	)
	(zone
		(layer "In1.Cu")
		(hatch none 0.5)
		(connect_pads
			(clearance 0)
		)
		(min_thickness 0.25)
		(keepout
			(tracks not_allowed)
			(vias allowed)
			(pads allowed)
			(copperpour not_allowed)
			(footprints allowed)
		)
		(placement
			(enabled no)
			(sheetname "")
		)
		(fill
			(thermal_gap 0.5)
			(thermal_bridge_width 0.5)
			(island_removal_mode 0)
		)
		(polygon
			(pts
				(arc
					(start 165.177216 -286.832548)
					(mid 165.173496 -286.841528)
					(end 165.164516 -286.845248)
				)
				(arc
					(start 163.691316 -286.845248)
					(mid 163.682336 -286.841528)
					(end 163.678616 -286.832548)
				)
				(arc
					(start 163.678616 -286.33801)
					(mid 163.682336 -286.32903)
					(end 163.691316 -286.32531)
				)
				(arc
					(start 165.164516 -286.32531)
					(mid 165.173496 -286.32903)
					(end 165.177216 -286.33801)
				)
			)
		)
	)
	(zone
		(layer "In1.Cu")
		(hatch none 0.5)
		(connect_pads
			(clearance 0)
		)
		(min_thickness 0.25)
		(keepout
			(tracks not_allowed)
			(vias allowed)
			(pads allowed)
			(copperpour not_allowed)
			(footprints allowed)
		)
		(placement
			(enabled no)
			(sheetname "")
		)
		(fill
			(thermal_gap 0.5)
			(thermal_bridge_width 0.5)
			(island_removal_mode 0)
		)
		(polygon
			(pts
				(arc
					(start 285.485332 -291.082222)
					(mid 285.481612 -291.091202)
					(end 285.472632 -291.094922)
				)
				(arc
					(start 283.999432 -291.094922)
					(mid 283.990452 -291.091202)
					(end 283.986732 -291.082222)
				)
				(arc
					(start 283.986732 -290.587684)
					(mid 283.990452 -290.578704)
					(end 283.999432 -290.574984)
				)
				(arc
					(start 285.472632 -290.574984)
					(mid 285.481612 -290.578704)
					(end 285.485332 -290.587684)
				)
			)
		)
	)
	(zone
		(layer "In1.Cu")
		(hatch none 0.5)
		(connect_pads
			(clearance 0)
		)
		(min_thickness 0.25)
		(keepout
			(tracks not_allowed)
			(vias allowed)
			(pads allowed)
			(copperpour not_allowed)
			(footprints allowed)
		)
		(placement
			(enabled no)
			(sheetname "")
		)
		(fill
			(thermal_gap 0.5)
			(thermal_bridge_width 0.5)
			(island_removal_mode 0)
		)
		(polygon
			(pts
				(arc
					(start 424.761406 -216.28227)
					(mid 424.757686 -216.29125)
					(end 424.748706 -216.29497)
				)
				(arc
					(start 423.275506 -216.29497)
					(mid 423.266526 -216.29125)
					(end 423.262806 -216.28227)
				)
				(arc
					(start 423.262806 -215.787732)
					(mid 423.266526 -215.778752)
					(end 423.275506 -215.775032)
				)
				(arc
					(start 424.748706 -215.775032)
					(mid 424.757686 -215.778752)
					(end 424.761406 -215.787732)
				)
			)
		)
	)
	(zone
		(layer "In1.Cu")
		(hatch none 0.5)
		(connect_pads
			(clearance 0)
		)
		(min_thickness 0.25)
		(keepout
			(tracks not_allowed)
			(vias allowed)
			(pads allowed)
			(copperpour not_allowed)
			(footprints allowed)
		)
		(placement
			(enabled no)
			(sheetname "")
		)
		(fill
			(thermal_gap 0.5)
			(thermal_bridge_width 0.5)
			(island_removal_mode 0)
		)
		(polygon
			(pts
				(arc
					(start 277.941532 -287.682178)
					(mid 277.937812 -287.691158)
					(end 277.928832 -287.694878)
				)
				(arc
					(start 276.455632 -287.694878)
					(mid 276.446652 -287.691158)
					(end 276.442932 -287.682178)
				)
				(arc
					(start 276.442932 -287.18764)
					(mid 276.446652 -287.17866)
					(end 276.455632 -287.17494)
				)
				(arc
					(start 277.928832 -287.17494)
					(mid 277.937812 -287.17866)
					(end 277.941532 -287.18764)
				)
			)
		)
	)
	(zone
		(layer "In1.Cu")
		(hatch none 0.5)
		(connect_pads
			(clearance 0)
		)
		(min_thickness 0.25)
		(keepout
			(tracks not_allowed)
			(vias allowed)
			(pads allowed)
			(copperpour not_allowed)
			(footprints allowed)
		)
		(placement
			(enabled no)
			(sheetname "")
		)
		(fill
			(thermal_gap 0.5)
			(thermal_bridge_width 0.5)
			(island_removal_mode 0)
		)
		(polygon
			(pts
				(arc
					(start 316.770258 -399.143474)
					(mid 316.465458 -399.143474)
					(end 316.770258 -399.143474)
				)
			)
		)
	)
	(zone
		(layer "In1.Cu")
		(hatch none 0.5)
		(connect_pads
			(clearance 0)
		)
		(min_thickness 0.25)
		(keepout
			(tracks not_allowed)
			(vias allowed)
			(pads allowed)
			(copperpour not_allowed)
			(footprints allowed)
		)
		(placement
			(enabled no)
			(sheetname "")
		)
		(fill
			(thermal_gap 0.5)
			(thermal_bridge_width 0.5)
			(island_removal_mode 0)
		)
		(polygon
			(pts
				(arc
					(start 18.357342 -285.98241)
					(mid 18.353622 -285.99139)
					(end 18.344642 -285.99511)
				)
				(arc
					(start 16.871442 -285.99511)
					(mid 16.862462 -285.99139)
					(end 16.858742 -285.98241)
				)
				(arc
					(start 16.858742 -285.487872)
					(mid 16.862462 -285.478892)
					(end 16.871442 -285.475172)
				)
				(arc
					(start 18.344642 -285.475172)
					(mid 18.353622 -285.478892)
					(end 18.357342 -285.487872)
				)
			)
		)
	)
	(zone
		(layer "In1.Cu")
		(hatch none 0.5)
		(connect_pads
			(clearance 0)
		)
		(min_thickness 0.25)
		(keepout
			(tracks not_allowed)
			(vias allowed)
			(pads allowed)
			(copperpour not_allowed)
			(footprints allowed)
		)
		(placement
			(enabled no)
			(sheetname "")
		)
		(fill
			(thermal_gap 0.5)
			(thermal_bridge_width 0.5)
			(island_removal_mode 0)
		)
		(polygon
			(pts
				(arc
					(start 417.217352 -254.53213)
					(mid 417.213632 -254.54111)
					(end 417.204652 -254.54483)
				)
				(arc
					(start 415.731452 -254.54483)
					(mid 415.722472 -254.54111)
					(end 415.718752 -254.53213)
				)
				(arc
					(start 415.718752 -254.037592)
					(mid 415.722472 -254.028612)
					(end 415.731452 -254.024892)
				)
				(arc
					(start 417.204652 -254.024892)
					(mid 417.213632 -254.028612)
					(end 417.217352 -254.037592)
				)
			)
		)
	)
	(zone
		(layer "In1.Cu")
		(hatch none 0.5)
		(connect_pads
			(clearance 0)
		)
		(min_thickness 0.25)
		(keepout
			(tracks not_allowed)
			(vias allowed)
			(pads allowed)
			(copperpour not_allowed)
			(footprints allowed)
		)
		(placement
			(enabled no)
			(sheetname "")
		)
		(fill
			(thermal_gap 0.5)
			(thermal_bridge_width 0.5)
			(island_removal_mode 0)
		)
		(polygon
			(pts
				(arc
					(start 304.017426 -235.832142)
					(mid 304.013706 -235.841122)
					(end 304.004726 -235.844842)
				)
				(arc
					(start 302.531526 -235.844842)
					(mid 302.522546 -235.841122)
					(end 302.518826 -235.832142)
				)
				(arc
					(start 302.518826 -235.337604)
					(mid 302.522546 -235.328624)
					(end 302.531526 -235.324904)
				)
				(arc
					(start 304.004726 -235.324904)
					(mid 304.013706 -235.328624)
					(end 304.017426 -235.337604)
				)
			)
		)
	)
	(zone
		(layer "In1.Cu")
		(hatch none 0.5)
		(connect_pads
			(clearance 0)
		)
		(min_thickness 0.25)
		(keepout
			(tracks not_allowed)
			(vias allowed)
			(pads allowed)
			(copperpour not_allowed)
			(footprints allowed)
		)
		(placement
			(enabled no)
			(sheetname "")
		)
		(fill
			(thermal_gap 0.5)
			(thermal_bridge_width 0.5)
			(island_removal_mode 0)
		)
		(polygon
			(pts
				(arc
					(start 435.749446 -268.98219)
					(mid 435.745726 -268.99117)
					(end 435.736746 -268.99489)
				)
				(arc
					(start 434.263546 -268.99489)
					(mid 434.254566 -268.99117)
					(end 434.250846 -268.98219)
				)
				(arc
					(start 434.250846 -268.487652)
					(mid 434.254566 -268.478672)
					(end 434.263546 -268.474952)
				)
				(arc
					(start 435.736746 -268.474952)
					(mid 435.745726 -268.478672)
					(end 435.749446 -268.487652)
				)
			)
		)
	)
	(zone
		(layer "In1.Cu")
		(hatch none 0.5)
		(connect_pads
			(clearance 0)
		)
		(min_thickness 0.25)
		(keepout
			(tracks not_allowed)
			(vias allowed)
			(pads allowed)
			(copperpour not_allowed)
			(footprints allowed)
		)
		(placement
			(enabled no)
			(sheetname "")
		)
		(fill
			(thermal_gap 0.5)
			(thermal_bridge_width 0.5)
			(island_removal_mode 0)
		)
		(polygon
			(pts
				(arc
					(start 266.29741 -254.53213)
					(mid 266.29369 -254.54111)
					(end 266.28471 -254.54483)
				)
				(arc
					(start 264.81151 -254.54483)
					(mid 264.80253 -254.54111)
					(end 264.79881 -254.53213)
				)
				(arc
					(start 264.79881 -254.037592)
					(mid 264.80253 -254.028612)
					(end 264.81151 -254.024892)
				)
				(arc
					(start 266.28471 -254.024892)
					(mid 266.29369 -254.028612)
					(end 266.29741 -254.037592)
				)
			)
		)
	)
	(zone
		(layer "In1.Cu")
		(hatch none 0.5)
		(connect_pads
			(clearance 0)
		)
		(min_thickness 0.25)
		(keepout
			(tracks not_allowed)
			(vias allowed)
			(pads allowed)
			(copperpour not_allowed)
			(footprints allowed)
		)
		(placement
			(enabled no)
			(sheetname "")
		)
		(fill
			(thermal_gap 0.5)
			(thermal_bridge_width 0.5)
			(island_removal_mode 0)
		)
		(polygon
			(pts
				(arc
					(start 95.988886 -389.467344)
					(mid 95.607886 -389.467344)
					(end 95.988886 -389.467344)
				)
			)
		)
	)
	(zone
		(layer "In1.Cu")
		(hatch none 0.5)
		(connect_pads
			(clearance 0)
		)
		(min_thickness 0.25)
		(keepout
			(tracks not_allowed)
			(vias allowed)
			(pads allowed)
			(copperpour not_allowed)
			(footprints allowed)
		)
		(placement
			(enabled no)
			(sheetname "")
		)
		(fill
			(thermal_gap 0.5)
			(thermal_bridge_width 0.5)
			(island_removal_mode 0)
		)
		(polygon
			(pts
				(arc
					(start 296.473372 -206.082138)
					(mid 296.469652 -206.091118)
					(end 296.460672 -206.094838)
				)
				(arc
					(start 294.987472 -206.094838)
					(mid 294.978492 -206.091118)
					(end 294.974772 -206.082138)
				)
				(arc
					(start 294.974772 -205.5876)
					(mid 294.978492 -205.57862)
					(end 294.987472 -205.5749)
				)
				(arc
					(start 296.460672 -205.5749)
					(mid 296.469652 -205.57862)
					(end 296.473372 -205.5876)
				)
			)
		)
	)
	(zone
		(layer "In1.Cu")
		(hatch none 0.5)
		(connect_pads
			(clearance 0)
		)
		(min_thickness 0.25)
		(keepout
			(tracks not_allowed)
			(vias allowed)
			(pads allowed)
			(copperpour not_allowed)
			(footprints allowed)
		)
		(placement
			(enabled no)
			(sheetname "")
		)
		(fill
			(thermal_gap 0.5)
			(thermal_bridge_width 0.5)
			(island_removal_mode 0)
		)
		(polygon
			(pts
				(arc
					(start 25.901396 -291.93236)
					(mid 25.897676 -291.94134)
					(end 25.888696 -291.94506)
				)
				(arc
					(start 24.415496 -291.94506)
					(mid 24.406516 -291.94134)
					(end 24.402796 -291.93236)
				)
				(arc
					(start 24.402796 -291.437822)
					(mid 24.406516 -291.428842)
					(end 24.415496 -291.425122)
				)
				(arc
					(start 25.888696 -291.425122)
					(mid 25.897676 -291.428842)
					(end 25.901396 -291.437822)
				)
			)
		)
	)
	(zone
		(layer "In1.Cu")
		(hatch none 0.5)
		(connect_pads
			(clearance 0)
		)
		(min_thickness 0.25)
		(keepout
			(tracks not_allowed)
			(vias allowed)
			(pads allowed)
			(copperpour not_allowed)
			(footprints allowed)
		)
		(placement
			(enabled no)
			(sheetname "")
		)
		(fill
			(thermal_gap 0.5)
			(thermal_bridge_width 0.5)
			(island_removal_mode 0)
		)
		(polygon
			(pts
				(arc
					(start 293.029386 -225.632264)
					(mid 293.025666 -225.641244)
					(end 293.016686 -225.644964)
				)
				(arc
					(start 291.543486 -225.644964)
					(mid 291.534506 -225.641244)
					(end 291.530786 -225.632264)
				)
				(arc
					(start 291.530786 -225.137726)
					(mid 291.534506 -225.128746)
					(end 291.543486 -225.125026)
				)
				(arc
					(start 293.016686 -225.125026)
					(mid 293.025666 -225.128746)
					(end 293.029386 -225.137726)
				)
			)
		)
	)
	(zone
		(layer "In1.Cu")
		(hatch none 0.5)
		(connect_pads
			(clearance 0)
		)
		(min_thickness 0.25)
		(keepout
			(tracks not_allowed)
			(vias allowed)
			(pads allowed)
			(copperpour not_allowed)
			(footprints allowed)
		)
		(placement
			(enabled no)
			(sheetname "")
		)
		(fill
			(thermal_gap 0.5)
			(thermal_bridge_width 0.5)
			(island_removal_mode 0)
		)
		(polygon
			(pts
				(arc
					(start 187.809378 -295.332404)
					(mid 187.805658 -295.341384)
					(end 187.796678 -295.345104)
				)
				(arc
					(start 186.323478 -295.345104)
					(mid 186.314498 -295.341384)
					(end 186.310778 -295.332404)
				)
				(arc
					(start 186.310778 -294.837866)
					(mid 186.314498 -294.828886)
					(end 186.323478 -294.825166)
				)
				(arc
					(start 187.796678 -294.825166)
					(mid 187.805658 -294.828886)
					(end 187.809378 -294.837866)
				)
			)
		)
	)
	(zone
		(layer "In1.Cu")
		(hatch none 0.5)
		(connect_pads
			(clearance 0)
		)
		(min_thickness 0.25)
		(keepout
			(tracks not_allowed)
			(vias allowed)
			(pads allowed)
			(copperpour not_allowed)
			(footprints allowed)
		)
		(placement
			(enabled no)
			(sheetname "")
		)
		(fill
			(thermal_gap 0.5)
			(thermal_bridge_width 0.5)
			(island_removal_mode 0)
		)
		(polygon
			(pts
				(arc
					(start 30.001464 -233.28249)
					(mid 29.997744 -233.29147)
					(end 29.988764 -233.29519)
				)
				(arc
					(start 28.515564 -233.29519)
					(mid 28.506584 -233.29147)
					(end 28.502864 -233.28249)
				)
				(arc
					(start 28.502864 -232.787952)
					(mid 28.506584 -232.778972)
					(end 28.515564 -232.775252)
				)
				(arc
					(start 29.988764 -232.775252)
					(mid 29.997744 -232.778972)
					(end 30.001464 -232.787952)
				)
			)
		)
	)
	(zone
		(layer "In1.Cu")
		(hatch none 0.5)
		(connect_pads
			(clearance 0)
		)
		(min_thickness 0.25)
		(keepout
			(tracks not_allowed)
			(vias allowed)
			(pads allowed)
			(copperpour not_allowed)
			(footprints allowed)
		)
		(placement
			(enabled no)
			(sheetname "")
		)
		(fill
			(thermal_gap 0.5)
			(thermal_bridge_width 0.5)
			(island_removal_mode 0)
		)
		(polygon
			(pts
				(arc
					(start 310.66105 -397.156432)
					(mid 310.28005 -397.156432)
					(end 310.66105 -397.156432)
				)
			)
		)
	)
	(zone
		(layer "In1.Cu")
		(hatch none 0.5)
		(connect_pads
			(clearance 0)
		)
		(min_thickness 0.25)
		(keepout
			(tracks not_allowed)
			(vias allowed)
			(pads allowed)
			(copperpour not_allowed)
			(footprints allowed)
		)
		(placement
			(enabled no)
			(sheetname "")
		)
		(fill
			(thermal_gap 0.5)
			(thermal_bridge_width 0.5)
			(island_removal_mode 0)
		)
		(polygon
			(pts
				(arc
					(start 30.001464 -263.032494)
					(mid 29.997744 -263.041474)
					(end 29.988764 -263.045194)
				)
				(arc
					(start 28.515564 -263.045194)
					(mid 28.506584 -263.041474)
					(end 28.502864 -263.032494)
				)
				(arc
					(start 28.502864 -262.537956)
					(mid 28.506584 -262.528976)
					(end 28.515564 -262.525256)
				)
				(arc
					(start 29.988764 -262.525256)
					(mid 29.997744 -262.528976)
					(end 30.001464 -262.537956)
				)
			)
		)
	)
	(zone
		(layer "In1.Cu")
		(hatch none 0.5)
		(connect_pads
			(clearance 0)
		)
		(min_thickness 0.25)
		(keepout
			(tracks not_allowed)
			(vias allowed)
			(pads allowed)
			(copperpour not_allowed)
			(footprints allowed)
		)
		(placement
			(enabled no)
			(sheetname "")
		)
		(fill
			(thermal_gap 0.5)
			(thermal_bridge_width 0.5)
			(island_removal_mode 0)
		)
		(polygon
			(pts
				(arc
					(start 46.355508 -17.967198)
					(mid 46.377826 -18.02108)
					(end 46.431708 -18.043398)
				)
				(arc
					(start 46.627288 -18.043398)
					(mid 46.649164 -18.040266)
					(end 46.669198 -18.030952)
				)
				(arc
					(start 46.962822 -17.83842)
					(mid 47.004478 -17.826018)
					(end 47.046134 -17.83842)
				)
				(arc
					(start 47.341028 -18.030952)
					(mid 47.360952 -18.040188)
					(end 47.382684 -18.043398)
				)
				(arc
					(start 47.577248 -18.043398)
					(mid 47.63113 -18.02108)
					(end 47.653448 -17.967198)
				)
				(arc
					(start 47.653448 -17.281398)
					(mid 47.63113 -17.227516)
					(end 47.577248 -17.205198)
				)
				(arc
					(start 47.382684 -17.205198)
					(mid 47.36094 -17.208366)
					(end 47.341028 -17.217644)
				)
				(arc
					(start 47.044864 -17.41043)
					(mid 47.00318 -17.422652)
					(end 46.961552 -17.410176)
				)
				(arc
					(start 46.667928 -17.217644)
					(mid 46.648004 -17.208408)
					(end 46.626272 -17.205198)
				)
				(arc
					(start 46.431708 -17.205198)
					(mid 46.377826 -17.227516)
					(end 46.355508 -17.281398)
				)
			)
		)
	)
	(zone
		(layer "In1.Cu")
		(hatch none 0.5)
		(connect_pads
			(clearance 0)
		)
		(min_thickness 0.25)
		(keepout
			(tracks not_allowed)
			(vias allowed)
			(pads allowed)
			(copperpour not_allowed)
			(footprints allowed)
		)
		(placement
			(enabled no)
			(sheetname "")
		)
		(fill
			(thermal_gap 0.5)
			(thermal_bridge_width 0.5)
			(island_removal_mode 0)
		)
		(polygon
			(pts
				(arc
					(start 126.670308 -390.761474)
					(mid 126.365508 -390.761474)
					(end 126.670308 -390.761474)
				)
			)
		)
	)
	(zone
		(layer "In1.Cu")
		(hatch none 0.5)
		(connect_pads
			(clearance 0)
		)
		(min_thickness 0.25)
		(keepout
			(tracks not_allowed)
			(vias allowed)
			(pads allowed)
			(copperpour not_allowed)
			(footprints allowed)
		)
		(placement
			(enabled no)
			(sheetname "")
		)
		(fill
			(thermal_gap 0.5)
			(thermal_bridge_width 0.5)
			(island_removal_mode 0)
		)
		(polygon
			(pts
				(arc
					(start 176.821338 -197.582536)
					(mid 176.817618 -197.591516)
					(end 176.808638 -197.595236)
				)
				(arc
					(start 175.335438 -197.595236)
					(mid 175.326458 -197.591516)
					(end 175.322738 -197.582536)
				)
				(arc
					(start 175.322738 -197.087998)
					(mid 175.326458 -197.079018)
					(end 175.335438 -197.075298)
				)
				(arc
					(start 176.808638 -197.075298)
					(mid 176.817618 -197.079018)
					(end 176.821338 -197.087998)
				)
			)
		)
	)
	(zone
		(layer "In1.Cu")
		(hatch none 0.5)
		(connect_pads
			(clearance 0)
		)
		(min_thickness 0.25)
		(keepout
			(tracks not_allowed)
			(vias allowed)
			(pads allowed)
			(copperpour not_allowed)
			(footprints allowed)
		)
		(placement
			(enabled no)
			(sheetname "")
		)
		(fill
			(thermal_gap 0.5)
			(thermal_bridge_width 0.5)
			(island_removal_mode 0)
		)
		(polygon
			(pts
				(arc
					(start 52.633372 -291.082476)
					(mid 52.629652 -291.091456)
					(end 52.620672 -291.095176)
				)
				(arc
					(start 51.147472 -291.095176)
					(mid 51.138492 -291.091456)
					(end 51.134772 -291.082476)
				)
				(arc
					(start 51.134772 -290.587938)
					(mid 51.138492 -290.578958)
					(end 51.147472 -290.575238)
				)
				(arc
					(start 52.620672 -290.575238)
					(mid 52.629652 -290.578958)
					(end 52.633372 -290.587938)
				)
			)
		)
	)
	(zone
		(layer "In1.Cu")
		(hatch none 0.5)
		(connect_pads
			(clearance 0)
		)
		(min_thickness 0.25)
		(keepout
			(tracks not_allowed)
			(vias allowed)
			(pads allowed)
			(copperpour not_allowed)
			(footprints allowed)
		)
		(placement
			(enabled no)
			(sheetname "")
		)
		(fill
			(thermal_gap 0.5)
			(thermal_bridge_width 0.5)
			(island_removal_mode 0)
		)
		(polygon
			(pts
				(arc
					(start 52.633372 -304.682398)
					(mid 52.629652 -304.691378)
					(end 52.620672 -304.695098)
				)
				(arc
					(start 51.147472 -304.695098)
					(mid 51.138492 -304.691378)
					(end 51.134772 -304.682398)
				)
				(arc
					(start 51.134772 -304.18786)
					(mid 51.138492 -304.17888)
					(end 51.147472 -304.17516)
				)
				(arc
					(start 52.620672 -304.17516)
					(mid 52.629652 -304.17888)
					(end 52.633372 -304.18786)
				)
			)
		)
	)
	(zone
		(layer "In1.Cu")
		(hatch none 0.5)
		(connect_pads
			(clearance 0)
		)
		(min_thickness 0.25)
		(keepout
			(tracks not_allowed)
			(vias allowed)
			(pads allowed)
			(copperpour not_allowed)
			(footprints allowed)
		)
		(placement
			(enabled no)
			(sheetname "")
		)
		(fill
			(thermal_gap 0.5)
			(thermal_bridge_width 0.5)
			(island_removal_mode 0)
		)
		(polygon
			(pts
				(arc
					(start 202.897232 -211.182458)
					(mid 202.893512 -211.191438)
					(end 202.884532 -211.195158)
				)
				(arc
					(start 201.411332 -211.195158)
					(mid 201.402352 -211.191438)
					(end 201.398632 -211.182458)
				)
				(arc
					(start 201.398632 -210.68792)
					(mid 201.402352 -210.67894)
					(end 201.411332 -210.67522)
				)
				(arc
					(start 202.884532 -210.67522)
					(mid 202.893512 -210.67894)
					(end 202.897232 -210.68792)
				)
			)
		)
	)
	(zone
		(layer "In1.Cu")
		(hatch none 0.5)
		(connect_pads
			(clearance 0)
		)
		(min_thickness 0.25)
		(keepout
			(tracks not_allowed)
			(vias allowed)
			(pads allowed)
			(copperpour not_allowed)
			(footprints allowed)
		)
		(placement
			(enabled no)
			(sheetname "")
		)
		(fill
			(thermal_gap 0.5)
			(thermal_bridge_width 0.5)
			(island_removal_mode 0)
		)
		(polygon
			(pts
				(arc
					(start 206.5782 -208.38541)
					(mid 205.9178 -208.38541)
					(end 206.5782 -208.38541)
				)
			)
		)
	)
	(zone
		(layer "In1.Cu")
		(hatch none 0.5)
		(connect_pads
			(clearance 0)
		)
		(min_thickness 0.25)
		(keepout
			(tracks not_allowed)
			(vias allowed)
			(pads allowed)
			(copperpour not_allowed)
			(footprints allowed)
		)
		(placement
			(enabled no)
			(sheetname "")
		)
		(fill
			(thermal_gap 0.5)
			(thermal_bridge_width 0.5)
			(island_removal_mode 0)
		)
		(polygon
			(pts
				(arc
					(start 191.909446 -309.782464)
					(mid 191.905726 -309.791444)
					(end 191.896746 -309.795164)
				)
				(arc
					(start 190.423546 -309.795164)
					(mid 190.414566 -309.791444)
					(end 190.410846 -309.782464)
				)
				(arc
					(start 190.410846 -309.287926)
					(mid 190.414566 -309.278946)
					(end 190.423546 -309.275226)
				)
				(arc
					(start 191.896746 -309.275226)
					(mid 191.905726 -309.278946)
					(end 191.909446 -309.287926)
				)
			)
		)
	)
	(zone
		(layer "In1.Cu")
		(hatch none 0.5)
		(connect_pads
			(clearance 0)
		)
		(min_thickness 0.25)
		(keepout
			(tracks not_allowed)
			(vias allowed)
			(pads allowed)
			(copperpour not_allowed)
			(footprints allowed)
		)
		(placement
			(enabled no)
			(sheetname "")
		)
		(fill
			(thermal_gap 0.5)
			(thermal_bridge_width 0.5)
			(island_removal_mode 0)
		)
		(polygon
			(pts
				(arc
					(start 270.397478 -242.63223)
					(mid 270.393758 -242.64121)
					(end 270.384778 -242.64493)
				)
				(arc
					(start 268.911578 -242.64493)
					(mid 268.902598 -242.64121)
					(end 268.898878 -242.63223)
				)
				(arc
					(start 268.898878 -242.137692)
					(mid 268.902598 -242.128712)
					(end 268.911578 -242.124992)
				)
				(arc
					(start 270.384778 -242.124992)
					(mid 270.393758 -242.128712)
					(end 270.397478 -242.137692)
				)
			)
		)
	)
	(zone
		(layer "In1.Cu")
		(hatch none 0.5)
		(connect_pads
			(clearance 0)
		)
		(min_thickness 0.25)
		(keepout
			(tracks not_allowed)
			(vias allowed)
			(pads allowed)
			(copperpour not_allowed)
			(footprints allowed)
		)
		(placement
			(enabled no)
			(sheetname "")
		)
		(fill
			(thermal_gap 0.5)
			(thermal_bridge_width 0.5)
			(island_removal_mode 0)
		)
		(polygon
			(pts
				(arc
					(start 304.017426 -299.582332)
					(mid 304.013706 -299.591312)
					(end 304.004726 -299.595032)
				)
				(arc
					(start 302.531526 -299.595032)
					(mid 302.522546 -299.591312)
					(end 302.518826 -299.582332)
				)
				(arc
					(start 302.518826 -299.087794)
					(mid 302.522546 -299.078814)
					(end 302.531526 -299.075094)
				)
				(arc
					(start 304.004726 -299.075094)
					(mid 304.013706 -299.078814)
					(end 304.017426 -299.087794)
				)
			)
		)
	)
	(zone
		(layer "In1.Cu")
		(hatch none 0.5)
		(connect_pads
			(clearance 0)
		)
		(min_thickness 0.25)
		(keepout
			(tracks not_allowed)
			(vias allowed)
			(pads allowed)
			(copperpour not_allowed)
			(footprints allowed)
		)
		(placement
			(enabled no)
			(sheetname "")
		)
		(fill
			(thermal_gap 0.5)
			(thermal_bridge_width 0.5)
			(island_removal_mode 0)
		)
		(polygon
			(pts
				(arc
					(start 176.821338 -266.432538)
					(mid 176.817618 -266.441518)
					(end 176.808638 -266.445238)
				)
				(arc
					(start 175.335438 -266.445238)
					(mid 175.326458 -266.441518)
					(end 175.322738 -266.432538)
				)
				(arc
					(start 175.322738 -265.938)
					(mid 175.326458 -265.92902)
					(end 175.335438 -265.9253)
				)
				(arc
					(start 176.808638 -265.9253)
					(mid 176.817618 -265.92902)
					(end 176.821338 -265.938)
				)
			)
		)
	)
	(zone
		(layer "In1.Cu")
		(hatch none 0.5)
		(connect_pads
			(clearance 0)
		)
		(min_thickness 0.25)
		(keepout
			(tracks not_allowed)
			(vias allowed)
			(pads allowed)
			(copperpour not_allowed)
			(footprints allowed)
		)
		(placement
			(enabled no)
			(sheetname "")
		)
		(fill
			(thermal_gap 0.5)
			(thermal_bridge_width 0.5)
			(island_removal_mode 0)
		)
		(polygon
			(pts
				(arc
					(start 48.770286 -383.92227)
					(mid 48.465486 -383.92227)
					(end 48.770286 -383.92227)
				)
			)
		)
	)
	(zone
		(layer "In1.Cu")
		(hatch none 0.5)
		(connect_pads
			(clearance 0)
		)
		(min_thickness 0.25)
		(keepout
			(tracks not_allowed)
			(vias allowed)
			(pads allowed)
			(copperpour not_allowed)
			(footprints allowed)
		)
		(placement
			(enabled no)
			(sheetname "")
		)
		(fill
			(thermal_gap 0.5)
			(thermal_bridge_width 0.5)
			(island_removal_mode 0)
		)
		(polygon
			(pts
				(arc
					(start 165.177216 -279.182576)
					(mid 165.173496 -279.191556)
					(end 165.164516 -279.195276)
				)
				(arc
					(start 163.691316 -279.195276)
					(mid 163.682336 -279.191556)
					(end 163.678616 -279.182576)
				)
				(arc
					(start 163.678616 -278.688038)
					(mid 163.682336 -278.679058)
					(end 163.691316 -278.675338)
				)
				(arc
					(start 165.164516 -278.675338)
					(mid 165.173496 -278.679058)
					(end 165.177216 -278.688038)
				)
			)
		)
	)
	(zone
		(layer "In1.Cu")
		(hatch none 0.5)
		(connect_pads
			(clearance 0)
		)
		(min_thickness 0.25)
		(keepout
			(tracks not_allowed)
			(vias allowed)
			(pads allowed)
			(copperpour not_allowed)
			(footprints allowed)
		)
		(placement
			(enabled no)
			(sheetname "")
		)
		(fill
			(thermal_gap 0.5)
			(thermal_bridge_width 0.5)
			(island_removal_mode 0)
		)
		(polygon
			(pts
				(arc
					(start 417.217352 -220.532198)
					(mid 417.213632 -220.541178)
					(end 417.204652 -220.544898)
				)
				(arc
					(start 415.731452 -220.544898)
					(mid 415.722472 -220.541178)
					(end 415.718752 -220.532198)
				)
				(arc
					(start 415.718752 -220.03766)
					(mid 415.722472 -220.02868)
					(end 415.731452 -220.02496)
				)
				(arc
					(start 417.204652 -220.02496)
					(mid 417.213632 -220.02868)
					(end 417.217352 -220.03766)
				)
			)
		)
	)
	(zone
		(layer "In1.Cu")
		(hatch none 0.5)
		(connect_pads
			(clearance 0)
		)
		(min_thickness 0.25)
		(keepout
			(tracks not_allowed)
			(vias allowed)
			(pads allowed)
			(copperpour not_allowed)
			(footprints allowed)
		)
		(placement
			(enabled no)
			(sheetname "")
		)
		(fill
			(thermal_gap 0.5)
			(thermal_bridge_width 0.5)
			(island_removal_mode 0)
		)
		(polygon
			(pts
				(arc
					(start 165.177216 -288.53257)
					(mid 165.173496 -288.54155)
					(end 165.164516 -288.54527)
				)
				(arc
					(start 163.691316 -288.54527)
					(mid 163.682336 -288.54155)
					(end 163.678616 -288.53257)
				)
				(arc
					(start 163.678616 -288.038032)
					(mid 163.682336 -288.029052)
					(end 163.691316 -288.025332)
				)
				(arc
					(start 165.164516 -288.025332)
					(mid 165.173496 -288.029052)
					(end 165.177216 -288.038032)
				)
			)
		)
	)
	(zone
		(layer "In1.Cu")
		(hatch none 0.5)
		(connect_pads
			(clearance 0)
		)
		(min_thickness 0.25)
		(keepout
			(tracks not_allowed)
			(vias allowed)
			(pads allowed)
			(copperpour not_allowed)
			(footprints allowed)
		)
		(placement
			(enabled no)
			(sheetname "")
		)
		(fill
			(thermal_gap 0.5)
			(thermal_bridge_width 0.5)
			(island_removal_mode 0)
		)
		(polygon
			(pts
				(arc
					(start 45.089318 -313.182508)
					(mid 45.085598 -313.191488)
					(end 45.076618 -313.195208)
				)
				(arc
					(start 43.603418 -313.195208)
					(mid 43.594438 -313.191488)
					(end 43.590718 -313.182508)
				)
				(arc
					(start 43.590718 -312.68797)
					(mid 43.594438 -312.67899)
					(end 43.603418 -312.67527)
				)
				(arc
					(start 45.076618 -312.67527)
					(mid 45.085598 -312.67899)
					(end 45.089318 -312.68797)
				)
			)
		)
	)
	(zone
		(layer "In1.Cu")
		(hatch none 0.5)
		(connect_pads
			(clearance 0)
		)
		(min_thickness 0.25)
		(keepout
			(tracks not_allowed)
			(vias allowed)
			(pads allowed)
			(copperpour not_allowed)
			(footprints allowed)
		)
		(placement
			(enabled no)
			(sheetname "")
		)
		(fill
			(thermal_gap 0.5)
			(thermal_bridge_width 0.5)
			(island_removal_mode 0)
		)
		(polygon
			(pts
				(arc
					(start 273.841464 -226.482148)
					(mid 273.837744 -226.491128)
					(end 273.828764 -226.494848)
				)
				(arc
					(start 272.355564 -226.494848)
					(mid 272.346584 -226.491128)
					(end 272.342864 -226.482148)
				)
				(arc
					(start 272.342864 -225.98761)
					(mid 272.346584 -225.97863)
					(end 272.355564 -225.97491)
				)
				(arc
					(start 273.828764 -225.97491)
					(mid 273.837744 -225.97863)
					(end 273.841464 -225.98761)
				)
			)
		)
	)
	(zone
		(layer "In1.Cu")
		(hatch none 0.5)
		(connect_pads
			(clearance 0)
		)
		(min_thickness 0.25)
		(keepout
			(tracks not_allowed)
			(vias allowed)
			(pads allowed)
			(copperpour not_allowed)
			(footprints allowed)
		)
		(placement
			(enabled no)
			(sheetname "")
		)
		(fill
			(thermal_gap 0.5)
			(thermal_bridge_width 0.5)
			(island_removal_mode 0)
		)
		(polygon
			(pts
				(arc
					(start 40.98925 -262.182356)
					(mid 40.98553 -262.191336)
					(end 40.97655 -262.195056)
				)
				(arc
					(start 39.50335 -262.195056)
					(mid 39.49437 -262.191336)
					(end 39.49065 -262.182356)
				)
				(arc
					(start 39.49065 -261.687818)
					(mid 39.49437 -261.678838)
					(end 39.50335 -261.675118)
				)
				(arc
					(start 40.97655 -261.675118)
					(mid 40.98553 -261.678838)
					(end 40.98925 -261.687818)
				)
			)
		)
	)
	(zone
		(layer "In1.Cu")
		(hatch none 0.5)
		(connect_pads
			(clearance 0)
		)
		(min_thickness 0.25)
		(keepout
			(tracks not_allowed)
			(vias allowed)
			(pads allowed)
			(copperpour not_allowed)
			(footprints allowed)
		)
		(placement
			(enabled no)
			(sheetname "")
		)
		(fill
			(thermal_gap 0.5)
			(thermal_bridge_width 0.5)
			(island_removal_mode 0)
		)
		(polygon
			(pts
				(arc
					(start 165.177216 -316.582552)
					(mid 165.173496 -316.591532)
					(end 165.164516 -316.595252)
				)
				(arc
					(start 163.691316 -316.595252)
					(mid 163.682336 -316.591532)
					(end 163.678616 -316.582552)
				)
				(arc
					(start 163.678616 -316.088014)
					(mid 163.682336 -316.079034)
					(end 163.691316 -316.075314)
				)
				(arc
					(start 165.164516 -316.075314)
					(mid 165.173496 -316.079034)
					(end 165.177216 -316.088014)
				)
			)
		)
	)
	(zone
		(layer "In1.Cu")
		(hatch none 0.5)
		(connect_pads
			(clearance 0)
		)
		(min_thickness 0.25)
		(keepout
			(tracks not_allowed)
			(vias allowed)
			(pads allowed)
			(copperpour not_allowed)
			(footprints allowed)
		)
		(placement
			(enabled no)
			(sheetname "")
		)
		(fill
			(thermal_gap 0.5)
			(thermal_bridge_width 0.5)
			(island_removal_mode 0)
		)
		(polygon
			(pts
				(arc
					(start 420.661338 -274.93214)
					(mid 420.657618 -274.94112)
					(end 420.648638 -274.94484)
				)
				(arc
					(start 419.175438 -274.94484)
					(mid 419.166458 -274.94112)
					(end 419.162738 -274.93214)
				)
				(arc
					(start 419.162738 -274.437602)
					(mid 419.166458 -274.428622)
					(end 419.175438 -274.424902)
				)
				(arc
					(start 420.648638 -274.424902)
					(mid 420.657618 -274.428622)
					(end 420.661338 -274.437602)
				)
			)
		)
	)
	(zone
		(layer "In1.Cu")
		(hatch none 0.5)
		(connect_pads
			(clearance 0)
		)
		(min_thickness 0.25)
		(keepout
			(tracks not_allowed)
			(vias allowed)
			(pads allowed)
			(copperpour not_allowed)
			(footprints allowed)
		)
		(placement
			(enabled no)
			(sheetname "")
		)
		(fill
			(thermal_gap 0.5)
			(thermal_bridge_width 0.5)
			(island_removal_mode 0)
		)
		(polygon
			(pts
				(arc
					(start 300.57344 -208.632298)
					(mid 300.56972 -208.641278)
					(end 300.56074 -208.644998)
				)
				(arc
					(start 299.08754 -208.644998)
					(mid 299.07856 -208.641278)
					(end 299.07484 -208.632298)
				)
				(arc
					(start 299.07484 -208.13776)
					(mid 299.07856 -208.12878)
					(end 299.08754 -208.12506)
				)
				(arc
					(start 300.56074 -208.12506)
					(mid 300.56972 -208.12878)
					(end 300.57344 -208.13776)
				)
			)
		)
	)
	(zone
		(layer "In1.Cu")
		(hatch none 0.5)
		(connect_pads
			(clearance 0)
		)
		(min_thickness 0.25)
		(keepout
			(tracks not_allowed)
			(vias allowed)
			(pads allowed)
			(copperpour not_allowed)
			(footprints allowed)
		)
		(placement
			(enabled no)
			(sheetname "")
		)
		(fill
			(thermal_gap 0.5)
			(thermal_bridge_width 0.5)
			(island_removal_mode 0)
		)
		(polygon
			(pts
				(arc
					(start 340.897972 -399.143474)
					(mid 340.593172 -399.143474)
					(end 340.897972 -399.143474)
				)
			)
		)
	)
	(zone
		(layer "In1.Cu")
		(hatch none 0.5)
		(connect_pads
			(clearance 0)
		)
		(min_thickness 0.25)
		(keepout
			(tracks not_allowed)
			(vias allowed)
			(pads allowed)
			(copperpour not_allowed)
			(footprints allowed)
		)
		(placement
			(enabled no)
			(sheetname "")
		)
		(fill
			(thermal_gap 0.5)
			(thermal_bridge_width 0.5)
			(island_removal_mode 0)
		)
		(polygon
			(pts
				(arc
					(start 424.761406 -314.032138)
					(mid 424.757686 -314.041118)
					(end 424.748706 -314.044838)
				)
				(arc
					(start 423.275506 -314.044838)
					(mid 423.266526 -314.041118)
					(end 423.262806 -314.032138)
				)
				(arc
					(start 423.262806 -313.5376)
					(mid 423.266526 -313.52862)
					(end 423.275506 -313.5249)
				)
				(arc
					(start 424.748706 -313.5249)
					(mid 424.757686 -313.52862)
					(end 424.761406 -313.5376)
				)
			)
		)
	)
	(zone
		(layer "In1.Cu")
		(hatch none 0.5)
		(connect_pads
			(clearance 0)
		)
		(min_thickness 0.25)
		(keepout
			(tracks not_allowed)
			(vias allowed)
			(pads allowed)
			(copperpour not_allowed)
			(footprints allowed)
		)
		(placement
			(enabled no)
			(sheetname "")
		)
		(fill
			(thermal_gap 0.5)
			(thermal_bridge_width 0.5)
			(island_removal_mode 0)
		)
		(polygon
			(pts
				(arc
					(start 432.30546 -280.032206)
					(mid 432.30174 -280.041186)
					(end 432.29276 -280.044906)
				)
				(arc
					(start 430.81956 -280.044906)
					(mid 430.81058 -280.041186)
					(end 430.80686 -280.032206)
				)
				(arc
					(start 430.80686 -279.537668)
					(mid 430.81058 -279.528688)
					(end 430.81956 -279.524968)
				)
				(arc
					(start 432.29276 -279.524968)
					(mid 432.30174 -279.528688)
					(end 432.30546 -279.537668)
				)
			)
		)
	)
	(zone
		(layer "In1.Cu")
		(hatch none 0.5)
		(connect_pads
			(clearance 0)
		)
		(min_thickness 0.25)
		(keepout
			(tracks not_allowed)
			(vias allowed)
			(pads allowed)
			(copperpour not_allowed)
			(footprints allowed)
		)
		(placement
			(enabled no)
			(sheetname "")
		)
		(fill
			(thermal_gap 0.5)
			(thermal_bridge_width 0.5)
			(island_removal_mode 0)
		)
		(polygon
			(pts
				(arc
					(start 195.353432 -217.132408)
					(mid 195.349712 -217.141388)
					(end 195.340732 -217.145108)
				)
				(arc
					(start 193.867532 -217.145108)
					(mid 193.858552 -217.141388)
					(end 193.854832 -217.132408)
				)
				(arc
					(start 193.854832 -216.63787)
					(mid 193.858552 -216.62889)
					(end 193.867532 -216.62517)
				)
				(arc
					(start 195.340732 -216.62517)
					(mid 195.349712 -216.62889)
					(end 195.353432 -216.63787)
				)
			)
		)
	)
	(zone
		(layer "In1.Cu")
		(hatch none 0.5)
		(connect_pads
			(clearance 0)
		)
		(min_thickness 0.25)
		(keepout
			(tracks not_allowed)
			(vias allowed)
			(pads allowed)
			(copperpour not_allowed)
			(footprints allowed)
		)
		(placement
			(enabled no)
			(sheetname "")
		)
		(fill
			(thermal_gap 0.5)
			(thermal_bridge_width 0.5)
			(island_removal_mode 0)
		)
		(polygon
			(pts
				(arc
					(start 33.445196 -279.182576)
					(mid 33.441476 -279.191556)
					(end 33.432496 -279.195276)
				)
				(arc
					(start 31.959296 -279.195276)
					(mid 31.950316 -279.191556)
					(end 31.946596 -279.182576)
				)
				(arc
					(start 31.946596 -278.688038)
					(mid 31.950316 -278.679058)
					(end 31.959296 -278.675338)
				)
				(arc
					(start 33.432496 -278.675338)
					(mid 33.441476 -278.679058)
					(end 33.445196 -278.688038)
				)
			)
		)
	)
	(zone
		(layer "In1.Cu")
		(hatch none 0.5)
		(connect_pads
			(clearance 0)
		)
		(min_thickness 0.25)
		(keepout
			(tracks not_allowed)
			(vias allowed)
			(pads allowed)
			(copperpour not_allowed)
			(footprints allowed)
		)
		(placement
			(enabled no)
			(sheetname "")
		)
		(fill
			(thermal_gap 0.5)
			(thermal_bridge_width 0.5)
			(island_removal_mode 0)
		)
		(polygon
			(pts
				(arc
					(start 52.633372 -280.03246)
					(mid 52.629652 -280.04144)
					(end 52.620672 -280.04516)
				)
				(arc
					(start 51.147472 -280.04516)
					(mid 51.138492 -280.04144)
					(end 51.134772 -280.03246)
				)
				(arc
					(start 51.134772 -279.537922)
					(mid 51.138492 -279.528942)
					(end 51.147472 -279.525222)
				)
				(arc
					(start 52.620672 -279.525222)
					(mid 52.629652 -279.528942)
					(end 52.633372 -279.537922)
				)
			)
		)
	)
	(zone
		(layer "In1.Cu")
		(hatch none 0.5)
		(connect_pads
			(clearance 0)
		)
		(min_thickness 0.25)
		(keepout
			(tracks not_allowed)
			(vias allowed)
			(pads allowed)
			(copperpour not_allowed)
			(footprints allowed)
		)
		(placement
			(enabled no)
			(sheetname "")
		)
		(fill
			(thermal_gap 0.5)
			(thermal_bridge_width 0.5)
			(island_removal_mode 0)
		)
		(polygon
			(pts
				(arc
					(start 33.445196 -276.632416)
					(mid 33.441476 -276.641396)
					(end 33.432496 -276.645116)
				)
				(arc
					(start 31.959296 -276.645116)
					(mid 31.950316 -276.641396)
					(end 31.946596 -276.632416)
				)
				(arc
					(start 31.946596 -276.137878)
					(mid 31.950316 -276.128898)
					(end 31.959296 -276.125178)
				)
				(arc
					(start 33.432496 -276.125178)
					(mid 33.441476 -276.128898)
					(end 33.445196 -276.137878)
				)
			)
		)
	)
	(zone
		(layer "In1.Cu")
		(hatch none 0.5)
		(connect_pads
			(clearance 0)
		)
		(min_thickness 0.25)
		(keepout
			(tracks not_allowed)
			(vias allowed)
			(pads allowed)
			(copperpour not_allowed)
			(footprints allowed)
		)
		(placement
			(enabled no)
			(sheetname "")
		)
		(fill
			(thermal_gap 0.5)
			(thermal_bridge_width 0.5)
			(island_removal_mode 0)
		)
		(polygon
			(pts
				(arc
					(start 184.365392 -219.682568)
					(mid 184.361672 -219.691548)
					(end 184.352692 -219.695268)
				)
				(arc
					(start 182.879492 -219.695268)
					(mid 182.870512 -219.691548)
					(end 182.866792 -219.682568)
				)
				(arc
					(start 182.866792 -219.18803)
					(mid 182.870512 -219.17905)
					(end 182.879492 -219.17533)
				)
				(arc
					(start 184.352692 -219.17533)
					(mid 184.361672 -219.17905)
					(end 184.365392 -219.18803)
				)
			)
		)
	)
	(zone
		(layer "In1.Cu")
		(hatch none 0.5)
		(connect_pads
			(clearance 0)
		)
		(min_thickness 0.25)
		(keepout
			(tracks not_allowed)
			(vias allowed)
			(pads allowed)
			(copperpour not_allowed)
			(footprints allowed)
		)
		(placement
			(enabled no)
			(sheetname "")
		)
		(fill
			(thermal_gap 0.5)
			(thermal_bridge_width 0.5)
			(island_removal_mode 0)
		)
		(polygon
			(pts
				(arc
					(start 165.177216 -293.632382)
					(mid 165.173496 -293.641362)
					(end 165.164516 -293.645082)
				)
				(arc
					(start 163.691316 -293.645082)
					(mid 163.682336 -293.641362)
					(end 163.678616 -293.632382)
				)
				(arc
					(start 163.678616 -293.137844)
					(mid 163.682336 -293.128864)
					(end 163.691316 -293.125144)
				)
				(arc
					(start 165.164516 -293.125144)
					(mid 165.173496 -293.128864)
					(end 165.177216 -293.137844)
				)
			)
		)
	)
	(zone
		(layer "In1.Cu")
		(hatch none 0.5)
		(connect_pads
			(clearance 0)
		)
		(min_thickness 0.25)
		(keepout
			(tracks not_allowed)
			(vias allowed)
			(pads allowed)
			(copperpour not_allowed)
			(footprints allowed)
		)
		(placement
			(enabled no)
			(sheetname "")
		)
		(fill
			(thermal_gap 0.5)
			(thermal_bridge_width 0.5)
			(island_removal_mode 0)
		)
		(polygon
			(pts
				(arc
					(start 25.901396 -293.632382)
					(mid 25.897676 -293.641362)
					(end 25.888696 -293.645082)
				)
				(arc
					(start 24.415496 -293.645082)
					(mid 24.406516 -293.641362)
					(end 24.402796 -293.632382)
				)
				(arc
					(start 24.402796 -293.137844)
					(mid 24.406516 -293.128864)
					(end 24.415496 -293.125144)
				)
				(arc
					(start 25.888696 -293.125144)
					(mid 25.897676 -293.128864)
					(end 25.901396 -293.137844)
				)
			)
		)
	)
	(zone
		(layer "In1.Cu")
		(hatch none 0.5)
		(connect_pads
			(clearance 0)
		)
		(min_thickness 0.25)
		(keepout
			(tracks not_allowed)
			(vias allowed)
			(pads allowed)
			(copperpour not_allowed)
			(footprints allowed)
		)
		(placement
			(enabled no)
			(sheetname "")
		)
		(fill
			(thermal_gap 0.5)
			(thermal_bridge_width 0.5)
			(island_removal_mode 0)
		)
		(polygon
			(pts
				(arc
					(start 277.941532 -303.83226)
					(mid 277.937812 -303.84124)
					(end 277.928832 -303.84496)
				)
				(arc
					(start 276.455632 -303.84496)
					(mid 276.446652 -303.84124)
					(end 276.442932 -303.83226)
				)
				(arc
					(start 276.442932 -303.337722)
					(mid 276.446652 -303.328742)
					(end 276.455632 -303.325022)
				)
				(arc
					(start 277.928832 -303.325022)
					(mid 277.937812 -303.328742)
					(end 277.941532 -303.337722)
				)
			)
		)
	)
	(zone
		(layer "In1.Cu")
		(hatch none 0.5)
		(connect_pads
			(clearance 0)
		)
		(min_thickness 0.25)
		(keepout
			(tracks not_allowed)
			(vias allowed)
			(pads allowed)
			(copperpour not_allowed)
			(footprints allowed)
		)
		(placement
			(enabled no)
			(sheetname "")
		)
		(fill
			(thermal_gap 0.5)
			(thermal_bridge_width 0.5)
			(island_removal_mode 0)
		)
		(polygon
			(pts
				(arc
					(start 416.688778 -397.849344)
					(mid 416.307778 -397.849344)
					(end 416.688778 -397.849344)
				)
			)
		)
	)
	(zone
		(layer "In1.Cu")
		(hatch none 0.5)
		(connect_pads
			(clearance 0)
		)
		(min_thickness 0.25)
		(keepout
			(tracks not_allowed)
			(vias allowed)
			(pads allowed)
			(copperpour not_allowed)
			(footprints allowed)
		)
		(placement
			(enabled no)
			(sheetname "")
		)
		(fill
			(thermal_gap 0.5)
			(thermal_bridge_width 0.5)
			(island_removal_mode 0)
		)
		(polygon
			(pts
				(arc
					(start 180.265324 -310.632348)
					(mid 180.261604 -310.641328)
					(end 180.252624 -310.645048)
				)
				(arc
					(start 178.779424 -310.645048)
					(mid 178.770444 -310.641328)
					(end 178.766724 -310.632348)
				)
				(arc
					(start 178.766724 -310.13781)
					(mid 178.770444 -310.12883)
					(end 178.779424 -310.12511)
				)
				(arc
					(start 180.252624 -310.12511)
					(mid 180.261604 -310.12883)
					(end 180.265324 -310.13781)
				)
			)
		)
	)
	(zone
		(layer "In1.Cu")
		(hatch none 0.5)
		(connect_pads
			(clearance 0)
		)
		(min_thickness 0.25)
		(keepout
			(tracks not_allowed)
			(vias allowed)
			(pads allowed)
			(copperpour not_allowed)
			(footprints allowed)
		)
		(placement
			(enabled no)
			(sheetname "")
		)
		(fill
			(thermal_gap 0.5)
			(thermal_bridge_width 0.5)
			(island_removal_mode 0)
		)
		(polygon
			(pts
				(arc
					(start 81.189068 -388.774432)
					(mid 80.808068 -388.774432)
					(end 81.189068 -388.774432)
				)
			)
		)
	)
	(zone
		(layer "In1.Cu")
		(hatch none 0.5)
		(connect_pads
			(clearance 0)
		)
		(min_thickness 0.25)
		(keepout
			(tracks not_allowed)
			(vias allowed)
			(pads allowed)
			(copperpour not_allowed)
			(footprints allowed)
		)
		(placement
			(enabled no)
			(sheetname "")
		)
		(fill
			(thermal_gap 0.5)
			(thermal_bridge_width 0.5)
			(island_removal_mode 0)
		)
		(polygon
			(pts
				(arc
					(start 277.941532 -236.68228)
					(mid 277.937812 -236.69126)
					(end 277.928832 -236.69498)
				)
				(arc
					(start 276.455632 -236.69498)
					(mid 276.446652 -236.69126)
					(end 276.442932 -236.68228)
				)
				(arc
					(start 276.442932 -236.187742)
					(mid 276.446652 -236.178762)
					(end 276.455632 -236.175042)
				)
				(arc
					(start 277.928832 -236.175042)
					(mid 277.937812 -236.178762)
					(end 277.941532 -236.187742)
				)
			)
		)
	)
	(zone
		(layer "In1.Cu")
		(hatch none 0.5)
		(connect_pads
			(clearance 0)
		)
		(min_thickness 0.25)
		(keepout
			(tracks not_allowed)
			(vias allowed)
			(pads allowed)
			(copperpour not_allowed)
			(footprints allowed)
		)
		(placement
			(enabled no)
			(sheetname "")
		)
		(fill
			(thermal_gap 0.5)
			(thermal_bridge_width 0.5)
			(island_removal_mode 0)
		)
		(polygon
			(pts
				(arc
					(start 277.941532 -249.432318)
					(mid 277.937812 -249.441298)
					(end 277.928832 -249.445018)
				)
				(arc
					(start 276.455632 -249.445018)
					(mid 276.446652 -249.441298)
					(end 276.442932 -249.432318)
				)
				(arc
					(start 276.442932 -248.93778)
					(mid 276.446652 -248.9288)
					(end 276.455632 -248.92508)
				)
				(arc
					(start 277.928832 -248.92508)
					(mid 277.937812 -248.9288)
					(end 277.941532 -248.93778)
				)
			)
		)
	)
	(zone
		(layer "In1.Cu")
		(hatch none 0.5)
		(connect_pads
			(clearance 0)
		)
		(min_thickness 0.25)
		(keepout
			(tracks not_allowed)
			(vias allowed)
			(pads allowed)
			(copperpour not_allowed)
			(footprints allowed)
		)
		(placement
			(enabled no)
			(sheetname "")
		)
		(fill
			(thermal_gap 0.5)
			(thermal_bridge_width 0.5)
			(island_removal_mode 0)
		)
		(polygon
			(pts
				(arc
					(start 206.9973 -315.732414)
					(mid 206.99358 -315.741394)
					(end 206.9846 -315.745114)
				)
				(arc
					(start 205.5114 -315.745114)
					(mid 205.50242 -315.741394)
					(end 205.4987 -315.732414)
				)
				(arc
					(start 205.4987 -315.237876)
					(mid 205.50242 -315.228896)
					(end 205.5114 -315.225176)
				)
				(arc
					(start 206.9846 -315.225176)
					(mid 206.99358 -315.228896)
					(end 206.9973 -315.237876)
				)
			)
		)
	)
	(zone
		(layer "In1.Cu")
		(hatch none 0.5)
		(connect_pads
			(clearance 0)
		)
		(min_thickness 0.25)
		(keepout
			(tracks not_allowed)
			(vias allowed)
			(pads allowed)
			(copperpour not_allowed)
			(footprints allowed)
		)
		(placement
			(enabled no)
			(sheetname "")
		)
		(fill
			(thermal_gap 0.5)
			(thermal_bridge_width 0.5)
			(island_removal_mode 0)
		)
		(polygon
			(pts
				(arc
					(start 270.397478 -294.482266)
					(mid 270.393758 -294.491246)
					(end 270.384778 -294.494966)
				)
				(arc
					(start 268.911578 -294.494966)
					(mid 268.902598 -294.491246)
					(end 268.898878 -294.482266)
				)
				(arc
					(start 268.898878 -293.987728)
					(mid 268.902598 -293.978748)
					(end 268.911578 -293.975028)
				)
				(arc
					(start 270.384778 -293.975028)
					(mid 270.393758 -293.978748)
					(end 270.397478 -293.987728)
				)
			)
		)
	)
	(zone
		(layer "In1.Cu")
		(hatch none 0.5)
		(connect_pads
			(clearance 0)
		)
		(min_thickness 0.25)
		(keepout
			(tracks not_allowed)
			(vias allowed)
			(pads allowed)
			(copperpour not_allowed)
			(footprints allowed)
		)
		(placement
			(enabled no)
			(sheetname "")
		)
		(fill
			(thermal_gap 0.5)
			(thermal_bridge_width 0.5)
			(island_removal_mode 0)
		)
		(polygon
			(pts
				(arc
					(start 420.661338 -201.83221)
					(mid 420.657618 -201.84119)
					(end 420.648638 -201.84491)
				)
				(arc
					(start 419.175438 -201.84491)
					(mid 419.166458 -201.84119)
					(end 419.162738 -201.83221)
				)
				(arc
					(start 419.162738 -201.337672)
					(mid 419.166458 -201.328692)
					(end 419.175438 -201.324972)
				)
				(arc
					(start 420.648638 -201.324972)
					(mid 420.657618 -201.328692)
					(end 420.661338 -201.337672)
				)
			)
		)
	)
	(zone
		(layer "In1.Cu")
		(hatch none 0.5)
		(connect_pads
			(clearance 0)
		)
		(min_thickness 0.25)
		(keepout
			(tracks not_allowed)
			(vias allowed)
			(pads allowed)
			(copperpour not_allowed)
			(footprints allowed)
		)
		(placement
			(enabled no)
			(sheetname "")
		)
		(fill
			(thermal_gap 0.5)
			(thermal_bridge_width 0.5)
			(island_removal_mode 0)
		)
		(polygon
			(pts
				(arc
					(start 265.87831 -220.285056)
					(mid 265.21791 -220.285056)
					(end 265.87831 -220.285056)
				)
			)
		)
	)
	(zone
		(layer "In1.Cu")
		(hatch none 0.5)
		(connect_pads
			(clearance 0)
		)
		(min_thickness 0.25)
		(keepout
			(tracks not_allowed)
			(vias allowed)
			(pads allowed)
			(copperpour not_allowed)
			(footprints allowed)
		)
		(placement
			(enabled no)
			(sheetname "")
		)
		(fill
			(thermal_gap 0.5)
			(thermal_bridge_width 0.5)
			(island_removal_mode 0)
		)
		(polygon
			(pts
				(arc
					(start 169.277284 -314.032392)
					(mid 169.273564 -314.041372)
					(end 169.264584 -314.045092)
				)
				(arc
					(start 167.791384 -314.045092)
					(mid 167.782404 -314.041372)
					(end 167.778684 -314.032392)
				)
				(arc
					(start 167.778684 -313.537854)
					(mid 167.782404 -313.528874)
					(end 167.791384 -313.525154)
				)
				(arc
					(start 169.264584 -313.525154)
					(mid 169.273564 -313.528874)
					(end 169.277284 -313.537854)
				)
			)
		)
	)
	(zone
		(layer "In1.Cu")
		(hatch none 0.5)
		(connect_pads
			(clearance 0)
		)
		(min_thickness 0.25)
		(keepout
			(tracks not_allowed)
			(vias allowed)
			(pads allowed)
			(copperpour not_allowed)
			(footprints allowed)
		)
		(placement
			(enabled no)
			(sheetname "")
		)
		(fill
			(thermal_gap 0.5)
			(thermal_bridge_width 0.5)
			(island_removal_mode 0)
		)
		(polygon
			(pts
				(arc
					(start 432.30546 -242.63223)
					(mid 432.30174 -242.64121)
					(end 432.29276 -242.64493)
				)
				(arc
					(start 430.81956 -242.64493)
					(mid 430.81058 -242.64121)
					(end 430.80686 -242.63223)
				)
				(arc
					(start 430.80686 -242.137692)
					(mid 430.81058 -242.128712)
					(end 430.81956 -242.124992)
				)
				(arc
					(start 432.29276 -242.124992)
					(mid 432.30174 -242.128712)
					(end 432.30546 -242.137692)
				)
			)
		)
	)
	(zone
		(layer "In1.Cu")
		(hatch none 0.5)
		(connect_pads
			(clearance 0)
		)
		(min_thickness 0.25)
		(keepout
			(tracks not_allowed)
			(vias allowed)
			(pads allowed)
			(copperpour not_allowed)
			(footprints allowed)
		)
		(placement
			(enabled no)
			(sheetname "")
		)
		(fill
			(thermal_gap 0.5)
			(thermal_bridge_width 0.5)
			(island_removal_mode 0)
		)
		(polygon
			(pts
				(arc
					(start 285.485332 -200.982326)
					(mid 285.481612 -200.991306)
					(end 285.472632 -200.995026)
				)
				(arc
					(start 283.999432 -200.995026)
					(mid 283.990452 -200.991306)
					(end 283.986732 -200.982326)
				)
				(arc
					(start 283.986732 -200.487788)
					(mid 283.990452 -200.478808)
					(end 283.999432 -200.475088)
				)
				(arc
					(start 285.472632 -200.475088)
					(mid 285.481612 -200.478808)
					(end 285.485332 -200.487788)
				)
			)
		)
	)
	(zone
		(layer "In1.Cu")
		(hatch none 0.5)
		(connect_pads
			(clearance 0)
		)
		(min_thickness 0.25)
		(keepout
			(tracks not_allowed)
			(vias allowed)
			(pads allowed)
			(copperpour not_allowed)
			(footprints allowed)
		)
		(placement
			(enabled no)
			(sheetname "")
		)
		(fill
			(thermal_gap 0.5)
			(thermal_bridge_width 0.5)
			(island_removal_mode 0)
		)
		(polygon
			(pts
				(arc
					(start 176.821338 -303.832514)
					(mid 176.817618 -303.841494)
					(end 176.808638 -303.845214)
				)
				(arc
					(start 175.335438 -303.845214)
					(mid 175.326458 -303.841494)
					(end 175.322738 -303.832514)
				)
				(arc
					(start 175.322738 -303.337976)
					(mid 175.326458 -303.328996)
					(end 175.335438 -303.325276)
				)
				(arc
					(start 176.808638 -303.325276)
					(mid 176.817618 -303.328996)
					(end 176.821338 -303.337976)
				)
			)
		)
	)
	(zone
		(layer "In1.Cu")
		(hatch none 0.5)
		(connect_pads
			(clearance 0)
		)
		(min_thickness 0.25)
		(keepout
			(tracks not_allowed)
			(vias allowed)
			(pads allowed)
			(copperpour not_allowed)
			(footprints allowed)
		)
		(placement
			(enabled no)
			(sheetname "")
		)
		(fill
			(thermal_gap 0.5)
			(thermal_bridge_width 0.5)
			(island_removal_mode 0)
		)
		(polygon
			(pts
				(arc
					(start 30.001464 -275.782532)
					(mid 29.997744 -275.791512)
					(end 29.988764 -275.795232)
				)
				(arc
					(start 28.515564 -275.795232)
					(mid 28.506584 -275.791512)
					(end 28.502864 -275.782532)
				)
				(arc
					(start 28.502864 -275.287994)
					(mid 28.506584 -275.279014)
					(end 28.515564 -275.275294)
				)
				(arc
					(start 29.988764 -275.275294)
					(mid 29.997744 -275.279014)
					(end 30.001464 -275.287994)
				)
			)
		)
	)
	(zone
		(layer "In1.Cu")
		(hatch none 0.5)
		(connect_pads
			(clearance 0)
		)
		(min_thickness 0.25)
		(keepout
			(tracks not_allowed)
			(vias allowed)
			(pads allowed)
			(copperpour not_allowed)
			(footprints allowed)
		)
		(placement
			(enabled no)
			(sheetname "")
		)
		(fill
			(thermal_gap 0.5)
			(thermal_bridge_width 0.5)
			(island_removal_mode 0)
		)
		(polygon
			(pts
				(arc
					(start 337.297776 -399.143474)
					(mid 336.992976 -399.143474)
					(end 337.297776 -399.143474)
				)
			)
		)
	)
	(zone
		(layer "In1.Cu")
		(hatch none 0.5)
		(connect_pads
			(clearance 0)
		)
		(min_thickness 0.25)
		(keepout
			(tracks not_allowed)
			(vias allowed)
			(pads allowed)
			(copperpour not_allowed)
			(footprints allowed)
		)
		(placement
			(enabled no)
			(sheetname "")
		)
		(fill
			(thermal_gap 0.5)
			(thermal_bridge_width 0.5)
			(island_removal_mode 0)
		)
		(polygon
			(pts
				(arc
					(start 191.909446 -205.232508)
					(mid 191.905726 -205.241488)
					(end 191.896746 -205.245208)
				)
				(arc
					(start 190.423546 -205.245208)
					(mid 190.414566 -205.241488)
					(end 190.410846 -205.232508)
				)
				(arc
					(start 190.410846 -204.73797)
					(mid 190.414566 -204.72899)
					(end 190.423546 -204.72527)
				)
				(arc
					(start 191.896746 -204.72527)
					(mid 191.905726 -204.72899)
					(end 191.909446 -204.73797)
				)
			)
		)
	)
	(zone
		(layer "In1.Cu")
		(hatch none 0.5)
		(connect_pads
			(clearance 0)
		)
		(min_thickness 0.25)
		(keepout
			(tracks not_allowed)
			(vias allowed)
			(pads allowed)
			(copperpour not_allowed)
			(footprints allowed)
		)
		(placement
			(enabled no)
			(sheetname "")
		)
		(fill
			(thermal_gap 0.5)
			(thermal_bridge_width 0.5)
			(island_removal_mode 0)
		)
		(polygon
			(pts
				(arc
					(start 57.061354 -388.774432)
					(mid 56.680354 -388.774432)
					(end 57.061354 -388.774432)
				)
			)
		)
	)
	(zone
		(layer "In1.Cu")
		(hatch none 0.5)
		(connect_pads
			(clearance 0)
		)
		(min_thickness 0.25)
		(keepout
			(tracks not_allowed)
			(vias allowed)
			(pads allowed)
			(copperpour not_allowed)
			(footprints allowed)
		)
		(placement
			(enabled no)
			(sheetname "")
		)
		(fill
			(thermal_gap 0.5)
			(thermal_bridge_width 0.5)
			(island_removal_mode 0)
		)
		(polygon
			(pts
				(arc
					(start 413.117284 -224.782126)
					(mid 413.113564 -224.791106)
					(end 413.104584 -224.794826)
				)
				(arc
					(start 411.631384 -224.794826)
					(mid 411.622404 -224.791106)
					(end 411.618684 -224.782126)
				)
				(arc
					(start 411.618684 -224.287588)
					(mid 411.622404 -224.278608)
					(end 411.631384 -224.274888)
				)
				(arc
					(start 413.104584 -224.274888)
					(mid 413.113564 -224.278608)
					(end 413.117284 -224.287588)
				)
			)
		)
	)
	(zone
		(layer "In1.Cu")
		(hatch none 0.5)
		(connect_pads
			(clearance 0)
		)
		(min_thickness 0.25)
		(keepout
			(tracks not_allowed)
			(vias allowed)
			(pads allowed)
			(copperpour not_allowed)
			(footprints allowed)
		)
		(placement
			(enabled no)
			(sheetname "")
		)
		(fill
			(thermal_gap 0.5)
			(thermal_bridge_width 0.5)
			(island_removal_mode 0)
		)
		(polygon
			(pts
				(arc
					(start 288.929318 -234.13212)
					(mid 288.925598 -234.1411)
					(end 288.916618 -234.14482)
				)
				(arc
					(start 287.443418 -234.14482)
					(mid 287.434438 -234.1411)
					(end 287.430718 -234.13212)
				)
				(arc
					(start 287.430718 -233.637582)
					(mid 287.434438 -233.628602)
					(end 287.443418 -233.624882)
				)
				(arc
					(start 288.916618 -233.624882)
					(mid 288.925598 -233.628602)
					(end 288.929318 -233.637582)
				)
			)
		)
	)
	(zone
		(layer "In1.Cu")
		(hatch none 0.5)
		(connect_pads
			(clearance 0)
		)
		(min_thickness 0.25)
		(keepout
			(tracks not_allowed)
			(vias allowed)
			(pads allowed)
			(copperpour not_allowed)
			(footprints allowed)
		)
		(placement
			(enabled no)
			(sheetname "")
		)
		(fill
			(thermal_gap 0.5)
			(thermal_bridge_width 0.5)
			(island_removal_mode 0)
		)
		(polygon
			(pts
				(arc
					(start 428.205392 -274.93214)
					(mid 428.201672 -274.94112)
					(end 428.192692 -274.94484)
				)
				(arc
					(start 426.719492 -274.94484)
					(mid 426.710512 -274.94112)
					(end 426.706792 -274.93214)
				)
				(arc
					(start 426.706792 -274.437602)
					(mid 426.710512 -274.428622)
					(end 426.719492 -274.424902)
				)
				(arc
					(start 428.192692 -274.424902)
					(mid 428.201672 -274.428622)
					(end 428.205392 -274.437602)
				)
			)
		)
	)
	(zone
		(layer "In1.Cu")
		(hatch none 0.5)
		(connect_pads
			(clearance 0)
		)
		(min_thickness 0.25)
		(keepout
			(tracks not_allowed)
			(vias allowed)
			(pads allowed)
			(copperpour not_allowed)
			(footprints allowed)
		)
		(placement
			(enabled no)
			(sheetname "")
		)
		(fill
			(thermal_gap 0.5)
			(thermal_bridge_width 0.5)
			(island_removal_mode 0)
		)
		(polygon
			(pts
				(arc
					(start 374.891046 -391.822686)
					(mid 375.018046 -391.949686)
					(end 375.145046 -391.822686)
				)
				(arc
					(start 375.145046 -391.746486)
					(mid 375.018046 -391.619486)
					(end 374.891046 -391.746486)
				)
			)
		)
	)
	(zone
		(layer "In1.Cu")
		(hatch none 0.5)
		(connect_pads
			(clearance 0)
		)
		(min_thickness 0.25)
		(keepout
			(tracks not_allowed)
			(vias allowed)
			(pads allowed)
			(copperpour not_allowed)
			(footprints allowed)
		)
		(placement
			(enabled no)
			(sheetname "")
		)
		(fill
			(thermal_gap 0.5)
			(thermal_bridge_width 0.5)
			(island_removal_mode 0)
		)
		(polygon
			(pts
				(arc
					(start 48.533304 -237.532418)
					(mid 48.529584 -237.541398)
					(end 48.520604 -237.545118)
				)
				(arc
					(start 47.047404 -237.545118)
					(mid 47.038424 -237.541398)
					(end 47.034704 -237.532418)
				)
				(arc
					(start 47.034704 -237.03788)
					(mid 47.038424 -237.0289)
					(end 47.047404 -237.02518)
				)
				(arc
					(start 48.520604 -237.02518)
					(mid 48.529584 -237.0289)
					(end 48.533304 -237.03788)
				)
			)
		)
	)
	(zone
		(layer "In1.Cu")
		(hatch none 0.5)
		(connect_pads
			(clearance 0)
		)
		(min_thickness 0.25)
		(keepout
			(tracks not_allowed)
			(vias allowed)
			(pads allowed)
			(copperpour not_allowed)
			(footprints allowed)
		)
		(placement
			(enabled no)
			(sheetname "")
		)
		(fill
			(thermal_gap 0.5)
			(thermal_bridge_width 0.5)
			(island_removal_mode 0)
		)
		(polygon
			(pts
				(arc
					(start 265.87831 -295.085008)
					(mid 265.21791 -295.085008)
					(end 265.87831 -295.085008)
				)
			)
		)
	)
	(zone
		(layer "In1.Cu")
		(hatch none 0.5)
		(connect_pads
			(clearance 0)
		)
		(min_thickness 0.25)
		(keepout
			(tracks not_allowed)
			(vias allowed)
			(pads allowed)
			(copperpour not_allowed)
			(footprints allowed)
		)
		(placement
			(enabled no)
			(sheetname "")
		)
		(fill
			(thermal_gap 0.5)
			(thermal_bridge_width 0.5)
			(island_removal_mode 0)
		)
		(polygon
			(pts
				(arc
					(start 206.9973 -223.932496)
					(mid 206.99358 -223.941476)
					(end 206.9846 -223.945196)
				)
				(arc
					(start 205.5114 -223.945196)
					(mid 205.50242 -223.941476)
					(end 205.4987 -223.932496)
				)
				(arc
					(start 205.4987 -223.437958)
					(mid 205.50242 -223.428978)
					(end 205.5114 -223.425258)
				)
				(arc
					(start 206.9846 -223.425258)
					(mid 206.99358 -223.428978)
					(end 206.9973 -223.437958)
				)
			)
		)
	)
	(zone
		(layer "In1.Cu")
		(hatch none 0.5)
		(connect_pads
			(clearance 0)
		)
		(min_thickness 0.25)
		(keepout
			(tracks not_allowed)
			(vias allowed)
			(pads allowed)
			(copperpour not_allowed)
			(footprints allowed)
		)
		(placement
			(enabled no)
			(sheetname "")
		)
		(fill
			(thermal_gap 0.5)
			(thermal_bridge_width 0.5)
			(island_removal_mode 0)
		)
		(polygon
			(pts
				(arc
					(start 18.357342 -211.182458)
					(mid 18.353622 -211.191438)
					(end 18.344642 -211.195158)
				)
				(arc
					(start 16.871442 -211.195158)
					(mid 16.862462 -211.191438)
					(end 16.858742 -211.182458)
				)
				(arc
					(start 16.858742 -210.68792)
					(mid 16.862462 -210.67894)
					(end 16.871442 -210.67522)
				)
				(arc
					(start 18.344642 -210.67522)
					(mid 18.353622 -210.67894)
					(end 18.357342 -210.68792)
				)
			)
		)
	)
	(zone
		(layer "In1.Cu")
		(hatch none 0.5)
		(connect_pads
			(clearance 0)
		)
		(min_thickness 0.25)
		(keepout
			(tracks not_allowed)
			(vias allowed)
			(pads allowed)
			(copperpour not_allowed)
			(footprints allowed)
		)
		(placement
			(enabled no)
			(sheetname "")
		)
		(fill
			(thermal_gap 0.5)
			(thermal_bridge_width 0.5)
			(island_removal_mode 0)
		)
		(polygon
			(pts
				(arc
					(start 172.72127 -220.532452)
					(mid 172.71755 -220.541432)
					(end 172.70857 -220.545152)
				)
				(arc
					(start 171.23537 -220.545152)
					(mid 171.22639 -220.541432)
					(end 171.22267 -220.532452)
				)
				(arc
					(start 171.22267 -220.037914)
					(mid 171.22639 -220.028934)
					(end 171.23537 -220.025214)
				)
				(arc
					(start 172.70857 -220.025214)
					(mid 172.71755 -220.028934)
					(end 172.72127 -220.037914)
				)
			)
		)
	)
	(zone
		(layer "In1.Cu")
		(hatch none 0.5)
		(connect_pads
			(clearance 0)
		)
		(min_thickness 0.25)
		(keepout
			(tracks not_allowed)
			(vias allowed)
			(pads allowed)
			(copperpour not_allowed)
			(footprints allowed)
		)
		(placement
			(enabled no)
			(sheetname "")
		)
		(fill
			(thermal_gap 0.5)
			(thermal_bridge_width 0.5)
			(island_removal_mode 0)
		)
		(polygon
			(pts
				(arc
					(start 424.761406 -315.73216)
					(mid 424.757686 -315.74114)
					(end 424.748706 -315.74486)
				)
				(arc
					(start 423.275506 -315.74486)
					(mid 423.266526 -315.74114)
					(end 423.262806 -315.73216)
				)
				(arc
					(start 423.262806 -315.237622)
					(mid 423.266526 -315.228642)
					(end 423.275506 -315.224922)
				)
				(arc
					(start 424.748706 -315.224922)
					(mid 424.757686 -315.228642)
					(end 424.761406 -315.237622)
				)
			)
		)
	)
	(zone
		(layer "In1.Cu")
		(hatch none 0.5)
		(connect_pads
			(clearance 0)
		)
		(min_thickness 0.25)
		(keepout
			(tracks not_allowed)
			(vias allowed)
			(pads allowed)
			(copperpour not_allowed)
			(footprints allowed)
		)
		(placement
			(enabled no)
			(sheetname "")
		)
		(fill
			(thermal_gap 0.5)
			(thermal_bridge_width 0.5)
			(island_removal_mode 0)
		)
		(polygon
			(pts
				(arc
					(start 450.8373 -220.532198)
					(mid 450.83358 -220.541178)
					(end 450.8246 -220.544898)
				)
				(arc
					(start 449.3514 -220.544898)
					(mid 449.34242 -220.541178)
					(end 449.3387 -220.532198)
				)
				(arc
					(start 449.3387 -220.03766)
					(mid 449.34242 -220.02868)
					(end 449.3514 -220.02496)
				)
				(arc
					(start 450.8246 -220.02496)
					(mid 450.83358 -220.02868)
					(end 450.8373 -220.03766)
				)
			)
		)
	)
	(zone
		(layer "In1.Cu")
		(hatch none 0.5)
		(connect_pads
			(clearance 0)
		)
		(min_thickness 0.25)
		(keepout
			(tracks not_allowed)
			(vias allowed)
			(pads allowed)
			(copperpour not_allowed)
			(footprints allowed)
		)
		(placement
			(enabled no)
			(sheetname "")
		)
		(fill
			(thermal_gap 0.5)
			(thermal_bridge_width 0.5)
			(island_removal_mode 0)
		)
		(polygon
			(pts
				(arc
					(start 293.029386 -206.932276)
					(mid 293.025666 -206.941256)
					(end 293.016686 -206.944976)
				)
				(arc
					(start 291.543486 -206.944976)
					(mid 291.534506 -206.941256)
					(end 291.530786 -206.932276)
				)
				(arc
					(start 291.530786 -206.437738)
					(mid 291.534506 -206.428758)
					(end 291.543486 -206.425038)
				)
				(arc
					(start 293.016686 -206.425038)
					(mid 293.025666 -206.428758)
					(end 293.029386 -206.437738)
				)
			)
		)
	)
	(zone
		(layer "In1.Cu")
		(hatch none 0.5)
		(connect_pads
			(clearance 0)
		)
		(min_thickness 0.25)
		(keepout
			(tracks not_allowed)
			(vias allowed)
			(pads allowed)
			(copperpour not_allowed)
			(footprints allowed)
		)
		(placement
			(enabled no)
			(sheetname "")
		)
		(fill
			(thermal_gap 0.5)
			(thermal_bridge_width 0.5)
			(island_removal_mode 0)
		)
		(polygon
			(pts
				(arc
					(start 60.177426 -203.532486)
					(mid 60.173706 -203.541466)
					(end 60.164726 -203.545186)
				)
				(arc
					(start 58.691526 -203.545186)
					(mid 58.682546 -203.541466)
					(end 58.678826 -203.532486)
				)
				(arc
					(start 58.678826 -203.037948)
					(mid 58.682546 -203.028968)
					(end 58.691526 -203.025248)
				)
				(arc
					(start 60.164726 -203.025248)
					(mid 60.173706 -203.028968)
					(end 60.177426 -203.037948)
				)
			)
		)
	)
	(zone
		(layer "In1.Cu")
		(hatch none 0.5)
		(connect_pads
			(clearance 0)
		)
		(min_thickness 0.25)
		(keepout
			(tracks not_allowed)
			(vias allowed)
			(pads allowed)
			(copperpour not_allowed)
			(footprints allowed)
		)
		(placement
			(enabled no)
			(sheetname "")
		)
		(fill
			(thermal_gap 0.5)
			(thermal_bridge_width 0.5)
			(island_removal_mode 0)
		)
		(polygon
			(pts
				(arc
					(start 195.353432 -273.232372)
					(mid 195.349712 -273.241352)
					(end 195.340732 -273.245072)
				)
				(arc
					(start 193.867532 -273.245072)
					(mid 193.858552 -273.241352)
					(end 193.854832 -273.232372)
				)
				(arc
					(start 193.854832 -272.737834)
					(mid 193.858552 -272.728854)
					(end 193.867532 -272.725134)
				)
				(arc
					(start 195.340732 -272.725134)
					(mid 195.349712 -272.728854)
					(end 195.353432 -272.737834)
				)
			)
		)
	)
	(zone
		(layer "In1.Cu")
		(hatch none 0.5)
		(connect_pads
			(clearance 0)
		)
		(min_thickness 0.25)
		(keepout
			(tracks not_allowed)
			(vias allowed)
			(pads allowed)
			(copperpour not_allowed)
			(footprints allowed)
		)
		(placement
			(enabled no)
			(sheetname "")
		)
		(fill
			(thermal_gap 0.5)
			(thermal_bridge_width 0.5)
			(island_removal_mode 0)
		)
		(polygon
			(pts
				(arc
					(start 180.265324 -217.132408)
					(mid 180.261604 -217.141388)
					(end 180.252624 -217.145108)
				)
				(arc
					(start 178.779424 -217.145108)
					(mid 178.770444 -217.141388)
					(end 178.766724 -217.132408)
				)
				(arc
					(start 178.766724 -216.63787)
					(mid 178.770444 -216.62889)
					(end 178.779424 -216.62517)
				)
				(arc
					(start 180.252624 -216.62517)
					(mid 180.261604 -216.62889)
					(end 180.265324 -216.63787)
				)
			)
		)
	)
	(zone
		(layer "In1.Cu")
		(hatch none 0.5)
		(connect_pads
			(clearance 0)
		)
		(min_thickness 0.25)
		(keepout
			(tracks not_allowed)
			(vias allowed)
			(pads allowed)
			(copperpour not_allowed)
			(footprints allowed)
		)
		(placement
			(enabled no)
			(sheetname "")
		)
		(fill
			(thermal_gap 0.5)
			(thermal_bridge_width 0.5)
			(island_removal_mode 0)
		)
		(polygon
			(pts
				(arc
					(start 52.633372 -216.282524)
					(mid 52.629652 -216.291504)
					(end 52.620672 -216.295224)
				)
				(arc
					(start 51.147472 -216.295224)
					(mid 51.138492 -216.291504)
					(end 51.134772 -216.282524)
				)
				(arc
					(start 51.134772 -215.787986)
					(mid 51.138492 -215.779006)
					(end 51.147472 -215.775286)
				)
				(arc
					(start 52.620672 -215.775286)
					(mid 52.629652 -215.779006)
					(end 52.633372 -215.787986)
				)
			)
		)
	)
	(zone
		(layer "In1.Cu")
		(hatch none 0.5)
		(connect_pads
			(clearance 0)
		)
		(min_thickness 0.25)
		(keepout
			(tracks not_allowed)
			(vias allowed)
			(pads allowed)
			(copperpour not_allowed)
			(footprints allowed)
		)
		(placement
			(enabled no)
			(sheetname "")
		)
		(fill
			(thermal_gap 0.5)
			(thermal_bridge_width 0.5)
			(island_removal_mode 0)
		)
		(polygon
			(pts
				(arc
					(start 151.088852 -389.467344)
					(mid 150.707852 -389.467344)
					(end 151.088852 -389.467344)
				)
			)
		)
	)
	(zone
		(layer "In1.Cu")
		(hatch none 0.5)
		(connect_pads
			(clearance 0)
		)
		(min_thickness 0.25)
		(keepout
			(tracks not_allowed)
			(vias allowed)
			(pads allowed)
			(copperpour not_allowed)
			(footprints allowed)
		)
		(placement
			(enabled no)
			(sheetname "")
		)
		(fill
			(thermal_gap 0.5)
			(thermal_bridge_width 0.5)
			(island_removal_mode 0)
		)
		(polygon
			(pts
				(arc
					(start 195.353432 -235.832396)
					(mid 195.349712 -235.841376)
					(end 195.340732 -235.845096)
				)
				(arc
					(start 193.867532 -235.845096)
					(mid 193.858552 -235.841376)
					(end 193.854832 -235.832396)
				)
				(arc
					(start 193.854832 -235.337858)
					(mid 193.858552 -235.328878)
					(end 193.867532 -235.325158)
				)
				(arc
					(start 195.340732 -235.325158)
					(mid 195.349712 -235.328878)
					(end 195.353432 -235.337858)
				)
			)
		)
	)
	(zone
		(layer "In1.Cu")
		(hatch none 0.5)
		(connect_pads
			(clearance 0)
		)
		(min_thickness 0.25)
		(keepout
			(tracks not_allowed)
			(vias allowed)
			(pads allowed)
			(copperpour not_allowed)
			(footprints allowed)
		)
		(placement
			(enabled no)
			(sheetname "")
		)
		(fill
			(thermal_gap 0.5)
			(thermal_bridge_width 0.5)
			(island_removal_mode 0)
		)
		(polygon
			(pts
				(arc
					(start 424.761406 -285.132272)
					(mid 424.757686 -285.141252)
					(end 424.748706 -285.144972)
				)
				(arc
					(start 423.275506 -285.144972)
					(mid 423.266526 -285.141252)
					(end 423.262806 -285.132272)
				)
				(arc
					(start 423.262806 -284.637734)
					(mid 423.266526 -284.628754)
					(end 423.275506 -284.625034)
				)
				(arc
					(start 424.748706 -284.625034)
					(mid 424.757686 -284.628754)
					(end 424.761406 -284.637734)
				)
			)
		)
	)
	(zone
		(layer "In1.Cu")
		(hatch none 0.5)
		(connect_pads
			(clearance 0)
		)
		(min_thickness 0.25)
		(keepout
			(tracks not_allowed)
			(vias allowed)
			(pads allowed)
			(copperpour not_allowed)
			(footprints allowed)
		)
		(placement
			(enabled no)
			(sheetname "")
		)
		(fill
			(thermal_gap 0.5)
			(thermal_bridge_width 0.5)
			(island_removal_mode 0)
		)
		(polygon
			(pts
				(arc
					(start 288.929318 -226.482148)
					(mid 288.925598 -226.491128)
					(end 288.916618 -226.494848)
				)
				(arc
					(start 287.443418 -226.494848)
					(mid 287.434438 -226.491128)
					(end 287.430718 -226.482148)
				)
				(arc
					(start 287.430718 -225.98761)
					(mid 287.434438 -225.97863)
					(end 287.443418 -225.97491)
				)
				(arc
					(start 288.916618 -225.97491)
					(mid 288.925598 -225.97863)
					(end 288.929318 -225.98761)
				)
			)
		)
	)
	(zone
		(layer "In1.Cu")
		(hatch none 0.5)
		(connect_pads
			(clearance 0)
		)
		(min_thickness 0.25)
		(keepout
			(tracks not_allowed)
			(vias allowed)
			(pads allowed)
			(copperpour not_allowed)
			(footprints allowed)
		)
		(placement
			(enabled no)
			(sheetname "")
		)
		(fill
			(thermal_gap 0.5)
			(thermal_bridge_width 0.5)
			(island_removal_mode 0)
		)
		(polygon
			(pts
				(arc
					(start 432.30546 -294.482266)
					(mid 432.30174 -294.491246)
					(end 432.29276 -294.494966)
				)
				(arc
					(start 430.81956 -294.494966)
					(mid 430.81058 -294.491246)
					(end 430.80686 -294.482266)
				)
				(arc
					(start 430.80686 -293.987728)
					(mid 430.81058 -293.978748)
					(end 430.81956 -293.975028)
				)
				(arc
					(start 432.29276 -293.975028)
					(mid 432.30174 -293.978748)
					(end 432.30546 -293.987728)
				)
			)
		)
	)
	(zone
		(layer "In1.Cu")
		(hatch none 0.5)
		(connect_pads
			(clearance 0)
		)
		(min_thickness 0.25)
		(keepout
			(tracks not_allowed)
			(vias allowed)
			(pads allowed)
			(copperpour not_allowed)
			(footprints allowed)
		)
		(placement
			(enabled no)
			(sheetname "")
		)
		(fill
			(thermal_gap 0.5)
			(thermal_bridge_width 0.5)
			(island_removal_mode 0)
		)
		(polygon
			(pts
				(arc
					(start 59.570366 -390.761474)
					(mid 59.265566 -390.761474)
					(end 59.570366 -390.761474)
				)
			)
		)
	)
	(zone
		(layer "In1.Cu")
		(hatch none 0.5)
		(connect_pads
			(clearance 0)
		)
		(min_thickness 0.25)
		(keepout
			(tracks not_allowed)
			(vias allowed)
			(pads allowed)
			(copperpour not_allowed)
			(footprints allowed)
		)
		(placement
			(enabled no)
			(sheetname "")
		)
		(fill
			(thermal_gap 0.5)
			(thermal_bridge_width 0.5)
			(island_removal_mode 0)
		)
		(polygon
			(pts
				(arc
					(start 18.357342 -221.382336)
					(mid 18.353622 -221.391316)
					(end 18.344642 -221.395036)
				)
				(arc
					(start 16.871442 -221.395036)
					(mid 16.862462 -221.391316)
					(end 16.858742 -221.382336)
				)
				(arc
					(start 16.858742 -220.887798)
					(mid 16.862462 -220.878818)
					(end 16.871442 -220.875098)
				)
				(arc
					(start 18.344642 -220.875098)
					(mid 18.353622 -220.878818)
					(end 18.357342 -220.887798)
				)
			)
		)
	)
	(zone
		(layer "In1.Cu")
		(hatch none 0.5)
		(connect_pads
			(clearance 0)
		)
		(min_thickness 0.25)
		(keepout
			(tracks not_allowed)
			(vias allowed)
			(pads allowed)
			(copperpour not_allowed)
			(footprints allowed)
		)
		(placement
			(enabled no)
			(sheetname "")
		)
		(fill
			(thermal_gap 0.5)
			(thermal_bridge_width 0.5)
			(island_removal_mode 0)
		)
		(polygon
			(pts
				(arc
					(start 195.353432 -263.882378)
					(mid 195.349712 -263.891358)
					(end 195.340732 -263.895078)
				)
				(arc
					(start 193.867532 -263.895078)
					(mid 193.858552 -263.891358)
					(end 193.854832 -263.882378)
				)
				(arc
					(start 193.854832 -263.38784)
					(mid 193.858552 -263.37886)
					(end 193.867532 -263.37514)
				)
				(arc
					(start 195.340732 -263.37514)
					(mid 195.349712 -263.37886)
					(end 195.353432 -263.38784)
				)
			)
		)
	)
	(zone
		(layer "In1.Cu")
		(hatch none 0.5)
		(connect_pads
			(clearance 0)
		)
		(min_thickness 0.25)
		(keepout
			(tracks not_allowed)
			(vias allowed)
			(pads allowed)
			(copperpour not_allowed)
			(footprints allowed)
		)
		(placement
			(enabled no)
			(sheetname "")
		)
		(fill
			(thermal_gap 0.5)
			(thermal_bridge_width 0.5)
			(island_removal_mode 0)
		)
		(polygon
			(pts
				(arc
					(start 45.089318 -264.732516)
					(mid 45.085598 -264.741496)
					(end 45.076618 -264.745216)
				)
				(arc
					(start 43.603418 -264.745216)
					(mid 43.594438 -264.741496)
					(end 43.590718 -264.732516)
				)
				(arc
					(start 43.590718 -264.237978)
					(mid 43.594438 -264.228998)
					(end 43.603418 -264.225278)
				)
				(arc
					(start 45.076618 -264.225278)
					(mid 45.085598 -264.228998)
					(end 45.089318 -264.237978)
				)
			)
		)
	)
	(zone
		(layer "In1.Cu")
		(hatch none 0.5)
		(connect_pads
			(clearance 0)
		)
		(min_thickness 0.25)
		(keepout
			(tracks not_allowed)
			(vias allowed)
			(pads allowed)
			(copperpour not_allowed)
			(footprints allowed)
		)
		(placement
			(enabled no)
			(sheetname "")
		)
		(fill
			(thermal_gap 0.5)
			(thermal_bridge_width 0.5)
			(island_removal_mode 0)
		)
		(polygon
			(pts
				(arc
					(start 169.277284 -254.532384)
					(mid 169.273564 -254.541364)
					(end 169.264584 -254.545084)
				)
				(arc
					(start 167.791384 -254.545084)
					(mid 167.782404 -254.541364)
					(end 167.778684 -254.532384)
				)
				(arc
					(start 167.778684 -254.037846)
					(mid 167.782404 -254.028866)
					(end 167.791384 -254.025146)
				)
				(arc
					(start 169.264584 -254.025146)
					(mid 169.273564 -254.028866)
					(end 169.277284 -254.037846)
				)
			)
		)
	)
	(zone
		(layer "In1.Cu")
		(hatch none 0.5)
		(connect_pads
			(clearance 0)
		)
		(min_thickness 0.25)
		(keepout
			(tracks not_allowed)
			(vias allowed)
			(pads allowed)
			(copperpour not_allowed)
			(footprints allowed)
		)
		(placement
			(enabled no)
			(sheetname "")
		)
		(fill
			(thermal_gap 0.5)
			(thermal_bridge_width 0.5)
			(island_removal_mode 0)
		)
		(polygon
			(pts
				(arc
					(start 184.365392 -280.03246)
					(mid 184.361672 -280.04144)
					(end 184.352692 -280.04516)
				)
				(arc
					(start 182.879492 -280.04516)
					(mid 182.870512 -280.04144)
					(end 182.866792 -280.03246)
				)
				(arc
					(start 182.866792 -279.537922)
					(mid 182.870512 -279.528942)
					(end 182.879492 -279.525222)
				)
				(arc
					(start 184.352692 -279.525222)
					(mid 184.361672 -279.528942)
					(end 184.365392 -279.537922)
				)
			)
		)
	)
	(zone
		(layer "In1.Cu")
		(hatch none 0.5)
		(connect_pads
			(clearance 0)
		)
		(min_thickness 0.25)
		(keepout
			(tracks not_allowed)
			(vias allowed)
			(pads allowed)
			(copperpour not_allowed)
			(footprints allowed)
		)
		(placement
			(enabled no)
			(sheetname "")
		)
		(fill
			(thermal_gap 0.5)
			(thermal_bridge_width 0.5)
			(island_removal_mode 0)
		)
		(polygon
			(pts
				(arc
					(start 377.761246 -397.156432)
					(mid 377.380246 -397.156432)
					(end 377.761246 -397.156432)
				)
			)
		)
	)
	(zone
		(layer "In1.Cu")
		(hatch none 0.5)
		(connect_pads
			(clearance 0)
		)
		(min_thickness 0.25)
		(keepout
			(tracks not_allowed)
			(vias allowed)
			(pads allowed)
			(copperpour not_allowed)
			(footprints allowed)
		)
		(placement
			(enabled no)
			(sheetname "")
		)
		(fill
			(thermal_gap 0.5)
			(thermal_bridge_width 0.5)
			(island_removal_mode 0)
		)
		(polygon
			(pts
				(arc
					(start 273.841464 -218.832176)
					(mid 273.837744 -218.841156)
					(end 273.828764 -218.844876)
				)
				(arc
					(start 272.355564 -218.844876)
					(mid 272.346584 -218.841156)
					(end 272.342864 -218.832176)
				)
				(arc
					(start 272.342864 -218.337638)
					(mid 272.346584 -218.328658)
					(end 272.355564 -218.324938)
				)
				(arc
					(start 273.828764 -218.324938)
					(mid 273.837744 -218.328658)
					(end 273.841464 -218.337638)
				)
			)
		)
	)
	(zone
		(layer "In1.Cu")
		(hatch none 0.5)
		(connect_pads
			(clearance 0)
		)
		(min_thickness 0.25)
		(keepout
			(tracks not_allowed)
			(vias allowed)
			(pads allowed)
			(copperpour not_allowed)
			(footprints allowed)
		)
		(placement
			(enabled no)
			(sheetname "")
		)
		(fill
			(thermal_gap 0.5)
			(thermal_bridge_width 0.5)
			(island_removal_mode 0)
		)
		(polygon
			(pts
				(arc
					(start 195.353432 -253.6825)
					(mid 195.349712 -253.69148)
					(end 195.340732 -253.6952)
				)
				(arc
					(start 193.867532 -253.6952)
					(mid 193.858552 -253.69148)
					(end 193.854832 -253.6825)
				)
				(arc
					(start 193.854832 -253.187962)
					(mid 193.858552 -253.178982)
					(end 193.867532 -253.175262)
				)
				(arc
					(start 195.340732 -253.175262)
					(mid 195.349712 -253.178982)
					(end 195.353432 -253.187962)
				)
			)
		)
	)
	(zone
		(layer "In1.Cu")
		(hatch none 0.5)
		(connect_pads
			(clearance 0)
		)
		(min_thickness 0.25)
		(keepout
			(tracks not_allowed)
			(vias allowed)
			(pads allowed)
			(copperpour not_allowed)
			(footprints allowed)
		)
		(placement
			(enabled no)
			(sheetname "")
		)
		(fill
			(thermal_gap 0.5)
			(thermal_bridge_width 0.5)
			(island_removal_mode 0)
		)
		(polygon
			(pts
				(arc
					(start 432.30546 -285.982156)
					(mid 432.30174 -285.991136)
					(end 432.29276 -285.994856)
				)
				(arc
					(start 430.81956 -285.994856)
					(mid 430.81058 -285.991136)
					(end 430.80686 -285.982156)
				)
				(arc
					(start 430.80686 -285.487618)
					(mid 430.81058 -285.478638)
					(end 430.81956 -285.474918)
				)
				(arc
					(start 432.29276 -285.474918)
					(mid 432.30174 -285.478638)
					(end 432.30546 -285.487618)
				)
			)
		)
	)
	(zone
		(layer "In1.Cu")
		(hatch none 0.5)
		(connect_pads
			(clearance 0)
		)
		(min_thickness 0.25)
		(keepout
			(tracks not_allowed)
			(vias allowed)
			(pads allowed)
			(copperpour not_allowed)
			(footprints allowed)
		)
		(placement
			(enabled no)
			(sheetname "")
		)
		(fill
			(thermal_gap 0.5)
			(thermal_bridge_width 0.5)
			(island_removal_mode 0)
		)
		(polygon
			(pts
				(arc
					(start 300.57344 -275.782278)
					(mid 300.56972 -275.791258)
					(end 300.56074 -275.794978)
				)
				(arc
					(start 299.08754 -275.794978)
					(mid 299.07856 -275.791258)
					(end 299.07484 -275.782278)
				)
				(arc
					(start 299.07484 -275.28774)
					(mid 299.07856 -275.27876)
					(end 299.08754 -275.27504)
				)
				(arc
					(start 300.56074 -275.27504)
					(mid 300.56972 -275.27876)
					(end 300.57344 -275.28774)
				)
			)
		)
	)
	(zone
		(layer "In1.Cu")
		(hatch none 0.5)
		(connect_pads
			(clearance 0)
		)
		(min_thickness 0.25)
		(keepout
			(tracks not_allowed)
			(vias allowed)
			(pads allowed)
			(copperpour not_allowed)
			(footprints allowed)
		)
		(placement
			(enabled no)
			(sheetname "")
		)
		(fill
			(thermal_gap 0.5)
			(thermal_bridge_width 0.5)
			(island_removal_mode 0)
		)
		(polygon
			(pts
				(arc
					(start 202.897232 -251.982478)
					(mid 202.893512 -251.991458)
					(end 202.884532 -251.995178)
				)
				(arc
					(start 201.411332 -251.995178)
					(mid 201.402352 -251.991458)
					(end 201.398632 -251.982478)
				)
				(arc
					(start 201.398632 -251.48794)
					(mid 201.402352 -251.47896)
					(end 201.411332 -251.47524)
				)
				(arc
					(start 202.884532 -251.47524)
					(mid 202.893512 -251.47896)
					(end 202.897232 -251.48794)
				)
			)
		)
	)
	(zone
		(layer "In1.Cu")
		(hatch none 0.5)
		(connect_pads
			(clearance 0)
		)
		(min_thickness 0.25)
		(keepout
			(tracks not_allowed)
			(vias allowed)
			(pads allowed)
			(copperpour not_allowed)
			(footprints allowed)
		)
		(placement
			(enabled no)
			(sheetname "")
		)
		(fill
			(thermal_gap 0.5)
			(thermal_bridge_width 0.5)
			(island_removal_mode 0)
		)
		(polygon
			(pts
				(arc
					(start 199.4535 -244.332506)
					(mid 199.44978 -244.341486)
					(end 199.4408 -244.345206)
				)
				(arc
					(start 197.9676 -244.345206)
					(mid 197.95862 -244.341486)
					(end 197.9549 -244.332506)
				)
				(arc
					(start 197.9549 -243.837968)
					(mid 197.95862 -243.828988)
					(end 197.9676 -243.825268)
				)
				(arc
					(start 199.4408 -243.825268)
					(mid 199.44978 -243.828988)
					(end 199.4535 -243.837968)
				)
			)
		)
	)
	(zone
		(layer "In1.Cu")
		(hatch none 0.5)
		(connect_pads
			(clearance 0)
		)
		(min_thickness 0.25)
		(keepout
			(tracks not_allowed)
			(vias allowed)
			(pads allowed)
			(copperpour not_allowed)
			(footprints allowed)
		)
		(placement
			(enabled no)
			(sheetname "")
		)
		(fill
			(thermal_gap 0.5)
			(thermal_bridge_width 0.5)
			(island_removal_mode 0)
		)
		(polygon
			(pts
				(arc
					(start 165.177216 -204.38237)
					(mid 165.173496 -204.39135)
					(end 165.164516 -204.39507)
				)
				(arc
					(start 163.691316 -204.39507)
					(mid 163.682336 -204.39135)
					(end 163.678616 -204.38237)
				)
				(arc
					(start 163.678616 -203.887832)
					(mid 163.682336 -203.878852)
					(end 163.691316 -203.875132)
				)
				(arc
					(start 165.164516 -203.875132)
					(mid 165.173496 -203.878852)
					(end 165.177216 -203.887832)
				)
			)
		)
	)
	(zone
		(layer "In1.Cu")
		(hatch none 0.5)
		(connect_pads
			(clearance 0)
		)
		(min_thickness 0.25)
		(keepout
			(tracks not_allowed)
			(vias allowed)
			(pads allowed)
			(copperpour not_allowed)
			(footprints allowed)
		)
		(placement
			(enabled no)
			(sheetname "")
		)
		(fill
			(thermal_gap 0.5)
			(thermal_bridge_width 0.5)
			(island_removal_mode 0)
		)
		(polygon
			(pts
				(arc
					(start 300.57344 -244.332252)
					(mid 300.56972 -244.341232)
					(end 300.56074 -244.344952)
				)
				(arc
					(start 299.08754 -244.344952)
					(mid 299.07856 -244.341232)
					(end 299.07484 -244.332252)
				)
				(arc
					(start 299.07484 -243.837714)
					(mid 299.07856 -243.828734)
					(end 299.08754 -243.825014)
				)
				(arc
					(start 300.56074 -243.825014)
					(mid 300.56972 -243.828734)
					(end 300.57344 -243.837714)
				)
			)
		)
	)
	(zone
		(layer "In1.Cu")
		(hatch none 0.5)
		(connect_pads
			(clearance 0)
		)
		(min_thickness 0.25)
		(keepout
			(tracks not_allowed)
			(vias allowed)
			(pads allowed)
			(copperpour not_allowed)
			(footprints allowed)
		)
		(placement
			(enabled no)
			(sheetname "")
		)
		(fill
			(thermal_gap 0.5)
			(thermal_bridge_width 0.5)
			(island_removal_mode 0)
		)
		(polygon
			(pts
				(arc
					(start 85.518752 -391.319258)
					(mid 85.645752 -391.446258)
					(end 85.772752 -391.319258)
				)
				(arc
					(start 85.772752 -391.243058)
					(mid 85.645752 -391.116058)
					(end 85.518752 -391.243058)
				)
			)
		)
	)
	(zone
		(layer "In1.Cu")
		(hatch none 0.5)
		(connect_pads
			(clearance 0)
		)
		(min_thickness 0.25)
		(keepout
			(tracks not_allowed)
			(vias allowed)
			(pads allowed)
			(copperpour not_allowed)
			(footprints allowed)
		)
		(placement
			(enabled no)
			(sheetname "")
		)
		(fill
			(thermal_gap 0.5)
			(thermal_bridge_width 0.5)
			(island_removal_mode 0)
		)
		(polygon
			(pts
				(arc
					(start 277.941532 -317.432182)
					(mid 277.937812 -317.441162)
					(end 277.928832 -317.444882)
				)
				(arc
					(start 276.455632 -317.444882)
					(mid 276.446652 -317.441162)
					(end 276.442932 -317.432182)
				)
				(arc
					(start 276.442932 -316.937644)
					(mid 276.446652 -316.928664)
					(end 276.455632 -316.924944)
				)
				(arc
					(start 277.928832 -316.924944)
					(mid 277.937812 -316.928664)
					(end 277.941532 -316.937644)
				)
			)
		)
	)
	(zone
		(layer "In1.Cu")
		(hatch none 0.5)
		(connect_pads
			(clearance 0)
		)
		(min_thickness 0.25)
		(keepout
			(tracks not_allowed)
			(vias allowed)
			(pads allowed)
			(copperpour not_allowed)
			(footprints allowed)
		)
		(placement
			(enabled no)
			(sheetname "")
		)
		(fill
			(thermal_gap 0.5)
			(thermal_bridge_width 0.5)
			(island_removal_mode 0)
		)
		(polygon
			(pts
				(arc
					(start 349.588582 -394.385292)
					(mid 349.207582 -394.385292)
					(end 349.588582 -394.385292)
				)
			)
		)
	)
	(zone
		(layer "In1.Cu")
		(hatch none 0.5)
		(connect_pads
			(clearance 0)
		)
		(min_thickness 0.25)
		(keepout
			(tracks not_allowed)
			(vias allowed)
			(pads allowed)
			(copperpour not_allowed)
			(footprints allowed)
		)
		(placement
			(enabled no)
			(sheetname "")
		)
		(fill
			(thermal_gap 0.5)
			(thermal_bridge_width 0.5)
			(island_removal_mode 0)
		)
		(polygon
			(pts
				(arc
					(start 48.533304 -206.082392)
					(mid 48.529584 -206.091372)
					(end 48.520604 -206.095092)
				)
				(arc
					(start 47.047404 -206.095092)
					(mid 47.038424 -206.091372)
					(end 47.034704 -206.082392)
				)
				(arc
					(start 47.034704 -205.587854)
					(mid 47.038424 -205.578874)
					(end 47.047404 -205.575154)
				)
				(arc
					(start 48.520604 -205.575154)
					(mid 48.529584 -205.578874)
					(end 48.533304 -205.587854)
				)
			)
		)
	)
	(zone
		(layer "In1.Cu")
		(hatch none 0.5)
		(connect_pads
			(clearance 0)
		)
		(min_thickness 0.25)
		(keepout
			(tracks not_allowed)
			(vias allowed)
			(pads allowed)
			(copperpour not_allowed)
			(footprints allowed)
		)
		(placement
			(enabled no)
			(sheetname "")
		)
		(fill
			(thermal_gap 0.5)
			(thermal_bridge_width 0.5)
			(island_removal_mode 0)
		)
		(polygon
			(pts
				(arc
					(start 270.397478 -317.432182)
					(mid 270.393758 -317.441162)
					(end 270.384778 -317.444882)
				)
				(arc
					(start 268.911578 -317.444882)
					(mid 268.902598 -317.441162)
					(end 268.898878 -317.432182)
				)
				(arc
					(start 268.898878 -316.937644)
					(mid 268.902598 -316.928664)
					(end 268.911578 -316.924944)
				)
				(arc
					(start 270.384778 -316.924944)
					(mid 270.393758 -316.928664)
					(end 270.397478 -316.937644)
				)
			)
		)
	)
	(zone
		(layer "In1.Cu")
		(hatch none 0.5)
		(connect_pads
			(clearance 0)
		)
		(min_thickness 0.25)
		(keepout
			(tracks not_allowed)
			(vias allowed)
			(pads allowed)
			(copperpour not_allowed)
			(footprints allowed)
		)
		(placement
			(enabled no)
			(sheetname "")
		)
		(fill
			(thermal_gap 0.5)
			(thermal_bridge_width 0.5)
			(island_removal_mode 0)
		)
		(polygon
			(pts
				(arc
					(start 18.357342 -240.082578)
					(mid 18.353622 -240.091558)
					(end 18.344642 -240.095278)
				)
				(arc
					(start 16.871442 -240.095278)
					(mid 16.862462 -240.091558)
					(end 16.858742 -240.082578)
				)
				(arc
					(start 16.858742 -239.58804)
					(mid 16.862462 -239.57906)
					(end 16.871442 -239.57534)
				)
				(arc
					(start 18.344642 -239.57534)
					(mid 18.353622 -239.57906)
					(end 18.357342 -239.58804)
				)
			)
		)
	)
	(zone
		(layer "In1.Cu")
		(hatch none 0.5)
		(connect_pads
			(clearance 0)
		)
		(min_thickness 0.25)
		(keepout
			(tracks not_allowed)
			(vias allowed)
			(pads allowed)
			(copperpour not_allowed)
			(footprints allowed)
		)
		(placement
			(enabled no)
			(sheetname "")
		)
		(fill
			(thermal_gap 0.5)
			(thermal_bridge_width 0.5)
			(island_removal_mode 0)
		)
		(polygon
			(pts
				(arc
					(start 40.98925 -310.632348)
					(mid 40.98553 -310.641328)
					(end 40.97655 -310.645048)
				)
				(arc
					(start 39.50335 -310.645048)
					(mid 39.49437 -310.641328)
					(end 39.49065 -310.632348)
				)
				(arc
					(start 39.49065 -310.13781)
					(mid 39.49437 -310.12883)
					(end 39.50335 -310.12511)
				)
				(arc
					(start 40.97655 -310.12511)
					(mid 40.98553 -310.12883)
					(end 40.98925 -310.13781)
				)
			)
		)
	)
	(zone
		(layer "In1.Cu")
		(hatch none 0.5)
		(connect_pads
			(clearance 0)
		)
		(min_thickness 0.25)
		(keepout
			(tracks not_allowed)
			(vias allowed)
			(pads allowed)
			(copperpour not_allowed)
			(footprints allowed)
		)
		(placement
			(enabled no)
			(sheetname "")
		)
		(fill
			(thermal_gap 0.5)
			(thermal_bridge_width 0.5)
			(island_removal_mode 0)
		)
		(polygon
			(pts
				(arc
					(start 285.485332 -239.232186)
					(mid 285.481612 -239.241166)
					(end 285.472632 -239.244886)
				)
				(arc
					(start 283.999432 -239.244886)
					(mid 283.990452 -239.241166)
					(end 283.986732 -239.232186)
				)
				(arc
					(start 283.986732 -238.737648)
					(mid 283.990452 -238.728668)
					(end 283.999432 -238.724948)
				)
				(arc
					(start 285.472632 -238.724948)
					(mid 285.481612 -238.728668)
					(end 285.485332 -238.737648)
				)
			)
		)
	)
	(zone
		(layer "In1.Cu")
		(hatch none 0.5)
		(connect_pads
			(clearance 0)
		)
		(min_thickness 0.25)
		(keepout
			(tracks not_allowed)
			(vias allowed)
			(pads allowed)
			(copperpour not_allowed)
			(footprints allowed)
		)
		(placement
			(enabled no)
			(sheetname "")
		)
		(fill
			(thermal_gap 0.5)
			(thermal_bridge_width 0.5)
			(island_removal_mode 0)
		)
		(polygon
			(pts
				(arc
					(start 288.929318 -277.4823)
					(mid 288.925598 -277.49128)
					(end 288.916618 -277.495)
				)
				(arc
					(start 287.443418 -277.495)
					(mid 287.434438 -277.49128)
					(end 287.430718 -277.4823)
				)
				(arc
					(start 287.430718 -276.987762)
					(mid 287.434438 -276.978782)
					(end 287.443418 -276.975062)
				)
				(arc
					(start 288.916618 -276.975062)
					(mid 288.925598 -276.978782)
					(end 288.929318 -276.987762)
				)
			)
		)
	)
	(zone
		(layer "In1.Cu")
		(hatch none 0.5)
		(connect_pads
			(clearance 0)
		)
		(min_thickness 0.25)
		(keepout
			(tracks not_allowed)
			(vias allowed)
			(pads allowed)
			(copperpour not_allowed)
			(footprints allowed)
		)
		(placement
			(enabled no)
			(sheetname "")
		)
		(fill
			(thermal_gap 0.5)
			(thermal_bridge_width 0.5)
			(island_removal_mode 0)
		)
		(polygon
			(pts
				(arc
					(start 420.661338 -314.032138)
					(mid 420.657618 -314.041118)
					(end 420.648638 -314.044838)
				)
				(arc
					(start 419.175438 -314.044838)
					(mid 419.166458 -314.041118)
					(end 419.162738 -314.032138)
				)
				(arc
					(start 419.162738 -313.5376)
					(mid 419.166458 -313.52862)
					(end 419.175438 -313.5249)
				)
				(arc
					(start 420.648638 -313.5249)
					(mid 420.657618 -313.52862)
					(end 420.661338 -313.5376)
				)
			)
		)
	)
	(zone
		(layer "In1.Cu")
		(hatch none 0.5)
		(connect_pads
			(clearance 0)
		)
		(min_thickness 0.25)
		(keepout
			(tracks not_allowed)
			(vias allowed)
			(pads allowed)
			(copperpour not_allowed)
			(footprints allowed)
		)
		(placement
			(enabled no)
			(sheetname "")
		)
		(fill
			(thermal_gap 0.5)
			(thermal_bridge_width 0.5)
			(island_removal_mode 0)
		)
		(polygon
			(pts
				(arc
					(start 273.841464 -274.93214)
					(mid 273.837744 -274.94112)
					(end 273.828764 -274.94484)
				)
				(arc
					(start 272.355564 -274.94484)
					(mid 272.346584 -274.94112)
					(end 272.342864 -274.93214)
				)
				(arc
					(start 272.342864 -274.437602)
					(mid 272.346584 -274.428622)
					(end 272.355564 -274.424902)
				)
				(arc
					(start 273.828764 -274.424902)
					(mid 273.837744 -274.428622)
					(end 273.841464 -274.437602)
				)
			)
		)
	)
	(zone
		(layer "In1.Cu")
		(hatch none 0.5)
		(connect_pads
			(clearance 0)
		)
		(min_thickness 0.25)
		(keepout
			(tracks not_allowed)
			(vias allowed)
			(pads allowed)
			(copperpour not_allowed)
			(footprints allowed)
		)
		(placement
			(enabled no)
			(sheetname "")
		)
		(fill
			(thermal_gap 0.5)
			(thermal_bridge_width 0.5)
			(island_removal_mode 0)
		)
		(polygon
			(pts
				(arc
					(start 265.87831 -202.434952)
					(mid 265.21791 -202.434952)
					(end 265.87831 -202.434952)
				)
			)
		)
	)
	(zone
		(layer "In1.Cu")
		(hatch none 0.5)
		(connect_pads
			(clearance 0)
		)
		(min_thickness 0.25)
		(keepout
			(tracks not_allowed)
			(vias allowed)
			(pads allowed)
			(copperpour not_allowed)
			(footprints allowed)
		)
		(placement
			(enabled no)
			(sheetname "")
		)
		(fill
			(thermal_gap 0.5)
			(thermal_bridge_width 0.5)
			(island_removal_mode 0)
		)
		(polygon
			(pts
				(arc
					(start 439.849514 -285.982156)
					(mid 439.845794 -285.991136)
					(end 439.836814 -285.994856)
				)
				(arc
					(start 438.363614 -285.994856)
					(mid 438.354634 -285.991136)
					(end 438.350914 -285.982156)
				)
				(arc
					(start 438.350914 -285.487618)
					(mid 438.354634 -285.478638)
					(end 438.363614 -285.474918)
				)
				(arc
					(start 439.836814 -285.474918)
					(mid 439.845794 -285.478638)
					(end 439.849514 -285.487618)
				)
			)
		)
	)
	(zone
		(layer "In1.Cu")
		(hatch none 0.5)
		(connect_pads
			(clearance 0)
		)
		(min_thickness 0.25)
		(keepout
			(tracks not_allowed)
			(vias allowed)
			(pads allowed)
			(copperpour not_allowed)
			(footprints allowed)
		)
		(placement
			(enabled no)
			(sheetname "")
		)
		(fill
			(thermal_gap 0.5)
			(thermal_bridge_width 0.5)
			(island_removal_mode 0)
		)
		(polygon
			(pts
				(arc
					(start 288.929318 -293.632128)
					(mid 288.925598 -293.641108)
					(end 288.916618 -293.644828)
				)
				(arc
					(start 287.443418 -293.644828)
					(mid 287.434438 -293.641108)
					(end 287.430718 -293.632128)
				)
				(arc
					(start 287.430718 -293.13759)
					(mid 287.434438 -293.12861)
					(end 287.443418 -293.12489)
				)
				(arc
					(start 288.916618 -293.12489)
					(mid 288.925598 -293.12861)
					(end 288.929318 -293.13759)
				)
			)
		)
	)
	(zone
		(layer "In1.Cu")
		(hatch none 0.5)
		(connect_pads
			(clearance 0)
		)
		(min_thickness 0.25)
		(keepout
			(tracks not_allowed)
			(vias allowed)
			(pads allowed)
			(copperpour not_allowed)
			(footprints allowed)
		)
		(placement
			(enabled no)
			(sheetname "")
		)
		(fill
			(thermal_gap 0.5)
			(thermal_bridge_width 0.5)
			(island_removal_mode 0)
		)
		(polygon
			(pts
				(arc
					(start 266.29741 -239.232186)
					(mid 266.29369 -239.241166)
					(end 266.28471 -239.244886)
				)
				(arc
					(start 264.81151 -239.244886)
					(mid 264.80253 -239.241166)
					(end 264.79881 -239.232186)
				)
				(arc
					(start 264.79881 -238.737648)
					(mid 264.80253 -238.728668)
					(end 264.81151 -238.724948)
				)
				(arc
					(start 266.28471 -238.724948)
					(mid 266.29369 -238.728668)
					(end 266.29741 -238.737648)
				)
			)
		)
	)
	(zone
		(layer "In1.Cu")
		(hatch none 0.5)
		(connect_pads
			(clearance 0)
		)
		(min_thickness 0.25)
		(keepout
			(tracks not_allowed)
			(vias allowed)
			(pads allowed)
			(copperpour not_allowed)
			(footprints allowed)
		)
		(placement
			(enabled no)
			(sheetname "")
		)
		(fill
			(thermal_gap 0.5)
			(thermal_bridge_width 0.5)
			(island_removal_mode 0)
		)
		(polygon
			(pts
				(arc
					(start 450.8373 -201.83221)
					(mid 450.83358 -201.84119)
					(end 450.8246 -201.84491)
				)
				(arc
					(start 449.3514 -201.84491)
					(mid 449.34242 -201.84119)
					(end 449.3387 -201.83221)
				)
				(arc
					(start 449.3387 -201.337672)
					(mid 449.34242 -201.328692)
					(end 449.3514 -201.324972)
				)
				(arc
					(start 450.8246 -201.324972)
					(mid 450.83358 -201.328692)
					(end 450.8373 -201.337672)
				)
			)
		)
	)
	(zone
		(layer "In1.Cu")
		(hatch none 0.5)
		(connect_pads
			(clearance 0)
		)
		(min_thickness 0.25)
		(keepout
			(tracks not_allowed)
			(vias allowed)
			(pads allowed)
			(copperpour not_allowed)
			(footprints allowed)
		)
		(placement
			(enabled no)
			(sheetname "")
		)
		(fill
			(thermal_gap 0.5)
			(thermal_bridge_width 0.5)
			(island_removal_mode 0)
		)
		(polygon
			(pts
				(arc
					(start 172.72127 -265.5824)
					(mid 172.71755 -265.59138)
					(end 172.70857 -265.5951)
				)
				(arc
					(start 171.23537 -265.5951)
					(mid 171.22639 -265.59138)
					(end 171.22267 -265.5824)
				)
				(arc
					(start 171.22267 -265.087862)
					(mid 171.22639 -265.078882)
					(end 171.23537 -265.075162)
				)
				(arc
					(start 172.70857 -265.075162)
					(mid 172.71755 -265.078882)
					(end 172.72127 -265.087862)
				)
			)
		)
	)
	(zone
		(layer "In1.Cu")
		(hatch none 0.5)
		(connect_pads
			(clearance 0)
		)
		(min_thickness 0.25)
		(keepout
			(tracks not_allowed)
			(vias allowed)
			(pads allowed)
			(copperpour not_allowed)
			(footprints allowed)
		)
		(placement
			(enabled no)
			(sheetname "")
		)
		(fill
			(thermal_gap 0.5)
			(thermal_bridge_width 0.5)
			(island_removal_mode 0)
		)
		(polygon
			(pts
				(arc
					(start 353.988624 -393.69238)
					(mid 353.607624 -393.69238)
					(end 353.988624 -393.69238)
				)
			)
		)
	)
	(zone
		(layer "In1.Cu")
		(hatch none 0.5)
		(connect_pads
			(clearance 0)
		)
		(min_thickness 0.25)
		(keepout
			(tracks not_allowed)
			(vias allowed)
			(pads allowed)
			(copperpour not_allowed)
			(footprints allowed)
		)
		(placement
			(enabled no)
			(sheetname "")
		)
		(fill
			(thermal_gap 0.5)
			(thermal_bridge_width 0.5)
			(island_removal_mode 0)
		)
		(polygon
			(pts
				(arc
					(start 48.533304 -204.38237)
					(mid 48.529584 -204.39135)
					(end 48.520604 -204.39507)
				)
				(arc
					(start 47.047404 -204.39507)
					(mid 47.038424 -204.39135)
					(end 47.034704 -204.38237)
				)
				(arc
					(start 47.034704 -203.887832)
					(mid 47.038424 -203.878852)
					(end 47.047404 -203.875132)
				)
				(arc
					(start 48.520604 -203.875132)
					(mid 48.529584 -203.878852)
					(end 48.533304 -203.887832)
				)
			)
		)
	)
	(zone
		(layer "In1.Cu")
		(hatch none 0.5)
		(connect_pads
			(clearance 0)
		)
		(min_thickness 0.25)
		(keepout
			(tracks not_allowed)
			(vias allowed)
			(pads allowed)
			(copperpour not_allowed)
			(footprints allowed)
		)
		(placement
			(enabled no)
			(sheetname "")
		)
		(fill
			(thermal_gap 0.5)
			(thermal_bridge_width 0.5)
			(island_removal_mode 0)
		)
		(polygon
			(pts
				(arc
					(start 26.491692 -16.443198)
					(mid 26.51401 -16.49708)
					(end 26.567892 -16.519398)
				)
				(arc
					(start 26.763472 -16.519398)
					(mid 26.785348 -16.516266)
					(end 26.805382 -16.506952)
				)
				(arc
					(start 27.099006 -16.31442)
					(mid 27.140662 -16.302018)
					(end 27.182318 -16.31442)
				)
				(arc
					(start 27.477212 -16.506952)
					(mid 27.497136 -16.516188)
					(end 27.518868 -16.519398)
				)
				(arc
					(start 27.713432 -16.519398)
					(mid 27.767314 -16.49708)
					(end 27.789632 -16.443198)
				)
				(arc
					(start 27.789632 -15.757398)
					(mid 27.767314 -15.703516)
					(end 27.713432 -15.681198)
				)
				(arc
					(start 27.518868 -15.681198)
					(mid 27.497124 -15.684366)
					(end 27.477212 -15.693644)
				)
				(arc
					(start 27.181048 -15.88643)
					(mid 27.139364 -15.898652)
					(end 27.097736 -15.886176)
				)
				(arc
					(start 26.804112 -15.693644)
					(mid 26.784188 -15.684408)
					(end 26.762456 -15.681198)
				)
				(arc
					(start 26.567892 -15.681198)
					(mid 26.51401 -15.703516)
					(end 26.491692 -15.757398)
				)
			)
		)
	)
	(zone
		(layer "In1.Cu")
		(hatch none 0.5)
		(connect_pads
			(clearance 0)
		)
		(min_thickness 0.25)
		(keepout
			(tracks not_allowed)
			(vias allowed)
			(pads allowed)
			(copperpour not_allowed)
			(footprints allowed)
		)
		(placement
			(enabled no)
			(sheetname "")
		)
		(fill
			(thermal_gap 0.5)
			(thermal_bridge_width 0.5)
			(island_removal_mode 0)
		)
		(polygon
			(pts
				(arc
					(start 82.498184 -383.92227)
					(mid 82.193384 -383.92227)
					(end 82.498184 -383.92227)
				)
			)
		)
	)
	(zone
		(layer "In1.Cu")
		(hatch none 0.5)
		(connect_pads
			(clearance 0)
		)
		(min_thickness 0.25)
		(keepout
			(tracks not_allowed)
			(vias allowed)
			(pads allowed)
			(copperpour not_allowed)
			(footprints allowed)
		)
		(placement
			(enabled no)
			(sheetname "")
		)
		(fill
			(thermal_gap 0.5)
			(thermal_bridge_width 0.5)
			(island_removal_mode 0)
		)
		(polygon
			(pts
				(arc
					(start 22.45741 -272.382488)
					(mid 22.45369 -272.391468)
					(end 22.44471 -272.395188)
				)
				(arc
					(start 20.97151 -272.395188)
					(mid 20.96253 -272.391468)
					(end 20.95881 -272.382488)
				)
				(arc
					(start 20.95881 -271.88795)
					(mid 20.96253 -271.87897)
					(end 20.97151 -271.87525)
				)
				(arc
					(start 22.44471 -271.87525)
					(mid 22.45369 -271.87897)
					(end 22.45741 -271.88795)
				)
			)
		)
	)
	(zone
		(layer "In1.Cu")
		(hatch none 0.5)
		(connect_pads
			(clearance 0)
		)
		(min_thickness 0.25)
		(keepout
			(tracks not_allowed)
			(vias allowed)
			(pads allowed)
			(copperpour not_allowed)
			(footprints allowed)
		)
		(placement
			(enabled no)
			(sheetname "")
		)
		(fill
			(thermal_gap 0.5)
			(thermal_bridge_width 0.5)
			(island_removal_mode 0)
		)
		(polygon
			(pts
				(arc
					(start 169.277284 -317.432436)
					(mid 169.273564 -317.441416)
					(end 169.264584 -317.445136)
				)
				(arc
					(start 167.791384 -317.445136)
					(mid 167.782404 -317.441416)
					(end 167.778684 -317.432436)
				)
				(arc
					(start 167.778684 -316.937898)
					(mid 167.782404 -316.928918)
					(end 167.791384 -316.925198)
				)
				(arc
					(start 169.264584 -316.925198)
					(mid 169.273564 -316.928918)
					(end 169.277284 -316.937898)
				)
			)
		)
	)
	(zone
		(layer "In1.Cu")
		(hatch none 0.5)
		(connect_pads
			(clearance 0)
		)
		(min_thickness 0.25)
		(keepout
			(tracks not_allowed)
			(vias allowed)
			(pads allowed)
			(copperpour not_allowed)
			(footprints allowed)
		)
		(placement
			(enabled no)
			(sheetname "")
		)
		(fill
			(thermal_gap 0.5)
			(thermal_bridge_width 0.5)
			(island_removal_mode 0)
		)
		(polygon
			(pts
				(arc
					(start 273.841464 -198.432166)
					(mid 273.837744 -198.441146)
					(end 273.828764 -198.444866)
				)
				(arc
					(start 272.355564 -198.444866)
					(mid 272.346584 -198.441146)
					(end 272.342864 -198.432166)
				)
				(arc
					(start 272.342864 -197.937628)
					(mid 272.346584 -197.928648)
					(end 272.355564 -197.924928)
				)
				(arc
					(start 273.828764 -197.924928)
					(mid 273.837744 -197.928648)
					(end 273.841464 -197.937628)
				)
			)
		)
	)
	(zone
		(layer "In1.Cu")
		(hatch none 0.5)
		(connect_pads
			(clearance 0)
		)
		(min_thickness 0.25)
		(keepout
			(tracks not_allowed)
			(vias allowed)
			(pads allowed)
			(copperpour not_allowed)
			(footprints allowed)
		)
		(placement
			(enabled no)
			(sheetname "")
		)
		(fill
			(thermal_gap 0.5)
			(thermal_bridge_width 0.5)
			(island_removal_mode 0)
		)
		(polygon
			(pts
				(arc
					(start 202.897232 -209.482436)
					(mid 202.893512 -209.491416)
					(end 202.884532 -209.495136)
				)
				(arc
					(start 201.411332 -209.495136)
					(mid 201.402352 -209.491416)
					(end 201.398632 -209.482436)
				)
				(arc
					(start 201.398632 -208.987898)
					(mid 201.402352 -208.978918)
					(end 201.411332 -208.975198)
				)
				(arc
					(start 202.884532 -208.975198)
					(mid 202.893512 -208.978918)
					(end 202.897232 -208.987898)
				)
			)
		)
	)
	(zone
		(layer "In1.Cu")
		(hatch none 0.5)
		(connect_pads
			(clearance 0)
		)
		(min_thickness 0.25)
		(keepout
			(tracks not_allowed)
			(vias allowed)
			(pads allowed)
			(copperpour not_allowed)
			(footprints allowed)
		)
		(placement
			(enabled no)
			(sheetname "")
		)
		(fill
			(thermal_gap 0.5)
			(thermal_bridge_width 0.5)
			(island_removal_mode 0)
		)
		(polygon
			(pts
				(arc
					(start 277.941532 -300.432216)
					(mid 277.937812 -300.441196)
					(end 277.928832 -300.444916)
				)
				(arc
					(start 276.455632 -300.444916)
					(mid 276.446652 -300.441196)
					(end 276.442932 -300.432216)
				)
				(arc
					(start 276.442932 -299.937678)
					(mid 276.446652 -299.928698)
					(end 276.455632 -299.924978)
				)
				(arc
					(start 277.928832 -299.924978)
					(mid 277.937812 -299.928698)
					(end 277.941532 -299.937678)
				)
			)
		)
	)
	(zone
		(layer "In1.Cu")
		(hatch none 0.5)
		(connect_pads
			(clearance 0)
		)
		(min_thickness 0.25)
		(keepout
			(tracks not_allowed)
			(vias allowed)
			(pads allowed)
			(copperpour not_allowed)
			(footprints allowed)
		)
		(placement
			(enabled no)
			(sheetname "")
		)
		(fill
			(thermal_gap 0.5)
			(thermal_bridge_width 0.5)
			(island_removal_mode 0)
		)
		(polygon
			(pts
				(arc
					(start 172.72127 -212.032342)
					(mid 172.71755 -212.041322)
					(end 172.70857 -212.045042)
				)
				(arc
					(start 171.23537 -212.045042)
					(mid 171.22639 -212.041322)
					(end 171.22267 -212.032342)
				)
				(arc
					(start 171.22267 -211.537804)
					(mid 171.22639 -211.528824)
					(end 171.23537 -211.525104)
				)
				(arc
					(start 172.70857 -211.525104)
					(mid 172.71755 -211.528824)
					(end 172.72127 -211.537804)
				)
			)
		)
	)
	(zone
		(layer "In1.Cu")
		(hatch none 0.5)
		(connect_pads
			(clearance 0)
		)
		(min_thickness 0.25)
		(keepout
			(tracks not_allowed)
			(vias allowed)
			(pads allowed)
			(copperpour not_allowed)
			(footprints allowed)
		)
		(placement
			(enabled no)
			(sheetname "")
		)
		(fill
			(thermal_gap 0.5)
			(thermal_bridge_width 0.5)
			(island_removal_mode 0)
		)
		(polygon
			(pts
				(arc
					(start 413.117284 -314.032138)
					(mid 413.113564 -314.041118)
					(end 413.104584 -314.044838)
				)
				(arc
					(start 411.631384 -314.044838)
					(mid 411.622404 -314.041118)
					(end 411.618684 -314.032138)
				)
				(arc
					(start 411.618684 -313.5376)
					(mid 411.622404 -313.52862)
					(end 411.631384 -313.5249)
				)
				(arc
					(start 413.104584 -313.5249)
					(mid 413.113564 -313.52862)
					(end 413.117284 -313.5376)
				)
			)
		)
	)
	(zone
		(layer "In1.Cu")
		(hatch none 0.5)
		(connect_pads
			(clearance 0)
		)
		(min_thickness 0.25)
		(keepout
			(tracks not_allowed)
			(vias allowed)
			(pads allowed)
			(copperpour not_allowed)
			(footprints allowed)
		)
		(placement
			(enabled no)
			(sheetname "")
		)
		(fill
			(thermal_gap 0.5)
			(thermal_bridge_width 0.5)
			(island_removal_mode 0)
		)
		(polygon
			(pts
				(arc
					(start 206.9973 -266.432538)
					(mid 206.99358 -266.441518)
					(end 206.9846 -266.445238)
				)
				(arc
					(start 205.5114 -266.445238)
					(mid 205.50242 -266.441518)
					(end 205.4987 -266.432538)
				)
				(arc
					(start 205.4987 -265.938)
					(mid 205.50242 -265.92902)
					(end 205.5114 -265.9253)
				)
				(arc
					(start 206.9846 -265.9253)
					(mid 206.99358 -265.92902)
					(end 206.9973 -265.938)
				)
			)
		)
	)
	(zone
		(layer "In1.Cu")
		(hatch none 0.5)
		(connect_pads
			(clearance 0)
		)
		(min_thickness 0.25)
		(keepout
			(tracks not_allowed)
			(vias allowed)
			(pads allowed)
			(copperpour not_allowed)
			(footprints allowed)
		)
		(placement
			(enabled no)
			(sheetname "")
		)
		(fill
			(thermal_gap 0.5)
			(thermal_bridge_width 0.5)
			(island_removal_mode 0)
		)
		(polygon
			(pts
				(arc
					(start 370.090954 -399.701258)
					(mid 370.217954 -399.828258)
					(end 370.344954 -399.701258)
				)
				(arc
					(start 370.344954 -399.625058)
					(mid 370.217954 -399.498058)
					(end 370.090954 -399.625058)
				)
			)
		)
	)
	(zone
		(layer "In1.Cu")
		(hatch none 0.5)
		(connect_pads
			(clearance 0)
		)
		(min_thickness 0.25)
		(keepout
			(tracks not_allowed)
			(vias allowed)
			(pads allowed)
			(copperpour not_allowed)
			(footprints allowed)
		)
		(placement
			(enabled no)
			(sheetname "")
		)
		(fill
			(thermal_gap 0.5)
			(thermal_bridge_width 0.5)
			(island_removal_mode 0)
		)
		(polygon
			(pts
				(arc
					(start 424.761406 -223.932242)
					(mid 424.757686 -223.941222)
					(end 424.748706 -223.944942)
				)
				(arc
					(start 423.275506 -223.944942)
					(mid 423.266526 -223.941222)
					(end 423.262806 -223.932242)
				)
				(arc
					(start 423.262806 -223.437704)
					(mid 423.266526 -223.428724)
					(end 423.275506 -223.425004)
				)
				(arc
					(start 424.748706 -223.425004)
					(mid 424.757686 -223.428724)
					(end 424.761406 -223.437704)
				)
			)
		)
	)
	(zone
		(layer "In1.Cu")
		(hatch none 0.5)
		(connect_pads
			(clearance 0)
		)
		(min_thickness 0.25)
		(keepout
			(tracks not_allowed)
			(vias allowed)
			(pads allowed)
			(copperpour not_allowed)
			(footprints allowed)
		)
		(placement
			(enabled no)
			(sheetname "")
		)
		(fill
			(thermal_gap 0.5)
			(thermal_bridge_width 0.5)
			(island_removal_mode 0)
		)
		(polygon
			(pts
				(arc
					(start 176.821338 -297.032426)
					(mid 176.817618 -297.041406)
					(end 176.808638 -297.045126)
				)
				(arc
					(start 175.335438 -297.045126)
					(mid 175.326458 -297.041406)
					(end 175.322738 -297.032426)
				)
				(arc
					(start 175.322738 -296.537888)
					(mid 175.326458 -296.528908)
					(end 175.335438 -296.525188)
				)
				(arc
					(start 176.808638 -296.525188)
					(mid 176.817618 -296.528908)
					(end 176.821338 -296.537888)
				)
			)
		)
	)
	(zone
		(layer "In1.Cu")
		(hatch none 0.5)
		(connect_pads
			(clearance 0)
		)
		(min_thickness 0.25)
		(keepout
			(tracks not_allowed)
			(vias allowed)
			(pads allowed)
			(copperpour not_allowed)
			(footprints allowed)
		)
		(placement
			(enabled no)
			(sheetname "")
		)
		(fill
			(thermal_gap 0.5)
			(thermal_bridge_width 0.5)
			(island_removal_mode 0)
		)
		(polygon
			(pts
				(arc
					(start 432.30546 -266.432284)
					(mid 432.30174 -266.441264)
					(end 432.29276 -266.444984)
				)
				(arc
					(start 430.81956 -266.444984)
					(mid 430.81058 -266.441264)
					(end 430.80686 -266.432284)
				)
				(arc
					(start 430.80686 -265.937746)
					(mid 430.81058 -265.928766)
					(end 430.81956 -265.925046)
				)
				(arc
					(start 432.29276 -265.925046)
					(mid 432.30174 -265.928766)
					(end 432.30546 -265.937746)
				)
			)
		)
	)
	(zone
		(layer "In1.Cu")
		(hatch none 0.5)
		(connect_pads
			(clearance 0)
		)
		(min_thickness 0.25)
		(keepout
			(tracks not_allowed)
			(vias allowed)
			(pads allowed)
			(copperpour not_allowed)
			(footprints allowed)
		)
		(placement
			(enabled no)
			(sheetname "")
		)
		(fill
			(thermal_gap 0.5)
			(thermal_bridge_width 0.5)
			(island_removal_mode 0)
		)
		(polygon
			(pts
				(arc
					(start 195.353432 -221.382336)
					(mid 195.349712 -221.391316)
					(end 195.340732 -221.395036)
				)
				(arc
					(start 193.867532 -221.395036)
					(mid 193.858552 -221.391316)
					(end 193.854832 -221.382336)
				)
				(arc
					(start 193.854832 -220.887798)
					(mid 193.858552 -220.878818)
					(end 193.867532 -220.875098)
				)
				(arc
					(start 195.340732 -220.875098)
					(mid 195.349712 -220.878818)
					(end 195.353432 -220.887798)
				)
			)
		)
	)
	(zone
		(layer "In1.Cu")
		(hatch none 0.5)
		(connect_pads
			(clearance 0)
		)
		(min_thickness 0.25)
		(keepout
			(tracks not_allowed)
			(vias allowed)
			(pads allowed)
			(copperpour not_allowed)
			(footprints allowed)
		)
		(placement
			(enabled no)
			(sheetname "")
		)
		(fill
			(thermal_gap 0.5)
			(thermal_bridge_width 0.5)
			(island_removal_mode 0)
		)
		(polygon
			(pts
				(arc
					(start 52.633372 -272.382488)
					(mid 52.629652 -272.391468)
					(end 52.620672 -272.395188)
				)
				(arc
					(start 51.147472 -272.395188)
					(mid 51.138492 -272.391468)
					(end 51.134772 -272.382488)
				)
				(arc
					(start 51.134772 -271.88795)
					(mid 51.138492 -271.87897)
					(end 51.147472 -271.87525)
				)
				(arc
					(start 52.620672 -271.87525)
					(mid 52.629652 -271.87897)
					(end 52.633372 -271.88795)
				)
			)
		)
	)
	(zone
		(layer "In1.Cu")
		(hatch none 0.5)
		(connect_pads
			(clearance 0)
		)
		(min_thickness 0.25)
		(keepout
			(tracks not_allowed)
			(vias allowed)
			(pads allowed)
			(copperpour not_allowed)
			(footprints allowed)
		)
		(placement
			(enabled no)
			(sheetname "")
		)
		(fill
			(thermal_gap 0.5)
			(thermal_bridge_width 0.5)
			(island_removal_mode 0)
		)
		(polygon
			(pts
				(arc
					(start 22.45741 -208.632552)
					(mid 22.45369 -208.641532)
					(end 22.44471 -208.645252)
				)
				(arc
					(start 20.97151 -208.645252)
					(mid 20.96253 -208.641532)
					(end 20.95881 -208.632552)
				)
				(arc
					(start 20.95881 -208.138014)
					(mid 20.96253 -208.129034)
					(end 20.97151 -208.125314)
				)
				(arc
					(start 22.44471 -208.125314)
					(mid 22.45369 -208.129034)
					(end 22.45741 -208.138014)
				)
			)
		)
	)
	(zone
		(layer "In1.Cu")
		(hatch none 0.5)
		(connect_pads
			(clearance 0)
		)
		(min_thickness 0.25)
		(keepout
			(tracks not_allowed)
			(vias allowed)
			(pads allowed)
			(copperpour not_allowed)
			(footprints allowed)
		)
		(placement
			(enabled no)
			(sheetname "")
		)
		(fill
			(thermal_gap 0.5)
			(thermal_bridge_width 0.5)
			(island_removal_mode 0)
		)
		(polygon
			(pts
				(arc
					(start 288.929318 -213.73211)
					(mid 288.925598 -213.74109)
					(end 288.916618 -213.74481)
				)
				(arc
					(start 287.443418 -213.74481)
					(mid 287.434438 -213.74109)
					(end 287.430718 -213.73211)
				)
				(arc
					(start 287.430718 -213.237572)
					(mid 287.434438 -213.228592)
					(end 287.443418 -213.224872)
				)
				(arc
					(start 288.916618 -213.224872)
					(mid 288.925598 -213.228592)
					(end 288.929318 -213.237572)
				)
			)
		)
	)
	(zone
		(layer "In1.Cu")
		(hatch none 0.5)
		(connect_pads
			(clearance 0)
		)
		(min_thickness 0.25)
		(keepout
			(tracks not_allowed)
			(vias allowed)
			(pads allowed)
			(copperpour not_allowed)
			(footprints allowed)
		)
		(placement
			(enabled no)
			(sheetname "")
		)
		(fill
			(thermal_gap 0.5)
			(thermal_bridge_width 0.5)
			(island_removal_mode 0)
		)
		(polygon
			(pts
				(arc
					(start 56.077358 -202.682348)
					(mid 56.073638 -202.691328)
					(end 56.064658 -202.695048)
				)
				(arc
					(start 54.591458 -202.695048)
					(mid 54.582478 -202.691328)
					(end 54.578758 -202.682348)
				)
				(arc
					(start 54.578758 -202.18781)
					(mid 54.582478 -202.17883)
					(end 54.591458 -202.17511)
				)
				(arc
					(start 56.064658 -202.17511)
					(mid 56.073638 -202.17883)
					(end 56.077358 -202.18781)
				)
			)
		)
	)
	(zone
		(layer "In1.Cu")
		(hatch none 0.5)
		(connect_pads
			(clearance 0)
		)
		(min_thickness 0.25)
		(keepout
			(tracks not_allowed)
			(vias allowed)
			(pads allowed)
			(copperpour not_allowed)
			(footprints allowed)
		)
		(placement
			(enabled no)
			(sheetname "")
		)
		(fill
			(thermal_gap 0.5)
			(thermal_bridge_width 0.5)
			(island_removal_mode 0)
		)
		(polygon
			(pts
				(arc
					(start 304.017426 -314.032138)
					(mid 304.013706 -314.041118)
					(end 304.004726 -314.044838)
				)
				(arc
					(start 302.531526 -314.044838)
					(mid 302.522546 -314.041118)
					(end 302.518826 -314.032138)
				)
				(arc
					(start 302.518826 -313.5376)
					(mid 302.522546 -313.52862)
					(end 302.531526 -313.5249)
				)
				(arc
					(start 304.004726 -313.5249)
					(mid 304.013706 -313.52862)
					(end 304.017426 -313.5376)
				)
			)
		)
	)
	(zone
		(layer "In1.Cu")
		(hatch none 0.5)
		(connect_pads
			(clearance 0)
		)
		(min_thickness 0.25)
		(keepout
			(tracks not_allowed)
			(vias allowed)
			(pads allowed)
			(copperpour not_allowed)
			(footprints allowed)
		)
		(placement
			(enabled no)
			(sheetname "")
		)
		(fill
			(thermal_gap 0.5)
			(thermal_bridge_width 0.5)
			(island_removal_mode 0)
		)
		(polygon
			(pts
				(arc
					(start 53.572664 -7.672324)
					(mid 53.594982 -7.618442)
					(end 53.648864 -7.596124)
				)
				(arc
					(start 54.685438 -7.596124)
					(mid 54.73932 -7.618442)
					(end 54.761638 -7.672324)
				)
				(arc
					(start 54.761638 -9.071864)
					(mid 54.73932 -9.125746)
					(end 54.685438 -9.148064)
				)
				(arc
					(start 53.648864 -9.148064)
					(mid 53.594982 -9.125746)
					(end 53.572664 -9.071864)
				)
			)
		)
	)
	(zone
		(layer "In1.Cu")
		(hatch none 0.5)
		(connect_pads
			(clearance 0)
		)
		(min_thickness 0.25)
		(keepout
			(tracks not_allowed)
			(vias allowed)
			(pads allowed)
			(copperpour not_allowed)
			(footprints allowed)
		)
		(placement
			(enabled no)
			(sheetname "")
		)
		(fill
			(thermal_gap 0.5)
			(thermal_bridge_width 0.5)
			(island_removal_mode 0)
		)
		(polygon
			(pts
				(arc
					(start 288.929318 -284.282134)
					(mid 288.925598 -284.291114)
					(end 288.916618 -284.294834)
				)
				(arc
					(start 287.443418 -284.294834)
					(mid 287.434438 -284.291114)
					(end 287.430718 -284.282134)
				)
				(arc
					(start 287.430718 -283.787596)
					(mid 287.434438 -283.778616)
					(end 287.443418 -283.774896)
				)
				(arc
					(start 288.916618 -283.774896)
					(mid 288.925598 -283.778616)
					(end 288.929318 -283.787596)
				)
			)
		)
	)
	(zone
		(layer "In1.Cu")
		(hatch none 0.5)
		(connect_pads
			(clearance 0)
		)
		(min_thickness 0.25)
		(keepout
			(tracks not_allowed)
			(vias allowed)
			(pads allowed)
			(copperpour not_allowed)
			(footprints allowed)
		)
		(placement
			(enabled no)
			(sheetname "")
		)
		(fill
			(thermal_gap 0.5)
			(thermal_bridge_width 0.5)
			(island_removal_mode 0)
		)
		(polygon
			(pts
				(arc
					(start 273.841464 -299.582332)
					(mid 273.837744 -299.591312)
					(end 273.828764 -299.595032)
				)
				(arc
					(start 272.355564 -299.595032)
					(mid 272.346584 -299.591312)
					(end 272.342864 -299.582332)
				)
				(arc
					(start 272.342864 -299.087794)
					(mid 272.346584 -299.078814)
					(end 272.355564 -299.075094)
				)
				(arc
					(start 273.828764 -299.075094)
					(mid 273.837744 -299.078814)
					(end 273.841464 -299.087794)
				)
			)
		)
	)
	(zone
		(layer "In1.Cu")
		(hatch none 0.5)
		(connect_pads
			(clearance 0)
		)
		(min_thickness 0.25)
		(keepout
			(tracks not_allowed)
			(vias allowed)
			(pads allowed)
			(copperpour not_allowed)
			(footprints allowed)
		)
		(placement
			(enabled no)
			(sheetname "")
		)
		(fill
			(thermal_gap 0.5)
			(thermal_bridge_width 0.5)
			(island_removal_mode 0)
		)
		(polygon
			(pts
				(arc
					(start 180.265324 -308.93258)
					(mid 180.261604 -308.94156)
					(end 180.252624 -308.94528)
				)
				(arc
					(start 178.779424 -308.94528)
					(mid 178.770444 -308.94156)
					(end 178.766724 -308.93258)
				)
				(arc
					(start 178.766724 -308.438042)
					(mid 178.770444 -308.429062)
					(end 178.779424 -308.425342)
				)
				(arc
					(start 180.252624 -308.425342)
					(mid 180.261604 -308.429062)
					(end 180.265324 -308.438042)
				)
			)
		)
	)
	(zone
		(layer "In1.Cu")
		(hatch none 0.5)
		(connect_pads
			(clearance 0)
		)
		(min_thickness 0.25)
		(keepout
			(tracks not_allowed)
			(vias allowed)
			(pads allowed)
			(copperpour not_allowed)
			(footprints allowed)
		)
		(placement
			(enabled no)
			(sheetname "")
		)
		(fill
			(thermal_gap 0.5)
			(thermal_bridge_width 0.5)
			(island_removal_mode 0)
		)
		(polygon
			(pts
				(arc
					(start 300.57344 -239.232186)
					(mid 300.56972 -239.241166)
					(end 300.56074 -239.244886)
				)
				(arc
					(start 299.08754 -239.244886)
					(mid 299.07856 -239.241166)
					(end 299.07484 -239.232186)
				)
				(arc
					(start 299.07484 -238.737648)
					(mid 299.07856 -238.728668)
					(end 299.08754 -238.724948)
				)
				(arc
					(start 300.56074 -238.724948)
					(mid 300.56972 -238.728668)
					(end 300.57344 -238.737648)
				)
			)
		)
	)
	(zone
		(layer "In1.Cu")
		(hatch none 0.5)
		(connect_pads
			(clearance 0)
		)
		(min_thickness 0.25)
		(keepout
			(tracks not_allowed)
			(vias allowed)
			(pads allowed)
			(copperpour not_allowed)
			(footprints allowed)
		)
		(placement
			(enabled no)
			(sheetname "")
		)
		(fill
			(thermal_gap 0.5)
			(thermal_bridge_width 0.5)
			(island_removal_mode 0)
		)
		(polygon
			(pts
				(arc
					(start 180.265324 -276.632416)
					(mid 180.261604 -276.641396)
					(end 180.252624 -276.645116)
				)
				(arc
					(start 178.779424 -276.645116)
					(mid 178.770444 -276.641396)
					(end 178.766724 -276.632416)
				)
				(arc
					(start 178.766724 -276.137878)
					(mid 178.770444 -276.128898)
					(end 178.779424 -276.125178)
				)
				(arc
					(start 180.252624 -276.125178)
					(mid 180.261604 -276.128898)
					(end 180.265324 -276.137878)
				)
			)
		)
	)
	(zone
		(layer "In1.Cu")
		(hatch none 0.5)
		(connect_pads
			(clearance 0)
		)
		(min_thickness 0.25)
		(keepout
			(tracks not_allowed)
			(vias allowed)
			(pads allowed)
			(copperpour not_allowed)
			(footprints allowed)
		)
		(placement
			(enabled no)
			(sheetname "")
		)
		(fill
			(thermal_gap 0.5)
			(thermal_bridge_width 0.5)
			(island_removal_mode 0)
		)
		(polygon
			(pts
				(arc
					(start 206.9973 -306.38242)
					(mid 206.99358 -306.3914)
					(end 206.9846 -306.39512)
				)
				(arc
					(start 205.5114 -306.39512)
					(mid 205.50242 -306.3914)
					(end 205.4987 -306.38242)
				)
				(arc
					(start 205.4987 -305.887882)
					(mid 205.50242 -305.878902)
					(end 205.5114 -305.875182)
				)
				(arc
					(start 206.9846 -305.875182)
					(mid 206.99358 -305.878902)
					(end 206.9973 -305.887882)
				)
			)
		)
	)
	(zone
		(layer "In1.Cu")
		(hatch none 0.5)
		(connect_pads
			(clearance 0)
		)
		(min_thickness 0.25)
		(keepout
			(tracks not_allowed)
			(vias allowed)
			(pads allowed)
			(copperpour not_allowed)
			(footprints allowed)
		)
		(placement
			(enabled no)
			(sheetname "")
		)
		(fill
			(thermal_gap 0.5)
			(thermal_bridge_width 0.5)
			(island_removal_mode 0)
		)
		(polygon
			(pts
				(arc
					(start 420.661338 -246.882158)
					(mid 420.657618 -246.891138)
					(end 420.648638 -246.894858)
				)
				(arc
					(start 419.175438 -246.894858)
					(mid 419.166458 -246.891138)
					(end 419.162738 -246.882158)
				)
				(arc
					(start 419.162738 -246.38762)
					(mid 419.166458 -246.37864)
					(end 419.175438 -246.37492)
				)
				(arc
					(start 420.648638 -246.37492)
					(mid 420.657618 -246.37864)
					(end 420.661338 -246.38762)
				)
			)
		)
	)
	(zone
		(layer "In1.Cu")
		(hatch none 0.5)
		(connect_pads
			(clearance 0)
		)
		(min_thickness 0.25)
		(keepout
			(tracks not_allowed)
			(vias allowed)
			(pads allowed)
			(copperpour not_allowed)
			(footprints allowed)
		)
		(placement
			(enabled no)
			(sheetname "")
		)
		(fill
			(thermal_gap 0.5)
			(thermal_bridge_width 0.5)
			(island_removal_mode 0)
		)
		(polygon
			(pts
				(arc
					(start 195.353432 -267.282422)
					(mid 195.349712 -267.291402)
					(end 195.340732 -267.295122)
				)
				(arc
					(start 193.867532 -267.295122)
					(mid 193.858552 -267.291402)
					(end 193.854832 -267.282422)
				)
				(arc
					(start 193.854832 -266.787884)
					(mid 193.858552 -266.778904)
					(end 193.867532 -266.775184)
				)
				(arc
					(start 195.340732 -266.775184)
					(mid 195.349712 -266.778904)
					(end 195.353432 -266.787884)
				)
			)
		)
	)
	(zone
		(layer "In1.Cu")
		(hatch none 0.5)
		(connect_pads
			(clearance 0)
		)
		(min_thickness 0.25)
		(keepout
			(tracks not_allowed)
			(vias allowed)
			(pads allowed)
			(copperpour not_allowed)
			(footprints allowed)
		)
		(placement
			(enabled no)
			(sheetname "")
		)
		(fill
			(thermal_gap 0.5)
			(thermal_bridge_width 0.5)
			(island_removal_mode 0)
		)
		(polygon
			(pts
				(arc
					(start 172.72127 -295.332404)
					(mid 172.71755 -295.341384)
					(end 172.70857 -295.345104)
				)
				(arc
					(start 171.23537 -295.345104)
					(mid 171.22639 -295.341384)
					(end 171.22267 -295.332404)
				)
				(arc
					(start 171.22267 -294.837866)
					(mid 171.22639 -294.828886)
					(end 171.23537 -294.825166)
				)
				(arc
					(start 172.70857 -294.825166)
					(mid 172.71755 -294.828886)
					(end 172.72127 -294.837866)
				)
			)
		)
	)
	(zone
		(layer "In1.Cu")
		(hatch none 0.5)
		(connect_pads
			(clearance 0)
		)
		(min_thickness 0.25)
		(keepout
			(tracks not_allowed)
			(vias allowed)
			(pads allowed)
			(copperpour not_allowed)
			(footprints allowed)
		)
		(placement
			(enabled no)
			(sheetname "")
		)
		(fill
			(thermal_gap 0.5)
			(thermal_bridge_width 0.5)
			(island_removal_mode 0)
		)
		(polygon
			(pts
				(arc
					(start 52.633372 -231.582468)
					(mid 52.629652 -231.591448)
					(end 52.620672 -231.595168)
				)
				(arc
					(start 51.147472 -231.595168)
					(mid 51.138492 -231.591448)
					(end 51.134772 -231.582468)
				)
				(arc
					(start 51.134772 -231.08793)
					(mid 51.138492 -231.07895)
					(end 51.147472 -231.07523)
				)
				(arc
					(start 52.620672 -231.07523)
					(mid 52.629652 -231.07895)
					(end 52.633372 -231.08793)
				)
			)
		)
	)
	(zone
		(layer "In1.Cu")
		(hatch none 0.5)
		(connect_pads
			(clearance 0)
		)
		(min_thickness 0.25)
		(keepout
			(tracks not_allowed)
			(vias allowed)
			(pads allowed)
			(copperpour not_allowed)
			(footprints allowed)
		)
		(placement
			(enabled no)
			(sheetname "")
		)
		(fill
			(thermal_gap 0.5)
			(thermal_bridge_width 0.5)
			(island_removal_mode 0)
		)
		(polygon
			(pts
				(arc
					(start 428.205392 -293.632128)
					(mid 428.201672 -293.641108)
					(end 428.192692 -293.644828)
				)
				(arc
					(start 426.719492 -293.644828)
					(mid 426.710512 -293.641108)
					(end 426.706792 -293.632128)
				)
				(arc
					(start 426.706792 -293.13759)
					(mid 426.710512 -293.12861)
					(end 426.719492 -293.12489)
				)
				(arc
					(start 428.192692 -293.12489)
					(mid 428.201672 -293.12861)
					(end 428.205392 -293.13759)
				)
			)
		)
	)
	(zone
		(layer "In1.Cu")
		(hatch none 0.5)
		(connect_pads
			(clearance 0)
		)
		(min_thickness 0.25)
		(keepout
			(tracks not_allowed)
			(vias allowed)
			(pads allowed)
			(copperpour not_allowed)
			(footprints allowed)
		)
		(placement
			(enabled no)
			(sheetname "")
		)
		(fill
			(thermal_gap 0.5)
			(thermal_bridge_width 0.5)
			(island_removal_mode 0)
		)
		(polygon
			(pts
				(arc
					(start 56.077358 -245.18239)
					(mid 56.073638 -245.19137)
					(end 56.064658 -245.19509)
				)
				(arc
					(start 54.591458 -245.19509)
					(mid 54.582478 -245.19137)
					(end 54.578758 -245.18239)
				)
				(arc
					(start 54.578758 -244.687852)
					(mid 54.582478 -244.678872)
					(end 54.591458 -244.675152)
				)
				(arc
					(start 56.064658 -244.675152)
					(mid 56.073638 -244.678872)
					(end 56.077358 -244.687852)
				)
			)
		)
	)
	(zone
		(layer "In1.Cu")
		(hatch none 0.5)
		(connect_pads
			(clearance 0)
		)
		(min_thickness 0.25)
		(keepout
			(tracks not_allowed)
			(vias allowed)
			(pads allowed)
			(copperpour not_allowed)
			(footprints allowed)
		)
		(placement
			(enabled no)
			(sheetname "")
		)
		(fill
			(thermal_gap 0.5)
			(thermal_bridge_width 0.5)
			(island_removal_mode 0)
		)
		(polygon
			(pts
				(arc
					(start 191.909446 -217.982546)
					(mid 191.905726 -217.991526)
					(end 191.896746 -217.995246)
				)
				(arc
					(start 190.423546 -217.995246)
					(mid 190.414566 -217.991526)
					(end 190.410846 -217.982546)
				)
				(arc
					(start 190.410846 -217.488008)
					(mid 190.414566 -217.479028)
					(end 190.423546 -217.475308)
				)
				(arc
					(start 191.896746 -217.475308)
					(mid 191.905726 -217.479028)
					(end 191.909446 -217.488008)
				)
			)
		)
	)
	(zone
		(layer "In1.Cu")
		(hatch none 0.5)
		(connect_pads
			(clearance 0)
		)
		(min_thickness 0.25)
		(keepout
			(tracks not_allowed)
			(vias allowed)
			(pads allowed)
			(copperpour not_allowed)
			(footprints allowed)
		)
		(placement
			(enabled no)
			(sheetname "")
		)
		(fill
			(thermal_gap 0.5)
			(thermal_bridge_width 0.5)
			(island_removal_mode 0)
		)
		(polygon
			(pts
				(arc
					(start 306.5907 -381.824484)
					(mid 306.610624 -381.83372)
					(end 306.632356 -381.83693)
				)
				(arc
					(start 306.82692 -381.83693)
					(mid 306.880802 -381.814612)
					(end 306.90312 -381.76073)
				)
				(arc
					(start 306.90312 -381.07493)
					(mid 306.880802 -381.021048)
					(end 306.82692 -380.99873)
				)
				(arc
					(start 306.632356 -380.99873)
					(mid 306.610612 -381.001898)
					(end 306.5907 -381.011176)
				)
				(arc
					(start 306.294536 -381.203962)
					(mid 306.252852 -381.216184)
					(end 306.211224 -381.203708)
				)
				(arc
					(start 305.9176 -381.011176)
					(mid 305.897676 -381.00194)
					(end 305.875944 -380.99873)
				)
				(arc
					(start 305.68138 -380.99873)
					(mid 305.627498 -381.021048)
					(end 305.60518 -381.07493)
				)
				(arc
					(start 305.60518 -381.76073)
					(mid 305.627498 -381.814612)
					(end 305.68138 -381.83693)
				)
				(arc
					(start 305.877214 -381.83693)
					(mid 305.898958 -381.833762)
					(end 305.91887 -381.824484)
				)
				(arc
					(start 306.212494 -381.631952)
					(mid 306.25415 -381.61955)
					(end 306.295806 -381.631952)
				)
			)
		)
	)
	(zone
		(layer "In1.Cu")
		(hatch none 0.5)
		(connect_pads
			(clearance 0)
		)
		(min_thickness 0.25)
		(keepout
			(tracks not_allowed)
			(vias allowed)
			(pads allowed)
			(copperpour not_allowed)
			(footprints allowed)
		)
		(placement
			(enabled no)
			(sheetname "")
		)
		(fill
			(thermal_gap 0.5)
			(thermal_bridge_width 0.5)
			(island_removal_mode 0)
		)
		(polygon
			(pts
				(arc
					(start 372.491 -391.822686)
					(mid 372.618 -391.949686)
					(end 372.745 -391.822686)
				)
				(arc
					(start 372.745 -391.746486)
					(mid 372.618 -391.619486)
					(end 372.491 -391.746486)
				)
			)
		)
	)
	(zone
		(layer "In1.Cu")
		(hatch none 0.5)
		(connect_pads
			(clearance 0)
		)
		(min_thickness 0.25)
		(keepout
			(tracks not_allowed)
			(vias allowed)
			(pads allowed)
			(copperpour not_allowed)
			(footprints allowed)
		)
		(placement
			(enabled no)
			(sheetname "")
		)
		(fill
			(thermal_gap 0.5)
			(thermal_bridge_width 0.5)
			(island_removal_mode 0)
		)
		(polygon
			(pts
				(arc
					(start 195.353432 -211.182458)
					(mid 195.349712 -211.191438)
					(end 195.340732 -211.195158)
				)
				(arc
					(start 193.867532 -211.195158)
					(mid 193.858552 -211.191438)
					(end 193.854832 -211.182458)
				)
				(arc
					(start 193.854832 -210.68792)
					(mid 193.858552 -210.67894)
					(end 193.867532 -210.67522)
				)
				(arc
					(start 195.340732 -210.67522)
					(mid 195.349712 -210.67894)
					(end 195.353432 -210.68792)
				)
			)
		)
	)
	(zone
		(layer "In1.Cu")
		(hatch none 0.5)
		(connect_pads
			(clearance 0)
		)
		(min_thickness 0.25)
		(keepout
			(tracks not_allowed)
			(vias allowed)
			(pads allowed)
			(copperpour not_allowed)
			(footprints allowed)
		)
		(placement
			(enabled no)
			(sheetname "")
		)
		(fill
			(thermal_gap 0.5)
			(thermal_bridge_width 0.5)
			(island_removal_mode 0)
		)
		(polygon
			(pts
				(arc
					(start 266.29741 -229.882192)
					(mid 266.29369 -229.891172)
					(end 266.28471 -229.894892)
				)
				(arc
					(start 264.81151 -229.894892)
					(mid 264.80253 -229.891172)
					(end 264.79881 -229.882192)
				)
				(arc
					(start 264.79881 -229.387654)
					(mid 264.80253 -229.378674)
					(end 264.81151 -229.374954)
				)
				(arc
					(start 266.28471 -229.374954)
					(mid 266.29369 -229.378674)
					(end 266.29741 -229.387654)
				)
			)
		)
	)
	(zone
		(layer "In1.Cu")
		(hatch none 0.5)
		(connect_pads
			(clearance 0)
		)
		(min_thickness 0.25)
		(keepout
			(tracks not_allowed)
			(vias allowed)
			(pads allowed)
			(copperpour not_allowed)
			(footprints allowed)
		)
		(placement
			(enabled no)
			(sheetname "")
		)
		(fill
			(thermal_gap 0.5)
			(thermal_bridge_width 0.5)
			(island_removal_mode 0)
		)
		(polygon
			(pts
				(arc
					(start 432.30546 -238.382302)
					(mid 432.30174 -238.391282)
					(end 432.29276 -238.395002)
				)
				(arc
					(start 430.81956 -238.395002)
					(mid 430.81058 -238.391282)
					(end 430.80686 -238.382302)
				)
				(arc
					(start 430.80686 -237.887764)
					(mid 430.81058 -237.878784)
					(end 430.81956 -237.875064)
				)
				(arc
					(start 432.29276 -237.875064)
					(mid 432.30174 -237.878784)
					(end 432.30546 -237.887764)
				)
			)
		)
	)
	(zone
		(layer "In1.Cu")
		(hatch none 0.5)
		(connect_pads
			(clearance 0)
		)
		(min_thickness 0.25)
		(keepout
			(tracks not_allowed)
			(vias allowed)
			(pads allowed)
			(copperpour not_allowed)
			(footprints allowed)
		)
		(placement
			(enabled no)
			(sheetname "")
		)
		(fill
			(thermal_gap 0.5)
			(thermal_bridge_width 0.5)
			(island_removal_mode 0)
		)
		(polygon
			(pts
				(arc
					(start 296.473372 -250.282202)
					(mid 296.469652 -250.291182)
					(end 296.460672 -250.294902)
				)
				(arc
					(start 294.987472 -250.294902)
					(mid 294.978492 -250.291182)
					(end 294.974772 -250.282202)
				)
				(arc
					(start 294.974772 -249.787664)
					(mid 294.978492 -249.778684)
					(end 294.987472 -249.774964)
				)
				(arc
					(start 296.460672 -249.774964)
					(mid 296.469652 -249.778684)
					(end 296.473372 -249.787664)
				)
			)
		)
	)
	(zone
		(layer "In1.Cu")
		(hatch none 0.5)
		(connect_pads
			(clearance 0)
		)
		(min_thickness 0.25)
		(keepout
			(tracks not_allowed)
			(vias allowed)
			(pads allowed)
			(copperpour not_allowed)
			(footprints allowed)
		)
		(placement
			(enabled no)
			(sheetname "")
		)
		(fill
			(thermal_gap 0.5)
			(thermal_bridge_width 0.5)
			(island_removal_mode 0)
		)
		(polygon
			(pts
				(arc
					(start 317.39078 -391.822686)
					(mid 317.51778 -391.949686)
					(end 317.64478 -391.822686)
				)
				(arc
					(start 317.64478 -391.746486)
					(mid 317.51778 -391.619486)
					(end 317.39078 -391.746486)
				)
			)
		)
	)
	(zone
		(layer "In1.Cu")
		(hatch none 0.5)
		(connect_pads
			(clearance 0)
		)
		(min_thickness 0.25)
		(keepout
			(tracks not_allowed)
			(vias allowed)
			(pads allowed)
			(copperpour not_allowed)
			(footprints allowed)
		)
		(placement
			(enabled no)
			(sheetname "")
		)
		(fill
			(thermal_gap 0.5)
			(thermal_bridge_width 0.5)
			(island_removal_mode 0)
		)
		(polygon
			(pts
				(arc
					(start 202.897232 -268.982444)
					(mid 202.893512 -268.991424)
					(end 202.884532 -268.995144)
				)
				(arc
					(start 201.411332 -268.995144)
					(mid 201.402352 -268.991424)
					(end 201.398632 -268.982444)
				)
				(arc
					(start 201.398632 -268.487906)
					(mid 201.402352 -268.478926)
					(end 201.411332 -268.475206)
				)
				(arc
					(start 202.884532 -268.475206)
					(mid 202.893512 -268.478926)
					(end 202.897232 -268.487906)
				)
			)
		)
	)
	(zone
		(layer "In1.Cu")
		(hatch none 0.5)
		(connect_pads
			(clearance 0)
		)
		(min_thickness 0.25)
		(keepout
			(tracks not_allowed)
			(vias allowed)
			(pads allowed)
			(copperpour not_allowed)
			(footprints allowed)
		)
		(placement
			(enabled no)
			(sheetname "")
		)
		(fill
			(thermal_gap 0.5)
			(thermal_bridge_width 0.5)
			(island_removal_mode 0)
		)
		(polygon
			(pts
				(arc
					(start 288.929318 -305.532282)
					(mid 288.925598 -305.541262)
					(end 288.916618 -305.544982)
				)
				(arc
					(start 287.443418 -305.544982)
					(mid 287.434438 -305.541262)
					(end 287.430718 -305.532282)
				)
				(arc
					(start 287.430718 -305.037744)
					(mid 287.434438 -305.028764)
					(end 287.443418 -305.025044)
				)
				(arc
					(start 288.916618 -305.025044)
					(mid 288.925598 -305.028764)
					(end 288.929318 -305.037744)
				)
			)
		)
	)
	(zone
		(layer "In1.Cu")
		(hatch none 0.5)
		(connect_pads
			(clearance 0)
		)
		(min_thickness 0.25)
		(keepout
			(tracks not_allowed)
			(vias allowed)
			(pads allowed)
			(copperpour not_allowed)
			(footprints allowed)
		)
		(placement
			(enabled no)
			(sheetname "")
		)
		(fill
			(thermal_gap 0.5)
			(thermal_bridge_width 0.5)
			(island_removal_mode 0)
		)
		(polygon
			(pts
				(arc
					(start 191.909446 -308.082442)
					(mid 191.905726 -308.091422)
					(end 191.896746 -308.095142)
				)
				(arc
					(start 190.423546 -308.095142)
					(mid 190.414566 -308.091422)
					(end 190.410846 -308.082442)
				)
				(arc
					(start 190.410846 -307.587904)
					(mid 190.414566 -307.578924)
					(end 190.423546 -307.575204)
				)
				(arc
					(start 191.896746 -307.575204)
					(mid 191.905726 -307.578924)
					(end 191.909446 -307.587904)
				)
			)
		)
	)
	(zone
		(layer "In1.Cu")
		(hatch none 0.5)
		(connect_pads
			(clearance 0)
		)
		(min_thickness 0.25)
		(keepout
			(tracks not_allowed)
			(vias allowed)
			(pads allowed)
			(copperpour not_allowed)
			(footprints allowed)
		)
		(placement
			(enabled no)
			(sheetname "")
		)
		(fill
			(thermal_gap 0.5)
			(thermal_bridge_width 0.5)
			(island_removal_mode 0)
		)
		(polygon
			(pts
				(arc
					(start 165.177216 -295.332404)
					(mid 165.173496 -295.341384)
					(end 165.164516 -295.345104)
				)
				(arc
					(start 163.691316 -295.345104)
					(mid 163.682336 -295.341384)
					(end 163.678616 -295.332404)
				)
				(arc
					(start 163.678616 -294.837866)
					(mid 163.682336 -294.828886)
					(end 163.691316 -294.825166)
				)
				(arc
					(start 165.164516 -294.825166)
					(mid 165.173496 -294.828886)
					(end 165.177216 -294.837866)
				)
			)
		)
	)
	(zone
		(layer "In1.Cu")
		(hatch none 0.5)
		(connect_pads
			(clearance 0)
		)
		(min_thickness 0.25)
		(keepout
			(tracks not_allowed)
			(vias allowed)
			(pads allowed)
			(copperpour not_allowed)
			(footprints allowed)
		)
		(placement
			(enabled no)
			(sheetname "")
		)
		(fill
			(thermal_gap 0.5)
			(thermal_bridge_width 0.5)
			(island_removal_mode 0)
		)
		(polygon
			(pts
				(arc
					(start 424.761406 -233.282236)
					(mid 424.757686 -233.291216)
					(end 424.748706 -233.294936)
				)
				(arc
					(start 423.275506 -233.294936)
					(mid 423.266526 -233.291216)
					(end 423.262806 -233.282236)
				)
				(arc
					(start 423.262806 -232.787698)
					(mid 423.266526 -232.778718)
					(end 423.275506 -232.774998)
				)
				(arc
					(start 424.748706 -232.774998)
					(mid 424.757686 -232.778718)
					(end 424.761406 -232.787698)
				)
			)
		)
	)
	(zone
		(layer "In1.Cu")
		(hatch none 0.5)
		(connect_pads
			(clearance 0)
		)
		(min_thickness 0.25)
		(keepout
			(tracks not_allowed)
			(vias allowed)
			(pads allowed)
			(copperpour not_allowed)
			(footprints allowed)
		)
		(placement
			(enabled no)
			(sheetname "")
		)
		(fill
			(thermal_gap 0.5)
			(thermal_bridge_width 0.5)
			(island_removal_mode 0)
		)
		(polygon
			(pts
				(arc
					(start 156.218636 -383.440686)
					(mid 156.345636 -383.567686)
					(end 156.472636 -383.440686)
				)
				(arc
					(start 156.472636 -383.364486)
					(mid 156.345636 -383.237486)
					(end 156.218636 -383.364486)
				)
			)
		)
	)
	(zone
		(layer "In1.Cu")
		(hatch none 0.5)
		(connect_pads
			(clearance 0)
		)
		(min_thickness 0.25)
		(keepout
			(tracks not_allowed)
			(vias allowed)
			(pads allowed)
			(copperpour not_allowed)
			(footprints allowed)
		)
		(placement
			(enabled no)
			(sheetname "")
		)
		(fill
			(thermal_gap 0.5)
			(thermal_bridge_width 0.5)
			(island_removal_mode 0)
		)
		(polygon
			(pts
				(arc
					(start 407.088848 -397.849344)
					(mid 406.707848 -397.849344)
					(end 407.088848 -397.849344)
				)
			)
		)
	)
	(zone
		(layer "In1.Cu")
		(hatch none 0.5)
		(connect_pads
			(clearance 0)
		)
		(min_thickness 0.25)
		(keepout
			(tracks not_allowed)
			(vias allowed)
			(pads allowed)
			(copperpour not_allowed)
			(footprints allowed)
		)
		(placement
			(enabled no)
			(sheetname "")
		)
		(fill
			(thermal_gap 0.5)
			(thermal_bridge_width 0.5)
			(island_removal_mode 0)
		)
		(polygon
			(pts
				(arc
					(start 308.117494 -212.882226)
					(mid 308.113774 -212.891206)
					(end 308.104794 -212.894926)
				)
				(arc
					(start 306.631594 -212.894926)
					(mid 306.622614 -212.891206)
					(end 306.618894 -212.882226)
				)
				(arc
					(start 306.618894 -212.387688)
					(mid 306.622614 -212.378708)
					(end 306.631594 -212.374988)
				)
				(arc
					(start 308.104794 -212.374988)
					(mid 308.113774 -212.378708)
					(end 308.117494 -212.387688)
				)
			)
		)
	)
	(zone
		(layer "In1.Cu")
		(hatch none 0.5)
		(connect_pads
			(clearance 0)
		)
		(min_thickness 0.25)
		(keepout
			(tracks not_allowed)
			(vias allowed)
			(pads allowed)
			(copperpour not_allowed)
			(footprints allowed)
		)
		(placement
			(enabled no)
			(sheetname "")
		)
		(fill
			(thermal_gap 0.5)
			(thermal_bridge_width 0.5)
			(island_removal_mode 0)
		)
		(polygon
			(pts
				(arc
					(start 52.633372 -285.98241)
					(mid 52.629652 -285.99139)
					(end 52.620672 -285.99511)
				)
				(arc
					(start 51.147472 -285.99511)
					(mid 51.138492 -285.99139)
					(end 51.134772 -285.98241)
				)
				(arc
					(start 51.134772 -285.487872)
					(mid 51.138492 -285.478892)
					(end 51.147472 -285.475172)
				)
				(arc
					(start 52.620672 -285.475172)
					(mid 52.629652 -285.478892)
					(end 52.633372 -285.487872)
				)
			)
		)
	)
	(zone
		(layer "In1.Cu")
		(hatch none 0.5)
		(connect_pads
			(clearance 0)
		)
		(min_thickness 0.25)
		(keepout
			(tracks not_allowed)
			(vias allowed)
			(pads allowed)
			(copperpour not_allowed)
			(footprints allowed)
		)
		(placement
			(enabled no)
			(sheetname "")
		)
		(fill
			(thermal_gap 0.5)
			(thermal_bridge_width 0.5)
			(island_removal_mode 0)
		)
		(polygon
			(pts
				(arc
					(start 273.841464 -209.482182)
					(mid 273.837744 -209.491162)
					(end 273.828764 -209.494882)
				)
				(arc
					(start 272.355564 -209.494882)
					(mid 272.346584 -209.491162)
					(end 272.342864 -209.482182)
				)
				(arc
					(start 272.342864 -208.987644)
					(mid 272.346584 -208.978664)
					(end 272.355564 -208.974944)
				)
				(arc
					(start 273.828764 -208.974944)
					(mid 273.837744 -208.978664)
					(end 273.841464 -208.987644)
				)
			)
		)
	)
	(zone
		(layer "In1.Cu")
		(hatch none 0.5)
		(connect_pads
			(clearance 0)
		)
		(min_thickness 0.25)
		(keepout
			(tracks not_allowed)
			(vias allowed)
			(pads allowed)
			(copperpour not_allowed)
			(footprints allowed)
		)
		(placement
			(enabled no)
			(sheetname "")
		)
		(fill
			(thermal_gap 0.5)
			(thermal_bridge_width 0.5)
			(island_removal_mode 0)
		)
		(polygon
			(pts
				(arc
					(start 265.87831 -289.985196)
					(mid 265.21791 -289.985196)
					(end 265.87831 -289.985196)
				)
			)
		)
	)
	(zone
		(layer "In1.Cu")
		(hatch none 0.5)
		(connect_pads
			(clearance 0)
		)
		(min_thickness 0.25)
		(keepout
			(tracks not_allowed)
			(vias allowed)
			(pads allowed)
			(copperpour not_allowed)
			(footprints allowed)
		)
		(placement
			(enabled no)
			(sheetname "")
		)
		(fill
			(thermal_gap 0.5)
			(thermal_bridge_width 0.5)
			(island_removal_mode 0)
		)
		(polygon
			(pts
				(arc
					(start 293.029386 -242.63223)
					(mid 293.025666 -242.64121)
					(end 293.016686 -242.64493)
				)
				(arc
					(start 291.543486 -242.64493)
					(mid 291.534506 -242.64121)
					(end 291.530786 -242.63223)
				)
				(arc
					(start 291.530786 -242.137692)
					(mid 291.534506 -242.128712)
					(end 291.543486 -242.124992)
				)
				(arc
					(start 293.016686 -242.124992)
					(mid 293.025666 -242.128712)
					(end 293.029386 -242.137692)
				)
			)
		)
	)
	(zone
		(layer "In1.Cu")
		(hatch none 0.5)
		(connect_pads
			(clearance 0)
		)
		(min_thickness 0.25)
		(keepout
			(tracks not_allowed)
			(vias allowed)
			(pads allowed)
			(copperpour not_allowed)
			(footprints allowed)
		)
		(placement
			(enabled no)
			(sheetname "")
		)
		(fill
			(thermal_gap 0.5)
			(thermal_bridge_width 0.5)
			(island_removal_mode 0)
		)
		(polygon
			(pts
				(arc
					(start 270.397478 -212.882226)
					(mid 270.393758 -212.891206)
					(end 270.384778 -212.894926)
				)
				(arc
					(start 268.911578 -212.894926)
					(mid 268.902598 -212.891206)
					(end 268.898878 -212.882226)
				)
				(arc
					(start 268.898878 -212.387688)
					(mid 268.902598 -212.378708)
					(end 268.911578 -212.374988)
				)
				(arc
					(start 270.384778 -212.374988)
					(mid 270.393758 -212.378708)
					(end 270.397478 -212.387688)
				)
			)
		)
	)
	(zone
		(layer "In1.Cu")
		(hatch none 0.5)
		(connect_pads
			(clearance 0)
		)
		(min_thickness 0.25)
		(keepout
			(tracks not_allowed)
			(vias allowed)
			(pads allowed)
			(copperpour not_allowed)
			(footprints allowed)
		)
		(placement
			(enabled no)
			(sheetname "")
		)
		(fill
			(thermal_gap 0.5)
			(thermal_bridge_width 0.5)
			(island_removal_mode 0)
		)
		(polygon
			(pts
				(arc
					(start 37.545264 -208.632552)
					(mid 37.541544 -208.641532)
					(end 37.532564 -208.645252)
				)
				(arc
					(start 36.059364 -208.645252)
					(mid 36.050384 -208.641532)
					(end 36.046664 -208.632552)
				)
				(arc
					(start 36.046664 -208.138014)
					(mid 36.050384 -208.129034)
					(end 36.059364 -208.125314)
				)
				(arc
					(start 37.532564 -208.125314)
					(mid 37.541544 -208.129034)
					(end 37.545264 -208.138014)
				)
			)
		)
	)
	(zone
		(layer "In1.Cu")
		(hatch none 0.5)
		(connect_pads
			(clearance 0)
		)
		(min_thickness 0.25)
		(keepout
			(tracks not_allowed)
			(vias allowed)
			(pads allowed)
			(copperpour not_allowed)
			(footprints allowed)
		)
		(placement
			(enabled no)
			(sheetname "")
		)
		(fill
			(thermal_gap 0.5)
			(thermal_bridge_width 0.5)
			(island_removal_mode 0)
		)
		(polygon
			(pts
				(arc
					(start 128.161034 -389.467344)
					(mid 127.780034 -389.467344)
					(end 128.161034 -389.467344)
				)
			)
		)
	)
	(zone
		(layer "In1.Cu")
		(hatch none 0.5)
		(connect_pads
			(clearance 0)
		)
		(min_thickness 0.25)
		(keepout
			(tracks not_allowed)
			(vias allowed)
			(pads allowed)
			(copperpour not_allowed)
			(footprints allowed)
		)
		(placement
			(enabled no)
			(sheetname "")
		)
		(fill
			(thermal_gap 0.5)
			(thermal_bridge_width 0.5)
			(island_removal_mode 0)
		)
		(polygon
			(pts
				(arc
					(start 450.8373 -276.632162)
					(mid 450.83358 -276.641142)
					(end 450.8246 -276.644862)
				)
				(arc
					(start 449.3514 -276.644862)
					(mid 449.34242 -276.641142)
					(end 449.3387 -276.632162)
				)
				(arc
					(start 449.3387 -276.137624)
					(mid 449.34242 -276.128644)
					(end 449.3514 -276.124924)
				)
				(arc
					(start 450.8246 -276.124924)
					(mid 450.83358 -276.128644)
					(end 450.8373 -276.137624)
				)
			)
		)
	)
	(zone
		(layer "In1.Cu")
		(hatch none 0.5)
		(connect_pads
			(clearance 0)
		)
		(min_thickness 0.25)
		(keepout
			(tracks not_allowed)
			(vias allowed)
			(pads allowed)
			(copperpour not_allowed)
			(footprints allowed)
		)
		(placement
			(enabled no)
			(sheetname "")
		)
		(fill
			(thermal_gap 0.5)
			(thermal_bridge_width 0.5)
			(island_removal_mode 0)
		)
		(polygon
			(pts
				(arc
					(start 273.841464 -217.132154)
					(mid 273.837744 -217.141134)
					(end 273.828764 -217.144854)
				)
				(arc
					(start 272.355564 -217.144854)
					(mid 272.346584 -217.141134)
					(end 272.342864 -217.132154)
				)
				(arc
					(start 272.342864 -216.637616)
					(mid 272.346584 -216.628636)
					(end 272.355564 -216.624916)
				)
				(arc
					(start 273.828764 -216.624916)
					(mid 273.837744 -216.628636)
					(end 273.841464 -216.637616)
				)
			)
		)
	)
	(zone
		(layer "In1.Cu")
		(hatch none 0.5)
		(connect_pads
			(clearance 0)
		)
		(min_thickness 0.25)
		(keepout
			(tracks not_allowed)
			(vias allowed)
			(pads allowed)
			(copperpour not_allowed)
			(footprints allowed)
		)
		(placement
			(enabled no)
			(sheetname "")
		)
		(fill
			(thermal_gap 0.5)
			(thermal_bridge_width 0.5)
			(island_removal_mode 0)
		)
		(polygon
			(pts
				(arc
					(start 435.749446 -263.882124)
					(mid 435.745726 -263.891104)
					(end 435.736746 -263.894824)
				)
				(arc
					(start 434.263546 -263.894824)
					(mid 434.254566 -263.891104)
					(end 434.250846 -263.882124)
				)
				(arc
					(start 434.250846 -263.387586)
					(mid 434.254566 -263.378606)
					(end 434.263546 -263.374886)
				)
				(arc
					(start 435.736746 -263.374886)
					(mid 435.745726 -263.378606)
					(end 435.749446 -263.387586)
				)
			)
		)
	)
	(zone
		(layer "In1.Cu")
		(hatch none 0.5)
		(connect_pads
			(clearance 0)
		)
		(min_thickness 0.25)
		(keepout
			(tracks not_allowed)
			(vias allowed)
			(pads allowed)
			(copperpour not_allowed)
			(footprints allowed)
		)
		(placement
			(enabled no)
			(sheetname "")
		)
		(fill
			(thermal_gap 0.5)
			(thermal_bridge_width 0.5)
			(island_removal_mode 0)
		)
		(polygon
			(pts
				(arc
					(start 148.688806 -386.003292)
					(mid 148.307806 -386.003292)
					(end 148.688806 -386.003292)
				)
			)
		)
	)
	(zone
		(layer "In1.Cu")
		(hatch none 0.5)
		(connect_pads
			(clearance 0)
		)
		(min_thickness 0.25)
		(keepout
			(tracks not_allowed)
			(vias allowed)
			(pads allowed)
			(copperpour not_allowed)
			(footprints allowed)
		)
		(placement
			(enabled no)
			(sheetname "")
		)
		(fill
			(thermal_gap 0.5)
			(thermal_bridge_width 0.5)
			(island_removal_mode 0)
		)
		(polygon
			(pts
				(arc
					(start 30.001464 -252.832362)
					(mid 29.997744 -252.841342)
					(end 29.988764 -252.845062)
				)
				(arc
					(start 28.515564 -252.845062)
					(mid 28.506584 -252.841342)
					(end 28.502864 -252.832362)
				)
				(arc
					(start 28.502864 -252.337824)
					(mid 28.506584 -252.328844)
					(end 28.515564 -252.325124)
				)
				(arc
					(start 29.988764 -252.325124)
					(mid 29.997744 -252.328844)
					(end 30.001464 -252.337824)
				)
			)
		)
	)
	(zone
		(layer "In1.Cu")
		(hatch none 0.5)
		(connect_pads
			(clearance 0)
		)
		(min_thickness 0.25)
		(keepout
			(tracks not_allowed)
			(vias allowed)
			(pads allowed)
			(copperpour not_allowed)
			(footprints allowed)
		)
		(placement
			(enabled no)
			(sheetname "")
		)
		(fill
			(thermal_gap 0.5)
			(thermal_bridge_width 0.5)
			(island_removal_mode 0)
		)
		(polygon
			(pts
				(arc
					(start 304.017426 -237.532164)
					(mid 304.013706 -237.541144)
					(end 304.004726 -237.544864)
				)
				(arc
					(start 302.531526 -237.544864)
					(mid 302.522546 -237.541144)
					(end 302.518826 -237.532164)
				)
				(arc
					(start 302.518826 -237.037626)
					(mid 302.522546 -237.028646)
					(end 302.531526 -237.024926)
				)
				(arc
					(start 304.004726 -237.024926)
					(mid 304.013706 -237.028646)
					(end 304.017426 -237.037626)
				)
			)
		)
	)
	(zone
		(layer "In1.Cu")
		(hatch none 0.5)
		(connect_pads
			(clearance 0)
		)
		(min_thickness 0.25)
		(keepout
			(tracks not_allowed)
			(vias allowed)
			(pads allowed)
			(copperpour not_allowed)
			(footprints allowed)
		)
		(placement
			(enabled no)
			(sheetname "")
		)
		(fill
			(thermal_gap 0.5)
			(thermal_bridge_width 0.5)
			(island_removal_mode 0)
		)
		(polygon
			(pts
				(arc
					(start 424.761406 -308.082188)
					(mid 424.757686 -308.091168)
					(end 424.748706 -308.094888)
				)
				(arc
					(start 423.275506 -308.094888)
					(mid 423.266526 -308.091168)
					(end 423.262806 -308.082188)
				)
				(arc
					(start 423.262806 -307.58765)
					(mid 423.266526 -307.57867)
					(end 423.275506 -307.57495)
				)
				(arc
					(start 424.748706 -307.57495)
					(mid 424.757686 -307.57867)
					(end 424.761406 -307.58765)
				)
			)
		)
	)
	(zone
		(layer "In1.Cu")
		(hatch none 0.5)
		(connect_pads
			(clearance 0)
		)
		(min_thickness 0.25)
		(keepout
			(tracks not_allowed)
			(vias allowed)
			(pads allowed)
			(copperpour not_allowed)
			(footprints allowed)
		)
		(placement
			(enabled no)
			(sheetname "")
		)
		(fill
			(thermal_gap 0.5)
			(thermal_bridge_width 0.5)
			(island_removal_mode 0)
		)
		(polygon
			(pts
				(arc
					(start 288.929318 -240.082324)
					(mid 288.925598 -240.091304)
					(end 288.916618 -240.095024)
				)
				(arc
					(start 287.443418 -240.095024)
					(mid 287.434438 -240.091304)
					(end 287.430718 -240.082324)
				)
				(arc
					(start 287.430718 -239.587786)
					(mid 287.434438 -239.578806)
					(end 287.443418 -239.575086)
				)
				(arc
					(start 288.916618 -239.575086)
					(mid 288.925598 -239.578806)
					(end 288.929318 -239.587786)
				)
			)
		)
	)
	(zone
		(layer "In1.Cu")
		(hatch none 0.5)
		(connect_pads
			(clearance 0)
		)
		(min_thickness 0.25)
		(keepout
			(tracks not_allowed)
			(vias allowed)
			(pads allowed)
			(copperpour not_allowed)
			(footprints allowed)
		)
		(placement
			(enabled no)
			(sheetname "")
		)
		(fill
			(thermal_gap 0.5)
			(thermal_bridge_width 0.5)
			(island_removal_mode 0)
		)
		(polygon
			(pts
				(arc
					(start 25.901396 -262.182356)
					(mid 25.897676 -262.191336)
					(end 25.888696 -262.195056)
				)
				(arc
					(start 24.415496 -262.195056)
					(mid 24.406516 -262.191336)
					(end 24.402796 -262.182356)
				)
				(arc
					(start 24.402796 -261.687818)
					(mid 24.406516 -261.678838)
					(end 24.415496 -261.675118)
				)
				(arc
					(start 25.888696 -261.675118)
					(mid 25.897676 -261.678838)
					(end 25.901396 -261.687818)
				)
			)
		)
	)
	(zone
		(layer "In1.Cu")
		(hatch none 0.5)
		(connect_pads
			(clearance 0)
		)
		(min_thickness 0.25)
		(keepout
			(tracks not_allowed)
			(vias allowed)
			(pads allowed)
			(copperpour not_allowed)
			(footprints allowed)
		)
		(placement
			(enabled no)
			(sheetname "")
		)
		(fill
			(thermal_gap 0.5)
			(thermal_bridge_width 0.5)
			(island_removal_mode 0)
		)
		(polygon
			(pts
				(arc
					(start 319.790826 -399.701258)
					(mid 319.917826 -399.828258)
					(end 320.044826 -399.701258)
				)
				(arc
					(start 320.044826 -399.625058)
					(mid 319.917826 -399.498058)
					(end 319.790826 -399.625058)
				)
			)
		)
	)
	(zone
		(layer "In1.Cu")
		(hatch none 0.5)
		(connect_pads
			(clearance 0)
		)
		(min_thickness 0.25)
		(keepout
			(tracks not_allowed)
			(vias allowed)
			(pads allowed)
			(copperpour not_allowed)
			(footprints allowed)
		)
		(placement
			(enabled no)
			(sheetname "")
		)
		(fill
			(thermal_gap 0.5)
			(thermal_bridge_width 0.5)
			(island_removal_mode 0)
		)
		(polygon
			(pts
				(arc
					(start 288.929318 -282.582112)
					(mid 288.925598 -282.591092)
					(end 288.916618 -282.594812)
				)
				(arc
					(start 287.443418 -282.594812)
					(mid 287.434438 -282.591092)
					(end 287.430718 -282.582112)
				)
				(arc
					(start 287.430718 -282.087574)
					(mid 287.434438 -282.078594)
					(end 287.443418 -282.074874)
				)
				(arc
					(start 288.916618 -282.074874)
					(mid 288.925598 -282.078594)
					(end 288.929318 -282.087574)
				)
			)
		)
	)
	(zone
		(layer "In1.Cu")
		(hatch none 0.5)
		(connect_pads
			(clearance 0)
		)
		(min_thickness 0.25)
		(keepout
			(tracks not_allowed)
			(vias allowed)
			(pads allowed)
			(copperpour not_allowed)
			(footprints allowed)
		)
		(placement
			(enabled no)
			(sheetname "")
		)
		(fill
			(thermal_gap 0.5)
			(thermal_bridge_width 0.5)
			(island_removal_mode 0)
		)
		(polygon
			(pts
				(arc
					(start 273.841464 -212.032088)
					(mid 273.837744 -212.041068)
					(end 273.828764 -212.044788)
				)
				(arc
					(start 272.355564 -212.044788)
					(mid 272.346584 -212.041068)
					(end 272.342864 -212.032088)
				)
				(arc
					(start 272.342864 -211.53755)
					(mid 272.346584 -211.52857)
					(end 272.355564 -211.52485)
				)
				(arc
					(start 273.828764 -211.52485)
					(mid 273.837744 -211.52857)
					(end 273.841464 -211.53755)
				)
			)
		)
	)
	(zone
		(layer "In1.Cu")
		(hatch none 0.5)
		(connect_pads
			(clearance 0)
		)
		(min_thickness 0.25)
		(keepout
			(tracks not_allowed)
			(vias allowed)
			(pads allowed)
			(copperpour not_allowed)
			(footprints allowed)
		)
		(placement
			(enabled no)
			(sheetname "")
		)
		(fill
			(thermal_gap 0.5)
			(thermal_bridge_width 0.5)
			(island_removal_mode 0)
		)
		(polygon
			(pts
				(arc
					(start 206.9973 -249.432572)
					(mid 206.99358 -249.441552)
					(end 206.9846 -249.445272)
				)
				(arc
					(start 205.5114 -249.445272)
					(mid 205.50242 -249.441552)
					(end 205.4987 -249.432572)
				)
				(arc
					(start 205.4987 -248.938034)
					(mid 205.50242 -248.929054)
					(end 205.5114 -248.925334)
				)
				(arc
					(start 206.9846 -248.925334)
					(mid 206.99358 -248.929054)
					(end 206.9973 -248.938034)
				)
			)
		)
	)
	(zone
		(layer "In1.Cu")
		(hatch none 0.5)
		(connect_pads
			(clearance 0)
		)
		(min_thickness 0.25)
		(keepout
			(tracks not_allowed)
			(vias allowed)
			(pads allowed)
			(copperpour not_allowed)
			(footprints allowed)
		)
		(placement
			(enabled no)
			(sheetname "")
		)
		(fill
			(thermal_gap 0.5)
			(thermal_bridge_width 0.5)
			(island_removal_mode 0)
		)
		(polygon
			(pts
				(arc
					(start 56.077358 -232.432352)
					(mid 56.073638 -232.441332)
					(end 56.064658 -232.445052)
				)
				(arc
					(start 54.591458 -232.445052)
					(mid 54.582478 -232.441332)
					(end 54.578758 -232.432352)
				)
				(arc
					(start 54.578758 -231.937814)
					(mid 54.582478 -231.928834)
					(end 54.591458 -231.925114)
				)
				(arc
					(start 56.064658 -231.925114)
					(mid 56.073638 -231.928834)
					(end 56.077358 -231.937814)
				)
			)
		)
	)
	(zone
		(layer "In1.Cu")
		(hatch none 0.5)
		(connect_pads
			(clearance 0)
		)
		(min_thickness 0.25)
		(keepout
			(tracks not_allowed)
			(vias allowed)
			(pads allowed)
			(copperpour not_allowed)
			(footprints allowed)
		)
		(placement
			(enabled no)
			(sheetname "")
		)
		(fill
			(thermal_gap 0.5)
			(thermal_bridge_width 0.5)
			(island_removal_mode 0)
		)
		(polygon
			(pts
				(arc
					(start 296.473372 -220.532198)
					(mid 296.469652 -220.541178)
					(end 296.460672 -220.544898)
				)
				(arc
					(start 294.987472 -220.544898)
					(mid 294.978492 -220.541178)
					(end 294.974772 -220.532198)
				)
				(arc
					(start 294.974772 -220.03766)
					(mid 294.978492 -220.02868)
					(end 294.987472 -220.02496)
				)
				(arc
					(start 296.460672 -220.02496)
					(mid 296.469652 -220.02868)
					(end 296.473372 -220.03766)
				)
			)
		)
	)
	(zone
		(layer "In1.Cu")
		(hatch none 0.5)
		(connect_pads
			(clearance 0)
		)
		(min_thickness 0.25)
		(keepout
			(tracks not_allowed)
			(vias allowed)
			(pads allowed)
			(copperpour not_allowed)
			(footprints allowed)
		)
		(placement
			(enabled no)
			(sheetname "")
		)
		(fill
			(thermal_gap 0.5)
			(thermal_bridge_width 0.5)
			(island_removal_mode 0)
		)
		(polygon
			(pts
				(arc
					(start 56.077358 -310.632348)
					(mid 56.073638 -310.641328)
					(end 56.064658 -310.645048)
				)
				(arc
					(start 54.591458 -310.645048)
					(mid 54.582478 -310.641328)
					(end 54.578758 -310.632348)
				)
				(arc
					(start 54.578758 -310.13781)
					(mid 54.582478 -310.12883)
					(end 54.591458 -310.12511)
				)
				(arc
					(start 56.064658 -310.12511)
					(mid 56.073638 -310.12883)
					(end 56.077358 -310.13781)
				)
			)
		)
	)
	(zone
		(layer "In1.Cu")
		(hatch none 0.5)
		(connect_pads
			(clearance 0)
		)
		(min_thickness 0.25)
		(keepout
			(tracks not_allowed)
			(vias allowed)
			(pads allowed)
			(copperpour not_allowed)
			(footprints allowed)
		)
		(placement
			(enabled no)
			(sheetname "")
		)
		(fill
			(thermal_gap 0.5)
			(thermal_bridge_width 0.5)
			(island_removal_mode 0)
		)
		(polygon
			(pts
				(arc
					(start 187.809378 -232.432352)
					(mid 187.805658 -232.441332)
					(end 187.796678 -232.445052)
				)
				(arc
					(start 186.323478 -232.445052)
					(mid 186.314498 -232.441332)
					(end 186.310778 -232.432352)
				)
				(arc
					(start 186.310778 -231.937814)
					(mid 186.314498 -231.928834)
					(end 186.323478 -231.925114)
				)
				(arc
					(start 187.796678 -231.925114)
					(mid 187.805658 -231.928834)
					(end 187.809378 -231.937814)
				)
			)
		)
	)
	(zone
		(layer "In1.Cu")
		(hatch none 0.5)
		(connect_pads
			(clearance 0)
		)
		(min_thickness 0.25)
		(keepout
			(tracks not_allowed)
			(vias allowed)
			(pads allowed)
			(copperpour not_allowed)
			(footprints allowed)
		)
		(placement
			(enabled no)
			(sheetname "")
		)
		(fill
			(thermal_gap 0.5)
			(thermal_bridge_width 0.5)
			(island_removal_mode 0)
		)
		(polygon
			(pts
				(arc
					(start 281.385264 -297.88231)
					(mid 281.381544 -297.89129)
					(end 281.372564 -297.89501)
				)
				(arc
					(start 279.899364 -297.89501)
					(mid 279.890384 -297.89129)
					(end 279.886664 -297.88231)
				)
				(arc
					(start 279.886664 -297.387772)
					(mid 279.890384 -297.378792)
					(end 279.899364 -297.375072)
				)
				(arc
					(start 281.372564 -297.375072)
					(mid 281.381544 -297.378792)
					(end 281.385264 -297.387772)
				)
			)
		)
	)
	(zone
		(layer "In1.Cu")
		(hatch none 0.5)
		(connect_pads
			(clearance 0)
		)
		(min_thickness 0.25)
		(keepout
			(tracks not_allowed)
			(vias allowed)
			(pads allowed)
			(copperpour not_allowed)
			(footprints allowed)
		)
		(placement
			(enabled no)
			(sheetname "")
		)
		(fill
			(thermal_gap 0.5)
			(thermal_bridge_width 0.5)
			(island_removal_mode 0)
		)
		(polygon
			(pts
				(arc
					(start 443.2935 -307.232304)
					(mid 443.28978 -307.241284)
					(end 443.2808 -307.245004)
				)
				(arc
					(start 441.8076 -307.245004)
					(mid 441.79862 -307.241284)
					(end 441.7949 -307.232304)
				)
				(arc
					(start 441.7949 -306.737766)
					(mid 441.79862 -306.728786)
					(end 441.8076 -306.725066)
				)
				(arc
					(start 443.2808 -306.725066)
					(mid 443.28978 -306.728786)
					(end 443.2935 -306.737766)
				)
			)
		)
	)
	(zone
		(layer "In1.Cu")
		(hatch none 0.5)
		(connect_pads
			(clearance 0)
		)
		(min_thickness 0.25)
		(keepout
			(tracks not_allowed)
			(vias allowed)
			(pads allowed)
			(copperpour not_allowed)
			(footprints allowed)
		)
		(placement
			(enabled no)
			(sheetname "")
		)
		(fill
			(thermal_gap 0.5)
			(thermal_bridge_width 0.5)
			(island_removal_mode 0)
		)
		(polygon
			(pts
				(arc
					(start 45.089318 -292.782498)
					(mid 45.085598 -292.791478)
					(end 45.076618 -292.795198)
				)
				(arc
					(start 43.603418 -292.795198)
					(mid 43.594438 -292.791478)
					(end 43.590718 -292.782498)
				)
				(arc
					(start 43.590718 -292.28796)
					(mid 43.594438 -292.27898)
					(end 43.603418 -292.27526)
				)
				(arc
					(start 45.076618 -292.27526)
					(mid 45.085598 -292.27898)
					(end 45.089318 -292.28796)
				)
			)
		)
	)
	(zone
		(layer "In1.Cu")
		(hatch none 0.5)
		(connect_pads
			(clearance 0)
		)
		(min_thickness 0.25)
		(keepout
			(tracks not_allowed)
			(vias allowed)
			(pads allowed)
			(copperpour not_allowed)
			(footprints allowed)
		)
		(placement
			(enabled no)
			(sheetname "")
		)
		(fill
			(thermal_gap 0.5)
			(thermal_bridge_width 0.5)
			(island_removal_mode 0)
		)
		(polygon
			(pts
				(arc
					(start 92.098114 -390.761474)
					(mid 91.793314 -390.761474)
					(end 92.098114 -390.761474)
				)
			)
		)
	)
	(zone
		(layer "In1.Cu")
		(hatch none 0.5)
		(connect_pads
			(clearance 0)
		)
		(min_thickness 0.25)
		(keepout
			(tracks not_allowed)
			(vias allowed)
			(pads allowed)
			(copperpour not_allowed)
			(footprints allowed)
		)
		(placement
			(enabled no)
			(sheetname "")
		)
		(fill
			(thermal_gap 0.5)
			(thermal_bridge_width 0.5)
			(island_removal_mode 0)
		)
		(polygon
			(pts
				(arc
					(start 428.205392 -295.33215)
					(mid 428.201672 -295.34113)
					(end 428.192692 -295.34485)
				)
				(arc
					(start 426.719492 -295.34485)
					(mid 426.710512 -295.34113)
					(end 426.706792 -295.33215)
				)
				(arc
					(start 426.706792 -294.837612)
					(mid 426.710512 -294.828632)
					(end 426.719492 -294.824912)
				)
				(arc
					(start 428.192692 -294.824912)
					(mid 428.201672 -294.828632)
					(end 428.205392 -294.837612)
				)
			)
		)
	)
	(zone
		(layer "In1.Cu")
		(hatch none 0.5)
		(connect_pads
			(clearance 0)
		)
		(min_thickness 0.25)
		(keepout
			(tracks not_allowed)
			(vias allowed)
			(pads allowed)
			(copperpour not_allowed)
			(footprints allowed)
		)
		(placement
			(enabled no)
			(sheetname "")
		)
		(fill
			(thermal_gap 0.5)
			(thermal_bridge_width 0.5)
			(island_removal_mode 0)
		)
		(polygon
			(pts
				(arc
					(start 273.841464 -235.832142)
					(mid 273.837744 -235.841122)
					(end 273.828764 -235.844842)
				)
				(arc
					(start 272.355564 -235.844842)
					(mid 272.346584 -235.841122)
					(end 272.342864 -235.832142)
				)
				(arc
					(start 272.342864 -235.337604)
					(mid 272.346584 -235.328624)
					(end 272.355564 -235.324904)
				)
				(arc
					(start 273.828764 -235.324904)
					(mid 273.837744 -235.328624)
					(end 273.841464 -235.337604)
				)
			)
		)
	)
	(zone
		(layer "In1.Cu")
		(hatch none 0.5)
		(connect_pads
			(clearance 0)
		)
		(min_thickness 0.25)
		(keepout
			(tracks not_allowed)
			(vias allowed)
			(pads allowed)
			(copperpour not_allowed)
			(footprints allowed)
		)
		(placement
			(enabled no)
			(sheetname "")
		)
		(fill
			(thermal_gap 0.5)
			(thermal_bridge_width 0.5)
			(island_removal_mode 0)
		)
		(polygon
			(pts
				(arc
					(start 308.117494 -227.332286)
					(mid 308.113774 -227.341266)
					(end 308.104794 -227.344986)
				)
				(arc
					(start 306.631594 -227.344986)
					(mid 306.622614 -227.341266)
					(end 306.618894 -227.332286)
				)
				(arc
					(start 306.618894 -226.837748)
					(mid 306.622614 -226.828768)
					(end 306.631594 -226.825048)
				)
				(arc
					(start 308.104794 -226.825048)
					(mid 308.113774 -226.828768)
					(end 308.117494 -226.837748)
				)
			)
		)
	)
	(zone
		(layer "In1.Cu")
		(hatch none 0.5)
		(connect_pads
			(clearance 0)
		)
		(min_thickness 0.25)
		(keepout
			(tracks not_allowed)
			(vias allowed)
			(pads allowed)
			(copperpour not_allowed)
			(footprints allowed)
		)
		(placement
			(enabled no)
			(sheetname "")
		)
		(fill
			(thermal_gap 0.5)
			(thermal_bridge_width 0.5)
			(island_removal_mode 0)
		)
		(polygon
			(pts
				(arc
					(start 172.72127 -318.282574)
					(mid 172.71755 -318.291554)
					(end 172.70857 -318.295274)
				)
				(arc
					(start 171.23537 -318.295274)
					(mid 171.22639 -318.291554)
					(end 171.22267 -318.282574)
				)
				(arc
					(start 171.22267 -317.788036)
					(mid 171.22639 -317.779056)
					(end 171.23537 -317.775336)
				)
				(arc
					(start 172.70857 -317.775336)
					(mid 172.71755 -317.779056)
					(end 172.72127 -317.788036)
				)
			)
		)
	)
	(zone
		(layer "In1.Cu")
		(hatch none 0.5)
		(connect_pads
			(clearance 0)
		)
		(min_thickness 0.25)
		(keepout
			(tracks not_allowed)
			(vias allowed)
			(pads allowed)
			(copperpour not_allowed)
			(footprints allowed)
		)
		(placement
			(enabled no)
			(sheetname "")
		)
		(fill
			(thermal_gap 0.5)
			(thermal_bridge_width 0.5)
			(island_removal_mode 0)
		)
		(polygon
			(pts
				(arc
					(start 273.841464 -220.532198)
					(mid 273.837744 -220.541178)
					(end 273.828764 -220.544898)
				)
				(arc
					(start 272.355564 -220.544898)
					(mid 272.346584 -220.541178)
					(end 272.342864 -220.532198)
				)
				(arc
					(start 272.342864 -220.03766)
					(mid 272.346584 -220.02868)
					(end 272.355564 -220.02496)
				)
				(arc
					(start 273.828764 -220.02496)
					(mid 273.837744 -220.02868)
					(end 273.841464 -220.03766)
				)
			)
		)
	)
	(zone
		(layer "In1.Cu")
		(hatch none 0.5)
		(connect_pads
			(clearance 0)
		)
		(min_thickness 0.25)
		(keepout
			(tracks not_allowed)
			(vias allowed)
			(pads allowed)
			(copperpour not_allowed)
			(footprints allowed)
		)
		(placement
			(enabled no)
			(sheetname "")
		)
		(fill
			(thermal_gap 0.5)
			(thermal_bridge_width 0.5)
			(island_removal_mode 0)
		)
		(polygon
			(pts
				(arc
					(start 439.849514 -280.032206)
					(mid 439.845794 -280.041186)
					(end 439.836814 -280.044906)
				)
				(arc
					(start 438.363614 -280.044906)
					(mid 438.354634 -280.041186)
					(end 438.350914 -280.032206)
				)
				(arc
					(start 438.350914 -279.537668)
					(mid 438.354634 -279.528688)
					(end 438.363614 -279.524968)
				)
				(arc
					(start 439.836814 -279.524968)
					(mid 439.845794 -279.528688)
					(end 439.849514 -279.537668)
				)
			)
		)
	)
	(zone
		(layer "In1.Cu")
		(hatch none 0.5)
		(connect_pads
			(clearance 0)
		)
		(min_thickness 0.25)
		(keepout
			(tracks not_allowed)
			(vias allowed)
			(pads allowed)
			(copperpour not_allowed)
			(footprints allowed)
		)
		(placement
			(enabled no)
			(sheetname "")
		)
		(fill
			(thermal_gap 0.5)
			(thermal_bridge_width 0.5)
			(island_removal_mode 0)
		)
		(polygon
			(pts
				(arc
					(start 435.749446 -299.582332)
					(mid 435.745726 -299.591312)
					(end 435.736746 -299.595032)
				)
				(arc
					(start 434.263546 -299.595032)
					(mid 434.254566 -299.591312)
					(end 434.250846 -299.582332)
				)
				(arc
					(start 434.250846 -299.087794)
					(mid 434.254566 -299.078814)
					(end 434.263546 -299.075094)
				)
				(arc
					(start 435.736746 -299.075094)
					(mid 435.745726 -299.078814)
					(end 435.749446 -299.087794)
				)
			)
		)
	)
	(zone
		(layer "In1.Cu")
		(hatch none 0.5)
		(connect_pads
			(clearance 0)
		)
		(min_thickness 0.25)
		(keepout
			(tracks not_allowed)
			(vias allowed)
			(pads allowed)
			(copperpour not_allowed)
			(footprints allowed)
		)
		(placement
			(enabled no)
			(sheetname "")
		)
		(fill
			(thermal_gap 0.5)
			(thermal_bridge_width 0.5)
			(island_removal_mode 0)
		)
		(polygon
			(pts
				(arc
					(start 184.365392 -295.332404)
					(mid 184.361672 -295.341384)
					(end 184.352692 -295.345104)
				)
				(arc
					(start 182.879492 -295.345104)
					(mid 182.870512 -295.341384)
					(end 182.866792 -295.332404)
				)
				(arc
					(start 182.866792 -294.837866)
					(mid 182.870512 -294.828886)
					(end 182.879492 -294.825166)
				)
				(arc
					(start 184.352692 -294.825166)
					(mid 184.361672 -294.828886)
					(end 184.365392 -294.837866)
				)
			)
		)
	)
	(zone
		(layer "In1.Cu")
		(hatch none 0.5)
		(connect_pads
			(clearance 0)
		)
		(min_thickness 0.25)
		(keepout
			(tracks not_allowed)
			(vias allowed)
			(pads allowed)
			(copperpour not_allowed)
			(footprints allowed)
		)
		(placement
			(enabled no)
			(sheetname "")
		)
		(fill
			(thermal_gap 0.5)
			(thermal_bridge_width 0.5)
			(island_removal_mode 0)
		)
		(polygon
			(pts
				(arc
					(start 409.81884 -391.822686)
					(mid 409.94584 -391.949686)
					(end 410.07284 -391.822686)
				)
				(arc
					(start 410.07284 -391.746486)
					(mid 409.94584 -391.619486)
					(end 409.81884 -391.746486)
				)
			)
		)
	)
	(zone
		(layer "In1.Cu")
		(hatch none 0.5)
		(connect_pads
			(clearance 0)
		)
		(min_thickness 0.25)
		(keepout
			(tracks not_allowed)
			(vias allowed)
			(pads allowed)
			(copperpour not_allowed)
			(footprints allowed)
		)
		(placement
			(enabled no)
			(sheetname "")
		)
		(fill
			(thermal_gap 0.5)
			(thermal_bridge_width 0.5)
			(island_removal_mode 0)
		)
		(polygon
			(pts
				(arc
					(start 454.937368 -308.082188)
					(mid 454.933648 -308.091168)
					(end 454.924668 -308.094888)
				)
				(arc
					(start 453.451468 -308.094888)
					(mid 453.442488 -308.091168)
					(end 453.438768 -308.082188)
				)
				(arc
					(start 453.438768 -307.58765)
					(mid 453.442488 -307.57867)
					(end 453.451468 -307.57495)
				)
				(arc
					(start 454.924668 -307.57495)
					(mid 454.933648 -307.57867)
					(end 454.937368 -307.58765)
				)
			)
		)
	)
	(zone
		(layer "In1.Cu")
		(hatch none 0.5)
		(connect_pads
			(clearance 0)
		)
		(min_thickness 0.25)
		(keepout
			(tracks not_allowed)
			(vias allowed)
			(pads allowed)
			(copperpour not_allowed)
			(footprints allowed)
		)
		(placement
			(enabled no)
			(sheetname "")
		)
		(fill
			(thermal_gap 0.5)
			(thermal_bridge_width 0.5)
			(island_removal_mode 0)
		)
		(polygon
			(pts
				(arc
					(start 413.117284 -246.882158)
					(mid 413.113564 -246.891138)
					(end 413.104584 -246.894858)
				)
				(arc
					(start 411.631384 -246.894858)
					(mid 411.622404 -246.891138)
					(end 411.618684 -246.882158)
				)
				(arc
					(start 411.618684 -246.38762)
					(mid 411.622404 -246.37864)
					(end 411.631384 -246.37492)
				)
				(arc
					(start 413.104584 -246.37492)
					(mid 413.113564 -246.37864)
					(end 413.117284 -246.38762)
				)
			)
		)
	)
	(zone
		(layer "In1.Cu")
		(hatch none 0.5)
		(connect_pads
			(clearance 0)
		)
		(min_thickness 0.25)
		(keepout
			(tracks not_allowed)
			(vias allowed)
			(pads allowed)
			(copperpour not_allowed)
			(footprints allowed)
		)
		(placement
			(enabled no)
			(sheetname "")
		)
		(fill
			(thermal_gap 0.5)
			(thermal_bridge_width 0.5)
			(island_removal_mode 0)
		)
		(polygon
			(pts
				(arc
					(start 352.788728 -393.69238)
					(mid 352.407728 -393.69238)
					(end 352.788728 -393.69238)
				)
			)
		)
	)
	(zone
		(layer "In1.Cu")
		(hatch none 0.5)
		(connect_pads
			(clearance 0)
		)
		(min_thickness 0.25)
		(keepout
			(tracks not_allowed)
			(vias allowed)
			(pads allowed)
			(copperpour not_allowed)
			(footprints allowed)
		)
		(placement
			(enabled no)
			(sheetname "")
		)
		(fill
			(thermal_gap 0.5)
			(thermal_bridge_width 0.5)
			(island_removal_mode 0)
		)
		(polygon
			(pts
				(arc
					(start 206.5782 -315.485272)
					(mid 205.9178 -315.485272)
					(end 206.5782 -315.485272)
				)
			)
		)
	)
	(zone
		(layer "In1.Cu")
		(hatch none 0.5)
		(connect_pads
			(clearance 0)
		)
		(min_thickness 0.25)
		(keepout
			(tracks not_allowed)
			(vias allowed)
			(pads allowed)
			(copperpour not_allowed)
			(footprints allowed)
		)
		(placement
			(enabled no)
			(sheetname "")
		)
		(fill
			(thermal_gap 0.5)
			(thermal_bridge_width 0.5)
			(island_removal_mode 0)
		)
		(polygon
			(pts
				(arc
					(start 191.909446 -263.032494)
					(mid 191.905726 -263.041474)
					(end 191.896746 -263.045194)
				)
				(arc
					(start 190.423546 -263.045194)
					(mid 190.414566 -263.041474)
					(end 190.410846 -263.032494)
				)
				(arc
					(start 190.410846 -262.537956)
					(mid 190.414566 -262.528976)
					(end 190.423546 -262.525256)
				)
				(arc
					(start 191.896746 -262.525256)
					(mid 191.905726 -262.528976)
					(end 191.909446 -262.537956)
				)
			)
		)
	)
	(zone
		(layer "In1.Cu")
		(hatch none 0.5)
		(connect_pads
			(clearance 0)
		)
		(min_thickness 0.25)
		(keepout
			(tracks not_allowed)
			(vias allowed)
			(pads allowed)
			(copperpour not_allowed)
			(footprints allowed)
		)
		(placement
			(enabled no)
			(sheetname "")
		)
		(fill
			(thermal_gap 0.5)
			(thermal_bridge_width 0.5)
			(island_removal_mode 0)
		)
		(polygon
			(pts
				(arc
					(start 60.177426 -212.88248)
					(mid 60.173706 -212.89146)
					(end 60.164726 -212.89518)
				)
				(arc
					(start 58.691526 -212.89518)
					(mid 58.682546 -212.89146)
					(end 58.678826 -212.88248)
				)
				(arc
					(start 58.678826 -212.387942)
					(mid 58.682546 -212.378962)
					(end 58.691526 -212.375242)
				)
				(arc
					(start 60.164726 -212.375242)
					(mid 60.173706 -212.378962)
					(end 60.177426 -212.387942)
				)
			)
		)
	)
	(zone
		(layer "In1.Cu")
		(hatch none 0.5)
		(connect_pads
			(clearance 0)
		)
		(min_thickness 0.25)
		(keepout
			(tracks not_allowed)
			(vias allowed)
			(pads allowed)
			(copperpour not_allowed)
			(footprints allowed)
		)
		(placement
			(enabled no)
			(sheetname "")
		)
		(fill
			(thermal_gap 0.5)
			(thermal_bridge_width 0.5)
			(island_removal_mode 0)
		)
		(polygon
			(pts
				(arc
					(start 412.218632 -399.701258)
					(mid 412.345632 -399.828258)
					(end 412.472632 -399.701258)
				)
				(arc
					(start 412.472632 -399.625058)
					(mid 412.345632 -399.498058)
					(end 412.218632 -399.625058)
				)
			)
		)
	)
	(zone
		(layer "In1.Cu")
		(hatch none 0.5)
		(connect_pads
			(clearance 0)
		)
		(min_thickness 0.25)
		(keepout
			(tracks not_allowed)
			(vias allowed)
			(pads allowed)
			(copperpour not_allowed)
			(footprints allowed)
		)
		(placement
			(enabled no)
			(sheetname "")
		)
		(fill
			(thermal_gap 0.5)
			(thermal_bridge_width 0.5)
			(island_removal_mode 0)
		)
		(polygon
			(pts
				(arc
					(start 195.353432 -314.88253)
					(mid 195.349712 -314.89151)
					(end 195.340732 -314.89523)
				)
				(arc
					(start 193.867532 -314.89523)
					(mid 193.858552 -314.89151)
					(end 193.854832 -314.88253)
				)
				(arc
					(start 193.854832 -314.387992)
					(mid 193.858552 -314.379012)
					(end 193.867532 -314.375292)
				)
				(arc
					(start 195.340732 -314.375292)
					(mid 195.349712 -314.379012)
					(end 195.353432 -314.387992)
				)
			)
		)
	)
	(zone
		(layer "In1.Cu")
		(hatch none 0.5)
		(connect_pads
			(clearance 0)
		)
		(min_thickness 0.25)
		(keepout
			(tracks not_allowed)
			(vias allowed)
			(pads allowed)
			(copperpour not_allowed)
			(footprints allowed)
		)
		(placement
			(enabled no)
			(sheetname "")
		)
		(fill
			(thermal_gap 0.5)
			(thermal_bridge_width 0.5)
			(island_removal_mode 0)
		)
		(polygon
			(pts
				(arc
					(start 187.809378 -243.482368)
					(mid 187.805658 -243.491348)
					(end 187.796678 -243.495068)
				)
				(arc
					(start 186.323478 -243.495068)
					(mid 186.314498 -243.491348)
					(end 186.310778 -243.482368)
				)
				(arc
					(start 186.310778 -242.98783)
					(mid 186.314498 -242.97885)
					(end 186.323478 -242.97513)
				)
				(arc
					(start 187.796678 -242.97513)
					(mid 187.805658 -242.97885)
					(end 187.809378 -242.98783)
				)
			)
		)
	)
	(zone
		(layer "In1.Cu")
		(hatch none 0.5)
		(connect_pads
			(clearance 0)
		)
		(min_thickness 0.25)
		(keepout
			(tracks not_allowed)
			(vias allowed)
			(pads allowed)
			(copperpour not_allowed)
			(footprints allowed)
		)
		(placement
			(enabled no)
			(sheetname "")
		)
		(fill
			(thermal_gap 0.5)
			(thermal_bridge_width 0.5)
			(island_removal_mode 0)
		)
		(polygon
			(pts
				(arc
					(start 293.029386 -308.082188)
					(mid 293.025666 -308.091168)
					(end 293.016686 -308.094888)
				)
				(arc
					(start 291.543486 -308.094888)
					(mid 291.534506 -308.091168)
					(end 291.530786 -308.082188)
				)
				(arc
					(start 291.530786 -307.58765)
					(mid 291.534506 -307.57867)
					(end 291.543486 -307.57495)
				)
				(arc
					(start 293.016686 -307.57495)
					(mid 293.025666 -307.57867)
					(end 293.029386 -307.58765)
				)
			)
		)
	)
	(zone
		(layer "In1.Cu")
		(hatch none 0.5)
		(connect_pads
			(clearance 0)
		)
		(min_thickness 0.25)
		(keepout
			(tracks not_allowed)
			(vias allowed)
			(pads allowed)
			(copperpour not_allowed)
			(footprints allowed)
		)
		(placement
			(enabled no)
			(sheetname "")
		)
		(fill
			(thermal_gap 0.5)
			(thermal_bridge_width 0.5)
			(island_removal_mode 0)
		)
		(polygon
			(pts
				(arc
					(start 265.87831 -222.834962)
					(mid 265.21791 -222.834962)
					(end 265.87831 -222.834962)
				)
			)
		)
	)
	(zone
		(layer "In1.Cu")
		(hatch none 0.5)
		(connect_pads
			(clearance 0)
		)
		(min_thickness 0.25)
		(keepout
			(tracks not_allowed)
			(vias allowed)
			(pads allowed)
			(copperpour not_allowed)
			(footprints allowed)
		)
		(placement
			(enabled no)
			(sheetname "")
		)
		(fill
			(thermal_gap 0.5)
			(thermal_bridge_width 0.5)
			(island_removal_mode 0)
		)
		(polygon
			(pts
				(arc
					(start 40.98925 -297.882564)
					(mid 40.98553 -297.891544)
					(end 40.97655 -297.895264)
				)
				(arc
					(start 39.50335 -297.895264)
					(mid 39.49437 -297.891544)
					(end 39.49065 -297.882564)
				)
				(arc
					(start 39.49065 -297.388026)
					(mid 39.49437 -297.379046)
					(end 39.50335 -297.375326)
				)
				(arc
					(start 40.97655 -297.375326)
					(mid 40.98553 -297.379046)
					(end 40.98925 -297.388026)
				)
			)
		)
	)
	(zone
		(layer "In1.Cu")
		(hatch none 0.5)
		(connect_pads
			(clearance 0)
		)
		(min_thickness 0.25)
		(keepout
			(tracks not_allowed)
			(vias allowed)
			(pads allowed)
			(copperpour not_allowed)
			(footprints allowed)
		)
		(placement
			(enabled no)
			(sheetname "")
		)
		(fill
			(thermal_gap 0.5)
			(thermal_bridge_width 0.5)
			(island_removal_mode 0)
		)
		(polygon
			(pts
				(arc
					(start 30.001464 -308.082442)
					(mid 29.997744 -308.091422)
					(end 29.988764 -308.095142)
				)
				(arc
					(start 28.515564 -308.095142)
					(mid 28.506584 -308.091422)
					(end 28.502864 -308.082442)
				)
				(arc
					(start 28.502864 -307.587904)
					(mid 28.506584 -307.578924)
					(end 28.515564 -307.575204)
				)
				(arc
					(start 29.988764 -307.575204)
					(mid 29.997744 -307.578924)
					(end 30.001464 -307.587904)
				)
			)
		)
	)
	(zone
		(layer "In1.Cu")
		(hatch none 0.5)
		(connect_pads
			(clearance 0)
		)
		(min_thickness 0.25)
		(keepout
			(tracks not_allowed)
			(vias allowed)
			(pads allowed)
			(copperpour not_allowed)
			(footprints allowed)
		)
		(placement
			(enabled no)
			(sheetname "")
		)
		(fill
			(thermal_gap 0.5)
			(thermal_bridge_width 0.5)
			(island_removal_mode 0)
		)
		(polygon
			(pts
				(arc
					(start 270.397478 -285.982156)
					(mid 270.393758 -285.991136)
					(end 270.384778 -285.994856)
				)
				(arc
					(start 268.911578 -285.994856)
					(mid 268.902598 -285.991136)
					(end 268.898878 -285.982156)
				)
				(arc
					(start 268.898878 -285.487618)
					(mid 268.902598 -285.478638)
					(end 268.911578 -285.474918)
				)
				(arc
					(start 270.384778 -285.474918)
					(mid 270.393758 -285.478638)
					(end 270.397478 -285.487618)
				)
			)
		)
	)
	(zone
		(layer "In1.Cu")
		(hatch none 0.5)
		(connect_pads
			(clearance 0)
		)
		(min_thickness 0.25)
		(keepout
			(tracks not_allowed)
			(vias allowed)
			(pads allowed)
			(copperpour not_allowed)
			(footprints allowed)
		)
		(placement
			(enabled no)
			(sheetname "")
		)
		(fill
			(thermal_gap 0.5)
			(thermal_bridge_width 0.5)
			(island_removal_mode 0)
		)
		(polygon
			(pts
				(arc
					(start 296.473372 -305.532282)
					(mid 296.469652 -305.541262)
					(end 296.460672 -305.544982)
				)
				(arc
					(start 294.987472 -305.544982)
					(mid 294.978492 -305.541262)
					(end 294.974772 -305.532282)
				)
				(arc
					(start 294.974772 -305.037744)
					(mid 294.978492 -305.028764)
					(end 294.987472 -305.025044)
				)
				(arc
					(start 296.460672 -305.025044)
					(mid 296.469652 -305.028764)
					(end 296.473372 -305.037744)
				)
			)
		)
	)
	(zone
		(layer "In1.Cu")
		(hatch none 0.5)
		(connect_pads
			(clearance 0)
		)
		(min_thickness 0.25)
		(keepout
			(tracks not_allowed)
			(vias allowed)
			(pads allowed)
			(copperpour not_allowed)
			(footprints allowed)
		)
		(placement
			(enabled no)
			(sheetname "")
		)
		(fill
			(thermal_gap 0.5)
			(thermal_bridge_width 0.5)
			(island_removal_mode 0)
		)
		(polygon
			(pts
				(arc
					(start 184.365392 -239.23244)
					(mid 184.361672 -239.24142)
					(end 184.352692 -239.24514)
				)
				(arc
					(start 182.879492 -239.24514)
					(mid 182.870512 -239.24142)
					(end 182.866792 -239.23244)
				)
				(arc
					(start 182.866792 -238.737902)
					(mid 182.870512 -238.728922)
					(end 182.879492 -238.725202)
				)
				(arc
					(start 184.352692 -238.725202)
					(mid 184.361672 -238.728922)
					(end 184.365392 -238.737902)
				)
			)
		)
	)
	(zone
		(layer "In1.Cu")
		(hatch none 0.5)
		(connect_pads
			(clearance 0)
		)
		(min_thickness 0.25)
		(keepout
			(tracks not_allowed)
			(vias allowed)
			(pads allowed)
			(copperpour not_allowed)
			(footprints allowed)
		)
		(placement
			(enabled no)
			(sheetname "")
		)
		(fill
			(thermal_gap 0.5)
			(thermal_bridge_width 0.5)
			(island_removal_mode 0)
		)
		(polygon
			(pts
				(arc
					(start 52.633372 -308.082442)
					(mid 52.629652 -308.091422)
					(end 52.620672 -308.095142)
				)
				(arc
					(start 51.147472 -308.095142)
					(mid 51.138492 -308.091422)
					(end 51.134772 -308.082442)
				)
				(arc
					(start 51.134772 -307.587904)
					(mid 51.138492 -307.578924)
					(end 51.147472 -307.575204)
				)
				(arc
					(start 52.620672 -307.575204)
					(mid 52.629652 -307.578924)
					(end 52.633372 -307.587904)
				)
			)
		)
	)
	(zone
		(layer "In1.Cu")
		(hatch none 0.5)
		(connect_pads
			(clearance 0)
		)
		(min_thickness 0.25)
		(keepout
			(tracks not_allowed)
			(vias allowed)
			(pads allowed)
			(copperpour not_allowed)
			(footprints allowed)
		)
		(placement
			(enabled no)
			(sheetname "")
		)
		(fill
			(thermal_gap 0.5)
			(thermal_bridge_width 0.5)
			(island_removal_mode 0)
		)
		(polygon
			(pts
				(arc
					(start 199.4535 -211.182458)
					(mid 199.44978 -211.191438)
					(end 199.4408 -211.195158)
				)
				(arc
					(start 197.9676 -211.195158)
					(mid 197.95862 -211.191438)
					(end 197.9549 -211.182458)
				)
				(arc
					(start 197.9549 -210.68792)
					(mid 197.95862 -210.67894)
					(end 197.9676 -210.67522)
				)
				(arc
					(start 199.4408 -210.67522)
					(mid 199.44978 -210.67894)
					(end 199.4535 -210.68792)
				)
			)
		)
	)
	(zone
		(layer "In1.Cu")
		(hatch none 0.5)
		(connect_pads
			(clearance 0)
		)
		(min_thickness 0.25)
		(keepout
			(tracks not_allowed)
			(vias allowed)
			(pads allowed)
			(copperpour not_allowed)
			(footprints allowed)
		)
		(placement
			(enabled no)
			(sheetname "")
		)
		(fill
			(thermal_gap 0.5)
			(thermal_bridge_width 0.5)
			(island_removal_mode 0)
		)
		(polygon
			(pts
				(arc
					(start 37.545264 -206.93253)
					(mid 37.541544 -206.94151)
					(end 37.532564 -206.94523)
				)
				(arc
					(start 36.059364 -206.94523)
					(mid 36.050384 -206.94151)
					(end 36.046664 -206.93253)
				)
				(arc
					(start 36.046664 -206.437992)
					(mid 36.050384 -206.429012)
					(end 36.059364 -206.425292)
				)
				(arc
					(start 37.532564 -206.425292)
					(mid 37.541544 -206.429012)
					(end 37.545264 -206.437992)
				)
			)
		)
	)
	(zone
		(layer "In1.Cu")
		(hatch none 0.5)
		(connect_pads
			(clearance 0)
		)
		(min_thickness 0.25)
		(keepout
			(tracks not_allowed)
			(vias allowed)
			(pads allowed)
			(copperpour not_allowed)
			(footprints allowed)
		)
		(placement
			(enabled no)
			(sheetname "")
		)
		(fill
			(thermal_gap 0.5)
			(thermal_bridge_width 0.5)
			(island_removal_mode 0)
		)
		(polygon
			(pts
				(arc
					(start 439.849514 -236.68228)
					(mid 439.845794 -236.69126)
					(end 439.836814 -236.69498)
				)
				(arc
					(start 438.363614 -236.69498)
					(mid 438.354634 -236.69126)
					(end 438.350914 -236.68228)
				)
				(arc
					(start 438.350914 -236.187742)
					(mid 438.354634 -236.178762)
					(end 438.363614 -236.175042)
				)
				(arc
					(start 439.836814 -236.175042)
					(mid 439.845794 -236.178762)
					(end 439.849514 -236.187742)
				)
			)
		)
	)
	(zone
		(layer "In1.Cu")
		(hatch none 0.5)
		(connect_pads
			(clearance 0)
		)
		(min_thickness 0.25)
		(keepout
			(tracks not_allowed)
			(vias allowed)
			(pads allowed)
			(copperpour not_allowed)
			(footprints allowed)
		)
		(placement
			(enabled no)
			(sheetname "")
		)
		(fill
			(thermal_gap 0.5)
			(thermal_bridge_width 0.5)
			(island_removal_mode 0)
		)
		(polygon
			(pts
				(arc
					(start 172.72127 -250.282456)
					(mid 172.71755 -250.291436)
					(end 172.70857 -250.295156)
				)
				(arc
					(start 171.23537 -250.295156)
					(mid 171.22639 -250.291436)
					(end 171.22267 -250.282456)
				)
				(arc
					(start 171.22267 -249.787918)
					(mid 171.22639 -249.778938)
					(end 171.23537 -249.775218)
				)
				(arc
					(start 172.70857 -249.775218)
					(mid 172.71755 -249.778938)
					(end 172.72127 -249.787918)
				)
			)
		)
	)
	(zone
		(layer "In1.Cu")
		(hatch none 0.5)
		(connect_pads
			(clearance 0)
		)
		(min_thickness 0.25)
		(keepout
			(tracks not_allowed)
			(vias allowed)
			(pads allowed)
			(copperpour not_allowed)
			(footprints allowed)
		)
		(placement
			(enabled no)
			(sheetname "")
		)
		(fill
			(thermal_gap 0.5)
			(thermal_bridge_width 0.5)
			(island_removal_mode 0)
		)
		(polygon
			(pts
				(arc
					(start 37.545264 -251.13234)
					(mid 37.541544 -251.14132)
					(end 37.532564 -251.14504)
				)
				(arc
					(start 36.059364 -251.14504)
					(mid 36.050384 -251.14132)
					(end 36.046664 -251.13234)
				)
				(arc
					(start 36.046664 -250.637802)
					(mid 36.050384 -250.628822)
					(end 36.059364 -250.625102)
				)
				(arc
					(start 37.532564 -250.625102)
					(mid 37.541544 -250.628822)
					(end 37.545264 -250.637802)
				)
			)
		)
	)
	(zone
		(layer "In1.Cu")
		(hatch none 0.5)
		(connect_pads
			(clearance 0)
		)
		(min_thickness 0.25)
		(keepout
			(tracks not_allowed)
			(vias allowed)
			(pads allowed)
			(copperpour not_allowed)
			(footprints allowed)
		)
		(placement
			(enabled no)
			(sheetname "")
		)
		(fill
			(thermal_gap 0.5)
			(thermal_bridge_width 0.5)
			(island_removal_mode 0)
		)
		(polygon
			(pts
				(arc
					(start 151.888952 -388.774432)
					(mid 151.507952 -388.774432)
					(end 151.888952 -388.774432)
				)
			)
		)
	)
	(zone
		(layer "In1.Cu")
		(hatch none 0.5)
		(connect_pads
			(clearance 0)
		)
		(min_thickness 0.25)
		(keepout
			(tracks not_allowed)
			(vias allowed)
			(pads allowed)
			(copperpour not_allowed)
			(footprints allowed)
		)
		(placement
			(enabled no)
			(sheetname "")
		)
		(fill
			(thermal_gap 0.5)
			(thermal_bridge_width 0.5)
			(island_removal_mode 0)
		)
		(polygon
			(pts
				(arc
					(start 125.94082 -34.275268)
					(mid 125.994702 -34.25295)
					(end 126.01702 -34.199068)
				)
				(arc
					(start 126.01702 -33.843468)
					(mid 125.994702 -33.789586)
					(end 125.94082 -33.767268)
				)
				(arc
					(start 124.03582 -33.767268)
					(mid 123.981938 -33.789586)
					(end 123.95962 -33.843468)
				)
				(arc
					(start 123.95962 -34.199068)
					(mid 123.981938 -34.25295)
					(end 124.03582 -34.275268)
				)
			)
		)
	)
	(zone
		(layer "In1.Cu")
		(hatch none 0.5)
		(connect_pads
			(clearance 0)
		)
		(min_thickness 0.25)
		(keepout
			(tracks not_allowed)
			(vias allowed)
			(pads allowed)
			(copperpour not_allowed)
			(footprints allowed)
		)
		(placement
			(enabled no)
			(sheetname "")
		)
		(fill
			(thermal_gap 0.5)
			(thermal_bridge_width 0.5)
			(island_removal_mode 0)
		)
		(polygon
			(pts
				(arc
					(start 184.365392 -222.232474)
					(mid 184.361672 -222.241454)
					(end 184.352692 -222.245174)
				)
				(arc
					(start 182.879492 -222.245174)
					(mid 182.870512 -222.241454)
					(end 182.866792 -222.232474)
				)
				(arc
					(start 182.866792 -221.737936)
					(mid 182.870512 -221.728956)
					(end 182.879492 -221.725236)
				)
				(arc
					(start 184.352692 -221.725236)
					(mid 184.361672 -221.728956)
					(end 184.365392 -221.737936)
				)
			)
		)
	)
	(zone
		(layer "In1.Cu")
		(hatch none 0.5)
		(connect_pads
			(clearance 0)
		)
		(min_thickness 0.25)
		(keepout
			(tracks not_allowed)
			(vias allowed)
			(pads allowed)
			(copperpour not_allowed)
			(footprints allowed)
		)
		(placement
			(enabled no)
			(sheetname "")
		)
		(fill
			(thermal_gap 0.5)
			(thermal_bridge_width 0.5)
			(island_removal_mode 0)
		)
		(polygon
			(pts
				(arc
					(start 293.029386 -264.732262)
					(mid 293.025666 -264.741242)
					(end 293.016686 -264.744962)
				)
				(arc
					(start 291.543486 -264.744962)
					(mid 291.534506 -264.741242)
					(end 291.530786 -264.732262)
				)
				(arc
					(start 291.530786 -264.237724)
					(mid 291.534506 -264.228744)
					(end 291.543486 -264.225024)
				)
				(arc
					(start 293.016686 -264.225024)
					(mid 293.025666 -264.228744)
					(end 293.029386 -264.237724)
				)
			)
		)
	)
	(zone
		(layer "In1.Cu")
		(hatch none 0.5)
		(connect_pads
			(clearance 0)
		)
		(min_thickness 0.25)
		(keepout
			(tracks not_allowed)
			(vias allowed)
			(pads allowed)
			(copperpour not_allowed)
			(footprints allowed)
		)
		(placement
			(enabled no)
			(sheetname "")
		)
		(fill
			(thermal_gap 0.5)
			(thermal_bridge_width 0.5)
			(island_removal_mode 0)
		)
		(polygon
			(pts
				(arc
					(start 285.485332 -225.632264)
					(mid 285.481612 -225.641244)
					(end 285.472632 -225.644964)
				)
				(arc
					(start 283.999432 -225.644964)
					(mid 283.990452 -225.641244)
					(end 283.986732 -225.632264)
				)
				(arc
					(start 283.986732 -225.137726)
					(mid 283.990452 -225.128746)
					(end 283.999432 -225.125026)
				)
				(arc
					(start 285.472632 -225.125026)
					(mid 285.481612 -225.128746)
					(end 285.485332 -225.137726)
				)
			)
		)
	)
	(zone
		(layer "In1.Cu")
		(hatch none 0.5)
		(connect_pads
			(clearance 0)
		)
		(min_thickness 0.25)
		(keepout
			(tracks not_allowed)
			(vias allowed)
			(pads allowed)
			(copperpour not_allowed)
			(footprints allowed)
		)
		(placement
			(enabled no)
			(sheetname "")
		)
		(fill
			(thermal_gap 0.5)
			(thermal_bridge_width 0.5)
			(island_removal_mode 0)
		)
		(polygon
			(pts
				(arc
					(start 281.385264 -200.132188)
					(mid 281.381544 -200.141168)
					(end 281.372564 -200.144888)
				)
				(arc
					(start 279.899364 -200.144888)
					(mid 279.890384 -200.141168)
					(end 279.886664 -200.132188)
				)
				(arc
					(start 279.886664 -199.63765)
					(mid 279.890384 -199.62867)
					(end 279.899364 -199.62495)
				)
				(arc
					(start 281.372564 -199.62495)
					(mid 281.381544 -199.62867)
					(end 281.385264 -199.63765)
				)
			)
		)
	)
	(zone
		(layer "In1.Cu")
		(hatch none 0.5)
		(connect_pads
			(clearance 0)
		)
		(min_thickness 0.25)
		(keepout
			(tracks not_allowed)
			(vias allowed)
			(pads allowed)
			(copperpour not_allowed)
			(footprints allowed)
		)
		(placement
			(enabled no)
			(sheetname "")
		)
		(fill
			(thermal_gap 0.5)
			(thermal_bridge_width 0.5)
			(island_removal_mode 0)
		)
		(polygon
			(pts
				(arc
					(start 199.4535 -231.582468)
					(mid 199.44978 -231.591448)
					(end 199.4408 -231.595168)
				)
				(arc
					(start 197.9676 -231.595168)
					(mid 197.95862 -231.591448)
					(end 197.9549 -231.582468)
				)
				(arc
					(start 197.9549 -231.08793)
					(mid 197.95862 -231.07895)
					(end 197.9676 -231.07523)
				)
				(arc
					(start 199.4408 -231.07523)
					(mid 199.44978 -231.07895)
					(end 199.4535 -231.08793)
				)
			)
		)
	)
	(zone
		(layer "In1.Cu")
		(hatch none 0.5)
		(connect_pads
			(clearance 0)
		)
		(min_thickness 0.25)
		(keepout
			(tracks not_allowed)
			(vias allowed)
			(pads allowed)
			(copperpour not_allowed)
			(footprints allowed)
		)
		(placement
			(enabled no)
			(sheetname "")
		)
		(fill
			(thermal_gap 0.5)
			(thermal_bridge_width 0.5)
			(island_removal_mode 0)
		)
		(polygon
			(pts
				(arc
					(start 439.849514 -317.432182)
					(mid 439.845794 -317.441162)
					(end 439.836814 -317.444882)
				)
				(arc
					(start 438.363614 -317.444882)
					(mid 438.354634 -317.441162)
					(end 438.350914 -317.432182)
				)
				(arc
					(start 438.350914 -316.937644)
					(mid 438.354634 -316.928664)
					(end 438.363614 -316.924944)
				)
				(arc
					(start 439.836814 -316.924944)
					(mid 439.845794 -316.928664)
					(end 439.849514 -316.937644)
				)
			)
		)
	)
	(zone
		(layer "In1.Cu")
		(hatch none 0.5)
		(connect_pads
			(clearance 0)
		)
		(min_thickness 0.25)
		(keepout
			(tracks not_allowed)
			(vias allowed)
			(pads allowed)
			(copperpour not_allowed)
			(footprints allowed)
		)
		(placement
			(enabled no)
			(sheetname "")
		)
		(fill
			(thermal_gap 0.5)
			(thermal_bridge_width 0.5)
			(island_removal_mode 0)
		)
		(polygon
			(pts
				(arc
					(start 310.77027 -399.143474)
					(mid 310.46547 -399.143474)
					(end 310.77027 -399.143474)
				)
			)
		)
	)
	(zone
		(layer "In1.Cu")
		(hatch none 0.5)
		(connect_pads
			(clearance 0)
		)
		(min_thickness 0.25)
		(keepout
			(tracks not_allowed)
			(vias allowed)
			(pads allowed)
			(copperpour not_allowed)
			(footprints allowed)
		)
		(placement
			(enabled no)
			(sheetname "")
		)
		(fill
			(thermal_gap 0.5)
			(thermal_bridge_width 0.5)
			(island_removal_mode 0)
		)
		(polygon
			(pts
				(arc
					(start 60.177426 -229.032562)
					(mid 60.173706 -229.041542)
					(end 60.164726 -229.045262)
				)
				(arc
					(start 58.691526 -229.045262)
					(mid 58.682546 -229.041542)
					(end 58.678826 -229.032562)
				)
				(arc
					(start 58.678826 -228.538024)
					(mid 58.682546 -228.529044)
					(end 58.691526 -228.525324)
				)
				(arc
					(start 60.164726 -228.525324)
					(mid 60.173706 -228.529044)
					(end 60.177426 -228.538024)
				)
			)
		)
	)
	(zone
		(layer "In1.Cu")
		(hatch none 0.5)
		(connect_pads
			(clearance 0)
		)
		(min_thickness 0.25)
		(keepout
			(tracks not_allowed)
			(vias allowed)
			(pads allowed)
			(copperpour not_allowed)
			(footprints allowed)
		)
		(placement
			(enabled no)
			(sheetname "")
		)
		(fill
			(thermal_gap 0.5)
			(thermal_bridge_width 0.5)
			(island_removal_mode 0)
		)
		(polygon
			(pts
				(arc
					(start 293.029386 -314.032138)
					(mid 293.025666 -314.041118)
					(end 293.016686 -314.044838)
				)
				(arc
					(start 291.543486 -314.044838)
					(mid 291.534506 -314.041118)
					(end 291.530786 -314.032138)
				)
				(arc
					(start 291.530786 -313.5376)
					(mid 291.534506 -313.52862)
					(end 291.543486 -313.5249)
				)
				(arc
					(start 293.016686 -313.5249)
					(mid 293.025666 -313.52862)
					(end 293.029386 -313.5376)
				)
			)
		)
	)
	(zone
		(layer "In1.Cu")
		(hatch none 0.5)
		(connect_pads
			(clearance 0)
		)
		(min_thickness 0.25)
		(keepout
			(tracks not_allowed)
			(vias allowed)
			(pads allowed)
			(copperpour not_allowed)
			(footprints allowed)
		)
		(placement
			(enabled no)
			(sheetname "")
		)
		(fill
			(thermal_gap 0.5)
			(thermal_bridge_width 0.5)
			(island_removal_mode 0)
		)
		(polygon
			(pts
				(arc
					(start 384.16103 -394.385292)
					(mid 383.78003 -394.385292)
					(end 384.16103 -394.385292)
				)
			)
		)
	)
	(zone
		(layer "In1.Cu")
		(hatch none 0.5)
		(connect_pads
			(clearance 0)
		)
		(min_thickness 0.25)
		(keepout
			(tracks not_allowed)
			(vias allowed)
			(pads allowed)
			(copperpour not_allowed)
			(footprints allowed)
		)
		(placement
			(enabled no)
			(sheetname "")
		)
		(fill
			(thermal_gap 0.5)
			(thermal_bridge_width 0.5)
			(island_removal_mode 0)
		)
		(polygon
			(pts
				(arc
					(start 265.87831 -215.18499)
					(mid 265.21791 -215.18499)
					(end 265.87831 -215.18499)
				)
			)
		)
	)
	(zone
		(layer "In1.Cu")
		(hatch none 0.5)
		(connect_pads
			(clearance 0)
		)
		(min_thickness 0.25)
		(keepout
			(tracks not_allowed)
			(vias allowed)
			(pads allowed)
			(copperpour not_allowed)
			(footprints allowed)
		)
		(placement
			(enabled no)
			(sheetname "")
		)
		(fill
			(thermal_gap 0.5)
			(thermal_bridge_width 0.5)
			(island_removal_mode 0)
		)
		(polygon
			(pts
				(arc
					(start 83.589114 -385.31038)
					(mid 83.208114 -385.31038)
					(end 83.589114 -385.31038)
				)
			)
		)
	)
	(zone
		(layer "In1.Cu")
		(hatch none 0.5)
		(connect_pads
			(clearance 0)
		)
		(min_thickness 0.25)
		(keepout
			(tracks not_allowed)
			(vias allowed)
			(pads allowed)
			(copperpour not_allowed)
			(footprints allowed)
		)
		(placement
			(enabled no)
			(sheetname "")
		)
		(fill
			(thermal_gap 0.5)
			(thermal_bridge_width 0.5)
			(island_removal_mode 0)
		)
		(polygon
			(pts
				(arc
					(start 187.809378 -240.082578)
					(mid 187.805658 -240.091558)
					(end 187.796678 -240.095278)
				)
				(arc
					(start 186.323478 -240.095278)
					(mid 186.314498 -240.091558)
					(end 186.310778 -240.082578)
				)
				(arc
					(start 186.310778 -239.58804)
					(mid 186.314498 -239.57906)
					(end 186.323478 -239.57534)
				)
				(arc
					(start 187.796678 -239.57534)
					(mid 187.805658 -239.57906)
					(end 187.809378 -239.58804)
				)
			)
		)
	)
	(zone
		(layer "In1.Cu")
		(hatch none 0.5)
		(connect_pads
			(clearance 0)
		)
		(min_thickness 0.25)
		(keepout
			(tracks not_allowed)
			(vias allowed)
			(pads allowed)
			(copperpour not_allowed)
			(footprints allowed)
		)
		(placement
			(enabled no)
			(sheetname "")
		)
		(fill
			(thermal_gap 0.5)
			(thermal_bridge_width 0.5)
			(island_removal_mode 0)
		)
		(polygon
			(pts
				(arc
					(start 123.360942 -386.003292)
					(mid 122.979942 -386.003292)
					(end 123.360942 -386.003292)
				)
			)
		)
	)
	(zone
		(layer "In1.Cu")
		(hatch none 0.5)
		(connect_pads
			(clearance 0)
		)
		(min_thickness 0.25)
		(keepout
			(tracks not_allowed)
			(vias allowed)
			(pads allowed)
			(copperpour not_allowed)
			(footprints allowed)
		)
		(placement
			(enabled no)
			(sheetname "")
		)
		(fill
			(thermal_gap 0.5)
			(thermal_bridge_width 0.5)
			(island_removal_mode 0)
		)
		(polygon
			(pts
				(arc
					(start 337.918552 -399.701258)
					(mid 338.045552 -399.828258)
					(end 338.172552 -399.701258)
				)
				(arc
					(start 338.172552 -399.625058)
					(mid 338.045552 -399.498058)
					(end 337.918552 -399.625058)
				)
			)
		)
	)
	(zone
		(layer "In1.Cu")
		(hatch none 0.5)
		(connect_pads
			(clearance 0)
		)
		(min_thickness 0.25)
		(keepout
			(tracks not_allowed)
			(vias allowed)
			(pads allowed)
			(copperpour not_allowed)
			(footprints allowed)
		)
		(placement
			(enabled no)
			(sheetname "")
		)
		(fill
			(thermal_gap 0.5)
			(thermal_bridge_width 0.5)
			(island_removal_mode 0)
		)
		(polygon
			(pts
				(arc
					(start 293.029386 -276.632162)
					(mid 293.025666 -276.641142)
					(end 293.016686 -276.644862)
				)
				(arc
					(start 291.543486 -276.644862)
					(mid 291.534506 -276.641142)
					(end 291.530786 -276.632162)
				)
				(arc
					(start 291.530786 -276.137624)
					(mid 291.534506 -276.128644)
					(end 291.543486 -276.124924)
				)
				(arc
					(start 293.016686 -276.124924)
					(mid 293.025666 -276.128644)
					(end 293.029386 -276.137624)
				)
			)
		)
	)
	(zone
		(layer "In1.Cu")
		(hatch none 0.5)
		(connect_pads
			(clearance 0)
		)
		(min_thickness 0.25)
		(keepout
			(tracks not_allowed)
			(vias allowed)
			(pads allowed)
			(copperpour not_allowed)
			(footprints allowed)
		)
		(placement
			(enabled no)
			(sheetname "")
		)
		(fill
			(thermal_gap 0.5)
			(thermal_bridge_width 0.5)
			(island_removal_mode 0)
		)
		(polygon
			(pts
				(arc
					(start 191.909446 -227.33254)
					(mid 191.905726 -227.34152)
					(end 191.896746 -227.34524)
				)
				(arc
					(start 190.423546 -227.34524)
					(mid 190.414566 -227.34152)
					(end 190.410846 -227.33254)
				)
				(arc
					(start 190.410846 -226.838002)
					(mid 190.414566 -226.829022)
					(end 190.423546 -226.825302)
				)
				(arc
					(start 191.896746 -226.825302)
					(mid 191.905726 -226.829022)
					(end 191.909446 -226.838002)
				)
			)
		)
	)
	(zone
		(layer "In1.Cu")
		(hatch none 0.5)
		(connect_pads
			(clearance 0)
		)
		(min_thickness 0.25)
		(keepout
			(tracks not_allowed)
			(vias allowed)
			(pads allowed)
			(copperpour not_allowed)
			(footprints allowed)
		)
		(placement
			(enabled no)
			(sheetname "")
		)
		(fill
			(thermal_gap 0.5)
			(thermal_bridge_width 0.5)
			(island_removal_mode 0)
		)
		(polygon
			(pts
				(arc
					(start 428.205392 -200.132188)
					(mid 428.201672 -200.141168)
					(end 428.192692 -200.144888)
				)
				(arc
					(start 426.719492 -200.144888)
					(mid 426.710512 -200.141168)
					(end 426.706792 -200.132188)
				)
				(arc
					(start 426.706792 -199.63765)
					(mid 426.710512 -199.62867)
					(end 426.719492 -199.62495)
				)
				(arc
					(start 428.192692 -199.62495)
					(mid 428.201672 -199.62867)
					(end 428.205392 -199.63765)
				)
			)
		)
	)
	(zone
		(layer "In1.Cu")
		(hatch none 0.5)
		(connect_pads
			(clearance 0)
		)
		(min_thickness 0.25)
		(keepout
			(tracks not_allowed)
			(vias allowed)
			(pads allowed)
			(copperpour not_allowed)
			(footprints allowed)
		)
		(placement
			(enabled no)
			(sheetname "")
		)
		(fill
			(thermal_gap 0.5)
			(thermal_bridge_width 0.5)
			(island_removal_mode 0)
		)
		(polygon
			(pts
				(arc
					(start 417.217352 -266.432284)
					(mid 417.213632 -266.441264)
					(end 417.204652 -266.444984)
				)
				(arc
					(start 415.731452 -266.444984)
					(mid 415.722472 -266.441264)
					(end 415.718752 -266.432284)
				)
				(arc
					(start 415.718752 -265.937746)
					(mid 415.722472 -265.928766)
					(end 415.731452 -265.925046)
				)
				(arc
					(start 417.204652 -265.925046)
					(mid 417.213632 -265.928766)
					(end 417.217352 -265.937746)
				)
			)
		)
	)
	(zone
		(layer "In1.Cu")
		(hatch none 0.5)
		(connect_pads
			(clearance 0)
		)
		(min_thickness 0.25)
		(keepout
			(tracks not_allowed)
			(vias allowed)
			(pads allowed)
			(copperpour not_allowed)
			(footprints allowed)
		)
		(placement
			(enabled no)
			(sheetname "")
		)
		(fill
			(thermal_gap 0.5)
			(thermal_bridge_width 0.5)
			(island_removal_mode 0)
		)
		(polygon
			(pts
				(arc
					(start 131.4704 -390.761474)
					(mid 131.1656 -390.761474)
					(end 131.4704 -390.761474)
				)
			)
		)
	)
	(zone
		(layer "In1.Cu")
		(hatch none 0.5)
		(connect_pads
			(clearance 0)
		)
		(min_thickness 0.25)
		(keepout
			(tracks not_allowed)
			(vias allowed)
			(pads allowed)
			(copperpour not_allowed)
			(footprints allowed)
		)
		(placement
			(enabled no)
			(sheetname "")
		)
		(fill
			(thermal_gap 0.5)
			(thermal_bridge_width 0.5)
			(island_removal_mode 0)
		)
		(polygon
			(pts
				(arc
					(start 48.533304 -273.232372)
					(mid 48.529584 -273.241352)
					(end 48.520604 -273.245072)
				)
				(arc
					(start 47.047404 -273.245072)
					(mid 47.038424 -273.241352)
					(end 47.034704 -273.232372)
				)
				(arc
					(start 47.034704 -272.737834)
					(mid 47.038424 -272.728854)
					(end 47.047404 -272.725134)
				)
				(arc
					(start 48.520604 -272.725134)
					(mid 48.529584 -272.728854)
					(end 48.533304 -272.737834)
				)
			)
		)
	)
	(zone
		(layer "In1.Cu")
		(hatch none 0.5)
		(connect_pads
			(clearance 0)
		)
		(min_thickness 0.25)
		(keepout
			(tracks not_allowed)
			(vias allowed)
			(pads allowed)
			(copperpour not_allowed)
			(footprints allowed)
		)
		(placement
			(enabled no)
			(sheetname "")
		)
		(fill
			(thermal_gap 0.5)
			(thermal_bridge_width 0.5)
			(island_removal_mode 0)
		)
		(polygon
			(pts
				(arc
					(start 52.633372 -298.732448)
					(mid 52.629652 -298.741428)
					(end 52.620672 -298.745148)
				)
				(arc
					(start 51.147472 -298.745148)
					(mid 51.138492 -298.741428)
					(end 51.134772 -298.732448)
				)
				(arc
					(start 51.134772 -298.23791)
					(mid 51.138492 -298.22893)
					(end 51.147472 -298.22521)
				)
				(arc
					(start 52.620672 -298.22521)
					(mid 52.629652 -298.22893)
					(end 52.633372 -298.23791)
				)
			)
		)
	)
	(zone
		(layer "In1.Cu")
		(hatch none 0.5)
		(connect_pads
			(clearance 0)
		)
		(min_thickness 0.25)
		(keepout
			(tracks not_allowed)
			(vias allowed)
			(pads allowed)
			(copperpour not_allowed)
			(footprints allowed)
		)
		(placement
			(enabled no)
			(sheetname "")
		)
		(fill
			(thermal_gap 0.5)
			(thermal_bridge_width 0.5)
			(island_removal_mode 0)
		)
		(polygon
			(pts
				(arc
					(start 60.177426 -275.782532)
					(mid 60.173706 -275.791512)
					(end 60.164726 -275.795232)
				)
				(arc
					(start 58.691526 -275.795232)
					(mid 58.682546 -275.791512)
					(end 58.678826 -275.782532)
				)
				(arc
					(start 58.678826 -275.287994)
					(mid 58.682546 -275.279014)
					(end 58.691526 -275.275294)
				)
				(arc
					(start 60.164726 -275.275294)
					(mid 60.173706 -275.279014)
					(end 60.177426 -275.287994)
				)
			)
		)
	)
	(zone
		(layer "In1.Cu")
		(hatch none 0.5)
		(connect_pads
			(clearance 0)
		)
		(min_thickness 0.25)
		(keepout
			(tracks not_allowed)
			(vias allowed)
			(pads allowed)
			(copperpour not_allowed)
			(footprints allowed)
		)
		(placement
			(enabled no)
			(sheetname "")
		)
		(fill
			(thermal_gap 0.5)
			(thermal_bridge_width 0.5)
			(island_removal_mode 0)
		)
		(polygon
			(pts
				(arc
					(start 157.88894 -388.774432)
					(mid 157.50794 -388.774432)
					(end 157.88894 -388.774432)
				)
			)
		)
	)
	(zone
		(layer "In1.Cu")
		(hatch none 0.5)
		(connect_pads
			(clearance 0)
		)
		(min_thickness 0.25)
		(keepout
			(tracks not_allowed)
			(vias allowed)
			(pads allowed)
			(copperpour not_allowed)
			(footprints allowed)
		)
		(placement
			(enabled no)
			(sheetname "")
		)
		(fill
			(thermal_gap 0.5)
			(thermal_bridge_width 0.5)
			(island_removal_mode 0)
		)
		(polygon
			(pts
				(arc
					(start 432.30546 -225.632264)
					(mid 432.30174 -225.641244)
					(end 432.29276 -225.644964)
				)
				(arc
					(start 430.81956 -225.644964)
					(mid 430.81058 -225.641244)
					(end 430.80686 -225.632264)
				)
				(arc
					(start 430.80686 -225.137726)
					(mid 430.81058 -225.128746)
					(end 430.81956 -225.125026)
				)
				(arc
					(start 432.29276 -225.125026)
					(mid 432.30174 -225.128746)
					(end 432.30546 -225.137726)
				)
			)
		)
	)
	(zone
		(layer "In1.Cu")
		(hatch none 0.5)
		(connect_pads
			(clearance 0)
		)
		(min_thickness 0.25)
		(keepout
			(tracks not_allowed)
			(vias allowed)
			(pads allowed)
			(copperpour not_allowed)
			(footprints allowed)
		)
		(placement
			(enabled no)
			(sheetname "")
		)
		(fill
			(thermal_gap 0.5)
			(thermal_bridge_width 0.5)
			(island_removal_mode 0)
		)
		(polygon
			(pts
				(arc
					(start 40.98925 -274.932394)
					(mid 40.98553 -274.941374)
					(end 40.97655 -274.945094)
				)
				(arc
					(start 39.50335 -274.945094)
					(mid 39.49437 -274.941374)
					(end 39.49065 -274.932394)
				)
				(arc
					(start 39.49065 -274.437856)
					(mid 39.49437 -274.428876)
					(end 39.50335 -274.425156)
				)
				(arc
					(start 40.97655 -274.425156)
					(mid 40.98553 -274.428876)
					(end 40.98925 -274.437856)
				)
			)
		)
	)
	(zone
		(layer "In1.Cu")
		(hatch none 0.5)
		(connect_pads
			(clearance 0)
		)
		(min_thickness 0.25)
		(keepout
			(tracks not_allowed)
			(vias allowed)
			(pads allowed)
			(copperpour not_allowed)
			(footprints allowed)
		)
		(placement
			(enabled no)
			(sheetname "")
		)
		(fill
			(thermal_gap 0.5)
			(thermal_bridge_width 0.5)
			(island_removal_mode 0)
		)
		(polygon
			(pts
				(arc
					(start 169.277284 -302.132492)
					(mid 169.273564 -302.141472)
					(end 169.264584 -302.145192)
				)
				(arc
					(start 167.791384 -302.145192)
					(mid 167.782404 -302.141472)
					(end 167.778684 -302.132492)
				)
				(arc
					(start 167.778684 -301.637954)
					(mid 167.782404 -301.628974)
					(end 167.791384 -301.625254)
				)
				(arc
					(start 169.264584 -301.625254)
					(mid 169.273564 -301.628974)
					(end 169.277284 -301.637954)
				)
			)
		)
	)
	(zone
		(layer "In1.Cu")
		(hatch none 0.5)
		(connect_pads
			(clearance 0)
		)
		(min_thickness 0.25)
		(keepout
			(tracks not_allowed)
			(vias allowed)
			(pads allowed)
			(copperpour not_allowed)
			(footprints allowed)
		)
		(placement
			(enabled no)
			(sheetname "")
		)
		(fill
			(thermal_gap 0.5)
			(thermal_bridge_width 0.5)
			(island_removal_mode 0)
		)
		(polygon
			(pts
				(arc
					(start 45.089318 -247.73255)
					(mid 45.085598 -247.74153)
					(end 45.076618 -247.74525)
				)
				(arc
					(start 43.603418 -247.74525)
					(mid 43.594438 -247.74153)
					(end 43.590718 -247.73255)
				)
				(arc
					(start 43.590718 -247.238012)
					(mid 43.594438 -247.229032)
					(end 43.603418 -247.225312)
				)
				(arc
					(start 45.076618 -247.225312)
					(mid 45.085598 -247.229032)
					(end 45.089318 -247.238012)
				)
			)
		)
	)
	(zone
		(layer "In1.Cu")
		(hatch none 0.5)
		(connect_pads
			(clearance 0)
		)
		(min_thickness 0.25)
		(keepout
			(tracks not_allowed)
			(vias allowed)
			(pads allowed)
			(copperpour not_allowed)
			(footprints allowed)
		)
		(placement
			(enabled no)
			(sheetname "")
		)
		(fill
			(thermal_gap 0.5)
			(thermal_bridge_width 0.5)
			(island_removal_mode 0)
		)
		(polygon
			(pts
				(arc
					(start 314.260992 -397.156432)
					(mid 313.879992 -397.156432)
					(end 314.260992 -397.156432)
				)
			)
		)
	)
	(zone
		(layer "In1.Cu")
		(hatch none 0.5)
		(connect_pads
			(clearance 0)
		)
		(min_thickness 0.25)
		(keepout
			(tracks not_allowed)
			(vias allowed)
			(pads allowed)
			(copperpour not_allowed)
			(footprints allowed)
		)
		(placement
			(enabled no)
			(sheetname "")
		)
		(fill
			(thermal_gap 0.5)
			(thermal_bridge_width 0.5)
			(island_removal_mode 0)
		)
		(polygon
			(pts
				(arc
					(start 58.26125 -385.31038)
					(mid 57.88025 -385.31038)
					(end 58.26125 -385.31038)
				)
			)
		)
	)
	(zone
		(layer "In1.Cu")
		(hatch none 0.5)
		(connect_pads
			(clearance 0)
		)
		(min_thickness 0.25)
		(keepout
			(tracks not_allowed)
			(vias allowed)
			(pads allowed)
			(copperpour not_allowed)
			(footprints allowed)
		)
		(placement
			(enabled no)
			(sheetname "")
		)
		(fill
			(thermal_gap 0.5)
			(thermal_bridge_width 0.5)
			(island_removal_mode 0)
		)
		(polygon
			(pts
				(arc
					(start 285.485332 -206.932276)
					(mid 285.481612 -206.941256)
					(end 285.472632 -206.944976)
				)
				(arc
					(start 283.999432 -206.944976)
					(mid 283.990452 -206.941256)
					(end 283.986732 -206.932276)
				)
				(arc
					(start 283.986732 -206.437738)
					(mid 283.990452 -206.428758)
					(end 283.999432 -206.425038)
				)
				(arc
					(start 285.472632 -206.425038)
					(mid 285.481612 -206.428758)
					(end 285.485332 -206.437738)
				)
			)
		)
	)
	(zone
		(layer "In1.Cu")
		(hatch none 0.5)
		(connect_pads
			(clearance 0)
		)
		(min_thickness 0.25)
		(keepout
			(tracks not_allowed)
			(vias allowed)
			(pads allowed)
			(copperpour not_allowed)
			(footprints allowed)
		)
		(placement
			(enabled no)
			(sheetname "")
		)
		(fill
			(thermal_gap 0.5)
			(thermal_bridge_width 0.5)
			(island_removal_mode 0)
		)
		(polygon
			(pts
				(arc
					(start 187.809378 -220.532452)
					(mid 187.805658 -220.541432)
					(end 187.796678 -220.545152)
				)
				(arc
					(start 186.323478 -220.545152)
					(mid 186.314498 -220.541432)
					(end 186.310778 -220.532452)
				)
				(arc
					(start 186.310778 -220.037914)
					(mid 186.314498 -220.028934)
					(end 186.323478 -220.025214)
				)
				(arc
					(start 187.796678 -220.025214)
					(mid 187.805658 -220.028934)
					(end 187.809378 -220.037914)
				)
			)
		)
	)
	(zone
		(layer "In1.Cu")
		(hatch none 0.5)
		(connect_pads
			(clearance 0)
		)
		(min_thickness 0.25)
		(keepout
			(tracks not_allowed)
			(vias allowed)
			(pads allowed)
			(copperpour not_allowed)
			(footprints allowed)
		)
		(placement
			(enabled no)
			(sheetname "")
		)
		(fill
			(thermal_gap 0.5)
			(thermal_bridge_width 0.5)
			(island_removal_mode 0)
		)
		(polygon
			(pts
				(arc
					(start 424.761406 -252.832108)
					(mid 424.757686 -252.841088)
					(end 424.748706 -252.844808)
				)
				(arc
					(start 423.275506 -252.844808)
					(mid 423.266526 -252.841088)
					(end 423.262806 -252.832108)
				)
				(arc
					(start 423.262806 -252.33757)
					(mid 423.266526 -252.32859)
					(end 423.275506 -252.32487)
				)
				(arc
					(start 424.748706 -252.32487)
					(mid 424.757686 -252.32859)
					(end 424.761406 -252.33757)
				)
			)
		)
	)
	(zone
		(layer "In1.Cu")
		(hatch none 0.5)
		(connect_pads
			(clearance 0)
		)
		(min_thickness 0.25)
		(keepout
			(tracks not_allowed)
			(vias allowed)
			(pads allowed)
			(copperpour not_allowed)
			(footprints allowed)
		)
		(placement
			(enabled no)
			(sheetname "")
		)
		(fill
			(thermal_gap 0.5)
			(thermal_bridge_width 0.5)
			(island_removal_mode 0)
		)
		(polygon
			(pts
				(arc
					(start 266.29741 -226.482148)
					(mid 266.29369 -226.491128)
					(end 266.28471 -226.494848)
				)
				(arc
					(start 264.81151 -226.494848)
					(mid 264.80253 -226.491128)
					(end 264.79881 -226.482148)
				)
				(arc
					(start 264.79881 -225.98761)
					(mid 264.80253 -225.97863)
					(end 264.81151 -225.97491)
				)
				(arc
					(start 266.28471 -225.97491)
					(mid 266.29369 -225.97863)
					(end 266.29741 -225.98761)
				)
			)
		)
	)
	(zone
		(layer "In1.Cu")
		(hatch none 0.5)
		(connect_pads
			(clearance 0)
		)
		(min_thickness 0.25)
		(keepout
			(tracks not_allowed)
			(vias allowed)
			(pads allowed)
			(copperpour not_allowed)
			(footprints allowed)
		)
		(placement
			(enabled no)
			(sheetname "")
		)
		(fill
			(thermal_gap 0.5)
			(thermal_bridge_width 0.5)
			(island_removal_mode 0)
		)
		(polygon
			(pts
				(arc
					(start 45.089318 -229.032562)
					(mid 45.085598 -229.041542)
					(end 45.076618 -229.045262)
				)
				(arc
					(start 43.603418 -229.045262)
					(mid 43.594438 -229.041542)
					(end 43.590718 -229.032562)
				)
				(arc
					(start 43.590718 -228.538024)
					(mid 43.594438 -228.529044)
					(end 43.603418 -228.525324)
				)
				(arc
					(start 45.076618 -228.525324)
					(mid 45.085598 -228.529044)
					(end 45.089318 -228.538024)
				)
			)
		)
	)
	(zone
		(layer "In1.Cu")
		(hatch none 0.5)
		(connect_pads
			(clearance 0)
		)
		(min_thickness 0.25)
		(keepout
			(tracks not_allowed)
			(vias allowed)
			(pads allowed)
			(copperpour not_allowed)
			(footprints allowed)
		)
		(placement
			(enabled no)
			(sheetname "")
		)
		(fill
			(thermal_gap 0.5)
			(thermal_bridge_width 0.5)
			(island_removal_mode 0)
		)
		(polygon
			(pts
				(arc
					(start 206.9973 -285.132526)
					(mid 206.99358 -285.141506)
					(end 206.9846 -285.145226)
				)
				(arc
					(start 205.5114 -285.145226)
					(mid 205.50242 -285.141506)
					(end 205.4987 -285.132526)
				)
				(arc
					(start 205.4987 -284.637988)
					(mid 205.50242 -284.629008)
					(end 205.5114 -284.625288)
				)
				(arc
					(start 206.9846 -284.625288)
					(mid 206.99358 -284.629008)
					(end 206.9973 -284.637988)
				)
			)
		)
	)
	(zone
		(layer "In1.Cu")
		(hatch none 0.5)
		(connect_pads
			(clearance 0)
		)
		(min_thickness 0.25)
		(keepout
			(tracks not_allowed)
			(vias allowed)
			(pads allowed)
			(copperpour not_allowed)
			(footprints allowed)
		)
		(placement
			(enabled no)
			(sheetname "")
		)
		(fill
			(thermal_gap 0.5)
			(thermal_bridge_width 0.5)
			(island_removal_mode 0)
		)
		(polygon
			(pts
				(arc
					(start 316.190884 -391.822686)
					(mid 316.317884 -391.949686)
					(end 316.444884 -391.822686)
				)
				(arc
					(start 316.444884 -391.746486)
					(mid 316.317884 -391.619486)
					(end 316.190884 -391.746486)
				)
			)
		)
	)
	(zone
		(layer "In1.Cu")
		(hatch none 0.5)
		(connect_pads
			(clearance 0)
		)
		(min_thickness 0.25)
		(keepout
			(tracks not_allowed)
			(vias allowed)
			(pads allowed)
			(copperpour not_allowed)
			(footprints allowed)
		)
		(placement
			(enabled no)
			(sheetname "")
		)
		(fill
			(thermal_gap 0.5)
			(thermal_bridge_width 0.5)
			(island_removal_mode 0)
		)
		(polygon
			(pts
				(arc
					(start 270.397478 -229.032308)
					(mid 270.393758 -229.041288)
					(end 270.384778 -229.045008)
				)
				(arc
					(start 268.911578 -229.045008)
					(mid 268.902598 -229.041288)
					(end 268.898878 -229.032308)
				)
				(arc
					(start 268.898878 -228.53777)
					(mid 268.902598 -228.52879)
					(end 268.911578 -228.52507)
				)
				(arc
					(start 270.384778 -228.52507)
					(mid 270.393758 -228.52879)
					(end 270.397478 -228.53777)
				)
			)
		)
	)
	(zone
		(layer "In1.Cu")
		(hatch none 0.5)
		(connect_pads
			(clearance 0)
		)
		(min_thickness 0.25)
		(keepout
			(tracks not_allowed)
			(vias allowed)
			(pads allowed)
			(copperpour not_allowed)
			(footprints allowed)
		)
		(placement
			(enabled no)
			(sheetname "")
		)
		(fill
			(thermal_gap 0.5)
			(thermal_bridge_width 0.5)
			(island_removal_mode 0)
		)
		(polygon
			(pts
				(arc
					(start 342.718644 -399.701258)
					(mid 342.845644 -399.828258)
					(end 342.972644 -399.701258)
				)
				(arc
					(start 342.972644 -399.625058)
					(mid 342.845644 -399.498058)
					(end 342.718644 -399.625058)
				)
			)
		)
	)
	(zone
		(layer "In1.Cu")
		(hatch none 0.5)
		(connect_pads
			(clearance 0)
		)
		(min_thickness 0.25)
		(keepout
			(tracks not_allowed)
			(vias allowed)
			(pads allowed)
			(copperpour not_allowed)
			(footprints allowed)
		)
		(placement
			(enabled no)
			(sheetname "")
		)
		(fill
			(thermal_gap 0.5)
			(thermal_bridge_width 0.5)
			(island_removal_mode 0)
		)
		(polygon
			(pts
				(arc
					(start 435.749446 -215.432132)
					(mid 435.745726 -215.441112)
					(end 435.736746 -215.444832)
				)
				(arc
					(start 434.263546 -215.444832)
					(mid 434.254566 -215.441112)
					(end 434.250846 -215.432132)
				)
				(arc
					(start 434.250846 -214.937594)
					(mid 434.254566 -214.928614)
					(end 434.263546 -214.924894)
				)
				(arc
					(start 435.736746 -214.924894)
					(mid 435.745726 -214.928614)
					(end 435.749446 -214.937594)
				)
			)
		)
	)
	(zone
		(layer "In1.Cu")
		(hatch none 0.5)
		(connect_pads
			(clearance 0)
		)
		(min_thickness 0.25)
		(keepout
			(tracks not_allowed)
			(vias allowed)
			(pads allowed)
			(copperpour not_allowed)
			(footprints allowed)
		)
		(placement
			(enabled no)
			(sheetname "")
		)
		(fill
			(thermal_gap 0.5)
			(thermal_bridge_width 0.5)
			(island_removal_mode 0)
		)
		(polygon
			(pts
				(arc
					(start 187.809378 -246.882412)
					(mid 187.805658 -246.891392)
					(end 187.796678 -246.895112)
				)
				(arc
					(start 186.323478 -246.895112)
					(mid 186.314498 -246.891392)
					(end 186.310778 -246.882412)
				)
				(arc
					(start 186.310778 -246.387874)
					(mid 186.314498 -246.378894)
					(end 186.323478 -246.375174)
				)
				(arc
					(start 187.796678 -246.375174)
					(mid 187.805658 -246.378894)
					(end 187.809378 -246.387874)
				)
			)
		)
	)
	(zone
		(layer "In1.Cu")
		(hatch none 0.5)
		(connect_pads
			(clearance 0)
		)
		(min_thickness 0.25)
		(keepout
			(tracks not_allowed)
			(vias allowed)
			(pads allowed)
			(copperpour not_allowed)
			(footprints allowed)
		)
		(placement
			(enabled no)
			(sheetname "")
		)
		(fill
			(thermal_gap 0.5)
			(thermal_bridge_width 0.5)
			(island_removal_mode 0)
		)
		(polygon
			(pts
				(arc
					(start 33.445196 -237.532418)
					(mid 33.441476 -237.541398)
					(end 33.432496 -237.545118)
				)
				(arc
					(start 31.959296 -237.545118)
					(mid 31.950316 -237.541398)
					(end 31.946596 -237.532418)
				)
				(arc
					(start 31.946596 -237.03788)
					(mid 31.950316 -237.0289)
					(end 31.959296 -237.02518)
				)
				(arc
					(start 33.432496 -237.02518)
					(mid 33.441476 -237.0289)
					(end 33.445196 -237.03788)
				)
			)
		)
	)
	(zone
		(layer "In1.Cu")
		(hatch none 0.5)
		(connect_pads
			(clearance 0)
		)
		(min_thickness 0.25)
		(keepout
			(tracks not_allowed)
			(vias allowed)
			(pads allowed)
			(copperpour not_allowed)
			(footprints allowed)
		)
		(placement
			(enabled no)
			(sheetname "")
		)
		(fill
			(thermal_gap 0.5)
			(thermal_bridge_width 0.5)
			(island_removal_mode 0)
		)
		(polygon
			(pts
				(arc
					(start 308.117494 -285.132272)
					(mid 308.113774 -285.141252)
					(end 308.104794 -285.144972)
				)
				(arc
					(start 306.631594 -285.144972)
					(mid 306.622614 -285.141252)
					(end 306.618894 -285.132272)
				)
				(arc
					(start 306.618894 -284.637734)
					(mid 306.622614 -284.628754)
					(end 306.631594 -284.625034)
				)
				(arc
					(start 308.104794 -284.625034)
					(mid 308.113774 -284.628754)
					(end 308.117494 -284.637734)
				)
			)
		)
	)
	(zone
		(layer "In1.Cu")
		(hatch none 0.5)
		(connect_pads
			(clearance 0)
		)
		(min_thickness 0.25)
		(keepout
			(tracks not_allowed)
			(vias allowed)
			(pads allowed)
			(copperpour not_allowed)
			(footprints allowed)
		)
		(placement
			(enabled no)
			(sheetname "")
		)
		(fill
			(thermal_gap 0.5)
			(thermal_bridge_width 0.5)
			(island_removal_mode 0)
		)
		(polygon
			(pts
				(arc
					(start 308.117494 -313.182254)
					(mid 308.113774 -313.191234)
					(end 308.104794 -313.194954)
				)
				(arc
					(start 306.631594 -313.194954)
					(mid 306.622614 -313.191234)
					(end 306.618894 -313.182254)
				)
				(arc
					(start 306.618894 -312.687716)
					(mid 306.622614 -312.678736)
					(end 306.631594 -312.675016)
				)
				(arc
					(start 308.104794 -312.675016)
					(mid 308.113774 -312.678736)
					(end 308.117494 -312.687716)
				)
			)
		)
	)
	(zone
		(layer "In1.Cu")
		(hatch none 0.5)
		(connect_pads
			(clearance 0)
		)
		(min_thickness 0.25)
		(keepout
			(tracks not_allowed)
			(vias allowed)
			(pads allowed)
			(copperpour not_allowed)
			(footprints allowed)
		)
		(placement
			(enabled no)
			(sheetname "")
		)
		(fill
			(thermal_gap 0.5)
			(thermal_bridge_width 0.5)
			(island_removal_mode 0)
		)
		(polygon
			(pts
				(arc
					(start 285.485332 -285.132272)
					(mid 285.481612 -285.141252)
					(end 285.472632 -285.144972)
				)
				(arc
					(start 283.999432 -285.144972)
					(mid 283.990452 -285.141252)
					(end 283.986732 -285.132272)
				)
				(arc
					(start 283.986732 -284.637734)
					(mid 283.990452 -284.628754)
					(end 283.999432 -284.625034)
				)
				(arc
					(start 285.472632 -284.625034)
					(mid 285.481612 -284.628754)
					(end 285.485332 -284.637734)
				)
			)
		)
	)
	(zone
		(layer "In1.Cu")
		(hatch none 0.5)
		(connect_pads
			(clearance 0)
		)
		(min_thickness 0.25)
		(keepout
			(tracks not_allowed)
			(vias allowed)
			(pads allowed)
			(copperpour not_allowed)
			(footprints allowed)
		)
		(placement
			(enabled no)
			(sheetname "")
		)
		(fill
			(thermal_gap 0.5)
			(thermal_bridge_width 0.5)
			(island_removal_mode 0)
		)
		(polygon
			(pts
				(arc
					(start 155.88869 -386.003292)
					(mid 155.50769 -386.003292)
					(end 155.88869 -386.003292)
				)
			)
		)
	)
	(zone
		(layer "In1.Cu")
		(hatch none 0.5)
		(connect_pads
			(clearance 0)
		)
		(min_thickness 0.25)
		(keepout
			(tracks not_allowed)
			(vias allowed)
			(pads allowed)
			(copperpour not_allowed)
			(footprints allowed)
		)
		(placement
			(enabled no)
			(sheetname "")
		)
		(fill
			(thermal_gap 0.5)
			(thermal_bridge_width 0.5)
			(island_removal_mode 0)
		)
		(polygon
			(pts
				(arc
					(start 40.50284 -426.817536)
					(mid 40.556722 -426.795218)
					(end 40.57904 -426.741336)
				)
				(arc
					(start 40.57904 -426.385736)
					(mid 40.556722 -426.331854)
					(end 40.50284 -426.309536)
				)
				(arc
					(start 38.59784 -426.309536)
					(mid 38.543958 -426.331854)
					(end 38.52164 -426.385736)
				)
				(arc
					(start 38.52164 -426.741336)
					(mid 38.543958 -426.795218)
					(end 38.59784 -426.817536)
				)
			)
		)
	)
	(zone
		(layer "In1.Cu")
		(hatch none 0.5)
		(connect_pads
			(clearance 0)
		)
		(min_thickness 0.25)
		(keepout
			(tracks not_allowed)
			(vias allowed)
			(pads allowed)
			(copperpour not_allowed)
			(footprints allowed)
		)
		(placement
			(enabled no)
			(sheetname "")
		)
		(fill
			(thermal_gap 0.5)
			(thermal_bridge_width 0.5)
			(island_removal_mode 0)
		)
		(polygon
			(pts
				(arc
					(start 432.30546 -222.23222)
					(mid 432.30174 -222.2412)
					(end 432.29276 -222.24492)
				)
				(arc
					(start 430.81956 -222.24492)
					(mid 430.81058 -222.2412)
					(end 430.80686 -222.23222)
				)
				(arc
					(start 430.80686 -221.737682)
					(mid 430.81058 -221.728702)
					(end 430.81956 -221.724982)
				)
				(arc
					(start 432.29276 -221.724982)
					(mid 432.30174 -221.728702)
					(end 432.30546 -221.737682)
				)
			)
		)
	)
	(zone
		(layer "In1.Cu")
		(hatch none 0.5)
		(connect_pads
			(clearance 0)
		)
		(min_thickness 0.25)
		(keepout
			(tracks not_allowed)
			(vias allowed)
			(pads allowed)
			(copperpour not_allowed)
			(footprints allowed)
		)
		(placement
			(enabled no)
			(sheetname "")
		)
		(fill
			(thermal_gap 0.5)
			(thermal_bridge_width 0.5)
			(island_removal_mode 0)
		)
		(polygon
			(pts
				(arc
					(start 296.473372 -223.082104)
					(mid 296.469652 -223.091084)
					(end 296.460672 -223.094804)
				)
				(arc
					(start 294.987472 -223.094804)
					(mid 294.978492 -223.091084)
					(end 294.974772 -223.082104)
				)
				(arc
					(start 294.974772 -222.587566)
					(mid 294.978492 -222.578586)
					(end 294.987472 -222.574866)
				)
				(arc
					(start 296.460672 -222.574866)
					(mid 296.469652 -222.578586)
					(end 296.473372 -222.587566)
				)
			)
		)
	)
	(zone
		(layer "In1.Cu")
		(hatch none 0.5)
		(connect_pads
			(clearance 0)
		)
		(min_thickness 0.25)
		(keepout
			(tracks not_allowed)
			(vias allowed)
			(pads allowed)
			(copperpour not_allowed)
			(footprints allowed)
		)
		(placement
			(enabled no)
			(sheetname "")
		)
		(fill
			(thermal_gap 0.5)
			(thermal_bridge_width 0.5)
			(island_removal_mode 0)
		)
		(polygon
			(pts
				(arc
					(start 304.017426 -204.382116)
					(mid 304.013706 -204.391096)
					(end 304.004726 -204.394816)
				)
				(arc
					(start 302.531526 -204.394816)
					(mid 302.522546 -204.391096)
					(end 302.518826 -204.382116)
				)
				(arc
					(start 302.518826 -203.887578)
					(mid 302.522546 -203.878598)
					(end 302.531526 -203.874878)
				)
				(arc
					(start 304.004726 -203.874878)
					(mid 304.013706 -203.878598)
					(end 304.017426 -203.887578)
				)
			)
		)
	)
	(zone
		(layer "In1.Cu")
		(hatch none 0.5)
		(connect_pads
			(clearance 0)
		)
		(min_thickness 0.25)
		(keepout
			(tracks not_allowed)
			(vias allowed)
			(pads allowed)
			(copperpour not_allowed)
			(footprints allowed)
		)
		(placement
			(enabled no)
			(sheetname "")
		)
		(fill
			(thermal_gap 0.5)
			(thermal_bridge_width 0.5)
			(island_removal_mode 0)
		)
		(polygon
			(pts
				(arc
					(start 18.357342 -226.482402)
					(mid 18.353622 -226.491382)
					(end 18.344642 -226.495102)
				)
				(arc
					(start 16.871442 -226.495102)
					(mid 16.862462 -226.491382)
					(end 16.858742 -226.482402)
				)
				(arc
					(start 16.858742 -225.987864)
					(mid 16.862462 -225.978884)
					(end 16.871442 -225.975164)
				)
				(arc
					(start 18.344642 -225.975164)
					(mid 18.353622 -225.978884)
					(end 18.357342 -225.987864)
				)
			)
		)
	)
	(zone
		(layer "In1.Cu")
		(hatch none 0.5)
		(connect_pads
			(clearance 0)
		)
		(min_thickness 0.25)
		(keepout
			(tracks not_allowed)
			(vias allowed)
			(pads allowed)
			(copperpour not_allowed)
			(footprints allowed)
		)
		(placement
			(enabled no)
			(sheetname "")
		)
		(fill
			(thermal_gap 0.5)
			(thermal_bridge_width 0.5)
			(island_removal_mode 0)
		)
		(polygon
			(pts
				(arc
					(start 265.87831 -314.635134)
					(mid 265.21791 -314.635134)
					(end 265.87831 -314.635134)
				)
			)
		)
	)
	(zone
		(layer "In1.Cu")
		(hatch none 0.5)
		(connect_pads
			(clearance 0)
		)
		(min_thickness 0.25)
		(keepout
			(tracks not_allowed)
			(vias allowed)
			(pads allowed)
			(copperpour not_allowed)
			(footprints allowed)
		)
		(placement
			(enabled no)
			(sheetname "")
		)
		(fill
			(thermal_gap 0.5)
			(thermal_bridge_width 0.5)
			(island_removal_mode 0)
		)
		(polygon
			(pts
				(arc
					(start 432.30546 -304.682144)
					(mid 432.30174 -304.691124)
					(end 432.29276 -304.694844)
				)
				(arc
					(start 430.81956 -304.694844)
					(mid 430.81058 -304.691124)
					(end 430.80686 -304.682144)
				)
				(arc
					(start 430.80686 -304.187606)
					(mid 430.81058 -304.178626)
					(end 430.81956 -304.174906)
				)
				(arc
					(start 432.29276 -304.174906)
					(mid 432.30174 -304.178626)
					(end 432.30546 -304.187606)
				)
			)
		)
	)
	(zone
		(layer "In1.Cu")
		(hatch none 0.5)
		(connect_pads
			(clearance 0)
		)
		(min_thickness 0.25)
		(keepout
			(tracks not_allowed)
			(vias allowed)
			(pads allowed)
			(copperpour not_allowed)
			(footprints allowed)
		)
		(placement
			(enabled no)
			(sheetname "")
		)
		(fill
			(thermal_gap 0.5)
			(thermal_bridge_width 0.5)
			(island_removal_mode 0)
		)
		(polygon
			(pts
				(arc
					(start 52.633372 -199.282558)
					(mid 52.629652 -199.291538)
					(end 52.620672 -199.295258)
				)
				(arc
					(start 51.147472 -199.295258)
					(mid 51.138492 -199.291538)
					(end 51.134772 -199.282558)
				)
				(arc
					(start 51.134772 -198.78802)
					(mid 51.138492 -198.77904)
					(end 51.147472 -198.77532)
				)
				(arc
					(start 52.620672 -198.77532)
					(mid 52.629652 -198.77904)
					(end 52.633372 -198.78802)
				)
			)
		)
	)
	(zone
		(layer "In1.Cu")
		(hatch none 0.5)
		(connect_pads
			(clearance 0)
		)
		(min_thickness 0.25)
		(keepout
			(tracks not_allowed)
			(vias allowed)
			(pads allowed)
			(copperpour not_allowed)
			(footprints allowed)
		)
		(placement
			(enabled no)
			(sheetname "")
		)
		(fill
			(thermal_gap 0.5)
			(thermal_bridge_width 0.5)
			(island_removal_mode 0)
		)
		(polygon
			(pts
				(arc
					(start 447.393568 -199.282304)
					(mid 447.389848 -199.291284)
					(end 447.380868 -199.295004)
				)
				(arc
					(start 445.907668 -199.295004)
					(mid 445.898688 -199.291284)
					(end 445.894968 -199.282304)
				)
				(arc
					(start 445.894968 -198.787766)
					(mid 445.898688 -198.778786)
					(end 445.907668 -198.775066)
				)
				(arc
					(start 447.380868 -198.775066)
					(mid 447.389848 -198.778786)
					(end 447.393568 -198.787766)
				)
			)
		)
	)
	(zone
		(layer "In1.Cu")
		(hatch none 0.5)
		(connect_pads
			(clearance 0)
		)
		(min_thickness 0.25)
		(keepout
			(tracks not_allowed)
			(vias allowed)
			(pads allowed)
			(copperpour not_allowed)
			(footprints allowed)
		)
		(placement
			(enabled no)
			(sheetname "")
		)
		(fill
			(thermal_gap 0.5)
			(thermal_bridge_width 0.5)
			(island_removal_mode 0)
		)
		(polygon
			(pts
				(arc
					(start 25.901396 -295.332404)
					(mid 25.897676 -295.341384)
					(end 25.888696 -295.345104)
				)
				(arc
					(start 24.415496 -295.345104)
					(mid 24.406516 -295.341384)
					(end 24.402796 -295.332404)
				)
				(arc
					(start 24.402796 -294.837866)
					(mid 24.406516 -294.828886)
					(end 24.415496 -294.825166)
				)
				(arc
					(start 25.888696 -294.825166)
					(mid 25.897676 -294.828886)
					(end 25.901396 -294.837866)
				)
			)
		)
	)
	(zone
		(layer "In1.Cu")
		(hatch none 0.5)
		(connect_pads
			(clearance 0)
		)
		(min_thickness 0.25)
		(keepout
			(tracks not_allowed)
			(vias allowed)
			(pads allowed)
			(copperpour not_allowed)
			(footprints allowed)
		)
		(placement
			(enabled no)
			(sheetname "")
		)
		(fill
			(thermal_gap 0.5)
			(thermal_bridge_width 0.5)
			(island_removal_mode 0)
		)
		(polygon
			(pts
				(arc
					(start 270.397478 -252.832108)
					(mid 270.393758 -252.841088)
					(end 270.384778 -252.844808)
				)
				(arc
					(start 268.911578 -252.844808)
					(mid 268.902598 -252.841088)
					(end 268.898878 -252.832108)
				)
				(arc
					(start 268.898878 -252.33757)
					(mid 268.902598 -252.32859)
					(end 268.911578 -252.32487)
				)
				(arc
					(start 270.384778 -252.32487)
					(mid 270.393758 -252.32859)
					(end 270.397478 -252.33757)
				)
			)
		)
	)
	(zone
		(layer "In1.Cu")
		(hatch none 0.5)
		(connect_pads
			(clearance 0)
		)
		(min_thickness 0.25)
		(keepout
			(tracks not_allowed)
			(vias allowed)
			(pads allowed)
			(copperpour not_allowed)
			(footprints allowed)
		)
		(placement
			(enabled no)
			(sheetname "")
		)
		(fill
			(thermal_gap 0.5)
			(thermal_bridge_width 0.5)
			(island_removal_mode 0)
		)
		(polygon
			(pts
				(arc
					(start 424.761406 -294.482266)
					(mid 424.757686 -294.491246)
					(end 424.748706 -294.494966)
				)
				(arc
					(start 423.275506 -294.494966)
					(mid 423.266526 -294.491246)
					(end 423.262806 -294.482266)
				)
				(arc
					(start 423.262806 -293.987728)
					(mid 423.266526 -293.978748)
					(end 423.275506 -293.975028)
				)
				(arc
					(start 424.748706 -293.975028)
					(mid 424.757686 -293.978748)
					(end 424.761406 -293.987728)
				)
			)
		)
	)
	(zone
		(layer "In1.Cu")
		(hatch none 0.5)
		(connect_pads
			(clearance 0)
		)
		(min_thickness 0.25)
		(keepout
			(tracks not_allowed)
			(vias allowed)
			(pads allowed)
			(copperpour not_allowed)
			(footprints allowed)
		)
		(placement
			(enabled no)
			(sheetname "")
		)
		(fill
			(thermal_gap 0.5)
			(thermal_bridge_width 0.5)
			(island_removal_mode 0)
		)
		(polygon
			(pts
				(arc
					(start 61.391038 -383.440686)
					(mid 61.518038 -383.567686)
					(end 61.645038 -383.440686)
				)
				(arc
					(start 61.645038 -383.364486)
					(mid 61.518038 -383.237486)
					(end 61.391038 -383.364486)
				)
			)
		)
	)
	(zone
		(layer "In1.Cu")
		(hatch none 0.5)
		(connect_pads
			(clearance 0)
		)
		(min_thickness 0.25)
		(keepout
			(tracks not_allowed)
			(vias allowed)
			(pads allowed)
			(copperpour not_allowed)
			(footprints allowed)
		)
		(placement
			(enabled no)
			(sheetname "")
		)
		(fill
			(thermal_gap 0.5)
			(thermal_bridge_width 0.5)
			(island_removal_mode 0)
		)
		(polygon
			(pts
				(arc
					(start 119.361204 -385.31038)
					(mid 118.980204 -385.31038)
					(end 119.361204 -385.31038)
				)
			)
		)
	)
	(zone
		(layer "In1.Cu")
		(hatch none 0.5)
		(connect_pads
			(clearance 0)
		)
		(min_thickness 0.25)
		(keepout
			(tracks not_allowed)
			(vias allowed)
			(pads allowed)
			(copperpour not_allowed)
			(footprints allowed)
		)
		(placement
			(enabled no)
			(sheetname "")
		)
		(fill
			(thermal_gap 0.5)
			(thermal_bridge_width 0.5)
			(island_removal_mode 0)
		)
		(polygon
			(pts
				(arc
					(start 60.177426 -300.43247)
					(mid 60.173706 -300.44145)
					(end 60.164726 -300.44517)
				)
				(arc
					(start 58.691526 -300.44517)
					(mid 58.682546 -300.44145)
					(end 58.678826 -300.43247)
				)
				(arc
					(start 58.678826 -299.937932)
					(mid 58.682546 -299.928952)
					(end 58.691526 -299.925232)
				)
				(arc
					(start 60.164726 -299.925232)
					(mid 60.173706 -299.928952)
					(end 60.177426 -299.937932)
				)
			)
		)
	)
	(zone
		(layer "In1.Cu")
		(hatch none 0.5)
		(connect_pads
			(clearance 0)
		)
		(min_thickness 0.25)
		(keepout
			(tracks not_allowed)
			(vias allowed)
			(pads allowed)
			(copperpour not_allowed)
			(footprints allowed)
		)
		(placement
			(enabled no)
			(sheetname "")
		)
		(fill
			(thermal_gap 0.5)
			(thermal_bridge_width 0.5)
			(island_removal_mode 0)
		)
		(polygon
			(pts
				(arc
					(start 265.87831 -224.534984)
					(mid 265.21791 -224.534984)
					(end 265.87831 -224.534984)
				)
			)
		)
	)
	(zone
		(layer "In1.Cu")
		(hatch none 0.5)
		(connect_pads
			(clearance 0)
		)
		(min_thickness 0.25)
		(keepout
			(tracks not_allowed)
			(vias allowed)
			(pads allowed)
			(copperpour not_allowed)
			(footprints allowed)
		)
		(placement
			(enabled no)
			(sheetname "")
		)
		(fill
			(thermal_gap 0.5)
			(thermal_bridge_width 0.5)
			(island_removal_mode 0)
		)
		(polygon
			(pts
				(arc
					(start 273.841464 -316.582298)
					(mid 273.837744 -316.591278)
					(end 273.828764 -316.594998)
				)
				(arc
					(start 272.355564 -316.594998)
					(mid 272.346584 -316.591278)
					(end 272.342864 -316.582298)
				)
				(arc
					(start 272.342864 -316.08776)
					(mid 272.346584 -316.07878)
					(end 272.355564 -316.07506)
				)
				(arc
					(start 273.828764 -316.07506)
					(mid 273.837744 -316.07878)
					(end 273.841464 -316.08776)
				)
			)
		)
	)
	(zone
		(layer "In1.Cu")
		(hatch none 0.5)
		(connect_pads
			(clearance 0)
		)
		(min_thickness 0.25)
		(keepout
			(tracks not_allowed)
			(vias allowed)
			(pads allowed)
			(copperpour not_allowed)
			(footprints allowed)
		)
		(placement
			(enabled no)
			(sheetname "")
		)
		(fill
			(thermal_gap 0.5)
			(thermal_bridge_width 0.5)
			(island_removal_mode 0)
		)
		(polygon
			(pts
				(arc
					(start 266.29741 -307.232304)
					(mid 266.29369 -307.241284)
					(end 266.28471 -307.245004)
				)
				(arc
					(start 264.81151 -307.245004)
					(mid 264.80253 -307.241284)
					(end 264.79881 -307.232304)
				)
				(arc
					(start 264.79881 -306.737766)
					(mid 264.80253 -306.728786)
					(end 264.81151 -306.725066)
				)
				(arc
					(start 266.28471 -306.725066)
					(mid 266.29369 -306.728786)
					(end 266.29741 -306.737766)
				)
			)
		)
	)
	(zone
		(layer "In1.Cu")
		(hatch none 0.5)
		(connect_pads
			(clearance 0)
		)
		(min_thickness 0.25)
		(keepout
			(tracks not_allowed)
			(vias allowed)
			(pads allowed)
			(copperpour not_allowed)
			(footprints allowed)
		)
		(placement
			(enabled no)
			(sheetname "")
		)
		(fill
			(thermal_gap 0.5)
			(thermal_bridge_width 0.5)
			(island_removal_mode 0)
		)
		(polygon
			(pts
				(arc
					(start 273.841464 -265.582146)
					(mid 273.837744 -265.591126)
					(end 273.828764 -265.594846)
				)
				(arc
					(start 272.355564 -265.594846)
					(mid 272.346584 -265.591126)
					(end 272.342864 -265.582146)
				)
				(arc
					(start 272.342864 -265.087608)
					(mid 272.346584 -265.078628)
					(end 272.355564 -265.074908)
				)
				(arc
					(start 273.828764 -265.074908)
					(mid 273.837744 -265.078628)
					(end 273.841464 -265.087608)
				)
			)
		)
	)
	(zone
		(layer "In1.Cu")
		(hatch none 0.5)
		(connect_pads
			(clearance 0)
		)
		(min_thickness 0.25)
		(keepout
			(tracks not_allowed)
			(vias allowed)
			(pads allowed)
			(copperpour not_allowed)
			(footprints allowed)
		)
		(placement
			(enabled no)
			(sheetname "")
		)
		(fill
			(thermal_gap 0.5)
			(thermal_bridge_width 0.5)
			(island_removal_mode 0)
		)
		(polygon
			(pts
				(arc
					(start 281.385264 -304.682144)
					(mid 281.381544 -304.691124)
					(end 281.372564 -304.694844)
				)
				(arc
					(start 279.899364 -304.694844)
					(mid 279.890384 -304.691124)
					(end 279.886664 -304.682144)
				)
				(arc
					(start 279.886664 -304.187606)
					(mid 279.890384 -304.178626)
					(end 279.899364 -304.174906)
				)
				(arc
					(start 281.372564 -304.174906)
					(mid 281.381544 -304.178626)
					(end 281.385264 -304.187606)
				)
			)
		)
	)
	(zone
		(layer "In1.Cu")
		(hatch none 0.5)
		(connect_pads
			(clearance 0)
		)
		(min_thickness 0.25)
		(keepout
			(tracks not_allowed)
			(vias allowed)
			(pads allowed)
			(copperpour not_allowed)
			(footprints allowed)
		)
		(placement
			(enabled no)
			(sheetname "")
		)
		(fill
			(thermal_gap 0.5)
			(thermal_bridge_width 0.5)
			(island_removal_mode 0)
		)
		(polygon
			(pts
				(arc
					(start 266.29741 -220.532198)
					(mid 266.29369 -220.541178)
					(end 266.28471 -220.544898)
				)
				(arc
					(start 264.81151 -220.544898)
					(mid 264.80253 -220.541178)
					(end 264.79881 -220.532198)
				)
				(arc
					(start 264.79881 -220.03766)
					(mid 264.80253 -220.02868)
					(end 264.81151 -220.02496)
				)
				(arc
					(start 266.28471 -220.02496)
					(mid 266.29369 -220.02868)
					(end 266.29741 -220.03766)
				)
			)
		)
	)
	(zone
		(layer "In1.Cu")
		(hatch none 0.5)
		(connect_pads
			(clearance 0)
		)
		(min_thickness 0.25)
		(keepout
			(tracks not_allowed)
			(vias allowed)
			(pads allowed)
			(copperpour not_allowed)
			(footprints allowed)
		)
		(placement
			(enabled no)
			(sheetname "")
		)
		(fill
			(thermal_gap 0.5)
			(thermal_bridge_width 0.5)
			(island_removal_mode 0)
		)
		(polygon
			(pts
				(arc
					(start 60.177426 -280.03246)
					(mid 60.173706 -280.04144)
					(end 60.164726 -280.04516)
				)
				(arc
					(start 58.691526 -280.04516)
					(mid 58.682546 -280.04144)
					(end 58.678826 -280.03246)
				)
				(arc
					(start 58.678826 -279.537922)
					(mid 58.682546 -279.528942)
					(end 58.691526 -279.525222)
				)
				(arc
					(start 60.164726 -279.525222)
					(mid 60.173706 -279.528942)
					(end 60.177426 -279.537922)
				)
			)
		)
	)
	(zone
		(layer "In1.Cu")
		(hatch none 0.5)
		(connect_pads
			(clearance 0)
		)
		(min_thickness 0.25)
		(keepout
			(tracks not_allowed)
			(vias allowed)
			(pads allowed)
			(copperpour not_allowed)
			(footprints allowed)
		)
		(placement
			(enabled no)
			(sheetname "")
		)
		(fill
			(thermal_gap 0.5)
			(thermal_bridge_width 0.5)
			(island_removal_mode 0)
		)
		(polygon
			(pts
				(arc
					(start 266.29741 -290.232338)
					(mid 266.29369 -290.241318)
					(end 266.28471 -290.245038)
				)
				(arc
					(start 264.81151 -290.245038)
					(mid 264.80253 -290.241318)
					(end 264.79881 -290.232338)
				)
				(arc
					(start 264.79881 -289.7378)
					(mid 264.80253 -289.72882)
					(end 264.81151 -289.7251)
				)
				(arc
					(start 266.28471 -289.7251)
					(mid 266.29369 -289.72882)
					(end 266.29741 -289.7378)
				)
			)
		)
	)
	(zone
		(layer "In1.Cu")
		(hatch none 0.5)
		(connect_pads
			(clearance 0)
		)
		(min_thickness 0.25)
		(keepout
			(tracks not_allowed)
			(vias allowed)
			(pads allowed)
			(copperpour not_allowed)
			(footprints allowed)
		)
		(placement
			(enabled no)
			(sheetname "")
		)
		(fill
			(thermal_gap 0.5)
			(thermal_bridge_width 0.5)
			(island_removal_mode 0)
		)
		(polygon
			(pts
				(arc
					(start 135.555228 -12.952984)
					(mid 135.577546 -12.899102)
					(end 135.631428 -12.876784)
				)
				(arc
					(start 136.459976 -12.876784)
					(mid 136.513858 -12.899102)
					(end 136.536176 -12.952984)
				)
				(arc
					(start 136.536176 -14.248384)
					(mid 136.513858 -14.302266)
					(end 136.459976 -14.324584)
				)
				(arc
					(start 135.631428 -14.324584)
					(mid 135.577546 -14.302266)
					(end 135.555228 -14.248384)
				)
			)
		)
	)
	(zone
		(layer "In1.Cu")
		(hatch none 0.5)
		(connect_pads
			(clearance 0)
		)
		(min_thickness 0.25)
		(keepout
			(tracks not_allowed)
			(vias allowed)
			(pads allowed)
			(copperpour not_allowed)
			(footprints allowed)
		)
		(placement
			(enabled no)
			(sheetname "")
		)
		(fill
			(thermal_gap 0.5)
			(thermal_bridge_width 0.5)
			(island_removal_mode 0)
		)
		(polygon
			(pts
				(arc
					(start 273.841464 -239.232186)
					(mid 273.837744 -239.241166)
					(end 273.828764 -239.244886)
				)
				(arc
					(start 272.355564 -239.244886)
					(mid 272.346584 -239.241166)
					(end 272.342864 -239.232186)
				)
				(arc
					(start 272.342864 -238.737648)
					(mid 272.346584 -238.728668)
					(end 272.355564 -238.724948)
				)
				(arc
					(start 273.828764 -238.724948)
					(mid 273.837744 -238.728668)
					(end 273.841464 -238.737648)
				)
			)
		)
	)
	(zone
		(layer "In1.Cu")
		(hatch none 0.5)
		(connect_pads
			(clearance 0)
		)
		(min_thickness 0.25)
		(keepout
			(tracks not_allowed)
			(vias allowed)
			(pads allowed)
			(copperpour not_allowed)
			(footprints allowed)
		)
		(placement
			(enabled no)
			(sheetname "")
		)
		(fill
			(thermal_gap 0.5)
			(thermal_bridge_width 0.5)
			(island_removal_mode 0)
		)
		(polygon
			(pts
				(arc
					(start 281.385264 -223.082104)
					(mid 281.381544 -223.091084)
					(end 281.372564 -223.094804)
				)
				(arc
					(start 279.899364 -223.094804)
					(mid 279.890384 -223.091084)
					(end 279.886664 -223.082104)
				)
				(arc
					(start 279.886664 -222.587566)
					(mid 279.890384 -222.578586)
					(end 279.899364 -222.574866)
				)
				(arc
					(start 281.372564 -222.574866)
					(mid 281.381544 -222.578586)
					(end 281.385264 -222.587566)
				)
			)
		)
	)
	(zone
		(layer "In1.Cu")
		(hatch none 0.5)
		(connect_pads
			(clearance 0)
		)
		(min_thickness 0.25)
		(keepout
			(tracks not_allowed)
			(vias allowed)
			(pads allowed)
			(copperpour not_allowed)
			(footprints allowed)
		)
		(placement
			(enabled no)
			(sheetname "")
		)
		(fill
			(thermal_gap 0.5)
			(thermal_bridge_width 0.5)
			(island_removal_mode 0)
		)
		(polygon
			(pts
				(arc
					(start 180.265324 -250.282456)
					(mid 180.261604 -250.291436)
					(end 180.252624 -250.295156)
				)
				(arc
					(start 178.779424 -250.295156)
					(mid 178.770444 -250.291436)
					(end 178.766724 -250.282456)
				)
				(arc
					(start 178.766724 -249.787918)
					(mid 178.770444 -249.778938)
					(end 178.779424 -249.775218)
				)
				(arc
					(start 180.252624 -249.775218)
					(mid 180.261604 -249.778938)
					(end 180.265324 -249.787918)
				)
			)
		)
	)
	(zone
		(layer "In1.Cu")
		(hatch none 0.5)
		(connect_pads
			(clearance 0)
		)
		(min_thickness 0.25)
		(keepout
			(tracks not_allowed)
			(vias allowed)
			(pads allowed)
			(copperpour not_allowed)
			(footprints allowed)
		)
		(placement
			(enabled no)
			(sheetname "")
		)
		(fill
			(thermal_gap 0.5)
			(thermal_bridge_width 0.5)
			(island_removal_mode 0)
		)
		(polygon
			(pts
				(arc
					(start 266.29741 -296.182288)
					(mid 266.29369 -296.191268)
					(end 266.28471 -296.194988)
				)
				(arc
					(start 264.81151 -296.194988)
					(mid 264.80253 -296.191268)
					(end 264.79881 -296.182288)
				)
				(arc
					(start 264.79881 -295.68775)
					(mid 264.80253 -295.67877)
					(end 264.81151 -295.67505)
				)
				(arc
					(start 266.28471 -295.67505)
					(mid 266.29369 -295.67877)
					(end 266.29741 -295.68775)
				)
			)
		)
	)
	(zone
		(layer "In1.Cu")
		(hatch none 0.5)
		(connect_pads
			(clearance 0)
		)
		(min_thickness 0.25)
		(keepout
			(tracks not_allowed)
			(vias allowed)
			(pads allowed)
			(copperpour not_allowed)
			(footprints allowed)
		)
		(placement
			(enabled no)
			(sheetname "")
		)
		(fill
			(thermal_gap 0.5)
			(thermal_bridge_width 0.5)
			(island_removal_mode 0)
		)
		(polygon
			(pts
				(arc
					(start 454.937368 -199.282304)
					(mid 454.933648 -199.291284)
					(end 454.924668 -199.295004)
				)
				(arc
					(start 453.451468 -199.295004)
					(mid 453.442488 -199.291284)
					(end 453.438768 -199.282304)
				)
				(arc
					(start 453.438768 -198.787766)
					(mid 453.442488 -198.778786)
					(end 453.451468 -198.775066)
				)
				(arc
					(start 454.924668 -198.775066)
					(mid 454.933648 -198.778786)
					(end 454.937368 -198.787766)
				)
			)
		)
	)
	(zone
		(layer "In1.Cu")
		(hatch none 0.5)
		(connect_pads
			(clearance 0)
		)
		(min_thickness 0.25)
		(keepout
			(tracks not_allowed)
			(vias allowed)
			(pads allowed)
			(copperpour not_allowed)
			(footprints allowed)
		)
		(placement
			(enabled no)
			(sheetname "")
		)
		(fill
			(thermal_gap 0.5)
			(thermal_bridge_width 0.5)
			(island_removal_mode 0)
		)
		(polygon
			(pts
				(arc
					(start 293.029386 -233.282236)
					(mid 293.025666 -233.291216)
					(end 293.016686 -233.294936)
				)
				(arc
					(start 291.543486 -233.294936)
					(mid 291.534506 -233.291216)
					(end 291.530786 -233.282236)
				)
				(arc
					(start 291.530786 -232.787698)
					(mid 291.534506 -232.778718)
					(end 291.543486 -232.774998)
				)
				(arc
					(start 293.016686 -232.774998)
					(mid 293.025666 -232.778718)
					(end 293.029386 -232.787698)
				)
			)
		)
	)
	(zone
		(layer "In1.Cu")
		(hatch none 0.5)
		(connect_pads
			(clearance 0)
		)
		(min_thickness 0.25)
		(keepout
			(tracks not_allowed)
			(vias allowed)
			(pads allowed)
			(copperpour not_allowed)
			(footprints allowed)
		)
		(placement
			(enabled no)
			(sheetname "")
		)
		(fill
			(thermal_gap 0.5)
			(thermal_bridge_width 0.5)
			(island_removal_mode 0)
		)
		(polygon
			(pts
				(arc
					(start 22.45741 -289.382454)
					(mid 22.45369 -289.391434)
					(end 22.44471 -289.395154)
				)
				(arc
					(start 20.97151 -289.395154)
					(mid 20.96253 -289.391434)
					(end 20.95881 -289.382454)
				)
				(arc
					(start 20.95881 -288.887916)
					(mid 20.96253 -288.878936)
					(end 20.97151 -288.875216)
				)
				(arc
					(start 22.44471 -288.875216)
					(mid 22.45369 -288.878936)
					(end 22.45741 -288.887916)
				)
			)
		)
	)
	(zone
		(layer "In1.Cu")
		(hatch none 0.5)
		(connect_pads
			(clearance 0)
		)
		(min_thickness 0.25)
		(keepout
			(tracks not_allowed)
			(vias allowed)
			(pads allowed)
			(copperpour not_allowed)
			(footprints allowed)
		)
		(placement
			(enabled no)
			(sheetname "")
		)
		(fill
			(thermal_gap 0.5)
			(thermal_bridge_width 0.5)
			(island_removal_mode 0)
		)
		(polygon
			(pts
				(arc
					(start 450.8373 -239.232186)
					(mid 450.83358 -239.241166)
					(end 450.8246 -239.244886)
				)
				(arc
					(start 449.3514 -239.244886)
					(mid 449.34242 -239.241166)
					(end 449.3387 -239.232186)
				)
				(arc
					(start 449.3387 -238.737648)
					(mid 449.34242 -238.728668)
					(end 449.3514 -238.724948)
				)
				(arc
					(start 450.8246 -238.724948)
					(mid 450.83358 -238.728668)
					(end 450.8373 -238.737648)
				)
			)
		)
	)
	(zone
		(layer "In1.Cu")
		(hatch none 0.5)
		(connect_pads
			(clearance 0)
		)
		(min_thickness 0.25)
		(keepout
			(tracks not_allowed)
			(vias allowed)
			(pads allowed)
			(copperpour not_allowed)
			(footprints allowed)
		)
		(placement
			(enabled no)
			(sheetname "")
		)
		(fill
			(thermal_gap 0.5)
			(thermal_bridge_width 0.5)
			(island_removal_mode 0)
		)
		(polygon
			(pts
				(arc
					(start 60.177426 -236.682534)
					(mid 60.173706 -236.691514)
					(end 60.164726 -236.695234)
				)
				(arc
					(start 58.691526 -236.695234)
					(mid 58.682546 -236.691514)
					(end 58.678826 -236.682534)
				)
				(arc
					(start 58.678826 -236.187996)
					(mid 58.682546 -236.179016)
					(end 58.691526 -236.175296)
				)
				(arc
					(start 60.164726 -236.175296)
					(mid 60.173706 -236.179016)
					(end 60.177426 -236.187996)
				)
			)
		)
	)
	(zone
		(layer "In1.Cu")
		(hatch none 0.5)
		(connect_pads
			(clearance 0)
		)
		(min_thickness 0.25)
		(keepout
			(tracks not_allowed)
			(vias allowed)
			(pads allowed)
			(copperpour not_allowed)
			(footprints allowed)
		)
		(placement
			(enabled no)
			(sheetname "")
		)
		(fill
			(thermal_gap 0.5)
			(thermal_bridge_width 0.5)
			(island_removal_mode 0)
		)
		(polygon
			(pts
				(arc
					(start 265.87831 -246.635016)
					(mid 265.21791 -246.635016)
					(end 265.87831 -246.635016)
				)
			)
		)
	)
	(zone
		(layer "In1.Cu")
		(hatch none 0.5)
		(connect_pads
			(clearance 0)
		)
		(min_thickness 0.25)
		(keepout
			(tracks not_allowed)
			(vias allowed)
			(pads allowed)
			(copperpour not_allowed)
			(footprints allowed)
		)
		(placement
			(enabled no)
			(sheetname "")
		)
		(fill
			(thermal_gap 0.5)
			(thermal_bridge_width 0.5)
			(island_removal_mode 0)
		)
		(polygon
			(pts
				(arc
					(start 45.089318 -280.03246)
					(mid 45.085598 -280.04144)
					(end 45.076618 -280.04516)
				)
				(arc
					(start 43.603418 -280.04516)
					(mid 43.594438 -280.04144)
					(end 43.590718 -280.03246)
				)
				(arc
					(start 43.590718 -279.537922)
					(mid 43.594438 -279.528942)
					(end 43.603418 -279.525222)
				)
				(arc
					(start 45.076618 -279.525222)
					(mid 45.085598 -279.528942)
					(end 45.089318 -279.537922)
				)
			)
		)
	)
	(zone
		(layer "In1.Cu")
		(hatch none 0.5)
		(connect_pads
			(clearance 0)
		)
		(min_thickness 0.25)
		(keepout
			(tracks not_allowed)
			(vias allowed)
			(pads allowed)
			(copperpour not_allowed)
			(footprints allowed)
		)
		(placement
			(enabled no)
			(sheetname "")
		)
		(fill
			(thermal_gap 0.5)
			(thermal_bridge_width 0.5)
			(island_removal_mode 0)
		)
		(polygon
			(pts
				(arc
					(start 281.385264 -274.93214)
					(mid 281.381544 -274.94112)
					(end 281.372564 -274.94484)
				)
				(arc
					(start 279.899364 -274.94484)
					(mid 279.890384 -274.94112)
					(end 279.886664 -274.93214)
				)
				(arc
					(start 279.886664 -274.437602)
					(mid 279.890384 -274.428622)
					(end 279.899364 -274.424902)
				)
				(arc
					(start 281.372564 -274.424902)
					(mid 281.381544 -274.428622)
					(end 281.385264 -274.437602)
				)
			)
		)
	)
	(zone
		(layer "In1.Cu")
		(hatch none 0.5)
		(connect_pads
			(clearance 0)
		)
		(min_thickness 0.25)
		(keepout
			(tracks not_allowed)
			(vias allowed)
			(pads allowed)
			(copperpour not_allowed)
			(footprints allowed)
		)
		(placement
			(enabled no)
			(sheetname "")
		)
		(fill
			(thermal_gap 0.5)
			(thermal_bridge_width 0.5)
			(island_removal_mode 0)
		)
		(polygon
			(pts
				(arc
					(start 266.29741 -288.532316)
					(mid 266.29369 -288.541296)
					(end 266.28471 -288.545016)
				)
				(arc
					(start 264.81151 -288.545016)
					(mid 264.80253 -288.541296)
					(end 264.79881 -288.532316)
				)
				(arc
					(start 264.79881 -288.037778)
					(mid 264.80253 -288.028798)
					(end 264.81151 -288.025078)
				)
				(arc
					(start 266.28471 -288.025078)
					(mid 266.29369 -288.028798)
					(end 266.29741 -288.037778)
				)
			)
		)
	)
	(zone
		(layer "In1.Cu")
		(hatch none 0.5)
		(connect_pads
			(clearance 0)
		)
		(min_thickness 0.25)
		(keepout
			(tracks not_allowed)
			(vias allowed)
			(pads allowed)
			(copperpour not_allowed)
			(footprints allowed)
		)
		(placement
			(enabled no)
			(sheetname "")
		)
		(fill
			(thermal_gap 0.5)
			(thermal_bridge_width 0.5)
			(island_removal_mode 0)
		)
		(polygon
			(pts
				(arc
					(start 99.861116 -294.031416)
					(mid 99.556316 -294.336216)
					(end 99.861116 -294.641016)
				)
				(arc
					(start 100.80117 -294.641016)
					(mid 101.10597 -294.336216)
					(end 100.80117 -294.031416)
				)
			)
		)
	)
	(zone
		(layer "In1.Cu")
		(hatch none 0.5)
		(connect_pads
			(clearance 0)
		)
		(min_thickness 0.25)
		(keepout
			(tracks not_allowed)
			(vias allowed)
			(pads allowed)
			(copperpour not_allowed)
			(footprints allowed)
		)
		(placement
			(enabled no)
			(sheetname "")
		)
		(fill
			(thermal_gap 0.5)
			(thermal_bridge_width 0.5)
			(island_removal_mode 0)
		)
		(polygon
			(pts
				(arc
					(start 285.485332 -261.332218)
					(mid 285.481612 -261.341198)
					(end 285.472632 -261.344918)
				)
				(arc
					(start 283.999432 -261.344918)
					(mid 283.990452 -261.341198)
					(end 283.986732 -261.332218)
				)
				(arc
					(start 283.986732 -260.83768)
					(mid 283.990452 -260.8287)
					(end 283.999432 -260.82498)
				)
				(arc
					(start 285.472632 -260.82498)
					(mid 285.481612 -260.8287)
					(end 285.485332 -260.83768)
				)
			)
		)
	)
	(zone
		(layer "In1.Cu")
		(hatch none 0.5)
		(connect_pads
			(clearance 0)
		)
		(min_thickness 0.25)
		(keepout
			(tracks not_allowed)
			(vias allowed)
			(pads allowed)
			(copperpour not_allowed)
			(footprints allowed)
		)
		(placement
			(enabled no)
			(sheetname "")
		)
		(fill
			(thermal_gap 0.5)
			(thermal_bridge_width 0.5)
			(island_removal_mode 0)
		)
		(polygon
			(pts
				(arc
					(start 155.88869 -389.467344)
					(mid 155.50769 -389.467344)
					(end 155.88869 -389.467344)
				)
			)
		)
	)
	(zone
		(layer "In1.Cu")
		(hatch none 0.5)
		(connect_pads
			(clearance 0)
		)
		(min_thickness 0.25)
		(keepout
			(tracks not_allowed)
			(vias allowed)
			(pads allowed)
			(copperpour not_allowed)
			(footprints allowed)
		)
		(placement
			(enabled no)
			(sheetname "")
		)
		(fill
			(thermal_gap 0.5)
			(thermal_bridge_width 0.5)
			(island_removal_mode 0)
		)
		(polygon
			(pts
				(arc
					(start 350.788478 -394.385292)
					(mid 350.407478 -394.385292)
					(end 350.788478 -394.385292)
				)
			)
		)
	)
	(zone
		(layer "In1.Cu")
		(hatch none 0.5)
		(connect_pads
			(clearance 0)
		)
		(min_thickness 0.25)
		(keepout
			(tracks not_allowed)
			(vias allowed)
			(pads allowed)
			(copperpour not_allowed)
			(footprints allowed)
		)
		(placement
			(enabled no)
			(sheetname "")
		)
		(fill
			(thermal_gap 0.5)
			(thermal_bridge_width 0.5)
			(island_removal_mode 0)
		)
		(polygon
			(pts
				(arc
					(start 277.941532 -222.23222)
					(mid 277.937812 -222.2412)
					(end 277.928832 -222.24492)
				)
				(arc
					(start 276.455632 -222.24492)
					(mid 276.446652 -222.2412)
					(end 276.442932 -222.23222)
				)
				(arc
					(start 276.442932 -221.737682)
					(mid 276.446652 -221.728702)
					(end 276.455632 -221.724982)
				)
				(arc
					(start 277.928832 -221.724982)
					(mid 277.937812 -221.728702)
					(end 277.941532 -221.737682)
				)
			)
		)
	)
	(zone
		(layer "In1.Cu")
		(hatch none 0.5)
		(connect_pads
			(clearance 0)
		)
		(min_thickness 0.25)
		(keepout
			(tracks not_allowed)
			(vias allowed)
			(pads allowed)
			(copperpour not_allowed)
			(footprints allowed)
		)
		(placement
			(enabled no)
			(sheetname "")
		)
		(fill
			(thermal_gap 0.5)
			(thermal_bridge_width 0.5)
			(island_removal_mode 0)
		)
		(polygon
			(pts
				(arc
					(start 163.418774 -383.440686)
					(mid 163.545774 -383.567686)
					(end 163.672774 -383.440686)
				)
				(arc
					(start 163.672774 -383.364486)
					(mid 163.545774 -383.237486)
					(end 163.418774 -383.364486)
				)
			)
		)
	)
	(zone
		(layer "In1.Cu")
		(hatch none 0.5)
		(connect_pads
			(clearance 0)
		)
		(min_thickness 0.25)
		(keepout
			(tracks not_allowed)
			(vias allowed)
			(pads allowed)
			(copperpour not_allowed)
			(footprints allowed)
		)
		(placement
			(enabled no)
			(sheetname "")
		)
		(fill
			(thermal_gap 0.5)
			(thermal_bridge_width 0.5)
			(island_removal_mode 0)
		)
		(polygon
			(pts
				(arc
					(start 30.001464 -294.48252)
					(mid 29.997744 -294.4915)
					(end 29.988764 -294.49522)
				)
				(arc
					(start 28.515564 -294.49522)
					(mid 28.506584 -294.4915)
					(end 28.502864 -294.48252)
				)
				(arc
					(start 28.502864 -293.987982)
					(mid 28.506584 -293.979002)
					(end 28.515564 -293.975282)
				)
				(arc
					(start 29.988764 -293.975282)
					(mid 29.997744 -293.979002)
					(end 30.001464 -293.987982)
				)
			)
		)
	)
	(zone
		(layer "In1.Cu")
		(hatch none 0.5)
		(connect_pads
			(clearance 0)
		)
		(min_thickness 0.25)
		(keepout
			(tracks not_allowed)
			(vias allowed)
			(pads allowed)
			(copperpour not_allowed)
			(footprints allowed)
		)
		(placement
			(enabled no)
			(sheetname "")
		)
		(fill
			(thermal_gap 0.5)
			(thermal_bridge_width 0.5)
			(island_removal_mode 0)
		)
		(polygon
			(pts
				(arc
					(start 125.361192 -385.31038)
					(mid 124.980192 -385.31038)
					(end 125.361192 -385.31038)
				)
			)
		)
	)
	(zone
		(layer "In1.Cu")
		(hatch none 0.5)
		(connect_pads
			(clearance 0)
		)
		(min_thickness 0.25)
		(keepout
			(tracks not_allowed)
			(vias allowed)
			(pads allowed)
			(copperpour not_allowed)
			(footprints allowed)
		)
		(placement
			(enabled no)
			(sheetname "")
		)
		(fill
			(thermal_gap 0.5)
			(thermal_bridge_width 0.5)
			(island_removal_mode 0)
		)
		(polygon
			(pts
				(arc
					(start 409.089098 -397.156432)
					(mid 408.708098 -397.156432)
					(end 409.089098 -397.156432)
				)
			)
		)
	)
	(zone
		(layer "In1.Cu")
		(hatch none 0.5)
		(connect_pads
			(clearance 0)
		)
		(min_thickness 0.25)
		(keepout
			(tracks not_allowed)
			(vias allowed)
			(pads allowed)
			(copperpour not_allowed)
			(footprints allowed)
		)
		(placement
			(enabled no)
			(sheetname "")
		)
		(fill
			(thermal_gap 0.5)
			(thermal_bridge_width 0.5)
			(island_removal_mode 0)
		)
		(polygon
			(pts
				(arc
					(start 382.670304 -399.143474)
					(mid 382.365504 -399.143474)
					(end 382.670304 -399.143474)
				)
			)
		)
	)
	(zone
		(layer "In1.Cu")
		(hatch none 0.5)
		(connect_pads
			(clearance 0)
		)
		(min_thickness 0.25)
		(keepout
			(tracks not_allowed)
			(vias allowed)
			(pads allowed)
			(copperpour not_allowed)
			(footprints allowed)
		)
		(placement
			(enabled no)
			(sheetname "")
		)
		(fill
			(thermal_gap 0.5)
			(thermal_bridge_width 0.5)
			(island_removal_mode 0)
		)
		(polygon
			(pts
				(arc
					(start 293.029386 -285.132272)
					(mid 293.025666 -285.141252)
					(end 293.016686 -285.144972)
				)
				(arc
					(start 291.543486 -285.144972)
					(mid 291.534506 -285.141252)
					(end 291.530786 -285.132272)
				)
				(arc
					(start 291.530786 -284.637734)
					(mid 291.534506 -284.628754)
					(end 291.543486 -284.625034)
				)
				(arc
					(start 293.016686 -284.625034)
					(mid 293.025666 -284.628754)
					(end 293.029386 -284.637734)
				)
			)
		)
	)
	(zone
		(layer "In1.Cu")
		(hatch none 0.5)
		(connect_pads
			(clearance 0)
		)
		(min_thickness 0.25)
		(keepout
			(tracks not_allowed)
			(vias allowed)
			(pads allowed)
			(copperpour not_allowed)
			(footprints allowed)
		)
		(placement
			(enabled no)
			(sheetname "")
		)
		(fill
			(thermal_gap 0.5)
			(thermal_bridge_width 0.5)
			(island_removal_mode 0)
		)
		(polygon
			(pts
				(arc
					(start 380.561088 -394.385292)
					(mid 380.180088 -394.385292)
					(end 380.561088 -394.385292)
				)
			)
		)
	)
	(zone
		(layer "In1.Cu")
		(hatch none 0.5)
		(connect_pads
			(clearance 0)
		)
		(min_thickness 0.25)
		(keepout
			(tracks not_allowed)
			(vias allowed)
			(pads allowed)
			(copperpour not_allowed)
			(footprints allowed)
		)
		(placement
			(enabled no)
			(sheetname "")
		)
		(fill
			(thermal_gap 0.5)
			(thermal_bridge_width 0.5)
			(island_removal_mode 0)
		)
		(polygon
			(pts
				(arc
					(start 454.937368 -229.882192)
					(mid 454.933648 -229.891172)
					(end 454.924668 -229.894892)
				)
				(arc
					(start 453.451468 -229.894892)
					(mid 453.442488 -229.891172)
					(end 453.438768 -229.882192)
				)
				(arc
					(start 453.438768 -229.387654)
					(mid 453.442488 -229.378674)
					(end 453.451468 -229.374954)
				)
				(arc
					(start 454.924668 -229.374954)
					(mid 454.933648 -229.378674)
					(end 454.937368 -229.387654)
				)
			)
		)
	)
	(zone
		(layer "In1.Cu")
		(hatch none 0.5)
		(connect_pads
			(clearance 0)
		)
		(min_thickness 0.25)
		(keepout
			(tracks not_allowed)
			(vias allowed)
			(pads allowed)
			(copperpour not_allowed)
			(footprints allowed)
		)
		(placement
			(enabled no)
			(sheetname "")
		)
		(fill
			(thermal_gap 0.5)
			(thermal_bridge_width 0.5)
			(island_removal_mode 0)
		)
		(polygon
			(pts
				(arc
					(start 277.941532 -272.382234)
					(mid 277.937812 -272.391214)
					(end 277.928832 -272.394934)
				)
				(arc
					(start 276.455632 -272.394934)
					(mid 276.446652 -272.391214)
					(end 276.442932 -272.382234)
				)
				(arc
					(start 276.442932 -271.887696)
					(mid 276.446652 -271.878716)
					(end 276.455632 -271.874996)
				)
				(arc
					(start 277.928832 -271.874996)
					(mid 277.937812 -271.878716)
					(end 277.941532 -271.887696)
				)
			)
		)
	)
	(zone
		(layer "In1.Cu")
		(hatch none 0.5)
		(connect_pads
			(clearance 0)
		)
		(min_thickness 0.25)
		(keepout
			(tracks not_allowed)
			(vias allowed)
			(pads allowed)
			(copperpour not_allowed)
			(footprints allowed)
		)
		(placement
			(enabled no)
			(sheetname "")
		)
		(fill
			(thermal_gap 0.5)
			(thermal_bridge_width 0.5)
			(island_removal_mode 0)
		)
		(polygon
			(pts
				(arc
					(start 30.001464 -246.032528)
					(mid 29.997744 -246.041508)
					(end 29.988764 -246.045228)
				)
				(arc
					(start 28.515564 -246.045228)
					(mid 28.506584 -246.041508)
					(end 28.502864 -246.032528)
				)
				(arc
					(start 28.502864 -245.53799)
					(mid 28.506584 -245.52901)
					(end 28.515564 -245.52529)
				)
				(arc
					(start 29.988764 -245.52529)
					(mid 29.997744 -245.52901)
					(end 30.001464 -245.53799)
				)
			)
		)
	)
	(zone
		(layer "In1.Cu")
		(hatch none 0.5)
		(connect_pads
			(clearance 0)
		)
		(min_thickness 0.25)
		(keepout
			(tracks not_allowed)
			(vias allowed)
			(pads allowed)
			(copperpour not_allowed)
			(footprints allowed)
		)
		(placement
			(enabled no)
			(sheetname "")
		)
		(fill
			(thermal_gap 0.5)
			(thermal_bridge_width 0.5)
			(island_removal_mode 0)
		)
		(polygon
			(pts
				(arc
					(start 296.473372 -314.882276)
					(mid 296.469652 -314.891256)
					(end 296.460672 -314.894976)
				)
				(arc
					(start 294.987472 -314.894976)
					(mid 294.978492 -314.891256)
					(end 294.974772 -314.882276)
				)
				(arc
					(start 294.974772 -314.387738)
					(mid 294.978492 -314.378758)
					(end 294.987472 -314.375038)
				)
				(arc
					(start 296.460672 -314.375038)
					(mid 296.469652 -314.378758)
					(end 296.473372 -314.387738)
				)
			)
		)
	)
	(zone
		(layer "In1.Cu")
		(hatch none 0.5)
		(connect_pads
			(clearance 0)
		)
		(min_thickness 0.25)
		(keepout
			(tracks not_allowed)
			(vias allowed)
			(pads allowed)
			(copperpour not_allowed)
			(footprints allowed)
		)
		(placement
			(enabled no)
			(sheetname "")
		)
		(fill
			(thermal_gap 0.5)
			(thermal_bridge_width 0.5)
			(island_removal_mode 0)
		)
		(polygon
			(pts
				(arc
					(start 432.30546 -217.982292)
					(mid 432.30174 -217.991272)
					(end 432.29276 -217.994992)
				)
				(arc
					(start 430.81956 -217.994992)
					(mid 430.81058 -217.991272)
					(end 430.80686 -217.982292)
				)
				(arc
					(start 430.80686 -217.487754)
					(mid 430.81058 -217.478774)
					(end 430.81956 -217.475054)
				)
				(arc
					(start 432.29276 -217.475054)
					(mid 432.30174 -217.478774)
					(end 432.30546 -217.487754)
				)
			)
		)
	)
	(zone
		(layer "In1.Cu")
		(hatch none 0.5)
		(connect_pads
			(clearance 0)
		)
		(min_thickness 0.25)
		(keepout
			(tracks not_allowed)
			(vias allowed)
			(pads allowed)
			(copperpour not_allowed)
			(footprints allowed)
		)
		(placement
			(enabled no)
			(sheetname "")
		)
		(fill
			(thermal_gap 0.5)
			(thermal_bridge_width 0.5)
			(island_removal_mode 0)
		)
		(polygon
			(pts
				(arc
					(start 308.117494 -283.43225)
					(mid 308.113774 -283.44123)
					(end 308.104794 -283.44495)
				)
				(arc
					(start 306.631594 -283.44495)
					(mid 306.622614 -283.44123)
					(end 306.618894 -283.43225)
				)
				(arc
					(start 306.618894 -282.937712)
					(mid 306.622614 -282.928732)
					(end 306.631594 -282.925012)
				)
				(arc
					(start 308.104794 -282.925012)
					(mid 308.113774 -282.928732)
					(end 308.117494 -282.937712)
				)
			)
		)
	)
	(zone
		(layer "In1.Cu")
		(hatch none 0.5)
		(connect_pads
			(clearance 0)
		)
		(min_thickness 0.25)
		(keepout
			(tracks not_allowed)
			(vias allowed)
			(pads allowed)
			(copperpour not_allowed)
			(footprints allowed)
		)
		(placement
			(enabled no)
			(sheetname "")
		)
		(fill
			(thermal_gap 0.5)
			(thermal_bridge_width 0.5)
			(island_removal_mode 0)
		)
		(polygon
			(pts
				(arc
					(start 432.30546 -300.432216)
					(mid 432.30174 -300.441196)
					(end 432.29276 -300.444916)
				)
				(arc
					(start 430.81956 -300.444916)
					(mid 430.81058 -300.441196)
					(end 430.80686 -300.432216)
				)
				(arc
					(start 430.80686 -299.937678)
					(mid 430.81058 -299.928698)
					(end 430.81956 -299.924978)
				)
				(arc
					(start 432.29276 -299.924978)
					(mid 432.30174 -299.928698)
					(end 432.30546 -299.937678)
				)
			)
		)
	)
	(zone
		(layer "In1.Cu")
		(hatch none 0.5)
		(connect_pads
			(clearance 0)
		)
		(min_thickness 0.25)
		(keepout
			(tracks not_allowed)
			(vias allowed)
			(pads allowed)
			(copperpour not_allowed)
			(footprints allowed)
		)
		(placement
			(enabled no)
			(sheetname "")
		)
		(fill
			(thermal_gap 0.5)
			(thermal_bridge_width 0.5)
			(island_removal_mode 0)
		)
		(polygon
			(pts
				(arc
					(start 293.029386 -302.132238)
					(mid 293.025666 -302.141218)
					(end 293.016686 -302.144938)
				)
				(arc
					(start 291.543486 -302.144938)
					(mid 291.534506 -302.141218)
					(end 291.530786 -302.132238)
				)
				(arc
					(start 291.530786 -301.6377)
					(mid 291.534506 -301.62872)
					(end 291.543486 -301.625)
				)
				(arc
					(start 293.016686 -301.625)
					(mid 293.025666 -301.62872)
					(end 293.029386 -301.6377)
				)
			)
		)
	)
	(zone
		(layer "In1.Cu")
		(hatch none 0.5)
		(connect_pads
			(clearance 0)
		)
		(min_thickness 0.25)
		(keepout
			(tracks not_allowed)
			(vias allowed)
			(pads allowed)
			(copperpour not_allowed)
			(footprints allowed)
		)
		(placement
			(enabled no)
			(sheetname "")
		)
		(fill
			(thermal_gap 0.5)
			(thermal_bridge_width 0.5)
			(island_removal_mode 0)
		)
		(polygon
			(pts
				(arc
					(start 52.633372 -251.13234)
					(mid 52.629652 -251.14132)
					(end 52.620672 -251.14504)
				)
				(arc
					(start 51.147472 -251.14504)
					(mid 51.138492 -251.14132)
					(end 51.134772 -251.13234)
				)
				(arc
					(start 51.134772 -250.637802)
					(mid 51.138492 -250.628822)
					(end 51.147472 -250.625102)
				)
				(arc
					(start 52.620672 -250.625102)
					(mid 52.629652 -250.628822)
					(end 52.633372 -250.637802)
				)
			)
		)
	)
	(zone
		(layer "In1.Cu")
		(hatch none 0.5)
		(connect_pads
			(clearance 0)
		)
		(min_thickness 0.25)
		(keepout
			(tracks not_allowed)
			(vias allowed)
			(pads allowed)
			(copperpour not_allowed)
			(footprints allowed)
		)
		(placement
			(enabled no)
			(sheetname "")
		)
		(fill
			(thermal_gap 0.5)
			(thermal_bridge_width 0.5)
			(island_removal_mode 0)
		)
		(polygon
			(pts
				(arc
					(start 206.9973 -269.832582)
					(mid 206.99358 -269.841562)
					(end 206.9846 -269.845282)
				)
				(arc
					(start 205.5114 -269.845282)
					(mid 205.50242 -269.841562)
					(end 205.4987 -269.832582)
				)
				(arc
					(start 205.4987 -269.338044)
					(mid 205.50242 -269.329064)
					(end 205.5114 -269.325344)
				)
				(arc
					(start 206.9846 -269.325344)
					(mid 206.99358 -269.329064)
					(end 206.9973 -269.338044)
				)
			)
		)
	)
	(zone
		(layer "In1.Cu")
		(hatch none 0.5)
		(connect_pads
			(clearance 0)
		)
		(min_thickness 0.25)
		(keepout
			(tracks not_allowed)
			(vias allowed)
			(pads allowed)
			(copperpour not_allowed)
			(footprints allowed)
		)
		(placement
			(enabled no)
			(sheetname "")
		)
		(fill
			(thermal_gap 0.5)
			(thermal_bridge_width 0.5)
			(island_removal_mode 0)
		)
		(polygon
			(pts
				(arc
					(start 304.017426 -229.882192)
					(mid 304.013706 -229.891172)
					(end 304.004726 -229.894892)
				)
				(arc
					(start 302.531526 -229.894892)
					(mid 302.522546 -229.891172)
					(end 302.518826 -229.882192)
				)
				(arc
					(start 302.518826 -229.387654)
					(mid 302.522546 -229.378674)
					(end 302.531526 -229.374954)
				)
				(arc
					(start 304.004726 -229.374954)
					(mid 304.013706 -229.378674)
					(end 304.017426 -229.387654)
				)
			)
		)
	)
	(zone
		(layer "In1.Cu")
		(hatch none 0.5)
		(connect_pads
			(clearance 0)
		)
		(min_thickness 0.25)
		(keepout
			(tracks not_allowed)
			(vias allowed)
			(pads allowed)
			(copperpour not_allowed)
			(footprints allowed)
		)
		(placement
			(enabled no)
			(sheetname "")
		)
		(fill
			(thermal_gap 0.5)
			(thermal_bridge_width 0.5)
			(island_removal_mode 0)
		)
		(polygon
			(pts
				(arc
					(start 60.177426 -263.032494)
					(mid 60.173706 -263.041474)
					(end 60.164726 -263.045194)
				)
				(arc
					(start 58.691526 -263.045194)
					(mid 58.682546 -263.041474)
					(end 58.678826 -263.032494)
				)
				(arc
					(start 58.678826 -262.537956)
					(mid 58.682546 -262.528976)
					(end 58.691526 -262.525256)
				)
				(arc
					(start 60.164726 -262.525256)
					(mid 60.173706 -262.528976)
					(end 60.177426 -262.537956)
				)
			)
		)
	)
	(zone
		(layer "In1.Cu")
		(hatch none 0.5)
		(connect_pads
			(clearance 0)
		)
		(min_thickness 0.25)
		(keepout
			(tracks not_allowed)
			(vias allowed)
			(pads allowed)
			(copperpour not_allowed)
			(footprints allowed)
		)
		(placement
			(enabled no)
			(sheetname "")
		)
		(fill
			(thermal_gap 0.5)
			(thermal_bridge_width 0.5)
			(island_removal_mode 0)
		)
		(polygon
			(pts
				(arc
					(start 281.385264 -284.282134)
					(mid 281.381544 -284.291114)
					(end 281.372564 -284.294834)
				)
				(arc
					(start 279.899364 -284.294834)
					(mid 279.890384 -284.291114)
					(end 279.886664 -284.282134)
				)
				(arc
					(start 279.886664 -283.787596)
					(mid 279.890384 -283.778616)
					(end 279.899364 -283.774896)
				)
				(arc
					(start 281.372564 -283.774896)
					(mid 281.381544 -283.778616)
					(end 281.385264 -283.787596)
				)
			)
		)
	)
	(zone
		(layer "In1.Cu")
		(hatch none 0.5)
		(connect_pads
			(clearance 0)
		)
		(min_thickness 0.25)
		(keepout
			(tracks not_allowed)
			(vias allowed)
			(pads allowed)
			(copperpour not_allowed)
			(footprints allowed)
		)
		(placement
			(enabled no)
			(sheetname "")
		)
		(fill
			(thermal_gap 0.5)
			(thermal_bridge_width 0.5)
			(island_removal_mode 0)
		)
		(polygon
			(pts
				(arc
					(start 18.357342 -282.582366)
					(mid 18.353622 -282.591346)
					(end 18.344642 -282.595066)
				)
				(arc
					(start 16.871442 -282.595066)
					(mid 16.862462 -282.591346)
					(end 16.858742 -282.582366)
				)
				(arc
					(start 16.858742 -282.087828)
					(mid 16.862462 -282.078848)
					(end 16.871442 -282.075128)
				)
				(arc
					(start 18.344642 -282.075128)
					(mid 18.353622 -282.078848)
					(end 18.357342 -282.087828)
				)
			)
		)
	)
	(zone
		(layer "In1.Cu")
		(hatch none 0.5)
		(connect_pads
			(clearance 0)
		)
		(min_thickness 0.25)
		(keepout
			(tracks not_allowed)
			(vias allowed)
			(pads allowed)
			(copperpour not_allowed)
			(footprints allowed)
		)
		(placement
			(enabled no)
			(sheetname "")
		)
		(fill
			(thermal_gap 0.5)
			(thermal_bridge_width 0.5)
			(island_removal_mode 0)
		)
		(polygon
			(pts
				(arc
					(start 435.749446 -243.482114)
					(mid 435.745726 -243.491094)
					(end 435.736746 -243.494814)
				)
				(arc
					(start 434.263546 -243.494814)
					(mid 434.254566 -243.491094)
					(end 434.250846 -243.482114)
				)
				(arc
					(start 434.250846 -242.987576)
					(mid 434.254566 -242.978596)
					(end 434.263546 -242.974876)
				)
				(arc
					(start 435.736746 -242.974876)
					(mid 435.745726 -242.978596)
					(end 435.749446 -242.987576)
				)
			)
		)
	)
	(zone
		(layer "In1.Cu")
		(hatch none 0.5)
		(connect_pads
			(clearance 0)
		)
		(min_thickness 0.25)
		(keepout
			(tracks not_allowed)
			(vias allowed)
			(pads allowed)
			(copperpour not_allowed)
			(footprints allowed)
		)
		(placement
			(enabled no)
			(sheetname "")
		)
		(fill
			(thermal_gap 0.5)
			(thermal_bridge_width 0.5)
			(island_removal_mode 0)
		)
		(polygon
			(pts
				(arc
					(start 206.5782 -298.485306)
					(mid 205.9178 -298.485306)
					(end 206.5782 -298.485306)
				)
			)
		)
	)
	(zone
		(layer "In1.Cu")
		(hatch none 0.5)
		(connect_pads
			(clearance 0)
		)
		(min_thickness 0.25)
		(keepout
			(tracks not_allowed)
			(vias allowed)
			(pads allowed)
			(copperpour not_allowed)
			(footprints allowed)
		)
		(placement
			(enabled no)
			(sheetname "")
		)
		(fill
			(thermal_gap 0.5)
			(thermal_bridge_width 0.5)
			(island_removal_mode 0)
		)
		(polygon
			(pts
				(arc
					(start 413.117284 -286.832294)
					(mid 413.113564 -286.841274)
					(end 413.104584 -286.844994)
				)
				(arc
					(start 411.631384 -286.844994)
					(mid 411.622404 -286.841274)
					(end 411.618684 -286.832294)
				)
				(arc
					(start 411.618684 -286.337756)
					(mid 411.622404 -286.328776)
					(end 411.631384 -286.325056)
				)
				(arc
					(start 413.104584 -286.325056)
					(mid 413.113564 -286.328776)
					(end 413.117284 -286.337756)
				)
			)
		)
	)
	(zone
		(layer "In1.Cu")
		(hatch none 0.5)
		(connect_pads
			(clearance 0)
		)
		(min_thickness 0.25)
		(keepout
			(tracks not_allowed)
			(vias allowed)
			(pads allowed)
			(copperpour not_allowed)
			(footprints allowed)
		)
		(placement
			(enabled no)
			(sheetname "")
		)
		(fill
			(thermal_gap 0.5)
			(thermal_bridge_width 0.5)
			(island_removal_mode 0)
		)
		(polygon
			(pts
				(arc
					(start 191.909446 -280.03246)
					(mid 191.905726 -280.04144)
					(end 191.896746 -280.04516)
				)
				(arc
					(start 190.423546 -280.04516)
					(mid 190.414566 -280.04144)
					(end 190.410846 -280.03246)
				)
				(arc
					(start 190.410846 -279.537922)
					(mid 190.414566 -279.528942)
					(end 190.423546 -279.525222)
				)
				(arc
					(start 191.896746 -279.525222)
					(mid 191.905726 -279.528942)
					(end 191.909446 -279.537922)
				)
			)
		)
	)
	(zone
		(layer "In1.Cu")
		(hatch none 0.5)
		(connect_pads
			(clearance 0)
		)
		(min_thickness 0.25)
		(keepout
			(tracks not_allowed)
			(vias allowed)
			(pads allowed)
			(copperpour not_allowed)
			(footprints allowed)
		)
		(placement
			(enabled no)
			(sheetname "")
		)
		(fill
			(thermal_gap 0.5)
			(thermal_bridge_width 0.5)
			(island_removal_mode 0)
		)
		(polygon
			(pts
				(arc
					(start 273.841464 -304.682144)
					(mid 273.837744 -304.691124)
					(end 273.828764 -304.694844)
				)
				(arc
					(start 272.355564 -304.694844)
					(mid 272.346584 -304.691124)
					(end 272.342864 -304.682144)
				)
				(arc
					(start 272.342864 -304.187606)
					(mid 272.346584 -304.178626)
					(end 272.355564 -304.174906)
				)
				(arc
					(start 273.828764 -304.174906)
					(mid 273.837744 -304.178626)
					(end 273.841464 -304.187606)
				)
			)
		)
	)
	(zone
		(layer "In1.Cu")
		(hatch none 0.5)
		(connect_pads
			(clearance 0)
		)
		(min_thickness 0.25)
		(keepout
			(tracks not_allowed)
			(vias allowed)
			(pads allowed)
			(copperpour not_allowed)
			(footprints allowed)
		)
		(placement
			(enabled no)
			(sheetname "")
		)
		(fill
			(thermal_gap 0.5)
			(thermal_bridge_width 0.5)
			(island_removal_mode 0)
		)
		(polygon
			(pts
				(arc
					(start 40.98925 -202.682348)
					(mid 40.98553 -202.691328)
					(end 40.97655 -202.695048)
				)
				(arc
					(start 39.50335 -202.695048)
					(mid 39.49437 -202.691328)
					(end 39.49065 -202.682348)
				)
				(arc
					(start 39.49065 -202.18781)
					(mid 39.49437 -202.17883)
					(end 39.50335 -202.17511)
				)
				(arc
					(start 40.97655 -202.17511)
					(mid 40.98553 -202.17883)
					(end 40.98925 -202.18781)
				)
			)
		)
	)
	(zone
		(layer "In1.Cu")
		(hatch none 0.5)
		(connect_pads
			(clearance 0)
		)
		(min_thickness 0.25)
		(keepout
			(tracks not_allowed)
			(vias allowed)
			(pads allowed)
			(copperpour not_allowed)
			(footprints allowed)
		)
		(placement
			(enabled no)
			(sheetname "")
		)
		(fill
			(thermal_gap 0.5)
			(thermal_bridge_width 0.5)
			(island_removal_mode 0)
		)
		(polygon
			(pts
				(arc
					(start 285.485332 -244.332252)
					(mid 285.481612 -244.341232)
					(end 285.472632 -244.344952)
				)
				(arc
					(start 283.999432 -244.344952)
					(mid 283.990452 -244.341232)
					(end 283.986732 -244.332252)
				)
				(arc
					(start 283.986732 -243.837714)
					(mid 283.990452 -243.828734)
					(end 283.999432 -243.825014)
				)
				(arc
					(start 285.472632 -243.825014)
					(mid 285.481612 -243.828734)
					(end 285.485332 -243.837714)
				)
			)
		)
	)
	(zone
		(layer "In1.Cu")
		(hatch none 0.5)
		(connect_pads
			(clearance 0)
		)
		(min_thickness 0.25)
		(keepout
			(tracks not_allowed)
			(vias allowed)
			(pads allowed)
			(copperpour not_allowed)
			(footprints allowed)
		)
		(placement
			(enabled no)
			(sheetname "")
		)
		(fill
			(thermal_gap 0.5)
			(thermal_bridge_width 0.5)
			(island_removal_mode 0)
		)
		(polygon
			(pts
				(arc
					(start 191.909446 -242.632484)
					(mid 191.905726 -242.641464)
					(end 191.896746 -242.645184)
				)
				(arc
					(start 190.423546 -242.645184)
					(mid 190.414566 -242.641464)
					(end 190.410846 -242.632484)
				)
				(arc
					(start 190.410846 -242.137946)
					(mid 190.414566 -242.128966)
					(end 190.423546 -242.125246)
				)
				(arc
					(start 191.896746 -242.125246)
					(mid 191.905726 -242.128966)
					(end 191.909446 -242.137946)
				)
			)
		)
	)
	(zone
		(layer "In1.Cu")
		(hatch none 0.5)
		(connect_pads
			(clearance 0)
		)
		(min_thickness 0.25)
		(keepout
			(tracks not_allowed)
			(vias allowed)
			(pads allowed)
			(copperpour not_allowed)
			(footprints allowed)
		)
		(placement
			(enabled no)
			(sheetname "")
		)
		(fill
			(thermal_gap 0.5)
			(thermal_bridge_width 0.5)
			(island_removal_mode 0)
		)
		(polygon
			(pts
				(arc
					(start 345.588844 -397.156432)
					(mid 345.207844 -397.156432)
					(end 345.588844 -397.156432)
				)
			)
		)
	)
	(zone
		(layer "In1.Cu")
		(hatch none 0.5)
		(connect_pads
			(clearance 0)
		)
		(min_thickness 0.25)
		(keepout
			(tracks not_allowed)
			(vias allowed)
			(pads allowed)
			(copperpour not_allowed)
			(footprints allowed)
		)
		(placement
			(enabled no)
			(sheetname "")
		)
		(fill
			(thermal_gap 0.5)
			(thermal_bridge_width 0.5)
			(island_removal_mode 0)
		)
		(polygon
			(pts
				(arc
					(start 265.87831 -199.885046)
					(mid 265.21791 -199.885046)
					(end 265.87831 -199.885046)
				)
			)
		)
	)
	(zone
		(layer "In1.Cu")
		(hatch none 0.5)
		(connect_pads
			(clearance 0)
		)
		(min_thickness 0.25)
		(keepout
			(tracks not_allowed)
			(vias allowed)
			(pads allowed)
			(copperpour not_allowed)
			(footprints allowed)
		)
		(placement
			(enabled no)
			(sheetname "")
		)
		(fill
			(thermal_gap 0.5)
			(thermal_bridge_width 0.5)
			(island_removal_mode 0)
		)
		(polygon
			(pts
				(arc
					(start 270.397478 -285.132272)
					(mid 270.393758 -285.141252)
					(end 270.384778 -285.144972)
				)
				(arc
					(start 268.911578 -285.144972)
					(mid 268.902598 -285.141252)
					(end 268.898878 -285.132272)
				)
				(arc
					(start 268.898878 -284.637734)
					(mid 268.902598 -284.628754)
					(end 268.911578 -284.625034)
				)
				(arc
					(start 270.384778 -284.625034)
					(mid 270.393758 -284.628754)
					(end 270.397478 -284.637734)
				)
			)
		)
	)
	(zone
		(layer "In1.Cu")
		(hatch none 0.5)
		(connect_pads
			(clearance 0)
		)
		(min_thickness 0.25)
		(keepout
			(tracks not_allowed)
			(vias allowed)
			(pads allowed)
			(copperpour not_allowed)
			(footprints allowed)
		)
		(placement
			(enabled no)
			(sheetname "")
		)
		(fill
			(thermal_gap 0.5)
			(thermal_bridge_width 0.5)
			(island_removal_mode 0)
		)
		(polygon
			(pts
				(arc
					(start 165.177216 -307.232558)
					(mid 165.173496 -307.241538)
					(end 165.164516 -307.245258)
				)
				(arc
					(start 163.691316 -307.245258)
					(mid 163.682336 -307.241538)
					(end 163.678616 -307.232558)
				)
				(arc
					(start 163.678616 -306.73802)
					(mid 163.682336 -306.72904)
					(end 163.691316 -306.72532)
				)
				(arc
					(start 165.164516 -306.72532)
					(mid 165.173496 -306.72904)
					(end 165.177216 -306.73802)
				)
			)
		)
	)
	(zone
		(layer "In1.Cu")
		(hatch none 0.5)
		(connect_pads
			(clearance 0)
		)
		(min_thickness 0.25)
		(keepout
			(tracks not_allowed)
			(vias allowed)
			(pads allowed)
			(copperpour not_allowed)
			(footprints allowed)
		)
		(placement
			(enabled no)
			(sheetname "")
		)
		(fill
			(thermal_gap 0.5)
			(thermal_bridge_width 0.5)
			(island_removal_mode 0)
		)
		(polygon
			(pts
				(arc
					(start 206.9973 -308.082442)
					(mid 206.99358 -308.091422)
					(end 206.9846 -308.095142)
				)
				(arc
					(start 205.5114 -308.095142)
					(mid 205.50242 -308.091422)
					(end 205.4987 -308.082442)
				)
				(arc
					(start 205.4987 -307.587904)
					(mid 205.50242 -307.578924)
					(end 205.5114 -307.575204)
				)
				(arc
					(start 206.9846 -307.575204)
					(mid 206.99358 -307.578924)
					(end 206.9973 -307.587904)
				)
			)
		)
	)
	(zone
		(layer "In1.Cu")
		(hatch none 0.5)
		(connect_pads
			(clearance 0)
		)
		(min_thickness 0.25)
		(keepout
			(tracks not_allowed)
			(vias allowed)
			(pads allowed)
			(copperpour not_allowed)
			(footprints allowed)
		)
		(placement
			(enabled no)
			(sheetname "")
		)
		(fill
			(thermal_gap 0.5)
			(thermal_bridge_width 0.5)
			(island_removal_mode 0)
		)
		(polygon
			(pts
				(arc
					(start 18.357342 -213.732364)
					(mid 18.353622 -213.741344)
					(end 18.344642 -213.745064)
				)
				(arc
					(start 16.871442 -213.745064)
					(mid 16.862462 -213.741344)
					(end 16.858742 -213.732364)
				)
				(arc
					(start 16.858742 -213.237826)
					(mid 16.862462 -213.228846)
					(end 16.871442 -213.225126)
				)
				(arc
					(start 18.344642 -213.225126)
					(mid 18.353622 -213.228846)
					(end 18.357342 -213.237826)
				)
			)
		)
	)
	(zone
		(layer "In1.Cu")
		(hatch none 0.5)
		(connect_pads
			(clearance 0)
		)
		(min_thickness 0.25)
		(keepout
			(tracks not_allowed)
			(vias allowed)
			(pads allowed)
			(copperpour not_allowed)
			(footprints allowed)
		)
		(placement
			(enabled no)
			(sheetname "")
		)
		(fill
			(thermal_gap 0.5)
			(thermal_bridge_width 0.5)
			(island_removal_mode 0)
		)
		(polygon
			(pts
				(arc
					(start 18.357342 -293.632382)
					(mid 18.353622 -293.641362)
					(end 18.344642 -293.645082)
				)
				(arc
					(start 16.871442 -293.645082)
					(mid 16.862462 -293.641362)
					(end 16.858742 -293.632382)
				)
				(arc
					(start 16.858742 -293.137844)
					(mid 16.862462 -293.128864)
					(end 16.871442 -293.125144)
				)
				(arc
					(start 18.344642 -293.125144)
					(mid 18.353622 -293.128864)
					(end 18.357342 -293.137844)
				)
			)
		)
	)
	(zone
		(layer "In1.Cu")
		(hatch none 0.5)
		(connect_pads
			(clearance 0)
		)
		(min_thickness 0.25)
		(keepout
			(tracks not_allowed)
			(vias allowed)
			(pads allowed)
			(copperpour not_allowed)
			(footprints allowed)
		)
		(placement
			(enabled no)
			(sheetname "")
		)
		(fill
			(thermal_gap 0.5)
			(thermal_bridge_width 0.5)
			(island_removal_mode 0)
		)
		(polygon
			(pts
				(arc
					(start 165.177216 -277.482554)
					(mid 165.173496 -277.491534)
					(end 165.164516 -277.495254)
				)
				(arc
					(start 163.691316 -277.495254)
					(mid 163.682336 -277.491534)
					(end 163.678616 -277.482554)
				)
				(arc
					(start 163.678616 -276.988016)
					(mid 163.682336 -276.979036)
					(end 163.691316 -276.975316)
				)
				(arc
					(start 165.164516 -276.975316)
					(mid 165.173496 -276.979036)
					(end 165.177216 -276.988016)
				)
			)
		)
	)
	(zone
		(layer "In1.Cu")
		(hatch none 0.5)
		(connect_pads
			(clearance 0)
		)
		(min_thickness 0.25)
		(keepout
			(tracks not_allowed)
			(vias allowed)
			(pads allowed)
			(copperpour not_allowed)
			(footprints allowed)
		)
		(placement
			(enabled no)
			(sheetname "")
		)
		(fill
			(thermal_gap 0.5)
			(thermal_bridge_width 0.5)
			(island_removal_mode 0)
		)
		(polygon
			(pts
				(arc
					(start 56.590946 -391.319258)
					(mid 56.717946 -391.446258)
					(end 56.844946 -391.319258)
				)
				(arc
					(start 56.844946 -391.243058)
					(mid 56.717946 -391.116058)
					(end 56.590946 -391.243058)
				)
			)
		)
	)
	(zone
		(layer "In1.Cu")
		(hatch none 0.5)
		(connect_pads
			(clearance 0)
		)
		(min_thickness 0.25)
		(keepout
			(tracks not_allowed)
			(vias allowed)
			(pads allowed)
			(copperpour not_allowed)
			(footprints allowed)
		)
		(placement
			(enabled no)
			(sheetname "")
		)
		(fill
			(thermal_gap 0.5)
			(thermal_bridge_width 0.5)
			(island_removal_mode 0)
		)
		(polygon
			(pts
				(arc
					(start 30.001464 -214.582502)
					(mid 29.997744 -214.591482)
					(end 29.988764 -214.595202)
				)
				(arc
					(start 28.515564 -214.595202)
					(mid 28.506584 -214.591482)
					(end 28.502864 -214.582502)
				)
				(arc
					(start 28.502864 -214.087964)
					(mid 28.506584 -214.078984)
					(end 28.515564 -214.075264)
				)
				(arc
					(start 29.988764 -214.075264)
					(mid 29.997744 -214.078984)
					(end 30.001464 -214.087964)
				)
			)
		)
	)
	(zone
		(layer "In1.Cu")
		(hatch none 0.5)
		(connect_pads
			(clearance 0)
		)
		(min_thickness 0.25)
		(keepout
			(tracks not_allowed)
			(vias allowed)
			(pads allowed)
			(copperpour not_allowed)
			(footprints allowed)
		)
		(placement
			(enabled no)
			(sheetname "")
		)
		(fill
			(thermal_gap 0.5)
			(thermal_bridge_width 0.5)
			(island_removal_mode 0)
		)
		(polygon
			(pts
				(arc
					(start 265.87831 -318.035178)
					(mid 265.21791 -318.035178)
					(end 265.87831 -318.035178)
				)
			)
		)
	)
	(zone
		(layer "In1.Cu")
		(hatch none 0.5)
		(connect_pads
			(clearance 0)
		)
		(min_thickness 0.25)
		(keepout
			(tracks not_allowed)
			(vias allowed)
			(pads allowed)
			(copperpour not_allowed)
			(footprints allowed)
		)
		(placement
			(enabled no)
			(sheetname "")
		)
		(fill
			(thermal_gap 0.5)
			(thermal_bridge_width 0.5)
			(island_removal_mode 0)
		)
		(polygon
			(pts
				(arc
					(start 316.661038 -393.69238)
					(mid 316.280038 -393.69238)
					(end 316.661038 -393.69238)
				)
			)
		)
	)
	(zone
		(layer "In1.Cu")
		(hatch none 0.5)
		(connect_pads
			(clearance 0)
		)
		(min_thickness 0.25)
		(keepout
			(tracks not_allowed)
			(vias allowed)
			(pads allowed)
			(copperpour not_allowed)
			(footprints allowed)
		)
		(placement
			(enabled no)
			(sheetname "")
		)
		(fill
			(thermal_gap 0.5)
			(thermal_bridge_width 0.5)
			(island_removal_mode 0)
		)
		(polygon
			(pts
				(arc
					(start 52.633372 -292.782498)
					(mid 52.629652 -292.791478)
					(end 52.620672 -292.795198)
				)
				(arc
					(start 51.147472 -292.795198)
					(mid 51.138492 -292.791478)
					(end 51.134772 -292.782498)
				)
				(arc
					(start 51.134772 -292.28796)
					(mid 51.138492 -292.27898)
					(end 51.147472 -292.27526)
				)
				(arc
					(start 52.620672 -292.27526)
					(mid 52.629652 -292.27898)
					(end 52.633372 -292.28796)
				)
			)
		)
	)
	(zone
		(layer "In1.Cu")
		(hatch none 0.5)
		(connect_pads
			(clearance 0)
		)
		(min_thickness 0.25)
		(keepout
			(tracks not_allowed)
			(vias allowed)
			(pads allowed)
			(copperpour not_allowed)
			(footprints allowed)
		)
		(placement
			(enabled no)
			(sheetname "")
		)
		(fill
			(thermal_gap 0.5)
			(thermal_bridge_width 0.5)
			(island_removal_mode 0)
		)
		(polygon
			(pts
				(arc
					(start 33.445196 -274.932394)
					(mid 33.441476 -274.941374)
					(end 33.432496 -274.945094)
				)
				(arc
					(start 31.959296 -274.945094)
					(mid 31.950316 -274.941374)
					(end 31.946596 -274.932394)
				)
				(arc
					(start 31.946596 -274.437856)
					(mid 31.950316 -274.428876)
					(end 31.959296 -274.425156)
				)
				(arc
					(start 33.432496 -274.425156)
					(mid 33.441476 -274.428876)
					(end 33.445196 -274.437856)
				)
			)
		)
	)
	(zone
		(layer "In1.Cu")
		(hatch none 0.5)
		(connect_pads
			(clearance 0)
		)
		(min_thickness 0.25)
		(keepout
			(tracks not_allowed)
			(vias allowed)
			(pads allowed)
			(copperpour not_allowed)
			(footprints allowed)
		)
		(placement
			(enabled no)
			(sheetname "")
		)
		(fill
			(thermal_gap 0.5)
			(thermal_bridge_width 0.5)
			(island_removal_mode 0)
		)
		(polygon
			(pts
				(arc
					(start 288.929318 -308.932326)
					(mid 288.925598 -308.941306)
					(end 288.916618 -308.945026)
				)
				(arc
					(start 287.443418 -308.945026)
					(mid 287.434438 -308.941306)
					(end 287.430718 -308.932326)
				)
				(arc
					(start 287.430718 -308.437788)
					(mid 287.434438 -308.428808)
					(end 287.443418 -308.425088)
				)
				(arc
					(start 288.916618 -308.425088)
					(mid 288.925598 -308.428808)
					(end 288.929318 -308.437788)
				)
			)
		)
	)
	(zone
		(layer "In1.Cu")
		(hatch none 0.5)
		(connect_pads
			(clearance 0)
		)
		(min_thickness 0.25)
		(keepout
			(tracks not_allowed)
			(vias allowed)
			(pads allowed)
			(copperpour not_allowed)
			(footprints allowed)
		)
		(placement
			(enabled no)
			(sheetname "")
		)
		(fill
			(thermal_gap 0.5)
			(thermal_bridge_width 0.5)
			(island_removal_mode 0)
		)
		(polygon
			(pts
				(arc
					(start 417.217352 -223.932242)
					(mid 417.213632 -223.941222)
					(end 417.204652 -223.944942)
				)
				(arc
					(start 415.731452 -223.944942)
					(mid 415.722472 -223.941222)
					(end 415.718752 -223.932242)
				)
				(arc
					(start 415.718752 -223.437704)
					(mid 415.722472 -223.428724)
					(end 415.731452 -223.425004)
				)
				(arc
					(start 417.204652 -223.425004)
					(mid 417.213632 -223.428724)
					(end 417.217352 -223.437704)
				)
			)
		)
	)
	(zone
		(layer "In1.Cu")
		(hatch none 0.5)
		(connect_pads
			(clearance 0)
		)
		(min_thickness 0.25)
		(keepout
			(tracks not_allowed)
			(vias allowed)
			(pads allowed)
			(copperpour not_allowed)
			(footprints allowed)
		)
		(placement
			(enabled no)
			(sheetname "")
		)
		(fill
			(thermal_gap 0.5)
			(thermal_bridge_width 0.5)
			(island_removal_mode 0)
		)
		(polygon
			(pts
				(arc
					(start 305.860958 -393.69238)
					(mid 305.479958 -393.69238)
					(end 305.860958 -393.69238)
				)
			)
		)
	)
	(zone
		(layer "In1.Cu")
		(hatch none 0.5)
		(connect_pads
			(clearance 0)
		)
		(min_thickness 0.25)
		(keepout
			(tracks not_allowed)
			(vias allowed)
			(pads allowed)
			(copperpour not_allowed)
			(footprints allowed)
		)
		(placement
			(enabled no)
			(sheetname "")
		)
		(fill
			(thermal_gap 0.5)
			(thermal_bridge_width 0.5)
			(island_removal_mode 0)
		)
		(polygon
			(pts
				(arc
					(start 348.097856 -399.143474)
					(mid 347.793056 -399.143474)
					(end 348.097856 -399.143474)
				)
			)
		)
	)
	(zone
		(layer "In1.Cu")
		(hatch none 0.5)
		(connect_pads
			(clearance 0)
		)
		(min_thickness 0.25)
		(keepout
			(tracks not_allowed)
			(vias allowed)
			(pads allowed)
			(copperpour not_allowed)
			(footprints allowed)
		)
		(placement
			(enabled no)
			(sheetname "")
		)
		(fill
			(thermal_gap 0.5)
			(thermal_bridge_width 0.5)
			(island_removal_mode 0)
		)
		(polygon
			(pts
				(arc
					(start 439.849514 -298.732194)
					(mid 439.845794 -298.741174)
					(end 439.836814 -298.744894)
				)
				(arc
					(start 438.363614 -298.744894)
					(mid 438.354634 -298.741174)
					(end 438.350914 -298.732194)
				)
				(arc
					(start 438.350914 -298.237656)
					(mid 438.354634 -298.228676)
					(end 438.363614 -298.224956)
				)
				(arc
					(start 439.836814 -298.224956)
					(mid 439.845794 -298.228676)
					(end 439.849514 -298.237656)
				)
			)
		)
	)
	(zone
		(layer "In1.Cu")
		(hatch none 0.5)
		(connect_pads
			(clearance 0)
		)
		(min_thickness 0.25)
		(keepout
			(tracks not_allowed)
			(vias allowed)
			(pads allowed)
			(copperpour not_allowed)
			(footprints allowed)
		)
		(placement
			(enabled no)
			(sheetname "")
		)
		(fill
			(thermal_gap 0.5)
			(thermal_bridge_width 0.5)
			(island_removal_mode 0)
		)
		(polygon
			(pts
				(arc
					(start 370.961158 -394.385292)
					(mid 370.580158 -394.385292)
					(end 370.961158 -394.385292)
				)
			)
		)
	)
	(zone
		(layer "In1.Cu")
		(hatch none 0.5)
		(connect_pads
			(clearance 0)
		)
		(min_thickness 0.25)
		(keepout
			(tracks not_allowed)
			(vias allowed)
			(pads allowed)
			(copperpour not_allowed)
			(footprints allowed)
		)
		(placement
			(enabled no)
			(sheetname "")
		)
		(fill
			(thermal_gap 0.5)
			(thermal_bridge_width 0.5)
			(island_removal_mode 0)
		)
		(polygon
			(pts
				(arc
					(start 432.30546 -287.682178)
					(mid 432.30174 -287.691158)
					(end 432.29276 -287.694878)
				)
				(arc
					(start 430.81956 -287.694878)
					(mid 430.81058 -287.691158)
					(end 430.80686 -287.682178)
				)
				(arc
					(start 430.80686 -287.18764)
					(mid 430.81058 -287.17866)
					(end 430.81956 -287.17494)
				)
				(arc
					(start 432.29276 -287.17494)
					(mid 432.30174 -287.17866)
					(end 432.30546 -287.18764)
				)
			)
		)
	)
	(zone
		(layer "In1.Cu")
		(hatch none 0.5)
		(connect_pads
			(clearance 0)
		)
		(min_thickness 0.25)
		(keepout
			(tracks not_allowed)
			(vias allowed)
			(pads allowed)
			(copperpour not_allowed)
			(footprints allowed)
		)
		(placement
			(enabled no)
			(sheetname "")
		)
		(fill
			(thermal_gap 0.5)
			(thermal_bridge_width 0.5)
			(island_removal_mode 0)
		)
		(polygon
			(pts
				(arc
					(start 413.117284 -277.4823)
					(mid 413.113564 -277.49128)
					(end 413.104584 -277.495)
				)
				(arc
					(start 411.631384 -277.495)
					(mid 411.622404 -277.49128)
					(end 411.618684 -277.4823)
				)
				(arc
					(start 411.618684 -276.987762)
					(mid 411.622404 -276.978782)
					(end 411.631384 -276.975062)
				)
				(arc
					(start 413.104584 -276.975062)
					(mid 413.113564 -276.978782)
					(end 413.117284 -276.987762)
				)
			)
		)
	)
	(zone
		(layer "In1.Cu")
		(hatch none 0.5)
		(connect_pads
			(clearance 0)
		)
		(min_thickness 0.25)
		(keepout
			(tracks not_allowed)
			(vias allowed)
			(pads allowed)
			(copperpour not_allowed)
			(footprints allowed)
		)
		(placement
			(enabled no)
			(sheetname "")
		)
		(fill
			(thermal_gap 0.5)
			(thermal_bridge_width 0.5)
			(island_removal_mode 0)
		)
		(polygon
			(pts
				(arc
					(start 443.2935 -217.132154)
					(mid 443.28978 -217.141134)
					(end 443.2808 -217.144854)
				)
				(arc
					(start 441.8076 -217.144854)
					(mid 441.79862 -217.141134)
					(end 441.7949 -217.132154)
				)
				(arc
					(start 441.7949 -216.637616)
					(mid 441.79862 -216.628636)
					(end 441.8076 -216.624916)
				)
				(arc
					(start 443.2808 -216.624916)
					(mid 443.28978 -216.628636)
					(end 443.2935 -216.637616)
				)
			)
		)
	)
	(zone
		(layer "In1.Cu")
		(hatch none 0.5)
		(connect_pads
			(clearance 0)
		)
		(min_thickness 0.25)
		(keepout
			(tracks not_allowed)
			(vias allowed)
			(pads allowed)
			(copperpour not_allowed)
			(footprints allowed)
		)
		(placement
			(enabled no)
			(sheetname "")
		)
		(fill
			(thermal_gap 0.5)
			(thermal_bridge_width 0.5)
			(island_removal_mode 0)
		)
		(polygon
			(pts
				(arc
					(start 206.5782 -273.835368)
					(mid 205.9178 -273.835368)
					(end 206.5782 -273.835368)
				)
			)
		)
	)
	(zone
		(layer "In1.Cu")
		(hatch none 0.5)
		(connect_pads
			(clearance 0)
		)
		(min_thickness 0.25)
		(keepout
			(tracks not_allowed)
			(vias allowed)
			(pads allowed)
			(copperpour not_allowed)
			(footprints allowed)
		)
		(placement
			(enabled no)
			(sheetname "")
		)
		(fill
			(thermal_gap 0.5)
			(thermal_bridge_width 0.5)
			(island_removal_mode 0)
		)
		(polygon
			(pts
				(arc
					(start 439.849514 -264.732262)
					(mid 439.845794 -264.741242)
					(end 439.836814 -264.744962)
				)
				(arc
					(start 438.363614 -264.744962)
					(mid 438.354634 -264.741242)
					(end 438.350914 -264.732262)
				)
				(arc
					(start 438.350914 -264.237724)
					(mid 438.354634 -264.228744)
					(end 438.363614 -264.225024)
				)
				(arc
					(start 439.836814 -264.225024)
					(mid 439.845794 -264.228744)
					(end 439.849514 -264.237724)
				)
			)
		)
	)
	(zone
		(layer "In1.Cu")
		(hatch none 0.5)
		(connect_pads
			(clearance 0)
		)
		(min_thickness 0.25)
		(keepout
			(tracks not_allowed)
			(vias allowed)
			(pads allowed)
			(copperpour not_allowed)
			(footprints allowed)
		)
		(placement
			(enabled no)
			(sheetname "")
		)
		(fill
			(thermal_gap 0.5)
			(thermal_bridge_width 0.5)
			(island_removal_mode 0)
		)
		(polygon
			(pts
				(arc
					(start 265.87831 -209.23504)
					(mid 265.21791 -209.23504)
					(end 265.87831 -209.23504)
				)
			)
		)
	)
	(zone
		(layer "In1.Cu")
		(hatch none 0.5)
		(connect_pads
			(clearance 0)
		)
		(min_thickness 0.25)
		(keepout
			(tracks not_allowed)
			(vias allowed)
			(pads allowed)
			(copperpour not_allowed)
			(footprints allowed)
		)
		(placement
			(enabled no)
			(sheetname "")
		)
		(fill
			(thermal_gap 0.5)
			(thermal_bridge_width 0.5)
			(island_removal_mode 0)
		)
		(polygon
			(pts
				(arc
					(start 304.017426 -293.632128)
					(mid 304.013706 -293.641108)
					(end 304.004726 -293.644828)
				)
				(arc
					(start 302.531526 -293.644828)
					(mid 302.522546 -293.641108)
					(end 302.518826 -293.632128)
				)
				(arc
					(start 302.518826 -293.13759)
					(mid 302.522546 -293.12861)
					(end 302.531526 -293.12489)
				)
				(arc
					(start 304.004726 -293.12489)
					(mid 304.013706 -293.12861)
					(end 304.017426 -293.13759)
				)
			)
		)
	)
	(zone
		(layer "In1.Cu")
		(hatch none 0.5)
		(connect_pads
			(clearance 0)
		)
		(min_thickness 0.25)
		(keepout
			(tracks not_allowed)
			(vias allowed)
			(pads allowed)
			(copperpour not_allowed)
			(footprints allowed)
		)
		(placement
			(enabled no)
			(sheetname "")
		)
		(fill
			(thermal_gap 0.5)
			(thermal_bridge_width 0.5)
			(island_removal_mode 0)
		)
		(polygon
			(pts
				(arc
					(start 124.270262 -383.92227)
					(mid 123.965462 -383.92227)
					(end 124.270262 -383.92227)
				)
			)
		)
	)
	(zone
		(layer "In1.Cu")
		(hatch none 0.5)
		(connect_pads
			(clearance 0)
		)
		(min_thickness 0.25)
		(keepout
			(tracks not_allowed)
			(vias allowed)
			(pads allowed)
			(copperpour not_allowed)
			(footprints allowed)
		)
		(placement
			(enabled no)
			(sheetname "")
		)
		(fill
			(thermal_gap 0.5)
			(thermal_bridge_width 0.5)
			(island_removal_mode 0)
		)
		(polygon
			(pts
				(arc
					(start 341.188548 -394.385292)
					(mid 340.807548 -394.385292)
					(end 341.188548 -394.385292)
				)
			)
		)
	)
	(zone
		(layer "In1.Cu")
		(hatch none 0.5)
		(connect_pads
			(clearance 0)
		)
		(min_thickness 0.25)
		(keepout
			(tracks not_allowed)
			(vias allowed)
			(pads allowed)
			(copperpour not_allowed)
			(footprints allowed)
		)
		(placement
			(enabled no)
			(sheetname "")
		)
		(fill
			(thermal_gap 0.5)
			(thermal_bridge_width 0.5)
			(island_removal_mode 0)
		)
		(polygon
			(pts
				(arc
					(start 439.849514 -229.882192)
					(mid 439.845794 -229.891172)
					(end 439.836814 -229.894892)
				)
				(arc
					(start 438.363614 -229.894892)
					(mid 438.354634 -229.891172)
					(end 438.350914 -229.882192)
				)
				(arc
					(start 438.350914 -229.387654)
					(mid 438.354634 -229.378674)
					(end 438.363614 -229.374954)
				)
				(arc
					(start 439.836814 -229.374954)
					(mid 439.845794 -229.378674)
					(end 439.849514 -229.387654)
				)
			)
		)
	)
	(zone
		(layer "In1.Cu")
		(hatch none 0.5)
		(connect_pads
			(clearance 0)
		)
		(min_thickness 0.25)
		(keepout
			(tracks not_allowed)
			(vias allowed)
			(pads allowed)
			(copperpour not_allowed)
			(footprints allowed)
		)
		(placement
			(enabled no)
			(sheetname "")
		)
		(fill
			(thermal_gap 0.5)
			(thermal_bridge_width 0.5)
			(island_removal_mode 0)
		)
		(polygon
			(pts
				(arc
					(start 439.849514 -300.432216)
					(mid 439.845794 -300.441196)
					(end 439.836814 -300.444916)
				)
				(arc
					(start 438.363614 -300.444916)
					(mid 438.354634 -300.441196)
					(end 438.350914 -300.432216)
				)
				(arc
					(start 438.350914 -299.937678)
					(mid 438.354634 -299.928698)
					(end 438.363614 -299.924978)
				)
				(arc
					(start 439.836814 -299.924978)
					(mid 439.845794 -299.928698)
					(end 439.849514 -299.937678)
				)
			)
		)
	)
	(zone
		(layer "In1.Cu")
		(hatch none 0.5)
		(connect_pads
			(clearance 0)
		)
		(min_thickness 0.25)
		(keepout
			(tracks not_allowed)
			(vias allowed)
			(pads allowed)
			(copperpour not_allowed)
			(footprints allowed)
		)
		(placement
			(enabled no)
			(sheetname "")
		)
		(fill
			(thermal_gap 0.5)
			(thermal_bridge_width 0.5)
			(island_removal_mode 0)
		)
		(polygon
			(pts
				(arc
					(start 202.897232 -280.882344)
					(mid 202.893512 -280.891324)
					(end 202.884532 -280.895044)
				)
				(arc
					(start 201.411332 -280.895044)
					(mid 201.402352 -280.891324)
					(end 201.398632 -280.882344)
				)
				(arc
					(start 201.398632 -280.387806)
					(mid 201.402352 -280.378826)
					(end 201.411332 -280.375106)
				)
				(arc
					(start 202.884532 -280.375106)
					(mid 202.893512 -280.378826)
					(end 202.897232 -280.387806)
				)
			)
		)
	)
	(zone
		(layer "In1.Cu")
		(hatch none 0.5)
		(connect_pads
			(clearance 0)
		)
		(min_thickness 0.25)
		(keepout
			(tracks not_allowed)
			(vias allowed)
			(pads allowed)
			(copperpour not_allowed)
			(footprints allowed)
		)
		(placement
			(enabled no)
			(sheetname "")
		)
		(fill
			(thermal_gap 0.5)
			(thermal_bridge_width 0.5)
			(island_removal_mode 0)
		)
		(polygon
			(pts
				(arc
					(start 417.217352 -251.132086)
					(mid 417.213632 -251.141066)
					(end 417.204652 -251.144786)
				)
				(arc
					(start 415.731452 -251.144786)
					(mid 415.722472 -251.141066)
					(end 415.718752 -251.132086)
				)
				(arc
					(start 415.718752 -250.637548)
					(mid 415.722472 -250.628568)
					(end 415.731452 -250.624848)
				)
				(arc
					(start 417.204652 -250.624848)
					(mid 417.213632 -250.628568)
					(end 417.217352 -250.637548)
				)
			)
		)
	)
	(zone
		(layer "In1.Cu")
		(hatch none 0.5)
		(connect_pads
			(clearance 0)
		)
		(min_thickness 0.25)
		(keepout
			(tracks not_allowed)
			(vias allowed)
			(pads allowed)
			(copperpour not_allowed)
			(footprints allowed)
		)
		(placement
			(enabled no)
			(sheetname "")
		)
		(fill
			(thermal_gap 0.5)
			(thermal_bridge_width 0.5)
			(island_removal_mode 0)
		)
		(polygon
			(pts
				(arc
					(start 447.393568 -214.582248)
					(mid 447.389848 -214.591228)
					(end 447.380868 -214.594948)
				)
				(arc
					(start 445.907668 -214.594948)
					(mid 445.898688 -214.591228)
					(end 445.894968 -214.582248)
				)
				(arc
					(start 445.894968 -214.08771)
					(mid 445.898688 -214.07873)
					(end 445.907668 -214.07501)
				)
				(arc
					(start 447.380868 -214.07501)
					(mid 447.389848 -214.07873)
					(end 447.393568 -214.08771)
				)
			)
		)
	)
	(zone
		(layer "In1.Cu")
		(hatch none 0.5)
		(connect_pads
			(clearance 0)
		)
		(min_thickness 0.25)
		(keepout
			(tracks not_allowed)
			(vias allowed)
			(pads allowed)
			(copperpour not_allowed)
			(footprints allowed)
		)
		(placement
			(enabled no)
			(sheetname "")
		)
		(fill
			(thermal_gap 0.5)
			(thermal_bridge_width 0.5)
			(island_removal_mode 0)
		)
		(polygon
			(pts
				(arc
					(start 56.077358 -201.832464)
					(mid 56.073638 -201.841444)
					(end 56.064658 -201.845164)
				)
				(arc
					(start 54.591458 -201.845164)
					(mid 54.582478 -201.841444)
					(end 54.578758 -201.832464)
				)
				(arc
					(start 54.578758 -201.337926)
					(mid 54.582478 -201.328946)
					(end 54.591458 -201.325226)
				)
				(arc
					(start 56.064658 -201.325226)
					(mid 56.073638 -201.328946)
					(end 56.077358 -201.337926)
				)
			)
		)
	)
	(zone
		(layer "In1.Cu")
		(hatch none 0.5)
		(connect_pads
			(clearance 0)
		)
		(min_thickness 0.25)
		(keepout
			(tracks not_allowed)
			(vias allowed)
			(pads allowed)
			(copperpour not_allowed)
			(footprints allowed)
		)
		(placement
			(enabled no)
			(sheetname "")
		)
		(fill
			(thermal_gap 0.5)
			(thermal_bridge_width 0.5)
			(island_removal_mode 0)
		)
		(polygon
			(pts
				(arc
					(start 45.089318 -244.332506)
					(mid 45.085598 -244.341486)
					(end 45.076618 -244.345206)
				)
				(arc
					(start 43.603418 -244.345206)
					(mid 43.594438 -244.341486)
					(end 43.590718 -244.332506)
				)
				(arc
					(start 43.590718 -243.837968)
					(mid 43.594438 -243.828988)
					(end 43.603418 -243.825268)
				)
				(arc
					(start 45.076618 -243.825268)
					(mid 45.085598 -243.828988)
					(end 45.089318 -243.837968)
				)
			)
		)
	)
	(zone
		(layer "In1.Cu")
		(hatch none 0.5)
		(connect_pads
			(clearance 0)
		)
		(min_thickness 0.25)
		(keepout
			(tracks not_allowed)
			(vias allowed)
			(pads allowed)
			(copperpour not_allowed)
			(footprints allowed)
		)
		(placement
			(enabled no)
			(sheetname "")
		)
		(fill
			(thermal_gap 0.5)
			(thermal_bridge_width 0.5)
			(island_removal_mode 0)
		)
		(polygon
			(pts
				(arc
					(start 270.397478 -276.632162)
					(mid 270.393758 -276.641142)
					(end 270.384778 -276.644862)
				)
				(arc
					(start 268.911578 -276.644862)
					(mid 268.902598 -276.641142)
					(end 268.898878 -276.632162)
				)
				(arc
					(start 268.898878 -276.137624)
					(mid 268.902598 -276.128644)
					(end 268.911578 -276.124924)
				)
				(arc
					(start 270.384778 -276.124924)
					(mid 270.393758 -276.128644)
					(end 270.397478 -276.137624)
				)
			)
		)
	)
	(zone
		(layer "In1.Cu")
		(hatch none 0.5)
		(connect_pads
			(clearance 0)
		)
		(min_thickness 0.25)
		(keepout
			(tracks not_allowed)
			(vias allowed)
			(pads allowed)
			(copperpour not_allowed)
			(footprints allowed)
		)
		(placement
			(enabled no)
			(sheetname "")
		)
		(fill
			(thermal_gap 0.5)
			(thermal_bridge_width 0.5)
			(island_removal_mode 0)
		)
		(polygon
			(pts
				(arc
					(start 172.72127 -305.532536)
					(mid 172.71755 -305.541516)
					(end 172.70857 -305.545236)
				)
				(arc
					(start 171.23537 -305.545236)
					(mid 171.22639 -305.541516)
					(end 171.22267 -305.532536)
				)
				(arc
					(start 171.22267 -305.037998)
					(mid 171.22639 -305.029018)
					(end 171.23537 -305.025298)
				)
				(arc
					(start 172.70857 -305.025298)
					(mid 172.71755 -305.029018)
					(end 172.72127 -305.037998)
				)
			)
		)
	)
	(zone
		(layer "In1.Cu")
		(hatch none 0.5)
		(connect_pads
			(clearance 0)
		)
		(min_thickness 0.25)
		(keepout
			(tracks not_allowed)
			(vias allowed)
			(pads allowed)
			(copperpour not_allowed)
			(footprints allowed)
		)
		(placement
			(enabled no)
			(sheetname "")
		)
		(fill
			(thermal_gap 0.5)
			(thermal_bridge_width 0.5)
			(island_removal_mode 0)
		)
		(polygon
			(pts
				(arc
					(start 118.89105 -391.319258)
					(mid 119.01805 -391.446258)
					(end 119.14505 -391.319258)
				)
				(arc
					(start 119.14505 -391.243058)
					(mid 119.01805 -391.116058)
					(end 118.89105 -391.243058)
				)
			)
		)
	)
	(zone
		(layer "In1.Cu")
		(hatch none 0.5)
		(connect_pads
			(clearance 0)
		)
		(min_thickness 0.25)
		(keepout
			(tracks not_allowed)
			(vias allowed)
			(pads allowed)
			(copperpour not_allowed)
			(footprints allowed)
		)
		(placement
			(enabled no)
			(sheetname "")
		)
		(fill
			(thermal_gap 0.5)
			(thermal_bridge_width 0.5)
			(island_removal_mode 0)
		)
		(polygon
			(pts
				(arc
					(start 40.98925 -312.33237)
					(mid 40.98553 -312.34135)
					(end 40.97655 -312.34507)
				)
				(arc
					(start 39.50335 -312.34507)
					(mid 39.49437 -312.34135)
					(end 39.49065 -312.33237)
				)
				(arc
					(start 39.49065 -311.837832)
					(mid 39.49437 -311.828852)
					(end 39.50335 -311.825132)
				)
				(arc
					(start 40.97655 -311.825132)
					(mid 40.98553 -311.828852)
					(end 40.98925 -311.837832)
				)
			)
		)
	)
	(zone
		(layer "In1.Cu")
		(hatch none 0.5)
		(connect_pads
			(clearance 0)
		)
		(min_thickness 0.25)
		(keepout
			(tracks not_allowed)
			(vias allowed)
			(pads allowed)
			(copperpour not_allowed)
			(footprints allowed)
		)
		(placement
			(enabled no)
			(sheetname "")
		)
		(fill
			(thermal_gap 0.5)
			(thermal_bridge_width 0.5)
			(island_removal_mode 0)
		)
		(polygon
			(pts
				(arc
					(start 132.56133 -388.774432)
					(mid 132.18033 -388.774432)
					(end 132.56133 -388.774432)
				)
			)
		)
	)
	(zone
		(layer "In1.Cu")
		(hatch none 0.5)
		(connect_pads
			(clearance 0)
		)
		(min_thickness 0.25)
		(keepout
			(tracks not_allowed)
			(vias allowed)
			(pads allowed)
			(copperpour not_allowed)
			(footprints allowed)
		)
		(placement
			(enabled no)
			(sheetname "")
		)
		(fill
			(thermal_gap 0.5)
			(thermal_bridge_width 0.5)
			(island_removal_mode 0)
		)
		(polygon
			(pts
				(arc
					(start 187.809378 -279.182576)
					(mid 187.805658 -279.191556)
					(end 187.796678 -279.195276)
				)
				(arc
					(start 186.323478 -279.195276)
					(mid 186.314498 -279.191556)
					(end 186.310778 -279.182576)
				)
				(arc
					(start 186.310778 -278.688038)
					(mid 186.314498 -278.679058)
					(end 186.323478 -278.675338)
				)
				(arc
					(start 187.796678 -278.675338)
					(mid 187.805658 -278.679058)
					(end 187.809378 -278.688038)
				)
			)
		)
	)
	(zone
		(layer "In1.Cu")
		(hatch none 0.5)
		(connect_pads
			(clearance 0)
		)
		(min_thickness 0.25)
		(keepout
			(tracks not_allowed)
			(vias allowed)
			(pads allowed)
			(copperpour not_allowed)
			(footprints allowed)
		)
		(placement
			(enabled no)
			(sheetname "")
		)
		(fill
			(thermal_gap 0.5)
			(thermal_bridge_width 0.5)
			(island_removal_mode 0)
		)
		(polygon
			(pts
				(arc
					(start 199.4535 -205.232508)
					(mid 199.44978 -205.241488)
					(end 199.4408 -205.245208)
				)
				(arc
					(start 197.9676 -205.245208)
					(mid 197.95862 -205.241488)
					(end 197.9549 -205.232508)
				)
				(arc
					(start 197.9549 -204.73797)
					(mid 197.95862 -204.72899)
					(end 197.9676 -204.72527)
				)
				(arc
					(start 199.4408 -204.72527)
					(mid 199.44978 -204.72899)
					(end 199.4535 -204.73797)
				)
			)
		)
	)
	(zone
		(layer "In1.Cu")
		(hatch none 0.5)
		(connect_pads
			(clearance 0)
		)
		(min_thickness 0.25)
		(keepout
			(tracks not_allowed)
			(vias allowed)
			(pads allowed)
			(copperpour not_allowed)
			(footprints allowed)
		)
		(placement
			(enabled no)
			(sheetname "")
		)
		(fill
			(thermal_gap 0.5)
			(thermal_bridge_width 0.5)
			(island_removal_mode 0)
		)
		(polygon
			(pts
				(arc
					(start 424.761406 -220.532198)
					(mid 424.757686 -220.541178)
					(end 424.748706 -220.544898)
				)
				(arc
					(start 423.275506 -220.544898)
					(mid 423.266526 -220.541178)
					(end 423.262806 -220.532198)
				)
				(arc
					(start 423.262806 -220.03766)
					(mid 423.266526 -220.02868)
					(end 423.275506 -220.02496)
				)
				(arc
					(start 424.748706 -220.02496)
					(mid 424.757686 -220.02868)
					(end 424.761406 -220.03766)
				)
			)
		)
	)
	(zone
		(layer "In1.Cu")
		(hatch none 0.5)
		(connect_pads
			(clearance 0)
		)
		(min_thickness 0.25)
		(keepout
			(tracks not_allowed)
			(vias allowed)
			(pads allowed)
			(copperpour not_allowed)
			(footprints allowed)
		)
		(placement
			(enabled no)
			(sheetname "")
		)
		(fill
			(thermal_gap 0.5)
			(thermal_bridge_width 0.5)
			(island_removal_mode 0)
		)
		(polygon
			(pts
				(arc
					(start 443.2935 -237.532164)
					(mid 443.28978 -237.541144)
					(end 443.2808 -237.544864)
				)
				(arc
					(start 441.8076 -237.544864)
					(mid 441.79862 -237.541144)
					(end 441.7949 -237.532164)
				)
				(arc
					(start 441.7949 -237.037626)
					(mid 441.79862 -237.028646)
					(end 441.8076 -237.024926)
				)
				(arc
					(start 443.2808 -237.024926)
					(mid 443.28978 -237.028646)
					(end 443.2935 -237.037626)
				)
			)
		)
	)
	(zone
		(layer "In1.Cu")
		(hatch none 0.5)
		(connect_pads
			(clearance 0)
		)
		(min_thickness 0.25)
		(keepout
			(tracks not_allowed)
			(vias allowed)
			(pads allowed)
			(copperpour not_allowed)
			(footprints allowed)
		)
		(placement
			(enabled no)
			(sheetname "")
		)
		(fill
			(thermal_gap 0.5)
			(thermal_bridge_width 0.5)
			(island_removal_mode 0)
		)
		(polygon
			(pts
				(arc
					(start 304.017426 -316.582298)
					(mid 304.013706 -316.591278)
					(end 304.004726 -316.594998)
				)
				(arc
					(start 302.531526 -316.594998)
					(mid 302.522546 -316.591278)
					(end 302.518826 -316.582298)
				)
				(arc
					(start 302.518826 -316.08776)
					(mid 302.522546 -316.07878)
					(end 302.531526 -316.07506)
				)
				(arc
					(start 304.004726 -316.07506)
					(mid 304.013706 -316.07878)
					(end 304.017426 -316.08776)
				)
			)
		)
	)
	(zone
		(layer "In1.Cu")
		(hatch none 0.5)
		(connect_pads
			(clearance 0)
		)
		(min_thickness 0.25)
		(keepout
			(tracks not_allowed)
			(vias allowed)
			(pads allowed)
			(copperpour not_allowed)
			(footprints allowed)
		)
		(placement
			(enabled no)
			(sheetname "")
		)
		(fill
			(thermal_gap 0.5)
			(thermal_bridge_width 0.5)
			(island_removal_mode 0)
		)
		(polygon
			(pts
				(arc
					(start 60.177426 -244.332506)
					(mid 60.173706 -244.341486)
					(end 60.164726 -244.345206)
				)
				(arc
					(start 58.691526 -244.345206)
					(mid 58.682546 -244.341486)
					(end 58.678826 -244.332506)
				)
				(arc
					(start 58.678826 -243.837968)
					(mid 58.682546 -243.828988)
					(end 58.691526 -243.825268)
				)
				(arc
					(start 60.164726 -243.825268)
					(mid 60.173706 -243.828988)
					(end 60.177426 -243.837968)
				)
			)
		)
	)
	(zone
		(layer "In1.Cu")
		(hatch none 0.5)
		(connect_pads
			(clearance 0)
		)
		(min_thickness 0.25)
		(keepout
			(tracks not_allowed)
			(vias allowed)
			(pads allowed)
			(copperpour not_allowed)
			(footprints allowed)
		)
		(placement
			(enabled no)
			(sheetname "")
		)
		(fill
			(thermal_gap 0.5)
			(thermal_bridge_width 0.5)
			(island_removal_mode 0)
		)
		(polygon
			(pts
				(arc
					(start 199.4535 -234.982512)
					(mid 199.44978 -234.991492)
					(end 199.4408 -234.995212)
				)
				(arc
					(start 197.9676 -234.995212)
					(mid 197.95862 -234.991492)
					(end 197.9549 -234.982512)
				)
				(arc
					(start 197.9549 -234.487974)
					(mid 197.95862 -234.478994)
					(end 197.9676 -234.475274)
				)
				(arc
					(start 199.4408 -234.475274)
					(mid 199.44978 -234.478994)
					(end 199.4535 -234.487974)
				)
			)
		)
	)
	(zone
		(layer "In1.Cu")
		(hatch none 0.5)
		(connect_pads
			(clearance 0)
		)
		(min_thickness 0.25)
		(keepout
			(tracks not_allowed)
			(vias allowed)
			(pads allowed)
			(copperpour not_allowed)
			(footprints allowed)
		)
		(placement
			(enabled no)
			(sheetname "")
		)
		(fill
			(thermal_gap 0.5)
			(thermal_bridge_width 0.5)
			(island_removal_mode 0)
		)
		(polygon
			(pts
				(arc
					(start 296.473372 -235.832142)
					(mid 296.469652 -235.841122)
					(end 296.460672 -235.844842)
				)
				(arc
					(start 294.987472 -235.844842)
					(mid 294.978492 -235.841122)
					(end 294.974772 -235.832142)
				)
				(arc
					(start 294.974772 -235.337604)
					(mid 294.978492 -235.328624)
					(end 294.987472 -235.324904)
				)
				(arc
					(start 296.460672 -235.324904)
					(mid 296.469652 -235.328624)
					(end 296.473372 -235.337604)
				)
			)
		)
	)
	(zone
		(layer "In1.Cu")
		(hatch none 0.5)
		(connect_pads
			(clearance 0)
		)
		(min_thickness 0.25)
		(keepout
			(tracks not_allowed)
			(vias allowed)
			(pads allowed)
			(copperpour not_allowed)
			(footprints allowed)
		)
		(placement
			(enabled no)
			(sheetname "")
		)
		(fill
			(thermal_gap 0.5)
			(thermal_bridge_width 0.5)
			(island_removal_mode 0)
		)
		(polygon
			(pts
				(arc
					(start 308.117494 -274.082256)
					(mid 308.113774 -274.091236)
					(end 308.104794 -274.094956)
				)
				(arc
					(start 306.631594 -274.094956)
					(mid 306.622614 -274.091236)
					(end 306.618894 -274.082256)
				)
				(arc
					(start 306.618894 -273.587718)
					(mid 306.622614 -273.578738)
					(end 306.631594 -273.575018)
				)
				(arc
					(start 308.104794 -273.575018)
					(mid 308.113774 -273.578738)
					(end 308.117494 -273.587718)
				)
			)
		)
	)
	(zone
		(layer "In1.Cu")
		(hatch none 0.5)
		(connect_pads
			(clearance 0)
		)
		(min_thickness 0.25)
		(keepout
			(tracks not_allowed)
			(vias allowed)
			(pads allowed)
			(copperpour not_allowed)
			(footprints allowed)
		)
		(placement
			(enabled no)
			(sheetname "")
		)
		(fill
			(thermal_gap 0.5)
			(thermal_bridge_width 0.5)
			(island_removal_mode 0)
		)
		(polygon
			(pts
				(arc
					(start 169.277284 -240.932462)
					(mid 169.273564 -240.941442)
					(end 169.264584 -240.945162)
				)
				(arc
					(start 167.791384 -240.945162)
					(mid 167.782404 -240.941442)
					(end 167.778684 -240.932462)
				)
				(arc
					(start 167.778684 -240.437924)
					(mid 167.782404 -240.428944)
					(end 167.791384 -240.425224)
				)
				(arc
					(start 169.264584 -240.425224)
					(mid 169.273564 -240.428944)
					(end 169.277284 -240.437924)
				)
			)
		)
	)
	(zone
		(layer "In1.Cu")
		(hatch none 0.5)
		(connect_pads
			(clearance 0)
		)
		(min_thickness 0.25)
		(keepout
			(tracks not_allowed)
			(vias allowed)
			(pads allowed)
			(copperpour not_allowed)
			(footprints allowed)
		)
		(placement
			(enabled no)
			(sheetname "")
		)
		(fill
			(thermal_gap 0.5)
			(thermal_bridge_width 0.5)
			(island_removal_mode 0)
		)
		(polygon
			(pts
				(arc
					(start 285.485332 -231.582214)
					(mid 285.481612 -231.591194)
					(end 285.472632 -231.594914)
				)
				(arc
					(start 283.999432 -231.594914)
					(mid 283.990452 -231.591194)
					(end 283.986732 -231.582214)
				)
				(arc
					(start 283.986732 -231.087676)
					(mid 283.990452 -231.078696)
					(end 283.999432 -231.074976)
				)
				(arc
					(start 285.472632 -231.074976)
					(mid 285.481612 -231.078696)
					(end 285.485332 -231.087676)
				)
			)
		)
	)
	(zone
		(layer "In1.Cu")
		(hatch none 0.5)
		(connect_pads
			(clearance 0)
		)
		(min_thickness 0.25)
		(keepout
			(tracks not_allowed)
			(vias allowed)
			(pads allowed)
			(copperpour not_allowed)
			(footprints allowed)
		)
		(placement
			(enabled no)
			(sheetname "")
		)
		(fill
			(thermal_gap 0.5)
			(thermal_bridge_width 0.5)
			(island_removal_mode 0)
		)
		(polygon
			(pts
				(arc
					(start 388.561326 -397.156432)
					(mid 388.180326 -397.156432)
					(end 388.561326 -397.156432)
				)
			)
		)
	)
	(zone
		(layer "In1.Cu")
		(hatch none 0.5)
		(connect_pads
			(clearance 0)
		)
		(min_thickness 0.25)
		(keepout
			(tracks not_allowed)
			(vias allowed)
			(pads allowed)
			(copperpour not_allowed)
			(footprints allowed)
		)
		(placement
			(enabled no)
			(sheetname "")
		)
		(fill
			(thermal_gap 0.5)
			(thermal_bridge_width 0.5)
			(island_removal_mode 0)
		)
		(polygon
			(pts
				(arc
					(start 417.217352 -309.78221)
					(mid 417.213632 -309.79119)
					(end 417.204652 -309.79491)
				)
				(arc
					(start 415.731452 -309.79491)
					(mid 415.722472 -309.79119)
					(end 415.718752 -309.78221)
				)
				(arc
					(start 415.718752 -309.287672)
					(mid 415.722472 -309.278692)
					(end 415.731452 -309.274972)
				)
				(arc
					(start 417.204652 -309.274972)
					(mid 417.213632 -309.278692)
					(end 417.217352 -309.287672)
				)
			)
		)
	)
	(zone
		(layer "In1.Cu")
		(hatch none 0.5)
		(connect_pads
			(clearance 0)
		)
		(min_thickness 0.25)
		(keepout
			(tracks not_allowed)
			(vias allowed)
			(pads allowed)
			(copperpour not_allowed)
			(footprints allowed)
		)
		(placement
			(enabled no)
			(sheetname "")
		)
		(fill
			(thermal_gap 0.5)
			(thermal_bridge_width 0.5)
			(island_removal_mode 0)
		)
		(polygon
			(pts
				(arc
					(start 443.2935 -279.182322)
					(mid 443.28978 -279.191302)
					(end 443.2808 -279.195022)
				)
				(arc
					(start 441.8076 -279.195022)
					(mid 441.79862 -279.191302)
					(end 441.7949 -279.182322)
				)
				(arc
					(start 441.7949 -278.687784)
					(mid 441.79862 -278.678804)
					(end 441.8076 -278.675084)
				)
				(arc
					(start 443.2808 -278.675084)
					(mid 443.28978 -278.678804)
					(end 443.2935 -278.687784)
				)
			)
		)
	)
	(zone
		(layer "In1.Cu")
		(hatch none 0.5)
		(connect_pads
			(clearance 0)
		)
		(min_thickness 0.25)
		(keepout
			(tracks not_allowed)
			(vias allowed)
			(pads allowed)
			(copperpour not_allowed)
			(footprints allowed)
		)
		(placement
			(enabled no)
			(sheetname "")
		)
		(fill
			(thermal_gap 0.5)
			(thermal_bridge_width 0.5)
			(island_removal_mode 0)
		)
		(polygon
			(pts
				(arc
					(start 22.45741 -249.432572)
					(mid 22.45369 -249.441552)
					(end 22.44471 -249.445272)
				)
				(arc
					(start 20.97151 -249.445272)
					(mid 20.96253 -249.441552)
					(end 20.95881 -249.432572)
				)
				(arc
					(start 20.95881 -248.938034)
					(mid 20.96253 -248.929054)
					(end 20.97151 -248.925334)
				)
				(arc
					(start 22.44471 -248.925334)
					(mid 22.45369 -248.929054)
					(end 22.45741 -248.938034)
				)
			)
		)
	)
	(zone
		(layer "In1.Cu")
		(hatch none 0.5)
		(connect_pads
			(clearance 0)
		)
		(min_thickness 0.25)
		(keepout
			(tracks not_allowed)
			(vias allowed)
			(pads allowed)
			(copperpour not_allowed)
			(footprints allowed)
		)
		(placement
			(enabled no)
			(sheetname "")
		)
		(fill
			(thermal_gap 0.5)
			(thermal_bridge_width 0.5)
			(island_removal_mode 0)
		)
		(polygon
			(pts
				(arc
					(start 169.277284 -298.732448)
					(mid 169.273564 -298.741428)
					(end 169.264584 -298.745148)
				)
				(arc
					(start 167.791384 -298.745148)
					(mid 167.782404 -298.741428)
					(end 167.778684 -298.732448)
				)
				(arc
					(start 167.778684 -298.23791)
					(mid 167.782404 -298.22893)
					(end 167.791384 -298.22521)
				)
				(arc
					(start 169.264584 -298.22521)
					(mid 169.273564 -298.22893)
					(end 169.277284 -298.23791)
				)
			)
		)
	)
	(zone
		(layer "In1.Cu")
		(hatch none 0.5)
		(connect_pads
			(clearance 0)
		)
		(min_thickness 0.25)
		(keepout
			(tracks not_allowed)
			(vias allowed)
			(pads allowed)
			(copperpour not_allowed)
			(footprints allowed)
		)
		(placement
			(enabled no)
			(sheetname "")
		)
		(fill
			(thermal_gap 0.5)
			(thermal_bridge_width 0.5)
			(island_removal_mode 0)
		)
		(polygon
			(pts
				(arc
					(start 265.87831 -274.684998)
					(mid 265.21791 -274.684998)
					(end 265.87831 -274.684998)
				)
			)
		)
	)
	(zone
		(layer "In1.Cu")
		(hatch none 0.5)
		(connect_pads
			(clearance 0)
		)
		(min_thickness 0.25)
		(keepout
			(tracks not_allowed)
			(vias allowed)
			(pads allowed)
			(copperpour not_allowed)
			(footprints allowed)
		)
		(placement
			(enabled no)
			(sheetname "")
		)
		(fill
			(thermal_gap 0.5)
			(thermal_bridge_width 0.5)
			(island_removal_mode 0)
		)
		(polygon
			(pts
				(arc
					(start 45.089318 -315.732414)
					(mid 45.085598 -315.741394)
					(end 45.076618 -315.745114)
				)
				(arc
					(start 43.603418 -315.745114)
					(mid 43.594438 -315.741394)
					(end 43.590718 -315.732414)
				)
				(arc
					(start 43.590718 -315.237876)
					(mid 43.594438 -315.228896)
					(end 43.603418 -315.225176)
				)
				(arc
					(start 45.076618 -315.225176)
					(mid 45.085598 -315.228896)
					(end 45.089318 -315.237876)
				)
			)
		)
	)
	(zone
		(layer "In1.Cu")
		(hatch none 0.5)
		(connect_pads
			(clearance 0)
		)
		(min_thickness 0.25)
		(keepout
			(tracks not_allowed)
			(vias allowed)
			(pads allowed)
			(copperpour not_allowed)
			(footprints allowed)
		)
		(placement
			(enabled no)
			(sheetname "")
		)
		(fill
			(thermal_gap 0.5)
			(thermal_bridge_width 0.5)
			(island_removal_mode 0)
		)
		(polygon
			(pts
				(arc
					(start 413.117284 -218.832176)
					(mid 413.113564 -218.841156)
					(end 413.104584 -218.844876)
				)
				(arc
					(start 411.631384 -218.844876)
					(mid 411.622404 -218.841156)
					(end 411.618684 -218.832176)
				)
				(arc
					(start 411.618684 -218.337638)
					(mid 411.622404 -218.328658)
					(end 411.631384 -218.324938)
				)
				(arc
					(start 413.104584 -218.324938)
					(mid 413.113564 -218.328658)
					(end 413.117284 -218.337638)
				)
			)
		)
	)
	(zone
		(layer "In1.Cu")
		(hatch none 0.5)
		(connect_pads
			(clearance 0)
		)
		(min_thickness 0.25)
		(keepout
			(tracks not_allowed)
			(vias allowed)
			(pads allowed)
			(copperpour not_allowed)
			(footprints allowed)
		)
		(placement
			(enabled no)
			(sheetname "")
		)
		(fill
			(thermal_gap 0.5)
			(thermal_bridge_width 0.5)
			(island_removal_mode 0)
		)
		(polygon
			(pts
				(arc
					(start 285.485332 -251.132086)
					(mid 285.481612 -251.141066)
					(end 285.472632 -251.144786)
				)
				(arc
					(start 283.999432 -251.144786)
					(mid 283.990452 -251.141066)
					(end 283.986732 -251.132086)
				)
				(arc
					(start 283.986732 -250.637548)
					(mid 283.990452 -250.628568)
					(end 283.999432 -250.624848)
				)
				(arc
					(start 285.472632 -250.624848)
					(mid 285.481612 -250.628568)
					(end 285.485332 -250.637548)
				)
			)
		)
	)
	(zone
		(layer "In1.Cu")
		(hatch none 0.5)
		(connect_pads
			(clearance 0)
		)
		(min_thickness 0.25)
		(keepout
			(tracks not_allowed)
			(vias allowed)
			(pads allowed)
			(copperpour not_allowed)
			(footprints allowed)
		)
		(placement
			(enabled no)
			(sheetname "")
		)
		(fill
			(thermal_gap 0.5)
			(thermal_bridge_width 0.5)
			(island_removal_mode 0)
		)
		(polygon
			(pts
				(arc
					(start 273.841464 -246.882158)
					(mid 273.837744 -246.891138)
					(end 273.828764 -246.894858)
				)
				(arc
					(start 272.355564 -246.894858)
					(mid 272.346584 -246.891138)
					(end 272.342864 -246.882158)
				)
				(arc
					(start 272.342864 -246.38762)
					(mid 272.346584 -246.37864)
					(end 272.355564 -246.37492)
				)
				(arc
					(start 273.828764 -246.37492)
					(mid 273.837744 -246.37864)
					(end 273.841464 -246.38762)
				)
			)
		)
	)
	(zone
		(layer "In1.Cu")
		(hatch none 0.5)
		(connect_pads
			(clearance 0)
		)
		(min_thickness 0.25)
		(keepout
			(tracks not_allowed)
			(vias allowed)
			(pads allowed)
			(copperpour not_allowed)
			(footprints allowed)
		)
		(placement
			(enabled no)
			(sheetname "")
		)
		(fill
			(thermal_gap 0.5)
			(thermal_bridge_width 0.5)
			(island_removal_mode 0)
		)
		(polygon
			(pts
				(arc
					(start 122.490992 -391.319258)
					(mid 122.617992 -391.446258)
					(end 122.744992 -391.319258)
				)
				(arc
					(start 122.744992 -391.243058)
					(mid 122.617992 -391.116058)
					(end 122.490992 -391.243058)
				)
			)
		)
	)
	(zone
		(layer "In1.Cu")
		(hatch none 0.5)
		(connect_pads
			(clearance 0)
		)
		(min_thickness 0.25)
		(keepout
			(tracks not_allowed)
			(vias allowed)
			(pads allowed)
			(copperpour not_allowed)
			(footprints allowed)
		)
		(placement
			(enabled no)
			(sheetname "")
		)
		(fill
			(thermal_gap 0.5)
			(thermal_bridge_width 0.5)
			(island_removal_mode 0)
		)
		(polygon
			(pts
				(arc
					(start 40.98925 -293.632382)
					(mid 40.98553 -293.641362)
					(end 40.97655 -293.645082)
				)
				(arc
					(start 39.50335 -293.645082)
					(mid 39.49437 -293.641362)
					(end 39.49065 -293.632382)
				)
				(arc
					(start 39.49065 -293.137844)
					(mid 39.49437 -293.128864)
					(end 39.50335 -293.125144)
				)
				(arc
					(start 40.97655 -293.125144)
					(mid 40.98553 -293.128864)
					(end 40.98925 -293.137844)
				)
			)
		)
	)
	(zone
		(layer "In1.Cu")
		(hatch none 0.5)
		(connect_pads
			(clearance 0)
		)
		(min_thickness 0.25)
		(keepout
			(tracks not_allowed)
			(vias allowed)
			(pads allowed)
			(copperpour not_allowed)
			(footprints allowed)
		)
		(placement
			(enabled no)
			(sheetname "")
		)
		(fill
			(thermal_gap 0.5)
			(thermal_bridge_width 0.5)
			(island_removal_mode 0)
		)
		(polygon
			(pts
				(arc
					(start 30.001464 -206.93253)
					(mid 29.997744 -206.94151)
					(end 29.988764 -206.94523)
				)
				(arc
					(start 28.515564 -206.94523)
					(mid 28.506584 -206.94151)
					(end 28.502864 -206.93253)
				)
				(arc
					(start 28.502864 -206.437992)
					(mid 28.506584 -206.429012)
					(end 28.515564 -206.425292)
				)
				(arc
					(start 29.988764 -206.425292)
					(mid 29.997744 -206.429012)
					(end 30.001464 -206.437992)
				)
			)
		)
	)
	(zone
		(layer "In1.Cu")
		(hatch none 0.5)
		(connect_pads
			(clearance 0)
		)
		(min_thickness 0.25)
		(keepout
			(tracks not_allowed)
			(vias allowed)
			(pads allowed)
			(copperpour not_allowed)
			(footprints allowed)
		)
		(placement
			(enabled no)
			(sheetname "")
		)
		(fill
			(thermal_gap 0.5)
			(thermal_bridge_width 0.5)
			(island_removal_mode 0)
		)
		(polygon
			(pts
				(arc
					(start 18.357342 -253.6825)
					(mid 18.353622 -253.69148)
					(end 18.344642 -253.6952)
				)
				(arc
					(start 16.871442 -253.6952)
					(mid 16.862462 -253.69148)
					(end 16.858742 -253.6825)
				)
				(arc
					(start 16.858742 -253.187962)
					(mid 16.862462 -253.178982)
					(end 16.871442 -253.175262)
				)
				(arc
					(start 18.344642 -253.175262)
					(mid 18.353622 -253.178982)
					(end 18.357342 -253.187962)
				)
			)
		)
	)
	(zone
		(layer "In1.Cu")
		(hatch none 0.5)
		(connect_pads
			(clearance 0)
		)
		(min_thickness 0.25)
		(keepout
			(tracks not_allowed)
			(vias allowed)
			(pads allowed)
			(copperpour not_allowed)
			(footprints allowed)
		)
		(placement
			(enabled no)
			(sheetname "")
		)
		(fill
			(thermal_gap 0.5)
			(thermal_bridge_width 0.5)
			(island_removal_mode 0)
		)
		(polygon
			(pts
				(arc
					(start 199.4535 -249.432572)
					(mid 199.44978 -249.441552)
					(end 199.4408 -249.445272)
				)
				(arc
					(start 197.9676 -249.445272)
					(mid 197.95862 -249.441552)
					(end 197.9549 -249.432572)
				)
				(arc
					(start 197.9549 -248.938034)
					(mid 197.95862 -248.929054)
					(end 197.9676 -248.925334)
				)
				(arc
					(start 199.4408 -248.925334)
					(mid 199.44978 -248.929054)
					(end 199.4535 -248.938034)
				)
			)
		)
	)
	(zone
		(layer "In1.Cu")
		(hatch none 0.5)
		(connect_pads
			(clearance 0)
		)
		(min_thickness 0.25)
		(keepout
			(tracks not_allowed)
			(vias allowed)
			(pads allowed)
			(copperpour not_allowed)
			(footprints allowed)
		)
		(placement
			(enabled no)
			(sheetname "")
		)
		(fill
			(thermal_gap 0.5)
			(thermal_bridge_width 0.5)
			(island_removal_mode 0)
		)
		(polygon
			(pts
				(arc
					(start 191.909446 -197.582536)
					(mid 191.905726 -197.591516)
					(end 191.896746 -197.595236)
				)
				(arc
					(start 190.423546 -197.595236)
					(mid 190.414566 -197.591516)
					(end 190.410846 -197.582536)
				)
				(arc
					(start 190.410846 -197.087998)
					(mid 190.414566 -197.079018)
					(end 190.423546 -197.075298)
				)
				(arc
					(start 191.896746 -197.075298)
					(mid 191.905726 -197.079018)
					(end 191.909446 -197.087998)
				)
			)
		)
	)
	(zone
		(layer "In1.Cu")
		(hatch none 0.5)
		(connect_pads
			(clearance 0)
		)
		(min_thickness 0.25)
		(keepout
			(tracks not_allowed)
			(vias allowed)
			(pads allowed)
			(copperpour not_allowed)
			(footprints allowed)
		)
		(placement
			(enabled no)
			(sheetname "")
		)
		(fill
			(thermal_gap 0.5)
			(thermal_bridge_width 0.5)
			(island_removal_mode 0)
		)
		(polygon
			(pts
				(arc
					(start 180.265324 -240.082578)
					(mid 180.261604 -240.091558)
					(end 180.252624 -240.095278)
				)
				(arc
					(start 178.779424 -240.095278)
					(mid 178.770444 -240.091558)
					(end 178.766724 -240.082578)
				)
				(arc
					(start 178.766724 -239.58804)
					(mid 178.770444 -239.57906)
					(end 178.779424 -239.57534)
				)
				(arc
					(start 180.252624 -239.57534)
					(mid 180.261604 -239.57906)
					(end 180.265324 -239.58804)
				)
			)
		)
	)
	(zone
		(layer "In1.Cu")
		(hatch none 0.5)
		(connect_pads
			(clearance 0)
		)
		(min_thickness 0.25)
		(keepout
			(tracks not_allowed)
			(vias allowed)
			(pads allowed)
			(copperpour not_allowed)
			(footprints allowed)
		)
		(placement
			(enabled no)
			(sheetname "")
		)
		(fill
			(thermal_gap 0.5)
			(thermal_bridge_width 0.5)
			(island_removal_mode 0)
		)
		(polygon
			(pts
				(arc
					(start 25.901396 -268.982444)
					(mid 25.897676 -268.991424)
					(end 25.888696 -268.995144)
				)
				(arc
					(start 24.415496 -268.995144)
					(mid 24.406516 -268.991424)
					(end 24.402796 -268.982444)
				)
				(arc
					(start 24.402796 -268.487906)
					(mid 24.406516 -268.478926)
					(end 24.415496 -268.475206)
				)
				(arc
					(start 25.888696 -268.475206)
					(mid 25.897676 -268.478926)
					(end 25.901396 -268.487906)
				)
			)
		)
	)
	(zone
		(layer "In1.Cu")
		(hatch none 0.5)
		(connect_pads
			(clearance 0)
		)
		(min_thickness 0.25)
		(keepout
			(tracks not_allowed)
			(vias allowed)
			(pads allowed)
			(copperpour not_allowed)
			(footprints allowed)
		)
		(placement
			(enabled no)
			(sheetname "")
		)
		(fill
			(thermal_gap 0.5)
			(thermal_bridge_width 0.5)
			(island_removal_mode 0)
		)
		(polygon
			(pts
				(arc
					(start 206.5782 -229.635304)
					(mid 205.9178 -229.635304)
					(end 206.5782 -229.635304)
				)
			)
		)
	)
	(zone
		(layer "In1.Cu")
		(hatch none 0.5)
		(connect_pads
			(clearance 0)
		)
		(min_thickness 0.25)
		(keepout
			(tracks not_allowed)
			(vias allowed)
			(pads allowed)
			(copperpour not_allowed)
			(footprints allowed)
		)
		(placement
			(enabled no)
			(sheetname "")
		)
		(fill
			(thermal_gap 0.5)
			(thermal_bridge_width 0.5)
			(island_removal_mode 0)
		)
		(polygon
			(pts
				(arc
					(start 202.897232 -223.082358)
					(mid 202.893512 -223.091338)
					(end 202.884532 -223.095058)
				)
				(arc
					(start 201.411332 -223.095058)
					(mid 201.402352 -223.091338)
					(end 201.398632 -223.082358)
				)
				(arc
					(start 201.398632 -222.58782)
					(mid 201.402352 -222.57884)
					(end 201.411332 -222.57512)
				)
				(arc
					(start 202.884532 -222.57512)
					(mid 202.893512 -222.57884)
					(end 202.897232 -222.58782)
				)
			)
		)
	)
	(zone
		(layer "In1.Cu")
		(hatch none 0.5)
		(connect_pads
			(clearance 0)
		)
		(min_thickness 0.25)
		(keepout
			(tracks not_allowed)
			(vias allowed)
			(pads allowed)
			(copperpour not_allowed)
			(footprints allowed)
		)
		(placement
			(enabled no)
			(sheetname "")
		)
		(fill
			(thermal_gap 0.5)
			(thermal_bridge_width 0.5)
			(island_removal_mode 0)
		)
		(polygon
			(pts
				(arc
					(start 124.891038 -383.440686)
					(mid 125.018038 -383.567686)
					(end 125.145038 -383.440686)
				)
				(arc
					(start 125.145038 -383.364486)
					(mid 125.018038 -383.237486)
					(end 124.891038 -383.364486)
				)
			)
		)
	)
	(zone
		(layer "In1.Cu")
		(hatch none 0.5)
		(connect_pads
			(clearance 0)
		)
		(min_thickness 0.25)
		(keepout
			(tracks not_allowed)
			(vias allowed)
			(pads allowed)
			(copperpour not_allowed)
			(footprints allowed)
		)
		(placement
			(enabled no)
			(sheetname "")
		)
		(fill
			(thermal_gap 0.5)
			(thermal_bridge_width 0.5)
			(island_removal_mode 0)
		)
		(polygon
			(pts
				(arc
					(start 51.061366 -385.31038)
					(mid 50.680366 -385.31038)
					(end 51.061366 -385.31038)
				)
			)
		)
	)
	(zone
		(layer "In1.Cu")
		(hatch none 0.5)
		(connect_pads
			(clearance 0)
		)
		(min_thickness 0.25)
		(keepout
			(tracks not_allowed)
			(vias allowed)
			(pads allowed)
			(copperpour not_allowed)
			(footprints allowed)
		)
		(placement
			(enabled no)
			(sheetname "")
		)
		(fill
			(thermal_gap 0.5)
			(thermal_bridge_width 0.5)
			(island_removal_mode 0)
		)
		(polygon
			(pts
				(arc
					(start 180.265324 -223.082358)
					(mid 180.261604 -223.091338)
					(end 180.252624 -223.095058)
				)
				(arc
					(start 178.779424 -223.095058)
					(mid 178.770444 -223.091338)
					(end 178.766724 -223.082358)
				)
				(arc
					(start 178.766724 -222.58782)
					(mid 178.770444 -222.57884)
					(end 178.779424 -222.57512)
				)
				(arc
					(start 180.252624 -222.57512)
					(mid 180.261604 -222.57884)
					(end 180.265324 -222.58782)
				)
			)
		)
	)
	(zone
		(layer "In1.Cu")
		(hatch none 0.5)
		(connect_pads
			(clearance 0)
		)
		(min_thickness 0.25)
		(keepout
			(tracks not_allowed)
			(vias allowed)
			(pads allowed)
			(copperpour not_allowed)
			(footprints allowed)
		)
		(placement
			(enabled no)
			(sheetname "")
		)
		(fill
			(thermal_gap 0.5)
			(thermal_bridge_width 0.5)
			(island_removal_mode 0)
		)
		(polygon
			(pts
				(arc
					(start 408.288744 -397.849344)
					(mid 407.907744 -397.849344)
					(end 408.288744 -397.849344)
				)
			)
		)
	)
	(zone
		(layer "In1.Cu")
		(hatch none 0.5)
		(connect_pads
			(clearance 0)
		)
		(min_thickness 0.25)
		(keepout
			(tracks not_allowed)
			(vias allowed)
			(pads allowed)
			(copperpour not_allowed)
			(footprints allowed)
		)
		(placement
			(enabled no)
			(sheetname "")
		)
		(fill
			(thermal_gap 0.5)
			(thermal_bridge_width 0.5)
			(island_removal_mode 0)
		)
		(polygon
			(pts
				(arc
					(start 184.365392 -223.932496)
					(mid 184.361672 -223.941476)
					(end 184.352692 -223.945196)
				)
				(arc
					(start 182.879492 -223.945196)
					(mid 182.870512 -223.941476)
					(end 182.866792 -223.932496)
				)
				(arc
					(start 182.866792 -223.437958)
					(mid 182.870512 -223.428978)
					(end 182.879492 -223.425258)
				)
				(arc
					(start 184.352692 -223.425258)
					(mid 184.361672 -223.428978)
					(end 184.365392 -223.437958)
				)
			)
		)
	)
	(zone
		(layer "In1.Cu")
		(hatch none 0.5)
		(connect_pads
			(clearance 0)
		)
		(min_thickness 0.25)
		(keepout
			(tracks not_allowed)
			(vias allowed)
			(pads allowed)
			(copperpour not_allowed)
			(footprints allowed)
		)
		(placement
			(enabled no)
			(sheetname "")
		)
		(fill
			(thermal_gap 0.5)
			(thermal_bridge_width 0.5)
			(island_removal_mode 0)
		)
		(polygon
			(pts
				(arc
					(start 93.58884 -386.003292)
					(mid 93.20784 -386.003292)
					(end 93.58884 -386.003292)
				)
			)
		)
	)
	(zone
		(layer "In1.Cu")
		(hatch none 0.5)
		(connect_pads
			(clearance 0)
		)
		(min_thickness 0.25)
		(keepout
			(tracks not_allowed)
			(vias allowed)
			(pads allowed)
			(copperpour not_allowed)
			(footprints allowed)
		)
		(placement
			(enabled no)
			(sheetname "")
		)
		(fill
			(thermal_gap 0.5)
			(thermal_bridge_width 0.5)
			(island_removal_mode 0)
		)
		(polygon
			(pts
				(arc
					(start 413.117284 -202.682094)
					(mid 413.113564 -202.691074)
					(end 413.104584 -202.694794)
				)
				(arc
					(start 411.631384 -202.694794)
					(mid 411.622404 -202.691074)
					(end 411.618684 -202.682094)
				)
				(arc
					(start 411.618684 -202.187556)
					(mid 411.622404 -202.178576)
					(end 411.631384 -202.174856)
				)
				(arc
					(start 413.104584 -202.174856)
					(mid 413.113564 -202.178576)
					(end 413.117284 -202.187556)
				)
			)
		)
	)
	(zone
		(layer "In1.Cu")
		(hatch none 0.5)
		(connect_pads
			(clearance 0)
		)
		(min_thickness 0.25)
		(keepout
			(tracks not_allowed)
			(vias allowed)
			(pads allowed)
			(copperpour not_allowed)
			(footprints allowed)
		)
		(placement
			(enabled no)
			(sheetname "")
		)
		(fill
			(thermal_gap 0.5)
			(thermal_bridge_width 0.5)
			(island_removal_mode 0)
		)
		(polygon
			(pts
				(arc
					(start 191.909446 -297.032426)
					(mid 191.905726 -297.041406)
					(end 191.896746 -297.045126)
				)
				(arc
					(start 190.423546 -297.045126)
					(mid 190.414566 -297.041406)
					(end 190.410846 -297.032426)
				)
				(arc
					(start 190.410846 -296.537888)
					(mid 190.414566 -296.528908)
					(end 190.423546 -296.525188)
				)
				(arc
					(start 191.896746 -296.525188)
					(mid 191.905726 -296.528908)
					(end 191.909446 -296.537888)
				)
			)
		)
	)
	(zone
		(layer "In1.Cu")
		(hatch none 0.5)
		(connect_pads
			(clearance 0)
		)
		(min_thickness 0.25)
		(keepout
			(tracks not_allowed)
			(vias allowed)
			(pads allowed)
			(copperpour not_allowed)
			(footprints allowed)
		)
		(placement
			(enabled no)
			(sheetname "")
		)
		(fill
			(thermal_gap 0.5)
			(thermal_bridge_width 0.5)
			(island_removal_mode 0)
		)
		(polygon
			(pts
				(arc
					(start 125.361192 -388.774432)
					(mid 124.980192 -388.774432)
					(end 125.361192 -388.774432)
				)
			)
		)
	)
	(zone
		(layer "In1.Cu")
		(hatch none 0.5)
		(connect_pads
			(clearance 0)
		)
		(min_thickness 0.25)
		(keepout
			(tracks not_allowed)
			(vias allowed)
			(pads allowed)
			(copperpour not_allowed)
			(footprints allowed)
		)
		(placement
			(enabled no)
			(sheetname "")
		)
		(fill
			(thermal_gap 0.5)
			(thermal_bridge_width 0.5)
			(island_removal_mode 0)
		)
		(polygon
			(pts
				(arc
					(start 48.533304 -301.282354)
					(mid 48.529584 -301.291334)
					(end 48.520604 -301.295054)
				)
				(arc
					(start 47.047404 -301.295054)
					(mid 47.038424 -301.291334)
					(end 47.034704 -301.282354)
				)
				(arc
					(start 47.034704 -300.787816)
					(mid 47.038424 -300.778836)
					(end 47.047404 -300.775116)
				)
				(arc
					(start 48.520604 -300.775116)
					(mid 48.529584 -300.778836)
					(end 48.533304 -300.787816)
				)
			)
		)
	)
	(zone
		(layer "In1.Cu")
		(hatch none 0.5)
		(connect_pads
			(clearance 0)
		)
		(min_thickness 0.25)
		(keepout
			(tracks not_allowed)
			(vias allowed)
			(pads allowed)
			(copperpour not_allowed)
			(footprints allowed)
		)
		(placement
			(enabled no)
			(sheetname "")
		)
		(fill
			(thermal_gap 0.5)
			(thermal_bridge_width 0.5)
			(island_removal_mode 0)
		)
		(polygon
			(pts
				(arc
					(start 413.117284 -234.13212)
					(mid 413.113564 -234.1411)
					(end 413.104584 -234.14482)
				)
				(arc
					(start 411.631384 -234.14482)
					(mid 411.622404 -234.1411)
					(end 411.618684 -234.13212)
				)
				(arc
					(start 411.618684 -233.637582)
					(mid 411.622404 -233.628602)
					(end 411.631384 -233.624882)
				)
				(arc
					(start 413.104584 -233.624882)
					(mid 413.113564 -233.628602)
					(end 413.117284 -233.637582)
				)
			)
		)
	)
	(zone
		(layer "In1.Cu")
		(hatch none 0.5)
		(connect_pads
			(clearance 0)
		)
		(min_thickness 0.25)
		(keepout
			(tracks not_allowed)
			(vias allowed)
			(pads allowed)
			(copperpour not_allowed)
			(footprints allowed)
		)
		(placement
			(enabled no)
			(sheetname "")
		)
		(fill
			(thermal_gap 0.5)
			(thermal_bridge_width 0.5)
			(island_removal_mode 0)
		)
		(polygon
			(pts
				(arc
					(start 420.661338 -262.182102)
					(mid 420.657618 -262.191082)
					(end 420.648638 -262.194802)
				)
				(arc
					(start 419.175438 -262.194802)
					(mid 419.166458 -262.191082)
					(end 419.162738 -262.182102)
				)
				(arc
					(start 419.162738 -261.687564)
					(mid 419.166458 -261.678584)
					(end 419.175438 -261.674864)
				)
				(arc
					(start 420.648638 -261.674864)
					(mid 420.657618 -261.678584)
					(end 420.661338 -261.687564)
				)
			)
		)
	)
	(zone
		(layer "In1.Cu")
		(hatch none 0.5)
		(connect_pads
			(clearance 0)
		)
		(min_thickness 0.25)
		(keepout
			(tracks not_allowed)
			(vias allowed)
			(pads allowed)
			(copperpour not_allowed)
			(footprints allowed)
		)
		(placement
			(enabled no)
			(sheetname "")
		)
		(fill
			(thermal_gap 0.5)
			(thermal_bridge_width 0.5)
			(island_removal_mode 0)
		)
		(polygon
			(pts
				(arc
					(start 351.588832 -397.156432)
					(mid 351.207832 -397.156432)
					(end 351.588832 -397.156432)
				)
			)
		)
	)
	(zone
		(layer "In1.Cu")
		(hatch none 0.5)
		(connect_pads
			(clearance 0)
		)
		(min_thickness 0.25)
		(keepout
			(tracks not_allowed)
			(vias allowed)
			(pads allowed)
			(copperpour not_allowed)
			(footprints allowed)
		)
		(placement
			(enabled no)
			(sheetname "")
		)
		(fill
			(thermal_gap 0.5)
			(thermal_bridge_width 0.5)
			(island_removal_mode 0)
		)
		(polygon
			(pts
				(arc
					(start 304.017426 -202.682094)
					(mid 304.013706 -202.691074)
					(end 304.004726 -202.694794)
				)
				(arc
					(start 302.531526 -202.694794)
					(mid 302.522546 -202.691074)
					(end 302.518826 -202.682094)
				)
				(arc
					(start 302.518826 -202.187556)
					(mid 302.522546 -202.178576)
					(end 302.531526 -202.174856)
				)
				(arc
					(start 304.004726 -202.174856)
					(mid 304.013706 -202.178576)
					(end 304.017426 -202.187556)
				)
			)
		)
	)
	(zone
		(layer "In1.Cu")
		(hatch none 0.5)
		(connect_pads
			(clearance 0)
		)
		(min_thickness 0.25)
		(keepout
			(tracks not_allowed)
			(vias allowed)
			(pads allowed)
			(copperpour not_allowed)
			(footprints allowed)
		)
		(placement
			(enabled no)
			(sheetname "")
		)
		(fill
			(thermal_gap 0.5)
			(thermal_bridge_width 0.5)
			(island_removal_mode 0)
		)
		(polygon
			(pts
				(arc
					(start 413.117284 -265.582146)
					(mid 413.113564 -265.591126)
					(end 413.104584 -265.594846)
				)
				(arc
					(start 411.631384 -265.594846)
					(mid 411.622404 -265.591126)
					(end 411.618684 -265.582146)
				)
				(arc
					(start 411.618684 -265.087608)
					(mid 411.622404 -265.078628)
					(end 411.631384 -265.074908)
				)
				(arc
					(start 413.104584 -265.074908)
					(mid 413.113564 -265.078628)
					(end 413.117284 -265.087608)
				)
			)
		)
	)
	(zone
		(layer "In1.Cu")
		(hatch none 0.5)
		(connect_pads
			(clearance 0)
		)
		(min_thickness 0.25)
		(keepout
			(tracks not_allowed)
			(vias allowed)
			(pads allowed)
			(copperpour not_allowed)
			(footprints allowed)
		)
		(placement
			(enabled no)
			(sheetname "")
		)
		(fill
			(thermal_gap 0.5)
			(thermal_bridge_width 0.5)
			(island_removal_mode 0)
		)
		(polygon
			(pts
				(arc
					(start 18.357342 -217.132408)
					(mid 18.353622 -217.141388)
					(end 18.344642 -217.145108)
				)
				(arc
					(start 16.871442 -217.145108)
					(mid 16.862462 -217.141388)
					(end 16.858742 -217.132408)
				)
				(arc
					(start 16.858742 -216.63787)
					(mid 16.862462 -216.62889)
					(end 16.871442 -216.62517)
				)
				(arc
					(start 18.344642 -216.62517)
					(mid 18.353622 -216.62889)
					(end 18.357342 -216.63787)
				)
			)
		)
	)
	(zone
		(layer "In1.Cu")
		(hatch none 0.5)
		(connect_pads
			(clearance 0)
		)
		(min_thickness 0.25)
		(keepout
			(tracks not_allowed)
			(vias allowed)
			(pads allowed)
			(copperpour not_allowed)
			(footprints allowed)
		)
		(placement
			(enabled no)
			(sheetname "")
		)
		(fill
			(thermal_gap 0.5)
			(thermal_bridge_width 0.5)
			(island_removal_mode 0)
		)
		(polygon
			(pts
				(arc
					(start 450.8373 -251.982224)
					(mid 450.83358 -251.991204)
					(end 450.8246 -251.994924)
				)
				(arc
					(start 449.3514 -251.994924)
					(mid 449.34242 -251.991204)
					(end 449.3387 -251.982224)
				)
				(arc
					(start 449.3387 -251.487686)
					(mid 449.34242 -251.478706)
					(end 449.3514 -251.474986)
				)
				(arc
					(start 450.8246 -251.474986)
					(mid 450.83358 -251.478706)
					(end 450.8373 -251.487686)
				)
			)
		)
	)
	(zone
		(layer "In1.Cu")
		(hatch none 0.5)
		(connect_pads
			(clearance 0)
		)
		(min_thickness 0.25)
		(keepout
			(tracks not_allowed)
			(vias allowed)
			(pads allowed)
			(copperpour not_allowed)
			(footprints allowed)
		)
		(placement
			(enabled no)
			(sheetname "")
		)
		(fill
			(thermal_gap 0.5)
			(thermal_bridge_width 0.5)
			(island_removal_mode 0)
		)
		(polygon
			(pts
				(arc
					(start 300.57344 -225.632264)
					(mid 300.56972 -225.641244)
					(end 300.56074 -225.644964)
				)
				(arc
					(start 299.08754 -225.644964)
					(mid 299.07856 -225.641244)
					(end 299.07484 -225.632264)
				)
				(arc
					(start 299.07484 -225.137726)
					(mid 299.07856 -225.128746)
					(end 299.08754 -225.125026)
				)
				(arc
					(start 300.56074 -225.125026)
					(mid 300.56972 -225.128746)
					(end 300.57344 -225.137726)
				)
			)
		)
	)
	(zone
		(layer "In1.Cu")
		(hatch none 0.5)
		(connect_pads
			(clearance 0)
		)
		(min_thickness 0.25)
		(keepout
			(tracks not_allowed)
			(vias allowed)
			(pads allowed)
			(copperpour not_allowed)
			(footprints allowed)
		)
		(placement
			(enabled no)
			(sheetname "")
		)
		(fill
			(thermal_gap 0.5)
			(thermal_bridge_width 0.5)
			(island_removal_mode 0)
		)
		(polygon
			(pts
				(arc
					(start 37.545264 -281.732482)
					(mid 37.541544 -281.741462)
					(end 37.532564 -281.745182)
				)
				(arc
					(start 36.059364 -281.745182)
					(mid 36.050384 -281.741462)
					(end 36.046664 -281.732482)
				)
				(arc
					(start 36.046664 -281.237944)
					(mid 36.050384 -281.228964)
					(end 36.059364 -281.225244)
				)
				(arc
					(start 37.532564 -281.225244)
					(mid 37.541544 -281.228964)
					(end 37.545264 -281.237944)
				)
			)
		)
	)
	(zone
		(layer "In1.Cu")
		(hatch none 0.5)
		(connect_pads
			(clearance 0)
		)
		(min_thickness 0.25)
		(keepout
			(tracks not_allowed)
			(vias allowed)
			(pads allowed)
			(copperpour not_allowed)
			(footprints allowed)
		)
		(placement
			(enabled no)
			(sheetname "")
		)
		(fill
			(thermal_gap 0.5)
			(thermal_bridge_width 0.5)
			(island_removal_mode 0)
		)
		(polygon
			(pts
				(arc
					(start 308.117494 -268.132306)
					(mid 308.113774 -268.141286)
					(end 308.104794 -268.145006)
				)
				(arc
					(start 306.631594 -268.145006)
					(mid 306.622614 -268.141286)
					(end 306.618894 -268.132306)
				)
				(arc
					(start 306.618894 -267.637768)
					(mid 306.622614 -267.628788)
					(end 306.631594 -267.625068)
				)
				(arc
					(start 308.104794 -267.625068)
					(mid 308.113774 -267.628788)
					(end 308.117494 -267.637768)
				)
			)
		)
	)
	(zone
		(layer "In1.Cu")
		(hatch none 0.5)
		(connect_pads
			(clearance 0)
		)
		(min_thickness 0.25)
		(keepout
			(tracks not_allowed)
			(vias allowed)
			(pads allowed)
			(copperpour not_allowed)
			(footprints allowed)
		)
		(placement
			(enabled no)
			(sheetname "")
		)
		(fill
			(thermal_gap 0.5)
			(thermal_bridge_width 0.5)
			(island_removal_mode 0)
		)
		(polygon
			(pts
				(arc
					(start 424.761406 -236.68228)
					(mid 424.757686 -236.69126)
					(end 424.748706 -236.69498)
				)
				(arc
					(start 423.275506 -236.69498)
					(mid 423.266526 -236.69126)
					(end 423.262806 -236.68228)
				)
				(arc
					(start 423.262806 -236.187742)
					(mid 423.266526 -236.178762)
					(end 423.275506 -236.175042)
				)
				(arc
					(start 424.748706 -236.175042)
					(mid 424.757686 -236.178762)
					(end 424.761406 -236.187742)
				)
			)
		)
	)
	(zone
		(layer "In1.Cu")
		(hatch none 0.5)
		(connect_pads
			(clearance 0)
		)
		(min_thickness 0.25)
		(keepout
			(tracks not_allowed)
			(vias allowed)
			(pads allowed)
			(copperpour not_allowed)
			(footprints allowed)
		)
		(placement
			(enabled no)
			(sheetname "")
		)
		(fill
			(thermal_gap 0.5)
			(thermal_bridge_width 0.5)
			(island_removal_mode 0)
		)
		(polygon
			(pts
				(arc
					(start 124.270262 -390.761474)
					(mid 123.965462 -390.761474)
					(end 124.270262 -390.761474)
				)
			)
		)
	)
	(zone
		(layer "In1.Cu")
		(hatch none 0.5)
		(connect_pads
			(clearance 0)
		)
		(min_thickness 0.25)
		(keepout
			(tracks not_allowed)
			(vias allowed)
			(pads allowed)
			(copperpour not_allowed)
			(footprints allowed)
		)
		(placement
			(enabled no)
			(sheetname "")
		)
		(fill
			(thermal_gap 0.5)
			(thermal_bridge_width 0.5)
			(island_removal_mode 0)
		)
		(polygon
			(pts
				(arc
					(start 416.862514 -7.672324)
					(mid 416.884832 -7.618442)
					(end 416.938714 -7.596124)
				)
				(arc
					(start 417.975288 -7.596124)
					(mid 418.02917 -7.618442)
					(end 418.051488 -7.672324)
				)
				(arc
					(start 418.051488 -9.071864)
					(mid 418.02917 -9.125746)
					(end 417.975288 -9.148064)
				)
				(arc
					(start 416.938714 -9.148064)
					(mid 416.884832 -9.125746)
					(end 416.862514 -9.071864)
				)
			)
		)
	)
	(zone
		(layer "In1.Cu")
		(hatch none 0.5)
		(connect_pads
			(clearance 0)
		)
		(min_thickness 0.25)
		(keepout
			(tracks not_allowed)
			(vias allowed)
			(pads allowed)
			(copperpour not_allowed)
			(footprints allowed)
		)
		(placement
			(enabled no)
			(sheetname "")
		)
		(fill
			(thermal_gap 0.5)
			(thermal_bridge_width 0.5)
			(island_removal_mode 0)
		)
		(polygon
			(pts
				(arc
					(start 306.260754 -397.849344)
					(mid 305.879754 -397.849344)
					(end 306.260754 -397.849344)
				)
			)
		)
	)
	(zone
		(layer "In1.Cu")
		(hatch none 0.5)
		(connect_pads
			(clearance 0)
		)
		(min_thickness 0.25)
		(keepout
			(tracks not_allowed)
			(vias allowed)
			(pads allowed)
			(copperpour not_allowed)
			(footprints allowed)
		)
		(placement
			(enabled no)
			(sheetname "")
		)
		(fill
			(thermal_gap 0.5)
			(thermal_bridge_width 0.5)
			(island_removal_mode 0)
		)
		(polygon
			(pts
				(arc
					(start 266.29741 -237.532164)
					(mid 266.29369 -237.541144)
					(end 266.28471 -237.544864)
				)
				(arc
					(start 264.81151 -237.544864)
					(mid 264.80253 -237.541144)
					(end 264.79881 -237.532164)
				)
				(arc
					(start 264.79881 -237.037626)
					(mid 264.80253 -237.028646)
					(end 264.81151 -237.024926)
				)
				(arc
					(start 266.28471 -237.024926)
					(mid 266.29369 -237.028646)
					(end 266.29741 -237.037626)
				)
			)
		)
	)
	(zone
		(layer "In1.Cu")
		(hatch none 0.5)
		(connect_pads
			(clearance 0)
		)
		(min_thickness 0.25)
		(keepout
			(tracks not_allowed)
			(vias allowed)
			(pads allowed)
			(copperpour not_allowed)
			(footprints allowed)
		)
		(placement
			(enabled no)
			(sheetname "")
		)
		(fill
			(thermal_gap 0.5)
			(thermal_bridge_width 0.5)
			(island_removal_mode 0)
		)
		(polygon
			(pts
				(arc
					(start 172.72127 -282.582366)
					(mid 172.71755 -282.591346)
					(end 172.70857 -282.595066)
				)
				(arc
					(start 171.23537 -282.595066)
					(mid 171.22639 -282.591346)
					(end 171.22267 -282.582366)
				)
				(arc
					(start 171.22267 -282.087828)
					(mid 171.22639 -282.078848)
					(end 171.23537 -282.075128)
				)
				(arc
					(start 172.70857 -282.075128)
					(mid 172.71755 -282.078848)
					(end 172.72127 -282.087828)
				)
			)
		)
	)
	(zone
		(layer "In1.Cu")
		(hatch none 0.5)
		(connect_pads
			(clearance 0)
		)
		(min_thickness 0.25)
		(keepout
			(tracks not_allowed)
			(vias allowed)
			(pads allowed)
			(copperpour not_allowed)
			(footprints allowed)
		)
		(placement
			(enabled no)
			(sheetname "")
		)
		(fill
			(thermal_gap 0.5)
			(thermal_bridge_width 0.5)
			(island_removal_mode 0)
		)
		(polygon
			(pts
				(arc
					(start 153.089102 -385.31038)
					(mid 152.708102 -385.31038)
					(end 153.089102 -385.31038)
				)
			)
		)
	)
	(zone
		(layer "In1.Cu")
		(hatch none 0.5)
		(connect_pads
			(clearance 0)
		)
		(min_thickness 0.25)
		(keepout
			(tracks not_allowed)
			(vias allowed)
			(pads allowed)
			(copperpour not_allowed)
			(footprints allowed)
		)
		(placement
			(enabled no)
			(sheetname "")
		)
		(fill
			(thermal_gap 0.5)
			(thermal_bridge_width 0.5)
			(island_removal_mode 0)
		)
		(polygon
			(pts
				(arc
					(start 419.41877 -399.701258)
					(mid 419.54577 -399.828258)
					(end 419.67277 -399.701258)
				)
				(arc
					(start 419.67277 -399.625058)
					(mid 419.54577 -399.498058)
					(end 419.41877 -399.625058)
				)
			)
		)
	)
	(zone
		(layer "In1.Cu")
		(hatch none 0.5)
		(connect_pads
			(clearance 0)
		)
		(min_thickness 0.25)
		(keepout
			(tracks not_allowed)
			(vias allowed)
			(pads allowed)
			(copperpour not_allowed)
			(footprints allowed)
		)
		(placement
			(enabled no)
			(sheetname "")
		)
		(fill
			(thermal_gap 0.5)
			(thermal_bridge_width 0.5)
			(island_removal_mode 0)
		)
		(polygon
			(pts
				(arc
					(start 22.45741 -227.33254)
					(mid 22.45369 -227.34152)
					(end 22.44471 -227.34524)
				)
				(arc
					(start 20.97151 -227.34524)
					(mid 20.96253 -227.34152)
					(end 20.95881 -227.33254)
				)
				(arc
					(start 20.95881 -226.838002)
					(mid 20.96253 -226.829022)
					(end 20.97151 -226.825302)
				)
				(arc
					(start 22.44471 -226.825302)
					(mid 22.45369 -226.829022)
					(end 22.45741 -226.838002)
				)
			)
		)
	)
	(zone
		(layer "In1.Cu")
		(hatch none 0.5)
		(connect_pads
			(clearance 0)
		)
		(min_thickness 0.25)
		(keepout
			(tracks not_allowed)
			(vias allowed)
			(pads allowed)
			(copperpour not_allowed)
			(footprints allowed)
		)
		(placement
			(enabled no)
			(sheetname "")
		)
		(fill
			(thermal_gap 0.5)
			(thermal_bridge_width 0.5)
			(island_removal_mode 0)
		)
		(polygon
			(pts
				(arc
					(start 281.385264 -265.582146)
					(mid 281.381544 -265.591126)
					(end 281.372564 -265.594846)
				)
				(arc
					(start 279.899364 -265.594846)
					(mid 279.890384 -265.591126)
					(end 279.886664 -265.582146)
				)
				(arc
					(start 279.886664 -265.087608)
					(mid 279.890384 -265.078628)
					(end 279.899364 -265.074908)
				)
				(arc
					(start 281.372564 -265.074908)
					(mid 281.381544 -265.078628)
					(end 281.385264 -265.087608)
				)
			)
		)
	)
	(zone
		(layer "In1.Cu")
		(hatch none 0.5)
		(connect_pads
			(clearance 0)
		)
		(min_thickness 0.25)
		(keepout
			(tracks not_allowed)
			(vias allowed)
			(pads allowed)
			(copperpour not_allowed)
			(footprints allowed)
		)
		(placement
			(enabled no)
			(sheetname "")
		)
		(fill
			(thermal_gap 0.5)
			(thermal_bridge_width 0.5)
			(island_removal_mode 0)
		)
		(polygon
			(pts
				(arc
					(start 180.265324 -212.032342)
					(mid 180.261604 -212.041322)
					(end 180.252624 -212.045042)
				)
				(arc
					(start 178.779424 -212.045042)
					(mid 178.770444 -212.041322)
					(end 178.766724 -212.032342)
				)
				(arc
					(start 178.766724 -211.537804)
					(mid 178.770444 -211.528824)
					(end 178.779424 -211.525104)
				)
				(arc
					(start 180.252624 -211.525104)
					(mid 180.261604 -211.528824)
					(end 180.265324 -211.537804)
				)
			)
		)
	)
	(zone
		(layer "In1.Cu")
		(hatch none 0.5)
		(connect_pads
			(clearance 0)
		)
		(min_thickness 0.25)
		(keepout
			(tracks not_allowed)
			(vias allowed)
			(pads allowed)
			(copperpour not_allowed)
			(footprints allowed)
		)
		(placement
			(enabled no)
			(sheetname "")
		)
		(fill
			(thermal_gap 0.5)
			(thermal_bridge_width 0.5)
			(island_removal_mode 0)
		)
		(polygon
			(pts
				(arc
					(start 125.470412 -390.761474)
					(mid 125.165612 -390.761474)
					(end 125.470412 -390.761474)
				)
			)
		)
	)
	(zone
		(layer "In1.Cu")
		(hatch none 0.5)
		(connect_pads
			(clearance 0)
		)
		(min_thickness 0.25)
		(keepout
			(tracks not_allowed)
			(vias allowed)
			(pads allowed)
			(copperpour not_allowed)
			(footprints allowed)
		)
		(placement
			(enabled no)
			(sheetname "")
		)
		(fill
			(thermal_gap 0.5)
			(thermal_bridge_width 0.5)
			(island_removal_mode 0)
		)
		(polygon
			(pts
				(arc
					(start 435.749446 -240.082324)
					(mid 435.745726 -240.091304)
					(end 435.736746 -240.095024)
				)
				(arc
					(start 434.263546 -240.095024)
					(mid 434.254566 -240.091304)
					(end 434.250846 -240.082324)
				)
				(arc
					(start 434.250846 -239.587786)
					(mid 434.254566 -239.578806)
					(end 434.263546 -239.575086)
				)
				(arc
					(start 435.736746 -239.575086)
					(mid 435.745726 -239.578806)
					(end 435.749446 -239.587786)
				)
			)
		)
	)
	(zone
		(layer "In1.Cu")
		(hatch none 0.5)
		(connect_pads
			(clearance 0)
		)
		(min_thickness 0.25)
		(keepout
			(tracks not_allowed)
			(vias allowed)
			(pads allowed)
			(copperpour not_allowed)
			(footprints allowed)
		)
		(placement
			(enabled no)
			(sheetname "")
		)
		(fill
			(thermal_gap 0.5)
			(thermal_bridge_width 0.5)
			(island_removal_mode 0)
		)
		(polygon
			(pts
				(arc
					(start 447.393568 -240.932208)
					(mid 447.389848 -240.941188)
					(end 447.380868 -240.944908)
				)
				(arc
					(start 445.907668 -240.944908)
					(mid 445.898688 -240.941188)
					(end 445.894968 -240.932208)
				)
				(arc
					(start 445.894968 -240.43767)
					(mid 445.898688 -240.42869)
					(end 445.907668 -240.42497)
				)
				(arc
					(start 447.380868 -240.42497)
					(mid 447.389848 -240.42869)
					(end 447.393568 -240.43767)
				)
			)
		)
	)
	(zone
		(layer "In1.Cu")
		(hatch none 0.5)
		(connect_pads
			(clearance 0)
		)
		(min_thickness 0.25)
		(keepout
			(tracks not_allowed)
			(vias allowed)
			(pads allowed)
			(copperpour not_allowed)
			(footprints allowed)
		)
		(placement
			(enabled no)
			(sheetname "")
		)
		(fill
			(thermal_gap 0.5)
			(thermal_bridge_width 0.5)
			(island_removal_mode 0)
		)
		(polygon
			(pts
				(arc
					(start 270.397478 -280.032206)
					(mid 270.393758 -280.041186)
					(end 270.384778 -280.044906)
				)
				(arc
					(start 268.911578 -280.044906)
					(mid 268.902598 -280.041186)
					(end 268.898878 -280.032206)
				)
				(arc
					(start 268.898878 -279.537668)
					(mid 268.902598 -279.528688)
					(end 268.911578 -279.524968)
				)
				(arc
					(start 270.384778 -279.524968)
					(mid 270.393758 -279.528688)
					(end 270.397478 -279.537668)
				)
			)
		)
	)
	(zone
		(layer "In1.Cu")
		(hatch none 0.5)
		(connect_pads
			(clearance 0)
		)
		(min_thickness 0.25)
		(keepout
			(tracks not_allowed)
			(vias allowed)
			(pads allowed)
			(copperpour not_allowed)
			(footprints allowed)
		)
		(placement
			(enabled no)
			(sheetname "")
		)
		(fill
			(thermal_gap 0.5)
			(thermal_bridge_width 0.5)
			(island_removal_mode 0)
		)
		(polygon
			(pts
				(arc
					(start 65.270634 -385.11988)
					(mid 65.270634 -385.50088)
					(end 65.270634 -385.11988)
				)
			)
		)
	)
	(zone
		(layer "In1.Cu")
		(hatch none 0.5)
		(connect_pads
			(clearance 0)
		)
		(min_thickness 0.25)
		(keepout
			(tracks not_allowed)
			(vias allowed)
			(pads allowed)
			(copperpour not_allowed)
			(footprints allowed)
		)
		(placement
			(enabled no)
			(sheetname "")
		)
		(fill
			(thermal_gap 0.5)
			(thermal_bridge_width 0.5)
			(island_removal_mode 0)
		)
		(polygon
			(pts
				(arc
					(start 383.29108 -399.701258)
					(mid 383.41808 -399.828258)
					(end 383.54508 -399.701258)
				)
				(arc
					(start 383.54508 -399.625058)
					(mid 383.41808 -399.498058)
					(end 383.29108 -399.625058)
				)
			)
		)
	)
	(zone
		(layer "In1.Cu")
		(hatch none 0.5)
		(connect_pads
			(clearance 0)
		)
		(min_thickness 0.25)
		(keepout
			(tracks not_allowed)
			(vias allowed)
			(pads allowed)
			(copperpour not_allowed)
			(footprints allowed)
		)
		(placement
			(enabled no)
			(sheetname "")
		)
		(fill
			(thermal_gap 0.5)
			(thermal_bridge_width 0.5)
			(island_removal_mode 0)
		)
		(polygon
			(pts
				(arc
					(start 304.017426 -207.78216)
					(mid 304.013706 -207.79114)
					(end 304.004726 -207.79486)
				)
				(arc
					(start 302.531526 -207.79486)
					(mid 302.522546 -207.79114)
					(end 302.518826 -207.78216)
				)
				(arc
					(start 302.518826 -207.287622)
					(mid 302.522546 -207.278642)
					(end 302.531526 -207.274922)
				)
				(arc
					(start 304.004726 -207.274922)
					(mid 304.013706 -207.278642)
					(end 304.017426 -207.287622)
				)
			)
		)
	)
	(zone
		(layer "In1.Cu")
		(hatch none 0.5)
		(connect_pads
			(clearance 0)
		)
		(min_thickness 0.25)
		(keepout
			(tracks not_allowed)
			(vias allowed)
			(pads allowed)
			(copperpour not_allowed)
			(footprints allowed)
		)
		(placement
			(enabled no)
			(sheetname "")
		)
		(fill
			(thermal_gap 0.5)
			(thermal_bridge_width 0.5)
			(island_removal_mode 0)
		)
		(polygon
			(pts
				(arc
					(start 43.561508 -16.443198)
					(mid 43.583826 -16.49708)
					(end 43.637708 -16.519398)
				)
				(arc
					(start 43.833288 -16.519398)
					(mid 43.855164 -16.516266)
					(end 43.875198 -16.506952)
				)
				(arc
					(start 44.168822 -16.31442)
					(mid 44.210478 -16.302018)
					(end 44.252134 -16.31442)
				)
				(arc
					(start 44.547028 -16.506952)
					(mid 44.566952 -16.516188)
					(end 44.588684 -16.519398)
				)
				(arc
					(start 44.783248 -16.519398)
					(mid 44.83713 -16.49708)
					(end 44.859448 -16.443198)
				)
				(arc
					(start 44.859448 -15.757398)
					(mid 44.83713 -15.703516)
					(end 44.783248 -15.681198)
				)
				(arc
					(start 44.588684 -15.681198)
					(mid 44.56694 -15.684366)
					(end 44.547028 -15.693644)
				)
				(arc
					(start 44.250864 -15.88643)
					(mid 44.20918 -15.898652)
					(end 44.167552 -15.886176)
				)
				(arc
					(start 43.873928 -15.693644)
					(mid 43.854004 -15.684408)
					(end 43.832272 -15.681198)
				)
				(arc
					(start 43.637708 -15.681198)
					(mid 43.583826 -15.703516)
					(end 43.561508 -15.757398)
				)
			)
		)
	)
	(zone
		(layer "In1.Cu")
		(hatch none 0.5)
		(connect_pads
			(clearance 0)
		)
		(min_thickness 0.25)
		(keepout
			(tracks not_allowed)
			(vias allowed)
			(pads allowed)
			(copperpour not_allowed)
			(footprints allowed)
		)
		(placement
			(enabled no)
			(sheetname "")
		)
		(fill
			(thermal_gap 0.5)
			(thermal_bridge_width 0.5)
			(island_removal_mode 0)
		)
		(polygon
			(pts
				(arc
					(start 33.445196 -295.332404)
					(mid 33.441476 -295.341384)
					(end 33.432496 -295.345104)
				)
				(arc
					(start 31.959296 -295.345104)
					(mid 31.950316 -295.341384)
					(end 31.946596 -295.332404)
				)
				(arc
					(start 31.946596 -294.837866)
					(mid 31.950316 -294.828886)
					(end 31.959296 -294.825166)
				)
				(arc
					(start 33.432496 -294.825166)
					(mid 33.441476 -294.828886)
					(end 33.445196 -294.837866)
				)
			)
		)
	)
	(zone
		(layer "In1.Cu")
		(hatch none 0.5)
		(connect_pads
			(clearance 0)
		)
		(min_thickness 0.25)
		(keepout
			(tracks not_allowed)
			(vias allowed)
			(pads allowed)
			(copperpour not_allowed)
			(footprints allowed)
		)
		(placement
			(enabled no)
			(sheetname "")
		)
		(fill
			(thermal_gap 0.5)
			(thermal_bridge_width 0.5)
			(island_removal_mode 0)
		)
		(polygon
			(pts
				(arc
					(start 206.5782 -313.78525)
					(mid 205.9178 -313.78525)
					(end 206.5782 -313.78525)
				)
			)
		)
	)
	(zone
		(layer "In1.Cu")
		(hatch none 0.5)
		(connect_pads
			(clearance 0)
		)
		(min_thickness 0.25)
		(keepout
			(tracks not_allowed)
			(vias allowed)
			(pads allowed)
			(copperpour not_allowed)
			(footprints allowed)
		)
		(placement
			(enabled no)
			(sheetname "")
		)
		(fill
			(thermal_gap 0.5)
			(thermal_bridge_width 0.5)
			(island_removal_mode 0)
		)
		(polygon
			(pts
				(arc
					(start 48.533304 -277.482554)
					(mid 48.529584 -277.491534)
					(end 48.520604 -277.495254)
				)
				(arc
					(start 47.047404 -277.495254)
					(mid 47.038424 -277.491534)
					(end 47.034704 -277.482554)
				)
				(arc
					(start 47.034704 -276.988016)
					(mid 47.038424 -276.979036)
					(end 47.047404 -276.975316)
				)
				(arc
					(start 48.520604 -276.975316)
					(mid 48.529584 -276.979036)
					(end 48.533304 -276.988016)
				)
			)
		)
	)
	(zone
		(layer "In1.Cu")
		(hatch none 0.5)
		(connect_pads
			(clearance 0)
		)
		(min_thickness 0.25)
		(keepout
			(tracks not_allowed)
			(vias allowed)
			(pads allowed)
			(copperpour not_allowed)
			(footprints allowed)
		)
		(placement
			(enabled no)
			(sheetname "")
		)
		(fill
			(thermal_gap 0.5)
			(thermal_bridge_width 0.5)
			(island_removal_mode 0)
		)
		(polygon
			(pts
				(arc
					(start 199.4535 -302.132492)
					(mid 199.44978 -302.141472)
					(end 199.4408 -302.145192)
				)
				(arc
					(start 197.9676 -302.145192)
					(mid 197.95862 -302.141472)
					(end 197.9549 -302.132492)
				)
				(arc
					(start 197.9549 -301.637954)
					(mid 197.95862 -301.628974)
					(end 197.9676 -301.625254)
				)
				(arc
					(start 199.4408 -301.625254)
					(mid 199.44978 -301.628974)
					(end 199.4535 -301.637954)
				)
			)
		)
	)
	(zone
		(layer "In1.Cu")
		(hatch none 0.5)
		(connect_pads
			(clearance 0)
		)
		(min_thickness 0.25)
		(keepout
			(tracks not_allowed)
			(vias allowed)
			(pads allowed)
			(copperpour not_allowed)
			(footprints allowed)
		)
		(placement
			(enabled no)
			(sheetname "")
		)
		(fill
			(thermal_gap 0.5)
			(thermal_bridge_width 0.5)
			(island_removal_mode 0)
		)
		(polygon
			(pts
				(arc
					(start 413.117284 -212.032088)
					(mid 413.113564 -212.041068)
					(end 413.104584 -212.044788)
				)
				(arc
					(start 411.631384 -212.044788)
					(mid 411.622404 -212.041068)
					(end 411.618684 -212.032088)
				)
				(arc
					(start 411.618684 -211.53755)
					(mid 411.622404 -211.52857)
					(end 411.631384 -211.52485)
				)
				(arc
					(start 413.104584 -211.52485)
					(mid 413.113564 -211.52857)
					(end 413.117284 -211.53755)
				)
			)
		)
	)
	(zone
		(layer "In1.Cu")
		(hatch none 0.5)
		(connect_pads
			(clearance 0)
		)
		(min_thickness 0.25)
		(keepout
			(tracks not_allowed)
			(vias allowed)
			(pads allowed)
			(copperpour not_allowed)
			(footprints allowed)
		)
		(placement
			(enabled no)
			(sheetname "")
		)
		(fill
			(thermal_gap 0.5)
			(thermal_bridge_width 0.5)
			(island_removal_mode 0)
		)
		(polygon
			(pts
				(arc
					(start 180.265324 -218.83243)
					(mid 180.261604 -218.84141)
					(end 180.252624 -218.84513)
				)
				(arc
					(start 178.779424 -218.84513)
					(mid 178.770444 -218.84141)
					(end 178.766724 -218.83243)
				)
				(arc
					(start 178.766724 -218.337892)
					(mid 178.770444 -218.328912)
					(end 178.779424 -218.325192)
				)
				(arc
					(start 180.252624 -218.325192)
					(mid 180.261604 -218.328912)
					(end 180.265324 -218.337892)
				)
			)
		)
	)
	(zone
		(layer "In1.Cu")
		(hatch none 0.5)
		(connect_pads
			(clearance 0)
		)
		(min_thickness 0.25)
		(keepout
			(tracks not_allowed)
			(vias allowed)
			(pads allowed)
			(copperpour not_allowed)
			(footprints allowed)
		)
		(placement
			(enabled no)
			(sheetname "")
		)
		(fill
			(thermal_gap 0.5)
			(thermal_bridge_width 0.5)
			(island_removal_mode 0)
		)
		(polygon
			(pts
				(arc
					(start 33.445196 -243.482368)
					(mid 33.441476 -243.491348)
					(end 33.432496 -243.495068)
				)
				(arc
					(start 31.959296 -243.495068)
					(mid 31.950316 -243.491348)
					(end 31.946596 -243.482368)
				)
				(arc
					(start 31.946596 -242.98783)
					(mid 31.950316 -242.97885)
					(end 31.959296 -242.97513)
				)
				(arc
					(start 33.432496 -242.97513)
					(mid 33.441476 -242.97885)
					(end 33.445196 -242.98783)
				)
			)
		)
	)
	(zone
		(layer "In1.Cu")
		(hatch none 0.5)
		(connect_pads
			(clearance 0)
		)
		(min_thickness 0.25)
		(keepout
			(tracks not_allowed)
			(vias allowed)
			(pads allowed)
			(copperpour not_allowed)
			(footprints allowed)
		)
		(placement
			(enabled no)
			(sheetname "")
		)
		(fill
			(thermal_gap 0.5)
			(thermal_bridge_width 0.5)
			(island_removal_mode 0)
		)
		(polygon
			(pts
				(arc
					(start 81.588864 -386.003292)
					(mid 81.207864 -386.003292)
					(end 81.588864 -386.003292)
				)
			)
		)
	)
	(zone
		(layer "In1.Cu")
		(hatch none 0.5)
		(connect_pads
			(clearance 0)
		)
		(min_thickness 0.25)
		(keepout
			(tracks not_allowed)
			(vias allowed)
			(pads allowed)
			(copperpour not_allowed)
			(footprints allowed)
		)
		(placement
			(enabled no)
			(sheetname "")
		)
		(fill
			(thermal_gap 0.5)
			(thermal_bridge_width 0.5)
			(island_removal_mode 0)
		)
		(polygon
			(pts
				(arc
					(start 447.393568 -317.432182)
					(mid 447.389848 -317.441162)
					(end 447.380868 -317.444882)
				)
				(arc
					(start 445.907668 -317.444882)
					(mid 445.898688 -317.441162)
					(end 445.894968 -317.432182)
				)
				(arc
					(start 445.894968 -316.937644)
					(mid 445.898688 -316.928664)
					(end 445.907668 -316.924944)
				)
				(arc
					(start 447.380868 -316.924944)
					(mid 447.389848 -316.928664)
					(end 447.393568 -316.937644)
				)
			)
		)
	)
	(zone
		(layer "In1.Cu")
		(hatch none 0.5)
		(connect_pads
			(clearance 0)
		)
		(min_thickness 0.25)
		(keepout
			(tracks not_allowed)
			(vias allowed)
			(pads allowed)
			(copperpour not_allowed)
			(footprints allowed)
		)
		(placement
			(enabled no)
			(sheetname "")
		)
		(fill
			(thermal_gap 0.5)
			(thermal_bridge_width 0.5)
			(island_removal_mode 0)
		)
		(polygon
			(pts
				(arc
					(start 25.901396 -230.732584)
					(mid 25.897676 -230.741564)
					(end 25.888696 -230.745284)
				)
				(arc
					(start 24.415496 -230.745284)
					(mid 24.406516 -230.741564)
					(end 24.402796 -230.732584)
				)
				(arc
					(start 24.402796 -230.238046)
					(mid 24.406516 -230.229066)
					(end 24.415496 -230.225346)
				)
				(arc
					(start 25.888696 -230.225346)
					(mid 25.897676 -230.229066)
					(end 25.901396 -230.238046)
				)
			)
		)
	)
	(zone
		(layer "In1.Cu")
		(hatch none 0.5)
		(connect_pads
			(clearance 0)
		)
		(min_thickness 0.25)
		(keepout
			(tracks not_allowed)
			(vias allowed)
			(pads allowed)
			(copperpour not_allowed)
			(footprints allowed)
		)
		(placement
			(enabled no)
			(sheetname "")
		)
		(fill
			(thermal_gap 0.5)
			(thermal_bridge_width 0.5)
			(island_removal_mode 0)
		)
		(polygon
			(pts
				(arc
					(start 293.029386 -236.68228)
					(mid 293.025666 -236.69126)
					(end 293.016686 -236.69498)
				)
				(arc
					(start 291.543486 -236.69498)
					(mid 291.534506 -236.69126)
					(end 291.530786 -236.68228)
				)
				(arc
					(start 291.530786 -236.187742)
					(mid 291.534506 -236.178762)
					(end 291.543486 -236.175042)
				)
				(arc
					(start 293.016686 -236.175042)
					(mid 293.025666 -236.178762)
					(end 293.029386 -236.187742)
				)
			)
		)
	)
	(zone
		(layer "In1.Cu")
		(hatch none 0.5)
		(connect_pads
			(clearance 0)
		)
		(min_thickness 0.25)
		(keepout
			(tracks not_allowed)
			(vias allowed)
			(pads allowed)
			(copperpour not_allowed)
			(footprints allowed)
		)
		(placement
			(enabled no)
			(sheetname "")
		)
		(fill
			(thermal_gap 0.5)
			(thermal_bridge_width 0.5)
			(island_removal_mode 0)
		)
		(polygon
			(pts
				(arc
					(start 296.473372 -207.78216)
					(mid 296.469652 -207.79114)
					(end 296.460672 -207.79486)
				)
				(arc
					(start 294.987472 -207.79486)
					(mid 294.978492 -207.79114)
					(end 294.974772 -207.78216)
				)
				(arc
					(start 294.974772 -207.287622)
					(mid 294.978492 -207.278642)
					(end 294.987472 -207.274922)
				)
				(arc
					(start 296.460672 -207.274922)
					(mid 296.469652 -207.278642)
					(end 296.473372 -207.287622)
				)
			)
		)
	)
	(zone
		(layer "In1.Cu")
		(hatch none 0.5)
		(connect_pads
			(clearance 0)
		)
		(min_thickness 0.25)
		(keepout
			(tracks not_allowed)
			(vias allowed)
			(pads allowed)
			(copperpour not_allowed)
			(footprints allowed)
		)
		(placement
			(enabled no)
			(sheetname "")
		)
		(fill
			(thermal_gap 0.5)
			(thermal_bridge_width 0.5)
			(island_removal_mode 0)
		)
		(polygon
			(pts
				(arc
					(start 206.9973 -208.632552)
					(mid 206.99358 -208.641532)
					(end 206.9846 -208.645252)
				)
				(arc
					(start 205.5114 -208.645252)
					(mid 205.50242 -208.641532)
					(end 205.4987 -208.632552)
				)
				(arc
					(start 205.4987 -208.138014)
					(mid 205.50242 -208.129034)
					(end 205.5114 -208.125314)
				)
				(arc
					(start 206.9846 -208.125314)
					(mid 206.99358 -208.129034)
					(end 206.9973 -208.138014)
				)
			)
		)
	)
	(zone
		(layer "In1.Cu")
		(hatch none 0.5)
		(connect_pads
			(clearance 0)
		)
		(min_thickness 0.25)
		(keepout
			(tracks not_allowed)
			(vias allowed)
			(pads allowed)
			(copperpour not_allowed)
			(footprints allowed)
		)
		(placement
			(enabled no)
			(sheetname "")
		)
		(fill
			(thermal_gap 0.5)
			(thermal_bridge_width 0.5)
			(island_removal_mode 0)
		)
		(polygon
			(pts
				(arc
					(start 37.545264 -294.48252)
					(mid 37.541544 -294.4915)
					(end 37.532564 -294.49522)
				)
				(arc
					(start 36.059364 -294.49522)
					(mid 36.050384 -294.4915)
					(end 36.046664 -294.48252)
				)
				(arc
					(start 36.046664 -293.987982)
					(mid 36.050384 -293.979002)
					(end 36.059364 -293.975282)
				)
				(arc
					(start 37.532564 -293.975282)
					(mid 37.541544 -293.979002)
					(end 37.545264 -293.987982)
				)
			)
		)
	)
	(zone
		(layer "In1.Cu")
		(hatch none 0.5)
		(connect_pads
			(clearance 0)
		)
		(min_thickness 0.25)
		(keepout
			(tracks not_allowed)
			(vias allowed)
			(pads allowed)
			(copperpour not_allowed)
			(footprints allowed)
		)
		(placement
			(enabled no)
			(sheetname "")
		)
		(fill
			(thermal_gap 0.5)
			(thermal_bridge_width 0.5)
			(island_removal_mode 0)
		)
		(polygon
			(pts
				(arc
					(start 266.29741 -206.082138)
					(mid 266.29369 -206.091118)
					(end 266.28471 -206.094838)
				)
				(arc
					(start 264.81151 -206.094838)
					(mid 264.80253 -206.091118)
					(end 264.79881 -206.082138)
				)
				(arc
					(start 264.79881 -205.5876)
					(mid 264.80253 -205.57862)
					(end 264.81151 -205.5749)
				)
				(arc
					(start 266.28471 -205.5749)
					(mid 266.29369 -205.57862)
					(end 266.29741 -205.5876)
				)
			)
		)
	)
	(zone
		(layer "In1.Cu")
		(hatch none 0.5)
		(connect_pads
			(clearance 0)
		)
		(min_thickness 0.25)
		(keepout
			(tracks not_allowed)
			(vias allowed)
			(pads allowed)
			(copperpour not_allowed)
			(footprints allowed)
		)
		(placement
			(enabled no)
			(sheetname "")
		)
		(fill
			(thermal_gap 0.5)
			(thermal_bridge_width 0.5)
			(island_removal_mode 0)
		)
		(polygon
			(pts
				(arc
					(start 319.061084 -397.156432)
					(mid 318.680084 -397.156432)
					(end 319.061084 -397.156432)
				)
			)
		)
	)
	(zone
		(layer "In1.Cu")
		(hatch none 0.5)
		(connect_pads
			(clearance 0)
		)
		(min_thickness 0.25)
		(keepout
			(tracks not_allowed)
			(vias allowed)
			(pads allowed)
			(copperpour not_allowed)
			(footprints allowed)
		)
		(placement
			(enabled no)
			(sheetname "")
		)
		(fill
			(thermal_gap 0.5)
			(thermal_bridge_width 0.5)
			(island_removal_mode 0)
		)
		(polygon
			(pts
				(arc
					(start 404.688802 -397.849344)
					(mid 404.307802 -397.849344)
					(end 404.688802 -397.849344)
				)
			)
		)
	)
	(zone
		(layer "In1.Cu")
		(hatch none 0.5)
		(connect_pads
			(clearance 0)
		)
		(min_thickness 0.25)
		(keepout
			(tracks not_allowed)
			(vias allowed)
			(pads allowed)
			(copperpour not_allowed)
			(footprints allowed)
		)
		(placement
			(enabled no)
			(sheetname "")
		)
		(fill
			(thermal_gap 0.5)
			(thermal_bridge_width 0.5)
			(island_removal_mode 0)
		)
		(polygon
			(pts
				(arc
					(start 165.177216 -290.232592)
					(mid 165.173496 -290.241572)
					(end 165.164516 -290.245292)
				)
				(arc
					(start 163.691316 -290.245292)
					(mid 163.682336 -290.241572)
					(end 163.678616 -290.232592)
				)
				(arc
					(start 163.678616 -289.738054)
					(mid 163.682336 -289.729074)
					(end 163.691316 -289.725354)
				)
				(arc
					(start 165.164516 -289.725354)
					(mid 165.173496 -289.729074)
					(end 165.177216 -289.738054)
				)
			)
		)
	)
	(zone
		(layer "In1.Cu")
		(hatch none 0.5)
		(connect_pads
			(clearance 0)
		)
		(min_thickness 0.25)
		(keepout
			(tracks not_allowed)
			(vias allowed)
			(pads allowed)
			(copperpour not_allowed)
			(footprints allowed)
		)
		(placement
			(enabled no)
			(sheetname "")
		)
		(fill
			(thermal_gap 0.5)
			(thermal_bridge_width 0.5)
			(island_removal_mode 0)
		)
		(polygon
			(pts
				(arc
					(start 428.205392 -226.482148)
					(mid 428.201672 -226.491128)
					(end 428.192692 -226.494848)
				)
				(arc
					(start 426.719492 -226.494848)
					(mid 426.710512 -226.491128)
					(end 426.706792 -226.482148)
				)
				(arc
					(start 426.706792 -225.98761)
					(mid 426.710512 -225.97863)
					(end 426.719492 -225.97491)
				)
				(arc
					(start 428.192692 -225.97491)
					(mid 428.201672 -225.97863)
					(end 428.205392 -225.98761)
				)
			)
		)
	)
	(zone
		(layer "In1.Cu")
		(hatch none 0.5)
		(connect_pads
			(clearance 0)
		)
		(min_thickness 0.25)
		(keepout
			(tracks not_allowed)
			(vias allowed)
			(pads allowed)
			(copperpour not_allowed)
			(footprints allowed)
		)
		(placement
			(enabled no)
			(sheetname "")
		)
		(fill
			(thermal_gap 0.5)
			(thermal_bridge_width 0.5)
			(island_removal_mode 0)
		)
		(polygon
			(pts
				(arc
					(start 60.177426 -281.732482)
					(mid 60.173706 -281.741462)
					(end 60.164726 -281.745182)
				)
				(arc
					(start 58.691526 -281.745182)
					(mid 58.682546 -281.741462)
					(end 58.678826 -281.732482)
				)
				(arc
					(start 58.678826 -281.237944)
					(mid 58.682546 -281.228964)
					(end 58.691526 -281.225244)
				)
				(arc
					(start 60.164726 -281.225244)
					(mid 60.173706 -281.228964)
					(end 60.177426 -281.237944)
				)
			)
		)
	)
	(zone
		(layer "In1.Cu")
		(hatch none 0.5)
		(connect_pads
			(clearance 0)
		)
		(min_thickness 0.25)
		(keepout
			(tracks not_allowed)
			(vias allowed)
			(pads allowed)
			(copperpour not_allowed)
			(footprints allowed)
		)
		(placement
			(enabled no)
			(sheetname "")
		)
		(fill
			(thermal_gap 0.5)
			(thermal_bridge_width 0.5)
			(island_removal_mode 0)
		)
		(polygon
			(pts
				(arc
					(start 202.897232 -279.182576)
					(mid 202.893512 -279.191556)
					(end 202.884532 -279.195276)
				)
				(arc
					(start 201.411332 -279.195276)
					(mid 201.402352 -279.191556)
					(end 201.398632 -279.182576)
				)
				(arc
					(start 201.398632 -278.688038)
					(mid 201.402352 -278.679058)
					(end 201.411332 -278.675338)
				)
				(arc
					(start 202.884532 -278.675338)
					(mid 202.893512 -278.679058)
					(end 202.897232 -278.688038)
				)
			)
		)
	)
	(zone
		(layer "In1.Cu")
		(hatch none 0.5)
		(connect_pads
			(clearance 0)
		)
		(min_thickness 0.25)
		(keepout
			(tracks not_allowed)
			(vias allowed)
			(pads allowed)
			(copperpour not_allowed)
			(footprints allowed)
		)
		(placement
			(enabled no)
			(sheetname "")
		)
		(fill
			(thermal_gap 0.5)
			(thermal_bridge_width 0.5)
			(island_removal_mode 0)
		)
		(polygon
			(pts
				(arc
					(start 428.205392 -209.482182)
					(mid 428.201672 -209.491162)
					(end 428.192692 -209.494882)
				)
				(arc
					(start 426.719492 -209.494882)
					(mid 426.710512 -209.491162)
					(end 426.706792 -209.482182)
				)
				(arc
					(start 426.706792 -208.987644)
					(mid 426.710512 -208.978664)
					(end 426.719492 -208.974944)
				)
				(arc
					(start 428.192692 -208.974944)
					(mid 428.201672 -208.978664)
					(end 428.205392 -208.987644)
				)
			)
		)
	)
	(zone
		(layer "In1.Cu")
		(hatch none 0.5)
		(connect_pads
			(clearance 0)
		)
		(min_thickness 0.25)
		(keepout
			(tracks not_allowed)
			(vias allowed)
			(pads allowed)
			(copperpour not_allowed)
			(footprints allowed)
		)
		(placement
			(enabled no)
			(sheetname "")
		)
		(fill
			(thermal_gap 0.5)
			(thermal_bridge_width 0.5)
			(island_removal_mode 0)
		)
		(polygon
			(pts
				(arc
					(start 25.901396 -212.032342)
					(mid 25.897676 -212.041322)
					(end 25.888696 -212.045042)
				)
				(arc
					(start 24.415496 -212.045042)
					(mid 24.406516 -212.041322)
					(end 24.402796 -212.032342)
				)
				(arc
					(start 24.402796 -211.537804)
					(mid 24.406516 -211.528824)
					(end 24.415496 -211.525104)
				)
				(arc
					(start 25.888696 -211.525104)
					(mid 25.897676 -211.528824)
					(end 25.901396 -211.537804)
				)
			)
		)
	)
	(zone
		(layer "In1.Cu")
		(hatch none 0.5)
		(connect_pads
			(clearance 0)
		)
		(min_thickness 0.25)
		(keepout
			(tracks not_allowed)
			(vias allowed)
			(pads allowed)
			(copperpour not_allowed)
			(footprints allowed)
		)
		(placement
			(enabled no)
			(sheetname "")
		)
		(fill
			(thermal_gap 0.5)
			(thermal_bridge_width 0.5)
			(island_removal_mode 0)
		)
		(polygon
			(pts
				(arc
					(start 25.901396 -286.832548)
					(mid 25.897676 -286.841528)
					(end 25.888696 -286.845248)
				)
				(arc
					(start 24.415496 -286.845248)
					(mid 24.406516 -286.841528)
					(end 24.402796 -286.832548)
				)
				(arc
					(start 24.402796 -286.33801)
					(mid 24.406516 -286.32903)
					(end 24.415496 -286.32531)
				)
				(arc
					(start 25.888696 -286.32531)
					(mid 25.897676 -286.32903)
					(end 25.901396 -286.33801)
				)
			)
		)
	)
	(zone
		(layer "In1.Cu")
		(hatch none 0.5)
		(connect_pads
			(clearance 0)
		)
		(min_thickness 0.25)
		(keepout
			(tracks not_allowed)
			(vias allowed)
			(pads allowed)
			(copperpour not_allowed)
			(footprints allowed)
		)
		(placement
			(enabled no)
			(sheetname "")
		)
		(fill
			(thermal_gap 0.5)
			(thermal_bridge_width 0.5)
			(island_removal_mode 0)
		)
		(polygon
			(pts
				(arc
					(start 14.429994 -105.41381)
					(mid 14.447955 -105.406371)
					(end 14.455394 -105.38841)
				)
				(arc
					(start 14.455394 -105.173272)
					(mid 14.462833 -105.155311)
					(end 14.480794 -105.147872)
				)
				(arc
					(start 14.489938 -105.147872)
					(mid 14.507899 -105.140433)
					(end 14.515338 -105.122472)
				)
				(arc
					(start 14.515338 -105.007664)
					(mid 14.486129 -104.937782)
					(end 14.416024 -104.909112)
				)
				(arc
					(start 14.11478 -104.909112)
					(mid 14.044675 -104.937782)
					(end 14.015466 -105.007664)
				)
				(arc
					(start 14.015466 -105.122472)
					(mid 14.022905 -105.140433)
					(end 14.040866 -105.147872)
				)
				(arc
					(start 14.05001 -105.147872)
					(mid 14.067971 -105.155311)
					(end 14.07541 -105.173272)
				)
				(arc
					(start 14.07541 -105.38841)
					(mid 14.082849 -105.406371)
					(end 14.10081 -105.41381)
				)
			)
		)
	)
	(zone
		(layer "In1.Cu")
		(hatch none 0.5)
		(connect_pads
			(clearance 0)
		)
		(min_thickness 0.25)
		(keepout
			(tracks not_allowed)
			(vias allowed)
			(pads allowed)
			(copperpour not_allowed)
			(footprints allowed)
		)
		(placement
			(enabled no)
			(sheetname "")
		)
		(fill
			(thermal_gap 0.5)
			(thermal_bridge_width 0.5)
			(island_removal_mode 0)
		)
		(polygon
			(pts
				(arc
					(start 172.72127 -206.082392)
					(mid 172.71755 -206.091372)
					(end 172.70857 -206.095092)
				)
				(arc
					(start 171.23537 -206.095092)
					(mid 171.22639 -206.091372)
					(end 171.22267 -206.082392)
				)
				(arc
					(start 171.22267 -205.587854)
					(mid 171.22639 -205.578874)
					(end 171.23537 -205.575154)
				)
				(arc
					(start 172.70857 -205.575154)
					(mid 172.71755 -205.578874)
					(end 172.72127 -205.587854)
				)
			)
		)
	)
	(zone
		(layer "In1.Cu")
		(hatch none 0.5)
		(connect_pads
			(clearance 0)
		)
		(min_thickness 0.25)
		(keepout
			(tracks not_allowed)
			(vias allowed)
			(pads allowed)
			(copperpour not_allowed)
			(footprints allowed)
		)
		(placement
			(enabled no)
			(sheetname "")
		)
		(fill
			(thermal_gap 0.5)
			(thermal_bridge_width 0.5)
			(island_removal_mode 0)
		)
		(polygon
			(pts
				(arc
					(start 172.72127 -254.532384)
					(mid 172.71755 -254.541364)
					(end 172.70857 -254.545084)
				)
				(arc
					(start 171.23537 -254.545084)
					(mid 171.22639 -254.541364)
					(end 171.22267 -254.532384)
				)
				(arc
					(start 171.22267 -254.037846)
					(mid 171.22639 -254.028866)
					(end 171.23537 -254.025146)
				)
				(arc
					(start 172.70857 -254.025146)
					(mid 172.71755 -254.028866)
					(end 172.72127 -254.037846)
				)
			)
		)
	)
	(zone
		(layer "In1.Cu")
		(hatch none 0.5)
		(connect_pads
			(clearance 0)
		)
		(min_thickness 0.25)
		(keepout
			(tracks not_allowed)
			(vias allowed)
			(pads allowed)
			(copperpour not_allowed)
			(footprints allowed)
		)
		(placement
			(enabled no)
			(sheetname "")
		)
		(fill
			(thermal_gap 0.5)
			(thermal_bridge_width 0.5)
			(island_removal_mode 0)
		)
		(polygon
			(pts
				(arc
					(start 61.970412 -383.92227)
					(mid 61.665612 -383.92227)
					(end 61.970412 -383.92227)
				)
			)
		)
	)
	(zone
		(layer "In1.Cu")
		(hatch none 0.5)
		(connect_pads
			(clearance 0)
		)
		(min_thickness 0.25)
		(keepout
			(tracks not_allowed)
			(vias allowed)
			(pads allowed)
			(copperpour not_allowed)
			(footprints allowed)
		)
		(placement
			(enabled no)
			(sheetname "")
		)
		(fill
			(thermal_gap 0.5)
			(thermal_bridge_width 0.5)
			(island_removal_mode 0)
		)
		(polygon
			(pts
				(arc
					(start 50.261012 -389.467344)
					(mid 49.880012 -389.467344)
					(end 50.261012 -389.467344)
				)
			)
		)
	)
	(zone
		(layer "In1.Cu")
		(hatch none 0.5)
		(connect_pads
			(clearance 0)
		)
		(min_thickness 0.25)
		(keepout
			(tracks not_allowed)
			(vias allowed)
			(pads allowed)
			(copperpour not_allowed)
			(footprints allowed)
		)
		(placement
			(enabled no)
			(sheetname "")
		)
		(fill
			(thermal_gap 0.5)
			(thermal_bridge_width 0.5)
			(island_removal_mode 0)
		)
		(polygon
			(pts
				(arc
					(start 266.29741 -253.682246)
					(mid 266.29369 -253.691226)
					(end 266.28471 -253.694946)
				)
				(arc
					(start 264.81151 -253.694946)
					(mid 264.80253 -253.691226)
					(end 264.79881 -253.682246)
				)
				(arc
					(start 264.79881 -253.187708)
					(mid 264.80253 -253.178728)
					(end 264.81151 -253.175008)
				)
				(arc
					(start 266.28471 -253.175008)
					(mid 266.29369 -253.178728)
					(end 266.29741 -253.187708)
				)
			)
		)
	)
	(zone
		(layer "In1.Cu")
		(hatch none 0.5)
		(connect_pads
			(clearance 0)
		)
		(min_thickness 0.25)
		(keepout
			(tracks not_allowed)
			(vias allowed)
			(pads allowed)
			(copperpour not_allowed)
			(footprints allowed)
		)
		(placement
			(enabled no)
			(sheetname "")
		)
		(fill
			(thermal_gap 0.5)
			(thermal_bridge_width 0.5)
			(island_removal_mode 0)
		)
		(polygon
			(pts
				(arc
					(start 18.357342 -241.782346)
					(mid 18.353622 -241.791326)
					(end 18.344642 -241.795046)
				)
				(arc
					(start 16.871442 -241.795046)
					(mid 16.862462 -241.791326)
					(end 16.858742 -241.782346)
				)
				(arc
					(start 16.858742 -241.287808)
					(mid 16.862462 -241.278828)
					(end 16.871442 -241.275108)
				)
				(arc
					(start 18.344642 -241.275108)
					(mid 18.353622 -241.278828)
					(end 18.357342 -241.287808)
				)
			)
		)
	)
	(zone
		(layer "In1.Cu")
		(hatch none 0.5)
		(connect_pads
			(clearance 0)
		)
		(min_thickness 0.25)
		(keepout
			(tracks not_allowed)
			(vias allowed)
			(pads allowed)
			(copperpour not_allowed)
			(footprints allowed)
		)
		(placement
			(enabled no)
			(sheetname "")
		)
		(fill
			(thermal_gap 0.5)
			(thermal_bridge_width 0.5)
			(island_removal_mode 0)
		)
		(polygon
			(pts
				(arc
					(start 308.6608 -394.385292)
					(mid 308.2798 -394.385292)
					(end 308.6608 -394.385292)
				)
			)
		)
	)
	(zone
		(layer "In1.Cu")
		(hatch none 0.5)
		(connect_pads
			(clearance 0)
		)
		(min_thickness 0.25)
		(keepout
			(tracks not_allowed)
			(vias allowed)
			(pads allowed)
			(copperpour not_allowed)
			(footprints allowed)
		)
		(placement
			(enabled no)
			(sheetname "")
		)
		(fill
			(thermal_gap 0.5)
			(thermal_bridge_width 0.5)
			(island_removal_mode 0)
		)
		(polygon
			(pts
				(arc
					(start 48.533304 -226.482402)
					(mid 48.529584 -226.491382)
					(end 48.520604 -226.495102)
				)
				(arc
					(start 47.047404 -226.495102)
					(mid 47.038424 -226.491382)
					(end 47.034704 -226.482402)
				)
				(arc
					(start 47.034704 -225.987864)
					(mid 47.038424 -225.978884)
					(end 47.047404 -225.975164)
				)
				(arc
					(start 48.520604 -225.975164)
					(mid 48.529584 -225.978884)
					(end 48.533304 -225.987864)
				)
			)
		)
	)
	(zone
		(layer "In1.Cu")
		(hatch none 0.5)
		(connect_pads
			(clearance 0)
		)
		(min_thickness 0.25)
		(keepout
			(tracks not_allowed)
			(vias allowed)
			(pads allowed)
			(copperpour not_allowed)
			(footprints allowed)
		)
		(placement
			(enabled no)
			(sheetname "")
		)
		(fill
			(thermal_gap 0.5)
			(thermal_bridge_width 0.5)
			(island_removal_mode 0)
		)
		(polygon
			(pts
				(arc
					(start 410.398214 -399.143474)
					(mid 410.093414 -399.143474)
					(end 410.398214 -399.143474)
				)
			)
		)
	)
	(zone
		(layer "In1.Cu")
		(hatch none 0.5)
		(connect_pads
			(clearance 0)
		)
		(min_thickness 0.25)
		(keepout
			(tracks not_allowed)
			(vias allowed)
			(pads allowed)
			(copperpour not_allowed)
			(footprints allowed)
		)
		(placement
			(enabled no)
			(sheetname "")
		)
		(fill
			(thermal_gap 0.5)
			(thermal_bridge_width 0.5)
			(island_removal_mode 0)
		)
		(polygon
			(pts
				(arc
					(start 18.357342 -223.082358)
					(mid 18.353622 -223.091338)
					(end 18.344642 -223.095058)
				)
				(arc
					(start 16.871442 -223.095058)
					(mid 16.862462 -223.091338)
					(end 16.858742 -223.082358)
				)
				(arc
					(start 16.858742 -222.58782)
					(mid 16.862462 -222.57884)
					(end 16.871442 -222.57512)
				)
				(arc
					(start 18.344642 -222.57512)
					(mid 18.353622 -222.57884)
					(end 18.357342 -222.58782)
				)
			)
		)
	)
	(zone
		(layer "In1.Cu")
		(hatch none 0.5)
		(connect_pads
			(clearance 0)
		)
		(min_thickness 0.25)
		(keepout
			(tracks not_allowed)
			(vias allowed)
			(pads allowed)
			(copperpour not_allowed)
			(footprints allowed)
		)
		(placement
			(enabled no)
			(sheetname "")
		)
		(fill
			(thermal_gap 0.5)
			(thermal_bridge_width 0.5)
			(island_removal_mode 0)
		)
		(polygon
			(pts
				(arc
					(start 96.318832 -383.440686)
					(mid 96.445832 -383.567686)
					(end 96.572832 -383.440686)
				)
				(arc
					(start 96.572832 -383.364486)
					(mid 96.445832 -383.237486)
					(end 96.318832 -383.364486)
				)
			)
		)
	)
	(zone
		(layer "In1.Cu")
		(hatch none 0.5)
		(connect_pads
			(clearance 0)
		)
		(min_thickness 0.25)
		(keepout
			(tracks not_allowed)
			(vias allowed)
			(pads allowed)
			(copperpour not_allowed)
			(footprints allowed)
		)
		(placement
			(enabled no)
			(sheetname "")
		)
		(fill
			(thermal_gap 0.5)
			(thermal_bridge_width 0.5)
			(island_removal_mode 0)
		)
		(polygon
			(pts
				(arc
					(start 435.749446 -265.582146)
					(mid 435.745726 -265.591126)
					(end 435.736746 -265.594846)
				)
				(arc
					(start 434.263546 -265.594846)
					(mid 434.254566 -265.591126)
					(end 434.250846 -265.582146)
				)
				(arc
					(start 434.250846 -265.087608)
					(mid 434.254566 -265.078628)
					(end 434.263546 -265.074908)
				)
				(arc
					(start 435.736746 -265.074908)
					(mid 435.745726 -265.078628)
					(end 435.749446 -265.087608)
				)
			)
		)
	)
	(zone
		(layer "In1.Cu")
		(hatch none 0.5)
		(connect_pads
			(clearance 0)
		)
		(min_thickness 0.25)
		(keepout
			(tracks not_allowed)
			(vias allowed)
			(pads allowed)
			(copperpour not_allowed)
			(footprints allowed)
		)
		(placement
			(enabled no)
			(sheetname "")
		)
		(fill
			(thermal_gap 0.5)
			(thermal_bridge_width 0.5)
			(island_removal_mode 0)
		)
		(polygon
			(pts
				(arc
					(start 273.841464 -310.632094)
					(mid 273.837744 -310.641074)
					(end 273.828764 -310.644794)
				)
				(arc
					(start 272.355564 -310.644794)
					(mid 272.346584 -310.641074)
					(end 272.342864 -310.632094)
				)
				(arc
					(start 272.342864 -310.137556)
					(mid 272.346584 -310.128576)
					(end 272.355564 -310.124856)
				)
				(arc
					(start 273.828764 -310.124856)
					(mid 273.837744 -310.128576)
					(end 273.841464 -310.137556)
				)
			)
		)
	)
	(zone
		(layer "In1.Cu")
		(hatch none 0.5)
		(connect_pads
			(clearance 0)
		)
		(min_thickness 0.25)
		(keepout
			(tracks not_allowed)
			(vias allowed)
			(pads allowed)
			(copperpour not_allowed)
			(footprints allowed)
		)
		(placement
			(enabled no)
			(sheetname "")
		)
		(fill
			(thermal_gap 0.5)
			(thermal_bridge_width 0.5)
			(island_removal_mode 0)
		)
		(polygon
			(pts
				(arc
					(start 318.5033 -384.288284)
					(mid 318.523224 -384.29752)
					(end 318.544956 -384.30073)
				)
				(arc
					(start 318.73952 -384.30073)
					(mid 318.793402 -384.278412)
					(end 318.81572 -384.22453)
				)
				(arc
					(start 318.81572 -383.53873)
					(mid 318.793402 -383.484848)
					(end 318.73952 -383.46253)
				)
				(arc
					(start 318.544956 -383.46253)
					(mid 318.523212 -383.465698)
					(end 318.5033 -383.474976)
				)
				(arc
					(start 318.207136 -383.667762)
					(mid 318.165452 -383.679984)
					(end 318.123824 -383.667508)
				)
				(arc
					(start 317.8302 -383.474976)
					(mid 317.810276 -383.46574)
					(end 317.788544 -383.46253)
				)
				(arc
					(start 317.59398 -383.46253)
					(mid 317.540098 -383.484848)
					(end 317.51778 -383.53873)
				)
				(arc
					(start 317.51778 -384.22453)
					(mid 317.540098 -384.278412)
					(end 317.59398 -384.30073)
				)
				(arc
					(start 317.789814 -384.30073)
					(mid 317.811558 -384.297562)
					(end 317.83147 -384.288284)
				)
				(arc
					(start 318.125094 -384.095752)
					(mid 318.16675 -384.08335)
					(end 318.208406 -384.095752)
				)
			)
		)
	)
	(zone
		(layer "In1.Cu")
		(hatch none 0.5)
		(connect_pads
			(clearance 0)
		)
		(min_thickness 0.25)
		(keepout
			(tracks not_allowed)
			(vias allowed)
			(pads allowed)
			(copperpour not_allowed)
			(footprints allowed)
		)
		(placement
			(enabled no)
			(sheetname "")
		)
		(fill
			(thermal_gap 0.5)
			(thermal_bridge_width 0.5)
			(island_removal_mode 0)
		)
		(polygon
			(pts
				(arc
					(start 432.30546 -315.73216)
					(mid 432.30174 -315.74114)
					(end 432.29276 -315.74486)
				)
				(arc
					(start 430.81956 -315.74486)
					(mid 430.81058 -315.74114)
					(end 430.80686 -315.73216)
				)
				(arc
					(start 430.80686 -315.237622)
					(mid 430.81058 -315.228642)
					(end 430.81956 -315.224922)
				)
				(arc
					(start 432.29276 -315.224922)
					(mid 432.30174 -315.228642)
					(end 432.30546 -315.237622)
				)
			)
		)
	)
	(zone
		(layer "In1.Cu")
		(hatch none 0.5)
		(connect_pads
			(clearance 0)
		)
		(min_thickness 0.25)
		(keepout
			(tracks not_allowed)
			(vias allowed)
			(pads allowed)
			(copperpour not_allowed)
			(footprints allowed)
		)
		(placement
			(enabled no)
			(sheetname "")
		)
		(fill
			(thermal_gap 0.5)
			(thermal_bridge_width 0.5)
			(island_removal_mode 0)
		)
		(polygon
			(pts
				(arc
					(start 195.353432 -243.482368)
					(mid 195.349712 -243.491348)
					(end 195.340732 -243.495068)
				)
				(arc
					(start 193.867532 -243.495068)
					(mid 193.858552 -243.491348)
					(end 193.854832 -243.482368)
				)
				(arc
					(start 193.854832 -242.98783)
					(mid 193.858552 -242.97885)
					(end 193.867532 -242.97513)
				)
				(arc
					(start 195.340732 -242.97513)
					(mid 195.349712 -242.97885)
					(end 195.353432 -242.98783)
				)
			)
		)
	)
	(zone
		(layer "In1.Cu")
		(hatch none 0.5)
		(connect_pads
			(clearance 0)
		)
		(min_thickness 0.25)
		(keepout
			(tracks not_allowed)
			(vias allowed)
			(pads allowed)
			(copperpour not_allowed)
			(footprints allowed)
		)
		(placement
			(enabled no)
			(sheetname "")
		)
		(fill
			(thermal_gap 0.5)
			(thermal_bridge_width 0.5)
			(island_removal_mode 0)
		)
		(polygon
			(pts
				(arc
					(start 439.849514 -200.982326)
					(mid 439.845794 -200.991306)
					(end 439.836814 -200.995026)
				)
				(arc
					(start 438.363614 -200.995026)
					(mid 438.354634 -200.991306)
					(end 438.350914 -200.982326)
				)
				(arc
					(start 438.350914 -200.487788)
					(mid 438.354634 -200.478808)
					(end 438.363614 -200.475088)
				)
				(arc
					(start 439.836814 -200.475088)
					(mid 439.845794 -200.478808)
					(end 439.849514 -200.487788)
				)
			)
		)
	)
	(zone
		(layer "In1.Cu")
		(hatch none 0.5)
		(connect_pads
			(clearance 0)
		)
		(min_thickness 0.25)
		(keepout
			(tracks not_allowed)
			(vias allowed)
			(pads allowed)
			(copperpour not_allowed)
			(footprints allowed)
		)
		(placement
			(enabled no)
			(sheetname "")
		)
		(fill
			(thermal_gap 0.5)
			(thermal_bridge_width 0.5)
			(island_removal_mode 0)
		)
		(polygon
			(pts
				(arc
					(start 308.117494 -266.432284)
					(mid 308.113774 -266.441264)
					(end 308.104794 -266.444984)
				)
				(arc
					(start 306.631594 -266.444984)
					(mid 306.622614 -266.441264)
					(end 306.618894 -266.432284)
				)
				(arc
					(start 306.618894 -265.937746)
					(mid 306.622614 -265.928766)
					(end 306.631594 -265.925046)
				)
				(arc
					(start 308.104794 -265.925046)
					(mid 308.113774 -265.928766)
					(end 308.117494 -265.937746)
				)
			)
		)
	)
	(zone
		(layer "In1.Cu")
		(hatch none 0.5)
		(connect_pads
			(clearance 0)
		)
		(min_thickness 0.25)
		(keepout
			(tracks not_allowed)
			(vias allowed)
			(pads allowed)
			(copperpour not_allowed)
			(footprints allowed)
		)
		(placement
			(enabled no)
			(sheetname "")
		)
		(fill
			(thermal_gap 0.5)
			(thermal_bridge_width 0.5)
			(island_removal_mode 0)
		)
		(polygon
			(pts
				(arc
					(start 450.8373 -305.532282)
					(mid 450.83358 -305.541262)
					(end 450.8246 -305.544982)
				)
				(arc
					(start 449.3514 -305.544982)
					(mid 449.34242 -305.541262)
					(end 449.3387 -305.532282)
				)
				(arc
					(start 449.3387 -305.037744)
					(mid 449.34242 -305.028764)
					(end 449.3514 -305.025044)
				)
				(arc
					(start 450.8246 -305.025044)
					(mid 450.83358 -305.028764)
					(end 450.8373 -305.037744)
				)
			)
		)
	)
	(zone
		(layer "In1.Cu")
		(hatch none 0.5)
		(connect_pads
			(clearance 0)
		)
		(min_thickness 0.25)
		(keepout
			(tracks not_allowed)
			(vias allowed)
			(pads allowed)
			(copperpour not_allowed)
			(footprints allowed)
		)
		(placement
			(enabled no)
			(sheetname "")
		)
		(fill
			(thermal_gap 0.5)
			(thermal_bridge_width 0.5)
			(island_removal_mode 0)
		)
		(polygon
			(pts
				(arc
					(start 285.485332 -229.032308)
					(mid 285.481612 -229.041288)
					(end 285.472632 -229.045008)
				)
				(arc
					(start 283.999432 -229.045008)
					(mid 283.990452 -229.041288)
					(end 283.986732 -229.032308)
				)
				(arc
					(start 283.986732 -228.53777)
					(mid 283.990452 -228.52879)
					(end 283.999432 -228.52507)
				)
				(arc
					(start 285.472632 -228.52507)
					(mid 285.481612 -228.52879)
					(end 285.485332 -228.53777)
				)
			)
		)
	)
	(zone
		(layer "In1.Cu")
		(hatch none 0.5)
		(connect_pads
			(clearance 0)
		)
		(min_thickness 0.25)
		(keepout
			(tracks not_allowed)
			(vias allowed)
			(pads allowed)
			(copperpour not_allowed)
			(footprints allowed)
		)
		(placement
			(enabled no)
			(sheetname "")
		)
		(fill
			(thermal_gap 0.5)
			(thermal_bridge_width 0.5)
			(island_removal_mode 0)
		)
		(polygon
			(pts
				(arc
					(start 454.937368 -212.882226)
					(mid 454.933648 -212.891206)
					(end 454.924668 -212.894926)
				)
				(arc
					(start 453.451468 -212.894926)
					(mid 453.442488 -212.891206)
					(end 453.438768 -212.882226)
				)
				(arc
					(start 453.438768 -212.387688)
					(mid 453.442488 -212.378708)
					(end 453.451468 -212.374988)
				)
				(arc
					(start 454.924668 -212.374988)
					(mid 454.933648 -212.378708)
					(end 454.937368 -212.387688)
				)
			)
		)
	)
	(zone
		(layer "In1.Cu")
		(hatch none 0.5)
		(connect_pads
			(clearance 0)
		)
		(min_thickness 0.25)
		(keepout
			(tracks not_allowed)
			(vias allowed)
			(pads allowed)
			(copperpour not_allowed)
			(footprints allowed)
		)
		(placement
			(enabled no)
			(sheetname "")
		)
		(fill
			(thermal_gap 0.5)
			(thermal_bridge_width 0.5)
			(island_removal_mode 0)
		)
		(polygon
			(pts
				(arc
					(start 165.177216 -212.032342)
					(mid 165.173496 -212.041322)
					(end 165.164516 -212.045042)
				)
				(arc
					(start 163.691316 -212.045042)
					(mid 163.682336 -212.041322)
					(end 163.678616 -212.032342)
				)
				(arc
					(start 163.678616 -211.537804)
					(mid 163.682336 -211.528824)
					(end 163.691316 -211.525104)
				)
				(arc
					(start 165.164516 -211.525104)
					(mid 165.173496 -211.528824)
					(end 165.177216 -211.537804)
				)
			)
		)
	)
	(zone
		(layer "In1.Cu")
		(hatch none 0.5)
		(connect_pads
			(clearance 0)
		)
		(min_thickness 0.25)
		(keepout
			(tracks not_allowed)
			(vias allowed)
			(pads allowed)
			(copperpour not_allowed)
			(footprints allowed)
		)
		(placement
			(enabled no)
			(sheetname "")
		)
		(fill
			(thermal_gap 0.5)
			(thermal_bridge_width 0.5)
			(island_removal_mode 0)
		)
		(polygon
			(pts
				(arc
					(start 307.79085 -399.701258)
					(mid 307.91785 -399.828258)
					(end 308.04485 -399.701258)
				)
				(arc
					(start 308.04485 -399.625058)
					(mid 307.91785 -399.498058)
					(end 307.79085 -399.625058)
				)
			)
		)
	)
	(zone
		(layer "In1.Cu")
		(hatch none 0.5)
		(connect_pads
			(clearance 0)
		)
		(min_thickness 0.25)
		(keepout
			(tracks not_allowed)
			(vias allowed)
			(pads allowed)
			(copperpour not_allowed)
			(footprints allowed)
		)
		(placement
			(enabled no)
			(sheetname "")
		)
		(fill
			(thermal_gap 0.5)
			(thermal_bridge_width 0.5)
			(island_removal_mode 0)
		)
		(polygon
			(pts
				(arc
					(start 191.909446 -199.282558)
					(mid 191.905726 -199.291538)
					(end 191.896746 -199.295258)
				)
				(arc
					(start 190.423546 -199.295258)
					(mid 190.414566 -199.291538)
					(end 190.410846 -199.282558)
				)
				(arc
					(start 190.410846 -198.78802)
					(mid 190.414566 -198.77904)
					(end 190.423546 -198.77532)
				)
				(arc
					(start 191.896746 -198.77532)
					(mid 191.905726 -198.77904)
					(end 191.909446 -198.78802)
				)
			)
		)
	)
	(zone
		(layer "In1.Cu")
		(hatch none 0.5)
		(connect_pads
			(clearance 0)
		)
		(min_thickness 0.25)
		(keepout
			(tracks not_allowed)
			(vias allowed)
			(pads allowed)
			(copperpour not_allowed)
			(footprints allowed)
		)
		(placement
			(enabled no)
			(sheetname "")
		)
		(fill
			(thermal_gap 0.5)
			(thermal_bridge_width 0.5)
			(island_removal_mode 0)
		)
		(polygon
			(pts
				(arc
					(start 435.749446 -254.53213)
					(mid 435.745726 -254.54111)
					(end 435.736746 -254.54483)
				)
				(arc
					(start 434.263546 -254.54483)
					(mid 434.254566 -254.54111)
					(end 434.250846 -254.53213)
				)
				(arc
					(start 434.250846 -254.037592)
					(mid 434.254566 -254.028612)
					(end 434.263546 -254.024892)
				)
				(arc
					(start 435.736746 -254.024892)
					(mid 435.745726 -254.028612)
					(end 435.749446 -254.037592)
				)
			)
		)
	)
	(zone
		(layer "In1.Cu")
		(hatch none 0.5)
		(connect_pads
			(clearance 0)
		)
		(min_thickness 0.25)
		(keepout
			(tracks not_allowed)
			(vias allowed)
			(pads allowed)
			(copperpour not_allowed)
			(footprints allowed)
		)
		(placement
			(enabled no)
			(sheetname "")
		)
		(fill
			(thermal_gap 0.5)
			(thermal_bridge_width 0.5)
			(island_removal_mode 0)
		)
		(polygon
			(pts
				(arc
					(start 443.2935 -295.33215)
					(mid 443.28978 -295.34113)
					(end 443.2808 -295.34485)
				)
				(arc
					(start 441.8076 -295.34485)
					(mid 441.79862 -295.34113)
					(end 441.7949 -295.33215)
				)
				(arc
					(start 441.7949 -294.837612)
					(mid 441.79862 -294.828632)
					(end 441.8076 -294.824912)
				)
				(arc
					(start 443.2808 -294.824912)
					(mid 443.28978 -294.828632)
					(end 443.2935 -294.837612)
				)
			)
		)
	)
	(zone
		(layer "In1.Cu")
		(hatch none 0.5)
		(connect_pads
			(clearance 0)
		)
		(min_thickness 0.25)
		(keepout
			(tracks not_allowed)
			(vias allowed)
			(pads allowed)
			(copperpour not_allowed)
			(footprints allowed)
		)
		(placement
			(enabled no)
			(sheetname "")
		)
		(fill
			(thermal_gap 0.5)
			(thermal_bridge_width 0.5)
			(island_removal_mode 0)
		)
		(polygon
			(pts
				(arc
					(start 206.5782 -236.435392)
					(mid 205.9178 -236.435392)
					(end 206.5782 -236.435392)
				)
			)
		)
	)
	(zone
		(layer "In1.Cu")
		(hatch none 0.5)
		(connect_pads
			(clearance 0)
		)
		(min_thickness 0.25)
		(keepout
			(tracks not_allowed)
			(vias allowed)
			(pads allowed)
			(copperpour not_allowed)
			(footprints allowed)
		)
		(placement
			(enabled no)
			(sheetname "")
		)
		(fill
			(thermal_gap 0.5)
			(thermal_bridge_width 0.5)
			(island_removal_mode 0)
		)
		(polygon
			(pts
				(arc
					(start 105.500932 -294.031416)
					(mid 105.196132 -294.336216)
					(end 105.500932 -294.641016)
				)
				(arc
					(start 106.440986 -294.641016)
					(mid 106.745786 -294.336216)
					(end 106.440986 -294.031416)
				)
			)
		)
	)
	(zone
		(layer "In1.Cu")
		(hatch none 0.5)
		(connect_pads
			(clearance 0)
		)
		(min_thickness 0.25)
		(keepout
			(tracks not_allowed)
			(vias allowed)
			(pads allowed)
			(copperpour not_allowed)
			(footprints allowed)
		)
		(placement
			(enabled no)
			(sheetname "")
		)
		(fill
			(thermal_gap 0.5)
			(thermal_bridge_width 0.5)
			(island_removal_mode 0)
		)
		(polygon
			(pts
				(arc
					(start 94.788736 -389.467344)
					(mid 94.407736 -389.467344)
					(end 94.788736 -389.467344)
				)
			)
		)
	)
	(zone
		(layer "In1.Cu")
		(hatch none 0.5)
		(connect_pads
			(clearance 0)
		)
		(min_thickness 0.25)
		(keepout
			(tracks not_allowed)
			(vias allowed)
			(pads allowed)
			(copperpour not_allowed)
			(footprints allowed)
		)
		(placement
			(enabled no)
			(sheetname "")
		)
		(fill
			(thermal_gap 0.5)
			(thermal_bridge_width 0.5)
			(island_removal_mode 0)
		)
		(polygon
			(pts
				(arc
					(start 304.017426 -243.482114)
					(mid 304.013706 -243.491094)
					(end 304.004726 -243.494814)
				)
				(arc
					(start 302.531526 -243.494814)
					(mid 302.522546 -243.491094)
					(end 302.518826 -243.482114)
				)
				(arc
					(start 302.518826 -242.987576)
					(mid 302.522546 -242.978596)
					(end 302.531526 -242.974876)
				)
				(arc
					(start 304.004726 -242.974876)
					(mid 304.013706 -242.978596)
					(end 304.017426 -242.987576)
				)
			)
		)
	)
	(zone
		(layer "In1.Cu")
		(hatch none 0.5)
		(connect_pads
			(clearance 0)
		)
		(min_thickness 0.25)
		(keepout
			(tracks not_allowed)
			(vias allowed)
			(pads allowed)
			(copperpour not_allowed)
			(footprints allowed)
		)
		(placement
			(enabled no)
			(sheetname "")
		)
		(fill
			(thermal_gap 0.5)
			(thermal_bridge_width 0.5)
			(island_removal_mode 0)
		)
		(polygon
			(pts
				(arc
					(start 169.277284 -229.032562)
					(mid 169.273564 -229.041542)
					(end 169.264584 -229.045262)
				)
				(arc
					(start 167.791384 -229.045262)
					(mid 167.782404 -229.041542)
					(end 167.778684 -229.032562)
				)
				(arc
					(start 167.778684 -228.538024)
					(mid 167.782404 -228.529044)
					(end 167.791384 -228.525324)
				)
				(arc
					(start 169.264584 -228.525324)
					(mid 169.273564 -228.529044)
					(end 169.277284 -228.538024)
				)
			)
		)
	)
	(zone
		(layer "In1.Cu")
		(hatch none 0.5)
		(connect_pads
			(clearance 0)
		)
		(min_thickness 0.25)
		(keepout
			(tracks not_allowed)
			(vias allowed)
			(pads allowed)
			(copperpour not_allowed)
			(footprints allowed)
		)
		(placement
			(enabled no)
			(sheetname "")
		)
		(fill
			(thermal_gap 0.5)
			(thermal_bridge_width 0.5)
			(island_removal_mode 0)
		)
		(polygon
			(pts
				(arc
					(start 304.017426 -246.882158)
					(mid 304.013706 -246.891138)
					(end 304.004726 -246.894858)
				)
				(arc
					(start 302.531526 -246.894858)
					(mid 302.522546 -246.891138)
					(end 302.518826 -246.882158)
				)
				(arc
					(start 302.518826 -246.38762)
					(mid 302.522546 -246.37864)
					(end 302.531526 -246.37492)
				)
				(arc
					(start 304.004726 -246.37492)
					(mid 304.013706 -246.37864)
					(end 304.017426 -246.38762)
				)
			)
		)
	)
	(zone
		(layer "In1.Cu")
		(hatch none 0.5)
		(connect_pads
			(clearance 0)
		)
		(min_thickness 0.25)
		(keepout
			(tracks not_allowed)
			(vias allowed)
			(pads allowed)
			(copperpour not_allowed)
			(footprints allowed)
		)
		(placement
			(enabled no)
			(sheetname "")
		)
		(fill
			(thermal_gap 0.5)
			(thermal_bridge_width 0.5)
			(island_removal_mode 0)
		)
		(polygon
			(pts
				(arc
					(start 424.761406 -205.232254)
					(mid 424.757686 -205.241234)
					(end 424.748706 -205.244954)
				)
				(arc
					(start 423.275506 -205.244954)
					(mid 423.266526 -205.241234)
					(end 423.262806 -205.232254)
				)
				(arc
					(start 423.262806 -204.737716)
					(mid 423.266526 -204.728736)
					(end 423.275506 -204.725016)
				)
				(arc
					(start 424.748706 -204.725016)
					(mid 424.757686 -204.728736)
					(end 424.761406 -204.737716)
				)
			)
		)
	)
	(zone
		(layer "In1.Cu")
		(hatch none 0.5)
		(connect_pads
			(clearance 0)
		)
		(min_thickness 0.25)
		(keepout
			(tracks not_allowed)
			(vias allowed)
			(pads allowed)
			(copperpour not_allowed)
			(footprints allowed)
		)
		(placement
			(enabled no)
			(sheetname "")
		)
		(fill
			(thermal_gap 0.5)
			(thermal_bridge_width 0.5)
			(island_removal_mode 0)
		)
		(polygon
			(pts
				(arc
					(start 308.117494 -278.332184)
					(mid 308.113774 -278.341164)
					(end 308.104794 -278.344884)
				)
				(arc
					(start 306.631594 -278.344884)
					(mid 306.622614 -278.341164)
					(end 306.618894 -278.332184)
				)
				(arc
					(start 306.618894 -277.837646)
					(mid 306.622614 -277.828666)
					(end 306.631594 -277.824946)
				)
				(arc
					(start 308.104794 -277.824946)
					(mid 308.113774 -277.828666)
					(end 308.117494 -277.837646)
				)
			)
		)
	)
	(zone
		(layer "In1.Cu")
		(hatch none 0.5)
		(connect_pads
			(clearance 0)
		)
		(min_thickness 0.25)
		(keepout
			(tracks not_allowed)
			(vias allowed)
			(pads allowed)
			(copperpour not_allowed)
			(footprints allowed)
		)
		(placement
			(enabled no)
			(sheetname "")
		)
		(fill
			(thermal_gap 0.5)
			(thermal_bridge_width 0.5)
			(island_removal_mode 0)
		)
		(polygon
			(pts
				(arc
					(start 293.029386 -244.332252)
					(mid 293.025666 -244.341232)
					(end 293.016686 -244.344952)
				)
				(arc
					(start 291.543486 -244.344952)
					(mid 291.534506 -244.341232)
					(end 291.530786 -244.332252)
				)
				(arc
					(start 291.530786 -243.837714)
					(mid 291.534506 -243.828734)
					(end 291.543486 -243.825014)
				)
				(arc
					(start 293.016686 -243.825014)
					(mid 293.025666 -243.828734)
					(end 293.029386 -243.837714)
				)
			)
		)
	)
	(zone
		(layer "In1.Cu")
		(hatch none 0.5)
		(connect_pads
			(clearance 0)
		)
		(min_thickness 0.25)
		(keepout
			(tracks not_allowed)
			(vias allowed)
			(pads allowed)
			(copperpour not_allowed)
			(footprints allowed)
		)
		(placement
			(enabled no)
			(sheetname "")
		)
		(fill
			(thermal_gap 0.5)
			(thermal_bridge_width 0.5)
			(island_removal_mode 0)
		)
		(polygon
			(pts
				(arc
					(start 424.761406 -206.932276)
					(mid 424.757686 -206.941256)
					(end 424.748706 -206.944976)
				)
				(arc
					(start 423.275506 -206.944976)
					(mid 423.266526 -206.941256)
					(end 423.262806 -206.932276)
				)
				(arc
					(start 423.262806 -206.437738)
					(mid 423.266526 -206.428758)
					(end 423.275506 -206.425038)
				)
				(arc
					(start 424.748706 -206.425038)
					(mid 424.757686 -206.428758)
					(end 424.761406 -206.437738)
				)
			)
		)
	)
	(zone
		(layer "In1.Cu")
		(hatch none 0.5)
		(connect_pads
			(clearance 0)
		)
		(min_thickness 0.25)
		(keepout
			(tracks not_allowed)
			(vias allowed)
			(pads allowed)
			(copperpour not_allowed)
			(footprints allowed)
		)
		(placement
			(enabled no)
			(sheetname "")
		)
		(fill
			(thermal_gap 0.5)
			(thermal_bridge_width 0.5)
			(island_removal_mode 0)
		)
		(polygon
			(pts
				(arc
					(start 37.545264 -295.332404)
					(mid 37.541544 -295.341384)
					(end 37.532564 -295.345104)
				)
				(arc
					(start 36.059364 -295.345104)
					(mid 36.050384 -295.341384)
					(end 36.046664 -295.332404)
				)
				(arc
					(start 36.046664 -294.837866)
					(mid 36.050384 -294.828886)
					(end 36.059364 -294.825166)
				)
				(arc
					(start 37.532564 -294.825166)
					(mid 37.541544 -294.828886)
					(end 37.545264 -294.837866)
				)
			)
		)
	)
	(zone
		(layer "In1.Cu")
		(hatch none 0.5)
		(connect_pads
			(clearance 0)
		)
		(min_thickness 0.25)
		(keepout
			(tracks not_allowed)
			(vias allowed)
			(pads allowed)
			(copperpour not_allowed)
			(footprints allowed)
		)
		(placement
			(enabled no)
			(sheetname "")
		)
		(fill
			(thermal_gap 0.5)
			(thermal_bridge_width 0.5)
			(island_removal_mode 0)
		)
		(polygon
			(pts
				(arc
					(start 52.633372 -234.982512)
					(mid 52.629652 -234.991492)
					(end 52.620672 -234.995212)
				)
				(arc
					(start 51.147472 -234.995212)
					(mid 51.138492 -234.991492)
					(end 51.134772 -234.982512)
				)
				(arc
					(start 51.134772 -234.487974)
					(mid 51.138492 -234.478994)
					(end 51.147472 -234.475274)
				)
				(arc
					(start 52.620672 -234.475274)
					(mid 52.629652 -234.478994)
					(end 52.633372 -234.487974)
				)
			)
		)
	)
	(zone
		(layer "In1.Cu")
		(hatch none 0.5)
		(connect_pads
			(clearance 0)
		)
		(min_thickness 0.25)
		(keepout
			(tracks not_allowed)
			(vias allowed)
			(pads allowed)
			(copperpour not_allowed)
			(footprints allowed)
		)
		(placement
			(enabled no)
			(sheetname "")
		)
		(fill
			(thermal_gap 0.5)
			(thermal_bridge_width 0.5)
			(island_removal_mode 0)
		)
		(polygon
			(pts
				(arc
					(start 212.820504 -4.526026)
					(mid 212.842822 -4.472144)
					(end 212.896704 -4.449826)
				)
				(arc
					(start 213.508844 -4.449826)
					(mid 213.562726 -4.472144)
					(end 213.585044 -4.526026)
				)
				(arc
					(start 213.585044 -5.623306)
					(mid 213.562726 -5.677188)
					(end 213.508844 -5.699506)
				)
				(arc
					(start 212.896704 -5.699506)
					(mid 212.842822 -5.677188)
					(end 212.820504 -5.623306)
				)
			)
		)
	)
	(zone
		(layer "In1.Cu")
		(hatch none 0.5)
		(connect_pads
			(clearance 0)
		)
		(min_thickness 0.25)
		(keepout
			(tracks not_allowed)
			(vias allowed)
			(pads allowed)
			(copperpour not_allowed)
			(footprints allowed)
		)
		(placement
			(enabled no)
			(sheetname "")
		)
		(fill
			(thermal_gap 0.5)
			(thermal_bridge_width 0.5)
			(island_removal_mode 0)
		)
		(polygon
			(pts
				(arc
					(start 277.941532 -280.032206)
					(mid 277.937812 -280.041186)
					(end 277.928832 -280.044906)
				)
				(arc
					(start 276.455632 -280.044906)
					(mid 276.446652 -280.041186)
					(end 276.442932 -280.032206)
				)
				(arc
					(start 276.442932 -279.537668)
					(mid 276.446652 -279.528688)
					(end 276.455632 -279.524968)
				)
				(arc
					(start 277.928832 -279.524968)
					(mid 277.937812 -279.528688)
					(end 277.941532 -279.537668)
				)
			)
		)
	)
	(zone
		(layer "In1.Cu")
		(hatch none 0.5)
		(connect_pads
			(clearance 0)
		)
		(min_thickness 0.25)
		(keepout
			(tracks not_allowed)
			(vias allowed)
			(pads allowed)
			(copperpour not_allowed)
			(footprints allowed)
		)
		(placement
			(enabled no)
			(sheetname "")
		)
		(fill
			(thermal_gap 0.5)
			(thermal_bridge_width 0.5)
			(island_removal_mode 0)
		)
		(polygon
			(pts
				(arc
					(start 270.397478 -302.132238)
					(mid 270.393758 -302.141218)
					(end 270.384778 -302.144938)
				)
				(arc
					(start 268.911578 -302.144938)
					(mid 268.902598 -302.141218)
					(end 268.898878 -302.132238)
				)
				(arc
					(start 268.898878 -301.6377)
					(mid 268.902598 -301.62872)
					(end 268.911578 -301.625)
				)
				(arc
					(start 270.384778 -301.625)
					(mid 270.393758 -301.62872)
					(end 270.397478 -301.6377)
				)
			)
		)
	)
	(zone
		(layer "In1.Cu")
		(hatch none 0.5)
		(connect_pads
			(clearance 0)
		)
		(min_thickness 0.25)
		(keepout
			(tracks not_allowed)
			(vias allowed)
			(pads allowed)
			(copperpour not_allowed)
			(footprints allowed)
		)
		(placement
			(enabled no)
			(sheetname "")
		)
		(fill
			(thermal_gap 0.5)
			(thermal_bridge_width 0.5)
			(island_removal_mode 0)
		)
		(polygon
			(pts
				(arc
					(start 439.849514 -233.282236)
					(mid 439.845794 -233.291216)
					(end 439.836814 -233.294936)
				)
				(arc
					(start 438.363614 -233.294936)
					(mid 438.354634 -233.291216)
					(end 438.350914 -233.282236)
				)
				(arc
					(start 438.350914 -232.787698)
					(mid 438.354634 -232.778718)
					(end 438.363614 -232.774998)
				)
				(arc
					(start 439.836814 -232.774998)
					(mid 439.845794 -232.778718)
					(end 439.849514 -232.787698)
				)
			)
		)
	)
	(zone
		(layer "In1.Cu")
		(hatch none 0.5)
		(connect_pads
			(clearance 0)
		)
		(min_thickness 0.25)
		(keepout
			(tracks not_allowed)
			(vias allowed)
			(pads allowed)
			(copperpour not_allowed)
			(footprints allowed)
		)
		(placement
			(enabled no)
			(sheetname "")
		)
		(fill
			(thermal_gap 0.5)
			(thermal_bridge_width 0.5)
			(island_removal_mode 0)
		)
		(polygon
			(pts
				(arc
					(start 206.9973 -285.98241)
					(mid 206.99358 -285.99139)
					(end 206.9846 -285.99511)
				)
				(arc
					(start 205.5114 -285.99511)
					(mid 205.50242 -285.99139)
					(end 205.4987 -285.98241)
				)
				(arc
					(start 205.4987 -285.487872)
					(mid 205.50242 -285.478892)
					(end 205.5114 -285.475172)
				)
				(arc
					(start 206.9846 -285.475172)
					(mid 206.99358 -285.478892)
					(end 206.9973 -285.487872)
				)
			)
		)
	)
	(zone
		(layer "In1.Cu")
		(hatch none 0.5)
		(connect_pads
			(clearance 0)
		)
		(min_thickness 0.25)
		(keepout
			(tracks not_allowed)
			(vias allowed)
			(pads allowed)
			(copperpour not_allowed)
			(footprints allowed)
		)
		(placement
			(enabled no)
			(sheetname "")
		)
		(fill
			(thermal_gap 0.5)
			(thermal_bridge_width 0.5)
			(island_removal_mode 0)
		)
		(polygon
			(pts
				(arc
					(start 56.077358 -228.182424)
					(mid 56.073638 -228.191404)
					(end 56.064658 -228.195124)
				)
				(arc
					(start 54.591458 -228.195124)
					(mid 54.582478 -228.191404)
					(end 54.578758 -228.182424)
				)
				(arc
					(start 54.578758 -227.687886)
					(mid 54.582478 -227.678906)
					(end 54.591458 -227.675186)
				)
				(arc
					(start 56.064658 -227.675186)
					(mid 56.073638 -227.678906)
					(end 56.077358 -227.687886)
				)
			)
		)
	)
	(zone
		(layer "In1.Cu")
		(hatch none 0.5)
		(connect_pads
			(clearance 0)
		)
		(min_thickness 0.25)
		(keepout
			(tracks not_allowed)
			(vias allowed)
			(pads allowed)
			(copperpour not_allowed)
			(footprints allowed)
		)
		(placement
			(enabled no)
			(sheetname "")
		)
		(fill
			(thermal_gap 0.5)
			(thermal_bridge_width 0.5)
			(island_removal_mode 0)
		)
		(polygon
			(pts
				(arc
					(start 447.393568 -266.432284)
					(mid 447.389848 -266.441264)
					(end 447.380868 -266.444984)
				)
				(arc
					(start 445.907668 -266.444984)
					(mid 445.898688 -266.441264)
					(end 445.894968 -266.432284)
				)
				(arc
					(start 445.894968 -265.937746)
					(mid 445.898688 -265.928766)
					(end 445.907668 -265.925046)
				)
				(arc
					(start 447.380868 -265.925046)
					(mid 447.389848 -265.928766)
					(end 447.393568 -265.937746)
				)
			)
		)
	)
	(zone
		(layer "In1.Cu")
		(hatch none 0.5)
		(connect_pads
			(clearance 0)
		)
		(min_thickness 0.25)
		(keepout
			(tracks not_allowed)
			(vias allowed)
			(pads allowed)
			(copperpour not_allowed)
			(footprints allowed)
		)
		(placement
			(enabled no)
			(sheetname "")
		)
		(fill
			(thermal_gap 0.5)
			(thermal_bridge_width 0.5)
			(island_removal_mode 0)
		)
		(polygon
			(pts
				(arc
					(start 184.365392 -242.632484)
					(mid 184.361672 -242.641464)
					(end 184.352692 -242.645184)
				)
				(arc
					(start 182.879492 -242.645184)
					(mid 182.870512 -242.641464)
					(end 182.866792 -242.632484)
				)
				(arc
					(start 182.866792 -242.137946)
					(mid 182.870512 -242.128966)
					(end 182.879492 -242.125246)
				)
				(arc
					(start 184.352692 -242.125246)
					(mid 184.361672 -242.128966)
					(end 184.365392 -242.137946)
				)
			)
		)
	)
	(zone
		(layer "In1.Cu")
		(hatch none 0.5)
		(connect_pads
			(clearance 0)
		)
		(min_thickness 0.25)
		(keepout
			(tracks not_allowed)
			(vias allowed)
			(pads allowed)
			(copperpour not_allowed)
			(footprints allowed)
		)
		(placement
			(enabled no)
			(sheetname "")
		)
		(fill
			(thermal_gap 0.5)
			(thermal_bridge_width 0.5)
			(island_removal_mode 0)
		)
		(polygon
			(pts
				(arc
					(start 285.485332 -269.832328)
					(mid 285.481612 -269.841308)
					(end 285.472632 -269.845028)
				)
				(arc
					(start 283.999432 -269.845028)
					(mid 283.990452 -269.841308)
					(end 283.986732 -269.832328)
				)
				(arc
					(start 283.986732 -269.33779)
					(mid 283.990452 -269.32881)
					(end 283.999432 -269.32509)
				)
				(arc
					(start 285.472632 -269.32509)
					(mid 285.481612 -269.32881)
					(end 285.485332 -269.33779)
				)
			)
		)
	)
	(zone
		(layer "In1.Cu")
		(hatch none 0.5)
		(connect_pads
			(clearance 0)
		)
		(min_thickness 0.25)
		(keepout
			(tracks not_allowed)
			(vias allowed)
			(pads allowed)
			(copperpour not_allowed)
			(footprints allowed)
		)
		(placement
			(enabled no)
			(sheetname "")
		)
		(fill
			(thermal_gap 0.5)
			(thermal_bridge_width 0.5)
			(island_removal_mode 0)
		)
		(polygon
			(pts
				(arc
					(start 176.821338 -294.48252)
					(mid 176.817618 -294.4915)
					(end 176.808638 -294.49522)
				)
				(arc
					(start 175.335438 -294.49522)
					(mid 175.326458 -294.4915)
					(end 175.322738 -294.48252)
				)
				(arc
					(start 175.322738 -293.987982)
					(mid 175.326458 -293.979002)
					(end 175.335438 -293.975282)
				)
				(arc
					(start 176.808638 -293.975282)
					(mid 176.817618 -293.979002)
					(end 176.821338 -293.987982)
				)
			)
		)
	)
	(zone
		(layer "In1.Cu")
		(hatch none 0.5)
		(connect_pads
			(clearance 0)
		)
		(min_thickness 0.25)
		(keepout
			(tracks not_allowed)
			(vias allowed)
			(pads allowed)
			(copperpour not_allowed)
			(footprints allowed)
		)
		(placement
			(enabled no)
			(sheetname "")
		)
		(fill
			(thermal_gap 0.5)
			(thermal_bridge_width 0.5)
			(island_removal_mode 0)
		)
		(polygon
			(pts
				(arc
					(start 52.633372 -315.732414)
					(mid 52.629652 -315.741394)
					(end 52.620672 -315.745114)
				)
				(arc
					(start 51.147472 -315.745114)
					(mid 51.138492 -315.741394)
					(end 51.134772 -315.732414)
				)
				(arc
					(start 51.134772 -315.237876)
					(mid 51.138492 -315.228896)
					(end 51.147472 -315.225176)
				)
				(arc
					(start 52.620672 -315.225176)
					(mid 52.629652 -315.228896)
					(end 52.633372 -315.237876)
				)
			)
		)
	)
	(zone
		(layer "In1.Cu")
		(hatch none 0.5)
		(connect_pads
			(clearance 0)
		)
		(min_thickness 0.25)
		(keepout
			(tracks not_allowed)
			(vias allowed)
			(pads allowed)
			(copperpour not_allowed)
			(footprints allowed)
		)
		(placement
			(enabled no)
			(sheetname "")
		)
		(fill
			(thermal_gap 0.5)
			(thermal_bridge_width 0.5)
			(island_removal_mode 0)
		)
		(polygon
			(pts
				(arc
					(start 48.533304 -282.582366)
					(mid 48.529584 -282.591346)
					(end 48.520604 -282.595066)
				)
				(arc
					(start 47.047404 -282.595066)
					(mid 47.038424 -282.591346)
					(end 47.034704 -282.582366)
				)
				(arc
					(start 47.034704 -282.087828)
					(mid 47.038424 -282.078848)
					(end 47.047404 -282.075128)
				)
				(arc
					(start 48.520604 -282.075128)
					(mid 48.529584 -282.078848)
					(end 48.533304 -282.087828)
				)
			)
		)
	)
	(zone
		(layer "In1.Cu")
		(hatch none 0.5)
		(connect_pads
			(clearance 0)
		)
		(min_thickness 0.25)
		(keepout
			(tracks not_allowed)
			(vias allowed)
			(pads allowed)
			(copperpour not_allowed)
			(footprints allowed)
		)
		(placement
			(enabled no)
			(sheetname "")
		)
		(fill
			(thermal_gap 0.5)
			(thermal_bridge_width 0.5)
			(island_removal_mode 0)
		)
		(polygon
			(pts
				(arc
					(start 304.017426 -226.482148)
					(mid 304.013706 -226.491128)
					(end 304.004726 -226.494848)
				)
				(arc
					(start 302.531526 -226.494848)
					(mid 302.522546 -226.491128)
					(end 302.518826 -226.482148)
				)
				(arc
					(start 302.518826 -225.98761)
					(mid 302.522546 -225.97863)
					(end 302.531526 -225.97491)
				)
				(arc
					(start 304.004726 -225.97491)
					(mid 304.013706 -225.97863)
					(end 304.017426 -225.98761)
				)
			)
		)
	)
	(zone
		(layer "In1.Cu")
		(hatch none 0.5)
		(connect_pads
			(clearance 0)
		)
		(min_thickness 0.25)
		(keepout
			(tracks not_allowed)
			(vias allowed)
			(pads allowed)
			(copperpour not_allowed)
			(footprints allowed)
		)
		(placement
			(enabled no)
			(sheetname "")
		)
		(fill
			(thermal_gap 0.5)
			(thermal_bridge_width 0.5)
			(island_removal_mode 0)
		)
		(polygon
			(pts
				(arc
					(start 357.862124 -385.243578)
					(mid 357.852888 -385.263502)
					(end 357.849678 -385.285234)
				)
				(arc
					(start 357.849678 -385.479798)
					(mid 357.871996 -385.53368)
					(end 357.925878 -385.555998)
				)
				(arc
					(start 358.611678 -385.555998)
					(mid 358.66556 -385.53368)
					(end 358.687878 -385.479798)
				)
				(arc
					(start 358.687878 -385.285234)
					(mid 358.68471 -385.26349)
					(end 358.675432 -385.243578)
				)
				(arc
					(start 358.482646 -384.947414)
					(mid 358.470424 -384.90573)
					(end 358.4829 -384.864102)
				)
				(arc
					(start 358.675432 -384.570478)
					(mid 358.684668 -384.550554)
					(end 358.687878 -384.528822)
				)
				(arc
					(start 358.687878 -384.334258)
					(mid 358.66556 -384.280376)
					(end 358.611678 -384.258058)
				)
				(arc
					(start 357.925878 -384.258058)
					(mid 357.871996 -384.280376)
					(end 357.849678 -384.334258)
				)
				(arc
					(start 357.849678 -384.530092)
					(mid 357.852846 -384.551836)
					(end 357.862124 -384.571748)
				)
				(arc
					(start 358.054656 -384.865372)
					(mid 358.067058 -384.907028)
					(end 358.054656 -384.948684)
				)
			)
		)
	)
	(zone
		(layer "In1.Cu")
		(hatch none 0.5)
		(connect_pads
			(clearance 0)
		)
		(min_thickness 0.25)
		(keepout
			(tracks not_allowed)
			(vias allowed)
			(pads allowed)
			(copperpour not_allowed)
			(footprints allowed)
		)
		(placement
			(enabled no)
			(sheetname "")
		)
		(fill
			(thermal_gap 0.5)
			(thermal_bridge_width 0.5)
			(island_removal_mode 0)
		)
		(polygon
			(pts
				(arc
					(start 417.217352 -197.582282)
					(mid 417.213632 -197.591262)
					(end 417.204652 -197.594982)
				)
				(arc
					(start 415.731452 -197.594982)
					(mid 415.722472 -197.591262)
					(end 415.718752 -197.582282)
				)
				(arc
					(start 415.718752 -197.087744)
					(mid 415.722472 -197.078764)
					(end 415.731452 -197.075044)
				)
				(arc
					(start 417.204652 -197.075044)
					(mid 417.213632 -197.078764)
					(end 417.217352 -197.087744)
				)
			)
		)
	)
	(zone
		(layer "In1.Cu")
		(hatch none 0.5)
		(connect_pads
			(clearance 0)
		)
		(min_thickness 0.25)
		(keepout
			(tracks not_allowed)
			(vias allowed)
			(pads allowed)
			(copperpour not_allowed)
			(footprints allowed)
		)
		(placement
			(enabled no)
			(sheetname "")
		)
		(fill
			(thermal_gap 0.5)
			(thermal_bridge_width 0.5)
			(island_removal_mode 0)
		)
		(polygon
			(pts
				(arc
					(start 308.117494 -261.332218)
					(mid 308.113774 -261.341198)
					(end 308.104794 -261.344918)
				)
				(arc
					(start 306.631594 -261.344918)
					(mid 306.622614 -261.341198)
					(end 306.618894 -261.332218)
				)
				(arc
					(start 306.618894 -260.83768)
					(mid 306.622614 -260.8287)
					(end 306.631594 -260.82498)
				)
				(arc
					(start 308.104794 -260.82498)
					(mid 308.113774 -260.8287)
					(end 308.117494 -260.83768)
				)
			)
		)
	)
	(zone
		(layer "In1.Cu")
		(hatch none 0.5)
		(connect_pads
			(clearance 0)
		)
		(min_thickness 0.25)
		(keepout
			(tracks not_allowed)
			(vias allowed)
			(pads allowed)
			(copperpour not_allowed)
			(footprints allowed)
		)
		(placement
			(enabled no)
			(sheetname "")
		)
		(fill
			(thermal_gap 0.5)
			(thermal_bridge_width 0.5)
			(island_removal_mode 0)
		)
		(polygon
			(pts
				(arc
					(start 420.661338 -250.282202)
					(mid 420.657618 -250.291182)
					(end 420.648638 -250.294902)
				)
				(arc
					(start 419.175438 -250.294902)
					(mid 419.166458 -250.291182)
					(end 419.162738 -250.282202)
				)
				(arc
					(start 419.162738 -249.787664)
					(mid 419.166458 -249.778684)
					(end 419.175438 -249.774964)
				)
				(arc
					(start 420.648638 -249.774964)
					(mid 420.657618 -249.778684)
					(end 420.661338 -249.787664)
				)
			)
		)
	)
	(zone
		(layer "In1.Cu")
		(hatch none 0.5)
		(connect_pads
			(clearance 0)
		)
		(min_thickness 0.25)
		(keepout
			(tracks not_allowed)
			(vias allowed)
			(pads allowed)
			(copperpour not_allowed)
			(footprints allowed)
		)
		(placement
			(enabled no)
			(sheetname "")
		)
		(fill
			(thermal_gap 0.5)
			(thermal_bridge_width 0.5)
			(island_removal_mode 0)
		)
		(polygon
			(pts
				(arc
					(start 265.87831 -316.335156)
					(mid 265.21791 -316.335156)
					(end 265.87831 -316.335156)
				)
			)
		)
	)
	(zone
		(layer "In1.Cu")
		(hatch none 0.5)
		(connect_pads
			(clearance 0)
		)
		(min_thickness 0.25)
		(keepout
			(tracks not_allowed)
			(vias allowed)
			(pads allowed)
			(copperpour not_allowed)
			(footprints allowed)
		)
		(placement
			(enabled no)
			(sheetname "")
		)
		(fill
			(thermal_gap 0.5)
			(thermal_bridge_width 0.5)
			(island_removal_mode 0)
		)
		(polygon
			(pts
				(arc
					(start 417.217352 -201.83221)
					(mid 417.213632 -201.84119)
					(end 417.204652 -201.84491)
				)
				(arc
					(start 415.731452 -201.84491)
					(mid 415.722472 -201.84119)
					(end 415.718752 -201.83221)
				)
				(arc
					(start 415.718752 -201.337672)
					(mid 415.722472 -201.328692)
					(end 415.731452 -201.324972)
				)
				(arc
					(start 417.204652 -201.324972)
					(mid 417.213632 -201.328692)
					(end 417.217352 -201.337672)
				)
			)
		)
	)
	(zone
		(layer "In1.Cu")
		(hatch none 0.5)
		(connect_pads
			(clearance 0)
		)
		(min_thickness 0.25)
		(keepout
			(tracks not_allowed)
			(vias allowed)
			(pads allowed)
			(copperpour not_allowed)
			(footprints allowed)
		)
		(placement
			(enabled no)
			(sheetname "")
		)
		(fill
			(thermal_gap 0.5)
			(thermal_bridge_width 0.5)
			(island_removal_mode 0)
		)
		(polygon
			(pts
				(arc
					(start 52.633372 -270.682466)
					(mid 52.629652 -270.691446)
					(end 52.620672 -270.695166)
				)
				(arc
					(start 51.147472 -270.695166)
					(mid 51.138492 -270.691446)
					(end 51.134772 -270.682466)
				)
				(arc
					(start 51.134772 -270.187928)
					(mid 51.138492 -270.178948)
					(end 51.147472 -270.175228)
				)
				(arc
					(start 52.620672 -270.175228)
					(mid 52.629652 -270.178948)
					(end 52.633372 -270.187928)
				)
			)
		)
	)
	(zone
		(layer "In1.Cu")
		(hatch none 0.5)
		(connect_pads
			(clearance 0)
		)
		(min_thickness 0.25)
		(keepout
			(tracks not_allowed)
			(vias allowed)
			(pads allowed)
			(copperpour not_allowed)
			(footprints allowed)
		)
		(placement
			(enabled no)
			(sheetname "")
		)
		(fill
			(thermal_gap 0.5)
			(thermal_bridge_width 0.5)
			(island_removal_mode 0)
		)
		(polygon
			(pts
				(arc
					(start 447.393568 -225.632264)
					(mid 447.389848 -225.641244)
					(end 447.380868 -225.644964)
				)
				(arc
					(start 445.907668 -225.644964)
					(mid 445.898688 -225.641244)
					(end 445.894968 -225.632264)
				)
				(arc
					(start 445.894968 -225.137726)
					(mid 445.898688 -225.128746)
					(end 445.907668 -225.125026)
				)
				(arc
					(start 447.380868 -225.125026)
					(mid 447.389848 -225.128746)
					(end 447.393568 -225.137726)
				)
			)
		)
	)
	(zone
		(layer "In1.Cu")
		(hatch none 0.5)
		(connect_pads
			(clearance 0)
		)
		(min_thickness 0.25)
		(keepout
			(tracks not_allowed)
			(vias allowed)
			(pads allowed)
			(copperpour not_allowed)
			(footprints allowed)
		)
		(placement
			(enabled no)
			(sheetname "")
		)
		(fill
			(thermal_gap 0.5)
			(thermal_bridge_width 0.5)
			(island_removal_mode 0)
		)
		(polygon
			(pts
				(arc
					(start 165.177216 -245.18239)
					(mid 165.173496 -245.19137)
					(end 165.164516 -245.19509)
				)
				(arc
					(start 163.691316 -245.19509)
					(mid 163.682336 -245.19137)
					(end 163.678616 -245.18239)
				)
				(arc
					(start 163.678616 -244.687852)
					(mid 163.682336 -244.678872)
					(end 163.691316 -244.675152)
				)
				(arc
					(start 165.164516 -244.675152)
					(mid 165.173496 -244.678872)
					(end 165.177216 -244.687852)
				)
			)
		)
	)
	(zone
		(layer "In1.Cu")
		(hatch none 0.5)
		(connect_pads
			(clearance 0)
		)
		(min_thickness 0.25)
		(keepout
			(tracks not_allowed)
			(vias allowed)
			(pads allowed)
			(copperpour not_allowed)
			(footprints allowed)
		)
		(placement
			(enabled no)
			(sheetname "")
		)
		(fill
			(thermal_gap 0.5)
			(thermal_bridge_width 0.5)
			(island_removal_mode 0)
		)
		(polygon
			(pts
				(arc
					(start 180.265324 -282.582366)
					(mid 180.261604 -282.591346)
					(end 180.252624 -282.595066)
				)
				(arc
					(start 178.779424 -282.595066)
					(mid 178.770444 -282.591346)
					(end 178.766724 -282.582366)
				)
				(arc
					(start 178.766724 -282.087828)
					(mid 178.770444 -282.078848)
					(end 178.779424 -282.075128)
				)
				(arc
					(start 180.252624 -282.075128)
					(mid 180.261604 -282.078848)
					(end 180.265324 -282.087828)
				)
			)
		)
	)
	(zone
		(layer "In1.Cu")
		(hatch none 0.5)
		(connect_pads
			(clearance 0)
		)
		(min_thickness 0.25)
		(keepout
			(tracks not_allowed)
			(vias allowed)
			(pads allowed)
			(copperpour not_allowed)
			(footprints allowed)
		)
		(placement
			(enabled no)
			(sheetname "")
		)
		(fill
			(thermal_gap 0.5)
			(thermal_bridge_width 0.5)
			(island_removal_mode 0)
		)
		(polygon
			(pts
				(arc
					(start 300.57344 -249.432318)
					(mid 300.56972 -249.441298)
					(end 300.56074 -249.445018)
				)
				(arc
					(start 299.08754 -249.445018)
					(mid 299.07856 -249.441298)
					(end 299.07484 -249.432318)
				)
				(arc
					(start 299.07484 -248.93778)
					(mid 299.07856 -248.9288)
					(end 299.08754 -248.92508)
				)
				(arc
					(start 300.56074 -248.92508)
					(mid 300.56972 -248.9288)
					(end 300.57344 -248.93778)
				)
			)
		)
	)
	(zone
		(layer "In1.Cu")
		(hatch none 0.5)
		(connect_pads
			(clearance 0)
		)
		(min_thickness 0.25)
		(keepout
			(tracks not_allowed)
			(vias allowed)
			(pads allowed)
			(copperpour not_allowed)
			(footprints allowed)
		)
		(placement
			(enabled no)
			(sheetname "")
		)
		(fill
			(thermal_gap 0.5)
			(thermal_bridge_width 0.5)
			(island_removal_mode 0)
		)
		(polygon
			(pts
				(arc
					(start 22.45741 -294.48252)
					(mid 22.45369 -294.4915)
					(end 22.44471 -294.49522)
				)
				(arc
					(start 20.97151 -294.49522)
					(mid 20.96253 -294.4915)
					(end 20.95881 -294.48252)
				)
				(arc
					(start 20.95881 -293.987982)
					(mid 20.96253 -293.979002)
					(end 20.97151 -293.975282)
				)
				(arc
					(start 22.44471 -293.975282)
					(mid 22.45369 -293.979002)
					(end 22.45741 -293.987982)
				)
			)
		)
	)
	(zone
		(layer "In1.Cu")
		(hatch none 0.5)
		(connect_pads
			(clearance 0)
		)
		(min_thickness 0.25)
		(keepout
			(tracks not_allowed)
			(vias allowed)
			(pads allowed)
			(copperpour not_allowed)
			(footprints allowed)
		)
		(placement
			(enabled no)
			(sheetname "")
		)
		(fill
			(thermal_gap 0.5)
			(thermal_bridge_width 0.5)
			(island_removal_mode 0)
		)
		(polygon
			(pts
				(arc
					(start 273.841464 -273.232118)
					(mid 273.837744 -273.241098)
					(end 273.828764 -273.244818)
				)
				(arc
					(start 272.355564 -273.244818)
					(mid 272.346584 -273.241098)
					(end 272.342864 -273.232118)
				)
				(arc
					(start 272.342864 -272.73758)
					(mid 272.346584 -272.7286)
					(end 272.355564 -272.72488)
				)
				(arc
					(start 273.828764 -272.72488)
					(mid 273.837744 -272.7286)
					(end 273.841464 -272.73758)
				)
			)
		)
	)
	(zone
		(layer "In1.Cu")
		(hatch none 0.5)
		(connect_pads
			(clearance 0)
		)
		(min_thickness 0.25)
		(keepout
			(tracks not_allowed)
			(vias allowed)
			(pads allowed)
			(copperpour not_allowed)
			(footprints allowed)
		)
		(placement
			(enabled no)
			(sheetname "")
		)
		(fill
			(thermal_gap 0.5)
			(thermal_bridge_width 0.5)
			(island_removal_mode 0)
		)
		(polygon
			(pts
				(arc
					(start 314.660788 -394.385292)
					(mid 314.279788 -394.385292)
					(end 314.660788 -394.385292)
				)
			)
		)
	)
	(zone
		(layer "In1.Cu")
		(hatch none 0.5)
		(connect_pads
			(clearance 0)
		)
		(min_thickness 0.25)
		(keepout
			(tracks not_allowed)
			(vias allowed)
			(pads allowed)
			(copperpour not_allowed)
			(footprints allowed)
		)
		(placement
			(enabled no)
			(sheetname "")
		)
		(fill
			(thermal_gap 0.5)
			(thermal_bridge_width 0.5)
			(island_removal_mode 0)
		)
		(polygon
			(pts
				(arc
					(start 351.031048 -384.288284)
					(mid 351.050972 -384.29752)
					(end 351.072704 -384.30073)
				)
				(arc
					(start 351.267268 -384.30073)
					(mid 351.32115 -384.278412)
					(end 351.343468 -384.22453)
				)
				(arc
					(start 351.343468 -383.53873)
					(mid 351.32115 -383.484848)
					(end 351.267268 -383.46253)
				)
				(arc
					(start 351.072704 -383.46253)
					(mid 351.05096 -383.465698)
					(end 351.031048 -383.474976)
				)
				(arc
					(start 350.734884 -383.667762)
					(mid 350.6932 -383.679984)
					(end 350.651572 -383.667508)
				)
				(arc
					(start 350.357948 -383.474976)
					(mid 350.338024 -383.46574)
					(end 350.316292 -383.46253)
				)
				(arc
					(start 350.121728 -383.46253)
					(mid 350.067846 -383.484848)
					(end 350.045528 -383.53873)
				)
				(arc
					(start 350.045528 -384.22453)
					(mid 350.067846 -384.278412)
					(end 350.121728 -384.30073)
				)
				(arc
					(start 350.317562 -384.30073)
					(mid 350.339306 -384.297562)
					(end 350.359218 -384.288284)
				)
				(arc
					(start 350.652842 -384.095752)
					(mid 350.694498 -384.08335)
					(end 350.736154 -384.095752)
				)
			)
		)
	)
	(zone
		(layer "In1.Cu")
		(hatch none 0.5)
		(connect_pads
			(clearance 0)
		)
		(min_thickness 0.25)
		(keepout
			(tracks not_allowed)
			(vias allowed)
			(pads allowed)
			(copperpour not_allowed)
			(footprints allowed)
		)
		(placement
			(enabled no)
			(sheetname "")
		)
		(fill
			(thermal_gap 0.5)
			(thermal_bridge_width 0.5)
			(island_removal_mode 0)
		)
		(polygon
			(pts
				(arc
					(start 180.265324 -318.282574)
					(mid 180.261604 -318.291554)
					(end 180.252624 -318.295274)
				)
				(arc
					(start 178.779424 -318.295274)
					(mid 178.770444 -318.291554)
					(end 178.766724 -318.282574)
				)
				(arc
					(start 178.766724 -317.788036)
					(mid 178.770444 -317.779056)
					(end 178.779424 -317.775336)
				)
				(arc
					(start 180.252624 -317.775336)
					(mid 180.261604 -317.779056)
					(end 180.265324 -317.788036)
				)
			)
		)
	)
	(zone
		(layer "In1.Cu")
		(hatch none 0.5)
		(connect_pads
			(clearance 0)
		)
		(min_thickness 0.25)
		(keepout
			(tracks not_allowed)
			(vias allowed)
			(pads allowed)
			(copperpour not_allowed)
			(footprints allowed)
		)
		(placement
			(enabled no)
			(sheetname "")
		)
		(fill
			(thermal_gap 0.5)
			(thermal_bridge_width 0.5)
			(island_removal_mode 0)
		)
		(polygon
			(pts
				(arc
					(start 432.30546 -306.382166)
					(mid 432.30174 -306.391146)
					(end 432.29276 -306.394866)
				)
				(arc
					(start 430.81956 -306.394866)
					(mid 430.81058 -306.391146)
					(end 430.80686 -306.382166)
				)
				(arc
					(start 430.80686 -305.887628)
					(mid 430.81058 -305.878648)
					(end 430.81956 -305.874928)
				)
				(arc
					(start 432.29276 -305.874928)
					(mid 432.30174 -305.878648)
					(end 432.30546 -305.887628)
				)
			)
		)
	)
	(zone
		(layer "In1.Cu")
		(hatch none 0.5)
		(connect_pads
			(clearance 0)
		)
		(min_thickness 0.25)
		(keepout
			(tracks not_allowed)
			(vias allowed)
			(pads allowed)
			(copperpour not_allowed)
			(footprints allowed)
		)
		(placement
			(enabled no)
			(sheetname "")
		)
		(fill
			(thermal_gap 0.5)
			(thermal_bridge_width 0.5)
			(island_removal_mode 0)
		)
		(polygon
			(pts
				(arc
					(start 313.061096 -397.156432)
					(mid 312.680096 -397.156432)
					(end 313.061096 -397.156432)
				)
			)
		)
	)
	(zone
		(layer "In1.Cu")
		(hatch none 0.5)
		(connect_pads
			(clearance 0)
		)
		(min_thickness 0.25)
		(keepout
			(tracks not_allowed)
			(vias allowed)
			(pads allowed)
			(copperpour not_allowed)
			(footprints allowed)
		)
		(placement
			(enabled no)
			(sheetname "")
		)
		(fill
			(thermal_gap 0.5)
			(thermal_bridge_width 0.5)
			(island_removal_mode 0)
		)
		(polygon
			(pts
				(arc
					(start 454.937368 -300.432216)
					(mid 454.933648 -300.441196)
					(end 454.924668 -300.444916)
				)
				(arc
					(start 453.451468 -300.444916)
					(mid 453.442488 -300.441196)
					(end 453.438768 -300.432216)
				)
				(arc
					(start 453.438768 -299.937678)
					(mid 453.442488 -299.928698)
					(end 453.451468 -299.924978)
				)
				(arc
					(start 454.924668 -299.924978)
					(mid 454.933648 -299.928698)
					(end 454.937368 -299.937678)
				)
			)
		)
	)
	(zone
		(layer "In1.Cu")
		(hatch none 0.5)
		(connect_pads
			(clearance 0)
		)
		(min_thickness 0.25)
		(keepout
			(tracks not_allowed)
			(vias allowed)
			(pads allowed)
			(copperpour not_allowed)
			(footprints allowed)
		)
		(placement
			(enabled no)
			(sheetname "")
		)
		(fill
			(thermal_gap 0.5)
			(thermal_bridge_width 0.5)
			(island_removal_mode 0)
		)
		(polygon
			(pts
				(arc
					(start 265.87831 -282.33497)
					(mid 265.21791 -282.33497)
					(end 265.87831 -282.33497)
				)
			)
		)
	)
	(zone
		(layer "In1.Cu")
		(hatch none 0.5)
		(connect_pads
			(clearance 0)
		)
		(min_thickness 0.25)
		(keepout
			(tracks not_allowed)
			(vias allowed)
			(pads allowed)
			(copperpour not_allowed)
			(footprints allowed)
		)
		(placement
			(enabled no)
			(sheetname "")
		)
		(fill
			(thermal_gap 0.5)
			(thermal_bridge_width 0.5)
			(island_removal_mode 0)
		)
		(polygon
			(pts
				(arc
					(start 37.545264 -236.682534)
					(mid 37.541544 -236.691514)
					(end 37.532564 -236.695234)
				)
				(arc
					(start 36.059364 -236.695234)
					(mid 36.050384 -236.691514)
					(end 36.046664 -236.682534)
				)
				(arc
					(start 36.046664 -236.187996)
					(mid 36.050384 -236.179016)
					(end 36.059364 -236.175296)
				)
				(arc
					(start 37.532564 -236.175296)
					(mid 37.541544 -236.179016)
					(end 37.545264 -236.187996)
				)
			)
		)
	)
	(zone
		(layer "In1.Cu")
		(hatch none 0.5)
		(connect_pads
			(clearance 0)
		)
		(min_thickness 0.25)
		(keepout
			(tracks not_allowed)
			(vias allowed)
			(pads allowed)
			(copperpour not_allowed)
			(footprints allowed)
		)
		(placement
			(enabled no)
			(sheetname "")
		)
		(fill
			(thermal_gap 0.5)
			(thermal_bridge_width 0.5)
			(island_removal_mode 0)
		)
		(polygon
			(pts
				(arc
					(start 381.470408 -399.143474)
					(mid 381.165608 -399.143474)
					(end 381.470408 -399.143474)
				)
			)
		)
	)
	(zone
		(layer "In1.Cu")
		(hatch none 0.5)
		(connect_pads
			(clearance 0)
		)
		(min_thickness 0.25)
		(keepout
			(tracks not_allowed)
			(vias allowed)
			(pads allowed)
			(copperpour not_allowed)
			(footprints allowed)
		)
		(placement
			(enabled no)
			(sheetname "")
		)
		(fill
			(thermal_gap 0.5)
			(thermal_bridge_width 0.5)
			(island_removal_mode 0)
		)
		(polygon
			(pts
				(arc
					(start 350.497902 -399.143474)
					(mid 350.193102 -399.143474)
					(end 350.497902 -399.143474)
				)
			)
		)
	)
	(zone
		(layer "In1.Cu")
		(hatch none 0.5)
		(connect_pads
			(clearance 0)
		)
		(min_thickness 0.25)
		(keepout
			(tracks not_allowed)
			(vias allowed)
			(pads allowed)
			(copperpour not_allowed)
			(footprints allowed)
		)
		(placement
			(enabled no)
			(sheetname "")
		)
		(fill
			(thermal_gap 0.5)
			(thermal_bridge_width 0.5)
			(island_removal_mode 0)
		)
		(polygon
			(pts
				(arc
					(start 288.929318 -263.882124)
					(mid 288.925598 -263.891104)
					(end 288.916618 -263.894824)
				)
				(arc
					(start 287.443418 -263.894824)
					(mid 287.434438 -263.891104)
					(end 287.430718 -263.882124)
				)
				(arc
					(start 287.430718 -263.387586)
					(mid 287.434438 -263.378606)
					(end 287.443418 -263.374886)
				)
				(arc
					(start 288.916618 -263.374886)
					(mid 288.925598 -263.378606)
					(end 288.929318 -263.387586)
				)
			)
		)
	)
	(zone
		(layer "In1.Cu")
		(hatch none 0.5)
		(connect_pads
			(clearance 0)
		)
		(min_thickness 0.25)
		(keepout
			(tracks not_allowed)
			(vias allowed)
			(pads allowed)
			(copperpour not_allowed)
			(footprints allowed)
		)
		(placement
			(enabled no)
			(sheetname "")
		)
		(fill
			(thermal_gap 0.5)
			(thermal_bridge_width 0.5)
			(island_removal_mode 0)
		)
		(polygon
			(pts
				(arc
					(start 184.365392 -283.432504)
					(mid 184.361672 -283.441484)
					(end 184.352692 -283.445204)
				)
				(arc
					(start 182.879492 -283.445204)
					(mid 182.870512 -283.441484)
					(end 182.866792 -283.432504)
				)
				(arc
					(start 182.866792 -282.937966)
					(mid 182.870512 -282.928986)
					(end 182.879492 -282.925266)
				)
				(arc
					(start 184.352692 -282.925266)
					(mid 184.361672 -282.928986)
					(end 184.365392 -282.937966)
				)
			)
		)
	)
	(zone
		(layer "In1.Cu")
		(hatch none 0.5)
		(connect_pads
			(clearance 0)
		)
		(min_thickness 0.25)
		(keepout
			(tracks not_allowed)
			(vias allowed)
			(pads allowed)
			(copperpour not_allowed)
			(footprints allowed)
		)
		(placement
			(enabled no)
			(sheetname "")
		)
		(fill
			(thermal_gap 0.5)
			(thermal_bridge_width 0.5)
			(island_removal_mode 0)
		)
		(polygon
			(pts
				(arc
					(start 90.318844 -383.440686)
					(mid 90.445844 -383.567686)
					(end 90.572844 -383.440686)
				)
				(arc
					(start 90.572844 -383.364486)
					(mid 90.445844 -383.237486)
					(end 90.318844 -383.364486)
				)
			)
		)
	)
	(zone
		(layer "In1.Cu")
		(hatch none 0.5)
		(connect_pads
			(clearance 0)
		)
		(min_thickness 0.25)
		(keepout
			(tracks not_allowed)
			(vias allowed)
			(pads allowed)
			(copperpour not_allowed)
			(footprints allowed)
		)
		(placement
			(enabled no)
			(sheetname "")
		)
		(fill
			(thermal_gap 0.5)
			(thermal_bridge_width 0.5)
			(island_removal_mode 0)
		)
		(polygon
			(pts
				(arc
					(start 184.365392 -201.832464)
					(mid 184.361672 -201.841444)
					(end 184.352692 -201.845164)
				)
				(arc
					(start 182.879492 -201.845164)
					(mid 182.870512 -201.841444)
					(end 182.866792 -201.832464)
				)
				(arc
					(start 182.866792 -201.337926)
					(mid 182.870512 -201.328946)
					(end 182.879492 -201.325226)
				)
				(arc
					(start 184.352692 -201.325226)
					(mid 184.361672 -201.328946)
					(end 184.365392 -201.337926)
				)
			)
		)
	)
	(zone
		(layer "In1.Cu")
		(hatch none 0.5)
		(connect_pads
			(clearance 0)
		)
		(min_thickness 0.25)
		(keepout
			(tracks not_allowed)
			(vias allowed)
			(pads allowed)
			(copperpour not_allowed)
			(footprints allowed)
		)
		(placement
			(enabled no)
			(sheetname "")
		)
		(fill
			(thermal_gap 0.5)
			(thermal_bridge_width 0.5)
			(island_removal_mode 0)
		)
		(polygon
			(pts
				(arc
					(start 84.78901 -388.774432)
					(mid 84.40801 -388.774432)
					(end 84.78901 -388.774432)
				)
			)
		)
	)
	(zone
		(layer "In1.Cu")
		(hatch none 0.5)
		(connect_pads
			(clearance 0)
		)
		(min_thickness 0.25)
		(keepout
			(tracks not_allowed)
			(vias allowed)
			(pads allowed)
			(copperpour not_allowed)
			(footprints allowed)
		)
		(placement
			(enabled no)
			(sheetname "")
		)
		(fill
			(thermal_gap 0.5)
			(thermal_bridge_width 0.5)
			(island_removal_mode 0)
		)
		(polygon
			(pts
				(arc
					(start 60.177426 -229.882446)
					(mid 60.173706 -229.891426)
					(end 60.164726 -229.895146)
				)
				(arc
					(start 58.691526 -229.895146)
					(mid 58.682546 -229.891426)
					(end 58.678826 -229.882446)
				)
				(arc
					(start 58.678826 -229.387908)
					(mid 58.682546 -229.378928)
					(end 58.691526 -229.375208)
				)
				(arc
					(start 60.164726 -229.375208)
					(mid 60.173706 -229.378928)
					(end 60.177426 -229.387908)
				)
			)
		)
	)
	(zone
		(layer "In1.Cu")
		(hatch none 0.5)
		(connect_pads
			(clearance 0)
		)
		(min_thickness 0.25)
		(keepout
			(tracks not_allowed)
			(vias allowed)
			(pads allowed)
			(copperpour not_allowed)
			(footprints allowed)
		)
		(placement
			(enabled no)
			(sheetname "")
		)
		(fill
			(thermal_gap 0.5)
			(thermal_bridge_width 0.5)
			(island_removal_mode 0)
		)
		(polygon
			(pts
				(arc
					(start 52.633372 -289.382454)
					(mid 52.629652 -289.391434)
					(end 52.620672 -289.395154)
				)
				(arc
					(start 51.147472 -289.395154)
					(mid 51.138492 -289.391434)
					(end 51.134772 -289.382454)
				)
				(arc
					(start 51.134772 -288.887916)
					(mid 51.138492 -288.878936)
					(end 51.147472 -288.875216)
				)
				(arc
					(start 52.620672 -288.875216)
					(mid 52.629652 -288.878936)
					(end 52.633372 -288.887916)
				)
			)
		)
	)
	(zone
		(layer "In1.Cu")
		(hatch none 0.5)
		(connect_pads
			(clearance 0)
		)
		(min_thickness 0.25)
		(keepout
			(tracks not_allowed)
			(vias allowed)
			(pads allowed)
			(copperpour not_allowed)
			(footprints allowed)
		)
		(placement
			(enabled no)
			(sheetname "")
		)
		(fill
			(thermal_gap 0.5)
			(thermal_bridge_width 0.5)
			(island_removal_mode 0)
		)
		(polygon
			(pts
				(arc
					(start 53.570378 -383.92227)
					(mid 53.265578 -383.92227)
					(end 53.570378 -383.92227)
				)
			)
		)
	)
	(zone
		(layer "In1.Cu")
		(hatch none 0.5)
		(connect_pads
			(clearance 0)
		)
		(min_thickness 0.25)
		(keepout
			(tracks not_allowed)
			(vias allowed)
			(pads allowed)
			(copperpour not_allowed)
			(footprints allowed)
		)
		(placement
			(enabled no)
			(sheetname "")
		)
		(fill
			(thermal_gap 0.5)
			(thermal_bridge_width 0.5)
			(island_removal_mode 0)
		)
		(polygon
			(pts
				(arc
					(start 202.897232 -273.232372)
					(mid 202.893512 -273.241352)
					(end 202.884532 -273.245072)
				)
				(arc
					(start 201.411332 -273.245072)
					(mid 201.402352 -273.241352)
					(end 201.398632 -273.232372)
				)
				(arc
					(start 201.398632 -272.737834)
					(mid 201.402352 -272.728854)
					(end 201.411332 -272.725134)
				)
				(arc
					(start 202.884532 -272.725134)
					(mid 202.893512 -272.728854)
					(end 202.897232 -272.737834)
				)
			)
		)
	)
	(zone
		(layer "In1.Cu")
		(hatch none 0.5)
		(connect_pads
			(clearance 0)
		)
		(min_thickness 0.25)
		(keepout
			(tracks not_allowed)
			(vias allowed)
			(pads allowed)
			(copperpour not_allowed)
			(footprints allowed)
		)
		(placement
			(enabled no)
			(sheetname "")
		)
		(fill
			(thermal_gap 0.5)
			(thermal_bridge_width 0.5)
			(island_removal_mode 0)
		)
		(polygon
			(pts
				(arc
					(start 308.6608 -397.849344)
					(mid 308.2798 -397.849344)
					(end 308.6608 -397.849344)
				)
			)
		)
	)
	(zone
		(layer "In1.Cu")
		(hatch none 0.5)
		(connect_pads
			(clearance 0)
		)
		(min_thickness 0.25)
		(keepout
			(tracks not_allowed)
			(vias allowed)
			(pads allowed)
			(copperpour not_allowed)
			(footprints allowed)
		)
		(placement
			(enabled no)
			(sheetname "")
		)
		(fill
			(thermal_gap 0.5)
			(thermal_bridge_width 0.5)
			(island_removal_mode 0)
		)
		(polygon
			(pts
				(arc
					(start 265.87831 -213.484968)
					(mid 265.21791 -213.484968)
					(end 265.87831 -213.484968)
				)
			)
		)
	)
	(zone
		(layer "In1.Cu")
		(hatch none 0.5)
		(connect_pads
			(clearance 0)
		)
		(min_thickness 0.25)
		(keepout
			(tracks not_allowed)
			(vias allowed)
			(pads allowed)
			(copperpour not_allowed)
			(footprints allowed)
		)
		(placement
			(enabled no)
			(sheetname "")
		)
		(fill
			(thermal_gap 0.5)
			(thermal_bridge_width 0.5)
			(island_removal_mode 0)
		)
		(polygon
			(pts
				(arc
					(start 191.909446 -212.88248)
					(mid 191.905726 -212.89146)
					(end 191.896746 -212.89518)
				)
				(arc
					(start 190.423546 -212.89518)
					(mid 190.414566 -212.89146)
					(end 190.410846 -212.88248)
				)
				(arc
					(start 190.410846 -212.387942)
					(mid 190.414566 -212.378962)
					(end 190.423546 -212.375242)
				)
				(arc
					(start 191.896746 -212.375242)
					(mid 191.905726 -212.378962)
					(end 191.909446 -212.387942)
				)
			)
		)
	)
	(zone
		(layer "In1.Cu")
		(hatch none 0.5)
		(connect_pads
			(clearance 0)
		)
		(min_thickness 0.25)
		(keepout
			(tracks not_allowed)
			(vias allowed)
			(pads allowed)
			(copperpour not_allowed)
			(footprints allowed)
		)
		(placement
			(enabled no)
			(sheetname "")
		)
		(fill
			(thermal_gap 0.5)
			(thermal_bridge_width 0.5)
			(island_removal_mode 0)
		)
		(polygon
			(pts
				(arc
					(start 447.393568 -289.3822)
					(mid 447.389848 -289.39118)
					(end 447.380868 -289.3949)
				)
				(arc
					(start 445.907668 -289.3949)
					(mid 445.898688 -289.39118)
					(end 445.894968 -289.3822)
				)
				(arc
					(start 445.894968 -288.887662)
					(mid 445.898688 -288.878682)
					(end 445.907668 -288.874962)
				)
				(arc
					(start 447.380868 -288.874962)
					(mid 447.389848 -288.878682)
					(end 447.393568 -288.887662)
				)
			)
		)
	)
	(zone
		(layer "In1.Cu")
		(hatch none 0.5)
		(connect_pads
			(clearance 0)
		)
		(min_thickness 0.25)
		(keepout
			(tracks not_allowed)
			(vias allowed)
			(pads allowed)
			(copperpour not_allowed)
			(footprints allowed)
		)
		(placement
			(enabled no)
			(sheetname "")
		)
		(fill
			(thermal_gap 0.5)
			(thermal_bridge_width 0.5)
			(island_removal_mode 0)
		)
		(polygon
			(pts
				(arc
					(start 266.29741 -314.032138)
					(mid 266.29369 -314.041118)
					(end 266.28471 -314.044838)
				)
				(arc
					(start 264.81151 -314.044838)
					(mid 264.80253 -314.041118)
					(end 264.79881 -314.032138)
				)
				(arc
					(start 264.79881 -313.5376)
					(mid 264.80253 -313.52862)
					(end 264.81151 -313.5249)
				)
				(arc
					(start 266.28471 -313.5249)
					(mid 266.29369 -313.52862)
					(end 266.29741 -313.5376)
				)
			)
		)
	)
	(zone
		(layer "In1.Cu")
		(hatch none 0.5)
		(connect_pads
			(clearance 0)
		)
		(min_thickness 0.25)
		(keepout
			(tracks not_allowed)
			(vias allowed)
			(pads allowed)
			(copperpour not_allowed)
			(footprints allowed)
		)
		(placement
			(enabled no)
			(sheetname "")
		)
		(fill
			(thermal_gap 0.5)
			(thermal_bridge_width 0.5)
			(island_removal_mode 0)
		)
		(polygon
			(pts
				(arc
					(start 96.788986 -385.31038)
					(mid 96.407986 -385.31038)
					(end 96.788986 -385.31038)
				)
			)
		)
	)
	(zone
		(layer "In1.Cu")
		(hatch none 0.5)
		(connect_pads
			(clearance 0)
		)
		(min_thickness 0.25)
		(keepout
			(tracks not_allowed)
			(vias allowed)
			(pads allowed)
			(copperpour not_allowed)
			(footprints allowed)
		)
		(placement
			(enabled no)
			(sheetname "")
		)
		(fill
			(thermal_gap 0.5)
			(thermal_bridge_width 0.5)
			(island_removal_mode 0)
		)
		(polygon
			(pts
				(arc
					(start 424.761406 -234.982258)
					(mid 424.757686 -234.991238)
					(end 424.748706 -234.994958)
				)
				(arc
					(start 423.275506 -234.994958)
					(mid 423.266526 -234.991238)
					(end 423.262806 -234.982258)
				)
				(arc
					(start 423.262806 -234.48772)
					(mid 423.266526 -234.47874)
					(end 423.275506 -234.47502)
				)
				(arc
					(start 424.748706 -234.47502)
					(mid 424.757686 -234.47874)
					(end 424.761406 -234.48772)
				)
			)
		)
	)
	(zone
		(layer "In1.Cu")
		(hatch none 0.5)
		(connect_pads
			(clearance 0)
		)
		(min_thickness 0.25)
		(keepout
			(tracks not_allowed)
			(vias allowed)
			(pads allowed)
			(copperpour not_allowed)
			(footprints allowed)
		)
		(placement
			(enabled no)
			(sheetname "")
		)
		(fill
			(thermal_gap 0.5)
			(thermal_bridge_width 0.5)
			(island_removal_mode 0)
		)
		(polygon
			(pts
				(arc
					(start 199.4535 -200.98258)
					(mid 199.44978 -200.99156)
					(end 199.4408 -200.99528)
				)
				(arc
					(start 197.9676 -200.99528)
					(mid 197.95862 -200.99156)
					(end 197.9549 -200.98258)
				)
				(arc
					(start 197.9549 -200.488042)
					(mid 197.95862 -200.479062)
					(end 197.9676 -200.475342)
				)
				(arc
					(start 199.4408 -200.475342)
					(mid 199.44978 -200.479062)
					(end 199.4535 -200.488042)
				)
			)
		)
	)
	(zone
		(layer "In1.Cu")
		(hatch none 0.5)
		(connect_pads
			(clearance 0)
		)
		(min_thickness 0.25)
		(keepout
			(tracks not_allowed)
			(vias allowed)
			(pads allowed)
			(copperpour not_allowed)
			(footprints allowed)
		)
		(placement
			(enabled no)
			(sheetname "")
		)
		(fill
			(thermal_gap 0.5)
			(thermal_bridge_width 0.5)
			(island_removal_mode 0)
		)
		(polygon
			(pts
				(arc
					(start 135.555228 -15.90294)
					(mid 135.577546 -15.849058)
					(end 135.631428 -15.82674)
				)
				(arc
					(start 136.459976 -15.82674)
					(mid 136.513858 -15.849058)
					(end 136.536176 -15.90294)
				)
				(arc
					(start 136.536176 -17.19834)
					(mid 136.513858 -17.252222)
					(end 136.459976 -17.27454)
				)
				(arc
					(start 135.631428 -17.27454)
					(mid 135.577546 -17.252222)
					(end 135.555228 -17.19834)
				)
			)
		)
	)
	(zone
		(layer "In1.Cu")
		(hatch none 0.5)
		(connect_pads
			(clearance 0)
		)
		(min_thickness 0.25)
		(keepout
			(tracks not_allowed)
			(vias allowed)
			(pads allowed)
			(copperpour not_allowed)
			(footprints allowed)
		)
		(placement
			(enabled no)
			(sheetname "")
		)
		(fill
			(thermal_gap 0.5)
			(thermal_bridge_width 0.5)
			(island_removal_mode 0)
		)
		(polygon
			(pts
				(arc
					(start 432.30546 -314.032138)
					(mid 432.30174 -314.041118)
					(end 432.29276 -314.044838)
				)
				(arc
					(start 430.81956 -314.044838)
					(mid 430.81058 -314.041118)
					(end 430.80686 -314.032138)
				)
				(arc
					(start 430.80686 -313.5376)
					(mid 430.81058 -313.52862)
					(end 430.81956 -313.5249)
				)
				(arc
					(start 432.29276 -313.5249)
					(mid 432.30174 -313.52862)
					(end 432.30546 -313.5376)
				)
			)
		)
	)
	(zone
		(layer "In1.Cu")
		(hatch none 0.5)
		(connect_pads
			(clearance 0)
		)
		(min_thickness 0.25)
		(keepout
			(tracks not_allowed)
			(vias allowed)
			(pads allowed)
			(copperpour not_allowed)
			(footprints allowed)
		)
		(placement
			(enabled no)
			(sheetname "")
		)
		(fill
			(thermal_gap 0.5)
			(thermal_bridge_width 0.5)
			(island_removal_mode 0)
		)
		(polygon
			(pts
				(arc
					(start 293.029386 -303.83226)
					(mid 293.025666 -303.84124)
					(end 293.016686 -303.84496)
				)
				(arc
					(start 291.543486 -303.84496)
					(mid 291.534506 -303.84124)
					(end 291.530786 -303.83226)
				)
				(arc
					(start 291.530786 -303.337722)
					(mid 291.534506 -303.328742)
					(end 291.543486 -303.325022)
				)
				(arc
					(start 293.016686 -303.325022)
					(mid 293.025666 -303.328742)
					(end 293.029386 -303.337722)
				)
			)
		)
	)
	(zone
		(layer "In1.Cu")
		(hatch none 0.5)
		(connect_pads
			(clearance 0)
		)
		(min_thickness 0.25)
		(keepout
			(tracks not_allowed)
			(vias allowed)
			(pads allowed)
			(copperpour not_allowed)
			(footprints allowed)
		)
		(placement
			(enabled no)
			(sheetname "")
		)
		(fill
			(thermal_gap 0.5)
			(thermal_bridge_width 0.5)
			(island_removal_mode 0)
		)
		(polygon
			(pts
				(arc
					(start 33.445196 -290.232592)
					(mid 33.441476 -290.241572)
					(end 33.432496 -290.245292)
				)
				(arc
					(start 31.959296 -290.245292)
					(mid 31.950316 -290.241572)
					(end 31.946596 -290.232592)
				)
				(arc
					(start 31.946596 -289.738054)
					(mid 31.950316 -289.729074)
					(end 31.959296 -289.725354)
				)
				(arc
					(start 33.432496 -289.725354)
					(mid 33.441476 -289.729074)
					(end 33.445196 -289.738054)
				)
			)
		)
	)
	(zone
		(layer "In1.Cu")
		(hatch none 0.5)
		(connect_pads
			(clearance 0)
		)
		(min_thickness 0.25)
		(keepout
			(tracks not_allowed)
			(vias allowed)
			(pads allowed)
			(copperpour not_allowed)
			(footprints allowed)
		)
		(placement
			(enabled no)
			(sheetname "")
		)
		(fill
			(thermal_gap 0.5)
			(thermal_bridge_width 0.5)
			(island_removal_mode 0)
		)
		(polygon
			(pts
				(arc
					(start 161.888678 -389.467344)
					(mid 161.507678 -389.467344)
					(end 161.888678 -389.467344)
				)
			)
		)
	)
	(zone
		(layer "In1.Cu")
		(hatch none 0.5)
		(connect_pads
			(clearance 0)
		)
		(min_thickness 0.25)
		(keepout
			(tracks not_allowed)
			(vias allowed)
			(pads allowed)
			(copperpour not_allowed)
			(footprints allowed)
		)
		(placement
			(enabled no)
			(sheetname "")
		)
		(fill
			(thermal_gap 0.5)
			(thermal_bridge_width 0.5)
			(island_removal_mode 0)
		)
		(polygon
			(pts
				(arc
					(start 435.749446 -202.682094)
					(mid 435.745726 -202.691074)
					(end 435.736746 -202.694794)
				)
				(arc
					(start 434.263546 -202.694794)
					(mid 434.254566 -202.691074)
					(end 434.250846 -202.682094)
				)
				(arc
					(start 434.250846 -202.187556)
					(mid 434.254566 -202.178576)
					(end 434.263546 -202.174856)
				)
				(arc
					(start 435.736746 -202.174856)
					(mid 435.745726 -202.178576)
					(end 435.749446 -202.187556)
				)
			)
		)
	)
	(zone
		(layer "In1.Cu")
		(hatch none 0.5)
		(connect_pads
			(clearance 0)
		)
		(min_thickness 0.25)
		(keepout
			(tracks not_allowed)
			(vias allowed)
			(pads allowed)
			(copperpour not_allowed)
			(footprints allowed)
		)
		(placement
			(enabled no)
			(sheetname "")
		)
		(fill
			(thermal_gap 0.5)
			(thermal_bridge_width 0.5)
			(island_removal_mode 0)
		)
		(polygon
			(pts
				(arc
					(start 60.177426 -238.382556)
					(mid 60.173706 -238.391536)
					(end 60.164726 -238.395256)
				)
				(arc
					(start 58.691526 -238.395256)
					(mid 58.682546 -238.391536)
					(end 58.678826 -238.382556)
				)
				(arc
					(start 58.678826 -237.888018)
					(mid 58.682546 -237.879038)
					(end 58.691526 -237.875318)
				)
				(arc
					(start 60.164726 -237.875318)
					(mid 60.173706 -237.879038)
					(end 60.177426 -237.888018)
				)
			)
		)
	)
	(zone
		(layer "In1.Cu")
		(hatch none 0.5)
		(connect_pads
			(clearance 0)
		)
		(min_thickness 0.25)
		(keepout
			(tracks not_allowed)
			(vias allowed)
			(pads allowed)
			(copperpour not_allowed)
			(footprints allowed)
		)
		(placement
			(enabled no)
			(sheetname "")
		)
		(fill
			(thermal_gap 0.5)
			(thermal_bridge_width 0.5)
			(island_removal_mode 0)
		)
		(polygon
			(pts
				(arc
					(start 376.090942 -399.701258)
					(mid 376.217942 -399.828258)
					(end 376.344942 -399.701258)
				)
				(arc
					(start 376.344942 -399.625058)
					(mid 376.217942 -399.498058)
					(end 376.090942 -399.625058)
				)
			)
		)
	)
	(zone
		(layer "In1.Cu")
		(hatch none 0.5)
		(connect_pads
			(clearance 0)
		)
		(min_thickness 0.25)
		(keepout
			(tracks not_allowed)
			(vias allowed)
			(pads allowed)
			(copperpour not_allowed)
			(footprints allowed)
		)
		(placement
			(enabled no)
			(sheetname "")
		)
		(fill
			(thermal_gap 0.5)
			(thermal_bridge_width 0.5)
			(island_removal_mode 0)
		)
		(polygon
			(pts
				(arc
					(start 30.001464 -298.732448)
					(mid 29.997744 -298.741428)
					(end 29.988764 -298.745148)
				)
				(arc
					(start 28.515564 -298.745148)
					(mid 28.506584 -298.741428)
					(end 28.502864 -298.732448)
				)
				(arc
					(start 28.502864 -298.23791)
					(mid 28.506584 -298.22893)
					(end 28.515564 -298.22521)
				)
				(arc
					(start 29.988764 -298.22521)
					(mid 29.997744 -298.22893)
					(end 30.001464 -298.23791)
				)
			)
		)
	)
	(zone
		(layer "In1.Cu")
		(hatch none 0.5)
		(connect_pads
			(clearance 0)
		)
		(min_thickness 0.25)
		(keepout
			(tracks not_allowed)
			(vias allowed)
			(pads allowed)
			(copperpour not_allowed)
			(footprints allowed)
		)
		(placement
			(enabled no)
			(sheetname "")
		)
		(fill
			(thermal_gap 0.5)
			(thermal_bridge_width 0.5)
			(island_removal_mode 0)
		)
		(polygon
			(pts
				(arc
					(start 351.988628 -397.849344)
					(mid 351.607628 -397.849344)
					(end 351.988628 -397.849344)
				)
			)
		)
	)
	(zone
		(layer "In1.Cu")
		(hatch none 0.5)
		(connect_pads
			(clearance 0)
		)
		(min_thickness 0.25)
		(keepout
			(tracks not_allowed)
			(vias allowed)
			(pads allowed)
			(copperpour not_allowed)
			(footprints allowed)
		)
		(placement
			(enabled no)
			(sheetname "")
		)
		(fill
			(thermal_gap 0.5)
			(thermal_bridge_width 0.5)
			(island_removal_mode 0)
		)
		(polygon
			(pts
				(arc
					(start 296.473372 -273.232118)
					(mid 296.469652 -273.241098)
					(end 296.460672 -273.244818)
				)
				(arc
					(start 294.987472 -273.244818)
					(mid 294.978492 -273.241098)
					(end 294.974772 -273.232118)
				)
				(arc
					(start 294.974772 -272.73758)
					(mid 294.978492 -272.7286)
					(end 294.987472 -272.72488)
				)
				(arc
					(start 296.460672 -272.72488)
					(mid 296.469652 -272.7286)
					(end 296.473372 -272.73758)
				)
			)
		)
	)
	(zone
		(layer "In1.Cu")
		(hatch none 0.5)
		(connect_pads
			(clearance 0)
		)
		(min_thickness 0.25)
		(keepout
			(tracks not_allowed)
			(vias allowed)
			(pads allowed)
			(copperpour not_allowed)
			(footprints allowed)
		)
		(placement
			(enabled no)
			(sheetname "")
		)
		(fill
			(thermal_gap 0.5)
			(thermal_bridge_width 0.5)
			(island_removal_mode 0)
		)
		(polygon
			(pts
				(arc
					(start 187.809378 -250.282456)
					(mid 187.805658 -250.291436)
					(end 187.796678 -250.295156)
				)
				(arc
					(start 186.323478 -250.295156)
					(mid 186.314498 -250.291436)
					(end 186.310778 -250.282456)
				)
				(arc
					(start 186.310778 -249.787918)
					(mid 186.314498 -249.778938)
					(end 186.323478 -249.775218)
				)
				(arc
					(start 187.796678 -249.775218)
					(mid 187.805658 -249.778938)
					(end 187.809378 -249.787918)
				)
			)
		)
	)
	(zone
		(layer "In1.Cu")
		(hatch none 0.5)
		(connect_pads
			(clearance 0)
		)
		(min_thickness 0.25)
		(keepout
			(tracks not_allowed)
			(vias allowed)
			(pads allowed)
			(copperpour not_allowed)
			(footprints allowed)
		)
		(placement
			(enabled no)
			(sheetname "")
		)
		(fill
			(thermal_gap 0.5)
			(thermal_bridge_width 0.5)
			(island_removal_mode 0)
		)
		(polygon
			(pts
				(arc
					(start 266.29741 -268.98219)
					(mid 266.29369 -268.99117)
					(end 266.28471 -268.99489)
				)
				(arc
					(start 264.81151 -268.99489)
					(mid 264.80253 -268.99117)
					(end 264.79881 -268.98219)
				)
				(arc
					(start 264.79881 -268.487652)
					(mid 264.80253 -268.478672)
					(end 264.81151 -268.474952)
				)
				(arc
					(start 266.28471 -268.474952)
					(mid 266.29369 -268.478672)
					(end 266.29741 -268.487652)
				)
			)
		)
	)
	(zone
		(layer "In1.Cu")
		(hatch none 0.5)
		(connect_pads
			(clearance 0)
		)
		(min_thickness 0.25)
		(keepout
			(tracks not_allowed)
			(vias allowed)
			(pads allowed)
			(copperpour not_allowed)
			(footprints allowed)
		)
		(placement
			(enabled no)
			(sheetname "")
		)
		(fill
			(thermal_gap 0.5)
			(thermal_bridge_width 0.5)
			(island_removal_mode 0)
		)
		(polygon
			(pts
				(arc
					(start 48.533304 -198.43242)
					(mid 48.529584 -198.4414)
					(end 48.520604 -198.44512)
				)
				(arc
					(start 47.047404 -198.44512)
					(mid 47.038424 -198.4414)
					(end 47.034704 -198.43242)
				)
				(arc
					(start 47.034704 -197.937882)
					(mid 47.038424 -197.928902)
					(end 47.047404 -197.925182)
				)
				(arc
					(start 48.520604 -197.925182)
					(mid 48.529584 -197.928902)
					(end 48.533304 -197.937882)
				)
			)
		)
	)
	(zone
		(layer "In1.Cu")
		(hatch none 0.5)
		(connect_pads
			(clearance 0)
		)
		(min_thickness 0.25)
		(keepout
			(tracks not_allowed)
			(vias allowed)
			(pads allowed)
			(copperpour not_allowed)
			(footprints allowed)
		)
		(placement
			(enabled no)
			(sheetname "")
		)
		(fill
			(thermal_gap 0.5)
			(thermal_bridge_width 0.5)
			(island_removal_mode 0)
		)
		(polygon
			(pts
				(arc
					(start 439.849514 -203.532232)
					(mid 439.845794 -203.541212)
					(end 439.836814 -203.544932)
				)
				(arc
					(start 438.363614 -203.544932)
					(mid 438.354634 -203.541212)
					(end 438.350914 -203.532232)
				)
				(arc
					(start 438.350914 -203.037694)
					(mid 438.354634 -203.028714)
					(end 438.363614 -203.024994)
				)
				(arc
					(start 439.836814 -203.024994)
					(mid 439.845794 -203.028714)
					(end 439.849514 -203.037694)
				)
			)
		)
	)
	(zone
		(layer "In1.Cu")
		(hatch none 0.5)
		(connect_pads
			(clearance 0)
		)
		(min_thickness 0.25)
		(keepout
			(tracks not_allowed)
			(vias allowed)
			(pads allowed)
			(copperpour not_allowed)
			(footprints allowed)
		)
		(placement
			(enabled no)
			(sheetname "")
		)
		(fill
			(thermal_gap 0.5)
			(thermal_bridge_width 0.5)
			(island_removal_mode 0)
		)
		(polygon
			(pts
				(arc
					(start 60.177426 -303.832514)
					(mid 60.173706 -303.841494)
					(end 60.164726 -303.845214)
				)
				(arc
					(start 58.691526 -303.845214)
					(mid 58.682546 -303.841494)
					(end 58.678826 -303.832514)
				)
				(arc
					(start 58.678826 -303.337976)
					(mid 58.682546 -303.328996)
					(end 58.691526 -303.325276)
				)
				(arc
					(start 60.164726 -303.325276)
					(mid 60.173706 -303.328996)
					(end 60.177426 -303.337976)
				)
			)
		)
	)
	(zone
		(layer "In1.Cu")
		(hatch none 0.5)
		(connect_pads
			(clearance 0)
		)
		(min_thickness 0.25)
		(keepout
			(tracks not_allowed)
			(vias allowed)
			(pads allowed)
			(copperpour not_allowed)
			(footprints allowed)
		)
		(placement
			(enabled no)
			(sheetname "")
		)
		(fill
			(thermal_gap 0.5)
			(thermal_bridge_width 0.5)
			(island_removal_mode 0)
		)
		(polygon
			(pts
				(arc
					(start 48.47082 -385.11988)
					(mid 48.47082 -385.50088)
					(end 48.47082 -385.11988)
				)
			)
		)
	)
	(zone
		(layer "In1.Cu")
		(hatch none 0.5)
		(connect_pads
			(clearance 0)
		)
		(min_thickness 0.25)
		(keepout
			(tracks not_allowed)
			(vias allowed)
			(pads allowed)
			(copperpour not_allowed)
			(footprints allowed)
		)
		(placement
			(enabled no)
			(sheetname "")
		)
		(fill
			(thermal_gap 0.5)
			(thermal_bridge_width 0.5)
			(island_removal_mode 0)
		)
		(polygon
			(pts
				(arc
					(start 285.485332 -272.382234)
					(mid 285.481612 -272.391214)
					(end 285.472632 -272.394934)
				)
				(arc
					(start 283.999432 -272.394934)
					(mid 283.990452 -272.391214)
					(end 283.986732 -272.382234)
				)
				(arc
					(start 283.986732 -271.887696)
					(mid 283.990452 -271.878716)
					(end 283.999432 -271.874996)
				)
				(arc
					(start 285.472632 -271.874996)
					(mid 285.481612 -271.878716)
					(end 285.485332 -271.887696)
				)
			)
		)
	)
	(zone
		(layer "In1.Cu")
		(hatch none 0.5)
		(connect_pads
			(clearance 0)
		)
		(min_thickness 0.25)
		(keepout
			(tracks not_allowed)
			(vias allowed)
			(pads allowed)
			(copperpour not_allowed)
			(footprints allowed)
		)
		(placement
			(enabled no)
			(sheetname "")
		)
		(fill
			(thermal_gap 0.5)
			(thermal_bridge_width 0.5)
			(island_removal_mode 0)
		)
		(polygon
			(pts
				(arc
					(start 420.661338 -218.832176)
					(mid 420.657618 -218.841156)
					(end 420.648638 -218.844876)
				)
				(arc
					(start 419.175438 -218.844876)
					(mid 419.166458 -218.841156)
					(end 419.162738 -218.832176)
				)
				(arc
					(start 419.162738 -218.337638)
					(mid 419.166458 -218.328658)
					(end 419.175438 -218.324938)
				)
				(arc
					(start 420.648638 -218.324938)
					(mid 420.657618 -218.328658)
					(end 420.661338 -218.337638)
				)
			)
		)
	)
	(zone
		(layer "In1.Cu")
		(hatch none 0.5)
		(connect_pads
			(clearance 0)
		)
		(min_thickness 0.25)
		(keepout
			(tracks not_allowed)
			(vias allowed)
			(pads allowed)
			(copperpour not_allowed)
			(footprints allowed)
		)
		(placement
			(enabled no)
			(sheetname "")
		)
		(fill
			(thermal_gap 0.5)
			(thermal_bridge_width 0.5)
			(island_removal_mode 0)
		)
		(polygon
			(pts
				(arc
					(start 56.077358 -243.482368)
					(mid 56.073638 -243.491348)
					(end 56.064658 -243.495068)
				)
				(arc
					(start 54.591458 -243.495068)
					(mid 54.582478 -243.491348)
					(end 54.578758 -243.482368)
				)
				(arc
					(start 54.578758 -242.98783)
					(mid 54.582478 -242.97885)
					(end 54.591458 -242.97513)
				)
				(arc
					(start 56.064658 -242.97513)
					(mid 56.073638 -242.97885)
					(end 56.077358 -242.98783)
				)
			)
		)
	)
	(zone
		(layer "In1.Cu")
		(hatch none 0.5)
		(connect_pads
			(clearance 0)
		)
		(min_thickness 0.25)
		(keepout
			(tracks not_allowed)
			(vias allowed)
			(pads allowed)
			(copperpour not_allowed)
			(footprints allowed)
		)
		(placement
			(enabled no)
			(sheetname "")
		)
		(fill
			(thermal_gap 0.5)
			(thermal_bridge_width 0.5)
			(island_removal_mode 0)
		)
		(polygon
			(pts
				(arc
					(start 424.761406 -242.63223)
					(mid 424.757686 -242.64121)
					(end 424.748706 -242.64493)
				)
				(arc
					(start 423.275506 -242.64493)
					(mid 423.266526 -242.64121)
					(end 423.262806 -242.63223)
				)
				(arc
					(start 423.262806 -242.137692)
					(mid 423.266526 -242.128712)
					(end 423.275506 -242.124992)
				)
				(arc
					(start 424.748706 -242.124992)
					(mid 424.757686 -242.128712)
					(end 424.761406 -242.137692)
				)
			)
		)
	)
	(zone
		(layer "In1.Cu")
		(hatch none 0.5)
		(connect_pads
			(clearance 0)
		)
		(min_thickness 0.25)
		(keepout
			(tracks not_allowed)
			(vias allowed)
			(pads allowed)
			(copperpour not_allowed)
			(footprints allowed)
		)
		(placement
			(enabled no)
			(sheetname "")
		)
		(fill
			(thermal_gap 0.5)
			(thermal_bridge_width 0.5)
			(island_removal_mode 0)
		)
		(polygon
			(pts
				(arc
					(start 424.761406 -239.232186)
					(mid 424.757686 -239.241166)
					(end 424.748706 -239.244886)
				)
				(arc
					(start 423.275506 -239.244886)
					(mid 423.266526 -239.241166)
					(end 423.262806 -239.232186)
				)
				(arc
					(start 423.262806 -238.737648)
					(mid 423.266526 -238.728668)
					(end 423.275506 -238.724948)
				)
				(arc
					(start 424.748706 -238.724948)
					(mid 424.757686 -238.728668)
					(end 424.761406 -238.737648)
				)
			)
		)
	)
	(zone
		(layer "In1.Cu")
		(hatch none 0.5)
		(connect_pads
			(clearance 0)
		)
		(min_thickness 0.25)
		(keepout
			(tracks not_allowed)
			(vias allowed)
			(pads allowed)
			(copperpour not_allowed)
			(footprints allowed)
		)
		(placement
			(enabled no)
			(sheetname "")
		)
		(fill
			(thermal_gap 0.5)
			(thermal_bridge_width 0.5)
			(island_removal_mode 0)
		)
		(polygon
			(pts
				(arc
					(start 169.277284 -199.282558)
					(mid 169.273564 -199.291538)
					(end 169.264584 -199.295258)
				)
				(arc
					(start 167.791384 -199.295258)
					(mid 167.782404 -199.291538)
					(end 167.778684 -199.282558)
				)
				(arc
					(start 167.778684 -198.78802)
					(mid 167.782404 -198.77904)
					(end 167.791384 -198.77532)
				)
				(arc
					(start 169.264584 -198.77532)
					(mid 169.273564 -198.77904)
					(end 169.277284 -198.78802)
				)
			)
		)
	)
	(zone
		(layer "In1.Cu")
		(hatch none 0.5)
		(connect_pads
			(clearance 0)
		)
		(min_thickness 0.25)
		(keepout
			(tracks not_allowed)
			(vias allowed)
			(pads allowed)
			(copperpour not_allowed)
			(footprints allowed)
		)
		(placement
			(enabled no)
			(sheetname "")
		)
		(fill
			(thermal_gap 0.5)
			(thermal_bridge_width 0.5)
			(island_removal_mode 0)
		)
		(polygon
			(pts
				(arc
					(start 199.4535 -315.732414)
					(mid 199.44978 -315.741394)
					(end 199.4408 -315.745114)
				)
				(arc
					(start 197.9676 -315.745114)
					(mid 197.95862 -315.741394)
					(end 197.9549 -315.732414)
				)
				(arc
					(start 197.9549 -315.237876)
					(mid 197.95862 -315.228896)
					(end 197.9676 -315.225176)
				)
				(arc
					(start 199.4408 -315.225176)
					(mid 199.44978 -315.228896)
					(end 199.4535 -315.237876)
				)
			)
		)
	)
	(zone
		(layer "In1.Cu")
		(hatch none 0.5)
		(connect_pads
			(clearance 0)
		)
		(min_thickness 0.25)
		(keepout
			(tracks not_allowed)
			(vias allowed)
			(pads allowed)
			(copperpour not_allowed)
			(footprints allowed)
		)
		(placement
			(enabled no)
			(sheetname "")
		)
		(fill
			(thermal_gap 0.5)
			(thermal_bridge_width 0.5)
			(island_removal_mode 0)
		)
		(polygon
			(pts
				(arc
					(start 300.57344 -217.982292)
					(mid 300.56972 -217.991272)
					(end 300.56074 -217.994992)
				)
				(arc
					(start 299.08754 -217.994992)
					(mid 299.07856 -217.991272)
					(end 299.07484 -217.982292)
				)
				(arc
					(start 299.07484 -217.487754)
					(mid 299.07856 -217.478774)
					(end 299.08754 -217.475054)
				)
				(arc
					(start 300.56074 -217.475054)
					(mid 300.56972 -217.478774)
					(end 300.57344 -217.487754)
				)
			)
		)
	)
	(zone
		(layer "In1.Cu")
		(hatch none 0.5)
		(connect_pads
			(clearance 0)
		)
		(min_thickness 0.25)
		(keepout
			(tracks not_allowed)
			(vias allowed)
			(pads allowed)
			(copperpour not_allowed)
			(footprints allowed)
		)
		(placement
			(enabled no)
			(sheetname "")
		)
		(fill
			(thermal_gap 0.5)
			(thermal_bridge_width 0.5)
			(island_removal_mode 0)
		)
		(polygon
			(pts
				(arc
					(start 417.217352 -205.232254)
					(mid 417.213632 -205.241234)
					(end 417.204652 -205.244954)
				)
				(arc
					(start 415.731452 -205.244954)
					(mid 415.722472 -205.241234)
					(end 415.718752 -205.232254)
				)
				(arc
					(start 415.718752 -204.737716)
					(mid 415.722472 -204.728736)
					(end 415.731452 -204.725016)
				)
				(arc
					(start 417.204652 -204.725016)
					(mid 417.213632 -204.728736)
					(end 417.217352 -204.737716)
				)
			)
		)
	)
	(zone
		(layer "In1.Cu")
		(hatch none 0.5)
		(connect_pads
			(clearance 0)
		)
		(min_thickness 0.25)
		(keepout
			(tracks not_allowed)
			(vias allowed)
			(pads allowed)
			(copperpour not_allowed)
			(footprints allowed)
		)
		(placement
			(enabled no)
			(sheetname "")
		)
		(fill
			(thermal_gap 0.5)
			(thermal_bridge_width 0.5)
			(island_removal_mode 0)
		)
		(polygon
			(pts
				(arc
					(start 155.01874 -383.440686)
					(mid 155.14574 -383.567686)
					(end 155.27274 -383.440686)
				)
				(arc
					(start 155.27274 -383.364486)
					(mid 155.14574 -383.237486)
					(end 155.01874 -383.364486)
				)
			)
		)
	)
	(zone
		(layer "In1.Cu")
		(hatch none 0.5)
		(connect_pads
			(clearance 0)
		)
		(min_thickness 0.25)
		(keepout
			(tracks not_allowed)
			(vias allowed)
			(pads allowed)
			(copperpour not_allowed)
			(footprints allowed)
		)
		(placement
			(enabled no)
			(sheetname "")
		)
		(fill
			(thermal_gap 0.5)
			(thermal_bridge_width 0.5)
			(island_removal_mode 0)
		)
		(polygon
			(pts
				(arc
					(start 22.45741 -268.13256)
					(mid 22.45369 -268.14154)
					(end 22.44471 -268.14526)
				)
				(arc
					(start 20.97151 -268.14526)
					(mid 20.96253 -268.14154)
					(end 20.95881 -268.13256)
				)
				(arc
					(start 20.95881 -267.638022)
					(mid 20.96253 -267.629042)
					(end 20.97151 -267.625322)
				)
				(arc
					(start 22.44471 -267.625322)
					(mid 22.45369 -267.629042)
					(end 22.45741 -267.638022)
				)
			)
		)
	)
	(zone
		(layer "In1.Cu")
		(hatch none 0.5)
		(connect_pads
			(clearance 0)
		)
		(min_thickness 0.25)
		(keepout
			(tracks not_allowed)
			(vias allowed)
			(pads allowed)
			(copperpour not_allowed)
			(footprints allowed)
		)
		(placement
			(enabled no)
			(sheetname "")
		)
		(fill
			(thermal_gap 0.5)
			(thermal_bridge_width 0.5)
			(island_removal_mode 0)
		)
		(polygon
			(pts
				(arc
					(start 293.029386 -220.532198)
					(mid 293.025666 -220.541178)
					(end 293.016686 -220.544898)
				)
				(arc
					(start 291.543486 -220.544898)
					(mid 291.534506 -220.541178)
					(end 291.530786 -220.532198)
				)
				(arc
					(start 291.530786 -220.03766)
					(mid 291.534506 -220.02868)
					(end 291.543486 -220.02496)
				)
				(arc
					(start 293.016686 -220.02496)
					(mid 293.025666 -220.02868)
					(end 293.029386 -220.03766)
				)
			)
		)
	)
	(zone
		(layer "In1.Cu")
		(hatch none 0.5)
		(connect_pads
			(clearance 0)
		)
		(min_thickness 0.25)
		(keepout
			(tracks not_allowed)
			(vias allowed)
			(pads allowed)
			(copperpour not_allowed)
			(footprints allowed)
		)
		(placement
			(enabled no)
			(sheetname "")
		)
		(fill
			(thermal_gap 0.5)
			(thermal_bridge_width 0.5)
			(island_removal_mode 0)
		)
		(polygon
			(pts
				(arc
					(start 435.749446 -267.282168)
					(mid 435.745726 -267.291148)
					(end 435.736746 -267.294868)
				)
				(arc
					(start 434.263546 -267.294868)
					(mid 434.254566 -267.291148)
					(end 434.250846 -267.282168)
				)
				(arc
					(start 434.250846 -266.78763)
					(mid 434.254566 -266.77865)
					(end 434.263546 -266.77493)
				)
				(arc
					(start 435.736746 -266.77493)
					(mid 435.745726 -266.77865)
					(end 435.749446 -266.78763)
				)
			)
		)
	)
	(zone
		(layer "In1.Cu")
		(hatch none 0.5)
		(connect_pads
			(clearance 0)
		)
		(min_thickness 0.25)
		(keepout
			(tracks not_allowed)
			(vias allowed)
			(pads allowed)
			(copperpour not_allowed)
			(footprints allowed)
		)
		(placement
			(enabled no)
			(sheetname "")
		)
		(fill
			(thermal_gap 0.5)
			(thermal_bridge_width 0.5)
			(island_removal_mode 0)
		)
		(polygon
			(pts
				(arc
					(start 92.098114 -383.92227)
					(mid 91.793314 -383.92227)
					(end 92.098114 -383.92227)
				)
			)
		)
	)
	(zone
		(layer "In1.Cu")
		(hatch none 0.5)
		(connect_pads
			(clearance 0)
		)
		(min_thickness 0.25)
		(keepout
			(tracks not_allowed)
			(vias allowed)
			(pads allowed)
			(copperpour not_allowed)
			(footprints allowed)
		)
		(placement
			(enabled no)
			(sheetname "")
		)
		(fill
			(thermal_gap 0.5)
			(thermal_bridge_width 0.5)
			(island_removal_mode 0)
		)
		(polygon
			(pts
				(arc
					(start 25.901396 -253.6825)
					(mid 25.897676 -253.69148)
					(end 25.888696 -253.6952)
				)
				(arc
					(start 24.415496 -253.6952)
					(mid 24.406516 -253.69148)
					(end 24.402796 -253.6825)
				)
				(arc
					(start 24.402796 -253.187962)
					(mid 24.406516 -253.178982)
					(end 24.415496 -253.175262)
				)
				(arc
					(start 25.888696 -253.175262)
					(mid 25.897676 -253.178982)
					(end 25.901396 -253.187962)
				)
			)
		)
	)
	(zone
		(layer "In1.Cu")
		(hatch none 0.5)
		(connect_pads
			(clearance 0)
		)
		(min_thickness 0.25)
		(keepout
			(tracks not_allowed)
			(vias allowed)
			(pads allowed)
			(copperpour not_allowed)
			(footprints allowed)
		)
		(placement
			(enabled no)
			(sheetname "")
		)
		(fill
			(thermal_gap 0.5)
			(thermal_bridge_width 0.5)
			(island_removal_mode 0)
		)
		(polygon
			(pts
				(arc
					(start 37.545264 -303.832514)
					(mid 37.541544 -303.841494)
					(end 37.532564 -303.845214)
				)
				(arc
					(start 36.059364 -303.845214)
					(mid 36.050384 -303.841494)
					(end 36.046664 -303.832514)
				)
				(arc
					(start 36.046664 -303.337976)
					(mid 36.050384 -303.328996)
					(end 36.059364 -303.325276)
				)
				(arc
					(start 37.532564 -303.325276)
					(mid 37.541544 -303.328996)
					(end 37.545264 -303.337976)
				)
			)
		)
	)
	(zone
		(layer "In1.Cu")
		(hatch none 0.5)
		(connect_pads
			(clearance 0)
		)
		(min_thickness 0.25)
		(keepout
			(tracks not_allowed)
			(vias allowed)
			(pads allowed)
			(copperpour not_allowed)
			(footprints allowed)
		)
		(placement
			(enabled no)
			(sheetname "")
		)
		(fill
			(thermal_gap 0.5)
			(thermal_bridge_width 0.5)
			(island_removal_mode 0)
		)
		(polygon
			(pts
				(arc
					(start 206.5782 -283.185362)
					(mid 205.9178 -283.185362)
					(end 206.5782 -283.185362)
				)
			)
		)
	)
	(zone
		(layer "In1.Cu")
		(hatch none 0.5)
		(connect_pads
			(clearance 0)
		)
		(min_thickness 0.25)
		(keepout
			(tracks not_allowed)
			(vias allowed)
			(pads allowed)
			(copperpour not_allowed)
			(footprints allowed)
		)
		(placement
			(enabled no)
			(sheetname "")
		)
		(fill
			(thermal_gap 0.5)
			(thermal_bridge_width 0.5)
			(island_removal_mode 0)
		)
		(polygon
			(pts
				(arc
					(start 82.388964 -388.774432)
					(mid 82.007964 -388.774432)
					(end 82.388964 -388.774432)
				)
			)
		)
	)
	(zone
		(layer "In1.Cu")
		(hatch none 0.5)
		(connect_pads
			(clearance 0)
		)
		(min_thickness 0.25)
		(keepout
			(tracks not_allowed)
			(vias allowed)
			(pads allowed)
			(copperpour not_allowed)
			(footprints allowed)
		)
		(placement
			(enabled no)
			(sheetname "")
		)
		(fill
			(thermal_gap 0.5)
			(thermal_bridge_width 0.5)
			(island_removal_mode 0)
		)
		(polygon
			(pts
				(arc
					(start 114.676936 -408.860244)
					(mid 114.699254 -408.914126)
					(end 114.753136 -408.936444)
				)
				(arc
					(start 114.948716 -408.936444)
					(mid 114.970592 -408.933312)
					(end 114.990626 -408.923998)
				)
				(arc
					(start 115.28425 -408.731466)
					(mid 115.325906 -408.719064)
					(end 115.367562 -408.731466)
				)
				(arc
					(start 115.662456 -408.923998)
					(mid 115.68238 -408.933234)
					(end 115.704112 -408.936444)
				)
				(arc
					(start 115.898676 -408.936444)
					(mid 115.952558 -408.914126)
					(end 115.974876 -408.860244)
				)
				(arc
					(start 115.974876 -408.174444)
					(mid 115.952558 -408.120562)
					(end 115.898676 -408.098244)
				)
				(arc
					(start 115.704112 -408.098244)
					(mid 115.682368 -408.101412)
					(end 115.662456 -408.11069)
				)
				(arc
					(start 115.366292 -408.303476)
					(mid 115.324608 -408.315698)
					(end 115.28298 -408.303222)
				)
				(arc
					(start 114.989356 -408.11069)
					(mid 114.969432 -408.101454)
					(end 114.9477 -408.098244)
				)
				(arc
					(start 114.753136 -408.098244)
					(mid 114.699254 -408.120562)
					(end 114.676936 -408.174444)
				)
			)
		)
	)
	(zone
		(layer "In1.Cu")
		(hatch none 0.5)
		(connect_pads
			(clearance 0)
		)
		(min_thickness 0.25)
		(keepout
			(tracks not_allowed)
			(vias allowed)
			(pads allowed)
			(copperpour not_allowed)
			(footprints allowed)
		)
		(placement
			(enabled no)
			(sheetname "")
		)
		(fill
			(thermal_gap 0.5)
			(thermal_bridge_width 0.5)
			(island_removal_mode 0)
		)
		(polygon
			(pts
				(arc
					(start 206.9973 -238.382556)
					(mid 206.99358 -238.391536)
					(end 206.9846 -238.395256)
				)
				(arc
					(start 205.5114 -238.395256)
					(mid 205.50242 -238.391536)
					(end 205.4987 -238.382556)
				)
				(arc
					(start 205.4987 -237.888018)
					(mid 205.50242 -237.879038)
					(end 205.5114 -237.875318)
				)
				(arc
					(start 206.9846 -237.875318)
					(mid 206.99358 -237.879038)
					(end 206.9973 -237.888018)
				)
			)
		)
	)
	(zone
		(layer "In1.Cu")
		(hatch none 0.5)
		(connect_pads
			(clearance 0)
		)
		(min_thickness 0.25)
		(keepout
			(tracks not_allowed)
			(vias allowed)
			(pads allowed)
			(copperpour not_allowed)
			(footprints allowed)
		)
		(placement
			(enabled no)
			(sheetname "")
		)
		(fill
			(thermal_gap 0.5)
			(thermal_bridge_width 0.5)
			(island_removal_mode 0)
		)
		(polygon
			(pts
				(arc
					(start 288.929318 -279.182322)
					(mid 288.925598 -279.191302)
					(end 288.916618 -279.195022)
				)
				(arc
					(start 287.443418 -279.195022)
					(mid 287.434438 -279.191302)
					(end 287.430718 -279.182322)
				)
				(arc
					(start 287.430718 -278.687784)
					(mid 287.434438 -278.678804)
					(end 287.443418 -278.675084)
				)
				(arc
					(start 288.916618 -278.675084)
					(mid 288.925598 -278.678804)
					(end 288.929318 -278.687784)
				)
			)
		)
	)
	(zone
		(layer "In1.Cu")
		(hatch none 0.5)
		(connect_pads
			(clearance 0)
		)
		(min_thickness 0.25)
		(keepout
			(tracks not_allowed)
			(vias allowed)
			(pads allowed)
			(copperpour not_allowed)
			(footprints allowed)
		)
		(placement
			(enabled no)
			(sheetname "")
		)
		(fill
			(thermal_gap 0.5)
			(thermal_bridge_width 0.5)
			(island_removal_mode 0)
		)
		(polygon
			(pts
				(arc
					(start 443.2935 -245.182136)
					(mid 443.28978 -245.191116)
					(end 443.2808 -245.194836)
				)
				(arc
					(start 441.8076 -245.194836)
					(mid 441.79862 -245.191116)
					(end 441.7949 -245.182136)
				)
				(arc
					(start 441.7949 -244.687598)
					(mid 441.79862 -244.678618)
					(end 441.8076 -244.674898)
				)
				(arc
					(start 443.2808 -244.674898)
					(mid 443.28978 -244.678618)
					(end 443.2935 -244.687598)
				)
			)
		)
	)
	(zone
		(layer "In1.Cu")
		(hatch none 0.5)
		(connect_pads
			(clearance 0)
		)
		(min_thickness 0.25)
		(keepout
			(tracks not_allowed)
			(vias allowed)
			(pads allowed)
			(copperpour not_allowed)
			(footprints allowed)
		)
		(placement
			(enabled no)
			(sheetname "")
		)
		(fill
			(thermal_gap 0.5)
			(thermal_bridge_width 0.5)
			(island_removal_mode 0)
		)
		(polygon
			(pts
				(arc
					(start 428.205392 -302.982122)
					(mid 428.201672 -302.991102)
					(end 428.192692 -302.994822)
				)
				(arc
					(start 426.719492 -302.994822)
					(mid 426.710512 -302.991102)
					(end 426.706792 -302.982122)
				)
				(arc
					(start 426.706792 -302.487584)
					(mid 426.710512 -302.478604)
					(end 426.719492 -302.474884)
				)
				(arc
					(start 428.192692 -302.474884)
					(mid 428.201672 -302.478604)
					(end 428.205392 -302.487584)
				)
			)
		)
	)
	(zone
		(layer "In1.Cu")
		(hatch none 0.5)
		(connect_pads
			(clearance 0)
		)
		(min_thickness 0.25)
		(keepout
			(tracks not_allowed)
			(vias allowed)
			(pads allowed)
			(copperpour not_allowed)
			(footprints allowed)
		)
		(placement
			(enabled no)
			(sheetname "")
		)
		(fill
			(thermal_gap 0.5)
			(thermal_bridge_width 0.5)
			(island_removal_mode 0)
		)
		(polygon
			(pts
				(arc
					(start 454.937368 -309.78221)
					(mid 454.933648 -309.79119)
					(end 454.924668 -309.79491)
				)
				(arc
					(start 453.451468 -309.79491)
					(mid 453.442488 -309.79119)
					(end 453.438768 -309.78221)
				)
				(arc
					(start 453.438768 -309.287672)
					(mid 453.442488 -309.278692)
					(end 453.451468 -309.274972)
				)
				(arc
					(start 454.924668 -309.274972)
					(mid 454.933648 -309.278692)
					(end 454.937368 -309.287672)
				)
			)
		)
	)
	(zone
		(layer "In1.Cu")
		(hatch none 0.5)
		(connect_pads
			(clearance 0)
		)
		(min_thickness 0.25)
		(keepout
			(tracks not_allowed)
			(vias allowed)
			(pads allowed)
			(copperpour not_allowed)
			(footprints allowed)
		)
		(placement
			(enabled no)
			(sheetname "")
		)
		(fill
			(thermal_gap 0.5)
			(thermal_bridge_width 0.5)
			(island_removal_mode 0)
		)
		(polygon
			(pts
				(arc
					(start 156.79801 -383.92227)
					(mid 156.49321 -383.92227)
					(end 156.79801 -383.92227)
				)
			)
		)
	)
	(zone
		(layer "In1.Cu")
		(hatch none 0.5)
		(connect_pads
			(clearance 0)
		)
		(min_thickness 0.25)
		(keepout
			(tracks not_allowed)
			(vias allowed)
			(pads allowed)
			(copperpour not_allowed)
			(footprints allowed)
		)
		(placement
			(enabled no)
			(sheetname "")
		)
		(fill
			(thermal_gap 0.5)
			(thermal_bridge_width 0.5)
			(island_removal_mode 0)
		)
		(polygon
			(pts
				(arc
					(start 293.029386 -263.03224)
					(mid 293.025666 -263.04122)
					(end 293.016686 -263.04494)
				)
				(arc
					(start 291.543486 -263.04494)
					(mid 291.534506 -263.04122)
					(end 291.530786 -263.03224)
				)
				(arc
					(start 291.530786 -262.537702)
					(mid 291.534506 -262.528722)
					(end 291.543486 -262.525002)
				)
				(arc
					(start 293.016686 -262.525002)
					(mid 293.025666 -262.528722)
					(end 293.029386 -262.537702)
				)
			)
		)
	)
	(zone
		(layer "In1.Cu")
		(hatch none 0.5)
		(connect_pads
			(clearance 0)
		)
		(min_thickness 0.25)
		(keepout
			(tracks not_allowed)
			(vias allowed)
			(pads allowed)
			(copperpour not_allowed)
			(footprints allowed)
		)
		(placement
			(enabled no)
			(sheetname "")
		)
		(fill
			(thermal_gap 0.5)
			(thermal_bridge_width 0.5)
			(island_removal_mode 0)
		)
		(polygon
			(pts
				(arc
					(start 18.357342 -277.482554)
					(mid 18.353622 -277.491534)
					(end 18.344642 -277.495254)
				)
				(arc
					(start 16.871442 -277.495254)
					(mid 16.862462 -277.491534)
					(end 16.858742 -277.482554)
				)
				(arc
					(start 16.858742 -276.988016)
					(mid 16.862462 -276.979036)
					(end 16.871442 -276.975316)
				)
				(arc
					(start 18.344642 -276.975316)
					(mid 18.353622 -276.979036)
					(end 18.357342 -276.988016)
				)
			)
		)
	)
	(zone
		(layer "In1.Cu")
		(hatch none 0.5)
		(connect_pads
			(clearance 0)
		)
		(min_thickness 0.25)
		(keepout
			(tracks not_allowed)
			(vias allowed)
			(pads allowed)
			(copperpour not_allowed)
			(footprints allowed)
		)
		(placement
			(enabled no)
			(sheetname "")
		)
		(fill
			(thermal_gap 0.5)
			(thermal_bridge_width 0.5)
			(island_removal_mode 0)
		)
		(polygon
			(pts
				(arc
					(start 56.077358 -290.232592)
					(mid 56.073638 -290.241572)
					(end 56.064658 -290.245292)
				)
				(arc
					(start 54.591458 -290.245292)
					(mid 54.582478 -290.241572)
					(end 54.578758 -290.232592)
				)
				(arc
					(start 54.578758 -289.738054)
					(mid 54.582478 -289.729074)
					(end 54.591458 -289.725354)
				)
				(arc
					(start 56.064658 -289.725354)
					(mid 56.073638 -289.729074)
					(end 56.077358 -289.738054)
				)
			)
		)
	)
	(zone
		(layer "In1.Cu")
		(hatch none 0.5)
		(connect_pads
			(clearance 0)
		)
		(min_thickness 0.25)
		(keepout
			(tracks not_allowed)
			(vias allowed)
			(pads allowed)
			(copperpour not_allowed)
			(footprints allowed)
		)
		(placement
			(enabled no)
			(sheetname "")
		)
		(fill
			(thermal_gap 0.5)
			(thermal_bridge_width 0.5)
			(island_removal_mode 0)
		)
		(polygon
			(pts
				(arc
					(start 45.089318 -197.582536)
					(mid 45.085598 -197.591516)
					(end 45.076618 -197.595236)
				)
				(arc
					(start 43.603418 -197.595236)
					(mid 43.594438 -197.591516)
					(end 43.590718 -197.582536)
				)
				(arc
					(start 43.590718 -197.087998)
					(mid 43.594438 -197.079018)
					(end 43.603418 -197.075298)
				)
				(arc
					(start 45.076618 -197.075298)
					(mid 45.085598 -197.079018)
					(end 45.089318 -197.087998)
				)
			)
		)
	)
	(zone
		(layer "In1.Cu")
		(hatch none 0.5)
		(connect_pads
			(clearance 0)
		)
		(min_thickness 0.25)
		(keepout
			(tracks not_allowed)
			(vias allowed)
			(pads allowed)
			(copperpour not_allowed)
			(footprints allowed)
		)
		(placement
			(enabled no)
			(sheetname "")
		)
		(fill
			(thermal_gap 0.5)
			(thermal_bridge_width 0.5)
			(island_removal_mode 0)
		)
		(polygon
			(pts
				(arc
					(start 184.365392 -212.88248)
					(mid 184.361672 -212.89146)
					(end 184.352692 -212.89518)
				)
				(arc
					(start 182.879492 -212.89518)
					(mid 182.870512 -212.89146)
					(end 182.866792 -212.88248)
				)
				(arc
					(start 182.866792 -212.387942)
					(mid 182.870512 -212.378962)
					(end 182.879492 -212.375242)
				)
				(arc
					(start 184.352692 -212.375242)
					(mid 184.361672 -212.378962)
					(end 184.365392 -212.387942)
				)
			)
		)
	)
	(zone
		(layer "In1.Cu")
		(hatch none 0.5)
		(connect_pads
			(clearance 0)
		)
		(min_thickness 0.25)
		(keepout
			(tracks not_allowed)
			(vias allowed)
			(pads allowed)
			(copperpour not_allowed)
			(footprints allowed)
		)
		(placement
			(enabled no)
			(sheetname "")
		)
		(fill
			(thermal_gap 0.5)
			(thermal_bridge_width 0.5)
			(island_removal_mode 0)
		)
		(polygon
			(pts
				(arc
					(start 293.029386 -317.432182)
					(mid 293.025666 -317.441162)
					(end 293.016686 -317.444882)
				)
				(arc
					(start 291.543486 -317.444882)
					(mid 291.534506 -317.441162)
					(end 291.530786 -317.432182)
				)
				(arc
					(start 291.530786 -316.937644)
					(mid 291.534506 -316.928664)
					(end 291.543486 -316.924944)
				)
				(arc
					(start 293.016686 -316.924944)
					(mid 293.025666 -316.928664)
					(end 293.029386 -316.937644)
				)
			)
		)
	)
	(zone
		(layer "In1.Cu")
		(hatch none 0.5)
		(connect_pads
			(clearance 0)
		)
		(min_thickness 0.25)
		(keepout
			(tracks not_allowed)
			(vias allowed)
			(pads allowed)
			(copperpour not_allowed)
			(footprints allowed)
		)
		(placement
			(enabled no)
			(sheetname "")
		)
		(fill
			(thermal_gap 0.5)
			(thermal_bridge_width 0.5)
			(island_removal_mode 0)
		)
		(polygon
			(pts
				(arc
					(start 180.265324 -246.882412)
					(mid 180.261604 -246.891392)
					(end 180.252624 -246.895112)
				)
				(arc
					(start 178.779424 -246.895112)
					(mid 178.770444 -246.891392)
					(end 178.766724 -246.882412)
				)
				(arc
					(start 178.766724 -246.387874)
					(mid 178.770444 -246.378894)
					(end 178.779424 -246.375174)
				)
				(arc
					(start 180.252624 -246.375174)
					(mid 180.261604 -246.378894)
					(end 180.265324 -246.387874)
				)
			)
		)
	)
	(zone
		(layer "In1.Cu")
		(hatch none 0.5)
		(connect_pads
			(clearance 0)
		)
		(min_thickness 0.25)
		(keepout
			(tracks not_allowed)
			(vias allowed)
			(pads allowed)
			(copperpour not_allowed)
			(footprints allowed)
		)
		(placement
			(enabled no)
			(sheetname "")
		)
		(fill
			(thermal_gap 0.5)
			(thermal_bridge_width 0.5)
			(island_removal_mode 0)
		)
		(polygon
			(pts
				(arc
					(start 288.929318 -286.832294)
					(mid 288.925598 -286.841274)
					(end 288.916618 -286.844994)
				)
				(arc
					(start 287.443418 -286.844994)
					(mid 287.434438 -286.841274)
					(end 287.430718 -286.832294)
				)
				(arc
					(start 287.430718 -286.337756)
					(mid 287.434438 -286.328776)
					(end 287.443418 -286.325056)
				)
				(arc
					(start 288.916618 -286.325056)
					(mid 288.925598 -286.328776)
					(end 288.929318 -286.337756)
				)
			)
		)
	)
	(zone
		(layer "In1.Cu")
		(hatch none 0.5)
		(connect_pads
			(clearance 0)
		)
		(min_thickness 0.25)
		(keepout
			(tracks not_allowed)
			(vias allowed)
			(pads allowed)
			(copperpour not_allowed)
			(footprints allowed)
		)
		(placement
			(enabled no)
			(sheetname "")
		)
		(fill
			(thermal_gap 0.5)
			(thermal_bridge_width 0.5)
			(island_removal_mode 0)
		)
		(polygon
			(pts
				(arc
					(start 273.841464 -229.882192)
					(mid 273.837744 -229.891172)
					(end 273.828764 -229.894892)
				)
				(arc
					(start 272.355564 -229.894892)
					(mid 272.346584 -229.891172)
					(end 272.342864 -229.882192)
				)
				(arc
					(start 272.342864 -229.387654)
					(mid 272.346584 -229.378674)
					(end 272.355564 -229.374954)
				)
				(arc
					(start 273.828764 -229.374954)
					(mid 273.837744 -229.378674)
					(end 273.841464 -229.387654)
				)
			)
		)
	)
	(zone
		(layer "In1.Cu")
		(hatch none 0.5)
		(connect_pads
			(clearance 0)
		)
		(min_thickness 0.25)
		(keepout
			(tracks not_allowed)
			(vias allowed)
			(pads allowed)
			(copperpour not_allowed)
			(footprints allowed)
		)
		(placement
			(enabled no)
			(sheetname "")
		)
		(fill
			(thermal_gap 0.5)
			(thermal_bridge_width 0.5)
			(island_removal_mode 0)
		)
		(polygon
			(pts
				(arc
					(start 300.57344 -270.682212)
					(mid 300.56972 -270.691192)
					(end 300.56074 -270.694912)
				)
				(arc
					(start 299.08754 -270.694912)
					(mid 299.07856 -270.691192)
					(end 299.07484 -270.682212)
				)
				(arc
					(start 299.07484 -270.187674)
					(mid 299.07856 -270.178694)
					(end 299.08754 -270.174974)
				)
				(arc
					(start 300.56074 -270.174974)
					(mid 300.56972 -270.178694)
					(end 300.57344 -270.187674)
				)
			)
		)
	)
	(zone
		(layer "In1.Cu")
		(hatch none 0.5)
		(connect_pads
			(clearance 0)
		)
		(min_thickness 0.25)
		(keepout
			(tracks not_allowed)
			(vias allowed)
			(pads allowed)
			(copperpour not_allowed)
			(footprints allowed)
		)
		(placement
			(enabled no)
			(sheetname "")
		)
		(fill
			(thermal_gap 0.5)
			(thermal_bridge_width 0.5)
			(island_removal_mode 0)
		)
		(polygon
			(pts
				(arc
					(start 428.205392 -296.182288)
					(mid 428.201672 -296.191268)
					(end 428.192692 -296.194988)
				)
				(arc
					(start 426.719492 -296.194988)
					(mid 426.710512 -296.191268)
					(end 426.706792 -296.182288)
				)
				(arc
					(start 426.706792 -295.68775)
					(mid 426.710512 -295.67877)
					(end 426.719492 -295.67505)
				)
				(arc
					(start 428.192692 -295.67505)
					(mid 428.201672 -295.67877)
					(end 428.205392 -295.68775)
				)
			)
		)
	)
	(zone
		(layer "In1.Cu")
		(hatch none 0.5)
		(connect_pads
			(clearance 0)
		)
		(min_thickness 0.25)
		(keepout
			(tracks not_allowed)
			(vias allowed)
			(pads allowed)
			(copperpour not_allowed)
			(footprints allowed)
		)
		(placement
			(enabled no)
			(sheetname "")
		)
		(fill
			(thermal_gap 0.5)
			(thermal_bridge_width 0.5)
			(island_removal_mode 0)
		)
		(polygon
			(pts
				(arc
					(start 180.265324 -245.18239)
					(mid 180.261604 -245.19137)
					(end 180.252624 -245.19509)
				)
				(arc
					(start 178.779424 -245.19509)
					(mid 178.770444 -245.19137)
					(end 178.766724 -245.18239)
				)
				(arc
					(start 178.766724 -244.687852)
					(mid 178.770444 -244.678872)
					(end 178.779424 -244.675152)
				)
				(arc
					(start 180.252624 -244.675152)
					(mid 180.261604 -244.678872)
					(end 180.265324 -244.687852)
				)
			)
		)
	)
	(zone
		(layer "In1.Cu")
		(hatch none 0.5)
		(connect_pads
			(clearance 0)
		)
		(min_thickness 0.25)
		(keepout
			(tracks not_allowed)
			(vias allowed)
			(pads allowed)
			(copperpour not_allowed)
			(footprints allowed)
		)
		(placement
			(enabled no)
			(sheetname "")
		)
		(fill
			(thermal_gap 0.5)
			(thermal_bridge_width 0.5)
			(island_removal_mode 0)
		)
		(polygon
			(pts
				(arc
					(start 202.897232 -253.6825)
					(mid 202.893512 -253.69148)
					(end 202.884532 -253.6952)
				)
				(arc
					(start 201.411332 -253.6952)
					(mid 201.402352 -253.69148)
					(end 201.398632 -253.6825)
				)
				(arc
					(start 201.398632 -253.187962)
					(mid 201.402352 -253.178982)
					(end 201.411332 -253.175262)
				)
				(arc
					(start 202.884532 -253.175262)
					(mid 202.893512 -253.178982)
					(end 202.897232 -253.187962)
				)
			)
		)
	)
	(zone
		(layer "In1.Cu")
		(hatch none 0.5)
		(connect_pads
			(clearance 0)
		)
		(min_thickness 0.25)
		(keepout
			(tracks not_allowed)
			(vias allowed)
			(pads allowed)
			(copperpour not_allowed)
			(footprints allowed)
		)
		(placement
			(enabled no)
			(sheetname "")
		)
		(fill
			(thermal_gap 0.5)
			(thermal_bridge_width 0.5)
			(island_removal_mode 0)
		)
		(polygon
			(pts
				(arc
					(start 447.393568 -254.53213)
					(mid 447.389848 -254.54111)
					(end 447.380868 -254.54483)
				)
				(arc
					(start 445.907668 -254.54483)
					(mid 445.898688 -254.54111)
					(end 445.894968 -254.53213)
				)
				(arc
					(start 445.894968 -254.037592)
					(mid 445.898688 -254.028612)
					(end 445.907668 -254.024892)
				)
				(arc
					(start 447.380868 -254.024892)
					(mid 447.389848 -254.028612)
					(end 447.393568 -254.037592)
				)
			)
		)
	)
	(zone
		(layer "In1.Cu")
		(hatch none 0.5)
		(connect_pads
			(clearance 0)
		)
		(min_thickness 0.25)
		(keepout
			(tracks not_allowed)
			(vias allowed)
			(pads allowed)
			(copperpour not_allowed)
			(footprints allowed)
		)
		(placement
			(enabled no)
			(sheetname "")
		)
		(fill
			(thermal_gap 0.5)
			(thermal_bridge_width 0.5)
			(island_removal_mode 0)
		)
		(polygon
			(pts
				(arc
					(start 293.029386 -261.332218)
					(mid 293.025666 -261.341198)
					(end 293.016686 -261.344918)
				)
				(arc
					(start 291.543486 -261.344918)
					(mid 291.534506 -261.341198)
					(end 291.530786 -261.332218)
				)
				(arc
					(start 291.530786 -260.83768)
					(mid 291.534506 -260.8287)
					(end 291.543486 -260.82498)
				)
				(arc
					(start 293.016686 -260.82498)
					(mid 293.025666 -260.8287)
					(end 293.029386 -260.83768)
				)
			)
		)
	)
	(zone
		(layer "In1.Cu")
		(hatch none 0.5)
		(connect_pads
			(clearance 0)
		)
		(min_thickness 0.25)
		(keepout
			(tracks not_allowed)
			(vias allowed)
			(pads allowed)
			(copperpour not_allowed)
			(footprints allowed)
		)
		(placement
			(enabled no)
			(sheetname "")
		)
		(fill
			(thermal_gap 0.5)
			(thermal_bridge_width 0.5)
			(island_removal_mode 0)
		)
		(polygon
			(pts
				(arc
					(start 22.45741 -200.98258)
					(mid 22.45369 -200.99156)
					(end 22.44471 -200.99528)
				)
				(arc
					(start 20.97151 -200.99528)
					(mid 20.96253 -200.99156)
					(end 20.95881 -200.98258)
				)
				(arc
					(start 20.95881 -200.488042)
					(mid 20.96253 -200.479062)
					(end 20.97151 -200.475342)
				)
				(arc
					(start 22.44471 -200.475342)
					(mid 22.45369 -200.479062)
					(end 22.45741 -200.488042)
				)
			)
		)
	)
	(zone
		(layer "In1.Cu")
		(hatch none 0.5)
		(connect_pads
			(clearance 0)
		)
		(min_thickness 0.25)
		(keepout
			(tracks not_allowed)
			(vias allowed)
			(pads allowed)
			(copperpour not_allowed)
			(footprints allowed)
		)
		(placement
			(enabled no)
			(sheetname "")
		)
		(fill
			(thermal_gap 0.5)
			(thermal_bridge_width 0.5)
			(island_removal_mode 0)
		)
		(polygon
			(pts
				(arc
					(start 206.5782 -264.485374)
					(mid 205.9178 -264.485374)
					(end 206.5782 -264.485374)
				)
			)
		)
	)
	(zone
		(layer "In1.Cu")
		(hatch none 0.5)
		(connect_pads
			(clearance 0)
		)
		(min_thickness 0.25)
		(keepout
			(tracks not_allowed)
			(vias allowed)
			(pads allowed)
			(copperpour not_allowed)
			(footprints allowed)
		)
		(placement
			(enabled no)
			(sheetname "")
		)
		(fill
			(thermal_gap 0.5)
			(thermal_bridge_width 0.5)
			(island_removal_mode 0)
		)
		(polygon
			(pts
				(arc
					(start 424.761406 -264.732262)
					(mid 424.757686 -264.741242)
					(end 424.748706 -264.744962)
				)
				(arc
					(start 423.275506 -264.744962)
					(mid 423.266526 -264.741242)
					(end 423.262806 -264.732262)
				)
				(arc
					(start 423.262806 -264.237724)
					(mid 423.266526 -264.228744)
					(end 423.275506 -264.225024)
				)
				(arc
					(start 424.748706 -264.225024)
					(mid 424.757686 -264.228744)
					(end 424.761406 -264.237724)
				)
			)
		)
	)
	(zone
		(layer "In1.Cu")
		(hatch none 0.5)
		(connect_pads
			(clearance 0)
		)
		(min_thickness 0.25)
		(keepout
			(tracks not_allowed)
			(vias allowed)
			(pads allowed)
			(copperpour not_allowed)
			(footprints allowed)
		)
		(placement
			(enabled no)
			(sheetname "")
		)
		(fill
			(thermal_gap 0.5)
			(thermal_bridge_width 0.5)
			(island_removal_mode 0)
		)
		(polygon
			(pts
				(arc
					(start 25.901396 -215.432386)
					(mid 25.897676 -215.441366)
					(end 25.888696 -215.445086)
				)
				(arc
					(start 24.415496 -215.445086)
					(mid 24.406516 -215.441366)
					(end 24.402796 -215.432386)
				)
				(arc
					(start 24.402796 -214.937848)
					(mid 24.406516 -214.928868)
					(end 24.415496 -214.925148)
				)
				(arc
					(start 25.888696 -214.925148)
					(mid 25.897676 -214.928868)
					(end 25.901396 -214.937848)
				)
			)
		)
	)
	(zone
		(layer "In1.Cu")
		(hatch none 0.5)
		(connect_pads
			(clearance 0)
		)
		(min_thickness 0.25)
		(keepout
			(tracks not_allowed)
			(vias allowed)
			(pads allowed)
			(copperpour not_allowed)
			(footprints allowed)
		)
		(placement
			(enabled no)
			(sheetname "")
		)
		(fill
			(thermal_gap 0.5)
			(thermal_bridge_width 0.5)
			(island_removal_mode 0)
		)
		(polygon
			(pts
				(arc
					(start 206.5782 -201.585322)
					(mid 205.9178 -201.585322)
					(end 206.5782 -201.585322)
				)
			)
		)
	)
	(zone
		(layer "In1.Cu")
		(hatch none 0.5)
		(connect_pads
			(clearance 0)
		)
		(min_thickness 0.25)
		(keepout
			(tracks not_allowed)
			(vias allowed)
			(pads allowed)
			(copperpour not_allowed)
			(footprints allowed)
		)
		(placement
			(enabled no)
			(sheetname "")
		)
		(fill
			(thermal_gap 0.5)
			(thermal_bridge_width 0.5)
			(island_removal_mode 0)
		)
		(polygon
			(pts
				(arc
					(start 265.87831 -210.935062)
					(mid 265.21791 -210.935062)
					(end 265.87831 -210.935062)
				)
			)
		)
	)
	(zone
		(layer "In1.Cu")
		(hatch none 0.5)
		(connect_pads
			(clearance 0)
		)
		(min_thickness 0.25)
		(keepout
			(tracks not_allowed)
			(vias allowed)
			(pads allowed)
			(copperpour not_allowed)
			(footprints allowed)
		)
		(placement
			(enabled no)
			(sheetname "")
		)
		(fill
			(thermal_gap 0.5)
			(thermal_bridge_width 0.5)
			(island_removal_mode 0)
		)
		(polygon
			(pts
				(arc
					(start 300.57344 -236.68228)
					(mid 300.56972 -236.69126)
					(end 300.56074 -236.69498)
				)
				(arc
					(start 299.08754 -236.69498)
					(mid 299.07856 -236.69126)
					(end 299.07484 -236.68228)
				)
				(arc
					(start 299.07484 -236.187742)
					(mid 299.07856 -236.178762)
					(end 299.08754 -236.175042)
				)
				(arc
					(start 300.56074 -236.175042)
					(mid 300.56972 -236.178762)
					(end 300.57344 -236.187742)
				)
			)
		)
	)
	(zone
		(layer "In1.Cu")
		(hatch none 0.5)
		(connect_pads
			(clearance 0)
		)
		(min_thickness 0.25)
		(keepout
			(tracks not_allowed)
			(vias allowed)
			(pads allowed)
			(copperpour not_allowed)
			(footprints allowed)
		)
		(placement
			(enabled no)
			(sheetname "")
		)
		(fill
			(thermal_gap 0.5)
			(thermal_bridge_width 0.5)
			(island_removal_mode 0)
		)
		(polygon
			(pts
				(arc
					(start 285.485332 -295.33215)
					(mid 285.481612 -295.34113)
					(end 285.472632 -295.34485)
				)
				(arc
					(start 283.999432 -295.34485)
					(mid 283.990452 -295.34113)
					(end 283.986732 -295.33215)
				)
				(arc
					(start 283.986732 -294.837612)
					(mid 283.990452 -294.828632)
					(end 283.999432 -294.824912)
				)
				(arc
					(start 285.472632 -294.824912)
					(mid 285.481612 -294.828632)
					(end 285.485332 -294.837612)
				)
			)
		)
	)
	(zone
		(layer "In1.Cu")
		(hatch none 0.5)
		(connect_pads
			(clearance 0)
		)
		(min_thickness 0.25)
		(keepout
			(tracks not_allowed)
			(vias allowed)
			(pads allowed)
			(copperpour not_allowed)
			(footprints allowed)
		)
		(placement
			(enabled no)
			(sheetname "")
		)
		(fill
			(thermal_gap 0.5)
			(thermal_bridge_width 0.5)
			(island_removal_mode 0)
		)
		(polygon
			(pts
				(arc
					(start 439.849514 -278.332184)
					(mid 439.845794 -278.341164)
					(end 439.836814 -278.344884)
				)
				(arc
					(start 438.363614 -278.344884)
					(mid 438.354634 -278.341164)
					(end 438.350914 -278.332184)
				)
				(arc
					(start 438.350914 -277.837646)
					(mid 438.354634 -277.828666)
					(end 438.363614 -277.824946)
				)
				(arc
					(start 439.836814 -277.824946)
					(mid 439.845794 -277.828666)
					(end 439.849514 -277.837646)
				)
			)
		)
	)
	(zone
		(layer "In1.Cu")
		(hatch none 0.5)
		(connect_pads
			(clearance 0)
		)
		(min_thickness 0.25)
		(keepout
			(tracks not_allowed)
			(vias allowed)
			(pads allowed)
			(copperpour not_allowed)
			(footprints allowed)
		)
		(placement
			(enabled no)
			(sheetname "")
		)
		(fill
			(thermal_gap 0.5)
			(thermal_bridge_width 0.5)
			(island_removal_mode 0)
		)
		(polygon
			(pts
				(arc
					(start 277.941532 -276.632162)
					(mid 277.937812 -276.641142)
					(end 277.928832 -276.644862)
				)
				(arc
					(start 276.455632 -276.644862)
					(mid 276.446652 -276.641142)
					(end 276.442932 -276.632162)
				)
				(arc
					(start 276.442932 -276.137624)
					(mid 276.446652 -276.128644)
					(end 276.455632 -276.124924)
				)
				(arc
					(start 277.928832 -276.124924)
					(mid 277.937812 -276.128644)
					(end 277.941532 -276.137624)
				)
			)
		)
	)
	(zone
		(layer "In1.Cu")
		(hatch none 0.5)
		(connect_pads
			(clearance 0)
		)
		(min_thickness 0.25)
		(keepout
			(tracks not_allowed)
			(vias allowed)
			(pads allowed)
			(copperpour not_allowed)
			(footprints allowed)
		)
		(placement
			(enabled no)
			(sheetname "")
		)
		(fill
			(thermal_gap 0.5)
			(thermal_bridge_width 0.5)
			(island_removal_mode 0)
		)
		(polygon
			(pts
				(arc
					(start 33.445196 -202.682348)
					(mid 33.441476 -202.691328)
					(end 33.432496 -202.695048)
				)
				(arc
					(start 31.959296 -202.695048)
					(mid 31.950316 -202.691328)
					(end 31.946596 -202.682348)
				)
				(arc
					(start 31.946596 -202.18781)
					(mid 31.950316 -202.17883)
					(end 31.959296 -202.17511)
				)
				(arc
					(start 33.432496 -202.17511)
					(mid 33.441476 -202.17883)
					(end 33.445196 -202.18781)
				)
			)
		)
	)
	(zone
		(layer "In1.Cu")
		(hatch none 0.5)
		(connect_pads
			(clearance 0)
		)
		(min_thickness 0.25)
		(keepout
			(tracks not_allowed)
			(vias allowed)
			(pads allowed)
			(copperpour not_allowed)
			(footprints allowed)
		)
		(placement
			(enabled no)
			(sheetname "")
		)
		(fill
			(thermal_gap 0.5)
			(thermal_bridge_width 0.5)
			(island_removal_mode 0)
		)
		(polygon
			(pts
				(arc
					(start 266.29741 -234.13212)
					(mid 266.29369 -234.1411)
					(end 266.28471 -234.14482)
				)
				(arc
					(start 264.81151 -234.14482)
					(mid 264.80253 -234.1411)
					(end 264.79881 -234.13212)
				)
				(arc
					(start 264.79881 -233.637582)
					(mid 264.80253 -233.628602)
					(end 264.81151 -233.624882)
				)
				(arc
					(start 266.28471 -233.624882)
					(mid 266.29369 -233.628602)
					(end 266.29741 -233.637582)
				)
			)
		)
	)
	(zone
		(layer "In1.Cu")
		(hatch none 0.5)
		(connect_pads
			(clearance 0)
		)
		(min_thickness 0.25)
		(keepout
			(tracks not_allowed)
			(vias allowed)
			(pads allowed)
			(copperpour not_allowed)
			(footprints allowed)
		)
		(placement
			(enabled no)
			(sheetname "")
		)
		(fill
			(thermal_gap 0.5)
			(thermal_bridge_width 0.5)
			(island_removal_mode 0)
		)
		(polygon
			(pts
				(arc
					(start 154.398218 -383.92227)
					(mid 154.093418 -383.92227)
					(end 154.398218 -383.92227)
				)
			)
		)
	)
	(zone
		(layer "In1.Cu")
		(hatch none 0.5)
		(connect_pads
			(clearance 0)
		)
		(min_thickness 0.25)
		(keepout
			(tracks not_allowed)
			(vias allowed)
			(pads allowed)
			(copperpour not_allowed)
			(footprints allowed)
		)
		(placement
			(enabled no)
			(sheetname "")
		)
		(fill
			(thermal_gap 0.5)
			(thermal_bridge_width 0.5)
			(island_removal_mode 0)
		)
		(polygon
			(pts
				(arc
					(start 56.077358 -220.532452)
					(mid 56.073638 -220.541432)
					(end 56.064658 -220.545152)
				)
				(arc
					(start 54.591458 -220.545152)
					(mid 54.582478 -220.541432)
					(end 54.578758 -220.532452)
				)
				(arc
					(start 54.578758 -220.037914)
					(mid 54.582478 -220.028934)
					(end 54.591458 -220.025214)
				)
				(arc
					(start 56.064658 -220.025214)
					(mid 56.073638 -220.028934)
					(end 56.077358 -220.037914)
				)
			)
		)
	)
	(zone
		(layer "In1.Cu")
		(hatch none 0.5)
		(connect_pads
			(clearance 0)
		)
		(min_thickness 0.25)
		(keepout
			(tracks not_allowed)
			(vias allowed)
			(pads allowed)
			(copperpour not_allowed)
			(footprints allowed)
		)
		(placement
			(enabled no)
			(sheetname "")
		)
		(fill
			(thermal_gap 0.5)
			(thermal_bridge_width 0.5)
			(island_removal_mode 0)
		)
		(polygon
			(pts
				(arc
					(start 199.4535 -216.282524)
					(mid 199.44978 -216.291504)
					(end 199.4408 -216.295224)
				)
				(arc
					(start 197.9676 -216.295224)
					(mid 197.95862 -216.291504)
					(end 197.9549 -216.282524)
				)
				(arc
					(start 197.9549 -215.787986)
					(mid 197.95862 -215.779006)
					(end 197.9676 -215.775286)
				)
				(arc
					(start 199.4408 -215.775286)
					(mid 199.44978 -215.779006)
					(end 199.4535 -215.787986)
				)
			)
		)
	)
	(zone
		(layer "In1.Cu")
		(hatch none 0.5)
		(connect_pads
			(clearance 0)
		)
		(min_thickness 0.25)
		(keepout
			(tracks not_allowed)
			(vias allowed)
			(pads allowed)
			(copperpour not_allowed)
			(footprints allowed)
		)
		(placement
			(enabled no)
			(sheetname "")
		)
		(fill
			(thermal_gap 0.5)
			(thermal_bridge_width 0.5)
			(island_removal_mode 0)
		)
		(polygon
			(pts
				(arc
					(start 202.897232 -291.93236)
					(mid 202.893512 -291.94134)
					(end 202.884532 -291.94506)
				)
				(arc
					(start 201.411332 -291.94506)
					(mid 201.402352 -291.94134)
					(end 201.398632 -291.93236)
				)
				(arc
					(start 201.398632 -291.437822)
					(mid 201.402352 -291.428842)
					(end 201.411332 -291.425122)
				)
				(arc
					(start 202.884532 -291.425122)
					(mid 202.893512 -291.428842)
					(end 202.897232 -291.437822)
				)
			)
		)
	)
	(zone
		(layer "In1.Cu")
		(hatch none 0.5)
		(connect_pads
			(clearance 0)
		)
		(min_thickness 0.25)
		(keepout
			(tracks not_allowed)
			(vias allowed)
			(pads allowed)
			(copperpour not_allowed)
			(footprints allowed)
		)
		(placement
			(enabled no)
			(sheetname "")
		)
		(fill
			(thermal_gap 0.5)
			(thermal_bridge_width 0.5)
			(island_removal_mode 0)
		)
		(polygon
			(pts
				(arc
					(start 191.909446 -266.432538)
					(mid 191.905726 -266.441518)
					(end 191.896746 -266.445238)
				)
				(arc
					(start 190.423546 -266.445238)
					(mid 190.414566 -266.441518)
					(end 190.410846 -266.432538)
				)
				(arc
					(start 190.410846 -265.938)
					(mid 190.414566 -265.92902)
					(end 190.423546 -265.9253)
				)
				(arc
					(start 191.896746 -265.9253)
					(mid 191.905726 -265.92902)
					(end 191.909446 -265.938)
				)
			)
		)
	)
	(zone
		(layer "In1.Cu")
		(hatch none 0.5)
		(connect_pads
			(clearance 0)
		)
		(min_thickness 0.25)
		(keepout
			(tracks not_allowed)
			(vias allowed)
			(pads allowed)
			(copperpour not_allowed)
			(footprints allowed)
		)
		(placement
			(enabled no)
			(sheetname "")
		)
		(fill
			(thermal_gap 0.5)
			(thermal_bridge_width 0.5)
			(island_removal_mode 0)
		)
		(polygon
			(pts
				(arc
					(start 22.45741 -274.08251)
					(mid 22.45369 -274.09149)
					(end 22.44471 -274.09521)
				)
				(arc
					(start 20.97151 -274.09521)
					(mid 20.96253 -274.09149)
					(end 20.95881 -274.08251)
				)
				(arc
					(start 20.95881 -273.587972)
					(mid 20.96253 -273.578992)
					(end 20.97151 -273.575272)
				)
				(arc
					(start 22.44471 -273.575272)
					(mid 22.45369 -273.578992)
					(end 22.45741 -273.587972)
				)
			)
		)
	)
	(zone
		(layer "In1.Cu")
		(hatch none 0.5)
		(connect_pads
			(clearance 0)
		)
		(min_thickness 0.25)
		(keepout
			(tracks not_allowed)
			(vias allowed)
			(pads allowed)
			(copperpour not_allowed)
			(footprints allowed)
		)
		(placement
			(enabled no)
			(sheetname "")
		)
		(fill
			(thermal_gap 0.5)
			(thermal_bridge_width 0.5)
			(island_removal_mode 0)
		)
		(polygon
			(pts
				(arc
					(start 191.909446 -229.882446)
					(mid 191.905726 -229.891426)
					(end 191.896746 -229.895146)
				)
				(arc
					(start 190.423546 -229.895146)
					(mid 190.414566 -229.891426)
					(end 190.410846 -229.882446)
				)
				(arc
					(start 190.410846 -229.387908)
					(mid 190.414566 -229.378928)
					(end 190.423546 -229.375208)
				)
				(arc
					(start 191.896746 -229.375208)
					(mid 191.905726 -229.378928)
					(end 191.909446 -229.387908)
				)
			)
		)
	)
	(zone
		(layer "In1.Cu")
		(hatch none 0.5)
		(connect_pads
			(clearance 0)
		)
		(min_thickness 0.25)
		(keepout
			(tracks not_allowed)
			(vias allowed)
			(pads allowed)
			(copperpour not_allowed)
			(footprints allowed)
		)
		(placement
			(enabled no)
			(sheetname "")
		)
		(fill
			(thermal_gap 0.5)
			(thermal_bridge_width 0.5)
			(island_removal_mode 0)
		)
		(polygon
			(pts
				(arc
					(start 118.161308 -385.31038)
					(mid 117.780308 -385.31038)
					(end 118.161308 -385.31038)
				)
			)
		)
	)
	(zone
		(layer "In1.Cu")
		(hatch none 0.5)
		(connect_pads
			(clearance 0)
		)
		(min_thickness 0.25)
		(keepout
			(tracks not_allowed)
			(vias allowed)
			(pads allowed)
			(copperpour not_allowed)
			(footprints allowed)
		)
		(placement
			(enabled no)
			(sheetname "")
		)
		(fill
			(thermal_gap 0.5)
			(thermal_bridge_width 0.5)
			(island_removal_mode 0)
		)
		(polygon
			(pts
				(arc
					(start 265.87831 -306.985162)
					(mid 265.21791 -306.985162)
					(end 265.87831 -306.985162)
				)
			)
		)
	)
	(zone
		(layer "In1.Cu")
		(hatch none 0.5)
		(connect_pads
			(clearance 0)
		)
		(min_thickness 0.25)
		(keepout
			(tracks not_allowed)
			(vias allowed)
			(pads allowed)
			(copperpour not_allowed)
			(footprints allowed)
		)
		(placement
			(enabled no)
			(sheetname "")
		)
		(fill
			(thermal_gap 0.5)
			(thermal_bridge_width 0.5)
			(island_removal_mode 0)
		)
		(polygon
			(pts
				(arc
					(start 180.265324 -198.43242)
					(mid 180.261604 -198.4414)
					(end 180.252624 -198.44512)
				)
				(arc
					(start 178.779424 -198.44512)
					(mid 178.770444 -198.4414)
					(end 178.766724 -198.43242)
				)
				(arc
					(start 178.766724 -197.937882)
					(mid 178.770444 -197.928902)
					(end 178.779424 -197.925182)
				)
				(arc
					(start 180.252624 -197.925182)
					(mid 180.261604 -197.928902)
					(end 180.265324 -197.937882)
				)
			)
		)
	)
	(zone
		(layer "In1.Cu")
		(hatch none 0.5)
		(connect_pads
			(clearance 0)
		)
		(min_thickness 0.25)
		(keepout
			(tracks not_allowed)
			(vias allowed)
			(pads allowed)
			(copperpour not_allowed)
			(footprints allowed)
		)
		(placement
			(enabled no)
			(sheetname "")
		)
		(fill
			(thermal_gap 0.5)
			(thermal_bridge_width 0.5)
			(island_removal_mode 0)
		)
		(polygon
			(pts
				(arc
					(start 37.545264 -238.382556)
					(mid 37.541544 -238.391536)
					(end 37.532564 -238.395256)
				)
				(arc
					(start 36.059364 -238.395256)
					(mid 36.050384 -238.391536)
					(end 36.046664 -238.382556)
				)
				(arc
					(start 36.046664 -237.888018)
					(mid 36.050384 -237.879038)
					(end 36.059364 -237.875318)
				)
				(arc
					(start 37.532564 -237.875318)
					(mid 37.541544 -237.879038)
					(end 37.545264 -237.888018)
				)
			)
		)
	)
	(zone
		(layer "In1.Cu")
		(hatch none 0.5)
		(connect_pads
			(clearance 0)
		)
		(min_thickness 0.25)
		(keepout
			(tracks not_allowed)
			(vias allowed)
			(pads allowed)
			(copperpour not_allowed)
			(footprints allowed)
		)
		(placement
			(enabled no)
			(sheetname "")
		)
		(fill
			(thermal_gap 0.5)
			(thermal_bridge_width 0.5)
			(island_removal_mode 0)
		)
		(polygon
			(pts
				(arc
					(start 417.217352 -291.082222)
					(mid 417.213632 -291.091202)
					(end 417.204652 -291.094922)
				)
				(arc
					(start 415.731452 -291.094922)
					(mid 415.722472 -291.091202)
					(end 415.718752 -291.082222)
				)
				(arc
					(start 415.718752 -290.587684)
					(mid 415.722472 -290.578704)
					(end 415.731452 -290.574984)
				)
				(arc
					(start 417.204652 -290.574984)
					(mid 417.213632 -290.578704)
					(end 417.217352 -290.587684)
				)
			)
		)
	)
	(zone
		(layer "In1.Cu")
		(hatch none 0.5)
		(connect_pads
			(clearance 0)
		)
		(min_thickness 0.25)
		(keepout
			(tracks not_allowed)
			(vias allowed)
			(pads allowed)
			(copperpour not_allowed)
			(footprints allowed)
		)
		(placement
			(enabled no)
			(sheetname "")
		)
		(fill
			(thermal_gap 0.5)
			(thermal_bridge_width 0.5)
			(island_removal_mode 0)
		)
		(polygon
			(pts
				(arc
					(start 308.117494 -317.432182)
					(mid 308.113774 -317.441162)
					(end 308.104794 -317.444882)
				)
				(arc
					(start 306.631594 -317.444882)
					(mid 306.622614 -317.441162)
					(end 306.618894 -317.432182)
				)
				(arc
					(start 306.618894 -316.937644)
					(mid 306.622614 -316.928664)
					(end 306.631594 -316.924944)
				)
				(arc
					(start 308.104794 -316.924944)
					(mid 308.113774 -316.928664)
					(end 308.117494 -316.937644)
				)
			)
		)
	)
	(zone
		(layer "In1.Cu")
		(hatch none 0.5)
		(connect_pads
			(clearance 0)
		)
		(min_thickness 0.25)
		(keepout
			(tracks not_allowed)
			(vias allowed)
			(pads allowed)
			(copperpour not_allowed)
			(footprints allowed)
		)
		(placement
			(enabled no)
			(sheetname "")
		)
		(fill
			(thermal_gap 0.5)
			(thermal_bridge_width 0.5)
			(island_removal_mode 0)
		)
		(polygon
			(pts
				(arc
					(start 82.78876 -389.467344)
					(mid 82.40776 -389.467344)
					(end 82.78876 -389.467344)
				)
			)
		)
	)
	(zone
		(layer "In1.Cu")
		(hatch none 0.5)
		(connect_pads
			(clearance 0)
		)
		(min_thickness 0.25)
		(keepout
			(tracks not_allowed)
			(vias allowed)
			(pads allowed)
			(copperpour not_allowed)
			(footprints allowed)
		)
		(placement
			(enabled no)
			(sheetname "")
		)
		(fill
			(thermal_gap 0.5)
			(thermal_bridge_width 0.5)
			(island_removal_mode 0)
		)
		(polygon
			(pts
				(arc
					(start 288.929318 -301.2821)
					(mid 288.925598 -301.29108)
					(end 288.916618 -301.2948)
				)
				(arc
					(start 287.443418 -301.2948)
					(mid 287.434438 -301.29108)
					(end 287.430718 -301.2821)
				)
				(arc
					(start 287.430718 -300.787562)
					(mid 287.434438 -300.778582)
					(end 287.443418 -300.774862)
				)
				(arc
					(start 288.916618 -300.774862)
					(mid 288.925598 -300.778582)
					(end 288.929318 -300.787562)
				)
			)
		)
	)
	(zone
		(layer "In1.Cu")
		(hatch none 0.5)
		(connect_pads
			(clearance 0)
		)
		(min_thickness 0.25)
		(keepout
			(tracks not_allowed)
			(vias allowed)
			(pads allowed)
			(copperpour not_allowed)
			(footprints allowed)
		)
		(placement
			(enabled no)
			(sheetname "")
		)
		(fill
			(thermal_gap 0.5)
			(thermal_bridge_width 0.5)
			(island_removal_mode 0)
		)
		(polygon
			(pts
				(arc
					(start 206.5782 -278.085296)
					(mid 205.9178 -278.085296)
					(end 206.5782 -278.085296)
				)
			)
		)
	)
	(zone
		(layer "In1.Cu")
		(hatch none 0.5)
		(connect_pads
			(clearance 0)
		)
		(min_thickness 0.25)
		(keepout
			(tracks not_allowed)
			(vias allowed)
			(pads allowed)
			(copperpour not_allowed)
			(footprints allowed)
		)
		(placement
			(enabled no)
			(sheetname "")
		)
		(fill
			(thermal_gap 0.5)
			(thermal_bridge_width 0.5)
			(island_removal_mode 0)
		)
		(polygon
			(pts
				(arc
					(start 22.45741 -246.032528)
					(mid 22.45369 -246.041508)
					(end 22.44471 -246.045228)
				)
				(arc
					(start 20.97151 -246.045228)
					(mid 20.96253 -246.041508)
					(end 20.95881 -246.032528)
				)
				(arc
					(start 20.95881 -245.53799)
					(mid 20.96253 -245.52901)
					(end 20.97151 -245.52529)
				)
				(arc
					(start 22.44471 -245.52529)
					(mid 22.45369 -245.52901)
					(end 22.45741 -245.53799)
				)
			)
		)
	)
	(zone
		(layer "In1.Cu")
		(hatch none 0.5)
		(connect_pads
			(clearance 0)
		)
		(min_thickness 0.25)
		(keepout
			(tracks not_allowed)
			(vias allowed)
			(pads allowed)
			(copperpour not_allowed)
			(footprints allowed)
		)
		(placement
			(enabled no)
			(sheetname "")
		)
		(fill
			(thermal_gap 0.5)
			(thermal_bridge_width 0.5)
			(island_removal_mode 0)
		)
		(polygon
			(pts
				(arc
					(start 202.897232 -206.082392)
					(mid 202.893512 -206.091372)
					(end 202.884532 -206.095092)
				)
				(arc
					(start 201.411332 -206.095092)
					(mid 201.402352 -206.091372)
					(end 201.398632 -206.082392)
				)
				(arc
					(start 201.398632 -205.587854)
					(mid 201.402352 -205.578874)
					(end 201.411332 -205.575154)
				)
				(arc
					(start 202.884532 -205.575154)
					(mid 202.893512 -205.578874)
					(end 202.897232 -205.587854)
				)
			)
		)
	)
	(zone
		(layer "In1.Cu")
		(hatch none 0.5)
		(connect_pads
			(clearance 0)
		)
		(min_thickness 0.25)
		(keepout
			(tracks not_allowed)
			(vias allowed)
			(pads allowed)
			(copperpour not_allowed)
			(footprints allowed)
		)
		(placement
			(enabled no)
			(sheetname "")
		)
		(fill
			(thermal_gap 0.5)
			(thermal_bridge_width 0.5)
			(island_removal_mode 0)
		)
		(polygon
			(pts
				(arc
					(start 127.870458 -383.92227)
					(mid 127.565658 -383.92227)
					(end 127.870458 -383.92227)
				)
			)
		)
	)
	(zone
		(layer "In1.Cu")
		(hatch none 0.5)
		(connect_pads
			(clearance 0)
		)
		(min_thickness 0.25)
		(keepout
			(tracks not_allowed)
			(vias allowed)
			(pads allowed)
			(copperpour not_allowed)
			(footprints allowed)
		)
		(placement
			(enabled no)
			(sheetname "")
		)
		(fill
			(thermal_gap 0.5)
			(thermal_bridge_width 0.5)
			(island_removal_mode 0)
		)
		(polygon
			(pts
				(arc
					(start 47.461424 -385.31038)
					(mid 47.080424 -385.31038)
					(end 47.461424 -385.31038)
				)
			)
		)
	)
	(zone
		(layer "In1.Cu")
		(hatch none 0.5)
		(connect_pads
			(clearance 0)
		)
		(min_thickness 0.25)
		(keepout
			(tracks not_allowed)
			(vias allowed)
			(pads allowed)
			(copperpour not_allowed)
			(footprints allowed)
		)
		(placement
			(enabled no)
			(sheetname "")
		)
		(fill
			(thermal_gap 0.5)
			(thermal_bridge_width 0.5)
			(island_removal_mode 0)
		)
		(polygon
			(pts
				(arc
					(start 18.357342 -288.53257)
					(mid 18.353622 -288.54155)
					(end 18.344642 -288.54527)
				)
				(arc
					(start 16.871442 -288.54527)
					(mid 16.862462 -288.54155)
					(end 16.858742 -288.53257)
				)
				(arc
					(start 16.858742 -288.038032)
					(mid 16.862462 -288.029052)
					(end 16.871442 -288.025332)
				)
				(arc
					(start 18.344642 -288.025332)
					(mid 18.353622 -288.029052)
					(end 18.357342 -288.038032)
				)
			)
		)
	)
	(zone
		(layer "In1.Cu")
		(hatch none 0.5)
		(connect_pads
			(clearance 0)
		)
		(min_thickness 0.25)
		(keepout
			(tracks not_allowed)
			(vias allowed)
			(pads allowed)
			(copperpour not_allowed)
			(footprints allowed)
		)
		(placement
			(enabled no)
			(sheetname "")
		)
		(fill
			(thermal_gap 0.5)
			(thermal_bridge_width 0.5)
			(island_removal_mode 0)
		)
		(polygon
			(pts
				(arc
					(start 305.860958 -397.156432)
					(mid 305.479958 -397.156432)
					(end 305.860958 -397.156432)
				)
			)
		)
	)
	(zone
		(layer "In1.Cu")
		(hatch none 0.5)
		(connect_pads
			(clearance 0)
		)
		(min_thickness 0.25)
		(keepout
			(tracks not_allowed)
			(vias allowed)
			(pads allowed)
			(copperpour not_allowed)
			(footprints allowed)
		)
		(placement
			(enabled no)
			(sheetname "")
		)
		(fill
			(thermal_gap 0.5)
			(thermal_bridge_width 0.5)
			(island_removal_mode 0)
		)
		(polygon
			(pts
				(arc
					(start 153.818844 -391.319258)
					(mid 153.945844 -391.446258)
					(end 154.072844 -391.319258)
				)
				(arc
					(start 154.072844 -391.243058)
					(mid 153.945844 -391.116058)
					(end 153.818844 -391.243058)
				)
			)
		)
	)
	(zone
		(layer "In1.Cu")
		(hatch none 0.5)
		(connect_pads
			(clearance 0)
		)
		(min_thickness 0.25)
		(keepout
			(tracks not_allowed)
			(vias allowed)
			(pads allowed)
			(copperpour not_allowed)
			(footprints allowed)
		)
		(placement
			(enabled no)
			(sheetname "")
		)
		(fill
			(thermal_gap 0.5)
			(thermal_bridge_width 0.5)
			(island_removal_mode 0)
		)
		(polygon
			(pts
				(arc
					(start 187.809378 -239.23244)
					(mid 187.805658 -239.24142)
					(end 187.796678 -239.24514)
				)
				(arc
					(start 186.323478 -239.24514)
					(mid 186.314498 -239.24142)
					(end 186.310778 -239.23244)
				)
				(arc
					(start 186.310778 -238.737902)
					(mid 186.314498 -238.728922)
					(end 186.323478 -238.725202)
				)
				(arc
					(start 187.796678 -238.725202)
					(mid 187.805658 -238.728922)
					(end 187.809378 -238.737902)
				)
			)
		)
	)
	(zone
		(layer "In1.Cu")
		(hatch none 0.5)
		(connect_pads
			(clearance 0)
		)
		(min_thickness 0.25)
		(keepout
			(tracks not_allowed)
			(vias allowed)
			(pads allowed)
			(copperpour not_allowed)
			(footprints allowed)
		)
		(placement
			(enabled no)
			(sheetname "")
		)
		(fill
			(thermal_gap 0.5)
			(thermal_bridge_width 0.5)
			(island_removal_mode 0)
		)
		(polygon
			(pts
				(arc
					(start 123.070366 -390.761474)
					(mid 122.765566 -390.761474)
					(end 123.070366 -390.761474)
				)
			)
		)
	)
	(zone
		(layer "In1.Cu")
		(hatch none 0.5)
		(connect_pads
			(clearance 0)
		)
		(min_thickness 0.25)
		(keepout
			(tracks not_allowed)
			(vias allowed)
			(pads allowed)
			(copperpour not_allowed)
			(footprints allowed)
		)
		(placement
			(enabled no)
			(sheetname "")
		)
		(fill
			(thermal_gap 0.5)
			(thermal_bridge_width 0.5)
			(island_removal_mode 0)
		)
		(polygon
			(pts
				(arc
					(start 439.849514 -297.032172)
					(mid 439.845794 -297.041152)
					(end 439.836814 -297.044872)
				)
				(arc
					(start 438.363614 -297.044872)
					(mid 438.354634 -297.041152)
					(end 438.350914 -297.032172)
				)
				(arc
					(start 438.350914 -296.537634)
					(mid 438.354634 -296.528654)
					(end 438.363614 -296.524934)
				)
				(arc
					(start 439.836814 -296.524934)
					(mid 439.845794 -296.528654)
					(end 439.849514 -296.537634)
				)
			)
		)
	)
	(zone
		(layer "In1.Cu")
		(hatch none 0.5)
		(connect_pads
			(clearance 0)
		)
		(min_thickness 0.25)
		(keepout
			(tracks not_allowed)
			(vias allowed)
			(pads allowed)
			(copperpour not_allowed)
			(footprints allowed)
		)
		(placement
			(enabled no)
			(sheetname "")
		)
		(fill
			(thermal_gap 0.5)
			(thermal_bridge_width 0.5)
			(island_removal_mode 0)
		)
		(polygon
			(pts
				(arc
					(start 265.87831 -250.03506)
					(mid 265.21791 -250.03506)
					(end 265.87831 -250.03506)
				)
			)
		)
	)
	(zone
		(layer "In1.Cu")
		(hatch none 0.5)
		(connect_pads
			(clearance 0)
		)
		(min_thickness 0.25)
		(keepout
			(tracks not_allowed)
			(vias allowed)
			(pads allowed)
			(copperpour not_allowed)
			(footprints allowed)
		)
		(placement
			(enabled no)
			(sheetname "")
		)
		(fill
			(thermal_gap 0.5)
			(thermal_bridge_width 0.5)
			(island_removal_mode 0)
		)
		(polygon
			(pts
				(arc
					(start 285.485332 -201.83221)
					(mid 285.481612 -201.84119)
					(end 285.472632 -201.84491)
				)
				(arc
					(start 283.999432 -201.84491)
					(mid 283.990452 -201.84119)
					(end 283.986732 -201.83221)
				)
				(arc
					(start 283.986732 -201.337672)
					(mid 283.990452 -201.328692)
					(end 283.999432 -201.324972)
				)
				(arc
					(start 285.472632 -201.324972)
					(mid 285.481612 -201.328692)
					(end 285.485332 -201.337672)
				)
			)
		)
	)
	(zone
		(layer "In1.Cu")
		(hatch none 0.5)
		(connect_pads
			(clearance 0)
		)
		(min_thickness 0.25)
		(keepout
			(tracks not_allowed)
			(vias allowed)
			(pads allowed)
			(copperpour not_allowed)
			(footprints allowed)
		)
		(placement
			(enabled no)
			(sheetname "")
		)
		(fill
			(thermal_gap 0.5)
			(thermal_bridge_width 0.5)
			(island_removal_mode 0)
		)
		(polygon
			(pts
				(arc
					(start 40.98925 -263.882378)
					(mid 40.98553 -263.891358)
					(end 40.97655 -263.895078)
				)
				(arc
					(start 39.50335 -263.895078)
					(mid 39.49437 -263.891358)
					(end 39.49065 -263.882378)
				)
				(arc
					(start 39.49065 -263.38784)
					(mid 39.49437 -263.37886)
					(end 39.50335 -263.37514)
				)
				(arc
					(start 40.97655 -263.37514)
					(mid 40.98553 -263.37886)
					(end 40.98925 -263.38784)
				)
			)
		)
	)
	(zone
		(layer "In1.Cu")
		(hatch none 0.5)
		(connect_pads
			(clearance 0)
		)
		(min_thickness 0.25)
		(keepout
			(tracks not_allowed)
			(vias allowed)
			(pads allowed)
			(copperpour not_allowed)
			(footprints allowed)
		)
		(placement
			(enabled no)
			(sheetname "")
		)
		(fill
			(thermal_gap 0.5)
			(thermal_bridge_width 0.5)
			(island_removal_mode 0)
		)
		(polygon
			(pts
				(arc
					(start 303.576736 -417.242244)
					(mid 303.599054 -417.296126)
					(end 303.652936 -417.318444)
				)
				(arc
					(start 303.848516 -417.318444)
					(mid 303.870392 -417.315312)
					(end 303.890426 -417.305998)
				)
				(arc
					(start 304.18405 -417.113466)
					(mid 304.225706 -417.101064)
					(end 304.267362 -417.113466)
				)
				(arc
					(start 304.562256 -417.305998)
					(mid 304.58218 -417.315234)
					(end 304.603912 -417.318444)
				)
				(arc
					(start 304.798476 -417.318444)
					(mid 304.852358 -417.296126)
					(end 304.874676 -417.242244)
				)
				(arc
					(start 304.874676 -416.556444)
					(mid 304.852358 -416.502562)
					(end 304.798476 -416.480244)
				)
				(arc
					(start 304.603912 -416.480244)
					(mid 304.582168 -416.483412)
					(end 304.562256 -416.49269)
				)
				(arc
					(start 304.266092 -416.685476)
					(mid 304.224408 -416.697698)
					(end 304.18278 -416.685222)
				)
				(arc
					(start 303.889156 -416.49269)
					(mid 303.869232 -416.483454)
					(end 303.8475 -416.480244)
				)
				(arc
					(start 303.652936 -416.480244)
					(mid 303.599054 -416.502562)
					(end 303.576736 -416.556444)
				)
			)
		)
	)
	(zone
		(layer "In1.Cu")
		(hatch none 0.5)
		(connect_pads
			(clearance 0)
		)
		(min_thickness 0.25)
		(keepout
			(tracks not_allowed)
			(vias allowed)
			(pads allowed)
			(copperpour not_allowed)
			(footprints allowed)
		)
		(placement
			(enabled no)
			(sheetname "")
		)
		(fill
			(thermal_gap 0.5)
			(thermal_bridge_width 0.5)
			(island_removal_mode 0)
		)
		(polygon
			(pts
				(arc
					(start 300.57344 -220.532198)
					(mid 300.56972 -220.541178)
					(end 300.56074 -220.544898)
				)
				(arc
					(start 299.08754 -220.544898)
					(mid 299.07856 -220.541178)
					(end 299.07484 -220.532198)
				)
				(arc
					(start 299.07484 -220.03766)
					(mid 299.07856 -220.02868)
					(end 299.08754 -220.02496)
				)
				(arc
					(start 300.56074 -220.02496)
					(mid 300.56972 -220.02868)
					(end 300.57344 -220.03766)
				)
			)
		)
	)
	(zone
		(layer "In1.Cu")
		(hatch none 0.5)
		(connect_pads
			(clearance 0)
		)
		(min_thickness 0.25)
		(keepout
			(tracks not_allowed)
			(vias allowed)
			(pads allowed)
			(copperpour not_allowed)
			(footprints allowed)
		)
		(placement
			(enabled no)
			(sheetname "")
		)
		(fill
			(thermal_gap 0.5)
			(thermal_bridge_width 0.5)
			(island_removal_mode 0)
		)
		(polygon
			(pts
				(arc
					(start 60.177426 -297.032426)
					(mid 60.173706 -297.041406)
					(end 60.164726 -297.045126)
				)
				(arc
					(start 58.691526 -297.045126)
					(mid 58.682546 -297.041406)
					(end 58.678826 -297.032426)
				)
				(arc
					(start 58.678826 -296.537888)
					(mid 58.682546 -296.528908)
					(end 58.691526 -296.525188)
				)
				(arc
					(start 60.164726 -296.525188)
					(mid 60.173706 -296.528908)
					(end 60.177426 -296.537888)
				)
			)
		)
	)
	(zone
		(layer "In1.Cu")
		(hatch none 0.5)
		(connect_pads
			(clearance 0)
		)
		(min_thickness 0.25)
		(keepout
			(tracks not_allowed)
			(vias allowed)
			(pads allowed)
			(copperpour not_allowed)
			(footprints allowed)
		)
		(placement
			(enabled no)
			(sheetname "")
		)
		(fill
			(thermal_gap 0.5)
			(thermal_bridge_width 0.5)
			(island_removal_mode 0)
		)
		(polygon
			(pts
				(arc
					(start 56.077358 -262.182356)
					(mid 56.073638 -262.191336)
					(end 56.064658 -262.195056)
				)
				(arc
					(start 54.591458 -262.195056)
					(mid 54.582478 -262.191336)
					(end 54.578758 -262.182356)
				)
				(arc
					(start 54.578758 -261.687818)
					(mid 54.582478 -261.678838)
					(end 54.591458 -261.675118)
				)
				(arc
					(start 56.064658 -261.675118)
					(mid 56.073638 -261.678838)
					(end 56.077358 -261.687818)
				)
			)
		)
	)
	(zone
		(layer "In1.Cu")
		(hatch none 0.5)
		(connect_pads
			(clearance 0)
		)
		(min_thickness 0.25)
		(keepout
			(tracks not_allowed)
			(vias allowed)
			(pads allowed)
			(copperpour not_allowed)
			(footprints allowed)
		)
		(placement
			(enabled no)
			(sheetname "")
		)
		(fill
			(thermal_gap 0.5)
			(thermal_bridge_width 0.5)
			(island_removal_mode 0)
		)
		(polygon
			(pts
				(arc
					(start 56.077358 -267.282422)
					(mid 56.073638 -267.291402)
					(end 56.064658 -267.295122)
				)
				(arc
					(start 54.591458 -267.295122)
					(mid 54.582478 -267.291402)
					(end 54.578758 -267.282422)
				)
				(arc
					(start 54.578758 -266.787884)
					(mid 54.582478 -266.778904)
					(end 54.591458 -266.775184)
				)
				(arc
					(start 56.064658 -266.775184)
					(mid 56.073638 -266.778904)
					(end 56.077358 -266.787884)
				)
			)
		)
	)
	(zone
		(layer "In1.Cu")
		(hatch none 0.5)
		(connect_pads
			(clearance 0)
		)
		(min_thickness 0.25)
		(keepout
			(tracks not_allowed)
			(vias allowed)
			(pads allowed)
			(copperpour not_allowed)
			(footprints allowed)
		)
		(placement
			(enabled no)
			(sheetname "")
		)
		(fill
			(thermal_gap 0.5)
			(thermal_bridge_width 0.5)
			(island_removal_mode 0)
		)
		(polygon
			(pts
				(arc
					(start 417.217352 -280.032206)
					(mid 417.213632 -280.041186)
					(end 417.204652 -280.044906)
				)
				(arc
					(start 415.731452 -280.044906)
					(mid 415.722472 -280.041186)
					(end 415.718752 -280.032206)
				)
				(arc
					(start 415.718752 -279.537668)
					(mid 415.722472 -279.528688)
					(end 415.731452 -279.524968)
				)
				(arc
					(start 417.204652 -279.524968)
					(mid 417.213632 -279.528688)
					(end 417.217352 -279.537668)
				)
			)
		)
	)
	(zone
		(layer "In1.Cu")
		(hatch none 0.5)
		(connect_pads
			(clearance 0)
		)
		(min_thickness 0.25)
		(keepout
			(tracks not_allowed)
			(vias allowed)
			(pads allowed)
			(copperpour not_allowed)
			(footprints allowed)
		)
		(placement
			(enabled no)
			(sheetname "")
		)
		(fill
			(thermal_gap 0.5)
			(thermal_bridge_width 0.5)
			(island_removal_mode 0)
		)
		(polygon
			(pts
				(arc
					(start 379.690884 -391.822686)
					(mid 379.817884 -391.949686)
					(end 379.944884 -391.822686)
				)
				(arc
					(start 379.944884 -391.746486)
					(mid 379.817884 -391.619486)
					(end 379.690884 -391.746486)
				)
			)
		)
	)
	(zone
		(layer "In1.Cu")
		(hatch none 0.5)
		(connect_pads
			(clearance 0)
		)
		(min_thickness 0.25)
		(keepout
			(tracks not_allowed)
			(vias allowed)
			(pads allowed)
			(copperpour not_allowed)
			(footprints allowed)
		)
		(placement
			(enabled no)
			(sheetname "")
		)
		(fill
			(thermal_gap 0.5)
			(thermal_bridge_width 0.5)
			(island_removal_mode 0)
		)
		(polygon
			(pts
				(arc
					(start 288.929318 -230.73233)
					(mid 288.925598 -230.74131)
					(end 288.916618 -230.74503)
				)
				(arc
					(start 287.443418 -230.74503)
					(mid 287.434438 -230.74131)
					(end 287.430718 -230.73233)
				)
				(arc
					(start 287.430718 -230.237792)
					(mid 287.434438 -230.228812)
					(end 287.443418 -230.225092)
				)
				(arc
					(start 288.916618 -230.225092)
					(mid 288.925598 -230.228812)
					(end 288.929318 -230.237792)
				)
			)
		)
	)
	(zone
		(layer "In1.Cu")
		(hatch none 0.5)
		(connect_pads
			(clearance 0)
		)
		(min_thickness 0.25)
		(keepout
			(tracks not_allowed)
			(vias allowed)
			(pads allowed)
			(copperpour not_allowed)
			(footprints allowed)
		)
		(placement
			(enabled no)
			(sheetname "")
		)
		(fill
			(thermal_gap 0.5)
			(thermal_bridge_width 0.5)
			(island_removal_mode 0)
		)
		(polygon
			(pts
				(arc
					(start 195.353432 -286.832548)
					(mid 195.349712 -286.841528)
					(end 195.340732 -286.845248)
				)
				(arc
					(start 193.867532 -286.845248)
					(mid 193.858552 -286.841528)
					(end 193.854832 -286.832548)
				)
				(arc
					(start 193.854832 -286.33801)
					(mid 193.858552 -286.32903)
					(end 193.867532 -286.32531)
				)
				(arc
					(start 195.340732 -286.32531)
					(mid 195.349712 -286.32903)
					(end 195.353432 -286.33801)
				)
			)
		)
	)
	(zone
		(layer "In1.Cu")
		(hatch none 0.5)
		(connect_pads
			(clearance 0)
		)
		(min_thickness 0.25)
		(keepout
			(tracks not_allowed)
			(vias allowed)
			(pads allowed)
			(copperpour not_allowed)
			(footprints allowed)
		)
		(placement
			(enabled no)
			(sheetname "")
		)
		(fill
			(thermal_gap 0.5)
			(thermal_bridge_width 0.5)
			(island_removal_mode 0)
		)
		(polygon
			(pts
				(arc
					(start 296.473372 -316.582298)
					(mid 296.469652 -316.591278)
					(end 296.460672 -316.594998)
				)
				(arc
					(start 294.987472 -316.594998)
					(mid 294.978492 -316.591278)
					(end 294.974772 -316.582298)
				)
				(arc
					(start 294.974772 -316.08776)
					(mid 294.978492 -316.07878)
					(end 294.987472 -316.07506)
				)
				(arc
					(start 296.460672 -316.07506)
					(mid 296.469652 -316.07878)
					(end 296.473372 -316.08776)
				)
			)
		)
	)
	(zone
		(layer "In1.Cu")
		(hatch none 0.5)
		(connect_pads
			(clearance 0)
		)
		(min_thickness 0.25)
		(keepout
			(tracks not_allowed)
			(vias allowed)
			(pads allowed)
			(copperpour not_allowed)
			(footprints allowed)
		)
		(placement
			(enabled no)
			(sheetname "")
		)
		(fill
			(thermal_gap 0.5)
			(thermal_bridge_width 0.5)
			(island_removal_mode 0)
		)
		(polygon
			(pts
				(arc
					(start 386.891022 -399.701258)
					(mid 387.018022 -399.828258)
					(end 387.145022 -399.701258)
				)
				(arc
					(start 387.145022 -399.625058)
					(mid 387.018022 -399.498058)
					(end 386.891022 -399.625058)
				)
			)
		)
	)
	(zone
		(layer "In1.Cu")
		(hatch none 0.5)
		(connect_pads
			(clearance 0)
		)
		(min_thickness 0.25)
		(keepout
			(tracks not_allowed)
			(vias allowed)
			(pads allowed)
			(copperpour not_allowed)
			(footprints allowed)
		)
		(placement
			(enabled no)
			(sheetname "")
		)
		(fill
			(thermal_gap 0.5)
			(thermal_bridge_width 0.5)
			(island_removal_mode 0)
		)
		(polygon
			(pts
				(arc
					(start 52.633372 -311.482486)
					(mid 52.629652 -311.491466)
					(end 52.620672 -311.495186)
				)
				(arc
					(start 51.147472 -311.495186)
					(mid 51.138492 -311.491466)
					(end 51.134772 -311.482486)
				)
				(arc
					(start 51.134772 -310.987948)
					(mid 51.138492 -310.978968)
					(end 51.147472 -310.975248)
				)
				(arc
					(start 52.620672 -310.975248)
					(mid 52.629652 -310.978968)
					(end 52.633372 -310.987948)
				)
			)
		)
	)
	(zone
		(layer "In1.Cu")
		(hatch none 0.5)
		(connect_pads
			(clearance 0)
		)
		(min_thickness 0.25)
		(keepout
			(tracks not_allowed)
			(vias allowed)
			(pads allowed)
			(copperpour not_allowed)
			(footprints allowed)
		)
		(placement
			(enabled no)
			(sheetname "")
		)
		(fill
			(thermal_gap 0.5)
			(thermal_bridge_width 0.5)
			(island_removal_mode 0)
		)
		(polygon
			(pts
				(arc
					(start 191.909446 -283.432504)
					(mid 191.905726 -283.441484)
					(end 191.896746 -283.445204)
				)
				(arc
					(start 190.423546 -283.445204)
					(mid 190.414566 -283.441484)
					(end 190.410846 -283.432504)
				)
				(arc
					(start 190.410846 -282.937966)
					(mid 190.414566 -282.928986)
					(end 190.423546 -282.925266)
				)
				(arc
					(start 191.896746 -282.925266)
					(mid 191.905726 -282.928986)
					(end 191.909446 -282.937966)
				)
			)
		)
	)
	(zone
		(layer "In1.Cu")
		(hatch none 0.5)
		(connect_pads
			(clearance 0)
		)
		(min_thickness 0.25)
		(keepout
			(tracks not_allowed)
			(vias allowed)
			(pads allowed)
			(copperpour not_allowed)
			(footprints allowed)
		)
		(placement
			(enabled no)
			(sheetname "")
		)
		(fill
			(thermal_gap 0.5)
			(thermal_bridge_width 0.5)
			(island_removal_mode 0)
		)
		(polygon
			(pts
				(arc
					(start 30.001464 -289.382454)
					(mid 29.997744 -289.391434)
					(end 29.988764 -289.395154)
				)
				(arc
					(start 28.515564 -289.395154)
					(mid 28.506584 -289.391434)
					(end 28.502864 -289.382454)
				)
				(arc
					(start 28.502864 -288.887916)
					(mid 28.506584 -288.878936)
					(end 28.515564 -288.875216)
				)
				(arc
					(start 29.988764 -288.875216)
					(mid 29.997744 -288.878936)
					(end 30.001464 -288.887916)
				)
			)
		)
	)
	(zone
		(layer "In1.Cu")
		(hatch none 0.5)
		(connect_pads
			(clearance 0)
		)
		(min_thickness 0.25)
		(keepout
			(tracks not_allowed)
			(vias allowed)
			(pads allowed)
			(copperpour not_allowed)
			(footprints allowed)
		)
		(placement
			(enabled no)
			(sheetname "")
		)
		(fill
			(thermal_gap 0.5)
			(thermal_bridge_width 0.5)
			(island_removal_mode 0)
		)
		(polygon
			(pts
				(arc
					(start 450.8373 -217.132154)
					(mid 450.83358 -217.141134)
					(end 450.8246 -217.144854)
				)
				(arc
					(start 449.3514 -217.144854)
					(mid 449.34242 -217.141134)
					(end 449.3387 -217.132154)
				)
				(arc
					(start 449.3387 -216.637616)
					(mid 449.34242 -216.628636)
					(end 449.3514 -216.624916)
				)
				(arc
					(start 450.8246 -216.624916)
					(mid 450.83358 -216.628636)
					(end 450.8373 -216.637616)
				)
			)
		)
	)
	(zone
		(layer "In1.Cu")
		(hatch none 0.5)
		(connect_pads
			(clearance 0)
		)
		(min_thickness 0.25)
		(keepout
			(tracks not_allowed)
			(vias allowed)
			(pads allowed)
			(copperpour not_allowed)
			(footprints allowed)
		)
		(placement
			(enabled no)
			(sheetname "")
		)
		(fill
			(thermal_gap 0.5)
			(thermal_bridge_width 0.5)
			(island_removal_mode 0)
		)
		(polygon
			(pts
				(arc
					(start 435.749446 -209.482182)
					(mid 435.745726 -209.491162)
					(end 435.736746 -209.494882)
				)
				(arc
					(start 434.263546 -209.494882)
					(mid 434.254566 -209.491162)
					(end 434.250846 -209.482182)
				)
				(arc
					(start 434.250846 -208.987644)
					(mid 434.254566 -208.978664)
					(end 434.263546 -208.974944)
				)
				(arc
					(start 435.736746 -208.974944)
					(mid 435.745726 -208.978664)
					(end 435.749446 -208.987644)
				)
			)
		)
	)
	(zone
		(layer "In1.Cu")
		(hatch none 0.5)
		(connect_pads
			(clearance 0)
		)
		(min_thickness 0.25)
		(keepout
			(tracks not_allowed)
			(vias allowed)
			(pads allowed)
			(copperpour not_allowed)
			(footprints allowed)
		)
		(placement
			(enabled no)
			(sheetname "")
		)
		(fill
			(thermal_gap 0.5)
			(thermal_bridge_width 0.5)
			(island_removal_mode 0)
		)
		(polygon
			(pts
				(arc
					(start 303.570132 -392.30427)
					(mid 303.265332 -392.30427)
					(end 303.570132 -392.30427)
				)
			)
		)
	)
	(zone
		(layer "In1.Cu")
		(hatch none 0.5)
		(connect_pads
			(clearance 0)
		)
		(min_thickness 0.25)
		(keepout
			(tracks not_allowed)
			(vias allowed)
			(pads allowed)
			(copperpour not_allowed)
			(footprints allowed)
		)
		(placement
			(enabled no)
			(sheetname "")
		)
		(fill
			(thermal_gap 0.5)
			(thermal_bridge_width 0.5)
			(island_removal_mode 0)
		)
		(polygon
			(pts
				(arc
					(start 432.30546 -251.132086)
					(mid 432.30174 -251.141066)
					(end 432.29276 -251.144786)
				)
				(arc
					(start 430.81956 -251.144786)
					(mid 430.81058 -251.141066)
					(end 430.80686 -251.132086)
				)
				(arc
					(start 430.80686 -250.637548)
					(mid 430.81058 -250.628568)
					(end 430.81956 -250.624848)
				)
				(arc
					(start 432.29276 -250.624848)
					(mid 432.30174 -250.628568)
					(end 432.30546 -250.637548)
				)
			)
		)
	)
	(zone
		(layer "In1.Cu")
		(hatch none 0.5)
		(connect_pads
			(clearance 0)
		)
		(min_thickness 0.25)
		(keepout
			(tracks not_allowed)
			(vias allowed)
			(pads allowed)
			(copperpour not_allowed)
			(footprints allowed)
		)
		(placement
			(enabled no)
			(sheetname "")
		)
		(fill
			(thermal_gap 0.5)
			(thermal_bridge_width 0.5)
			(island_removal_mode 0)
		)
		(polygon
			(pts
				(arc
					(start 374.161304 -397.156432)
					(mid 373.780304 -397.156432)
					(end 374.161304 -397.156432)
				)
			)
		)
	)
	(zone
		(layer "In1.Cu")
		(hatch none 0.5)
		(connect_pads
			(clearance 0)
		)
		(min_thickness 0.25)
		(keepout
			(tracks not_allowed)
			(vias allowed)
			(pads allowed)
			(copperpour not_allowed)
			(footprints allowed)
		)
		(placement
			(enabled no)
			(sheetname "")
		)
		(fill
			(thermal_gap 0.5)
			(thermal_bridge_width 0.5)
			(island_removal_mode 0)
		)
		(polygon
			(pts
				(arc
					(start 417.217352 -239.232186)
					(mid 417.213632 -239.241166)
					(end 417.204652 -239.244886)
				)
				(arc
					(start 415.731452 -239.244886)
					(mid 415.722472 -239.241166)
					(end 415.718752 -239.232186)
				)
				(arc
					(start 415.718752 -238.737648)
					(mid 415.722472 -238.728668)
					(end 415.731452 -238.724948)
				)
				(arc
					(start 417.204652 -238.724948)
					(mid 417.213632 -238.728668)
					(end 417.217352 -238.737648)
				)
			)
		)
	)
	(zone
		(layer "In1.Cu")
		(hatch none 0.5)
		(connect_pads
			(clearance 0)
		)
		(min_thickness 0.25)
		(keepout
			(tracks not_allowed)
			(vias allowed)
			(pads allowed)
			(copperpour not_allowed)
			(footprints allowed)
		)
		(placement
			(enabled no)
			(sheetname "")
		)
		(fill
			(thermal_gap 0.5)
			(thermal_bridge_width 0.5)
			(island_removal_mode 0)
		)
		(polygon
			(pts
				(arc
					(start 62.260988 -386.003292)
					(mid 61.879988 -386.003292)
					(end 62.260988 -386.003292)
				)
			)
		)
	)
	(zone
		(layer "In1.Cu")
		(hatch none 0.5)
		(connect_pads
			(clearance 0)
		)
		(min_thickness 0.25)
		(keepout
			(tracks not_allowed)
			(vias allowed)
			(pads allowed)
			(copperpour not_allowed)
			(footprints allowed)
		)
		(placement
			(enabled no)
			(sheetname "")
		)
		(fill
			(thermal_gap 0.5)
			(thermal_bridge_width 0.5)
			(island_removal_mode 0)
		)
		(polygon
			(pts
				(arc
					(start 56.077358 -279.182576)
					(mid 56.073638 -279.191556)
					(end 56.064658 -279.195276)
				)
				(arc
					(start 54.591458 -279.195276)
					(mid 54.582478 -279.191556)
					(end 54.578758 -279.182576)
				)
				(arc
					(start 54.578758 -278.688038)
					(mid 54.582478 -278.679058)
					(end 54.591458 -278.675338)
				)
				(arc
					(start 56.064658 -278.675338)
					(mid 56.073638 -278.679058)
					(end 56.077358 -278.688038)
				)
			)
		)
	)
	(zone
		(layer "In1.Cu")
		(hatch none 0.5)
		(connect_pads
			(clearance 0)
		)
		(min_thickness 0.25)
		(keepout
			(tracks not_allowed)
			(vias allowed)
			(pads allowed)
			(copperpour not_allowed)
			(footprints allowed)
		)
		(placement
			(enabled no)
			(sheetname "")
		)
		(fill
			(thermal_gap 0.5)
			(thermal_bridge_width 0.5)
			(island_removal_mode 0)
		)
		(polygon
			(pts
				(arc
					(start 288.929318 -268.98219)
					(mid 288.925598 -268.99117)
					(end 288.916618 -268.99489)
				)
				(arc
					(start 287.443418 -268.99489)
					(mid 287.434438 -268.99117)
					(end 287.430718 -268.98219)
				)
				(arc
					(start 287.430718 -268.487652)
					(mid 287.434438 -268.478672)
					(end 287.443418 -268.474952)
				)
				(arc
					(start 288.916618 -268.474952)
					(mid 288.925598 -268.478672)
					(end 288.929318 -268.487652)
				)
			)
		)
	)
	(zone
		(layer "In1.Cu")
		(hatch none 0.5)
		(connect_pads
			(clearance 0)
		)
		(min_thickness 0.25)
		(keepout
			(tracks not_allowed)
			(vias allowed)
			(pads allowed)
			(copperpour not_allowed)
			(footprints allowed)
		)
		(placement
			(enabled no)
			(sheetname "")
		)
		(fill
			(thermal_gap 0.5)
			(thermal_bridge_width 0.5)
			(island_removal_mode 0)
		)
		(polygon
			(pts
				(arc
					(start 285.485332 -242.63223)
					(mid 285.481612 -242.64121)
					(end 285.472632 -242.64493)
				)
				(arc
					(start 283.999432 -242.64493)
					(mid 283.990452 -242.64121)
					(end 283.986732 -242.63223)
				)
				(arc
					(start 283.986732 -242.137692)
					(mid 283.990452 -242.128712)
					(end 283.999432 -242.124992)
				)
				(arc
					(start 285.472632 -242.124992)
					(mid 285.481612 -242.128712)
					(end 285.485332 -242.137692)
				)
			)
		)
	)
	(zone
		(layer "In1.Cu")
		(hatch none 0.5)
		(connect_pads
			(clearance 0)
		)
		(min_thickness 0.25)
		(keepout
			(tracks not_allowed)
			(vias allowed)
			(pads allowed)
			(copperpour not_allowed)
			(footprints allowed)
		)
		(placement
			(enabled no)
			(sheetname "")
		)
		(fill
			(thermal_gap 0.5)
			(thermal_bridge_width 0.5)
			(island_removal_mode 0)
		)
		(polygon
			(pts
				(arc
					(start 187.809378 -286.832548)
					(mid 187.805658 -286.841528)
					(end 187.796678 -286.845248)
				)
				(arc
					(start 186.323478 -286.845248)
					(mid 186.314498 -286.841528)
					(end 186.310778 -286.832548)
				)
				(arc
					(start 186.310778 -286.33801)
					(mid 186.314498 -286.32903)
					(end 186.323478 -286.32531)
				)
				(arc
					(start 187.796678 -286.32531)
					(mid 187.805658 -286.32903)
					(end 187.809378 -286.33801)
				)
			)
		)
	)
	(zone
		(layer "In1.Cu")
		(hatch none 0.5)
		(connect_pads
			(clearance 0)
		)
		(min_thickness 0.25)
		(keepout
			(tracks not_allowed)
			(vias allowed)
			(pads allowed)
			(copperpour not_allowed)
			(footprints allowed)
		)
		(placement
			(enabled no)
			(sheetname "")
		)
		(fill
			(thermal_gap 0.5)
			(thermal_bridge_width 0.5)
			(island_removal_mode 0)
		)
		(polygon
			(pts
				(arc
					(start 308.117494 -306.382166)
					(mid 308.113774 -306.391146)
					(end 308.104794 -306.394866)
				)
				(arc
					(start 306.631594 -306.394866)
					(mid 306.622614 -306.391146)
					(end 306.618894 -306.382166)
				)
				(arc
					(start 306.618894 -305.887628)
					(mid 306.622614 -305.878648)
					(end 306.631594 -305.874928)
				)
				(arc
					(start 308.104794 -305.874928)
					(mid 308.113774 -305.878648)
					(end 308.117494 -305.887628)
				)
			)
		)
	)
	(zone
		(layer "In1.Cu")
		(hatch none 0.5)
		(connect_pads
			(clearance 0)
		)
		(min_thickness 0.25)
		(keepout
			(tracks not_allowed)
			(vias allowed)
			(pads allowed)
			(copperpour not_allowed)
			(footprints allowed)
		)
		(placement
			(enabled no)
			(sheetname "")
		)
		(fill
			(thermal_gap 0.5)
			(thermal_bridge_width 0.5)
			(island_removal_mode 0)
		)
		(polygon
			(pts
				(arc
					(start 165.177216 -296.182542)
					(mid 165.173496 -296.191522)
					(end 165.164516 -296.195242)
				)
				(arc
					(start 163.691316 -296.195242)
					(mid 163.682336 -296.191522)
					(end 163.678616 -296.182542)
				)
				(arc
					(start 163.678616 -295.688004)
					(mid 163.682336 -295.679024)
					(end 163.691316 -295.675304)
				)
				(arc
					(start 165.164516 -295.675304)
					(mid 165.173496 -295.679024)
					(end 165.177216 -295.688004)
				)
			)
		)
	)
	(zone
		(layer "In1.Cu")
		(hatch none 0.5)
		(connect_pads
			(clearance 0)
		)
		(min_thickness 0.25)
		(keepout
			(tracks not_allowed)
			(vias allowed)
			(pads allowed)
			(copperpour not_allowed)
			(footprints allowed)
		)
		(placement
			(enabled no)
			(sheetname "")
		)
		(fill
			(thermal_gap 0.5)
			(thermal_bridge_width 0.5)
			(island_removal_mode 0)
		)
		(polygon
			(pts
				(arc
					(start 13.61694 -16.036036)
					(mid 13.563058 -16.013718)
					(end 13.54074 -15.959836)
				)
				(arc
					(start 13.54074 -14.685518)
					(mid 13.563058 -14.631636)
					(end 13.61694 -14.609318)
				)
				(arc
					(start 14.125194 -14.609318)
					(mid 14.179076 -14.631636)
					(end 14.201394 -14.685518)
				)
				(arc
					(start 14.201394 -15.959836)
					(mid 14.179076 -16.013718)
					(end 14.125194 -16.036036)
				)
			)
		)
	)
	(zone
		(layer "In1.Cu")
		(hatch none 0.5)
		(connect_pads
			(clearance 0)
		)
		(min_thickness 0.25)
		(keepout
			(tracks not_allowed)
			(vias allowed)
			(pads allowed)
			(copperpour not_allowed)
			(footprints allowed)
		)
		(placement
			(enabled no)
			(sheetname "")
		)
		(fill
			(thermal_gap 0.5)
			(thermal_bridge_width 0.5)
			(island_removal_mode 0)
		)
		(polygon
			(pts
				(arc
					(start 180.265324 -288.53257)
					(mid 180.261604 -288.54155)
					(end 180.252624 -288.54527)
				)
				(arc
					(start 178.779424 -288.54527)
					(mid 178.770444 -288.54155)
					(end 178.766724 -288.53257)
				)
				(arc
					(start 178.766724 -288.038032)
					(mid 178.770444 -288.029052)
					(end 178.779424 -288.025332)
				)
				(arc
					(start 180.252624 -288.025332)
					(mid 180.261604 -288.029052)
					(end 180.265324 -288.038032)
				)
			)
		)
	)
	(zone
		(layer "In1.Cu")
		(hatch none 0.5)
		(connect_pads
			(clearance 0)
		)
		(min_thickness 0.25)
		(keepout
			(tracks not_allowed)
			(vias allowed)
			(pads allowed)
			(copperpour not_allowed)
			(footprints allowed)
		)
		(placement
			(enabled no)
			(sheetname "")
		)
		(fill
			(thermal_gap 0.5)
			(thermal_bridge_width 0.5)
			(island_removal_mode 0)
		)
		(polygon
			(pts
				(arc
					(start 33.445196 -246.882412)
					(mid 33.441476 -246.891392)
					(end 33.432496 -246.895112)
				)
				(arc
					(start 31.959296 -246.895112)
					(mid 31.950316 -246.891392)
					(end 31.946596 -246.882412)
				)
				(arc
					(start 31.946596 -246.387874)
					(mid 31.950316 -246.378894)
					(end 31.959296 -246.375174)
				)
				(arc
					(start 33.432496 -246.375174)
					(mid 33.441476 -246.378894)
					(end 33.445196 -246.387874)
				)
			)
		)
	)
	(zone
		(layer "In1.Cu")
		(hatch none 0.5)
		(connect_pads
			(clearance 0)
		)
		(min_thickness 0.25)
		(keepout
			(tracks not_allowed)
			(vias allowed)
			(pads allowed)
			(copperpour not_allowed)
			(footprints allowed)
		)
		(placement
			(enabled no)
			(sheetname "")
		)
		(fill
			(thermal_gap 0.5)
			(thermal_bridge_width 0.5)
			(island_removal_mode 0)
		)
		(polygon
			(pts
				(arc
					(start 428.205392 -212.032088)
					(mid 428.201672 -212.041068)
					(end 428.192692 -212.044788)
				)
				(arc
					(start 426.719492 -212.044788)
					(mid 426.710512 -212.041068)
					(end 426.706792 -212.032088)
				)
				(arc
					(start 426.706792 -211.53755)
					(mid 426.710512 -211.52857)
					(end 426.719492 -211.52485)
				)
				(arc
					(start 428.192692 -211.52485)
					(mid 428.201672 -211.52857)
					(end 428.205392 -211.53755)
				)
			)
		)
	)
	(zone
		(layer "In1.Cu")
		(hatch none 0.5)
		(connect_pads
			(clearance 0)
		)
		(min_thickness 0.25)
		(keepout
			(tracks not_allowed)
			(vias allowed)
			(pads allowed)
			(copperpour not_allowed)
			(footprints allowed)
		)
		(placement
			(enabled no)
			(sheetname "")
		)
		(fill
			(thermal_gap 0.5)
			(thermal_bridge_width 0.5)
			(island_removal_mode 0)
		)
		(polygon
			(pts
				(arc
					(start 277.941532 -216.28227)
					(mid 277.937812 -216.29125)
					(end 277.928832 -216.29497)
				)
				(arc
					(start 276.455632 -216.29497)
					(mid 276.446652 -216.29125)
					(end 276.442932 -216.28227)
				)
				(arc
					(start 276.442932 -215.787732)
					(mid 276.446652 -215.778752)
					(end 276.455632 -215.775032)
				)
				(arc
					(start 277.928832 -215.775032)
					(mid 277.937812 -215.778752)
					(end 277.941532 -215.787732)
				)
			)
		)
	)
	(zone
		(layer "In1.Cu")
		(hatch none 0.5)
		(connect_pads
			(clearance 0)
		)
		(min_thickness 0.25)
		(keepout
			(tracks not_allowed)
			(vias allowed)
			(pads allowed)
			(copperpour not_allowed)
			(footprints allowed)
		)
		(placement
			(enabled no)
			(sheetname "")
		)
		(fill
			(thermal_gap 0.5)
			(thermal_bridge_width 0.5)
			(island_removal_mode 0)
		)
		(polygon
			(pts
				(arc
					(start 40.98925 -223.082358)
					(mid 40.98553 -223.091338)
					(end 40.97655 -223.095058)
				)
				(arc
					(start 39.50335 -223.095058)
					(mid 39.49437 -223.091338)
					(end 39.49065 -223.082358)
				)
				(arc
					(start 39.49065 -222.58782)
					(mid 39.49437 -222.57884)
					(end 39.50335 -222.57512)
				)
				(arc
					(start 40.97655 -222.57512)
					(mid 40.98553 -222.57884)
					(end 40.98925 -222.58782)
				)
			)
		)
	)
	(zone
		(layer "In1.Cu")
		(hatch none 0.5)
		(connect_pads
			(clearance 0)
		)
		(min_thickness 0.25)
		(keepout
			(tracks not_allowed)
			(vias allowed)
			(pads allowed)
			(copperpour not_allowed)
			(footprints allowed)
		)
		(placement
			(enabled no)
			(sheetname "")
		)
		(fill
			(thermal_gap 0.5)
			(thermal_bridge_width 0.5)
			(island_removal_mode 0)
		)
		(polygon
			(pts
				(arc
					(start 288.929318 -209.482182)
					(mid 288.925598 -209.491162)
					(end 288.916618 -209.494882)
				)
				(arc
					(start 287.443418 -209.494882)
					(mid 287.434438 -209.491162)
					(end 287.430718 -209.482182)
				)
				(arc
					(start 287.430718 -208.987644)
					(mid 287.434438 -208.978664)
					(end 287.443418 -208.974944)
				)
				(arc
					(start 288.916618 -208.974944)
					(mid 288.925598 -208.978664)
					(end 288.929318 -208.987644)
				)
			)
		)
	)
	(zone
		(layer "In1.Cu")
		(hatch none 0.5)
		(connect_pads
			(clearance 0)
		)
		(min_thickness 0.25)
		(keepout
			(tracks not_allowed)
			(vias allowed)
			(pads allowed)
			(copperpour not_allowed)
			(footprints allowed)
		)
		(placement
			(enabled no)
			(sheetname "")
		)
		(fill
			(thermal_gap 0.5)
			(thermal_bridge_width 0.5)
			(island_removal_mode 0)
		)
		(polygon
			(pts
				(arc
					(start 447.393568 -229.882192)
					(mid 447.389848 -229.891172)
					(end 447.380868 -229.894892)
				)
				(arc
					(start 445.907668 -229.894892)
					(mid 445.898688 -229.891172)
					(end 445.894968 -229.882192)
				)
				(arc
					(start 445.894968 -229.387654)
					(mid 445.898688 -229.378674)
					(end 445.907668 -229.374954)
				)
				(arc
					(start 447.380868 -229.374954)
					(mid 447.389848 -229.378674)
					(end 447.393568 -229.387654)
				)
			)
		)
	)
	(zone
		(layer "In1.Cu")
		(hatch none 0.5)
		(connect_pads
			(clearance 0)
		)
		(min_thickness 0.25)
		(keepout
			(tracks not_allowed)
			(vias allowed)
			(pads allowed)
			(copperpour not_allowed)
			(footprints allowed)
		)
		(placement
			(enabled no)
			(sheetname "")
		)
		(fill
			(thermal_gap 0.5)
			(thermal_bridge_width 0.5)
			(island_removal_mode 0)
		)
		(polygon
			(pts
				(arc
					(start 432.30546 -252.832108)
					(mid 432.30174 -252.841088)
					(end 432.29276 -252.844808)
				)
				(arc
					(start 430.81956 -252.844808)
					(mid 430.81058 -252.841088)
					(end 430.80686 -252.832108)
				)
				(arc
					(start 430.80686 -252.33757)
					(mid 430.81058 -252.32859)
					(end 430.81956 -252.32487)
				)
				(arc
					(start 432.29276 -252.32487)
					(mid 432.30174 -252.32859)
					(end 432.30546 -252.33757)
				)
			)
		)
	)
	(zone
		(layer "In1.Cu")
		(hatch none 0.5)
		(connect_pads
			(clearance 0)
		)
		(min_thickness 0.25)
		(keepout
			(tracks not_allowed)
			(vias allowed)
			(pads allowed)
			(copperpour not_allowed)
			(footprints allowed)
		)
		(placement
			(enabled no)
			(sheetname "")
		)
		(fill
			(thermal_gap 0.5)
			(thermal_bridge_width 0.5)
			(island_removal_mode 0)
		)
		(polygon
			(pts
				(arc
					(start 199.4535 -295.332404)
					(mid 199.44978 -295.341384)
					(end 199.4408 -295.345104)
				)
				(arc
					(start 197.9676 -295.345104)
					(mid 197.95862 -295.341384)
					(end 197.9549 -295.332404)
				)
				(arc
					(start 197.9549 -294.837866)
					(mid 197.95862 -294.828886)
					(end 197.9676 -294.825166)
				)
				(arc
					(start 199.4408 -294.825166)
					(mid 199.44978 -294.828886)
					(end 199.4535 -294.837866)
				)
			)
		)
	)
	(zone
		(layer "In1.Cu")
		(hatch none 0.5)
		(connect_pads
			(clearance 0)
		)
		(min_thickness 0.25)
		(keepout
			(tracks not_allowed)
			(vias allowed)
			(pads allowed)
			(copperpour not_allowed)
			(footprints allowed)
		)
		(placement
			(enabled no)
			(sheetname "")
		)
		(fill
			(thermal_gap 0.5)
			(thermal_bridge_width 0.5)
			(island_removal_mode 0)
		)
		(polygon
			(pts
				(arc
					(start 33.445196 -204.38237)
					(mid 33.441476 -204.39135)
					(end 33.432496 -204.39507)
				)
				(arc
					(start 31.959296 -204.39507)
					(mid 31.950316 -204.39135)
					(end 31.946596 -204.38237)
				)
				(arc
					(start 31.946596 -203.887832)
					(mid 31.950316 -203.878852)
					(end 31.959296 -203.875132)
				)
				(arc
					(start 33.432496 -203.875132)
					(mid 33.441476 -203.878852)
					(end 33.445196 -203.887832)
				)
			)
		)
	)
	(zone
		(layer "In1.Cu")
		(hatch none 0.5)
		(connect_pads
			(clearance 0)
		)
		(min_thickness 0.25)
		(keepout
			(tracks not_allowed)
			(vias allowed)
			(pads allowed)
			(copperpour not_allowed)
			(footprints allowed)
		)
		(placement
			(enabled no)
			(sheetname "")
		)
		(fill
			(thermal_gap 0.5)
			(thermal_bridge_width 0.5)
			(island_removal_mode 0)
		)
		(polygon
			(pts
				(arc
					(start 428.205392 -279.182322)
					(mid 428.201672 -279.191302)
					(end 428.192692 -279.195022)
				)
				(arc
					(start 426.719492 -279.195022)
					(mid 426.710512 -279.191302)
					(end 426.706792 -279.182322)
				)
				(arc
					(start 426.706792 -278.687784)
					(mid 426.710512 -278.678804)
					(end 426.719492 -278.675084)
				)
				(arc
					(start 428.192692 -278.675084)
					(mid 428.201672 -278.678804)
					(end 428.205392 -278.687784)
				)
			)
		)
	)
	(zone
		(layer "In1.Cu")
		(hatch none 0.5)
		(connect_pads
			(clearance 0)
		)
		(min_thickness 0.25)
		(keepout
			(tracks not_allowed)
			(vias allowed)
			(pads allowed)
			(copperpour not_allowed)
			(footprints allowed)
		)
		(placement
			(enabled no)
			(sheetname "")
		)
		(fill
			(thermal_gap 0.5)
			(thermal_bridge_width 0.5)
			(island_removal_mode 0)
		)
		(polygon
			(pts
				(arc
					(start 454.937368 -292.782244)
					(mid 454.933648 -292.791224)
					(end 454.924668 -292.794944)
				)
				(arc
					(start 453.451468 -292.794944)
					(mid 453.442488 -292.791224)
					(end 453.438768 -292.782244)
				)
				(arc
					(start 453.438768 -292.287706)
					(mid 453.442488 -292.278726)
					(end 453.451468 -292.275006)
				)
				(arc
					(start 454.924668 -292.275006)
					(mid 454.933648 -292.278726)
					(end 454.937368 -292.287706)
				)
			)
		)
	)
	(zone
		(layer "In1.Cu")
		(hatch none 0.5)
		(connect_pads
			(clearance 0)
		)
		(min_thickness 0.25)
		(keepout
			(tracks not_allowed)
			(vias allowed)
			(pads allowed)
			(copperpour not_allowed)
			(footprints allowed)
		)
		(placement
			(enabled no)
			(sheetname "")
		)
		(fill
			(thermal_gap 0.5)
			(thermal_bridge_width 0.5)
			(island_removal_mode 0)
		)
		(polygon
			(pts
				(arc
					(start 56.077358 -297.882564)
					(mid 56.073638 -297.891544)
					(end 56.064658 -297.895264)
				)
				(arc
					(start 54.591458 -297.895264)
					(mid 54.582478 -297.891544)
					(end 54.578758 -297.882564)
				)
				(arc
					(start 54.578758 -297.388026)
					(mid 54.582478 -297.379046)
					(end 54.591458 -297.375326)
				)
				(arc
					(start 56.064658 -297.375326)
					(mid 56.073638 -297.379046)
					(end 56.077358 -297.388026)
				)
			)
		)
	)
	(zone
		(layer "In1.Cu")
		(hatch none 0.5)
		(connect_pads
			(clearance 0)
		)
		(min_thickness 0.25)
		(keepout
			(tracks not_allowed)
			(vias allowed)
			(pads allowed)
			(copperpour not_allowed)
			(footprints allowed)
		)
		(placement
			(enabled no)
			(sheetname "")
		)
		(fill
			(thermal_gap 0.5)
			(thermal_bridge_width 0.5)
			(island_removal_mode 0)
		)
		(polygon
			(pts
				(arc
					(start 199.4535 -311.482486)
					(mid 199.44978 -311.491466)
					(end 199.4408 -311.495186)
				)
				(arc
					(start 197.9676 -311.495186)
					(mid 197.95862 -311.491466)
					(end 197.9549 -311.482486)
				)
				(arc
					(start 197.9549 -310.987948)
					(mid 197.95862 -310.978968)
					(end 197.9676 -310.975248)
				)
				(arc
					(start 199.4408 -310.975248)
					(mid 199.44978 -310.978968)
					(end 199.4535 -310.987948)
				)
			)
		)
	)
	(zone
		(layer "In1.Cu")
		(hatch none 0.5)
		(connect_pads
			(clearance 0)
		)
		(min_thickness 0.25)
		(keepout
			(tracks not_allowed)
			(vias allowed)
			(pads allowed)
			(copperpour not_allowed)
			(footprints allowed)
		)
		(placement
			(enabled no)
			(sheetname "")
		)
		(fill
			(thermal_gap 0.5)
			(thermal_bridge_width 0.5)
			(island_removal_mode 0)
		)
		(polygon
			(pts
				(arc
					(start 424.761406 -251.132086)
					(mid 424.757686 -251.141066)
					(end 424.748706 -251.144786)
				)
				(arc
					(start 423.275506 -251.144786)
					(mid 423.266526 -251.141066)
					(end 423.262806 -251.132086)
				)
				(arc
					(start 423.262806 -250.637548)
					(mid 423.266526 -250.628568)
					(end 423.275506 -250.624848)
				)
				(arc
					(start 424.748706 -250.624848)
					(mid 424.757686 -250.628568)
					(end 424.761406 -250.637548)
				)
			)
		)
	)
	(zone
		(layer "In1.Cu")
		(hatch none 0.5)
		(connect_pads
			(clearance 0)
		)
		(min_thickness 0.25)
		(keepout
			(tracks not_allowed)
			(vias allowed)
			(pads allowed)
			(copperpour not_allowed)
			(footprints allowed)
		)
		(placement
			(enabled no)
			(sheetname "")
		)
		(fill
			(thermal_gap 0.5)
			(thermal_bridge_width 0.5)
			(island_removal_mode 0)
		)
		(polygon
			(pts
				(arc
					(start 52.991004 -391.319258)
					(mid 53.118004 -391.446258)
					(end 53.245004 -391.319258)
				)
				(arc
					(start 53.245004 -391.243058)
					(mid 53.118004 -391.116058)
					(end 52.991004 -391.243058)
				)
			)
		)
	)
	(zone
		(layer "In1.Cu")
		(hatch none 0.5)
		(connect_pads
			(clearance 0)
		)
		(min_thickness 0.25)
		(keepout
			(tracks not_allowed)
			(vias allowed)
			(pads allowed)
			(copperpour not_allowed)
			(footprints allowed)
		)
		(placement
			(enabled no)
			(sheetname "")
		)
		(fill
			(thermal_gap 0.5)
			(thermal_bridge_width 0.5)
			(island_removal_mode 0)
		)
		(polygon
			(pts
				(arc
					(start 443.2935 -301.2821)
					(mid 443.28978 -301.29108)
					(end 443.2808 -301.2948)
				)
				(arc
					(start 441.8076 -301.2948)
					(mid 441.79862 -301.29108)
					(end 441.7949 -301.2821)
				)
				(arc
					(start 441.7949 -300.787562)
					(mid 441.79862 -300.778582)
					(end 441.8076 -300.774862)
				)
				(arc
					(start 443.2808 -300.774862)
					(mid 443.28978 -300.778582)
					(end 443.2935 -300.787562)
				)
			)
		)
	)
	(zone
		(layer "In1.Cu")
		(hatch none 0.5)
		(connect_pads
			(clearance 0)
		)
		(min_thickness 0.25)
		(keepout
			(tracks not_allowed)
			(vias allowed)
			(pads allowed)
			(copperpour not_allowed)
			(footprints allowed)
		)
		(placement
			(enabled no)
			(sheetname "")
		)
		(fill
			(thermal_gap 0.5)
			(thermal_bridge_width 0.5)
			(island_removal_mode 0)
		)
		(polygon
			(pts
				(arc
					(start 131.4704 -383.92227)
					(mid 131.1656 -383.92227)
					(end 131.4704 -383.92227)
				)
			)
		)
	)
	(zone
		(layer "In1.Cu")
		(hatch none 0.5)
		(connect_pads
			(clearance 0)
		)
		(min_thickness 0.25)
		(keepout
			(tracks not_allowed)
			(vias allowed)
			(pads allowed)
			(copperpour not_allowed)
			(footprints allowed)
		)
		(placement
			(enabled no)
			(sheetname "")
		)
		(fill
			(thermal_gap 0.5)
			(thermal_bridge_width 0.5)
			(island_removal_mode 0)
		)
		(polygon
			(pts
				(arc
					(start 172.72127 -198.43242)
					(mid 172.71755 -198.4414)
					(end 172.70857 -198.44512)
				)
				(arc
					(start 171.23537 -198.44512)
					(mid 171.22639 -198.4414)
					(end 171.22267 -198.43242)
				)
				(arc
					(start 171.22267 -197.937882)
					(mid 171.22639 -197.928902)
					(end 171.23537 -197.925182)
				)
				(arc
					(start 172.70857 -197.925182)
					(mid 172.71755 -197.928902)
					(end 172.72127 -197.937882)
				)
			)
		)
	)
	(zone
		(layer "In1.Cu")
		(hatch none 0.5)
		(connect_pads
			(clearance 0)
		)
		(min_thickness 0.25)
		(keepout
			(tracks not_allowed)
			(vias allowed)
			(pads allowed)
			(copperpour not_allowed)
			(footprints allowed)
		)
		(placement
			(enabled no)
			(sheetname "")
		)
		(fill
			(thermal_gap 0.5)
			(thermal_bridge_width 0.5)
			(island_removal_mode 0)
		)
		(polygon
			(pts
				(arc
					(start 432.30546 -317.432182)
					(mid 432.30174 -317.441162)
					(end 432.29276 -317.444882)
				)
				(arc
					(start 430.81956 -317.444882)
					(mid 430.81058 -317.441162)
					(end 430.80686 -317.432182)
				)
				(arc
					(start 430.80686 -316.937644)
					(mid 430.81058 -316.928664)
					(end 430.81956 -316.924944)
				)
				(arc
					(start 432.29276 -316.924944)
					(mid 432.30174 -316.928664)
					(end 432.30546 -316.937644)
				)
			)
		)
	)
	(zone
		(layer "In1.Cu")
		(hatch none 0.5)
		(connect_pads
			(clearance 0)
		)
		(min_thickness 0.25)
		(keepout
			(tracks not_allowed)
			(vias allowed)
			(pads allowed)
			(copperpour not_allowed)
			(footprints allowed)
		)
		(placement
			(enabled no)
			(sheetname "")
		)
		(fill
			(thermal_gap 0.5)
			(thermal_bridge_width 0.5)
			(island_removal_mode 0)
		)
		(polygon
			(pts
				(arc
					(start 56.077358 -217.132408)
					(mid 56.073638 -217.141388)
					(end 56.064658 -217.145108)
				)
				(arc
					(start 54.591458 -217.145108)
					(mid 54.582478 -217.141388)
					(end 54.578758 -217.132408)
				)
				(arc
					(start 54.578758 -216.63787)
					(mid 54.582478 -216.62889)
					(end 54.591458 -216.62517)
				)
				(arc
					(start 56.064658 -216.62517)
					(mid 56.073638 -216.62889)
					(end 56.077358 -216.63787)
				)
			)
		)
	)
	(zone
		(layer "In1.Cu")
		(hatch none 0.5)
		(connect_pads
			(clearance 0)
		)
		(min_thickness 0.25)
		(keepout
			(tracks not_allowed)
			(vias allowed)
			(pads allowed)
			(copperpour not_allowed)
			(footprints allowed)
		)
		(placement
			(enabled no)
			(sheetname "")
		)
		(fill
			(thermal_gap 0.5)
			(thermal_bridge_width 0.5)
			(island_removal_mode 0)
		)
		(polygon
			(pts
				(arc
					(start 273.841464 -206.082138)
					(mid 273.837744 -206.091118)
					(end 273.828764 -206.094838)
				)
				(arc
					(start 272.355564 -206.094838)
					(mid 272.346584 -206.091118)
					(end 272.342864 -206.082138)
				)
				(arc
					(start 272.342864 -205.5876)
					(mid 272.346584 -205.57862)
					(end 272.355564 -205.5749)
				)
				(arc
					(start 273.828764 -205.5749)
					(mid 273.837744 -205.57862)
					(end 273.841464 -205.5876)
				)
			)
		)
	)
	(zone
		(layer "In1.Cu")
		(hatch none 0.5)
		(connect_pads
			(clearance 0)
		)
		(min_thickness 0.25)
		(keepout
			(tracks not_allowed)
			(vias allowed)
			(pads allowed)
			(copperpour not_allowed)
			(footprints allowed)
		)
		(placement
			(enabled no)
			(sheetname "")
		)
		(fill
			(thermal_gap 0.5)
			(thermal_bridge_width 0.5)
			(island_removal_mode 0)
		)
		(polygon
			(pts
				(arc
					(start 206.5782 -234.73537)
					(mid 205.9178 -234.73537)
					(end 206.5782 -234.73537)
				)
			)
		)
	)
	(zone
		(layer "In1.Cu")
		(hatch none 0.5)
		(connect_pads
			(clearance 0)
		)
		(min_thickness 0.25)
		(keepout
			(tracks not_allowed)
			(vias allowed)
			(pads allowed)
			(copperpour not_allowed)
			(footprints allowed)
		)
		(placement
			(enabled no)
			(sheetname "")
		)
		(fill
			(thermal_gap 0.5)
			(thermal_bridge_width 0.5)
			(island_removal_mode 0)
		)
		(polygon
			(pts
				(arc
					(start 288.929318 -299.582332)
					(mid 288.925598 -299.591312)
					(end 288.916618 -299.595032)
				)
				(arc
					(start 287.443418 -299.595032)
					(mid 287.434438 -299.591312)
					(end 287.430718 -299.582332)
				)
				(arc
					(start 287.430718 -299.087794)
					(mid 287.434438 -299.078814)
					(end 287.443418 -299.075094)
				)
				(arc
					(start 288.916618 -299.075094)
					(mid 288.925598 -299.078814)
					(end 288.929318 -299.087794)
				)
			)
		)
	)
	(zone
		(layer "In1.Cu")
		(hatch none 0.5)
		(connect_pads
			(clearance 0)
		)
		(min_thickness 0.25)
		(keepout
			(tracks not_allowed)
			(vias allowed)
			(pads allowed)
			(copperpour not_allowed)
			(footprints allowed)
		)
		(placement
			(enabled no)
			(sheetname "")
		)
		(fill
			(thermal_gap 0.5)
			(thermal_bridge_width 0.5)
			(island_removal_mode 0)
		)
		(polygon
			(pts
				(arc
					(start 413.117284 -250.282202)
					(mid 413.113564 -250.291182)
					(end 413.104584 -250.294902)
				)
				(arc
					(start 411.631384 -250.294902)
					(mid 411.622404 -250.291182)
					(end 411.618684 -250.282202)
				)
				(arc
					(start 411.618684 -249.787664)
					(mid 411.622404 -249.778684)
					(end 411.631384 -249.774964)
				)
				(arc
					(start 413.104584 -249.774964)
					(mid 413.113564 -249.778684)
					(end 413.117284 -249.787664)
				)
			)
		)
	)
	(zone
		(layer "In1.Cu")
		(hatch none 0.5)
		(connect_pads
			(clearance 0)
		)
		(min_thickness 0.25)
		(keepout
			(tracks not_allowed)
			(vias allowed)
			(pads allowed)
			(copperpour not_allowed)
			(footprints allowed)
		)
		(placement
			(enabled no)
			(sheetname "")
		)
		(fill
			(thermal_gap 0.5)
			(thermal_bridge_width 0.5)
			(island_removal_mode 0)
		)
		(polygon
			(pts
				(arc
					(start 180.265324 -267.282422)
					(mid 180.261604 -267.291402)
					(end 180.252624 -267.295122)
				)
				(arc
					(start 178.779424 -267.295122)
					(mid 178.770444 -267.291402)
					(end 178.766724 -267.282422)
				)
				(arc
					(start 178.766724 -266.787884)
					(mid 178.770444 -266.778904)
					(end 178.779424 -266.775184)
				)
				(arc
					(start 180.252624 -266.775184)
					(mid 180.261604 -266.778904)
					(end 180.265324 -266.787884)
				)
			)
		)
	)
	(zone
		(layer "In1.Cu")
		(hatch none 0.5)
		(connect_pads
			(clearance 0)
		)
		(min_thickness 0.25)
		(keepout
			(tracks not_allowed)
			(vias allowed)
			(pads allowed)
			(copperpour not_allowed)
			(footprints allowed)
		)
		(placement
			(enabled no)
			(sheetname "")
		)
		(fill
			(thermal_gap 0.5)
			(thermal_bridge_width 0.5)
			(island_removal_mode 0)
		)
		(polygon
			(pts
				(arc
					(start 443.2935 -235.832142)
					(mid 443.28978 -235.841122)
					(end 443.2808 -235.844842)
				)
				(arc
					(start 441.8076 -235.844842)
					(mid 441.79862 -235.841122)
					(end 441.7949 -235.832142)
				)
				(arc
					(start 441.7949 -235.337604)
					(mid 441.79862 -235.328624)
					(end 441.8076 -235.324904)
				)
				(arc
					(start 443.2808 -235.324904)
					(mid 443.28978 -235.328624)
					(end 443.2935 -235.337604)
				)
			)
		)
	)
	(zone
		(layer "In1.Cu")
		(hatch none 0.5)
		(connect_pads
			(clearance 0)
		)
		(min_thickness 0.25)
		(keepout
			(tracks not_allowed)
			(vias allowed)
			(pads allowed)
			(copperpour not_allowed)
			(footprints allowed)
		)
		(placement
			(enabled no)
			(sheetname "")
		)
		(fill
			(thermal_gap 0.5)
			(thermal_bridge_width 0.5)
			(island_removal_mode 0)
		)
		(polygon
			(pts
				(arc
					(start 342.097868 -399.143474)
					(mid 341.793068 -399.143474)
					(end 342.097868 -399.143474)
				)
			)
		)
	)
	(zone
		(layer "In1.Cu")
		(hatch none 0.5)
		(connect_pads
			(clearance 0)
		)
		(min_thickness 0.25)
		(keepout
			(tracks not_allowed)
			(vias allowed)
			(pads allowed)
			(copperpour not_allowed)
			(footprints allowed)
		)
		(placement
			(enabled no)
			(sheetname "")
		)
		(fill
			(thermal_gap 0.5)
			(thermal_bridge_width 0.5)
			(island_removal_mode 0)
		)
		(polygon
			(pts
				(arc
					(start 443.2935 -293.632128)
					(mid 443.28978 -293.641108)
					(end 443.2808 -293.644828)
				)
				(arc
					(start 441.8076 -293.644828)
					(mid 441.79862 -293.641108)
					(end 441.7949 -293.632128)
				)
				(arc
					(start 441.7949 -293.13759)
					(mid 441.79862 -293.12861)
					(end 441.8076 -293.12489)
				)
				(arc
					(start 443.2808 -293.12489)
					(mid 443.28978 -293.12861)
					(end 443.2935 -293.13759)
				)
			)
		)
	)
	(zone
		(layer "In1.Cu")
		(hatch none 0.5)
		(connect_pads
			(clearance 0)
		)
		(min_thickness 0.25)
		(keepout
			(tracks not_allowed)
			(vias allowed)
			(pads allowed)
			(copperpour not_allowed)
			(footprints allowed)
		)
		(placement
			(enabled no)
			(sheetname "")
		)
		(fill
			(thermal_gap 0.5)
			(thermal_bridge_width 0.5)
			(island_removal_mode 0)
		)
		(polygon
			(pts
				(arc
					(start 199.4535 -225.632518)
					(mid 199.44978 -225.641498)
					(end 199.4408 -225.645218)
				)
				(arc
					(start 197.9676 -225.645218)
					(mid 197.95862 -225.641498)
					(end 197.9549 -225.632518)
				)
				(arc
					(start 197.9549 -225.13798)
					(mid 197.95862 -225.129)
					(end 197.9676 -225.12528)
				)
				(arc
					(start 199.4408 -225.12528)
					(mid 199.44978 -225.129)
					(end 199.4535 -225.13798)
				)
			)
		)
	)
	(zone
		(layer "In1.Cu")
		(hatch none 0.5)
		(connect_pads
			(clearance 0)
		)
		(min_thickness 0.25)
		(keepout
			(tracks not_allowed)
			(vias allowed)
			(pads allowed)
			(copperpour not_allowed)
			(footprints allowed)
		)
		(placement
			(enabled no)
			(sheetname "")
		)
		(fill
			(thermal_gap 0.5)
			(thermal_bridge_width 0.5)
			(island_removal_mode 0)
		)
		(polygon
			(pts
				(arc
					(start 447.393568 -285.132272)
					(mid 447.389848 -285.141252)
					(end 447.380868 -285.144972)
				)
				(arc
					(start 445.907668 -285.144972)
					(mid 445.898688 -285.141252)
					(end 445.894968 -285.132272)
				)
				(arc
					(start 445.894968 -284.637734)
					(mid 445.898688 -284.628754)
					(end 445.907668 -284.625034)
				)
				(arc
					(start 447.380868 -284.625034)
					(mid 447.389848 -284.628754)
					(end 447.393568 -284.637734)
				)
			)
		)
	)
	(zone
		(layer "In1.Cu")
		(hatch none 0.5)
		(connect_pads
			(clearance 0)
		)
		(min_thickness 0.25)
		(keepout
			(tracks not_allowed)
			(vias allowed)
			(pads allowed)
			(copperpour not_allowed)
			(footprints allowed)
		)
		(placement
			(enabled no)
			(sheetname "")
		)
		(fill
			(thermal_gap 0.5)
			(thermal_bridge_width 0.5)
			(island_removal_mode 0)
		)
		(polygon
			(pts
				(arc
					(start 281.385264 -273.232118)
					(mid 281.381544 -273.241098)
					(end 281.372564 -273.244818)
				)
				(arc
					(start 279.899364 -273.244818)
					(mid 279.890384 -273.241098)
					(end 279.886664 -273.232118)
				)
				(arc
					(start 279.886664 -272.73758)
					(mid 279.890384 -272.7286)
					(end 279.899364 -272.72488)
				)
				(arc
					(start 281.372564 -272.72488)
					(mid 281.381544 -272.7286)
					(end 281.385264 -272.73758)
				)
			)
		)
	)
	(zone
		(layer "In1.Cu")
		(hatch none 0.5)
		(connect_pads
			(clearance 0)
		)
		(min_thickness 0.25)
		(keepout
			(tracks not_allowed)
			(vias allowed)
			(pads allowed)
			(copperpour not_allowed)
			(footprints allowed)
		)
		(placement
			(enabled no)
			(sheetname "")
		)
		(fill
			(thermal_gap 0.5)
			(thermal_bridge_width 0.5)
			(island_removal_mode 0)
		)
		(polygon
			(pts
				(arc
					(start 439.849514 -272.382234)
					(mid 439.845794 -272.391214)
					(end 439.836814 -272.394934)
				)
				(arc
					(start 438.363614 -272.394934)
					(mid 438.354634 -272.391214)
					(end 438.350914 -272.382234)
				)
				(arc
					(start 438.350914 -271.887696)
					(mid 438.354634 -271.878716)
					(end 438.363614 -271.874996)
				)
				(arc
					(start 439.836814 -271.874996)
					(mid 439.845794 -271.878716)
					(end 439.849514 -271.887696)
				)
			)
		)
	)
	(zone
		(layer "In1.Cu")
		(hatch none 0.5)
		(connect_pads
			(clearance 0)
		)
		(min_thickness 0.25)
		(keepout
			(tracks not_allowed)
			(vias allowed)
			(pads allowed)
			(copperpour not_allowed)
			(footprints allowed)
		)
		(placement
			(enabled no)
			(sheetname "")
		)
		(fill
			(thermal_gap 0.5)
			(thermal_bridge_width 0.5)
			(island_removal_mode 0)
		)
		(polygon
			(pts
				(arc
					(start 273.841464 -241.782092)
					(mid 273.837744 -241.791072)
					(end 273.828764 -241.794792)
				)
				(arc
					(start 272.355564 -241.794792)
					(mid 272.346584 -241.791072)
					(end 272.342864 -241.782092)
				)
				(arc
					(start 272.342864 -241.287554)
					(mid 272.346584 -241.278574)
					(end 272.355564 -241.274854)
				)
				(arc
					(start 273.828764 -241.274854)
					(mid 273.837744 -241.278574)
					(end 273.841464 -241.287554)
				)
			)
		)
	)
	(zone
		(layer "In1.Cu")
		(hatch none 0.5)
		(connect_pads
			(clearance 0)
		)
		(min_thickness 0.25)
		(keepout
			(tracks not_allowed)
			(vias allowed)
			(pads allowed)
			(copperpour not_allowed)
			(footprints allowed)
		)
		(placement
			(enabled no)
			(sheetname "")
		)
		(fill
			(thermal_gap 0.5)
			(thermal_bridge_width 0.5)
			(island_removal_mode 0)
		)
		(polygon
			(pts
				(arc
					(start 33.445196 -234.132374)
					(mid 33.441476 -234.141354)
					(end 33.432496 -234.145074)
				)
				(arc
					(start 31.959296 -234.145074)
					(mid 31.950316 -234.141354)
					(end 31.946596 -234.132374)
				)
				(arc
					(start 31.946596 -233.637836)
					(mid 31.950316 -233.628856)
					(end 31.959296 -233.625136)
				)
				(arc
					(start 33.432496 -233.625136)
					(mid 33.441476 -233.628856)
					(end 33.445196 -233.637836)
				)
			)
		)
	)
	(zone
		(layer "In1.Cu")
		(hatch none 0.5)
		(connect_pads
			(clearance 0)
		)
		(min_thickness 0.25)
		(keepout
			(tracks not_allowed)
			(vias allowed)
			(pads allowed)
			(copperpour not_allowed)
			(footprints allowed)
		)
		(placement
			(enabled no)
			(sheetname "")
		)
		(fill
			(thermal_gap 0.5)
			(thermal_bridge_width 0.5)
			(island_removal_mode 0)
		)
		(polygon
			(pts
				(arc
					(start 300.189392 -5.628386)
					(mid 300.167074 -5.682268)
					(end 300.113192 -5.704586)
				)
				(arc
					(start 299.501052 -5.704586)
					(mid 299.44717 -5.682268)
					(end 299.424852 -5.628386)
				)
				(arc
					(start 299.424852 -4.531106)
					(mid 299.44717 -4.477224)
					(end 299.501052 -4.454906)
				)
				(arc
					(start 300.113192 -4.454906)
					(mid 300.167074 -4.477224)
					(end 300.189392 -4.531106)
				)
			)
		)
	)
	(zone
		(layer "In1.Cu")
		(hatch none 0.5)
		(connect_pads
			(clearance 0)
		)
		(min_thickness 0.25)
		(keepout
			(tracks not_allowed)
			(vias allowed)
			(pads allowed)
			(copperpour not_allowed)
			(footprints allowed)
		)
		(placement
			(enabled no)
			(sheetname "")
		)
		(fill
			(thermal_gap 0.5)
			(thermal_bridge_width 0.5)
			(island_removal_mode 0)
		)
		(polygon
			(pts
				(arc
					(start 195.353432 -295.332404)
					(mid 195.349712 -295.341384)
					(end 195.340732 -295.345104)
				)
				(arc
					(start 193.867532 -295.345104)
					(mid 193.858552 -295.341384)
					(end 193.854832 -295.332404)
				)
				(arc
					(start 193.854832 -294.837866)
					(mid 193.858552 -294.828886)
					(end 193.867532 -294.825166)
				)
				(arc
					(start 195.340732 -294.825166)
					(mid 195.349712 -294.828886)
					(end 195.353432 -294.837866)
				)
			)
		)
	)
	(zone
		(layer "In1.Cu")
		(hatch none 0.5)
		(connect_pads
			(clearance 0)
		)
		(min_thickness 0.25)
		(keepout
			(tracks not_allowed)
			(vias allowed)
			(pads allowed)
			(copperpour not_allowed)
			(footprints allowed)
		)
		(placement
			(enabled no)
			(sheetname "")
		)
		(fill
			(thermal_gap 0.5)
			(thermal_bridge_width 0.5)
			(island_removal_mode 0)
		)
		(polygon
			(pts
				(arc
					(start 300.57344 -283.43225)
					(mid 300.56972 -283.44123)
					(end 300.56074 -283.44495)
				)
				(arc
					(start 299.08754 -283.44495)
					(mid 299.07856 -283.44123)
					(end 299.07484 -283.43225)
				)
				(arc
					(start 299.07484 -282.937712)
					(mid 299.07856 -282.928732)
					(end 299.08754 -282.925012)
				)
				(arc
					(start 300.56074 -282.925012)
					(mid 300.56972 -282.928732)
					(end 300.57344 -282.937712)
				)
			)
		)
	)
	(zone
		(layer "In1.Cu")
		(hatch none 0.5)
		(connect_pads
			(clearance 0)
		)
		(min_thickness 0.25)
		(keepout
			(tracks not_allowed)
			(vias allowed)
			(pads allowed)
			(copperpour not_allowed)
			(footprints allowed)
		)
		(placement
			(enabled no)
			(sheetname "")
		)
		(fill
			(thermal_gap 0.5)
			(thermal_bridge_width 0.5)
			(island_removal_mode 0)
		)
		(polygon
			(pts
				(arc
					(start 25.901396 -209.482436)
					(mid 25.897676 -209.491416)
					(end 25.888696 -209.495136)
				)
				(arc
					(start 24.415496 -209.495136)
					(mid 24.406516 -209.491416)
					(end 24.402796 -209.482436)
				)
				(arc
					(start 24.402796 -208.987898)
					(mid 24.406516 -208.978918)
					(end 24.415496 -208.975198)
				)
				(arc
					(start 25.888696 -208.975198)
					(mid 25.897676 -208.978918)
					(end 25.901396 -208.987898)
				)
			)
		)
	)
	(zone
		(layer "In1.Cu")
		(hatch none 0.5)
		(connect_pads
			(clearance 0)
		)
		(min_thickness 0.25)
		(keepout
			(tracks not_allowed)
			(vias allowed)
			(pads allowed)
			(copperpour not_allowed)
			(footprints allowed)
		)
		(placement
			(enabled no)
			(sheetname "")
		)
		(fill
			(thermal_gap 0.5)
			(thermal_bridge_width 0.5)
			(island_removal_mode 0)
		)
		(polygon
			(pts
				(arc
					(start 454.937368 -236.68228)
					(mid 454.933648 -236.69126)
					(end 454.924668 -236.69498)
				)
				(arc
					(start 453.451468 -236.69498)
					(mid 453.442488 -236.69126)
					(end 453.438768 -236.68228)
				)
				(arc
					(start 453.438768 -236.187742)
					(mid 453.442488 -236.178762)
					(end 453.451468 -236.175042)
				)
				(arc
					(start 454.924668 -236.175042)
					(mid 454.933648 -236.178762)
					(end 454.937368 -236.187742)
				)
			)
		)
	)
	(zone
		(layer "In1.Cu")
		(hatch none 0.5)
		(connect_pads
			(clearance 0)
		)
		(min_thickness 0.25)
		(keepout
			(tracks not_allowed)
			(vias allowed)
			(pads allowed)
			(copperpour not_allowed)
			(footprints allowed)
		)
		(placement
			(enabled no)
			(sheetname "")
		)
		(fill
			(thermal_gap 0.5)
			(thermal_bridge_width 0.5)
			(island_removal_mode 0)
		)
		(polygon
			(pts
				(arc
					(start 281.385264 -202.682094)
					(mid 281.381544 -202.691074)
					(end 281.372564 -202.694794)
				)
				(arc
					(start 279.899364 -202.694794)
					(mid 279.890384 -202.691074)
					(end 279.886664 -202.682094)
				)
				(arc
					(start 279.886664 -202.187556)
					(mid 279.890384 -202.178576)
					(end 279.899364 -202.174856)
				)
				(arc
					(start 281.372564 -202.174856)
					(mid 281.381544 -202.178576)
					(end 281.385264 -202.187556)
				)
			)
		)
	)
	(zone
		(layer "In1.Cu")
		(hatch none 0.5)
		(connect_pads
			(clearance 0)
		)
		(min_thickness 0.25)
		(keepout
			(tracks not_allowed)
			(vias allowed)
			(pads allowed)
			(copperpour not_allowed)
			(footprints allowed)
		)
		(placement
			(enabled no)
			(sheetname "")
		)
		(fill
			(thermal_gap 0.5)
			(thermal_bridge_width 0.5)
			(island_removal_mode 0)
		)
		(polygon
			(pts
				(arc
					(start 424.761406 -266.432284)
					(mid 424.757686 -266.441264)
					(end 424.748706 -266.444984)
				)
				(arc
					(start 423.275506 -266.444984)
					(mid 423.266526 -266.441264)
					(end 423.262806 -266.432284)
				)
				(arc
					(start 423.262806 -265.937746)
					(mid 423.266526 -265.928766)
					(end 423.275506 -265.925046)
				)
				(arc
					(start 424.748706 -265.925046)
					(mid 424.757686 -265.928766)
					(end 424.761406 -265.937746)
				)
			)
		)
	)
	(zone
		(layer "In1.Cu")
		(hatch none 0.5)
		(connect_pads
			(clearance 0)
		)
		(min_thickness 0.25)
		(keepout
			(tracks not_allowed)
			(vias allowed)
			(pads allowed)
			(copperpour not_allowed)
			(footprints allowed)
		)
		(placement
			(enabled no)
			(sheetname "")
		)
		(fill
			(thermal_gap 0.5)
			(thermal_bridge_width 0.5)
			(island_removal_mode 0)
		)
		(polygon
			(pts
				(arc
					(start 424.761406 -272.382234)
					(mid 424.757686 -272.391214)
					(end 424.748706 -272.394934)
				)
				(arc
					(start 423.275506 -272.394934)
					(mid 423.266526 -272.391214)
					(end 423.262806 -272.382234)
				)
				(arc
					(start 423.262806 -271.887696)
					(mid 423.266526 -271.878716)
					(end 423.275506 -271.874996)
				)
				(arc
					(start 424.748706 -271.874996)
					(mid 424.757686 -271.878716)
					(end 424.761406 -271.887696)
				)
			)
		)
	)
	(zone
		(layer "In1.Cu")
		(hatch none 0.5)
		(connect_pads
			(clearance 0)
		)
		(min_thickness 0.25)
		(keepout
			(tracks not_allowed)
			(vias allowed)
			(pads allowed)
			(copperpour not_allowed)
			(footprints allowed)
		)
		(placement
			(enabled no)
			(sheetname "")
		)
		(fill
			(thermal_gap 0.5)
			(thermal_bridge_width 0.5)
			(island_removal_mode 0)
		)
		(polygon
			(pts
				(arc
					(start 22.45741 -223.932496)
					(mid 22.45369 -223.941476)
					(end 22.44471 -223.945196)
				)
				(arc
					(start 20.97151 -223.945196)
					(mid 20.96253 -223.941476)
					(end 20.95881 -223.932496)
				)
				(arc
					(start 20.95881 -223.437958)
					(mid 20.96253 -223.428978)
					(end 20.97151 -223.425258)
				)
				(arc
					(start 22.44471 -223.425258)
					(mid 22.45369 -223.428978)
					(end 22.45741 -223.437958)
				)
			)
		)
	)
	(zone
		(layer "In1.Cu")
		(hatch none 0.5)
		(connect_pads
			(clearance 0)
		)
		(min_thickness 0.25)
		(keepout
			(tracks not_allowed)
			(vias allowed)
			(pads allowed)
			(copperpour not_allowed)
			(footprints allowed)
		)
		(placement
			(enabled no)
			(sheetname "")
		)
		(fill
			(thermal_gap 0.5)
			(thermal_bridge_width 0.5)
			(island_removal_mode 0)
		)
		(polygon
			(pts
				(arc
					(start 60.177426 -223.932496)
					(mid 60.173706 -223.941476)
					(end 60.164726 -223.945196)
				)
				(arc
					(start 58.691526 -223.945196)
					(mid 58.682546 -223.941476)
					(end 58.678826 -223.932496)
				)
				(arc
					(start 58.678826 -223.437958)
					(mid 58.682546 -223.428978)
					(end 58.691526 -223.425258)
				)
				(arc
					(start 60.164726 -223.425258)
					(mid 60.173706 -223.428978)
					(end 60.177426 -223.437958)
				)
			)
		)
	)
	(zone
		(layer "In1.Cu")
		(hatch none 0.5)
		(connect_pads
			(clearance 0)
		)
		(min_thickness 0.25)
		(keepout
			(tracks not_allowed)
			(vias allowed)
			(pads allowed)
			(copperpour not_allowed)
			(footprints allowed)
		)
		(placement
			(enabled no)
			(sheetname "")
		)
		(fill
			(thermal_gap 0.5)
			(thermal_bridge_width 0.5)
			(island_removal_mode 0)
		)
		(polygon
			(pts
				(arc
					(start 30.001464 -264.732516)
					(mid 29.997744 -264.741496)
					(end 29.988764 -264.745216)
				)
				(arc
					(start 28.515564 -264.745216)
					(mid 28.506584 -264.741496)
					(end 28.502864 -264.732516)
				)
				(arc
					(start 28.502864 -264.237978)
					(mid 28.506584 -264.228998)
					(end 28.515564 -264.225278)
				)
				(arc
					(start 29.988764 -264.225278)
					(mid 29.997744 -264.228998)
					(end 30.001464 -264.237978)
				)
			)
		)
	)
	(zone
		(layer "In1.Cu")
		(hatch none 0.5)
		(connect_pads
			(clearance 0)
		)
		(min_thickness 0.25)
		(keepout
			(tracks not_allowed)
			(vias allowed)
			(pads allowed)
			(copperpour not_allowed)
			(footprints allowed)
		)
		(placement
			(enabled no)
			(sheetname "")
		)
		(fill
			(thermal_gap 0.5)
			(thermal_bridge_width 0.5)
			(island_removal_mode 0)
		)
		(polygon
			(pts
				(arc
					(start 450.8373 -273.232118)
					(mid 450.83358 -273.241098)
					(end 450.8246 -273.244818)
				)
				(arc
					(start 449.3514 -273.244818)
					(mid 449.34242 -273.241098)
					(end 449.3387 -273.232118)
				)
				(arc
					(start 449.3387 -272.73758)
					(mid 449.34242 -272.7286)
					(end 449.3514 -272.72488)
				)
				(arc
					(start 450.8246 -272.72488)
					(mid 450.83358 -272.7286)
					(end 450.8373 -272.73758)
				)
			)
		)
	)
	(zone
		(layer "In1.Cu")
		(hatch none 0.5)
		(connect_pads
			(clearance 0)
		)
		(min_thickness 0.25)
		(keepout
			(tracks not_allowed)
			(vias allowed)
			(pads allowed)
			(copperpour not_allowed)
			(footprints allowed)
		)
		(placement
			(enabled no)
			(sheetname "")
		)
		(fill
			(thermal_gap 0.5)
			(thermal_bridge_width 0.5)
			(island_removal_mode 0)
		)
		(polygon
			(pts
				(arc
					(start 206.9973 -251.13234)
					(mid 206.99358 -251.14132)
					(end 206.9846 -251.14504)
				)
				(arc
					(start 205.5114 -251.14504)
					(mid 205.50242 -251.14132)
					(end 205.4987 -251.13234)
				)
				(arc
					(start 205.4987 -250.637802)
					(mid 205.50242 -250.628822)
					(end 205.5114 -250.625102)
				)
				(arc
					(start 206.9846 -250.625102)
					(mid 206.99358 -250.628822)
					(end 206.9973 -250.637802)
				)
			)
		)
	)
	(zone
		(layer "In1.Cu")
		(hatch none 0.5)
		(connect_pads
			(clearance 0)
		)
		(min_thickness 0.25)
		(keepout
			(tracks not_allowed)
			(vias allowed)
			(pads allowed)
			(copperpour not_allowed)
			(footprints allowed)
		)
		(placement
			(enabled no)
			(sheetname "")
		)
		(fill
			(thermal_gap 0.5)
			(thermal_bridge_width 0.5)
			(island_removal_mode 0)
		)
		(polygon
			(pts
				(arc
					(start 371.761258 -397.156432)
					(mid 371.380258 -397.156432)
					(end 371.761258 -397.156432)
				)
			)
		)
	)
	(zone
		(layer "In1.Cu")
		(hatch none 0.5)
		(connect_pads
			(clearance 0)
		)
		(min_thickness 0.25)
		(keepout
			(tracks not_allowed)
			(vias allowed)
			(pads allowed)
			(copperpour not_allowed)
			(footprints allowed)
		)
		(placement
			(enabled no)
			(sheetname "")
		)
		(fill
			(thermal_gap 0.5)
			(thermal_bridge_width 0.5)
			(island_removal_mode 0)
		)
		(polygon
			(pts
				(arc
					(start 49.061116 -386.003292)
					(mid 48.680116 -386.003292)
					(end 49.061116 -386.003292)
				)
			)
		)
	)
	(zone
		(layer "In1.Cu")
		(hatch none 0.5)
		(connect_pads
			(clearance 0)
		)
		(min_thickness 0.25)
		(keepout
			(tracks not_allowed)
			(vias allowed)
			(pads allowed)
			(copperpour not_allowed)
			(footprints allowed)
		)
		(placement
			(enabled no)
			(sheetname "")
		)
		(fill
			(thermal_gap 0.5)
			(thermal_bridge_width 0.5)
			(island_removal_mode 0)
		)
		(polygon
			(pts
				(arc
					(start 454.937368 -254.53213)
					(mid 454.933648 -254.54111)
					(end 454.924668 -254.54483)
				)
				(arc
					(start 453.451468 -254.54483)
					(mid 453.442488 -254.54111)
					(end 453.438768 -254.53213)
				)
				(arc
					(start 453.438768 -254.037592)
					(mid 453.442488 -254.028612)
					(end 453.451468 -254.024892)
				)
				(arc
					(start 454.924668 -254.024892)
					(mid 454.933648 -254.028612)
					(end 454.937368 -254.037592)
				)
			)
		)
	)
	(zone
		(layer "In1.Cu")
		(hatch none 0.5)
		(connect_pads
			(clearance 0)
		)
		(min_thickness 0.25)
		(keepout
			(tracks not_allowed)
			(vias allowed)
			(pads allowed)
			(copperpour not_allowed)
			(footprints allowed)
		)
		(placement
			(enabled no)
			(sheetname "")
		)
		(fill
			(thermal_gap 0.5)
			(thermal_bridge_width 0.5)
			(island_removal_mode 0)
		)
		(polygon
			(pts
				(arc
					(start 417.217352 -264.732262)
					(mid 417.213632 -264.741242)
					(end 417.204652 -264.744962)
				)
				(arc
					(start 415.731452 -264.744962)
					(mid 415.722472 -264.741242)
					(end 415.718752 -264.732262)
				)
				(arc
					(start 415.718752 -264.237724)
					(mid 415.722472 -264.228744)
					(end 415.731452 -264.225024)
				)
				(arc
					(start 417.204652 -264.225024)
					(mid 417.213632 -264.228744)
					(end 417.217352 -264.237724)
				)
			)
		)
	)
	(zone
		(layer "In1.Cu")
		(hatch none 0.5)
		(connect_pads
			(clearance 0)
		)
		(min_thickness 0.25)
		(keepout
			(tracks not_allowed)
			(vias allowed)
			(pads allowed)
			(copperpour not_allowed)
			(footprints allowed)
		)
		(placement
			(enabled no)
			(sheetname "")
		)
		(fill
			(thermal_gap 0.5)
			(thermal_bridge_width 0.5)
			(island_removal_mode 0)
		)
		(polygon
			(pts
				(arc
					(start 281.385264 -206.082138)
					(mid 281.381544 -206.091118)
					(end 281.372564 -206.094838)
				)
				(arc
					(start 279.899364 -206.094838)
					(mid 279.890384 -206.091118)
					(end 279.886664 -206.082138)
				)
				(arc
					(start 279.886664 -205.5876)
					(mid 279.890384 -205.57862)
					(end 279.899364 -205.5749)
				)
				(arc
					(start 281.372564 -205.5749)
					(mid 281.381544 -205.57862)
					(end 281.385264 -205.5876)
				)
			)
		)
	)
	(zone
		(layer "In1.Cu")
		(hatch none 0.5)
		(connect_pads
			(clearance 0)
		)
		(min_thickness 0.25)
		(keepout
			(tracks not_allowed)
			(vias allowed)
			(pads allowed)
			(copperpour not_allowed)
			(footprints allowed)
		)
		(placement
			(enabled no)
			(sheetname "")
		)
		(fill
			(thermal_gap 0.5)
			(thermal_bridge_width 0.5)
			(island_removal_mode 0)
		)
		(polygon
			(pts
				(arc
					(start 432.30546 -297.032172)
					(mid 432.30174 -297.041152)
					(end 432.29276 -297.044872)
				)
				(arc
					(start 430.81956 -297.044872)
					(mid 430.81058 -297.041152)
					(end 430.80686 -297.032172)
				)
				(arc
					(start 430.80686 -296.537634)
					(mid 430.81058 -296.528654)
					(end 430.81956 -296.524934)
				)
				(arc
					(start 432.29276 -296.524934)
					(mid 432.30174 -296.528654)
					(end 432.30546 -296.537634)
				)
			)
		)
	)
	(zone
		(layer "In1.Cu")
		(hatch none 0.5)
		(connect_pads
			(clearance 0)
		)
		(min_thickness 0.25)
		(keepout
			(tracks not_allowed)
			(vias allowed)
			(pads allowed)
			(copperpour not_allowed)
			(footprints allowed)
		)
		(placement
			(enabled no)
			(sheetname "")
		)
		(fill
			(thermal_gap 0.5)
			(thermal_bridge_width 0.5)
			(island_removal_mode 0)
		)
		(polygon
			(pts
				(arc
					(start 60.177426 -219.682568)
					(mid 60.173706 -219.691548)
					(end 60.164726 -219.695268)
				)
				(arc
					(start 58.691526 -219.695268)
					(mid 58.682546 -219.691548)
					(end 58.678826 -219.682568)
				)
				(arc
					(start 58.678826 -219.18803)
					(mid 58.682546 -219.17905)
					(end 58.691526 -219.17533)
				)
				(arc
					(start 60.164726 -219.17533)
					(mid 60.173706 -219.17905)
					(end 60.177426 -219.18803)
				)
			)
		)
	)
	(zone
		(layer "In1.Cu")
		(hatch none 0.5)
		(connect_pads
			(clearance 0)
		)
		(min_thickness 0.25)
		(keepout
			(tracks not_allowed)
			(vias allowed)
			(pads allowed)
			(copperpour not_allowed)
			(footprints allowed)
		)
		(placement
			(enabled no)
			(sheetname "")
		)
		(fill
			(thermal_gap 0.5)
			(thermal_bridge_width 0.5)
			(island_removal_mode 0)
		)
		(polygon
			(pts
				(arc
					(start 37.545264 -227.33254)
					(mid 37.541544 -227.34152)
					(end 37.532564 -227.34524)
				)
				(arc
					(start 36.059364 -227.34524)
					(mid 36.050384 -227.34152)
					(end 36.046664 -227.33254)
				)
				(arc
					(start 36.046664 -226.838002)
					(mid 36.050384 -226.829022)
					(end 36.059364 -226.825302)
				)
				(arc
					(start 37.532564 -226.825302)
					(mid 37.541544 -226.829022)
					(end 37.545264 -226.838002)
				)
			)
		)
	)
	(zone
		(layer "In1.Cu")
		(hatch none 0.5)
		(connect_pads
			(clearance 0)
		)
		(min_thickness 0.25)
		(keepout
			(tracks not_allowed)
			(vias allowed)
			(pads allowed)
			(copperpour not_allowed)
			(footprints allowed)
		)
		(placement
			(enabled no)
			(sheetname "")
		)
		(fill
			(thermal_gap 0.5)
			(thermal_bridge_width 0.5)
			(island_removal_mode 0)
		)
		(polygon
			(pts
				(arc
					(start 187.809378 -291.93236)
					(mid 187.805658 -291.94134)
					(end 187.796678 -291.94506)
				)
				(arc
					(start 186.323478 -291.94506)
					(mid 186.314498 -291.94134)
					(end 186.310778 -291.93236)
				)
				(arc
					(start 186.310778 -291.437822)
					(mid 186.314498 -291.428842)
					(end 186.323478 -291.425122)
				)
				(arc
					(start 187.796678 -291.425122)
					(mid 187.805658 -291.428842)
					(end 187.809378 -291.437822)
				)
			)
		)
	)
	(zone
		(layer "In1.Cu")
		(hatch none 0.5)
		(connect_pads
			(clearance 0)
		)
		(min_thickness 0.25)
		(keepout
			(tracks not_allowed)
			(vias allowed)
			(pads allowed)
			(copperpour not_allowed)
			(footprints allowed)
		)
		(placement
			(enabled no)
			(sheetname "")
		)
		(fill
			(thermal_gap 0.5)
			(thermal_bridge_width 0.5)
			(island_removal_mode 0)
		)
		(polygon
			(pts
				(arc
					(start 191.909446 -278.332438)
					(mid 191.905726 -278.341418)
					(end 191.896746 -278.345138)
				)
				(arc
					(start 190.423546 -278.345138)
					(mid 190.414566 -278.341418)
					(end 190.410846 -278.332438)
				)
				(arc
					(start 190.410846 -277.8379)
					(mid 190.414566 -277.82892)
					(end 190.423546 -277.8252)
				)
				(arc
					(start 191.896746 -277.8252)
					(mid 191.905726 -277.82892)
					(end 191.909446 -277.8379)
				)
			)
		)
	)
	(zone
		(layer "In1.Cu")
		(hatch none 0.5)
		(connect_pads
			(clearance 0)
		)
		(min_thickness 0.25)
		(keepout
			(tracks not_allowed)
			(vias allowed)
			(pads allowed)
			(copperpour not_allowed)
			(footprints allowed)
		)
		(placement
			(enabled no)
			(sheetname "")
		)
		(fill
			(thermal_gap 0.5)
			(thermal_bridge_width 0.5)
			(island_removal_mode 0)
		)
		(polygon
			(pts
				(arc
					(start 447.393568 -308.082188)
					(mid 447.389848 -308.091168)
					(end 447.380868 -308.094888)
				)
				(arc
					(start 445.907668 -308.094888)
					(mid 445.898688 -308.091168)
					(end 445.894968 -308.082188)
				)
				(arc
					(start 445.894968 -307.58765)
					(mid 445.898688 -307.57867)
					(end 445.907668 -307.57495)
				)
				(arc
					(start 447.380868 -307.57495)
					(mid 447.389848 -307.57867)
					(end 447.393568 -307.58765)
				)
			)
		)
	)
	(zone
		(layer "In1.Cu")
		(hatch none 0.5)
		(connect_pads
			(clearance 0)
		)
		(min_thickness 0.25)
		(keepout
			(tracks not_allowed)
			(vias allowed)
			(pads allowed)
			(copperpour not_allowed)
			(footprints allowed)
		)
		(placement
			(enabled no)
			(sheetname "")
		)
		(fill
			(thermal_gap 0.5)
			(thermal_bridge_width 0.5)
			(island_removal_mode 0)
		)
		(polygon
			(pts
				(arc
					(start 191.909446 -216.282524)
					(mid 191.905726 -216.291504)
					(end 191.896746 -216.295224)
				)
				(arc
					(start 190.423546 -216.295224)
					(mid 190.414566 -216.291504)
					(end 190.410846 -216.282524)
				)
				(arc
					(start 190.410846 -215.787986)
					(mid 190.414566 -215.779006)
					(end 190.423546 -215.775286)
				)
				(arc
					(start 191.896746 -215.775286)
					(mid 191.905726 -215.779006)
					(end 191.909446 -215.787986)
				)
			)
		)
	)
	(zone
		(layer "In1.Cu")
		(hatch none 0.5)
		(connect_pads
			(clearance 0)
		)
		(min_thickness 0.25)
		(keepout
			(tracks not_allowed)
			(vias allowed)
			(pads allowed)
			(copperpour not_allowed)
			(footprints allowed)
		)
		(placement
			(enabled no)
			(sheetname "")
		)
		(fill
			(thermal_gap 0.5)
			(thermal_bridge_width 0.5)
			(island_removal_mode 0)
		)
		(polygon
			(pts
				(arc
					(start 288.929318 -316.582298)
					(mid 288.925598 -316.591278)
					(end 288.916618 -316.594998)
				)
				(arc
					(start 287.443418 -316.594998)
					(mid 287.434438 -316.591278)
					(end 287.430718 -316.582298)
				)
				(arc
					(start 287.430718 -316.08776)
					(mid 287.434438 -316.07878)
					(end 287.443418 -316.07506)
				)
				(arc
					(start 288.916618 -316.07506)
					(mid 288.925598 -316.07878)
					(end 288.929318 -316.08776)
				)
			)
		)
	)
	(zone
		(layer "In1.Cu")
		(hatch none 0.5)
		(connect_pads
			(clearance 0)
		)
		(min_thickness 0.25)
		(keepout
			(tracks not_allowed)
			(vias allowed)
			(pads allowed)
			(copperpour not_allowed)
			(footprints allowed)
		)
		(placement
			(enabled no)
			(sheetname "")
		)
		(fill
			(thermal_gap 0.5)
			(thermal_bridge_width 0.5)
			(island_removal_mode 0)
		)
		(polygon
			(pts
				(arc
					(start 443.2935 -213.73211)
					(mid 443.28978 -213.74109)
					(end 443.2808 -213.74481)
				)
				(arc
					(start 441.8076 -213.74481)
					(mid 441.79862 -213.74109)
					(end 441.7949 -213.73211)
				)
				(arc
					(start 441.7949 -213.237572)
					(mid 441.79862 -213.228592)
					(end 441.8076 -213.224872)
				)
				(arc
					(start 443.2808 -213.224872)
					(mid 443.28978 -213.228592)
					(end 443.2935 -213.237572)
				)
			)
		)
	)
	(zone
		(layer "In1.Cu")
		(hatch none 0.5)
		(connect_pads
			(clearance 0)
		)
		(min_thickness 0.25)
		(keepout
			(tracks not_allowed)
			(vias allowed)
			(pads allowed)
			(copperpour not_allowed)
			(footprints allowed)
		)
		(placement
			(enabled no)
			(sheetname "")
		)
		(fill
			(thermal_gap 0.5)
			(thermal_bridge_width 0.5)
			(island_removal_mode 0)
		)
		(polygon
			(pts
				(arc
					(start 199.4535 -303.832514)
					(mid 199.44978 -303.841494)
					(end 199.4408 -303.845214)
				)
				(arc
					(start 197.9676 -303.845214)
					(mid 197.95862 -303.841494)
					(end 197.9549 -303.832514)
				)
				(arc
					(start 197.9549 -303.337976)
					(mid 197.95862 -303.328996)
					(end 197.9676 -303.325276)
				)
				(arc
					(start 199.4408 -303.325276)
					(mid 199.44978 -303.328996)
					(end 199.4535 -303.337976)
				)
			)
		)
	)
	(zone
		(layer "In1.Cu")
		(hatch none 0.5)
		(connect_pads
			(clearance 0)
		)
		(min_thickness 0.25)
		(keepout
			(tracks not_allowed)
			(vias allowed)
			(pads allowed)
			(copperpour not_allowed)
			(footprints allowed)
		)
		(placement
			(enabled no)
			(sheetname "")
		)
		(fill
			(thermal_gap 0.5)
			(thermal_bridge_width 0.5)
			(island_removal_mode 0)
		)
		(polygon
			(pts
				(arc
					(start 56.077358 -273.232372)
					(mid 56.073638 -273.241352)
					(end 56.064658 -273.245072)
				)
				(arc
					(start 54.591458 -273.245072)
					(mid 54.582478 -273.241352)
					(end 54.578758 -273.232372)
				)
				(arc
					(start 54.578758 -272.737834)
					(mid 54.582478 -272.728854)
					(end 54.591458 -272.725134)
				)
				(arc
					(start 56.064658 -272.725134)
					(mid 56.073638 -272.728854)
					(end 56.077358 -272.737834)
				)
			)
		)
	)
	(zone
		(layer "In1.Cu")
		(hatch none 0.5)
		(connect_pads
			(clearance 0)
		)
		(min_thickness 0.25)
		(keepout
			(tracks not_allowed)
			(vias allowed)
			(pads allowed)
			(copperpour not_allowed)
			(footprints allowed)
		)
		(placement
			(enabled no)
			(sheetname "")
		)
		(fill
			(thermal_gap 0.5)
			(thermal_bridge_width 0.5)
			(island_removal_mode 0)
		)
		(polygon
			(pts
				(arc
					(start 432.30546 -276.632162)
					(mid 432.30174 -276.641142)
					(end 432.29276 -276.644862)
				)
				(arc
					(start 430.81956 -276.644862)
					(mid 430.81058 -276.641142)
					(end 430.80686 -276.632162)
				)
				(arc
					(start 430.80686 -276.137624)
					(mid 430.81058 -276.128644)
					(end 430.81956 -276.124924)
				)
				(arc
					(start 432.29276 -276.124924)
					(mid 432.30174 -276.128644)
					(end 432.30546 -276.137624)
				)
			)
		)
	)
	(zone
		(layer "In1.Cu")
		(hatch none 0.5)
		(connect_pads
			(clearance 0)
		)
		(min_thickness 0.25)
		(keepout
			(tracks not_allowed)
			(vias allowed)
			(pads allowed)
			(copperpour not_allowed)
			(footprints allowed)
		)
		(placement
			(enabled no)
			(sheetname "")
		)
		(fill
			(thermal_gap 0.5)
			(thermal_bridge_width 0.5)
			(island_removal_mode 0)
		)
		(polygon
			(pts
				(arc
					(start 33.445196 -212.032342)
					(mid 33.441476 -212.041322)
					(end 33.432496 -212.045042)
				)
				(arc
					(start 31.959296 -212.045042)
					(mid 31.950316 -212.041322)
					(end 31.946596 -212.032342)
				)
				(arc
					(start 31.946596 -211.537804)
					(mid 31.950316 -211.528824)
					(end 31.959296 -211.525104)
				)
				(arc
					(start 33.432496 -211.525104)
					(mid 33.441476 -211.528824)
					(end 33.445196 -211.537804)
				)
			)
		)
	)
	(zone
		(layer "In1.Cu")
		(hatch none 0.5)
		(connect_pads
			(clearance 0)
		)
		(min_thickness 0.25)
		(keepout
			(tracks not_allowed)
			(vias allowed)
			(pads allowed)
			(copperpour not_allowed)
			(footprints allowed)
		)
		(placement
			(enabled no)
			(sheetname "")
		)
		(fill
			(thermal_gap 0.5)
			(thermal_bridge_width 0.5)
			(island_removal_mode 0)
		)
		(polygon
			(pts
				(arc
					(start 89.698068 -383.92227)
					(mid 89.393268 -383.92227)
					(end 89.698068 -383.92227)
				)
			)
		)
	)
	(zone
		(layer "In1.Cu")
		(hatch none 0.5)
		(connect_pads
			(clearance 0)
		)
		(min_thickness 0.25)
		(keepout
			(tracks not_allowed)
			(vias allowed)
			(pads allowed)
			(copperpour not_allowed)
			(footprints allowed)
		)
		(placement
			(enabled no)
			(sheetname "")
		)
		(fill
			(thermal_gap 0.5)
			(thermal_bridge_width 0.5)
			(island_removal_mode 0)
		)
		(polygon
			(pts
				(arc
					(start 191.909446 -303.832514)
					(mid 191.905726 -303.841494)
					(end 191.896746 -303.845214)
				)
				(arc
					(start 190.423546 -303.845214)
					(mid 190.414566 -303.841494)
					(end 190.410846 -303.832514)
				)
				(arc
					(start 190.410846 -303.337976)
					(mid 190.414566 -303.328996)
					(end 190.423546 -303.325276)
				)
				(arc
					(start 191.896746 -303.325276)
					(mid 191.905726 -303.328996)
					(end 191.909446 -303.337976)
				)
			)
		)
	)
	(zone
		(layer "In1.Cu")
		(hatch none 0.5)
		(connect_pads
			(clearance 0)
		)
		(min_thickness 0.25)
		(keepout
			(tracks not_allowed)
			(vias allowed)
			(pads allowed)
			(copperpour not_allowed)
			(footprints allowed)
		)
		(placement
			(enabled no)
			(sheetname "")
		)
		(fill
			(thermal_gap 0.5)
			(thermal_bridge_width 0.5)
			(island_removal_mode 0)
		)
		(polygon
			(pts
				(arc
					(start 281.385264 -246.882158)
					(mid 281.381544 -246.891138)
					(end 281.372564 -246.894858)
				)
				(arc
					(start 279.899364 -246.894858)
					(mid 279.890384 -246.891138)
					(end 279.886664 -246.882158)
				)
				(arc
					(start 279.886664 -246.38762)
					(mid 279.890384 -246.37864)
					(end 279.899364 -246.37492)
				)
				(arc
					(start 281.372564 -246.37492)
					(mid 281.381544 -246.37864)
					(end 281.385264 -246.38762)
				)
			)
		)
	)
	(zone
		(layer "In1.Cu")
		(hatch none 0.5)
		(connect_pads
			(clearance 0)
		)
		(min_thickness 0.25)
		(keepout
			(tracks not_allowed)
			(vias allowed)
			(pads allowed)
			(copperpour not_allowed)
			(footprints allowed)
		)
		(placement
			(enabled no)
			(sheetname "")
		)
		(fill
			(thermal_gap 0.5)
			(thermal_bridge_width 0.5)
			(island_removal_mode 0)
		)
		(polygon
			(pts
				(arc
					(start 379.690884 -399.701258)
					(mid 379.817884 -399.828258)
					(end 379.944884 -399.701258)
				)
				(arc
					(start 379.944884 -399.625058)
					(mid 379.817884 -399.498058)
					(end 379.690884 -399.625058)
				)
			)
		)
	)
	(zone
		(layer "In1.Cu")
		(hatch none 0.5)
		(connect_pads
			(clearance 0)
		)
		(min_thickness 0.25)
		(keepout
			(tracks not_allowed)
			(vias allowed)
			(pads allowed)
			(copperpour not_allowed)
			(footprints allowed)
		)
		(placement
			(enabled no)
			(sheetname "")
		)
		(fill
			(thermal_gap 0.5)
			(thermal_bridge_width 0.5)
			(island_removal_mode 0)
		)
		(polygon
			(pts
				(arc
					(start 202.897232 -314.032392)
					(mid 202.893512 -314.041372)
					(end 202.884532 -314.045092)
				)
				(arc
					(start 201.411332 -314.045092)
					(mid 201.402352 -314.041372)
					(end 201.398632 -314.032392)
				)
				(arc
					(start 201.398632 -313.537854)
					(mid 201.402352 -313.528874)
					(end 201.411332 -313.525154)
				)
				(arc
					(start 202.884532 -313.525154)
					(mid 202.893512 -313.528874)
					(end 202.897232 -313.537854)
				)
			)
		)
	)
	(zone
		(layer "In1.Cu")
		(hatch none 0.5)
		(connect_pads
			(clearance 0)
		)
		(min_thickness 0.25)
		(keepout
			(tracks not_allowed)
			(vias allowed)
			(pads allowed)
			(copperpour not_allowed)
			(footprints allowed)
		)
		(placement
			(enabled no)
			(sheetname "")
		)
		(fill
			(thermal_gap 0.5)
			(thermal_bridge_width 0.5)
			(island_removal_mode 0)
		)
		(polygon
			(pts
				(arc
					(start 202.897232 -305.532536)
					(mid 202.893512 -305.541516)
					(end 202.884532 -305.545236)
				)
				(arc
					(start 201.411332 -305.545236)
					(mid 201.402352 -305.541516)
					(end 201.398632 -305.532536)
				)
				(arc
					(start 201.398632 -305.037998)
					(mid 201.402352 -305.029018)
					(end 201.411332 -305.025298)
				)
				(arc
					(start 202.884532 -305.025298)
					(mid 202.893512 -305.029018)
					(end 202.897232 -305.037998)
				)
			)
		)
	)
	(zone
		(layer "In1.Cu")
		(hatch none 0.5)
		(connect_pads
			(clearance 0)
		)
		(min_thickness 0.25)
		(keepout
			(tracks not_allowed)
			(vias allowed)
			(pads allowed)
			(copperpour not_allowed)
			(footprints allowed)
		)
		(placement
			(enabled no)
			(sheetname "")
		)
		(fill
			(thermal_gap 0.5)
			(thermal_bridge_width 0.5)
			(island_removal_mode 0)
		)
		(polygon
			(pts
				(arc
					(start 96.898206 -390.761474)
					(mid 96.593406 -390.761474)
					(end 96.898206 -390.761474)
				)
			)
		)
	)
	(zone
		(layer "In1.Cu")
		(hatch none 0.5)
		(connect_pads
			(clearance 0)
		)
		(min_thickness 0.25)
		(keepout
			(tracks not_allowed)
			(vias allowed)
			(pads allowed)
			(copperpour not_allowed)
			(footprints allowed)
		)
		(placement
			(enabled no)
			(sheetname "")
		)
		(fill
			(thermal_gap 0.5)
			(thermal_bridge_width 0.5)
			(island_removal_mode 0)
		)
		(polygon
			(pts
				(arc
					(start 384.490976 -399.701258)
					(mid 384.617976 -399.828258)
					(end 384.744976 -399.701258)
				)
				(arc
					(start 384.744976 -399.625058)
					(mid 384.617976 -399.498058)
					(end 384.490976 -399.625058)
				)
			)
		)
	)
	(zone
		(layer "In1.Cu")
		(hatch none 0.5)
		(connect_pads
			(clearance 0)
		)
		(min_thickness 0.25)
		(keepout
			(tracks not_allowed)
			(vias allowed)
			(pads allowed)
			(copperpour not_allowed)
			(footprints allowed)
		)
		(placement
			(enabled no)
			(sheetname "")
		)
		(fill
			(thermal_gap 0.5)
			(thermal_bridge_width 0.5)
			(island_removal_mode 0)
		)
		(polygon
			(pts
				(arc
					(start 273.841464 -223.082104)
					(mid 273.837744 -223.091084)
					(end 273.828764 -223.094804)
				)
				(arc
					(start 272.355564 -223.094804)
					(mid 272.346584 -223.091084)
					(end 272.342864 -223.082104)
				)
				(arc
					(start 272.342864 -222.587566)
					(mid 272.346584 -222.578586)
					(end 272.355564 -222.574866)
				)
				(arc
					(start 273.828764 -222.574866)
					(mid 273.837744 -222.578586)
					(end 273.841464 -222.587566)
				)
			)
		)
	)
	(zone
		(layer "In1.Cu")
		(hatch none 0.5)
		(connect_pads
			(clearance 0)
		)
		(min_thickness 0.25)
		(keepout
			(tracks not_allowed)
			(vias allowed)
			(pads allowed)
			(copperpour not_allowed)
			(footprints allowed)
		)
		(placement
			(enabled no)
			(sheetname "")
		)
		(fill
			(thermal_gap 0.5)
			(thermal_bridge_width 0.5)
			(island_removal_mode 0)
		)
		(polygon
			(pts
				(arc
					(start 439.849514 -227.332286)
					(mid 439.845794 -227.341266)
					(end 439.836814 -227.344986)
				)
				(arc
					(start 438.363614 -227.344986)
					(mid 438.354634 -227.341266)
					(end 438.350914 -227.332286)
				)
				(arc
					(start 438.350914 -226.837748)
					(mid 438.354634 -226.828768)
					(end 438.363614 -226.825048)
				)
				(arc
					(start 439.836814 -226.825048)
					(mid 439.845794 -226.828768)
					(end 439.849514 -226.837748)
				)
			)
		)
	)
	(zone
		(layer "In1.Cu")
		(hatch none 0.5)
		(connect_pads
			(clearance 0)
		)
		(min_thickness 0.25)
		(keepout
			(tracks not_allowed)
			(vias allowed)
			(pads allowed)
			(copperpour not_allowed)
			(footprints allowed)
		)
		(placement
			(enabled no)
			(sheetname "")
		)
		(fill
			(thermal_gap 0.5)
			(thermal_bridge_width 0.5)
			(island_removal_mode 0)
		)
		(polygon
			(pts
				(arc
					(start 439.849514 -303.83226)
					(mid 439.845794 -303.84124)
					(end 439.836814 -303.84496)
				)
				(arc
					(start 438.363614 -303.84496)
					(mid 438.354634 -303.84124)
					(end 438.350914 -303.83226)
				)
				(arc
					(start 438.350914 -303.337722)
					(mid 438.354634 -303.328742)
					(end 438.363614 -303.325022)
				)
				(arc
					(start 439.836814 -303.325022)
					(mid 439.845794 -303.328742)
					(end 439.849514 -303.337722)
				)
			)
		)
	)
	(zone
		(layer "In1.Cu")
		(hatch none 0.5)
		(connect_pads
			(clearance 0)
		)
		(min_thickness 0.25)
		(keepout
			(tracks not_allowed)
			(vias allowed)
			(pads allowed)
			(copperpour not_allowed)
			(footprints allowed)
		)
		(placement
			(enabled no)
			(sheetname "")
		)
		(fill
			(thermal_gap 0.5)
			(thermal_bridge_width 0.5)
			(island_removal_mode 0)
		)
		(polygon
			(pts
				(arc
					(start 439.849514 -289.3822)
					(mid 439.845794 -289.39118)
					(end 439.836814 -289.3949)
				)
				(arc
					(start 438.363614 -289.3949)
					(mid 438.354634 -289.39118)
					(end 438.350914 -289.3822)
				)
				(arc
					(start 438.350914 -288.887662)
					(mid 438.354634 -288.878682)
					(end 438.363614 -288.874962)
				)
				(arc
					(start 439.836814 -288.874962)
					(mid 439.845794 -288.878682)
					(end 439.849514 -288.887662)
				)
			)
		)
	)
	(zone
		(layer "In1.Cu")
		(hatch none 0.5)
		(connect_pads
			(clearance 0)
		)
		(min_thickness 0.25)
		(keepout
			(tracks not_allowed)
			(vias allowed)
			(pads allowed)
			(copperpour not_allowed)
			(footprints allowed)
		)
		(placement
			(enabled no)
			(sheetname "")
		)
		(fill
			(thermal_gap 0.5)
			(thermal_bridge_width 0.5)
			(island_removal_mode 0)
		)
		(polygon
			(pts
				(arc
					(start 126.961138 -386.003292)
					(mid 126.580138 -386.003292)
					(end 126.961138 -386.003292)
				)
			)
		)
	)
	(zone
		(layer "In1.Cu")
		(hatch none 0.5)
		(connect_pads
			(clearance 0)
		)
		(min_thickness 0.25)
		(keepout
			(tracks not_allowed)
			(vias allowed)
			(pads allowed)
			(copperpour not_allowed)
			(footprints allowed)
		)
		(placement
			(enabled no)
			(sheetname "")
		)
		(fill
			(thermal_gap 0.5)
			(thermal_bridge_width 0.5)
			(island_removal_mode 0)
		)
		(polygon
			(pts
				(arc
					(start 22.45741 -302.132492)
					(mid 22.45369 -302.141472)
					(end 22.44471 -302.145192)
				)
				(arc
					(start 20.97151 -302.145192)
					(mid 20.96253 -302.141472)
					(end 20.95881 -302.132492)
				)
				(arc
					(start 20.95881 -301.637954)
					(mid 20.96253 -301.628974)
					(end 20.97151 -301.625254)
				)
				(arc
					(start 22.44471 -301.625254)
					(mid 22.45369 -301.628974)
					(end 22.45741 -301.637954)
				)
			)
		)
	)
	(zone
		(layer "In1.Cu")
		(hatch none 0.5)
		(connect_pads
			(clearance 0)
		)
		(min_thickness 0.25)
		(keepout
			(tracks not_allowed)
			(vias allowed)
			(pads allowed)
			(copperpour not_allowed)
			(footprints allowed)
		)
		(placement
			(enabled no)
			(sheetname "")
		)
		(fill
			(thermal_gap 0.5)
			(thermal_bridge_width 0.5)
			(island_removal_mode 0)
		)
		(polygon
			(pts
				(arc
					(start 408.61869 -399.701258)
					(mid 408.74569 -399.828258)
					(end 408.87269 -399.701258)
				)
				(arc
					(start 408.87269 -399.625058)
					(mid 408.74569 -399.498058)
					(end 408.61869 -399.625058)
				)
			)
		)
	)
	(zone
		(layer "In1.Cu")
		(hatch none 0.5)
		(connect_pads
			(clearance 0)
		)
		(min_thickness 0.25)
		(keepout
			(tracks not_allowed)
			(vias allowed)
			(pads allowed)
			(copperpour not_allowed)
			(footprints allowed)
		)
		(placement
			(enabled no)
			(sheetname "")
		)
		(fill
			(thermal_gap 0.5)
			(thermal_bridge_width 0.5)
			(island_removal_mode 0)
		)
		(polygon
			(pts
				(arc
					(start 308.117494 -276.632162)
					(mid 308.113774 -276.641142)
					(end 308.104794 -276.644862)
				)
				(arc
					(start 306.631594 -276.644862)
					(mid 306.622614 -276.641142)
					(end 306.618894 -276.632162)
				)
				(arc
					(start 306.618894 -276.137624)
					(mid 306.622614 -276.128644)
					(end 306.631594 -276.124924)
				)
				(arc
					(start 308.104794 -276.124924)
					(mid 308.113774 -276.128644)
					(end 308.117494 -276.137624)
				)
			)
		)
	)
	(zone
		(layer "In1.Cu")
		(hatch none 0.5)
		(connect_pads
			(clearance 0)
		)
		(min_thickness 0.25)
		(keepout
			(tracks not_allowed)
			(vias allowed)
			(pads allowed)
			(copperpour not_allowed)
			(footprints allowed)
		)
		(placement
			(enabled no)
			(sheetname "")
		)
		(fill
			(thermal_gap 0.5)
			(thermal_bridge_width 0.5)
			(island_removal_mode 0)
		)
		(polygon
			(pts
				(arc
					(start 420.661338 -204.382116)
					(mid 420.657618 -204.391096)
					(end 420.648638 -204.394816)
				)
				(arc
					(start 419.175438 -204.394816)
					(mid 419.166458 -204.391096)
					(end 419.162738 -204.382116)
				)
				(arc
					(start 419.162738 -203.887578)
					(mid 419.166458 -203.878598)
					(end 419.175438 -203.874878)
				)
				(arc
					(start 420.648638 -203.874878)
					(mid 420.657618 -203.878598)
					(end 420.661338 -203.887578)
				)
			)
		)
	)
	(zone
		(layer "In1.Cu")
		(hatch none 0.5)
		(connect_pads
			(clearance 0)
		)
		(min_thickness 0.25)
		(keepout
			(tracks not_allowed)
			(vias allowed)
			(pads allowed)
			(copperpour not_allowed)
			(footprints allowed)
		)
		(placement
			(enabled no)
			(sheetname "")
		)
		(fill
			(thermal_gap 0.5)
			(thermal_bridge_width 0.5)
			(island_removal_mode 0)
		)
		(polygon
			(pts
				(arc
					(start 22.45741 -280.03246)
					(mid 22.45369 -280.04144)
					(end 22.44471 -280.04516)
				)
				(arc
					(start 20.97151 -280.04516)
					(mid 20.96253 -280.04144)
					(end 20.95881 -280.03246)
				)
				(arc
					(start 20.95881 -279.537922)
					(mid 20.96253 -279.528942)
					(end 20.97151 -279.525222)
				)
				(arc
					(start 22.44471 -279.525222)
					(mid 22.45369 -279.528942)
					(end 22.45741 -279.537922)
				)
			)
		)
	)
	(zone
		(layer "In1.Cu")
		(hatch none 0.5)
		(connect_pads
			(clearance 0)
		)
		(min_thickness 0.25)
		(keepout
			(tracks not_allowed)
			(vias allowed)
			(pads allowed)
			(copperpour not_allowed)
			(footprints allowed)
		)
		(placement
			(enabled no)
			(sheetname "")
		)
		(fill
			(thermal_gap 0.5)
			(thermal_bridge_width 0.5)
			(island_removal_mode 0)
		)
		(polygon
			(pts
				(arc
					(start 340.788752 -393.69238)
					(mid 340.407752 -393.69238)
					(end 340.788752 -393.69238)
				)
			)
		)
	)
	(zone
		(layer "In1.Cu")
		(hatch none 0.5)
		(connect_pads
			(clearance 0)
		)
		(min_thickness 0.25)
		(keepout
			(tracks not_allowed)
			(vias allowed)
			(pads allowed)
			(copperpour not_allowed)
			(footprints allowed)
		)
		(placement
			(enabled no)
			(sheetname "")
		)
		(fill
			(thermal_gap 0.5)
			(thermal_bridge_width 0.5)
			(island_removal_mode 0)
		)
		(polygon
			(pts
				(arc
					(start 30.001464 -254.532384)
					(mid 29.997744 -254.541364)
					(end 29.988764 -254.545084)
				)
				(arc
					(start 28.515564 -254.545084)
					(mid 28.506584 -254.541364)
					(end 28.502864 -254.532384)
				)
				(arc
					(start 28.502864 -254.037846)
					(mid 28.506584 -254.028866)
					(end 28.515564 -254.025146)
				)
				(arc
					(start 29.988764 -254.025146)
					(mid 29.997744 -254.028866)
					(end 30.001464 -254.037846)
				)
			)
		)
	)
	(zone
		(layer "In1.Cu")
		(hatch none 0.5)
		(connect_pads
			(clearance 0)
		)
		(min_thickness 0.25)
		(keepout
			(tracks not_allowed)
			(vias allowed)
			(pads allowed)
			(copperpour not_allowed)
			(footprints allowed)
		)
		(placement
			(enabled no)
			(sheetname "")
		)
		(fill
			(thermal_gap 0.5)
			(thermal_bridge_width 0.5)
			(island_removal_mode 0)
		)
		(polygon
			(pts
				(arc
					(start 341.988902 -397.156432)
					(mid 341.607902 -397.156432)
					(end 341.988902 -397.156432)
				)
			)
		)
	)
	(zone
		(layer "In1.Cu")
		(hatch none 0.5)
		(connect_pads
			(clearance 0)
		)
		(min_thickness 0.25)
		(keepout
			(tracks not_allowed)
			(vias allowed)
			(pads allowed)
			(copperpour not_allowed)
			(footprints allowed)
		)
		(placement
			(enabled no)
			(sheetname "")
		)
		(fill
			(thermal_gap 0.5)
			(thermal_bridge_width 0.5)
			(island_removal_mode 0)
		)
		(polygon
			(pts
				(arc
					(start 195.353432 -228.182424)
					(mid 195.349712 -228.191404)
					(end 195.340732 -228.195124)
				)
				(arc
					(start 193.867532 -228.195124)
					(mid 193.858552 -228.191404)
					(end 193.854832 -228.182424)
				)
				(arc
					(start 193.854832 -227.687886)
					(mid 193.858552 -227.678906)
					(end 193.867532 -227.675186)
				)
				(arc
					(start 195.340732 -227.675186)
					(mid 195.349712 -227.678906)
					(end 195.353432 -227.687886)
				)
			)
		)
	)
	(zone
		(layer "In1.Cu")
		(hatch none 0.5)
		(connect_pads
			(clearance 0)
		)
		(min_thickness 0.25)
		(keepout
			(tracks not_allowed)
			(vias allowed)
			(pads allowed)
			(copperpour not_allowed)
			(footprints allowed)
		)
		(placement
			(enabled no)
			(sheetname "")
		)
		(fill
			(thermal_gap 0.5)
			(thermal_bridge_width 0.5)
			(island_removal_mode 0)
		)
		(polygon
			(pts
				(arc
					(start 370.561362 -397.156432)
					(mid 370.180362 -397.156432)
					(end 370.561362 -397.156432)
				)
			)
		)
	)
	(zone
		(layer "In1.Cu")
		(hatch none 0.5)
		(connect_pads
			(clearance 0)
		)
		(min_thickness 0.25)
		(keepout
			(tracks not_allowed)
			(vias allowed)
			(pads allowed)
			(copperpour not_allowed)
			(footprints allowed)
		)
		(placement
			(enabled no)
			(sheetname "")
		)
		(fill
			(thermal_gap 0.5)
			(thermal_bridge_width 0.5)
			(island_removal_mode 0)
		)
		(polygon
			(pts
				(arc
					(start 450.8373 -316.582298)
					(mid 450.83358 -316.591278)
					(end 450.8246 -316.594998)
				)
				(arc
					(start 449.3514 -316.594998)
					(mid 449.34242 -316.591278)
					(end 449.3387 -316.582298)
				)
				(arc
					(start 449.3387 -316.08776)
					(mid 449.34242 -316.07878)
					(end 449.3514 -316.07506)
				)
				(arc
					(start 450.8246 -316.07506)
					(mid 450.83358 -316.07878)
					(end 450.8373 -316.08776)
				)
			)
		)
	)
	(zone
		(layer "In1.Cu")
		(hatch none 0.5)
		(connect_pads
			(clearance 0)
		)
		(min_thickness 0.25)
		(keepout
			(tracks not_allowed)
			(vias allowed)
			(pads allowed)
			(copperpour not_allowed)
			(footprints allowed)
		)
		(placement
			(enabled no)
			(sheetname "")
		)
		(fill
			(thermal_gap 0.5)
			(thermal_bridge_width 0.5)
			(island_removal_mode 0)
		)
		(polygon
			(pts
				(arc
					(start 96.318832 -391.319258)
					(mid 96.445832 -391.446258)
					(end 96.572832 -391.319258)
				)
				(arc
					(start 96.572832 -391.243058)
					(mid 96.445832 -391.116058)
					(end 96.318832 -391.243058)
				)
			)
		)
	)
	(zone
		(layer "In1.Cu")
		(hatch none 0.5)
		(connect_pads
			(clearance 0)
		)
		(min_thickness 0.25)
		(keepout
			(tracks not_allowed)
			(vias allowed)
			(pads allowed)
			(copperpour not_allowed)
			(footprints allowed)
		)
		(placement
			(enabled no)
			(sheetname "")
		)
		(fill
			(thermal_gap 0.5)
			(thermal_bridge_width 0.5)
			(island_removal_mode 0)
		)
		(polygon
			(pts
				(arc
					(start 165.177216 -297.882564)
					(mid 165.173496 -297.891544)
					(end 165.164516 -297.895264)
				)
				(arc
					(start 163.691316 -297.895264)
					(mid 163.682336 -297.891544)
					(end 163.678616 -297.882564)
				)
				(arc
					(start 163.678616 -297.388026)
					(mid 163.682336 -297.379046)
					(end 163.691316 -297.375326)
				)
				(arc
					(start 165.164516 -297.375326)
					(mid 165.173496 -297.379046)
					(end 165.177216 -297.388026)
				)
			)
		)
	)
	(zone
		(layer "In1.Cu")
		(hatch none 0.5)
		(connect_pads
			(clearance 0)
		)
		(min_thickness 0.25)
		(keepout
			(tracks not_allowed)
			(vias allowed)
			(pads allowed)
			(copperpour not_allowed)
			(footprints allowed)
		)
		(placement
			(enabled no)
			(sheetname "")
		)
		(fill
			(thermal_gap 0.5)
			(thermal_bridge_width 0.5)
			(island_removal_mode 0)
		)
		(polygon
			(pts
				(arc
					(start 450.8373 -198.432166)
					(mid 450.83358 -198.441146)
					(end 450.8246 -198.444866)
				)
				(arc
					(start 449.3514 -198.444866)
					(mid 449.34242 -198.441146)
					(end 449.3387 -198.432166)
				)
				(arc
					(start 449.3387 -197.937628)
					(mid 449.34242 -197.928648)
					(end 449.3514 -197.924928)
				)
				(arc
					(start 450.8246 -197.924928)
					(mid 450.83358 -197.928648)
					(end 450.8373 -197.937628)
				)
			)
		)
	)
	(zone
		(layer "In1.Cu")
		(hatch none 0.5)
		(connect_pads
			(clearance 0)
		)
		(min_thickness 0.25)
		(keepout
			(tracks not_allowed)
			(vias allowed)
			(pads allowed)
			(copperpour not_allowed)
			(footprints allowed)
		)
		(placement
			(enabled no)
			(sheetname "")
		)
		(fill
			(thermal_gap 0.5)
			(thermal_bridge_width 0.5)
			(island_removal_mode 0)
		)
		(polygon
			(pts
				(arc
					(start 64.99098 -383.440686)
					(mid 65.11798 -383.567686)
					(end 65.24498 -383.440686)
				)
				(arc
					(start 65.24498 -383.364486)
					(mid 65.11798 -383.237486)
					(end 64.99098 -383.364486)
				)
			)
		)
	)
	(zone
		(layer "In1.Cu")
		(hatch none 0.5)
		(connect_pads
			(clearance 0)
		)
		(min_thickness 0.25)
		(keepout
			(tracks not_allowed)
			(vias allowed)
			(pads allowed)
			(copperpour not_allowed)
			(footprints allowed)
		)
		(placement
			(enabled no)
			(sheetname "")
		)
		(fill
			(thermal_gap 0.5)
			(thermal_bridge_width 0.5)
			(island_removal_mode 0)
		)
		(polygon
			(pts
				(arc
					(start 454.937368 -297.032172)
					(mid 454.933648 -297.041152)
					(end 454.924668 -297.044872)
				)
				(arc
					(start 453.451468 -297.044872)
					(mid 453.442488 -297.041152)
					(end 453.438768 -297.032172)
				)
				(arc
					(start 453.438768 -296.537634)
					(mid 453.442488 -296.528654)
					(end 453.451468 -296.524934)
				)
				(arc
					(start 454.924668 -296.524934)
					(mid 454.933648 -296.528654)
					(end 454.937368 -296.537634)
				)
			)
		)
	)
	(zone
		(layer "In1.Cu")
		(hatch none 0.5)
		(connect_pads
			(clearance 0)
		)
		(min_thickness 0.25)
		(keepout
			(tracks not_allowed)
			(vias allowed)
			(pads allowed)
			(copperpour not_allowed)
			(footprints allowed)
		)
		(placement
			(enabled no)
			(sheetname "")
		)
		(fill
			(thermal_gap 0.5)
			(thermal_bridge_width 0.5)
			(island_removal_mode 0)
		)
		(polygon
			(pts
				(arc
					(start 176.821338 -274.08251)
					(mid 176.817618 -274.09149)
					(end 176.808638 -274.09521)
				)
				(arc
					(start 175.335438 -274.09521)
					(mid 175.326458 -274.09149)
					(end 175.322738 -274.08251)
				)
				(arc
					(start 175.322738 -273.587972)
					(mid 175.326458 -273.578992)
					(end 175.335438 -273.575272)
				)
				(arc
					(start 176.808638 -273.575272)
					(mid 176.817618 -273.578992)
					(end 176.821338 -273.587972)
				)
			)
		)
	)
	(zone
		(layer "In1.Cu")
		(hatch none 0.5)
		(connect_pads
			(clearance 0)
		)
		(min_thickness 0.25)
		(keepout
			(tracks not_allowed)
			(vias allowed)
			(pads allowed)
			(copperpour not_allowed)
			(footprints allowed)
		)
		(placement
			(enabled no)
			(sheetname "")
		)
		(fill
			(thermal_gap 0.5)
			(thermal_bridge_width 0.5)
			(island_removal_mode 0)
		)
		(polygon
			(pts
				(arc
					(start 191.909446 -254.532384)
					(mid 191.905726 -254.541364)
					(end 191.896746 -254.545084)
				)
				(arc
					(start 190.423546 -254.545084)
					(mid 190.414566 -254.541364)
					(end 190.410846 -254.532384)
				)
				(arc
					(start 190.410846 -254.037846)
					(mid 190.414566 -254.028866)
					(end 190.423546 -254.025146)
				)
				(arc
					(start 191.896746 -254.025146)
					(mid 191.905726 -254.028866)
					(end 191.909446 -254.037846)
				)
			)
		)
	)
	(zone
		(layer "In1.Cu")
		(hatch none 0.5)
		(connect_pads
			(clearance 0)
		)
		(min_thickness 0.25)
		(keepout
			(tracks not_allowed)
			(vias allowed)
			(pads allowed)
			(copperpour not_allowed)
			(footprints allowed)
		)
		(placement
			(enabled no)
			(sheetname "")
		)
		(fill
			(thermal_gap 0.5)
			(thermal_bridge_width 0.5)
			(island_removal_mode 0)
		)
		(polygon
			(pts
				(arc
					(start 265.87831 -218.585034)
					(mid 265.21791 -218.585034)
					(end 265.87831 -218.585034)
				)
			)
		)
	)
	(zone
		(layer "In1.Cu")
		(hatch none 0.5)
		(connect_pads
			(clearance 0)
		)
		(min_thickness 0.25)
		(keepout
			(tracks not_allowed)
			(vias allowed)
			(pads allowed)
			(copperpour not_allowed)
			(footprints allowed)
		)
		(placement
			(enabled no)
			(sheetname "")
		)
		(fill
			(thermal_gap 0.5)
			(thermal_bridge_width 0.5)
			(island_removal_mode 0)
		)
		(polygon
			(pts
				(arc
					(start 265.87831 -272.984976)
					(mid 265.21791 -272.984976)
					(end 265.87831 -272.984976)
				)
			)
		)
	)
	(zone
		(layer "In1.Cu")
		(hatch none 0.5)
		(connect_pads
			(clearance 0)
		)
		(min_thickness 0.25)
		(keepout
			(tracks not_allowed)
			(vias allowed)
			(pads allowed)
			(copperpour not_allowed)
			(footprints allowed)
		)
		(placement
			(enabled no)
			(sheetname "")
		)
		(fill
			(thermal_gap 0.5)
			(thermal_bridge_width 0.5)
			(island_removal_mode 0)
		)
		(polygon
			(pts
				(arc
					(start 180.265324 -280.882344)
					(mid 180.261604 -280.891324)
					(end 180.252624 -280.895044)
				)
				(arc
					(start 178.779424 -280.895044)
					(mid 178.770444 -280.891324)
					(end 178.766724 -280.882344)
				)
				(arc
					(start 178.766724 -280.387806)
					(mid 178.770444 -280.378826)
					(end 178.779424 -280.375106)
				)
				(arc
					(start 180.252624 -280.375106)
					(mid 180.261604 -280.378826)
					(end 180.265324 -280.387806)
				)
			)
		)
	)
	(zone
		(layer "In1.Cu")
		(hatch none 0.5)
		(connect_pads
			(clearance 0)
		)
		(min_thickness 0.25)
		(keepout
			(tracks not_allowed)
			(vias allowed)
			(pads allowed)
			(copperpour not_allowed)
			(footprints allowed)
		)
		(placement
			(enabled no)
			(sheetname "")
		)
		(fill
			(thermal_gap 0.5)
			(thermal_bridge_width 0.5)
			(island_removal_mode 0)
		)
		(polygon
			(pts
				(arc
					(start 349.298006 -399.143474)
					(mid 348.993206 -399.143474)
					(end 349.298006 -399.143474)
				)
			)
		)
	)
	(zone
		(layer "In1.Cu")
		(hatch none 0.5)
		(connect_pads
			(clearance 0)
		)
		(min_thickness 0.25)
		(keepout
			(tracks not_allowed)
			(vias allowed)
			(pads allowed)
			(copperpour not_allowed)
			(footprints allowed)
		)
		(placement
			(enabled no)
			(sheetname "")
		)
		(fill
			(thermal_gap 0.5)
			(thermal_bridge_width 0.5)
			(island_removal_mode 0)
		)
		(polygon
			(pts
				(arc
					(start 288.929318 -239.232186)
					(mid 288.925598 -239.241166)
					(end 288.916618 -239.244886)
				)
				(arc
					(start 287.443418 -239.244886)
					(mid 287.434438 -239.241166)
					(end 287.430718 -239.232186)
				)
				(arc
					(start 287.430718 -238.737648)
					(mid 287.434438 -238.728668)
					(end 287.443418 -238.724948)
				)
				(arc
					(start 288.916618 -238.724948)
					(mid 288.925598 -238.728668)
					(end 288.929318 -238.737648)
				)
			)
		)
	)
	(zone
		(layer "In1.Cu")
		(hatch none 0.5)
		(connect_pads
			(clearance 0)
		)
		(min_thickness 0.25)
		(keepout
			(tracks not_allowed)
			(vias allowed)
			(pads allowed)
			(copperpour not_allowed)
			(footprints allowed)
		)
		(placement
			(enabled no)
			(sheetname "")
		)
		(fill
			(thermal_gap 0.5)
			(thermal_bridge_width 0.5)
			(island_removal_mode 0)
		)
		(polygon
			(pts
				(arc
					(start 372.961154 -393.69238)
					(mid 372.580154 -393.69238)
					(end 372.961154 -393.69238)
				)
			)
		)
	)
	(zone
		(layer "In1.Cu")
		(hatch none 0.5)
		(connect_pads
			(clearance 0)
		)
		(min_thickness 0.25)
		(keepout
			(tracks not_allowed)
			(vias allowed)
			(pads allowed)
			(copperpour not_allowed)
			(footprints allowed)
		)
		(placement
			(enabled no)
			(sheetname "")
		)
		(fill
			(thermal_gap 0.5)
			(thermal_bridge_width 0.5)
			(island_removal_mode 0)
		)
		(polygon
			(pts
				(arc
					(start 184.365392 -308.082442)
					(mid 184.361672 -308.091422)
					(end 184.352692 -308.095142)
				)
				(arc
					(start 182.879492 -308.095142)
					(mid 182.870512 -308.091422)
					(end 182.866792 -308.082442)
				)
				(arc
					(start 182.866792 -307.587904)
					(mid 182.870512 -307.578924)
					(end 182.879492 -307.575204)
				)
				(arc
					(start 184.352692 -307.575204)
					(mid 184.361672 -307.578924)
					(end 184.365392 -307.587904)
				)
			)
		)
	)
	(zone
		(layer "In1.Cu")
		(hatch none 0.5)
		(connect_pads
			(clearance 0)
		)
		(min_thickness 0.25)
		(keepout
			(tracks not_allowed)
			(vias allowed)
			(pads allowed)
			(copperpour not_allowed)
			(footprints allowed)
		)
		(placement
			(enabled no)
			(sheetname "")
		)
		(fill
			(thermal_gap 0.5)
			(thermal_bridge_width 0.5)
			(island_removal_mode 0)
		)
		(polygon
			(pts
				(arc
					(start 89.988898 -386.003292)
					(mid 89.607898 -386.003292)
					(end 89.988898 -386.003292)
				)
			)
		)
	)
	(zone
		(layer "In1.Cu")
		(hatch none 0.5)
		(connect_pads
			(clearance 0)
		)
		(min_thickness 0.25)
		(keepout
			(tracks not_allowed)
			(vias allowed)
			(pads allowed)
			(copperpour not_allowed)
			(footprints allowed)
		)
		(placement
			(enabled no)
			(sheetname "")
		)
		(fill
			(thermal_gap 0.5)
			(thermal_bridge_width 0.5)
			(island_removal_mode 0)
		)
		(polygon
			(pts
				(arc
					(start 56.077358 -241.782346)
					(mid 56.073638 -241.791326)
					(end 56.064658 -241.795046)
				)
				(arc
					(start 54.591458 -241.795046)
					(mid 54.582478 -241.791326)
					(end 54.578758 -241.782346)
				)
				(arc
					(start 54.578758 -241.287808)
					(mid 54.582478 -241.278828)
					(end 54.591458 -241.275108)
				)
				(arc
					(start 56.064658 -241.275108)
					(mid 56.073638 -241.278828)
					(end 56.077358 -241.287808)
				)
			)
		)
	)
	(zone
		(layer "In1.Cu")
		(hatch none 0.5)
		(connect_pads
			(clearance 0)
		)
		(min_thickness 0.25)
		(keepout
			(tracks not_allowed)
			(vias allowed)
			(pads allowed)
			(copperpour not_allowed)
			(footprints allowed)
		)
		(placement
			(enabled no)
			(sheetname "")
		)
		(fill
			(thermal_gap 0.5)
			(thermal_bridge_width 0.5)
			(island_removal_mode 0)
		)
		(polygon
			(pts
				(arc
					(start 56.077358 -246.882412)
					(mid 56.073638 -246.891392)
					(end 56.064658 -246.895112)
				)
				(arc
					(start 54.591458 -246.895112)
					(mid 54.582478 -246.891392)
					(end 54.578758 -246.882412)
				)
				(arc
					(start 54.578758 -246.387874)
					(mid 54.582478 -246.378894)
					(end 54.591458 -246.375174)
				)
				(arc
					(start 56.064658 -246.375174)
					(mid 56.073638 -246.378894)
					(end 56.077358 -246.387874)
				)
			)
		)
	)
	(zone
		(layer "In1.Cu")
		(hatch none 0.5)
		(connect_pads
			(clearance 0)
		)
		(min_thickness 0.25)
		(keepout
			(tracks not_allowed)
			(vias allowed)
			(pads allowed)
			(copperpour not_allowed)
			(footprints allowed)
		)
		(placement
			(enabled no)
			(sheetname "")
		)
		(fill
			(thermal_gap 0.5)
			(thermal_bridge_width 0.5)
			(island_removal_mode 0)
		)
		(polygon
			(pts
				(arc
					(start 417.217352 -285.982156)
					(mid 417.213632 -285.991136)
					(end 417.204652 -285.994856)
				)
				(arc
					(start 415.731452 -285.994856)
					(mid 415.722472 -285.991136)
					(end 415.718752 -285.982156)
				)
				(arc
					(start 415.718752 -285.487618)
					(mid 415.722472 -285.478638)
					(end 415.731452 -285.474918)
				)
				(arc
					(start 417.204652 -285.474918)
					(mid 417.213632 -285.478638)
					(end 417.217352 -285.487618)
				)
			)
		)
	)
	(zone
		(layer "In1.Cu")
		(hatch none 0.5)
		(connect_pads
			(clearance 0)
		)
		(min_thickness 0.25)
		(keepout
			(tracks not_allowed)
			(vias allowed)
			(pads allowed)
			(copperpour not_allowed)
			(footprints allowed)
		)
		(placement
			(enabled no)
			(sheetname "")
		)
		(fill
			(thermal_gap 0.5)
			(thermal_bridge_width 0.5)
			(island_removal_mode 0)
		)
		(polygon
			(pts
				(arc
					(start 169.277284 -269.832582)
					(mid 169.273564 -269.841562)
					(end 169.264584 -269.845282)
				)
				(arc
					(start 167.791384 -269.845282)
					(mid 167.782404 -269.841562)
					(end 167.778684 -269.832582)
				)
				(arc
					(start 167.778684 -269.338044)
					(mid 167.782404 -269.329064)
					(end 167.791384 -269.325344)
				)
				(arc
					(start 169.264584 -269.325344)
					(mid 169.273564 -269.329064)
					(end 169.277284 -269.338044)
				)
			)
		)
	)
	(zone
		(layer "In1.Cu")
		(hatch none 0.5)
		(connect_pads
			(clearance 0)
		)
		(min_thickness 0.25)
		(keepout
			(tracks not_allowed)
			(vias allowed)
			(pads allowed)
			(copperpour not_allowed)
			(footprints allowed)
		)
		(placement
			(enabled no)
			(sheetname "")
		)
		(fill
			(thermal_gap 0.5)
			(thermal_bridge_width 0.5)
			(island_removal_mode 0)
		)
		(polygon
			(pts
				(arc
					(start 172.72127 -232.432352)
					(mid 172.71755 -232.441332)
					(end 172.70857 -232.445052)
				)
				(arc
					(start 171.23537 -232.445052)
					(mid 171.22639 -232.441332)
					(end 171.22267 -232.432352)
				)
				(arc
					(start 171.22267 -231.937814)
					(mid 171.22639 -231.928834)
					(end 171.23537 -231.925114)
				)
				(arc
					(start 172.70857 -231.925114)
					(mid 172.71755 -231.928834)
					(end 172.72127 -231.937814)
				)
			)
		)
	)
	(zone
		(layer "In1.Cu")
		(hatch none 0.5)
		(connect_pads
			(clearance 0)
		)
		(min_thickness 0.25)
		(keepout
			(tracks not_allowed)
			(vias allowed)
			(pads allowed)
			(copperpour not_allowed)
			(footprints allowed)
		)
		(placement
			(enabled no)
			(sheetname "")
		)
		(fill
			(thermal_gap 0.5)
			(thermal_bridge_width 0.5)
			(island_removal_mode 0)
		)
		(polygon
			(pts
				(arc
					(start 411.888686 -397.849344)
					(mid 411.507686 -397.849344)
					(end 411.888686 -397.849344)
				)
			)
		)
	)
	(zone
		(layer "In1.Cu")
		(hatch none 0.5)
		(connect_pads
			(clearance 0)
		)
		(min_thickness 0.25)
		(keepout
			(tracks not_allowed)
			(vias allowed)
			(pads allowed)
			(copperpour not_allowed)
			(footprints allowed)
		)
		(placement
			(enabled no)
			(sheetname "")
		)
		(fill
			(thermal_gap 0.5)
			(thermal_bridge_width 0.5)
			(island_removal_mode 0)
		)
		(polygon
			(pts
				(arc
					(start 33.445196 -310.632348)
					(mid 33.441476 -310.641328)
					(end 33.432496 -310.645048)
				)
				(arc
					(start 31.959296 -310.645048)
					(mid 31.950316 -310.641328)
					(end 31.946596 -310.632348)
				)
				(arc
					(start 31.946596 -310.13781)
					(mid 31.950316 -310.12883)
					(end 31.959296 -310.12511)
				)
				(arc
					(start 33.432496 -310.12511)
					(mid 33.441476 -310.12883)
					(end 33.445196 -310.13781)
				)
			)
		)
	)
	(zone
		(layer "In1.Cu")
		(hatch none 0.5)
		(connect_pads
			(clearance 0)
		)
		(min_thickness 0.25)
		(keepout
			(tracks not_allowed)
			(vias allowed)
			(pads allowed)
			(copperpour not_allowed)
			(footprints allowed)
		)
		(placement
			(enabled no)
			(sheetname "")
		)
		(fill
			(thermal_gap 0.5)
			(thermal_bridge_width 0.5)
			(island_removal_mode 0)
		)
		(polygon
			(pts
				(arc
					(start 270.397478 -272.382234)
					(mid 270.393758 -272.391214)
					(end 270.384778 -272.394934)
				)
				(arc
					(start 268.911578 -272.394934)
					(mid 268.902598 -272.391214)
					(end 268.898878 -272.382234)
				)
				(arc
					(start 268.898878 -271.887696)
					(mid 268.902598 -271.878716)
					(end 268.911578 -271.874996)
				)
				(arc
					(start 270.384778 -271.874996)
					(mid 270.393758 -271.878716)
					(end 270.397478 -271.887696)
				)
			)
		)
	)
	(zone
		(layer "In1.Cu")
		(hatch none 0.5)
		(connect_pads
			(clearance 0)
		)
		(min_thickness 0.25)
		(keepout
			(tracks not_allowed)
			(vias allowed)
			(pads allowed)
			(copperpour not_allowed)
			(footprints allowed)
		)
		(placement
			(enabled no)
			(sheetname "")
		)
		(fill
			(thermal_gap 0.5)
			(thermal_bridge_width 0.5)
			(island_removal_mode 0)
		)
		(polygon
			(pts
				(arc
					(start 308.117494 -251.132086)
					(mid 308.113774 -251.141066)
					(end 308.104794 -251.144786)
				)
				(arc
					(start 306.631594 -251.144786)
					(mid 306.622614 -251.141066)
					(end 306.618894 -251.132086)
				)
				(arc
					(start 306.618894 -250.637548)
					(mid 306.622614 -250.628568)
					(end 306.631594 -250.624848)
				)
				(arc
					(start 308.104794 -250.624848)
					(mid 308.113774 -250.628568)
					(end 308.117494 -250.637548)
				)
			)
		)
	)
	(zone
		(layer "In1.Cu")
		(hatch none 0.5)
		(connect_pads
			(clearance 0)
		)
		(min_thickness 0.25)
		(keepout
			(tracks not_allowed)
			(vias allowed)
			(pads allowed)
			(copperpour not_allowed)
			(footprints allowed)
		)
		(placement
			(enabled no)
			(sheetname "")
		)
		(fill
			(thermal_gap 0.5)
			(thermal_bridge_width 0.5)
			(island_removal_mode 0)
		)
		(polygon
			(pts
				(arc
					(start 308.117494 -264.732262)
					(mid 308.113774 -264.741242)
					(end 308.104794 -264.744962)
				)
				(arc
					(start 306.631594 -264.744962)
					(mid 306.622614 -264.741242)
					(end 306.618894 -264.732262)
				)
				(arc
					(start 306.618894 -264.237724)
					(mid 306.622614 -264.228744)
					(end 306.631594 -264.225024)
				)
				(arc
					(start 308.104794 -264.225024)
					(mid 308.113774 -264.228744)
					(end 308.117494 -264.237724)
				)
			)
		)
	)
	(zone
		(layer "In1.Cu")
		(hatch none 0.5)
		(connect_pads
			(clearance 0)
		)
		(min_thickness 0.25)
		(keepout
			(tracks not_allowed)
			(vias allowed)
			(pads allowed)
			(copperpour not_allowed)
			(footprints allowed)
		)
		(placement
			(enabled no)
			(sheetname "")
		)
		(fill
			(thermal_gap 0.5)
			(thermal_bridge_width 0.5)
			(island_removal_mode 0)
		)
		(polygon
			(pts
				(arc
					(start 418.21862 -391.822686)
					(mid 418.34562 -391.949686)
					(end 418.47262 -391.822686)
				)
				(arc
					(start 418.47262 -391.746486)
					(mid 418.34562 -391.619486)
					(end 418.21862 -391.746486)
				)
			)
		)
	)
	(zone
		(layer "In1.Cu")
		(hatch none 0.5)
		(connect_pads
			(clearance 0)
		)
		(min_thickness 0.25)
		(keepout
			(tracks not_allowed)
			(vias allowed)
			(pads allowed)
			(copperpour not_allowed)
			(footprints allowed)
		)
		(placement
			(enabled no)
			(sheetname "")
		)
		(fill
			(thermal_gap 0.5)
			(thermal_bridge_width 0.5)
			(island_removal_mode 0)
		)
		(polygon
			(pts
				(arc
					(start 169.277284 -304.682398)
					(mid 169.273564 -304.691378)
					(end 169.264584 -304.695098)
				)
				(arc
					(start 167.791384 -304.695098)
					(mid 167.782404 -304.691378)
					(end 167.778684 -304.682398)
				)
				(arc
					(start 167.778684 -304.18786)
					(mid 167.782404 -304.17888)
					(end 167.791384 -304.17516)
				)
				(arc
					(start 169.264584 -304.17516)
					(mid 169.273564 -304.17888)
					(end 169.277284 -304.18786)
				)
			)
		)
	)
	(zone
		(layer "In1.Cu")
		(hatch none 0.5)
		(connect_pads
			(clearance 0)
		)
		(min_thickness 0.25)
		(keepout
			(tracks not_allowed)
			(vias allowed)
			(pads allowed)
			(copperpour not_allowed)
			(footprints allowed)
		)
		(placement
			(enabled no)
			(sheetname "")
		)
		(fill
			(thermal_gap 0.5)
			(thermal_bridge_width 0.5)
			(island_removal_mode 0)
		)
		(polygon
			(pts
				(arc
					(start 439.849514 -315.73216)
					(mid 439.845794 -315.74114)
					(end 439.836814 -315.74486)
				)
				(arc
					(start 438.363614 -315.74486)
					(mid 438.354634 -315.74114)
					(end 438.350914 -315.73216)
				)
				(arc
					(start 438.350914 -315.237622)
					(mid 438.354634 -315.228642)
					(end 438.363614 -315.224922)
				)
				(arc
					(start 439.836814 -315.224922)
					(mid 439.845794 -315.228642)
					(end 439.849514 -315.237622)
				)
			)
		)
	)
	(zone
		(layer "In1.Cu")
		(hatch none 0.5)
		(connect_pads
			(clearance 0)
		)
		(min_thickness 0.25)
		(keepout
			(tracks not_allowed)
			(vias allowed)
			(pads allowed)
			(copperpour not_allowed)
			(footprints allowed)
		)
		(placement
			(enabled no)
			(sheetname "")
		)
		(fill
			(thermal_gap 0.5)
			(thermal_bridge_width 0.5)
			(island_removal_mode 0)
		)
		(polygon
			(pts
				(arc
					(start 450.8373 -230.73233)
					(mid 450.83358 -230.74131)
					(end 450.8246 -230.74503)
				)
				(arc
					(start 449.3514 -230.74503)
					(mid 449.34242 -230.74131)
					(end 449.3387 -230.73233)
				)
				(arc
					(start 449.3387 -230.237792)
					(mid 449.34242 -230.228812)
					(end 449.3514 -230.225092)
				)
				(arc
					(start 450.8246 -230.225092)
					(mid 450.83358 -230.228812)
					(end 450.8373 -230.237792)
				)
			)
		)
	)
	(zone
		(layer "In1.Cu")
		(hatch none 0.5)
		(connect_pads
			(clearance 0)
		)
		(min_thickness 0.25)
		(keepout
			(tracks not_allowed)
			(vias allowed)
			(pads allowed)
			(copperpour not_allowed)
			(footprints allowed)
		)
		(placement
			(enabled no)
			(sheetname "")
		)
		(fill
			(thermal_gap 0.5)
			(thermal_bridge_width 0.5)
			(island_removal_mode 0)
		)
		(polygon
			(pts
				(arc
					(start 281.385264 -295.33215)
					(mid 281.381544 -295.34113)
					(end 281.372564 -295.34485)
				)
				(arc
					(start 279.899364 -295.34485)
					(mid 279.890384 -295.34113)
					(end 279.886664 -295.33215)
				)
				(arc
					(start 279.886664 -294.837612)
					(mid 279.890384 -294.828632)
					(end 279.899364 -294.824912)
				)
				(arc
					(start 281.372564 -294.824912)
					(mid 281.381544 -294.828632)
					(end 281.385264 -294.837612)
				)
			)
		)
	)
	(zone
		(layer "In1.Cu")
		(hatch none 0.5)
		(connect_pads
			(clearance 0)
		)
		(min_thickness 0.25)
		(keepout
			(tracks not_allowed)
			(vias allowed)
			(pads allowed)
			(copperpour not_allowed)
			(footprints allowed)
		)
		(placement
			(enabled no)
			(sheetname "")
		)
		(fill
			(thermal_gap 0.5)
			(thermal_bridge_width 0.5)
			(island_removal_mode 0)
		)
		(polygon
			(pts
				(arc
					(start 308.117494 -309.78221)
					(mid 308.113774 -309.79119)
					(end 308.104794 -309.79491)
				)
				(arc
					(start 306.631594 -309.79491)
					(mid 306.622614 -309.79119)
					(end 306.618894 -309.78221)
				)
				(arc
					(start 306.618894 -309.287672)
					(mid 306.622614 -309.278692)
					(end 306.631594 -309.274972)
				)
				(arc
					(start 308.104794 -309.274972)
					(mid 308.113774 -309.278692)
					(end 308.117494 -309.287672)
				)
			)
		)
	)
	(zone
		(layer "In1.Cu")
		(hatch none 0.5)
		(connect_pads
			(clearance 0)
		)
		(min_thickness 0.25)
		(keepout
			(tracks not_allowed)
			(vias allowed)
			(pads allowed)
			(copperpour not_allowed)
			(footprints allowed)
		)
		(placement
			(enabled no)
			(sheetname "")
		)
		(fill
			(thermal_gap 0.5)
			(thermal_bridge_width 0.5)
			(island_removal_mode 0)
		)
		(polygon
			(pts
				(arc
					(start 424.761406 -219.682314)
					(mid 424.757686 -219.691294)
					(end 424.748706 -219.695014)
				)
				(arc
					(start 423.275506 -219.695014)
					(mid 423.266526 -219.691294)
					(end 423.262806 -219.682314)
				)
				(arc
					(start 423.262806 -219.187776)
					(mid 423.266526 -219.178796)
					(end 423.275506 -219.175076)
				)
				(arc
					(start 424.748706 -219.175076)
					(mid 424.757686 -219.178796)
					(end 424.761406 -219.187776)
				)
			)
		)
	)
	(zone
		(layer "In1.Cu")
		(hatch none 0.5)
		(connect_pads
			(clearance 0)
		)
		(min_thickness 0.25)
		(keepout
			(tracks not_allowed)
			(vias allowed)
			(pads allowed)
			(copperpour not_allowed)
			(footprints allowed)
		)
		(placement
			(enabled no)
			(sheetname "")
		)
		(fill
			(thermal_gap 0.5)
			(thermal_bridge_width 0.5)
			(island_removal_mode 0)
		)
		(polygon
			(pts
				(arc
					(start 435.749446 -213.73211)
					(mid 435.745726 -213.74109)
					(end 435.736746 -213.74481)
				)
				(arc
					(start 434.263546 -213.74481)
					(mid 434.254566 -213.74109)
					(end 434.250846 -213.73211)
				)
				(arc
					(start 434.250846 -213.237572)
					(mid 434.254566 -213.228592)
					(end 434.263546 -213.224872)
				)
				(arc
					(start 435.736746 -213.224872)
					(mid 435.745726 -213.228592)
					(end 435.749446 -213.237572)
				)
			)
		)
	)
	(zone
		(layer "In1.Cu")
		(hatch none 0.5)
		(connect_pads
			(clearance 0)
		)
		(min_thickness 0.25)
		(keepout
			(tracks not_allowed)
			(vias allowed)
			(pads allowed)
			(copperpour not_allowed)
			(footprints allowed)
		)
		(placement
			(enabled no)
			(sheetname "")
		)
		(fill
			(thermal_gap 0.5)
			(thermal_bridge_width 0.5)
			(island_removal_mode 0)
		)
		(polygon
			(pts
				(arc
					(start 95.988886 -386.003292)
					(mid 95.607886 -386.003292)
					(end 95.988886 -386.003292)
				)
			)
		)
	)
	(zone
		(layer "In1.Cu")
		(hatch none 0.5)
		(connect_pads
			(clearance 0)
		)
		(min_thickness 0.25)
		(keepout
			(tracks not_allowed)
			(vias allowed)
			(pads allowed)
			(copperpour not_allowed)
			(footprints allowed)
		)
		(placement
			(enabled no)
			(sheetname "")
		)
		(fill
			(thermal_gap 0.5)
			(thermal_bridge_width 0.5)
			(island_removal_mode 0)
		)
		(polygon
			(pts
				(arc
					(start 296.473372 -237.532164)
					(mid 296.469652 -237.541144)
					(end 296.460672 -237.544864)
				)
				(arc
					(start 294.987472 -237.544864)
					(mid 294.978492 -237.541144)
					(end 294.974772 -237.532164)
				)
				(arc
					(start 294.974772 -237.037626)
					(mid 294.978492 -237.028646)
					(end 294.987472 -237.024926)
				)
				(arc
					(start 296.460672 -237.024926)
					(mid 296.469652 -237.028646)
					(end 296.473372 -237.037626)
				)
			)
		)
	)
	(zone
		(layer "In1.Cu")
		(hatch none 0.5)
		(connect_pads
			(clearance 0)
		)
		(min_thickness 0.25)
		(keepout
			(tracks not_allowed)
			(vias allowed)
			(pads allowed)
			(copperpour not_allowed)
			(footprints allowed)
		)
		(placement
			(enabled no)
			(sheetname "")
		)
		(fill
			(thermal_gap 0.5)
			(thermal_bridge_width 0.5)
			(island_removal_mode 0)
		)
		(polygon
			(pts
				(arc
					(start 407.998168 -392.30427)
					(mid 407.693368 -392.30427)
					(end 407.998168 -392.30427)
				)
			)
		)
	)
	(zone
		(layer "In1.Cu")
		(hatch none 0.5)
		(connect_pads
			(clearance 0)
		)
		(min_thickness 0.25)
		(keepout
			(tracks not_allowed)
			(vias allowed)
			(pads allowed)
			(copperpour not_allowed)
			(footprints allowed)
		)
		(placement
			(enabled no)
			(sheetname "")
		)
		(fill
			(thermal_gap 0.5)
			(thermal_bridge_width 0.5)
			(island_removal_mode 0)
		)
		(polygon
			(pts
				(arc
					(start 169.277284 -220.532452)
					(mid 169.273564 -220.541432)
					(end 169.264584 -220.545152)
				)
				(arc
					(start 167.791384 -220.545152)
					(mid 167.782404 -220.541432)
					(end 167.778684 -220.532452)
				)
				(arc
					(start 167.778684 -220.037914)
					(mid 167.782404 -220.028934)
					(end 167.791384 -220.025214)
				)
				(arc
					(start 169.264584 -220.025214)
					(mid 169.273564 -220.028934)
					(end 169.277284 -220.037914)
				)
			)
		)
	)
	(zone
		(layer "In1.Cu")
		(hatch none 0.5)
		(connect_pads
			(clearance 0)
		)
		(min_thickness 0.25)
		(keepout
			(tracks not_allowed)
			(vias allowed)
			(pads allowed)
			(copperpour not_allowed)
			(footprints allowed)
		)
		(placement
			(enabled no)
			(sheetname "")
		)
		(fill
			(thermal_gap 0.5)
			(thermal_bridge_width 0.5)
			(island_removal_mode 0)
		)
		(polygon
			(pts
				(arc
					(start 304.017426 -218.832176)
					(mid 304.013706 -218.841156)
					(end 304.004726 -218.844876)
				)
				(arc
					(start 302.531526 -218.844876)
					(mid 302.522546 -218.841156)
					(end 302.518826 -218.832176)
				)
				(arc
					(start 302.518826 -218.337638)
					(mid 302.522546 -218.328658)
					(end 302.531526 -218.324938)
				)
				(arc
					(start 304.004726 -218.324938)
					(mid 304.013706 -218.328658)
					(end 304.017426 -218.337638)
				)
			)
		)
	)
	(zone
		(layer "In1.Cu")
		(hatch none 0.5)
		(connect_pads
			(clearance 0)
		)
		(min_thickness 0.25)
		(keepout
			(tracks not_allowed)
			(vias allowed)
			(pads allowed)
			(copperpour not_allowed)
			(footprints allowed)
		)
		(placement
			(enabled no)
			(sheetname "")
		)
		(fill
			(thermal_gap 0.5)
			(thermal_bridge_width 0.5)
			(island_removal_mode 0)
		)
		(polygon
			(pts
				(arc
					(start 206.5782 -200.735438)
					(mid 205.9178 -200.735438)
					(end 206.5782 -200.735438)
				)
			)
		)
	)
	(zone
		(layer "In1.Cu")
		(hatch none 0.5)
		(connect_pads
			(clearance 0)
		)
		(min_thickness 0.25)
		(keepout
			(tracks not_allowed)
			(vias allowed)
			(pads allowed)
			(copperpour not_allowed)
			(footprints allowed)
		)
		(placement
			(enabled no)
			(sheetname "")
		)
		(fill
			(thermal_gap 0.5)
			(thermal_bridge_width 0.5)
			(island_removal_mode 0)
		)
		(polygon
			(pts
				(arc
					(start 55.861204 -385.31038)
					(mid 55.480204 -385.31038)
					(end 55.861204 -385.31038)
				)
			)
		)
	)
	(zone
		(layer "In1.Cu")
		(hatch none 0.5)
		(connect_pads
			(clearance 0)
		)
		(min_thickness 0.25)
		(keepout
			(tracks not_allowed)
			(vias allowed)
			(pads allowed)
			(copperpour not_allowed)
			(footprints allowed)
		)
		(placement
			(enabled no)
			(sheetname "")
		)
		(fill
			(thermal_gap 0.5)
			(thermal_bridge_width 0.5)
			(island_removal_mode 0)
		)
		(polygon
			(pts
				(arc
					(start 32.079692 -16.443198)
					(mid 32.10201 -16.49708)
					(end 32.155892 -16.519398)
				)
				(arc
					(start 32.351472 -16.519398)
					(mid 32.373348 -16.516266)
					(end 32.393382 -16.506952)
				)
				(arc
					(start 32.687006 -16.31442)
					(mid 32.728662 -16.302018)
					(end 32.770318 -16.31442)
				)
				(arc
					(start 33.065212 -16.506952)
					(mid 33.085136 -16.516188)
					(end 33.106868 -16.519398)
				)
				(arc
					(start 33.301432 -16.519398)
					(mid 33.355314 -16.49708)
					(end 33.377632 -16.443198)
				)
				(arc
					(start 33.377632 -15.757398)
					(mid 33.355314 -15.703516)
					(end 33.301432 -15.681198)
				)
				(arc
					(start 33.106868 -15.681198)
					(mid 33.085124 -15.684366)
					(end 33.065212 -15.693644)
				)
				(arc
					(start 32.769048 -15.88643)
					(mid 32.727364 -15.898652)
					(end 32.685736 -15.886176)
				)
				(arc
					(start 32.392112 -15.693644)
					(mid 32.372188 -15.684408)
					(end 32.350456 -15.681198)
				)
				(arc
					(start 32.155892 -15.681198)
					(mid 32.10201 -15.703516)
					(end 32.079692 -15.757398)
				)
			)
		)
	)
	(zone
		(layer "In1.Cu")
		(hatch none 0.5)
		(connect_pads
			(clearance 0)
		)
		(min_thickness 0.25)
		(keepout
			(tracks not_allowed)
			(vias allowed)
			(pads allowed)
			(copperpour not_allowed)
			(footprints allowed)
		)
		(placement
			(enabled no)
			(sheetname "")
		)
		(fill
			(thermal_gap 0.5)
			(thermal_bridge_width 0.5)
			(island_removal_mode 0)
		)
		(polygon
			(pts
				(arc
					(start 293.029386 -211.182204)
					(mid 293.025666 -211.191184)
					(end 293.016686 -211.194904)
				)
				(arc
					(start 291.543486 -211.194904)
					(mid 291.534506 -211.191184)
					(end 291.530786 -211.182204)
				)
				(arc
					(start 291.530786 -210.687666)
					(mid 291.534506 -210.678686)
					(end 291.543486 -210.674966)
				)
				(arc
					(start 293.016686 -210.674966)
					(mid 293.025666 -210.678686)
					(end 293.029386 -210.687666)
				)
			)
		)
	)
	(zone
		(layer "In1.Cu")
		(hatch none 0.5)
		(connect_pads
			(clearance 0)
		)
		(min_thickness 0.25)
		(keepout
			(tracks not_allowed)
			(vias allowed)
			(pads allowed)
			(copperpour not_allowed)
			(footprints allowed)
		)
		(placement
			(enabled no)
			(sheetname "")
		)
		(fill
			(thermal_gap 0.5)
			(thermal_bridge_width 0.5)
			(island_removal_mode 0)
		)
		(polygon
			(pts
				(arc
					(start 300.57344 -246.032274)
					(mid 300.56972 -246.041254)
					(end 300.56074 -246.044974)
				)
				(arc
					(start 299.08754 -246.044974)
					(mid 299.07856 -246.041254)
					(end 299.07484 -246.032274)
				)
				(arc
					(start 299.07484 -245.537736)
					(mid 299.07856 -245.528756)
					(end 299.08754 -245.525036)
				)
				(arc
					(start 300.56074 -245.525036)
					(mid 300.56972 -245.528756)
					(end 300.57344 -245.537736)
				)
			)
		)
	)
	(zone
		(layer "In1.Cu")
		(hatch none 0.5)
		(connect_pads
			(clearance 0)
		)
		(min_thickness 0.25)
		(keepout
			(tracks not_allowed)
			(vias allowed)
			(pads allowed)
			(copperpour not_allowed)
			(footprints allowed)
		)
		(placement
			(enabled no)
			(sheetname "")
		)
		(fill
			(thermal_gap 0.5)
			(thermal_bridge_width 0.5)
			(island_removal_mode 0)
		)
		(polygon
			(pts
				(arc
					(start 308.117494 -239.232186)
					(mid 308.113774 -239.241166)
					(end 308.104794 -239.244886)
				)
				(arc
					(start 306.631594 -239.244886)
					(mid 306.622614 -239.241166)
					(end 306.618894 -239.232186)
				)
				(arc
					(start 306.618894 -238.737648)
					(mid 306.622614 -238.728668)
					(end 306.631594 -238.724948)
				)
				(arc
					(start 308.104794 -238.724948)
					(mid 308.113774 -238.728668)
					(end 308.117494 -238.737648)
				)
			)
		)
	)
	(zone
		(layer "In1.Cu")
		(hatch none 0.5)
		(connect_pads
			(clearance 0)
		)
		(min_thickness 0.25)
		(keepout
			(tracks not_allowed)
			(vias allowed)
			(pads allowed)
			(copperpour not_allowed)
			(footprints allowed)
		)
		(placement
			(enabled no)
			(sheetname "")
		)
		(fill
			(thermal_gap 0.5)
			(thermal_bridge_width 0.5)
			(island_removal_mode 0)
		)
		(polygon
			(pts
				(arc
					(start 56.077358 -305.532536)
					(mid 56.073638 -305.541516)
					(end 56.064658 -305.545236)
				)
				(arc
					(start 54.591458 -305.545236)
					(mid 54.582478 -305.541516)
					(end 54.578758 -305.532536)
				)
				(arc
					(start 54.578758 -305.037998)
					(mid 54.582478 -305.029018)
					(end 54.591458 -305.025298)
				)
				(arc
					(start 56.064658 -305.025298)
					(mid 56.073638 -305.029018)
					(end 56.077358 -305.037998)
				)
			)
		)
	)
	(zone
		(layer "In1.Cu")
		(hatch none 0.5)
		(connect_pads
			(clearance 0)
		)
		(min_thickness 0.25)
		(keepout
			(tracks not_allowed)
			(vias allowed)
			(pads allowed)
			(copperpour not_allowed)
			(footprints allowed)
		)
		(placement
			(enabled no)
			(sheetname "")
		)
		(fill
			(thermal_gap 0.5)
			(thermal_bridge_width 0.5)
			(island_removal_mode 0)
		)
		(polygon
			(pts
				(arc
					(start 165.177216 -280.882344)
					(mid 165.173496 -280.891324)
					(end 165.164516 -280.895044)
				)
				(arc
					(start 163.691316 -280.895044)
					(mid 163.682336 -280.891324)
					(end 163.678616 -280.882344)
				)
				(arc
					(start 163.678616 -280.387806)
					(mid 163.682336 -280.378826)
					(end 163.691316 -280.375106)
				)
				(arc
					(start 165.164516 -280.375106)
					(mid 165.173496 -280.378826)
					(end 165.177216 -280.387806)
				)
			)
		)
	)
	(zone
		(layer "In1.Cu")
		(hatch none 0.5)
		(connect_pads
			(clearance 0)
		)
		(min_thickness 0.25)
		(keepout
			(tracks not_allowed)
			(vias allowed)
			(pads allowed)
			(copperpour not_allowed)
			(footprints allowed)
		)
		(placement
			(enabled no)
			(sheetname "")
		)
		(fill
			(thermal_gap 0.5)
			(thermal_bridge_width 0.5)
			(island_removal_mode 0)
		)
		(polygon
			(pts
				(arc
					(start 89.589102 -388.774432)
					(mid 89.208102 -388.774432)
					(end 89.589102 -388.774432)
				)
			)
		)
	)
	(zone
		(layer "In1.Cu")
		(hatch none 0.5)
		(connect_pads
			(clearance 0)
		)
		(min_thickness 0.25)
		(keepout
			(tracks not_allowed)
			(vias allowed)
			(pads allowed)
			(copperpour not_allowed)
			(footprints allowed)
		)
		(placement
			(enabled no)
			(sheetname "")
		)
		(fill
			(thermal_gap 0.5)
			(thermal_bridge_width 0.5)
			(island_removal_mode 0)
		)
		(polygon
			(pts
				(arc
					(start 55.061104 -389.467344)
					(mid 54.680104 -389.467344)
					(end 55.061104 -389.467344)
				)
			)
		)
	)
	(zone
		(layer "In1.Cu")
		(hatch none 0.5)
		(connect_pads
			(clearance 0)
		)
		(min_thickness 0.25)
		(keepout
			(tracks not_allowed)
			(vias allowed)
			(pads allowed)
			(copperpour not_allowed)
			(footprints allowed)
		)
		(placement
			(enabled no)
			(sheetname "")
		)
		(fill
			(thermal_gap 0.5)
			(thermal_bridge_width 0.5)
			(island_removal_mode 0)
		)
		(polygon
			(pts
				(arc
					(start 377.291092 -391.822686)
					(mid 377.418092 -391.949686)
					(end 377.545092 -391.822686)
				)
				(arc
					(start 377.545092 -391.746486)
					(mid 377.418092 -391.619486)
					(end 377.291092 -391.746486)
				)
			)
		)
	)
	(zone
		(layer "In1.Cu")
		(hatch none 0.5)
		(connect_pads
			(clearance 0)
		)
		(min_thickness 0.25)
		(keepout
			(tracks not_allowed)
			(vias allowed)
			(pads allowed)
			(copperpour not_allowed)
			(footprints allowed)
		)
		(placement
			(enabled no)
			(sheetname "")
		)
		(fill
			(thermal_gap 0.5)
			(thermal_bridge_width 0.5)
			(island_removal_mode 0)
		)
		(polygon
			(pts
				(arc
					(start 172.72127 -308.93258)
					(mid 172.71755 -308.94156)
					(end 172.70857 -308.94528)
				)
				(arc
					(start 171.23537 -308.94528)
					(mid 171.22639 -308.94156)
					(end 171.22267 -308.93258)
				)
				(arc
					(start 171.22267 -308.438042)
					(mid 171.22639 -308.429062)
					(end 171.23537 -308.425342)
				)
				(arc
					(start 172.70857 -308.425342)
					(mid 172.71755 -308.429062)
					(end 172.72127 -308.438042)
				)
			)
		)
	)
	(zone
		(layer "In1.Cu")
		(hatch none 0.5)
		(connect_pads
			(clearance 0)
		)
		(min_thickness 0.25)
		(keepout
			(tracks not_allowed)
			(vias allowed)
			(pads allowed)
			(copperpour not_allowed)
			(footprints allowed)
		)
		(placement
			(enabled no)
			(sheetname "")
		)
		(fill
			(thermal_gap 0.5)
			(thermal_bridge_width 0.5)
			(island_removal_mode 0)
		)
		(polygon
			(pts
				(arc
					(start 45.089318 -227.33254)
					(mid 45.085598 -227.34152)
					(end 45.076618 -227.34524)
				)
				(arc
					(start 43.603418 -227.34524)
					(mid 43.594438 -227.34152)
					(end 43.590718 -227.33254)
				)
				(arc
					(start 43.590718 -226.838002)
					(mid 43.594438 -226.829022)
					(end 43.603418 -226.825302)
				)
				(arc
					(start 45.076618 -226.825302)
					(mid 45.085598 -226.829022)
					(end 45.089318 -226.838002)
				)
			)
		)
	)
	(zone
		(layer "In1.Cu")
		(hatch none 0.5)
		(connect_pads
			(clearance 0)
		)
		(min_thickness 0.25)
		(keepout
			(tracks not_allowed)
			(vias allowed)
			(pads allowed)
			(copperpour not_allowed)
			(footprints allowed)
		)
		(placement
			(enabled no)
			(sheetname "")
		)
		(fill
			(thermal_gap 0.5)
			(thermal_bridge_width 0.5)
			(island_removal_mode 0)
		)
		(polygon
			(pts
				(arc
					(start 139.15517 -15.90294)
					(mid 139.177488 -15.849058)
					(end 139.23137 -15.82674)
				)
				(arc
					(start 140.059918 -15.82674)
					(mid 140.1138 -15.849058)
					(end 140.136118 -15.90294)
				)
				(arc
					(start 140.136118 -17.19834)
					(mid 140.1138 -17.252222)
					(end 140.059918 -17.27454)
				)
				(arc
					(start 139.23137 -17.27454)
					(mid 139.177488 -17.252222)
					(end 139.15517 -17.19834)
				)
			)
		)
	)
	(zone
		(layer "In1.Cu")
		(hatch none 0.5)
		(connect_pads
			(clearance 0)
		)
		(min_thickness 0.25)
		(keepout
			(tracks not_allowed)
			(vias allowed)
			(pads allowed)
			(copperpour not_allowed)
			(footprints allowed)
		)
		(placement
			(enabled no)
			(sheetname "")
		)
		(fill
			(thermal_gap 0.5)
			(thermal_bridge_width 0.5)
			(island_removal_mode 0)
		)
		(polygon
			(pts
				(arc
					(start 40.98925 -286.832548)
					(mid 40.98553 -286.841528)
					(end 40.97655 -286.845248)
				)
				(arc
					(start 39.50335 -286.845248)
					(mid 39.49437 -286.841528)
					(end 39.49065 -286.832548)
				)
				(arc
					(start 39.49065 -286.33801)
					(mid 39.49437 -286.32903)
					(end 39.50335 -286.32531)
				)
				(arc
					(start 40.97655 -286.32531)
					(mid 40.98553 -286.32903)
					(end 40.98925 -286.33801)
				)
			)
		)
	)
	(zone
		(layer "In1.Cu")
		(hatch none 0.5)
		(connect_pads
			(clearance 0)
		)
		(min_thickness 0.25)
		(keepout
			(tracks not_allowed)
			(vias allowed)
			(pads allowed)
			(copperpour not_allowed)
			(footprints allowed)
		)
		(placement
			(enabled no)
			(sheetname "")
		)
		(fill
			(thermal_gap 0.5)
			(thermal_bridge_width 0.5)
			(island_removal_mode 0)
		)
		(polygon
			(pts
				(arc
					(start 265.87831 -291.684964)
					(mid 265.21791 -291.684964)
					(end 265.87831 -291.684964)
				)
			)
		)
	)
	(zone
		(layer "In1.Cu")
		(hatch none 0.5)
		(connect_pads
			(clearance 0)
		)
		(min_thickness 0.25)
		(keepout
			(tracks not_allowed)
			(vias allowed)
			(pads allowed)
			(copperpour not_allowed)
			(footprints allowed)
		)
		(placement
			(enabled no)
			(sheetname "")
		)
		(fill
			(thermal_gap 0.5)
			(thermal_bridge_width 0.5)
			(island_removal_mode 0)
		)
		(polygon
			(pts
				(arc
					(start 266.29741 -224.782126)
					(mid 266.29369 -224.791106)
					(end 266.28471 -224.794826)
				)
				(arc
					(start 264.81151 -224.794826)
					(mid 264.80253 -224.791106)
					(end 264.79881 -224.782126)
				)
				(arc
					(start 264.79881 -224.287588)
					(mid 264.80253 -224.278608)
					(end 264.81151 -224.274888)
				)
				(arc
					(start 266.28471 -224.274888)
					(mid 266.29369 -224.278608)
					(end 266.29741 -224.287588)
				)
			)
		)
	)
	(zone
		(layer "In1.Cu")
		(hatch none 0.5)
		(connect_pads
			(clearance 0)
		)
		(min_thickness 0.25)
		(keepout
			(tracks not_allowed)
			(vias allowed)
			(pads allowed)
			(copperpour not_allowed)
			(footprints allowed)
		)
		(placement
			(enabled no)
			(sheetname "")
		)
		(fill
			(thermal_gap 0.5)
			(thermal_bridge_width 0.5)
			(island_removal_mode 0)
		)
		(polygon
			(pts
				(arc
					(start 417.217352 -297.032172)
					(mid 417.213632 -297.041152)
					(end 417.204652 -297.044872)
				)
				(arc
					(start 415.731452 -297.044872)
					(mid 415.722472 -297.041152)
					(end 415.718752 -297.032172)
				)
				(arc
					(start 415.718752 -296.537634)
					(mid 415.722472 -296.528654)
					(end 415.731452 -296.524934)
				)
				(arc
					(start 417.204652 -296.524934)
					(mid 417.213632 -296.528654)
					(end 417.217352 -296.537634)
				)
			)
		)
	)
	(zone
		(layer "In1.Cu")
		(hatch none 0.5)
		(connect_pads
			(clearance 0)
		)
		(min_thickness 0.25)
		(keepout
			(tracks not_allowed)
			(vias allowed)
			(pads allowed)
			(copperpour not_allowed)
			(footprints allowed)
		)
		(placement
			(enabled no)
			(sheetname "")
		)
		(fill
			(thermal_gap 0.5)
			(thermal_bridge_width 0.5)
			(island_removal_mode 0)
		)
		(polygon
			(pts
				(arc
					(start 454.937368 -278.332184)
					(mid 454.933648 -278.341164)
					(end 454.924668 -278.344884)
				)
				(arc
					(start 453.451468 -278.344884)
					(mid 453.442488 -278.341164)
					(end 453.438768 -278.332184)
				)
				(arc
					(start 453.438768 -277.837646)
					(mid 453.442488 -277.828666)
					(end 453.451468 -277.824946)
				)
				(arc
					(start 454.924668 -277.824946)
					(mid 454.933648 -277.828666)
					(end 454.937368 -277.837646)
				)
			)
		)
	)
	(zone
		(layer "In1.Cu")
		(hatch none 0.5)
		(connect_pads
			(clearance 0)
		)
		(min_thickness 0.25)
		(keepout
			(tracks not_allowed)
			(vias allowed)
			(pads allowed)
			(copperpour not_allowed)
			(footprints allowed)
		)
		(placement
			(enabled no)
			(sheetname "")
		)
		(fill
			(thermal_gap 0.5)
			(thermal_bridge_width 0.5)
			(island_removal_mode 0)
		)
		(polygon
			(pts
				(arc
					(start 281.385264 -254.53213)
					(mid 281.381544 -254.54111)
					(end 281.372564 -254.54483)
				)
				(arc
					(start 279.899364 -254.54483)
					(mid 279.890384 -254.54111)
					(end 279.886664 -254.53213)
				)
				(arc
					(start 279.886664 -254.037592)
					(mid 279.890384 -254.028612)
					(end 279.899364 -254.024892)
				)
				(arc
					(start 281.372564 -254.024892)
					(mid 281.381544 -254.028612)
					(end 281.385264 -254.037592)
				)
			)
		)
	)
	(zone
		(layer "In1.Cu")
		(hatch none 0.5)
		(connect_pads
			(clearance 0)
		)
		(min_thickness 0.25)
		(keepout
			(tracks not_allowed)
			(vias allowed)
			(pads allowed)
			(copperpour not_allowed)
			(footprints allowed)
		)
		(placement
			(enabled no)
			(sheetname "")
		)
		(fill
			(thermal_gap 0.5)
			(thermal_bridge_width 0.5)
			(island_removal_mode 0)
		)
		(polygon
			(pts
				(arc
					(start 308.117494 -289.3822)
					(mid 308.113774 -289.39118)
					(end 308.104794 -289.3949)
				)
				(arc
					(start 306.631594 -289.3949)
					(mid 306.622614 -289.39118)
					(end 306.618894 -289.3822)
				)
				(arc
					(start 306.618894 -288.887662)
					(mid 306.622614 -288.878682)
					(end 306.631594 -288.874962)
				)
				(arc
					(start 308.104794 -288.874962)
					(mid 308.113774 -288.878682)
					(end 308.117494 -288.887662)
				)
			)
		)
	)
	(zone
		(layer "In1.Cu")
		(hatch none 0.5)
		(connect_pads
			(clearance 0)
		)
		(min_thickness 0.25)
		(keepout
			(tracks not_allowed)
			(vias allowed)
			(pads allowed)
			(copperpour not_allowed)
			(footprints allowed)
		)
		(placement
			(enabled no)
			(sheetname "")
		)
		(fill
			(thermal_gap 0.5)
			(thermal_bridge_width 0.5)
			(island_removal_mode 0)
		)
		(polygon
			(pts
				(arc
					(start 273.841464 -213.73211)
					(mid 273.837744 -213.74109)
					(end 273.828764 -213.74481)
				)
				(arc
					(start 272.355564 -213.74481)
					(mid 272.346584 -213.74109)
					(end 272.342864 -213.73211)
				)
				(arc
					(start 272.342864 -213.237572)
					(mid 272.346584 -213.228592)
					(end 272.355564 -213.224872)
				)
				(arc
					(start 273.828764 -213.224872)
					(mid 273.837744 -213.228592)
					(end 273.841464 -213.237572)
				)
			)
		)
	)
	(zone
		(layer "In1.Cu")
		(hatch none 0.5)
		(connect_pads
			(clearance 0)
		)
		(min_thickness 0.25)
		(keepout
			(tracks not_allowed)
			(vias allowed)
			(pads allowed)
			(copperpour not_allowed)
			(footprints allowed)
		)
		(placement
			(enabled no)
			(sheetname "")
		)
		(fill
			(thermal_gap 0.5)
			(thermal_bridge_width 0.5)
			(island_removal_mode 0)
		)
		(polygon
			(pts
				(arc
					(start 206.9973 -314.032392)
					(mid 206.99358 -314.041372)
					(end 206.9846 -314.045092)
				)
				(arc
					(start 205.5114 -314.045092)
					(mid 205.50242 -314.041372)
					(end 205.4987 -314.032392)
				)
				(arc
					(start 205.4987 -313.537854)
					(mid 205.50242 -313.528874)
					(end 205.5114 -313.525154)
				)
				(arc
					(start 206.9846 -313.525154)
					(mid 206.99358 -313.528874)
					(end 206.9973 -313.537854)
				)
			)
		)
	)
	(zone
		(layer "In1.Cu")
		(hatch none 0.5)
		(connect_pads
			(clearance 0)
		)
		(min_thickness 0.25)
		(keepout
			(tracks not_allowed)
			(vias allowed)
			(pads allowed)
			(copperpour not_allowed)
			(footprints allowed)
		)
		(placement
			(enabled no)
			(sheetname "")
		)
		(fill
			(thermal_gap 0.5)
			(thermal_bridge_width 0.5)
			(island_removal_mode 0)
		)
		(polygon
			(pts
				(arc
					(start 206.5782 -238.985298)
					(mid 205.9178 -238.985298)
					(end 206.5782 -238.985298)
				)
			)
		)
	)
	(zone
		(layer "In1.Cu")
		(hatch none 0.5)
		(connect_pads
			(clearance 0)
		)
		(min_thickness 0.25)
		(keepout
			(tracks not_allowed)
			(vias allowed)
			(pads allowed)
			(copperpour not_allowed)
			(footprints allowed)
		)
		(placement
			(enabled no)
			(sheetname "")
		)
		(fill
			(thermal_gap 0.5)
			(thermal_bridge_width 0.5)
			(island_removal_mode 0)
		)
		(polygon
			(pts
				(arc
					(start 30.001464 -315.732414)
					(mid 29.997744 -315.741394)
					(end 29.988764 -315.745114)
				)
				(arc
					(start 28.515564 -315.745114)
					(mid 28.506584 -315.741394)
					(end 28.502864 -315.732414)
				)
				(arc
					(start 28.502864 -315.237876)
					(mid 28.506584 -315.228896)
					(end 28.515564 -315.225176)
				)
				(arc
					(start 29.988764 -315.225176)
					(mid 29.997744 -315.228896)
					(end 30.001464 -315.237876)
				)
			)
		)
	)
	(zone
		(layer "In1.Cu")
		(hatch none 0.5)
		(connect_pads
			(clearance 0)
		)
		(min_thickness 0.25)
		(keepout
			(tracks not_allowed)
			(vias allowed)
			(pads allowed)
			(copperpour not_allowed)
			(footprints allowed)
		)
		(placement
			(enabled no)
			(sheetname "")
		)
		(fill
			(thermal_gap 0.5)
			(thermal_bridge_width 0.5)
			(island_removal_mode 0)
		)
		(polygon
			(pts
				(arc
					(start 379.360938 -394.385292)
					(mid 378.979938 -394.385292)
					(end 379.360938 -394.385292)
				)
			)
		)
	)
	(zone
		(layer "In1.Cu")
		(hatch none 0.5)
		(connect_pads
			(clearance 0)
		)
		(min_thickness 0.25)
		(keepout
			(tracks not_allowed)
			(vias allowed)
			(pads allowed)
			(copperpour not_allowed)
			(footprints allowed)
		)
		(placement
			(enabled no)
			(sheetname "")
		)
		(fill
			(thermal_gap 0.5)
			(thermal_bridge_width 0.5)
			(island_removal_mode 0)
		)
		(polygon
			(pts
				(arc
					(start 428.205392 -291.932106)
					(mid 428.201672 -291.941086)
					(end 428.192692 -291.944806)
				)
				(arc
					(start 426.719492 -291.944806)
					(mid 426.710512 -291.941086)
					(end 426.706792 -291.932106)
				)
				(arc
					(start 426.706792 -291.437568)
					(mid 426.710512 -291.428588)
					(end 426.719492 -291.424868)
				)
				(arc
					(start 428.192692 -291.424868)
					(mid 428.201672 -291.428588)
					(end 428.205392 -291.437568)
				)
			)
		)
	)
	(zone
		(layer "In1.Cu")
		(hatch none 0.5)
		(connect_pads
			(clearance 0)
		)
		(min_thickness 0.25)
		(keepout
			(tracks not_allowed)
			(vias allowed)
			(pads allowed)
			(copperpour not_allowed)
			(footprints allowed)
		)
		(placement
			(enabled no)
			(sheetname "")
		)
		(fill
			(thermal_gap 0.5)
			(thermal_bridge_width 0.5)
			(island_removal_mode 0)
		)
		(polygon
			(pts
				(arc
					(start 165.177216 -310.632348)
					(mid 165.173496 -310.641328)
					(end 165.164516 -310.645048)
				)
				(arc
					(start 163.691316 -310.645048)
					(mid 163.682336 -310.641328)
					(end 163.678616 -310.632348)
				)
				(arc
					(start 163.678616 -310.13781)
					(mid 163.682336 -310.12883)
					(end 163.691316 -310.12511)
				)
				(arc
					(start 165.164516 -310.12511)
					(mid 165.173496 -310.12883)
					(end 165.177216 -310.13781)
				)
			)
		)
	)
	(zone
		(layer "In1.Cu")
		(hatch none 0.5)
		(connect_pads
			(clearance 0)
		)
		(min_thickness 0.25)
		(keepout
			(tracks not_allowed)
			(vias allowed)
			(pads allowed)
			(copperpour not_allowed)
			(footprints allowed)
		)
		(placement
			(enabled no)
			(sheetname "")
		)
		(fill
			(thermal_gap 0.5)
			(thermal_bridge_width 0.5)
			(island_removal_mode 0)
		)
		(polygon
			(pts
				(arc
					(start 202.897232 -228.182424)
					(mid 202.893512 -228.191404)
					(end 202.884532 -228.195124)
				)
				(arc
					(start 201.411332 -228.195124)
					(mid 201.402352 -228.191404)
					(end 201.398632 -228.182424)
				)
				(arc
					(start 201.398632 -227.687886)
					(mid 201.402352 -227.678906)
					(end 201.411332 -227.675186)
				)
				(arc
					(start 202.884532 -227.675186)
					(mid 202.893512 -227.678906)
					(end 202.897232 -227.687886)
				)
			)
		)
	)
	(zone
		(layer "In1.Cu")
		(hatch none 0.5)
		(connect_pads
			(clearance 0)
		)
		(min_thickness 0.25)
		(keepout
			(tracks not_allowed)
			(vias allowed)
			(pads allowed)
			(copperpour not_allowed)
			(footprints allowed)
		)
		(placement
			(enabled no)
			(sheetname "")
		)
		(fill
			(thermal_gap 0.5)
			(thermal_bridge_width 0.5)
			(island_removal_mode 0)
		)
		(polygon
			(pts
				(arc
					(start 202.897232 -284.282388)
					(mid 202.893512 -284.291368)
					(end 202.884532 -284.295088)
				)
				(arc
					(start 201.411332 -284.295088)
					(mid 201.402352 -284.291368)
					(end 201.398632 -284.282388)
				)
				(arc
					(start 201.398632 -283.78785)
					(mid 201.402352 -283.77887)
					(end 201.411332 -283.77515)
				)
				(arc
					(start 202.884532 -283.77515)
					(mid 202.893512 -283.77887)
					(end 202.897232 -283.78785)
				)
			)
		)
	)
	(zone
		(layer "In1.Cu")
		(hatch none 0.5)
		(connect_pads
			(clearance 0)
		)
		(min_thickness 0.25)
		(keepout
			(tracks not_allowed)
			(vias allowed)
			(pads allowed)
			(copperpour not_allowed)
			(footprints allowed)
		)
		(placement
			(enabled no)
			(sheetname "")
		)
		(fill
			(thermal_gap 0.5)
			(thermal_bridge_width 0.5)
			(island_removal_mode 0)
		)
		(polygon
			(pts
				(arc
					(start 337.588606 -397.849344)
					(mid 337.207606 -397.849344)
					(end 337.588606 -397.849344)
				)
			)
		)
	)
	(zone
		(layer "In1.Cu")
		(hatch none 0.5)
		(connect_pads
			(clearance 0)
		)
		(min_thickness 0.25)
		(keepout
			(tracks not_allowed)
			(vias allowed)
			(pads allowed)
			(copperpour not_allowed)
			(footprints allowed)
		)
		(placement
			(enabled no)
			(sheetname "")
		)
		(fill
			(thermal_gap 0.5)
			(thermal_bridge_width 0.5)
			(island_removal_mode 0)
		)
		(polygon
			(pts
				(arc
					(start 191.909446 -313.182508)
					(mid 191.905726 -313.191488)
					(end 191.896746 -313.195208)
				)
				(arc
					(start 190.423546 -313.195208)
					(mid 190.414566 -313.191488)
					(end 190.410846 -313.182508)
				)
				(arc
					(start 190.410846 -312.68797)
					(mid 190.414566 -312.67899)
					(end 190.423546 -312.67527)
				)
				(arc
					(start 191.896746 -312.67527)
					(mid 191.905726 -312.67899)
					(end 191.909446 -312.68797)
				)
			)
		)
	)
	(zone
		(layer "In1.Cu")
		(hatch none 0.5)
		(connect_pads
			(clearance 0)
		)
		(min_thickness 0.25)
		(keepout
			(tracks not_allowed)
			(vias allowed)
			(pads allowed)
			(copperpour not_allowed)
			(footprints allowed)
		)
		(placement
			(enabled no)
			(sheetname "")
		)
		(fill
			(thermal_gap 0.5)
			(thermal_bridge_width 0.5)
			(island_removal_mode 0)
		)
		(polygon
			(pts
				(arc
					(start 25.901396 -297.882564)
					(mid 25.897676 -297.891544)
					(end 25.888696 -297.895264)
				)
				(arc
					(start 24.415496 -297.895264)
					(mid 24.406516 -297.891544)
					(end 24.402796 -297.882564)
				)
				(arc
					(start 24.402796 -297.388026)
					(mid 24.406516 -297.379046)
					(end 24.415496 -297.375326)
				)
				(arc
					(start 25.888696 -297.375326)
					(mid 25.897676 -297.379046)
					(end 25.901396 -297.388026)
				)
			)
		)
	)
	(zone
		(layer "In1.Cu")
		(hatch none 0.5)
		(connect_pads
			(clearance 0)
		)
		(min_thickness 0.25)
		(keepout
			(tracks not_allowed)
			(vias allowed)
			(pads allowed)
			(copperpour not_allowed)
			(footprints allowed)
		)
		(placement
			(enabled no)
			(sheetname "")
		)
		(fill
			(thermal_gap 0.5)
			(thermal_bridge_width 0.5)
			(island_removal_mode 0)
		)
		(polygon
			(pts
				(arc
					(start 206.5782 -244.085364)
					(mid 205.9178 -244.085364)
					(end 206.5782 -244.085364)
				)
			)
		)
	)
	(zone
		(layer "In1.Cu")
		(hatch none 0.5)
		(connect_pads
			(clearance 0)
		)
		(min_thickness 0.25)
		(keepout
			(tracks not_allowed)
			(vias allowed)
			(pads allowed)
			(copperpour not_allowed)
			(footprints allowed)
		)
		(placement
			(enabled no)
			(sheetname "")
		)
		(fill
			(thermal_gap 0.5)
			(thermal_bridge_width 0.5)
			(island_removal_mode 0)
		)
		(polygon
			(pts
				(arc
					(start 202.897232 -297.882564)
					(mid 202.893512 -297.891544)
					(end 202.884532 -297.895264)
				)
				(arc
					(start 201.411332 -297.895264)
					(mid 201.402352 -297.891544)
					(end 201.398632 -297.882564)
				)
				(arc
					(start 201.398632 -297.388026)
					(mid 201.402352 -297.379046)
					(end 201.411332 -297.375326)
				)
				(arc
					(start 202.884532 -297.375326)
					(mid 202.893512 -297.379046)
					(end 202.897232 -297.388026)
				)
			)
		)
	)
	(zone
		(layer "In1.Cu")
		(hatch none 0.5)
		(connect_pads
			(clearance 0)
		)
		(min_thickness 0.25)
		(keepout
			(tracks not_allowed)
			(vias allowed)
			(pads allowed)
			(copperpour not_allowed)
			(footprints allowed)
		)
		(placement
			(enabled no)
			(sheetname "")
		)
		(fill
			(thermal_gap 0.5)
			(thermal_bridge_width 0.5)
			(island_removal_mode 0)
		)
		(polygon
			(pts
				(arc
					(start 277.941532 -297.032172)
					(mid 277.937812 -297.041152)
					(end 277.928832 -297.044872)
				)
				(arc
					(start 276.455632 -297.044872)
					(mid 276.446652 -297.041152)
					(end 276.442932 -297.032172)
				)
				(arc
					(start 276.442932 -296.537634)
					(mid 276.446652 -296.528654)
					(end 276.455632 -296.524934)
				)
				(arc
					(start 277.928832 -296.524934)
					(mid 277.937812 -296.528654)
					(end 277.941532 -296.537634)
				)
			)
		)
	)
	(zone
		(layer "In1.Cu")
		(hatch none 0.5)
		(connect_pads
			(clearance 0)
		)
		(min_thickness 0.25)
		(keepout
			(tracks not_allowed)
			(vias allowed)
			(pads allowed)
			(copperpour not_allowed)
			(footprints allowed)
		)
		(placement
			(enabled no)
			(sheetname "")
		)
		(fill
			(thermal_gap 0.5)
			(thermal_bridge_width 0.5)
			(island_removal_mode 0)
		)
		(polygon
			(pts
				(arc
					(start 180.265324 -220.532452)
					(mid 180.261604 -220.541432)
					(end 180.252624 -220.545152)
				)
				(arc
					(start 178.779424 -220.545152)
					(mid 178.770444 -220.541432)
					(end 178.766724 -220.532452)
				)
				(arc
					(start 178.766724 -220.037914)
					(mid 178.770444 -220.028934)
					(end 178.779424 -220.025214)
				)
				(arc
					(start 180.252624 -220.025214)
					(mid 180.261604 -220.028934)
					(end 180.265324 -220.037914)
				)
			)
		)
	)
	(zone
		(layer "In1.Cu")
		(hatch none 0.5)
		(connect_pads
			(clearance 0)
		)
		(min_thickness 0.25)
		(keepout
			(tracks not_allowed)
			(vias allowed)
			(pads allowed)
			(copperpour not_allowed)
			(footprints allowed)
		)
		(placement
			(enabled no)
			(sheetname "")
		)
		(fill
			(thermal_gap 0.5)
			(thermal_bridge_width 0.5)
			(island_removal_mode 0)
		)
		(polygon
			(pts
				(arc
					(start 447.393568 -313.182254)
					(mid 447.389848 -313.191234)
					(end 447.380868 -313.194954)
				)
				(arc
					(start 445.907668 -313.194954)
					(mid 445.898688 -313.191234)
					(end 445.894968 -313.182254)
				)
				(arc
					(start 445.894968 -312.687716)
					(mid 445.898688 -312.678736)
					(end 445.907668 -312.675016)
				)
				(arc
					(start 447.380868 -312.675016)
					(mid 447.389848 -312.678736)
					(end 447.393568 -312.687716)
				)
			)
		)
	)
	(zone
		(layer "In1.Cu")
		(hatch none 0.5)
		(connect_pads
			(clearance 0)
		)
		(min_thickness 0.25)
		(keepout
			(tracks not_allowed)
			(vias allowed)
			(pads allowed)
			(copperpour not_allowed)
			(footprints allowed)
		)
		(placement
			(enabled no)
			(sheetname "")
		)
		(fill
			(thermal_gap 0.5)
			(thermal_bridge_width 0.5)
			(island_removal_mode 0)
		)
		(polygon
			(pts
				(arc
					(start 443.2935 -198.432166)
					(mid 443.28978 -198.441146)
					(end 443.2808 -198.444866)
				)
				(arc
					(start 441.8076 -198.444866)
					(mid 441.79862 -198.441146)
					(end 441.7949 -198.432166)
				)
				(arc
					(start 441.7949 -197.937628)
					(mid 441.79862 -197.928648)
					(end 441.8076 -197.924928)
				)
				(arc
					(start 443.2808 -197.924928)
					(mid 443.28978 -197.928648)
					(end 443.2935 -197.937628)
				)
			)
		)
	)
	(zone
		(layer "In1.Cu")
		(hatch none 0.5)
		(connect_pads
			(clearance 0)
		)
		(min_thickness 0.25)
		(keepout
			(tracks not_allowed)
			(vias allowed)
			(pads allowed)
			(copperpour not_allowed)
			(footprints allowed)
		)
		(placement
			(enabled no)
			(sheetname "")
		)
		(fill
			(thermal_gap 0.5)
			(thermal_bridge_width 0.5)
			(island_removal_mode 0)
		)
		(polygon
			(pts
				(arc
					(start 172.72127 -310.632348)
					(mid 172.71755 -310.641328)
					(end 172.70857 -310.645048)
				)
				(arc
					(start 171.23537 -310.645048)
					(mid 171.22639 -310.641328)
					(end 171.22267 -310.632348)
				)
				(arc
					(start 171.22267 -310.13781)
					(mid 171.22639 -310.12883)
					(end 171.23537 -310.12511)
				)
				(arc
					(start 172.70857 -310.12511)
					(mid 172.71755 -310.12883)
					(end 172.72127 -310.13781)
				)
			)
		)
	)
	(zone
		(layer "In1.Cu")
		(hatch none 0.5)
		(connect_pads
			(clearance 0)
		)
		(min_thickness 0.25)
		(keepout
			(tracks not_allowed)
			(vias allowed)
			(pads allowed)
			(copperpour not_allowed)
			(footprints allowed)
		)
		(placement
			(enabled no)
			(sheetname "")
		)
		(fill
			(thermal_gap 0.5)
			(thermal_bridge_width 0.5)
			(island_removal_mode 0)
		)
		(polygon
			(pts
				(arc
					(start 172.72127 -284.282388)
					(mid 172.71755 -284.291368)
					(end 172.70857 -284.295088)
				)
				(arc
					(start 171.23537 -284.295088)
					(mid 171.22639 -284.291368)
					(end 171.22267 -284.282388)
				)
				(arc
					(start 171.22267 -283.78785)
					(mid 171.22639 -283.77887)
					(end 171.23537 -283.77515)
				)
				(arc
					(start 172.70857 -283.77515)
					(mid 172.71755 -283.77887)
					(end 172.72127 -283.78785)
				)
			)
		)
	)
	(zone
		(layer "In1.Cu")
		(hatch none 0.5)
		(connect_pads
			(clearance 0)
		)
		(min_thickness 0.25)
		(keepout
			(tracks not_allowed)
			(vias allowed)
			(pads allowed)
			(copperpour not_allowed)
			(footprints allowed)
		)
		(placement
			(enabled no)
			(sheetname "")
		)
		(fill
			(thermal_gap 0.5)
			(thermal_bridge_width 0.5)
			(island_removal_mode 0)
		)
		(polygon
			(pts
				(arc
					(start 132.090922 -391.319258)
					(mid 132.217922 -391.446258)
					(end 132.344922 -391.319258)
				)
				(arc
					(start 132.344922 -391.243058)
					(mid 132.217922 -391.116058)
					(end 132.090922 -391.243058)
				)
			)
		)
	)
	(zone
		(layer "In1.Cu")
		(hatch none 0.5)
		(connect_pads
			(clearance 0)
		)
		(min_thickness 0.25)
		(keepout
			(tracks not_allowed)
			(vias allowed)
			(pads allowed)
			(copperpour not_allowed)
			(footprints allowed)
		)
		(placement
			(enabled no)
			(sheetname "")
		)
		(fill
			(thermal_gap 0.5)
			(thermal_bridge_width 0.5)
			(island_removal_mode 0)
		)
		(polygon
			(pts
				(arc
					(start 293.029386 -252.832108)
					(mid 293.025666 -252.841088)
					(end 293.016686 -252.844808)
				)
				(arc
					(start 291.543486 -252.844808)
					(mid 291.534506 -252.841088)
					(end 291.530786 -252.832108)
				)
				(arc
					(start 291.530786 -252.33757)
					(mid 291.534506 -252.32859)
					(end 291.543486 -252.32487)
				)
				(arc
					(start 293.016686 -252.32487)
					(mid 293.025666 -252.32859)
					(end 293.029386 -252.33757)
				)
			)
		)
	)
	(zone
		(layer "In1.Cu")
		(hatch none 0.5)
		(connect_pads
			(clearance 0)
		)
		(min_thickness 0.25)
		(keepout
			(tracks not_allowed)
			(vias allowed)
			(pads allowed)
			(copperpour not_allowed)
			(footprints allowed)
		)
		(placement
			(enabled no)
			(sheetname "")
		)
		(fill
			(thermal_gap 0.5)
			(thermal_bridge_width 0.5)
			(island_removal_mode 0)
		)
		(polygon
			(pts
				(arc
					(start 447.393568 -203.532232)
					(mid 447.389848 -203.541212)
					(end 447.380868 -203.544932)
				)
				(arc
					(start 445.907668 -203.544932)
					(mid 445.898688 -203.541212)
					(end 445.894968 -203.532232)
				)
				(arc
					(start 445.894968 -203.037694)
					(mid 445.898688 -203.028714)
					(end 445.907668 -203.024994)
				)
				(arc
					(start 447.380868 -203.024994)
					(mid 447.389848 -203.028714)
					(end 447.393568 -203.037694)
				)
			)
		)
	)
	(zone
		(layer "In1.Cu")
		(hatch none 0.5)
		(connect_pads
			(clearance 0)
		)
		(min_thickness 0.25)
		(keepout
			(tracks not_allowed)
			(vias allowed)
			(pads allowed)
			(copperpour not_allowed)
			(footprints allowed)
		)
		(placement
			(enabled no)
			(sheetname "")
		)
		(fill
			(thermal_gap 0.5)
			(thermal_bridge_width 0.5)
			(island_removal_mode 0)
		)
		(polygon
			(pts
				(arc
					(start 266.29741 -204.382116)
					(mid 266.29369 -204.391096)
					(end 266.28471 -204.394816)
				)
				(arc
					(start 264.81151 -204.394816)
					(mid 264.80253 -204.391096)
					(end 264.79881 -204.382116)
				)
				(arc
					(start 264.79881 -203.887578)
					(mid 264.80253 -203.878598)
					(end 264.81151 -203.874878)
				)
				(arc
					(start 266.28471 -203.874878)
					(mid 266.29369 -203.878598)
					(end 266.29741 -203.887578)
				)
			)
		)
	)
	(zone
		(layer "In1.Cu")
		(hatch none 0.5)
		(connect_pads
			(clearance 0)
		)
		(min_thickness 0.25)
		(keepout
			(tracks not_allowed)
			(vias allowed)
			(pads allowed)
			(copperpour not_allowed)
			(footprints allowed)
		)
		(placement
			(enabled no)
			(sheetname "")
		)
		(fill
			(thermal_gap 0.5)
			(thermal_bridge_width 0.5)
			(island_removal_mode 0)
		)
		(polygon
			(pts
				(arc
					(start 56.077358 -277.482554)
					(mid 56.073638 -277.491534)
					(end 56.064658 -277.495254)
				)
				(arc
					(start 54.591458 -277.495254)
					(mid 54.582478 -277.491534)
					(end 54.578758 -277.482554)
				)
				(arc
					(start 54.578758 -276.988016)
					(mid 54.582478 -276.979036)
					(end 54.591458 -276.975316)
				)
				(arc
					(start 56.064658 -276.975316)
					(mid 56.073638 -276.979036)
					(end 56.077358 -276.988016)
				)
			)
		)
	)
)
